(kicad_pcb
	(version 20260206)
	(generator "pcbnew")
	(generator_version "10.0")
	(general
		(thickness 1.6)
		(legacy_teardrops no)
	)
	(paper "A4")
	(layers
		(0 "F.Cu" signal "TOP")
		(4 "In1.Cu" signal "GND")
		(6 "In2.Cu" signal "VCC")
		(8 "In3.Cu" signal "VCC1")
		(10 "In4.Cu" signal "GND1")
		(12 "In5.Cu" signal "IN1")
		(14 "In6.Cu" signal "GND2")
		(16 "In7.Cu" signal "IN2")
		(18 "In8.Cu" signal "GND3")
		(20 "In9.Cu" signal "IN3")
		(22 "In10.Cu" signal "GND4")
		(24 "In11.Cu" signal "IN4")
		(26 "In12.Cu" signal "GND5")
		(28 "In13.Cu" signal "IN5")
		(30 "In14.Cu" signal "GND6")
		(32 "In15.Cu" signal "IN6")
		(34 "In16.Cu" signal "GND7")
		(2 "B.Cu" signal "BOTTOM")
		(9 "F.Adhes" user "F.Adhesive")
		(11 "B.Adhes" user "B.Adhesive")
		(13 "F.Paste" user "Package Geometry/Pastemask Top")
		(15 "B.Paste" user "Package Geometry/Pastemask Bottom")
		(5 "F.SilkS" user "Ref Des/Silkscreen Top")
		(7 "B.SilkS" user "Ref Des/Silkscreen Bottom")
		(1 "F.Mask" user "Board Geometry/Soldermask Top")
		(3 "B.Mask" user "Board Geometry/Soldermask Bottom")
		(17 "Dwgs.User" user "User.Drawings")
		(19 "Cmts.User" user "User.Comments")
		(21 "Eco1.User" user "User.Eco1")
		(23 "Eco2.User" user "User.Eco2")
		(25 "Edge.Cuts" user "Board Geometry/Outline")
		(27 "Margin" user)
		(31 "F.CrtYd" user "Package Geometry/Place Bound Top")
		(29 "B.CrtYd" user "Package Geometry/Place Bound Bottom")
		(35 "F.Fab" user "Ref Des/Assembly Top")
		(33 "B.Fab" user "Ref Des/Assembly Bottom")
	)
	(setup
		(pad_to_mask_clearance 0)
		(allow_soldermask_bridges_in_footprints no)
		(tenting
			(front yes)
			(back yes)
		)
		(covering
			(front no)
			(back no)
		)
		(plugging
			(front no)
			(back no)
		)
		(capping no)
		(filling no)
		(pcbplotparams
			(layerselection 0x00000000_00000000_55555555_5755f5ff)
			(plot_on_all_layers_selection 0x00000000_00000000_00000000_00000000)
			(disableapertmacros no)
			(usegerberextensions no)
			(usegerberattributes yes)
			(usegerberadvancedattributes yes)
			(creategerberjobfile yes)
			(dashed_line_dash_ratio 12)
			(dashed_line_gap_ratio 3)
			(svgprecision 4)
			(plotframeref no)
			(mode 1)
			(useauxorigin no)
			(pdf_front_fp_property_popups yes)
			(pdf_back_fp_property_popups yes)
			(pdf_metadata yes)
			(pdf_single_document no)
			(dxfpolygonmode yes)
			(dxfimperialunits yes)
			(dxfusepcbnewfont yes)
			(psnegative no)
			(psa4output no)
			(plot_black_and_white yes)
			(sketchpadsonfab no)
			(plotpadnumbers no)
			(hidednponfab no)
			(sketchdnponfab yes)
			(crossoutdnponfab yes)
			(subtractmaskfromsilk no)
			(outputformat 1)
			(mirror no)
			(drillshape 1)
			(scaleselection 1)
			(outputdirectory "")
		)
	)
	(footprint ""
		(layer "F.Cu")
		(at 22.027896 -35.876738)
		(property "Reference" "R5871"
			(at 0 0 0)
			(layer "F.SilkS")
			(hide yes)
			(effects
				(font
					(size 1.27 1.27)
				)
			)
		)
		(property "Value" ""
			(at 0 0 0)
			(layer "F.Fab")
			(effects
				(font
					(size 1.27 1.27)
				)
			)
		)
		(duplicate_pad_numbers_are_jumpers no)
		(fp_line
			(start -0.7874 -0.4064)
			(end 0.7874 -0.4064)
			(stroke
				(width 0.1524)
				(type default)
			)
			(layer "F.SilkS")
		)
		(fp_line
			(start -0.7874 0.4064)
			(end -0.7874 -0.4064)
			(stroke
				(width 0.1524)
				(type default)
			)
			(layer "F.SilkS")
		)
		(fp_line
			(start 0.7874 -0.4064)
			(end 0.7874 0.4064)
			(stroke
				(width 0.1524)
				(type default)
			)
			(layer "F.SilkS")
		)
		(fp_line
			(start 0.7874 0.4064)
			(end -0.7874 0.4064)
			(stroke
				(width 0.1524)
				(type default)
			)
			(layer "F.SilkS")
		)
		(fp_line
			(start -0.67945 -0.305054)
			(end -0.12065 -0.305054)
			(stroke
				(width 0.1)
				(type default)
			)
			(layer "F.Fab")
		)
		(fp_line
			(start -0.67945 0.3048)
			(end -0.67945 -0.305054)
			(stroke
				(width 0.1)
				(type default)
			)
			(layer "F.Fab")
		)
		(fp_line
			(start -0.12065 -0.305054)
			(end -0.12065 -0.2794)
			(stroke
				(width 0.1)
				(type default)
			)
			(layer "F.Fab")
		)
		(fp_line
			(start -0.12065 -0.2794)
			(end 0.12065 -0.2794)
			(stroke
				(width 0.1)
				(type default)
			)
			(layer "F.Fab")
		)
		(fp_line
			(start -0.12065 0.2794)
			(end -0.12065 0.3048)
			(stroke
				(width 0.1)
				(type default)
			)
			(layer "F.Fab")
		)
		(fp_line
			(start -0.12065 0.3048)
			(end -0.67945 0.3048)
			(stroke
				(width 0.1)
				(type default)
			)
			(layer "F.Fab")
		)
		(fp_line
			(start 0.120396 0.2794)
			(end -0.12065 0.2794)
			(stroke
				(width 0.1)
				(type default)
			)
			(layer "F.Fab")
		)
		(fp_line
			(start 0.120396 0.3048)
			(end 0.120396 0.2794)
			(stroke
				(width 0.1)
				(type default)
			)
			(layer "F.Fab")
		)
		(fp_line
			(start 0.12065 -0.3048)
			(end 0.67945 -0.3048)
			(stroke
				(width 0.1)
				(type default)
			)
			(layer "F.Fab")
		)
		(fp_line
			(start 0.12065 -0.2794)
			(end 0.12065 -0.3048)
			(stroke
				(width 0.1)
				(type default)
			)
			(layer "F.Fab")
		)
		(fp_line
			(start 0.67945 -0.3048)
			(end 0.67945 0.3048)
			(stroke
				(width 0.1)
				(type default)
			)
			(layer "F.Fab")
		)
		(fp_line
			(start 0.67945 0.3048)
			(end 0.120396 0.3048)
			(stroke
				(width 0.1)
				(type default)
			)
			(layer "F.Fab")
		)
		(pad "1" smd circle
			(at -0.40005 0)
			(size 0 0)
			(layers "F.Cu" "F.Mask" "F.Paste")
			(net "PWRGD_P3V3_SSD1_D")
		)
		(pad "2" smd circle
			(at 0.40005 0)
			(size 0 0)
			(layers "F.Cu" "F.Mask" "F.Paste")
			(net "PWRGD_P3V3_SSD1_R")
		)
	)
	(footprint ""
		(layer "F.Cu")
		(at 242.349782 -148.872702)
		(property "Reference" "PD94"
			(at -3.4544 -2.225548 0)
			(unlocked yes)
			(layer "F.SilkS")
			(effects
				(font
					(size 0.7874 0.5842)
					(thickness 0.1524)
				)
				(justify left)
			)
		)
		(property "Value" ""
			(at 0 0 0)
			(layer "F.Fab")
			(effects
				(font
					(size 1.27 1.27)
				)
			)
		)
		(duplicate_pad_numbers_are_jumpers no)
		(fp_line
			(start -3.400044 -1.459992)
			(end 4.107942 -1.459992)
			(stroke
				(width 0.1524)
				(type default)
			)
			(layer "F.SilkS")
		)
		(fp_line
			(start -3.400044 1.459992)
			(end -3.400044 -1.459992)
			(stroke
				(width 0.1524)
				(type default)
			)
			(layer "F.SilkS")
		)
		(fp_line
			(start 4.107942 -1.459992)
			(end 4.107942 1.459992)
			(stroke
				(width 0.1524)
				(type default)
			)
			(layer "F.SilkS")
		)
		(fp_line
			(start 4.107942 1.459992)
			(end -3.400044 1.459992)
			(stroke
				(width 0.1524)
				(type default)
			)
			(layer "F.SilkS")
		)
		(fp_poly
			(pts
				(xy 4.107942 -1.459992) (xy 4.107942 1.459992) (xy 3.308096 1.459992) (xy 3.308096 -1.459992)
			)
			(stroke
				(width 0)
				(type default)
			)
			(fill yes)
			(layer "F.SilkS")
		)
		(fp_line
			(start -2.29997 -1.459992)
			(end 2.29997 -1.459992)
			(stroke
				(width 0.1)
				(type default)
			)
			(layer "F.Fab")
		)
		(fp_line
			(start -2.29997 1.459992)
			(end -2.29997 -1.459992)
			(stroke
				(width 0.1)
				(type default)
			)
			(layer "F.Fab")
		)
		(fp_line
			(start 2.29997 -1.459992)
			(end 2.29997 1.459992)
			(stroke
				(width 0.1)
				(type default)
			)
			(layer "F.Fab")
		)
		(fp_line
			(start 2.29997 1.459992)
			(end -2.29997 1.459992)
			(stroke
				(width 0.1)
				(type default)
			)
			(layer "F.Fab")
		)
		(fp_text user "+"
			(at -4.7752 -0.12065 0)
			(unlocked yes)
			(layer "F.SilkS")
			(effects
				(font
					(size 1.905 1.4224)
					(thickness 0.1524)
				)
				(justify left)
			)
		)
		(fp_text user "-"
			(at 5.4102 0.29845 180)
			(unlocked yes)
			(layer "F.SilkS")
			(effects
				(font
					(size 1.905 1.4224)
					(thickness 0.1524)
				)
				(justify left)
			)
		)
		(fp_text user "+"
			(at -4.7752 -0.12065 0)
			(unlocked yes)
			(layer "F.Fab")
			(effects
				(font
					(size 1.905 1.4224)
					(thickness 0.1524)
				)
				(justify left)
			)
		)
		(fp_text user "-"
			(at 5.4102 0.29845 180)
			(unlocked yes)
			(layer "F.Fab")
			(effects
				(font
					(size 1.905 1.4224)
					(thickness 0.1524)
				)
				(justify left)
			)
		)
		(pad "A" smd rect
			(at -1.999996 0 90)
			(size 1.7018 2.5146)
			(layers "F.Cu" "F.Mask" "F.Paste")
			(net "GND")
		)
		(pad "C" smd rect
			(at 1.999996 0 90)
			(size 1.7018 2.5146)
			(layers "F.Cu" "F.Mask" "F.Paste")
			(net "P12V_NIC4_R")
		)
	)
	(footprint ""
		(layer "F.Cu")
		(at 7.856728 -45.071792 180)
		(property "Reference" "R5539"
			(at 0 0 180)
			(layer "F.SilkS")
			(hide yes)
			(effects
				(font
					(size 1.27 1.27)
				)
			)
		)
		(property "Value" ""
			(at 0 0 180)
			(layer "F.Fab")
			(effects
				(font
					(size 1.27 1.27)
				)
			)
		)
		(duplicate_pad_numbers_are_jumpers no)
		(fp_line
			(start 0.7874 0.4064)
			(end -0.7874 0.4064)
			(stroke
				(width 0.1524)
				(type default)
			)
			(layer "F.SilkS")
		)
		(fp_line
			(start 0.7874 -0.4064)
			(end 0.7874 0.4064)
			(stroke
				(width 0.1524)
				(type default)
			)
			(layer "F.SilkS")
		)
		(fp_line
			(start -0.7874 0.4064)
			(end -0.7874 -0.4064)
			(stroke
				(width 0.1524)
				(type default)
			)
			(layer "F.SilkS")
		)
		(fp_line
			(start -0.7874 -0.4064)
			(end 0.7874 -0.4064)
			(stroke
				(width 0.1524)
				(type default)
			)
			(layer "F.SilkS")
		)
		(fp_line
			(start 0.67945 0.3048)
			(end 0.120396 0.3048)
			(stroke
				(width 0.1)
				(type default)
			)
			(layer "F.Fab")
		)
		(fp_line
			(start 0.67945 -0.3048)
			(end 0.67945 0.3048)
			(stroke
				(width 0.1)
				(type default)
			)
			(layer "F.Fab")
		)
		(fp_line
			(start 0.12065 -0.2794)
			(end 0.12065 -0.3048)
			(stroke
				(width 0.1)
				(type default)
			)
			(layer "F.Fab")
		)
		(fp_line
			(start 0.12065 -0.3048)
			(end 0.67945 -0.3048)
			(stroke
				(width 0.1)
				(type default)
			)
			(layer "F.Fab")
		)
		(fp_line
			(start 0.120396 0.3048)
			(end 0.120396 0.2794)
			(stroke
				(width 0.1)
				(type default)
			)
			(layer "F.Fab")
		)
		(fp_line
			(start 0.120396 0.2794)
			(end -0.12065 0.2794)
			(stroke
				(width 0.1)
				(type default)
			)
			(layer "F.Fab")
		)
		(fp_line
			(start -0.12065 0.3048)
			(end -0.67945 0.3048)
			(stroke
				(width 0.1)
				(type default)
			)
			(layer "F.Fab")
		)
		(fp_line
			(start -0.12065 0.2794)
			(end -0.12065 0.3048)
			(stroke
				(width 0.1)
				(type default)
			)
			(layer "F.Fab")
		)
		(fp_line
			(start -0.12065 -0.2794)
			(end 0.12065 -0.2794)
			(stroke
				(width 0.1)
				(type default)
			)
			(layer "F.Fab")
		)
		(fp_line
			(start -0.12065 -0.305054)
			(end -0.12065 -0.2794)
			(stroke
				(width 0.1)
				(type default)
			)
			(layer "F.Fab")
		)
		(fp_line
			(start -0.67945 0.3048)
			(end -0.67945 -0.305054)
			(stroke
				(width 0.1)
				(type default)
			)
			(layer "F.Fab")
		)
		(fp_line
			(start -0.67945 -0.305054)
			(end -0.12065 -0.305054)
			(stroke
				(width 0.1)
				(type default)
			)
			(layer "F.Fab")
		)
		(pad "1" smd circle
			(at -0.40005 0 180)
			(size 0 0)
			(layers "F.Cu" "F.Mask" "F.Paste")
			(net "PRSNT_SSD0_R1_N")
		)
		(pad "2" smd circle
			(at 0.40005 0 180)
			(size 0 0)
			(layers "F.Cu" "F.Mask" "F.Paste")
			(net "PRSNT_SSD0_R_N")
		)
	)
	(footprint ""
		(layer "F.Cu")
		(at 204.591158 -81.627472)
		(property "Reference" "R4333"
			(at 0 0 0)
			(layer "F.SilkS")
			(hide yes)
			(effects
				(font
					(size 1.27 1.27)
				)
			)
		)
		(property "Value" ""
			(at 0 0 0)
			(layer "F.Fab")
			(effects
				(font
					(size 1.27 1.27)
				)
			)
		)
		(duplicate_pad_numbers_are_jumpers no)
		(fp_line
			(start -0.7874 -0.4064)
			(end 0.7874 -0.4064)
			(stroke
				(width 0.1524)
				(type default)
			)
			(layer "F.SilkS")
		)
		(fp_line
			(start -0.7874 0.4064)
			(end -0.7874 -0.4064)
			(stroke
				(width 0.1524)
				(type default)
			)
			(layer "F.SilkS")
		)
		(fp_line
			(start 0.7874 -0.4064)
			(end 0.7874 0.4064)
			(stroke
				(width 0.1524)
				(type default)
			)
			(layer "F.SilkS")
		)
		(fp_line
			(start 0.7874 0.4064)
			(end -0.7874 0.4064)
			(stroke
				(width 0.1524)
				(type default)
			)
			(layer "F.SilkS")
		)
		(fp_line
			(start -0.67945 -0.305054)
			(end -0.12065 -0.305054)
			(stroke
				(width 0.1)
				(type default)
			)
			(layer "F.Fab")
		)
		(fp_line
			(start -0.67945 0.3048)
			(end -0.67945 -0.305054)
			(stroke
				(width 0.1)
				(type default)
			)
			(layer "F.Fab")
		)
		(fp_line
			(start -0.12065 -0.305054)
			(end -0.12065 -0.2794)
			(stroke
				(width 0.1)
				(type default)
			)
			(layer "F.Fab")
		)
		(fp_line
			(start -0.12065 -0.2794)
			(end 0.12065 -0.2794)
			(stroke
				(width 0.1)
				(type default)
			)
			(layer "F.Fab")
		)
		(fp_line
			(start -0.12065 0.2794)
			(end -0.12065 0.3048)
			(stroke
				(width 0.1)
				(type default)
			)
			(layer "F.Fab")
		)
		(fp_line
			(start -0.12065 0.3048)
			(end -0.67945 0.3048)
			(stroke
				(width 0.1)
				(type default)
			)
			(layer "F.Fab")
		)
		(fp_line
			(start 0.120396 0.2794)
			(end -0.12065 0.2794)
			(stroke
				(width 0.1)
				(type default)
			)
			(layer "F.Fab")
		)
		(fp_line
			(start 0.120396 0.3048)
			(end 0.120396 0.2794)
			(stroke
				(width 0.1)
				(type default)
			)
			(layer "F.Fab")
		)
		(fp_line
			(start 0.12065 -0.3048)
			(end 0.67945 -0.3048)
			(stroke
				(width 0.1)
				(type default)
			)
			(layer "F.Fab")
		)
		(fp_line
			(start 0.12065 -0.2794)
			(end 0.12065 -0.3048)
			(stroke
				(width 0.1)
				(type default)
			)
			(layer "F.Fab")
		)
		(fp_line
			(start 0.67945 -0.3048)
			(end 0.67945 0.3048)
			(stroke
				(width 0.1)
				(type default)
			)
			(layer "F.Fab")
		)
		(fp_line
			(start 0.67945 0.3048)
			(end 0.120396 0.3048)
			(stroke
				(width 0.1)
				(type default)
			)
			(layer "F.Fab")
		)
		(pad "1" smd circle
			(at -0.40005 0)
			(size 0 0)
			(layers "F.Cu" "F.Mask" "F.Paste")
			(net "P3V3_AUX")
		)
		(pad "2" smd circle
			(at 0.40005 0)
			(size 0 0)
			(layers "F.Cu" "F.Mask" "F.Paste")
			(net "SSD3_LED_R")
		)
	)
	(footprint ""
		(layer "F.Cu")
		(at 97.796096 -47.20082 90)
		(property "Reference" "C211"
			(at 0 0 90)
			(layer "F.SilkS")
			(hide yes)
			(effects
				(font
					(size 1.27 1.27)
				)
			)
		)
		(property "Value" ""
			(at 0 0 90)
			(layer "F.Fab")
			(effects
				(font
					(size 1.27 1.27)
				)
			)
		)
		(duplicate_pad_numbers_are_jumpers no)
		(fp_line
			(start 0.7874 -0.4064)
			(end 0.7874 0.4064)
			(stroke
				(width 0.1524)
				(type default)
			)
			(layer "F.SilkS")
		)
		(fp_line
			(start -0.7874 -0.4064)
			(end 0.7874 -0.4064)
			(stroke
				(width 0.1524)
				(type default)
			)
			(layer "F.SilkS")
		)
		(fp_line
			(start 0.7874 0.4064)
			(end -0.7874 0.4064)
			(stroke
				(width 0.1524)
				(type default)
			)
			(layer "F.SilkS")
		)
		(fp_line
			(start -0.7874 0.4064)
			(end -0.7874 -0.4064)
			(stroke
				(width 0.1524)
				(type default)
			)
			(layer "F.SilkS")
		)
		(fp_line
			(start -0.12065 -0.305054)
			(end -0.12065 -0.2794)
			(stroke
				(width 0.1)
				(type default)
			)
			(layer "F.Fab")
		)
		(fp_line
			(start -0.67945 -0.305054)
			(end -0.12065 -0.305054)
			(stroke
				(width 0.1)
				(type default)
			)
			(layer "F.Fab")
		)
		(fp_line
			(start 0.67945 -0.3048)
			(end 0.67945 0.3048)
			(stroke
				(width 0.1)
				(type default)
			)
			(layer "F.Fab")
		)
		(fp_line
			(start 0.12065 -0.3048)
			(end 0.67945 -0.3048)
			(stroke
				(width 0.1)
				(type default)
			)
			(layer "F.Fab")
		)
		(fp_line
			(start 0.12065 -0.2794)
			(end 0.12065 -0.3048)
			(stroke
				(width 0.1)
				(type default)
			)
			(layer "F.Fab")
		)
		(fp_line
			(start -0.12065 -0.2794)
			(end 0.12065 -0.2794)
			(stroke
				(width 0.1)
				(type default)
			)
			(layer "F.Fab")
		)
		(fp_line
			(start 0.120396 0.2794)
			(end -0.12065 0.2794)
			(stroke
				(width 0.1)
				(type default)
			)
			(layer "F.Fab")
		)
		(fp_line
			(start -0.12065 0.2794)
			(end -0.12065 0.3048)
			(stroke
				(width 0.1)
				(type default)
			)
			(layer "F.Fab")
		)
		(fp_line
			(start 0.67945 0.3048)
			(end 0.120396 0.3048)
			(stroke
				(width 0.1)
				(type default)
			)
			(layer "F.Fab")
		)
		(fp_line
			(start 0.120396 0.3048)
			(end 0.120396 0.2794)
			(stroke
				(width 0.1)
				(type default)
			)
			(layer "F.Fab")
		)
		(fp_line
			(start -0.12065 0.3048)
			(end -0.67945 0.3048)
			(stroke
				(width 0.1)
				(type default)
			)
			(layer "F.Fab")
		)
		(fp_line
			(start -0.67945 0.3048)
			(end -0.67945 -0.305054)
			(stroke
				(width 0.1)
				(type default)
			)
			(layer "F.Fab")
		)
		(pad "1" smd circle
			(at -0.40005 0 90)
			(size 0 0)
			(layers "F.Cu" "F.Mask" "F.Paste")
			(net "P12V_SSD3_R")
		)
		(pad "2" smd circle
			(at 0.40005 0 90)
			(size 0 0)
			(layers "F.Cu" "F.Mask" "F.Paste")
			(net "GND")
		)
	)
	(footprint ""
		(layer "F.Cu")
		(at 215.075516 -118.207028 180)
		(property "Reference" "R884"
			(at 0 0 180)
			(layer "F.SilkS")
			(hide yes)
			(effects
				(font
					(size 1.27 1.27)
				)
			)
		)
		(property "Value" ""
			(at 0 0 180)
			(layer "F.Fab")
			(effects
				(font
					(size 1.27 1.27)
				)
			)
		)
		(duplicate_pad_numbers_are_jumpers no)
		(fp_line
			(start 0.7874 0.4064)
			(end -0.7874 0.4064)
			(stroke
				(width 0.1524)
				(type default)
			)
			(layer "F.SilkS")
		)
		(fp_line
			(start 0.7874 -0.4064)
			(end 0.7874 0.4064)
			(stroke
				(width 0.1524)
				(type default)
			)
			(layer "F.SilkS")
		)
		(fp_line
			(start -0.7874 0.4064)
			(end -0.7874 -0.4064)
			(stroke
				(width 0.1524)
				(type default)
			)
			(layer "F.SilkS")
		)
		(fp_line
			(start -0.7874 -0.4064)
			(end 0.7874 -0.4064)
			(stroke
				(width 0.1524)
				(type default)
			)
			(layer "F.SilkS")
		)
		(fp_line
			(start 0.67945 0.3048)
			(end 0.120396 0.3048)
			(stroke
				(width 0.1)
				(type default)
			)
			(layer "F.Fab")
		)
		(fp_line
			(start 0.67945 -0.3048)
			(end 0.67945 0.3048)
			(stroke
				(width 0.1)
				(type default)
			)
			(layer "F.Fab")
		)
		(fp_line
			(start 0.12065 -0.2794)
			(end 0.12065 -0.3048)
			(stroke
				(width 0.1)
				(type default)
			)
			(layer "F.Fab")
		)
		(fp_line
			(start 0.12065 -0.3048)
			(end 0.67945 -0.3048)
			(stroke
				(width 0.1)
				(type default)
			)
			(layer "F.Fab")
		)
		(fp_line
			(start 0.120396 0.3048)
			(end 0.120396 0.2794)
			(stroke
				(width 0.1)
				(type default)
			)
			(layer "F.Fab")
		)
		(fp_line
			(start 0.120396 0.2794)
			(end -0.12065 0.2794)
			(stroke
				(width 0.1)
				(type default)
			)
			(layer "F.Fab")
		)
		(fp_line
			(start -0.12065 0.3048)
			(end -0.67945 0.3048)
			(stroke
				(width 0.1)
				(type default)
			)
			(layer "F.Fab")
		)
		(fp_line
			(start -0.12065 0.2794)
			(end -0.12065 0.3048)
			(stroke
				(width 0.1)
				(type default)
			)
			(layer "F.Fab")
		)
		(fp_line
			(start -0.12065 -0.2794)
			(end 0.12065 -0.2794)
			(stroke
				(width 0.1)
				(type default)
			)
			(layer "F.Fab")
		)
		(fp_line
			(start -0.12065 -0.305054)
			(end -0.12065 -0.2794)
			(stroke
				(width 0.1)
				(type default)
			)
			(layer "F.Fab")
		)
		(fp_line
			(start -0.67945 0.3048)
			(end -0.67945 -0.305054)
			(stroke
				(width 0.1)
				(type default)
			)
			(layer "F.Fab")
		)
		(fp_line
			(start -0.67945 -0.305054)
			(end -0.12065 -0.305054)
			(stroke
				(width 0.1)
				(type default)
			)
			(layer "F.Fab")
		)
		(pad "1" smd circle
			(at -0.40005 0 180)
			(size 0 0)
			(layers "F.Cu" "F.Mask" "F.Paste")
			(net "P3V3_NIC3")
		)
		(pad "2" smd circle
			(at 0.40005 0 180)
			(size 0 0)
			(layers "F.Cu" "F.Mask" "F.Paste")
			(net "PWRGD_P3V3_NIC3")
		)
	)
	(footprint ""
		(layer "F.Cu")
		(at 250.879864 -135.62711 90)
		(property "Reference" "PD7"
			(at -3.49631 2.207006 90)
			(unlocked yes)
			(layer "F.SilkS")
			(effects
				(font
					(size 0.7874 0.5842)
					(thickness 0.1524)
				)
				(justify left)
			)
		)
		(property "Value" ""
			(at 0 0 90)
			(layer "F.Fab")
			(effects
				(font
					(size 1.27 1.27)
				)
			)
		)
		(duplicate_pad_numbers_are_jumpers no)
		(fp_line
			(start 4.107942 -1.459992)
			(end 4.107942 1.459992)
			(stroke
				(width 0.1524)
				(type default)
			)
			(layer "F.SilkS")
		)
		(fp_line
			(start -3.400044 -1.459992)
			(end 4.107942 -1.459992)
			(stroke
				(width 0.1524)
				(type default)
			)
			(layer "F.SilkS")
		)
		(fp_line
			(start 4.107942 1.459992)
			(end -3.400044 1.459992)
			(stroke
				(width 0.1524)
				(type default)
			)
			(layer "F.SilkS")
		)
		(fp_line
			(start -3.400044 1.459992)
			(end -3.400044 -1.459992)
			(stroke
				(width 0.1524)
				(type default)
			)
			(layer "F.SilkS")
		)
		(fp_poly
			(pts
				(xy 4.107942 -1.459992) (xy 4.107942 1.459992) (xy 3.308096 1.459992) (xy 3.308096 -1.459992)
			)
			(stroke
				(width 0)
				(type default)
			)
			(fill yes)
			(layer "F.SilkS")
		)
		(fp_line
			(start 2.29997 -1.459992)
			(end 2.29997 1.459992)
			(stroke
				(width 0.1)
				(type default)
			)
			(layer "F.Fab")
		)
		(fp_line
			(start -2.29997 -1.459992)
			(end 2.29997 -1.459992)
			(stroke
				(width 0.1)
				(type default)
			)
			(layer "F.Fab")
		)
		(fp_line
			(start 2.29997 1.459992)
			(end -2.29997 1.459992)
			(stroke
				(width 0.1)
				(type default)
			)
			(layer "F.Fab")
		)
		(fp_line
			(start -2.29997 1.459992)
			(end -2.29997 -1.459992)
			(stroke
				(width 0.1)
				(type default)
			)
			(layer "F.Fab")
		)
		(fp_text user "+"
			(at -4.7752 -0.12065 90)
			(unlocked yes)
			(layer "F.SilkS")
			(effects
				(font
					(size 1.905 1.4224)
					(thickness 0.1524)
				)
				(justify left)
			)
		)
		(fp_text user "-"
			(at 4.663694 2.10312 270)
			(unlocked yes)
			(layer "F.SilkS")
			(effects
				(font
					(size 1.905 1.4224)
					(thickness 0.1524)
				)
				(justify left)
			)
		)
		(fp_text user "+"
			(at -4.7752 -0.12065 90)
			(unlocked yes)
			(layer "F.Fab")
			(effects
				(font
					(size 1.905 1.4224)
					(thickness 0.1524)
				)
				(justify left)
			)
		)
		(fp_text user "-"
			(at 5.4102 0.29845 270)
			(unlocked yes)
			(layer "F.Fab")
			(effects
				(font
					(size 1.905 1.4224)
					(thickness 0.1524)
				)
				(justify left)
			)
		)
		(pad "A" smd rect
			(at -1.999996 0 180)
			(size 1.7018 2.5146)
			(layers "F.Cu" "F.Mask" "F.Paste")
			(net "GND")
		)
		(pad "C" smd rect
			(at 1.999996 0 180)
			(size 1.7018 2.5146)
			(layers "F.Cu" "F.Mask" "F.Paste")
			(net "P12V_NIC4_R")
		)
	)
	(footprint ""
		(layer "F.Cu")
		(at 406.619964 -372.877842 180)
		(property "Reference" "R6681"
			(at 0 0 180)
			(layer "F.SilkS")
			(hide yes)
			(effects
				(font
					(size 1.27 1.27)
				)
			)
		)
		(property "Value" ""
			(at 0 0 180)
			(layer "F.Fab")
			(effects
				(font
					(size 1.27 1.27)
				)
			)
		)
		(duplicate_pad_numbers_are_jumpers no)
		(fp_line
			(start 0.7874 0.4064)
			(end -0.7874 0.4064)
			(stroke
				(width 0.1524)
				(type default)
			)
			(layer "F.SilkS")
		)
		(fp_line
			(start 0.7874 -0.4064)
			(end 0.7874 0.4064)
			(stroke
				(width 0.1524)
				(type default)
			)
			(layer "F.SilkS")
		)
		(fp_line
			(start -0.7874 0.4064)
			(end -0.7874 -0.4064)
			(stroke
				(width 0.1524)
				(type default)
			)
			(layer "F.SilkS")
		)
		(fp_line
			(start -0.7874 -0.4064)
			(end 0.7874 -0.4064)
			(stroke
				(width 0.1524)
				(type default)
			)
			(layer "F.SilkS")
		)
		(fp_line
			(start 0.67945 0.3048)
			(end 0.120396 0.3048)
			(stroke
				(width 0.1)
				(type default)
			)
			(layer "F.Fab")
		)
		(fp_line
			(start 0.67945 -0.3048)
			(end 0.67945 0.3048)
			(stroke
				(width 0.1)
				(type default)
			)
			(layer "F.Fab")
		)
		(fp_line
			(start 0.12065 -0.2794)
			(end 0.12065 -0.3048)
			(stroke
				(width 0.1)
				(type default)
			)
			(layer "F.Fab")
		)
		(fp_line
			(start 0.12065 -0.3048)
			(end 0.67945 -0.3048)
			(stroke
				(width 0.1)
				(type default)
			)
			(layer "F.Fab")
		)
		(fp_line
			(start 0.120396 0.3048)
			(end 0.120396 0.2794)
			(stroke
				(width 0.1)
				(type default)
			)
			(layer "F.Fab")
		)
		(fp_line
			(start 0.120396 0.2794)
			(end -0.12065 0.2794)
			(stroke
				(width 0.1)
				(type default)
			)
			(layer "F.Fab")
		)
		(fp_line
			(start -0.12065 0.3048)
			(end -0.67945 0.3048)
			(stroke
				(width 0.1)
				(type default)
			)
			(layer "F.Fab")
		)
		(fp_line
			(start -0.12065 0.2794)
			(end -0.12065 0.3048)
			(stroke
				(width 0.1)
				(type default)
			)
			(layer "F.Fab")
		)
		(fp_line
			(start -0.12065 -0.2794)
			(end 0.12065 -0.2794)
			(stroke
				(width 0.1)
				(type default)
			)
			(layer "F.Fab")
		)
		(fp_line
			(start -0.12065 -0.305054)
			(end -0.12065 -0.2794)
			(stroke
				(width 0.1)
				(type default)
			)
			(layer "F.Fab")
		)
		(fp_line
			(start -0.67945 0.3048)
			(end -0.67945 -0.305054)
			(stroke
				(width 0.1)
				(type default)
			)
			(layer "F.Fab")
		)
		(fp_line
			(start -0.67945 -0.305054)
			(end -0.12065 -0.305054)
			(stroke
				(width 0.1)
				(type default)
			)
			(layer "F.Fab")
		)
		(pad "1" smd circle
			(at -0.40005 0 180)
			(size 0 0)
			(layers "F.Cu" "F.Mask" "F.Paste")
			(net "P3V3_AUX")
		)
		(pad "2" smd circle
			(at 0.40005 0 180)
			(size 0 0)
			(layers "F.Cu" "F.Mask" "F.Paste")
			(net "GPU_3V3IO_RSVD1")
		)
	)
	(footprint ""
		(layer "F.Cu")
		(at 396.209266 -82.642202 180)
		(property "Reference" "R1756"
			(at 0 0 180)
			(layer "F.SilkS")
			(hide yes)
			(effects
				(font
					(size 1.27 1.27)
				)
			)
		)
		(property "Value" ""
			(at 0 0 180)
			(layer "F.Fab")
			(effects
				(font
					(size 1.27 1.27)
				)
			)
		)
		(duplicate_pad_numbers_are_jumpers no)
		(fp_line
			(start 0.7874 0.4064)
			(end -0.7874 0.4064)
			(stroke
				(width 0.1524)
				(type default)
			)
			(layer "F.SilkS")
		)
		(fp_line
			(start 0.7874 -0.4064)
			(end 0.7874 0.4064)
			(stroke
				(width 0.1524)
				(type default)
			)
			(layer "F.SilkS")
		)
		(fp_line
			(start -0.7874 0.4064)
			(end -0.7874 -0.4064)
			(stroke
				(width 0.1524)
				(type default)
			)
			(layer "F.SilkS")
		)
		(fp_line
			(start -0.7874 -0.4064)
			(end 0.7874 -0.4064)
			(stroke
				(width 0.1524)
				(type default)
			)
			(layer "F.SilkS")
		)
		(fp_line
			(start 0.67945 0.3048)
			(end 0.120396 0.3048)
			(stroke
				(width 0.1)
				(type default)
			)
			(layer "F.Fab")
		)
		(fp_line
			(start 0.67945 -0.3048)
			(end 0.67945 0.3048)
			(stroke
				(width 0.1)
				(type default)
			)
			(layer "F.Fab")
		)
		(fp_line
			(start 0.12065 -0.2794)
			(end 0.12065 -0.3048)
			(stroke
				(width 0.1)
				(type default)
			)
			(layer "F.Fab")
		)
		(fp_line
			(start 0.12065 -0.3048)
			(end 0.67945 -0.3048)
			(stroke
				(width 0.1)
				(type default)
			)
			(layer "F.Fab")
		)
		(fp_line
			(start 0.120396 0.3048)
			(end 0.120396 0.2794)
			(stroke
				(width 0.1)
				(type default)
			)
			(layer "F.Fab")
		)
		(fp_line
			(start 0.120396 0.2794)
			(end -0.12065 0.2794)
			(stroke
				(width 0.1)
				(type default)
			)
			(layer "F.Fab")
		)
		(fp_line
			(start -0.12065 0.3048)
			(end -0.67945 0.3048)
			(stroke
				(width 0.1)
				(type default)
			)
			(layer "F.Fab")
		)
		(fp_line
			(start -0.12065 0.2794)
			(end -0.12065 0.3048)
			(stroke
				(width 0.1)
				(type default)
			)
			(layer "F.Fab")
		)
		(fp_line
			(start -0.12065 -0.2794)
			(end 0.12065 -0.2794)
			(stroke
				(width 0.1)
				(type default)
			)
			(layer "F.Fab")
		)
		(fp_line
			(start -0.12065 -0.305054)
			(end -0.12065 -0.2794)
			(stroke
				(width 0.1)
				(type default)
			)
			(layer "F.Fab")
		)
		(fp_line
			(start -0.67945 0.3048)
			(end -0.67945 -0.305054)
			(stroke
				(width 0.1)
				(type default)
			)
			(layer "F.Fab")
		)
		(fp_line
			(start -0.67945 -0.305054)
			(end -0.12065 -0.305054)
			(stroke
				(width 0.1)
				(type default)
			)
			(layer "F.Fab")
		)
		(pad "1" smd circle
			(at -0.40005 0 180)
			(size 0 0)
			(layers "F.Cu" "F.Mask" "F.Paste")
			(net "P3V3_AUX")
		)
		(pad "2" smd circle
			(at 0.40005 0 180)
			(size 0 0)
			(layers "F.Cu" "F.Mask" "F.Paste")
			(net "SMB_BIC_I2C6_MUX_CLK_R_SDA")
		)
	)
	(footprint ""
		(layer "F.Cu")
		(at 102.790244 -10.534142 -90)
		(property "Reference" "R1654"
			(at 0 0 270)
			(layer "F.SilkS")
			(hide yes)
			(effects
				(font
					(size 1.27 1.27)
				)
			)
		)
		(property "Value" ""
			(at 0 0 270)
			(layer "F.Fab")
			(effects
				(font
					(size 1.27 1.27)
				)
			)
		)
		(duplicate_pad_numbers_are_jumpers no)
		(fp_line
			(start -0.7874 0.4064)
			(end -0.7874 -0.4064)
			(stroke
				(width 0.1524)
				(type default)
			)
			(layer "F.SilkS")
		)
		(fp_line
			(start 0.7874 0.4064)
			(end -0.7874 0.4064)
			(stroke
				(width 0.1524)
				(type default)
			)
			(layer "F.SilkS")
		)
		(fp_line
			(start -0.7874 -0.4064)
			(end 0.7874 -0.4064)
			(stroke
				(width 0.1524)
				(type default)
			)
			(layer "F.SilkS")
		)
		(fp_line
			(start 0.7874 -0.4064)
			(end 0.7874 0.4064)
			(stroke
				(width 0.1524)
				(type default)
			)
			(layer "F.SilkS")
		)
		(fp_line
			(start -0.67945 0.3048)
			(end -0.67945 -0.305054)
			(stroke
				(width 0.1)
				(type default)
			)
			(layer "F.Fab")
		)
		(fp_line
			(start -0.12065 0.3048)
			(end -0.67945 0.3048)
			(stroke
				(width 0.1)
				(type default)
			)
			(layer "F.Fab")
		)
		(fp_line
			(start 0.120396 0.3048)
			(end 0.120396 0.2794)
			(stroke
				(width 0.1)
				(type default)
			)
			(layer "F.Fab")
		)
		(fp_line
			(start 0.67945 0.3048)
			(end 0.120396 0.3048)
			(stroke
				(width 0.1)
				(type default)
			)
			(layer "F.Fab")
		)
		(fp_line
			(start -0.12065 0.2794)
			(end -0.12065 0.3048)
			(stroke
				(width 0.1)
				(type default)
			)
			(layer "F.Fab")
		)
		(fp_line
			(start 0.120396 0.2794)
			(end -0.12065 0.2794)
			(stroke
				(width 0.1)
				(type default)
			)
			(layer "F.Fab")
		)
		(fp_line
			(start -0.12065 -0.2794)
			(end 0.12065 -0.2794)
			(stroke
				(width 0.1)
				(type default)
			)
			(layer "F.Fab")
		)
		(fp_line
			(start 0.12065 -0.2794)
			(end 0.12065 -0.3048)
			(stroke
				(width 0.1)
				(type default)
			)
			(layer "F.Fab")
		)
		(fp_line
			(start 0.12065 -0.3048)
			(end 0.67945 -0.3048)
			(stroke
				(width 0.1)
				(type default)
			)
			(layer "F.Fab")
		)
		(fp_line
			(start 0.67945 -0.3048)
			(end 0.67945 0.3048)
			(stroke
				(width 0.1)
				(type default)
			)
			(layer "F.Fab")
		)
		(fp_line
			(start -0.67945 -0.305054)
			(end -0.12065 -0.305054)
			(stroke
				(width 0.1)
				(type default)
			)
			(layer "F.Fab")
		)
		(fp_line
			(start -0.12065 -0.305054)
			(end -0.12065 -0.2794)
			(stroke
				(width 0.1)
				(type default)
			)
			(layer "F.Fab")
		)
		(pad "1" smd circle
			(at -0.40005 0 270)
			(size 0 0)
			(layers "F.Cu" "F.Mask" "F.Paste")
			(net "SMB_ISO_SSD3_R_SDA")
		)
		(pad "2" smd circle
			(at 0.40005 0 270)
			(size 0 0)
			(layers "F.Cu" "F.Mask" "F.Paste")
			(net "SMB_ISO_SSD3_SDA")
		)
	)
	(footprint ""
		(layer "F.Cu")
		(at 284.467808 -53.051456)
		(property "Reference" "R4468"
			(at 0 0 0)
			(layer "F.SilkS")
			(hide yes)
			(effects
				(font
					(size 1.27 1.27)
				)
			)
		)
		(property "Value" ""
			(at 0 0 0)
			(layer "F.Fab")
			(effects
				(font
					(size 1.27 1.27)
				)
			)
		)
		(duplicate_pad_numbers_are_jumpers no)
		(fp_line
			(start -0.7874 -0.4064)
			(end 0.7874 -0.4064)
			(stroke
				(width 0.1524)
				(type default)
			)
			(layer "F.SilkS")
		)
		(fp_line
			(start -0.7874 0.4064)
			(end -0.7874 -0.4064)
			(stroke
				(width 0.1524)
				(type default)
			)
			(layer "F.SilkS")
		)
		(fp_line
			(start 0.7874 -0.4064)
			(end 0.7874 0.4064)
			(stroke
				(width 0.1524)
				(type default)
			)
			(layer "F.SilkS")
		)
		(fp_line
			(start 0.7874 0.4064)
			(end -0.7874 0.4064)
			(stroke
				(width 0.1524)
				(type default)
			)
			(layer "F.SilkS")
		)
		(fp_line
			(start -0.67945 -0.305054)
			(end -0.12065 -0.305054)
			(stroke
				(width 0.1)
				(type default)
			)
			(layer "F.Fab")
		)
		(fp_line
			(start -0.67945 0.3048)
			(end -0.67945 -0.305054)
			(stroke
				(width 0.1)
				(type default)
			)
			(layer "F.Fab")
		)
		(fp_line
			(start -0.12065 -0.305054)
			(end -0.12065 -0.2794)
			(stroke
				(width 0.1)
				(type default)
			)
			(layer "F.Fab")
		)
		(fp_line
			(start -0.12065 -0.2794)
			(end 0.12065 -0.2794)
			(stroke
				(width 0.1)
				(type default)
			)
			(layer "F.Fab")
		)
		(fp_line
			(start -0.12065 0.2794)
			(end -0.12065 0.3048)
			(stroke
				(width 0.1)
				(type default)
			)
			(layer "F.Fab")
		)
		(fp_line
			(start -0.12065 0.3048)
			(end -0.67945 0.3048)
			(stroke
				(width 0.1)
				(type default)
			)
			(layer "F.Fab")
		)
		(fp_line
			(start 0.120396 0.2794)
			(end -0.12065 0.2794)
			(stroke
				(width 0.1)
				(type default)
			)
			(layer "F.Fab")
		)
		(fp_line
			(start 0.120396 0.3048)
			(end 0.120396 0.2794)
			(stroke
				(width 0.1)
				(type default)
			)
			(layer "F.Fab")
		)
		(fp_line
			(start 0.12065 -0.3048)
			(end 0.67945 -0.3048)
			(stroke
				(width 0.1)
				(type default)
			)
			(layer "F.Fab")
		)
		(fp_line
			(start 0.12065 -0.2794)
			(end 0.12065 -0.3048)
			(stroke
				(width 0.1)
				(type default)
			)
			(layer "F.Fab")
		)
		(fp_line
			(start 0.67945 -0.3048)
			(end 0.67945 0.3048)
			(stroke
				(width 0.1)
				(type default)
			)
			(layer "F.Fab")
		)
		(fp_line
			(start 0.67945 0.3048)
			(end 0.120396 0.3048)
			(stroke
				(width 0.1)
				(type default)
			)
			(layer "F.Fab")
		)
		(pad "1" smd circle
			(at -0.40005 0)
			(size 0 0)
			(layers "F.Cu" "F.Mask" "F.Paste")
			(net "PWRGD_P12V_SSD9")
		)
		(pad "2" smd circle
			(at 0.40005 0)
			(size 0 0)
			(layers "F.Cu" "F.Mask" "F.Paste")
			(net "PWRGD_P12V_SSD9_R")
		)
	)
	(footprint ""
		(layer "F.Cu")
		(at 188.27496 -48.753014 180)
		(property "Reference" "C318"
			(at 0 0 180)
			(layer "F.SilkS")
			(hide yes)
			(effects
				(font
					(size 1.27 1.27)
				)
			)
		)
		(property "Value" ""
			(at 0 0 180)
			(layer "F.Fab")
			(effects
				(font
					(size 1.27 1.27)
				)
			)
		)
		(duplicate_pad_numbers_are_jumpers no)
		(fp_line
			(start 0.7874 0.4064)
			(end -0.7874 0.4064)
			(stroke
				(width 0.1524)
				(type default)
			)
			(layer "F.SilkS")
		)
		(fp_line
			(start 0.7874 -0.4064)
			(end 0.7874 0.4064)
			(stroke
				(width 0.1524)
				(type default)
			)
			(layer "F.SilkS")
		)
		(fp_line
			(start -0.7874 0.4064)
			(end -0.7874 -0.4064)
			(stroke
				(width 0.1524)
				(type default)
			)
			(layer "F.SilkS")
		)
		(fp_line
			(start -0.7874 -0.4064)
			(end 0.7874 -0.4064)
			(stroke
				(width 0.1524)
				(type default)
			)
			(layer "F.SilkS")
		)
		(fp_line
			(start 0.67945 0.3048)
			(end 0.120396 0.3048)
			(stroke
				(width 0.1)
				(type default)
			)
			(layer "F.Fab")
		)
		(fp_line
			(start 0.67945 -0.3048)
			(end 0.67945 0.3048)
			(stroke
				(width 0.1)
				(type default)
			)
			(layer "F.Fab")
		)
		(fp_line
			(start 0.12065 -0.2794)
			(end 0.12065 -0.3048)
			(stroke
				(width 0.1)
				(type default)
			)
			(layer "F.Fab")
		)
		(fp_line
			(start 0.12065 -0.3048)
			(end 0.67945 -0.3048)
			(stroke
				(width 0.1)
				(type default)
			)
			(layer "F.Fab")
		)
		(fp_line
			(start 0.120396 0.3048)
			(end 0.120396 0.2794)
			(stroke
				(width 0.1)
				(type default)
			)
			(layer "F.Fab")
		)
		(fp_line
			(start 0.120396 0.2794)
			(end -0.12065 0.2794)
			(stroke
				(width 0.1)
				(type default)
			)
			(layer "F.Fab")
		)
		(fp_line
			(start -0.12065 0.3048)
			(end -0.67945 0.3048)
			(stroke
				(width 0.1)
				(type default)
			)
			(layer "F.Fab")
		)
		(fp_line
			(start -0.12065 0.2794)
			(end -0.12065 0.3048)
			(stroke
				(width 0.1)
				(type default)
			)
			(layer "F.Fab")
		)
		(fp_line
			(start -0.12065 -0.2794)
			(end 0.12065 -0.2794)
			(stroke
				(width 0.1)
				(type default)
			)
			(layer "F.Fab")
		)
		(fp_line
			(start -0.12065 -0.305054)
			(end -0.12065 -0.2794)
			(stroke
				(width 0.1)
				(type default)
			)
			(layer "F.Fab")
		)
		(fp_line
			(start -0.67945 0.3048)
			(end -0.67945 -0.305054)
			(stroke
				(width 0.1)
				(type default)
			)
			(layer "F.Fab")
		)
		(fp_line
			(start -0.67945 -0.305054)
			(end -0.12065 -0.305054)
			(stroke
				(width 0.1)
				(type default)
			)
			(layer "F.Fab")
		)
		(pad "1" smd circle
			(at -0.40005 0 180)
			(size 0 0)
			(layers "F.Cu" "F.Mask" "F.Paste")
			(net "P3V3_AUX")
		)
		(pad "2" smd circle
			(at 0.40005 0 180)
			(size 0 0)
			(layers "F.Cu" "F.Mask" "F.Paste")
			(net "GND")
		)
	)
	(footprint ""
		(layer "F.Cu")
		(at 59.421268 -393.16279 -90)
		(property "Reference" "C4038"
			(at 0 0 270)
			(layer "F.SilkS")
			(hide yes)
			(effects
				(font
					(size 1.27 1.27)
				)
			)
		)
		(property "Value" ""
			(at 0 0 270)
			(layer "F.Fab")
			(effects
				(font
					(size 1.27 1.27)
				)
			)
		)
		(duplicate_pad_numbers_are_jumpers no)
		(fp_line
			(start -0.7874 0.4064)
			(end -0.7874 -0.4064)
			(stroke
				(width 0.1524)
				(type default)
			)
			(layer "F.SilkS")
		)
		(fp_line
			(start 0.7874 0.4064)
			(end -0.7874 0.4064)
			(stroke
				(width 0.1524)
				(type default)
			)
			(layer "F.SilkS")
		)
		(fp_line
			(start -0.7874 -0.4064)
			(end 0.7874 -0.4064)
			(stroke
				(width 0.1524)
				(type default)
			)
			(layer "F.SilkS")
		)
		(fp_line
			(start 0.7874 -0.4064)
			(end 0.7874 0.4064)
			(stroke
				(width 0.1524)
				(type default)
			)
			(layer "F.SilkS")
		)
		(fp_line
			(start -0.67945 0.3048)
			(end -0.67945 -0.305054)
			(stroke
				(width 0.1)
				(type default)
			)
			(layer "F.Fab")
		)
		(fp_line
			(start -0.12065 0.3048)
			(end -0.67945 0.3048)
			(stroke
				(width 0.1)
				(type default)
			)
			(layer "F.Fab")
		)
		(fp_line
			(start 0.120396 0.3048)
			(end 0.120396 0.2794)
			(stroke
				(width 0.1)
				(type default)
			)
			(layer "F.Fab")
		)
		(fp_line
			(start 0.67945 0.3048)
			(end 0.120396 0.3048)
			(stroke
				(width 0.1)
				(type default)
			)
			(layer "F.Fab")
		)
		(fp_line
			(start -0.12065 0.2794)
			(end -0.12065 0.3048)
			(stroke
				(width 0.1)
				(type default)
			)
			(layer "F.Fab")
		)
		(fp_line
			(start 0.120396 0.2794)
			(end -0.12065 0.2794)
			(stroke
				(width 0.1)
				(type default)
			)
			(layer "F.Fab")
		)
		(fp_line
			(start -0.12065 -0.2794)
			(end 0.12065 -0.2794)
			(stroke
				(width 0.1)
				(type default)
			)
			(layer "F.Fab")
		)
		(fp_line
			(start 0.12065 -0.2794)
			(end 0.12065 -0.3048)
			(stroke
				(width 0.1)
				(type default)
			)
			(layer "F.Fab")
		)
		(fp_line
			(start 0.12065 -0.3048)
			(end 0.67945 -0.3048)
			(stroke
				(width 0.1)
				(type default)
			)
			(layer "F.Fab")
		)
		(fp_line
			(start 0.67945 -0.3048)
			(end 0.67945 0.3048)
			(stroke
				(width 0.1)
				(type default)
			)
			(layer "F.Fab")
		)
		(fp_line
			(start -0.67945 -0.305054)
			(end -0.12065 -0.305054)
			(stroke
				(width 0.1)
				(type default)
			)
			(layer "F.Fab")
		)
		(fp_line
			(start -0.12065 -0.305054)
			(end -0.12065 -0.2794)
			(stroke
				(width 0.1)
				(type default)
			)
			(layer "F.Fab")
		)
		(pad "1" smd circle
			(at -0.40005 0 270)
			(size 0 0)
			(layers "F.Cu" "F.Mask" "F.Paste")
			(net "GND")
		)
		(pad "2" smd circle
			(at 0.40005 0 270)
			(size 0 0)
			(layers "F.Cu" "F.Mask" "F.Paste")
			(net "RST_GPU_FPGA_PEX_RST_N")
		)
	)
	(footprint ""
		(layer "F.Cu")
		(at 234.499912 -373.9134 180)
		(property "Reference" "PR36"
			(at 0 0 180)
			(layer "F.SilkS")
			(hide yes)
			(effects
				(font
					(size 1.27 1.27)
				)
			)
		)
		(property "Value" ""
			(at 0 0 180)
			(layer "F.Fab")
			(effects
				(font
					(size 1.27 1.27)
				)
			)
		)
		(duplicate_pad_numbers_are_jumpers no)
		(fp_line
			(start 0.7874 0.4064)
			(end -0.7874 0.4064)
			(stroke
				(width 0.1524)
				(type default)
			)
			(layer "F.SilkS")
		)
		(fp_line
			(start 0.7874 -0.4064)
			(end 0.7874 0.4064)
			(stroke
				(width 0.1524)
				(type default)
			)
			(layer "F.SilkS")
		)
		(fp_line
			(start -0.7874 0.4064)
			(end -0.7874 -0.4064)
			(stroke
				(width 0.1524)
				(type default)
			)
			(layer "F.SilkS")
		)
		(fp_line
			(start -0.7874 -0.4064)
			(end 0.7874 -0.4064)
			(stroke
				(width 0.1524)
				(type default)
			)
			(layer "F.SilkS")
		)
		(fp_line
			(start 0.67945 0.3048)
			(end 0.120396 0.3048)
			(stroke
				(width 0.1)
				(type default)
			)
			(layer "F.Fab")
		)
		(fp_line
			(start 0.67945 -0.3048)
			(end 0.67945 0.3048)
			(stroke
				(width 0.1)
				(type default)
			)
			(layer "F.Fab")
		)
		(fp_line
			(start 0.12065 -0.2794)
			(end 0.12065 -0.3048)
			(stroke
				(width 0.1)
				(type default)
			)
			(layer "F.Fab")
		)
		(fp_line
			(start 0.12065 -0.3048)
			(end 0.67945 -0.3048)
			(stroke
				(width 0.1)
				(type default)
			)
			(layer "F.Fab")
		)
		(fp_line
			(start 0.120396 0.3048)
			(end 0.120396 0.2794)
			(stroke
				(width 0.1)
				(type default)
			)
			(layer "F.Fab")
		)
		(fp_line
			(start 0.120396 0.2794)
			(end -0.12065 0.2794)
			(stroke
				(width 0.1)
				(type default)
			)
			(layer "F.Fab")
		)
		(fp_line
			(start -0.12065 0.3048)
			(end -0.67945 0.3048)
			(stroke
				(width 0.1)
				(type default)
			)
			(layer "F.Fab")
		)
		(fp_line
			(start -0.12065 0.2794)
			(end -0.12065 0.3048)
			(stroke
				(width 0.1)
				(type default)
			)
			(layer "F.Fab")
		)
		(fp_line
			(start -0.12065 -0.2794)
			(end 0.12065 -0.2794)
			(stroke
				(width 0.1)
				(type default)
			)
			(layer "F.Fab")
		)
		(fp_line
			(start -0.12065 -0.305054)
			(end -0.12065 -0.2794)
			(stroke
				(width 0.1)
				(type default)
			)
			(layer "F.Fab")
		)
		(fp_line
			(start -0.67945 0.3048)
			(end -0.67945 -0.305054)
			(stroke
				(width 0.1)
				(type default)
			)
			(layer "F.Fab")
		)
		(fp_line
			(start -0.67945 -0.305054)
			(end -0.12065 -0.305054)
			(stroke
				(width 0.1)
				(type default)
			)
			(layer "F.Fab")
		)
		(pad "1" smd circle
			(at -0.40005 0 180)
			(size 0 0)
			(layers "F.Cu" "F.Mask" "F.Paste")
			(net "AGND_HSC")
		)
		(pad "2" smd circle
			(at 0.40005 0 180)
			(size 0 0)
			(layers "F.Cu" "F.Mask" "F.Paste")
			(net "HSC_MODE_2")
		)
	)
	(footprint ""
		(layer "F.Cu")
		(at 430.961546 -145.311114 180)
		(property "Reference" "C646"
			(at 0 0 180)
			(layer "F.SilkS")
			(hide yes)
			(effects
				(font
					(size 1.27 1.27)
				)
			)
		)
		(property "Value" ""
			(at 0 0 180)
			(layer "F.Fab")
			(effects
				(font
					(size 1.27 1.27)
				)
			)
		)
		(duplicate_pad_numbers_are_jumpers no)
		(fp_line
			(start 0.299974 0.150114)
			(end -0.299974 0.150114)
			(stroke
				(width 0.1)
				(type default)
			)
			(layer "F.Fab")
		)
		(fp_line
			(start 0.299974 -0.150114)
			(end 0.299974 0.150114)
			(stroke
				(width 0.1)
				(type default)
			)
			(layer "F.Fab")
		)
		(fp_line
			(start -0.299974 0.150114)
			(end -0.299974 -0.150114)
			(stroke
				(width 0.1)
				(type default)
			)
			(layer "F.Fab")
		)
		(fp_line
			(start -0.299974 -0.150114)
			(end 0.299974 -0.150114)
			(stroke
				(width 0.1)
				(type default)
			)
			(layer "F.Fab")
		)
		(pad "1" smd rect
			(at -0.2667 0 180)
			(size 0.3048 0.381)
			(layers "F.Cu" "F.Mask" "F.Paste")
			(net "P5E_PEX3_STN0_TX_DP<9>")
		)
		(pad "2" smd rect
			(at 0.2667 0 180)
			(size 0.3048 0.381)
			(layers "F.Cu" "F.Mask" "F.Paste")
			(net "P5E_PEX3_STN0_TX_C_DP<9>")
		)
	)
	(footprint ""
		(layer "F.Cu")
		(at 394.814552 -66.32194 90)
		(property "Reference" "R6011"
			(at 0 0 90)
			(layer "F.SilkS")
			(hide yes)
			(effects
				(font
					(size 1.27 1.27)
				)
			)
		)
		(property "Value" ""
			(at 0 0 90)
			(layer "F.Fab")
			(effects
				(font
					(size 1.27 1.27)
				)
			)
		)
		(duplicate_pad_numbers_are_jumpers no)
		(fp_line
			(start 0.7874 -0.4064)
			(end 0.7874 0.4064)
			(stroke
				(width 0.1524)
				(type default)
			)
			(layer "F.SilkS")
		)
		(fp_line
			(start -0.7874 -0.4064)
			(end 0.7874 -0.4064)
			(stroke
				(width 0.1524)
				(type default)
			)
			(layer "F.SilkS")
		)
		(fp_line
			(start 0.7874 0.4064)
			(end -0.7874 0.4064)
			(stroke
				(width 0.1524)
				(type default)
			)
			(layer "F.SilkS")
		)
		(fp_line
			(start -0.7874 0.4064)
			(end -0.7874 -0.4064)
			(stroke
				(width 0.1524)
				(type default)
			)
			(layer "F.SilkS")
		)
		(fp_line
			(start -0.12065 -0.305054)
			(end -0.12065 -0.2794)
			(stroke
				(width 0.1)
				(type default)
			)
			(layer "F.Fab")
		)
		(fp_line
			(start -0.67945 -0.305054)
			(end -0.12065 -0.305054)
			(stroke
				(width 0.1)
				(type default)
			)
			(layer "F.Fab")
		)
		(fp_line
			(start 0.67945 -0.3048)
			(end 0.67945 0.3048)
			(stroke
				(width 0.1)
				(type default)
			)
			(layer "F.Fab")
		)
		(fp_line
			(start 0.12065 -0.3048)
			(end 0.67945 -0.3048)
			(stroke
				(width 0.1)
				(type default)
			)
			(layer "F.Fab")
		)
		(fp_line
			(start 0.12065 -0.2794)
			(end 0.12065 -0.3048)
			(stroke
				(width 0.1)
				(type default)
			)
			(layer "F.Fab")
		)
		(fp_line
			(start -0.12065 -0.2794)
			(end 0.12065 -0.2794)
			(stroke
				(width 0.1)
				(type default)
			)
			(layer "F.Fab")
		)
		(fp_line
			(start 0.120396 0.2794)
			(end -0.12065 0.2794)
			(stroke
				(width 0.1)
				(type default)
			)
			(layer "F.Fab")
		)
		(fp_line
			(start -0.12065 0.2794)
			(end -0.12065 0.3048)
			(stroke
				(width 0.1)
				(type default)
			)
			(layer "F.Fab")
		)
		(fp_line
			(start 0.67945 0.3048)
			(end 0.120396 0.3048)
			(stroke
				(width 0.1)
				(type default)
			)
			(layer "F.Fab")
		)
		(fp_line
			(start 0.120396 0.3048)
			(end 0.120396 0.2794)
			(stroke
				(width 0.1)
				(type default)
			)
			(layer "F.Fab")
		)
		(fp_line
			(start -0.12065 0.3048)
			(end -0.67945 0.3048)
			(stroke
				(width 0.1)
				(type default)
			)
			(layer "F.Fab")
		)
		(fp_line
			(start -0.67945 0.3048)
			(end -0.67945 -0.305054)
			(stroke
				(width 0.1)
				(type default)
			)
			(layer "F.Fab")
		)
		(pad "1" smd circle
			(at -0.40005 0 90)
			(size 0 0)
			(layers "F.Cu" "F.Mask" "F.Paste")
			(net "SSD13_PWR_EN_R")
		)
		(pad "2" smd circle
			(at 0.40005 0 90)
			(size 0 0)
			(layers "F.Cu" "F.Mask" "F.Paste")
			(net "P12V_SSD13_CO_EN")
		)
	)
	(footprint ""
		(layer "F.Cu")
		(at 148.675852 -36.915598 -90)
		(property "Reference" "R5556"
			(at 0 0 270)
			(layer "F.SilkS")
			(hide yes)
			(effects
				(font
					(size 1.27 1.27)
				)
			)
		)
		(property "Value" ""
			(at 0 0 270)
			(layer "F.Fab")
			(effects
				(font
					(size 1.27 1.27)
				)
			)
		)
		(duplicate_pad_numbers_are_jumpers no)
		(fp_line
			(start -0.7874 0.4064)
			(end -0.7874 -0.4064)
			(stroke
				(width 0.1524)
				(type default)
			)
			(layer "F.SilkS")
		)
		(fp_line
			(start 0.7874 0.4064)
			(end -0.7874 0.4064)
			(stroke
				(width 0.1524)
				(type default)
			)
			(layer "F.SilkS")
		)
		(fp_line
			(start -0.7874 -0.4064)
			(end 0.7874 -0.4064)
			(stroke
				(width 0.1524)
				(type default)
			)
			(layer "F.SilkS")
		)
		(fp_line
			(start 0.7874 -0.4064)
			(end 0.7874 0.4064)
			(stroke
				(width 0.1524)
				(type default)
			)
			(layer "F.SilkS")
		)
		(fp_line
			(start -0.67945 0.3048)
			(end -0.67945 -0.305054)
			(stroke
				(width 0.1)
				(type default)
			)
			(layer "F.Fab")
		)
		(fp_line
			(start -0.12065 0.3048)
			(end -0.67945 0.3048)
			(stroke
				(width 0.1)
				(type default)
			)
			(layer "F.Fab")
		)
		(fp_line
			(start 0.120396 0.3048)
			(end 0.120396 0.2794)
			(stroke
				(width 0.1)
				(type default)
			)
			(layer "F.Fab")
		)
		(fp_line
			(start 0.67945 0.3048)
			(end 0.120396 0.3048)
			(stroke
				(width 0.1)
				(type default)
			)
			(layer "F.Fab")
		)
		(fp_line
			(start -0.12065 0.2794)
			(end -0.12065 0.3048)
			(stroke
				(width 0.1)
				(type default)
			)
			(layer "F.Fab")
		)
		(fp_line
			(start 0.120396 0.2794)
			(end -0.12065 0.2794)
			(stroke
				(width 0.1)
				(type default)
			)
			(layer "F.Fab")
		)
		(fp_line
			(start -0.12065 -0.2794)
			(end 0.12065 -0.2794)
			(stroke
				(width 0.1)
				(type default)
			)
			(layer "F.Fab")
		)
		(fp_line
			(start 0.12065 -0.2794)
			(end 0.12065 -0.3048)
			(stroke
				(width 0.1)
				(type default)
			)
			(layer "F.Fab")
		)
		(fp_line
			(start 0.12065 -0.3048)
			(end 0.67945 -0.3048)
			(stroke
				(width 0.1)
				(type default)
			)
			(layer "F.Fab")
		)
		(fp_line
			(start 0.67945 -0.3048)
			(end 0.67945 0.3048)
			(stroke
				(width 0.1)
				(type default)
			)
			(layer "F.Fab")
		)
		(fp_line
			(start -0.67945 -0.305054)
			(end -0.12065 -0.305054)
			(stroke
				(width 0.1)
				(type default)
			)
			(layer "F.Fab")
		)
		(fp_line
			(start -0.12065 -0.305054)
			(end -0.12065 -0.2794)
			(stroke
				(width 0.1)
				(type default)
			)
			(layer "F.Fab")
		)
		(pad "1" smd circle
			(at -0.40005 0 270)
			(size 0 0)
			(layers "F.Cu" "F.Mask" "F.Paste")
			(net "PRSNT_SSD5_R1_N")
		)
		(pad "2" smd circle
			(at 0.40005 0 270)
			(size 0 0)
			(layers "F.Cu" "F.Mask" "F.Paste")
			(net "PRSNT_SSD5_R_N")
		)
	)
	(footprint ""
		(layer "F.Cu")
		(at 247.897904 -122.780552)
		(property "Reference" "PC474"
			(at 0 0 0)
			(layer "F.SilkS")
			(hide yes)
			(effects
				(font
					(size 1.27 1.27)
				)
			)
		)
		(property "Value" ""
			(at 0 0 0)
			(layer "F.Fab")
			(effects
				(font
					(size 1.27 1.27)
				)
			)
		)
		(duplicate_pad_numbers_are_jumpers no)
		(fp_line
			(start -0.7874 -0.4064)
			(end 0.7874 -0.4064)
			(stroke
				(width 0.1524)
				(type default)
			)
			(layer "F.SilkS")
		)
		(fp_line
			(start -0.7874 0.4064)
			(end -0.7874 -0.4064)
			(stroke
				(width 0.1524)
				(type default)
			)
			(layer "F.SilkS")
		)
		(fp_line
			(start 0.7874 -0.4064)
			(end 0.7874 0.4064)
			(stroke
				(width 0.1524)
				(type default)
			)
			(layer "F.SilkS")
		)
		(fp_line
			(start 0.7874 0.4064)
			(end -0.7874 0.4064)
			(stroke
				(width 0.1524)
				(type default)
			)
			(layer "F.SilkS")
		)
		(fp_line
			(start -0.67945 -0.305054)
			(end -0.12065 -0.305054)
			(stroke
				(width 0.1)
				(type default)
			)
			(layer "F.Fab")
		)
		(fp_line
			(start -0.67945 0.3048)
			(end -0.67945 -0.305054)
			(stroke
				(width 0.1)
				(type default)
			)
			(layer "F.Fab")
		)
		(fp_line
			(start -0.12065 -0.305054)
			(end -0.12065 -0.2794)
			(stroke
				(width 0.1)
				(type default)
			)
			(layer "F.Fab")
		)
		(fp_line
			(start -0.12065 -0.2794)
			(end 0.12065 -0.2794)
			(stroke
				(width 0.1)
				(type default)
			)
			(layer "F.Fab")
		)
		(fp_line
			(start -0.12065 0.2794)
			(end -0.12065 0.3048)
			(stroke
				(width 0.1)
				(type default)
			)
			(layer "F.Fab")
		)
		(fp_line
			(start -0.12065 0.3048)
			(end -0.67945 0.3048)
			(stroke
				(width 0.1)
				(type default)
			)
			(layer "F.Fab")
		)
		(fp_line
			(start 0.120396 0.2794)
			(end -0.12065 0.2794)
			(stroke
				(width 0.1)
				(type default)
			)
			(layer "F.Fab")
		)
		(fp_line
			(start 0.120396 0.3048)
			(end 0.120396 0.2794)
			(stroke
				(width 0.1)
				(type default)
			)
			(layer "F.Fab")
		)
		(fp_line
			(start 0.12065 -0.3048)
			(end 0.67945 -0.3048)
			(stroke
				(width 0.1)
				(type default)
			)
			(layer "F.Fab")
		)
		(fp_line
			(start 0.12065 -0.2794)
			(end 0.12065 -0.3048)
			(stroke
				(width 0.1)
				(type default)
			)
			(layer "F.Fab")
		)
		(fp_line
			(start 0.67945 -0.3048)
			(end 0.67945 0.3048)
			(stroke
				(width 0.1)
				(type default)
			)
			(layer "F.Fab")
		)
		(fp_line
			(start 0.67945 0.3048)
			(end 0.120396 0.3048)
			(stroke
				(width 0.1)
				(type default)
			)
			(layer "F.Fab")
		)
		(pad "1" smd circle
			(at -0.40005 0)
			(size 0 0)
			(layers "F.Cu" "F.Mask" "F.Paste")
			(net "P3V3_AUX")
		)
		(pad "2" smd circle
			(at 0.40005 0)
			(size 0 0)
			(layers "F.Cu" "F.Mask" "F.Paste")
			(net "GND")
		)
	)
	(footprint ""
		(layer "F.Cu")
		(at 240.5888 -213.3854 -90)
		(property "Reference" "R6592"
			(at 0 0 270)
			(layer "F.SilkS")
			(hide yes)
			(effects
				(font
					(size 1.27 1.27)
				)
			)
		)
		(property "Value" ""
			(at 0 0 270)
			(layer "F.Fab")
			(effects
				(font
					(size 1.27 1.27)
				)
			)
		)
		(duplicate_pad_numbers_are_jumpers no)
		(fp_line
			(start -0.7874 0.4064)
			(end -0.7874 -0.4064)
			(stroke
				(width 0.1524)
				(type default)
			)
			(layer "F.SilkS")
		)
		(fp_line
			(start 0.7874 0.4064)
			(end -0.7874 0.4064)
			(stroke
				(width 0.1524)
				(type default)
			)
			(layer "F.SilkS")
		)
		(fp_line
			(start -0.7874 -0.4064)
			(end 0.7874 -0.4064)
			(stroke
				(width 0.1524)
				(type default)
			)
			(layer "F.SilkS")
		)
		(fp_line
			(start 0.7874 -0.4064)
			(end 0.7874 0.4064)
			(stroke
				(width 0.1524)
				(type default)
			)
			(layer "F.SilkS")
		)
		(fp_line
			(start -0.67945 0.3048)
			(end -0.67945 -0.305054)
			(stroke
				(width 0.1)
				(type default)
			)
			(layer "F.Fab")
		)
		(fp_line
			(start -0.12065 0.3048)
			(end -0.67945 0.3048)
			(stroke
				(width 0.1)
				(type default)
			)
			(layer "F.Fab")
		)
		(fp_line
			(start 0.120396 0.3048)
			(end 0.120396 0.2794)
			(stroke
				(width 0.1)
				(type default)
			)
			(layer "F.Fab")
		)
		(fp_line
			(start 0.67945 0.3048)
			(end 0.120396 0.3048)
			(stroke
				(width 0.1)
				(type default)
			)
			(layer "F.Fab")
		)
		(fp_line
			(start -0.12065 0.2794)
			(end -0.12065 0.3048)
			(stroke
				(width 0.1)
				(type default)
			)
			(layer "F.Fab")
		)
		(fp_line
			(start 0.120396 0.2794)
			(end -0.12065 0.2794)
			(stroke
				(width 0.1)
				(type default)
			)
			(layer "F.Fab")
		)
		(fp_line
			(start -0.12065 -0.2794)
			(end 0.12065 -0.2794)
			(stroke
				(width 0.1)
				(type default)
			)
			(layer "F.Fab")
		)
		(fp_line
			(start 0.12065 -0.2794)
			(end 0.12065 -0.3048)
			(stroke
				(width 0.1)
				(type default)
			)
			(layer "F.Fab")
		)
		(fp_line
			(start 0.12065 -0.3048)
			(end 0.67945 -0.3048)
			(stroke
				(width 0.1)
				(type default)
			)
			(layer "F.Fab")
		)
		(fp_line
			(start 0.67945 -0.3048)
			(end 0.67945 0.3048)
			(stroke
				(width 0.1)
				(type default)
			)
			(layer "F.Fab")
		)
		(fp_line
			(start -0.67945 -0.305054)
			(end -0.12065 -0.305054)
			(stroke
				(width 0.1)
				(type default)
			)
			(layer "F.Fab")
		)
		(fp_line
			(start -0.12065 -0.305054)
			(end -0.12065 -0.2794)
			(stroke
				(width 0.1)
				(type default)
			)
			(layer "F.Fab")
		)
		(pad "1" smd circle
			(at -0.40005 0 270)
			(size 0 0)
			(layers "F.Cu" "F.Mask" "F.Paste")
			(net "P1V8_PLL0_PEX1_SCALED")
		)
		(pad "2" smd circle
			(at 0.40005 0 270)
			(size 0 0)
			(layers "F.Cu" "F.Mask" "F.Paste")
			(net "GND")
		)
	)
	(footprint ""
		(layer "F.Cu")
		(at 5.073396 -283.624782 180)
		(property "Reference" "PC217"
			(at 0 0 180)
			(layer "F.SilkS")
			(hide yes)
			(effects
				(font
					(size 1.27 1.27)
				)
			)
		)
		(property "Value" ""
			(at 0 0 180)
			(layer "F.Fab")
			(effects
				(font
					(size 1.27 1.27)
				)
			)
		)
		(duplicate_pad_numbers_are_jumpers no)
		(fp_line
			(start 2.750058 2.750058)
			(end 2.750058 0.9398)
			(stroke
				(width 0.1524)
				(type default)
			)
			(layer "F.SilkS")
		)
		(fp_line
			(start 2.750058 -0.9398)
			(end 2.750058 -2.750058)
			(stroke
				(width 0.1524)
				(type default)
			)
			(layer "F.SilkS")
		)
		(fp_line
			(start 2.750058 -2.750058)
			(end -1.988058 -2.750058)
			(stroke
				(width 0.1524)
				(type default)
			)
			(layer "F.SilkS")
		)
		(fp_line
			(start -1.988058 2.750058)
			(end 2.750058 2.750058)
			(stroke
				(width 0.1524)
				(type default)
			)
			(layer "F.SilkS")
		)
		(fp_line
			(start -1.988058 -2.750058)
			(end -2.750058 -1.988058)
			(stroke
				(width 0.1524)
				(type default)
			)
			(layer "F.SilkS")
		)
		(fp_line
			(start -2.750058 1.988058)
			(end -1.988058 2.750058)
			(stroke
				(width 0.1524)
				(type default)
			)
			(layer "F.SilkS")
		)
		(fp_line
			(start -2.750058 0.9398)
			(end -2.750058 1.988058)
			(stroke
				(width 0.1524)
				(type default)
			)
			(layer "F.SilkS")
		)
		(fp_line
			(start -2.750058 -1.988058)
			(end -2.750058 -0.9398)
			(stroke
				(width 0.1524)
				(type default)
			)
			(layer "F.SilkS")
		)
		(fp_line
			(start 2.750058 2.750058)
			(end 2.750058 -2.750058)
			(stroke
				(width 0.1)
				(type default)
			)
			(layer "F.Fab")
		)
		(fp_line
			(start 2.750058 -2.750058)
			(end -2.750058 -2.750058)
			(stroke
				(width 0.1)
				(type default)
			)
			(layer "F.Fab")
		)
		(fp_line
			(start -2.750058 2.750058)
			(end 2.750058 2.750058)
			(stroke
				(width 0.1)
				(type default)
			)
			(layer "F.Fab")
		)
		(fp_line
			(start -2.750058 -2.750058)
			(end -2.750058 2.750058)
			(stroke
				(width 0.1)
				(type default)
			)
			(layer "F.Fab")
		)
		(pad "1" smd rect
			(at -2.199894 0 270)
			(size 1.6002 3.0226)
			(layers "F.Cu" "F.Mask" "F.Paste")
			(net "P1V25_PEX0_R")
		)
		(pad "2" smd rect
			(at 2.199894 0 270)
			(size 1.6002 3.0226)
			(layers "F.Cu" "F.Mask" "F.Paste")
			(net "GND")
		)
	)
	(footprint ""
		(layer "F.Cu")
		(at 51.311048 -343.952322 90)
		(property "Reference" "C2181"
			(at 0 0 90)
			(layer "F.SilkS")
			(hide yes)
			(effects
				(font
					(size 1.27 1.27)
				)
			)
		)
		(property "Value" ""
			(at 0 0 90)
			(layer "F.Fab")
			(effects
				(font
					(size 1.27 1.27)
				)
			)
		)
		(duplicate_pad_numbers_are_jumpers no)
		(fp_line
			(start 0.299974 -0.150114)
			(end 0.299974 0.150114)
			(stroke
				(width 0.1)
				(type default)
			)
			(layer "F.Fab")
		)
		(fp_line
			(start -0.299974 -0.150114)
			(end 0.299974 -0.150114)
			(stroke
				(width 0.1)
				(type default)
			)
			(layer "F.Fab")
		)
		(fp_line
			(start 0.299974 0.150114)
			(end -0.299974 0.150114)
			(stroke
				(width 0.1)
				(type default)
			)
			(layer "F.Fab")
		)
		(fp_line
			(start -0.299974 0.150114)
			(end -0.299974 -0.150114)
			(stroke
				(width 0.1)
				(type default)
			)
			(layer "F.Fab")
		)
		(pad "1" smd rect
			(at -0.2667 0 90)
			(size 0.3048 0.381)
			(layers "F.Cu" "F.Mask" "F.Paste")
			(net "P5E_PEX0_STN4_TX_DN<65>")
		)
		(pad "2" smd rect
			(at 0.2667 0 90)
			(size 0.3048 0.381)
			(layers "F.Cu" "F.Mask" "F.Paste")
			(net "P5E_PEX0_STN4_TX_C_DN<65>")
		)
	)
	(footprint ""
		(layer "F.Cu")
		(at 376.809 -172.11802)
		(property "Reference" "R4713"
			(at 0 0 0)
			(layer "F.SilkS")
			(hide yes)
			(effects
				(font
					(size 1.27 1.27)
				)
			)
		)
		(property "Value" ""
			(at 0 0 0)
			(layer "F.Fab")
			(effects
				(font
					(size 1.27 1.27)
				)
			)
		)
		(duplicate_pad_numbers_are_jumpers no)
		(fp_line
			(start -0.7874 -0.4064)
			(end 0.7874 -0.4064)
			(stroke
				(width 0.1524)
				(type default)
			)
			(layer "F.SilkS")
		)
		(fp_line
			(start -0.7874 0.4064)
			(end -0.7874 -0.4064)
			(stroke
				(width 0.1524)
				(type default)
			)
			(layer "F.SilkS")
		)
		(fp_line
			(start 0.7874 -0.4064)
			(end 0.7874 0.4064)
			(stroke
				(width 0.1524)
				(type default)
			)
			(layer "F.SilkS")
		)
		(fp_line
			(start 0.7874 0.4064)
			(end -0.7874 0.4064)
			(stroke
				(width 0.1524)
				(type default)
			)
			(layer "F.SilkS")
		)
		(fp_line
			(start -0.67945 -0.305054)
			(end -0.12065 -0.305054)
			(stroke
				(width 0.1)
				(type default)
			)
			(layer "F.Fab")
		)
		(fp_line
			(start -0.67945 0.3048)
			(end -0.67945 -0.305054)
			(stroke
				(width 0.1)
				(type default)
			)
			(layer "F.Fab")
		)
		(fp_line
			(start -0.12065 -0.305054)
			(end -0.12065 -0.2794)
			(stroke
				(width 0.1)
				(type default)
			)
			(layer "F.Fab")
		)
		(fp_line
			(start -0.12065 -0.2794)
			(end 0.12065 -0.2794)
			(stroke
				(width 0.1)
				(type default)
			)
			(layer "F.Fab")
		)
		(fp_line
			(start -0.12065 0.2794)
			(end -0.12065 0.3048)
			(stroke
				(width 0.1)
				(type default)
			)
			(layer "F.Fab")
		)
		(fp_line
			(start -0.12065 0.3048)
			(end -0.67945 0.3048)
			(stroke
				(width 0.1)
				(type default)
			)
			(layer "F.Fab")
		)
		(fp_line
			(start 0.120396 0.2794)
			(end -0.12065 0.2794)
			(stroke
				(width 0.1)
				(type default)
			)
			(layer "F.Fab")
		)
		(fp_line
			(start 0.120396 0.3048)
			(end 0.120396 0.2794)
			(stroke
				(width 0.1)
				(type default)
			)
			(layer "F.Fab")
		)
		(fp_line
			(start 0.12065 -0.3048)
			(end 0.67945 -0.3048)
			(stroke
				(width 0.1)
				(type default)
			)
			(layer "F.Fab")
		)
		(fp_line
			(start 0.12065 -0.2794)
			(end 0.12065 -0.3048)
			(stroke
				(width 0.1)
				(type default)
			)
			(layer "F.Fab")
		)
		(fp_line
			(start 0.67945 -0.3048)
			(end 0.67945 0.3048)
			(stroke
				(width 0.1)
				(type default)
			)
			(layer "F.Fab")
		)
		(fp_line
			(start 0.67945 0.3048)
			(end 0.120396 0.3048)
			(stroke
				(width 0.1)
				(type default)
			)
			(layer "F.Fab")
		)
		(pad "1" smd circle
			(at -0.40005 0)
			(size 0 0)
			(layers "F.Cu" "F.Mask" "F.Paste")
			(net "PRSNT_NIC3_FPGA_PCA9555_N")
		)
		(pad "2" smd circle
			(at 0.40005 0)
			(size 0 0)
			(layers "F.Cu" "F.Mask" "F.Paste")
			(net "PRSNT_NIC3_FPGA_R_N")
		)
	)
	(footprint ""
		(layer "F.Cu")
		(at 331.175614 -119.477028 180)
		(property "Reference" "R881"
			(at 0 0 180)
			(layer "F.SilkS")
			(hide yes)
			(effects
				(font
					(size 1.27 1.27)
				)
			)
		)
		(property "Value" ""
			(at 0 0 180)
			(layer "F.Fab")
			(effects
				(font
					(size 1.27 1.27)
				)
			)
		)
		(duplicate_pad_numbers_are_jumpers no)
		(fp_line
			(start 0.7874 0.4064)
			(end -0.7874 0.4064)
			(stroke
				(width 0.1524)
				(type default)
			)
			(layer "F.SilkS")
		)
		(fp_line
			(start 0.7874 -0.4064)
			(end 0.7874 0.4064)
			(stroke
				(width 0.1524)
				(type default)
			)
			(layer "F.SilkS")
		)
		(fp_line
			(start -0.7874 0.4064)
			(end -0.7874 -0.4064)
			(stroke
				(width 0.1524)
				(type default)
			)
			(layer "F.SilkS")
		)
		(fp_line
			(start -0.7874 -0.4064)
			(end 0.7874 -0.4064)
			(stroke
				(width 0.1524)
				(type default)
			)
			(layer "F.SilkS")
		)
		(fp_line
			(start 0.67945 0.3048)
			(end 0.120396 0.3048)
			(stroke
				(width 0.1)
				(type default)
			)
			(layer "F.Fab")
		)
		(fp_line
			(start 0.67945 -0.3048)
			(end 0.67945 0.3048)
			(stroke
				(width 0.1)
				(type default)
			)
			(layer "F.Fab")
		)
		(fp_line
			(start 0.12065 -0.2794)
			(end 0.12065 -0.3048)
			(stroke
				(width 0.1)
				(type default)
			)
			(layer "F.Fab")
		)
		(fp_line
			(start 0.12065 -0.3048)
			(end 0.67945 -0.3048)
			(stroke
				(width 0.1)
				(type default)
			)
			(layer "F.Fab")
		)
		(fp_line
			(start 0.120396 0.3048)
			(end 0.120396 0.2794)
			(stroke
				(width 0.1)
				(type default)
			)
			(layer "F.Fab")
		)
		(fp_line
			(start 0.120396 0.2794)
			(end -0.12065 0.2794)
			(stroke
				(width 0.1)
				(type default)
			)
			(layer "F.Fab")
		)
		(fp_line
			(start -0.12065 0.3048)
			(end -0.67945 0.3048)
			(stroke
				(width 0.1)
				(type default)
			)
			(layer "F.Fab")
		)
		(fp_line
			(start -0.12065 0.2794)
			(end -0.12065 0.3048)
			(stroke
				(width 0.1)
				(type default)
			)
			(layer "F.Fab")
		)
		(fp_line
			(start -0.12065 -0.2794)
			(end 0.12065 -0.2794)
			(stroke
				(width 0.1)
				(type default)
			)
			(layer "F.Fab")
		)
		(fp_line
			(start -0.12065 -0.305054)
			(end -0.12065 -0.2794)
			(stroke
				(width 0.1)
				(type default)
			)
			(layer "F.Fab")
		)
		(fp_line
			(start -0.67945 0.3048)
			(end -0.67945 -0.305054)
			(stroke
				(width 0.1)
				(type default)
			)
			(layer "F.Fab")
		)
		(fp_line
			(start -0.67945 -0.305054)
			(end -0.12065 -0.305054)
			(stroke
				(width 0.1)
				(type default)
			)
			(layer "F.Fab")
		)
		(pad "1" smd circle
			(at -0.40005 0 180)
			(size 0 0)
			(layers "F.Cu" "F.Mask" "F.Paste")
			(net "P3V3_NIC5")
		)
		(pad "2" smd circle
			(at 0.40005 0 180)
			(size 0 0)
			(layers "F.Cu" "F.Mask" "F.Paste")
			(net "PWRGD_P3V3_NIC5")
		)
	)
	(footprint ""
		(layer "F.Cu")
		(at 440.34964 -304.036476 90)
		(property "Reference" "R1456"
			(at 0 0 90)
			(layer "F.SilkS")
			(hide yes)
			(effects
				(font
					(size 1.27 1.27)
				)
			)
		)
		(property "Value" ""
			(at 0 0 90)
			(layer "F.Fab")
			(effects
				(font
					(size 1.27 1.27)
				)
			)
		)
		(duplicate_pad_numbers_are_jumpers no)
		(fp_line
			(start 0.7874 -0.4064)
			(end 0.7874 0.4064)
			(stroke
				(width 0.1524)
				(type default)
			)
			(layer "F.SilkS")
		)
		(fp_line
			(start -0.7874 -0.4064)
			(end 0.7874 -0.4064)
			(stroke
				(width 0.1524)
				(type default)
			)
			(layer "F.SilkS")
		)
		(fp_line
			(start 0.7874 0.4064)
			(end -0.7874 0.4064)
			(stroke
				(width 0.1524)
				(type default)
			)
			(layer "F.SilkS")
		)
		(fp_line
			(start -0.7874 0.4064)
			(end -0.7874 -0.4064)
			(stroke
				(width 0.1524)
				(type default)
			)
			(layer "F.SilkS")
		)
		(fp_line
			(start -0.12065 -0.305054)
			(end -0.12065 -0.2794)
			(stroke
				(width 0.1)
				(type default)
			)
			(layer "F.Fab")
		)
		(fp_line
			(start -0.67945 -0.305054)
			(end -0.12065 -0.305054)
			(stroke
				(width 0.1)
				(type default)
			)
			(layer "F.Fab")
		)
		(fp_line
			(start 0.67945 -0.3048)
			(end 0.67945 0.3048)
			(stroke
				(width 0.1)
				(type default)
			)
			(layer "F.Fab")
		)
		(fp_line
			(start 0.12065 -0.3048)
			(end 0.67945 -0.3048)
			(stroke
				(width 0.1)
				(type default)
			)
			(layer "F.Fab")
		)
		(fp_line
			(start 0.12065 -0.2794)
			(end 0.12065 -0.3048)
			(stroke
				(width 0.1)
				(type default)
			)
			(layer "F.Fab")
		)
		(fp_line
			(start -0.12065 -0.2794)
			(end 0.12065 -0.2794)
			(stroke
				(width 0.1)
				(type default)
			)
			(layer "F.Fab")
		)
		(fp_line
			(start 0.120396 0.2794)
			(end -0.12065 0.2794)
			(stroke
				(width 0.1)
				(type default)
			)
			(layer "F.Fab")
		)
		(fp_line
			(start -0.12065 0.2794)
			(end -0.12065 0.3048)
			(stroke
				(width 0.1)
				(type default)
			)
			(layer "F.Fab")
		)
		(fp_line
			(start 0.67945 0.3048)
			(end 0.120396 0.3048)
			(stroke
				(width 0.1)
				(type default)
			)
			(layer "F.Fab")
		)
		(fp_line
			(start 0.120396 0.3048)
			(end 0.120396 0.2794)
			(stroke
				(width 0.1)
				(type default)
			)
			(layer "F.Fab")
		)
		(fp_line
			(start -0.12065 0.3048)
			(end -0.67945 0.3048)
			(stroke
				(width 0.1)
				(type default)
			)
			(layer "F.Fab")
		)
		(fp_line
			(start -0.67945 0.3048)
			(end -0.67945 -0.305054)
			(stroke
				(width 0.1)
				(type default)
			)
			(layer "F.Fab")
		)
		(pad "1" smd circle
			(at -0.40005 0 90)
			(size 0 0)
			(layers "F.Cu" "F.Mask" "F.Paste")
			(net "GND")
		)
		(pad "2" smd circle
			(at 0.40005 0 90)
			(size 0 0)
			(layers "F.Cu" "F.Mask" "F.Paste")
			(net "PEX3_SPARE6")
		)
	)
	(footprint ""
		(layer "F.Cu")
		(at 261.622286 -250.070874 -90)
		(property "Reference" "R1339"
			(at 0 0 270)
			(layer "F.SilkS")
			(hide yes)
			(effects
				(font
					(size 1.27 1.27)
				)
			)
		)
		(property "Value" ""
			(at 0 0 270)
			(layer "F.Fab")
			(effects
				(font
					(size 1.27 1.27)
				)
			)
		)
		(duplicate_pad_numbers_are_jumpers no)
		(fp_line
			(start -0.7874 0.4064)
			(end -0.7874 -0.4064)
			(stroke
				(width 0.1524)
				(type default)
			)
			(layer "F.SilkS")
		)
		(fp_line
			(start 0.7874 0.4064)
			(end -0.7874 0.4064)
			(stroke
				(width 0.1524)
				(type default)
			)
			(layer "F.SilkS")
		)
		(fp_line
			(start -0.7874 -0.4064)
			(end 0.7874 -0.4064)
			(stroke
				(width 0.1524)
				(type default)
			)
			(layer "F.SilkS")
		)
		(fp_line
			(start 0.7874 -0.4064)
			(end 0.7874 0.4064)
			(stroke
				(width 0.1524)
				(type default)
			)
			(layer "F.SilkS")
		)
		(fp_line
			(start -0.67945 0.3048)
			(end -0.67945 -0.305054)
			(stroke
				(width 0.1)
				(type default)
			)
			(layer "F.Fab")
		)
		(fp_line
			(start -0.12065 0.3048)
			(end -0.67945 0.3048)
			(stroke
				(width 0.1)
				(type default)
			)
			(layer "F.Fab")
		)
		(fp_line
			(start 0.120396 0.3048)
			(end 0.120396 0.2794)
			(stroke
				(width 0.1)
				(type default)
			)
			(layer "F.Fab")
		)
		(fp_line
			(start 0.67945 0.3048)
			(end 0.120396 0.3048)
			(stroke
				(width 0.1)
				(type default)
			)
			(layer "F.Fab")
		)
		(fp_line
			(start -0.12065 0.2794)
			(end -0.12065 0.3048)
			(stroke
				(width 0.1)
				(type default)
			)
			(layer "F.Fab")
		)
		(fp_line
			(start 0.120396 0.2794)
			(end -0.12065 0.2794)
			(stroke
				(width 0.1)
				(type default)
			)
			(layer "F.Fab")
		)
		(fp_line
			(start -0.12065 -0.2794)
			(end 0.12065 -0.2794)
			(stroke
				(width 0.1)
				(type default)
			)
			(layer "F.Fab")
		)
		(fp_line
			(start 0.12065 -0.2794)
			(end 0.12065 -0.3048)
			(stroke
				(width 0.1)
				(type default)
			)
			(layer "F.Fab")
		)
		(fp_line
			(start 0.12065 -0.3048)
			(end 0.67945 -0.3048)
			(stroke
				(width 0.1)
				(type default)
			)
			(layer "F.Fab")
		)
		(fp_line
			(start 0.67945 -0.3048)
			(end 0.67945 0.3048)
			(stroke
				(width 0.1)
				(type default)
			)
			(layer "F.Fab")
		)
		(fp_line
			(start -0.67945 -0.305054)
			(end -0.12065 -0.305054)
			(stroke
				(width 0.1)
				(type default)
			)
			(layer "F.Fab")
		)
		(fp_line
			(start -0.12065 -0.305054)
			(end -0.12065 -0.2794)
			(stroke
				(width 0.1)
				(type default)
			)
			(layer "F.Fab")
		)
		(pad "1" smd circle
			(at -0.40005 0 270)
			(size 0 0)
			(layers "F.Cu" "F.Mask" "F.Paste")
			(net "PEX2_MODE_SEL3")
		)
		(pad "2" smd circle
			(at 0.40005 0 270)
			(size 0 0)
			(layers "F.Cu" "F.Mask" "F.Paste")
			(net "P1V8_PEX")
		)
	)
	(footprint ""
		(layer "F.Cu")
		(at 373.658384 -252.356874 -90)
		(property "Reference" "R1432"
			(at 0 0 270)
			(layer "F.SilkS")
			(hide yes)
			(effects
				(font
					(size 1.27 1.27)
				)
			)
		)
		(property "Value" ""
			(at 0 0 270)
			(layer "F.Fab")
			(effects
				(font
					(size 1.27 1.27)
				)
			)
		)
		(duplicate_pad_numbers_are_jumpers no)
		(fp_line
			(start -0.7874 0.4064)
			(end -0.7874 -0.4064)
			(stroke
				(width 0.1524)
				(type default)
			)
			(layer "F.SilkS")
		)
		(fp_line
			(start 0.7874 0.4064)
			(end -0.7874 0.4064)
			(stroke
				(width 0.1524)
				(type default)
			)
			(layer "F.SilkS")
		)
		(fp_line
			(start -0.7874 -0.4064)
			(end 0.7874 -0.4064)
			(stroke
				(width 0.1524)
				(type default)
			)
			(layer "F.SilkS")
		)
		(fp_line
			(start 0.7874 -0.4064)
			(end 0.7874 0.4064)
			(stroke
				(width 0.1524)
				(type default)
			)
			(layer "F.SilkS")
		)
		(fp_line
			(start -0.67945 0.3048)
			(end -0.67945 -0.305054)
			(stroke
				(width 0.1)
				(type default)
			)
			(layer "F.Fab")
		)
		(fp_line
			(start -0.12065 0.3048)
			(end -0.67945 0.3048)
			(stroke
				(width 0.1)
				(type default)
			)
			(layer "F.Fab")
		)
		(fp_line
			(start 0.120396 0.3048)
			(end 0.120396 0.2794)
			(stroke
				(width 0.1)
				(type default)
			)
			(layer "F.Fab")
		)
		(fp_line
			(start 0.67945 0.3048)
			(end 0.120396 0.3048)
			(stroke
				(width 0.1)
				(type default)
			)
			(layer "F.Fab")
		)
		(fp_line
			(start -0.12065 0.2794)
			(end -0.12065 0.3048)
			(stroke
				(width 0.1)
				(type default)
			)
			(layer "F.Fab")
		)
		(fp_line
			(start 0.120396 0.2794)
			(end -0.12065 0.2794)
			(stroke
				(width 0.1)
				(type default)
			)
			(layer "F.Fab")
		)
		(fp_line
			(start -0.12065 -0.2794)
			(end 0.12065 -0.2794)
			(stroke
				(width 0.1)
				(type default)
			)
			(layer "F.Fab")
		)
		(fp_line
			(start 0.12065 -0.2794)
			(end 0.12065 -0.3048)
			(stroke
				(width 0.1)
				(type default)
			)
			(layer "F.Fab")
		)
		(fp_line
			(start 0.12065 -0.3048)
			(end 0.67945 -0.3048)
			(stroke
				(width 0.1)
				(type default)
			)
			(layer "F.Fab")
		)
		(fp_line
			(start 0.67945 -0.3048)
			(end 0.67945 0.3048)
			(stroke
				(width 0.1)
				(type default)
			)
			(layer "F.Fab")
		)
		(fp_line
			(start -0.67945 -0.305054)
			(end -0.12065 -0.305054)
			(stroke
				(width 0.1)
				(type default)
			)
			(layer "F.Fab")
		)
		(fp_line
			(start -0.12065 -0.305054)
			(end -0.12065 -0.2794)
			(stroke
				(width 0.1)
				(type default)
			)
			(layer "F.Fab")
		)
		(pad "1" smd circle
			(at -0.40005 0 270)
			(size 0 0)
			(layers "F.Cu" "F.Mask" "F.Paste")
			(net "GND")
		)
		(pad "2" smd circle
			(at 0.40005 0 270)
			(size 0 0)
			(layers "F.Cu" "F.Mask" "F.Paste")
			(net "PEX3_MODE_SEL7")
		)
	)
	(footprint ""
		(layer "F.Cu")
		(at 337.947 -234.061 90)
		(property "Reference" "R3555"
			(at 0 0 90)
			(layer "F.SilkS")
			(hide yes)
			(effects
				(font
					(size 1.27 1.27)
				)
			)
		)
		(property "Value" ""
			(at 0 0 90)
			(layer "F.Fab")
			(effects
				(font
					(size 1.27 1.27)
				)
			)
		)
		(duplicate_pad_numbers_are_jumpers no)
		(fp_line
			(start 0.7874 -0.4064)
			(end 0.7874 0.4064)
			(stroke
				(width 0.1524)
				(type default)
			)
			(layer "F.SilkS")
		)
		(fp_line
			(start -0.7874 -0.4064)
			(end 0.7874 -0.4064)
			(stroke
				(width 0.1524)
				(type default)
			)
			(layer "F.SilkS")
		)
		(fp_line
			(start 0.7874 0.4064)
			(end -0.7874 0.4064)
			(stroke
				(width 0.1524)
				(type default)
			)
			(layer "F.SilkS")
		)
		(fp_line
			(start -0.7874 0.4064)
			(end -0.7874 -0.4064)
			(stroke
				(width 0.1524)
				(type default)
			)
			(layer "F.SilkS")
		)
		(fp_line
			(start -0.12065 -0.305054)
			(end -0.12065 -0.2794)
			(stroke
				(width 0.1)
				(type default)
			)
			(layer "F.Fab")
		)
		(fp_line
			(start -0.67945 -0.305054)
			(end -0.12065 -0.305054)
			(stroke
				(width 0.1)
				(type default)
			)
			(layer "F.Fab")
		)
		(fp_line
			(start 0.67945 -0.3048)
			(end 0.67945 0.3048)
			(stroke
				(width 0.1)
				(type default)
			)
			(layer "F.Fab")
		)
		(fp_line
			(start 0.12065 -0.3048)
			(end 0.67945 -0.3048)
			(stroke
				(width 0.1)
				(type default)
			)
			(layer "F.Fab")
		)
		(fp_line
			(start 0.12065 -0.2794)
			(end 0.12065 -0.3048)
			(stroke
				(width 0.1)
				(type default)
			)
			(layer "F.Fab")
		)
		(fp_line
			(start -0.12065 -0.2794)
			(end 0.12065 -0.2794)
			(stroke
				(width 0.1)
				(type default)
			)
			(layer "F.Fab")
		)
		(fp_line
			(start 0.120396 0.2794)
			(end -0.12065 0.2794)
			(stroke
				(width 0.1)
				(type default)
			)
			(layer "F.Fab")
		)
		(fp_line
			(start -0.12065 0.2794)
			(end -0.12065 0.3048)
			(stroke
				(width 0.1)
				(type default)
			)
			(layer "F.Fab")
		)
		(fp_line
			(start 0.67945 0.3048)
			(end 0.120396 0.3048)
			(stroke
				(width 0.1)
				(type default)
			)
			(layer "F.Fab")
		)
		(fp_line
			(start 0.120396 0.3048)
			(end 0.120396 0.2794)
			(stroke
				(width 0.1)
				(type default)
			)
			(layer "F.Fab")
		)
		(fp_line
			(start -0.12065 0.3048)
			(end -0.67945 0.3048)
			(stroke
				(width 0.1)
				(type default)
			)
			(layer "F.Fab")
		)
		(fp_line
			(start -0.67945 0.3048)
			(end -0.67945 -0.305054)
			(stroke
				(width 0.1)
				(type default)
			)
			(layer "F.Fab")
		)
		(pad "1" smd circle
			(at -0.40005 0 90)
			(size 0 0)
			(layers "F.Cu" "F.Mask" "F.Paste")
			(net "FM_SOL_UART_CH_SEL_R")
		)
		(pad "2" smd circle
			(at 0.40005 0 90)
			(size 0 0)
			(layers "F.Cu" "F.Mask" "F.Paste")
			(net "FM_SOL_UART_CH_SEL")
		)
	)
	(footprint ""
		(layer "F.Cu")
		(at 127.658114 -257.115564)
		(property "Reference" "PR83"
			(at 0 0 0)
			(layer "F.SilkS")
			(hide yes)
			(effects
				(font
					(size 1.27 1.27)
				)
			)
		)
		(property "Value" ""
			(at 0 0 0)
			(layer "F.Fab")
			(effects
				(font
					(size 1.27 1.27)
				)
			)
		)
		(duplicate_pad_numbers_are_jumpers no)
		(fp_line
			(start -0.7874 -0.4064)
			(end 0.7874 -0.4064)
			(stroke
				(width 0.1524)
				(type default)
			)
			(layer "F.SilkS")
		)
		(fp_line
			(start -0.7874 0.4064)
			(end -0.7874 -0.4064)
			(stroke
				(width 0.1524)
				(type default)
			)
			(layer "F.SilkS")
		)
		(fp_line
			(start 0.7874 -0.4064)
			(end 0.7874 0.4064)
			(stroke
				(width 0.1524)
				(type default)
			)
			(layer "F.SilkS")
		)
		(fp_line
			(start 0.7874 0.4064)
			(end -0.7874 0.4064)
			(stroke
				(width 0.1524)
				(type default)
			)
			(layer "F.SilkS")
		)
		(fp_line
			(start -0.67945 -0.305054)
			(end -0.12065 -0.305054)
			(stroke
				(width 0.1)
				(type default)
			)
			(layer "F.Fab")
		)
		(fp_line
			(start -0.67945 0.3048)
			(end -0.67945 -0.305054)
			(stroke
				(width 0.1)
				(type default)
			)
			(layer "F.Fab")
		)
		(fp_line
			(start -0.12065 -0.305054)
			(end -0.12065 -0.2794)
			(stroke
				(width 0.1)
				(type default)
			)
			(layer "F.Fab")
		)
		(fp_line
			(start -0.12065 -0.2794)
			(end 0.12065 -0.2794)
			(stroke
				(width 0.1)
				(type default)
			)
			(layer "F.Fab")
		)
		(fp_line
			(start -0.12065 0.2794)
			(end -0.12065 0.3048)
			(stroke
				(width 0.1)
				(type default)
			)
			(layer "F.Fab")
		)
		(fp_line
			(start -0.12065 0.3048)
			(end -0.67945 0.3048)
			(stroke
				(width 0.1)
				(type default)
			)
			(layer "F.Fab")
		)
		(fp_line
			(start 0.120396 0.2794)
			(end -0.12065 0.2794)
			(stroke
				(width 0.1)
				(type default)
			)
			(layer "F.Fab")
		)
		(fp_line
			(start 0.120396 0.3048)
			(end 0.120396 0.2794)
			(stroke
				(width 0.1)
				(type default)
			)
			(layer "F.Fab")
		)
		(fp_line
			(start 0.12065 -0.3048)
			(end 0.67945 -0.3048)
			(stroke
				(width 0.1)
				(type default)
			)
			(layer "F.Fab")
		)
		(fp_line
			(start 0.12065 -0.2794)
			(end 0.12065 -0.3048)
			(stroke
				(width 0.1)
				(type default)
			)
			(layer "F.Fab")
		)
		(fp_line
			(start 0.67945 -0.3048)
			(end 0.67945 0.3048)
			(stroke
				(width 0.1)
				(type default)
			)
			(layer "F.Fab")
		)
		(fp_line
			(start 0.67945 0.3048)
			(end 0.120396 0.3048)
			(stroke
				(width 0.1)
				(type default)
			)
			(layer "F.Fab")
		)
		(pad "1" smd circle
			(at -0.40005 0)
			(size 0 0)
			(layers "F.Cu" "F.Mask" "F.Paste")
			(net "P0V8_PEX0_PINALRT")
		)
		(pad "2" smd circle
			(at 0.40005 0)
			(size 0 0)
			(layers "F.Cu" "F.Mask" "F.Paste")
			(net "P3V3_AUX")
		)
	)
	(footprint ""
		(layer "F.Cu")
		(at 258.46786 -54.067456)
		(property "Reference" "PR225"
			(at 0 0 0)
			(layer "F.SilkS")
			(hide yes)
			(effects
				(font
					(size 1.27 1.27)
				)
			)
		)
		(property "Value" ""
			(at 0 0 0)
			(layer "F.Fab")
			(effects
				(font
					(size 1.27 1.27)
				)
			)
		)
		(duplicate_pad_numbers_are_jumpers no)
		(fp_line
			(start -0.7874 -0.4064)
			(end 0.7874 -0.4064)
			(stroke
				(width 0.1524)
				(type default)
			)
			(layer "F.SilkS")
		)
		(fp_line
			(start -0.7874 0.4064)
			(end -0.7874 -0.4064)
			(stroke
				(width 0.1524)
				(type default)
			)
			(layer "F.SilkS")
		)
		(fp_line
			(start 0.7874 -0.4064)
			(end 0.7874 0.4064)
			(stroke
				(width 0.1524)
				(type default)
			)
			(layer "F.SilkS")
		)
		(fp_line
			(start 0.7874 0.4064)
			(end -0.7874 0.4064)
			(stroke
				(width 0.1524)
				(type default)
			)
			(layer "F.SilkS")
		)
		(fp_line
			(start -0.67945 -0.305054)
			(end -0.12065 -0.305054)
			(stroke
				(width 0.1)
				(type default)
			)
			(layer "F.Fab")
		)
		(fp_line
			(start -0.67945 0.3048)
			(end -0.67945 -0.305054)
			(stroke
				(width 0.1)
				(type default)
			)
			(layer "F.Fab")
		)
		(fp_line
			(start -0.12065 -0.305054)
			(end -0.12065 -0.2794)
			(stroke
				(width 0.1)
				(type default)
			)
			(layer "F.Fab")
		)
		(fp_line
			(start -0.12065 -0.2794)
			(end 0.12065 -0.2794)
			(stroke
				(width 0.1)
				(type default)
			)
			(layer "F.Fab")
		)
		(fp_line
			(start -0.12065 0.2794)
			(end -0.12065 0.3048)
			(stroke
				(width 0.1)
				(type default)
			)
			(layer "F.Fab")
		)
		(fp_line
			(start -0.12065 0.3048)
			(end -0.67945 0.3048)
			(stroke
				(width 0.1)
				(type default)
			)
			(layer "F.Fab")
		)
		(fp_line
			(start 0.120396 0.2794)
			(end -0.12065 0.2794)
			(stroke
				(width 0.1)
				(type default)
			)
			(layer "F.Fab")
		)
		(fp_line
			(start 0.120396 0.3048)
			(end 0.120396 0.2794)
			(stroke
				(width 0.1)
				(type default)
			)
			(layer "F.Fab")
		)
		(fp_line
			(start 0.12065 -0.3048)
			(end 0.67945 -0.3048)
			(stroke
				(width 0.1)
				(type default)
			)
			(layer "F.Fab")
		)
		(fp_line
			(start 0.12065 -0.2794)
			(end 0.12065 -0.3048)
			(stroke
				(width 0.1)
				(type default)
			)
			(layer "F.Fab")
		)
		(fp_line
			(start 0.67945 -0.3048)
			(end 0.67945 0.3048)
			(stroke
				(width 0.1)
				(type default)
			)
			(layer "F.Fab")
		)
		(fp_line
			(start 0.67945 0.3048)
			(end 0.120396 0.3048)
			(stroke
				(width 0.1)
				(type default)
			)
			(layer "F.Fab")
		)
		(pad "1" smd circle
			(at -0.40005 0)
			(size 0 0)
			(layers "F.Cu" "F.Mask" "F.Paste")
			(net "P12V_SSD8_OCP")
		)
		(pad "2" smd circle
			(at 0.40005 0)
			(size 0 0)
			(layers "F.Cu" "F.Mask" "F.Paste")
			(net "GND")
		)
	)
	(footprint ""
		(layer "F.Cu")
		(at 312.21934 -129.880106 180)
		(property "Reference" "C446"
			(at 0 0 180)
			(layer "F.SilkS")
			(hide yes)
			(effects
				(font
					(size 1.27 1.27)
				)
			)
		)
		(property "Value" ""
			(at 0 0 180)
			(layer "F.Fab")
			(effects
				(font
					(size 1.27 1.27)
				)
			)
		)
		(duplicate_pad_numbers_are_jumpers no)
		(fp_line
			(start 0.299974 0.150114)
			(end -0.299974 0.150114)
			(stroke
				(width 0.1)
				(type default)
			)
			(layer "F.Fab")
		)
		(fp_line
			(start 0.299974 -0.150114)
			(end 0.299974 0.150114)
			(stroke
				(width 0.1)
				(type default)
			)
			(layer "F.Fab")
		)
		(fp_line
			(start -0.299974 0.150114)
			(end -0.299974 -0.150114)
			(stroke
				(width 0.1)
				(type default)
			)
			(layer "F.Fab")
		)
		(fp_line
			(start -0.299974 -0.150114)
			(end 0.299974 -0.150114)
			(stroke
				(width 0.1)
				(type default)
			)
			(layer "F.Fab")
		)
		(pad "1" smd rect
			(at -0.2667 0 180)
			(size 0.3048 0.381)
			(layers "F.Cu" "F.Mask" "F.Paste")
			(net "P5E_PEX2_STN0_TX_DN<4>")
		)
		(pad "2" smd rect
			(at 0.2667 0 180)
			(size 0.3048 0.381)
			(layers "F.Cu" "F.Mask" "F.Paste")
			(net "P5E_PEX2_STN0_TX_C_DN<4>")
		)
	)
	(footprint ""
		(layer "F.Cu")
		(at 459.04658 -373.852948 -90)
		(property "Reference" "C4453"
			(at 0 0 270)
			(layer "F.SilkS")
			(hide yes)
			(effects
				(font
					(size 1.27 1.27)
				)
			)
		)
		(property "Value" ""
			(at 0 0 270)
			(layer "F.Fab")
			(effects
				(font
					(size 1.27 1.27)
				)
			)
		)
		(duplicate_pad_numbers_are_jumpers no)
		(fp_line
			(start -0.299974 0.150114)
			(end -0.299974 -0.150114)
			(stroke
				(width 0.1)
				(type default)
			)
			(layer "F.Fab")
		)
		(fp_line
			(start 0.299974 0.150114)
			(end -0.299974 0.150114)
			(stroke
				(width 0.1)
				(type default)
			)
			(layer "F.Fab")
		)
		(fp_line
			(start -0.299974 -0.150114)
			(end 0.299974 -0.150114)
			(stroke
				(width 0.1)
				(type default)
			)
			(layer "F.Fab")
		)
		(fp_line
			(start 0.299974 -0.150114)
			(end 0.299974 0.150114)
			(stroke
				(width 0.1)
				(type default)
			)
			(layer "F.Fab")
		)
		(pad "1" smd rect
			(at -0.2667 0 270)
			(size 0.3048 0.381)
			(layers "F.Cu" "F.Mask" "F.Paste")
			(net "GPU_3V3IO_RSVD3_ISO")
		)
		(pad "2" smd rect
			(at 0.2667 0 270)
			(size 0.3048 0.381)
			(layers "F.Cu" "F.Mask" "F.Paste")
			(net "GND")
		)
	)
	(footprint ""
		(layer "F.Cu")
		(at 188.773054 -22.867366 90)
		(property "Reference" "C3914"
			(at 0 0 90)
			(layer "F.SilkS")
			(hide yes)
			(effects
				(font
					(size 1.27 1.27)
				)
			)
		)
		(property "Value" ""
			(at 0 0 90)
			(layer "F.Fab")
			(effects
				(font
					(size 1.27 1.27)
				)
			)
		)
		(duplicate_pad_numbers_are_jumpers no)
		(fp_line
			(start 0.7874 -0.4064)
			(end 0.7874 0.4064)
			(stroke
				(width 0.1524)
				(type default)
			)
			(layer "F.SilkS")
		)
		(fp_line
			(start -0.7874 -0.4064)
			(end 0.7874 -0.4064)
			(stroke
				(width 0.1524)
				(type default)
			)
			(layer "F.SilkS")
		)
		(fp_line
			(start 0.7874 0.4064)
			(end -0.7874 0.4064)
			(stroke
				(width 0.1524)
				(type default)
			)
			(layer "F.SilkS")
		)
		(fp_line
			(start -0.7874 0.4064)
			(end -0.7874 -0.4064)
			(stroke
				(width 0.1524)
				(type default)
			)
			(layer "F.SilkS")
		)
		(fp_line
			(start -0.12065 -0.305054)
			(end -0.12065 -0.2794)
			(stroke
				(width 0.1)
				(type default)
			)
			(layer "F.Fab")
		)
		(fp_line
			(start -0.67945 -0.305054)
			(end -0.12065 -0.305054)
			(stroke
				(width 0.1)
				(type default)
			)
			(layer "F.Fab")
		)
		(fp_line
			(start 0.67945 -0.3048)
			(end 0.67945 0.3048)
			(stroke
				(width 0.1)
				(type default)
			)
			(layer "F.Fab")
		)
		(fp_line
			(start 0.12065 -0.3048)
			(end 0.67945 -0.3048)
			(stroke
				(width 0.1)
				(type default)
			)
			(layer "F.Fab")
		)
		(fp_line
			(start 0.12065 -0.2794)
			(end 0.12065 -0.3048)
			(stroke
				(width 0.1)
				(type default)
			)
			(layer "F.Fab")
		)
		(fp_line
			(start -0.12065 -0.2794)
			(end 0.12065 -0.2794)
			(stroke
				(width 0.1)
				(type default)
			)
			(layer "F.Fab")
		)
		(fp_line
			(start 0.120396 0.2794)
			(end -0.12065 0.2794)
			(stroke
				(width 0.1)
				(type default)
			)
			(layer "F.Fab")
		)
		(fp_line
			(start -0.12065 0.2794)
			(end -0.12065 0.3048)
			(stroke
				(width 0.1)
				(type default)
			)
			(layer "F.Fab")
		)
		(fp_line
			(start 0.67945 0.3048)
			(end 0.120396 0.3048)
			(stroke
				(width 0.1)
				(type default)
			)
			(layer "F.Fab")
		)
		(fp_line
			(start 0.120396 0.3048)
			(end 0.120396 0.2794)
			(stroke
				(width 0.1)
				(type default)
			)
			(layer "F.Fab")
		)
		(fp_line
			(start -0.12065 0.3048)
			(end -0.67945 0.3048)
			(stroke
				(width 0.1)
				(type default)
			)
			(layer "F.Fab")
		)
		(fp_line
			(start -0.67945 0.3048)
			(end -0.67945 -0.305054)
			(stroke
				(width 0.1)
				(type default)
			)
			(layer "F.Fab")
		)
		(pad "1" smd circle
			(at -0.40005 0 90)
			(size 0 0)
			(layers "F.Cu" "F.Mask" "F.Paste")
			(net "P12V_SSD6")
		)
		(pad "2" smd circle
			(at 0.40005 0 90)
			(size 0 0)
			(layers "F.Cu" "F.Mask" "F.Paste")
			(net "GND")
		)
	)
	(footprint ""
		(layer "F.Cu")
		(at 329.03414 -95.263716 -90)
		(property "Reference" "R4447"
			(at 0 0 270)
			(layer "F.SilkS")
			(hide yes)
			(effects
				(font
					(size 1.27 1.27)
				)
			)
		)
		(property "Value" ""
			(at 0 0 270)
			(layer "F.Fab")
			(effects
				(font
					(size 1.27 1.27)
				)
			)
		)
		(duplicate_pad_numbers_are_jumpers no)
		(fp_line
			(start -0.7874 0.4064)
			(end -0.7874 -0.4064)
			(stroke
				(width 0.1524)
				(type default)
			)
			(layer "F.SilkS")
		)
		(fp_line
			(start 0.7874 0.4064)
			(end -0.7874 0.4064)
			(stroke
				(width 0.1524)
				(type default)
			)
			(layer "F.SilkS")
		)
		(fp_line
			(start -0.7874 -0.4064)
			(end 0.7874 -0.4064)
			(stroke
				(width 0.1524)
				(type default)
			)
			(layer "F.SilkS")
		)
		(fp_line
			(start 0.7874 -0.4064)
			(end 0.7874 0.4064)
			(stroke
				(width 0.1524)
				(type default)
			)
			(layer "F.SilkS")
		)
		(fp_line
			(start -0.67945 0.3048)
			(end -0.67945 -0.305054)
			(stroke
				(width 0.1)
				(type default)
			)
			(layer "F.Fab")
		)
		(fp_line
			(start -0.12065 0.3048)
			(end -0.67945 0.3048)
			(stroke
				(width 0.1)
				(type default)
			)
			(layer "F.Fab")
		)
		(fp_line
			(start 0.120396 0.3048)
			(end 0.120396 0.2794)
			(stroke
				(width 0.1)
				(type default)
			)
			(layer "F.Fab")
		)
		(fp_line
			(start 0.67945 0.3048)
			(end 0.120396 0.3048)
			(stroke
				(width 0.1)
				(type default)
			)
			(layer "F.Fab")
		)
		(fp_line
			(start -0.12065 0.2794)
			(end -0.12065 0.3048)
			(stroke
				(width 0.1)
				(type default)
			)
			(layer "F.Fab")
		)
		(fp_line
			(start 0.120396 0.2794)
			(end -0.12065 0.2794)
			(stroke
				(width 0.1)
				(type default)
			)
			(layer "F.Fab")
		)
		(fp_line
			(start -0.12065 -0.2794)
			(end 0.12065 -0.2794)
			(stroke
				(width 0.1)
				(type default)
			)
			(layer "F.Fab")
		)
		(fp_line
			(start 0.12065 -0.2794)
			(end 0.12065 -0.3048)
			(stroke
				(width 0.1)
				(type default)
			)
			(layer "F.Fab")
		)
		(fp_line
			(start 0.12065 -0.3048)
			(end 0.67945 -0.3048)
			(stroke
				(width 0.1)
				(type default)
			)
			(layer "F.Fab")
		)
		(fp_line
			(start 0.67945 -0.3048)
			(end 0.67945 0.3048)
			(stroke
				(width 0.1)
				(type default)
			)
			(layer "F.Fab")
		)
		(fp_line
			(start -0.67945 -0.305054)
			(end -0.12065 -0.305054)
			(stroke
				(width 0.1)
				(type default)
			)
			(layer "F.Fab")
		)
		(fp_line
			(start -0.12065 -0.305054)
			(end -0.12065 -0.2794)
			(stroke
				(width 0.1)
				(type default)
			)
			(layer "F.Fab")
		)
		(pad "1" smd circle
			(at -0.40005 0 270)
			(size 0 0)
			(layers "F.Cu" "F.Mask" "F.Paste")
			(net "PWRGD_P12V_NIC5")
		)
		(pad "2" smd circle
			(at 0.40005 0 270)
			(size 0 0)
			(layers "F.Cu" "F.Mask" "F.Paste")
			(net "PWRGD_P12V_NIC5_R")
		)
	)
	(footprint ""
		(layer "F.Cu")
		(at 104.243632 -46.90491)
		(property "Reference" "R541"
			(at 0 0 0)
			(layer "F.SilkS")
			(hide yes)
			(effects
				(font
					(size 1.27 1.27)
				)
			)
		)
		(property "Value" ""
			(at 0 0 0)
			(layer "F.Fab")
			(effects
				(font
					(size 1.27 1.27)
				)
			)
		)
		(duplicate_pad_numbers_are_jumpers no)
		(fp_line
			(start -0.7874 -0.4064)
			(end 0.7874 -0.4064)
			(stroke
				(width 0.1524)
				(type default)
			)
			(layer "F.SilkS")
		)
		(fp_line
			(start -0.7874 0.4064)
			(end -0.7874 -0.4064)
			(stroke
				(width 0.1524)
				(type default)
			)
			(layer "F.SilkS")
		)
		(fp_line
			(start 0.7874 -0.4064)
			(end 0.7874 0.4064)
			(stroke
				(width 0.1524)
				(type default)
			)
			(layer "F.SilkS")
		)
		(fp_line
			(start 0.7874 0.4064)
			(end -0.7874 0.4064)
			(stroke
				(width 0.1524)
				(type default)
			)
			(layer "F.SilkS")
		)
		(fp_line
			(start -0.67945 -0.305054)
			(end -0.12065 -0.305054)
			(stroke
				(width 0.1)
				(type default)
			)
			(layer "F.Fab")
		)
		(fp_line
			(start -0.67945 0.3048)
			(end -0.67945 -0.305054)
			(stroke
				(width 0.1)
				(type default)
			)
			(layer "F.Fab")
		)
		(fp_line
			(start -0.12065 -0.305054)
			(end -0.12065 -0.2794)
			(stroke
				(width 0.1)
				(type default)
			)
			(layer "F.Fab")
		)
		(fp_line
			(start -0.12065 -0.2794)
			(end 0.12065 -0.2794)
			(stroke
				(width 0.1)
				(type default)
			)
			(layer "F.Fab")
		)
		(fp_line
			(start -0.12065 0.2794)
			(end -0.12065 0.3048)
			(stroke
				(width 0.1)
				(type default)
			)
			(layer "F.Fab")
		)
		(fp_line
			(start -0.12065 0.3048)
			(end -0.67945 0.3048)
			(stroke
				(width 0.1)
				(type default)
			)
			(layer "F.Fab")
		)
		(fp_line
			(start 0.120396 0.2794)
			(end -0.12065 0.2794)
			(stroke
				(width 0.1)
				(type default)
			)
			(layer "F.Fab")
		)
		(fp_line
			(start 0.120396 0.3048)
			(end 0.120396 0.2794)
			(stroke
				(width 0.1)
				(type default)
			)
			(layer "F.Fab")
		)
		(fp_line
			(start 0.12065 -0.3048)
			(end 0.67945 -0.3048)
			(stroke
				(width 0.1)
				(type default)
			)
			(layer "F.Fab")
		)
		(fp_line
			(start 0.12065 -0.2794)
			(end 0.12065 -0.3048)
			(stroke
				(width 0.1)
				(type default)
			)
			(layer "F.Fab")
		)
		(fp_line
			(start 0.67945 -0.3048)
			(end 0.67945 0.3048)
			(stroke
				(width 0.1)
				(type default)
			)
			(layer "F.Fab")
		)
		(fp_line
			(start 0.67945 0.3048)
			(end 0.120396 0.3048)
			(stroke
				(width 0.1)
				(type default)
			)
			(layer "F.Fab")
		)
		(pad "1" smd circle
			(at -0.40005 0)
			(size 0 0)
			(layers "F.Cu" "F.Mask" "F.Paste")
			(net "SSD3_ADC_ALERT_N")
		)
		(pad "2" smd circle
			(at 0.40005 0)
			(size 0 0)
			(layers "F.Cu" "F.Mask" "F.Paste")
			(net "SSD_0_7_ADC_ALERT_N")
		)
	)
	(footprint ""
		(layer "F.Cu")
		(at 358.542844 -392.418316 -90)
		(property "Reference" "R6698"
			(at 0 0 270)
			(layer "F.SilkS")
			(hide yes)
			(effects
				(font
					(size 1.27 1.27)
				)
			)
		)
		(property "Value" ""
			(at 0 0 270)
			(layer "F.Fab")
			(effects
				(font
					(size 1.27 1.27)
				)
			)
		)
		(duplicate_pad_numbers_are_jumpers no)
		(fp_line
			(start -0.7874 0.4064)
			(end -0.7874 -0.4064)
			(stroke
				(width 0.1524)
				(type default)
			)
			(layer "F.SilkS")
		)
		(fp_line
			(start 0.7874 0.4064)
			(end -0.7874 0.4064)
			(stroke
				(width 0.1524)
				(type default)
			)
			(layer "F.SilkS")
		)
		(fp_line
			(start -0.7874 -0.4064)
			(end 0.7874 -0.4064)
			(stroke
				(width 0.1524)
				(type default)
			)
			(layer "F.SilkS")
		)
		(fp_line
			(start 0.7874 -0.4064)
			(end 0.7874 0.4064)
			(stroke
				(width 0.1524)
				(type default)
			)
			(layer "F.SilkS")
		)
		(fp_line
			(start -0.67945 0.3048)
			(end -0.67945 -0.305054)
			(stroke
				(width 0.1)
				(type default)
			)
			(layer "F.Fab")
		)
		(fp_line
			(start -0.12065 0.3048)
			(end -0.67945 0.3048)
			(stroke
				(width 0.1)
				(type default)
			)
			(layer "F.Fab")
		)
		(fp_line
			(start 0.120396 0.3048)
			(end 0.120396 0.2794)
			(stroke
				(width 0.1)
				(type default)
			)
			(layer "F.Fab")
		)
		(fp_line
			(start 0.67945 0.3048)
			(end 0.120396 0.3048)
			(stroke
				(width 0.1)
				(type default)
			)
			(layer "F.Fab")
		)
		(fp_line
			(start -0.12065 0.2794)
			(end -0.12065 0.3048)
			(stroke
				(width 0.1)
				(type default)
			)
			(layer "F.Fab")
		)
		(fp_line
			(start 0.120396 0.2794)
			(end -0.12065 0.2794)
			(stroke
				(width 0.1)
				(type default)
			)
			(layer "F.Fab")
		)
		(fp_line
			(start -0.12065 -0.2794)
			(end 0.12065 -0.2794)
			(stroke
				(width 0.1)
				(type default)
			)
			(layer "F.Fab")
		)
		(fp_line
			(start 0.12065 -0.2794)
			(end 0.12065 -0.3048)
			(stroke
				(width 0.1)
				(type default)
			)
			(layer "F.Fab")
		)
		(fp_line
			(start 0.12065 -0.3048)
			(end 0.67945 -0.3048)
			(stroke
				(width 0.1)
				(type default)
			)
			(layer "F.Fab")
		)
		(fp_line
			(start 0.67945 -0.3048)
			(end 0.67945 0.3048)
			(stroke
				(width 0.1)
				(type default)
			)
			(layer "F.Fab")
		)
		(fp_line
			(start -0.67945 -0.305054)
			(end -0.12065 -0.305054)
			(stroke
				(width 0.1)
				(type default)
			)
			(layer "F.Fab")
		)
		(fp_line
			(start -0.12065 -0.305054)
			(end -0.12065 -0.2794)
			(stroke
				(width 0.1)
				(type default)
			)
			(layer "F.Fab")
		)
		(pad "1" smd circle
			(at -0.40005 0 270)
			(size 0 0)
			(layers "F.Cu" "F.Mask" "F.Paste")
			(net "MB_3V3IO_RSVD1_ISO_R")
		)
		(pad "2" smd circle
			(at 0.40005 0 270)
			(size 0 0)
			(layers "F.Cu" "F.Mask" "F.Paste")
			(net "MB_3V3IO_RSVD1_ISO")
		)
	)
	(footprint ""
		(layer "F.Cu")
		(at 207.734408 -310.478932 -45)
		(property "Reference" "R3944"
			(at 0 0 315)
			(layer "F.SilkS")
			(hide yes)
			(effects
				(font
					(size 1.27 1.27)
				)
			)
		)
		(property "Value" ""
			(at 0 0 315)
			(layer "F.Fab")
			(effects
				(font
					(size 1.27 1.27)
				)
			)
		)
		(duplicate_pad_numbers_are_jumpers no)
		(fp_line
			(start -0.787389 0.406267)
			(end -0.787389 -0.406267)
			(stroke
				(width 0.1524)
				(type default)
			)
			(layer "F.SilkS")
		)
		(fp_line
			(start -0.787389 -0.406267)
			(end 0.787389 -0.406267)
			(stroke
				(width 0.1524)
				(type default)
			)
			(layer "F.SilkS")
		)
		(fp_line
			(start 0.787389 0.406267)
			(end -0.787389 0.406267)
			(stroke
				(width 0.1524)
				(type default)
			)
			(layer "F.SilkS")
		)
		(fp_line
			(start 0.787389 -0.406267)
			(end 0.787389 0.406267)
			(stroke
				(width 0.1524)
				(type default)
			)
			(layer "F.SilkS")
		)
		(fp_line
			(start -0.679446 0.30479)
			(end -0.679446 -0.305149)
			(stroke
				(width 0.1)
				(type default)
			)
			(layer "F.Fab")
		)
		(fp_line
			(start -0.120515 0.30479)
			(end -0.679446 0.30479)
			(stroke
				(width 0.1)
				(type default)
			)
			(layer "F.Fab")
		)
		(fp_line
			(start -0.120695 0.279466)
			(end -0.120515 0.30479)
			(stroke
				(width 0.1)
				(type default)
			)
			(layer "F.Fab")
		)
		(fp_line
			(start -0.679446 -0.305149)
			(end -0.120695 -0.304969)
			(stroke
				(width 0.1)
				(type default)
			)
			(layer "F.Fab")
		)
		(fp_line
			(start 0.120515 0.30479)
			(end 0.120335 0.279466)
			(stroke
				(width 0.1)
				(type default)
			)
			(layer "F.Fab")
		)
		(fp_line
			(start 0.120335 0.279466)
			(end -0.120695 0.279466)
			(stroke
				(width 0.1)
				(type default)
			)
			(layer "F.Fab")
		)
		(fp_line
			(start -0.120695 -0.279466)
			(end 0.120695 -0.279466)
			(stroke
				(width 0.1)
				(type default)
			)
			(layer "F.Fab")
		)
		(fp_line
			(start -0.120695 -0.304969)
			(end -0.120695 -0.279466)
			(stroke
				(width 0.1)
				(type default)
			)
			(layer "F.Fab")
		)
		(fp_line
			(start 0.679446 0.30479)
			(end 0.120515 0.30479)
			(stroke
				(width 0.1)
				(type default)
			)
			(layer "F.Fab")
		)
		(fp_line
			(start 0.120695 -0.279466)
			(end 0.120515 -0.30479)
			(stroke
				(width 0.1)
				(type default)
			)
			(layer "F.Fab")
		)
		(fp_line
			(start 0.120515 -0.30479)
			(end 0.679446 -0.30479)
			(stroke
				(width 0.1)
				(type default)
			)
			(layer "F.Fab")
		)
		(fp_line
			(start 0.679446 -0.30479)
			(end 0.679446 0.30479)
			(stroke
				(width 0.1)
				(type default)
			)
			(layer "F.Fab")
		)
		(pad "1" smd circle
			(at -0.40005 0 315)
			(size 0 0)
			(layers "F.Cu" "F.Mask" "F.Paste")
			(net "PU_PEX1_SIO_BLINK")
		)
		(pad "2" smd circle
			(at 0.40005 0 315)
			(size 0 0)
			(layers "F.Cu" "F.Mask" "F.Paste")
			(net "P1V8_PEX")
		)
	)
	(footprint ""
		(layer "F.Cu")
		(at 352.920554 -91.788234 180)
		(property "Reference" "R1607"
			(at 0 0 180)
			(layer "F.SilkS")
			(hide yes)
			(effects
				(font
					(size 1.27 1.27)
				)
			)
		)
		(property "Value" ""
			(at 0 0 180)
			(layer "F.Fab")
			(effects
				(font
					(size 1.27 1.27)
				)
			)
		)
		(duplicate_pad_numbers_are_jumpers no)
		(fp_line
			(start 0.7874 0.4064)
			(end -0.7874 0.4064)
			(stroke
				(width 0.1524)
				(type default)
			)
			(layer "F.SilkS")
		)
		(fp_line
			(start 0.7874 -0.4064)
			(end 0.7874 0.4064)
			(stroke
				(width 0.1524)
				(type default)
			)
			(layer "F.SilkS")
		)
		(fp_line
			(start -0.7874 0.4064)
			(end -0.7874 -0.4064)
			(stroke
				(width 0.1524)
				(type default)
			)
			(layer "F.SilkS")
		)
		(fp_line
			(start -0.7874 -0.4064)
			(end 0.7874 -0.4064)
			(stroke
				(width 0.1524)
				(type default)
			)
			(layer "F.SilkS")
		)
		(fp_line
			(start 0.67945 0.3048)
			(end 0.120396 0.3048)
			(stroke
				(width 0.1)
				(type default)
			)
			(layer "F.Fab")
		)
		(fp_line
			(start 0.67945 -0.3048)
			(end 0.67945 0.3048)
			(stroke
				(width 0.1)
				(type default)
			)
			(layer "F.Fab")
		)
		(fp_line
			(start 0.12065 -0.2794)
			(end 0.12065 -0.3048)
			(stroke
				(width 0.1)
				(type default)
			)
			(layer "F.Fab")
		)
		(fp_line
			(start 0.12065 -0.3048)
			(end 0.67945 -0.3048)
			(stroke
				(width 0.1)
				(type default)
			)
			(layer "F.Fab")
		)
		(fp_line
			(start 0.120396 0.3048)
			(end 0.120396 0.2794)
			(stroke
				(width 0.1)
				(type default)
			)
			(layer "F.Fab")
		)
		(fp_line
			(start 0.120396 0.2794)
			(end -0.12065 0.2794)
			(stroke
				(width 0.1)
				(type default)
			)
			(layer "F.Fab")
		)
		(fp_line
			(start -0.12065 0.3048)
			(end -0.67945 0.3048)
			(stroke
				(width 0.1)
				(type default)
			)
			(layer "F.Fab")
		)
		(fp_line
			(start -0.12065 0.2794)
			(end -0.12065 0.3048)
			(stroke
				(width 0.1)
				(type default)
			)
			(layer "F.Fab")
		)
		(fp_line
			(start -0.12065 -0.2794)
			(end 0.12065 -0.2794)
			(stroke
				(width 0.1)
				(type default)
			)
			(layer "F.Fab")
		)
		(fp_line
			(start -0.12065 -0.305054)
			(end -0.12065 -0.2794)
			(stroke
				(width 0.1)
				(type default)
			)
			(layer "F.Fab")
		)
		(fp_line
			(start -0.67945 0.3048)
			(end -0.67945 -0.305054)
			(stroke
				(width 0.1)
				(type default)
			)
			(layer "F.Fab")
		)
		(fp_line
			(start -0.67945 -0.305054)
			(end -0.12065 -0.305054)
			(stroke
				(width 0.1)
				(type default)
			)
			(layer "F.Fab")
		)
		(pad "1" smd circle
			(at -0.40005 0 180)
			(size 0 0)
			(layers "F.Cu" "F.Mask" "F.Paste")
			(net "BIC_I2C9_SSD_MUX1_A0")
		)
		(pad "2" smd circle
			(at 0.40005 0 180)
			(size 0 0)
			(layers "F.Cu" "F.Mask" "F.Paste")
			(net "GND")
		)
	)
	(footprint ""
		(layer "F.Cu")
		(at 234.021122 -92.266516 90)
		(property "Reference" "U112"
			(at 0 0 90)
			(layer "F.SilkS")
			(hide yes)
			(effects
				(font
					(size 1.27 1.27)
				)
			)
		)
		(property "Value" ""
			(at 0 0 90)
			(layer "F.Fab")
			(effects
				(font
					(size 1.27 1.27)
				)
			)
		)
		(duplicate_pad_numbers_are_jumpers no)
		(fp_line
			(start 0 -2.921)
			(end 0 -3.302)
			(stroke
				(width 0.1524)
				(type default)
			)
			(layer "F.SilkS")
		)
		(fp_line
			(start 2.500122 -2.500122)
			(end 2.500122 -1.778)
			(stroke
				(width 0.1524)
				(type default)
			)
			(layer "F.SilkS")
		)
		(fp_line
			(start 1.778 -2.500122)
			(end 2.500122 -2.500122)
			(stroke
				(width 0.1524)
				(type default)
			)
			(layer "F.SilkS")
		)
		(fp_line
			(start -2.500122 -2.500122)
			(end -1.778 -2.500122)
			(stroke
				(width 0.1524)
				(type default)
			)
			(layer "F.SilkS")
		)
		(fp_line
			(start -2.500122 -1.778)
			(end -2.500122 -2.500122)
			(stroke
				(width 0.1524)
				(type default)
			)
			(layer "F.SilkS")
		)
		(fp_line
			(start 2.921 -1.016)
			(end 3.683 -1.016)
			(stroke
				(width 0.1524)
				(type default)
			)
			(layer "F.SilkS")
		)
		(fp_line
			(start -2.921 0.508)
			(end -3.302 0.508)
			(stroke
				(width 0.1524)
				(type default)
			)
			(layer "F.SilkS")
		)
		(fp_line
			(start 2.921 1.524)
			(end 3.302 1.524)
			(stroke
				(width 0.1524)
				(type default)
			)
			(layer "F.SilkS")
		)
		(fp_line
			(start 2.500122 1.778)
			(end 2.500122 2.500122)
			(stroke
				(width 0.1524)
				(type default)
			)
			(layer "F.SilkS")
		)
		(fp_line
			(start 2.500122 2.500122)
			(end 1.778 2.500122)
			(stroke
				(width 0.1524)
				(type default)
			)
			(layer "F.SilkS")
		)
		(fp_line
			(start -1.778 2.500122)
			(end -2.500122 2.500122)
			(stroke
				(width 0.1524)
				(type default)
			)
			(layer "F.SilkS")
		)
		(fp_line
			(start -2.500122 2.500122)
			(end -2.500122 1.778)
			(stroke
				(width 0.1524)
				(type default)
			)
			(layer "F.SilkS")
		)
		(fp_line
			(start -0.508 2.921)
			(end -0.508 3.683)
			(stroke
				(width 0.1524)
				(type default)
			)
			(layer "F.SilkS")
		)
		(fp_poly
			(pts
				(xy -2.883408 -2.518918) (xy -2.632964 -1.768602) (xy -3.383534 -2.018792)
			)
			(stroke
				(width 0)
				(type default)
			)
			(fill yes)
			(layer "F.SilkS")
		)
		(fp_line
			(start 0 -2.921)
			(end 0 -3.302)
			(stroke
				(width 0.1)
				(type default)
			)
			(layer "F.Fab")
		)
		(fp_line
			(start 2.500122 -2.500122)
			(end 2.500122 2.500122)
			(stroke
				(width 0.1)
				(type default)
			)
			(layer "F.Fab")
		)
		(fp_line
			(start -2.500122 -2.500122)
			(end 2.500122 -2.500122)
			(stroke
				(width 0.1)
				(type default)
			)
			(layer "F.Fab")
		)
		(fp_line
			(start 2.921 -1.016)
			(end 3.683 -1.016)
			(stroke
				(width 0.1)
				(type default)
			)
			(layer "F.Fab")
		)
		(fp_line
			(start -2.921 0.508)
			(end -3.302 0.508)
			(stroke
				(width 0.1)
				(type default)
			)
			(layer "F.Fab")
		)
		(fp_line
			(start 2.921 1.524)
			(end 3.302 1.524)
			(stroke
				(width 0.1)
				(type default)
			)
			(layer "F.Fab")
		)
		(fp_line
			(start 2.500122 2.500122)
			(end -2.500122 2.500122)
			(stroke
				(width 0.1)
				(type default)
			)
			(layer "F.Fab")
		)
		(fp_line
			(start -2.500122 2.500122)
			(end -2.500122 -2.500122)
			(stroke
				(width 0.1)
				(type default)
			)
			(layer "F.Fab")
		)
		(fp_line
			(start -0.508 2.921)
			(end -0.508 3.683)
			(stroke
				(width 0.1)
				(type default)
			)
			(layer "F.Fab")
		)
		(fp_poly
			(pts
				(xy -3.7592 -1.933194) (xy -2.892806 -1.500124) (xy -3.7592 -1.0668)
			)
			(stroke
				(width 0)
				(type default)
			)
			(fill yes)
			(layer "F.Fab")
		)
		(fp_text user "28"
			(at -2.241804 -3.229356 90)
			(unlocked yes)
			(layer "F.SilkS")
			(effects
				(font
					(size 0.635 0.4064)
					(thickness 0.1524)
				)
			)
		)
		(fp_text user "22"
			(at 2.2352 -3.172968 90)
			(unlocked yes)
			(layer "F.SilkS")
			(effects
				(font
					(size 0.635 0.4064)
					(thickness 0.1524)
				)
			)
		)
		(fp_text user "21"
			(at 3.227832 -2.2606 180)
			(unlocked yes)
			(layer "F.SilkS")
			(effects
				(font
					(size 0.635 0.4064)
					(thickness 0.1524)
				)
			)
		)
		(fp_text user "7"
			(at -3.147568 1.8034 180)
			(unlocked yes)
			(layer "F.SilkS")
			(effects
				(font
					(size 0.635 0.4064)
					(thickness 0.1524)
				)
			)
		)
		(fp_text user "15"
			(at 3.253232 2.2352 180)
			(unlocked yes)
			(layer "F.SilkS")
			(effects
				(font
					(size 0.635 0.4064)
					(thickness 0.1524)
				)
			)
		)
		(fp_text user "14"
			(at 2.1336 3.253232 90)
			(unlocked yes)
			(layer "F.SilkS")
			(effects
				(font
					(size 0.635 0.4064)
					(thickness 0.1524)
				)
			)
		)
		(fp_text user "8"
			(at -1.8796 3.253232 90)
			(unlocked yes)
			(layer "F.SilkS")
			(effects
				(font
					(size 0.635 0.4064)
					(thickness 0.1524)
				)
			)
		)
		(fp_text user "22"
			(at 2.2352 -3.172968 90)
			(unlocked yes)
			(layer "F.Fab")
			(effects
				(font
					(size 0.635 0.4064)
					(thickness 0.1524)
				)
			)
		)
		(fp_text user "28"
			(at -2.2098 -3.172968 90)
			(unlocked yes)
			(layer "F.Fab")
			(effects
				(font
					(size 0.635 0.4064)
					(thickness 0.1524)
				)
			)
		)
		(fp_text user "21"
			(at 3.227832 -2.2606 180)
			(unlocked yes)
			(layer "F.Fab")
			(effects
				(font
					(size 0.635 0.4064)
					(thickness 0.1524)
				)
			)
		)
		(fp_text user "7"
			(at -3.147568 1.8034 180)
			(unlocked yes)
			(layer "F.Fab")
			(effects
				(font
					(size 0.635 0.4064)
					(thickness 0.1524)
				)
			)
		)
		(fp_text user "15"
			(at 3.253232 2.2352 180)
			(unlocked yes)
			(layer "F.Fab")
			(effects
				(font
					(size 0.635 0.4064)
					(thickness 0.1524)
				)
			)
		)
		(fp_text user "14"
			(at 2.1336 3.253232 90)
			(unlocked yes)
			(layer "F.Fab")
			(effects
				(font
					(size 0.635 0.4064)
					(thickness 0.1524)
				)
			)
		)
		(fp_text user "8"
			(at -1.8796 3.253232 90)
			(unlocked yes)
			(layer "F.Fab")
			(effects
				(font
					(size 0.635 0.4064)
					(thickness 0.1524)
				)
			)
		)
		(pad "1" smd rect
			(at -2.412492 -1.500124 180)
			(size 0.254 0.7366)
			(layers "F.Cu" "F.Mask" "F.Paste")
			(net "USB2_PEX_HUB_R_DN")
		)
		(pad "2" smd rect
			(at -2.412492 -0.999998 180)
			(size 0.254 0.7366)
			(layers "F.Cu" "F.Mask" "F.Paste")
			(net "USB2_PEX_HUB_R_DP")
		)
		(pad "3" smd rect
			(at -2.412492 -0.499872 180)
			(size 0.254 0.7366)
			(layers "F.Cu" "F.Mask" "F.Paste")
			(net "USB2_FT4232_SDB_R_DN")
		)
		(pad "4" smd rect
			(at -2.412492 0 180)
			(size 0.254 0.7366)
			(layers "F.Cu" "F.Mask" "F.Paste")
			(net "USB2_FT4232_SDB_R_DP")
		)
		(pad "5" smd rect
			(at -2.412492 0.499872 180)
			(size 0.254 0.7366)
			(layers "F.Cu" "F.Mask" "F.Paste")
			(net "P3V3_PEX_USB_HUB")
		)
		(pad "6" smd rect
			(at -2.412492 0.999998 180)
			(size 0.254 0.7366)
			(layers "F.Cu" "F.Mask" "F.Paste")
			(net "USB2_FT4232_CLI_R_DN")
		)
		(pad "7" smd rect
			(at -2.412492 1.500124 180)
			(size 0.254 0.7366)
			(layers "F.Cu" "F.Mask" "F.Paste")
			(net "USB2_FT4232_CLI_R_DP")
		)
		(pad "8" smd rect
			(at -1.500124 2.412492 90)
			(size 0.254 0.7366)
			(layers "F.Cu" "F.Mask" "F.Paste")
			(net "PEX_USB_HUB_RREF")
		)
		(pad "9" smd rect
			(at -0.999998 2.412492 90)
			(size 0.254 0.7366)
			(layers "F.Cu" "F.Mask" "F.Paste")
			(net "P3V3_PEX_USB_HUB")
		)
		(pad "10" smd rect
			(at -0.499872 2.412492 90)
			(size 0.254 0.7366)
			(layers "F.Cu" "F.Mask" "F.Paste")
			(net "PEX_USB_HUB_XIN")
		)
		(pad "11" smd rect
			(at 0 2.412492 90)
			(size 0.254 0.7366)
			(layers "F.Cu" "F.Mask" "F.Paste")
			(net "PEX_USB_HUB_XOUT")
		)
		(pad "12" smd rect
			(at 0.499872 2.412492 90)
			(size 0.254 0.7366)
			(layers "F.Cu" "F.Mask" "F.Paste")
			(net "Net_4251")
		)
		(pad "13" smd rect
			(at 0.999998 2.412492 90)
			(size 0.254 0.7366)
			(layers "F.Cu" "F.Mask" "F.Paste")
			(net "Net_4253")
		)
		(pad "14" smd rect
			(at 1.500124 2.412492 90)
			(size 0.254 0.7366)
			(layers "F.Cu" "F.Mask" "F.Paste")
			(net "P3V3_PEX_USB_HUB")
		)
		(pad "15" smd rect
			(at 2.412492 1.500124 180)
			(size 0.254 0.7366)
			(layers "F.Cu" "F.Mask" "F.Paste")
			(net "Net_4252")
		)
		(pad "16" smd rect
			(at 2.412492 0.999998 180)
			(size 0.254 0.7366)
			(layers "F.Cu" "F.Mask" "F.Paste")
			(net "Net_4254")
		)
		(pad "17" smd rect
			(at 2.412492 0.499872 180)
			(size 0.254 0.7366)
			(layers "F.Cu" "F.Mask" "F.Paste")
			(net "RST_PEX_USB_HUB_R_N")
		)
		(pad "18" smd rect
			(at 2.412492 0 180)
			(size 0.254 0.7366)
			(layers "F.Cu" "F.Mask" "F.Paste")
			(net "PEX_USB_HUB_TEST")
		)
		(pad "19" smd rect
			(at 2.412492 -0.499872 180)
			(size 0.254 0.7366)
			(layers "F.Cu" "F.Mask" "F.Paste")
			(net "PEX_USB_HUB_OVCUR4")
		)
		(pad "20" smd rect
			(at 2.412492 -0.999998 180)
			(size 0.254 0.7366)
			(layers "F.Cu" "F.Mask" "F.Paste")
			(net "PEX_USB_HUB_OVCUR3")
		)
		(pad "21" smd rect
			(at 2.412492 -1.500124 180)
			(size 0.254 0.7366)
			(layers "F.Cu" "F.Mask" "F.Paste")
			(net "P3V3_PEX_USB_HUB")
		)
		(pad "22" smd rect
			(at 1.500124 -2.412492 90)
			(size 0.254 0.7366)
			(layers "F.Cu" "F.Mask" "F.Paste")
			(net "PEX_USB_HUB_PSELF")
		)
		(pad "23" smd rect
			(at 0.999998 -2.412492 90)
			(size 0.254 0.7366)
			(layers "F.Cu" "F.Mask" "F.Paste")
			(net "PEX_USB_HUB_PGANG")
		)
		(pad "24" smd rect
			(at 0.499872 -2.412492 90)
			(size 0.254 0.7366)
			(layers "F.Cu" "F.Mask" "F.Paste")
			(net "PEX_USB_HUB_OVCUR2")
		)
		(pad "25" smd rect
			(at 0 -2.412492 90)
			(size 0.254 0.7366)
			(layers "F.Cu" "F.Mask" "F.Paste")
			(net "PEX_USB_HUB_OVCUR1")
		)
		(pad "26" smd rect
			(at -0.499872 -2.412492 90)
			(size 0.254 0.7366)
			(layers "F.Cu" "F.Mask" "F.Paste")
			(net "Net_4255")
		)
		(pad "27" smd rect
			(at -0.999998 -2.412492 90)
			(size 0.254 0.7366)
			(layers "F.Cu" "F.Mask" "F.Paste")
			(net "P3V3_PEX_USB_HUB")
		)
		(pad "28" smd rect
			(at -1.500124 -2.412492 90)
			(size 0.254 0.7366)
			(layers "F.Cu" "F.Mask" "F.Paste")
			(net "P3V3_PEX_USB_HUB")
		)
		(pad "TH" smd rect
			(at 0 0 90)
			(size 3.556 3.556)
			(layers "F.Cu" "F.Mask" "F.Paste")
			(net "GND")
		)
		(zone
			(layer "F.Cu")
			(hatch none 0.5)
			(connect_pads
				(clearance 0)
			)
			(min_thickness 0.25)
			(keepout
				(tracks not_allowed)
				(vias allowed)
				(pads allowed)
				(copperpour not_allowed)
				(footprints allowed)
			)
			(placement
				(enabled no)
				(sheetname "")
			)
			(fill
				(thermal_gap 0.5)
				(thermal_bridge_width 0.5)
				(island_removal_mode 0)
			)
			(polygon
				(pts
					(xy 232.039922 -93.206316) (xy 232.192322 -93.206316) (xy 232.192322 -90.437716) (xy 235.849922 -90.437716)
					(xy 235.849922 -94.095316) (xy 232.192322 -94.095316) (xy 232.192322 -93.231716) (xy 232.039922 -93.231716)
					(xy 232.039922 -94.247716) (xy 236.002322 -94.247716) (xy 236.002322 -90.285316) (xy 232.039922 -90.285316)
				)
			)
		)
	)
	(footprint ""
		(layer "F.Cu")
		(at 144.261332 -389.58901 90)
		(property "Reference" "C4106"
			(at 0 0 90)
			(layer "F.SilkS")
			(hide yes)
			(effects
				(font
					(size 1.27 1.27)
				)
			)
		)
		(property "Value" ""
			(at 0 0 90)
			(layer "F.Fab")
			(effects
				(font
					(size 1.27 1.27)
				)
			)
		)
		(duplicate_pad_numbers_are_jumpers no)
		(fp_line
			(start 0.7874 -0.4064)
			(end 0.7874 0.4064)
			(stroke
				(width 0.1524)
				(type default)
			)
			(layer "F.SilkS")
		)
		(fp_line
			(start -0.7874 -0.4064)
			(end 0.7874 -0.4064)
			(stroke
				(width 0.1524)
				(type default)
			)
			(layer "F.SilkS")
		)
		(fp_line
			(start 0.7874 0.4064)
			(end -0.7874 0.4064)
			(stroke
				(width 0.1524)
				(type default)
			)
			(layer "F.SilkS")
		)
		(fp_line
			(start -0.7874 0.4064)
			(end -0.7874 -0.4064)
			(stroke
				(width 0.1524)
				(type default)
			)
			(layer "F.SilkS")
		)
		(fp_line
			(start -0.12065 -0.305054)
			(end -0.12065 -0.2794)
			(stroke
				(width 0.1)
				(type default)
			)
			(layer "F.Fab")
		)
		(fp_line
			(start -0.67945 -0.305054)
			(end -0.12065 -0.305054)
			(stroke
				(width 0.1)
				(type default)
			)
			(layer "F.Fab")
		)
		(fp_line
			(start 0.67945 -0.3048)
			(end 0.67945 0.3048)
			(stroke
				(width 0.1)
				(type default)
			)
			(layer "F.Fab")
		)
		(fp_line
			(start 0.12065 -0.3048)
			(end 0.67945 -0.3048)
			(stroke
				(width 0.1)
				(type default)
			)
			(layer "F.Fab")
		)
		(fp_line
			(start 0.12065 -0.2794)
			(end 0.12065 -0.3048)
			(stroke
				(width 0.1)
				(type default)
			)
			(layer "F.Fab")
		)
		(fp_line
			(start -0.12065 -0.2794)
			(end 0.12065 -0.2794)
			(stroke
				(width 0.1)
				(type default)
			)
			(layer "F.Fab")
		)
		(fp_line
			(start 0.120396 0.2794)
			(end -0.12065 0.2794)
			(stroke
				(width 0.1)
				(type default)
			)
			(layer "F.Fab")
		)
		(fp_line
			(start -0.12065 0.2794)
			(end -0.12065 0.3048)
			(stroke
				(width 0.1)
				(type default)
			)
			(layer "F.Fab")
		)
		(fp_line
			(start 0.67945 0.3048)
			(end 0.120396 0.3048)
			(stroke
				(width 0.1)
				(type default)
			)
			(layer "F.Fab")
		)
		(fp_line
			(start 0.120396 0.3048)
			(end 0.120396 0.2794)
			(stroke
				(width 0.1)
				(type default)
			)
			(layer "F.Fab")
		)
		(fp_line
			(start -0.12065 0.3048)
			(end -0.67945 0.3048)
			(stroke
				(width 0.1)
				(type default)
			)
			(layer "F.Fab")
		)
		(fp_line
			(start -0.67945 0.3048)
			(end -0.67945 -0.305054)
			(stroke
				(width 0.1)
				(type default)
			)
			(layer "F.Fab")
		)
		(pad "1" smd circle
			(at -0.40005 0 90)
			(size 0 0)
			(layers "F.Cu" "F.Mask" "F.Paste")
			(net "GND")
		)
		(pad "2" smd circle
			(at 0.40005 0 90)
			(size 0 0)
			(layers "F.Cu" "F.Mask" "F.Paste")
			(net "SMB_GPU1_ALERT_N")
		)
	)
	(footprint ""
		(layer "F.Cu")
		(at 383.818384 -250.070874 -90)
		(property "Reference" "R1417"
			(at 0 0 270)
			(layer "F.SilkS")
			(hide yes)
			(effects
				(font
					(size 1.27 1.27)
				)
			)
		)
		(property "Value" ""
			(at 0 0 270)
			(layer "F.Fab")
			(effects
				(font
					(size 1.27 1.27)
				)
			)
		)
		(duplicate_pad_numbers_are_jumpers no)
		(fp_line
			(start -0.7874 0.4064)
			(end -0.7874 -0.4064)
			(stroke
				(width 0.1524)
				(type default)
			)
			(layer "F.SilkS")
		)
		(fp_line
			(start 0.7874 0.4064)
			(end -0.7874 0.4064)
			(stroke
				(width 0.1524)
				(type default)
			)
			(layer "F.SilkS")
		)
		(fp_line
			(start -0.7874 -0.4064)
			(end 0.7874 -0.4064)
			(stroke
				(width 0.1524)
				(type default)
			)
			(layer "F.SilkS")
		)
		(fp_line
			(start 0.7874 -0.4064)
			(end 0.7874 0.4064)
			(stroke
				(width 0.1524)
				(type default)
			)
			(layer "F.SilkS")
		)
		(fp_line
			(start -0.67945 0.3048)
			(end -0.67945 -0.305054)
			(stroke
				(width 0.1)
				(type default)
			)
			(layer "F.Fab")
		)
		(fp_line
			(start -0.12065 0.3048)
			(end -0.67945 0.3048)
			(stroke
				(width 0.1)
				(type default)
			)
			(layer "F.Fab")
		)
		(fp_line
			(start 0.120396 0.3048)
			(end 0.120396 0.2794)
			(stroke
				(width 0.1)
				(type default)
			)
			(layer "F.Fab")
		)
		(fp_line
			(start 0.67945 0.3048)
			(end 0.120396 0.3048)
			(stroke
				(width 0.1)
				(type default)
			)
			(layer "F.Fab")
		)
		(fp_line
			(start -0.12065 0.2794)
			(end -0.12065 0.3048)
			(stroke
				(width 0.1)
				(type default)
			)
			(layer "F.Fab")
		)
		(fp_line
			(start 0.120396 0.2794)
			(end -0.12065 0.2794)
			(stroke
				(width 0.1)
				(type default)
			)
			(layer "F.Fab")
		)
		(fp_line
			(start -0.12065 -0.2794)
			(end 0.12065 -0.2794)
			(stroke
				(width 0.1)
				(type default)
			)
			(layer "F.Fab")
		)
		(fp_line
			(start 0.12065 -0.2794)
			(end 0.12065 -0.3048)
			(stroke
				(width 0.1)
				(type default)
			)
			(layer "F.Fab")
		)
		(fp_line
			(start 0.12065 -0.3048)
			(end 0.67945 -0.3048)
			(stroke
				(width 0.1)
				(type default)
			)
			(layer "F.Fab")
		)
		(fp_line
			(start 0.67945 -0.3048)
			(end 0.67945 0.3048)
			(stroke
				(width 0.1)
				(type default)
			)
			(layer "F.Fab")
		)
		(fp_line
			(start -0.67945 -0.305054)
			(end -0.12065 -0.305054)
			(stroke
				(width 0.1)
				(type default)
			)
			(layer "F.Fab")
		)
		(fp_line
			(start -0.12065 -0.305054)
			(end -0.12065 -0.2794)
			(stroke
				(width 0.1)
				(type default)
			)
			(layer "F.Fab")
		)
		(pad "1" smd circle
			(at -0.40005 0 270)
			(size 0 0)
			(layers "F.Cu" "F.Mask" "F.Paste")
			(net "PEX3_MODE_SEL12")
		)
		(pad "2" smd circle
			(at 0.40005 0 270)
			(size 0 0)
			(layers "F.Cu" "F.Mask" "F.Paste")
			(net "P1V8_PEX")
		)
	)
	(footprint ""
		(layer "F.Cu")
		(at 245.77675 -258.034536 -90)
		(property "Reference" "R6525"
			(at 0 0 270)
			(layer "F.SilkS")
			(hide yes)
			(effects
				(font
					(size 1.27 1.27)
				)
			)
		)
		(property "Value" ""
			(at 0 0 270)
			(layer "F.Fab")
			(effects
				(font
					(size 1.27 1.27)
				)
			)
		)
		(duplicate_pad_numbers_are_jumpers no)
		(fp_line
			(start -0.7874 0.4064)
			(end -0.7874 -0.4064)
			(stroke
				(width 0.1524)
				(type default)
			)
			(layer "F.SilkS")
		)
		(fp_line
			(start 0.7874 0.4064)
			(end -0.7874 0.4064)
			(stroke
				(width 0.1524)
				(type default)
			)
			(layer "F.SilkS")
		)
		(fp_line
			(start -0.7874 -0.4064)
			(end 0.7874 -0.4064)
			(stroke
				(width 0.1524)
				(type default)
			)
			(layer "F.SilkS")
		)
		(fp_line
			(start 0.7874 -0.4064)
			(end 0.7874 0.4064)
			(stroke
				(width 0.1524)
				(type default)
			)
			(layer "F.SilkS")
		)
		(fp_line
			(start -0.67945 0.3048)
			(end -0.67945 -0.305054)
			(stroke
				(width 0.1)
				(type default)
			)
			(layer "F.Fab")
		)
		(fp_line
			(start -0.12065 0.3048)
			(end -0.67945 0.3048)
			(stroke
				(width 0.1)
				(type default)
			)
			(layer "F.Fab")
		)
		(fp_line
			(start 0.120396 0.3048)
			(end 0.120396 0.2794)
			(stroke
				(width 0.1)
				(type default)
			)
			(layer "F.Fab")
		)
		(fp_line
			(start 0.67945 0.3048)
			(end 0.120396 0.3048)
			(stroke
				(width 0.1)
				(type default)
			)
			(layer "F.Fab")
		)
		(fp_line
			(start -0.12065 0.2794)
			(end -0.12065 0.3048)
			(stroke
				(width 0.1)
				(type default)
			)
			(layer "F.Fab")
		)
		(fp_line
			(start 0.120396 0.2794)
			(end -0.12065 0.2794)
			(stroke
				(width 0.1)
				(type default)
			)
			(layer "F.Fab")
		)
		(fp_line
			(start -0.12065 -0.2794)
			(end 0.12065 -0.2794)
			(stroke
				(width 0.1)
				(type default)
			)
			(layer "F.Fab")
		)
		(fp_line
			(start 0.12065 -0.2794)
			(end 0.12065 -0.3048)
			(stroke
				(width 0.1)
				(type default)
			)
			(layer "F.Fab")
		)
		(fp_line
			(start 0.12065 -0.3048)
			(end 0.67945 -0.3048)
			(stroke
				(width 0.1)
				(type default)
			)
			(layer "F.Fab")
		)
		(fp_line
			(start 0.67945 -0.3048)
			(end 0.67945 0.3048)
			(stroke
				(width 0.1)
				(type default)
			)
			(layer "F.Fab")
		)
		(fp_line
			(start -0.67945 -0.305054)
			(end -0.12065 -0.305054)
			(stroke
				(width 0.1)
				(type default)
			)
			(layer "F.Fab")
		)
		(fp_line
			(start -0.12065 -0.305054)
			(end -0.12065 -0.2794)
			(stroke
				(width 0.1)
				(type default)
			)
			(layer "F.Fab")
		)
		(pad "1" smd circle
			(at -0.40005 0 270)
			(size 0 0)
			(layers "F.Cu" "F.Mask" "F.Paste")
			(net "P1V25_SERDES_VDDPLL_PEX2")
		)
		(pad "2" smd circle
			(at 0.40005 0 270)
			(size 0 0)
			(layers "F.Cu" "F.Mask" "F.Paste")
			(net "P1V25_SERDES_VDDPLL_PEX2_C4")
		)
	)
	(footprint ""
		(layer "F.Cu")
		(at 453.17283 -258.331208 -90)
		(property "Reference" "R6552"
			(at 0 0 270)
			(layer "F.SilkS")
			(hide yes)
			(effects
				(font
					(size 1.27 1.27)
				)
			)
		)
		(property "Value" ""
			(at 0 0 270)
			(layer "F.Fab")
			(effects
				(font
					(size 1.27 1.27)
				)
			)
		)
		(duplicate_pad_numbers_are_jumpers no)
		(fp_line
			(start -0.7874 0.4064)
			(end -0.7874 -0.4064)
			(stroke
				(width 0.1524)
				(type default)
			)
			(layer "F.SilkS")
		)
		(fp_line
			(start 0.7874 0.4064)
			(end -0.7874 0.4064)
			(stroke
				(width 0.1524)
				(type default)
			)
			(layer "F.SilkS")
		)
		(fp_line
			(start -0.7874 -0.4064)
			(end 0.7874 -0.4064)
			(stroke
				(width 0.1524)
				(type default)
			)
			(layer "F.SilkS")
		)
		(fp_line
			(start 0.7874 -0.4064)
			(end 0.7874 0.4064)
			(stroke
				(width 0.1524)
				(type default)
			)
			(layer "F.SilkS")
		)
		(fp_line
			(start -0.67945 0.3048)
			(end -0.67945 -0.305054)
			(stroke
				(width 0.1)
				(type default)
			)
			(layer "F.Fab")
		)
		(fp_line
			(start -0.12065 0.3048)
			(end -0.67945 0.3048)
			(stroke
				(width 0.1)
				(type default)
			)
			(layer "F.Fab")
		)
		(fp_line
			(start 0.120396 0.3048)
			(end 0.120396 0.2794)
			(stroke
				(width 0.1)
				(type default)
			)
			(layer "F.Fab")
		)
		(fp_line
			(start 0.67945 0.3048)
			(end 0.120396 0.3048)
			(stroke
				(width 0.1)
				(type default)
			)
			(layer "F.Fab")
		)
		(fp_line
			(start -0.12065 0.2794)
			(end -0.12065 0.3048)
			(stroke
				(width 0.1)
				(type default)
			)
			(layer "F.Fab")
		)
		(fp_line
			(start 0.120396 0.2794)
			(end -0.12065 0.2794)
			(stroke
				(width 0.1)
				(type default)
			)
			(layer "F.Fab")
		)
		(fp_line
			(start -0.12065 -0.2794)
			(end 0.12065 -0.2794)
			(stroke
				(width 0.1)
				(type default)
			)
			(layer "F.Fab")
		)
		(fp_line
			(start 0.12065 -0.2794)
			(end 0.12065 -0.3048)
			(stroke
				(width 0.1)
				(type default)
			)
			(layer "F.Fab")
		)
		(fp_line
			(start 0.12065 -0.3048)
			(end 0.67945 -0.3048)
			(stroke
				(width 0.1)
				(type default)
			)
			(layer "F.Fab")
		)
		(fp_line
			(start 0.67945 -0.3048)
			(end 0.67945 0.3048)
			(stroke
				(width 0.1)
				(type default)
			)
			(layer "F.Fab")
		)
		(fp_line
			(start -0.67945 -0.305054)
			(end -0.12065 -0.305054)
			(stroke
				(width 0.1)
				(type default)
			)
			(layer "F.Fab")
		)
		(fp_line
			(start -0.12065 -0.305054)
			(end -0.12065 -0.2794)
			(stroke
				(width 0.1)
				(type default)
			)
			(layer "F.Fab")
		)
		(pad "1" smd circle
			(at -0.40005 0 270)
			(size 0 0)
			(layers "F.Cu" "F.Mask" "F.Paste")
			(net "P1V25_SERDES_VDDPLL_PEX3")
		)
		(pad "2" smd circle
			(at 0.40005 0 270)
			(size 0 0)
			(layers "F.Cu" "F.Mask" "F.Paste")
			(net "P1V25_SERDES_VDDPLL_PEX3_C1")
		)
	)
	(footprint ""
		(layer "F.Cu")
		(at 357.44277 -398.180052 90)
		(property "Reference" "R6701"
			(at 0 0 90)
			(layer "F.SilkS")
			(hide yes)
			(effects
				(font
					(size 1.27 1.27)
				)
			)
		)
		(property "Value" ""
			(at 0 0 90)
			(layer "F.Fab")
			(effects
				(font
					(size 1.27 1.27)
				)
			)
		)
		(duplicate_pad_numbers_are_jumpers no)
		(fp_line
			(start 0.7874 -0.4064)
			(end 0.7874 0.4064)
			(stroke
				(width 0.1524)
				(type default)
			)
			(layer "F.SilkS")
		)
		(fp_line
			(start -0.7874 -0.4064)
			(end 0.7874 -0.4064)
			(stroke
				(width 0.1524)
				(type default)
			)
			(layer "F.SilkS")
		)
		(fp_line
			(start 0.7874 0.4064)
			(end -0.7874 0.4064)
			(stroke
				(width 0.1524)
				(type default)
			)
			(layer "F.SilkS")
		)
		(fp_line
			(start -0.7874 0.4064)
			(end -0.7874 -0.4064)
			(stroke
				(width 0.1524)
				(type default)
			)
			(layer "F.SilkS")
		)
		(fp_line
			(start -0.12065 -0.305054)
			(end -0.12065 -0.2794)
			(stroke
				(width 0.1)
				(type default)
			)
			(layer "F.Fab")
		)
		(fp_line
			(start -0.67945 -0.305054)
			(end -0.12065 -0.305054)
			(stroke
				(width 0.1)
				(type default)
			)
			(layer "F.Fab")
		)
		(fp_line
			(start 0.67945 -0.3048)
			(end 0.67945 0.3048)
			(stroke
				(width 0.1)
				(type default)
			)
			(layer "F.Fab")
		)
		(fp_line
			(start 0.12065 -0.3048)
			(end 0.67945 -0.3048)
			(stroke
				(width 0.1)
				(type default)
			)
			(layer "F.Fab")
		)
		(fp_line
			(start 0.12065 -0.2794)
			(end 0.12065 -0.3048)
			(stroke
				(width 0.1)
				(type default)
			)
			(layer "F.Fab")
		)
		(fp_line
			(start -0.12065 -0.2794)
			(end 0.12065 -0.2794)
			(stroke
				(width 0.1)
				(type default)
			)
			(layer "F.Fab")
		)
		(fp_line
			(start 0.120396 0.2794)
			(end -0.12065 0.2794)
			(stroke
				(width 0.1)
				(type default)
			)
			(layer "F.Fab")
		)
		(fp_line
			(start -0.12065 0.2794)
			(end -0.12065 0.3048)
			(stroke
				(width 0.1)
				(type default)
			)
			(layer "F.Fab")
		)
		(fp_line
			(start 0.67945 0.3048)
			(end 0.120396 0.3048)
			(stroke
				(width 0.1)
				(type default)
			)
			(layer "F.Fab")
		)
		(fp_line
			(start 0.120396 0.3048)
			(end 0.120396 0.2794)
			(stroke
				(width 0.1)
				(type default)
			)
			(layer "F.Fab")
		)
		(fp_line
			(start -0.12065 0.3048)
			(end -0.67945 0.3048)
			(stroke
				(width 0.1)
				(type default)
			)
			(layer "F.Fab")
		)
		(fp_line
			(start -0.67945 0.3048)
			(end -0.67945 -0.305054)
			(stroke
				(width 0.1)
				(type default)
			)
			(layer "F.Fab")
		)
		(pad "1" smd circle
			(at -0.40005 0 90)
			(size 0 0)
			(layers "F.Cu" "F.Mask" "F.Paste")
			(net "MB_3V3IO_RSVD3_ISO")
		)
		(pad "2" smd circle
			(at 0.40005 0 90)
			(size 0 0)
			(layers "F.Cu" "F.Mask" "F.Paste")
			(net "P3V3_AUX")
		)
	)
	(footprint ""
		(layer "F.Cu")
		(at 440.689746 -298.885102 -90)
		(property "Reference" "R3992"
			(at 0 0 270)
			(layer "F.SilkS")
			(hide yes)
			(effects
				(font
					(size 1.27 1.27)
				)
			)
		)
		(property "Value" ""
			(at 0 0 270)
			(layer "F.Fab")
			(effects
				(font
					(size 1.27 1.27)
				)
			)
		)
		(duplicate_pad_numbers_are_jumpers no)
		(fp_line
			(start -0.7874 0.4064)
			(end -0.7874 -0.4064)
			(stroke
				(width 0.1524)
				(type default)
			)
			(layer "F.SilkS")
		)
		(fp_line
			(start 0.7874 0.4064)
			(end -0.7874 0.4064)
			(stroke
				(width 0.1524)
				(type default)
			)
			(layer "F.SilkS")
		)
		(fp_line
			(start -0.7874 -0.4064)
			(end 0.7874 -0.4064)
			(stroke
				(width 0.1524)
				(type default)
			)
			(layer "F.SilkS")
		)
		(fp_line
			(start 0.7874 -0.4064)
			(end 0.7874 0.4064)
			(stroke
				(width 0.1524)
				(type default)
			)
			(layer "F.SilkS")
		)
		(fp_line
			(start -0.67945 0.3048)
			(end -0.67945 -0.305054)
			(stroke
				(width 0.1)
				(type default)
			)
			(layer "F.Fab")
		)
		(fp_line
			(start -0.12065 0.3048)
			(end -0.67945 0.3048)
			(stroke
				(width 0.1)
				(type default)
			)
			(layer "F.Fab")
		)
		(fp_line
			(start 0.120396 0.3048)
			(end 0.120396 0.2794)
			(stroke
				(width 0.1)
				(type default)
			)
			(layer "F.Fab")
		)
		(fp_line
			(start 0.67945 0.3048)
			(end 0.120396 0.3048)
			(stroke
				(width 0.1)
				(type default)
			)
			(layer "F.Fab")
		)
		(fp_line
			(start -0.12065 0.2794)
			(end -0.12065 0.3048)
			(stroke
				(width 0.1)
				(type default)
			)
			(layer "F.Fab")
		)
		(fp_line
			(start 0.120396 0.2794)
			(end -0.12065 0.2794)
			(stroke
				(width 0.1)
				(type default)
			)
			(layer "F.Fab")
		)
		(fp_line
			(start -0.12065 -0.2794)
			(end 0.12065 -0.2794)
			(stroke
				(width 0.1)
				(type default)
			)
			(layer "F.Fab")
		)
		(fp_line
			(start 0.12065 -0.2794)
			(end 0.12065 -0.3048)
			(stroke
				(width 0.1)
				(type default)
			)
			(layer "F.Fab")
		)
		(fp_line
			(start 0.12065 -0.3048)
			(end 0.67945 -0.3048)
			(stroke
				(width 0.1)
				(type default)
			)
			(layer "F.Fab")
		)
		(fp_line
			(start 0.67945 -0.3048)
			(end 0.67945 0.3048)
			(stroke
				(width 0.1)
				(type default)
			)
			(layer "F.Fab")
		)
		(fp_line
			(start -0.67945 -0.305054)
			(end -0.12065 -0.305054)
			(stroke
				(width 0.1)
				(type default)
			)
			(layer "F.Fab")
		)
		(fp_line
			(start -0.12065 -0.305054)
			(end -0.12065 -0.2794)
			(stroke
				(width 0.1)
				(type default)
			)
			(layer "F.Fab")
		)
		(pad "1" smd circle
			(at -0.40005 0 270)
			(size 0 0)
			(layers "F.Cu" "F.Mask" "F.Paste")
			(net "I2C_PEX3_HOST_SCL")
		)
		(pad "2" smd circle
			(at 0.40005 0 270)
			(size 0 0)
			(layers "F.Cu" "F.Mask" "F.Paste")
			(net "I2C_PEX3_HOST_R_SCL")
		)
	)
	(footprint ""
		(layer "F.Cu")
		(at 340.458044 -350.098614 90)
		(property "Reference" "C577"
			(at 0 0 90)
			(layer "F.SilkS")
			(hide yes)
			(effects
				(font
					(size 1.27 1.27)
				)
			)
		)
		(property "Value" ""
			(at 0 0 90)
			(layer "F.Fab")
			(effects
				(font
					(size 1.27 1.27)
				)
			)
		)
		(duplicate_pad_numbers_are_jumpers no)
		(fp_line
			(start 0.299974 -0.150114)
			(end 0.299974 0.150114)
			(stroke
				(width 0.1)
				(type default)
			)
			(layer "F.Fab")
		)
		(fp_line
			(start -0.299974 -0.150114)
			(end 0.299974 -0.150114)
			(stroke
				(width 0.1)
				(type default)
			)
			(layer "F.Fab")
		)
		(fp_line
			(start 0.299974 0.150114)
			(end -0.299974 0.150114)
			(stroke
				(width 0.1)
				(type default)
			)
			(layer "F.Fab")
		)
		(fp_line
			(start -0.299974 0.150114)
			(end -0.299974 -0.150114)
			(stroke
				(width 0.1)
				(type default)
			)
			(layer "F.Fab")
		)
		(pad "1" smd rect
			(at -0.2667 0 90)
			(size 0.3048 0.381)
			(layers "F.Cu" "F.Mask" "F.Paste")
			(net "P5E_PEX2_STN6_TX_DP<98>")
		)
		(pad "2" smd rect
			(at 0.2667 0 90)
			(size 0.3048 0.381)
			(layers "F.Cu" "F.Mask" "F.Paste")
			(net "P5E_PEX2_STN6_TX_C_DP<98>")
		)
	)
	(footprint ""
		(layer "F.Cu")
		(at 130.25882 -319.545462 90)
		(property "Reference" "L29"
			(at 3.089402 2.267458 0)
			(unlocked yes)
			(layer "F.SilkS")
			(effects
				(font
					(size 0.7874 0.5842)
					(thickness 0.1524)
				)
				(justify left)
			)
		)
		(property "Value" ""
			(at 0 0 90)
			(layer "F.Fab")
			(effects
				(font
					(size 1.27 1.27)
				)
			)
		)
		(duplicate_pad_numbers_are_jumpers no)
		(fp_line
			(start 2.248154 -4.9911)
			(end -2.248154 -4.9911)
			(stroke
				(width 0.1524)
				(type default)
			)
			(layer "F.SilkS")
		)
		(fp_line
			(start -2.248154 -4.9911)
			(end -2.248154 -1.61925)
			(stroke
				(width 0.1524)
				(type default)
			)
			(layer "F.SilkS")
		)
		(fp_line
			(start 2.248154 -1.663192)
			(end 2.248154 -4.9911)
			(stroke
				(width 0.1524)
				(type default)
			)
			(layer "F.SilkS")
		)
		(fp_line
			(start -2.248154 1.564894)
			(end -2.248154 4.9911)
			(stroke
				(width 0.1524)
				(type default)
			)
			(layer "F.SilkS")
		)
		(fp_line
			(start 2.248154 4.9911)
			(end 2.248154 1.553972)
			(stroke
				(width 0.1524)
				(type default)
			)
			(layer "F.SilkS")
		)
		(fp_line
			(start -2.248154 4.9911)
			(end 2.248154 4.9911)
			(stroke
				(width 0.1524)
				(type default)
			)
			(layer "F.SilkS")
		)
		(fp_line
			(start 1.700022 -0.899922)
			(end -1.700022 -0.899922)
			(stroke
				(width 0.1)
				(type default)
			)
			(layer "F.Fab")
		)
		(fp_line
			(start -1.700022 -0.899922)
			(end -1.700022 0.899922)
			(stroke
				(width 0.1)
				(type default)
			)
			(layer "F.Fab")
		)
		(fp_line
			(start 1.700022 0.899922)
			(end 1.700022 -0.899922)
			(stroke
				(width 0.1)
				(type default)
			)
			(layer "F.Fab")
		)
		(fp_line
			(start -1.700022 0.899922)
			(end 1.700022 0.899922)
			(stroke
				(width 0.1)
				(type default)
			)
			(layer "F.Fab")
		)
		(pad "1" smd rect
			(at -1.575054 0 90)
			(size 1.1684 9.8044)
			(layers "F.Cu" "F.Mask" "F.Paste")
			(net "P0V8_PEX1")
		)
		(pad "2" smd rect
			(at 1.575054 0 90)
			(size 1.1684 9.8044)
			(layers "F.Cu" "F.Mask" "F.Paste")
			(net "P0V8_SERDES_VDDA_PEX1")
		)
	)
	(footprint ""
		(layer "F.Cu")
		(at 383.59842 -350.098614 90)
		(property "Reference" "C790"
			(at 0 0 90)
			(layer "F.SilkS")
			(hide yes)
			(effects
				(font
					(size 1.27 1.27)
				)
			)
		)
		(property "Value" ""
			(at 0 0 90)
			(layer "F.Fab")
			(effects
				(font
					(size 1.27 1.27)
				)
			)
		)
		(duplicate_pad_numbers_are_jumpers no)
		(fp_line
			(start 0.299974 -0.150114)
			(end 0.299974 0.150114)
			(stroke
				(width 0.1)
				(type default)
			)
			(layer "F.Fab")
		)
		(fp_line
			(start -0.299974 -0.150114)
			(end 0.299974 -0.150114)
			(stroke
				(width 0.1)
				(type default)
			)
			(layer "F.Fab")
		)
		(fp_line
			(start 0.299974 0.150114)
			(end -0.299974 0.150114)
			(stroke
				(width 0.1)
				(type default)
			)
			(layer "F.Fab")
		)
		(fp_line
			(start -0.299974 0.150114)
			(end -0.299974 -0.150114)
			(stroke
				(width 0.1)
				(type default)
			)
			(layer "F.Fab")
		)
		(pad "1" smd rect
			(at -0.2667 0 90)
			(size 0.3048 0.381)
			(layers "F.Cu" "F.Mask" "F.Paste")
			(net "P5E_PEX3_STN6_TX_DP<97>")
		)
		(pad "2" smd rect
			(at 0.2667 0 90)
			(size 0.3048 0.381)
			(layers "F.Cu" "F.Mask" "F.Paste")
			(net "P5E_PEX3_STN6_TX_C_DP<97>")
		)
	)
	(footprint ""
		(layer "F.Cu")
		(at 377.910344 18.028412 180)
		(property "Reference" "DE04F_1"
			(at 2.472944 3.066542 0)
			(unlocked yes)
			(layer "F.SilkS")
			(effects
				(font
					(size 0.7874 0.5842)
					(thickness 0.1524)
				)
				(justify left)
			)
		)
		(property "Value" ""
			(at 0 0 180)
			(layer "F.Fab")
			(effects
				(font
					(size 1.27 1.27)
				)
			)
		)
		(duplicate_pad_numbers_are_jumpers no)
		(fp_line
			(start 1.2192 2.1082)
			(end -1.2192 2.1082)
			(stroke
				(width 0.1524)
				(type default)
			)
			(layer "F.SilkS")
		)
		(fp_line
			(start 1.2192 -2.1082)
			(end 1.2192 2.1082)
			(stroke
				(width 0.1524)
				(type default)
			)
			(layer "F.SilkS")
		)
		(fp_line
			(start -1.2192 2.1082)
			(end -1.2192 -2.1082)
			(stroke
				(width 0.1524)
				(type default)
			)
			(layer "F.SilkS")
		)
		(fp_line
			(start -1.2192 -2.1082)
			(end 1.2192 -2.1082)
			(stroke
				(width 0.1524)
				(type default)
			)
			(layer "F.SilkS")
		)
		(pad "" np_thru_hole circle
			(at -2.8829 -1.27 90)
			(size 1.0414 1.0414)
			(drill 1.0414)
			(layers "*.Cu" "*.Mask")
			(clearance 0.381)
			(thermal_gap 0.381)
		)
		(pad "" np_thru_hole circle
			(at -2.8829 1.27 90)
			(size 1.0414 1.0414)
			(drill 1.0414)
			(layers "*.Cu" "*.Mask")
			(clearance 0.381)
			(thermal_gap 0.381)
		)
		(pad "" np_thru_hole circle
			(at 3.4671 -1.27 90)
			(size 1.0414 1.0414)
			(drill 1.0414)
			(layers "*.Cu" "*.Mask")
			(clearance 0.381)
			(thermal_gap 0.381)
		)
		(pad "" np_thru_hole circle
			(at 3.4671 1.27 90)
			(size 1.0414 1.0414)
			(drill 1.0414)
			(layers "*.Cu" "*.Mask")
			(clearance 0.381)
			(thermal_gap 0.381)
		)
		(pad "1" smd rect
			(at 0.8255 -0.249936 90)
			(size 0.3048 0.508)
			(layers "F.Cu" "F.Mask" "F.Paste")
			(net "85_5INCH_IN2_DN")
		)
		(pad "2" smd rect
			(at 0.8255 0.249936 90)
			(size 0.3048 0.508)
			(layers "F.Cu" "F.Mask" "F.Paste")
			(net "85_5INCH_IN2_DP")
		)
		(pad "3" smd circle
			(at 0 0 180)
			(size 0 0)
			(layers "F.Cu" "F.Mask" "F.Paste")
			(net "COUPON_GND2")
		)
		(zone
			(layer "F.Cu")
			(hatch none 0.5)
			(connect_pads
				(clearance 0)
			)
			(min_thickness 0.25)
			(keepout
				(tracks not_allowed)
				(vias allowed)
				(pads allowed)
				(copperpour not_allowed)
				(footprints allowed)
			)
			(placement
				(enabled no)
				(sheetname "")
			)
			(fill
				(thermal_gap 0.5)
				(thermal_bridge_width 0.5)
				(island_removal_mode 0)
			)
			(polygon
				(pts
					(xy 376.792744 18.577052) (xy 376.792744 18.481548) (xy 377.389644 18.481548) (xy 377.389644 18.075148)
					(xy 376.792744 18.075148) (xy 376.792744 17.981676) (xy 377.389644 17.981676) (xy 377.389644 17.575276)
					(xy 376.792744 17.575276) (xy 376.792744 17.479772) (xy 377.491244 17.479772) (xy 377.491244 18.577052)
				)
			)
		)
		(zone
			(layers "F.Cu" "B.Cu" "In1.Cu" "In2.Cu" "In3.Cu" "In4.Cu" "In5.Cu" "In6.Cu"
				"In7.Cu" "In8.Cu" "In9.Cu" "In10.Cu" "In11.Cu" "In12.Cu" "In13.Cu" "In14.Cu"
				"In15.Cu" "In16.Cu"
			)
			(hatch none 0.5)
			(connect_pads
				(clearance 0)
			)
			(min_thickness 0.25)
			(keepout
				(tracks not_allowed)
				(vias allowed)
				(pads allowed)
				(copperpour not_allowed)
				(footprints allowed)
			)
			(placement
				(enabled no)
				(sheetname "")
			)
			(fill
				(thermal_gap 0.5)
				(thermal_bridge_width 0.5)
				(island_removal_mode 0)
			)
			(polygon
				(pts
					(arc
						(start 375.370344 16.758412)
						(mid 373.516144 16.758412)
						(end 375.370344 16.758412)
					)
				)
			)
		)
		(zone
			(layers "F.Cu" "B.Cu" "In1.Cu" "In2.Cu" "In3.Cu" "In4.Cu" "In5.Cu" "In6.Cu"
				"In7.Cu" "In8.Cu" "In9.Cu" "In10.Cu" "In11.Cu" "In12.Cu" "In13.Cu" "In14.Cu"
				"In15.Cu" "In16.Cu"
			)
			(hatch none 0.5)
			(connect_pads
				(clearance 0)
			)
			(min_thickness 0.25)
			(keepout
				(tracks not_allowed)
				(vias allowed)
				(pads allowed)
				(copperpour not_allowed)
				(footprints allowed)
			)
			(placement
				(enabled no)
				(sheetname "")
			)
			(fill
				(thermal_gap 0.5)
				(thermal_bridge_width 0.5)
				(island_removal_mode 0)
			)
			(polygon
				(pts
					(arc
						(start 375.370344 19.298412)
						(mid 373.516144 19.298412)
						(end 375.370344 19.298412)
					)
				)
			)
		)
		(zone
			(layers "F.Cu" "B.Cu" "In1.Cu" "In2.Cu" "In3.Cu" "In4.Cu" "In5.Cu" "In6.Cu"
				"In7.Cu" "In8.Cu" "In9.Cu" "In10.Cu" "In11.Cu" "In12.Cu" "In13.Cu" "In14.Cu"
				"In15.Cu" "In16.Cu"
			)
			(hatch none 0.5)
			(connect_pads
				(clearance 0)
			)
			(min_thickness 0.25)
			(keepout
				(tracks not_allowed)
				(vias allowed)
				(pads allowed)
				(copperpour not_allowed)
				(footprints allowed)
			)
			(placement
				(enabled no)
				(sheetname "")
			)
			(fill
				(thermal_gap 0.5)
				(thermal_bridge_width 0.5)
				(island_removal_mode 0)
			)
			(polygon
				(pts
					(arc
						(start 381.720344 16.758412)
						(mid 379.866144 16.758412)
						(end 381.720344 16.758412)
					)
				)
			)
		)
		(zone
			(layers "F.Cu" "B.Cu" "In1.Cu" "In2.Cu" "In3.Cu" "In4.Cu" "In5.Cu" "In6.Cu"
				"In7.Cu" "In8.Cu" "In9.Cu" "In10.Cu" "In11.Cu" "In12.Cu" "In13.Cu" "In14.Cu"
				"In15.Cu" "In16.Cu"
			)
			(hatch none 0.5)
			(connect_pads
				(clearance 0)
			)
			(min_thickness 0.25)
			(keepout
				(tracks not_allowed)
				(vias allowed)
				(pads allowed)
				(copperpour not_allowed)
				(footprints allowed)
			)
			(placement
				(enabled no)
				(sheetname "")
			)
			(fill
				(thermal_gap 0.5)
				(thermal_bridge_width 0.5)
				(island_removal_mode 0)
			)
			(polygon
				(pts
					(arc
						(start 381.720344 19.298412)
						(mid 379.866144 19.298412)
						(end 381.720344 19.298412)
					)
				)
			)
		)
	)
	(footprint ""
		(layer "F.Cu")
		(at 456.964288 -318.772032 -90)
		(property "Reference" "PL23"
			(at 0 0 270)
			(layer "F.SilkS")
			(hide yes)
			(effects
				(font
					(size 1.27 1.27)
				)
			)
		)
		(property "Value" ""
			(at 0 0 270)
			(layer "F.Fab")
			(effects
				(font
					(size 1.27 1.27)
				)
			)
		)
		(duplicate_pad_numbers_are_jumpers no)
		(fp_line
			(start -1.27 0.5842)
			(end -1.27 -0.5842)
			(stroke
				(width 0.1524)
				(type default)
			)
			(layer "F.SilkS")
		)
		(fp_line
			(start 1.27 0.5842)
			(end -1.27 0.5842)
			(stroke
				(width 0.1524)
				(type default)
			)
			(layer "F.SilkS")
		)
		(fp_line
			(start 1.27 0.5842)
			(end 1.27 -0.5842)
			(stroke
				(width 0.1524)
				(type default)
			)
			(layer "F.SilkS")
		)
		(fp_line
			(start -1.27 -0.5588)
			(end -1.27 -0.5842)
			(stroke
				(width 0.1524)
				(type default)
			)
			(layer "F.SilkS")
		)
		(fp_line
			(start -1.27 -0.5842)
			(end 1.27 -0.5842)
			(stroke
				(width 0.1524)
				(type default)
			)
			(layer "F.SilkS")
		)
		(fp_line
			(start -0.9144 0.508)
			(end -0.9144 0.406654)
			(stroke
				(width 0.1)
				(type default)
			)
			(layer "F.Fab")
		)
		(fp_line
			(start 0.9144 0.508)
			(end -0.9144 0.508)
			(stroke
				(width 0.1)
				(type default)
			)
			(layer "F.Fab")
		)
		(fp_line
			(start -1.194308 0.406654)
			(end -1.194308 -0.406654)
			(stroke
				(width 0.1)
				(type default)
			)
			(layer "F.Fab")
		)
		(fp_line
			(start -0.9144 0.406654)
			(end -1.194308 0.406654)
			(stroke
				(width 0.1)
				(type default)
			)
			(layer "F.Fab")
		)
		(fp_line
			(start 0.9144 0.4064)
			(end 0.9144 0.508)
			(stroke
				(width 0.1)
				(type default)
			)
			(layer "F.Fab")
		)
		(fp_line
			(start 1.1938 0.4064)
			(end 0.9144 0.4064)
			(stroke
				(width 0.1)
				(type default)
			)
			(layer "F.Fab")
		)
		(fp_line
			(start -1.194308 -0.406654)
			(end -0.9144 -0.406654)
			(stroke
				(width 0.1)
				(type default)
			)
			(layer "F.Fab")
		)
		(fp_line
			(start -0.9144 -0.406654)
			(end -0.9144 -0.508)
			(stroke
				(width 0.1)
				(type default)
			)
			(layer "F.Fab")
		)
		(fp_line
			(start 0.9144 -0.406654)
			(end 1.1938 -0.406654)
			(stroke
				(width 0.1)
				(type default)
			)
			(layer "F.Fab")
		)
		(fp_line
			(start 1.1938 -0.406654)
			(end 1.1938 0.4064)
			(stroke
				(width 0.1)
				(type default)
			)
			(layer "F.Fab")
		)
		(fp_line
			(start -0.9144 -0.508)
			(end 0.9144 -0.508)
			(stroke
				(width 0.1)
				(type default)
			)
			(layer "F.Fab")
		)
		(fp_line
			(start 0.9144 -0.508)
			(end 0.9144 -0.406654)
			(stroke
				(width 0.1)
				(type default)
			)
			(layer "F.Fab")
		)
		(pad "1" smd rect
			(at -0.7366 0 180)
			(size 0.7112 0.8128)
			(layers "F.Cu" "F.Mask" "F.Paste")
			(net "P12V_AUX")
		)
		(pad "2" smd rect
			(at 0.7366 0 180)
			(size 0.7112 0.8128)
			(layers "F.Cu" "F.Mask" "F.Paste")
			(net "SW_P12V_P1V25_PEX3_FLT")
		)
	)
	(footprint ""
		(layer "F.Cu")
		(at 322.91909 -229.952296)
		(property "Reference" "Q113"
			(at -4.13893 -1.342898 0)
			(unlocked yes)
			(layer "F.SilkS")
			(effects
				(font
					(size 0.7874 0.5842)
					(thickness 0.1524)
				)
			)
		)
		(property "Value" ""
			(at 0 0 0)
			(layer "F.Fab")
			(effects
				(font
					(size 1.27 1.27)
				)
			)
		)
		(duplicate_pad_numbers_are_jumpers no)
		(fp_line
			(start -1.376172 -1.199896)
			(end -0.508 -1.199896)
			(stroke
				(width 0.1524)
				(type default)
			)
			(layer "F.SilkS")
		)
		(fp_line
			(start -1.376172 1.199896)
			(end -1.376172 -1.199896)
			(stroke
				(width 0.1524)
				(type default)
			)
			(layer "F.SilkS")
		)
		(fp_line
			(start -0.508 -1.199896)
			(end 0 -0.762)
			(stroke
				(width 0.1524)
				(type default)
			)
			(layer "F.SilkS")
		)
		(fp_line
			(start 0 -0.762)
			(end 0.508 -1.199896)
			(stroke
				(width 0.1524)
				(type default)
			)
			(layer "F.SilkS")
		)
		(fp_line
			(start 0.508 -1.199896)
			(end 1.376172 -1.199896)
			(stroke
				(width 0.1524)
				(type default)
			)
			(layer "F.SilkS")
		)
		(fp_line
			(start 1.376172 -1.199896)
			(end 1.376172 1.199896)
			(stroke
				(width 0.1524)
				(type default)
			)
			(layer "F.SilkS")
		)
		(fp_line
			(start 1.376172 1.199896)
			(end -1.376172 1.199896)
			(stroke
				(width 0.1524)
				(type default)
			)
			(layer "F.SilkS")
		)
		(fp_poly
			(pts
				(xy -1.350772 -1.041908) (xy -2.112772 -1.422908) (xy -2.112772 -0.660908)
			)
			(stroke
				(width 0)
				(type default)
			)
			(fill yes)
			(layer "F.SilkS")
		)
		(fp_line
			(start -0.674878 -1.100074)
			(end 0.674878 -1.100074)
			(stroke
				(width 0.1)
				(type default)
			)
			(layer "F.Fab")
		)
		(fp_line
			(start -0.674878 1.100074)
			(end -0.674878 -1.100074)
			(stroke
				(width 0.1)
				(type default)
			)
			(layer "F.Fab")
		)
		(fp_line
			(start 0.674878 -1.100074)
			(end 0.674878 1.100074)
			(stroke
				(width 0.1)
				(type default)
			)
			(layer "F.Fab")
		)
		(fp_line
			(start 0.674878 1.100074)
			(end -0.674878 1.100074)
			(stroke
				(width 0.1)
				(type default)
			)
			(layer "F.Fab")
		)
		(fp_poly
			(pts
				(xy -1.4605 -0.7493) (xy -2.2225 -1.1303) (xy -2.2225 -0.3683)
			)
			(stroke
				(width 0)
				(type default)
			)
			(fill yes)
			(layer "F.Fab")
		)
		(pad "1" smd rect
			(at -0.899922 -0.750062 270)
			(size 0.6096 0.6096)
			(layers "F.Cu" "F.Mask" "F.Paste")
			(net "GND")
		)
		(pad "2" smd rect
			(at -0.899922 0 270)
			(size 0.4064 0.6096)
			(layers "F.Cu" "F.Mask" "F.Paste")
			(net "FPGA_DEBUG_LED")
		)
		(pad "3" smd rect
			(at -0.899922 0.750062 270)
			(size 0.6096 0.6096)
			(layers "F.Cu" "F.Mask" "F.Paste")
			(net "Net_9082")
		)
		(pad "4" smd rect
			(at 0.899922 0.750062 270)
			(size 0.6096 0.6096)
			(layers "F.Cu" "F.Mask" "F.Paste")
			(net "Net_9080")
		)
		(pad "5" smd rect
			(at 0.899922 0 270)
			(size 0.4064 0.6096)
			(layers "F.Cu" "F.Mask" "F.Paste")
			(net "Net_9081")
		)
		(pad "6" smd rect
			(at 0.899922 -0.750062 270)
			(size 0.6096 0.6096)
			(layers "F.Cu" "F.Mask" "F.Paste")
			(net "FPGA_DEBUG_LED_N")
		)
	)
	(footprint ""
		(layer "F.Cu")
		(at 393.954762 -22.867366 90)
		(property "Reference" "C3969"
			(at 0 0 90)
			(layer "F.SilkS")
			(hide yes)
			(effects
				(font
					(size 1.27 1.27)
				)
			)
		)
		(property "Value" ""
			(at 0 0 90)
			(layer "F.Fab")
			(effects
				(font
					(size 1.27 1.27)
				)
			)
		)
		(duplicate_pad_numbers_are_jumpers no)
		(fp_line
			(start 0.7874 -0.4064)
			(end 0.7874 0.4064)
			(stroke
				(width 0.1524)
				(type default)
			)
			(layer "F.SilkS")
		)
		(fp_line
			(start -0.7874 -0.4064)
			(end 0.7874 -0.4064)
			(stroke
				(width 0.1524)
				(type default)
			)
			(layer "F.SilkS")
		)
		(fp_line
			(start 0.7874 0.4064)
			(end -0.7874 0.4064)
			(stroke
				(width 0.1524)
				(type default)
			)
			(layer "F.SilkS")
		)
		(fp_line
			(start -0.7874 0.4064)
			(end -0.7874 -0.4064)
			(stroke
				(width 0.1524)
				(type default)
			)
			(layer "F.SilkS")
		)
		(fp_line
			(start -0.12065 -0.305054)
			(end -0.12065 -0.2794)
			(stroke
				(width 0.1)
				(type default)
			)
			(layer "F.Fab")
		)
		(fp_line
			(start -0.67945 -0.305054)
			(end -0.12065 -0.305054)
			(stroke
				(width 0.1)
				(type default)
			)
			(layer "F.Fab")
		)
		(fp_line
			(start 0.67945 -0.3048)
			(end 0.67945 0.3048)
			(stroke
				(width 0.1)
				(type default)
			)
			(layer "F.Fab")
		)
		(fp_line
			(start 0.12065 -0.3048)
			(end 0.67945 -0.3048)
			(stroke
				(width 0.1)
				(type default)
			)
			(layer "F.Fab")
		)
		(fp_line
			(start 0.12065 -0.2794)
			(end 0.12065 -0.3048)
			(stroke
				(width 0.1)
				(type default)
			)
			(layer "F.Fab")
		)
		(fp_line
			(start -0.12065 -0.2794)
			(end 0.12065 -0.2794)
			(stroke
				(width 0.1)
				(type default)
			)
			(layer "F.Fab")
		)
		(fp_line
			(start 0.120396 0.2794)
			(end -0.12065 0.2794)
			(stroke
				(width 0.1)
				(type default)
			)
			(layer "F.Fab")
		)
		(fp_line
			(start -0.12065 0.2794)
			(end -0.12065 0.3048)
			(stroke
				(width 0.1)
				(type default)
			)
			(layer "F.Fab")
		)
		(fp_line
			(start 0.67945 0.3048)
			(end 0.120396 0.3048)
			(stroke
				(width 0.1)
				(type default)
			)
			(layer "F.Fab")
		)
		(fp_line
			(start 0.120396 0.3048)
			(end 0.120396 0.2794)
			(stroke
				(width 0.1)
				(type default)
			)
			(layer "F.Fab")
		)
		(fp_line
			(start -0.12065 0.3048)
			(end -0.67945 0.3048)
			(stroke
				(width 0.1)
				(type default)
			)
			(layer "F.Fab")
		)
		(fp_line
			(start -0.67945 0.3048)
			(end -0.67945 -0.305054)
			(stroke
				(width 0.1)
				(type default)
			)
			(layer "F.Fab")
		)
		(pad "1" smd circle
			(at -0.40005 0 90)
			(size 0 0)
			(layers "F.Cu" "F.Mask" "F.Paste")
			(net "P12V_SSD13")
		)
		(pad "2" smd circle
			(at 0.40005 0 90)
			(size 0 0)
			(layers "F.Cu" "F.Mask" "F.Paste")
			(net "GND")
		)
	)
	(footprint ""
		(layer "F.Cu")
		(at 69.792342 -28.225242 180)
		(property "Reference" "C88"
			(at 0 0 180)
			(layer "F.SilkS")
			(hide yes)
			(effects
				(font
					(size 1.27 1.27)
				)
			)
		)
		(property "Value" ""
			(at 0 0 180)
			(layer "F.Fab")
			(effects
				(font
					(size 1.27 1.27)
				)
			)
		)
		(duplicate_pad_numbers_are_jumpers no)
		(fp_line
			(start 0.299974 0.150114)
			(end -0.299974 0.150114)
			(stroke
				(width 0.1)
				(type default)
			)
			(layer "F.Fab")
		)
		(fp_line
			(start 0.299974 -0.150114)
			(end 0.299974 0.150114)
			(stroke
				(width 0.1)
				(type default)
			)
			(layer "F.Fab")
		)
		(fp_line
			(start -0.299974 0.150114)
			(end -0.299974 -0.150114)
			(stroke
				(width 0.1)
				(type default)
			)
			(layer "F.Fab")
		)
		(fp_line
			(start -0.299974 -0.150114)
			(end 0.299974 -0.150114)
			(stroke
				(width 0.1)
				(type default)
			)
			(layer "F.Fab")
		)
		(pad "1" smd rect
			(at -0.2667 0 180)
			(size 0.3048 0.381)
			(layers "F.Cu" "F.Mask" "F.Paste")
			(net "P5E_PEX0_STN2_TX_DN<36>")
		)
		(pad "2" smd rect
			(at 0.2667 0 180)
			(size 0.3048 0.381)
			(layers "F.Cu" "F.Mask" "F.Paste")
			(net "P5E_PEX0_STN2_TX_C_DN<36>")
		)
	)
	(footprint ""
		(layer "F.Cu")
		(at 352.17227 -32.848042 90)
		(property "Reference" "PC961"
			(at 0 0 90)
			(layer "F.SilkS")
			(hide yes)
			(effects
				(font
					(size 1.27 1.27)
				)
			)
		)
		(property "Value" ""
			(at 0 0 90)
			(layer "F.Fab")
			(effects
				(font
					(size 1.27 1.27)
				)
			)
		)
		(duplicate_pad_numbers_are_jumpers no)
		(fp_line
			(start 0.7874 -0.4064)
			(end 0.7874 0.4064)
			(stroke
				(width 0.1524)
				(type default)
			)
			(layer "F.SilkS")
		)
		(fp_line
			(start -0.7874 -0.4064)
			(end 0.7874 -0.4064)
			(stroke
				(width 0.1524)
				(type default)
			)
			(layer "F.SilkS")
		)
		(fp_line
			(start 0.7874 0.4064)
			(end -0.7874 0.4064)
			(stroke
				(width 0.1524)
				(type default)
			)
			(layer "F.SilkS")
		)
		(fp_line
			(start -0.7874 0.4064)
			(end -0.7874 -0.4064)
			(stroke
				(width 0.1524)
				(type default)
			)
			(layer "F.SilkS")
		)
		(fp_line
			(start -0.12065 -0.305054)
			(end -0.12065 -0.2794)
			(stroke
				(width 0.1)
				(type default)
			)
			(layer "F.Fab")
		)
		(fp_line
			(start -0.67945 -0.305054)
			(end -0.12065 -0.305054)
			(stroke
				(width 0.1)
				(type default)
			)
			(layer "F.Fab")
		)
		(fp_line
			(start 0.67945 -0.3048)
			(end 0.67945 0.3048)
			(stroke
				(width 0.1)
				(type default)
			)
			(layer "F.Fab")
		)
		(fp_line
			(start 0.12065 -0.3048)
			(end 0.67945 -0.3048)
			(stroke
				(width 0.1)
				(type default)
			)
			(layer "F.Fab")
		)
		(fp_line
			(start 0.12065 -0.2794)
			(end 0.12065 -0.3048)
			(stroke
				(width 0.1)
				(type default)
			)
			(layer "F.Fab")
		)
		(fp_line
			(start -0.12065 -0.2794)
			(end 0.12065 -0.2794)
			(stroke
				(width 0.1)
				(type default)
			)
			(layer "F.Fab")
		)
		(fp_line
			(start 0.120396 0.2794)
			(end -0.12065 0.2794)
			(stroke
				(width 0.1)
				(type default)
			)
			(layer "F.Fab")
		)
		(fp_line
			(start -0.12065 0.2794)
			(end -0.12065 0.3048)
			(stroke
				(width 0.1)
				(type default)
			)
			(layer "F.Fab")
		)
		(fp_line
			(start 0.67945 0.3048)
			(end 0.120396 0.3048)
			(stroke
				(width 0.1)
				(type default)
			)
			(layer "F.Fab")
		)
		(fp_line
			(start 0.120396 0.3048)
			(end 0.120396 0.2794)
			(stroke
				(width 0.1)
				(type default)
			)
			(layer "F.Fab")
		)
		(fp_line
			(start -0.12065 0.3048)
			(end -0.67945 0.3048)
			(stroke
				(width 0.1)
				(type default)
			)
			(layer "F.Fab")
		)
		(fp_line
			(start -0.67945 0.3048)
			(end -0.67945 -0.305054)
			(stroke
				(width 0.1)
				(type default)
			)
			(layer "F.Fab")
		)
		(pad "1" smd circle
			(at -0.40005 0 90)
			(size 0 0)
			(layers "F.Cu" "F.Mask" "F.Paste")
			(net "P3V3_SSD12_CO_GATE")
		)
		(pad "2" smd circle
			(at 0.40005 0 90)
			(size 0 0)
			(layers "F.Cu" "F.Mask" "F.Paste")
			(net "GND")
		)
	)
	(footprint ""
		(layer "F.Cu")
		(at 329.692 -234.061 -90)
		(property "Reference" "R1781"
			(at 0 0 270)
			(layer "F.SilkS")
			(hide yes)
			(effects
				(font
					(size 1.27 1.27)
				)
			)
		)
		(property "Value" ""
			(at 0 0 270)
			(layer "F.Fab")
			(effects
				(font
					(size 1.27 1.27)
				)
			)
		)
		(duplicate_pad_numbers_are_jumpers no)
		(fp_line
			(start -0.7874 0.4064)
			(end -0.7874 -0.4064)
			(stroke
				(width 0.1524)
				(type default)
			)
			(layer "F.SilkS")
		)
		(fp_line
			(start 0.7874 0.4064)
			(end -0.7874 0.4064)
			(stroke
				(width 0.1524)
				(type default)
			)
			(layer "F.SilkS")
		)
		(fp_line
			(start -0.7874 -0.4064)
			(end 0.7874 -0.4064)
			(stroke
				(width 0.1524)
				(type default)
			)
			(layer "F.SilkS")
		)
		(fp_line
			(start 0.7874 -0.4064)
			(end 0.7874 0.4064)
			(stroke
				(width 0.1524)
				(type default)
			)
			(layer "F.SilkS")
		)
		(fp_line
			(start -0.67945 0.3048)
			(end -0.67945 -0.305054)
			(stroke
				(width 0.1)
				(type default)
			)
			(layer "F.Fab")
		)
		(fp_line
			(start -0.12065 0.3048)
			(end -0.67945 0.3048)
			(stroke
				(width 0.1)
				(type default)
			)
			(layer "F.Fab")
		)
		(fp_line
			(start 0.120396 0.3048)
			(end 0.120396 0.2794)
			(stroke
				(width 0.1)
				(type default)
			)
			(layer "F.Fab")
		)
		(fp_line
			(start 0.67945 0.3048)
			(end 0.120396 0.3048)
			(stroke
				(width 0.1)
				(type default)
			)
			(layer "F.Fab")
		)
		(fp_line
			(start -0.12065 0.2794)
			(end -0.12065 0.3048)
			(stroke
				(width 0.1)
				(type default)
			)
			(layer "F.Fab")
		)
		(fp_line
			(start 0.120396 0.2794)
			(end -0.12065 0.2794)
			(stroke
				(width 0.1)
				(type default)
			)
			(layer "F.Fab")
		)
		(fp_line
			(start -0.12065 -0.2794)
			(end 0.12065 -0.2794)
			(stroke
				(width 0.1)
				(type default)
			)
			(layer "F.Fab")
		)
		(fp_line
			(start 0.12065 -0.2794)
			(end 0.12065 -0.3048)
			(stroke
				(width 0.1)
				(type default)
			)
			(layer "F.Fab")
		)
		(fp_line
			(start 0.12065 -0.3048)
			(end 0.67945 -0.3048)
			(stroke
				(width 0.1)
				(type default)
			)
			(layer "F.Fab")
		)
		(fp_line
			(start 0.67945 -0.3048)
			(end 0.67945 0.3048)
			(stroke
				(width 0.1)
				(type default)
			)
			(layer "F.Fab")
		)
		(fp_line
			(start -0.67945 -0.305054)
			(end -0.12065 -0.305054)
			(stroke
				(width 0.1)
				(type default)
			)
			(layer "F.Fab")
		)
		(fp_line
			(start -0.12065 -0.305054)
			(end -0.12065 -0.2794)
			(stroke
				(width 0.1)
				(type default)
			)
			(layer "F.Fab")
		)
		(pad "1" smd circle
			(at -0.40005 0 270)
			(size 0 0)
			(layers "F.Cu" "F.Mask" "F.Paste")
			(net "PRSNT_GPU_ISO_N")
		)
		(pad "2" smd circle
			(at 0.40005 0 270)
			(size 0 0)
			(layers "F.Cu" "F.Mask" "F.Paste")
			(net "P3V3_AUX")
		)
	)
	(footprint ""
		(layer "F.Cu")
		(at 227.736654 -310.568848)
		(property "Reference" "R844"
			(at 0 0 0)
			(layer "F.SilkS")
			(hide yes)
			(effects
				(font
					(size 1.27 1.27)
				)
			)
		)
		(property "Value" ""
			(at 0 0 0)
			(layer "F.Fab")
			(effects
				(font
					(size 1.27 1.27)
				)
			)
		)
		(duplicate_pad_numbers_are_jumpers no)
		(fp_line
			(start -0.7874 -0.4064)
			(end 0.7874 -0.4064)
			(stroke
				(width 0.1524)
				(type default)
			)
			(layer "F.SilkS")
		)
		(fp_line
			(start -0.7874 0.4064)
			(end -0.7874 -0.4064)
			(stroke
				(width 0.1524)
				(type default)
			)
			(layer "F.SilkS")
		)
		(fp_line
			(start 0.7874 -0.4064)
			(end 0.7874 0.4064)
			(stroke
				(width 0.1524)
				(type default)
			)
			(layer "F.SilkS")
		)
		(fp_line
			(start 0.7874 0.4064)
			(end -0.7874 0.4064)
			(stroke
				(width 0.1524)
				(type default)
			)
			(layer "F.SilkS")
		)
		(fp_line
			(start -0.67945 -0.305054)
			(end -0.12065 -0.305054)
			(stroke
				(width 0.1)
				(type default)
			)
			(layer "F.Fab")
		)
		(fp_line
			(start -0.67945 0.3048)
			(end -0.67945 -0.305054)
			(stroke
				(width 0.1)
				(type default)
			)
			(layer "F.Fab")
		)
		(fp_line
			(start -0.12065 -0.305054)
			(end -0.12065 -0.2794)
			(stroke
				(width 0.1)
				(type default)
			)
			(layer "F.Fab")
		)
		(fp_line
			(start -0.12065 -0.2794)
			(end 0.12065 -0.2794)
			(stroke
				(width 0.1)
				(type default)
			)
			(layer "F.Fab")
		)
		(fp_line
			(start -0.12065 0.2794)
			(end -0.12065 0.3048)
			(stroke
				(width 0.1)
				(type default)
			)
			(layer "F.Fab")
		)
		(fp_line
			(start -0.12065 0.3048)
			(end -0.67945 0.3048)
			(stroke
				(width 0.1)
				(type default)
			)
			(layer "F.Fab")
		)
		(fp_line
			(start 0.120396 0.2794)
			(end -0.12065 0.2794)
			(stroke
				(width 0.1)
				(type default)
			)
			(layer "F.Fab")
		)
		(fp_line
			(start 0.120396 0.3048)
			(end 0.120396 0.2794)
			(stroke
				(width 0.1)
				(type default)
			)
			(layer "F.Fab")
		)
		(fp_line
			(start 0.12065 -0.3048)
			(end 0.67945 -0.3048)
			(stroke
				(width 0.1)
				(type default)
			)
			(layer "F.Fab")
		)
		(fp_line
			(start 0.12065 -0.2794)
			(end 0.12065 -0.3048)
			(stroke
				(width 0.1)
				(type default)
			)
			(layer "F.Fab")
		)
		(fp_line
			(start 0.67945 -0.3048)
			(end 0.67945 0.3048)
			(stroke
				(width 0.1)
				(type default)
			)
			(layer "F.Fab")
		)
		(fp_line
			(start 0.67945 0.3048)
			(end 0.120396 0.3048)
			(stroke
				(width 0.1)
				(type default)
			)
			(layer "F.Fab")
		)
		(pad "1" smd circle
			(at -0.40005 0)
			(size 0 0)
			(layers "F.Cu" "F.Mask" "F.Paste")
			(net "P1V25_PEX1_EN")
		)
		(pad "2" smd circle
			(at 0.40005 0)
			(size 0 0)
			(layers "F.Cu" "F.Mask" "F.Paste")
			(net "PWR_EN_PEX_R")
		)
	)
	(footprint ""
		(layer "F.Cu")
		(at 221.990158 -77.563472)
		(property "Reference" "R4268"
			(at 0 0 0)
			(layer "F.SilkS")
			(hide yes)
			(effects
				(font
					(size 1.27 1.27)
				)
			)
		)
		(property "Value" ""
			(at 0 0 0)
			(layer "F.Fab")
			(effects
				(font
					(size 1.27 1.27)
				)
			)
		)
		(duplicate_pad_numbers_are_jumpers no)
		(fp_line
			(start -0.7874 -0.4064)
			(end 0.7874 -0.4064)
			(stroke
				(width 0.1524)
				(type default)
			)
			(layer "F.SilkS")
		)
		(fp_line
			(start -0.7874 0.4064)
			(end -0.7874 -0.4064)
			(stroke
				(width 0.1524)
				(type default)
			)
			(layer "F.SilkS")
		)
		(fp_line
			(start 0.7874 -0.4064)
			(end 0.7874 0.4064)
			(stroke
				(width 0.1524)
				(type default)
			)
			(layer "F.SilkS")
		)
		(fp_line
			(start 0.7874 0.4064)
			(end -0.7874 0.4064)
			(stroke
				(width 0.1524)
				(type default)
			)
			(layer "F.SilkS")
		)
		(fp_line
			(start -0.67945 -0.305054)
			(end -0.12065 -0.305054)
			(stroke
				(width 0.1)
				(type default)
			)
			(layer "F.Fab")
		)
		(fp_line
			(start -0.67945 0.3048)
			(end -0.67945 -0.305054)
			(stroke
				(width 0.1)
				(type default)
			)
			(layer "F.Fab")
		)
		(fp_line
			(start -0.12065 -0.305054)
			(end -0.12065 -0.2794)
			(stroke
				(width 0.1)
				(type default)
			)
			(layer "F.Fab")
		)
		(fp_line
			(start -0.12065 -0.2794)
			(end 0.12065 -0.2794)
			(stroke
				(width 0.1)
				(type default)
			)
			(layer "F.Fab")
		)
		(fp_line
			(start -0.12065 0.2794)
			(end -0.12065 0.3048)
			(stroke
				(width 0.1)
				(type default)
			)
			(layer "F.Fab")
		)
		(fp_line
			(start -0.12065 0.3048)
			(end -0.67945 0.3048)
			(stroke
				(width 0.1)
				(type default)
			)
			(layer "F.Fab")
		)
		(fp_line
			(start 0.120396 0.2794)
			(end -0.12065 0.2794)
			(stroke
				(width 0.1)
				(type default)
			)
			(layer "F.Fab")
		)
		(fp_line
			(start 0.120396 0.3048)
			(end 0.120396 0.2794)
			(stroke
				(width 0.1)
				(type default)
			)
			(layer "F.Fab")
		)
		(fp_line
			(start 0.12065 -0.3048)
			(end 0.67945 -0.3048)
			(stroke
				(width 0.1)
				(type default)
			)
			(layer "F.Fab")
		)
		(fp_line
			(start 0.12065 -0.2794)
			(end 0.12065 -0.3048)
			(stroke
				(width 0.1)
				(type default)
			)
			(layer "F.Fab")
		)
		(fp_line
			(start 0.67945 -0.3048)
			(end 0.67945 0.3048)
			(stroke
				(width 0.1)
				(type default)
			)
			(layer "F.Fab")
		)
		(fp_line
			(start 0.67945 0.3048)
			(end 0.120396 0.3048)
			(stroke
				(width 0.1)
				(type default)
			)
			(layer "F.Fab")
		)
		(pad "1" smd circle
			(at -0.40005 0)
			(size 0 0)
			(layers "F.Cu" "F.Mask" "F.Paste")
			(net "SSD8_LED")
		)
		(pad "2" smd circle
			(at 0.40005 0)
			(size 0 0)
			(layers "F.Cu" "F.Mask" "F.Paste")
			(net "SSD8_LED_R")
		)
	)
	(footprint ""
		(layer "F.Cu")
		(at 336.042 -176.911)
		(property "Reference" "R4731"
			(at 0 0 0)
			(layer "F.SilkS")
			(hide yes)
			(effects
				(font
					(size 1.27 1.27)
				)
			)
		)
		(property "Value" ""
			(at 0 0 0)
			(layer "F.Fab")
			(effects
				(font
					(size 1.27 1.27)
				)
			)
		)
		(duplicate_pad_numbers_are_jumpers no)
		(fp_line
			(start -0.7874 -0.4064)
			(end 0.7874 -0.4064)
			(stroke
				(width 0.1524)
				(type default)
			)
			(layer "F.SilkS")
		)
		(fp_line
			(start -0.7874 0.4064)
			(end -0.7874 -0.4064)
			(stroke
				(width 0.1524)
				(type default)
			)
			(layer "F.SilkS")
		)
		(fp_line
			(start 0.7874 -0.4064)
			(end 0.7874 0.4064)
			(stroke
				(width 0.1524)
				(type default)
			)
			(layer "F.SilkS")
		)
		(fp_line
			(start 0.7874 0.4064)
			(end -0.7874 0.4064)
			(stroke
				(width 0.1524)
				(type default)
			)
			(layer "F.SilkS")
		)
		(fp_line
			(start -0.67945 -0.305054)
			(end -0.12065 -0.305054)
			(stroke
				(width 0.1)
				(type default)
			)
			(layer "F.Fab")
		)
		(fp_line
			(start -0.67945 0.3048)
			(end -0.67945 -0.305054)
			(stroke
				(width 0.1)
				(type default)
			)
			(layer "F.Fab")
		)
		(fp_line
			(start -0.12065 -0.305054)
			(end -0.12065 -0.2794)
			(stroke
				(width 0.1)
				(type default)
			)
			(layer "F.Fab")
		)
		(fp_line
			(start -0.12065 -0.2794)
			(end 0.12065 -0.2794)
			(stroke
				(width 0.1)
				(type default)
			)
			(layer "F.Fab")
		)
		(fp_line
			(start -0.12065 0.2794)
			(end -0.12065 0.3048)
			(stroke
				(width 0.1)
				(type default)
			)
			(layer "F.Fab")
		)
		(fp_line
			(start -0.12065 0.3048)
			(end -0.67945 0.3048)
			(stroke
				(width 0.1)
				(type default)
			)
			(layer "F.Fab")
		)
		(fp_line
			(start 0.120396 0.2794)
			(end -0.12065 0.2794)
			(stroke
				(width 0.1)
				(type default)
			)
			(layer "F.Fab")
		)
		(fp_line
			(start 0.120396 0.3048)
			(end 0.120396 0.2794)
			(stroke
				(width 0.1)
				(type default)
			)
			(layer "F.Fab")
		)
		(fp_line
			(start 0.12065 -0.3048)
			(end 0.67945 -0.3048)
			(stroke
				(width 0.1)
				(type default)
			)
			(layer "F.Fab")
		)
		(fp_line
			(start 0.12065 -0.2794)
			(end 0.12065 -0.3048)
			(stroke
				(width 0.1)
				(type default)
			)
			(layer "F.Fab")
		)
		(fp_line
			(start 0.67945 -0.3048)
			(end 0.67945 0.3048)
			(stroke
				(width 0.1)
				(type default)
			)
			(layer "F.Fab")
		)
		(fp_line
			(start 0.67945 0.3048)
			(end 0.120396 0.3048)
			(stroke
				(width 0.1)
				(type default)
			)
			(layer "F.Fab")
		)
		(pad "1" smd circle
			(at -0.40005 0)
			(size 0 0)
			(layers "F.Cu" "F.Mask" "F.Paste")
			(net "P3V3_AUX")
		)
		(pad "2" smd circle
			(at 0.40005 0)
			(size 0 0)
			(layers "F.Cu" "F.Mask" "F.Paste")
			(net "RST_PEX_SSD9_PERST_R_N")
		)
	)
	(footprint ""
		(layer "F.Cu")
		(at 289.101784 -32.849312 90)
		(property "Reference" "R5694"
			(at 0 0 90)
			(layer "F.SilkS")
			(hide yes)
			(effects
				(font
					(size 1.27 1.27)
				)
			)
		)
		(property "Value" ""
			(at 0 0 90)
			(layer "F.Fab")
			(effects
				(font
					(size 1.27 1.27)
				)
			)
		)
		(duplicate_pad_numbers_are_jumpers no)
		(fp_line
			(start 0.7874 -0.4064)
			(end 0.7874 0.4064)
			(stroke
				(width 0.1524)
				(type default)
			)
			(layer "F.SilkS")
		)
		(fp_line
			(start -0.7874 -0.4064)
			(end 0.7874 -0.4064)
			(stroke
				(width 0.1524)
				(type default)
			)
			(layer "F.SilkS")
		)
		(fp_line
			(start 0.7874 0.4064)
			(end -0.7874 0.4064)
			(stroke
				(width 0.1524)
				(type default)
			)
			(layer "F.SilkS")
		)
		(fp_line
			(start -0.7874 0.4064)
			(end -0.7874 -0.4064)
			(stroke
				(width 0.1524)
				(type default)
			)
			(layer "F.SilkS")
		)
		(fp_line
			(start -0.12065 -0.305054)
			(end -0.12065 -0.2794)
			(stroke
				(width 0.1)
				(type default)
			)
			(layer "F.Fab")
		)
		(fp_line
			(start -0.67945 -0.305054)
			(end -0.12065 -0.305054)
			(stroke
				(width 0.1)
				(type default)
			)
			(layer "F.Fab")
		)
		(fp_line
			(start 0.67945 -0.3048)
			(end 0.67945 0.3048)
			(stroke
				(width 0.1)
				(type default)
			)
			(layer "F.Fab")
		)
		(fp_line
			(start 0.12065 -0.3048)
			(end 0.67945 -0.3048)
			(stroke
				(width 0.1)
				(type default)
			)
			(layer "F.Fab")
		)
		(fp_line
			(start 0.12065 -0.2794)
			(end 0.12065 -0.3048)
			(stroke
				(width 0.1)
				(type default)
			)
			(layer "F.Fab")
		)
		(fp_line
			(start -0.12065 -0.2794)
			(end 0.12065 -0.2794)
			(stroke
				(width 0.1)
				(type default)
			)
			(layer "F.Fab")
		)
		(fp_line
			(start 0.120396 0.2794)
			(end -0.12065 0.2794)
			(stroke
				(width 0.1)
				(type default)
			)
			(layer "F.Fab")
		)
		(fp_line
			(start -0.12065 0.2794)
			(end -0.12065 0.3048)
			(stroke
				(width 0.1)
				(type default)
			)
			(layer "F.Fab")
		)
		(fp_line
			(start 0.67945 0.3048)
			(end 0.120396 0.3048)
			(stroke
				(width 0.1)
				(type default)
			)
			(layer "F.Fab")
		)
		(fp_line
			(start 0.120396 0.3048)
			(end 0.120396 0.2794)
			(stroke
				(width 0.1)
				(type default)
			)
			(layer "F.Fab")
		)
		(fp_line
			(start -0.12065 0.3048)
			(end -0.67945 0.3048)
			(stroke
				(width 0.1)
				(type default)
			)
			(layer "F.Fab")
		)
		(fp_line
			(start -0.67945 0.3048)
			(end -0.67945 -0.305054)
			(stroke
				(width 0.1)
				(type default)
			)
			(layer "F.Fab")
		)
		(pad "1" smd circle
			(at -0.40005 0 90)
			(size 0 0)
			(layers "F.Cu" "F.Mask" "F.Paste")
			(net "RST_SMB_SSD10_ISO_R_N")
		)
		(pad "2" smd circle
			(at 0.40005 0 90)
			(size 0 0)
			(layers "F.Cu" "F.Mask" "F.Paste")
			(net "RST_SMB_SSD10_ISO_N")
		)
	)
	(footprint ""
		(layer "F.Cu")
		(at 378.852684 -84.2518)
		(property "Reference" "R1773"
			(at 0 0 0)
			(layer "F.SilkS")
			(hide yes)
			(effects
				(font
					(size 1.27 1.27)
				)
			)
		)
		(property "Value" ""
			(at 0 0 0)
			(layer "F.Fab")
			(effects
				(font
					(size 1.27 1.27)
				)
			)
		)
		(duplicate_pad_numbers_are_jumpers no)
		(fp_line
			(start -0.7874 -0.4064)
			(end 0.7874 -0.4064)
			(stroke
				(width 0.1524)
				(type default)
			)
			(layer "F.SilkS")
		)
		(fp_line
			(start -0.7874 0.4064)
			(end -0.7874 -0.4064)
			(stroke
				(width 0.1524)
				(type default)
			)
			(layer "F.SilkS")
		)
		(fp_line
			(start 0.7874 -0.4064)
			(end 0.7874 0.4064)
			(stroke
				(width 0.1524)
				(type default)
			)
			(layer "F.SilkS")
		)
		(fp_line
			(start 0.7874 0.4064)
			(end -0.7874 0.4064)
			(stroke
				(width 0.1524)
				(type default)
			)
			(layer "F.SilkS")
		)
		(fp_line
			(start -0.67945 -0.305054)
			(end -0.12065 -0.305054)
			(stroke
				(width 0.1)
				(type default)
			)
			(layer "F.Fab")
		)
		(fp_line
			(start -0.67945 0.3048)
			(end -0.67945 -0.305054)
			(stroke
				(width 0.1)
				(type default)
			)
			(layer "F.Fab")
		)
		(fp_line
			(start -0.12065 -0.305054)
			(end -0.12065 -0.2794)
			(stroke
				(width 0.1)
				(type default)
			)
			(layer "F.Fab")
		)
		(fp_line
			(start -0.12065 -0.2794)
			(end 0.12065 -0.2794)
			(stroke
				(width 0.1)
				(type default)
			)
			(layer "F.Fab")
		)
		(fp_line
			(start -0.12065 0.2794)
			(end -0.12065 0.3048)
			(stroke
				(width 0.1)
				(type default)
			)
			(layer "F.Fab")
		)
		(fp_line
			(start -0.12065 0.3048)
			(end -0.67945 0.3048)
			(stroke
				(width 0.1)
				(type default)
			)
			(layer "F.Fab")
		)
		(fp_line
			(start 0.120396 0.2794)
			(end -0.12065 0.2794)
			(stroke
				(width 0.1)
				(type default)
			)
			(layer "F.Fab")
		)
		(fp_line
			(start 0.120396 0.3048)
			(end 0.120396 0.2794)
			(stroke
				(width 0.1)
				(type default)
			)
			(layer "F.Fab")
		)
		(fp_line
			(start 0.12065 -0.3048)
			(end 0.67945 -0.3048)
			(stroke
				(width 0.1)
				(type default)
			)
			(layer "F.Fab")
		)
		(fp_line
			(start 0.12065 -0.2794)
			(end 0.12065 -0.3048)
			(stroke
				(width 0.1)
				(type default)
			)
			(layer "F.Fab")
		)
		(fp_line
			(start 0.67945 -0.3048)
			(end 0.67945 0.3048)
			(stroke
				(width 0.1)
				(type default)
			)
			(layer "F.Fab")
		)
		(fp_line
			(start 0.67945 0.3048)
			(end 0.120396 0.3048)
			(stroke
				(width 0.1)
				(type default)
			)
			(layer "F.Fab")
		)
		(pad "1" smd circle
			(at -0.40005 0)
			(size 0 0)
			(layers "F.Cu" "F.Mask" "F.Paste")
			(net "SMB_BIC_I2C6_MUX_THERMAL_R_SDA")
		)
		(pad "2" smd circle
			(at 0.40005 0)
			(size 0 0)
			(layers "F.Cu" "F.Mask" "F.Paste")
			(net "SMB_BIC_I2C6_MUX_THERMAL_SDA")
		)
	)
	(footprint ""
		(layer "F.Cu")
		(at 135.598662 -66.32194 -90)
		(property "Reference" "PC840"
			(at 0 0 270)
			(layer "F.SilkS")
			(hide yes)
			(effects
				(font
					(size 1.27 1.27)
				)
			)
		)
		(property "Value" ""
			(at 0 0 270)
			(layer "F.Fab")
			(effects
				(font
					(size 1.27 1.27)
				)
			)
		)
		(duplicate_pad_numbers_are_jumpers no)
		(fp_line
			(start -0.7874 0.4064)
			(end -0.7874 -0.4064)
			(stroke
				(width 0.1524)
				(type default)
			)
			(layer "F.SilkS")
		)
		(fp_line
			(start 0.7874 0.4064)
			(end -0.7874 0.4064)
			(stroke
				(width 0.1524)
				(type default)
			)
			(layer "F.SilkS")
		)
		(fp_line
			(start -0.7874 -0.4064)
			(end 0.7874 -0.4064)
			(stroke
				(width 0.1524)
				(type default)
			)
			(layer "F.SilkS")
		)
		(fp_line
			(start 0.7874 -0.4064)
			(end 0.7874 0.4064)
			(stroke
				(width 0.1524)
				(type default)
			)
			(layer "F.SilkS")
		)
		(fp_line
			(start -0.67945 0.3048)
			(end -0.67945 -0.305054)
			(stroke
				(width 0.1)
				(type default)
			)
			(layer "F.Fab")
		)
		(fp_line
			(start -0.12065 0.3048)
			(end -0.67945 0.3048)
			(stroke
				(width 0.1)
				(type default)
			)
			(layer "F.Fab")
		)
		(fp_line
			(start 0.120396 0.3048)
			(end 0.120396 0.2794)
			(stroke
				(width 0.1)
				(type default)
			)
			(layer "F.Fab")
		)
		(fp_line
			(start 0.67945 0.3048)
			(end 0.120396 0.3048)
			(stroke
				(width 0.1)
				(type default)
			)
			(layer "F.Fab")
		)
		(fp_line
			(start -0.12065 0.2794)
			(end -0.12065 0.3048)
			(stroke
				(width 0.1)
				(type default)
			)
			(layer "F.Fab")
		)
		(fp_line
			(start 0.120396 0.2794)
			(end -0.12065 0.2794)
			(stroke
				(width 0.1)
				(type default)
			)
			(layer "F.Fab")
		)
		(fp_line
			(start -0.12065 -0.2794)
			(end 0.12065 -0.2794)
			(stroke
				(width 0.1)
				(type default)
			)
			(layer "F.Fab")
		)
		(fp_line
			(start 0.12065 -0.2794)
			(end 0.12065 -0.3048)
			(stroke
				(width 0.1)
				(type default)
			)
			(layer "F.Fab")
		)
		(fp_line
			(start 0.12065 -0.3048)
			(end 0.67945 -0.3048)
			(stroke
				(width 0.1)
				(type default)
			)
			(layer "F.Fab")
		)
		(fp_line
			(start 0.67945 -0.3048)
			(end 0.67945 0.3048)
			(stroke
				(width 0.1)
				(type default)
			)
			(layer "F.Fab")
		)
		(fp_line
			(start -0.67945 -0.305054)
			(end -0.12065 -0.305054)
			(stroke
				(width 0.1)
				(type default)
			)
			(layer "F.Fab")
		)
		(fp_line
			(start -0.12065 -0.305054)
			(end -0.12065 -0.2794)
			(stroke
				(width 0.1)
				(type default)
			)
			(layer "F.Fab")
		)
		(pad "1" smd circle
			(at -0.40005 0 270)
			(size 0 0)
			(layers "F.Cu" "F.Mask" "F.Paste")
			(net "P12V_SSD4_CO_GATE")
		)
		(pad "2" smd circle
			(at 0.40005 0 270)
			(size 0 0)
			(layers "F.Cu" "F.Mask" "F.Paste")
			(net "GND")
		)
	)
	(footprint ""
		(layer "F.Cu")
		(at 358.830626 -146.099276 180)
		(property "Reference" "PC822"
			(at 0 0 180)
			(layer "F.SilkS")
			(hide yes)
			(effects
				(font
					(size 1.27 1.27)
				)
			)
		)
		(property "Value" ""
			(at 0 0 180)
			(layer "F.Fab")
			(effects
				(font
					(size 1.27 1.27)
				)
			)
		)
		(duplicate_pad_numbers_are_jumpers no)
		(fp_line
			(start 1.524 0.762)
			(end -1.524 0.762)
			(stroke
				(width 0.1524)
				(type default)
			)
			(layer "F.SilkS")
		)
		(fp_line
			(start 1.524 -0.762)
			(end 1.524 0.762)
			(stroke
				(width 0.1524)
				(type default)
			)
			(layer "F.SilkS")
		)
		(fp_line
			(start -1.524 0.762)
			(end -1.524 -0.762)
			(stroke
				(width 0.1524)
				(type default)
			)
			(layer "F.SilkS")
		)
		(fp_line
			(start -1.524 -0.762)
			(end 1.524 -0.762)
			(stroke
				(width 0.1524)
				(type default)
			)
			(layer "F.SilkS")
		)
		(fp_line
			(start 1.1049 0.724916)
			(end 1.1049 -0.724916)
			(stroke
				(width 0.1)
				(type default)
			)
			(layer "F.Fab")
		)
		(fp_line
			(start 1.1049 -0.724916)
			(end -1.1049 -0.724916)
			(stroke
				(width 0.1)
				(type default)
			)
			(layer "F.Fab")
		)
		(fp_line
			(start -1.1049 0.724916)
			(end 1.1049 0.724916)
			(stroke
				(width 0.1)
				(type default)
			)
			(layer "F.Fab")
		)
		(fp_line
			(start -1.1049 -0.724916)
			(end -1.1049 0.724916)
			(stroke
				(width 0.1)
				(type default)
			)
			(layer "F.Fab")
		)
		(pad "1" smd rect
			(at -0.889 0)
			(size 1.016 1.27)
			(layers "F.Cu" "F.Mask" "F.Paste")
			(net "P12V_NIC6_R")
		)
		(pad "2" smd rect
			(at 0.889 0)
			(size 1.016 1.27)
			(layers "F.Cu" "F.Mask" "F.Paste")
			(net "GND")
		)
	)
	(footprint ""
		(layer "F.Cu")
		(at 334.583278 -49.94148)
		(property "Reference" "R5903"
			(at 0 0 0)
			(layer "F.SilkS")
			(hide yes)
			(effects
				(font
					(size 1.27 1.27)
				)
			)
		)
		(property "Value" ""
			(at 0 0 0)
			(layer "F.Fab")
			(effects
				(font
					(size 1.27 1.27)
				)
			)
		)
		(duplicate_pad_numbers_are_jumpers no)
		(fp_line
			(start -0.7874 -0.4064)
			(end 0.7874 -0.4064)
			(stroke
				(width 0.1524)
				(type default)
			)
			(layer "F.SilkS")
		)
		(fp_line
			(start -0.7874 0.4064)
			(end -0.7874 -0.4064)
			(stroke
				(width 0.1524)
				(type default)
			)
			(layer "F.SilkS")
		)
		(fp_line
			(start 0.7874 -0.4064)
			(end 0.7874 0.4064)
			(stroke
				(width 0.1524)
				(type default)
			)
			(layer "F.SilkS")
		)
		(fp_line
			(start 0.7874 0.4064)
			(end -0.7874 0.4064)
			(stroke
				(width 0.1524)
				(type default)
			)
			(layer "F.SilkS")
		)
		(fp_line
			(start -0.67945 -0.305054)
			(end -0.12065 -0.305054)
			(stroke
				(width 0.1)
				(type default)
			)
			(layer "F.Fab")
		)
		(fp_line
			(start -0.67945 0.3048)
			(end -0.67945 -0.305054)
			(stroke
				(width 0.1)
				(type default)
			)
			(layer "F.Fab")
		)
		(fp_line
			(start -0.12065 -0.305054)
			(end -0.12065 -0.2794)
			(stroke
				(width 0.1)
				(type default)
			)
			(layer "F.Fab")
		)
		(fp_line
			(start -0.12065 -0.2794)
			(end 0.12065 -0.2794)
			(stroke
				(width 0.1)
				(type default)
			)
			(layer "F.Fab")
		)
		(fp_line
			(start -0.12065 0.2794)
			(end -0.12065 0.3048)
			(stroke
				(width 0.1)
				(type default)
			)
			(layer "F.Fab")
		)
		(fp_line
			(start -0.12065 0.3048)
			(end -0.67945 0.3048)
			(stroke
				(width 0.1)
				(type default)
			)
			(layer "F.Fab")
		)
		(fp_line
			(start 0.120396 0.2794)
			(end -0.12065 0.2794)
			(stroke
				(width 0.1)
				(type default)
			)
			(layer "F.Fab")
		)
		(fp_line
			(start 0.120396 0.3048)
			(end 0.120396 0.2794)
			(stroke
				(width 0.1)
				(type default)
			)
			(layer "F.Fab")
		)
		(fp_line
			(start 0.12065 -0.3048)
			(end 0.67945 -0.3048)
			(stroke
				(width 0.1)
				(type default)
			)
			(layer "F.Fab")
		)
		(fp_line
			(start 0.12065 -0.2794)
			(end 0.12065 -0.3048)
			(stroke
				(width 0.1)
				(type default)
			)
			(layer "F.Fab")
		)
		(fp_line
			(start 0.67945 -0.3048)
			(end 0.67945 0.3048)
			(stroke
				(width 0.1)
				(type default)
			)
			(layer "F.Fab")
		)
		(fp_line
			(start 0.67945 0.3048)
			(end 0.120396 0.3048)
			(stroke
				(width 0.1)
				(type default)
			)
			(layer "F.Fab")
		)
		(pad "1" smd circle
			(at -0.40005 0)
			(size 0 0)
			(layers "F.Cu" "F.Mask" "F.Paste")
			(net "SSD11_ADC_A0")
		)
		(pad "2" smd circle
			(at 0.40005 0)
			(size 0 0)
			(layers "F.Cu" "F.Mask" "F.Paste")
			(net "SMB_SSD11_ADC_SCL")
		)
	)
	(footprint ""
		(layer "F.Cu")
		(at 330.708 -234.061 -90)
		(property "Reference" "R6147"
			(at 0 0 270)
			(layer "F.SilkS")
			(hide yes)
			(effects
				(font
					(size 1.27 1.27)
				)
			)
		)
		(property "Value" ""
			(at 0 0 270)
			(layer "F.Fab")
			(effects
				(font
					(size 1.27 1.27)
				)
			)
		)
		(duplicate_pad_numbers_are_jumpers no)
		(fp_line
			(start -0.7874 0.4064)
			(end -0.7874 -0.4064)
			(stroke
				(width 0.1524)
				(type default)
			)
			(layer "F.SilkS")
		)
		(fp_line
			(start 0.7874 0.4064)
			(end -0.7874 0.4064)
			(stroke
				(width 0.1524)
				(type default)
			)
			(layer "F.SilkS")
		)
		(fp_line
			(start -0.7874 -0.4064)
			(end 0.7874 -0.4064)
			(stroke
				(width 0.1524)
				(type default)
			)
			(layer "F.SilkS")
		)
		(fp_line
			(start 0.7874 -0.4064)
			(end 0.7874 0.4064)
			(stroke
				(width 0.1524)
				(type default)
			)
			(layer "F.SilkS")
		)
		(fp_line
			(start -0.67945 0.3048)
			(end -0.67945 -0.305054)
			(stroke
				(width 0.1)
				(type default)
			)
			(layer "F.Fab")
		)
		(fp_line
			(start -0.12065 0.3048)
			(end -0.67945 0.3048)
			(stroke
				(width 0.1)
				(type default)
			)
			(layer "F.Fab")
		)
		(fp_line
			(start 0.120396 0.3048)
			(end 0.120396 0.2794)
			(stroke
				(width 0.1)
				(type default)
			)
			(layer "F.Fab")
		)
		(fp_line
			(start 0.67945 0.3048)
			(end 0.120396 0.3048)
			(stroke
				(width 0.1)
				(type default)
			)
			(layer "F.Fab")
		)
		(fp_line
			(start -0.12065 0.2794)
			(end -0.12065 0.3048)
			(stroke
				(width 0.1)
				(type default)
			)
			(layer "F.Fab")
		)
		(fp_line
			(start 0.120396 0.2794)
			(end -0.12065 0.2794)
			(stroke
				(width 0.1)
				(type default)
			)
			(layer "F.Fab")
		)
		(fp_line
			(start -0.12065 -0.2794)
			(end 0.12065 -0.2794)
			(stroke
				(width 0.1)
				(type default)
			)
			(layer "F.Fab")
		)
		(fp_line
			(start 0.12065 -0.2794)
			(end 0.12065 -0.3048)
			(stroke
				(width 0.1)
				(type default)
			)
			(layer "F.Fab")
		)
		(fp_line
			(start 0.12065 -0.3048)
			(end 0.67945 -0.3048)
			(stroke
				(width 0.1)
				(type default)
			)
			(layer "F.Fab")
		)
		(fp_line
			(start 0.67945 -0.3048)
			(end 0.67945 0.3048)
			(stroke
				(width 0.1)
				(type default)
			)
			(layer "F.Fab")
		)
		(fp_line
			(start -0.67945 -0.305054)
			(end -0.12065 -0.305054)
			(stroke
				(width 0.1)
				(type default)
			)
			(layer "F.Fab")
		)
		(fp_line
			(start -0.12065 -0.305054)
			(end -0.12065 -0.2794)
			(stroke
				(width 0.1)
				(type default)
			)
			(layer "F.Fab")
		)
		(pad "1" smd circle
			(at -0.40005 0 270)
			(size 0 0)
			(layers "F.Cu" "F.Mask" "F.Paste")
			(net "PRSNT_GPU_ISO_N")
		)
		(pad "2" smd circle
			(at 0.40005 0 270)
			(size 0 0)
			(layers "F.Cu" "F.Mask" "F.Paste")
			(net "PRSNT_GPU_ISO_R1_N")
		)
	)
	(footprint ""
		(layer "F.Cu")
		(at 240.638838 -276.19325)
		(property "Reference" "R800"
			(at 0 0 0)
			(layer "F.SilkS")
			(hide yes)
			(effects
				(font
					(size 1.27 1.27)
				)
			)
		)
		(property "Value" ""
			(at 0 0 0)
			(layer "F.Fab")
			(effects
				(font
					(size 1.27 1.27)
				)
			)
		)
		(duplicate_pad_numbers_are_jumpers no)
		(fp_line
			(start -0.7874 -0.4064)
			(end 0.7874 -0.4064)
			(stroke
				(width 0.1524)
				(type default)
			)
			(layer "F.SilkS")
		)
		(fp_line
			(start -0.7874 0.4064)
			(end -0.7874 -0.4064)
			(stroke
				(width 0.1524)
				(type default)
			)
			(layer "F.SilkS")
		)
		(fp_line
			(start 0.7874 -0.4064)
			(end 0.7874 0.4064)
			(stroke
				(width 0.1524)
				(type default)
			)
			(layer "F.SilkS")
		)
		(fp_line
			(start 0.7874 0.4064)
			(end -0.7874 0.4064)
			(stroke
				(width 0.1524)
				(type default)
			)
			(layer "F.SilkS")
		)
		(fp_line
			(start -0.67945 -0.305054)
			(end -0.12065 -0.305054)
			(stroke
				(width 0.1)
				(type default)
			)
			(layer "F.Fab")
		)
		(fp_line
			(start -0.67945 0.3048)
			(end -0.67945 -0.305054)
			(stroke
				(width 0.1)
				(type default)
			)
			(layer "F.Fab")
		)
		(fp_line
			(start -0.12065 -0.305054)
			(end -0.12065 -0.2794)
			(stroke
				(width 0.1)
				(type default)
			)
			(layer "F.Fab")
		)
		(fp_line
			(start -0.12065 -0.2794)
			(end 0.12065 -0.2794)
			(stroke
				(width 0.1)
				(type default)
			)
			(layer "F.Fab")
		)
		(fp_line
			(start -0.12065 0.2794)
			(end -0.12065 0.3048)
			(stroke
				(width 0.1)
				(type default)
			)
			(layer "F.Fab")
		)
		(fp_line
			(start -0.12065 0.3048)
			(end -0.67945 0.3048)
			(stroke
				(width 0.1)
				(type default)
			)
			(layer "F.Fab")
		)
		(fp_line
			(start 0.120396 0.2794)
			(end -0.12065 0.2794)
			(stroke
				(width 0.1)
				(type default)
			)
			(layer "F.Fab")
		)
		(fp_line
			(start 0.120396 0.3048)
			(end 0.120396 0.2794)
			(stroke
				(width 0.1)
				(type default)
			)
			(layer "F.Fab")
		)
		(fp_line
			(start 0.12065 -0.3048)
			(end 0.67945 -0.3048)
			(stroke
				(width 0.1)
				(type default)
			)
			(layer "F.Fab")
		)
		(fp_line
			(start 0.12065 -0.2794)
			(end 0.12065 -0.3048)
			(stroke
				(width 0.1)
				(type default)
			)
			(layer "F.Fab")
		)
		(fp_line
			(start 0.67945 -0.3048)
			(end 0.67945 0.3048)
			(stroke
				(width 0.1)
				(type default)
			)
			(layer "F.Fab")
		)
		(fp_line
			(start 0.67945 0.3048)
			(end 0.120396 0.3048)
			(stroke
				(width 0.1)
				(type default)
			)
			(layer "F.Fab")
		)
		(pad "1" smd circle
			(at -0.40005 0)
			(size 0 0)
			(layers "F.Cu" "F.Mask" "F.Paste")
			(net "P1V25_PEX2")
		)
		(pad "2" smd circle
			(at 0.40005 0)
			(size 0 0)
			(layers "F.Cu" "F.Mask" "F.Paste")
			(net "P12V_PEX2_P1V25_VIN_N")
		)
	)
	(footprint ""
		(layer "F.Cu")
		(at 113.432082 -280.44902 -90)
		(property "Reference" "PR104"
			(at 0 0 270)
			(layer "F.SilkS")
			(hide yes)
			(effects
				(font
					(size 1.27 1.27)
				)
			)
		)
		(property "Value" ""
			(at 0 0 270)
			(layer "F.Fab")
			(effects
				(font
					(size 1.27 1.27)
				)
			)
		)
		(duplicate_pad_numbers_are_jumpers no)
		(fp_line
			(start -0.7874 0.4064)
			(end -0.7874 -0.4064)
			(stroke
				(width 0.1524)
				(type default)
			)
			(layer "F.SilkS")
		)
		(fp_line
			(start 0.7874 0.4064)
			(end -0.7874 0.4064)
			(stroke
				(width 0.1524)
				(type default)
			)
			(layer "F.SilkS")
		)
		(fp_line
			(start -0.7874 -0.4064)
			(end 0.7874 -0.4064)
			(stroke
				(width 0.1524)
				(type default)
			)
			(layer "F.SilkS")
		)
		(fp_line
			(start 0.7874 -0.4064)
			(end 0.7874 0.4064)
			(stroke
				(width 0.1524)
				(type default)
			)
			(layer "F.SilkS")
		)
		(fp_line
			(start -0.67945 0.3048)
			(end -0.67945 -0.305054)
			(stroke
				(width 0.1)
				(type default)
			)
			(layer "F.Fab")
		)
		(fp_line
			(start -0.12065 0.3048)
			(end -0.67945 0.3048)
			(stroke
				(width 0.1)
				(type default)
			)
			(layer "F.Fab")
		)
		(fp_line
			(start 0.120396 0.3048)
			(end 0.120396 0.2794)
			(stroke
				(width 0.1)
				(type default)
			)
			(layer "F.Fab")
		)
		(fp_line
			(start 0.67945 0.3048)
			(end 0.120396 0.3048)
			(stroke
				(width 0.1)
				(type default)
			)
			(layer "F.Fab")
		)
		(fp_line
			(start -0.12065 0.2794)
			(end -0.12065 0.3048)
			(stroke
				(width 0.1)
				(type default)
			)
			(layer "F.Fab")
		)
		(fp_line
			(start 0.120396 0.2794)
			(end -0.12065 0.2794)
			(stroke
				(width 0.1)
				(type default)
			)
			(layer "F.Fab")
		)
		(fp_line
			(start -0.12065 -0.2794)
			(end 0.12065 -0.2794)
			(stroke
				(width 0.1)
				(type default)
			)
			(layer "F.Fab")
		)
		(fp_line
			(start 0.12065 -0.2794)
			(end 0.12065 -0.3048)
			(stroke
				(width 0.1)
				(type default)
			)
			(layer "F.Fab")
		)
		(fp_line
			(start 0.12065 -0.3048)
			(end 0.67945 -0.3048)
			(stroke
				(width 0.1)
				(type default)
			)
			(layer "F.Fab")
		)
		(fp_line
			(start 0.67945 -0.3048)
			(end 0.67945 0.3048)
			(stroke
				(width 0.1)
				(type default)
			)
			(layer "F.Fab")
		)
		(fp_line
			(start -0.67945 -0.305054)
			(end -0.12065 -0.305054)
			(stroke
				(width 0.1)
				(type default)
			)
			(layer "F.Fab")
		)
		(fp_line
			(start -0.12065 -0.305054)
			(end -0.12065 -0.2794)
			(stroke
				(width 0.1)
				(type default)
			)
			(layer "F.Fab")
		)
		(pad "1" smd circle
			(at -0.40005 0 270)
			(size 0 0)
			(layers "F.Cu" "F.Mask" "F.Paste")
			(net "SW_P0V8_PEX0_BOOT2")
		)
		(pad "2" smd circle
			(at 0.40005 0 270)
			(size 0 0)
			(layers "F.Cu" "F.Mask" "F.Paste")
			(net "SW_P0V8_PEX0_BOOT2_R")
		)
	)
	(footprint ""
		(layer "F.Cu")
		(at 375.18594 -343.952322 90)
		(property "Reference" "C781"
			(at 0 0 90)
			(layer "F.SilkS")
			(hide yes)
			(effects
				(font
					(size 1.27 1.27)
				)
			)
		)
		(property "Value" ""
			(at 0 0 90)
			(layer "F.Fab")
			(effects
				(font
					(size 1.27 1.27)
				)
			)
		)
		(duplicate_pad_numbers_are_jumpers no)
		(fp_line
			(start 0.299974 -0.150114)
			(end 0.299974 0.150114)
			(stroke
				(width 0.1)
				(type default)
			)
			(layer "F.Fab")
		)
		(fp_line
			(start -0.299974 -0.150114)
			(end 0.299974 -0.150114)
			(stroke
				(width 0.1)
				(type default)
			)
			(layer "F.Fab")
		)
		(fp_line
			(start 0.299974 0.150114)
			(end -0.299974 0.150114)
			(stroke
				(width 0.1)
				(type default)
			)
			(layer "F.Fab")
		)
		(fp_line
			(start -0.299974 0.150114)
			(end -0.299974 -0.150114)
			(stroke
				(width 0.1)
				(type default)
			)
			(layer "F.Fab")
		)
		(pad "1" smd rect
			(at -0.2667 0 90)
			(size 0.3048 0.381)
			(layers "F.Cu" "F.Mask" "F.Paste")
			(net "P5E_PEX3_STN6_TX_DN<102>")
		)
		(pad "2" smd rect
			(at 0.2667 0 90)
			(size 0.3048 0.381)
			(layers "F.Cu" "F.Mask" "F.Paste")
			(net "P5E_PEX3_STN6_TX_C_DN<102>")
		)
	)
	(footprint ""
		(layer "F.Cu")
		(at 359.156 -180.086 180)
		(property "Reference" "R4701"
			(at 0 0 180)
			(layer "F.SilkS")
			(hide yes)
			(effects
				(font
					(size 1.27 1.27)
				)
			)
		)
		(property "Value" ""
			(at 0 0 180)
			(layer "F.Fab")
			(effects
				(font
					(size 1.27 1.27)
				)
			)
		)
		(duplicate_pad_numbers_are_jumpers no)
		(fp_line
			(start 0.7874 0.4064)
			(end -0.7874 0.4064)
			(stroke
				(width 0.1524)
				(type default)
			)
			(layer "F.SilkS")
		)
		(fp_line
			(start 0.7874 -0.4064)
			(end 0.7874 0.4064)
			(stroke
				(width 0.1524)
				(type default)
			)
			(layer "F.SilkS")
		)
		(fp_line
			(start -0.7874 0.4064)
			(end -0.7874 -0.4064)
			(stroke
				(width 0.1524)
				(type default)
			)
			(layer "F.SilkS")
		)
		(fp_line
			(start -0.7874 -0.4064)
			(end 0.7874 -0.4064)
			(stroke
				(width 0.1524)
				(type default)
			)
			(layer "F.SilkS")
		)
		(fp_line
			(start 0.67945 0.3048)
			(end 0.120396 0.3048)
			(stroke
				(width 0.1)
				(type default)
			)
			(layer "F.Fab")
		)
		(fp_line
			(start 0.67945 -0.3048)
			(end 0.67945 0.3048)
			(stroke
				(width 0.1)
				(type default)
			)
			(layer "F.Fab")
		)
		(fp_line
			(start 0.12065 -0.2794)
			(end 0.12065 -0.3048)
			(stroke
				(width 0.1)
				(type default)
			)
			(layer "F.Fab")
		)
		(fp_line
			(start 0.12065 -0.3048)
			(end 0.67945 -0.3048)
			(stroke
				(width 0.1)
				(type default)
			)
			(layer "F.Fab")
		)
		(fp_line
			(start 0.120396 0.3048)
			(end 0.120396 0.2794)
			(stroke
				(width 0.1)
				(type default)
			)
			(layer "F.Fab")
		)
		(fp_line
			(start 0.120396 0.2794)
			(end -0.12065 0.2794)
			(stroke
				(width 0.1)
				(type default)
			)
			(layer "F.Fab")
		)
		(fp_line
			(start -0.12065 0.3048)
			(end -0.67945 0.3048)
			(stroke
				(width 0.1)
				(type default)
			)
			(layer "F.Fab")
		)
		(fp_line
			(start -0.12065 0.2794)
			(end -0.12065 0.3048)
			(stroke
				(width 0.1)
				(type default)
			)
			(layer "F.Fab")
		)
		(fp_line
			(start -0.12065 -0.2794)
			(end 0.12065 -0.2794)
			(stroke
				(width 0.1)
				(type default)
			)
			(layer "F.Fab")
		)
		(fp_line
			(start -0.12065 -0.305054)
			(end -0.12065 -0.2794)
			(stroke
				(width 0.1)
				(type default)
			)
			(layer "F.Fab")
		)
		(fp_line
			(start -0.67945 0.3048)
			(end -0.67945 -0.305054)
			(stroke
				(width 0.1)
				(type default)
			)
			(layer "F.Fab")
		)
		(fp_line
			(start -0.67945 -0.305054)
			(end -0.12065 -0.305054)
			(stroke
				(width 0.1)
				(type default)
			)
			(layer "F.Fab")
		)
		(pad "1" smd circle
			(at -0.40005 0 180)
			(size 0 0)
			(layers "F.Cu" "F.Mask" "F.Paste")
			(net "PCA9555_1_PEX1_A2")
		)
		(pad "2" smd circle
			(at 0.40005 0 180)
			(size 0 0)
			(layers "F.Cu" "F.Mask" "F.Paste")
			(net "P3V3_AUX")
		)
	)
	(footprint ""
		(layer "F.Cu")
		(at 415.442654 -70.844918 -90)
		(property "Reference" "PD47"
			(at 4.093718 2.183384 90)
			(unlocked yes)
			(layer "F.SilkS")
			(effects
				(font
					(size 0.7874 0.5842)
					(thickness 0.1524)
				)
				(justify left)
			)
		)
		(property "Value" ""
			(at 0 0 270)
			(layer "F.Fab")
			(effects
				(font
					(size 1.27 1.27)
				)
			)
		)
		(duplicate_pad_numbers_are_jumpers no)
		(fp_line
			(start -3.400044 1.459992)
			(end -3.400044 -1.459992)
			(stroke
				(width 0.1524)
				(type default)
			)
			(layer "F.SilkS")
		)
		(fp_line
			(start 4.107942 1.459992)
			(end -3.400044 1.459992)
			(stroke
				(width 0.1524)
				(type default)
			)
			(layer "F.SilkS")
		)
		(fp_line
			(start -3.400044 -1.459992)
			(end 4.107942 -1.459992)
			(stroke
				(width 0.1524)
				(type default)
			)
			(layer "F.SilkS")
		)
		(fp_line
			(start 4.107942 -1.459992)
			(end 4.107942 1.459992)
			(stroke
				(width 0.1524)
				(type default)
			)
			(layer "F.SilkS")
		)
		(fp_poly
			(pts
				(xy 4.107942 -1.459992) (xy 4.107942 1.459992) (xy 3.308096 1.459992) (xy 3.308096 -1.459992)
			)
			(stroke
				(width 0)
				(type default)
			)
			(fill yes)
			(layer "F.SilkS")
		)
		(fp_line
			(start -2.29997 1.459992)
			(end -2.29997 -1.459992)
			(stroke
				(width 0.1)
				(type default)
			)
			(layer "F.Fab")
		)
		(fp_line
			(start 2.29997 1.459992)
			(end -2.29997 1.459992)
			(stroke
				(width 0.1)
				(type default)
			)
			(layer "F.Fab")
		)
		(fp_line
			(start -2.29997 -1.459992)
			(end 2.29997 -1.459992)
			(stroke
				(width 0.1)
				(type default)
			)
			(layer "F.Fab")
		)
		(fp_line
			(start 2.29997 -1.459992)
			(end 2.29997 1.459992)
			(stroke
				(width 0.1)
				(type default)
			)
			(layer "F.Fab")
		)
		(fp_text user "-"
			(at 5.4102 0.29845 90)
			(unlocked yes)
			(layer "F.SilkS")
			(effects
				(font
					(size 1.905 1.4224)
					(thickness 0.1524)
				)
				(justify left)
			)
		)
		(fp_text user "+"
			(at -5.184648 -0.258318 270)
			(unlocked yes)
			(layer "F.SilkS")
			(effects
				(font
					(size 1.905 1.4224)
					(thickness 0.1524)
				)
				(justify left)
			)
		)
		(fp_text user "-"
			(at 5.4102 0.29845 90)
			(unlocked yes)
			(layer "F.Fab")
			(effects
				(font
					(size 1.905 1.4224)
					(thickness 0.1524)
				)
				(justify left)
			)
		)
		(fp_text user "+"
			(at -4.7752 -0.12065 270)
			(unlocked yes)
			(layer "F.Fab")
			(effects
				(font
					(size 1.905 1.4224)
					(thickness 0.1524)
				)
				(justify left)
			)
		)
		(pad "A" smd rect
			(at -1.999996 0)
			(size 1.7018 2.5146)
			(layers "F.Cu" "F.Mask" "F.Paste")
			(net "GND")
		)
		(pad "C" smd rect
			(at 1.999996 0)
			(size 1.7018 2.5146)
			(layers "F.Cu" "F.Mask" "F.Paste")
			(net "P12V_SSD14_R")
		)
	)
	(footprint ""
		(layer "F.Cu")
		(at 98.434398 -30.94609 180)
		(property "Reference" "C93"
			(at 0 0 180)
			(layer "F.SilkS")
			(hide yes)
			(effects
				(font
					(size 1.27 1.27)
				)
			)
		)
		(property "Value" ""
			(at 0 0 180)
			(layer "F.Fab")
			(effects
				(font
					(size 1.27 1.27)
				)
			)
		)
		(duplicate_pad_numbers_are_jumpers no)
		(fp_line
			(start 0.299974 0.150114)
			(end -0.299974 0.150114)
			(stroke
				(width 0.1)
				(type default)
			)
			(layer "F.Fab")
		)
		(fp_line
			(start 0.299974 -0.150114)
			(end 0.299974 0.150114)
			(stroke
				(width 0.1)
				(type default)
			)
			(layer "F.Fab")
		)
		(fp_line
			(start -0.299974 0.150114)
			(end -0.299974 -0.150114)
			(stroke
				(width 0.1)
				(type default)
			)
			(layer "F.Fab")
		)
		(fp_line
			(start -0.299974 -0.150114)
			(end 0.299974 -0.150114)
			(stroke
				(width 0.1)
				(type default)
			)
			(layer "F.Fab")
		)
		(pad "1" smd rect
			(at -0.2667 0 180)
			(size 0.3048 0.381)
			(layers "F.Cu" "F.Mask" "F.Paste")
			(net "P5E_PEX0_STN2_TX_DP<33>")
		)
		(pad "2" smd rect
			(at 0.2667 0 180)
			(size 0.3048 0.381)
			(layers "F.Cu" "F.Mask" "F.Paste")
			(net "P5E_PEX0_STN2_TX_C_DP<33>")
		)
	)
	(footprint ""
		(layer "F.Cu")
		(at 358.41051 -122.931428 180)
		(property "Reference" "PC480"
			(at 0 0 180)
			(layer "F.SilkS")
			(hide yes)
			(effects
				(font
					(size 1.27 1.27)
				)
			)
		)
		(property "Value" ""
			(at 0 0 180)
			(layer "F.Fab")
			(effects
				(font
					(size 1.27 1.27)
				)
			)
		)
		(duplicate_pad_numbers_are_jumpers no)
		(fp_line
			(start 0.7874 0.4064)
			(end -0.7874 0.4064)
			(stroke
				(width 0.1524)
				(type default)
			)
			(layer "F.SilkS")
		)
		(fp_line
			(start 0.7874 -0.4064)
			(end 0.7874 0.4064)
			(stroke
				(width 0.1524)
				(type default)
			)
			(layer "F.SilkS")
		)
		(fp_line
			(start -0.7874 0.4064)
			(end -0.7874 -0.4064)
			(stroke
				(width 0.1524)
				(type default)
			)
			(layer "F.SilkS")
		)
		(fp_line
			(start -0.7874 -0.4064)
			(end 0.7874 -0.4064)
			(stroke
				(width 0.1524)
				(type default)
			)
			(layer "F.SilkS")
		)
		(fp_line
			(start 0.67945 0.3048)
			(end 0.120396 0.3048)
			(stroke
				(width 0.1)
				(type default)
			)
			(layer "F.Fab")
		)
		(fp_line
			(start 0.67945 -0.3048)
			(end 0.67945 0.3048)
			(stroke
				(width 0.1)
				(type default)
			)
			(layer "F.Fab")
		)
		(fp_line
			(start 0.12065 -0.2794)
			(end 0.12065 -0.3048)
			(stroke
				(width 0.1)
				(type default)
			)
			(layer "F.Fab")
		)
		(fp_line
			(start 0.12065 -0.3048)
			(end 0.67945 -0.3048)
			(stroke
				(width 0.1)
				(type default)
			)
			(layer "F.Fab")
		)
		(fp_line
			(start 0.120396 0.3048)
			(end 0.120396 0.2794)
			(stroke
				(width 0.1)
				(type default)
			)
			(layer "F.Fab")
		)
		(fp_line
			(start 0.120396 0.2794)
			(end -0.12065 0.2794)
			(stroke
				(width 0.1)
				(type default)
			)
			(layer "F.Fab")
		)
		(fp_line
			(start -0.12065 0.3048)
			(end -0.67945 0.3048)
			(stroke
				(width 0.1)
				(type default)
			)
			(layer "F.Fab")
		)
		(fp_line
			(start -0.12065 0.2794)
			(end -0.12065 0.3048)
			(stroke
				(width 0.1)
				(type default)
			)
			(layer "F.Fab")
		)
		(fp_line
			(start -0.12065 -0.2794)
			(end 0.12065 -0.2794)
			(stroke
				(width 0.1)
				(type default)
			)
			(layer "F.Fab")
		)
		(fp_line
			(start -0.12065 -0.305054)
			(end -0.12065 -0.2794)
			(stroke
				(width 0.1)
				(type default)
			)
			(layer "F.Fab")
		)
		(fp_line
			(start -0.67945 0.3048)
			(end -0.67945 -0.305054)
			(stroke
				(width 0.1)
				(type default)
			)
			(layer "F.Fab")
		)
		(fp_line
			(start -0.67945 -0.305054)
			(end -0.12065 -0.305054)
			(stroke
				(width 0.1)
				(type default)
			)
			(layer "F.Fab")
		)
		(pad "1" smd circle
			(at -0.40005 0 180)
			(size 0 0)
			(layers "F.Cu" "F.Mask" "F.Paste")
			(net "P5V_AUX")
		)
		(pad "2" smd circle
			(at 0.40005 0 180)
			(size 0 0)
			(layers "F.Cu" "F.Mask" "F.Paste")
			(net "GND")
		)
	)
	(footprint ""
		(layer "F.Cu")
		(at 185.97118 -412.39186 90)
		(property "Reference" "R498"
			(at 0 0 90)
			(layer "F.SilkS")
			(hide yes)
			(effects
				(font
					(size 1.27 1.27)
				)
			)
		)
		(property "Value" ""
			(at 0 0 90)
			(layer "F.Fab")
			(effects
				(font
					(size 1.27 1.27)
				)
			)
		)
		(duplicate_pad_numbers_are_jumpers no)
		(fp_line
			(start 0.7874 -0.4064)
			(end 0.7874 0.4064)
			(stroke
				(width 0.1524)
				(type default)
			)
			(layer "F.SilkS")
		)
		(fp_line
			(start -0.7874 -0.4064)
			(end 0.7874 -0.4064)
			(stroke
				(width 0.1524)
				(type default)
			)
			(layer "F.SilkS")
		)
		(fp_line
			(start 0.7874 0.4064)
			(end -0.7874 0.4064)
			(stroke
				(width 0.1524)
				(type default)
			)
			(layer "F.SilkS")
		)
		(fp_line
			(start -0.7874 0.4064)
			(end -0.7874 -0.4064)
			(stroke
				(width 0.1524)
				(type default)
			)
			(layer "F.SilkS")
		)
		(fp_line
			(start -0.12065 -0.305054)
			(end -0.12065 -0.2794)
			(stroke
				(width 0.1)
				(type default)
			)
			(layer "F.Fab")
		)
		(fp_line
			(start -0.67945 -0.305054)
			(end -0.12065 -0.305054)
			(stroke
				(width 0.1)
				(type default)
			)
			(layer "F.Fab")
		)
		(fp_line
			(start 0.67945 -0.3048)
			(end 0.67945 0.3048)
			(stroke
				(width 0.1)
				(type default)
			)
			(layer "F.Fab")
		)
		(fp_line
			(start 0.12065 -0.3048)
			(end 0.67945 -0.3048)
			(stroke
				(width 0.1)
				(type default)
			)
			(layer "F.Fab")
		)
		(fp_line
			(start 0.12065 -0.2794)
			(end 0.12065 -0.3048)
			(stroke
				(width 0.1)
				(type default)
			)
			(layer "F.Fab")
		)
		(fp_line
			(start -0.12065 -0.2794)
			(end 0.12065 -0.2794)
			(stroke
				(width 0.1)
				(type default)
			)
			(layer "F.Fab")
		)
		(fp_line
			(start 0.120396 0.2794)
			(end -0.12065 0.2794)
			(stroke
				(width 0.1)
				(type default)
			)
			(layer "F.Fab")
		)
		(fp_line
			(start -0.12065 0.2794)
			(end -0.12065 0.3048)
			(stroke
				(width 0.1)
				(type default)
			)
			(layer "F.Fab")
		)
		(fp_line
			(start 0.67945 0.3048)
			(end 0.120396 0.3048)
			(stroke
				(width 0.1)
				(type default)
			)
			(layer "F.Fab")
		)
		(fp_line
			(start 0.120396 0.3048)
			(end 0.120396 0.2794)
			(stroke
				(width 0.1)
				(type default)
			)
			(layer "F.Fab")
		)
		(fp_line
			(start -0.12065 0.3048)
			(end -0.67945 0.3048)
			(stroke
				(width 0.1)
				(type default)
			)
			(layer "F.Fab")
		)
		(fp_line
			(start -0.67945 0.3048)
			(end -0.67945 -0.305054)
			(stroke
				(width 0.1)
				(type default)
			)
			(layer "F.Fab")
		)
		(pad "1" smd circle
			(at -0.40005 0 90)
			(size 0 0)
			(layers "F.Cu" "F.Mask" "F.Paste")
			(net "HSC_UV_N")
		)
		(pad "2" smd circle
			(at 0.40005 0 90)
			(size 0 0)
			(layers "F.Cu" "F.Mask" "F.Paste")
			(net "HSC_UV_R_N")
		)
	)
	(footprint ""
		(layer "F.Cu")
		(at 264.517632 -115.336574 90)
		(property "Reference" "R247"
			(at 0 0 90)
			(layer "F.SilkS")
			(hide yes)
			(effects
				(font
					(size 1.27 1.27)
				)
			)
		)
		(property "Value" ""
			(at 0 0 90)
			(layer "F.Fab")
			(effects
				(font
					(size 1.27 1.27)
				)
			)
		)
		(duplicate_pad_numbers_are_jumpers no)
		(fp_line
			(start 0.7874 -0.4064)
			(end 0.7874 0.4064)
			(stroke
				(width 0.1524)
				(type default)
			)
			(layer "F.SilkS")
		)
		(fp_line
			(start -0.7874 -0.4064)
			(end 0.7874 -0.4064)
			(stroke
				(width 0.1524)
				(type default)
			)
			(layer "F.SilkS")
		)
		(fp_line
			(start 0.7874 0.4064)
			(end -0.7874 0.4064)
			(stroke
				(width 0.1524)
				(type default)
			)
			(layer "F.SilkS")
		)
		(fp_line
			(start -0.7874 0.4064)
			(end -0.7874 -0.4064)
			(stroke
				(width 0.1524)
				(type default)
			)
			(layer "F.SilkS")
		)
		(fp_line
			(start -0.12065 -0.305054)
			(end -0.12065 -0.2794)
			(stroke
				(width 0.1)
				(type default)
			)
			(layer "F.Fab")
		)
		(fp_line
			(start -0.67945 -0.305054)
			(end -0.12065 -0.305054)
			(stroke
				(width 0.1)
				(type default)
			)
			(layer "F.Fab")
		)
		(fp_line
			(start 0.67945 -0.3048)
			(end 0.67945 0.3048)
			(stroke
				(width 0.1)
				(type default)
			)
			(layer "F.Fab")
		)
		(fp_line
			(start 0.12065 -0.3048)
			(end 0.67945 -0.3048)
			(stroke
				(width 0.1)
				(type default)
			)
			(layer "F.Fab")
		)
		(fp_line
			(start 0.12065 -0.2794)
			(end 0.12065 -0.3048)
			(stroke
				(width 0.1)
				(type default)
			)
			(layer "F.Fab")
		)
		(fp_line
			(start -0.12065 -0.2794)
			(end 0.12065 -0.2794)
			(stroke
				(width 0.1)
				(type default)
			)
			(layer "F.Fab")
		)
		(fp_line
			(start 0.120396 0.2794)
			(end -0.12065 0.2794)
			(stroke
				(width 0.1)
				(type default)
			)
			(layer "F.Fab")
		)
		(fp_line
			(start -0.12065 0.2794)
			(end -0.12065 0.3048)
			(stroke
				(width 0.1)
				(type default)
			)
			(layer "F.Fab")
		)
		(fp_line
			(start 0.67945 0.3048)
			(end 0.120396 0.3048)
			(stroke
				(width 0.1)
				(type default)
			)
			(layer "F.Fab")
		)
		(fp_line
			(start 0.120396 0.3048)
			(end 0.120396 0.2794)
			(stroke
				(width 0.1)
				(type default)
			)
			(layer "F.Fab")
		)
		(fp_line
			(start -0.12065 0.3048)
			(end -0.67945 0.3048)
			(stroke
				(width 0.1)
				(type default)
			)
			(layer "F.Fab")
		)
		(fp_line
			(start -0.67945 0.3048)
			(end -0.67945 -0.305054)
			(stroke
				(width 0.1)
				(type default)
			)
			(layer "F.Fab")
		)
		(pad "1" smd circle
			(at -0.40005 0 90)
			(size 0 0)
			(layers "F.Cu" "F.Mask" "F.Paste")
			(net "PRSNT_NIC4_R_N")
		)
		(pad "2" smd circle
			(at 0.40005 0 90)
			(size 0 0)
			(layers "F.Cu" "F.Mask" "F.Paste")
			(net "PRSNT_NIC4_N")
		)
	)
	(footprint ""
		(layer "F.Cu")
		(at 196.119242 -122.270266 180)
		(property "Reference" "C239"
			(at 0 0 180)
			(layer "F.SilkS")
			(hide yes)
			(effects
				(font
					(size 1.27 1.27)
				)
			)
		)
		(property "Value" ""
			(at 0 0 180)
			(layer "F.Fab")
			(effects
				(font
					(size 1.27 1.27)
				)
			)
		)
		(duplicate_pad_numbers_are_jumpers no)
		(fp_line
			(start 0.299974 0.150114)
			(end -0.299974 0.150114)
			(stroke
				(width 0.1)
				(type default)
			)
			(layer "F.Fab")
		)
		(fp_line
			(start 0.299974 -0.150114)
			(end 0.299974 0.150114)
			(stroke
				(width 0.1)
				(type default)
			)
			(layer "F.Fab")
		)
		(fp_line
			(start -0.299974 0.150114)
			(end -0.299974 -0.150114)
			(stroke
				(width 0.1)
				(type default)
			)
			(layer "F.Fab")
		)
		(fp_line
			(start -0.299974 -0.150114)
			(end 0.299974 -0.150114)
			(stroke
				(width 0.1)
				(type default)
			)
			(layer "F.Fab")
		)
		(pad "1" smd rect
			(at -0.2667 0 180)
			(size 0.3048 0.381)
			(layers "F.Cu" "F.Mask" "F.Paste")
			(net "P5E_PEX1_STN0_TX_DN<2>")
		)
		(pad "2" smd rect
			(at 0.2667 0 180)
			(size 0.3048 0.381)
			(layers "F.Cu" "F.Mask" "F.Paste")
			(net "P5E_PEX1_STN0_TX_C_DN<2>")
		)
	)
	(footprint ""
		(layer "F.Cu")
		(at 244.94871 -162.003994 90)
		(property "Reference" "PR7032"
			(at 0 0 90)
			(layer "F.SilkS")
			(hide yes)
			(effects
				(font
					(size 1.27 1.27)
				)
			)
		)
		(property "Value" ""
			(at 0 0 90)
			(layer "F.Fab")
			(effects
				(font
					(size 1.27 1.27)
				)
			)
		)
		(duplicate_pad_numbers_are_jumpers no)
		(fp_line
			(start 0.7874 -0.4064)
			(end 0.7874 0.4064)
			(stroke
				(width 0.1524)
				(type default)
			)
			(layer "F.SilkS")
		)
		(fp_line
			(start -0.7874 -0.4064)
			(end 0.7874 -0.4064)
			(stroke
				(width 0.1524)
				(type default)
			)
			(layer "F.SilkS")
		)
		(fp_line
			(start 0.7874 0.4064)
			(end -0.7874 0.4064)
			(stroke
				(width 0.1524)
				(type default)
			)
			(layer "F.SilkS")
		)
		(fp_line
			(start -0.7874 0.4064)
			(end -0.7874 -0.4064)
			(stroke
				(width 0.1524)
				(type default)
			)
			(layer "F.SilkS")
		)
		(fp_line
			(start -0.12065 -0.305054)
			(end -0.12065 -0.2794)
			(stroke
				(width 0.1)
				(type default)
			)
			(layer "F.Fab")
		)
		(fp_line
			(start -0.67945 -0.305054)
			(end -0.12065 -0.305054)
			(stroke
				(width 0.1)
				(type default)
			)
			(layer "F.Fab")
		)
		(fp_line
			(start 0.67945 -0.3048)
			(end 0.67945 0.3048)
			(stroke
				(width 0.1)
				(type default)
			)
			(layer "F.Fab")
		)
		(fp_line
			(start 0.12065 -0.3048)
			(end 0.67945 -0.3048)
			(stroke
				(width 0.1)
				(type default)
			)
			(layer "F.Fab")
		)
		(fp_line
			(start 0.12065 -0.2794)
			(end 0.12065 -0.3048)
			(stroke
				(width 0.1)
				(type default)
			)
			(layer "F.Fab")
		)
		(fp_line
			(start -0.12065 -0.2794)
			(end 0.12065 -0.2794)
			(stroke
				(width 0.1)
				(type default)
			)
			(layer "F.Fab")
		)
		(fp_line
			(start 0.120396 0.2794)
			(end -0.12065 0.2794)
			(stroke
				(width 0.1)
				(type default)
			)
			(layer "F.Fab")
		)
		(fp_line
			(start -0.12065 0.2794)
			(end -0.12065 0.3048)
			(stroke
				(width 0.1)
				(type default)
			)
			(layer "F.Fab")
		)
		(fp_line
			(start 0.67945 0.3048)
			(end 0.120396 0.3048)
			(stroke
				(width 0.1)
				(type default)
			)
			(layer "F.Fab")
		)
		(fp_line
			(start 0.120396 0.3048)
			(end 0.120396 0.2794)
			(stroke
				(width 0.1)
				(type default)
			)
			(layer "F.Fab")
		)
		(fp_line
			(start -0.12065 0.3048)
			(end -0.67945 0.3048)
			(stroke
				(width 0.1)
				(type default)
			)
			(layer "F.Fab")
		)
		(fp_line
			(start -0.67945 0.3048)
			(end -0.67945 -0.305054)
			(stroke
				(width 0.1)
				(type default)
			)
			(layer "F.Fab")
		)
		(pad "1" smd circle
			(at -0.40005 0 90)
			(size 0 0)
			(layers "F.Cu" "F.Mask" "F.Paste")
			(net "P12V_NIC4_CO_ISET")
		)
		(pad "2" smd circle
			(at 0.40005 0 90)
			(size 0 0)
			(layers "F.Cu" "F.Mask" "F.Paste")
			(net "GND")
		)
	)
	(footprint ""
		(layer "F.Cu")
		(at 234.040172 -172.55998 -90)
		(property "Reference" "R4256"
			(at 0 0 270)
			(layer "F.SilkS")
			(hide yes)
			(effects
				(font
					(size 1.27 1.27)
				)
			)
		)
		(property "Value" ""
			(at 0 0 270)
			(layer "F.Fab")
			(effects
				(font
					(size 1.27 1.27)
				)
			)
		)
		(duplicate_pad_numbers_are_jumpers no)
		(fp_line
			(start -0.7874 0.4064)
			(end -0.7874 -0.4064)
			(stroke
				(width 0.1524)
				(type default)
			)
			(layer "F.SilkS")
		)
		(fp_line
			(start 0.7874 0.4064)
			(end -0.7874 0.4064)
			(stroke
				(width 0.1524)
				(type default)
			)
			(layer "F.SilkS")
		)
		(fp_line
			(start -0.7874 -0.4064)
			(end 0.7874 -0.4064)
			(stroke
				(width 0.1524)
				(type default)
			)
			(layer "F.SilkS")
		)
		(fp_line
			(start 0.7874 -0.4064)
			(end 0.7874 0.4064)
			(stroke
				(width 0.1524)
				(type default)
			)
			(layer "F.SilkS")
		)
		(fp_line
			(start -0.67945 0.3048)
			(end -0.67945 -0.305054)
			(stroke
				(width 0.1)
				(type default)
			)
			(layer "F.Fab")
		)
		(fp_line
			(start -0.12065 0.3048)
			(end -0.67945 0.3048)
			(stroke
				(width 0.1)
				(type default)
			)
			(layer "F.Fab")
		)
		(fp_line
			(start 0.120396 0.3048)
			(end 0.120396 0.2794)
			(stroke
				(width 0.1)
				(type default)
			)
			(layer "F.Fab")
		)
		(fp_line
			(start 0.67945 0.3048)
			(end 0.120396 0.3048)
			(stroke
				(width 0.1)
				(type default)
			)
			(layer "F.Fab")
		)
		(fp_line
			(start -0.12065 0.2794)
			(end -0.12065 0.3048)
			(stroke
				(width 0.1)
				(type default)
			)
			(layer "F.Fab")
		)
		(fp_line
			(start 0.120396 0.2794)
			(end -0.12065 0.2794)
			(stroke
				(width 0.1)
				(type default)
			)
			(layer "F.Fab")
		)
		(fp_line
			(start -0.12065 -0.2794)
			(end 0.12065 -0.2794)
			(stroke
				(width 0.1)
				(type default)
			)
			(layer "F.Fab")
		)
		(fp_line
			(start 0.12065 -0.2794)
			(end 0.12065 -0.3048)
			(stroke
				(width 0.1)
				(type default)
			)
			(layer "F.Fab")
		)
		(fp_line
			(start 0.12065 -0.3048)
			(end 0.67945 -0.3048)
			(stroke
				(width 0.1)
				(type default)
			)
			(layer "F.Fab")
		)
		(fp_line
			(start 0.67945 -0.3048)
			(end 0.67945 0.3048)
			(stroke
				(width 0.1)
				(type default)
			)
			(layer "F.Fab")
		)
		(fp_line
			(start -0.67945 -0.305054)
			(end -0.12065 -0.305054)
			(stroke
				(width 0.1)
				(type default)
			)
			(layer "F.Fab")
		)
		(fp_line
			(start -0.12065 -0.305054)
			(end -0.12065 -0.2794)
			(stroke
				(width 0.1)
				(type default)
			)
			(layer "F.Fab")
		)
		(pad "1" smd circle
			(at -0.40005 0 270)
			(size 0 0)
			(layers "F.Cu" "F.Mask" "F.Paste")
			(net "RST_BIC_SRST_N")
		)
		(pad "2" smd circle
			(at 0.40005 0 270)
			(size 0 0)
			(layers "F.Cu" "F.Mask" "F.Paste")
			(net "RST_BIC_SRST_R_N")
		)
	)
	(footprint ""
		(layer "F.Cu")
		(at 291.97173 -24.807418)
		(property "Reference" "R441"
			(at 0 0 0)
			(layer "F.SilkS")
			(hide yes)
			(effects
				(font
					(size 1.27 1.27)
				)
			)
		)
		(property "Value" ""
			(at 0 0 0)
			(layer "F.Fab")
			(effects
				(font
					(size 1.27 1.27)
				)
			)
		)
		(duplicate_pad_numbers_are_jumpers no)
		(fp_line
			(start -0.7874 -0.4064)
			(end 0.7874 -0.4064)
			(stroke
				(width 0.1524)
				(type default)
			)
			(layer "F.SilkS")
		)
		(fp_line
			(start -0.7874 0.4064)
			(end -0.7874 -0.4064)
			(stroke
				(width 0.1524)
				(type default)
			)
			(layer "F.SilkS")
		)
		(fp_line
			(start 0.7874 -0.4064)
			(end 0.7874 0.4064)
			(stroke
				(width 0.1524)
				(type default)
			)
			(layer "F.SilkS")
		)
		(fp_line
			(start 0.7874 0.4064)
			(end -0.7874 0.4064)
			(stroke
				(width 0.1524)
				(type default)
			)
			(layer "F.SilkS")
		)
		(fp_line
			(start -0.67945 -0.305054)
			(end -0.12065 -0.305054)
			(stroke
				(width 0.1)
				(type default)
			)
			(layer "F.Fab")
		)
		(fp_line
			(start -0.67945 0.3048)
			(end -0.67945 -0.305054)
			(stroke
				(width 0.1)
				(type default)
			)
			(layer "F.Fab")
		)
		(fp_line
			(start -0.12065 -0.305054)
			(end -0.12065 -0.2794)
			(stroke
				(width 0.1)
				(type default)
			)
			(layer "F.Fab")
		)
		(fp_line
			(start -0.12065 -0.2794)
			(end 0.12065 -0.2794)
			(stroke
				(width 0.1)
				(type default)
			)
			(layer "F.Fab")
		)
		(fp_line
			(start -0.12065 0.2794)
			(end -0.12065 0.3048)
			(stroke
				(width 0.1)
				(type default)
			)
			(layer "F.Fab")
		)
		(fp_line
			(start -0.12065 0.3048)
			(end -0.67945 0.3048)
			(stroke
				(width 0.1)
				(type default)
			)
			(layer "F.Fab")
		)
		(fp_line
			(start 0.120396 0.2794)
			(end -0.12065 0.2794)
			(stroke
				(width 0.1)
				(type default)
			)
			(layer "F.Fab")
		)
		(fp_line
			(start 0.120396 0.3048)
			(end 0.120396 0.2794)
			(stroke
				(width 0.1)
				(type default)
			)
			(layer "F.Fab")
		)
		(fp_line
			(start 0.12065 -0.3048)
			(end 0.67945 -0.3048)
			(stroke
				(width 0.1)
				(type default)
			)
			(layer "F.Fab")
		)
		(fp_line
			(start 0.12065 -0.2794)
			(end 0.12065 -0.3048)
			(stroke
				(width 0.1)
				(type default)
			)
			(layer "F.Fab")
		)
		(fp_line
			(start 0.67945 -0.3048)
			(end 0.67945 0.3048)
			(stroke
				(width 0.1)
				(type default)
			)
			(layer "F.Fab")
		)
		(fp_line
			(start 0.67945 0.3048)
			(end 0.120396 0.3048)
			(stroke
				(width 0.1)
				(type default)
			)
			(layer "F.Fab")
		)
		(pad "1" smd circle
			(at -0.40005 0)
			(size 0 0)
			(layers "F.Cu" "F.Mask" "F.Paste")
			(net "P3V3_SSD10")
		)
		(pad "2" smd circle
			(at 0.40005 0)
			(size 0 0)
			(layers "F.Cu" "F.Mask" "F.Paste")
			(net "PU_CLKREQ10")
		)
	)
	(footprint ""
		(layer "F.Cu")
		(at 198.913496 -114.42954 180)
		(property "Reference" "R187"
			(at 0 0 180)
			(layer "F.SilkS")
			(hide yes)
			(effects
				(font
					(size 1.27 1.27)
				)
			)
		)
		(property "Value" ""
			(at 0 0 180)
			(layer "F.Fab")
			(effects
				(font
					(size 1.27 1.27)
				)
			)
		)
		(duplicate_pad_numbers_are_jumpers no)
		(fp_line
			(start 0.7874 0.4064)
			(end -0.7874 0.4064)
			(stroke
				(width 0.1524)
				(type default)
			)
			(layer "F.SilkS")
		)
		(fp_line
			(start 0.7874 -0.4064)
			(end 0.7874 0.4064)
			(stroke
				(width 0.1524)
				(type default)
			)
			(layer "F.SilkS")
		)
		(fp_line
			(start -0.7874 0.4064)
			(end -0.7874 -0.4064)
			(stroke
				(width 0.1524)
				(type default)
			)
			(layer "F.SilkS")
		)
		(fp_line
			(start -0.7874 -0.4064)
			(end 0.7874 -0.4064)
			(stroke
				(width 0.1524)
				(type default)
			)
			(layer "F.SilkS")
		)
		(fp_line
			(start 0.67945 0.3048)
			(end 0.120396 0.3048)
			(stroke
				(width 0.1)
				(type default)
			)
			(layer "F.Fab")
		)
		(fp_line
			(start 0.67945 -0.3048)
			(end 0.67945 0.3048)
			(stroke
				(width 0.1)
				(type default)
			)
			(layer "F.Fab")
		)
		(fp_line
			(start 0.12065 -0.2794)
			(end 0.12065 -0.3048)
			(stroke
				(width 0.1)
				(type default)
			)
			(layer "F.Fab")
		)
		(fp_line
			(start 0.12065 -0.3048)
			(end 0.67945 -0.3048)
			(stroke
				(width 0.1)
				(type default)
			)
			(layer "F.Fab")
		)
		(fp_line
			(start 0.120396 0.3048)
			(end 0.120396 0.2794)
			(stroke
				(width 0.1)
				(type default)
			)
			(layer "F.Fab")
		)
		(fp_line
			(start 0.120396 0.2794)
			(end -0.12065 0.2794)
			(stroke
				(width 0.1)
				(type default)
			)
			(layer "F.Fab")
		)
		(fp_line
			(start -0.12065 0.3048)
			(end -0.67945 0.3048)
			(stroke
				(width 0.1)
				(type default)
			)
			(layer "F.Fab")
		)
		(fp_line
			(start -0.12065 0.2794)
			(end -0.12065 0.3048)
			(stroke
				(width 0.1)
				(type default)
			)
			(layer "F.Fab")
		)
		(fp_line
			(start -0.12065 -0.2794)
			(end 0.12065 -0.2794)
			(stroke
				(width 0.1)
				(type default)
			)
			(layer "F.Fab")
		)
		(fp_line
			(start -0.12065 -0.305054)
			(end -0.12065 -0.2794)
			(stroke
				(width 0.1)
				(type default)
			)
			(layer "F.Fab")
		)
		(fp_line
			(start -0.67945 0.3048)
			(end -0.67945 -0.305054)
			(stroke
				(width 0.1)
				(type default)
			)
			(layer "F.Fab")
		)
		(fp_line
			(start -0.67945 -0.305054)
			(end -0.12065 -0.305054)
			(stroke
				(width 0.1)
				(type default)
			)
			(layer "F.Fab")
		)
		(pad "1" smd circle
			(at -0.40005 0 180)
			(size 0 0)
			(layers "F.Cu" "F.Mask" "F.Paste")
			(net "NIC3_BIF2_N")
		)
		(pad "2" smd circle
			(at 0.40005 0 180)
			(size 0 0)
			(layers "F.Cu" "F.Mask" "F.Paste")
			(net "GND")
		)
	)
	(footprint ""
		(layer "F.Cu")
		(at 298.961302 -356.244906 90)
		(property "Reference" "C2371"
			(at 0 0 90)
			(layer "F.SilkS")
			(hide yes)
			(effects
				(font
					(size 1.27 1.27)
				)
			)
		)
		(property "Value" ""
			(at 0 0 90)
			(layer "F.Fab")
			(effects
				(font
					(size 1.27 1.27)
				)
			)
		)
		(duplicate_pad_numbers_are_jumpers no)
		(fp_line
			(start 0.299974 -0.150114)
			(end 0.299974 0.150114)
			(stroke
				(width 0.1)
				(type default)
			)
			(layer "F.Fab")
		)
		(fp_line
			(start -0.299974 -0.150114)
			(end 0.299974 -0.150114)
			(stroke
				(width 0.1)
				(type default)
			)
			(layer "F.Fab")
		)
		(fp_line
			(start 0.299974 0.150114)
			(end -0.299974 0.150114)
			(stroke
				(width 0.1)
				(type default)
			)
			(layer "F.Fab")
		)
		(fp_line
			(start -0.299974 0.150114)
			(end -0.299974 -0.150114)
			(stroke
				(width 0.1)
				(type default)
			)
			(layer "F.Fab")
		)
		(pad "1" smd rect
			(at -0.2667 0 90)
			(size 0.3048 0.381)
			(layers "F.Cu" "F.Mask" "F.Paste")
			(net "P5E_PEX2_STN4_TX_DP<64>")
		)
		(pad "2" smd rect
			(at 0.2667 0 90)
			(size 0.3048 0.381)
			(layers "F.Cu" "F.Mask" "F.Paste")
			(net "P5E_PEX2_STN4_TX_C_DP<64>")
		)
	)
	(footprint ""
		(layer "F.Cu")
		(at 374.27154 -356.244906 90)
		(property "Reference" "C782"
			(at 0 0 90)
			(layer "F.SilkS")
			(hide yes)
			(effects
				(font
					(size 1.27 1.27)
				)
			)
		)
		(property "Value" ""
			(at 0 0 90)
			(layer "F.Fab")
			(effects
				(font
					(size 1.27 1.27)
				)
			)
		)
		(duplicate_pad_numbers_are_jumpers no)
		(fp_line
			(start 0.299974 -0.150114)
			(end 0.299974 0.150114)
			(stroke
				(width 0.1)
				(type default)
			)
			(layer "F.Fab")
		)
		(fp_line
			(start -0.299974 -0.150114)
			(end 0.299974 -0.150114)
			(stroke
				(width 0.1)
				(type default)
			)
			(layer "F.Fab")
		)
		(fp_line
			(start 0.299974 0.150114)
			(end -0.299974 0.150114)
			(stroke
				(width 0.1)
				(type default)
			)
			(layer "F.Fab")
		)
		(fp_line
			(start -0.299974 0.150114)
			(end -0.299974 -0.150114)
			(stroke
				(width 0.1)
				(type default)
			)
			(layer "F.Fab")
		)
		(pad "1" smd rect
			(at -0.2667 0 90)
			(size 0.3048 0.381)
			(layers "F.Cu" "F.Mask" "F.Paste")
			(net "P5E_PEX3_STN6_TX_DP<101>")
		)
		(pad "2" smd rect
			(at 0.2667 0 90)
			(size 0.3048 0.381)
			(layers "F.Cu" "F.Mask" "F.Paste")
			(net "P5E_PEX3_STN6_TX_C_DP<101>")
		)
	)
	(footprint ""
		(layer "F.Cu")
		(at 98.975672 -123.795028)
		(property "Reference" "C2879"
			(at 0 0 0)
			(layer "F.SilkS")
			(hide yes)
			(effects
				(font
					(size 1.27 1.27)
				)
			)
		)
		(property "Value" ""
			(at 0 0 0)
			(layer "F.Fab")
			(effects
				(font
					(size 1.27 1.27)
				)
			)
		)
		(duplicate_pad_numbers_are_jumpers no)
		(fp_line
			(start -0.7874 -0.4064)
			(end 0.7874 -0.4064)
			(stroke
				(width 0.1524)
				(type default)
			)
			(layer "F.SilkS")
		)
		(fp_line
			(start -0.7874 0.4064)
			(end -0.7874 -0.4064)
			(stroke
				(width 0.1524)
				(type default)
			)
			(layer "F.SilkS")
		)
		(fp_line
			(start 0.7874 -0.4064)
			(end 0.7874 0.4064)
			(stroke
				(width 0.1524)
				(type default)
			)
			(layer "F.SilkS")
		)
		(fp_line
			(start 0.7874 0.4064)
			(end -0.7874 0.4064)
			(stroke
				(width 0.1524)
				(type default)
			)
			(layer "F.SilkS")
		)
		(fp_line
			(start -0.67945 -0.305054)
			(end -0.12065 -0.305054)
			(stroke
				(width 0.1)
				(type default)
			)
			(layer "F.Fab")
		)
		(fp_line
			(start -0.67945 0.3048)
			(end -0.67945 -0.305054)
			(stroke
				(width 0.1)
				(type default)
			)
			(layer "F.Fab")
		)
		(fp_line
			(start -0.12065 -0.305054)
			(end -0.12065 -0.2794)
			(stroke
				(width 0.1)
				(type default)
			)
			(layer "F.Fab")
		)
		(fp_line
			(start -0.12065 -0.2794)
			(end 0.12065 -0.2794)
			(stroke
				(width 0.1)
				(type default)
			)
			(layer "F.Fab")
		)
		(fp_line
			(start -0.12065 0.2794)
			(end -0.12065 0.3048)
			(stroke
				(width 0.1)
				(type default)
			)
			(layer "F.Fab")
		)
		(fp_line
			(start -0.12065 0.3048)
			(end -0.67945 0.3048)
			(stroke
				(width 0.1)
				(type default)
			)
			(layer "F.Fab")
		)
		(fp_line
			(start 0.120396 0.2794)
			(end -0.12065 0.2794)
			(stroke
				(width 0.1)
				(type default)
			)
			(layer "F.Fab")
		)
		(fp_line
			(start 0.120396 0.3048)
			(end 0.120396 0.2794)
			(stroke
				(width 0.1)
				(type default)
			)
			(layer "F.Fab")
		)
		(fp_line
			(start 0.12065 -0.3048)
			(end 0.67945 -0.3048)
			(stroke
				(width 0.1)
				(type default)
			)
			(layer "F.Fab")
		)
		(fp_line
			(start 0.12065 -0.2794)
			(end 0.12065 -0.3048)
			(stroke
				(width 0.1)
				(type default)
			)
			(layer "F.Fab")
		)
		(fp_line
			(start 0.67945 -0.3048)
			(end 0.67945 0.3048)
			(stroke
				(width 0.1)
				(type default)
			)
			(layer "F.Fab")
		)
		(fp_line
			(start 0.67945 0.3048)
			(end 0.120396 0.3048)
			(stroke
				(width 0.1)
				(type default)
			)
			(layer "F.Fab")
		)
		(pad "1" smd circle
			(at -0.40005 0)
			(size 0 0)
			(layers "F.Cu" "F.Mask" "F.Paste")
			(net "HP_NIC1_EN")
		)
		(pad "2" smd circle
			(at 0.40005 0)
			(size 0 0)
			(layers "F.Cu" "F.Mask" "F.Paste")
			(net "GND")
		)
	)
	(footprint ""
		(layer "F.Cu")
		(at 123.203462 -59.571636 90)
		(property "Reference" "PR258"
			(at 0 0 90)
			(layer "F.SilkS")
			(hide yes)
			(effects
				(font
					(size 1.27 1.27)
				)
			)
		)
		(property "Value" ""
			(at 0 0 90)
			(layer "F.Fab")
			(effects
				(font
					(size 1.27 1.27)
				)
			)
		)
		(duplicate_pad_numbers_are_jumpers no)
		(fp_line
			(start 0.7874 -0.4064)
			(end 0.7874 0.4064)
			(stroke
				(width 0.1524)
				(type default)
			)
			(layer "F.SilkS")
		)
		(fp_line
			(start -0.7874 -0.4064)
			(end 0.7874 -0.4064)
			(stroke
				(width 0.1524)
				(type default)
			)
			(layer "F.SilkS")
		)
		(fp_line
			(start 0.7874 0.4064)
			(end -0.7874 0.4064)
			(stroke
				(width 0.1524)
				(type default)
			)
			(layer "F.SilkS")
		)
		(fp_line
			(start -0.7874 0.4064)
			(end -0.7874 -0.4064)
			(stroke
				(width 0.1524)
				(type default)
			)
			(layer "F.SilkS")
		)
		(fp_line
			(start -0.12065 -0.305054)
			(end -0.12065 -0.2794)
			(stroke
				(width 0.1)
				(type default)
			)
			(layer "F.Fab")
		)
		(fp_line
			(start -0.67945 -0.305054)
			(end -0.12065 -0.305054)
			(stroke
				(width 0.1)
				(type default)
			)
			(layer "F.Fab")
		)
		(fp_line
			(start 0.67945 -0.3048)
			(end 0.67945 0.3048)
			(stroke
				(width 0.1)
				(type default)
			)
			(layer "F.Fab")
		)
		(fp_line
			(start 0.12065 -0.3048)
			(end 0.67945 -0.3048)
			(stroke
				(width 0.1)
				(type default)
			)
			(layer "F.Fab")
		)
		(fp_line
			(start 0.12065 -0.2794)
			(end 0.12065 -0.3048)
			(stroke
				(width 0.1)
				(type default)
			)
			(layer "F.Fab")
		)
		(fp_line
			(start -0.12065 -0.2794)
			(end 0.12065 -0.2794)
			(stroke
				(width 0.1)
				(type default)
			)
			(layer "F.Fab")
		)
		(fp_line
			(start 0.120396 0.2794)
			(end -0.12065 0.2794)
			(stroke
				(width 0.1)
				(type default)
			)
			(layer "F.Fab")
		)
		(fp_line
			(start -0.12065 0.2794)
			(end -0.12065 0.3048)
			(stroke
				(width 0.1)
				(type default)
			)
			(layer "F.Fab")
		)
		(fp_line
			(start 0.67945 0.3048)
			(end 0.120396 0.3048)
			(stroke
				(width 0.1)
				(type default)
			)
			(layer "F.Fab")
		)
		(fp_line
			(start 0.120396 0.3048)
			(end 0.120396 0.2794)
			(stroke
				(width 0.1)
				(type default)
			)
			(layer "F.Fab")
		)
		(fp_line
			(start -0.12065 0.3048)
			(end -0.67945 0.3048)
			(stroke
				(width 0.1)
				(type default)
			)
			(layer "F.Fab")
		)
		(fp_line
			(start -0.67945 0.3048)
			(end -0.67945 -0.305054)
			(stroke
				(width 0.1)
				(type default)
			)
			(layer "F.Fab")
		)
		(pad "1" smd circle
			(at -0.40005 0 90)
			(size 0 0)
			(layers "F.Cu" "F.Mask" "F.Paste")
			(net "P3V3_SSD4_OCP")
		)
		(pad "2" smd circle
			(at 0.40005 0 90)
			(size 0 0)
			(layers "F.Cu" "F.Mask" "F.Paste")
			(net "GND")
		)
	)
	(footprint ""
		(layer "F.Cu")
		(at 329.438 -84.709 180)
		(property "Reference" "R1471"
			(at 0 0 180)
			(layer "F.SilkS")
			(hide yes)
			(effects
				(font
					(size 1.27 1.27)
				)
			)
		)
		(property "Value" ""
			(at 0 0 180)
			(layer "F.Fab")
			(effects
				(font
					(size 1.27 1.27)
				)
			)
		)
		(duplicate_pad_numbers_are_jumpers no)
		(fp_line
			(start 0.7874 0.4064)
			(end -0.7874 0.4064)
			(stroke
				(width 0.1524)
				(type default)
			)
			(layer "F.SilkS")
		)
		(fp_line
			(start 0.7874 -0.4064)
			(end 0.7874 0.4064)
			(stroke
				(width 0.1524)
				(type default)
			)
			(layer "F.SilkS")
		)
		(fp_line
			(start -0.7874 0.4064)
			(end -0.7874 -0.4064)
			(stroke
				(width 0.1524)
				(type default)
			)
			(layer "F.SilkS")
		)
		(fp_line
			(start -0.7874 -0.4064)
			(end 0.7874 -0.4064)
			(stroke
				(width 0.1524)
				(type default)
			)
			(layer "F.SilkS")
		)
		(fp_line
			(start 0.67945 0.3048)
			(end 0.120396 0.3048)
			(stroke
				(width 0.1)
				(type default)
			)
			(layer "F.Fab")
		)
		(fp_line
			(start 0.67945 -0.3048)
			(end 0.67945 0.3048)
			(stroke
				(width 0.1)
				(type default)
			)
			(layer "F.Fab")
		)
		(fp_line
			(start 0.12065 -0.2794)
			(end 0.12065 -0.3048)
			(stroke
				(width 0.1)
				(type default)
			)
			(layer "F.Fab")
		)
		(fp_line
			(start 0.12065 -0.3048)
			(end 0.67945 -0.3048)
			(stroke
				(width 0.1)
				(type default)
			)
			(layer "F.Fab")
		)
		(fp_line
			(start 0.120396 0.3048)
			(end 0.120396 0.2794)
			(stroke
				(width 0.1)
				(type default)
			)
			(layer "F.Fab")
		)
		(fp_line
			(start 0.120396 0.2794)
			(end -0.12065 0.2794)
			(stroke
				(width 0.1)
				(type default)
			)
			(layer "F.Fab")
		)
		(fp_line
			(start -0.12065 0.3048)
			(end -0.67945 0.3048)
			(stroke
				(width 0.1)
				(type default)
			)
			(layer "F.Fab")
		)
		(fp_line
			(start -0.12065 0.2794)
			(end -0.12065 0.3048)
			(stroke
				(width 0.1)
				(type default)
			)
			(layer "F.Fab")
		)
		(fp_line
			(start -0.12065 -0.2794)
			(end 0.12065 -0.2794)
			(stroke
				(width 0.1)
				(type default)
			)
			(layer "F.Fab")
		)
		(fp_line
			(start -0.12065 -0.305054)
			(end -0.12065 -0.2794)
			(stroke
				(width 0.1)
				(type default)
			)
			(layer "F.Fab")
		)
		(fp_line
			(start -0.67945 0.3048)
			(end -0.67945 -0.305054)
			(stroke
				(width 0.1)
				(type default)
			)
			(layer "F.Fab")
		)
		(fp_line
			(start -0.67945 -0.305054)
			(end -0.12065 -0.305054)
			(stroke
				(width 0.1)
				(type default)
			)
			(layer "F.Fab")
		)
		(pad "1" smd circle
			(at -0.40005 0 180)
			(size 0 0)
			(layers "F.Cu" "F.Mask" "F.Paste")
			(net "SMB_BMC_9ZXL0851_8_15_SDA")
		)
		(pad "2" smd circle
			(at 0.40005 0 180)
			(size 0 0)
			(layers "F.Cu" "F.Mask" "F.Paste")
			(net "SMB_ISO_CB_SDA")
		)
	)
	(footprint ""
		(layer "F.Cu")
		(at 481.686362 -554.994826 90)
		(property "Reference" "HS_BP3"
			(at -0.5842 -1.31953 90)
			(unlocked yes)
			(layer "B.SilkS")
			(effects
				(font
					(size 0.7874 0.5842)
					(thickness 0.1524)
				)
				(justify left mirror)
			)
		)
		(property "Value" ""
			(at 0 0 90)
			(layer "F.Fab")
			(effects
				(font
					(size 1.27 1.27)
				)
			)
		)
		(duplicate_pad_numbers_are_jumpers no)
		(pad "1" thru_hole circle
			(at 0 0 90)
			(size 0.4572 0.4572)
			(drill 0.2032)
			(layers "*.Cu" "*.Mask")
			(remove_unused_layers no)
			(net "Net_9199")
			(clearance 0.127)
			(thermal_gap 0.127)
			(padstack
				(mode front_inner_back)
				(layer "Inner"
					(shape circle)
					(size 0.4572 0.4572)
					(clearance 0.127)
				)
				(layer "B.Cu"
					(shape circle)
					(size 0.508 0.508)
					(clearance 0.1016)
				)
			)
		)
	)
	(footprint ""
		(layer "F.Cu")
		(at 95.177356 -201.109326 -90)
		(property "Reference" "R6621"
			(at 0 0 270)
			(layer "F.SilkS")
			(hide yes)
			(effects
				(font
					(size 1.27 1.27)
				)
			)
		)
		(property "Value" ""
			(at 0 0 270)
			(layer "F.Fab")
			(effects
				(font
					(size 1.27 1.27)
				)
			)
		)
		(duplicate_pad_numbers_are_jumpers no)
		(fp_line
			(start -0.7874 0.4064)
			(end -0.7874 -0.4064)
			(stroke
				(width 0.1524)
				(type default)
			)
			(layer "F.SilkS")
		)
		(fp_line
			(start 0.7874 0.4064)
			(end -0.7874 0.4064)
			(stroke
				(width 0.1524)
				(type default)
			)
			(layer "F.SilkS")
		)
		(fp_line
			(start -0.7874 -0.4064)
			(end 0.7874 -0.4064)
			(stroke
				(width 0.1524)
				(type default)
			)
			(layer "F.SilkS")
		)
		(fp_line
			(start 0.7874 -0.4064)
			(end 0.7874 0.4064)
			(stroke
				(width 0.1524)
				(type default)
			)
			(layer "F.SilkS")
		)
		(fp_line
			(start -0.67945 0.3048)
			(end -0.67945 -0.305054)
			(stroke
				(width 0.1)
				(type default)
			)
			(layer "F.Fab")
		)
		(fp_line
			(start -0.12065 0.3048)
			(end -0.67945 0.3048)
			(stroke
				(width 0.1)
				(type default)
			)
			(layer "F.Fab")
		)
		(fp_line
			(start 0.120396 0.3048)
			(end 0.120396 0.2794)
			(stroke
				(width 0.1)
				(type default)
			)
			(layer "F.Fab")
		)
		(fp_line
			(start 0.67945 0.3048)
			(end 0.120396 0.3048)
			(stroke
				(width 0.1)
				(type default)
			)
			(layer "F.Fab")
		)
		(fp_line
			(start -0.12065 0.2794)
			(end -0.12065 0.3048)
			(stroke
				(width 0.1)
				(type default)
			)
			(layer "F.Fab")
		)
		(fp_line
			(start 0.120396 0.2794)
			(end -0.12065 0.2794)
			(stroke
				(width 0.1)
				(type default)
			)
			(layer "F.Fab")
		)
		(fp_line
			(start -0.12065 -0.2794)
			(end 0.12065 -0.2794)
			(stroke
				(width 0.1)
				(type default)
			)
			(layer "F.Fab")
		)
		(fp_line
			(start 0.12065 -0.2794)
			(end 0.12065 -0.3048)
			(stroke
				(width 0.1)
				(type default)
			)
			(layer "F.Fab")
		)
		(fp_line
			(start 0.12065 -0.3048)
			(end 0.67945 -0.3048)
			(stroke
				(width 0.1)
				(type default)
			)
			(layer "F.Fab")
		)
		(fp_line
			(start 0.67945 -0.3048)
			(end 0.67945 0.3048)
			(stroke
				(width 0.1)
				(type default)
			)
			(layer "F.Fab")
		)
		(fp_line
			(start -0.67945 -0.305054)
			(end -0.12065 -0.305054)
			(stroke
				(width 0.1)
				(type default)
			)
			(layer "F.Fab")
		)
		(fp_line
			(start -0.12065 -0.305054)
			(end -0.12065 -0.2794)
			(stroke
				(width 0.1)
				(type default)
			)
			(layer "F.Fab")
		)
		(pad "1" smd circle
			(at -0.40005 0 270)
			(size 0 0)
			(layers "F.Cu" "F.Mask" "F.Paste")
			(net "P3V3_AUX")
		)
		(pad "2" smd circle
			(at 0.40005 0 270)
			(size 0 0)
			(layers "F.Cu" "F.Mask" "F.Paste")
			(net "RST_CP2108_CLI_R_N")
		)
	)
	(footprint ""
		(layer "F.Cu")
		(at 328.820018 -15.649956 180)
		(property "Reference" "H106"
			(at -3.981958 -2.599182 0)
			(unlocked yes)
			(layer "B.SilkS")
			(effects
				(font
					(size 0.7874 0.5842)
					(thickness 0.1524)
				)
				(justify left mirror)
			)
		)
		(property "Value" ""
			(at 0 0 180)
			(layer "F.Fab")
			(effects
				(font
					(size 1.27 1.27)
				)
			)
		)
		(duplicate_pad_numbers_are_jumpers no)
		(pad "1" thru_hole rect
			(at 0 0 180)
			(size 4.2164 5.0038)
			(drill 2.0066
				(offset 0.099822 0)
			)
			(layers "*.Cu" "*.Mask")
			(remove_unused_layers no)
			(net "Net_8557")
			(clearance -0.8509)
			(padstack
				(mode front_inner_back)
				(layer "Inner"
					(shape circle)
					(size 4.0132 4.0132)
					(clearance -0.7493)
				)
				(layer "B.Cu"
					(shape circle)
					(size 4.0132 4.0132)
					(clearance -0.7493)
				)
			)
		)
	)
	(footprint ""
		(layer "F.Cu")
		(at 164.747194 -54.3941)
		(property "Reference" "PU33"
			(at -1.707642 3.195574 0)
			(unlocked yes)
			(layer "F.SilkS")
			(effects
				(font
					(size 0.7874 0.5842)
					(thickness 0.1524)
				)
				(justify left)
			)
		)
		(property "Value" ""
			(at 0 0 0)
			(layer "F.Fab")
			(effects
				(font
					(size 1.27 1.27)
				)
			)
		)
		(duplicate_pad_numbers_are_jumpers no)
		(fp_line
			(start -1.943608 -1.549908)
			(end 1.943608 -1.549908)
			(stroke
				(width 0.1524)
				(type default)
			)
			(layer "F.SilkS")
		)
		(fp_line
			(start -1.943608 1.549908)
			(end -1.943608 -1.549908)
			(stroke
				(width 0.1524)
				(type default)
			)
			(layer "F.SilkS")
		)
		(fp_line
			(start 1.943608 -1.549908)
			(end 1.943608 1.549908)
			(stroke
				(width 0.1524)
				(type default)
			)
			(layer "F.SilkS")
		)
		(fp_line
			(start 1.943608 1.549908)
			(end -1.943608 1.549908)
			(stroke
				(width 0.1524)
				(type default)
			)
			(layer "F.SilkS")
		)
		(fp_poly
			(pts
				(xy -2.019808 -1.549908) (xy -1.257808 -1.549908) (xy -1.257808 -1.880108) (xy -2.019808 -1.880108)
			)
			(stroke
				(width 0)
				(type default)
			)
			(fill yes)
			(layer "F.SilkS")
		)
		(fp_line
			(start -1.549908 -1.549908)
			(end 1.549908 -1.549908)
			(stroke
				(width 0.1)
				(type default)
			)
			(layer "F.Fab")
		)
		(fp_line
			(start -1.549908 1.549908)
			(end -1.549908 -1.549908)
			(stroke
				(width 0.1)
				(type default)
			)
			(layer "F.Fab")
		)
		(fp_line
			(start 1.549908 -1.549908)
			(end 1.549908 1.549908)
			(stroke
				(width 0.1)
				(type default)
			)
			(layer "F.Fab")
		)
		(fp_line
			(start 1.549908 1.549908)
			(end -1.549908 1.549908)
			(stroke
				(width 0.1)
				(type default)
			)
			(layer "F.Fab")
		)
		(fp_poly
			(pts
				(xy -2.019808 -1.549908) (xy -1.257808 -1.549908) (xy -1.257808 -1.880108) (xy -2.019808 -1.880108)
			)
			(stroke
				(width 0)
				(type default)
			)
			(fill yes)
			(layer "F.Fab")
		)
		(pad "1" smd rect
			(at -1.500124 -1.249934 270)
			(size 0.2794 0.6096)
			(layers "F.Cu" "F.Mask" "F.Paste")
			(net "P12V_SSD5_R")
		)
		(pad "2" smd rect
			(at -1.500124 -0.750062 270)
			(size 0.2794 0.6096)
			(layers "F.Cu" "F.Mask" "F.Paste")
			(net "P12V_SSD5_R")
		)
		(pad "3" smd rect
			(at -1.500124 -0.249936 270)
			(size 0.2794 0.6096)
			(layers "F.Cu" "F.Mask" "F.Paste")
			(net "P12V_SSD5_R")
		)
		(pad "4" smd rect
			(at -1.500124 0.249936 270)
			(size 0.2794 0.6096)
			(layers "F.Cu" "F.Mask" "F.Paste")
			(net "P12V_SSD5_R")
		)
		(pad "5" smd rect
			(at -1.500124 0.750062 270)
			(size 0.2794 0.6096)
			(layers "F.Cu" "F.Mask" "F.Paste")
			(net "P12V_SSD5_R")
		)
		(pad "6" smd rect
			(at -1.500124 1.249934 270)
			(size 0.2794 0.6096)
			(layers "F.Cu" "F.Mask" "F.Paste")
			(net "GND")
		)
		(pad "7" smd rect
			(at 1.500124 1.249934 270)
			(size 0.2794 0.6096)
			(layers "F.Cu" "F.Mask" "F.Paste")
			(net "P12V_SSD5_SS")
		)
		(pad "8" smd rect
			(at 1.500124 0.750062 270)
			(size 0.2794 0.6096)
			(layers "F.Cu" "F.Mask" "F.Paste")
			(net "PWRGD_P12V_SSD5")
		)
		(pad "9" smd rect
			(at 1.500124 0.249936 270)
			(size 0.2794 0.6096)
			(layers "F.Cu" "F.Mask" "F.Paste")
			(net "P12V_SSD5_OCP")
		)
		(pad "10" smd rect
			(at 1.500124 -0.249936 270)
			(size 0.2794 0.6096)
			(layers "F.Cu" "F.Mask" "F.Paste")
			(net "P5V_AUX")
		)
		(pad "11" smd rect
			(at 1.500124 -0.750062 270)
			(size 0.2794 0.6096)
			(layers "F.Cu" "F.Mask" "F.Paste")
			(net "SSD5_PWR_EN_R")
		)
		(pad "12" smd rect
			(at 1.500124 -1.249934 270)
			(size 0.2794 0.6096)
			(layers "F.Cu" "F.Mask" "F.Paste")
			(net "P12V_AUX")
		)
		(pad "13" smd rect
			(at 0 0)
			(size 1.9812 2.7178)
			(layers "F.Cu" "F.Mask" "F.Paste")
			(net "P12V_AUX")
		)
		(zone
			(layer "F.Cu")
			(hatch none 0.5)
			(connect_pads
				(clearance 0)
			)
			(min_thickness 0.25)
			(keepout
				(tracks not_allowed)
				(vias allowed)
				(pads allowed)
				(copperpour not_allowed)
				(footprints allowed)
			)
			(placement
				(enabled no)
				(sheetname "")
			)
			(fill
				(thermal_gap 0.5)
				(thermal_bridge_width 0.5)
				(island_removal_mode 0)
			)
			(polygon
				(pts
					(xy 165.890194 -55.9435) (xy 165.890194 -55.8165) (xy 165.890194 -52.8447) (xy 165.890194 -52.844192)
					(xy 163.604194 -52.844192) (xy 163.604194 -52.8447) (xy 163.604194 -52.9717) (xy 163.604194 -54.3941)
					(xy 163.705794 -54.3941) (xy 163.705794 -52.9717) (xy 165.788594 -52.9717) (xy 165.788594 -55.8165)
					(xy 163.705794 -55.8165) (xy 163.705794 -54.4195) (xy 163.604194 -54.4195) (xy 163.604194 -55.8165)
					(xy 163.604194 -55.9435) (xy 163.604194 -55.944008) (xy 165.890194 -55.944008)
				)
			)
		)
	)
	(footprint ""
		(layer "F.Cu")
		(at 278.374856 -48.753014 180)
		(property "Reference" "C330"
			(at 0 0 180)
			(layer "F.SilkS")
			(hide yes)
			(effects
				(font
					(size 1.27 1.27)
				)
			)
		)
		(property "Value" ""
			(at 0 0 180)
			(layer "F.Fab")
			(effects
				(font
					(size 1.27 1.27)
				)
			)
		)
		(duplicate_pad_numbers_are_jumpers no)
		(fp_line
			(start 0.7874 0.4064)
			(end -0.7874 0.4064)
			(stroke
				(width 0.1524)
				(type default)
			)
			(layer "F.SilkS")
		)
		(fp_line
			(start 0.7874 -0.4064)
			(end 0.7874 0.4064)
			(stroke
				(width 0.1524)
				(type default)
			)
			(layer "F.SilkS")
		)
		(fp_line
			(start -0.7874 0.4064)
			(end -0.7874 -0.4064)
			(stroke
				(width 0.1524)
				(type default)
			)
			(layer "F.SilkS")
		)
		(fp_line
			(start -0.7874 -0.4064)
			(end 0.7874 -0.4064)
			(stroke
				(width 0.1524)
				(type default)
			)
			(layer "F.SilkS")
		)
		(fp_line
			(start 0.67945 0.3048)
			(end 0.120396 0.3048)
			(stroke
				(width 0.1)
				(type default)
			)
			(layer "F.Fab")
		)
		(fp_line
			(start 0.67945 -0.3048)
			(end 0.67945 0.3048)
			(stroke
				(width 0.1)
				(type default)
			)
			(layer "F.Fab")
		)
		(fp_line
			(start 0.12065 -0.2794)
			(end 0.12065 -0.3048)
			(stroke
				(width 0.1)
				(type default)
			)
			(layer "F.Fab")
		)
		(fp_line
			(start 0.12065 -0.3048)
			(end 0.67945 -0.3048)
			(stroke
				(width 0.1)
				(type default)
			)
			(layer "F.Fab")
		)
		(fp_line
			(start 0.120396 0.3048)
			(end 0.120396 0.2794)
			(stroke
				(width 0.1)
				(type default)
			)
			(layer "F.Fab")
		)
		(fp_line
			(start 0.120396 0.2794)
			(end -0.12065 0.2794)
			(stroke
				(width 0.1)
				(type default)
			)
			(layer "F.Fab")
		)
		(fp_line
			(start -0.12065 0.3048)
			(end -0.67945 0.3048)
			(stroke
				(width 0.1)
				(type default)
			)
			(layer "F.Fab")
		)
		(fp_line
			(start -0.12065 0.2794)
			(end -0.12065 0.3048)
			(stroke
				(width 0.1)
				(type default)
			)
			(layer "F.Fab")
		)
		(fp_line
			(start -0.12065 -0.2794)
			(end 0.12065 -0.2794)
			(stroke
				(width 0.1)
				(type default)
			)
			(layer "F.Fab")
		)
		(fp_line
			(start -0.12065 -0.305054)
			(end -0.12065 -0.2794)
			(stroke
				(width 0.1)
				(type default)
			)
			(layer "F.Fab")
		)
		(fp_line
			(start -0.67945 0.3048)
			(end -0.67945 -0.305054)
			(stroke
				(width 0.1)
				(type default)
			)
			(layer "F.Fab")
		)
		(fp_line
			(start -0.67945 -0.305054)
			(end -0.12065 -0.305054)
			(stroke
				(width 0.1)
				(type default)
			)
			(layer "F.Fab")
		)
		(pad "1" smd circle
			(at -0.40005 0 180)
			(size 0 0)
			(layers "F.Cu" "F.Mask" "F.Paste")
			(net "P3V3_AUX")
		)
		(pad "2" smd circle
			(at 0.40005 0 180)
			(size 0 0)
			(layers "F.Cu" "F.Mask" "F.Paste")
			(net "GND")
		)
	)
	(footprint ""
		(layer "F.Cu")
		(at 222.690944 -98.36912 90)
		(property "Reference" "R859"
			(at 0 0 90)
			(layer "F.SilkS")
			(hide yes)
			(effects
				(font
					(size 1.27 1.27)
				)
			)
		)
		(property "Value" ""
			(at 0 0 90)
			(layer "F.Fab")
			(effects
				(font
					(size 1.27 1.27)
				)
			)
		)
		(duplicate_pad_numbers_are_jumpers no)
		(fp_line
			(start 0.7874 -0.4064)
			(end 0.7874 0.4064)
			(stroke
				(width 0.1524)
				(type default)
			)
			(layer "F.SilkS")
		)
		(fp_line
			(start -0.7874 -0.4064)
			(end 0.7874 -0.4064)
			(stroke
				(width 0.1524)
				(type default)
			)
			(layer "F.SilkS")
		)
		(fp_line
			(start 0.7874 0.4064)
			(end -0.7874 0.4064)
			(stroke
				(width 0.1524)
				(type default)
			)
			(layer "F.SilkS")
		)
		(fp_line
			(start -0.7874 0.4064)
			(end -0.7874 -0.4064)
			(stroke
				(width 0.1524)
				(type default)
			)
			(layer "F.SilkS")
		)
		(fp_line
			(start -0.12065 -0.305054)
			(end -0.12065 -0.2794)
			(stroke
				(width 0.1)
				(type default)
			)
			(layer "F.Fab")
		)
		(fp_line
			(start -0.67945 -0.305054)
			(end -0.12065 -0.305054)
			(stroke
				(width 0.1)
				(type default)
			)
			(layer "F.Fab")
		)
		(fp_line
			(start 0.67945 -0.3048)
			(end 0.67945 0.3048)
			(stroke
				(width 0.1)
				(type default)
			)
			(layer "F.Fab")
		)
		(fp_line
			(start 0.12065 -0.3048)
			(end 0.67945 -0.3048)
			(stroke
				(width 0.1)
				(type default)
			)
			(layer "F.Fab")
		)
		(fp_line
			(start 0.12065 -0.2794)
			(end 0.12065 -0.3048)
			(stroke
				(width 0.1)
				(type default)
			)
			(layer "F.Fab")
		)
		(fp_line
			(start -0.12065 -0.2794)
			(end 0.12065 -0.2794)
			(stroke
				(width 0.1)
				(type default)
			)
			(layer "F.Fab")
		)
		(fp_line
			(start 0.120396 0.2794)
			(end -0.12065 0.2794)
			(stroke
				(width 0.1)
				(type default)
			)
			(layer "F.Fab")
		)
		(fp_line
			(start -0.12065 0.2794)
			(end -0.12065 0.3048)
			(stroke
				(width 0.1)
				(type default)
			)
			(layer "F.Fab")
		)
		(fp_line
			(start 0.67945 0.3048)
			(end 0.120396 0.3048)
			(stroke
				(width 0.1)
				(type default)
			)
			(layer "F.Fab")
		)
		(fp_line
			(start 0.120396 0.3048)
			(end 0.120396 0.2794)
			(stroke
				(width 0.1)
				(type default)
			)
			(layer "F.Fab")
		)
		(fp_line
			(start -0.12065 0.3048)
			(end -0.67945 0.3048)
			(stroke
				(width 0.1)
				(type default)
			)
			(layer "F.Fab")
		)
		(fp_line
			(start -0.67945 0.3048)
			(end -0.67945 -0.305054)
			(stroke
				(width 0.1)
				(type default)
			)
			(layer "F.Fab")
		)
		(pad "1" smd circle
			(at -0.40005 0 90)
			(size 0 0)
			(layers "F.Cu" "F.Mask" "F.Paste")
			(net "P3V3_AUX")
		)
		(pad "2" smd circle
			(at 0.40005 0 90)
			(size 0 0)
			(layers "F.Cu" "F.Mask" "F.Paste")
			(net "PWRGD_P12V_NIC3")
		)
	)
	(footprint ""
		(layer "F.Cu")
		(at 248.421144 18.028412 180)
		(property "Reference" "DE01F_1"
			(at 2.472944 3.371342 0)
			(unlocked yes)
			(layer "F.SilkS")
			(effects
				(font
					(size 0.7874 0.5842)
					(thickness 0.1524)
				)
				(justify left)
			)
		)
		(property "Value" ""
			(at 0 0 180)
			(layer "F.Fab")
			(effects
				(font
					(size 1.27 1.27)
				)
			)
		)
		(duplicate_pad_numbers_are_jumpers no)
		(fp_line
			(start 1.2192 2.1082)
			(end -1.2192 2.1082)
			(stroke
				(width 0.1524)
				(type default)
			)
			(layer "F.SilkS")
		)
		(fp_line
			(start 1.2192 -2.1082)
			(end 1.2192 2.1082)
			(stroke
				(width 0.1524)
				(type default)
			)
			(layer "F.SilkS")
		)
		(fp_line
			(start -1.2192 2.1082)
			(end -1.2192 -2.1082)
			(stroke
				(width 0.1524)
				(type default)
			)
			(layer "F.SilkS")
		)
		(fp_line
			(start -1.2192 -2.1082)
			(end 1.2192 -2.1082)
			(stroke
				(width 0.1524)
				(type default)
			)
			(layer "F.SilkS")
		)
		(pad "" np_thru_hole circle
			(at -2.8829 -1.27 90)
			(size 1.0414 1.0414)
			(drill 1.0414)
			(layers "*.Cu" "*.Mask")
			(clearance 0.381)
			(thermal_gap 0.381)
		)
		(pad "" np_thru_hole circle
			(at -2.8829 1.27 90)
			(size 1.0414 1.0414)
			(drill 1.0414)
			(layers "*.Cu" "*.Mask")
			(clearance 0.381)
			(thermal_gap 0.381)
		)
		(pad "" np_thru_hole circle
			(at 3.4671 -1.27 90)
			(size 1.0414 1.0414)
			(drill 1.0414)
			(layers "*.Cu" "*.Mask")
			(clearance 0.381)
			(thermal_gap 0.381)
		)
		(pad "" np_thru_hole circle
			(at 3.4671 1.27 90)
			(size 1.0414 1.0414)
			(drill 1.0414)
			(layers "*.Cu" "*.Mask")
			(clearance 0.381)
			(thermal_gap 0.381)
		)
		(pad "1" smd rect
			(at 0.8255 -0.249936 90)
			(size 0.3048 0.508)
			(layers "F.Cu" "F.Mask" "F.Paste")
			(net "85_5INCH_TOP_DP")
		)
		(pad "2" smd rect
			(at 0.8255 0.249936 90)
			(size 0.3048 0.508)
			(layers "F.Cu" "F.Mask" "F.Paste")
			(net "85_5INCH_TOP_DN")
		)
		(pad "3" smd circle
			(at 0 0 180)
			(size 0 0)
			(layers "F.Cu" "F.Mask" "F.Paste")
			(net "COUPON_GND2")
		)
		(zone
			(layer "F.Cu")
			(hatch none 0.5)
			(connect_pads
				(clearance 0)
			)
			(min_thickness 0.25)
			(keepout
				(tracks not_allowed)
				(vias allowed)
				(pads allowed)
				(copperpour not_allowed)
				(footprints allowed)
			)
			(placement
				(enabled no)
				(sheetname "")
			)
			(fill
				(thermal_gap 0.5)
				(thermal_bridge_width 0.5)
				(island_removal_mode 0)
			)
			(polygon
				(pts
					(xy 247.303544 18.577052) (xy 247.303544 18.481548) (xy 247.900444 18.481548) (xy 247.900444 18.075148)
					(xy 247.303544 18.075148) (xy 247.303544 17.981676) (xy 247.900444 17.981676) (xy 247.900444 17.575276)
					(xy 247.303544 17.575276) (xy 247.303544 17.479772) (xy 248.002044 17.479772) (xy 248.002044 18.577052)
				)
			)
		)
		(zone
			(layers "F.Cu" "B.Cu" "In1.Cu" "In2.Cu" "In3.Cu" "In4.Cu" "In5.Cu" "In6.Cu"
				"In7.Cu" "In8.Cu" "In9.Cu" "In10.Cu" "In11.Cu" "In12.Cu" "In13.Cu" "In14.Cu"
				"In15.Cu" "In16.Cu"
			)
			(hatch none 0.5)
			(connect_pads
				(clearance 0)
			)
			(min_thickness 0.25)
			(keepout
				(tracks not_allowed)
				(vias allowed)
				(pads allowed)
				(copperpour not_allowed)
				(footprints allowed)
			)
			(placement
				(enabled no)
				(sheetname "")
			)
			(fill
				(thermal_gap 0.5)
				(thermal_bridge_width 0.5)
				(island_removal_mode 0)
			)
			(polygon
				(pts
					(arc
						(start 245.881144 16.758412)
						(mid 244.026944 16.758412)
						(end 245.881144 16.758412)
					)
				)
			)
		)
		(zone
			(layers "F.Cu" "B.Cu" "In1.Cu" "In2.Cu" "In3.Cu" "In4.Cu" "In5.Cu" "In6.Cu"
				"In7.Cu" "In8.Cu" "In9.Cu" "In10.Cu" "In11.Cu" "In12.Cu" "In13.Cu" "In14.Cu"
				"In15.Cu" "In16.Cu"
			)
			(hatch none 0.5)
			(connect_pads
				(clearance 0)
			)
			(min_thickness 0.25)
			(keepout
				(tracks not_allowed)
				(vias allowed)
				(pads allowed)
				(copperpour not_allowed)
				(footprints allowed)
			)
			(placement
				(enabled no)
				(sheetname "")
			)
			(fill
				(thermal_gap 0.5)
				(thermal_bridge_width 0.5)
				(island_removal_mode 0)
			)
			(polygon
				(pts
					(arc
						(start 245.881144 19.298412)
						(mid 244.026944 19.298412)
						(end 245.881144 19.298412)
					)
				)
			)
		)
		(zone
			(layers "F.Cu" "B.Cu" "In1.Cu" "In2.Cu" "In3.Cu" "In4.Cu" "In5.Cu" "In6.Cu"
				"In7.Cu" "In8.Cu" "In9.Cu" "In10.Cu" "In11.Cu" "In12.Cu" "In13.Cu" "In14.Cu"
				"In15.Cu" "In16.Cu"
			)
			(hatch none 0.5)
			(connect_pads
				(clearance 0)
			)
			(min_thickness 0.25)
			(keepout
				(tracks not_allowed)
				(vias allowed)
				(pads allowed)
				(copperpour not_allowed)
				(footprints allowed)
			)
			(placement
				(enabled no)
				(sheetname "")
			)
			(fill
				(thermal_gap 0.5)
				(thermal_bridge_width 0.5)
				(island_removal_mode 0)
			)
			(polygon
				(pts
					(arc
						(start 252.231144 16.758412)
						(mid 250.376944 16.758412)
						(end 252.231144 16.758412)
					)
				)
			)
		)
		(zone
			(layers "F.Cu" "B.Cu" "In1.Cu" "In2.Cu" "In3.Cu" "In4.Cu" "In5.Cu" "In6.Cu"
				"In7.Cu" "In8.Cu" "In9.Cu" "In10.Cu" "In11.Cu" "In12.Cu" "In13.Cu" "In14.Cu"
				"In15.Cu" "In16.Cu"
			)
			(hatch none 0.5)
			(connect_pads
				(clearance 0)
			)
			(min_thickness 0.25)
			(keepout
				(tracks not_allowed)
				(vias allowed)
				(pads allowed)
				(copperpour not_allowed)
				(footprints allowed)
			)
			(placement
				(enabled no)
				(sheetname "")
			)
			(fill
				(thermal_gap 0.5)
				(thermal_bridge_width 0.5)
				(island_removal_mode 0)
			)
			(polygon
				(pts
					(arc
						(start 252.231144 19.298412)
						(mid 250.376944 19.298412)
						(end 252.231144 19.298412)
					)
				)
			)
		)
	)
	(footprint ""
		(layer "F.Cu")
		(at 283.59862 -180.372766 180)
		(property "Reference" "R254"
			(at 0 0 180)
			(layer "F.SilkS")
			(hide yes)
			(effects
				(font
					(size 1.27 1.27)
				)
			)
		)
		(property "Value" ""
			(at 0 0 180)
			(layer "F.Fab")
			(effects
				(font
					(size 1.27 1.27)
				)
			)
		)
		(duplicate_pad_numbers_are_jumpers no)
		(fp_line
			(start 0.7874 0.4064)
			(end -0.7874 0.4064)
			(stroke
				(width 0.1524)
				(type default)
			)
			(layer "F.SilkS")
		)
		(fp_line
			(start 0.7874 -0.4064)
			(end 0.7874 0.4064)
			(stroke
				(width 0.1524)
				(type default)
			)
			(layer "F.SilkS")
		)
		(fp_line
			(start -0.7874 0.4064)
			(end -0.7874 -0.4064)
			(stroke
				(width 0.1524)
				(type default)
			)
			(layer "F.SilkS")
		)
		(fp_line
			(start -0.7874 -0.4064)
			(end 0.7874 -0.4064)
			(stroke
				(width 0.1524)
				(type default)
			)
			(layer "F.SilkS")
		)
		(fp_line
			(start 0.67945 0.3048)
			(end 0.120396 0.3048)
			(stroke
				(width 0.1)
				(type default)
			)
			(layer "F.Fab")
		)
		(fp_line
			(start 0.67945 -0.3048)
			(end 0.67945 0.3048)
			(stroke
				(width 0.1)
				(type default)
			)
			(layer "F.Fab")
		)
		(fp_line
			(start 0.12065 -0.2794)
			(end 0.12065 -0.3048)
			(stroke
				(width 0.1)
				(type default)
			)
			(layer "F.Fab")
		)
		(fp_line
			(start 0.12065 -0.3048)
			(end 0.67945 -0.3048)
			(stroke
				(width 0.1)
				(type default)
			)
			(layer "F.Fab")
		)
		(fp_line
			(start 0.120396 0.3048)
			(end 0.120396 0.2794)
			(stroke
				(width 0.1)
				(type default)
			)
			(layer "F.Fab")
		)
		(fp_line
			(start 0.120396 0.2794)
			(end -0.12065 0.2794)
			(stroke
				(width 0.1)
				(type default)
			)
			(layer "F.Fab")
		)
		(fp_line
			(start -0.12065 0.3048)
			(end -0.67945 0.3048)
			(stroke
				(width 0.1)
				(type default)
			)
			(layer "F.Fab")
		)
		(fp_line
			(start -0.12065 0.2794)
			(end -0.12065 0.3048)
			(stroke
				(width 0.1)
				(type default)
			)
			(layer "F.Fab")
		)
		(fp_line
			(start -0.12065 -0.2794)
			(end 0.12065 -0.2794)
			(stroke
				(width 0.1)
				(type default)
			)
			(layer "F.Fab")
		)
		(fp_line
			(start -0.12065 -0.305054)
			(end -0.12065 -0.2794)
			(stroke
				(width 0.1)
				(type default)
			)
			(layer "F.Fab")
		)
		(fp_line
			(start -0.67945 0.3048)
			(end -0.67945 -0.305054)
			(stroke
				(width 0.1)
				(type default)
			)
			(layer "F.Fab")
		)
		(fp_line
			(start -0.67945 -0.305054)
			(end -0.12065 -0.305054)
			(stroke
				(width 0.1)
				(type default)
			)
			(layer "F.Fab")
		)
		(pad "1" smd circle
			(at -0.40005 0 180)
			(size 0 0)
			(layers "F.Cu" "F.Mask" "F.Paste")
			(net "P3V3_AUX")
		)
		(pad "2" smd circle
			(at 0.40005 0 180)
			(size 0 0)
			(layers "F.Cu" "F.Mask" "F.Paste")
			(net "HP_NIC4_HSC_PWRGD_N")
		)
	)
	(footprint ""
		(layer "F.Cu")
		(at 292.743382 -350.098614 90)
		(property "Reference" "C589"
			(at 0 0 90)
			(layer "F.SilkS")
			(hide yes)
			(effects
				(font
					(size 1.27 1.27)
				)
			)
		)
		(property "Value" ""
			(at 0 0 90)
			(layer "F.Fab")
			(effects
				(font
					(size 1.27 1.27)
				)
			)
		)
		(duplicate_pad_numbers_are_jumpers no)
		(fp_line
			(start 0.299974 -0.150114)
			(end 0.299974 0.150114)
			(stroke
				(width 0.1)
				(type default)
			)
			(layer "F.Fab")
		)
		(fp_line
			(start -0.299974 -0.150114)
			(end 0.299974 -0.150114)
			(stroke
				(width 0.1)
				(type default)
			)
			(layer "F.Fab")
		)
		(fp_line
			(start 0.299974 0.150114)
			(end -0.299974 0.150114)
			(stroke
				(width 0.1)
				(type default)
			)
			(layer "F.Fab")
		)
		(fp_line
			(start -0.299974 0.150114)
			(end -0.299974 -0.150114)
			(stroke
				(width 0.1)
				(type default)
			)
			(layer "F.Fab")
		)
		(pad "1" smd rect
			(at -0.2667 0 90)
			(size 0.3048 0.381)
			(layers "F.Cu" "F.Mask" "F.Paste")
			(net "P5E_PEX2_STN7_TX_DP<124>")
		)
		(pad "2" smd rect
			(at 0.2667 0 90)
			(size 0.3048 0.381)
			(layers "F.Cu" "F.Mask" "F.Paste")
			(net "P5E_PEX2_STN7_TX_C_DP<124>")
		)
	)
	(footprint ""
		(layer "F.Cu")
		(at 123.415044 -20.72513)
		(property "Reference" "H102"
			(at -2.337054 -1.98628 0)
			(unlocked yes)
			(layer "B.SilkS")
			(effects
				(font
					(size 0.7874 0.5842)
					(thickness 0.1524)
				)
				(justify left mirror)
			)
		)
		(property "Value" ""
			(at 0 0 0)
			(layer "F.Fab")
			(effects
				(font
					(size 1.27 1.27)
				)
			)
		)
		(duplicate_pad_numbers_are_jumpers no)
		(pad "1" thru_hole rect
			(at 0 0)
			(size 4.2164 5.0038)
			(drill 2.0066
				(offset 0.099822 0)
			)
			(layers "*.Cu" "*.Mask")
			(remove_unused_layers no)
			(net "Net_8561")
			(clearance -0.8509)
			(padstack
				(mode front_inner_back)
				(layer "Inner"
					(shape circle)
					(size 4.0132 4.0132)
					(clearance -0.7493)
				)
				(layer "B.Cu"
					(shape circle)
					(size 4.0132 4.0132)
					(clearance -0.7493)
				)
			)
		)
	)
	(footprint ""
		(layer "F.Cu")
		(at 299.40123 -55.78475 -90)
		(property "Reference" "PD114"
			(at 4.01955 2.21996 90)
			(unlocked yes)
			(layer "F.SilkS")
			(effects
				(font
					(size 0.7874 0.5842)
					(thickness 0.1524)
				)
				(justify left)
			)
		)
		(property "Value" ""
			(at 0 0 270)
			(layer "F.Fab")
			(effects
				(font
					(size 1.27 1.27)
				)
			)
		)
		(duplicate_pad_numbers_are_jumpers no)
		(fp_line
			(start -3.400044 1.459992)
			(end -3.400044 -1.459992)
			(stroke
				(width 0.1524)
				(type default)
			)
			(layer "F.SilkS")
		)
		(fp_line
			(start 4.107942 1.459992)
			(end -3.400044 1.459992)
			(stroke
				(width 0.1524)
				(type default)
			)
			(layer "F.SilkS")
		)
		(fp_line
			(start -3.400044 -1.459992)
			(end 4.107942 -1.459992)
			(stroke
				(width 0.1524)
				(type default)
			)
			(layer "F.SilkS")
		)
		(fp_line
			(start 4.107942 -1.459992)
			(end 4.107942 1.459992)
			(stroke
				(width 0.1524)
				(type default)
			)
			(layer "F.SilkS")
		)
		(fp_poly
			(pts
				(xy 4.107942 -1.459992) (xy 4.107942 1.459992) (xy 3.308096 1.459992) (xy 3.308096 -1.459992)
			)
			(stroke
				(width 0)
				(type default)
			)
			(fill yes)
			(layer "F.SilkS")
		)
		(fp_line
			(start -2.29997 1.459992)
			(end -2.29997 -1.459992)
			(stroke
				(width 0.1)
				(type default)
			)
			(layer "F.Fab")
		)
		(fp_line
			(start 2.29997 1.459992)
			(end -2.29997 1.459992)
			(stroke
				(width 0.1)
				(type default)
			)
			(layer "F.Fab")
		)
		(fp_line
			(start -2.29997 -1.459992)
			(end 2.29997 -1.459992)
			(stroke
				(width 0.1)
				(type default)
			)
			(layer "F.Fab")
		)
		(fp_line
			(start 2.29997 -1.459992)
			(end 2.29997 1.459992)
			(stroke
				(width 0.1)
				(type default)
			)
			(layer "F.Fab")
		)
		(fp_text user "-"
			(at 5.4102 0.29845 90)
			(unlocked yes)
			(layer "F.SilkS")
			(effects
				(font
					(size 1.905 1.4224)
					(thickness 0.1524)
				)
				(justify left)
			)
		)
		(fp_text user "+"
			(at -4.7752 -0.12065 270)
			(unlocked yes)
			(layer "F.SilkS")
			(effects
				(font
					(size 1.905 1.4224)
					(thickness 0.1524)
				)
				(justify left)
			)
		)
		(fp_text user "-"
			(at 5.4102 0.29845 90)
			(unlocked yes)
			(layer "F.Fab")
			(effects
				(font
					(size 1.905 1.4224)
					(thickness 0.1524)
				)
				(justify left)
			)
		)
		(fp_text user "+"
			(at -4.7752 -0.12065 270)
			(unlocked yes)
			(layer "F.Fab")
			(effects
				(font
					(size 1.905 1.4224)
					(thickness 0.1524)
				)
				(justify left)
			)
		)
		(pad "A" smd rect
			(at -1.999996 0)
			(size 1.7018 2.5146)
			(layers "F.Cu" "F.Mask" "F.Paste")
			(net "GND")
		)
		(pad "C" smd rect
			(at 1.999996 0)
			(size 1.7018 2.5146)
			(layers "F.Cu" "F.Mask" "F.Paste")
			(net "P12V_SSD10_R")
		)
	)
	(footprint ""
		(layer "F.Cu")
		(at 344.327988 -35.876738)
		(property "Reference" "R6106"
			(at 0 0 0)
			(layer "F.SilkS")
			(hide yes)
			(effects
				(font
					(size 1.27 1.27)
				)
			)
		)
		(property "Value" ""
			(at 0 0 0)
			(layer "F.Fab")
			(effects
				(font
					(size 1.27 1.27)
				)
			)
		)
		(duplicate_pad_numbers_are_jumpers no)
		(fp_line
			(start -0.7874 -0.4064)
			(end 0.7874 -0.4064)
			(stroke
				(width 0.1524)
				(type default)
			)
			(layer "F.SilkS")
		)
		(fp_line
			(start -0.7874 0.4064)
			(end -0.7874 -0.4064)
			(stroke
				(width 0.1524)
				(type default)
			)
			(layer "F.SilkS")
		)
		(fp_line
			(start 0.7874 -0.4064)
			(end 0.7874 0.4064)
			(stroke
				(width 0.1524)
				(type default)
			)
			(layer "F.SilkS")
		)
		(fp_line
			(start 0.7874 0.4064)
			(end -0.7874 0.4064)
			(stroke
				(width 0.1524)
				(type default)
			)
			(layer "F.SilkS")
		)
		(fp_line
			(start -0.67945 -0.305054)
			(end -0.12065 -0.305054)
			(stroke
				(width 0.1)
				(type default)
			)
			(layer "F.Fab")
		)
		(fp_line
			(start -0.67945 0.3048)
			(end -0.67945 -0.305054)
			(stroke
				(width 0.1)
				(type default)
			)
			(layer "F.Fab")
		)
		(fp_line
			(start -0.12065 -0.305054)
			(end -0.12065 -0.2794)
			(stroke
				(width 0.1)
				(type default)
			)
			(layer "F.Fab")
		)
		(fp_line
			(start -0.12065 -0.2794)
			(end 0.12065 -0.2794)
			(stroke
				(width 0.1)
				(type default)
			)
			(layer "F.Fab")
		)
		(fp_line
			(start -0.12065 0.2794)
			(end -0.12065 0.3048)
			(stroke
				(width 0.1)
				(type default)
			)
			(layer "F.Fab")
		)
		(fp_line
			(start -0.12065 0.3048)
			(end -0.67945 0.3048)
			(stroke
				(width 0.1)
				(type default)
			)
			(layer "F.Fab")
		)
		(fp_line
			(start 0.120396 0.2794)
			(end -0.12065 0.2794)
			(stroke
				(width 0.1)
				(type default)
			)
			(layer "F.Fab")
		)
		(fp_line
			(start 0.120396 0.3048)
			(end 0.120396 0.2794)
			(stroke
				(width 0.1)
				(type default)
			)
			(layer "F.Fab")
		)
		(fp_line
			(start 0.12065 -0.3048)
			(end 0.67945 -0.3048)
			(stroke
				(width 0.1)
				(type default)
			)
			(layer "F.Fab")
		)
		(fp_line
			(start 0.12065 -0.2794)
			(end 0.12065 -0.3048)
			(stroke
				(width 0.1)
				(type default)
			)
			(layer "F.Fab")
		)
		(fp_line
			(start 0.67945 -0.3048)
			(end 0.67945 0.3048)
			(stroke
				(width 0.1)
				(type default)
			)
			(layer "F.Fab")
		)
		(fp_line
			(start 0.67945 0.3048)
			(end 0.120396 0.3048)
			(stroke
				(width 0.1)
				(type default)
			)
			(layer "F.Fab")
		)
		(pad "1" smd circle
			(at -0.40005 0)
			(size 0 0)
			(layers "F.Cu" "F.Mask" "F.Paste")
			(net "PWRGD_P3V3_SSD12_D")
		)
		(pad "2" smd circle
			(at 0.40005 0)
			(size 0 0)
			(layers "F.Cu" "F.Mask" "F.Paste")
			(net "PWRGD_P3V3_SSD12_R")
		)
	)
	(footprint ""
		(layer "F.Cu")
		(at 201.203306 -59.571636 90)
		(property "Reference" "PR269"
			(at 0 0 90)
			(layer "F.SilkS")
			(hide yes)
			(effects
				(font
					(size 1.27 1.27)
				)
			)
		)
		(property "Value" ""
			(at 0 0 90)
			(layer "F.Fab")
			(effects
				(font
					(size 1.27 1.27)
				)
			)
		)
		(duplicate_pad_numbers_are_jumpers no)
		(fp_line
			(start 0.7874 -0.4064)
			(end 0.7874 0.4064)
			(stroke
				(width 0.1524)
				(type default)
			)
			(layer "F.SilkS")
		)
		(fp_line
			(start -0.7874 -0.4064)
			(end 0.7874 -0.4064)
			(stroke
				(width 0.1524)
				(type default)
			)
			(layer "F.SilkS")
		)
		(fp_line
			(start 0.7874 0.4064)
			(end -0.7874 0.4064)
			(stroke
				(width 0.1524)
				(type default)
			)
			(layer "F.SilkS")
		)
		(fp_line
			(start -0.7874 0.4064)
			(end -0.7874 -0.4064)
			(stroke
				(width 0.1524)
				(type default)
			)
			(layer "F.SilkS")
		)
		(fp_line
			(start -0.12065 -0.305054)
			(end -0.12065 -0.2794)
			(stroke
				(width 0.1)
				(type default)
			)
			(layer "F.Fab")
		)
		(fp_line
			(start -0.67945 -0.305054)
			(end -0.12065 -0.305054)
			(stroke
				(width 0.1)
				(type default)
			)
			(layer "F.Fab")
		)
		(fp_line
			(start 0.67945 -0.3048)
			(end 0.67945 0.3048)
			(stroke
				(width 0.1)
				(type default)
			)
			(layer "F.Fab")
		)
		(fp_line
			(start 0.12065 -0.3048)
			(end 0.67945 -0.3048)
			(stroke
				(width 0.1)
				(type default)
			)
			(layer "F.Fab")
		)
		(fp_line
			(start 0.12065 -0.2794)
			(end 0.12065 -0.3048)
			(stroke
				(width 0.1)
				(type default)
			)
			(layer "F.Fab")
		)
		(fp_line
			(start -0.12065 -0.2794)
			(end 0.12065 -0.2794)
			(stroke
				(width 0.1)
				(type default)
			)
			(layer "F.Fab")
		)
		(fp_line
			(start 0.120396 0.2794)
			(end -0.12065 0.2794)
			(stroke
				(width 0.1)
				(type default)
			)
			(layer "F.Fab")
		)
		(fp_line
			(start -0.12065 0.2794)
			(end -0.12065 0.3048)
			(stroke
				(width 0.1)
				(type default)
			)
			(layer "F.Fab")
		)
		(fp_line
			(start 0.67945 0.3048)
			(end 0.120396 0.3048)
			(stroke
				(width 0.1)
				(type default)
			)
			(layer "F.Fab")
		)
		(fp_line
			(start 0.120396 0.3048)
			(end 0.120396 0.2794)
			(stroke
				(width 0.1)
				(type default)
			)
			(layer "F.Fab")
		)
		(fp_line
			(start -0.12065 0.3048)
			(end -0.67945 0.3048)
			(stroke
				(width 0.1)
				(type default)
			)
			(layer "F.Fab")
		)
		(fp_line
			(start -0.67945 0.3048)
			(end -0.67945 -0.305054)
			(stroke
				(width 0.1)
				(type default)
			)
			(layer "F.Fab")
		)
		(pad "1" smd circle
			(at -0.40005 0 90)
			(size 0 0)
			(layers "F.Cu" "F.Mask" "F.Paste")
			(net "P3V3_SSD7_OCP")
		)
		(pad "2" smd circle
			(at 0.40005 0 90)
			(size 0 0)
			(layers "F.Cu" "F.Mask" "F.Paste")
			(net "GND")
		)
	)
	(footprint ""
		(layer "F.Cu")
		(at 20.174966 -48.753014 180)
		(property "Reference" "C201"
			(at 0 0 180)
			(layer "F.SilkS")
			(hide yes)
			(effects
				(font
					(size 1.27 1.27)
				)
			)
		)
		(property "Value" ""
			(at 0 0 180)
			(layer "F.Fab")
			(effects
				(font
					(size 1.27 1.27)
				)
			)
		)
		(duplicate_pad_numbers_are_jumpers no)
		(fp_line
			(start 0.7874 0.4064)
			(end -0.7874 0.4064)
			(stroke
				(width 0.1524)
				(type default)
			)
			(layer "F.SilkS")
		)
		(fp_line
			(start 0.7874 -0.4064)
			(end 0.7874 0.4064)
			(stroke
				(width 0.1524)
				(type default)
			)
			(layer "F.SilkS")
		)
		(fp_line
			(start -0.7874 0.4064)
			(end -0.7874 -0.4064)
			(stroke
				(width 0.1524)
				(type default)
			)
			(layer "F.SilkS")
		)
		(fp_line
			(start -0.7874 -0.4064)
			(end 0.7874 -0.4064)
			(stroke
				(width 0.1524)
				(type default)
			)
			(layer "F.SilkS")
		)
		(fp_line
			(start 0.67945 0.3048)
			(end 0.120396 0.3048)
			(stroke
				(width 0.1)
				(type default)
			)
			(layer "F.Fab")
		)
		(fp_line
			(start 0.67945 -0.3048)
			(end 0.67945 0.3048)
			(stroke
				(width 0.1)
				(type default)
			)
			(layer "F.Fab")
		)
		(fp_line
			(start 0.12065 -0.2794)
			(end 0.12065 -0.3048)
			(stroke
				(width 0.1)
				(type default)
			)
			(layer "F.Fab")
		)
		(fp_line
			(start 0.12065 -0.3048)
			(end 0.67945 -0.3048)
			(stroke
				(width 0.1)
				(type default)
			)
			(layer "F.Fab")
		)
		(fp_line
			(start 0.120396 0.3048)
			(end 0.120396 0.2794)
			(stroke
				(width 0.1)
				(type default)
			)
			(layer "F.Fab")
		)
		(fp_line
			(start 0.120396 0.2794)
			(end -0.12065 0.2794)
			(stroke
				(width 0.1)
				(type default)
			)
			(layer "F.Fab")
		)
		(fp_line
			(start -0.12065 0.3048)
			(end -0.67945 0.3048)
			(stroke
				(width 0.1)
				(type default)
			)
			(layer "F.Fab")
		)
		(fp_line
			(start -0.12065 0.2794)
			(end -0.12065 0.3048)
			(stroke
				(width 0.1)
				(type default)
			)
			(layer "F.Fab")
		)
		(fp_line
			(start -0.12065 -0.2794)
			(end 0.12065 -0.2794)
			(stroke
				(width 0.1)
				(type default)
			)
			(layer "F.Fab")
		)
		(fp_line
			(start -0.12065 -0.305054)
			(end -0.12065 -0.2794)
			(stroke
				(width 0.1)
				(type default)
			)
			(layer "F.Fab")
		)
		(fp_line
			(start -0.67945 0.3048)
			(end -0.67945 -0.305054)
			(stroke
				(width 0.1)
				(type default)
			)
			(layer "F.Fab")
		)
		(fp_line
			(start -0.67945 -0.305054)
			(end -0.12065 -0.305054)
			(stroke
				(width 0.1)
				(type default)
			)
			(layer "F.Fab")
		)
		(pad "1" smd circle
			(at -0.40005 0 180)
			(size 0 0)
			(layers "F.Cu" "F.Mask" "F.Paste")
			(net "P3V3_AUX")
		)
		(pad "2" smd circle
			(at 0.40005 0 180)
			(size 0 0)
			(layers "F.Cu" "F.Mask" "F.Paste")
			(net "GND")
		)
	)
	(footprint ""
		(layer "F.Cu")
		(at 387.580632 -107.403138)
		(property "Reference" "C689"
			(at 0 0 0)
			(layer "F.SilkS")
			(hide yes)
			(effects
				(font
					(size 1.27 1.27)
				)
			)
		)
		(property "Value" ""
			(at 0 0 0)
			(layer "F.Fab")
			(effects
				(font
					(size 1.27 1.27)
				)
			)
		)
		(duplicate_pad_numbers_are_jumpers no)
		(fp_line
			(start -0.299974 -0.150114)
			(end 0.299974 -0.150114)
			(stroke
				(width 0.1)
				(type default)
			)
			(layer "F.Fab")
		)
		(fp_line
			(start -0.299974 0.150114)
			(end -0.299974 -0.150114)
			(stroke
				(width 0.1)
				(type default)
			)
			(layer "F.Fab")
		)
		(fp_line
			(start 0.299974 -0.150114)
			(end 0.299974 0.150114)
			(stroke
				(width 0.1)
				(type default)
			)
			(layer "F.Fab")
		)
		(fp_line
			(start 0.299974 0.150114)
			(end -0.299974 0.150114)
			(stroke
				(width 0.1)
				(type default)
			)
			(layer "F.Fab")
		)
		(pad "1" smd rect
			(at -0.2667 0)
			(size 0.3048 0.381)
			(layers "F.Cu" "F.Mask" "F.Paste")
			(net "P5E_PEX3_STN1_TX_DN<20>")
		)
		(pad "2" smd rect
			(at 0.2667 0)
			(size 0.3048 0.381)
			(layers "F.Cu" "F.Mask" "F.Paste")
			(net "P5E_PEX3_STN1_TX_C_DN<20>")
		)
	)
	(footprint ""
		(layer "F.Cu")
		(at 322.22821 -300.64202 -90)
		(property "Reference" "R3970"
			(at 0 0 270)
			(layer "F.SilkS")
			(hide yes)
			(effects
				(font
					(size 1.27 1.27)
				)
			)
		)
		(property "Value" ""
			(at 0 0 270)
			(layer "F.Fab")
			(effects
				(font
					(size 1.27 1.27)
				)
			)
		)
		(duplicate_pad_numbers_are_jumpers no)
		(fp_line
			(start -0.7874 0.4064)
			(end -0.7874 -0.4064)
			(stroke
				(width 0.1524)
				(type default)
			)
			(layer "F.SilkS")
		)
		(fp_line
			(start 0.7874 0.4064)
			(end -0.7874 0.4064)
			(stroke
				(width 0.1524)
				(type default)
			)
			(layer "F.SilkS")
		)
		(fp_line
			(start -0.7874 -0.4064)
			(end 0.7874 -0.4064)
			(stroke
				(width 0.1524)
				(type default)
			)
			(layer "F.SilkS")
		)
		(fp_line
			(start 0.7874 -0.4064)
			(end 0.7874 0.4064)
			(stroke
				(width 0.1524)
				(type default)
			)
			(layer "F.SilkS")
		)
		(fp_line
			(start -0.67945 0.3048)
			(end -0.67945 -0.305054)
			(stroke
				(width 0.1)
				(type default)
			)
			(layer "F.Fab")
		)
		(fp_line
			(start -0.12065 0.3048)
			(end -0.67945 0.3048)
			(stroke
				(width 0.1)
				(type default)
			)
			(layer "F.Fab")
		)
		(fp_line
			(start 0.120396 0.3048)
			(end 0.120396 0.2794)
			(stroke
				(width 0.1)
				(type default)
			)
			(layer "F.Fab")
		)
		(fp_line
			(start 0.67945 0.3048)
			(end 0.120396 0.3048)
			(stroke
				(width 0.1)
				(type default)
			)
			(layer "F.Fab")
		)
		(fp_line
			(start -0.12065 0.2794)
			(end -0.12065 0.3048)
			(stroke
				(width 0.1)
				(type default)
			)
			(layer "F.Fab")
		)
		(fp_line
			(start 0.120396 0.2794)
			(end -0.12065 0.2794)
			(stroke
				(width 0.1)
				(type default)
			)
			(layer "F.Fab")
		)
		(fp_line
			(start -0.12065 -0.2794)
			(end 0.12065 -0.2794)
			(stroke
				(width 0.1)
				(type default)
			)
			(layer "F.Fab")
		)
		(fp_line
			(start 0.12065 -0.2794)
			(end 0.12065 -0.3048)
			(stroke
				(width 0.1)
				(type default)
			)
			(layer "F.Fab")
		)
		(fp_line
			(start 0.12065 -0.3048)
			(end 0.67945 -0.3048)
			(stroke
				(width 0.1)
				(type default)
			)
			(layer "F.Fab")
		)
		(fp_line
			(start 0.67945 -0.3048)
			(end 0.67945 0.3048)
			(stroke
				(width 0.1)
				(type default)
			)
			(layer "F.Fab")
		)
		(fp_line
			(start -0.67945 -0.305054)
			(end -0.12065 -0.305054)
			(stroke
				(width 0.1)
				(type default)
			)
			(layer "F.Fab")
		)
		(fp_line
			(start -0.12065 -0.305054)
			(end -0.12065 -0.2794)
			(stroke
				(width 0.1)
				(type default)
			)
			(layer "F.Fab")
		)
		(pad "1" smd circle
			(at -0.40005 0 270)
			(size 0 0)
			(layers "F.Cu" "F.Mask" "F.Paste")
			(net "I2C0_PEX2_SDA")
		)
		(pad "2" smd circle
			(at 0.40005 0 270)
			(size 0 0)
			(layers "F.Cu" "F.Mask" "F.Paste")
			(net "I2C_PEX2_HOST_SDA")
		)
	)
	(footprint ""
		(layer "F.Cu")
		(at 363.442758 -70.844918 -90)
		(property "Reference" "PD118"
			(at 4.093718 2.101088 90)
			(unlocked yes)
			(layer "F.SilkS")
			(effects
				(font
					(size 0.7874 0.5842)
					(thickness 0.1524)
				)
				(justify left)
			)
		)
		(property "Value" ""
			(at 0 0 270)
			(layer "F.Fab")
			(effects
				(font
					(size 1.27 1.27)
				)
			)
		)
		(duplicate_pad_numbers_are_jumpers no)
		(fp_line
			(start -3.400044 1.459992)
			(end -3.400044 -1.459992)
			(stroke
				(width 0.1524)
				(type default)
			)
			(layer "F.SilkS")
		)
		(fp_line
			(start 4.107942 1.459992)
			(end -3.400044 1.459992)
			(stroke
				(width 0.1524)
				(type default)
			)
			(layer "F.SilkS")
		)
		(fp_line
			(start -3.400044 -1.459992)
			(end 4.107942 -1.459992)
			(stroke
				(width 0.1524)
				(type default)
			)
			(layer "F.SilkS")
		)
		(fp_line
			(start 4.107942 -1.459992)
			(end 4.107942 1.459992)
			(stroke
				(width 0.1524)
				(type default)
			)
			(layer "F.SilkS")
		)
		(fp_poly
			(pts
				(xy 4.107942 -1.459992) (xy 4.107942 1.459992) (xy 3.308096 1.459992) (xy 3.308096 -1.459992)
			)
			(stroke
				(width 0)
				(type default)
			)
			(fill yes)
			(layer "F.SilkS")
		)
		(fp_line
			(start -2.29997 1.459992)
			(end -2.29997 -1.459992)
			(stroke
				(width 0.1)
				(type default)
			)
			(layer "F.Fab")
		)
		(fp_line
			(start 2.29997 1.459992)
			(end -2.29997 1.459992)
			(stroke
				(width 0.1)
				(type default)
			)
			(layer "F.Fab")
		)
		(fp_line
			(start -2.29997 -1.459992)
			(end 2.29997 -1.459992)
			(stroke
				(width 0.1)
				(type default)
			)
			(layer "F.Fab")
		)
		(fp_line
			(start 2.29997 -1.459992)
			(end 2.29997 1.459992)
			(stroke
				(width 0.1)
				(type default)
			)
			(layer "F.Fab")
		)
		(fp_text user "-"
			(at 5.4102 0.29845 90)
			(unlocked yes)
			(layer "F.SilkS")
			(effects
				(font
					(size 1.905 1.4224)
					(thickness 0.1524)
				)
				(justify left)
			)
		)
		(fp_text user "+"
			(at -5.16636 -0.171958 270)
			(unlocked yes)
			(layer "F.SilkS")
			(effects
				(font
					(size 1.905 1.4224)
					(thickness 0.1524)
				)
				(justify left)
			)
		)
		(fp_text user "-"
			(at 5.4102 0.29845 90)
			(unlocked yes)
			(layer "F.Fab")
			(effects
				(font
					(size 1.905 1.4224)
					(thickness 0.1524)
				)
				(justify left)
			)
		)
		(fp_text user "+"
			(at -4.7752 -0.12065 270)
			(unlocked yes)
			(layer "F.Fab")
			(effects
				(font
					(size 1.905 1.4224)
					(thickness 0.1524)
				)
				(justify left)
			)
		)
		(pad "A" smd rect
			(at -1.999996 0)
			(size 1.7018 2.5146)
			(layers "F.Cu" "F.Mask" "F.Paste")
			(net "GND")
		)
		(pad "C" smd rect
			(at 1.999996 0)
			(size 1.7018 2.5146)
			(layers "F.Cu" "F.Mask" "F.Paste")
			(net "P12V_SSD12_R")
		)
	)
	(footprint ""
		(layer "F.Cu")
		(at 132.019802 -200.08342 90)
		(property "Reference" "C4495"
			(at 0 0 90)
			(layer "F.SilkS")
			(hide yes)
			(effects
				(font
					(size 1.27 1.27)
				)
			)
		)
		(property "Value" ""
			(at 0 0 90)
			(layer "F.Fab")
			(effects
				(font
					(size 1.27 1.27)
				)
			)
		)
		(duplicate_pad_numbers_are_jumpers no)
		(fp_line
			(start 0.7874 -0.4064)
			(end 0.7874 0.4064)
			(stroke
				(width 0.1524)
				(type default)
			)
			(layer "F.SilkS")
		)
		(fp_line
			(start -0.7874 -0.4064)
			(end 0.7874 -0.4064)
			(stroke
				(width 0.1524)
				(type default)
			)
			(layer "F.SilkS")
		)
		(fp_line
			(start 0.7874 0.4064)
			(end -0.7874 0.4064)
			(stroke
				(width 0.1524)
				(type default)
			)
			(layer "F.SilkS")
		)
		(fp_line
			(start -0.7874 0.4064)
			(end -0.7874 -0.4064)
			(stroke
				(width 0.1524)
				(type default)
			)
			(layer "F.SilkS")
		)
		(fp_line
			(start -0.12065 -0.305054)
			(end -0.12065 -0.2794)
			(stroke
				(width 0.1)
				(type default)
			)
			(layer "F.Fab")
		)
		(fp_line
			(start -0.67945 -0.305054)
			(end -0.12065 -0.305054)
			(stroke
				(width 0.1)
				(type default)
			)
			(layer "F.Fab")
		)
		(fp_line
			(start 0.67945 -0.3048)
			(end 0.67945 0.3048)
			(stroke
				(width 0.1)
				(type default)
			)
			(layer "F.Fab")
		)
		(fp_line
			(start 0.12065 -0.3048)
			(end 0.67945 -0.3048)
			(stroke
				(width 0.1)
				(type default)
			)
			(layer "F.Fab")
		)
		(fp_line
			(start 0.12065 -0.2794)
			(end 0.12065 -0.3048)
			(stroke
				(width 0.1)
				(type default)
			)
			(layer "F.Fab")
		)
		(fp_line
			(start -0.12065 -0.2794)
			(end 0.12065 -0.2794)
			(stroke
				(width 0.1)
				(type default)
			)
			(layer "F.Fab")
		)
		(fp_line
			(start 0.120396 0.2794)
			(end -0.12065 0.2794)
			(stroke
				(width 0.1)
				(type default)
			)
			(layer "F.Fab")
		)
		(fp_line
			(start -0.12065 0.2794)
			(end -0.12065 0.3048)
			(stroke
				(width 0.1)
				(type default)
			)
			(layer "F.Fab")
		)
		(fp_line
			(start 0.67945 0.3048)
			(end 0.120396 0.3048)
			(stroke
				(width 0.1)
				(type default)
			)
			(layer "F.Fab")
		)
		(fp_line
			(start 0.120396 0.3048)
			(end 0.120396 0.2794)
			(stroke
				(width 0.1)
				(type default)
			)
			(layer "F.Fab")
		)
		(fp_line
			(start -0.12065 0.3048)
			(end -0.67945 0.3048)
			(stroke
				(width 0.1)
				(type default)
			)
			(layer "F.Fab")
		)
		(fp_line
			(start -0.67945 0.3048)
			(end -0.67945 -0.305054)
			(stroke
				(width 0.1)
				(type default)
			)
			(layer "F.Fab")
		)
		(pad "1" smd circle
			(at -0.40005 0 90)
			(size 0 0)
			(layers "F.Cu" "F.Mask" "F.Paste")
			(net "NIC6_CLK_EN_R_N")
		)
		(pad "2" smd circle
			(at 0.40005 0 90)
			(size 0 0)
			(layers "F.Cu" "F.Mask" "F.Paste")
			(net "GND")
		)
	)
	(footprint ""
		(layer "F.Cu")
		(at 286.525462 -350.098614 90)
		(property "Reference" "C596"
			(at 0 0 90)
			(layer "F.SilkS")
			(hide yes)
			(effects
				(font
					(size 1.27 1.27)
				)
			)
		)
		(property "Value" ""
			(at 0 0 90)
			(layer "F.Fab")
			(effects
				(font
					(size 1.27 1.27)
				)
			)
		)
		(duplicate_pad_numbers_are_jumpers no)
		(fp_line
			(start 0.299974 -0.150114)
			(end 0.299974 0.150114)
			(stroke
				(width 0.1)
				(type default)
			)
			(layer "F.Fab")
		)
		(fp_line
			(start -0.299974 -0.150114)
			(end 0.299974 -0.150114)
			(stroke
				(width 0.1)
				(type default)
			)
			(layer "F.Fab")
		)
		(fp_line
			(start 0.299974 0.150114)
			(end -0.299974 0.150114)
			(stroke
				(width 0.1)
				(type default)
			)
			(layer "F.Fab")
		)
		(fp_line
			(start -0.299974 0.150114)
			(end -0.299974 -0.150114)
			(stroke
				(width 0.1)
				(type default)
			)
			(layer "F.Fab")
		)
		(pad "1" smd rect
			(at -0.2667 0 90)
			(size 0.3048 0.381)
			(layers "F.Cu" "F.Mask" "F.Paste")
			(net "P5E_PEX2_STN7_TX_DN<121>")
		)
		(pad "2" smd rect
			(at 0.2667 0 90)
			(size 0.3048 0.381)
			(layers "F.Cu" "F.Mask" "F.Paste")
			(net "P5E_PEX2_STN7_TX_C_DN<121>")
		)
	)
	(footprint ""
		(layer "F.Cu")
		(at 369.495578 -86.070694 180)
		(property "Reference" "R1606"
			(at 0 0 180)
			(layer "F.SilkS")
			(hide yes)
			(effects
				(font
					(size 1.27 1.27)
				)
			)
		)
		(property "Value" ""
			(at 0 0 180)
			(layer "F.Fab")
			(effects
				(font
					(size 1.27 1.27)
				)
			)
		)
		(duplicate_pad_numbers_are_jumpers no)
		(fp_line
			(start 0.7874 0.4064)
			(end -0.7874 0.4064)
			(stroke
				(width 0.1524)
				(type default)
			)
			(layer "F.SilkS")
		)
		(fp_line
			(start 0.7874 -0.4064)
			(end 0.7874 0.4064)
			(stroke
				(width 0.1524)
				(type default)
			)
			(layer "F.SilkS")
		)
		(fp_line
			(start -0.7874 0.4064)
			(end -0.7874 -0.4064)
			(stroke
				(width 0.1524)
				(type default)
			)
			(layer "F.SilkS")
		)
		(fp_line
			(start -0.7874 -0.4064)
			(end 0.7874 -0.4064)
			(stroke
				(width 0.1524)
				(type default)
			)
			(layer "F.SilkS")
		)
		(fp_line
			(start 0.67945 0.3048)
			(end 0.120396 0.3048)
			(stroke
				(width 0.1)
				(type default)
			)
			(layer "F.Fab")
		)
		(fp_line
			(start 0.67945 -0.3048)
			(end 0.67945 0.3048)
			(stroke
				(width 0.1)
				(type default)
			)
			(layer "F.Fab")
		)
		(fp_line
			(start 0.12065 -0.2794)
			(end 0.12065 -0.3048)
			(stroke
				(width 0.1)
				(type default)
			)
			(layer "F.Fab")
		)
		(fp_line
			(start 0.12065 -0.3048)
			(end 0.67945 -0.3048)
			(stroke
				(width 0.1)
				(type default)
			)
			(layer "F.Fab")
		)
		(fp_line
			(start 0.120396 0.3048)
			(end 0.120396 0.2794)
			(stroke
				(width 0.1)
				(type default)
			)
			(layer "F.Fab")
		)
		(fp_line
			(start 0.120396 0.2794)
			(end -0.12065 0.2794)
			(stroke
				(width 0.1)
				(type default)
			)
			(layer "F.Fab")
		)
		(fp_line
			(start -0.12065 0.3048)
			(end -0.67945 0.3048)
			(stroke
				(width 0.1)
				(type default)
			)
			(layer "F.Fab")
		)
		(fp_line
			(start -0.12065 0.2794)
			(end -0.12065 0.3048)
			(stroke
				(width 0.1)
				(type default)
			)
			(layer "F.Fab")
		)
		(fp_line
			(start -0.12065 -0.2794)
			(end 0.12065 -0.2794)
			(stroke
				(width 0.1)
				(type default)
			)
			(layer "F.Fab")
		)
		(fp_line
			(start -0.12065 -0.305054)
			(end -0.12065 -0.2794)
			(stroke
				(width 0.1)
				(type default)
			)
			(layer "F.Fab")
		)
		(fp_line
			(start -0.67945 0.3048)
			(end -0.67945 -0.305054)
			(stroke
				(width 0.1)
				(type default)
			)
			(layer "F.Fab")
		)
		(fp_line
			(start -0.67945 -0.305054)
			(end -0.12065 -0.305054)
			(stroke
				(width 0.1)
				(type default)
			)
			(layer "F.Fab")
		)
		(pad "1" smd circle
			(at -0.40005 0 180)
			(size 0 0)
			(layers "F.Cu" "F.Mask" "F.Paste")
			(net "P3V3_AUX")
		)
		(pad "2" smd circle
			(at 0.40005 0 180)
			(size 0 0)
			(layers "F.Cu" "F.Mask" "F.Paste")
			(net "SMB_BIC_I2C9_MUX1_SSD14_R_SDA")
		)
	)
	(footprint ""
		(layer "F.Cu")
		(at 415.487612 -343.952322 90)
		(property "Reference" "C820"
			(at 0 0 90)
			(layer "F.SilkS")
			(hide yes)
			(effects
				(font
					(size 1.27 1.27)
				)
			)
		)
		(property "Value" ""
			(at 0 0 90)
			(layer "F.Fab")
			(effects
				(font
					(size 1.27 1.27)
				)
			)
		)
		(duplicate_pad_numbers_are_jumpers no)
		(fp_line
			(start 0.299974 -0.150114)
			(end 0.299974 0.150114)
			(stroke
				(width 0.1)
				(type default)
			)
			(layer "F.Fab")
		)
		(fp_line
			(start -0.299974 -0.150114)
			(end 0.299974 -0.150114)
			(stroke
				(width 0.1)
				(type default)
			)
			(layer "F.Fab")
		)
		(fp_line
			(start 0.299974 0.150114)
			(end -0.299974 0.150114)
			(stroke
				(width 0.1)
				(type default)
			)
			(layer "F.Fab")
		)
		(fp_line
			(start -0.299974 0.150114)
			(end -0.299974 -0.150114)
			(stroke
				(width 0.1)
				(type default)
			)
			(layer "F.Fab")
		)
		(pad "1" smd rect
			(at -0.2667 0 90)
			(size 0.3048 0.381)
			(layers "F.Cu" "F.Mask" "F.Paste")
			(net "P5E_PEX3_STN7_TX_DP<114>")
		)
		(pad "2" smd rect
			(at 0.2667 0 90)
			(size 0.3048 0.381)
			(layers "F.Cu" "F.Mask" "F.Paste")
			(net "P5E_PEX3_STN7_TX_C_DP<114>")
		)
	)
	(footprint ""
		(layer "F.Cu")
		(at 217.235786 -224.398586 180)
		(property "Reference" "R1483"
			(at 0 0 180)
			(layer "F.SilkS")
			(hide yes)
			(effects
				(font
					(size 1.27 1.27)
				)
			)
		)
		(property "Value" ""
			(at 0 0 180)
			(layer "F.Fab")
			(effects
				(font
					(size 1.27 1.27)
				)
			)
		)
		(duplicate_pad_numbers_are_jumpers no)
		(fp_line
			(start 0.7874 0.4064)
			(end -0.7874 0.4064)
			(stroke
				(width 0.1524)
				(type default)
			)
			(layer "F.SilkS")
		)
		(fp_line
			(start 0.7874 -0.4064)
			(end 0.7874 0.4064)
			(stroke
				(width 0.1524)
				(type default)
			)
			(layer "F.SilkS")
		)
		(fp_line
			(start -0.7874 0.4064)
			(end -0.7874 -0.4064)
			(stroke
				(width 0.1524)
				(type default)
			)
			(layer "F.SilkS")
		)
		(fp_line
			(start -0.7874 -0.4064)
			(end 0.7874 -0.4064)
			(stroke
				(width 0.1524)
				(type default)
			)
			(layer "F.SilkS")
		)
		(fp_line
			(start 0.67945 0.3048)
			(end 0.120396 0.3048)
			(stroke
				(width 0.1)
				(type default)
			)
			(layer "F.Fab")
		)
		(fp_line
			(start 0.67945 -0.3048)
			(end 0.67945 0.3048)
			(stroke
				(width 0.1)
				(type default)
			)
			(layer "F.Fab")
		)
		(fp_line
			(start 0.12065 -0.2794)
			(end 0.12065 -0.3048)
			(stroke
				(width 0.1)
				(type default)
			)
			(layer "F.Fab")
		)
		(fp_line
			(start 0.12065 -0.3048)
			(end 0.67945 -0.3048)
			(stroke
				(width 0.1)
				(type default)
			)
			(layer "F.Fab")
		)
		(fp_line
			(start 0.120396 0.3048)
			(end 0.120396 0.2794)
			(stroke
				(width 0.1)
				(type default)
			)
			(layer "F.Fab")
		)
		(fp_line
			(start 0.120396 0.2794)
			(end -0.12065 0.2794)
			(stroke
				(width 0.1)
				(type default)
			)
			(layer "F.Fab")
		)
		(fp_line
			(start -0.12065 0.3048)
			(end -0.67945 0.3048)
			(stroke
				(width 0.1)
				(type default)
			)
			(layer "F.Fab")
		)
		(fp_line
			(start -0.12065 0.2794)
			(end -0.12065 0.3048)
			(stroke
				(width 0.1)
				(type default)
			)
			(layer "F.Fab")
		)
		(fp_line
			(start -0.12065 -0.2794)
			(end 0.12065 -0.2794)
			(stroke
				(width 0.1)
				(type default)
			)
			(layer "F.Fab")
		)
		(fp_line
			(start -0.12065 -0.305054)
			(end -0.12065 -0.2794)
			(stroke
				(width 0.1)
				(type default)
			)
			(layer "F.Fab")
		)
		(fp_line
			(start -0.67945 0.3048)
			(end -0.67945 -0.305054)
			(stroke
				(width 0.1)
				(type default)
			)
			(layer "F.Fab")
		)
		(fp_line
			(start -0.67945 -0.305054)
			(end -0.12065 -0.305054)
			(stroke
				(width 0.1)
				(type default)
			)
			(layer "F.Fab")
		)
		(pad "1" smd circle
			(at -0.40005 0 180)
			(size 0 0)
			(layers "F.Cu" "F.Mask" "F.Paste")
			(net "I3C_MB_SCL")
		)
		(pad "2" smd circle
			(at 0.40005 0 180)
			(size 0 0)
			(layers "F.Cu" "F.Mask" "F.Paste")
			(net "SMB_MB_I3C_ISO_SCL")
		)
	)
	(footprint ""
		(layer "F.Cu")
		(at 213.571582 -25.342342 -90)
		(property "Reference" "R430"
			(at 0 0 270)
			(layer "F.SilkS")
			(hide yes)
			(effects
				(font
					(size 1.27 1.27)
				)
			)
		)
		(property "Value" ""
			(at 0 0 270)
			(layer "F.Fab")
			(effects
				(font
					(size 1.27 1.27)
				)
			)
		)
		(duplicate_pad_numbers_are_jumpers no)
		(fp_line
			(start -0.7874 0.4064)
			(end -0.7874 -0.4064)
			(stroke
				(width 0.1524)
				(type default)
			)
			(layer "F.SilkS")
		)
		(fp_line
			(start 0.7874 0.4064)
			(end -0.7874 0.4064)
			(stroke
				(width 0.1524)
				(type default)
			)
			(layer "F.SilkS")
		)
		(fp_line
			(start -0.7874 -0.4064)
			(end 0.7874 -0.4064)
			(stroke
				(width 0.1524)
				(type default)
			)
			(layer "F.SilkS")
		)
		(fp_line
			(start 0.7874 -0.4064)
			(end 0.7874 0.4064)
			(stroke
				(width 0.1524)
				(type default)
			)
			(layer "F.SilkS")
		)
		(fp_line
			(start -0.67945 0.3048)
			(end -0.67945 -0.305054)
			(stroke
				(width 0.1)
				(type default)
			)
			(layer "F.Fab")
		)
		(fp_line
			(start -0.12065 0.3048)
			(end -0.67945 0.3048)
			(stroke
				(width 0.1)
				(type default)
			)
			(layer "F.Fab")
		)
		(fp_line
			(start 0.120396 0.3048)
			(end 0.120396 0.2794)
			(stroke
				(width 0.1)
				(type default)
			)
			(layer "F.Fab")
		)
		(fp_line
			(start 0.67945 0.3048)
			(end 0.120396 0.3048)
			(stroke
				(width 0.1)
				(type default)
			)
			(layer "F.Fab")
		)
		(fp_line
			(start -0.12065 0.2794)
			(end -0.12065 0.3048)
			(stroke
				(width 0.1)
				(type default)
			)
			(layer "F.Fab")
		)
		(fp_line
			(start 0.120396 0.2794)
			(end -0.12065 0.2794)
			(stroke
				(width 0.1)
				(type default)
			)
			(layer "F.Fab")
		)
		(fp_line
			(start -0.12065 -0.2794)
			(end 0.12065 -0.2794)
			(stroke
				(width 0.1)
				(type default)
			)
			(layer "F.Fab")
		)
		(fp_line
			(start 0.12065 -0.2794)
			(end 0.12065 -0.3048)
			(stroke
				(width 0.1)
				(type default)
			)
			(layer "F.Fab")
		)
		(fp_line
			(start 0.12065 -0.3048)
			(end 0.67945 -0.3048)
			(stroke
				(width 0.1)
				(type default)
			)
			(layer "F.Fab")
		)
		(fp_line
			(start 0.67945 -0.3048)
			(end 0.67945 0.3048)
			(stroke
				(width 0.1)
				(type default)
			)
			(layer "F.Fab")
		)
		(fp_line
			(start -0.67945 -0.305054)
			(end -0.12065 -0.305054)
			(stroke
				(width 0.1)
				(type default)
			)
			(layer "F.Fab")
		)
		(fp_line
			(start -0.12065 -0.305054)
			(end -0.12065 -0.2794)
			(stroke
				(width 0.1)
				(type default)
			)
			(layer "F.Fab")
		)
		(pad "1" smd circle
			(at -0.40005 0 270)
			(size 0 0)
			(layers "F.Cu" "F.Mask" "F.Paste")
			(net "P3V3_SSD7")
		)
		(pad "2" smd circle
			(at 0.40005 0 270)
			(size 0 0)
			(layers "F.Cu" "F.Mask" "F.Paste")
			(net "DUALPORT_N_SSD7")
		)
	)
	(footprint ""
		(layer "F.Cu")
		(at 337.471766 -280.44902 -90)
		(property "Reference" "PR149"
			(at 0 0 270)
			(layer "F.SilkS")
			(hide yes)
			(effects
				(font
					(size 1.27 1.27)
				)
			)
		)
		(property "Value" ""
			(at 0 0 270)
			(layer "F.Fab")
			(effects
				(font
					(size 1.27 1.27)
				)
			)
		)
		(duplicate_pad_numbers_are_jumpers no)
		(fp_line
			(start -0.7874 0.4064)
			(end -0.7874 -0.4064)
			(stroke
				(width 0.1524)
				(type default)
			)
			(layer "F.SilkS")
		)
		(fp_line
			(start 0.7874 0.4064)
			(end -0.7874 0.4064)
			(stroke
				(width 0.1524)
				(type default)
			)
			(layer "F.SilkS")
		)
		(fp_line
			(start -0.7874 -0.4064)
			(end 0.7874 -0.4064)
			(stroke
				(width 0.1524)
				(type default)
			)
			(layer "F.SilkS")
		)
		(fp_line
			(start 0.7874 -0.4064)
			(end 0.7874 0.4064)
			(stroke
				(width 0.1524)
				(type default)
			)
			(layer "F.SilkS")
		)
		(fp_line
			(start -0.67945 0.3048)
			(end -0.67945 -0.305054)
			(stroke
				(width 0.1)
				(type default)
			)
			(layer "F.Fab")
		)
		(fp_line
			(start -0.12065 0.3048)
			(end -0.67945 0.3048)
			(stroke
				(width 0.1)
				(type default)
			)
			(layer "F.Fab")
		)
		(fp_line
			(start 0.120396 0.3048)
			(end 0.120396 0.2794)
			(stroke
				(width 0.1)
				(type default)
			)
			(layer "F.Fab")
		)
		(fp_line
			(start 0.67945 0.3048)
			(end 0.120396 0.3048)
			(stroke
				(width 0.1)
				(type default)
			)
			(layer "F.Fab")
		)
		(fp_line
			(start -0.12065 0.2794)
			(end -0.12065 0.3048)
			(stroke
				(width 0.1)
				(type default)
			)
			(layer "F.Fab")
		)
		(fp_line
			(start 0.120396 0.2794)
			(end -0.12065 0.2794)
			(stroke
				(width 0.1)
				(type default)
			)
			(layer "F.Fab")
		)
		(fp_line
			(start -0.12065 -0.2794)
			(end 0.12065 -0.2794)
			(stroke
				(width 0.1)
				(type default)
			)
			(layer "F.Fab")
		)
		(fp_line
			(start 0.12065 -0.2794)
			(end 0.12065 -0.3048)
			(stroke
				(width 0.1)
				(type default)
			)
			(layer "F.Fab")
		)
		(fp_line
			(start 0.12065 -0.3048)
			(end 0.67945 -0.3048)
			(stroke
				(width 0.1)
				(type default)
			)
			(layer "F.Fab")
		)
		(fp_line
			(start 0.67945 -0.3048)
			(end 0.67945 0.3048)
			(stroke
				(width 0.1)
				(type default)
			)
			(layer "F.Fab")
		)
		(fp_line
			(start -0.67945 -0.305054)
			(end -0.12065 -0.305054)
			(stroke
				(width 0.1)
				(type default)
			)
			(layer "F.Fab")
		)
		(fp_line
			(start -0.12065 -0.305054)
			(end -0.12065 -0.2794)
			(stroke
				(width 0.1)
				(type default)
			)
			(layer "F.Fab")
		)
		(pad "1" smd circle
			(at -0.40005 0 270)
			(size 0 0)
			(layers "F.Cu" "F.Mask" "F.Paste")
			(net "SW_P0V8_PEX2_BOOT1")
		)
		(pad "2" smd circle
			(at 0.40005 0 270)
			(size 0 0)
			(layers "F.Cu" "F.Mask" "F.Paste")
			(net "SW_P0V8_PEX2_BOOT1_R")
		)
	)
	(footprint ""
		(layer "F.Cu")
		(at 14.252956 -394.13053 -90)
		(property "Reference" "R6746"
			(at 0 0 270)
			(layer "F.SilkS")
			(hide yes)
			(effects
				(font
					(size 1.27 1.27)
				)
			)
		)
		(property "Value" ""
			(at 0 0 270)
			(layer "F.Fab")
			(effects
				(font
					(size 1.27 1.27)
				)
			)
		)
		(duplicate_pad_numbers_are_jumpers no)
		(fp_line
			(start -0.7874 0.4064)
			(end -0.7874 -0.4064)
			(stroke
				(width 0.1524)
				(type default)
			)
			(layer "F.SilkS")
		)
		(fp_line
			(start 0.7874 0.4064)
			(end -0.7874 0.4064)
			(stroke
				(width 0.1524)
				(type default)
			)
			(layer "F.SilkS")
		)
		(fp_line
			(start -0.7874 -0.4064)
			(end 0.7874 -0.4064)
			(stroke
				(width 0.1524)
				(type default)
			)
			(layer "F.SilkS")
		)
		(fp_line
			(start 0.7874 -0.4064)
			(end 0.7874 0.4064)
			(stroke
				(width 0.1524)
				(type default)
			)
			(layer "F.SilkS")
		)
		(fp_line
			(start -0.67945 0.3048)
			(end -0.67945 -0.305054)
			(stroke
				(width 0.1)
				(type default)
			)
			(layer "F.Fab")
		)
		(fp_line
			(start -0.12065 0.3048)
			(end -0.67945 0.3048)
			(stroke
				(width 0.1)
				(type default)
			)
			(layer "F.Fab")
		)
		(fp_line
			(start 0.120396 0.3048)
			(end 0.120396 0.2794)
			(stroke
				(width 0.1)
				(type default)
			)
			(layer "F.Fab")
		)
		(fp_line
			(start 0.67945 0.3048)
			(end 0.120396 0.3048)
			(stroke
				(width 0.1)
				(type default)
			)
			(layer "F.Fab")
		)
		(fp_line
			(start -0.12065 0.2794)
			(end -0.12065 0.3048)
			(stroke
				(width 0.1)
				(type default)
			)
			(layer "F.Fab")
		)
		(fp_line
			(start 0.120396 0.2794)
			(end -0.12065 0.2794)
			(stroke
				(width 0.1)
				(type default)
			)
			(layer "F.Fab")
		)
		(fp_line
			(start -0.12065 -0.2794)
			(end 0.12065 -0.2794)
			(stroke
				(width 0.1)
				(type default)
			)
			(layer "F.Fab")
		)
		(fp_line
			(start 0.12065 -0.2794)
			(end 0.12065 -0.3048)
			(stroke
				(width 0.1)
				(type default)
			)
			(layer "F.Fab")
		)
		(fp_line
			(start 0.12065 -0.3048)
			(end 0.67945 -0.3048)
			(stroke
				(width 0.1)
				(type default)
			)
			(layer "F.Fab")
		)
		(fp_line
			(start 0.67945 -0.3048)
			(end 0.67945 0.3048)
			(stroke
				(width 0.1)
				(type default)
			)
			(layer "F.Fab")
		)
		(fp_line
			(start -0.67945 -0.305054)
			(end -0.12065 -0.305054)
			(stroke
				(width 0.1)
				(type default)
			)
			(layer "F.Fab")
		)
		(fp_line
			(start -0.12065 -0.305054)
			(end -0.12065 -0.2794)
			(stroke
				(width 0.1)
				(type default)
			)
			(layer "F.Fab")
		)
		(pad "1" smd circle
			(at -0.40005 0 270)
			(size 0 0)
			(layers "F.Cu" "F.Mask" "F.Paste")
			(net "GND")
		)
		(pad "2" smd circle
			(at 0.40005 0 270)
			(size 0 0)
			(layers "F.Cu" "F.Mask" "F.Paste")
			(net "BIC_USB_8042_HUB_FULLPWRMGMTZ")
		)
	)
	(footprint ""
		(layer "F.Cu")
		(at 114.23523 -159.27324 -90)
		(property "Reference" "PC42"
			(at 0 0 270)
			(layer "F.SilkS")
			(hide yes)
			(effects
				(font
					(size 1.27 1.27)
				)
			)
		)
		(property "Value" ""
			(at 0 0 270)
			(layer "F.Fab")
			(effects
				(font
					(size 1.27 1.27)
				)
			)
		)
		(duplicate_pad_numbers_are_jumpers no)
		(fp_line
			(start -0.7874 0.4064)
			(end -0.7874 -0.4064)
			(stroke
				(width 0.1524)
				(type default)
			)
			(layer "F.SilkS")
		)
		(fp_line
			(start 0.7874 0.4064)
			(end -0.7874 0.4064)
			(stroke
				(width 0.1524)
				(type default)
			)
			(layer "F.SilkS")
		)
		(fp_line
			(start -0.7874 -0.4064)
			(end 0.7874 -0.4064)
			(stroke
				(width 0.1524)
				(type default)
			)
			(layer "F.SilkS")
		)
		(fp_line
			(start 0.7874 -0.4064)
			(end 0.7874 0.4064)
			(stroke
				(width 0.1524)
				(type default)
			)
			(layer "F.SilkS")
		)
		(fp_line
			(start -0.67945 0.3048)
			(end -0.67945 -0.305054)
			(stroke
				(width 0.1)
				(type default)
			)
			(layer "F.Fab")
		)
		(fp_line
			(start -0.12065 0.3048)
			(end -0.67945 0.3048)
			(stroke
				(width 0.1)
				(type default)
			)
			(layer "F.Fab")
		)
		(fp_line
			(start 0.120396 0.3048)
			(end 0.120396 0.2794)
			(stroke
				(width 0.1)
				(type default)
			)
			(layer "F.Fab")
		)
		(fp_line
			(start 0.67945 0.3048)
			(end 0.120396 0.3048)
			(stroke
				(width 0.1)
				(type default)
			)
			(layer "F.Fab")
		)
		(fp_line
			(start -0.12065 0.2794)
			(end -0.12065 0.3048)
			(stroke
				(width 0.1)
				(type default)
			)
			(layer "F.Fab")
		)
		(fp_line
			(start 0.120396 0.2794)
			(end -0.12065 0.2794)
			(stroke
				(width 0.1)
				(type default)
			)
			(layer "F.Fab")
		)
		(fp_line
			(start -0.12065 -0.2794)
			(end 0.12065 -0.2794)
			(stroke
				(width 0.1)
				(type default)
			)
			(layer "F.Fab")
		)
		(fp_line
			(start 0.12065 -0.2794)
			(end 0.12065 -0.3048)
			(stroke
				(width 0.1)
				(type default)
			)
			(layer "F.Fab")
		)
		(fp_line
			(start 0.12065 -0.3048)
			(end 0.67945 -0.3048)
			(stroke
				(width 0.1)
				(type default)
			)
			(layer "F.Fab")
		)
		(fp_line
			(start 0.67945 -0.3048)
			(end 0.67945 0.3048)
			(stroke
				(width 0.1)
				(type default)
			)
			(layer "F.Fab")
		)
		(fp_line
			(start -0.67945 -0.305054)
			(end -0.12065 -0.305054)
			(stroke
				(width 0.1)
				(type default)
			)
			(layer "F.Fab")
		)
		(fp_line
			(start -0.12065 -0.305054)
			(end -0.12065 -0.2794)
			(stroke
				(width 0.1)
				(type default)
			)
			(layer "F.Fab")
		)
		(pad "1" smd circle
			(at -0.40005 0 270)
			(size 0 0)
			(layers "F.Cu" "F.Mask" "F.Paste")
			(net "P3V3_AUX_REF")
		)
		(pad "2" smd circle
			(at 0.40005 0 270)
			(size 0 0)
			(layers "F.Cu" "F.Mask" "F.Paste")
			(net "GND")
		)
	)
	(footprint ""
		(layer "F.Cu")
		(at 325.197724 -296.365168 90)
		(property "Reference" "C2782"
			(at 0 0 90)
			(layer "F.SilkS")
			(hide yes)
			(effects
				(font
					(size 1.27 1.27)
				)
			)
		)
		(property "Value" ""
			(at 0 0 90)
			(layer "F.Fab")
			(effects
				(font
					(size 1.27 1.27)
				)
			)
		)
		(duplicate_pad_numbers_are_jumpers no)
		(fp_line
			(start 0.7874 -0.4064)
			(end 0.7874 0.4064)
			(stroke
				(width 0.1524)
				(type default)
			)
			(layer "F.SilkS")
		)
		(fp_line
			(start -0.7874 -0.4064)
			(end 0.7874 -0.4064)
			(stroke
				(width 0.1524)
				(type default)
			)
			(layer "F.SilkS")
		)
		(fp_line
			(start 0.7874 0.4064)
			(end -0.7874 0.4064)
			(stroke
				(width 0.1524)
				(type default)
			)
			(layer "F.SilkS")
		)
		(fp_line
			(start -0.7874 0.4064)
			(end -0.7874 -0.4064)
			(stroke
				(width 0.1524)
				(type default)
			)
			(layer "F.SilkS")
		)
		(fp_line
			(start -0.12065 -0.305054)
			(end -0.12065 -0.2794)
			(stroke
				(width 0.1)
				(type default)
			)
			(layer "F.Fab")
		)
		(fp_line
			(start -0.67945 -0.305054)
			(end -0.12065 -0.305054)
			(stroke
				(width 0.1)
				(type default)
			)
			(layer "F.Fab")
		)
		(fp_line
			(start 0.67945 -0.3048)
			(end 0.67945 0.3048)
			(stroke
				(width 0.1)
				(type default)
			)
			(layer "F.Fab")
		)
		(fp_line
			(start 0.12065 -0.3048)
			(end 0.67945 -0.3048)
			(stroke
				(width 0.1)
				(type default)
			)
			(layer "F.Fab")
		)
		(fp_line
			(start 0.12065 -0.2794)
			(end 0.12065 -0.3048)
			(stroke
				(width 0.1)
				(type default)
			)
			(layer "F.Fab")
		)
		(fp_line
			(start -0.12065 -0.2794)
			(end 0.12065 -0.2794)
			(stroke
				(width 0.1)
				(type default)
			)
			(layer "F.Fab")
		)
		(fp_line
			(start 0.120396 0.2794)
			(end -0.12065 0.2794)
			(stroke
				(width 0.1)
				(type default)
			)
			(layer "F.Fab")
		)
		(fp_line
			(start -0.12065 0.2794)
			(end -0.12065 0.3048)
			(stroke
				(width 0.1)
				(type default)
			)
			(layer "F.Fab")
		)
		(fp_line
			(start 0.67945 0.3048)
			(end 0.120396 0.3048)
			(stroke
				(width 0.1)
				(type default)
			)
			(layer "F.Fab")
		)
		(fp_line
			(start 0.120396 0.3048)
			(end 0.120396 0.2794)
			(stroke
				(width 0.1)
				(type default)
			)
			(layer "F.Fab")
		)
		(fp_line
			(start -0.12065 0.3048)
			(end -0.67945 0.3048)
			(stroke
				(width 0.1)
				(type default)
			)
			(layer "F.Fab")
		)
		(fp_line
			(start -0.67945 0.3048)
			(end -0.67945 -0.305054)
			(stroke
				(width 0.1)
				(type default)
			)
			(layer "F.Fab")
		)
		(pad "1" smd circle
			(at -0.40005 0 90)
			(size 0 0)
			(layers "F.Cu" "F.Mask" "F.Paste")
			(net "GND")
		)
		(pad "2" smd circle
			(at 0.40005 0 90)
			(size 0 0)
			(layers "F.Cu" "F.Mask" "F.Paste")
			(net "P1V8_PEX")
		)
	)
	(footprint ""
		(layer "F.Cu")
		(at 83.650074 -50.96383 180)
		(property "Reference" "PC539"
			(at 0 0 180)
			(layer "F.SilkS")
			(hide yes)
			(effects
				(font
					(size 1.27 1.27)
				)
			)
		)
		(property "Value" ""
			(at 0 0 180)
			(layer "F.Fab")
			(effects
				(font
					(size 1.27 1.27)
				)
			)
		)
		(duplicate_pad_numbers_are_jumpers no)
		(fp_line
			(start 1.524 0.762)
			(end -1.524 0.762)
			(stroke
				(width 0.1524)
				(type default)
			)
			(layer "F.SilkS")
		)
		(fp_line
			(start 1.524 -0.762)
			(end 1.524 0.762)
			(stroke
				(width 0.1524)
				(type default)
			)
			(layer "F.SilkS")
		)
		(fp_line
			(start -1.524 0.762)
			(end -1.524 -0.762)
			(stroke
				(width 0.1524)
				(type default)
			)
			(layer "F.SilkS")
		)
		(fp_line
			(start -1.524 -0.762)
			(end 1.524 -0.762)
			(stroke
				(width 0.1524)
				(type default)
			)
			(layer "F.SilkS")
		)
		(fp_line
			(start 1.1049 0.724916)
			(end 1.1049 -0.724916)
			(stroke
				(width 0.1)
				(type default)
			)
			(layer "F.Fab")
		)
		(fp_line
			(start 1.1049 -0.724916)
			(end -1.1049 -0.724916)
			(stroke
				(width 0.1)
				(type default)
			)
			(layer "F.Fab")
		)
		(fp_line
			(start -1.1049 0.724916)
			(end 1.1049 0.724916)
			(stroke
				(width 0.1)
				(type default)
			)
			(layer "F.Fab")
		)
		(fp_line
			(start -1.1049 -0.724916)
			(end -1.1049 0.724916)
			(stroke
				(width 0.1)
				(type default)
			)
			(layer "F.Fab")
		)
		(pad "1" smd rect
			(at -0.889 0)
			(size 1.016 1.27)
			(layers "F.Cu" "F.Mask" "F.Paste")
			(net "P3V3_SSD3")
		)
		(pad "2" smd rect
			(at 0.889 0)
			(size 1.016 1.27)
			(layers "F.Cu" "F.Mask" "F.Paste")
			(net "GND")
		)
	)
	(footprint ""
		(layer "F.Cu")
		(at 41.142666 -70.844918 -90)
		(property "Reference" "PD87"
			(at 3.839718 2.126996 90)
			(unlocked yes)
			(layer "F.SilkS")
			(effects
				(font
					(size 0.7874 0.5842)
					(thickness 0.1524)
				)
				(justify left)
			)
		)
		(property "Value" ""
			(at 0 0 270)
			(layer "F.Fab")
			(effects
				(font
					(size 1.27 1.27)
				)
			)
		)
		(duplicate_pad_numbers_are_jumpers no)
		(fp_line
			(start -3.400044 1.459992)
			(end -3.400044 -1.459992)
			(stroke
				(width 0.1524)
				(type default)
			)
			(layer "F.SilkS")
		)
		(fp_line
			(start 4.107942 1.459992)
			(end -3.400044 1.459992)
			(stroke
				(width 0.1524)
				(type default)
			)
			(layer "F.SilkS")
		)
		(fp_line
			(start -3.400044 -1.459992)
			(end 4.107942 -1.459992)
			(stroke
				(width 0.1524)
				(type default)
			)
			(layer "F.SilkS")
		)
		(fp_line
			(start 4.107942 -1.459992)
			(end 4.107942 1.459992)
			(stroke
				(width 0.1524)
				(type default)
			)
			(layer "F.SilkS")
		)
		(fp_poly
			(pts
				(xy 4.107942 -1.459992) (xy 4.107942 1.459992) (xy 3.308096 1.459992) (xy 3.308096 -1.459992)
			)
			(stroke
				(width 0)
				(type default)
			)
			(fill yes)
			(layer "F.SilkS")
		)
		(fp_line
			(start -2.29997 1.459992)
			(end -2.29997 -1.459992)
			(stroke
				(width 0.1)
				(type default)
			)
			(layer "F.Fab")
		)
		(fp_line
			(start 2.29997 1.459992)
			(end -2.29997 1.459992)
			(stroke
				(width 0.1)
				(type default)
			)
			(layer "F.Fab")
		)
		(fp_line
			(start -2.29997 -1.459992)
			(end 2.29997 -1.459992)
			(stroke
				(width 0.1)
				(type default)
			)
			(layer "F.Fab")
		)
		(fp_line
			(start 2.29997 -1.459992)
			(end 2.29997 1.459992)
			(stroke
				(width 0.1)
				(type default)
			)
			(layer "F.Fab")
		)
		(fp_text user "-"
			(at 5.4102 0.29845 90)
			(unlocked yes)
			(layer "F.SilkS")
			(effects
				(font
					(size 1.905 1.4224)
					(thickness 0.1524)
				)
				(justify left)
			)
		)
		(fp_text user "+"
			(at -5.239258 -0.200914 270)
			(unlocked yes)
			(layer "F.SilkS")
			(effects
				(font
					(size 1.905 1.4224)
					(thickness 0.1524)
				)
				(justify left)
			)
		)
		(fp_text user "-"
			(at 5.4102 0.29845 90)
			(unlocked yes)
			(layer "F.Fab")
			(effects
				(font
					(size 1.905 1.4224)
					(thickness 0.1524)
				)
				(justify left)
			)
		)
		(fp_text user "+"
			(at -4.7752 -0.12065 270)
			(unlocked yes)
			(layer "F.Fab")
			(effects
				(font
					(size 1.905 1.4224)
					(thickness 0.1524)
				)
				(justify left)
			)
		)
		(pad "A" smd rect
			(at -1.999996 0)
			(size 1.7018 2.5146)
			(layers "F.Cu" "F.Mask" "F.Paste")
			(net "GND")
		)
		(pad "C" smd rect
			(at 1.999996 0)
			(size 1.7018 2.5146)
			(layers "F.Cu" "F.Mask" "F.Paste")
			(net "P12V_SSD1_R")
		)
	)
	(footprint ""
		(layer "F.Cu")
		(at 39.280592 -110.088934)
		(property "Reference" "C51"
			(at 0 0 0)
			(layer "F.SilkS")
			(hide yes)
			(effects
				(font
					(size 1.27 1.27)
				)
			)
		)
		(property "Value" ""
			(at 0 0 0)
			(layer "F.Fab")
			(effects
				(font
					(size 1.27 1.27)
				)
			)
		)
		(duplicate_pad_numbers_are_jumpers no)
		(fp_line
			(start -0.299974 -0.150114)
			(end 0.299974 -0.150114)
			(stroke
				(width 0.1)
				(type default)
			)
			(layer "F.Fab")
		)
		(fp_line
			(start -0.299974 0.150114)
			(end -0.299974 -0.150114)
			(stroke
				(width 0.1)
				(type default)
			)
			(layer "F.Fab")
		)
		(fp_line
			(start 0.299974 -0.150114)
			(end 0.299974 0.150114)
			(stroke
				(width 0.1)
				(type default)
			)
			(layer "F.Fab")
		)
		(fp_line
			(start 0.299974 0.150114)
			(end -0.299974 0.150114)
			(stroke
				(width 0.1)
				(type default)
			)
			(layer "F.Fab")
		)
		(pad "1" smd rect
			(at -0.2667 0)
			(size 0.3048 0.381)
			(layers "F.Cu" "F.Mask" "F.Paste")
			(net "P5E_PEX0_STN1_TX_DP<22>")
		)
		(pad "2" smd rect
			(at 0.2667 0)
			(size 0.3048 0.381)
			(layers "F.Cu" "F.Mask" "F.Paste")
			(net "P5E_PEX0_STN1_TX_C_DP<22>")
		)
	)
	(footprint ""
		(layer "F.Cu")
		(at 378.079 -214.376 90)
		(property "Reference" "C3597"
			(at 0 0 90)
			(layer "F.SilkS")
			(hide yes)
			(effects
				(font
					(size 1.27 1.27)
				)
			)
		)
		(property "Value" ""
			(at 0 0 90)
			(layer "F.Fab")
			(effects
				(font
					(size 1.27 1.27)
				)
			)
		)
		(duplicate_pad_numbers_are_jumpers no)
		(fp_line
			(start 0.7874 -0.4064)
			(end 0.7874 0.4064)
			(stroke
				(width 0.1524)
				(type default)
			)
			(layer "F.SilkS")
		)
		(fp_line
			(start -0.7874 -0.4064)
			(end 0.7874 -0.4064)
			(stroke
				(width 0.1524)
				(type default)
			)
			(layer "F.SilkS")
		)
		(fp_line
			(start 0.7874 0.4064)
			(end -0.7874 0.4064)
			(stroke
				(width 0.1524)
				(type default)
			)
			(layer "F.SilkS")
		)
		(fp_line
			(start -0.7874 0.4064)
			(end -0.7874 -0.4064)
			(stroke
				(width 0.1524)
				(type default)
			)
			(layer "F.SilkS")
		)
		(fp_line
			(start -0.12065 -0.305054)
			(end -0.12065 -0.2794)
			(stroke
				(width 0.1)
				(type default)
			)
			(layer "F.Fab")
		)
		(fp_line
			(start -0.67945 -0.305054)
			(end -0.12065 -0.305054)
			(stroke
				(width 0.1)
				(type default)
			)
			(layer "F.Fab")
		)
		(fp_line
			(start 0.67945 -0.3048)
			(end 0.67945 0.3048)
			(stroke
				(width 0.1)
				(type default)
			)
			(layer "F.Fab")
		)
		(fp_line
			(start 0.12065 -0.3048)
			(end 0.67945 -0.3048)
			(stroke
				(width 0.1)
				(type default)
			)
			(layer "F.Fab")
		)
		(fp_line
			(start 0.12065 -0.2794)
			(end 0.12065 -0.3048)
			(stroke
				(width 0.1)
				(type default)
			)
			(layer "F.Fab")
		)
		(fp_line
			(start -0.12065 -0.2794)
			(end 0.12065 -0.2794)
			(stroke
				(width 0.1)
				(type default)
			)
			(layer "F.Fab")
		)
		(fp_line
			(start 0.120396 0.2794)
			(end -0.12065 0.2794)
			(stroke
				(width 0.1)
				(type default)
			)
			(layer "F.Fab")
		)
		(fp_line
			(start -0.12065 0.2794)
			(end -0.12065 0.3048)
			(stroke
				(width 0.1)
				(type default)
			)
			(layer "F.Fab")
		)
		(fp_line
			(start 0.67945 0.3048)
			(end 0.120396 0.3048)
			(stroke
				(width 0.1)
				(type default)
			)
			(layer "F.Fab")
		)
		(fp_line
			(start 0.120396 0.3048)
			(end 0.120396 0.2794)
			(stroke
				(width 0.1)
				(type default)
			)
			(layer "F.Fab")
		)
		(fp_line
			(start -0.12065 0.3048)
			(end -0.67945 0.3048)
			(stroke
				(width 0.1)
				(type default)
			)
			(layer "F.Fab")
		)
		(fp_line
			(start -0.67945 0.3048)
			(end -0.67945 -0.305054)
			(stroke
				(width 0.1)
				(type default)
			)
			(layer "F.Fab")
		)
		(pad "1" smd circle
			(at -0.40005 0 90)
			(size 0 0)
			(layers "F.Cu" "F.Mask" "F.Paste")
			(net "P3V3_AUX")
		)
		(pad "2" smd circle
			(at 0.40005 0 90)
			(size 0 0)
			(layers "F.Cu" "F.Mask" "F.Paste")
			(net "GND")
		)
	)
	(footprint ""
		(layer "F.Cu")
		(at 120.77573 -258.394962 90)
		(property "Reference" "PU6"
			(at -6.600952 0.403098 0)
			(unlocked yes)
			(layer "F.SilkS")
			(effects
				(font
					(size 0.7874 0.5842)
					(thickness 0.1524)
				)
				(justify left)
			)
		)
		(property "Value" ""
			(at 0 0 90)
			(layer "F.Fab")
			(effects
				(font
					(size 1.27 1.27)
				)
			)
		)
		(duplicate_pad_numbers_are_jumpers no)
		(fp_line
			(start 0.1778 -3.2385)
			(end 0.1778 -2.8575)
			(stroke
				(width 0.1524)
				(type default)
			)
			(layer "F.SilkS")
		)
		(fp_line
			(start -1.8034 -2.8702)
			(end -1.8034 -3.6322)
			(stroke
				(width 0.1524)
				(type default)
			)
			(layer "F.SilkS")
		)
		(fp_line
			(start 2.500122 -2.500122)
			(end 2.500122 -2.015998)
			(stroke
				(width 0.1524)
				(type default)
			)
			(layer "F.SilkS")
		)
		(fp_line
			(start 2.015998 -2.500122)
			(end 2.500122 -2.500122)
			(stroke
				(width 0.1524)
				(type default)
			)
			(layer "F.SilkS")
		)
		(fp_line
			(start -2.500122 -2.500122)
			(end -2.015998 -2.500122)
			(stroke
				(width 0.1524)
				(type default)
			)
			(layer "F.SilkS")
		)
		(fp_line
			(start -2.500122 -2.015998)
			(end -2.500122 -2.500122)
			(stroke
				(width 0.1524)
				(type default)
			)
			(layer "F.SilkS")
		)
		(fp_line
			(start 2.8702 -1.778)
			(end 3.6322 -1.778)
			(stroke
				(width 0.1524)
				(type default)
			)
			(layer "F.SilkS")
		)
		(fp_line
			(start -3.2639 -0.1778)
			(end -2.8829 -0.1778)
			(stroke
				(width 0.1524)
				(type default)
			)
			(layer "F.SilkS")
		)
		(fp_line
			(start 2.8829 0.2032)
			(end 3.2639 0.2032)
			(stroke
				(width 0.1524)
				(type default)
			)
			(layer "F.SilkS")
		)
		(fp_line
			(start -3.6576 1.8034)
			(end -2.8956 1.8034)
			(stroke
				(width 0.1524)
				(type default)
			)
			(layer "F.SilkS")
		)
		(fp_line
			(start 2.500122 2.015998)
			(end 2.500122 2.500122)
			(stroke
				(width 0.1524)
				(type default)
			)
			(layer "F.SilkS")
		)
		(fp_line
			(start 2.500122 2.500122)
			(end 2.015998 2.500122)
			(stroke
				(width 0.1524)
				(type default)
			)
			(layer "F.SilkS")
		)
		(fp_line
			(start -2.015998 2.500122)
			(end -2.500122 2.500122)
			(stroke
				(width 0.1524)
				(type default)
			)
			(layer "F.SilkS")
		)
		(fp_line
			(start -2.500122 2.500122)
			(end -2.500122 2.018538)
			(stroke
				(width 0.1524)
				(type default)
			)
			(layer "F.SilkS")
		)
		(fp_line
			(start -0.2032 2.8829)
			(end -0.2032 3.2639)
			(stroke
				(width 0.1524)
				(type default)
			)
			(layer "F.SilkS")
		)
		(fp_line
			(start 1.778 3.6322)
			(end 1.778 2.8702)
			(stroke
				(width 0.1524)
				(type default)
			)
			(layer "F.SilkS")
		)
		(fp_poly
			(pts
				(xy -2.921 -1.800098) (xy -3.504184 -1.508506) (xy -3.504184 -2.09169)
			)
			(stroke
				(width 0)
				(type default)
			)
			(fill yes)
			(layer "F.SilkS")
		)
		(fp_line
			(start 0.1778 -3.2385)
			(end 0.1778 -2.8575)
			(stroke
				(width 0.1)
				(type default)
			)
			(layer "F.Fab")
		)
		(fp_line
			(start -1.8034 -2.8702)
			(end -1.8034 -3.6322)
			(stroke
				(width 0.1)
				(type default)
			)
			(layer "F.Fab")
		)
		(fp_line
			(start 2.500122 -2.500122)
			(end 2.500122 2.500122)
			(stroke
				(width 0.1)
				(type default)
			)
			(layer "F.Fab")
		)
		(fp_line
			(start -2.500122 -2.500122)
			(end 2.500122 -2.500122)
			(stroke
				(width 0.1)
				(type default)
			)
			(layer "F.Fab")
		)
		(fp_line
			(start 2.8702 -1.778)
			(end 3.6322 -1.778)
			(stroke
				(width 0.1)
				(type default)
			)
			(layer "F.Fab")
		)
		(fp_line
			(start -3.2639 -0.1778)
			(end -2.8829 -0.1778)
			(stroke
				(width 0.1)
				(type default)
			)
			(layer "F.Fab")
		)
		(fp_line
			(start 2.8829 0.2032)
			(end 3.2639 0.2032)
			(stroke
				(width 0.1)
				(type default)
			)
			(layer "F.Fab")
		)
		(fp_line
			(start -3.6576 1.8034)
			(end -2.8956 1.8034)
			(stroke
				(width 0.1)
				(type default)
			)
			(layer "F.Fab")
		)
		(fp_line
			(start 2.500122 2.500122)
			(end -2.500122 2.500122)
			(stroke
				(width 0.1)
				(type default)
			)
			(layer "F.Fab")
		)
		(fp_line
			(start -2.500122 2.500122)
			(end -2.500122 -2.500122)
			(stroke
				(width 0.1)
				(type default)
			)
			(layer "F.Fab")
		)
		(fp_line
			(start -0.2032 2.8829)
			(end -0.2032 3.2639)
			(stroke
				(width 0.1)
				(type default)
			)
			(layer "F.Fab")
		)
		(fp_line
			(start 1.778 3.6322)
			(end 1.778 2.8702)
			(stroke
				(width 0.1)
				(type default)
			)
			(layer "F.Fab")
		)
		(fp_poly
			(pts
				(xy -2.921 -1.800098) (xy -3.504184 -1.508506) (xy -3.504184 -2.09169)
			)
			(stroke
				(width 0)
				(type default)
			)
			(fill yes)
			(layer "F.Fab")
		)
		(fp_text user "31"
			(at 0.444246 -3.39852 90)
			(unlocked yes)
			(layer "F.SilkS")
			(effects
				(font
					(size 0.635 0.4064)
					(thickness 0.1524)
				)
				(justify left)
			)
		)
		(fp_text user "30"
			(at 3.223768 -3.0988 0)
			(unlocked yes)
			(layer "F.SilkS")
			(effects
				(font
					(size 0.635 0.4064)
					(thickness 0.1524)
				)
				(justify left)
			)
		)
		(fp_text user "40"
			(at -3.2004 -3.096768 90)
			(unlocked yes)
			(layer "F.SilkS")
			(effects
				(font
					(size 0.635 0.4064)
					(thickness 0.1524)
				)
				(justify left)
			)
		)
		(fp_text user "10"
			(at -3.099562 2.1336 0)
			(unlocked yes)
			(layer "F.SilkS")
			(effects
				(font
					(size 0.635 0.4064)
					(thickness 0.1524)
				)
				(justify left)
			)
		)
		(fp_text user "21"
			(at 2.727198 2.554478 0)
			(unlocked yes)
			(layer "F.SilkS")
			(effects
				(font
					(size 0.635 0.4064)
					(thickness 0.1524)
				)
				(justify left)
			)
		)
		(fp_text user "11"
			(at -2.71653 3.278632 90)
			(unlocked yes)
			(layer "F.SilkS")
			(effects
				(font
					(size 0.635 0.4064)
					(thickness 0.1524)
				)
				(justify left)
			)
		)
		(fp_text user "20"
			(at 0.614426 3.354324 90)
			(unlocked yes)
			(layer "F.SilkS")
			(effects
				(font
					(size 0.635 0.4064)
					(thickness 0.1524)
				)
				(justify left)
			)
		)
		(fp_text user "31"
			(at 1.8542 -3.172968 90)
			(unlocked yes)
			(layer "F.Fab")
			(effects
				(font
					(size 0.635 0.4064)
					(thickness 0.1524)
				)
				(justify left)
			)
		)
		(fp_text user "30"
			(at 3.223768 -3.0988 0)
			(unlocked yes)
			(layer "F.Fab")
			(effects
				(font
					(size 0.635 0.4064)
					(thickness 0.1524)
				)
				(justify left)
			)
		)
		(fp_text user "40"
			(at -3.2004 -3.096768 90)
			(unlocked yes)
			(layer "F.Fab")
			(effects
				(font
					(size 0.635 0.4064)
					(thickness 0.1524)
				)
				(justify left)
			)
		)
		(fp_text user "21"
			(at 3.274568 1.8796 0)
			(unlocked yes)
			(layer "F.Fab")
			(effects
				(font
					(size 0.635 0.4064)
					(thickness 0.1524)
				)
				(justify left)
			)
		)
		(fp_text user "10"
			(at -3.253232 2.1336 0)
			(unlocked yes)
			(layer "F.Fab")
			(effects
				(font
					(size 0.635 0.4064)
					(thickness 0.1524)
				)
				(justify left)
			)
		)
		(fp_text user "20"
			(at 2.0828 3.253232 90)
			(unlocked yes)
			(layer "F.Fab")
			(effects
				(font
					(size 0.635 0.4064)
					(thickness 0.1524)
				)
				(justify left)
			)
		)
		(fp_text user "11"
			(at -2.8702 3.278632 90)
			(unlocked yes)
			(layer "F.Fab")
			(effects
				(font
					(size 0.635 0.4064)
					(thickness 0.1524)
				)
				(justify left)
			)
		)
		(pad "1" smd rect
			(at -2.400046 -1.800098)
			(size 0.1778 0.6096)
			(layers "F.Cu" "F.Mask" "F.Paste")
			(net "P0V8_PEX1_PWM1")
		)
		(pad "2" smd rect
			(at -2.400046 -1.400048)
			(size 0.1778 0.6096)
			(layers "F.Cu" "F.Mask" "F.Paste")
			(net "P0V8_PEX1_PWM2")
		)
		(pad "3" smd rect
			(at -2.400046 -0.999998)
			(size 0.1778 0.6096)
			(layers "F.Cu" "F.Mask" "F.Paste")
			(net "NC_P0V8_PEX0_PWM2")
		)
		(pad "4" smd rect
			(at -2.400046 -0.599948)
			(size 0.1778 0.6096)
			(layers "F.Cu" "F.Mask" "F.Paste")
			(net "NC_P0V8_PEX0_PWM3")
		)
		(pad "5" smd rect
			(at -2.400046 -0.199898)
			(size 0.1778 0.6096)
			(layers "F.Cu" "F.Mask" "F.Paste")
			(net "NC_P0V8_PEX0_PWM4")
		)
		(pad "6" smd rect
			(at -2.400046 0.199898)
			(size 0.1778 0.6096)
			(layers "F.Cu" "F.Mask" "F.Paste")
			(net "NC_P0V8_PEX0_PWM5")
		)
		(pad "7" smd rect
			(at -2.400046 0.599948)
			(size 0.1778 0.6096)
			(layers "F.Cu" "F.Mask" "F.Paste")
			(net "P0V8_PEX0_PWM2")
		)
		(pad "8" smd rect
			(at -2.400046 0.999998)
			(size 0.1778 0.6096)
			(layers "F.Cu" "F.Mask" "F.Paste")
			(net "P0V8_PEX0_PWM1")
		)
		(pad "9" smd rect
			(at -2.400046 1.400048)
			(size 0.1778 0.6096)
			(layers "F.Cu" "F.Mask" "F.Paste")
			(net "SMB_VR_P0V8_PEX0_SDA")
		)
		(pad "10" smd rect
			(at -2.400046 1.800098)
			(size 0.1778 0.6096)
			(layers "F.Cu" "F.Mask" "F.Paste")
			(net "SMB_VR_P0V8_PEX0_SCL")
		)
		(pad "11" smd rect
			(at -1.800098 2.400046 90)
			(size 0.1778 0.6096)
			(layers "F.Cu" "F.Mask" "F.Paste")
			(net "P0V8_PEX0_SMBALERT")
		)
		(pad "12" smd rect
			(at -1.400048 2.400046 90)
			(size 0.1778 0.6096)
			(layers "F.Cu" "F.Mask" "F.Paste")
			(net "P0V8_PEX0_AVRRDY")
		)
		(pad "13" smd rect
			(at -0.999998 2.400046 90)
			(size 0.1778 0.6096)
			(layers "F.Cu" "F.Mask" "F.Paste")
			(net "FM_P0V8_PEX0_EN_R")
		)
		(pad "14" smd rect
			(at -0.599948 2.400046 90)
			(size 0.1778 0.6096)
			(layers "F.Cu" "F.Mask" "F.Paste")
			(net "P0V8_PEX0_VRHOT_R")
		)
		(pad "15" smd rect
			(at -0.199898 2.400046 90)
			(size 0.1778 0.6096)
			(layers "F.Cu" "F.Mask" "F.Paste")
			(net "P0V8_PEX0_PINALRT")
		)
		(pad "16" smd rect
			(at 0.199898 2.400046 90)
			(size 0.1778 0.6096)
			(layers "F.Cu" "F.Mask" "F.Paste")
			(net "P0V8_PEX1_BVRRDY")
		)
		(pad "17" smd rect
			(at 0.599948 2.400046 90)
			(size 0.1778 0.6096)
			(layers "F.Cu" "F.Mask" "F.Paste")
			(net "P0V8_PEX0_SVID")
		)
		(pad "18" smd rect
			(at 0.999998 2.400046 90)
			(size 0.1778 0.6096)
			(layers "F.Cu" "F.Mask" "F.Paste")
			(net "P0V8_PEX0_SVID")
		)
		(pad "19" smd rect
			(at 1.400048 2.400046 90)
			(size 0.1778 0.6096)
			(layers "F.Cu" "F.Mask" "F.Paste")
			(net "NC_P0V8_PEX0_SVID_ALERT_N_R")
		)
		(pad "20" smd rect
			(at 1.800098 2.400046 90)
			(size 0.1778 0.6096)
			(layers "F.Cu" "F.Mask" "F.Paste")
			(net "FM_P0V8_PEX1_EN_R")
		)
		(pad "21" smd rect
			(at 2.400046 1.800098)
			(size 0.1778 0.6096)
			(layers "F.Cu" "F.Mask" "F.Paste")
			(net "P0V8_PEX0_VSEN0")
		)
		(pad "22" smd rect
			(at 2.400046 1.400048)
			(size 0.1778 0.6096)
			(layers "F.Cu" "F.Mask" "F.Paste")
			(net "SH_P0V8_PEX0_RGND0")
		)
		(pad "23" smd rect
			(at 2.400046 0.999998)
			(size 0.1778 0.6096)
			(layers "F.Cu" "F.Mask" "F.Paste")
			(net "P0V8_PEX0_ISEN1")
		)
		(pad "24" smd rect
			(at 2.400046 0.599948)
			(size 0.1778 0.6096)
			(layers "F.Cu" "F.Mask" "F.Paste")
			(net "P0V8_PEX0_ISEN2")
		)
		(pad "25" smd rect
			(at 2.400046 0.199898)
			(size 0.1778 0.6096)
			(layers "F.Cu" "F.Mask" "F.Paste")
			(net "NC_P0V8_PEX0_ISEN5")
		)
		(pad "26" smd rect
			(at 2.400046 -0.199898)
			(size 0.1778 0.6096)
			(layers "F.Cu" "F.Mask" "F.Paste")
			(net "NC_P0V8_PEX0_ISEN4")
		)
		(pad "27" smd rect
			(at 2.400046 -0.599948)
			(size 0.1778 0.6096)
			(layers "F.Cu" "F.Mask" "F.Paste")
			(net "NC_P0V8_PEX0_ISEN3")
		)
		(pad "28" smd rect
			(at 2.400046 -0.999998)
			(size 0.1778 0.6096)
			(layers "F.Cu" "F.Mask" "F.Paste")
			(net "NC_P0V8_PEX0_ISEN2")
		)
		(pad "29" smd rect
			(at 2.400046 -1.400048)
			(size 0.1778 0.6096)
			(layers "F.Cu" "F.Mask" "F.Paste")
			(net "P0V8_PEX1_ISEN2")
		)
		(pad "30" smd rect
			(at 2.400046 -1.800098)
			(size 0.1778 0.6096)
			(layers "F.Cu" "F.Mask" "F.Paste")
			(net "P0V8_PEX1_ISEN1")
		)
		(pad "31" smd rect
			(at 1.800098 -2.400046 90)
			(size 0.1778 0.6096)
			(layers "F.Cu" "F.Mask" "F.Paste")
			(net "SH_P0V8_PEX1_RGND1")
		)
		(pad "32" smd rect
			(at 1.400048 -2.400046 90)
			(size 0.1778 0.6096)
			(layers "F.Cu" "F.Mask" "F.Paste")
			(net "P0V8_PEX1_VSEN1")
		)
		(pad "33" smd rect
			(at 0.999998 -2.400046 90)
			(size 0.1778 0.6096)
			(layers "F.Cu" "F.Mask" "F.Paste")
			(net "P0V8_PEX0_VR_CONFIG")
		)
		(pad "34" smd rect
			(at 0.599948 -2.400046 90)
			(size 0.1778 0.6096)
			(layers "F.Cu" "F.Mask" "F.Paste")
			(net "P0V8_PEX0_ADDR")
		)
		(pad "35" smd rect
			(at 0.199898 -2.400046 90)
			(size 0.1778 0.6096)
			(layers "F.Cu" "F.Mask" "F.Paste")
			(net "P0V8_PEX0_TSEN_R")
		)
		(pad "36" smd rect
			(at -0.199898 -2.400046 90)
			(size 0.1778 0.6096)
			(layers "F.Cu" "F.Mask" "F.Paste")
			(net "P0V8_PEX1_TSEN_R")
		)
		(pad "37" smd rect
			(at -0.599948 -2.400046 90)
			(size 0.1778 0.6096)
			(layers "F.Cu" "F.Mask" "F.Paste")
			(net "P0V8_PEX0_IINSEN")
		)
		(pad "38" smd rect
			(at -0.999998 -2.400046 90)
			(size 0.1778 0.6096)
			(layers "F.Cu" "F.Mask" "F.Paste")
			(net "P0V8_PEX0_VINSEN")
		)
		(pad "39" smd rect
			(at -1.400048 -2.400046 90)
			(size 0.1778 0.6096)
			(layers "F.Cu" "F.Mask" "F.Paste")
			(net "P0V8_PEX0_VDD")
		)
		(pad "40" smd rect
			(at -1.800098 -2.400046 90)
			(size 0.1778 0.6096)
			(layers "F.Cu" "F.Mask" "F.Paste")
			(net "P0V8_PEX0_VREF")
		)
		(pad "TH" smd rect
			(at 0 0 90)
			(size 3.6576 3.6576)
			(layers "F.Cu" "F.Mask" "F.Paste")
			(net "GND")
		)
		(zone
			(layer "F.Cu")
			(hatch none 0.5)
			(connect_pads
				(clearance 0)
			)
			(min_thickness 0.25)
			(keepout
				(tracks not_allowed)
				(vias allowed)
				(pads allowed)
				(copperpour not_allowed)
				(footprints allowed)
			)
			(placement
				(enabled no)
				(sheetname "")
			)
			(fill
				(thermal_gap 0.5)
				(thermal_bridge_width 0.5)
				(island_removal_mode 0)
			)
			(polygon
				(pts
					(xy 118.74373 -256.362962) (xy 118.74373 -260.426962) (xy 122.80773 -260.426962) (xy 122.80773 -256.362962)
					(xy 118.92153 -256.362962) (xy 118.92153 -256.515362) (xy 122.65533 -256.515362) (xy 122.65533 -260.274562)
					(xy 118.89613 -260.274562) (xy 118.89613 -256.362962)
				)
			)
		)
	)
	(footprint ""
		(layer "F.Cu")
		(at 428.754794 -22.961346 90)
		(property "Reference" "R1729"
			(at 0 0 90)
			(layer "F.SilkS")
			(hide yes)
			(effects
				(font
					(size 1.27 1.27)
				)
			)
		)
		(property "Value" ""
			(at 0 0 90)
			(layer "F.Fab")
			(effects
				(font
					(size 1.27 1.27)
				)
			)
		)
		(duplicate_pad_numbers_are_jumpers no)
		(fp_line
			(start 0.7874 -0.4064)
			(end 0.7874 0.4064)
			(stroke
				(width 0.1524)
				(type default)
			)
			(layer "F.SilkS")
		)
		(fp_line
			(start -0.7874 -0.4064)
			(end 0.7874 -0.4064)
			(stroke
				(width 0.1524)
				(type default)
			)
			(layer "F.SilkS")
		)
		(fp_line
			(start 0.7874 0.4064)
			(end -0.7874 0.4064)
			(stroke
				(width 0.1524)
				(type default)
			)
			(layer "F.SilkS")
		)
		(fp_line
			(start -0.7874 0.4064)
			(end -0.7874 -0.4064)
			(stroke
				(width 0.1524)
				(type default)
			)
			(layer "F.SilkS")
		)
		(fp_line
			(start -0.12065 -0.305054)
			(end -0.12065 -0.2794)
			(stroke
				(width 0.1)
				(type default)
			)
			(layer "F.Fab")
		)
		(fp_line
			(start -0.67945 -0.305054)
			(end -0.12065 -0.305054)
			(stroke
				(width 0.1)
				(type default)
			)
			(layer "F.Fab")
		)
		(fp_line
			(start 0.67945 -0.3048)
			(end 0.67945 0.3048)
			(stroke
				(width 0.1)
				(type default)
			)
			(layer "F.Fab")
		)
		(fp_line
			(start 0.12065 -0.3048)
			(end 0.67945 -0.3048)
			(stroke
				(width 0.1)
				(type default)
			)
			(layer "F.Fab")
		)
		(fp_line
			(start 0.12065 -0.2794)
			(end 0.12065 -0.3048)
			(stroke
				(width 0.1)
				(type default)
			)
			(layer "F.Fab")
		)
		(fp_line
			(start -0.12065 -0.2794)
			(end 0.12065 -0.2794)
			(stroke
				(width 0.1)
				(type default)
			)
			(layer "F.Fab")
		)
		(fp_line
			(start 0.120396 0.2794)
			(end -0.12065 0.2794)
			(stroke
				(width 0.1)
				(type default)
			)
			(layer "F.Fab")
		)
		(fp_line
			(start -0.12065 0.2794)
			(end -0.12065 0.3048)
			(stroke
				(width 0.1)
				(type default)
			)
			(layer "F.Fab")
		)
		(fp_line
			(start 0.67945 0.3048)
			(end 0.120396 0.3048)
			(stroke
				(width 0.1)
				(type default)
			)
			(layer "F.Fab")
		)
		(fp_line
			(start 0.120396 0.3048)
			(end 0.120396 0.2794)
			(stroke
				(width 0.1)
				(type default)
			)
			(layer "F.Fab")
		)
		(fp_line
			(start -0.12065 0.3048)
			(end -0.67945 0.3048)
			(stroke
				(width 0.1)
				(type default)
			)
			(layer "F.Fab")
		)
		(fp_line
			(start -0.67945 0.3048)
			(end -0.67945 -0.305054)
			(stroke
				(width 0.1)
				(type default)
			)
			(layer "F.Fab")
		)
		(pad "1" smd circle
			(at -0.40005 0 90)
			(size 0 0)
			(layers "F.Cu" "F.Mask" "F.Paste")
			(net "SMB_SSD14_ISO_EN")
		)
		(pad "2" smd circle
			(at 0.40005 0 90)
			(size 0 0)
			(layers "F.Cu" "F.Mask" "F.Paste")
			(net "P3V3_AUX")
		)
	)
	(footprint ""
		(layer "F.Cu")
		(at 178.619912 -350.098614 90)
		(property "Reference" "C387"
			(at 0 0 90)
			(layer "F.SilkS")
			(hide yes)
			(effects
				(font
					(size 1.27 1.27)
				)
			)
		)
		(property "Value" ""
			(at 0 0 90)
			(layer "F.Fab")
			(effects
				(font
					(size 1.27 1.27)
				)
			)
		)
		(duplicate_pad_numbers_are_jumpers no)
		(fp_line
			(start 0.299974 -0.150114)
			(end 0.299974 0.150114)
			(stroke
				(width 0.1)
				(type default)
			)
			(layer "F.Fab")
		)
		(fp_line
			(start -0.299974 -0.150114)
			(end 0.299974 -0.150114)
			(stroke
				(width 0.1)
				(type default)
			)
			(layer "F.Fab")
		)
		(fp_line
			(start 0.299974 0.150114)
			(end -0.299974 0.150114)
			(stroke
				(width 0.1)
				(type default)
			)
			(layer "F.Fab")
		)
		(fp_line
			(start -0.299974 0.150114)
			(end -0.299974 -0.150114)
			(stroke
				(width 0.1)
				(type default)
			)
			(layer "F.Fab")
		)
		(pad "1" smd rect
			(at -0.2667 0 90)
			(size 0.3048 0.381)
			(layers "F.Cu" "F.Mask" "F.Paste")
			(net "P5E_PEX1_STN7_TX_DN<120>")
		)
		(pad "2" smd rect
			(at 0.2667 0 90)
			(size 0.3048 0.381)
			(layers "F.Cu" "F.Mask" "F.Paste")
			(net "P5E_PEX1_STN7_TX_C_DN<120>")
		)
	)
	(footprint ""
		(layer "F.Cu")
		(at 213.6267 -55.418228 90)
		(property "Reference" "PC394"
			(at 0 0 90)
			(layer "F.SilkS")
			(hide yes)
			(effects
				(font
					(size 1.27 1.27)
				)
			)
		)
		(property "Value" ""
			(at 0 0 90)
			(layer "F.Fab")
			(effects
				(font
					(size 1.27 1.27)
				)
			)
		)
		(duplicate_pad_numbers_are_jumpers no)
		(fp_line
			(start 0.7874 -0.4064)
			(end 0.7874 0.4064)
			(stroke
				(width 0.1524)
				(type default)
			)
			(layer "F.SilkS")
		)
		(fp_line
			(start -0.7874 -0.4064)
			(end 0.7874 -0.4064)
			(stroke
				(width 0.1524)
				(type default)
			)
			(layer "F.SilkS")
		)
		(fp_line
			(start 0.7874 0.4064)
			(end -0.7874 0.4064)
			(stroke
				(width 0.1524)
				(type default)
			)
			(layer "F.SilkS")
		)
		(fp_line
			(start -0.7874 0.4064)
			(end -0.7874 -0.4064)
			(stroke
				(width 0.1524)
				(type default)
			)
			(layer "F.SilkS")
		)
		(fp_line
			(start -0.12065 -0.305054)
			(end -0.12065 -0.2794)
			(stroke
				(width 0.1)
				(type default)
			)
			(layer "F.Fab")
		)
		(fp_line
			(start -0.67945 -0.305054)
			(end -0.12065 -0.305054)
			(stroke
				(width 0.1)
				(type default)
			)
			(layer "F.Fab")
		)
		(fp_line
			(start 0.67945 -0.3048)
			(end 0.67945 0.3048)
			(stroke
				(width 0.1)
				(type default)
			)
			(layer "F.Fab")
		)
		(fp_line
			(start 0.12065 -0.3048)
			(end 0.67945 -0.3048)
			(stroke
				(width 0.1)
				(type default)
			)
			(layer "F.Fab")
		)
		(fp_line
			(start 0.12065 -0.2794)
			(end 0.12065 -0.3048)
			(stroke
				(width 0.1)
				(type default)
			)
			(layer "F.Fab")
		)
		(fp_line
			(start -0.12065 -0.2794)
			(end 0.12065 -0.2794)
			(stroke
				(width 0.1)
				(type default)
			)
			(layer "F.Fab")
		)
		(fp_line
			(start 0.120396 0.2794)
			(end -0.12065 0.2794)
			(stroke
				(width 0.1)
				(type default)
			)
			(layer "F.Fab")
		)
		(fp_line
			(start -0.12065 0.2794)
			(end -0.12065 0.3048)
			(stroke
				(width 0.1)
				(type default)
			)
			(layer "F.Fab")
		)
		(fp_line
			(start 0.67945 0.3048)
			(end 0.120396 0.3048)
			(stroke
				(width 0.1)
				(type default)
			)
			(layer "F.Fab")
		)
		(fp_line
			(start 0.120396 0.3048)
			(end 0.120396 0.2794)
			(stroke
				(width 0.1)
				(type default)
			)
			(layer "F.Fab")
		)
		(fp_line
			(start -0.12065 0.3048)
			(end -0.67945 0.3048)
			(stroke
				(width 0.1)
				(type default)
			)
			(layer "F.Fab")
		)
		(fp_line
			(start -0.67945 0.3048)
			(end -0.67945 -0.305054)
			(stroke
				(width 0.1)
				(type default)
			)
			(layer "F.Fab")
		)
		(pad "1" smd circle
			(at -0.40005 0 90)
			(size 0 0)
			(layers "F.Cu" "F.Mask" "F.Paste")
			(net "P12V_SSD7_R")
		)
		(pad "2" smd circle
			(at 0.40005 0 90)
			(size 0 0)
			(layers "F.Cu" "F.Mask" "F.Paste")
			(net "GND")
		)
	)
	(footprint ""
		(layer "F.Cu")
		(at 265.686286 -250.070874 -90)
		(property "Reference" "R1333"
			(at 0 0 270)
			(layer "F.SilkS")
			(hide yes)
			(effects
				(font
					(size 1.27 1.27)
				)
			)
		)
		(property "Value" ""
			(at 0 0 270)
			(layer "F.Fab")
			(effects
				(font
					(size 1.27 1.27)
				)
			)
		)
		(duplicate_pad_numbers_are_jumpers no)
		(fp_line
			(start -0.7874 0.4064)
			(end -0.7874 -0.4064)
			(stroke
				(width 0.1524)
				(type default)
			)
			(layer "F.SilkS")
		)
		(fp_line
			(start 0.7874 0.4064)
			(end -0.7874 0.4064)
			(stroke
				(width 0.1524)
				(type default)
			)
			(layer "F.SilkS")
		)
		(fp_line
			(start -0.7874 -0.4064)
			(end 0.7874 -0.4064)
			(stroke
				(width 0.1524)
				(type default)
			)
			(layer "F.SilkS")
		)
		(fp_line
			(start 0.7874 -0.4064)
			(end 0.7874 0.4064)
			(stroke
				(width 0.1524)
				(type default)
			)
			(layer "F.SilkS")
		)
		(fp_line
			(start -0.67945 0.3048)
			(end -0.67945 -0.305054)
			(stroke
				(width 0.1)
				(type default)
			)
			(layer "F.Fab")
		)
		(fp_line
			(start -0.12065 0.3048)
			(end -0.67945 0.3048)
			(stroke
				(width 0.1)
				(type default)
			)
			(layer "F.Fab")
		)
		(fp_line
			(start 0.120396 0.3048)
			(end 0.120396 0.2794)
			(stroke
				(width 0.1)
				(type default)
			)
			(layer "F.Fab")
		)
		(fp_line
			(start 0.67945 0.3048)
			(end 0.120396 0.3048)
			(stroke
				(width 0.1)
				(type default)
			)
			(layer "F.Fab")
		)
		(fp_line
			(start -0.12065 0.2794)
			(end -0.12065 0.3048)
			(stroke
				(width 0.1)
				(type default)
			)
			(layer "F.Fab")
		)
		(fp_line
			(start 0.120396 0.2794)
			(end -0.12065 0.2794)
			(stroke
				(width 0.1)
				(type default)
			)
			(layer "F.Fab")
		)
		(fp_line
			(start -0.12065 -0.2794)
			(end 0.12065 -0.2794)
			(stroke
				(width 0.1)
				(type default)
			)
			(layer "F.Fab")
		)
		(fp_line
			(start 0.12065 -0.2794)
			(end 0.12065 -0.3048)
			(stroke
				(width 0.1)
				(type default)
			)
			(layer "F.Fab")
		)
		(fp_line
			(start 0.12065 -0.3048)
			(end 0.67945 -0.3048)
			(stroke
				(width 0.1)
				(type default)
			)
			(layer "F.Fab")
		)
		(fp_line
			(start 0.67945 -0.3048)
			(end 0.67945 0.3048)
			(stroke
				(width 0.1)
				(type default)
			)
			(layer "F.Fab")
		)
		(fp_line
			(start -0.67945 -0.305054)
			(end -0.12065 -0.305054)
			(stroke
				(width 0.1)
				(type default)
			)
			(layer "F.Fab")
		)
		(fp_line
			(start -0.12065 -0.305054)
			(end -0.12065 -0.2794)
			(stroke
				(width 0.1)
				(type default)
			)
			(layer "F.Fab")
		)
		(pad "1" smd circle
			(at -0.40005 0 270)
			(size 0 0)
			(layers "F.Cu" "F.Mask" "F.Paste")
			(net "PEX2_DBG_MODE2")
		)
		(pad "2" smd circle
			(at 0.40005 0 270)
			(size 0 0)
			(layers "F.Cu" "F.Mask" "F.Paste")
			(net "P1V8_PEX")
		)
	)
	(footprint ""
		(layer "F.Cu")
		(at 32.71139 -27.04973 180)
		(property "Reference" "C2763"
			(at 0 0 180)
			(layer "F.SilkS")
			(hide yes)
			(effects
				(font
					(size 1.27 1.27)
				)
			)
		)
		(property "Value" ""
			(at 0 0 180)
			(layer "F.Fab")
			(effects
				(font
					(size 1.27 1.27)
				)
			)
		)
		(duplicate_pad_numbers_are_jumpers no)
		(fp_line
			(start 0.7874 0.4064)
			(end -0.7874 0.4064)
			(stroke
				(width 0.1524)
				(type default)
			)
			(layer "F.SilkS")
		)
		(fp_line
			(start 0.7874 -0.4064)
			(end 0.7874 0.4064)
			(stroke
				(width 0.1524)
				(type default)
			)
			(layer "F.SilkS")
		)
		(fp_line
			(start -0.7874 0.4064)
			(end -0.7874 -0.4064)
			(stroke
				(width 0.1524)
				(type default)
			)
			(layer "F.SilkS")
		)
		(fp_line
			(start -0.7874 -0.4064)
			(end 0.7874 -0.4064)
			(stroke
				(width 0.1524)
				(type default)
			)
			(layer "F.SilkS")
		)
		(fp_line
			(start 0.67945 0.3048)
			(end 0.120396 0.3048)
			(stroke
				(width 0.1)
				(type default)
			)
			(layer "F.Fab")
		)
		(fp_line
			(start 0.67945 -0.3048)
			(end 0.67945 0.3048)
			(stroke
				(width 0.1)
				(type default)
			)
			(layer "F.Fab")
		)
		(fp_line
			(start 0.12065 -0.2794)
			(end 0.12065 -0.3048)
			(stroke
				(width 0.1)
				(type default)
			)
			(layer "F.Fab")
		)
		(fp_line
			(start 0.12065 -0.3048)
			(end 0.67945 -0.3048)
			(stroke
				(width 0.1)
				(type default)
			)
			(layer "F.Fab")
		)
		(fp_line
			(start 0.120396 0.3048)
			(end 0.120396 0.2794)
			(stroke
				(width 0.1)
				(type default)
			)
			(layer "F.Fab")
		)
		(fp_line
			(start 0.120396 0.2794)
			(end -0.12065 0.2794)
			(stroke
				(width 0.1)
				(type default)
			)
			(layer "F.Fab")
		)
		(fp_line
			(start -0.12065 0.3048)
			(end -0.67945 0.3048)
			(stroke
				(width 0.1)
				(type default)
			)
			(layer "F.Fab")
		)
		(fp_line
			(start -0.12065 0.2794)
			(end -0.12065 0.3048)
			(stroke
				(width 0.1)
				(type default)
			)
			(layer "F.Fab")
		)
		(fp_line
			(start -0.12065 -0.2794)
			(end 0.12065 -0.2794)
			(stroke
				(width 0.1)
				(type default)
			)
			(layer "F.Fab")
		)
		(fp_line
			(start -0.12065 -0.305054)
			(end -0.12065 -0.2794)
			(stroke
				(width 0.1)
				(type default)
			)
			(layer "F.Fab")
		)
		(fp_line
			(start -0.67945 0.3048)
			(end -0.67945 -0.305054)
			(stroke
				(width 0.1)
				(type default)
			)
			(layer "F.Fab")
		)
		(fp_line
			(start -0.67945 -0.305054)
			(end -0.12065 -0.305054)
			(stroke
				(width 0.1)
				(type default)
			)
			(layer "F.Fab")
		)
		(pad "1" smd circle
			(at -0.40005 0 180)
			(size 0 0)
			(layers "F.Cu" "F.Mask" "F.Paste")
			(net "PRSNT_SSD1_R_N")
		)
		(pad "2" smd circle
			(at 0.40005 0 180)
			(size 0 0)
			(layers "F.Cu" "F.Mask" "F.Paste")
			(net "GND")
		)
	)
	(footprint ""
		(layer "F.Cu")
		(at 173.00194 -32.849312 90)
		(property "Reference" "R5678"
			(at 0 0 90)
			(layer "F.SilkS")
			(hide yes)
			(effects
				(font
					(size 1.27 1.27)
				)
			)
		)
		(property "Value" ""
			(at 0 0 90)
			(layer "F.Fab")
			(effects
				(font
					(size 1.27 1.27)
				)
			)
		)
		(duplicate_pad_numbers_are_jumpers no)
		(fp_line
			(start 0.7874 -0.4064)
			(end 0.7874 0.4064)
			(stroke
				(width 0.1524)
				(type default)
			)
			(layer "F.SilkS")
		)
		(fp_line
			(start -0.7874 -0.4064)
			(end 0.7874 -0.4064)
			(stroke
				(width 0.1524)
				(type default)
			)
			(layer "F.SilkS")
		)
		(fp_line
			(start 0.7874 0.4064)
			(end -0.7874 0.4064)
			(stroke
				(width 0.1524)
				(type default)
			)
			(layer "F.SilkS")
		)
		(fp_line
			(start -0.7874 0.4064)
			(end -0.7874 -0.4064)
			(stroke
				(width 0.1524)
				(type default)
			)
			(layer "F.SilkS")
		)
		(fp_line
			(start -0.12065 -0.305054)
			(end -0.12065 -0.2794)
			(stroke
				(width 0.1)
				(type default)
			)
			(layer "F.Fab")
		)
		(fp_line
			(start -0.67945 -0.305054)
			(end -0.12065 -0.305054)
			(stroke
				(width 0.1)
				(type default)
			)
			(layer "F.Fab")
		)
		(fp_line
			(start 0.67945 -0.3048)
			(end 0.67945 0.3048)
			(stroke
				(width 0.1)
				(type default)
			)
			(layer "F.Fab")
		)
		(fp_line
			(start 0.12065 -0.3048)
			(end 0.67945 -0.3048)
			(stroke
				(width 0.1)
				(type default)
			)
			(layer "F.Fab")
		)
		(fp_line
			(start 0.12065 -0.2794)
			(end 0.12065 -0.3048)
			(stroke
				(width 0.1)
				(type default)
			)
			(layer "F.Fab")
		)
		(fp_line
			(start -0.12065 -0.2794)
			(end 0.12065 -0.2794)
			(stroke
				(width 0.1)
				(type default)
			)
			(layer "F.Fab")
		)
		(fp_line
			(start 0.120396 0.2794)
			(end -0.12065 0.2794)
			(stroke
				(width 0.1)
				(type default)
			)
			(layer "F.Fab")
		)
		(fp_line
			(start -0.12065 0.2794)
			(end -0.12065 0.3048)
			(stroke
				(width 0.1)
				(type default)
			)
			(layer "F.Fab")
		)
		(fp_line
			(start 0.67945 0.3048)
			(end 0.120396 0.3048)
			(stroke
				(width 0.1)
				(type default)
			)
			(layer "F.Fab")
		)
		(fp_line
			(start 0.120396 0.3048)
			(end 0.120396 0.2794)
			(stroke
				(width 0.1)
				(type default)
			)
			(layer "F.Fab")
		)
		(fp_line
			(start -0.12065 0.3048)
			(end -0.67945 0.3048)
			(stroke
				(width 0.1)
				(type default)
			)
			(layer "F.Fab")
		)
		(fp_line
			(start -0.67945 0.3048)
			(end -0.67945 -0.305054)
			(stroke
				(width 0.1)
				(type default)
			)
			(layer "F.Fab")
		)
		(pad "1" smd circle
			(at -0.40005 0 90)
			(size 0 0)
			(layers "F.Cu" "F.Mask" "F.Paste")
			(net "RST_SMB_SSD6_ISO_R_N")
		)
		(pad "2" smd circle
			(at 0.40005 0 90)
			(size 0 0)
			(layers "F.Cu" "F.Mask" "F.Paste")
			(net "RST_SMB_SSD6_ISO_N")
		)
	)
	(footprint ""
		(layer "F.Cu")
		(at 430.961546 -132.601208 180)
		(property "Reference" "C654"
			(at 0 0 180)
			(layer "F.SilkS")
			(hide yes)
			(effects
				(font
					(size 1.27 1.27)
				)
			)
		)
		(property "Value" ""
			(at 0 0 180)
			(layer "F.Fab")
			(effects
				(font
					(size 1.27 1.27)
				)
			)
		)
		(duplicate_pad_numbers_are_jumpers no)
		(fp_line
			(start 0.299974 0.150114)
			(end -0.299974 0.150114)
			(stroke
				(width 0.1)
				(type default)
			)
			(layer "F.Fab")
		)
		(fp_line
			(start 0.299974 -0.150114)
			(end 0.299974 0.150114)
			(stroke
				(width 0.1)
				(type default)
			)
			(layer "F.Fab")
		)
		(fp_line
			(start -0.299974 0.150114)
			(end -0.299974 -0.150114)
			(stroke
				(width 0.1)
				(type default)
			)
			(layer "F.Fab")
		)
		(fp_line
			(start -0.299974 -0.150114)
			(end 0.299974 -0.150114)
			(stroke
				(width 0.1)
				(type default)
			)
			(layer "F.Fab")
		)
		(pad "1" smd rect
			(at -0.2667 0 180)
			(size 0.3048 0.381)
			(layers "F.Cu" "F.Mask" "F.Paste")
			(net "P5E_PEX3_STN0_TX_DP<5>")
		)
		(pad "2" smd rect
			(at 0.2667 0 180)
			(size 0.3048 0.381)
			(layers "F.Cu" "F.Mask" "F.Paste")
			(net "P5E_PEX3_STN0_TX_C_DP<5>")
		)
	)
	(footprint ""
		(layer "F.Cu")
		(at 375.252742 -262.649208 90)
		(property "Reference" "C3593"
			(at 0 0 90)
			(layer "F.SilkS")
			(hide yes)
			(effects
				(font
					(size 1.27 1.27)
				)
			)
		)
		(property "Value" ""
			(at 0 0 90)
			(layer "F.Fab")
			(effects
				(font
					(size 1.27 1.27)
				)
			)
		)
		(duplicate_pad_numbers_are_jumpers no)
		(fp_line
			(start 0.299974 -0.150114)
			(end 0.299974 0.150114)
			(stroke
				(width 0.1)
				(type default)
			)
			(layer "F.Fab")
		)
		(fp_line
			(start -0.299974 -0.150114)
			(end 0.299974 -0.150114)
			(stroke
				(width 0.1)
				(type default)
			)
			(layer "F.Fab")
		)
		(fp_line
			(start 0.299974 0.150114)
			(end -0.299974 0.150114)
			(stroke
				(width 0.1)
				(type default)
			)
			(layer "F.Fab")
		)
		(fp_line
			(start -0.299974 0.150114)
			(end -0.299974 -0.150114)
			(stroke
				(width 0.1)
				(type default)
			)
			(layer "F.Fab")
		)
		(pad "1" smd rect
			(at -0.2667 0 90)
			(size 0.3048 0.381)
			(layers "F.Cu" "F.Mask" "F.Paste")
			(net "P1V8_VDDA_PEX3")
		)
		(pad "2" smd rect
			(at 0.2667 0 90)
			(size 0.3048 0.381)
			(layers "F.Cu" "F.Mask" "F.Paste")
			(net "GND")
		)
	)
	(footprint ""
		(layer "F.Cu")
		(at 204.93609 -289.230816 90)
		(property "Reference" "R3940"
			(at 0 0 90)
			(layer "F.SilkS")
			(hide yes)
			(effects
				(font
					(size 1.27 1.27)
				)
			)
		)
		(property "Value" ""
			(at 0 0 90)
			(layer "F.Fab")
			(effects
				(font
					(size 1.27 1.27)
				)
			)
		)
		(duplicate_pad_numbers_are_jumpers no)
		(fp_line
			(start 0.7874 -0.4064)
			(end 0.7874 0.4064)
			(stroke
				(width 0.1524)
				(type default)
			)
			(layer "F.SilkS")
		)
		(fp_line
			(start -0.7874 -0.4064)
			(end 0.7874 -0.4064)
			(stroke
				(width 0.1524)
				(type default)
			)
			(layer "F.SilkS")
		)
		(fp_line
			(start 0.7874 0.4064)
			(end -0.7874 0.4064)
			(stroke
				(width 0.1524)
				(type default)
			)
			(layer "F.SilkS")
		)
		(fp_line
			(start -0.7874 0.4064)
			(end -0.7874 -0.4064)
			(stroke
				(width 0.1524)
				(type default)
			)
			(layer "F.SilkS")
		)
		(fp_line
			(start -0.12065 -0.305054)
			(end -0.12065 -0.2794)
			(stroke
				(width 0.1)
				(type default)
			)
			(layer "F.Fab")
		)
		(fp_line
			(start -0.67945 -0.305054)
			(end -0.12065 -0.305054)
			(stroke
				(width 0.1)
				(type default)
			)
			(layer "F.Fab")
		)
		(fp_line
			(start 0.67945 -0.3048)
			(end 0.67945 0.3048)
			(stroke
				(width 0.1)
				(type default)
			)
			(layer "F.Fab")
		)
		(fp_line
			(start 0.12065 -0.3048)
			(end 0.67945 -0.3048)
			(stroke
				(width 0.1)
				(type default)
			)
			(layer "F.Fab")
		)
		(fp_line
			(start 0.12065 -0.2794)
			(end 0.12065 -0.3048)
			(stroke
				(width 0.1)
				(type default)
			)
			(layer "F.Fab")
		)
		(fp_line
			(start -0.12065 -0.2794)
			(end 0.12065 -0.2794)
			(stroke
				(width 0.1)
				(type default)
			)
			(layer "F.Fab")
		)
		(fp_line
			(start 0.120396 0.2794)
			(end -0.12065 0.2794)
			(stroke
				(width 0.1)
				(type default)
			)
			(layer "F.Fab")
		)
		(fp_line
			(start -0.12065 0.2794)
			(end -0.12065 0.3048)
			(stroke
				(width 0.1)
				(type default)
			)
			(layer "F.Fab")
		)
		(fp_line
			(start 0.67945 0.3048)
			(end 0.120396 0.3048)
			(stroke
				(width 0.1)
				(type default)
			)
			(layer "F.Fab")
		)
		(fp_line
			(start 0.120396 0.3048)
			(end 0.120396 0.2794)
			(stroke
				(width 0.1)
				(type default)
			)
			(layer "F.Fab")
		)
		(fp_line
			(start -0.12065 0.3048)
			(end -0.67945 0.3048)
			(stroke
				(width 0.1)
				(type default)
			)
			(layer "F.Fab")
		)
		(fp_line
			(start -0.67945 0.3048)
			(end -0.67945 -0.305054)
			(stroke
				(width 0.1)
				(type default)
			)
			(layer "F.Fab")
		)
		(pad "1" smd circle
			(at -0.40005 0 90)
			(size 0 0)
			(layers "F.Cu" "F.Mask" "F.Paste")
			(net "SMB_PEX1_FPGA_SDA")
		)
		(pad "2" smd circle
			(at 0.40005 0 90)
			(size 0 0)
			(layers "F.Cu" "F.Mask" "F.Paste")
			(net "SMB_PEX1_HOST_LS_SDA")
		)
	)
	(footprint ""
		(layer "F.Cu")
		(at 13.220192 -394.130784 -90)
		(property "Reference" "R6745"
			(at 0 0 270)
			(layer "F.SilkS")
			(hide yes)
			(effects
				(font
					(size 1.27 1.27)
				)
			)
		)
		(property "Value" ""
			(at 0 0 270)
			(layer "F.Fab")
			(effects
				(font
					(size 1.27 1.27)
				)
			)
		)
		(duplicate_pad_numbers_are_jumpers no)
		(fp_line
			(start -0.7874 0.4064)
			(end -0.7874 -0.4064)
			(stroke
				(width 0.1524)
				(type default)
			)
			(layer "F.SilkS")
		)
		(fp_line
			(start 0.7874 0.4064)
			(end -0.7874 0.4064)
			(stroke
				(width 0.1524)
				(type default)
			)
			(layer "F.SilkS")
		)
		(fp_line
			(start -0.7874 -0.4064)
			(end 0.7874 -0.4064)
			(stroke
				(width 0.1524)
				(type default)
			)
			(layer "F.SilkS")
		)
		(fp_line
			(start 0.7874 -0.4064)
			(end 0.7874 0.4064)
			(stroke
				(width 0.1524)
				(type default)
			)
			(layer "F.SilkS")
		)
		(fp_line
			(start -0.67945 0.3048)
			(end -0.67945 -0.305054)
			(stroke
				(width 0.1)
				(type default)
			)
			(layer "F.Fab")
		)
		(fp_line
			(start -0.12065 0.3048)
			(end -0.67945 0.3048)
			(stroke
				(width 0.1)
				(type default)
			)
			(layer "F.Fab")
		)
		(fp_line
			(start 0.120396 0.3048)
			(end 0.120396 0.2794)
			(stroke
				(width 0.1)
				(type default)
			)
			(layer "F.Fab")
		)
		(fp_line
			(start 0.67945 0.3048)
			(end 0.120396 0.3048)
			(stroke
				(width 0.1)
				(type default)
			)
			(layer "F.Fab")
		)
		(fp_line
			(start -0.12065 0.2794)
			(end -0.12065 0.3048)
			(stroke
				(width 0.1)
				(type default)
			)
			(layer "F.Fab")
		)
		(fp_line
			(start 0.120396 0.2794)
			(end -0.12065 0.2794)
			(stroke
				(width 0.1)
				(type default)
			)
			(layer "F.Fab")
		)
		(fp_line
			(start -0.12065 -0.2794)
			(end 0.12065 -0.2794)
			(stroke
				(width 0.1)
				(type default)
			)
			(layer "F.Fab")
		)
		(fp_line
			(start 0.12065 -0.2794)
			(end 0.12065 -0.3048)
			(stroke
				(width 0.1)
				(type default)
			)
			(layer "F.Fab")
		)
		(fp_line
			(start 0.12065 -0.3048)
			(end 0.67945 -0.3048)
			(stroke
				(width 0.1)
				(type default)
			)
			(layer "F.Fab")
		)
		(fp_line
			(start 0.67945 -0.3048)
			(end 0.67945 0.3048)
			(stroke
				(width 0.1)
				(type default)
			)
			(layer "F.Fab")
		)
		(fp_line
			(start -0.67945 -0.305054)
			(end -0.12065 -0.305054)
			(stroke
				(width 0.1)
				(type default)
			)
			(layer "F.Fab")
		)
		(fp_line
			(start -0.12065 -0.305054)
			(end -0.12065 -0.2794)
			(stroke
				(width 0.1)
				(type default)
			)
			(layer "F.Fab")
		)
		(pad "1" smd circle
			(at -0.40005 0 270)
			(size 0 0)
			(layers "F.Cu" "F.Mask" "F.Paste")
			(net "GND")
		)
		(pad "2" smd circle
			(at 0.40005 0 270)
			(size 0 0)
			(layers "F.Cu" "F.Mask" "F.Paste")
			(net "BIC_USB_8042_HUB_GANGED")
		)
	)
	(footprint ""
		(layer "F.Cu")
		(at 60.437268 -393.16279 -90)
		(property "Reference" "C4010"
			(at 0 0 270)
			(layer "F.SilkS")
			(hide yes)
			(effects
				(font
					(size 1.27 1.27)
				)
			)
		)
		(property "Value" ""
			(at 0 0 270)
			(layer "F.Fab")
			(effects
				(font
					(size 1.27 1.27)
				)
			)
		)
		(duplicate_pad_numbers_are_jumpers no)
		(fp_line
			(start -0.7874 0.4064)
			(end -0.7874 -0.4064)
			(stroke
				(width 0.1524)
				(type default)
			)
			(layer "F.SilkS")
		)
		(fp_line
			(start 0.7874 0.4064)
			(end -0.7874 0.4064)
			(stroke
				(width 0.1524)
				(type default)
			)
			(layer "F.SilkS")
		)
		(fp_line
			(start -0.7874 -0.4064)
			(end 0.7874 -0.4064)
			(stroke
				(width 0.1524)
				(type default)
			)
			(layer "F.SilkS")
		)
		(fp_line
			(start 0.7874 -0.4064)
			(end 0.7874 0.4064)
			(stroke
				(width 0.1524)
				(type default)
			)
			(layer "F.SilkS")
		)
		(fp_line
			(start -0.67945 0.3048)
			(end -0.67945 -0.305054)
			(stroke
				(width 0.1)
				(type default)
			)
			(layer "F.Fab")
		)
		(fp_line
			(start -0.12065 0.3048)
			(end -0.67945 0.3048)
			(stroke
				(width 0.1)
				(type default)
			)
			(layer "F.Fab")
		)
		(fp_line
			(start 0.120396 0.3048)
			(end 0.120396 0.2794)
			(stroke
				(width 0.1)
				(type default)
			)
			(layer "F.Fab")
		)
		(fp_line
			(start 0.67945 0.3048)
			(end 0.120396 0.3048)
			(stroke
				(width 0.1)
				(type default)
			)
			(layer "F.Fab")
		)
		(fp_line
			(start -0.12065 0.2794)
			(end -0.12065 0.3048)
			(stroke
				(width 0.1)
				(type default)
			)
			(layer "F.Fab")
		)
		(fp_line
			(start 0.120396 0.2794)
			(end -0.12065 0.2794)
			(stroke
				(width 0.1)
				(type default)
			)
			(layer "F.Fab")
		)
		(fp_line
			(start -0.12065 -0.2794)
			(end 0.12065 -0.2794)
			(stroke
				(width 0.1)
				(type default)
			)
			(layer "F.Fab")
		)
		(fp_line
			(start 0.12065 -0.2794)
			(end 0.12065 -0.3048)
			(stroke
				(width 0.1)
				(type default)
			)
			(layer "F.Fab")
		)
		(fp_line
			(start 0.12065 -0.3048)
			(end 0.67945 -0.3048)
			(stroke
				(width 0.1)
				(type default)
			)
			(layer "F.Fab")
		)
		(fp_line
			(start 0.67945 -0.3048)
			(end 0.67945 0.3048)
			(stroke
				(width 0.1)
				(type default)
			)
			(layer "F.Fab")
		)
		(fp_line
			(start -0.67945 -0.305054)
			(end -0.12065 -0.305054)
			(stroke
				(width 0.1)
				(type default)
			)
			(layer "F.Fab")
		)
		(fp_line
			(start -0.12065 -0.305054)
			(end -0.12065 -0.2794)
			(stroke
				(width 0.1)
				(type default)
			)
			(layer "F.Fab")
		)
		(pad "1" smd circle
			(at -0.40005 0 270)
			(size 0 0)
			(layers "F.Cu" "F.Mask" "F.Paste")
			(net "GND")
		)
		(pad "2" smd circle
			(at 0.40005 0 270)
			(size 0 0)
			(layers "F.Cu" "F.Mask" "F.Paste")
			(net "GPU_HGX_DETECT_N")
		)
	)
	(footprint ""
		(layer "F.Cu")
		(at 431.032412 -356.244906 90)
		(property "Reference" "C2461"
			(at 0 0 90)
			(layer "F.SilkS")
			(hide yes)
			(effects
				(font
					(size 1.27 1.27)
				)
			)
		)
		(property "Value" ""
			(at 0 0 90)
			(layer "F.Fab")
			(effects
				(font
					(size 1.27 1.27)
				)
			)
		)
		(duplicate_pad_numbers_are_jumpers no)
		(fp_line
			(start 0.299974 -0.150114)
			(end 0.299974 0.150114)
			(stroke
				(width 0.1)
				(type default)
			)
			(layer "F.Fab")
		)
		(fp_line
			(start -0.299974 -0.150114)
			(end 0.299974 -0.150114)
			(stroke
				(width 0.1)
				(type default)
			)
			(layer "F.Fab")
		)
		(fp_line
			(start 0.299974 0.150114)
			(end -0.299974 0.150114)
			(stroke
				(width 0.1)
				(type default)
			)
			(layer "F.Fab")
		)
		(fp_line
			(start -0.299974 0.150114)
			(end -0.299974 -0.150114)
			(stroke
				(width 0.1)
				(type default)
			)
			(layer "F.Fab")
		)
		(pad "1" smd rect
			(at -0.2667 0 90)
			(size 0.3048 0.381)
			(layers "F.Cu" "F.Mask" "F.Paste")
			(net "P5E_PEX3_STN4_TX_DP<68>")
		)
		(pad "2" smd rect
			(at 0.2667 0 90)
			(size 0.3048 0.381)
			(layers "F.Cu" "F.Mask" "F.Paste")
			(net "P5E_PEX3_STN4_TX_C_DP<68>")
		)
	)
	(footprint ""
		(layer "F.Cu")
		(at 89.0016 -304.036476 90)
		(property "Reference" "R1247"
			(at 0 0 90)
			(layer "F.SilkS")
			(hide yes)
			(effects
				(font
					(size 1.27 1.27)
				)
			)
		)
		(property "Value" ""
			(at 0 0 90)
			(layer "F.Fab")
			(effects
				(font
					(size 1.27 1.27)
				)
			)
		)
		(duplicate_pad_numbers_are_jumpers no)
		(fp_line
			(start 0.7874 -0.4064)
			(end 0.7874 0.4064)
			(stroke
				(width 0.1524)
				(type default)
			)
			(layer "F.SilkS")
		)
		(fp_line
			(start -0.7874 -0.4064)
			(end 0.7874 -0.4064)
			(stroke
				(width 0.1524)
				(type default)
			)
			(layer "F.SilkS")
		)
		(fp_line
			(start 0.7874 0.4064)
			(end -0.7874 0.4064)
			(stroke
				(width 0.1524)
				(type default)
			)
			(layer "F.SilkS")
		)
		(fp_line
			(start -0.7874 0.4064)
			(end -0.7874 -0.4064)
			(stroke
				(width 0.1524)
				(type default)
			)
			(layer "F.SilkS")
		)
		(fp_line
			(start -0.12065 -0.305054)
			(end -0.12065 -0.2794)
			(stroke
				(width 0.1)
				(type default)
			)
			(layer "F.Fab")
		)
		(fp_line
			(start -0.67945 -0.305054)
			(end -0.12065 -0.305054)
			(stroke
				(width 0.1)
				(type default)
			)
			(layer "F.Fab")
		)
		(fp_line
			(start 0.67945 -0.3048)
			(end 0.67945 0.3048)
			(stroke
				(width 0.1)
				(type default)
			)
			(layer "F.Fab")
		)
		(fp_line
			(start 0.12065 -0.3048)
			(end 0.67945 -0.3048)
			(stroke
				(width 0.1)
				(type default)
			)
			(layer "F.Fab")
		)
		(fp_line
			(start 0.12065 -0.2794)
			(end 0.12065 -0.3048)
			(stroke
				(width 0.1)
				(type default)
			)
			(layer "F.Fab")
		)
		(fp_line
			(start -0.12065 -0.2794)
			(end 0.12065 -0.2794)
			(stroke
				(width 0.1)
				(type default)
			)
			(layer "F.Fab")
		)
		(fp_line
			(start 0.120396 0.2794)
			(end -0.12065 0.2794)
			(stroke
				(width 0.1)
				(type default)
			)
			(layer "F.Fab")
		)
		(fp_line
			(start -0.12065 0.2794)
			(end -0.12065 0.3048)
			(stroke
				(width 0.1)
				(type default)
			)
			(layer "F.Fab")
		)
		(fp_line
			(start 0.67945 0.3048)
			(end 0.120396 0.3048)
			(stroke
				(width 0.1)
				(type default)
			)
			(layer "F.Fab")
		)
		(fp_line
			(start 0.120396 0.3048)
			(end 0.120396 0.2794)
			(stroke
				(width 0.1)
				(type default)
			)
			(layer "F.Fab")
		)
		(fp_line
			(start -0.12065 0.3048)
			(end -0.67945 0.3048)
			(stroke
				(width 0.1)
				(type default)
			)
			(layer "F.Fab")
		)
		(fp_line
			(start -0.67945 0.3048)
			(end -0.67945 -0.305054)
			(stroke
				(width 0.1)
				(type default)
			)
			(layer "F.Fab")
		)
		(pad "1" smd circle
			(at -0.40005 0 90)
			(size 0 0)
			(layers "F.Cu" "F.Mask" "F.Paste")
			(net "GND")
		)
		(pad "2" smd circle
			(at 0.40005 0 90)
			(size 0 0)
			(layers "F.Cu" "F.Mask" "F.Paste")
			(net "PEX0_SPARE4")
		)
	)
	(footprint ""
		(layer "F.Cu")
		(at 341.546942 -37.47516)
		(property "Reference" "R6110"
			(at 0 0 0)
			(layer "F.SilkS")
			(hide yes)
			(effects
				(font
					(size 1.27 1.27)
				)
			)
		)
		(property "Value" ""
			(at 0 0 0)
			(layer "F.Fab")
			(effects
				(font
					(size 1.27 1.27)
				)
			)
		)
		(duplicate_pad_numbers_are_jumpers no)
		(fp_line
			(start -0.7874 -0.4064)
			(end 0.7874 -0.4064)
			(stroke
				(width 0.1524)
				(type default)
			)
			(layer "F.SilkS")
		)
		(fp_line
			(start -0.7874 0.4064)
			(end -0.7874 -0.4064)
			(stroke
				(width 0.1524)
				(type default)
			)
			(layer "F.SilkS")
		)
		(fp_line
			(start 0.7874 -0.4064)
			(end 0.7874 0.4064)
			(stroke
				(width 0.1524)
				(type default)
			)
			(layer "F.SilkS")
		)
		(fp_line
			(start 0.7874 0.4064)
			(end -0.7874 0.4064)
			(stroke
				(width 0.1524)
				(type default)
			)
			(layer "F.SilkS")
		)
		(fp_line
			(start -0.67945 -0.305054)
			(end -0.12065 -0.305054)
			(stroke
				(width 0.1)
				(type default)
			)
			(layer "F.Fab")
		)
		(fp_line
			(start -0.67945 0.3048)
			(end -0.67945 -0.305054)
			(stroke
				(width 0.1)
				(type default)
			)
			(layer "F.Fab")
		)
		(fp_line
			(start -0.12065 -0.305054)
			(end -0.12065 -0.2794)
			(stroke
				(width 0.1)
				(type default)
			)
			(layer "F.Fab")
		)
		(fp_line
			(start -0.12065 -0.2794)
			(end 0.12065 -0.2794)
			(stroke
				(width 0.1)
				(type default)
			)
			(layer "F.Fab")
		)
		(fp_line
			(start -0.12065 0.2794)
			(end -0.12065 0.3048)
			(stroke
				(width 0.1)
				(type default)
			)
			(layer "F.Fab")
		)
		(fp_line
			(start -0.12065 0.3048)
			(end -0.67945 0.3048)
			(stroke
				(width 0.1)
				(type default)
			)
			(layer "F.Fab")
		)
		(fp_line
			(start 0.120396 0.2794)
			(end -0.12065 0.2794)
			(stroke
				(width 0.1)
				(type default)
			)
			(layer "F.Fab")
		)
		(fp_line
			(start 0.120396 0.3048)
			(end 0.120396 0.2794)
			(stroke
				(width 0.1)
				(type default)
			)
			(layer "F.Fab")
		)
		(fp_line
			(start 0.12065 -0.3048)
			(end 0.67945 -0.3048)
			(stroke
				(width 0.1)
				(type default)
			)
			(layer "F.Fab")
		)
		(fp_line
			(start 0.12065 -0.2794)
			(end 0.12065 -0.3048)
			(stroke
				(width 0.1)
				(type default)
			)
			(layer "F.Fab")
		)
		(fp_line
			(start 0.67945 -0.3048)
			(end 0.67945 0.3048)
			(stroke
				(width 0.1)
				(type default)
			)
			(layer "F.Fab")
		)
		(fp_line
			(start 0.67945 0.3048)
			(end 0.120396 0.3048)
			(stroke
				(width 0.1)
				(type default)
			)
			(layer "F.Fab")
		)
		(pad "1" smd circle
			(at -0.40005 0)
			(size 0 0)
			(layers "F.Cu" "F.Mask" "F.Paste")
			(net "P3V3_SSD12")
		)
		(pad "2" smd circle
			(at 0.40005 0)
			(size 0 0)
			(layers "F.Cu" "F.Mask" "F.Paste")
			(net "P3V3_SSD12_PG_G1")
		)
	)
	(footprint ""
		(layer "F.Cu")
		(at 19.47164 -25.342342 -90)
		(property "Reference" "R409"
			(at 0 0 270)
			(layer "F.SilkS")
			(hide yes)
			(effects
				(font
					(size 1.27 1.27)
				)
			)
		)
		(property "Value" ""
			(at 0 0 270)
			(layer "F.Fab")
			(effects
				(font
					(size 1.27 1.27)
				)
			)
		)
		(duplicate_pad_numbers_are_jumpers no)
		(fp_line
			(start -0.7874 0.4064)
			(end -0.7874 -0.4064)
			(stroke
				(width 0.1524)
				(type default)
			)
			(layer "F.SilkS")
		)
		(fp_line
			(start 0.7874 0.4064)
			(end -0.7874 0.4064)
			(stroke
				(width 0.1524)
				(type default)
			)
			(layer "F.SilkS")
		)
		(fp_line
			(start -0.7874 -0.4064)
			(end 0.7874 -0.4064)
			(stroke
				(width 0.1524)
				(type default)
			)
			(layer "F.SilkS")
		)
		(fp_line
			(start 0.7874 -0.4064)
			(end 0.7874 0.4064)
			(stroke
				(width 0.1524)
				(type default)
			)
			(layer "F.SilkS")
		)
		(fp_line
			(start -0.67945 0.3048)
			(end -0.67945 -0.305054)
			(stroke
				(width 0.1)
				(type default)
			)
			(layer "F.Fab")
		)
		(fp_line
			(start -0.12065 0.3048)
			(end -0.67945 0.3048)
			(stroke
				(width 0.1)
				(type default)
			)
			(layer "F.Fab")
		)
		(fp_line
			(start 0.120396 0.3048)
			(end 0.120396 0.2794)
			(stroke
				(width 0.1)
				(type default)
			)
			(layer "F.Fab")
		)
		(fp_line
			(start 0.67945 0.3048)
			(end 0.120396 0.3048)
			(stroke
				(width 0.1)
				(type default)
			)
			(layer "F.Fab")
		)
		(fp_line
			(start -0.12065 0.2794)
			(end -0.12065 0.3048)
			(stroke
				(width 0.1)
				(type default)
			)
			(layer "F.Fab")
		)
		(fp_line
			(start 0.120396 0.2794)
			(end -0.12065 0.2794)
			(stroke
				(width 0.1)
				(type default)
			)
			(layer "F.Fab")
		)
		(fp_line
			(start -0.12065 -0.2794)
			(end 0.12065 -0.2794)
			(stroke
				(width 0.1)
				(type default)
			)
			(layer "F.Fab")
		)
		(fp_line
			(start 0.12065 -0.2794)
			(end 0.12065 -0.3048)
			(stroke
				(width 0.1)
				(type default)
			)
			(layer "F.Fab")
		)
		(fp_line
			(start 0.12065 -0.3048)
			(end 0.67945 -0.3048)
			(stroke
				(width 0.1)
				(type default)
			)
			(layer "F.Fab")
		)
		(fp_line
			(start 0.67945 -0.3048)
			(end 0.67945 0.3048)
			(stroke
				(width 0.1)
				(type default)
			)
			(layer "F.Fab")
		)
		(fp_line
			(start -0.67945 -0.305054)
			(end -0.12065 -0.305054)
			(stroke
				(width 0.1)
				(type default)
			)
			(layer "F.Fab")
		)
		(fp_line
			(start -0.12065 -0.305054)
			(end -0.12065 -0.2794)
			(stroke
				(width 0.1)
				(type default)
			)
			(layer "F.Fab")
		)
		(pad "1" smd circle
			(at -0.40005 0 270)
			(size 0 0)
			(layers "F.Cu" "F.Mask" "F.Paste")
			(net "P3V3_SSD0")
		)
		(pad "2" smd circle
			(at 0.40005 0 270)
			(size 0 0)
			(layers "F.Cu" "F.Mask" "F.Paste")
			(net "DUALPORT_N_SSD0")
		)
	)
	(footprint ""
		(layer "F.Cu")
		(at 17.006316 -306.28209)
		(property "Reference" "PJ9"
			(at 1.541018 -0.15875 0)
			(unlocked yes)
			(layer "F.SilkS")
			(effects
				(font
					(size 0.7874 0.5842)
					(thickness 0.1524)
				)
				(justify left)
			)
		)
		(property "Value" ""
			(at 0 0 0)
			(layer "F.Fab")
			(effects
				(font
					(size 1.27 1.27)
				)
			)
		)
		(duplicate_pad_numbers_are_jumpers no)
		(pad "1" smd circle
			(at -0.40005 0 90)
			(size 0 0)
			(layers "F.Cu" "F.Mask" "F.Paste")
			(net "SH_P1V25_PEX0_FB_P")
		)
		(pad "2" smd rect
			(at 0.40005 0 180)
			(size 0.4572 0.508)
			(layers "F.Cu" "F.Mask" "F.Paste")
			(net "P1V25_PEX0")
		)
		(zone
			(layer "F.Cu")
			(hatch none 0.5)
			(connect_pads
				(clearance 0)
			)
			(min_thickness 0.25)
			(keepout
				(tracks allowed)
				(vias not_allowed)
				(pads allowed)
				(copperpour not_allowed)
				(footprints allowed)
			)
			(placement
				(enabled no)
				(sheetname "")
			)
			(fill
				(thermal_gap 0.5)
				(thermal_bridge_width 0.5)
				(island_removal_mode 0)
			)
			(polygon
				(pts
					(xy 16.320516 -305.97729) (xy 17.692116 -305.97729) (xy 17.692116 -306.58689) (xy 16.320516 -306.58689)
				)
			)
		)
	)
	(footprint ""
		(layer "F.Cu")
		(at 210.439 -202.819 180)
		(property "Reference" "R1518"
			(at 0 0 180)
			(layer "F.SilkS")
			(hide yes)
			(effects
				(font
					(size 1.27 1.27)
				)
			)
		)
		(property "Value" ""
			(at 0 0 180)
			(layer "F.Fab")
			(effects
				(font
					(size 1.27 1.27)
				)
			)
		)
		(duplicate_pad_numbers_are_jumpers no)
		(fp_line
			(start 0.7874 0.4064)
			(end -0.7874 0.4064)
			(stroke
				(width 0.1524)
				(type default)
			)
			(layer "F.SilkS")
		)
		(fp_line
			(start 0.7874 -0.4064)
			(end 0.7874 0.4064)
			(stroke
				(width 0.1524)
				(type default)
			)
			(layer "F.SilkS")
		)
		(fp_line
			(start -0.7874 0.4064)
			(end -0.7874 -0.4064)
			(stroke
				(width 0.1524)
				(type default)
			)
			(layer "F.SilkS")
		)
		(fp_line
			(start -0.7874 -0.4064)
			(end 0.7874 -0.4064)
			(stroke
				(width 0.1524)
				(type default)
			)
			(layer "F.SilkS")
		)
		(fp_line
			(start 0.67945 0.3048)
			(end 0.120396 0.3048)
			(stroke
				(width 0.1)
				(type default)
			)
			(layer "F.Fab")
		)
		(fp_line
			(start 0.67945 -0.3048)
			(end 0.67945 0.3048)
			(stroke
				(width 0.1)
				(type default)
			)
			(layer "F.Fab")
		)
		(fp_line
			(start 0.12065 -0.2794)
			(end 0.12065 -0.3048)
			(stroke
				(width 0.1)
				(type default)
			)
			(layer "F.Fab")
		)
		(fp_line
			(start 0.12065 -0.3048)
			(end 0.67945 -0.3048)
			(stroke
				(width 0.1)
				(type default)
			)
			(layer "F.Fab")
		)
		(fp_line
			(start 0.120396 0.3048)
			(end 0.120396 0.2794)
			(stroke
				(width 0.1)
				(type default)
			)
			(layer "F.Fab")
		)
		(fp_line
			(start 0.120396 0.2794)
			(end -0.12065 0.2794)
			(stroke
				(width 0.1)
				(type default)
			)
			(layer "F.Fab")
		)
		(fp_line
			(start -0.12065 0.3048)
			(end -0.67945 0.3048)
			(stroke
				(width 0.1)
				(type default)
			)
			(layer "F.Fab")
		)
		(fp_line
			(start -0.12065 0.2794)
			(end -0.12065 0.3048)
			(stroke
				(width 0.1)
				(type default)
			)
			(layer "F.Fab")
		)
		(fp_line
			(start -0.12065 -0.2794)
			(end 0.12065 -0.2794)
			(stroke
				(width 0.1)
				(type default)
			)
			(layer "F.Fab")
		)
		(fp_line
			(start -0.12065 -0.305054)
			(end -0.12065 -0.2794)
			(stroke
				(width 0.1)
				(type default)
			)
			(layer "F.Fab")
		)
		(fp_line
			(start -0.67945 0.3048)
			(end -0.67945 -0.305054)
			(stroke
				(width 0.1)
				(type default)
			)
			(layer "F.Fab")
		)
		(fp_line
			(start -0.67945 -0.305054)
			(end -0.12065 -0.305054)
			(stroke
				(width 0.1)
				(type default)
			)
			(layer "F.Fab")
		)
		(pad "1" smd circle
			(at -0.40005 0 180)
			(size 0 0)
			(layers "F.Cu" "F.Mask" "F.Paste")
			(net "SMB_NIC5_R_SDA")
		)
		(pad "2" smd circle
			(at 0.40005 0 180)
			(size 0 0)
			(layers "F.Cu" "F.Mask" "F.Paste")
			(net "P1V2_AUX")
		)
	)
	(footprint ""
		(layer "F.Cu")
		(at 148.511514 -286.844232 -90)
		(property "Reference" "R4574"
			(at 0 0 270)
			(layer "F.SilkS")
			(hide yes)
			(effects
				(font
					(size 1.27 1.27)
				)
			)
		)
		(property "Value" ""
			(at 0 0 270)
			(layer "F.Fab")
			(effects
				(font
					(size 1.27 1.27)
				)
			)
		)
		(duplicate_pad_numbers_are_jumpers no)
		(fp_line
			(start -0.7874 0.4064)
			(end -0.7874 -0.4064)
			(stroke
				(width 0.1524)
				(type default)
			)
			(layer "F.SilkS")
		)
		(fp_line
			(start 0.7874 0.4064)
			(end -0.7874 0.4064)
			(stroke
				(width 0.1524)
				(type default)
			)
			(layer "F.SilkS")
		)
		(fp_line
			(start -0.7874 -0.4064)
			(end 0.7874 -0.4064)
			(stroke
				(width 0.1524)
				(type default)
			)
			(layer "F.SilkS")
		)
		(fp_line
			(start 0.7874 -0.4064)
			(end 0.7874 0.4064)
			(stroke
				(width 0.1524)
				(type default)
			)
			(layer "F.SilkS")
		)
		(fp_line
			(start -0.67945 0.3048)
			(end -0.67945 -0.305054)
			(stroke
				(width 0.1)
				(type default)
			)
			(layer "F.Fab")
		)
		(fp_line
			(start -0.12065 0.3048)
			(end -0.67945 0.3048)
			(stroke
				(width 0.1)
				(type default)
			)
			(layer "F.Fab")
		)
		(fp_line
			(start 0.120396 0.3048)
			(end 0.120396 0.2794)
			(stroke
				(width 0.1)
				(type default)
			)
			(layer "F.Fab")
		)
		(fp_line
			(start 0.67945 0.3048)
			(end 0.120396 0.3048)
			(stroke
				(width 0.1)
				(type default)
			)
			(layer "F.Fab")
		)
		(fp_line
			(start -0.12065 0.2794)
			(end -0.12065 0.3048)
			(stroke
				(width 0.1)
				(type default)
			)
			(layer "F.Fab")
		)
		(fp_line
			(start 0.120396 0.2794)
			(end -0.12065 0.2794)
			(stroke
				(width 0.1)
				(type default)
			)
			(layer "F.Fab")
		)
		(fp_line
			(start -0.12065 -0.2794)
			(end 0.12065 -0.2794)
			(stroke
				(width 0.1)
				(type default)
			)
			(layer "F.Fab")
		)
		(fp_line
			(start 0.12065 -0.2794)
			(end 0.12065 -0.3048)
			(stroke
				(width 0.1)
				(type default)
			)
			(layer "F.Fab")
		)
		(fp_line
			(start 0.12065 -0.3048)
			(end 0.67945 -0.3048)
			(stroke
				(width 0.1)
				(type default)
			)
			(layer "F.Fab")
		)
		(fp_line
			(start 0.67945 -0.3048)
			(end 0.67945 0.3048)
			(stroke
				(width 0.1)
				(type default)
			)
			(layer "F.Fab")
		)
		(fp_line
			(start -0.67945 -0.305054)
			(end -0.12065 -0.305054)
			(stroke
				(width 0.1)
				(type default)
			)
			(layer "F.Fab")
		)
		(fp_line
			(start -0.12065 -0.305054)
			(end -0.12065 -0.2794)
			(stroke
				(width 0.1)
				(type default)
			)
			(layer "F.Fab")
		)
		(pad "1" smd circle
			(at -0.40005 0 270)
			(size 0 0)
			(layers "F.Cu" "F.Mask" "F.Paste")
			(net "PCEPLL6_VDDA18_PEX1")
		)
		(pad "2" smd circle
			(at 0.40005 0 270)
			(size 0 0)
			(layers "F.Cu" "F.Mask" "F.Paste")
			(net "PCEPLL6_VDDA18_PEX1_R")
		)
	)
	(footprint ""
		(layer "F.Cu")
		(at 191.756538 -17.419574 180)
		(property "Reference" "R1674"
			(at 0 0 180)
			(layer "F.SilkS")
			(hide yes)
			(effects
				(font
					(size 1.27 1.27)
				)
			)
		)
		(property "Value" ""
			(at 0 0 180)
			(layer "F.Fab")
			(effects
				(font
					(size 1.27 1.27)
				)
			)
		)
		(duplicate_pad_numbers_are_jumpers no)
		(fp_line
			(start 0.7874 0.4064)
			(end -0.7874 0.4064)
			(stroke
				(width 0.1524)
				(type default)
			)
			(layer "F.SilkS")
		)
		(fp_line
			(start 0.7874 -0.4064)
			(end 0.7874 0.4064)
			(stroke
				(width 0.1524)
				(type default)
			)
			(layer "F.SilkS")
		)
		(fp_line
			(start -0.7874 0.4064)
			(end -0.7874 -0.4064)
			(stroke
				(width 0.1524)
				(type default)
			)
			(layer "F.SilkS")
		)
		(fp_line
			(start -0.7874 -0.4064)
			(end 0.7874 -0.4064)
			(stroke
				(width 0.1524)
				(type default)
			)
			(layer "F.SilkS")
		)
		(fp_line
			(start 0.67945 0.3048)
			(end 0.120396 0.3048)
			(stroke
				(width 0.1)
				(type default)
			)
			(layer "F.Fab")
		)
		(fp_line
			(start 0.67945 -0.3048)
			(end 0.67945 0.3048)
			(stroke
				(width 0.1)
				(type default)
			)
			(layer "F.Fab")
		)
		(fp_line
			(start 0.12065 -0.2794)
			(end 0.12065 -0.3048)
			(stroke
				(width 0.1)
				(type default)
			)
			(layer "F.Fab")
		)
		(fp_line
			(start 0.12065 -0.3048)
			(end 0.67945 -0.3048)
			(stroke
				(width 0.1)
				(type default)
			)
			(layer "F.Fab")
		)
		(fp_line
			(start 0.120396 0.3048)
			(end 0.120396 0.2794)
			(stroke
				(width 0.1)
				(type default)
			)
			(layer "F.Fab")
		)
		(fp_line
			(start 0.120396 0.2794)
			(end -0.12065 0.2794)
			(stroke
				(width 0.1)
				(type default)
			)
			(layer "F.Fab")
		)
		(fp_line
			(start -0.12065 0.3048)
			(end -0.67945 0.3048)
			(stroke
				(width 0.1)
				(type default)
			)
			(layer "F.Fab")
		)
		(fp_line
			(start -0.12065 0.2794)
			(end -0.12065 0.3048)
			(stroke
				(width 0.1)
				(type default)
			)
			(layer "F.Fab")
		)
		(fp_line
			(start -0.12065 -0.2794)
			(end 0.12065 -0.2794)
			(stroke
				(width 0.1)
				(type default)
			)
			(layer "F.Fab")
		)
		(fp_line
			(start -0.12065 -0.305054)
			(end -0.12065 -0.2794)
			(stroke
				(width 0.1)
				(type default)
			)
			(layer "F.Fab")
		)
		(fp_line
			(start -0.67945 0.3048)
			(end -0.67945 -0.305054)
			(stroke
				(width 0.1)
				(type default)
			)
			(layer "F.Fab")
		)
		(fp_line
			(start -0.67945 -0.305054)
			(end -0.12065 -0.305054)
			(stroke
				(width 0.1)
				(type default)
			)
			(layer "F.Fab")
		)
		(pad "1" smd circle
			(at -0.40005 0 180)
			(size 0 0)
			(layers "F.Cu" "F.Mask" "F.Paste")
			(net "P3V3_SSD6")
		)
		(pad "2" smd circle
			(at 0.40005 0 180)
			(size 0 0)
			(layers "F.Cu" "F.Mask" "F.Paste")
			(net "SMB_ISO_SSD6_SCL")
		)
	)
	(footprint ""
		(layer "F.Cu")
		(at 291.194998 -97.718372 180)
		(property "Reference" "R303"
			(at 0 0 180)
			(layer "F.SilkS")
			(hide yes)
			(effects
				(font
					(size 1.27 1.27)
				)
			)
		)
		(property "Value" ""
			(at 0 0 180)
			(layer "F.Fab")
			(effects
				(font
					(size 1.27 1.27)
				)
			)
		)
		(duplicate_pad_numbers_are_jumpers no)
		(fp_line
			(start 0.7874 0.4064)
			(end -0.7874 0.4064)
			(stroke
				(width 0.1524)
				(type default)
			)
			(layer "F.SilkS")
		)
		(fp_line
			(start 0.7874 -0.4064)
			(end 0.7874 0.4064)
			(stroke
				(width 0.1524)
				(type default)
			)
			(layer "F.SilkS")
		)
		(fp_line
			(start -0.7874 0.4064)
			(end -0.7874 -0.4064)
			(stroke
				(width 0.1524)
				(type default)
			)
			(layer "F.SilkS")
		)
		(fp_line
			(start -0.7874 -0.4064)
			(end 0.7874 -0.4064)
			(stroke
				(width 0.1524)
				(type default)
			)
			(layer "F.SilkS")
		)
		(fp_line
			(start 0.67945 0.3048)
			(end 0.120396 0.3048)
			(stroke
				(width 0.1)
				(type default)
			)
			(layer "F.Fab")
		)
		(fp_line
			(start 0.67945 -0.3048)
			(end 0.67945 0.3048)
			(stroke
				(width 0.1)
				(type default)
			)
			(layer "F.Fab")
		)
		(fp_line
			(start 0.12065 -0.2794)
			(end 0.12065 -0.3048)
			(stroke
				(width 0.1)
				(type default)
			)
			(layer "F.Fab")
		)
		(fp_line
			(start 0.12065 -0.3048)
			(end 0.67945 -0.3048)
			(stroke
				(width 0.1)
				(type default)
			)
			(layer "F.Fab")
		)
		(fp_line
			(start 0.120396 0.3048)
			(end 0.120396 0.2794)
			(stroke
				(width 0.1)
				(type default)
			)
			(layer "F.Fab")
		)
		(fp_line
			(start 0.120396 0.2794)
			(end -0.12065 0.2794)
			(stroke
				(width 0.1)
				(type default)
			)
			(layer "F.Fab")
		)
		(fp_line
			(start -0.12065 0.3048)
			(end -0.67945 0.3048)
			(stroke
				(width 0.1)
				(type default)
			)
			(layer "F.Fab")
		)
		(fp_line
			(start -0.12065 0.2794)
			(end -0.12065 0.3048)
			(stroke
				(width 0.1)
				(type default)
			)
			(layer "F.Fab")
		)
		(fp_line
			(start -0.12065 -0.2794)
			(end 0.12065 -0.2794)
			(stroke
				(width 0.1)
				(type default)
			)
			(layer "F.Fab")
		)
		(fp_line
			(start -0.12065 -0.305054)
			(end -0.12065 -0.2794)
			(stroke
				(width 0.1)
				(type default)
			)
			(layer "F.Fab")
		)
		(fp_line
			(start -0.67945 0.3048)
			(end -0.67945 -0.305054)
			(stroke
				(width 0.1)
				(type default)
			)
			(layer "F.Fab")
		)
		(fp_line
			(start -0.67945 -0.305054)
			(end -0.12065 -0.305054)
			(stroke
				(width 0.1)
				(type default)
			)
			(layer "F.Fab")
		)
		(pad "1" smd circle
			(at -0.40005 0 180)
			(size 0 0)
			(layers "F.Cu" "F.Mask" "F.Paste")
			(net "RST_NIC5_PERST3_R_N")
		)
		(pad "2" smd circle
			(at 0.40005 0 180)
			(size 0 0)
			(layers "F.Cu" "F.Mask" "F.Paste")
			(net "RST_HP_NIC5_BUF_N")
		)
	)
	(footprint ""
		(layer "F.Cu")
		(at 438.013348 -104.267508 -90)
		(property "Reference" "R767"
			(at 0 0 270)
			(layer "F.SilkS")
			(hide yes)
			(effects
				(font
					(size 1.27 1.27)
				)
			)
		)
		(property "Value" ""
			(at 0 0 270)
			(layer "F.Fab")
			(effects
				(font
					(size 1.27 1.27)
				)
			)
		)
		(duplicate_pad_numbers_are_jumpers no)
		(fp_line
			(start -0.7874 0.4064)
			(end -0.7874 -0.4064)
			(stroke
				(width 0.1524)
				(type default)
			)
			(layer "F.SilkS")
		)
		(fp_line
			(start 0.7874 0.4064)
			(end -0.7874 0.4064)
			(stroke
				(width 0.1524)
				(type default)
			)
			(layer "F.SilkS")
		)
		(fp_line
			(start -0.7874 -0.4064)
			(end 0.7874 -0.4064)
			(stroke
				(width 0.1524)
				(type default)
			)
			(layer "F.SilkS")
		)
		(fp_line
			(start 0.7874 -0.4064)
			(end 0.7874 0.4064)
			(stroke
				(width 0.1524)
				(type default)
			)
			(layer "F.SilkS")
		)
		(fp_line
			(start -0.67945 0.3048)
			(end -0.67945 -0.305054)
			(stroke
				(width 0.1)
				(type default)
			)
			(layer "F.Fab")
		)
		(fp_line
			(start -0.12065 0.3048)
			(end -0.67945 0.3048)
			(stroke
				(width 0.1)
				(type default)
			)
			(layer "F.Fab")
		)
		(fp_line
			(start 0.120396 0.3048)
			(end 0.120396 0.2794)
			(stroke
				(width 0.1)
				(type default)
			)
			(layer "F.Fab")
		)
		(fp_line
			(start 0.67945 0.3048)
			(end 0.120396 0.3048)
			(stroke
				(width 0.1)
				(type default)
			)
			(layer "F.Fab")
		)
		(fp_line
			(start -0.12065 0.2794)
			(end -0.12065 0.3048)
			(stroke
				(width 0.1)
				(type default)
			)
			(layer "F.Fab")
		)
		(fp_line
			(start 0.120396 0.2794)
			(end -0.12065 0.2794)
			(stroke
				(width 0.1)
				(type default)
			)
			(layer "F.Fab")
		)
		(fp_line
			(start -0.12065 -0.2794)
			(end 0.12065 -0.2794)
			(stroke
				(width 0.1)
				(type default)
			)
			(layer "F.Fab")
		)
		(fp_line
			(start 0.12065 -0.2794)
			(end 0.12065 -0.3048)
			(stroke
				(width 0.1)
				(type default)
			)
			(layer "F.Fab")
		)
		(fp_line
			(start 0.12065 -0.3048)
			(end 0.67945 -0.3048)
			(stroke
				(width 0.1)
				(type default)
			)
			(layer "F.Fab")
		)
		(fp_line
			(start 0.67945 -0.3048)
			(end 0.67945 0.3048)
			(stroke
				(width 0.1)
				(type default)
			)
			(layer "F.Fab")
		)
		(fp_line
			(start -0.67945 -0.305054)
			(end -0.12065 -0.305054)
			(stroke
				(width 0.1)
				(type default)
			)
			(layer "F.Fab")
		)
		(fp_line
			(start -0.12065 -0.305054)
			(end -0.12065 -0.2794)
			(stroke
				(width 0.1)
				(type default)
			)
			(layer "F.Fab")
		)
		(pad "1" smd circle
			(at -0.40005 0 270)
			(size 0 0)
			(layers "F.Cu" "F.Mask" "F.Paste")
			(net "P12V_NIC7")
		)
		(pad "2" smd circle
			(at 0.40005 0 270)
			(size 0 0)
			(layers "F.Cu" "F.Mask" "F.Paste")
			(net "P12V_NIC7_VIN_N")
		)
	)
	(footprint ""
		(layer "F.Cu")
		(at 271.480534 -124.605542)
		(property "Reference" "C463"
			(at 0 0 0)
			(layer "F.SilkS")
			(hide yes)
			(effects
				(font
					(size 1.27 1.27)
				)
			)
		)
		(property "Value" ""
			(at 0 0 0)
			(layer "F.Fab")
			(effects
				(font
					(size 1.27 1.27)
				)
			)
		)
		(duplicate_pad_numbers_are_jumpers no)
		(fp_line
			(start -0.299974 -0.150114)
			(end 0.299974 -0.150114)
			(stroke
				(width 0.1)
				(type default)
			)
			(layer "F.Fab")
		)
		(fp_line
			(start -0.299974 0.150114)
			(end -0.299974 -0.150114)
			(stroke
				(width 0.1)
				(type default)
			)
			(layer "F.Fab")
		)
		(fp_line
			(start 0.299974 -0.150114)
			(end 0.299974 0.150114)
			(stroke
				(width 0.1)
				(type default)
			)
			(layer "F.Fab")
		)
		(fp_line
			(start 0.299974 0.150114)
			(end -0.299974 0.150114)
			(stroke
				(width 0.1)
				(type default)
			)
			(layer "F.Fab")
		)
		(pad "1" smd rect
			(at -0.2667 0)
			(size 0.3048 0.381)
			(layers "F.Cu" "F.Mask" "F.Paste")
			(net "P5E_PEX2_STN1_TX_DN<27>")
		)
		(pad "2" smd rect
			(at 0.2667 0)
			(size 0.3048 0.381)
			(layers "F.Cu" "F.Mask" "F.Paste")
			(net "P5E_PEX2_STN1_TX_C_DN<27>")
		)
	)
	(footprint ""
		(layer "F.Cu")
		(at 254.161036 -37.951156)
		(property "Reference" "Q225"
			(at -0.059436 -1.925574 0)
			(unlocked yes)
			(layer "F.SilkS")
			(effects
				(font
					(size 0.7874 0.5842)
					(thickness 0.1524)
				)
			)
		)
		(property "Value" ""
			(at 0 0 0)
			(layer "F.Fab")
			(effects
				(font
					(size 1.27 1.27)
				)
			)
		)
		(duplicate_pad_numbers_are_jumpers no)
		(fp_line
			(start -1.376172 -1.199896)
			(end -0.508 -1.199896)
			(stroke
				(width 0.1524)
				(type default)
			)
			(layer "F.SilkS")
		)
		(fp_line
			(start -1.376172 1.199896)
			(end -1.376172 -1.199896)
			(stroke
				(width 0.1524)
				(type default)
			)
			(layer "F.SilkS")
		)
		(fp_line
			(start -0.508 -1.199896)
			(end 0 -0.762)
			(stroke
				(width 0.1524)
				(type default)
			)
			(layer "F.SilkS")
		)
		(fp_line
			(start 0 -0.762)
			(end 0.508 -1.199896)
			(stroke
				(width 0.1524)
				(type default)
			)
			(layer "F.SilkS")
		)
		(fp_line
			(start 0.508 -1.199896)
			(end 1.376172 -1.199896)
			(stroke
				(width 0.1524)
				(type default)
			)
			(layer "F.SilkS")
		)
		(fp_line
			(start 1.376172 -1.199896)
			(end 1.376172 1.199896)
			(stroke
				(width 0.1524)
				(type default)
			)
			(layer "F.SilkS")
		)
		(fp_line
			(start 1.376172 1.199896)
			(end -1.376172 1.199896)
			(stroke
				(width 0.1524)
				(type default)
			)
			(layer "F.SilkS")
		)
		(fp_poly
			(pts
				(xy -1.517142 -1.242314) (xy -1.786636 -2.050542) (xy -2.32537 -1.511554)
			)
			(stroke
				(width 0)
				(type default)
			)
			(fill yes)
			(layer "F.SilkS")
		)
		(fp_line
			(start -0.674878 -1.100074)
			(end 0.674878 -1.100074)
			(stroke
				(width 0.1)
				(type default)
			)
			(layer "F.Fab")
		)
		(fp_line
			(start -0.674878 1.100074)
			(end -0.674878 -1.100074)
			(stroke
				(width 0.1)
				(type default)
			)
			(layer "F.Fab")
		)
		(fp_line
			(start 0.674878 -1.100074)
			(end 0.674878 1.100074)
			(stroke
				(width 0.1)
				(type default)
			)
			(layer "F.Fab")
		)
		(fp_line
			(start 0.674878 1.100074)
			(end -0.674878 1.100074)
			(stroke
				(width 0.1)
				(type default)
			)
			(layer "F.Fab")
		)
		(fp_poly
			(pts
				(xy -1.4605 -0.7493) (xy -2.2225 -1.1303) (xy -2.2225 -0.3683)
			)
			(stroke
				(width 0)
				(type default)
			)
			(fill yes)
			(layer "F.Fab")
		)
		(pad "1" smd rect
			(at -0.899922 -0.750062 270)
			(size 0.6096 0.6096)
			(layers "F.Cu" "F.Mask" "F.Paste")
			(net "GND")
		)
		(pad "2" smd rect
			(at -0.899922 0 270)
			(size 0.4064 0.6096)
			(layers "F.Cu" "F.Mask" "F.Paste")
			(net "P3V3_SSD9_PG_G1")
		)
		(pad "3" smd rect
			(at -0.899922 0.750062 270)
			(size 0.6096 0.6096)
			(layers "F.Cu" "F.Mask" "F.Paste")
			(net "PWRGD_P3V3_SSD9_D")
		)
		(pad "4" smd rect
			(at 0.899922 0.750062 270)
			(size 0.6096 0.6096)
			(layers "F.Cu" "F.Mask" "F.Paste")
			(net "GND")
		)
		(pad "5" smd rect
			(at 0.899922 0 270)
			(size 0.4064 0.6096)
			(layers "F.Cu" "F.Mask" "F.Paste")
			(net "P3V3_SSD9_PG_G2")
		)
		(pad "6" smd rect
			(at 0.899922 -0.750062 270)
			(size 0.6096 0.6096)
			(layers "F.Cu" "F.Mask" "F.Paste")
			(net "P3V3_SSD9_PG_G2")
		)
	)
	(footprint ""
		(layer "F.Cu")
		(at 296.79519 -195.32854 90)
		(property "Reference" "R3390"
			(at 0 0 90)
			(layer "F.SilkS")
			(hide yes)
			(effects
				(font
					(size 1.27 1.27)
				)
			)
		)
		(property "Value" ""
			(at 0 0 90)
			(layer "F.Fab")
			(effects
				(font
					(size 1.27 1.27)
				)
			)
		)
		(duplicate_pad_numbers_are_jumpers no)
		(fp_line
			(start 0.7874 -0.4064)
			(end 0.7874 0.4064)
			(stroke
				(width 0.1524)
				(type default)
			)
			(layer "F.SilkS")
		)
		(fp_line
			(start -0.7874 -0.4064)
			(end 0.7874 -0.4064)
			(stroke
				(width 0.1524)
				(type default)
			)
			(layer "F.SilkS")
		)
		(fp_line
			(start 0.7874 0.4064)
			(end -0.7874 0.4064)
			(stroke
				(width 0.1524)
				(type default)
			)
			(layer "F.SilkS")
		)
		(fp_line
			(start -0.7874 0.4064)
			(end -0.7874 -0.4064)
			(stroke
				(width 0.1524)
				(type default)
			)
			(layer "F.SilkS")
		)
		(fp_line
			(start -0.12065 -0.305054)
			(end -0.12065 -0.2794)
			(stroke
				(width 0.1)
				(type default)
			)
			(layer "F.Fab")
		)
		(fp_line
			(start -0.67945 -0.305054)
			(end -0.12065 -0.305054)
			(stroke
				(width 0.1)
				(type default)
			)
			(layer "F.Fab")
		)
		(fp_line
			(start 0.67945 -0.3048)
			(end 0.67945 0.3048)
			(stroke
				(width 0.1)
				(type default)
			)
			(layer "F.Fab")
		)
		(fp_line
			(start 0.12065 -0.3048)
			(end 0.67945 -0.3048)
			(stroke
				(width 0.1)
				(type default)
			)
			(layer "F.Fab")
		)
		(fp_line
			(start 0.12065 -0.2794)
			(end 0.12065 -0.3048)
			(stroke
				(width 0.1)
				(type default)
			)
			(layer "F.Fab")
		)
		(fp_line
			(start -0.12065 -0.2794)
			(end 0.12065 -0.2794)
			(stroke
				(width 0.1)
				(type default)
			)
			(layer "F.Fab")
		)
		(fp_line
			(start 0.120396 0.2794)
			(end -0.12065 0.2794)
			(stroke
				(width 0.1)
				(type default)
			)
			(layer "F.Fab")
		)
		(fp_line
			(start -0.12065 0.2794)
			(end -0.12065 0.3048)
			(stroke
				(width 0.1)
				(type default)
			)
			(layer "F.Fab")
		)
		(fp_line
			(start 0.67945 0.3048)
			(end 0.120396 0.3048)
			(stroke
				(width 0.1)
				(type default)
			)
			(layer "F.Fab")
		)
		(fp_line
			(start 0.120396 0.3048)
			(end 0.120396 0.2794)
			(stroke
				(width 0.1)
				(type default)
			)
			(layer "F.Fab")
		)
		(fp_line
			(start -0.12065 0.3048)
			(end -0.67945 0.3048)
			(stroke
				(width 0.1)
				(type default)
			)
			(layer "F.Fab")
		)
		(fp_line
			(start -0.67945 0.3048)
			(end -0.67945 -0.305054)
			(stroke
				(width 0.1)
				(type default)
			)
			(layer "F.Fab")
		)
		(pad "1" smd circle
			(at -0.40005 0 90)
			(size 0 0)
			(layers "F.Cu" "F.Mask" "F.Paste")
			(net "SPI_BIC1_CS0_R1_N")
		)
		(pad "2" smd circle
			(at 0.40005 0 90)
			(size 0 0)
			(layers "F.Cu" "F.Mask" "F.Paste")
			(net "SPI_BIC1_CS0_R3_N")
		)
	)
	(footprint ""
		(layer "F.Cu")
		(at 145.522442 -252.356874 -90)
		(property "Reference" "R1292"
			(at 0 0 270)
			(layer "F.SilkS")
			(hide yes)
			(effects
				(font
					(size 1.27 1.27)
				)
			)
		)
		(property "Value" ""
			(at 0 0 270)
			(layer "F.Fab")
			(effects
				(font
					(size 1.27 1.27)
				)
			)
		)
		(duplicate_pad_numbers_are_jumpers no)
		(fp_line
			(start -0.7874 0.4064)
			(end -0.7874 -0.4064)
			(stroke
				(width 0.1524)
				(type default)
			)
			(layer "F.SilkS")
		)
		(fp_line
			(start 0.7874 0.4064)
			(end -0.7874 0.4064)
			(stroke
				(width 0.1524)
				(type default)
			)
			(layer "F.SilkS")
		)
		(fp_line
			(start -0.7874 -0.4064)
			(end 0.7874 -0.4064)
			(stroke
				(width 0.1524)
				(type default)
			)
			(layer "F.SilkS")
		)
		(fp_line
			(start 0.7874 -0.4064)
			(end 0.7874 0.4064)
			(stroke
				(width 0.1524)
				(type default)
			)
			(layer "F.SilkS")
		)
		(fp_line
			(start -0.67945 0.3048)
			(end -0.67945 -0.305054)
			(stroke
				(width 0.1)
				(type default)
			)
			(layer "F.Fab")
		)
		(fp_line
			(start -0.12065 0.3048)
			(end -0.67945 0.3048)
			(stroke
				(width 0.1)
				(type default)
			)
			(layer "F.Fab")
		)
		(fp_line
			(start 0.120396 0.3048)
			(end 0.120396 0.2794)
			(stroke
				(width 0.1)
				(type default)
			)
			(layer "F.Fab")
		)
		(fp_line
			(start 0.67945 0.3048)
			(end 0.120396 0.3048)
			(stroke
				(width 0.1)
				(type default)
			)
			(layer "F.Fab")
		)
		(fp_line
			(start -0.12065 0.2794)
			(end -0.12065 0.3048)
			(stroke
				(width 0.1)
				(type default)
			)
			(layer "F.Fab")
		)
		(fp_line
			(start 0.120396 0.2794)
			(end -0.12065 0.2794)
			(stroke
				(width 0.1)
				(type default)
			)
			(layer "F.Fab")
		)
		(fp_line
			(start -0.12065 -0.2794)
			(end 0.12065 -0.2794)
			(stroke
				(width 0.1)
				(type default)
			)
			(layer "F.Fab")
		)
		(fp_line
			(start 0.12065 -0.2794)
			(end 0.12065 -0.3048)
			(stroke
				(width 0.1)
				(type default)
			)
			(layer "F.Fab")
		)
		(fp_line
			(start 0.12065 -0.3048)
			(end 0.67945 -0.3048)
			(stroke
				(width 0.1)
				(type default)
			)
			(layer "F.Fab")
		)
		(fp_line
			(start 0.67945 -0.3048)
			(end 0.67945 0.3048)
			(stroke
				(width 0.1)
				(type default)
			)
			(layer "F.Fab")
		)
		(fp_line
			(start -0.67945 -0.305054)
			(end -0.12065 -0.305054)
			(stroke
				(width 0.1)
				(type default)
			)
			(layer "F.Fab")
		)
		(fp_line
			(start -0.12065 -0.305054)
			(end -0.12065 -0.2794)
			(stroke
				(width 0.1)
				(type default)
			)
			(layer "F.Fab")
		)
		(pad "1" smd circle
			(at -0.40005 0 270)
			(size 0 0)
			(layers "F.Cu" "F.Mask" "F.Paste")
			(net "GND")
		)
		(pad "2" smd circle
			(at 0.40005 0 270)
			(size 0 0)
			(layers "F.Cu" "F.Mask" "F.Paste")
			(net "PEX1_MODE_SEL3")
		)
	)
	(footprint ""
		(layer "F.Cu")
		(at 11.1379 -264.586466)
		(property "Reference" "R6129"
			(at 0 0 0)
			(layer "F.SilkS")
			(hide yes)
			(effects
				(font
					(size 1.27 1.27)
				)
			)
		)
		(property "Value" ""
			(at 0 0 0)
			(layer "F.Fab")
			(effects
				(font
					(size 1.27 1.27)
				)
			)
		)
		(duplicate_pad_numbers_are_jumpers no)
		(fp_line
			(start -2.576322 -1.1303)
			(end 2.576322 -1.1303)
			(stroke
				(width 0.1524)
				(type default)
			)
			(layer "F.SilkS")
		)
		(fp_line
			(start -2.576322 1.1303)
			(end -2.576322 -1.1303)
			(stroke
				(width 0.1524)
				(type default)
			)
			(layer "F.SilkS")
		)
		(fp_line
			(start 2.576322 -1.1303)
			(end 2.576322 1.1303)
			(stroke
				(width 0.1524)
				(type default)
			)
			(layer "F.SilkS")
		)
		(fp_line
			(start 2.576322 1.1303)
			(end -2.576322 1.1303)
			(stroke
				(width 0.1524)
				(type default)
			)
			(layer "F.SilkS")
		)
		(fp_line
			(start -1.649984 -0.899922)
			(end -1.649984 0.899922)
			(stroke
				(width 0.1)
				(type default)
			)
			(layer "F.Fab")
		)
		(fp_line
			(start -1.649984 0.899922)
			(end 1.649984 0.899922)
			(stroke
				(width 0.1)
				(type default)
			)
			(layer "F.Fab")
		)
		(fp_line
			(start 1.649984 -0.899922)
			(end -1.649984 -0.899922)
			(stroke
				(width 0.1)
				(type default)
			)
			(layer "F.Fab")
		)
		(fp_line
			(start 1.649984 0.899922)
			(end 1.649984 -0.899922)
			(stroke
				(width 0.1)
				(type default)
			)
			(layer "F.Fab")
		)
		(pad "1A" smd rect
			(at -1.700022 0)
			(size 1.4986 2.0066)
			(layers "F.Cu" "F.Mask" "F.Paste")
			(net "P1V25_PEX0")
		)
		(pad "1B" smd rect
			(at -1.077722 0)
			(size 0.254 0.508)
			(layers "F.Cu" "F.Mask" "F.Paste")
			(net "P1V25_PEX0")
		)
		(pad "2A" smd rect
			(at 1.700022 0)
			(size 1.4986 2.0066)
			(layers "F.Cu" "F.Mask" "F.Paste")
			(net "P1V25_SERDES_VDDPLL_PEX0")
		)
		(pad "2B" smd rect
			(at 1.077722 0)
			(size 0.254 0.508)
			(layers "F.Cu" "F.Mask" "F.Paste")
			(net "P1V25_SERDES_VDDPLL_PEX0")
		)
	)
	(footprint ""
		(layer "F.Cu")
		(at 155.380436 -136.729724)
		(property "Reference" "C245"
			(at 0 0 0)
			(layer "F.SilkS")
			(hide yes)
			(effects
				(font
					(size 1.27 1.27)
				)
			)
		)
		(property "Value" ""
			(at 0 0 0)
			(layer "F.Fab")
			(effects
				(font
					(size 1.27 1.27)
				)
			)
		)
		(duplicate_pad_numbers_are_jumpers no)
		(fp_line
			(start -0.299974 -0.150114)
			(end 0.299974 -0.150114)
			(stroke
				(width 0.1)
				(type default)
			)
			(layer "F.Fab")
		)
		(fp_line
			(start -0.299974 0.150114)
			(end -0.299974 -0.150114)
			(stroke
				(width 0.1)
				(type default)
			)
			(layer "F.Fab")
		)
		(fp_line
			(start 0.299974 -0.150114)
			(end 0.299974 0.150114)
			(stroke
				(width 0.1)
				(type default)
			)
			(layer "F.Fab")
		)
		(fp_line
			(start 0.299974 0.150114)
			(end -0.299974 0.150114)
			(stroke
				(width 0.1)
				(type default)
			)
			(layer "F.Fab")
		)
		(pad "1" smd rect
			(at -0.2667 0)
			(size 0.3048 0.381)
			(layers "F.Cu" "F.Mask" "F.Paste")
			(net "P5E_PEX1_STN1_TX_DP<31>")
		)
		(pad "2" smd rect
			(at 0.2667 0)
			(size 0.3048 0.381)
			(layers "F.Cu" "F.Mask" "F.Paste")
			(net "P5E_PEX1_STN1_TX_C_DP<31>")
		)
	)
	(footprint ""
		(layer "F.Cu")
		(at 448.436238 -95.264224 -90)
		(property "Reference" "C2860"
			(at 0 0 270)
			(layer "F.SilkS")
			(hide yes)
			(effects
				(font
					(size 1.27 1.27)
				)
			)
		)
		(property "Value" ""
			(at 0 0 270)
			(layer "F.Fab")
			(effects
				(font
					(size 1.27 1.27)
				)
			)
		)
		(duplicate_pad_numbers_are_jumpers no)
		(fp_line
			(start -0.7874 0.4064)
			(end -0.7874 -0.4064)
			(stroke
				(width 0.1524)
				(type default)
			)
			(layer "F.SilkS")
		)
		(fp_line
			(start 0.7874 0.4064)
			(end -0.7874 0.4064)
			(stroke
				(width 0.1524)
				(type default)
			)
			(layer "F.SilkS")
		)
		(fp_line
			(start -0.7874 -0.4064)
			(end 0.7874 -0.4064)
			(stroke
				(width 0.1524)
				(type default)
			)
			(layer "F.SilkS")
		)
		(fp_line
			(start 0.7874 -0.4064)
			(end 0.7874 0.4064)
			(stroke
				(width 0.1524)
				(type default)
			)
			(layer "F.SilkS")
		)
		(fp_line
			(start -0.67945 0.3048)
			(end -0.67945 -0.305054)
			(stroke
				(width 0.1)
				(type default)
			)
			(layer "F.Fab")
		)
		(fp_line
			(start -0.12065 0.3048)
			(end -0.67945 0.3048)
			(stroke
				(width 0.1)
				(type default)
			)
			(layer "F.Fab")
		)
		(fp_line
			(start 0.120396 0.3048)
			(end 0.120396 0.2794)
			(stroke
				(width 0.1)
				(type default)
			)
			(layer "F.Fab")
		)
		(fp_line
			(start 0.67945 0.3048)
			(end 0.120396 0.3048)
			(stroke
				(width 0.1)
				(type default)
			)
			(layer "F.Fab")
		)
		(fp_line
			(start -0.12065 0.2794)
			(end -0.12065 0.3048)
			(stroke
				(width 0.1)
				(type default)
			)
			(layer "F.Fab")
		)
		(fp_line
			(start 0.120396 0.2794)
			(end -0.12065 0.2794)
			(stroke
				(width 0.1)
				(type default)
			)
			(layer "F.Fab")
		)
		(fp_line
			(start -0.12065 -0.2794)
			(end 0.12065 -0.2794)
			(stroke
				(width 0.1)
				(type default)
			)
			(layer "F.Fab")
		)
		(fp_line
			(start 0.12065 -0.2794)
			(end 0.12065 -0.3048)
			(stroke
				(width 0.1)
				(type default)
			)
			(layer "F.Fab")
		)
		(fp_line
			(start 0.12065 -0.3048)
			(end 0.67945 -0.3048)
			(stroke
				(width 0.1)
				(type default)
			)
			(layer "F.Fab")
		)
		(fp_line
			(start 0.67945 -0.3048)
			(end 0.67945 0.3048)
			(stroke
				(width 0.1)
				(type default)
			)
			(layer "F.Fab")
		)
		(fp_line
			(start -0.67945 -0.305054)
			(end -0.12065 -0.305054)
			(stroke
				(width 0.1)
				(type default)
			)
			(layer "F.Fab")
		)
		(fp_line
			(start -0.12065 -0.305054)
			(end -0.12065 -0.2794)
			(stroke
				(width 0.1)
				(type default)
			)
			(layer "F.Fab")
		)
		(pad "1" smd circle
			(at -0.40005 0 270)
			(size 0 0)
			(layers "F.Cu" "F.Mask" "F.Paste")
			(net "P12V_NIC7_EN_R")
		)
		(pad "2" smd circle
			(at 0.40005 0 270)
			(size 0 0)
			(layers "F.Cu" "F.Mask" "F.Paste")
			(net "GND")
		)
	)
	(footprint ""
		(layer "F.Cu")
		(at 325.596504 -237.133892 180)
		(property "Reference" "R1783"
			(at 0 0 180)
			(layer "F.SilkS")
			(hide yes)
			(effects
				(font
					(size 1.27 1.27)
				)
			)
		)
		(property "Value" ""
			(at 0 0 180)
			(layer "F.Fab")
			(effects
				(font
					(size 1.27 1.27)
				)
			)
		)
		(duplicate_pad_numbers_are_jumpers no)
		(fp_line
			(start 0.7874 0.4064)
			(end -0.7874 0.4064)
			(stroke
				(width 0.1524)
				(type default)
			)
			(layer "F.SilkS")
		)
		(fp_line
			(start 0.7874 -0.4064)
			(end 0.7874 0.4064)
			(stroke
				(width 0.1524)
				(type default)
			)
			(layer "F.SilkS")
		)
		(fp_line
			(start -0.7874 0.4064)
			(end -0.7874 -0.4064)
			(stroke
				(width 0.1524)
				(type default)
			)
			(layer "F.SilkS")
		)
		(fp_line
			(start -0.7874 -0.4064)
			(end 0.7874 -0.4064)
			(stroke
				(width 0.1524)
				(type default)
			)
			(layer "F.SilkS")
		)
		(fp_line
			(start 0.67945 0.3048)
			(end 0.120396 0.3048)
			(stroke
				(width 0.1)
				(type default)
			)
			(layer "F.Fab")
		)
		(fp_line
			(start 0.67945 -0.3048)
			(end 0.67945 0.3048)
			(stroke
				(width 0.1)
				(type default)
			)
			(layer "F.Fab")
		)
		(fp_line
			(start 0.12065 -0.2794)
			(end 0.12065 -0.3048)
			(stroke
				(width 0.1)
				(type default)
			)
			(layer "F.Fab")
		)
		(fp_line
			(start 0.12065 -0.3048)
			(end 0.67945 -0.3048)
			(stroke
				(width 0.1)
				(type default)
			)
			(layer "F.Fab")
		)
		(fp_line
			(start 0.120396 0.3048)
			(end 0.120396 0.2794)
			(stroke
				(width 0.1)
				(type default)
			)
			(layer "F.Fab")
		)
		(fp_line
			(start 0.120396 0.2794)
			(end -0.12065 0.2794)
			(stroke
				(width 0.1)
				(type default)
			)
			(layer "F.Fab")
		)
		(fp_line
			(start -0.12065 0.3048)
			(end -0.67945 0.3048)
			(stroke
				(width 0.1)
				(type default)
			)
			(layer "F.Fab")
		)
		(fp_line
			(start -0.12065 0.2794)
			(end -0.12065 0.3048)
			(stroke
				(width 0.1)
				(type default)
			)
			(layer "F.Fab")
		)
		(fp_line
			(start -0.12065 -0.2794)
			(end 0.12065 -0.2794)
			(stroke
				(width 0.1)
				(type default)
			)
			(layer "F.Fab")
		)
		(fp_line
			(start -0.12065 -0.305054)
			(end -0.12065 -0.2794)
			(stroke
				(width 0.1)
				(type default)
			)
			(layer "F.Fab")
		)
		(fp_line
			(start -0.67945 0.3048)
			(end -0.67945 -0.305054)
			(stroke
				(width 0.1)
				(type default)
			)
			(layer "F.Fab")
		)
		(fp_line
			(start -0.67945 -0.305054)
			(end -0.12065 -0.305054)
			(stroke
				(width 0.1)
				(type default)
			)
			(layer "F.Fab")
		)
		(pad "1" smd circle
			(at -0.40005 0 180)
			(size 0 0)
			(layers "F.Cu" "F.Mask" "F.Paste")
			(net "PRSNT_GPU_ISO_N")
		)
		(pad "2" smd circle
			(at 0.40005 0 180)
			(size 0 0)
			(layers "F.Cu" "F.Mask" "F.Paste")
			(net "PRSNT_GPU_ISO_R_N")
		)
	)
	(footprint ""
		(layer "F.Cu")
		(at 112.128046 -35.876738)
		(property "Reference" "R6058"
			(at 0 0 0)
			(layer "F.SilkS")
			(hide yes)
			(effects
				(font
					(size 1.27 1.27)
				)
			)
		)
		(property "Value" ""
			(at 0 0 0)
			(layer "F.Fab")
			(effects
				(font
					(size 1.27 1.27)
				)
			)
		)
		(duplicate_pad_numbers_are_jumpers no)
		(fp_line
			(start -0.7874 -0.4064)
			(end 0.7874 -0.4064)
			(stroke
				(width 0.1524)
				(type default)
			)
			(layer "F.SilkS")
		)
		(fp_line
			(start -0.7874 0.4064)
			(end -0.7874 -0.4064)
			(stroke
				(width 0.1524)
				(type default)
			)
			(layer "F.SilkS")
		)
		(fp_line
			(start 0.7874 -0.4064)
			(end 0.7874 0.4064)
			(stroke
				(width 0.1524)
				(type default)
			)
			(layer "F.SilkS")
		)
		(fp_line
			(start 0.7874 0.4064)
			(end -0.7874 0.4064)
			(stroke
				(width 0.1524)
				(type default)
			)
			(layer "F.SilkS")
		)
		(fp_line
			(start -0.67945 -0.305054)
			(end -0.12065 -0.305054)
			(stroke
				(width 0.1)
				(type default)
			)
			(layer "F.Fab")
		)
		(fp_line
			(start -0.67945 0.3048)
			(end -0.67945 -0.305054)
			(stroke
				(width 0.1)
				(type default)
			)
			(layer "F.Fab")
		)
		(fp_line
			(start -0.12065 -0.305054)
			(end -0.12065 -0.2794)
			(stroke
				(width 0.1)
				(type default)
			)
			(layer "F.Fab")
		)
		(fp_line
			(start -0.12065 -0.2794)
			(end 0.12065 -0.2794)
			(stroke
				(width 0.1)
				(type default)
			)
			(layer "F.Fab")
		)
		(fp_line
			(start -0.12065 0.2794)
			(end -0.12065 0.3048)
			(stroke
				(width 0.1)
				(type default)
			)
			(layer "F.Fab")
		)
		(fp_line
			(start -0.12065 0.3048)
			(end -0.67945 0.3048)
			(stroke
				(width 0.1)
				(type default)
			)
			(layer "F.Fab")
		)
		(fp_line
			(start 0.120396 0.2794)
			(end -0.12065 0.2794)
			(stroke
				(width 0.1)
				(type default)
			)
			(layer "F.Fab")
		)
		(fp_line
			(start 0.120396 0.3048)
			(end 0.120396 0.2794)
			(stroke
				(width 0.1)
				(type default)
			)
			(layer "F.Fab")
		)
		(fp_line
			(start 0.12065 -0.3048)
			(end 0.67945 -0.3048)
			(stroke
				(width 0.1)
				(type default)
			)
			(layer "F.Fab")
		)
		(fp_line
			(start 0.12065 -0.2794)
			(end 0.12065 -0.3048)
			(stroke
				(width 0.1)
				(type default)
			)
			(layer "F.Fab")
		)
		(fp_line
			(start 0.67945 -0.3048)
			(end 0.67945 0.3048)
			(stroke
				(width 0.1)
				(type default)
			)
			(layer "F.Fab")
		)
		(fp_line
			(start 0.67945 0.3048)
			(end 0.120396 0.3048)
			(stroke
				(width 0.1)
				(type default)
			)
			(layer "F.Fab")
		)
		(pad "1" smd circle
			(at -0.40005 0)
			(size 0 0)
			(layers "F.Cu" "F.Mask" "F.Paste")
			(net "PWRGD_P3V3_SSD4_D")
		)
		(pad "2" smd circle
			(at 0.40005 0)
			(size 0 0)
			(layers "F.Cu" "F.Mask" "F.Paste")
			(net "PWRGD_P3V3_SSD4_R")
		)
	)
	(footprint ""
		(layer "F.Cu")
		(at 224.856294 -184.703212)
		(property "Reference" "C2185"
			(at 0 0 0)
			(layer "F.SilkS")
			(hide yes)
			(effects
				(font
					(size 1.27 1.27)
				)
			)
		)
		(property "Value" ""
			(at 0 0 0)
			(layer "F.Fab")
			(effects
				(font
					(size 1.27 1.27)
				)
			)
		)
		(duplicate_pad_numbers_are_jumpers no)
		(fp_line
			(start -0.7874 -0.4064)
			(end 0.7874 -0.4064)
			(stroke
				(width 0.1524)
				(type default)
			)
			(layer "F.SilkS")
		)
		(fp_line
			(start -0.7874 0.4064)
			(end -0.7874 -0.4064)
			(stroke
				(width 0.1524)
				(type default)
			)
			(layer "F.SilkS")
		)
		(fp_line
			(start 0.7874 -0.4064)
			(end 0.7874 0.4064)
			(stroke
				(width 0.1524)
				(type default)
			)
			(layer "F.SilkS")
		)
		(fp_line
			(start 0.7874 0.4064)
			(end -0.7874 0.4064)
			(stroke
				(width 0.1524)
				(type default)
			)
			(layer "F.SilkS")
		)
		(fp_line
			(start -0.67945 -0.305054)
			(end -0.12065 -0.305054)
			(stroke
				(width 0.1)
				(type default)
			)
			(layer "F.Fab")
		)
		(fp_line
			(start -0.67945 0.3048)
			(end -0.67945 -0.305054)
			(stroke
				(width 0.1)
				(type default)
			)
			(layer "F.Fab")
		)
		(fp_line
			(start -0.12065 -0.305054)
			(end -0.12065 -0.2794)
			(stroke
				(width 0.1)
				(type default)
			)
			(layer "F.Fab")
		)
		(fp_line
			(start -0.12065 -0.2794)
			(end 0.12065 -0.2794)
			(stroke
				(width 0.1)
				(type default)
			)
			(layer "F.Fab")
		)
		(fp_line
			(start -0.12065 0.2794)
			(end -0.12065 0.3048)
			(stroke
				(width 0.1)
				(type default)
			)
			(layer "F.Fab")
		)
		(fp_line
			(start -0.12065 0.3048)
			(end -0.67945 0.3048)
			(stroke
				(width 0.1)
				(type default)
			)
			(layer "F.Fab")
		)
		(fp_line
			(start 0.120396 0.2794)
			(end -0.12065 0.2794)
			(stroke
				(width 0.1)
				(type default)
			)
			(layer "F.Fab")
		)
		(fp_line
			(start 0.120396 0.3048)
			(end 0.120396 0.2794)
			(stroke
				(width 0.1)
				(type default)
			)
			(layer "F.Fab")
		)
		(fp_line
			(start 0.12065 -0.3048)
			(end 0.67945 -0.3048)
			(stroke
				(width 0.1)
				(type default)
			)
			(layer "F.Fab")
		)
		(fp_line
			(start 0.12065 -0.2794)
			(end 0.12065 -0.3048)
			(stroke
				(width 0.1)
				(type default)
			)
			(layer "F.Fab")
		)
		(fp_line
			(start 0.67945 -0.3048)
			(end 0.67945 0.3048)
			(stroke
				(width 0.1)
				(type default)
			)
			(layer "F.Fab")
		)
		(fp_line
			(start 0.67945 0.3048)
			(end 0.120396 0.3048)
			(stroke
				(width 0.1)
				(type default)
			)
			(layer "F.Fab")
		)
		(pad "1" smd circle
			(at -0.40005 0)
			(size 0 0)
			(layers "F.Cu" "F.Mask" "F.Paste")
			(net "P3V3_AUX")
		)
		(pad "2" smd circle
			(at 0.40005 0)
			(size 0 0)
			(layers "F.Cu" "F.Mask" "F.Paste")
			(net "GND")
		)
	)
	(footprint ""
		(layer "F.Cu")
		(at 265.487658 -288.419032)
		(property "Reference" "C3403"
			(at 0 0 0)
			(layer "F.SilkS")
			(hide yes)
			(effects
				(font
					(size 1.27 1.27)
				)
			)
		)
		(property "Value" ""
			(at 0 0 0)
			(layer "F.Fab")
			(effects
				(font
					(size 1.27 1.27)
				)
			)
		)
		(duplicate_pad_numbers_are_jumpers no)
		(fp_line
			(start -1.2954 -0.5842)
			(end 1.2954 -0.5842)
			(stroke
				(width 0.1524)
				(type default)
			)
			(layer "F.SilkS")
		)
		(fp_line
			(start -1.2954 0.5842)
			(end -1.2954 -0.5842)
			(stroke
				(width 0.1524)
				(type default)
			)
			(layer "F.SilkS")
		)
		(fp_line
			(start 1.2954 -0.5842)
			(end 1.2954 0.5842)
			(stroke
				(width 0.1524)
				(type default)
			)
			(layer "F.SilkS")
		)
		(fp_line
			(start 1.2954 0.5842)
			(end -1.2954 0.5842)
			(stroke
				(width 0.1524)
				(type default)
			)
			(layer "F.SilkS")
		)
		(fp_line
			(start -1.1938 -0.4064)
			(end -0.8636 -0.4064)
			(stroke
				(width 0.1)
				(type default)
			)
			(layer "F.Fab")
		)
		(fp_line
			(start -1.1938 0.4064)
			(end -1.1938 -0.4064)
			(stroke
				(width 0.1)
				(type default)
			)
			(layer "F.Fab")
		)
		(fp_line
			(start -0.8636 -0.4572)
			(end 0.8636 -0.4572)
			(stroke
				(width 0.1)
				(type default)
			)
			(layer "F.Fab")
		)
		(fp_line
			(start -0.8636 -0.4064)
			(end -0.8636 -0.4572)
			(stroke
				(width 0.1)
				(type default)
			)
			(layer "F.Fab")
		)
		(fp_line
			(start -0.8636 0.4064)
			(end -1.1938 0.4064)
			(stroke
				(width 0.1)
				(type default)
			)
			(layer "F.Fab")
		)
		(fp_line
			(start -0.8636 0.4572)
			(end -0.8636 0.4064)
			(stroke
				(width 0.1)
				(type default)
			)
			(layer "F.Fab")
		)
		(fp_line
			(start 0.8636 -0.4572)
			(end 0.8636 -0.4064)
			(stroke
				(width 0.1)
				(type default)
			)
			(layer "F.Fab")
		)
		(fp_line
			(start 0.8636 -0.4064)
			(end 1.1938 -0.4064)
			(stroke
				(width 0.1)
				(type default)
			)
			(layer "F.Fab")
		)
		(fp_line
			(start 0.8636 0.4064)
			(end 0.8636 0.4572)
			(stroke
				(width 0.1)
				(type default)
			)
			(layer "F.Fab")
		)
		(fp_line
			(start 0.8636 0.4572)
			(end -0.8636 0.4572)
			(stroke
				(width 0.1)
				(type default)
			)
			(layer "F.Fab")
		)
		(fp_line
			(start 1.1938 -0.4064)
			(end 1.1938 0.4064)
			(stroke
				(width 0.1)
				(type default)
			)
			(layer "F.Fab")
		)
		(fp_line
			(start 1.1938 0.4064)
			(end 0.8636 0.4064)
			(stroke
				(width 0.1)
				(type default)
			)
			(layer "F.Fab")
		)
		(pad "1" smd rect
			(at -0.7366 0 270)
			(size 0.7112 0.8128)
			(layers "F.Cu" "F.Mask" "F.Paste")
			(net "PCEPLL6_VDDA18_PEX2")
		)
		(pad "2" smd rect
			(at 0.7366 0 270)
			(size 0.7112 0.8128)
			(layers "F.Cu" "F.Mask" "F.Paste")
			(net "GND")
		)
	)
	(footprint ""
		(layer "F.Cu")
		(at 261.05612 -32.848042 -90)
		(property "Reference" "R6079"
			(at 0 0 270)
			(layer "F.SilkS")
			(hide yes)
			(effects
				(font
					(size 1.27 1.27)
				)
			)
		)
		(property "Value" ""
			(at 0 0 270)
			(layer "F.Fab")
			(effects
				(font
					(size 1.27 1.27)
				)
			)
		)
		(duplicate_pad_numbers_are_jumpers no)
		(fp_line
			(start -0.7874 0.4064)
			(end -0.7874 -0.4064)
			(stroke
				(width 0.1524)
				(type default)
			)
			(layer "F.SilkS")
		)
		(fp_line
			(start 0.7874 0.4064)
			(end -0.7874 0.4064)
			(stroke
				(width 0.1524)
				(type default)
			)
			(layer "F.SilkS")
		)
		(fp_line
			(start -0.7874 -0.4064)
			(end 0.7874 -0.4064)
			(stroke
				(width 0.1524)
				(type default)
			)
			(layer "F.SilkS")
		)
		(fp_line
			(start 0.7874 -0.4064)
			(end 0.7874 0.4064)
			(stroke
				(width 0.1524)
				(type default)
			)
			(layer "F.SilkS")
		)
		(fp_line
			(start -0.67945 0.3048)
			(end -0.67945 -0.305054)
			(stroke
				(width 0.1)
				(type default)
			)
			(layer "F.Fab")
		)
		(fp_line
			(start -0.12065 0.3048)
			(end -0.67945 0.3048)
			(stroke
				(width 0.1)
				(type default)
			)
			(layer "F.Fab")
		)
		(fp_line
			(start 0.120396 0.3048)
			(end 0.120396 0.2794)
			(stroke
				(width 0.1)
				(type default)
			)
			(layer "F.Fab")
		)
		(fp_line
			(start 0.67945 0.3048)
			(end 0.120396 0.3048)
			(stroke
				(width 0.1)
				(type default)
			)
			(layer "F.Fab")
		)
		(fp_line
			(start -0.12065 0.2794)
			(end -0.12065 0.3048)
			(stroke
				(width 0.1)
				(type default)
			)
			(layer "F.Fab")
		)
		(fp_line
			(start 0.120396 0.2794)
			(end -0.12065 0.2794)
			(stroke
				(width 0.1)
				(type default)
			)
			(layer "F.Fab")
		)
		(fp_line
			(start -0.12065 -0.2794)
			(end 0.12065 -0.2794)
			(stroke
				(width 0.1)
				(type default)
			)
			(layer "F.Fab")
		)
		(fp_line
			(start 0.12065 -0.2794)
			(end 0.12065 -0.3048)
			(stroke
				(width 0.1)
				(type default)
			)
			(layer "F.Fab")
		)
		(fp_line
			(start 0.12065 -0.3048)
			(end 0.67945 -0.3048)
			(stroke
				(width 0.1)
				(type default)
			)
			(layer "F.Fab")
		)
		(fp_line
			(start 0.67945 -0.3048)
			(end 0.67945 0.3048)
			(stroke
				(width 0.1)
				(type default)
			)
			(layer "F.Fab")
		)
		(fp_line
			(start -0.67945 -0.305054)
			(end -0.12065 -0.305054)
			(stroke
				(width 0.1)
				(type default)
			)
			(layer "F.Fab")
		)
		(fp_line
			(start -0.12065 -0.305054)
			(end -0.12065 -0.2794)
			(stroke
				(width 0.1)
				(type default)
			)
			(layer "F.Fab")
		)
		(pad "1" smd circle
			(at -0.40005 0 270)
			(size 0 0)
			(layers "F.Cu" "F.Mask" "F.Paste")
			(net "SSD9_AUX_P3V3_EN_R")
		)
		(pad "2" smd circle
			(at 0.40005 0 270)
			(size 0 0)
			(layers "F.Cu" "F.Mask" "F.Paste")
			(net "P3V3_SSD9_CO_EN")
		)
	)
	(footprint ""
		(layer "F.Cu")
		(at 123.31319 -110.722918 -90)
		(property "Reference" "R5825"
			(at 0 0 270)
			(layer "F.SilkS")
			(hide yes)
			(effects
				(font
					(size 1.27 1.27)
				)
			)
		)
		(property "Value" ""
			(at 0 0 270)
			(layer "F.Fab")
			(effects
				(font
					(size 1.27 1.27)
				)
			)
		)
		(duplicate_pad_numbers_are_jumpers no)
		(fp_line
			(start -0.7874 0.4064)
			(end -0.7874 -0.4064)
			(stroke
				(width 0.1524)
				(type default)
			)
			(layer "F.SilkS")
		)
		(fp_line
			(start 0.7874 0.4064)
			(end -0.7874 0.4064)
			(stroke
				(width 0.1524)
				(type default)
			)
			(layer "F.SilkS")
		)
		(fp_line
			(start -0.7874 -0.4064)
			(end 0.7874 -0.4064)
			(stroke
				(width 0.1524)
				(type default)
			)
			(layer "F.SilkS")
		)
		(fp_line
			(start 0.7874 -0.4064)
			(end 0.7874 0.4064)
			(stroke
				(width 0.1524)
				(type default)
			)
			(layer "F.SilkS")
		)
		(fp_line
			(start -0.67945 0.3048)
			(end -0.67945 -0.305054)
			(stroke
				(width 0.1)
				(type default)
			)
			(layer "F.Fab")
		)
		(fp_line
			(start -0.12065 0.3048)
			(end -0.67945 0.3048)
			(stroke
				(width 0.1)
				(type default)
			)
			(layer "F.Fab")
		)
		(fp_line
			(start 0.120396 0.3048)
			(end 0.120396 0.2794)
			(stroke
				(width 0.1)
				(type default)
			)
			(layer "F.Fab")
		)
		(fp_line
			(start 0.67945 0.3048)
			(end 0.120396 0.3048)
			(stroke
				(width 0.1)
				(type default)
			)
			(layer "F.Fab")
		)
		(fp_line
			(start -0.12065 0.2794)
			(end -0.12065 0.3048)
			(stroke
				(width 0.1)
				(type default)
			)
			(layer "F.Fab")
		)
		(fp_line
			(start 0.120396 0.2794)
			(end -0.12065 0.2794)
			(stroke
				(width 0.1)
				(type default)
			)
			(layer "F.Fab")
		)
		(fp_line
			(start -0.12065 -0.2794)
			(end 0.12065 -0.2794)
			(stroke
				(width 0.1)
				(type default)
			)
			(layer "F.Fab")
		)
		(fp_line
			(start 0.12065 -0.2794)
			(end 0.12065 -0.3048)
			(stroke
				(width 0.1)
				(type default)
			)
			(layer "F.Fab")
		)
		(fp_line
			(start 0.12065 -0.3048)
			(end 0.67945 -0.3048)
			(stroke
				(width 0.1)
				(type default)
			)
			(layer "F.Fab")
		)
		(fp_line
			(start 0.67945 -0.3048)
			(end 0.67945 0.3048)
			(stroke
				(width 0.1)
				(type default)
			)
			(layer "F.Fab")
		)
		(fp_line
			(start -0.67945 -0.305054)
			(end -0.12065 -0.305054)
			(stroke
				(width 0.1)
				(type default)
			)
			(layer "F.Fab")
		)
		(fp_line
			(start -0.12065 -0.305054)
			(end -0.12065 -0.2794)
			(stroke
				(width 0.1)
				(type default)
			)
			(layer "F.Fab")
		)
		(pad "1" smd circle
			(at -0.40005 0 270)
			(size 0 0)
			(layers "F.Cu" "F.Mask" "F.Paste")
			(net "P3V3")
		)
		(pad "2" smd circle
			(at 0.40005 0 270)
			(size 0 0)
			(layers "F.Cu" "F.Mask" "F.Paste")
			(net "PWRGD_P3V3_D")
		)
	)
	(footprint ""
		(layer "F.Cu")
		(at 359.85831 -253.178564 180)
		(property "Reference" "PR124"
			(at 0 0 180)
			(layer "F.SilkS")
			(hide yes)
			(effects
				(font
					(size 1.27 1.27)
				)
			)
		)
		(property "Value" ""
			(at 0 0 180)
			(layer "F.Fab")
			(effects
				(font
					(size 1.27 1.27)
				)
			)
		)
		(duplicate_pad_numbers_are_jumpers no)
		(fp_line
			(start 0.7874 0.4064)
			(end -0.7874 0.4064)
			(stroke
				(width 0.1524)
				(type default)
			)
			(layer "F.SilkS")
		)
		(fp_line
			(start 0.7874 -0.4064)
			(end 0.7874 0.4064)
			(stroke
				(width 0.1524)
				(type default)
			)
			(layer "F.SilkS")
		)
		(fp_line
			(start -0.7874 0.4064)
			(end -0.7874 -0.4064)
			(stroke
				(width 0.1524)
				(type default)
			)
			(layer "F.SilkS")
		)
		(fp_line
			(start -0.7874 -0.4064)
			(end 0.7874 -0.4064)
			(stroke
				(width 0.1524)
				(type default)
			)
			(layer "F.SilkS")
		)
		(fp_line
			(start 0.67945 0.3048)
			(end 0.120396 0.3048)
			(stroke
				(width 0.1)
				(type default)
			)
			(layer "F.Fab")
		)
		(fp_line
			(start 0.67945 -0.3048)
			(end 0.67945 0.3048)
			(stroke
				(width 0.1)
				(type default)
			)
			(layer "F.Fab")
		)
		(fp_line
			(start 0.12065 -0.2794)
			(end 0.12065 -0.3048)
			(stroke
				(width 0.1)
				(type default)
			)
			(layer "F.Fab")
		)
		(fp_line
			(start 0.12065 -0.3048)
			(end 0.67945 -0.3048)
			(stroke
				(width 0.1)
				(type default)
			)
			(layer "F.Fab")
		)
		(fp_line
			(start 0.120396 0.3048)
			(end 0.120396 0.2794)
			(stroke
				(width 0.1)
				(type default)
			)
			(layer "F.Fab")
		)
		(fp_line
			(start 0.120396 0.2794)
			(end -0.12065 0.2794)
			(stroke
				(width 0.1)
				(type default)
			)
			(layer "F.Fab")
		)
		(fp_line
			(start -0.12065 0.3048)
			(end -0.67945 0.3048)
			(stroke
				(width 0.1)
				(type default)
			)
			(layer "F.Fab")
		)
		(fp_line
			(start -0.12065 0.2794)
			(end -0.12065 0.3048)
			(stroke
				(width 0.1)
				(type default)
			)
			(layer "F.Fab")
		)
		(fp_line
			(start -0.12065 -0.2794)
			(end 0.12065 -0.2794)
			(stroke
				(width 0.1)
				(type default)
			)
			(layer "F.Fab")
		)
		(fp_line
			(start -0.12065 -0.305054)
			(end -0.12065 -0.2794)
			(stroke
				(width 0.1)
				(type default)
			)
			(layer "F.Fab")
		)
		(fp_line
			(start -0.67945 0.3048)
			(end -0.67945 -0.305054)
			(stroke
				(width 0.1)
				(type default)
			)
			(layer "F.Fab")
		)
		(fp_line
			(start -0.67945 -0.305054)
			(end -0.12065 -0.305054)
			(stroke
				(width 0.1)
				(type default)
			)
			(layer "F.Fab")
		)
		(pad "1" smd circle
			(at -0.40005 0 180)
			(size 0 0)
			(layers "F.Cu" "F.Mask" "F.Paste")
			(net "P3V3_AUX")
		)
		(pad "2" smd circle
			(at 0.40005 0 180)
			(size 0 0)
			(layers "F.Cu" "F.Mask" "F.Paste")
			(net "P0V8_PEX2_SMBALERT")
		)
	)
	(footprint ""
		(layer "F.Cu")
		(at 226.33686 -275.602192 135)
		(property "Reference" "C630"
			(at 0 0 135)
			(layer "F.SilkS")
			(hide yes)
			(effects
				(font
					(size 1.27 1.27)
				)
			)
		)
		(property "Value" ""
			(at 0 0 135)
			(layer "F.Fab")
			(effects
				(font
					(size 1.27 1.27)
				)
			)
		)
		(duplicate_pad_numbers_are_jumpers no)
		(fp_line
			(start 0.787389 -0.406267)
			(end 0.787389 0.406267)
			(stroke
				(width 0.1524)
				(type default)
			)
			(layer "F.SilkS")
		)
		(fp_line
			(start 0.787389 0.406267)
			(end -0.787389 0.406267)
			(stroke
				(width 0.1524)
				(type default)
			)
			(layer "F.SilkS")
		)
		(fp_line
			(start -0.787389 -0.406267)
			(end 0.787389 -0.406267)
			(stroke
				(width 0.1524)
				(type default)
			)
			(layer "F.SilkS")
		)
		(fp_line
			(start -0.787389 0.406267)
			(end -0.787389 -0.406267)
			(stroke
				(width 0.1524)
				(type default)
			)
			(layer "F.SilkS")
		)
		(fp_line
			(start 0.679446 -0.30479)
			(end 0.679446 0.30479)
			(stroke
				(width 0.1)
				(type default)
			)
			(layer "F.Fab")
		)
		(fp_line
			(start 0.120515 -0.30479)
			(end 0.679446 -0.30479)
			(stroke
				(width 0.1)
				(type default)
			)
			(layer "F.Fab")
		)
		(fp_line
			(start 0.120695 -0.279466)
			(end 0.120515 -0.30479)
			(stroke
				(width 0.1)
				(type default)
			)
			(layer "F.Fab")
		)
		(fp_line
			(start 0.679446 0.30479)
			(end 0.120515 0.30479)
			(stroke
				(width 0.1)
				(type default)
			)
			(layer "F.Fab")
		)
		(fp_line
			(start -0.120695 -0.304969)
			(end -0.120695 -0.279466)
			(stroke
				(width 0.1)
				(type default)
			)
			(layer "F.Fab")
		)
		(fp_line
			(start -0.120695 -0.279466)
			(end 0.120695 -0.279466)
			(stroke
				(width 0.1)
				(type default)
			)
			(layer "F.Fab")
		)
		(fp_line
			(start 0.120335 0.279466)
			(end -0.120695 0.279466)
			(stroke
				(width 0.1)
				(type default)
			)
			(layer "F.Fab")
		)
		(fp_line
			(start 0.120515 0.30479)
			(end 0.120335 0.279466)
			(stroke
				(width 0.1)
				(type default)
			)
			(layer "F.Fab")
		)
		(fp_line
			(start -0.679446 -0.305149)
			(end -0.120695 -0.304969)
			(stroke
				(width 0.1)
				(type default)
			)
			(layer "F.Fab")
		)
		(fp_line
			(start -0.120695 0.279466)
			(end -0.120515 0.30479)
			(stroke
				(width 0.1)
				(type default)
			)
			(layer "F.Fab")
		)
		(fp_line
			(start -0.120515 0.30479)
			(end -0.679446 0.30479)
			(stroke
				(width 0.1)
				(type default)
			)
			(layer "F.Fab")
		)
		(fp_line
			(start -0.679446 0.30479)
			(end -0.679446 -0.305149)
			(stroke
				(width 0.1)
				(type default)
			)
			(layer "F.Fab")
		)
		(pad "1" smd circle
			(at -0.40005 0 135)
			(size 0 0)
			(layers "F.Cu" "F.Mask" "F.Paste")
			(net "P12V_PEX1_P1V25_VIN_P")
		)
		(pad "2" smd circle
			(at 0.40005 0 135)
			(size 0 0)
			(layers "F.Cu" "F.Mask" "F.Paste")
			(net "P12V_PEX1_P1V25_VIN_N")
		)
	)
	(footprint ""
		(layer "F.Cu")
		(at 201.06894 -405.895302 -90)
		(property "Reference" "C4006"
			(at 0 0 270)
			(layer "F.SilkS")
			(hide yes)
			(effects
				(font
					(size 1.27 1.27)
				)
			)
		)
		(property "Value" ""
			(at 0 0 270)
			(layer "F.Fab")
			(effects
				(font
					(size 1.27 1.27)
				)
			)
		)
		(duplicate_pad_numbers_are_jumpers no)
		(fp_line
			(start -0.7874 0.4064)
			(end -0.7874 -0.4064)
			(stroke
				(width 0.1524)
				(type default)
			)
			(layer "F.SilkS")
		)
		(fp_line
			(start 0.7874 0.4064)
			(end -0.7874 0.4064)
			(stroke
				(width 0.1524)
				(type default)
			)
			(layer "F.SilkS")
		)
		(fp_line
			(start -0.7874 -0.4064)
			(end 0.7874 -0.4064)
			(stroke
				(width 0.1524)
				(type default)
			)
			(layer "F.SilkS")
		)
		(fp_line
			(start 0.7874 -0.4064)
			(end 0.7874 0.4064)
			(stroke
				(width 0.1524)
				(type default)
			)
			(layer "F.SilkS")
		)
		(fp_line
			(start -0.67945 0.3048)
			(end -0.67945 -0.305054)
			(stroke
				(width 0.1)
				(type default)
			)
			(layer "F.Fab")
		)
		(fp_line
			(start -0.12065 0.3048)
			(end -0.67945 0.3048)
			(stroke
				(width 0.1)
				(type default)
			)
			(layer "F.Fab")
		)
		(fp_line
			(start 0.120396 0.3048)
			(end 0.120396 0.2794)
			(stroke
				(width 0.1)
				(type default)
			)
			(layer "F.Fab")
		)
		(fp_line
			(start 0.67945 0.3048)
			(end 0.120396 0.3048)
			(stroke
				(width 0.1)
				(type default)
			)
			(layer "F.Fab")
		)
		(fp_line
			(start -0.12065 0.2794)
			(end -0.12065 0.3048)
			(stroke
				(width 0.1)
				(type default)
			)
			(layer "F.Fab")
		)
		(fp_line
			(start 0.120396 0.2794)
			(end -0.12065 0.2794)
			(stroke
				(width 0.1)
				(type default)
			)
			(layer "F.Fab")
		)
		(fp_line
			(start -0.12065 -0.2794)
			(end 0.12065 -0.2794)
			(stroke
				(width 0.1)
				(type default)
			)
			(layer "F.Fab")
		)
		(fp_line
			(start 0.12065 -0.2794)
			(end 0.12065 -0.3048)
			(stroke
				(width 0.1)
				(type default)
			)
			(layer "F.Fab")
		)
		(fp_line
			(start 0.12065 -0.3048)
			(end 0.67945 -0.3048)
			(stroke
				(width 0.1)
				(type default)
			)
			(layer "F.Fab")
		)
		(fp_line
			(start 0.67945 -0.3048)
			(end 0.67945 0.3048)
			(stroke
				(width 0.1)
				(type default)
			)
			(layer "F.Fab")
		)
		(fp_line
			(start -0.67945 -0.305054)
			(end -0.12065 -0.305054)
			(stroke
				(width 0.1)
				(type default)
			)
			(layer "F.Fab")
		)
		(fp_line
			(start -0.12065 -0.305054)
			(end -0.12065 -0.2794)
			(stroke
				(width 0.1)
				(type default)
			)
			(layer "F.Fab")
		)
		(pad "1" smd circle
			(at -0.40005 0 270)
			(size 0 0)
			(layers "F.Cu" "F.Mask" "F.Paste")
			(net "MB_HSC_EN")
		)
		(pad "2" smd circle
			(at 0.40005 0 270)
			(size 0 0)
			(layers "F.Cu" "F.Mask" "F.Paste")
			(net "GND")
		)
	)
	(footprint ""
		(layer "F.Cu")
		(at 355.854 -166.624)
		(property "Reference" "R4744"
			(at 0 0 0)
			(layer "F.SilkS")
			(hide yes)
			(effects
				(font
					(size 1.27 1.27)
				)
			)
		)
		(property "Value" ""
			(at 0 0 0)
			(layer "F.Fab")
			(effects
				(font
					(size 1.27 1.27)
				)
			)
		)
		(duplicate_pad_numbers_are_jumpers no)
		(fp_line
			(start -0.7874 -0.4064)
			(end 0.7874 -0.4064)
			(stroke
				(width 0.1524)
				(type default)
			)
			(layer "F.SilkS")
		)
		(fp_line
			(start -0.7874 0.4064)
			(end -0.7874 -0.4064)
			(stroke
				(width 0.1524)
				(type default)
			)
			(layer "F.SilkS")
		)
		(fp_line
			(start 0.7874 -0.4064)
			(end 0.7874 0.4064)
			(stroke
				(width 0.1524)
				(type default)
			)
			(layer "F.SilkS")
		)
		(fp_line
			(start 0.7874 0.4064)
			(end -0.7874 0.4064)
			(stroke
				(width 0.1524)
				(type default)
			)
			(layer "F.SilkS")
		)
		(fp_line
			(start -0.67945 -0.305054)
			(end -0.12065 -0.305054)
			(stroke
				(width 0.1)
				(type default)
			)
			(layer "F.Fab")
		)
		(fp_line
			(start -0.67945 0.3048)
			(end -0.67945 -0.305054)
			(stroke
				(width 0.1)
				(type default)
			)
			(layer "F.Fab")
		)
		(fp_line
			(start -0.12065 -0.305054)
			(end -0.12065 -0.2794)
			(stroke
				(width 0.1)
				(type default)
			)
			(layer "F.Fab")
		)
		(fp_line
			(start -0.12065 -0.2794)
			(end 0.12065 -0.2794)
			(stroke
				(width 0.1)
				(type default)
			)
			(layer "F.Fab")
		)
		(fp_line
			(start -0.12065 0.2794)
			(end -0.12065 0.3048)
			(stroke
				(width 0.1)
				(type default)
			)
			(layer "F.Fab")
		)
		(fp_line
			(start -0.12065 0.3048)
			(end -0.67945 0.3048)
			(stroke
				(width 0.1)
				(type default)
			)
			(layer "F.Fab")
		)
		(fp_line
			(start 0.120396 0.2794)
			(end -0.12065 0.2794)
			(stroke
				(width 0.1)
				(type default)
			)
			(layer "F.Fab")
		)
		(fp_line
			(start 0.120396 0.3048)
			(end 0.120396 0.2794)
			(stroke
				(width 0.1)
				(type default)
			)
			(layer "F.Fab")
		)
		(fp_line
			(start 0.12065 -0.3048)
			(end 0.67945 -0.3048)
			(stroke
				(width 0.1)
				(type default)
			)
			(layer "F.Fab")
		)
		(fp_line
			(start 0.12065 -0.2794)
			(end 0.12065 -0.3048)
			(stroke
				(width 0.1)
				(type default)
			)
			(layer "F.Fab")
		)
		(fp_line
			(start 0.67945 -0.3048)
			(end 0.67945 0.3048)
			(stroke
				(width 0.1)
				(type default)
			)
			(layer "F.Fab")
		)
		(fp_line
			(start 0.67945 0.3048)
			(end 0.120396 0.3048)
			(stroke
				(width 0.1)
				(type default)
			)
			(layer "F.Fab")
		)
		(pad "1" smd circle
			(at -0.40005 0)
			(size 0 0)
			(layers "F.Cu" "F.Mask" "F.Paste")
			(net "NIC5_PEX_PWR_EN_R")
		)
		(pad "2" smd circle
			(at 0.40005 0)
			(size 0 0)
			(layers "F.Cu" "F.Mask" "F.Paste")
			(net "GND")
		)
	)
	(footprint ""
		(layer "F.Cu")
		(at 342.624918 -201.168 90)
		(property "Reference" "R6416"
			(at 0 0 90)
			(layer "F.SilkS")
			(hide yes)
			(effects
				(font
					(size 1.27 1.27)
				)
			)
		)
		(property "Value" ""
			(at 0 0 90)
			(layer "F.Fab")
			(effects
				(font
					(size 1.27 1.27)
				)
			)
		)
		(duplicate_pad_numbers_are_jumpers no)
		(fp_line
			(start 0.7874 -0.4064)
			(end 0.7874 0.4064)
			(stroke
				(width 0.1524)
				(type default)
			)
			(layer "F.SilkS")
		)
		(fp_line
			(start -0.7874 -0.4064)
			(end 0.7874 -0.4064)
			(stroke
				(width 0.1524)
				(type default)
			)
			(layer "F.SilkS")
		)
		(fp_line
			(start 0.7874 0.4064)
			(end -0.7874 0.4064)
			(stroke
				(width 0.1524)
				(type default)
			)
			(layer "F.SilkS")
		)
		(fp_line
			(start -0.7874 0.4064)
			(end -0.7874 -0.4064)
			(stroke
				(width 0.1524)
				(type default)
			)
			(layer "F.SilkS")
		)
		(fp_line
			(start -0.12065 -0.305054)
			(end -0.12065 -0.2794)
			(stroke
				(width 0.1)
				(type default)
			)
			(layer "F.Fab")
		)
		(fp_line
			(start -0.67945 -0.305054)
			(end -0.12065 -0.305054)
			(stroke
				(width 0.1)
				(type default)
			)
			(layer "F.Fab")
		)
		(fp_line
			(start 0.67945 -0.3048)
			(end 0.67945 0.3048)
			(stroke
				(width 0.1)
				(type default)
			)
			(layer "F.Fab")
		)
		(fp_line
			(start 0.12065 -0.3048)
			(end 0.67945 -0.3048)
			(stroke
				(width 0.1)
				(type default)
			)
			(layer "F.Fab")
		)
		(fp_line
			(start 0.12065 -0.2794)
			(end 0.12065 -0.3048)
			(stroke
				(width 0.1)
				(type default)
			)
			(layer "F.Fab")
		)
		(fp_line
			(start -0.12065 -0.2794)
			(end 0.12065 -0.2794)
			(stroke
				(width 0.1)
				(type default)
			)
			(layer "F.Fab")
		)
		(fp_line
			(start 0.120396 0.2794)
			(end -0.12065 0.2794)
			(stroke
				(width 0.1)
				(type default)
			)
			(layer "F.Fab")
		)
		(fp_line
			(start -0.12065 0.2794)
			(end -0.12065 0.3048)
			(stroke
				(width 0.1)
				(type default)
			)
			(layer "F.Fab")
		)
		(fp_line
			(start 0.67945 0.3048)
			(end 0.120396 0.3048)
			(stroke
				(width 0.1)
				(type default)
			)
			(layer "F.Fab")
		)
		(fp_line
			(start 0.120396 0.3048)
			(end 0.120396 0.2794)
			(stroke
				(width 0.1)
				(type default)
			)
			(layer "F.Fab")
		)
		(fp_line
			(start -0.12065 0.3048)
			(end -0.67945 0.3048)
			(stroke
				(width 0.1)
				(type default)
			)
			(layer "F.Fab")
		)
		(fp_line
			(start -0.67945 0.3048)
			(end -0.67945 -0.305054)
			(stroke
				(width 0.1)
				(type default)
			)
			(layer "F.Fab")
		)
		(pad "1" smd circle
			(at -0.40005 0 90)
			(size 0 0)
			(layers "F.Cu" "F.Mask" "F.Paste")
			(net "FPGA_PEX0_MODE_SEL2_R")
		)
		(pad "2" smd circle
			(at 0.40005 0 90)
			(size 0 0)
			(layers "F.Cu" "F.Mask" "F.Paste")
			(net "FPGA_PEX0_MODE_SEL2")
		)
	)
	(footprint ""
		(layer "F.Cu")
		(at 260.606286 -250.070874 -90)
		(property "Reference" "R1334"
			(at 0 0 270)
			(layer "F.SilkS")
			(hide yes)
			(effects
				(font
					(size 1.27 1.27)
				)
			)
		)
		(property "Value" ""
			(at 0 0 270)
			(layer "F.Fab")
			(effects
				(font
					(size 1.27 1.27)
				)
			)
		)
		(duplicate_pad_numbers_are_jumpers no)
		(fp_line
			(start -0.7874 0.4064)
			(end -0.7874 -0.4064)
			(stroke
				(width 0.1524)
				(type default)
			)
			(layer "F.SilkS")
		)
		(fp_line
			(start 0.7874 0.4064)
			(end -0.7874 0.4064)
			(stroke
				(width 0.1524)
				(type default)
			)
			(layer "F.SilkS")
		)
		(fp_line
			(start -0.7874 -0.4064)
			(end 0.7874 -0.4064)
			(stroke
				(width 0.1524)
				(type default)
			)
			(layer "F.SilkS")
		)
		(fp_line
			(start 0.7874 -0.4064)
			(end 0.7874 0.4064)
			(stroke
				(width 0.1524)
				(type default)
			)
			(layer "F.SilkS")
		)
		(fp_line
			(start -0.67945 0.3048)
			(end -0.67945 -0.305054)
			(stroke
				(width 0.1)
				(type default)
			)
			(layer "F.Fab")
		)
		(fp_line
			(start -0.12065 0.3048)
			(end -0.67945 0.3048)
			(stroke
				(width 0.1)
				(type default)
			)
			(layer "F.Fab")
		)
		(fp_line
			(start 0.120396 0.3048)
			(end 0.120396 0.2794)
			(stroke
				(width 0.1)
				(type default)
			)
			(layer "F.Fab")
		)
		(fp_line
			(start 0.67945 0.3048)
			(end 0.120396 0.3048)
			(stroke
				(width 0.1)
				(type default)
			)
			(layer "F.Fab")
		)
		(fp_line
			(start -0.12065 0.2794)
			(end -0.12065 0.3048)
			(stroke
				(width 0.1)
				(type default)
			)
			(layer "F.Fab")
		)
		(fp_line
			(start 0.120396 0.2794)
			(end -0.12065 0.2794)
			(stroke
				(width 0.1)
				(type default)
			)
			(layer "F.Fab")
		)
		(fp_line
			(start -0.12065 -0.2794)
			(end 0.12065 -0.2794)
			(stroke
				(width 0.1)
				(type default)
			)
			(layer "F.Fab")
		)
		(fp_line
			(start 0.12065 -0.2794)
			(end 0.12065 -0.3048)
			(stroke
				(width 0.1)
				(type default)
			)
			(layer "F.Fab")
		)
		(fp_line
			(start 0.12065 -0.3048)
			(end 0.67945 -0.3048)
			(stroke
				(width 0.1)
				(type default)
			)
			(layer "F.Fab")
		)
		(fp_line
			(start 0.67945 -0.3048)
			(end 0.67945 0.3048)
			(stroke
				(width 0.1)
				(type default)
			)
			(layer "F.Fab")
		)
		(fp_line
			(start -0.67945 -0.305054)
			(end -0.12065 -0.305054)
			(stroke
				(width 0.1)
				(type default)
			)
			(layer "F.Fab")
		)
		(fp_line
			(start -0.12065 -0.305054)
			(end -0.12065 -0.2794)
			(stroke
				(width 0.1)
				(type default)
			)
			(layer "F.Fab")
		)
		(pad "1" smd circle
			(at -0.40005 0 270)
			(size 0 0)
			(layers "F.Cu" "F.Mask" "F.Paste")
			(net "PEX2_DBG_MODE3")
		)
		(pad "2" smd circle
			(at 0.40005 0 270)
			(size 0 0)
			(layers "F.Cu" "F.Mask" "F.Paste")
			(net "P1V8_PEX")
		)
	)
	(footprint ""
		(layer "F.Cu")
		(at 353.822 -166.624)
		(property "Reference" "R4777"
			(at 0 0 0)
			(layer "F.SilkS")
			(hide yes)
			(effects
				(font
					(size 1.27 1.27)
				)
			)
		)
		(property "Value" ""
			(at 0 0 0)
			(layer "F.Fab")
			(effects
				(font
					(size 1.27 1.27)
				)
			)
		)
		(duplicate_pad_numbers_are_jumpers no)
		(fp_line
			(start -0.7874 -0.4064)
			(end 0.7874 -0.4064)
			(stroke
				(width 0.1524)
				(type default)
			)
			(layer "F.SilkS")
		)
		(fp_line
			(start -0.7874 0.4064)
			(end -0.7874 -0.4064)
			(stroke
				(width 0.1524)
				(type default)
			)
			(layer "F.SilkS")
		)
		(fp_line
			(start 0.7874 -0.4064)
			(end 0.7874 0.4064)
			(stroke
				(width 0.1524)
				(type default)
			)
			(layer "F.SilkS")
		)
		(fp_line
			(start 0.7874 0.4064)
			(end -0.7874 0.4064)
			(stroke
				(width 0.1524)
				(type default)
			)
			(layer "F.SilkS")
		)
		(fp_line
			(start -0.67945 -0.305054)
			(end -0.12065 -0.305054)
			(stroke
				(width 0.1)
				(type default)
			)
			(layer "F.Fab")
		)
		(fp_line
			(start -0.67945 0.3048)
			(end -0.67945 -0.305054)
			(stroke
				(width 0.1)
				(type default)
			)
			(layer "F.Fab")
		)
		(fp_line
			(start -0.12065 -0.305054)
			(end -0.12065 -0.2794)
			(stroke
				(width 0.1)
				(type default)
			)
			(layer "F.Fab")
		)
		(fp_line
			(start -0.12065 -0.2794)
			(end 0.12065 -0.2794)
			(stroke
				(width 0.1)
				(type default)
			)
			(layer "F.Fab")
		)
		(fp_line
			(start -0.12065 0.2794)
			(end -0.12065 0.3048)
			(stroke
				(width 0.1)
				(type default)
			)
			(layer "F.Fab")
		)
		(fp_line
			(start -0.12065 0.3048)
			(end -0.67945 0.3048)
			(stroke
				(width 0.1)
				(type default)
			)
			(layer "F.Fab")
		)
		(fp_line
			(start 0.120396 0.2794)
			(end -0.12065 0.2794)
			(stroke
				(width 0.1)
				(type default)
			)
			(layer "F.Fab")
		)
		(fp_line
			(start 0.120396 0.3048)
			(end 0.120396 0.2794)
			(stroke
				(width 0.1)
				(type default)
			)
			(layer "F.Fab")
		)
		(fp_line
			(start 0.12065 -0.3048)
			(end 0.67945 -0.3048)
			(stroke
				(width 0.1)
				(type default)
			)
			(layer "F.Fab")
		)
		(fp_line
			(start 0.12065 -0.2794)
			(end 0.12065 -0.3048)
			(stroke
				(width 0.1)
				(type default)
			)
			(layer "F.Fab")
		)
		(fp_line
			(start 0.67945 -0.3048)
			(end 0.67945 0.3048)
			(stroke
				(width 0.1)
				(type default)
			)
			(layer "F.Fab")
		)
		(fp_line
			(start 0.67945 0.3048)
			(end 0.120396 0.3048)
			(stroke
				(width 0.1)
				(type default)
			)
			(layer "F.Fab")
		)
		(pad "1" smd circle
			(at -0.40005 0)
			(size 0 0)
			(layers "F.Cu" "F.Mask" "F.Paste")
			(net "NIC5_PEX_PWR_EN")
		)
		(pad "2" smd circle
			(at 0.40005 0)
			(size 0 0)
			(layers "F.Cu" "F.Mask" "F.Paste")
			(net "NIC5_PEX_PWR_EN_R")
		)
	)
	(footprint ""
		(layer "F.Cu")
		(at 231.874314 -261.137654 180)
		(property "Reference" "C4336"
			(at 0 0 180)
			(layer "F.SilkS")
			(hide yes)
			(effects
				(font
					(size 1.27 1.27)
				)
			)
		)
		(property "Value" ""
			(at 0 0 180)
			(layer "F.Fab")
			(effects
				(font
					(size 1.27 1.27)
				)
			)
		)
		(duplicate_pad_numbers_are_jumpers no)
		(fp_line
			(start 0.299974 0.150114)
			(end -0.299974 0.150114)
			(stroke
				(width 0.1)
				(type default)
			)
			(layer "F.Fab")
		)
		(fp_line
			(start 0.299974 -0.150114)
			(end 0.299974 0.150114)
			(stroke
				(width 0.1)
				(type default)
			)
			(layer "F.Fab")
		)
		(fp_line
			(start -0.299974 0.150114)
			(end -0.299974 -0.150114)
			(stroke
				(width 0.1)
				(type default)
			)
			(layer "F.Fab")
		)
		(fp_line
			(start -0.299974 -0.150114)
			(end 0.299974 -0.150114)
			(stroke
				(width 0.1)
				(type default)
			)
			(layer "F.Fab")
		)
		(pad "1" smd rect
			(at -0.2667 0 180)
			(size 0.3048 0.381)
			(layers "F.Cu" "F.Mask" "F.Paste")
			(net "P1V25_SERDES_VDDPLL_PEX2")
		)
		(pad "2" smd rect
			(at 0.2667 0 180)
			(size 0.3048 0.381)
			(layers "F.Cu" "F.Mask" "F.Paste")
			(net "GND")
		)
	)
	(footprint ""
		(layer "F.Cu")
		(at 452.567802 -56.353456)
		(property "Reference" "C2876"
			(at 0 0 0)
			(layer "F.SilkS")
			(hide yes)
			(effects
				(font
					(size 1.27 1.27)
				)
			)
		)
		(property "Value" ""
			(at 0 0 0)
			(layer "F.Fab")
			(effects
				(font
					(size 1.27 1.27)
				)
			)
		)
		(duplicate_pad_numbers_are_jumpers no)
		(fp_line
			(start -0.7874 -0.4064)
			(end 0.7874 -0.4064)
			(stroke
				(width 0.1524)
				(type default)
			)
			(layer "F.SilkS")
		)
		(fp_line
			(start -0.7874 0.4064)
			(end -0.7874 -0.4064)
			(stroke
				(width 0.1524)
				(type default)
			)
			(layer "F.SilkS")
		)
		(fp_line
			(start 0.7874 -0.4064)
			(end 0.7874 0.4064)
			(stroke
				(width 0.1524)
				(type default)
			)
			(layer "F.SilkS")
		)
		(fp_line
			(start 0.7874 0.4064)
			(end -0.7874 0.4064)
			(stroke
				(width 0.1524)
				(type default)
			)
			(layer "F.SilkS")
		)
		(fp_line
			(start -0.67945 -0.305054)
			(end -0.12065 -0.305054)
			(stroke
				(width 0.1)
				(type default)
			)
			(layer "F.Fab")
		)
		(fp_line
			(start -0.67945 0.3048)
			(end -0.67945 -0.305054)
			(stroke
				(width 0.1)
				(type default)
			)
			(layer "F.Fab")
		)
		(fp_line
			(start -0.12065 -0.305054)
			(end -0.12065 -0.2794)
			(stroke
				(width 0.1)
				(type default)
			)
			(layer "F.Fab")
		)
		(fp_line
			(start -0.12065 -0.2794)
			(end 0.12065 -0.2794)
			(stroke
				(width 0.1)
				(type default)
			)
			(layer "F.Fab")
		)
		(fp_line
			(start -0.12065 0.2794)
			(end -0.12065 0.3048)
			(stroke
				(width 0.1)
				(type default)
			)
			(layer "F.Fab")
		)
		(fp_line
			(start -0.12065 0.3048)
			(end -0.67945 0.3048)
			(stroke
				(width 0.1)
				(type default)
			)
			(layer "F.Fab")
		)
		(fp_line
			(start 0.120396 0.2794)
			(end -0.12065 0.2794)
			(stroke
				(width 0.1)
				(type default)
			)
			(layer "F.Fab")
		)
		(fp_line
			(start 0.120396 0.3048)
			(end 0.120396 0.2794)
			(stroke
				(width 0.1)
				(type default)
			)
			(layer "F.Fab")
		)
		(fp_line
			(start 0.12065 -0.3048)
			(end 0.67945 -0.3048)
			(stroke
				(width 0.1)
				(type default)
			)
			(layer "F.Fab")
		)
		(fp_line
			(start 0.12065 -0.2794)
			(end 0.12065 -0.3048)
			(stroke
				(width 0.1)
				(type default)
			)
			(layer "F.Fab")
		)
		(fp_line
			(start 0.67945 -0.3048)
			(end 0.67945 0.3048)
			(stroke
				(width 0.1)
				(type default)
			)
			(layer "F.Fab")
		)
		(fp_line
			(start 0.67945 0.3048)
			(end 0.120396 0.3048)
			(stroke
				(width 0.1)
				(type default)
			)
			(layer "F.Fab")
		)
		(pad "1" smd circle
			(at -0.40005 0)
			(size 0 0)
			(layers "F.Cu" "F.Mask" "F.Paste")
			(net "SSD15_PWR_EN_R")
		)
		(pad "2" smd circle
			(at 0.40005 0)
			(size 0 0)
			(layers "F.Cu" "F.Mask" "F.Paste")
			(net "GND")
		)
	)
	(footprint ""
		(layer "F.Cu")
		(at 445.55791 -72.766682 90)
		(property "Reference" "PC893"
			(at 0 0 90)
			(layer "F.SilkS")
			(hide yes)
			(effects
				(font
					(size 1.27 1.27)
				)
			)
		)
		(property "Value" ""
			(at 0 0 90)
			(layer "F.Fab")
			(effects
				(font
					(size 1.27 1.27)
				)
			)
		)
		(duplicate_pad_numbers_are_jumpers no)
		(fp_line
			(start 0.7874 -0.4064)
			(end 0.7874 0.4064)
			(stroke
				(width 0.1524)
				(type default)
			)
			(layer "F.SilkS")
		)
		(fp_line
			(start -0.7874 -0.4064)
			(end 0.7874 -0.4064)
			(stroke
				(width 0.1524)
				(type default)
			)
			(layer "F.SilkS")
		)
		(fp_line
			(start 0.7874 0.4064)
			(end -0.7874 0.4064)
			(stroke
				(width 0.1524)
				(type default)
			)
			(layer "F.SilkS")
		)
		(fp_line
			(start -0.7874 0.4064)
			(end -0.7874 -0.4064)
			(stroke
				(width 0.1524)
				(type default)
			)
			(layer "F.SilkS")
		)
		(fp_line
			(start -0.12065 -0.305054)
			(end -0.12065 -0.2794)
			(stroke
				(width 0.1)
				(type default)
			)
			(layer "F.Fab")
		)
		(fp_line
			(start -0.67945 -0.305054)
			(end -0.12065 -0.305054)
			(stroke
				(width 0.1)
				(type default)
			)
			(layer "F.Fab")
		)
		(fp_line
			(start 0.67945 -0.3048)
			(end 0.67945 0.3048)
			(stroke
				(width 0.1)
				(type default)
			)
			(layer "F.Fab")
		)
		(fp_line
			(start 0.12065 -0.3048)
			(end 0.67945 -0.3048)
			(stroke
				(width 0.1)
				(type default)
			)
			(layer "F.Fab")
		)
		(fp_line
			(start 0.12065 -0.2794)
			(end 0.12065 -0.3048)
			(stroke
				(width 0.1)
				(type default)
			)
			(layer "F.Fab")
		)
		(fp_line
			(start -0.12065 -0.2794)
			(end 0.12065 -0.2794)
			(stroke
				(width 0.1)
				(type default)
			)
			(layer "F.Fab")
		)
		(fp_line
			(start 0.120396 0.2794)
			(end -0.12065 0.2794)
			(stroke
				(width 0.1)
				(type default)
			)
			(layer "F.Fab")
		)
		(fp_line
			(start -0.12065 0.2794)
			(end -0.12065 0.3048)
			(stroke
				(width 0.1)
				(type default)
			)
			(layer "F.Fab")
		)
		(fp_line
			(start 0.67945 0.3048)
			(end 0.120396 0.3048)
			(stroke
				(width 0.1)
				(type default)
			)
			(layer "F.Fab")
		)
		(fp_line
			(start 0.120396 0.3048)
			(end 0.120396 0.2794)
			(stroke
				(width 0.1)
				(type default)
			)
			(layer "F.Fab")
		)
		(fp_line
			(start -0.12065 0.3048)
			(end -0.67945 0.3048)
			(stroke
				(width 0.1)
				(type default)
			)
			(layer "F.Fab")
		)
		(fp_line
			(start -0.67945 0.3048)
			(end -0.67945 -0.305054)
			(stroke
				(width 0.1)
				(type default)
			)
			(layer "F.Fab")
		)
		(pad "1" smd circle
			(at -0.40005 0 90)
			(size 0 0)
			(layers "F.Cu" "F.Mask" "F.Paste")
			(net "P12V_SSD15_CO_MODE")
		)
		(pad "2" smd circle
			(at 0.40005 0 90)
			(size 0 0)
			(layers "F.Cu" "F.Mask" "F.Paste")
			(net "GND")
		)
	)
	(footprint ""
		(layer "F.Cu")
		(at 312.21934 -118.670324 180)
		(property "Reference" "C454"
			(at 0 0 180)
			(layer "F.SilkS")
			(hide yes)
			(effects
				(font
					(size 1.27 1.27)
				)
			)
		)
		(property "Value" ""
			(at 0 0 180)
			(layer "F.Fab")
			(effects
				(font
					(size 1.27 1.27)
				)
			)
		)
		(duplicate_pad_numbers_are_jumpers no)
		(fp_line
			(start 0.299974 0.150114)
			(end -0.299974 0.150114)
			(stroke
				(width 0.1)
				(type default)
			)
			(layer "F.Fab")
		)
		(fp_line
			(start 0.299974 -0.150114)
			(end 0.299974 0.150114)
			(stroke
				(width 0.1)
				(type default)
			)
			(layer "F.Fab")
		)
		(fp_line
			(start -0.299974 0.150114)
			(end -0.299974 -0.150114)
			(stroke
				(width 0.1)
				(type default)
			)
			(layer "F.Fab")
		)
		(fp_line
			(start -0.299974 -0.150114)
			(end 0.299974 -0.150114)
			(stroke
				(width 0.1)
				(type default)
			)
			(layer "F.Fab")
		)
		(pad "1" smd rect
			(at -0.2667 0 180)
			(size 0.3048 0.381)
			(layers "F.Cu" "F.Mask" "F.Paste")
			(net "P5E_PEX2_STN0_TX_DN<0>")
		)
		(pad "2" smd rect
			(at 0.2667 0 180)
			(size 0.3048 0.381)
			(layers "F.Cu" "F.Mask" "F.Paste")
			(net "P5E_PEX2_STN0_TX_C_DN<0>")
		)
	)
	(footprint ""
		(layer "F.Cu")
		(at 104.009952 -407.599896)
		(property "Reference" "H50"
			(at -4.538218 -5.058918 0)
			(unlocked yes)
			(layer "F.SilkS")
			(effects
				(font
					(size 0.7874 0.5842)
					(thickness 0.1524)
				)
				(justify left)
			)
		)
		(property "Value" ""
			(at 0 0 0)
			(layer "F.Fab")
			(effects
				(font
					(size 1.27 1.27)
				)
			)
		)
		(duplicate_pad_numbers_are_jumpers no)
		(pad "1" thru_hole circle
			(at 0 0)
			(size 10.0076 10.0076)
			(drill 5.6134)
			(layers "*.Cu" "*.Mask")
			(remove_unused_layers no)
			(net "GND")
			(clearance -1.9431)
		)
	)
	(footprint ""
		(layer "F.Cu")
		(at 55.8292 -117.5512)
		(property "Reference" "R6"
			(at 0 0 0)
			(layer "F.SilkS")
			(hide yes)
			(effects
				(font
					(size 1.27 1.27)
				)
			)
		)
		(property "Value" ""
			(at 0 0 0)
			(layer "F.Fab")
			(effects
				(font
					(size 1.27 1.27)
				)
			)
		)
		(duplicate_pad_numbers_are_jumpers no)
		(fp_line
			(start -0.7874 -0.4064)
			(end 0.7874 -0.4064)
			(stroke
				(width 0.1524)
				(type default)
			)
			(layer "F.SilkS")
		)
		(fp_line
			(start -0.7874 0.4064)
			(end -0.7874 -0.4064)
			(stroke
				(width 0.1524)
				(type default)
			)
			(layer "F.SilkS")
		)
		(fp_line
			(start 0.7874 -0.4064)
			(end 0.7874 0.4064)
			(stroke
				(width 0.1524)
				(type default)
			)
			(layer "F.SilkS")
		)
		(fp_line
			(start 0.7874 0.4064)
			(end -0.7874 0.4064)
			(stroke
				(width 0.1524)
				(type default)
			)
			(layer "F.SilkS")
		)
		(fp_line
			(start -0.67945 -0.305054)
			(end -0.12065 -0.305054)
			(stroke
				(width 0.1)
				(type default)
			)
			(layer "F.Fab")
		)
		(fp_line
			(start -0.67945 0.3048)
			(end -0.67945 -0.305054)
			(stroke
				(width 0.1)
				(type default)
			)
			(layer "F.Fab")
		)
		(fp_line
			(start -0.12065 -0.305054)
			(end -0.12065 -0.2794)
			(stroke
				(width 0.1)
				(type default)
			)
			(layer "F.Fab")
		)
		(fp_line
			(start -0.12065 -0.2794)
			(end 0.12065 -0.2794)
			(stroke
				(width 0.1)
				(type default)
			)
			(layer "F.Fab")
		)
		(fp_line
			(start -0.12065 0.2794)
			(end -0.12065 0.3048)
			(stroke
				(width 0.1)
				(type default)
			)
			(layer "F.Fab")
		)
		(fp_line
			(start -0.12065 0.3048)
			(end -0.67945 0.3048)
			(stroke
				(width 0.1)
				(type default)
			)
			(layer "F.Fab")
		)
		(fp_line
			(start 0.120396 0.2794)
			(end -0.12065 0.2794)
			(stroke
				(width 0.1)
				(type default)
			)
			(layer "F.Fab")
		)
		(fp_line
			(start 0.120396 0.3048)
			(end 0.120396 0.2794)
			(stroke
				(width 0.1)
				(type default)
			)
			(layer "F.Fab")
		)
		(fp_line
			(start 0.12065 -0.3048)
			(end 0.67945 -0.3048)
			(stroke
				(width 0.1)
				(type default)
			)
			(layer "F.Fab")
		)
		(fp_line
			(start 0.12065 -0.2794)
			(end 0.12065 -0.3048)
			(stroke
				(width 0.1)
				(type default)
			)
			(layer "F.Fab")
		)
		(fp_line
			(start 0.67945 -0.3048)
			(end 0.67945 0.3048)
			(stroke
				(width 0.1)
				(type default)
			)
			(layer "F.Fab")
		)
		(fp_line
			(start 0.67945 0.3048)
			(end 0.120396 0.3048)
			(stroke
				(width 0.1)
				(type default)
			)
			(layer "F.Fab")
		)
		(pad "1" smd circle
			(at -0.40005 0)
			(size 0 0)
			(layers "F.Cu" "F.Mask" "F.Paste")
			(net "PRSNTB1_NIC0_N")
		)
		(pad "2" smd circle
			(at 0.40005 0)
			(size 0 0)
			(layers "F.Cu" "F.Mask" "F.Paste")
			(net "P3V3_AUX")
		)
	)
	(footprint ""
		(layer "F.Cu")
		(at 371.16258 -350.098614 90)
		(property "Reference" "C778"
			(at 0 0 90)
			(layer "F.SilkS")
			(hide yes)
			(effects
				(font
					(size 1.27 1.27)
				)
			)
		)
		(property "Value" ""
			(at 0 0 90)
			(layer "F.Fab")
			(effects
				(font
					(size 1.27 1.27)
				)
			)
		)
		(duplicate_pad_numbers_are_jumpers no)
		(fp_line
			(start 0.299974 -0.150114)
			(end 0.299974 0.150114)
			(stroke
				(width 0.1)
				(type default)
			)
			(layer "F.Fab")
		)
		(fp_line
			(start -0.299974 -0.150114)
			(end 0.299974 -0.150114)
			(stroke
				(width 0.1)
				(type default)
			)
			(layer "F.Fab")
		)
		(fp_line
			(start 0.299974 0.150114)
			(end -0.299974 0.150114)
			(stroke
				(width 0.1)
				(type default)
			)
			(layer "F.Fab")
		)
		(fp_line
			(start -0.299974 0.150114)
			(end -0.299974 -0.150114)
			(stroke
				(width 0.1)
				(type default)
			)
			(layer "F.Fab")
		)
		(pad "1" smd rect
			(at -0.2667 0 90)
			(size 0.3048 0.381)
			(layers "F.Cu" "F.Mask" "F.Paste")
			(net "P5E_PEX3_STN6_TX_DP<103>")
		)
		(pad "2" smd rect
			(at 0.2667 0 90)
			(size 0.3048 0.381)
			(layers "F.Cu" "F.Mask" "F.Paste")
			(net "P5E_PEX3_STN6_TX_C_DP<103>")
		)
	)
	(footprint ""
		(layer "F.Cu")
		(at 241.51971 -162.003994 90)
		(property "Reference" "PR7033"
			(at 0 0 90)
			(layer "F.SilkS")
			(hide yes)
			(effects
				(font
					(size 1.27 1.27)
				)
			)
		)
		(property "Value" ""
			(at 0 0 90)
			(layer "F.Fab")
			(effects
				(font
					(size 1.27 1.27)
				)
			)
		)
		(duplicate_pad_numbers_are_jumpers no)
		(fp_line
			(start 0.7874 -0.4064)
			(end 0.7874 0.4064)
			(stroke
				(width 0.1524)
				(type default)
			)
			(layer "F.SilkS")
		)
		(fp_line
			(start -0.7874 -0.4064)
			(end 0.7874 -0.4064)
			(stroke
				(width 0.1524)
				(type default)
			)
			(layer "F.SilkS")
		)
		(fp_line
			(start 0.7874 0.4064)
			(end -0.7874 0.4064)
			(stroke
				(width 0.1524)
				(type default)
			)
			(layer "F.SilkS")
		)
		(fp_line
			(start -0.7874 0.4064)
			(end -0.7874 -0.4064)
			(stroke
				(width 0.1524)
				(type default)
			)
			(layer "F.SilkS")
		)
		(fp_line
			(start -0.12065 -0.305054)
			(end -0.12065 -0.2794)
			(stroke
				(width 0.1)
				(type default)
			)
			(layer "F.Fab")
		)
		(fp_line
			(start -0.67945 -0.305054)
			(end -0.12065 -0.305054)
			(stroke
				(width 0.1)
				(type default)
			)
			(layer "F.Fab")
		)
		(fp_line
			(start 0.67945 -0.3048)
			(end 0.67945 0.3048)
			(stroke
				(width 0.1)
				(type default)
			)
			(layer "F.Fab")
		)
		(fp_line
			(start 0.12065 -0.3048)
			(end 0.67945 -0.3048)
			(stroke
				(width 0.1)
				(type default)
			)
			(layer "F.Fab")
		)
		(fp_line
			(start 0.12065 -0.2794)
			(end 0.12065 -0.3048)
			(stroke
				(width 0.1)
				(type default)
			)
			(layer "F.Fab")
		)
		(fp_line
			(start -0.12065 -0.2794)
			(end 0.12065 -0.2794)
			(stroke
				(width 0.1)
				(type default)
			)
			(layer "F.Fab")
		)
		(fp_line
			(start 0.120396 0.2794)
			(end -0.12065 0.2794)
			(stroke
				(width 0.1)
				(type default)
			)
			(layer "F.Fab")
		)
		(fp_line
			(start -0.12065 0.2794)
			(end -0.12065 0.3048)
			(stroke
				(width 0.1)
				(type default)
			)
			(layer "F.Fab")
		)
		(fp_line
			(start 0.67945 0.3048)
			(end 0.120396 0.3048)
			(stroke
				(width 0.1)
				(type default)
			)
			(layer "F.Fab")
		)
		(fp_line
			(start 0.120396 0.3048)
			(end 0.120396 0.2794)
			(stroke
				(width 0.1)
				(type default)
			)
			(layer "F.Fab")
		)
		(fp_line
			(start -0.12065 0.3048)
			(end -0.67945 0.3048)
			(stroke
				(width 0.1)
				(type default)
			)
			(layer "F.Fab")
		)
		(fp_line
			(start -0.67945 0.3048)
			(end -0.67945 -0.305054)
			(stroke
				(width 0.1)
				(type default)
			)
			(layer "F.Fab")
		)
		(pad "1" smd circle
			(at -0.40005 0 90)
			(size 0 0)
			(layers "F.Cu" "F.Mask" "F.Paste")
			(net "P12V_NIC4_CO_IMON_VR")
		)
		(pad "2" smd circle
			(at 0.40005 0 90)
			(size 0 0)
			(layers "F.Cu" "F.Mask" "F.Paste")
			(net "GND")
		)
	)
	(footprint ""
		(layer "F.Cu")
		(at 83.109562 -356.244906 90)
		(property "Reference" "C105"
			(at 0 0 90)
			(layer "F.SilkS")
			(hide yes)
			(effects
				(font
					(size 1.27 1.27)
				)
			)
		)
		(property "Value" ""
			(at 0 0 90)
			(layer "F.Fab")
			(effects
				(font
					(size 1.27 1.27)
				)
			)
		)
		(duplicate_pad_numbers_are_jumpers no)
		(fp_line
			(start 0.299974 -0.150114)
			(end 0.299974 0.150114)
			(stroke
				(width 0.1)
				(type default)
			)
			(layer "F.Fab")
		)
		(fp_line
			(start -0.299974 -0.150114)
			(end 0.299974 -0.150114)
			(stroke
				(width 0.1)
				(type default)
			)
			(layer "F.Fab")
		)
		(fp_line
			(start 0.299974 0.150114)
			(end -0.299974 0.150114)
			(stroke
				(width 0.1)
				(type default)
			)
			(layer "F.Fab")
		)
		(fp_line
			(start -0.299974 0.150114)
			(end -0.299974 -0.150114)
			(stroke
				(width 0.1)
				(type default)
			)
			(layer "F.Fab")
		)
		(pad "1" smd rect
			(at -0.2667 0 90)
			(size 0.3048 0.381)
			(layers "F.Cu" "F.Mask" "F.Paste")
			(net "P5E_PEX0_STN5_TX_DP<91>")
		)
		(pad "2" smd rect
			(at 0.2667 0 90)
			(size 0.3048 0.381)
			(layers "F.Cu" "F.Mask" "F.Paste")
			(net "P5E_PEX0_STN5_TX_C_DP<91>")
		)
	)
	(footprint ""
		(layer "F.Cu")
		(at 425.728892 -343.952322 90)
		(property "Reference" "C2454"
			(at 0 0 90)
			(layer "F.SilkS")
			(hide yes)
			(effects
				(font
					(size 1.27 1.27)
				)
			)
		)
		(property "Value" ""
			(at 0 0 90)
			(layer "F.Fab")
			(effects
				(font
					(size 1.27 1.27)
				)
			)
		)
		(duplicate_pad_numbers_are_jumpers no)
		(fp_line
			(start 0.299974 -0.150114)
			(end 0.299974 0.150114)
			(stroke
				(width 0.1)
				(type default)
			)
			(layer "F.Fab")
		)
		(fp_line
			(start -0.299974 -0.150114)
			(end 0.299974 -0.150114)
			(stroke
				(width 0.1)
				(type default)
			)
			(layer "F.Fab")
		)
		(fp_line
			(start 0.299974 0.150114)
			(end -0.299974 0.150114)
			(stroke
				(width 0.1)
				(type default)
			)
			(layer "F.Fab")
		)
		(fp_line
			(start -0.299974 0.150114)
			(end -0.299974 -0.150114)
			(stroke
				(width 0.1)
				(type default)
			)
			(layer "F.Fab")
		)
		(pad "1" smd rect
			(at -0.2667 0 90)
			(size 0.3048 0.381)
			(layers "F.Cu" "F.Mask" "F.Paste")
			(net "P5E_PEX3_STN4_TX_DN<72>")
		)
		(pad "2" smd rect
			(at 0.2667 0 90)
			(size 0.3048 0.381)
			(layers "F.Cu" "F.Mask" "F.Paste")
			(net "P5E_PEX3_STN4_TX_C_DN<72>")
		)
	)
	(footprint ""
		(layer "F.Cu")
		(at 97.498408 -66.32194 -90)
		(property "Reference" "PC654"
			(at 0 0 270)
			(layer "F.SilkS")
			(hide yes)
			(effects
				(font
					(size 1.27 1.27)
				)
			)
		)
		(property "Value" ""
			(at 0 0 270)
			(layer "F.Fab")
			(effects
				(font
					(size 1.27 1.27)
				)
			)
		)
		(duplicate_pad_numbers_are_jumpers no)
		(fp_line
			(start -0.7874 0.4064)
			(end -0.7874 -0.4064)
			(stroke
				(width 0.1524)
				(type default)
			)
			(layer "F.SilkS")
		)
		(fp_line
			(start 0.7874 0.4064)
			(end -0.7874 0.4064)
			(stroke
				(width 0.1524)
				(type default)
			)
			(layer "F.SilkS")
		)
		(fp_line
			(start -0.7874 -0.4064)
			(end 0.7874 -0.4064)
			(stroke
				(width 0.1524)
				(type default)
			)
			(layer "F.SilkS")
		)
		(fp_line
			(start 0.7874 -0.4064)
			(end 0.7874 0.4064)
			(stroke
				(width 0.1524)
				(type default)
			)
			(layer "F.SilkS")
		)
		(fp_line
			(start -0.67945 0.3048)
			(end -0.67945 -0.305054)
			(stroke
				(width 0.1)
				(type default)
			)
			(layer "F.Fab")
		)
		(fp_line
			(start -0.12065 0.3048)
			(end -0.67945 0.3048)
			(stroke
				(width 0.1)
				(type default)
			)
			(layer "F.Fab")
		)
		(fp_line
			(start 0.120396 0.3048)
			(end 0.120396 0.2794)
			(stroke
				(width 0.1)
				(type default)
			)
			(layer "F.Fab")
		)
		(fp_line
			(start 0.67945 0.3048)
			(end 0.120396 0.3048)
			(stroke
				(width 0.1)
				(type default)
			)
			(layer "F.Fab")
		)
		(fp_line
			(start -0.12065 0.2794)
			(end -0.12065 0.3048)
			(stroke
				(width 0.1)
				(type default)
			)
			(layer "F.Fab")
		)
		(fp_line
			(start 0.120396 0.2794)
			(end -0.12065 0.2794)
			(stroke
				(width 0.1)
				(type default)
			)
			(layer "F.Fab")
		)
		(fp_line
			(start -0.12065 -0.2794)
			(end 0.12065 -0.2794)
			(stroke
				(width 0.1)
				(type default)
			)
			(layer "F.Fab")
		)
		(fp_line
			(start 0.12065 -0.2794)
			(end 0.12065 -0.3048)
			(stroke
				(width 0.1)
				(type default)
			)
			(layer "F.Fab")
		)
		(fp_line
			(start 0.12065 -0.3048)
			(end 0.67945 -0.3048)
			(stroke
				(width 0.1)
				(type default)
			)
			(layer "F.Fab")
		)
		(fp_line
			(start 0.67945 -0.3048)
			(end 0.67945 0.3048)
			(stroke
				(width 0.1)
				(type default)
			)
			(layer "F.Fab")
		)
		(fp_line
			(start -0.67945 -0.305054)
			(end -0.12065 -0.305054)
			(stroke
				(width 0.1)
				(type default)
			)
			(layer "F.Fab")
		)
		(fp_line
			(start -0.12065 -0.305054)
			(end -0.12065 -0.2794)
			(stroke
				(width 0.1)
				(type default)
			)
			(layer "F.Fab")
		)
		(pad "1" smd circle
			(at -0.40005 0 270)
			(size 0 0)
			(layers "F.Cu" "F.Mask" "F.Paste")
			(net "P12V_SSD3_CO_GATE")
		)
		(pad "2" smd circle
			(at 0.40005 0 270)
			(size 0 0)
			(layers "F.Cu" "F.Mask" "F.Paste")
			(net "GND")
		)
	)
	(footprint ""
		(layer "F.Cu")
		(at 142.343886 -43.85691)
		(property "Reference" "R553"
			(at 0 0 0)
			(layer "F.SilkS")
			(hide yes)
			(effects
				(font
					(size 1.27 1.27)
				)
			)
		)
		(property "Value" ""
			(at 0 0 0)
			(layer "F.Fab")
			(effects
				(font
					(size 1.27 1.27)
				)
			)
		)
		(duplicate_pad_numbers_are_jumpers no)
		(fp_line
			(start -0.7874 -0.4064)
			(end 0.7874 -0.4064)
			(stroke
				(width 0.1524)
				(type default)
			)
			(layer "F.SilkS")
		)
		(fp_line
			(start -0.7874 0.4064)
			(end -0.7874 -0.4064)
			(stroke
				(width 0.1524)
				(type default)
			)
			(layer "F.SilkS")
		)
		(fp_line
			(start 0.7874 -0.4064)
			(end 0.7874 0.4064)
			(stroke
				(width 0.1524)
				(type default)
			)
			(layer "F.SilkS")
		)
		(fp_line
			(start 0.7874 0.4064)
			(end -0.7874 0.4064)
			(stroke
				(width 0.1524)
				(type default)
			)
			(layer "F.SilkS")
		)
		(fp_line
			(start -0.67945 -0.305054)
			(end -0.12065 -0.305054)
			(stroke
				(width 0.1)
				(type default)
			)
			(layer "F.Fab")
		)
		(fp_line
			(start -0.67945 0.3048)
			(end -0.67945 -0.305054)
			(stroke
				(width 0.1)
				(type default)
			)
			(layer "F.Fab")
		)
		(fp_line
			(start -0.12065 -0.305054)
			(end -0.12065 -0.2794)
			(stroke
				(width 0.1)
				(type default)
			)
			(layer "F.Fab")
		)
		(fp_line
			(start -0.12065 -0.2794)
			(end 0.12065 -0.2794)
			(stroke
				(width 0.1)
				(type default)
			)
			(layer "F.Fab")
		)
		(fp_line
			(start -0.12065 0.2794)
			(end -0.12065 0.3048)
			(stroke
				(width 0.1)
				(type default)
			)
			(layer "F.Fab")
		)
		(fp_line
			(start -0.12065 0.3048)
			(end -0.67945 0.3048)
			(stroke
				(width 0.1)
				(type default)
			)
			(layer "F.Fab")
		)
		(fp_line
			(start 0.120396 0.2794)
			(end -0.12065 0.2794)
			(stroke
				(width 0.1)
				(type default)
			)
			(layer "F.Fab")
		)
		(fp_line
			(start 0.120396 0.3048)
			(end 0.120396 0.2794)
			(stroke
				(width 0.1)
				(type default)
			)
			(layer "F.Fab")
		)
		(fp_line
			(start 0.12065 -0.3048)
			(end 0.67945 -0.3048)
			(stroke
				(width 0.1)
				(type default)
			)
			(layer "F.Fab")
		)
		(fp_line
			(start 0.12065 -0.2794)
			(end 0.12065 -0.3048)
			(stroke
				(width 0.1)
				(type default)
			)
			(layer "F.Fab")
		)
		(fp_line
			(start 0.67945 -0.3048)
			(end 0.67945 0.3048)
			(stroke
				(width 0.1)
				(type default)
			)
			(layer "F.Fab")
		)
		(fp_line
			(start 0.67945 0.3048)
			(end 0.120396 0.3048)
			(stroke
				(width 0.1)
				(type default)
			)
			(layer "F.Fab")
		)
		(pad "1" smd circle
			(at -0.40005 0)
			(size 0 0)
			(layers "F.Cu" "F.Mask" "F.Paste")
			(net "SSD4_ADC_A1")
		)
		(pad "2" smd circle
			(at 0.40005 0)
			(size 0 0)
			(layers "F.Cu" "F.Mask" "F.Paste")
			(net "GND")
		)
	)
	(footprint ""
		(layer "F.Cu")
		(at 204.591158 -77.563472)
		(property "Reference" "R4337"
			(at 0 0 0)
			(layer "F.SilkS")
			(hide yes)
			(effects
				(font
					(size 1.27 1.27)
				)
			)
		)
		(property "Value" ""
			(at 0 0 0)
			(layer "F.Fab")
			(effects
				(font
					(size 1.27 1.27)
				)
			)
		)
		(duplicate_pad_numbers_are_jumpers no)
		(fp_line
			(start -0.7874 -0.4064)
			(end 0.7874 -0.4064)
			(stroke
				(width 0.1524)
				(type default)
			)
			(layer "F.SilkS")
		)
		(fp_line
			(start -0.7874 0.4064)
			(end -0.7874 -0.4064)
			(stroke
				(width 0.1524)
				(type default)
			)
			(layer "F.SilkS")
		)
		(fp_line
			(start 0.7874 -0.4064)
			(end 0.7874 0.4064)
			(stroke
				(width 0.1524)
				(type default)
			)
			(layer "F.SilkS")
		)
		(fp_line
			(start 0.7874 0.4064)
			(end -0.7874 0.4064)
			(stroke
				(width 0.1524)
				(type default)
			)
			(layer "F.SilkS")
		)
		(fp_line
			(start -0.67945 -0.305054)
			(end -0.12065 -0.305054)
			(stroke
				(width 0.1)
				(type default)
			)
			(layer "F.Fab")
		)
		(fp_line
			(start -0.67945 0.3048)
			(end -0.67945 -0.305054)
			(stroke
				(width 0.1)
				(type default)
			)
			(layer "F.Fab")
		)
		(fp_line
			(start -0.12065 -0.305054)
			(end -0.12065 -0.2794)
			(stroke
				(width 0.1)
				(type default)
			)
			(layer "F.Fab")
		)
		(fp_line
			(start -0.12065 -0.2794)
			(end 0.12065 -0.2794)
			(stroke
				(width 0.1)
				(type default)
			)
			(layer "F.Fab")
		)
		(fp_line
			(start -0.12065 0.2794)
			(end -0.12065 0.3048)
			(stroke
				(width 0.1)
				(type default)
			)
			(layer "F.Fab")
		)
		(fp_line
			(start -0.12065 0.3048)
			(end -0.67945 0.3048)
			(stroke
				(width 0.1)
				(type default)
			)
			(layer "F.Fab")
		)
		(fp_line
			(start 0.120396 0.2794)
			(end -0.12065 0.2794)
			(stroke
				(width 0.1)
				(type default)
			)
			(layer "F.Fab")
		)
		(fp_line
			(start 0.120396 0.3048)
			(end 0.120396 0.2794)
			(stroke
				(width 0.1)
				(type default)
			)
			(layer "F.Fab")
		)
		(fp_line
			(start 0.12065 -0.3048)
			(end 0.67945 -0.3048)
			(stroke
				(width 0.1)
				(type default)
			)
			(layer "F.Fab")
		)
		(fp_line
			(start 0.12065 -0.2794)
			(end 0.12065 -0.3048)
			(stroke
				(width 0.1)
				(type default)
			)
			(layer "F.Fab")
		)
		(fp_line
			(start 0.67945 -0.3048)
			(end 0.67945 0.3048)
			(stroke
				(width 0.1)
				(type default)
			)
			(layer "F.Fab")
		)
		(fp_line
			(start 0.67945 0.3048)
			(end 0.120396 0.3048)
			(stroke
				(width 0.1)
				(type default)
			)
			(layer "F.Fab")
		)
		(pad "1" smd circle
			(at -0.40005 0)
			(size 0 0)
			(layers "F.Cu" "F.Mask" "F.Paste")
			(net "P3V3_AUX")
		)
		(pad "2" smd circle
			(at 0.40005 0)
			(size 0 0)
			(layers "F.Cu" "F.Mask" "F.Paste")
			(net "SSD7_LED_R")
		)
	)
	(footprint ""
		(layer "F.Cu")
		(at 381.127 -201.168)
		(property "Reference" "R4700"
			(at 0 0 0)
			(layer "F.SilkS")
			(hide yes)
			(effects
				(font
					(size 1.27 1.27)
				)
			)
		)
		(property "Value" ""
			(at 0 0 0)
			(layer "F.Fab")
			(effects
				(font
					(size 1.27 1.27)
				)
			)
		)
		(duplicate_pad_numbers_are_jumpers no)
		(fp_line
			(start -0.7874 -0.4064)
			(end 0.7874 -0.4064)
			(stroke
				(width 0.1524)
				(type default)
			)
			(layer "F.SilkS")
		)
		(fp_line
			(start -0.7874 0.4064)
			(end -0.7874 -0.4064)
			(stroke
				(width 0.1524)
				(type default)
			)
			(layer "F.SilkS")
		)
		(fp_line
			(start 0.7874 -0.4064)
			(end 0.7874 0.4064)
			(stroke
				(width 0.1524)
				(type default)
			)
			(layer "F.SilkS")
		)
		(fp_line
			(start 0.7874 0.4064)
			(end -0.7874 0.4064)
			(stroke
				(width 0.1524)
				(type default)
			)
			(layer "F.SilkS")
		)
		(fp_line
			(start -0.67945 -0.305054)
			(end -0.12065 -0.305054)
			(stroke
				(width 0.1)
				(type default)
			)
			(layer "F.Fab")
		)
		(fp_line
			(start -0.67945 0.3048)
			(end -0.67945 -0.305054)
			(stroke
				(width 0.1)
				(type default)
			)
			(layer "F.Fab")
		)
		(fp_line
			(start -0.12065 -0.305054)
			(end -0.12065 -0.2794)
			(stroke
				(width 0.1)
				(type default)
			)
			(layer "F.Fab")
		)
		(fp_line
			(start -0.12065 -0.2794)
			(end 0.12065 -0.2794)
			(stroke
				(width 0.1)
				(type default)
			)
			(layer "F.Fab")
		)
		(fp_line
			(start -0.12065 0.2794)
			(end -0.12065 0.3048)
			(stroke
				(width 0.1)
				(type default)
			)
			(layer "F.Fab")
		)
		(fp_line
			(start -0.12065 0.3048)
			(end -0.67945 0.3048)
			(stroke
				(width 0.1)
				(type default)
			)
			(layer "F.Fab")
		)
		(fp_line
			(start 0.120396 0.2794)
			(end -0.12065 0.2794)
			(stroke
				(width 0.1)
				(type default)
			)
			(layer "F.Fab")
		)
		(fp_line
			(start 0.120396 0.3048)
			(end 0.120396 0.2794)
			(stroke
				(width 0.1)
				(type default)
			)
			(layer "F.Fab")
		)
		(fp_line
			(start 0.12065 -0.3048)
			(end 0.67945 -0.3048)
			(stroke
				(width 0.1)
				(type default)
			)
			(layer "F.Fab")
		)
		(fp_line
			(start 0.12065 -0.2794)
			(end 0.12065 -0.3048)
			(stroke
				(width 0.1)
				(type default)
			)
			(layer "F.Fab")
		)
		(fp_line
			(start 0.67945 -0.3048)
			(end 0.67945 0.3048)
			(stroke
				(width 0.1)
				(type default)
			)
			(layer "F.Fab")
		)
		(fp_line
			(start 0.67945 0.3048)
			(end 0.120396 0.3048)
			(stroke
				(width 0.1)
				(type default)
			)
			(layer "F.Fab")
		)
		(pad "1" smd circle
			(at -0.40005 0)
			(size 0 0)
			(layers "F.Cu" "F.Mask" "F.Paste")
			(net "GND")
		)
		(pad "2" smd circle
			(at 0.40005 0)
			(size 0 0)
			(layers "F.Cu" "F.Mask" "F.Paste")
			(net "PCA9555_0_PEX1_A0")
		)
	)
	(footprint ""
		(layer "F.Cu")
		(at 258.623562 -214.162386)
		(property "Reference" "C2849"
			(at 0 0 0)
			(layer "F.SilkS")
			(hide yes)
			(effects
				(font
					(size 1.27 1.27)
				)
			)
		)
		(property "Value" ""
			(at 0 0 0)
			(layer "F.Fab")
			(effects
				(font
					(size 1.27 1.27)
				)
			)
		)
		(duplicate_pad_numbers_are_jumpers no)
		(fp_line
			(start -1.524 -0.762)
			(end 1.524 -0.762)
			(stroke
				(width 0.1524)
				(type default)
			)
			(layer "F.SilkS")
		)
		(fp_line
			(start -1.524 0.762)
			(end -1.524 -0.762)
			(stroke
				(width 0.1524)
				(type default)
			)
			(layer "F.SilkS")
		)
		(fp_line
			(start 1.524 -0.762)
			(end 1.524 0.762)
			(stroke
				(width 0.1524)
				(type default)
			)
			(layer "F.SilkS")
		)
		(fp_line
			(start 1.524 0.762)
			(end -1.524 0.762)
			(stroke
				(width 0.1524)
				(type default)
			)
			(layer "F.SilkS")
		)
		(fp_line
			(start -1.1049 -0.724916)
			(end -1.1049 0.724916)
			(stroke
				(width 0.1)
				(type default)
			)
			(layer "F.Fab")
		)
		(fp_line
			(start -1.1049 0.724916)
			(end 1.1049 0.724916)
			(stroke
				(width 0.1)
				(type default)
			)
			(layer "F.Fab")
		)
		(fp_line
			(start 1.1049 -0.724916)
			(end -1.1049 -0.724916)
			(stroke
				(width 0.1)
				(type default)
			)
			(layer "F.Fab")
		)
		(fp_line
			(start 1.1049 0.724916)
			(end 1.1049 -0.724916)
			(stroke
				(width 0.1)
				(type default)
			)
			(layer "F.Fab")
		)
		(pad "1" smd rect
			(at -0.889 0 180)
			(size 1.016 1.27)
			(layers "F.Cu" "F.Mask" "F.Paste")
			(net "P3V3_AUX")
		)
		(pad "2" smd rect
			(at 0.889 0 180)
			(size 1.016 1.27)
			(layers "F.Cu" "F.Mask" "F.Paste")
			(net "GND")
		)
	)
	(footprint ""
		(layer "F.Cu")
		(at 374.567958 -52.035456 180)
		(property "Reference" "R870"
			(at 0 0 180)
			(layer "F.SilkS")
			(hide yes)
			(effects
				(font
					(size 1.27 1.27)
				)
			)
		)
		(property "Value" ""
			(at 0 0 180)
			(layer "F.Fab")
			(effects
				(font
					(size 1.27 1.27)
				)
			)
		)
		(duplicate_pad_numbers_are_jumpers no)
		(fp_line
			(start 0.7874 0.4064)
			(end -0.7874 0.4064)
			(stroke
				(width 0.1524)
				(type default)
			)
			(layer "F.SilkS")
		)
		(fp_line
			(start 0.7874 -0.4064)
			(end 0.7874 0.4064)
			(stroke
				(width 0.1524)
				(type default)
			)
			(layer "F.SilkS")
		)
		(fp_line
			(start -0.7874 0.4064)
			(end -0.7874 -0.4064)
			(stroke
				(width 0.1524)
				(type default)
			)
			(layer "F.SilkS")
		)
		(fp_line
			(start -0.7874 -0.4064)
			(end 0.7874 -0.4064)
			(stroke
				(width 0.1524)
				(type default)
			)
			(layer "F.SilkS")
		)
		(fp_line
			(start 0.67945 0.3048)
			(end 0.120396 0.3048)
			(stroke
				(width 0.1)
				(type default)
			)
			(layer "F.Fab")
		)
		(fp_line
			(start 0.67945 -0.3048)
			(end 0.67945 0.3048)
			(stroke
				(width 0.1)
				(type default)
			)
			(layer "F.Fab")
		)
		(fp_line
			(start 0.12065 -0.2794)
			(end 0.12065 -0.3048)
			(stroke
				(width 0.1)
				(type default)
			)
			(layer "F.Fab")
		)
		(fp_line
			(start 0.12065 -0.3048)
			(end 0.67945 -0.3048)
			(stroke
				(width 0.1)
				(type default)
			)
			(layer "F.Fab")
		)
		(fp_line
			(start 0.120396 0.3048)
			(end 0.120396 0.2794)
			(stroke
				(width 0.1)
				(type default)
			)
			(layer "F.Fab")
		)
		(fp_line
			(start 0.120396 0.2794)
			(end -0.12065 0.2794)
			(stroke
				(width 0.1)
				(type default)
			)
			(layer "F.Fab")
		)
		(fp_line
			(start -0.12065 0.3048)
			(end -0.67945 0.3048)
			(stroke
				(width 0.1)
				(type default)
			)
			(layer "F.Fab")
		)
		(fp_line
			(start -0.12065 0.2794)
			(end -0.12065 0.3048)
			(stroke
				(width 0.1)
				(type default)
			)
			(layer "F.Fab")
		)
		(fp_line
			(start -0.12065 -0.2794)
			(end 0.12065 -0.2794)
			(stroke
				(width 0.1)
				(type default)
			)
			(layer "F.Fab")
		)
		(fp_line
			(start -0.12065 -0.305054)
			(end -0.12065 -0.2794)
			(stroke
				(width 0.1)
				(type default)
			)
			(layer "F.Fab")
		)
		(fp_line
			(start -0.67945 0.3048)
			(end -0.67945 -0.305054)
			(stroke
				(width 0.1)
				(type default)
			)
			(layer "F.Fab")
		)
		(fp_line
			(start -0.67945 -0.305054)
			(end -0.12065 -0.305054)
			(stroke
				(width 0.1)
				(type default)
			)
			(layer "F.Fab")
		)
		(pad "1" smd circle
			(at -0.40005 0 180)
			(size 0 0)
			(layers "F.Cu" "F.Mask" "F.Paste")
			(net "P3V3_AUX")
		)
		(pad "2" smd circle
			(at 0.40005 0 180)
			(size 0 0)
			(layers "F.Cu" "F.Mask" "F.Paste")
			(net "PWRGD_P12V_SSD12")
		)
	)
	(footprint ""
		(layer "F.Cu")
		(at 356.676706 -392.284712 90)
		(property "Reference" "C4455"
			(at 0 0 90)
			(layer "F.SilkS")
			(hide yes)
			(effects
				(font
					(size 1.27 1.27)
				)
			)
		)
		(property "Value" ""
			(at 0 0 90)
			(layer "F.Fab")
			(effects
				(font
					(size 1.27 1.27)
				)
			)
		)
		(duplicate_pad_numbers_are_jumpers no)
		(fp_line
			(start 0.299974 -0.150114)
			(end 0.299974 0.150114)
			(stroke
				(width 0.1)
				(type default)
			)
			(layer "F.Fab")
		)
		(fp_line
			(start -0.299974 -0.150114)
			(end 0.299974 -0.150114)
			(stroke
				(width 0.1)
				(type default)
			)
			(layer "F.Fab")
		)
		(fp_line
			(start 0.299974 0.150114)
			(end -0.299974 0.150114)
			(stroke
				(width 0.1)
				(type default)
			)
			(layer "F.Fab")
		)
		(fp_line
			(start -0.299974 0.150114)
			(end -0.299974 -0.150114)
			(stroke
				(width 0.1)
				(type default)
			)
			(layer "F.Fab")
		)
		(pad "1" smd rect
			(at -0.2667 0 90)
			(size 0.3048 0.381)
			(layers "F.Cu" "F.Mask" "F.Paste")
			(net "MB_3V3IO_RSVD1_ISO")
		)
		(pad "2" smd rect
			(at 0.2667 0 90)
			(size 0.3048 0.381)
			(layers "F.Cu" "F.Mask" "F.Paste")
			(net "GND")
		)
	)
	(footprint ""
		(layer "F.Cu")
		(at 241.647218 -278.675846 90)
		(property "Reference" "C632"
			(at 0 0 90)
			(layer "F.SilkS")
			(hide yes)
			(effects
				(font
					(size 1.27 1.27)
				)
			)
		)
		(property "Value" ""
			(at 0 0 90)
			(layer "F.Fab")
			(effects
				(font
					(size 1.27 1.27)
				)
			)
		)
		(duplicate_pad_numbers_are_jumpers no)
		(fp_line
			(start 0.7874 -0.4064)
			(end 0.7874 0.4064)
			(stroke
				(width 0.1524)
				(type default)
			)
			(layer "F.SilkS")
		)
		(fp_line
			(start -0.7874 -0.4064)
			(end 0.7874 -0.4064)
			(stroke
				(width 0.1524)
				(type default)
			)
			(layer "F.SilkS")
		)
		(fp_line
			(start 0.7874 0.4064)
			(end -0.7874 0.4064)
			(stroke
				(width 0.1524)
				(type default)
			)
			(layer "F.SilkS")
		)
		(fp_line
			(start -0.7874 0.4064)
			(end -0.7874 -0.4064)
			(stroke
				(width 0.1524)
				(type default)
			)
			(layer "F.SilkS")
		)
		(fp_line
			(start -0.12065 -0.305054)
			(end -0.12065 -0.2794)
			(stroke
				(width 0.1)
				(type default)
			)
			(layer "F.Fab")
		)
		(fp_line
			(start -0.67945 -0.305054)
			(end -0.12065 -0.305054)
			(stroke
				(width 0.1)
				(type default)
			)
			(layer "F.Fab")
		)
		(fp_line
			(start 0.67945 -0.3048)
			(end 0.67945 0.3048)
			(stroke
				(width 0.1)
				(type default)
			)
			(layer "F.Fab")
		)
		(fp_line
			(start 0.12065 -0.3048)
			(end 0.67945 -0.3048)
			(stroke
				(width 0.1)
				(type default)
			)
			(layer "F.Fab")
		)
		(fp_line
			(start 0.12065 -0.2794)
			(end 0.12065 -0.3048)
			(stroke
				(width 0.1)
				(type default)
			)
			(layer "F.Fab")
		)
		(fp_line
			(start -0.12065 -0.2794)
			(end 0.12065 -0.2794)
			(stroke
				(width 0.1)
				(type default)
			)
			(layer "F.Fab")
		)
		(fp_line
			(start 0.120396 0.2794)
			(end -0.12065 0.2794)
			(stroke
				(width 0.1)
				(type default)
			)
			(layer "F.Fab")
		)
		(fp_line
			(start -0.12065 0.2794)
			(end -0.12065 0.3048)
			(stroke
				(width 0.1)
				(type default)
			)
			(layer "F.Fab")
		)
		(fp_line
			(start 0.67945 0.3048)
			(end 0.120396 0.3048)
			(stroke
				(width 0.1)
				(type default)
			)
			(layer "F.Fab")
		)
		(fp_line
			(start 0.120396 0.3048)
			(end 0.120396 0.2794)
			(stroke
				(width 0.1)
				(type default)
			)
			(layer "F.Fab")
		)
		(fp_line
			(start -0.12065 0.3048)
			(end -0.67945 0.3048)
			(stroke
				(width 0.1)
				(type default)
			)
			(layer "F.Fab")
		)
		(fp_line
			(start -0.67945 0.3048)
			(end -0.67945 -0.305054)
			(stroke
				(width 0.1)
				(type default)
			)
			(layer "F.Fab")
		)
		(pad "1" smd circle
			(at -0.40005 0 90)
			(size 0 0)
			(layers "F.Cu" "F.Mask" "F.Paste")
			(net "P1V25_PEX2_R")
		)
		(pad "2" smd circle
			(at 0.40005 0 90)
			(size 0 0)
			(layers "F.Cu" "F.Mask" "F.Paste")
			(net "GND")
		)
	)
	(footprint ""
		(layer "F.Cu")
		(at 404.943056 -373.76481 90)
		(property "Reference" "C3996"
			(at 0 0 90)
			(layer "F.SilkS")
			(hide yes)
			(effects
				(font
					(size 1.27 1.27)
				)
			)
		)
		(property "Value" ""
			(at 0 0 90)
			(layer "F.Fab")
			(effects
				(font
					(size 1.27 1.27)
				)
			)
		)
		(duplicate_pad_numbers_are_jumpers no)
		(fp_line
			(start 0.7874 -0.4064)
			(end 0.7874 0.4064)
			(stroke
				(width 0.1524)
				(type default)
			)
			(layer "F.SilkS")
		)
		(fp_line
			(start -0.7874 -0.4064)
			(end 0.7874 -0.4064)
			(stroke
				(width 0.1524)
				(type default)
			)
			(layer "F.SilkS")
		)
		(fp_line
			(start 0.7874 0.4064)
			(end -0.7874 0.4064)
			(stroke
				(width 0.1524)
				(type default)
			)
			(layer "F.SilkS")
		)
		(fp_line
			(start -0.7874 0.4064)
			(end -0.7874 -0.4064)
			(stroke
				(width 0.1524)
				(type default)
			)
			(layer "F.SilkS")
		)
		(fp_line
			(start -0.12065 -0.305054)
			(end -0.12065 -0.2794)
			(stroke
				(width 0.1)
				(type default)
			)
			(layer "F.Fab")
		)
		(fp_line
			(start -0.67945 -0.305054)
			(end -0.12065 -0.305054)
			(stroke
				(width 0.1)
				(type default)
			)
			(layer "F.Fab")
		)
		(fp_line
			(start 0.67945 -0.3048)
			(end 0.67945 0.3048)
			(stroke
				(width 0.1)
				(type default)
			)
			(layer "F.Fab")
		)
		(fp_line
			(start 0.12065 -0.3048)
			(end 0.67945 -0.3048)
			(stroke
				(width 0.1)
				(type default)
			)
			(layer "F.Fab")
		)
		(fp_line
			(start 0.12065 -0.2794)
			(end 0.12065 -0.3048)
			(stroke
				(width 0.1)
				(type default)
			)
			(layer "F.Fab")
		)
		(fp_line
			(start -0.12065 -0.2794)
			(end 0.12065 -0.2794)
			(stroke
				(width 0.1)
				(type default)
			)
			(layer "F.Fab")
		)
		(fp_line
			(start 0.120396 0.2794)
			(end -0.12065 0.2794)
			(stroke
				(width 0.1)
				(type default)
			)
			(layer "F.Fab")
		)
		(fp_line
			(start -0.12065 0.2794)
			(end -0.12065 0.3048)
			(stroke
				(width 0.1)
				(type default)
			)
			(layer "F.Fab")
		)
		(fp_line
			(start 0.67945 0.3048)
			(end 0.120396 0.3048)
			(stroke
				(width 0.1)
				(type default)
			)
			(layer "F.Fab")
		)
		(fp_line
			(start 0.120396 0.3048)
			(end 0.120396 0.2794)
			(stroke
				(width 0.1)
				(type default)
			)
			(layer "F.Fab")
		)
		(fp_line
			(start -0.12065 0.3048)
			(end -0.67945 0.3048)
			(stroke
				(width 0.1)
				(type default)
			)
			(layer "F.Fab")
		)
		(fp_line
			(start -0.67945 0.3048)
			(end -0.67945 -0.305054)
			(stroke
				(width 0.1)
				(type default)
			)
			(layer "F.Fab")
		)
		(pad "1" smd circle
			(at -0.40005 0 90)
			(size 0 0)
			(layers "F.Cu" "F.Mask" "F.Paste")
			(net "GND")
		)
		(pad "2" smd circle
			(at 0.40005 0 90)
			(size 0 0)
			(layers "F.Cu" "F.Mask" "F.Paste")
			(net "P3V3_AUX")
		)
	)
	(footprint ""
		(layer "F.Cu")
		(at 48.845978 -46.4439 180)
		(property "Reference" "U54"
			(at 0.128778 -2.40157 0)
			(unlocked yes)
			(layer "F.SilkS")
			(effects
				(font
					(size 0.7874 0.5842)
					(thickness 0.1524)
				)
			)
		)
		(property "Value" ""
			(at 0 0 180)
			(layer "F.Fab")
			(effects
				(font
					(size 1.27 1.27)
				)
			)
		)
		(duplicate_pad_numbers_are_jumpers no)
		(fp_line
			(start 1.500124 1.500124)
			(end 1.004062 1.500124)
			(stroke
				(width 0.1524)
				(type default)
			)
			(layer "F.SilkS")
		)
		(fp_line
			(start 1.500124 1.004062)
			(end 1.500124 1.500124)
			(stroke
				(width 0.1524)
				(type default)
			)
			(layer "F.SilkS")
		)
		(fp_line
			(start 1.500124 -1.500124)
			(end 1.500124 -1.004062)
			(stroke
				(width 0.1524)
				(type default)
			)
			(layer "F.SilkS")
		)
		(fp_line
			(start 1.004062 -1.500124)
			(end 1.500124 -1.500124)
			(stroke
				(width 0.1524)
				(type default)
			)
			(layer "F.SilkS")
		)
		(fp_line
			(start -1.004062 1.500124)
			(end -1.500124 1.500124)
			(stroke
				(width 0.1524)
				(type default)
			)
			(layer "F.SilkS")
		)
		(fp_line
			(start -1.500124 1.500124)
			(end -1.500124 1.004062)
			(stroke
				(width 0.1524)
				(type default)
			)
			(layer "F.SilkS")
		)
		(fp_line
			(start -1.500124 -1.004062)
			(end -1.500124 -1.500124)
			(stroke
				(width 0.1524)
				(type default)
			)
			(layer "F.SilkS")
		)
		(fp_line
			(start -1.500124 -1.500124)
			(end -1.004062 -1.500124)
			(stroke
				(width 0.1524)
				(type default)
			)
			(layer "F.SilkS")
		)
		(fp_poly
			(pts
				(xy -1.879346 -2.55905) (xy -2.597658 -1.840738) (xy -1.52019 -1.481328)
			)
			(stroke
				(width 0)
				(type default)
			)
			(fill yes)
			(layer "F.SilkS")
		)
		(fp_line
			(start 1.500124 1.500124)
			(end -1.500124 1.500124)
			(stroke
				(width 0.1)
				(type default)
			)
			(layer "F.Fab")
		)
		(fp_line
			(start 1.500124 -1.500124)
			(end 1.500124 1.500124)
			(stroke
				(width 0.1)
				(type default)
			)
			(layer "F.Fab")
		)
		(fp_line
			(start -1.500124 1.500124)
			(end -1.500124 -1.500124)
			(stroke
				(width 0.1)
				(type default)
			)
			(layer "F.Fab")
		)
		(fp_line
			(start -1.500124 -1.500124)
			(end 1.500124 -1.500124)
			(stroke
				(width 0.1)
				(type default)
			)
			(layer "F.Fab")
		)
		(fp_poly
			(pts
				(xy -2.847848 -1.258062) (xy -2.847848 -0.242062) (xy -1.831848 -0.750062)
			)
			(stroke
				(width 0)
				(type default)
			)
			(fill yes)
			(layer "F.Fab")
		)
		(pad "1" smd rect
			(at -1.400048 -0.750062 90)
			(size 0.2286 0.6096)
			(layers "F.Cu" "F.Mask" "F.Paste")
			(net "SSD1_ADC_A1")
		)
		(pad "2" smd rect
			(at -1.400048 -0.249936 90)
			(size 0.2286 0.6096)
			(layers "F.Cu" "F.Mask" "F.Paste")
			(net "SSD1_ADC_A0")
		)
		(pad "3" smd rect
			(at -1.400048 0.249936 90)
			(size 0.2286 0.6096)
			(layers "F.Cu" "F.Mask" "F.Paste")
			(net "SSD1_ADC_ALERT_N")
		)
		(pad "4" smd rect
			(at -1.400048 0.750062 90)
			(size 0.2286 0.6096)
			(layers "F.Cu" "F.Mask" "F.Paste")
			(net "SMB_SSD1_ADC_SDA")
		)
		(pad "5" smd rect
			(at -0.750062 1.400048 180)
			(size 0.2286 0.6096)
			(layers "F.Cu" "F.Mask" "F.Paste")
			(net "SMB_SSD1_ADC_SCL")
		)
		(pad "6" smd rect
			(at -0.249936 1.400048 180)
			(size 0.2286 0.6096)
			(layers "F.Cu" "F.Mask" "F.Paste")
			(net "Net_4615")
		)
		(pad "7" smd rect
			(at 0.249936 1.400048 180)
			(size 0.2286 0.6096)
			(layers "F.Cu" "F.Mask" "F.Paste")
			(net "Net_4616")
		)
		(pad "8" smd rect
			(at 0.750062 1.400048 180)
			(size 0.2286 0.6096)
			(layers "F.Cu" "F.Mask" "F.Paste")
			(net "Net_4617")
		)
		(pad "9" smd rect
			(at 1.400048 0.750062 90)
			(size 0.2286 0.6096)
			(layers "F.Cu" "F.Mask" "F.Paste")
			(net "P3V3_AUX")
		)
		(pad "10" smd rect
			(at 1.400048 0.249936 90)
			(size 0.2286 0.6096)
			(layers "F.Cu" "F.Mask" "F.Paste")
			(net "GND")
		)
		(pad "11" smd rect
			(at 1.400048 -0.249936 90)
			(size 0.2286 0.6096)
			(layers "F.Cu" "F.Mask" "F.Paste")
			(net "P12V_SSD1_R")
		)
		(pad "12" smd rect
			(at 1.400048 -0.750062 90)
			(size 0.2286 0.6096)
			(layers "F.Cu" "F.Mask" "F.Paste")
			(net "P12V_SSD1_VIN_N")
		)
		(pad "13" smd rect
			(at 0.750062 -1.400048 180)
			(size 0.2286 0.6096)
			(layers "F.Cu" "F.Mask" "F.Paste")
			(net "P12V_SSD1_VIN_P")
		)
		(pad "14" smd rect
			(at 0.249936 -1.400048 180)
			(size 0.2286 0.6096)
			(layers "F.Cu" "F.Mask" "F.Paste")
			(net "Net_4618")
		)
		(pad "15" smd rect
			(at -0.249936 -1.400048 180)
			(size 0.2286 0.6096)
			(layers "F.Cu" "F.Mask" "F.Paste")
			(net "Net_4619")
		)
		(pad "16" smd rect
			(at -0.750062 -1.400048 180)
			(size 0.2286 0.6096)
			(layers "F.Cu" "F.Mask" "F.Paste")
			(net "Net_4620")
		)
		(pad "TH" smd rect
			(at 0 0 180)
			(size 1.7018 1.7018)
			(layers "F.Cu" "F.Mask" "F.Paste")
			(net "GND")
		)
		(zone
			(layer "F.Cu")
			(hatch none 0.5)
			(connect_pads
				(clearance 0)
			)
			(min_thickness 0.25)
			(keepout
				(tracks not_allowed)
				(vias allowed)
				(pads allowed)
				(copperpour not_allowed)
				(footprints allowed)
			)
			(placement
				(enabled no)
				(sheetname "")
			)
			(fill
				(thermal_gap 0.5)
				(thermal_bridge_width 0.5)
				(island_removal_mode 0)
			)
			(polygon
				(pts
					(xy 49.890426 -46.4185) (xy 49.890426 -45.399452) (xy 47.80153 -45.399452) (xy 47.80153 -47.488348)
					(xy 49.890426 -47.488348) (xy 49.890426 -46.4439) (xy 49.747678 -46.4439) (xy 49.747678 -47.3456)
					(xy 47.944278 -47.3456) (xy 47.944278 -45.5422) (xy 49.747678 -45.5422) (xy 49.747678 -46.4185)
				)
			)
		)
	)
	(footprint ""
		(layer "F.Cu")
		(at 54.454806 -22.961346 90)
		(property "Reference" "R1634"
			(at 0 0 90)
			(layer "F.SilkS")
			(hide yes)
			(effects
				(font
					(size 1.27 1.27)
				)
			)
		)
		(property "Value" ""
			(at 0 0 90)
			(layer "F.Fab")
			(effects
				(font
					(size 1.27 1.27)
				)
			)
		)
		(duplicate_pad_numbers_are_jumpers no)
		(fp_line
			(start 0.7874 -0.4064)
			(end 0.7874 0.4064)
			(stroke
				(width 0.1524)
				(type default)
			)
			(layer "F.SilkS")
		)
		(fp_line
			(start -0.7874 -0.4064)
			(end 0.7874 -0.4064)
			(stroke
				(width 0.1524)
				(type default)
			)
			(layer "F.SilkS")
		)
		(fp_line
			(start 0.7874 0.4064)
			(end -0.7874 0.4064)
			(stroke
				(width 0.1524)
				(type default)
			)
			(layer "F.SilkS")
		)
		(fp_line
			(start -0.7874 0.4064)
			(end -0.7874 -0.4064)
			(stroke
				(width 0.1524)
				(type default)
			)
			(layer "F.SilkS")
		)
		(fp_line
			(start -0.12065 -0.305054)
			(end -0.12065 -0.2794)
			(stroke
				(width 0.1)
				(type default)
			)
			(layer "F.Fab")
		)
		(fp_line
			(start -0.67945 -0.305054)
			(end -0.12065 -0.305054)
			(stroke
				(width 0.1)
				(type default)
			)
			(layer "F.Fab")
		)
		(fp_line
			(start 0.67945 -0.3048)
			(end 0.67945 0.3048)
			(stroke
				(width 0.1)
				(type default)
			)
			(layer "F.Fab")
		)
		(fp_line
			(start 0.12065 -0.3048)
			(end 0.67945 -0.3048)
			(stroke
				(width 0.1)
				(type default)
			)
			(layer "F.Fab")
		)
		(fp_line
			(start 0.12065 -0.2794)
			(end 0.12065 -0.3048)
			(stroke
				(width 0.1)
				(type default)
			)
			(layer "F.Fab")
		)
		(fp_line
			(start -0.12065 -0.2794)
			(end 0.12065 -0.2794)
			(stroke
				(width 0.1)
				(type default)
			)
			(layer "F.Fab")
		)
		(fp_line
			(start 0.120396 0.2794)
			(end -0.12065 0.2794)
			(stroke
				(width 0.1)
				(type default)
			)
			(layer "F.Fab")
		)
		(fp_line
			(start -0.12065 0.2794)
			(end -0.12065 0.3048)
			(stroke
				(width 0.1)
				(type default)
			)
			(layer "F.Fab")
		)
		(fp_line
			(start 0.67945 0.3048)
			(end 0.120396 0.3048)
			(stroke
				(width 0.1)
				(type default)
			)
			(layer "F.Fab")
		)
		(fp_line
			(start 0.120396 0.3048)
			(end 0.120396 0.2794)
			(stroke
				(width 0.1)
				(type default)
			)
			(layer "F.Fab")
		)
		(fp_line
			(start -0.12065 0.3048)
			(end -0.67945 0.3048)
			(stroke
				(width 0.1)
				(type default)
			)
			(layer "F.Fab")
		)
		(fp_line
			(start -0.67945 0.3048)
			(end -0.67945 -0.305054)
			(stroke
				(width 0.1)
				(type default)
			)
			(layer "F.Fab")
		)
		(pad "1" smd circle
			(at -0.40005 0 90)
			(size 0 0)
			(layers "F.Cu" "F.Mask" "F.Paste")
			(net "SMB_SSD1_ISO_EN")
		)
		(pad "2" smd circle
			(at 0.40005 0 90)
			(size 0 0)
			(layers "F.Cu" "F.Mask" "F.Paste")
			(net "P3V3_AUX")
		)
	)
	(footprint ""
		(layer "F.Cu")
		(at 224.836482 -109.802422 180)
		(property "Reference" "PD83"
			(at 4.059682 2.210308 0)
			(unlocked yes)
			(layer "F.SilkS")
			(effects
				(font
					(size 0.7874 0.5842)
					(thickness 0.1524)
				)
				(justify left)
			)
		)
		(property "Value" ""
			(at 0 0 180)
			(layer "F.Fab")
			(effects
				(font
					(size 1.27 1.27)
				)
			)
		)
		(duplicate_pad_numbers_are_jumpers no)
		(fp_line
			(start 4.107942 1.459992)
			(end -3.400044 1.459992)
			(stroke
				(width 0.1524)
				(type default)
			)
			(layer "F.SilkS")
		)
		(fp_line
			(start 4.107942 -1.459992)
			(end 4.107942 1.459992)
			(stroke
				(width 0.1524)
				(type default)
			)
			(layer "F.SilkS")
		)
		(fp_line
			(start -3.400044 1.459992)
			(end -3.400044 -1.459992)
			(stroke
				(width 0.1524)
				(type default)
			)
			(layer "F.SilkS")
		)
		(fp_line
			(start -3.400044 -1.459992)
			(end 4.107942 -1.459992)
			(stroke
				(width 0.1524)
				(type default)
			)
			(layer "F.SilkS")
		)
		(fp_poly
			(pts
				(xy 4.107942 -1.459992) (xy 4.107942 1.459992) (xy 3.308096 1.459992) (xy 3.308096 -1.459992)
			)
			(stroke
				(width 0)
				(type default)
			)
			(fill yes)
			(layer "F.SilkS")
		)
		(fp_line
			(start 2.29997 1.459992)
			(end -2.29997 1.459992)
			(stroke
				(width 0.1)
				(type default)
			)
			(layer "F.Fab")
		)
		(fp_line
			(start 2.29997 -1.459992)
			(end 2.29997 1.459992)
			(stroke
				(width 0.1)
				(type default)
			)
			(layer "F.Fab")
		)
		(fp_line
			(start -2.29997 1.459992)
			(end -2.29997 -1.459992)
			(stroke
				(width 0.1)
				(type default)
			)
			(layer "F.Fab")
		)
		(fp_line
			(start -2.29997 -1.459992)
			(end 2.29997 -1.459992)
			(stroke
				(width 0.1)
				(type default)
			)
			(layer "F.Fab")
		)
		(fp_text user "-"
			(at 5.4102 0.29845 0)
			(unlocked yes)
			(layer "F.SilkS")
			(effects
				(font
					(size 1.905 1.4224)
					(thickness 0.1524)
				)
				(justify left)
			)
		)
		(fp_text user "+"
			(at -3.643122 -2.449322 180)
			(unlocked yes)
			(layer "F.SilkS")
			(effects
				(font
					(size 1.905 1.4224)
					(thickness 0.1524)
				)
				(justify left)
			)
		)
		(fp_text user "-"
			(at 5.4102 0.29845 0)
			(unlocked yes)
			(layer "F.Fab")
			(effects
				(font
					(size 1.905 1.4224)
					(thickness 0.1524)
				)
				(justify left)
			)
		)
		(fp_text user "+"
			(at -4.7752 -0.12065 180)
			(unlocked yes)
			(layer "F.Fab")
			(effects
				(font
					(size 1.905 1.4224)
					(thickness 0.1524)
				)
				(justify left)
			)
		)
		(pad "A" smd rect
			(at -1.999996 0 270)
			(size 1.7018 2.5146)
			(layers "F.Cu" "F.Mask" "F.Paste")
			(net "GND")
		)
		(pad "C" smd rect
			(at 1.999996 0 270)
			(size 1.7018 2.5146)
			(layers "F.Cu" "F.Mask" "F.Paste")
			(net "P12V_NIC3_R")
		)
	)
	(footprint ""
		(layer "F.Cu")
		(at 375.230136 -287.604708 -90)
		(property "Reference" "C3575"
			(at 0 0 270)
			(layer "F.SilkS")
			(hide yes)
			(effects
				(font
					(size 1.27 1.27)
				)
			)
		)
		(property "Value" ""
			(at 0 0 270)
			(layer "F.Fab")
			(effects
				(font
					(size 1.27 1.27)
				)
			)
		)
		(duplicate_pad_numbers_are_jumpers no)
		(fp_line
			(start -1.2954 0.5842)
			(end -1.2954 -0.5842)
			(stroke
				(width 0.1524)
				(type default)
			)
			(layer "F.SilkS")
		)
		(fp_line
			(start 1.2954 0.5842)
			(end -1.2954 0.5842)
			(stroke
				(width 0.1524)
				(type default)
			)
			(layer "F.SilkS")
		)
		(fp_line
			(start -1.2954 -0.5842)
			(end 1.2954 -0.5842)
			(stroke
				(width 0.1524)
				(type default)
			)
			(layer "F.SilkS")
		)
		(fp_line
			(start 1.2954 -0.5842)
			(end 1.2954 0.5842)
			(stroke
				(width 0.1524)
				(type default)
			)
			(layer "F.SilkS")
		)
		(fp_line
			(start -0.8636 0.4572)
			(end -0.8636 0.4064)
			(stroke
				(width 0.1)
				(type default)
			)
			(layer "F.Fab")
		)
		(fp_line
			(start 0.8636 0.4572)
			(end -0.8636 0.4572)
			(stroke
				(width 0.1)
				(type default)
			)
			(layer "F.Fab")
		)
		(fp_line
			(start -1.1938 0.4064)
			(end -1.1938 -0.4064)
			(stroke
				(width 0.1)
				(type default)
			)
			(layer "F.Fab")
		)
		(fp_line
			(start -0.8636 0.4064)
			(end -1.1938 0.4064)
			(stroke
				(width 0.1)
				(type default)
			)
			(layer "F.Fab")
		)
		(fp_line
			(start 0.8636 0.4064)
			(end 0.8636 0.4572)
			(stroke
				(width 0.1)
				(type default)
			)
			(layer "F.Fab")
		)
		(fp_line
			(start 1.1938 0.4064)
			(end 0.8636 0.4064)
			(stroke
				(width 0.1)
				(type default)
			)
			(layer "F.Fab")
		)
		(fp_line
			(start -1.1938 -0.4064)
			(end -0.8636 -0.4064)
			(stroke
				(width 0.1)
				(type default)
			)
			(layer "F.Fab")
		)
		(fp_line
			(start -0.8636 -0.4064)
			(end -0.8636 -0.4572)
			(stroke
				(width 0.1)
				(type default)
			)
			(layer "F.Fab")
		)
		(fp_line
			(start 0.8636 -0.4064)
			(end 1.1938 -0.4064)
			(stroke
				(width 0.1)
				(type default)
			)
			(layer "F.Fab")
		)
		(fp_line
			(start 1.1938 -0.4064)
			(end 1.1938 0.4064)
			(stroke
				(width 0.1)
				(type default)
			)
			(layer "F.Fab")
		)
		(fp_line
			(start -0.8636 -0.4572)
			(end 0.8636 -0.4572)
			(stroke
				(width 0.1)
				(type default)
			)
			(layer "F.Fab")
		)
		(fp_line
			(start 0.8636 -0.4572)
			(end 0.8636 -0.4064)
			(stroke
				(width 0.1)
				(type default)
			)
			(layer "F.Fab")
		)
		(pad "1" smd rect
			(at -0.7366 0 180)
			(size 0.7112 0.8128)
			(layers "F.Cu" "F.Mask" "F.Paste")
			(net "P1V8_PLL0_PEX3")
		)
		(pad "2" smd rect
			(at 0.7366 0 180)
			(size 0.7112 0.8128)
			(layers "F.Cu" "F.Mask" "F.Paste")
			(net "GND")
		)
	)
	(footprint ""
		(layer "F.Cu")
		(at 371.968014 -19.453098)
		(property "Reference" "R1723"
			(at 0 0 0)
			(layer "F.SilkS")
			(hide yes)
			(effects
				(font
					(size 1.27 1.27)
				)
			)
		)
		(property "Value" ""
			(at 0 0 0)
			(layer "F.Fab")
			(effects
				(font
					(size 1.27 1.27)
				)
			)
		)
		(duplicate_pad_numbers_are_jumpers no)
		(fp_line
			(start -0.7874 -0.4064)
			(end 0.7874 -0.4064)
			(stroke
				(width 0.1524)
				(type default)
			)
			(layer "F.SilkS")
		)
		(fp_line
			(start -0.7874 0.4064)
			(end -0.7874 -0.4064)
			(stroke
				(width 0.1524)
				(type default)
			)
			(layer "F.SilkS")
		)
		(fp_line
			(start 0.7874 -0.4064)
			(end 0.7874 0.4064)
			(stroke
				(width 0.1524)
				(type default)
			)
			(layer "F.SilkS")
		)
		(fp_line
			(start 0.7874 0.4064)
			(end -0.7874 0.4064)
			(stroke
				(width 0.1524)
				(type default)
			)
			(layer "F.SilkS")
		)
		(fp_line
			(start -0.67945 -0.305054)
			(end -0.12065 -0.305054)
			(stroke
				(width 0.1)
				(type default)
			)
			(layer "F.Fab")
		)
		(fp_line
			(start -0.67945 0.3048)
			(end -0.67945 -0.305054)
			(stroke
				(width 0.1)
				(type default)
			)
			(layer "F.Fab")
		)
		(fp_line
			(start -0.12065 -0.305054)
			(end -0.12065 -0.2794)
			(stroke
				(width 0.1)
				(type default)
			)
			(layer "F.Fab")
		)
		(fp_line
			(start -0.12065 -0.2794)
			(end 0.12065 -0.2794)
			(stroke
				(width 0.1)
				(type default)
			)
			(layer "F.Fab")
		)
		(fp_line
			(start -0.12065 0.2794)
			(end -0.12065 0.3048)
			(stroke
				(width 0.1)
				(type default)
			)
			(layer "F.Fab")
		)
		(fp_line
			(start -0.12065 0.3048)
			(end -0.67945 0.3048)
			(stroke
				(width 0.1)
				(type default)
			)
			(layer "F.Fab")
		)
		(fp_line
			(start 0.120396 0.2794)
			(end -0.12065 0.2794)
			(stroke
				(width 0.1)
				(type default)
			)
			(layer "F.Fab")
		)
		(fp_line
			(start 0.120396 0.3048)
			(end 0.120396 0.2794)
			(stroke
				(width 0.1)
				(type default)
			)
			(layer "F.Fab")
		)
		(fp_line
			(start 0.12065 -0.3048)
			(end 0.67945 -0.3048)
			(stroke
				(width 0.1)
				(type default)
			)
			(layer "F.Fab")
		)
		(fp_line
			(start 0.12065 -0.2794)
			(end 0.12065 -0.3048)
			(stroke
				(width 0.1)
				(type default)
			)
			(layer "F.Fab")
		)
		(fp_line
			(start 0.67945 -0.3048)
			(end 0.67945 0.3048)
			(stroke
				(width 0.1)
				(type default)
			)
			(layer "F.Fab")
		)
		(fp_line
			(start 0.67945 0.3048)
			(end 0.120396 0.3048)
			(stroke
				(width 0.1)
				(type default)
			)
			(layer "F.Fab")
		)
		(pad "1" smd circle
			(at -0.40005 0)
			(size 0 0)
			(layers "F.Cu" "F.Mask" "F.Paste")
			(net "SMB_ISO_SSD12_R_SDA")
		)
		(pad "2" smd circle
			(at 0.40005 0)
			(size 0 0)
			(layers "F.Cu" "F.Mask" "F.Paste")
			(net "SMB_ISO_SSD12_SDA")
		)
	)
	(footprint ""
		(layer "F.Cu")
		(at 255.020572 -70.307454 90)
		(property "Reference" "PC859"
			(at 0 0 90)
			(layer "F.SilkS")
			(hide yes)
			(effects
				(font
					(size 1.27 1.27)
				)
			)
		)
		(property "Value" ""
			(at 0 0 90)
			(layer "F.Fab")
			(effects
				(font
					(size 1.27 1.27)
				)
			)
		)
		(duplicate_pad_numbers_are_jumpers no)
		(fp_line
			(start 0.7874 -0.4064)
			(end 0.7874 0.4064)
			(stroke
				(width 0.1524)
				(type default)
			)
			(layer "F.SilkS")
		)
		(fp_line
			(start -0.7874 -0.4064)
			(end 0.7874 -0.4064)
			(stroke
				(width 0.1524)
				(type default)
			)
			(layer "F.SilkS")
		)
		(fp_line
			(start 0.7874 0.4064)
			(end -0.7874 0.4064)
			(stroke
				(width 0.1524)
				(type default)
			)
			(layer "F.SilkS")
		)
		(fp_line
			(start -0.7874 0.4064)
			(end -0.7874 -0.4064)
			(stroke
				(width 0.1524)
				(type default)
			)
			(layer "F.SilkS")
		)
		(fp_line
			(start -0.12065 -0.305054)
			(end -0.12065 -0.2794)
			(stroke
				(width 0.1)
				(type default)
			)
			(layer "F.Fab")
		)
		(fp_line
			(start -0.67945 -0.305054)
			(end -0.12065 -0.305054)
			(stroke
				(width 0.1)
				(type default)
			)
			(layer "F.Fab")
		)
		(fp_line
			(start 0.67945 -0.3048)
			(end 0.67945 0.3048)
			(stroke
				(width 0.1)
				(type default)
			)
			(layer "F.Fab")
		)
		(fp_line
			(start 0.12065 -0.3048)
			(end 0.67945 -0.3048)
			(stroke
				(width 0.1)
				(type default)
			)
			(layer "F.Fab")
		)
		(fp_line
			(start 0.12065 -0.2794)
			(end 0.12065 -0.3048)
			(stroke
				(width 0.1)
				(type default)
			)
			(layer "F.Fab")
		)
		(fp_line
			(start -0.12065 -0.2794)
			(end 0.12065 -0.2794)
			(stroke
				(width 0.1)
				(type default)
			)
			(layer "F.Fab")
		)
		(fp_line
			(start 0.120396 0.2794)
			(end -0.12065 0.2794)
			(stroke
				(width 0.1)
				(type default)
			)
			(layer "F.Fab")
		)
		(fp_line
			(start -0.12065 0.2794)
			(end -0.12065 0.3048)
			(stroke
				(width 0.1)
				(type default)
			)
			(layer "F.Fab")
		)
		(fp_line
			(start 0.67945 0.3048)
			(end 0.120396 0.3048)
			(stroke
				(width 0.1)
				(type default)
			)
			(layer "F.Fab")
		)
		(fp_line
			(start 0.120396 0.3048)
			(end 0.120396 0.2794)
			(stroke
				(width 0.1)
				(type default)
			)
			(layer "F.Fab")
		)
		(fp_line
			(start -0.12065 0.3048)
			(end -0.67945 0.3048)
			(stroke
				(width 0.1)
				(type default)
			)
			(layer "F.Fab")
		)
		(fp_line
			(start -0.67945 0.3048)
			(end -0.67945 -0.305054)
			(stroke
				(width 0.1)
				(type default)
			)
			(layer "F.Fab")
		)
		(pad "1" smd circle
			(at -0.40005 0 90)
			(size 0 0)
			(layers "F.Cu" "F.Mask" "F.Paste")
			(net "P12V_AUX")
		)
		(pad "2" smd circle
			(at 0.40005 0 90)
			(size 0 0)
			(layers "F.Cu" "F.Mask" "F.Paste")
			(net "GND")
		)
	)
	(footprint ""
		(layer "F.Cu")
		(at 338.074 -157.734 180)
		(property "Reference" "R4814"
			(at 0 0 180)
			(layer "F.SilkS")
			(hide yes)
			(effects
				(font
					(size 1.27 1.27)
				)
			)
		)
		(property "Value" ""
			(at 0 0 180)
			(layer "F.Fab")
			(effects
				(font
					(size 1.27 1.27)
				)
			)
		)
		(duplicate_pad_numbers_are_jumpers no)
		(fp_line
			(start 0.7874 0.4064)
			(end -0.7874 0.4064)
			(stroke
				(width 0.1524)
				(type default)
			)
			(layer "F.SilkS")
		)
		(fp_line
			(start 0.7874 -0.4064)
			(end 0.7874 0.4064)
			(stroke
				(width 0.1524)
				(type default)
			)
			(layer "F.SilkS")
		)
		(fp_line
			(start -0.7874 0.4064)
			(end -0.7874 -0.4064)
			(stroke
				(width 0.1524)
				(type default)
			)
			(layer "F.SilkS")
		)
		(fp_line
			(start -0.7874 -0.4064)
			(end 0.7874 -0.4064)
			(stroke
				(width 0.1524)
				(type default)
			)
			(layer "F.SilkS")
		)
		(fp_line
			(start 0.67945 0.3048)
			(end 0.120396 0.3048)
			(stroke
				(width 0.1)
				(type default)
			)
			(layer "F.Fab")
		)
		(fp_line
			(start 0.67945 -0.3048)
			(end 0.67945 0.3048)
			(stroke
				(width 0.1)
				(type default)
			)
			(layer "F.Fab")
		)
		(fp_line
			(start 0.12065 -0.2794)
			(end 0.12065 -0.3048)
			(stroke
				(width 0.1)
				(type default)
			)
			(layer "F.Fab")
		)
		(fp_line
			(start 0.12065 -0.3048)
			(end 0.67945 -0.3048)
			(stroke
				(width 0.1)
				(type default)
			)
			(layer "F.Fab")
		)
		(fp_line
			(start 0.120396 0.3048)
			(end 0.120396 0.2794)
			(stroke
				(width 0.1)
				(type default)
			)
			(layer "F.Fab")
		)
		(fp_line
			(start 0.120396 0.2794)
			(end -0.12065 0.2794)
			(stroke
				(width 0.1)
				(type default)
			)
			(layer "F.Fab")
		)
		(fp_line
			(start -0.12065 0.3048)
			(end -0.67945 0.3048)
			(stroke
				(width 0.1)
				(type default)
			)
			(layer "F.Fab")
		)
		(fp_line
			(start -0.12065 0.2794)
			(end -0.12065 0.3048)
			(stroke
				(width 0.1)
				(type default)
			)
			(layer "F.Fab")
		)
		(fp_line
			(start -0.12065 -0.2794)
			(end 0.12065 -0.2794)
			(stroke
				(width 0.1)
				(type default)
			)
			(layer "F.Fab")
		)
		(fp_line
			(start -0.12065 -0.305054)
			(end -0.12065 -0.2794)
			(stroke
				(width 0.1)
				(type default)
			)
			(layer "F.Fab")
		)
		(fp_line
			(start -0.67945 0.3048)
			(end -0.67945 -0.305054)
			(stroke
				(width 0.1)
				(type default)
			)
			(layer "F.Fab")
		)
		(fp_line
			(start -0.67945 -0.305054)
			(end -0.12065 -0.305054)
			(stroke
				(width 0.1)
				(type default)
			)
			(layer "F.Fab")
		)
		(pad "1" smd circle
			(at -0.40005 0 180)
			(size 0 0)
			(layers "F.Cu" "F.Mask" "F.Paste")
			(net "RST_PEX_SSD12_PERST_N")
		)
		(pad "2" smd circle
			(at 0.40005 0 180)
			(size 0 0)
			(layers "F.Cu" "F.Mask" "F.Paste")
			(net "RST_PEX_SSD12_PERST_R_N")
		)
	)
	(footprint ""
		(layer "F.Cu")
		(at 353.695 -171.45)
		(property "Reference" "R4782"
			(at 0 0 0)
			(layer "F.SilkS")
			(hide yes)
			(effects
				(font
					(size 1.27 1.27)
				)
			)
		)
		(property "Value" ""
			(at 0 0 0)
			(layer "F.Fab")
			(effects
				(font
					(size 1.27 1.27)
				)
			)
		)
		(duplicate_pad_numbers_are_jumpers no)
		(fp_line
			(start -0.7874 -0.4064)
			(end 0.7874 -0.4064)
			(stroke
				(width 0.1524)
				(type default)
			)
			(layer "F.SilkS")
		)
		(fp_line
			(start -0.7874 0.4064)
			(end -0.7874 -0.4064)
			(stroke
				(width 0.1524)
				(type default)
			)
			(layer "F.SilkS")
		)
		(fp_line
			(start 0.7874 -0.4064)
			(end 0.7874 0.4064)
			(stroke
				(width 0.1524)
				(type default)
			)
			(layer "F.SilkS")
		)
		(fp_line
			(start 0.7874 0.4064)
			(end -0.7874 0.4064)
			(stroke
				(width 0.1524)
				(type default)
			)
			(layer "F.SilkS")
		)
		(fp_line
			(start -0.67945 -0.305054)
			(end -0.12065 -0.305054)
			(stroke
				(width 0.1)
				(type default)
			)
			(layer "F.Fab")
		)
		(fp_line
			(start -0.67945 0.3048)
			(end -0.67945 -0.305054)
			(stroke
				(width 0.1)
				(type default)
			)
			(layer "F.Fab")
		)
		(fp_line
			(start -0.12065 -0.305054)
			(end -0.12065 -0.2794)
			(stroke
				(width 0.1)
				(type default)
			)
			(layer "F.Fab")
		)
		(fp_line
			(start -0.12065 -0.2794)
			(end 0.12065 -0.2794)
			(stroke
				(width 0.1)
				(type default)
			)
			(layer "F.Fab")
		)
		(fp_line
			(start -0.12065 0.2794)
			(end -0.12065 0.3048)
			(stroke
				(width 0.1)
				(type default)
			)
			(layer "F.Fab")
		)
		(fp_line
			(start -0.12065 0.3048)
			(end -0.67945 0.3048)
			(stroke
				(width 0.1)
				(type default)
			)
			(layer "F.Fab")
		)
		(fp_line
			(start 0.120396 0.2794)
			(end -0.12065 0.2794)
			(stroke
				(width 0.1)
				(type default)
			)
			(layer "F.Fab")
		)
		(fp_line
			(start 0.120396 0.3048)
			(end 0.120396 0.2794)
			(stroke
				(width 0.1)
				(type default)
			)
			(layer "F.Fab")
		)
		(fp_line
			(start 0.12065 -0.3048)
			(end 0.67945 -0.3048)
			(stroke
				(width 0.1)
				(type default)
			)
			(layer "F.Fab")
		)
		(fp_line
			(start 0.12065 -0.2794)
			(end 0.12065 -0.3048)
			(stroke
				(width 0.1)
				(type default)
			)
			(layer "F.Fab")
		)
		(fp_line
			(start 0.67945 -0.3048)
			(end 0.67945 0.3048)
			(stroke
				(width 0.1)
				(type default)
			)
			(layer "F.Fab")
		)
		(fp_line
			(start 0.67945 0.3048)
			(end 0.120396 0.3048)
			(stroke
				(width 0.1)
				(type default)
			)
			(layer "F.Fab")
		)
		(pad "1" smd circle
			(at -0.40005 0)
			(size 0 0)
			(layers "F.Cu" "F.Mask" "F.Paste")
			(net "GND")
		)
		(pad "2" smd circle
			(at 0.40005 0)
			(size 0 0)
			(layers "F.Cu" "F.Mask" "F.Paste")
			(net "PCA9555_1_PEX2_A0")
		)
	)
	(footprint ""
		(layer "F.Cu")
		(at 44.178728 -356.244906 90)
		(property "Reference" "C2176"
			(at 0 0 90)
			(layer "F.SilkS")
			(hide yes)
			(effects
				(font
					(size 1.27 1.27)
				)
			)
		)
		(property "Value" ""
			(at 0 0 90)
			(layer "F.Fab")
			(effects
				(font
					(size 1.27 1.27)
				)
			)
		)
		(duplicate_pad_numbers_are_jumpers no)
		(fp_line
			(start 0.299974 -0.150114)
			(end 0.299974 0.150114)
			(stroke
				(width 0.1)
				(type default)
			)
			(layer "F.Fab")
		)
		(fp_line
			(start -0.299974 -0.150114)
			(end 0.299974 -0.150114)
			(stroke
				(width 0.1)
				(type default)
			)
			(layer "F.Fab")
		)
		(fp_line
			(start 0.299974 0.150114)
			(end -0.299974 0.150114)
			(stroke
				(width 0.1)
				(type default)
			)
			(layer "F.Fab")
		)
		(fp_line
			(start -0.299974 0.150114)
			(end -0.299974 -0.150114)
			(stroke
				(width 0.1)
				(type default)
			)
			(layer "F.Fab")
		)
		(pad "1" smd rect
			(at -0.2667 0 90)
			(size 0.3048 0.381)
			(layers "F.Cu" "F.Mask" "F.Paste")
			(net "P5E_PEX0_STN4_TX_DP<67>")
		)
		(pad "2" smd rect
			(at 0.2667 0 90)
			(size 0.3048 0.381)
			(layers "F.Cu" "F.Mask" "F.Paste")
			(net "P5E_PEX0_STN4_TX_C_DP<67>")
		)
	)
	(footprint ""
		(layer "F.Cu")
		(at 133.177026 -193.136774 -90)
		(property "Reference" "R6667"
			(at 0 0 270)
			(layer "F.SilkS")
			(hide yes)
			(effects
				(font
					(size 1.27 1.27)
				)
			)
		)
		(property "Value" ""
			(at 0 0 270)
			(layer "F.Fab")
			(effects
				(font
					(size 1.27 1.27)
				)
			)
		)
		(duplicate_pad_numbers_are_jumpers no)
		(fp_line
			(start -0.7874 0.4064)
			(end -0.7874 -0.4064)
			(stroke
				(width 0.1524)
				(type default)
			)
			(layer "F.SilkS")
		)
		(fp_line
			(start 0.7874 0.4064)
			(end -0.7874 0.4064)
			(stroke
				(width 0.1524)
				(type default)
			)
			(layer "F.SilkS")
		)
		(fp_line
			(start -0.7874 -0.4064)
			(end 0.7874 -0.4064)
			(stroke
				(width 0.1524)
				(type default)
			)
			(layer "F.SilkS")
		)
		(fp_line
			(start 0.7874 -0.4064)
			(end 0.7874 0.4064)
			(stroke
				(width 0.1524)
				(type default)
			)
			(layer "F.SilkS")
		)
		(fp_line
			(start -0.67945 0.3048)
			(end -0.67945 -0.305054)
			(stroke
				(width 0.1)
				(type default)
			)
			(layer "F.Fab")
		)
		(fp_line
			(start -0.12065 0.3048)
			(end -0.67945 0.3048)
			(stroke
				(width 0.1)
				(type default)
			)
			(layer "F.Fab")
		)
		(fp_line
			(start 0.120396 0.3048)
			(end 0.120396 0.2794)
			(stroke
				(width 0.1)
				(type default)
			)
			(layer "F.Fab")
		)
		(fp_line
			(start 0.67945 0.3048)
			(end 0.120396 0.3048)
			(stroke
				(width 0.1)
				(type default)
			)
			(layer "F.Fab")
		)
		(fp_line
			(start -0.12065 0.2794)
			(end -0.12065 0.3048)
			(stroke
				(width 0.1)
				(type default)
			)
			(layer "F.Fab")
		)
		(fp_line
			(start 0.120396 0.2794)
			(end -0.12065 0.2794)
			(stroke
				(width 0.1)
				(type default)
			)
			(layer "F.Fab")
		)
		(fp_line
			(start -0.12065 -0.2794)
			(end 0.12065 -0.2794)
			(stroke
				(width 0.1)
				(type default)
			)
			(layer "F.Fab")
		)
		(fp_line
			(start 0.12065 -0.2794)
			(end 0.12065 -0.3048)
			(stroke
				(width 0.1)
				(type default)
			)
			(layer "F.Fab")
		)
		(fp_line
			(start 0.12065 -0.3048)
			(end 0.67945 -0.3048)
			(stroke
				(width 0.1)
				(type default)
			)
			(layer "F.Fab")
		)
		(fp_line
			(start 0.67945 -0.3048)
			(end 0.67945 0.3048)
			(stroke
				(width 0.1)
				(type default)
			)
			(layer "F.Fab")
		)
		(fp_line
			(start -0.67945 -0.305054)
			(end -0.12065 -0.305054)
			(stroke
				(width 0.1)
				(type default)
			)
			(layer "F.Fab")
		)
		(fp_line
			(start -0.12065 -0.305054)
			(end -0.12065 -0.2794)
			(stroke
				(width 0.1)
				(type default)
			)
			(layer "F.Fab")
		)
		(pad "1" smd circle
			(at -0.40005 0 270)
			(size 0 0)
			(layers "F.Cu" "F.Mask" "F.Paste")
			(net "NIC6_CLK_EN_BUF_N")
		)
		(pad "2" smd circle
			(at 0.40005 0 270)
			(size 0 0)
			(layers "F.Cu" "F.Mask" "F.Paste")
			(net "NIC6_CLK_EN_BUF_R_N")
		)
	)
	(footprint ""
		(layer "F.Cu")
		(at 136.759696 -61.612526)
		(property "Reference" "PD16"
			(at -3.7084 -2.733548 0)
			(unlocked yes)
			(layer "F.SilkS")
			(effects
				(font
					(size 0.7874 0.5842)
					(thickness 0.1524)
				)
				(justify left)
			)
		)
		(property "Value" ""
			(at 0 0 0)
			(layer "F.Fab")
			(effects
				(font
					(size 1.27 1.27)
				)
			)
		)
		(duplicate_pad_numbers_are_jumpers no)
		(fp_line
			(start -3.656584 -1.970024)
			(end -3.656584 1.970024)
			(stroke
				(width 0.1524)
				(type default)
			)
			(layer "F.SilkS")
		)
		(fp_line
			(start -3.656584 1.970024)
			(end 4.240784 1.970024)
			(stroke
				(width 0.1524)
				(type default)
			)
			(layer "F.SilkS")
		)
		(fp_line
			(start 4.240784 -1.970024)
			(end -3.656584 -1.970024)
			(stroke
				(width 0.1524)
				(type default)
			)
			(layer "F.SilkS")
		)
		(fp_line
			(start 4.240784 1.970024)
			(end 4.240784 -1.970024)
			(stroke
				(width 0.1524)
				(type default)
			)
			(layer "F.SilkS")
		)
		(fp_poly
			(pts
				(xy 3.580384 1.970024) (xy 3.580384 -1.970024) (xy 4.240784 -1.970024) (xy 4.240784 1.970024)
			)
			(stroke
				(width 0)
				(type default)
			)
			(fill yes)
			(layer "F.SilkS")
		)
		(fp_line
			(start -2.3749 -1.970024)
			(end -2.3749 1.970024)
			(stroke
				(width 0.1)
				(type default)
			)
			(layer "F.Fab")
		)
		(fp_line
			(start -2.3749 1.970024)
			(end 2.3749 1.970024)
			(stroke
				(width 0.1)
				(type default)
			)
			(layer "F.Fab")
		)
		(fp_line
			(start 2.3749 -1.970024)
			(end -2.3749 -1.970024)
			(stroke
				(width 0.1)
				(type default)
			)
			(layer "F.Fab")
		)
		(fp_line
			(start 2.3749 1.970024)
			(end 2.3749 -1.970024)
			(stroke
				(width 0.1)
				(type default)
			)
			(layer "F.Fab")
		)
		(fp_text user "+"
			(at -4.9784 -0.23495 0)
			(unlocked yes)
			(layer "F.Fab")
			(effects
				(font
					(size 1.905 1.4224)
					(thickness 0.1524)
				)
				(justify left)
			)
		)
		(fp_text user "-"
			(at 4.1656 -0.23495 0)
			(unlocked yes)
			(layer "F.Fab")
			(effects
				(font
					(size 1.905 1.4224)
					(thickness 0.1524)
				)
				(justify left)
			)
		)
		(pad "A" smd rect
			(at -2.450084 0)
			(size 2.159 2.2606)
			(layers "F.Cu" "F.Mask" "F.Paste")
			(net "GND")
		)
		(pad "C" smd rect
			(at 2.450084 0)
			(size 2.159 2.2606)
			(layers "F.Cu" "F.Mask" "F.Paste")
			(net "P12V_AUX")
		)
	)
	(footprint ""
		(layer "F.Cu")
		(at 39.280592 -132.215382)
		(property "Reference" "C37"
			(at 0 0 0)
			(layer "F.SilkS")
			(hide yes)
			(effects
				(font
					(size 1.27 1.27)
				)
			)
		)
		(property "Value" ""
			(at 0 0 0)
			(layer "F.Fab")
			(effects
				(font
					(size 1.27 1.27)
				)
			)
		)
		(duplicate_pad_numbers_are_jumpers no)
		(fp_line
			(start -0.299974 -0.150114)
			(end 0.299974 -0.150114)
			(stroke
				(width 0.1)
				(type default)
			)
			(layer "F.Fab")
		)
		(fp_line
			(start -0.299974 0.150114)
			(end -0.299974 -0.150114)
			(stroke
				(width 0.1)
				(type default)
			)
			(layer "F.Fab")
		)
		(fp_line
			(start 0.299974 -0.150114)
			(end 0.299974 0.150114)
			(stroke
				(width 0.1)
				(type default)
			)
			(layer "F.Fab")
		)
		(fp_line
			(start 0.299974 0.150114)
			(end -0.299974 0.150114)
			(stroke
				(width 0.1)
				(type default)
			)
			(layer "F.Fab")
		)
		(pad "1" smd rect
			(at -0.2667 0)
			(size 0.3048 0.381)
			(layers "F.Cu" "F.Mask" "F.Paste")
			(net "P5E_PEX0_STN1_TX_DN<29>")
		)
		(pad "2" smd rect
			(at 0.2667 0)
			(size 0.3048 0.381)
			(layers "F.Cu" "F.Mask" "F.Paste")
			(net "P5E_PEX0_STN1_TX_C_DN<29>")
		)
	)
	(footprint ""
		(layer "F.Cu")
		(at 231.832404 -311.533032 90)
		(property "Reference" "R4436"
			(at 0 0 90)
			(layer "F.SilkS")
			(hide yes)
			(effects
				(font
					(size 1.27 1.27)
				)
			)
		)
		(property "Value" ""
			(at 0 0 90)
			(layer "F.Fab")
			(effects
				(font
					(size 1.27 1.27)
				)
			)
		)
		(duplicate_pad_numbers_are_jumpers no)
		(fp_line
			(start 0.7874 -0.4064)
			(end 0.7874 0.4064)
			(stroke
				(width 0.1524)
				(type default)
			)
			(layer "F.SilkS")
		)
		(fp_line
			(start -0.7874 -0.4064)
			(end 0.7874 -0.4064)
			(stroke
				(width 0.1524)
				(type default)
			)
			(layer "F.SilkS")
		)
		(fp_line
			(start 0.7874 0.4064)
			(end -0.7874 0.4064)
			(stroke
				(width 0.1524)
				(type default)
			)
			(layer "F.SilkS")
		)
		(fp_line
			(start -0.7874 0.4064)
			(end -0.7874 -0.4064)
			(stroke
				(width 0.1524)
				(type default)
			)
			(layer "F.SilkS")
		)
		(fp_line
			(start -0.12065 -0.305054)
			(end -0.12065 -0.2794)
			(stroke
				(width 0.1)
				(type default)
			)
			(layer "F.Fab")
		)
		(fp_line
			(start -0.67945 -0.305054)
			(end -0.12065 -0.305054)
			(stroke
				(width 0.1)
				(type default)
			)
			(layer "F.Fab")
		)
		(fp_line
			(start 0.67945 -0.3048)
			(end 0.67945 0.3048)
			(stroke
				(width 0.1)
				(type default)
			)
			(layer "F.Fab")
		)
		(fp_line
			(start 0.12065 -0.3048)
			(end 0.67945 -0.3048)
			(stroke
				(width 0.1)
				(type default)
			)
			(layer "F.Fab")
		)
		(fp_line
			(start 0.12065 -0.2794)
			(end 0.12065 -0.3048)
			(stroke
				(width 0.1)
				(type default)
			)
			(layer "F.Fab")
		)
		(fp_line
			(start -0.12065 -0.2794)
			(end 0.12065 -0.2794)
			(stroke
				(width 0.1)
				(type default)
			)
			(layer "F.Fab")
		)
		(fp_line
			(start 0.120396 0.2794)
			(end -0.12065 0.2794)
			(stroke
				(width 0.1)
				(type default)
			)
			(layer "F.Fab")
		)
		(fp_line
			(start -0.12065 0.2794)
			(end -0.12065 0.3048)
			(stroke
				(width 0.1)
				(type default)
			)
			(layer "F.Fab")
		)
		(fp_line
			(start 0.67945 0.3048)
			(end 0.120396 0.3048)
			(stroke
				(width 0.1)
				(type default)
			)
			(layer "F.Fab")
		)
		(fp_line
			(start 0.120396 0.3048)
			(end 0.120396 0.2794)
			(stroke
				(width 0.1)
				(type default)
			)
			(layer "F.Fab")
		)
		(fp_line
			(start -0.12065 0.3048)
			(end -0.67945 0.3048)
			(stroke
				(width 0.1)
				(type default)
			)
			(layer "F.Fab")
		)
		(fp_line
			(start -0.67945 0.3048)
			(end -0.67945 -0.305054)
			(stroke
				(width 0.1)
				(type default)
			)
			(layer "F.Fab")
		)
		(pad "1" smd circle
			(at -0.40005 0 90)
			(size 0 0)
			(layers "F.Cu" "F.Mask" "F.Paste")
			(net "PWRGD_P1V25_PEX1_R")
		)
		(pad "2" smd circle
			(at 0.40005 0 90)
			(size 0 0)
			(layers "F.Cu" "F.Mask" "F.Paste")
			(net "PWRGD_P1V25_PEX1")
		)
	)
	(footprint ""
		(layer "F.Cu")
		(at 379.279912 -310.28894 -135)
		(property "Reference" "R1400"
			(at 0 0 225)
			(layer "F.SilkS")
			(hide yes)
			(effects
				(font
					(size 1.27 1.27)
				)
			)
		)
		(property "Value" ""
			(at 0 0 225)
			(layer "F.Fab")
			(effects
				(font
					(size 1.27 1.27)
				)
			)
		)
		(duplicate_pad_numbers_are_jumpers no)
		(fp_line
			(start 0.787389 0.406267)
			(end -0.787389 0.406267)
			(stroke
				(width 0.1524)
				(type default)
			)
			(layer "F.SilkS")
		)
		(fp_line
			(start 0.787389 -0.406267)
			(end 0.787389 0.406267)
			(stroke
				(width 0.1524)
				(type default)
			)
			(layer "F.SilkS")
		)
		(fp_line
			(start -0.787389 0.406267)
			(end -0.787389 -0.406267)
			(stroke
				(width 0.1524)
				(type default)
			)
			(layer "F.SilkS")
		)
		(fp_line
			(start -0.787389 -0.406267)
			(end 0.787389 -0.406267)
			(stroke
				(width 0.1524)
				(type default)
			)
			(layer "F.SilkS")
		)
		(fp_line
			(start 0.679446 0.30479)
			(end 0.120515 0.30479)
			(stroke
				(width 0.1)
				(type default)
			)
			(layer "F.Fab")
		)
		(fp_line
			(start 0.120515 0.30479)
			(end 0.120335 0.279466)
			(stroke
				(width 0.1)
				(type default)
			)
			(layer "F.Fab")
		)
		(fp_line
			(start 0.120335 0.279466)
			(end -0.120695 0.279466)
			(stroke
				(width 0.1)
				(type default)
			)
			(layer "F.Fab")
		)
		(fp_line
			(start 0.679446 -0.30479)
			(end 0.679446 0.30479)
			(stroke
				(width 0.1)
				(type default)
			)
			(layer "F.Fab")
		)
		(fp_line
			(start -0.120515 0.30479)
			(end -0.679446 0.30479)
			(stroke
				(width 0.1)
				(type default)
			)
			(layer "F.Fab")
		)
		(fp_line
			(start -0.120695 0.279466)
			(end -0.120515 0.30479)
			(stroke
				(width 0.1)
				(type default)
			)
			(layer "F.Fab")
		)
		(fp_line
			(start 0.120695 -0.279466)
			(end 0.120515 -0.30479)
			(stroke
				(width 0.1)
				(type default)
			)
			(layer "F.Fab")
		)
		(fp_line
			(start 0.120515 -0.30479)
			(end 0.679446 -0.30479)
			(stroke
				(width 0.1)
				(type default)
			)
			(layer "F.Fab")
		)
		(fp_line
			(start -0.679446 0.30479)
			(end -0.679446 -0.305149)
			(stroke
				(width 0.1)
				(type default)
			)
			(layer "F.Fab")
		)
		(fp_line
			(start -0.120695 -0.279466)
			(end 0.120695 -0.279466)
			(stroke
				(width 0.1)
				(type default)
			)
			(layer "F.Fab")
		)
		(fp_line
			(start -0.120695 -0.304969)
			(end -0.120695 -0.279466)
			(stroke
				(width 0.1)
				(type default)
			)
			(layer "F.Fab")
		)
		(fp_line
			(start -0.679446 -0.305149)
			(end -0.120695 -0.304969)
			(stroke
				(width 0.1)
				(type default)
			)
			(layer "F.Fab")
		)
		(pad "1" smd circle
			(at -0.40005 0 225)
			(size 0 0)
			(layers "F.Cu" "F.Mask" "F.Paste")
			(net "PEX3_DBG_MODE0")
		)
		(pad "2" smd circle
			(at 0.40005 0 225)
			(size 0 0)
			(layers "F.Cu" "F.Mask" "F.Paste")
			(net "P1V8_PEX")
		)
	)
	(footprint ""
		(layer "F.Cu")
		(at 381.786384 -252.356874 -90)
		(property "Reference" "R1422"
			(at 0 0 270)
			(layer "F.SilkS")
			(hide yes)
			(effects
				(font
					(size 1.27 1.27)
				)
			)
		)
		(property "Value" ""
			(at 0 0 270)
			(layer "F.Fab")
			(effects
				(font
					(size 1.27 1.27)
				)
			)
		)
		(duplicate_pad_numbers_are_jumpers no)
		(fp_line
			(start -0.7874 0.4064)
			(end -0.7874 -0.4064)
			(stroke
				(width 0.1524)
				(type default)
			)
			(layer "F.SilkS")
		)
		(fp_line
			(start 0.7874 0.4064)
			(end -0.7874 0.4064)
			(stroke
				(width 0.1524)
				(type default)
			)
			(layer "F.SilkS")
		)
		(fp_line
			(start -0.7874 -0.4064)
			(end 0.7874 -0.4064)
			(stroke
				(width 0.1524)
				(type default)
			)
			(layer "F.SilkS")
		)
		(fp_line
			(start 0.7874 -0.4064)
			(end 0.7874 0.4064)
			(stroke
				(width 0.1524)
				(type default)
			)
			(layer "F.SilkS")
		)
		(fp_line
			(start -0.67945 0.3048)
			(end -0.67945 -0.305054)
			(stroke
				(width 0.1)
				(type default)
			)
			(layer "F.Fab")
		)
		(fp_line
			(start -0.12065 0.3048)
			(end -0.67945 0.3048)
			(stroke
				(width 0.1)
				(type default)
			)
			(layer "F.Fab")
		)
		(fp_line
			(start 0.120396 0.3048)
			(end 0.120396 0.2794)
			(stroke
				(width 0.1)
				(type default)
			)
			(layer "F.Fab")
		)
		(fp_line
			(start 0.67945 0.3048)
			(end 0.120396 0.3048)
			(stroke
				(width 0.1)
				(type default)
			)
			(layer "F.Fab")
		)
		(fp_line
			(start -0.12065 0.2794)
			(end -0.12065 0.3048)
			(stroke
				(width 0.1)
				(type default)
			)
			(layer "F.Fab")
		)
		(fp_line
			(start 0.120396 0.2794)
			(end -0.12065 0.2794)
			(stroke
				(width 0.1)
				(type default)
			)
			(layer "F.Fab")
		)
		(fp_line
			(start -0.12065 -0.2794)
			(end 0.12065 -0.2794)
			(stroke
				(width 0.1)
				(type default)
			)
			(layer "F.Fab")
		)
		(fp_line
			(start 0.12065 -0.2794)
			(end 0.12065 -0.3048)
			(stroke
				(width 0.1)
				(type default)
			)
			(layer "F.Fab")
		)
		(fp_line
			(start 0.12065 -0.3048)
			(end 0.67945 -0.3048)
			(stroke
				(width 0.1)
				(type default)
			)
			(layer "F.Fab")
		)
		(fp_line
			(start 0.67945 -0.3048)
			(end 0.67945 0.3048)
			(stroke
				(width 0.1)
				(type default)
			)
			(layer "F.Fab")
		)
		(fp_line
			(start -0.67945 -0.305054)
			(end -0.12065 -0.305054)
			(stroke
				(width 0.1)
				(type default)
			)
			(layer "F.Fab")
		)
		(fp_line
			(start -0.12065 -0.305054)
			(end -0.12065 -0.2794)
			(stroke
				(width 0.1)
				(type default)
			)
			(layer "F.Fab")
		)
		(pad "1" smd circle
			(at -0.40005 0 270)
			(size 0 0)
			(layers "F.Cu" "F.Mask" "F.Paste")
			(net "GND")
		)
		(pad "2" smd circle
			(at 0.40005 0 270)
			(size 0 0)
			(layers "F.Cu" "F.Mask" "F.Paste")
			(net "PEX3_DBG_MODE2")
		)
	)
	(footprint ""
		(layer "F.Cu")
		(at 346.782136 -38.041072 180)
		(property "Reference" "R6108"
			(at 0 0 180)
			(layer "F.SilkS")
			(hide yes)
			(effects
				(font
					(size 1.27 1.27)
				)
			)
		)
		(property "Value" ""
			(at 0 0 180)
			(layer "F.Fab")
			(effects
				(font
					(size 1.27 1.27)
				)
			)
		)
		(duplicate_pad_numbers_are_jumpers no)
		(fp_line
			(start 0.7874 0.4064)
			(end -0.7874 0.4064)
			(stroke
				(width 0.1524)
				(type default)
			)
			(layer "F.SilkS")
		)
		(fp_line
			(start 0.7874 -0.4064)
			(end 0.7874 0.4064)
			(stroke
				(width 0.1524)
				(type default)
			)
			(layer "F.SilkS")
		)
		(fp_line
			(start -0.7874 0.4064)
			(end -0.7874 -0.4064)
			(stroke
				(width 0.1524)
				(type default)
			)
			(layer "F.SilkS")
		)
		(fp_line
			(start -0.7874 -0.4064)
			(end 0.7874 -0.4064)
			(stroke
				(width 0.1524)
				(type default)
			)
			(layer "F.SilkS")
		)
		(fp_line
			(start 0.67945 0.3048)
			(end 0.120396 0.3048)
			(stroke
				(width 0.1)
				(type default)
			)
			(layer "F.Fab")
		)
		(fp_line
			(start 0.67945 -0.3048)
			(end 0.67945 0.3048)
			(stroke
				(width 0.1)
				(type default)
			)
			(layer "F.Fab")
		)
		(fp_line
			(start 0.12065 -0.2794)
			(end 0.12065 -0.3048)
			(stroke
				(width 0.1)
				(type default)
			)
			(layer "F.Fab")
		)
		(fp_line
			(start 0.12065 -0.3048)
			(end 0.67945 -0.3048)
			(stroke
				(width 0.1)
				(type default)
			)
			(layer "F.Fab")
		)
		(fp_line
			(start 0.120396 0.3048)
			(end 0.120396 0.2794)
			(stroke
				(width 0.1)
				(type default)
			)
			(layer "F.Fab")
		)
		(fp_line
			(start 0.120396 0.2794)
			(end -0.12065 0.2794)
			(stroke
				(width 0.1)
				(type default)
			)
			(layer "F.Fab")
		)
		(fp_line
			(start -0.12065 0.3048)
			(end -0.67945 0.3048)
			(stroke
				(width 0.1)
				(type default)
			)
			(layer "F.Fab")
		)
		(fp_line
			(start -0.12065 0.2794)
			(end -0.12065 0.3048)
			(stroke
				(width 0.1)
				(type default)
			)
			(layer "F.Fab")
		)
		(fp_line
			(start -0.12065 -0.2794)
			(end 0.12065 -0.2794)
			(stroke
				(width 0.1)
				(type default)
			)
			(layer "F.Fab")
		)
		(fp_line
			(start -0.12065 -0.305054)
			(end -0.12065 -0.2794)
			(stroke
				(width 0.1)
				(type default)
			)
			(layer "F.Fab")
		)
		(fp_line
			(start -0.67945 0.3048)
			(end -0.67945 -0.305054)
			(stroke
				(width 0.1)
				(type default)
			)
			(layer "F.Fab")
		)
		(fp_line
			(start -0.67945 -0.305054)
			(end -0.12065 -0.305054)
			(stroke
				(width 0.1)
				(type default)
			)
			(layer "F.Fab")
		)
		(pad "1" smd circle
			(at -0.40005 0 180)
			(size 0 0)
			(layers "F.Cu" "F.Mask" "F.Paste")
			(net "P5V_AUX")
		)
		(pad "2" smd circle
			(at 0.40005 0 180)
			(size 0 0)
			(layers "F.Cu" "F.Mask" "F.Paste")
			(net "P3V3_SSD12_PG_G2")
		)
	)
	(footprint ""
		(layer "F.Cu")
		(at 375.230136 -294.005508 -90)
		(property "Reference" "C3541"
			(at 0 0 270)
			(layer "F.SilkS")
			(hide yes)
			(effects
				(font
					(size 1.27 1.27)
				)
			)
		)
		(property "Value" ""
			(at 0 0 270)
			(layer "F.Fab")
			(effects
				(font
					(size 1.27 1.27)
				)
			)
		)
		(duplicate_pad_numbers_are_jumpers no)
		(fp_line
			(start -1.2954 0.5842)
			(end -1.2954 -0.5842)
			(stroke
				(width 0.1524)
				(type default)
			)
			(layer "F.SilkS")
		)
		(fp_line
			(start 1.2954 0.5842)
			(end -1.2954 0.5842)
			(stroke
				(width 0.1524)
				(type default)
			)
			(layer "F.SilkS")
		)
		(fp_line
			(start -1.2954 -0.5842)
			(end 1.2954 -0.5842)
			(stroke
				(width 0.1524)
				(type default)
			)
			(layer "F.SilkS")
		)
		(fp_line
			(start 1.2954 -0.5842)
			(end 1.2954 0.5842)
			(stroke
				(width 0.1524)
				(type default)
			)
			(layer "F.SilkS")
		)
		(fp_line
			(start -0.8636 0.4572)
			(end -0.8636 0.4064)
			(stroke
				(width 0.1)
				(type default)
			)
			(layer "F.Fab")
		)
		(fp_line
			(start 0.8636 0.4572)
			(end -0.8636 0.4572)
			(stroke
				(width 0.1)
				(type default)
			)
			(layer "F.Fab")
		)
		(fp_line
			(start -1.1938 0.4064)
			(end -1.1938 -0.4064)
			(stroke
				(width 0.1)
				(type default)
			)
			(layer "F.Fab")
		)
		(fp_line
			(start -0.8636 0.4064)
			(end -1.1938 0.4064)
			(stroke
				(width 0.1)
				(type default)
			)
			(layer "F.Fab")
		)
		(fp_line
			(start 0.8636 0.4064)
			(end 0.8636 0.4572)
			(stroke
				(width 0.1)
				(type default)
			)
			(layer "F.Fab")
		)
		(fp_line
			(start 1.1938 0.4064)
			(end 0.8636 0.4064)
			(stroke
				(width 0.1)
				(type default)
			)
			(layer "F.Fab")
		)
		(fp_line
			(start -1.1938 -0.4064)
			(end -0.8636 -0.4064)
			(stroke
				(width 0.1)
				(type default)
			)
			(layer "F.Fab")
		)
		(fp_line
			(start -0.8636 -0.4064)
			(end -0.8636 -0.4572)
			(stroke
				(width 0.1)
				(type default)
			)
			(layer "F.Fab")
		)
		(fp_line
			(start 0.8636 -0.4064)
			(end 1.1938 -0.4064)
			(stroke
				(width 0.1)
				(type default)
			)
			(layer "F.Fab")
		)
		(fp_line
			(start 1.1938 -0.4064)
			(end 1.1938 0.4064)
			(stroke
				(width 0.1)
				(type default)
			)
			(layer "F.Fab")
		)
		(fp_line
			(start -0.8636 -0.4572)
			(end 0.8636 -0.4572)
			(stroke
				(width 0.1)
				(type default)
			)
			(layer "F.Fab")
		)
		(fp_line
			(start 0.8636 -0.4572)
			(end 0.8636 -0.4064)
			(stroke
				(width 0.1)
				(type default)
			)
			(layer "F.Fab")
		)
		(pad "1" smd rect
			(at -0.7366 0 180)
			(size 0.7112 0.8128)
			(layers "F.Cu" "F.Mask" "F.Paste")
			(net "P1V8_PLL0_PEX3")
		)
		(pad "2" smd rect
			(at 0.7366 0 180)
			(size 0.7112 0.8128)
			(layers "F.Cu" "F.Mask" "F.Paste")
			(net "GND")
		)
	)
	(footprint ""
		(layer "F.Cu")
		(at 289.634422 -356.244906 90)
		(property "Reference" "C591"
			(at 0 0 90)
			(layer "F.SilkS")
			(hide yes)
			(effects
				(font
					(size 1.27 1.27)
				)
			)
		)
		(property "Value" ""
			(at 0 0 90)
			(layer "F.Fab")
			(effects
				(font
					(size 1.27 1.27)
				)
			)
		)
		(duplicate_pad_numbers_are_jumpers no)
		(fp_line
			(start 0.299974 -0.150114)
			(end 0.299974 0.150114)
			(stroke
				(width 0.1)
				(type default)
			)
			(layer "F.Fab")
		)
		(fp_line
			(start -0.299974 -0.150114)
			(end 0.299974 -0.150114)
			(stroke
				(width 0.1)
				(type default)
			)
			(layer "F.Fab")
		)
		(fp_line
			(start 0.299974 0.150114)
			(end -0.299974 0.150114)
			(stroke
				(width 0.1)
				(type default)
			)
			(layer "F.Fab")
		)
		(fp_line
			(start -0.299974 0.150114)
			(end -0.299974 -0.150114)
			(stroke
				(width 0.1)
				(type default)
			)
			(layer "F.Fab")
		)
		(pad "1" smd rect
			(at -0.2667 0 90)
			(size 0.3048 0.381)
			(layers "F.Cu" "F.Mask" "F.Paste")
			(net "P5E_PEX2_STN7_TX_DP<123>")
		)
		(pad "2" smd rect
			(at 0.2667 0 90)
			(size 0.3048 0.381)
			(layers "F.Cu" "F.Mask" "F.Paste")
			(net "P5E_PEX2_STN7_TX_C_DP<123>")
		)
	)
	(footprint ""
		(layer "F.Cu")
		(at 241.444018 -236.682026 -90)
		(property "Reference" "R6237"
			(at 0 0 270)
			(layer "F.SilkS")
			(hide yes)
			(effects
				(font
					(size 1.27 1.27)
				)
			)
		)
		(property "Value" ""
			(at 0 0 270)
			(layer "F.Fab")
			(effects
				(font
					(size 1.27 1.27)
				)
			)
		)
		(duplicate_pad_numbers_are_jumpers no)
		(fp_line
			(start -0.7874 0.4064)
			(end -0.7874 -0.4064)
			(stroke
				(width 0.1524)
				(type default)
			)
			(layer "F.SilkS")
		)
		(fp_line
			(start 0.7874 0.4064)
			(end -0.7874 0.4064)
			(stroke
				(width 0.1524)
				(type default)
			)
			(layer "F.SilkS")
		)
		(fp_line
			(start -0.7874 -0.4064)
			(end 0.7874 -0.4064)
			(stroke
				(width 0.1524)
				(type default)
			)
			(layer "F.SilkS")
		)
		(fp_line
			(start 0.7874 -0.4064)
			(end 0.7874 0.4064)
			(stroke
				(width 0.1524)
				(type default)
			)
			(layer "F.SilkS")
		)
		(fp_line
			(start -0.67945 0.3048)
			(end -0.67945 -0.305054)
			(stroke
				(width 0.1)
				(type default)
			)
			(layer "F.Fab")
		)
		(fp_line
			(start -0.12065 0.3048)
			(end -0.67945 0.3048)
			(stroke
				(width 0.1)
				(type default)
			)
			(layer "F.Fab")
		)
		(fp_line
			(start 0.120396 0.3048)
			(end 0.120396 0.2794)
			(stroke
				(width 0.1)
				(type default)
			)
			(layer "F.Fab")
		)
		(fp_line
			(start 0.67945 0.3048)
			(end 0.120396 0.3048)
			(stroke
				(width 0.1)
				(type default)
			)
			(layer "F.Fab")
		)
		(fp_line
			(start -0.12065 0.2794)
			(end -0.12065 0.3048)
			(stroke
				(width 0.1)
				(type default)
			)
			(layer "F.Fab")
		)
		(fp_line
			(start 0.120396 0.2794)
			(end -0.12065 0.2794)
			(stroke
				(width 0.1)
				(type default)
			)
			(layer "F.Fab")
		)
		(fp_line
			(start -0.12065 -0.2794)
			(end 0.12065 -0.2794)
			(stroke
				(width 0.1)
				(type default)
			)
			(layer "F.Fab")
		)
		(fp_line
			(start 0.12065 -0.2794)
			(end 0.12065 -0.3048)
			(stroke
				(width 0.1)
				(type default)
			)
			(layer "F.Fab")
		)
		(fp_line
			(start 0.12065 -0.3048)
			(end 0.67945 -0.3048)
			(stroke
				(width 0.1)
				(type default)
			)
			(layer "F.Fab")
		)
		(fp_line
			(start 0.67945 -0.3048)
			(end 0.67945 0.3048)
			(stroke
				(width 0.1)
				(type default)
			)
			(layer "F.Fab")
		)
		(fp_line
			(start -0.67945 -0.305054)
			(end -0.12065 -0.305054)
			(stroke
				(width 0.1)
				(type default)
			)
			(layer "F.Fab")
		)
		(fp_line
			(start -0.12065 -0.305054)
			(end -0.12065 -0.2794)
			(stroke
				(width 0.1)
				(type default)
			)
			(layer "F.Fab")
		)
		(pad "1" smd circle
			(at -0.40005 0 270)
			(size 0 0)
			(layers "F.Cu" "F.Mask" "F.Paste")
			(net "BIC_RECOVER_IOEXP_A0")
		)
		(pad "2" smd circle
			(at 0.40005 0 270)
			(size 0 0)
			(layers "F.Cu" "F.Mask" "F.Paste")
			(net "GND")
		)
	)
	(footprint ""
		(layer "F.Cu")
		(at 118.054628 -350.098614 90)
		(property "Reference" "C362"
			(at 0 0 90)
			(layer "F.SilkS")
			(hide yes)
			(effects
				(font
					(size 1.27 1.27)
				)
			)
		)
		(property "Value" ""
			(at 0 0 90)
			(layer "F.Fab")
			(effects
				(font
					(size 1.27 1.27)
				)
			)
		)
		(duplicate_pad_numbers_are_jumpers no)
		(fp_line
			(start 0.299974 -0.150114)
			(end 0.299974 0.150114)
			(stroke
				(width 0.1)
				(type default)
			)
			(layer "F.Fab")
		)
		(fp_line
			(start -0.299974 -0.150114)
			(end 0.299974 -0.150114)
			(stroke
				(width 0.1)
				(type default)
			)
			(layer "F.Fab")
		)
		(fp_line
			(start 0.299974 0.150114)
			(end -0.299974 0.150114)
			(stroke
				(width 0.1)
				(type default)
			)
			(layer "F.Fab")
		)
		(fp_line
			(start -0.299974 0.150114)
			(end -0.299974 -0.150114)
			(stroke
				(width 0.1)
				(type default)
			)
			(layer "F.Fab")
		)
		(pad "1" smd rect
			(at -0.2667 0 90)
			(size 0.3048 0.381)
			(layers "F.Cu" "F.Mask" "F.Paste")
			(net "P5E_PEX1_STN6_TX_DP<100>")
		)
		(pad "2" smd rect
			(at 0.2667 0 90)
			(size 0.3048 0.381)
			(layers "F.Cu" "F.Mask" "F.Paste")
			(net "P5E_PEX1_STN6_TX_C_DP<100>")
		)
	)
	(footprint ""
		(layer "F.Cu")
		(at 242.310412 -123.947428 180)
		(property "Reference" "PR242"
			(at 0 0 180)
			(layer "F.SilkS")
			(hide yes)
			(effects
				(font
					(size 1.27 1.27)
				)
			)
		)
		(property "Value" ""
			(at 0 0 180)
			(layer "F.Fab")
			(effects
				(font
					(size 1.27 1.27)
				)
			)
		)
		(duplicate_pad_numbers_are_jumpers no)
		(fp_line
			(start 0.7874 0.4064)
			(end -0.7874 0.4064)
			(stroke
				(width 0.1524)
				(type default)
			)
			(layer "F.SilkS")
		)
		(fp_line
			(start 0.7874 -0.4064)
			(end 0.7874 0.4064)
			(stroke
				(width 0.1524)
				(type default)
			)
			(layer "F.SilkS")
		)
		(fp_line
			(start -0.7874 0.4064)
			(end -0.7874 -0.4064)
			(stroke
				(width 0.1524)
				(type default)
			)
			(layer "F.SilkS")
		)
		(fp_line
			(start -0.7874 -0.4064)
			(end 0.7874 -0.4064)
			(stroke
				(width 0.1524)
				(type default)
			)
			(layer "F.SilkS")
		)
		(fp_line
			(start 0.67945 0.3048)
			(end 0.120396 0.3048)
			(stroke
				(width 0.1)
				(type default)
			)
			(layer "F.Fab")
		)
		(fp_line
			(start 0.67945 -0.3048)
			(end 0.67945 0.3048)
			(stroke
				(width 0.1)
				(type default)
			)
			(layer "F.Fab")
		)
		(fp_line
			(start 0.12065 -0.2794)
			(end 0.12065 -0.3048)
			(stroke
				(width 0.1)
				(type default)
			)
			(layer "F.Fab")
		)
		(fp_line
			(start 0.12065 -0.3048)
			(end 0.67945 -0.3048)
			(stroke
				(width 0.1)
				(type default)
			)
			(layer "F.Fab")
		)
		(fp_line
			(start 0.120396 0.3048)
			(end 0.120396 0.2794)
			(stroke
				(width 0.1)
				(type default)
			)
			(layer "F.Fab")
		)
		(fp_line
			(start 0.120396 0.2794)
			(end -0.12065 0.2794)
			(stroke
				(width 0.1)
				(type default)
			)
			(layer "F.Fab")
		)
		(fp_line
			(start -0.12065 0.3048)
			(end -0.67945 0.3048)
			(stroke
				(width 0.1)
				(type default)
			)
			(layer "F.Fab")
		)
		(fp_line
			(start -0.12065 0.2794)
			(end -0.12065 0.3048)
			(stroke
				(width 0.1)
				(type default)
			)
			(layer "F.Fab")
		)
		(fp_line
			(start -0.12065 -0.2794)
			(end 0.12065 -0.2794)
			(stroke
				(width 0.1)
				(type default)
			)
			(layer "F.Fab")
		)
		(fp_line
			(start -0.12065 -0.305054)
			(end -0.12065 -0.2794)
			(stroke
				(width 0.1)
				(type default)
			)
			(layer "F.Fab")
		)
		(fp_line
			(start -0.67945 0.3048)
			(end -0.67945 -0.305054)
			(stroke
				(width 0.1)
				(type default)
			)
			(layer "F.Fab")
		)
		(fp_line
			(start -0.67945 -0.305054)
			(end -0.12065 -0.305054)
			(stroke
				(width 0.1)
				(type default)
			)
			(layer "F.Fab")
		)
		(pad "1" smd circle
			(at -0.40005 0 180)
			(size 0 0)
			(layers "F.Cu" "F.Mask" "F.Paste")
			(net "P3V3_NIC4_OCP")
		)
		(pad "2" smd circle
			(at 0.40005 0 180)
			(size 0 0)
			(layers "F.Cu" "F.Mask" "F.Paste")
			(net "GND")
		)
	)
	(footprint ""
		(layer "F.Cu")
		(at 361.188 -178.054 180)
		(property "Reference" "R4706"
			(at 0 0 180)
			(layer "F.SilkS")
			(hide yes)
			(effects
				(font
					(size 1.27 1.27)
				)
			)
		)
		(property "Value" ""
			(at 0 0 180)
			(layer "F.Fab")
			(effects
				(font
					(size 1.27 1.27)
				)
			)
		)
		(duplicate_pad_numbers_are_jumpers no)
		(fp_line
			(start 0.7874 0.4064)
			(end -0.7874 0.4064)
			(stroke
				(width 0.1524)
				(type default)
			)
			(layer "F.SilkS")
		)
		(fp_line
			(start 0.7874 -0.4064)
			(end 0.7874 0.4064)
			(stroke
				(width 0.1524)
				(type default)
			)
			(layer "F.SilkS")
		)
		(fp_line
			(start -0.7874 0.4064)
			(end -0.7874 -0.4064)
			(stroke
				(width 0.1524)
				(type default)
			)
			(layer "F.SilkS")
		)
		(fp_line
			(start -0.7874 -0.4064)
			(end 0.7874 -0.4064)
			(stroke
				(width 0.1524)
				(type default)
			)
			(layer "F.SilkS")
		)
		(fp_line
			(start 0.67945 0.3048)
			(end 0.120396 0.3048)
			(stroke
				(width 0.1)
				(type default)
			)
			(layer "F.Fab")
		)
		(fp_line
			(start 0.67945 -0.3048)
			(end 0.67945 0.3048)
			(stroke
				(width 0.1)
				(type default)
			)
			(layer "F.Fab")
		)
		(fp_line
			(start 0.12065 -0.2794)
			(end 0.12065 -0.3048)
			(stroke
				(width 0.1)
				(type default)
			)
			(layer "F.Fab")
		)
		(fp_line
			(start 0.12065 -0.3048)
			(end 0.67945 -0.3048)
			(stroke
				(width 0.1)
				(type default)
			)
			(layer "F.Fab")
		)
		(fp_line
			(start 0.120396 0.3048)
			(end 0.120396 0.2794)
			(stroke
				(width 0.1)
				(type default)
			)
			(layer "F.Fab")
		)
		(fp_line
			(start 0.120396 0.2794)
			(end -0.12065 0.2794)
			(stroke
				(width 0.1)
				(type default)
			)
			(layer "F.Fab")
		)
		(fp_line
			(start -0.12065 0.3048)
			(end -0.67945 0.3048)
			(stroke
				(width 0.1)
				(type default)
			)
			(layer "F.Fab")
		)
		(fp_line
			(start -0.12065 0.2794)
			(end -0.12065 0.3048)
			(stroke
				(width 0.1)
				(type default)
			)
			(layer "F.Fab")
		)
		(fp_line
			(start -0.12065 -0.2794)
			(end 0.12065 -0.2794)
			(stroke
				(width 0.1)
				(type default)
			)
			(layer "F.Fab")
		)
		(fp_line
			(start -0.12065 -0.305054)
			(end -0.12065 -0.2794)
			(stroke
				(width 0.1)
				(type default)
			)
			(layer "F.Fab")
		)
		(fp_line
			(start -0.67945 0.3048)
			(end -0.67945 -0.305054)
			(stroke
				(width 0.1)
				(type default)
			)
			(layer "F.Fab")
		)
		(fp_line
			(start -0.67945 -0.305054)
			(end -0.12065 -0.305054)
			(stroke
				(width 0.1)
				(type default)
			)
			(layer "F.Fab")
		)
		(pad "1" smd circle
			(at -0.40005 0 180)
			(size 0 0)
			(layers "F.Cu" "F.Mask" "F.Paste")
			(net "SSD6_PEX_PWR_EN")
		)
		(pad "2" smd circle
			(at 0.40005 0 180)
			(size 0 0)
			(layers "F.Cu" "F.Mask" "F.Paste")
			(net "SSD6_PEX_PWR_EN_R")
		)
	)
	(footprint ""
		(layer "F.Cu")
		(at 68.479162 -343.952322 90)
		(property "Reference" "C134"
			(at 0 0 90)
			(layer "F.SilkS")
			(hide yes)
			(effects
				(font
					(size 1.27 1.27)
				)
			)
		)
		(property "Value" ""
			(at 0 0 90)
			(layer "F.Fab")
			(effects
				(font
					(size 1.27 1.27)
				)
			)
		)
		(duplicate_pad_numbers_are_jumpers no)
		(fp_line
			(start 0.299974 -0.150114)
			(end 0.299974 0.150114)
			(stroke
				(width 0.1)
				(type default)
			)
			(layer "F.Fab")
		)
		(fp_line
			(start -0.299974 -0.150114)
			(end 0.299974 -0.150114)
			(stroke
				(width 0.1)
				(type default)
			)
			(layer "F.Fab")
		)
		(fp_line
			(start 0.299974 0.150114)
			(end -0.299974 0.150114)
			(stroke
				(width 0.1)
				(type default)
			)
			(layer "F.Fab")
		)
		(fp_line
			(start -0.299974 0.150114)
			(end -0.299974 -0.150114)
			(stroke
				(width 0.1)
				(type default)
			)
			(layer "F.Fab")
		)
		(pad "1" smd rect
			(at -0.2667 0 90)
			(size 0.3048 0.381)
			(layers "F.Cu" "F.Mask" "F.Paste")
			(net "P5E_PEX0_STN6_TX_DN<109>")
		)
		(pad "2" smd rect
			(at 0.2667 0 90)
			(size 0.3048 0.381)
			(layers "F.Cu" "F.Mask" "F.Paste")
			(net "P5E_PEX0_STN6_TX_C_DN<109>")
		)
	)
	(footprint ""
		(layer "F.Cu")
		(at 261.78129 -209.434684)
		(property "Reference" "JP2"
			(at 2.708656 18.429986 90)
			(unlocked yes)
			(layer "F.SilkS")
			(effects
				(font
					(size 0.7874 0.5842)
					(thickness 0.1524)
				)
				(justify left)
			)
		)
		(property "Value" ""
			(at 0 0 0)
			(layer "F.Fab")
			(effects
				(font
					(size 1.27 1.27)
				)
			)
		)
		(duplicate_pad_numbers_are_jumpers no)
		(fp_line
			(start -1.249934 -1.320038)
			(end 1.249934 -1.320038)
			(stroke
				(width 0.1524)
				(type default)
			)
			(layer "F.SilkS")
		)
		(fp_line
			(start -1.249934 19.100038)
			(end -1.249934 -1.320038)
			(stroke
				(width 0.1524)
				(type default)
			)
			(layer "F.SilkS")
		)
		(fp_line
			(start 1.249934 -1.320038)
			(end 1.249934 19.100038)
			(stroke
				(width 0.1524)
				(type default)
			)
			(layer "F.SilkS")
		)
		(fp_line
			(start 1.249934 19.100038)
			(end -1.249934 19.100038)
			(stroke
				(width 0.1524)
				(type default)
			)
			(layer "F.SilkS")
		)
		(fp_poly
			(pts
				(xy -0.626872 -2.74955) (xy 0.650748 -2.74955) (xy 0.011938 -1.472184)
			)
			(stroke
				(width 0)
				(type default)
			)
			(fill yes)
			(layer "F.SilkS")
		)
		(fp_line
			(start -1.249934 -1.320038)
			(end 1.249934 -1.320038)
			(stroke
				(width 0.1)
				(type default)
			)
			(layer "F.Fab")
		)
		(fp_line
			(start -1.249934 19.100038)
			(end -1.249934 -1.320038)
			(stroke
				(width 0.1)
				(type default)
			)
			(layer "F.Fab")
		)
		(fp_line
			(start 1.249934 -1.320038)
			(end 1.249934 19.100038)
			(stroke
				(width 0.1)
				(type default)
			)
			(layer "F.Fab")
		)
		(fp_line
			(start 1.249934 19.100038)
			(end -1.249934 19.100038)
			(stroke
				(width 0.1)
				(type default)
			)
			(layer "F.Fab")
		)
		(fp_poly
			(pts
				(xy -2.7432 0.63881) (xy -2.7432 -0.63881) (xy -1.465834 0)
			)
			(stroke
				(width 0)
				(type default)
			)
			(fill yes)
			(layer "F.Fab")
		)
		(fp_text user "8"
			(at -1.7526 17.80667 0)
			(unlocked yes)
			(layer "F.SilkS")
			(effects
				(font
					(size 0.7874 0.5842)
					(thickness 0.1524)
				)
			)
		)
		(fp_text user "8"
			(at -1.1938 17.80667 0)
			(unlocked yes)
			(layer "B.SilkS")
			(effects
				(font
					(size 0.7874 0.5842)
					(thickness 0.1524)
				)
				(justify mirror)
			)
		)
		(fp_text user "1"
			(at -1.1176 -0.02413 0)
			(unlocked yes)
			(layer "B.SilkS")
			(effects
				(font
					(size 0.7874 0.5842)
					(thickness 0.1524)
				)
				(justify mirror)
			)
		)
		(fp_text user "8"
			(at -1.1938 17.80667 0)
			(unlocked yes)
			(layer "B.Fab")
			(effects
				(font
					(size 0.7874 0.5842)
					(thickness 0.1524)
				)
				(justify mirror)
			)
		)
		(fp_text user "1"
			(at -1.1176 -0.02413 0)
			(unlocked yes)
			(layer "B.Fab")
			(effects
				(font
					(size 0.7874 0.5842)
					(thickness 0.1524)
				)
				(justify mirror)
			)
		)
		(fp_text user "8"
			(at -1.7526 17.80667 0)
			(unlocked yes)
			(layer "F.Fab")
			(effects
				(font
					(size 0.7874 0.5842)
					(thickness 0.1524)
				)
			)
		)
		(pad "1" thru_hole rect
			(at 0 0)
			(size 1.5494 1.5494)
			(drill 1.0414)
			(layers "*.Cu" "*.Mask")
			(remove_unused_layers no)
			(net "P3V3_AUX_JTAG")
			(clearance 0)
			(padstack
				(mode front_inner_back)
				(layer "Inner"
					(shape circle)
					(size 1.5494 1.5494)
					(clearance 0)
				)
				(layer "B.Cu"
					(shape rect)
					(size 1.5494 1.5494)
					(clearance 0)
				)
			)
		)
		(pad "2" thru_hole circle
			(at 0 2.54)
			(size 1.5494 1.5494)
			(drill 1.0414)
			(layers "*.Cu" "*.Mask")
			(remove_unused_layers no)
			(net "JTAG_CONN_TDO")
			(clearance 0)
		)
		(pad "3" thru_hole circle
			(at 0 5.08)
			(size 1.5494 1.5494)
			(drill 1.0414)
			(layers "*.Cu" "*.Mask")
			(remove_unused_layers no)
			(net "JTAG_CONN_TDI")
			(clearance 0)
		)
		(pad "4" thru_hole circle
			(at 0 7.62)
			(size 1.5494 1.5494)
			(drill 1.0414)
			(layers "*.Cu" "*.Mask")
			(remove_unused_layers no)
			(net "TP_JTAG_PIN4")
			(clearance 0)
		)
		(pad "5" thru_hole circle
			(at 0 10.16)
			(size 1.5494 1.5494)
			(drill 1.0414)
			(layers "*.Cu" "*.Mask")
			(remove_unused_layers no)
			(net "TP_JTAG_PIN5")
			(clearance 0)
		)
		(pad "6" thru_hole circle
			(at 0 12.7)
			(size 1.5494 1.5494)
			(drill 1.0414)
			(layers "*.Cu" "*.Mask")
			(remove_unused_layers no)
			(net "JTAG_CONN_TMS")
			(clearance 0)
		)
		(pad "7" thru_hole circle
			(at 0 15.24)
			(size 1.5494 1.5494)
			(drill 1.0414)
			(layers "*.Cu" "*.Mask")
			(remove_unused_layers no)
			(net "GND")
			(clearance 0)
		)
		(pad "8" thru_hole circle
			(at 0 17.78)
			(size 1.5494 1.5494)
			(drill 1.0414)
			(layers "*.Cu" "*.Mask")
			(remove_unused_layers no)
			(net "JTAG_CONN_TCK")
			(clearance 0)
		)
	)
	(footprint ""
		(layer "F.Cu")
		(at 337.488022 -319.545462 90)
		(property "Reference" "L63"
			(at 0 0 90)
			(layer "F.SilkS")
			(hide yes)
			(effects
				(font
					(size 1.27 1.27)
				)
			)
		)
		(property "Value" ""
			(at 0 0 90)
			(layer "F.Fab")
			(effects
				(font
					(size 1.27 1.27)
				)
			)
		)
		(duplicate_pad_numbers_are_jumpers no)
		(fp_line
			(start 2.248154 -4.9911)
			(end -2.248154 -4.9911)
			(stroke
				(width 0.1524)
				(type default)
			)
			(layer "F.SilkS")
		)
		(fp_line
			(start -2.248154 -4.9911)
			(end -2.248154 -1.618234)
			(stroke
				(width 0.1524)
				(type default)
			)
			(layer "F.SilkS")
		)
		(fp_line
			(start 2.248154 -1.7018)
			(end 2.248154 -4.9911)
			(stroke
				(width 0.1524)
				(type default)
			)
			(layer "F.SilkS")
		)
		(fp_line
			(start -2.248154 1.708658)
			(end -2.248154 4.9911)
			(stroke
				(width 0.1524)
				(type default)
			)
			(layer "F.SilkS")
		)
		(fp_line
			(start 2.248154 4.9911)
			(end 2.248154 1.679956)
			(stroke
				(width 0.1524)
				(type default)
			)
			(layer "F.SilkS")
		)
		(fp_line
			(start -2.248154 4.9911)
			(end 2.248154 4.9911)
			(stroke
				(width 0.1524)
				(type default)
			)
			(layer "F.SilkS")
		)
		(fp_line
			(start 1.700022 -0.899922)
			(end -1.700022 -0.899922)
			(stroke
				(width 0.1)
				(type default)
			)
			(layer "F.Fab")
		)
		(fp_line
			(start -1.700022 -0.899922)
			(end -1.700022 0.899922)
			(stroke
				(width 0.1)
				(type default)
			)
			(layer "F.Fab")
		)
		(fp_line
			(start 1.700022 0.899922)
			(end 1.700022 -0.899922)
			(stroke
				(width 0.1)
				(type default)
			)
			(layer "F.Fab")
		)
		(fp_line
			(start -1.700022 0.899922)
			(end 1.700022 0.899922)
			(stroke
				(width 0.1)
				(type default)
			)
			(layer "F.Fab")
		)
		(pad "1" smd rect
			(at -1.575054 0 90)
			(size 1.1684 9.8044)
			(layers "F.Cu" "F.Mask" "F.Paste")
			(net "P0V8_PEX2")
		)
		(pad "2" smd rect
			(at 1.575054 0 90)
			(size 1.1684 9.8044)
			(layers "F.Cu" "F.Mask" "F.Paste")
			(net "P0V8_SERDES_VDDA_PEX2")
		)
	)
	(footprint ""
		(layer "F.Cu")
		(at 142.926308 -343.952322 90)
		(property "Reference" "C2245"
			(at 0 0 90)
			(layer "F.SilkS")
			(hide yes)
			(effects
				(font
					(size 1.27 1.27)
				)
			)
		)
		(property "Value" ""
			(at 0 0 90)
			(layer "F.Fab")
			(effects
				(font
					(size 1.27 1.27)
				)
			)
		)
		(duplicate_pad_numbers_are_jumpers no)
		(fp_line
			(start 0.299974 -0.150114)
			(end 0.299974 0.150114)
			(stroke
				(width 0.1)
				(type default)
			)
			(layer "F.Fab")
		)
		(fp_line
			(start -0.299974 -0.150114)
			(end 0.299974 -0.150114)
			(stroke
				(width 0.1)
				(type default)
			)
			(layer "F.Fab")
		)
		(fp_line
			(start 0.299974 0.150114)
			(end -0.299974 0.150114)
			(stroke
				(width 0.1)
				(type default)
			)
			(layer "F.Fab")
		)
		(fp_line
			(start -0.299974 0.150114)
			(end -0.299974 -0.150114)
			(stroke
				(width 0.1)
				(type default)
			)
			(layer "F.Fab")
		)
		(pad "1" smd rect
			(at -0.2667 0 90)
			(size 0.3048 0.381)
			(layers "F.Cu" "F.Mask" "F.Paste")
			(net "P5E_PEX1_STN5_TX_DP<94>")
		)
		(pad "2" smd rect
			(at 0.2667 0 90)
			(size 0.3048 0.381)
			(layers "F.Cu" "F.Mask" "F.Paste")
			(net "P5E_PEX1_STN5_TX_C_DP<94>")
		)
	)
	(footprint ""
		(layer "F.Cu")
		(at 101.780594 -308.531768 -90)
		(property "Reference" "C4196"
			(at 0 0 270)
			(layer "F.SilkS")
			(hide yes)
			(effects
				(font
					(size 1.27 1.27)
				)
			)
		)
		(property "Value" ""
			(at 0 0 270)
			(layer "F.Fab")
			(effects
				(font
					(size 1.27 1.27)
				)
			)
		)
		(duplicate_pad_numbers_are_jumpers no)
		(fp_line
			(start -1.2954 0.5842)
			(end -1.2954 -0.5842)
			(stroke
				(width 0.1524)
				(type default)
			)
			(layer "F.SilkS")
		)
		(fp_line
			(start 1.2954 0.5842)
			(end -1.2954 0.5842)
			(stroke
				(width 0.1524)
				(type default)
			)
			(layer "F.SilkS")
		)
		(fp_line
			(start -1.2954 -0.5842)
			(end 1.2954 -0.5842)
			(stroke
				(width 0.1524)
				(type default)
			)
			(layer "F.SilkS")
		)
		(fp_line
			(start 1.2954 -0.5842)
			(end 1.2954 0.5842)
			(stroke
				(width 0.1524)
				(type default)
			)
			(layer "F.SilkS")
		)
		(fp_line
			(start -0.8636 0.4572)
			(end -0.8636 0.4064)
			(stroke
				(width 0.1)
				(type default)
			)
			(layer "F.Fab")
		)
		(fp_line
			(start 0.8636 0.4572)
			(end -0.8636 0.4572)
			(stroke
				(width 0.1)
				(type default)
			)
			(layer "F.Fab")
		)
		(fp_line
			(start -1.1938 0.4064)
			(end -1.1938 -0.4064)
			(stroke
				(width 0.1)
				(type default)
			)
			(layer "F.Fab")
		)
		(fp_line
			(start -0.8636 0.4064)
			(end -1.1938 0.4064)
			(stroke
				(width 0.1)
				(type default)
			)
			(layer "F.Fab")
		)
		(fp_line
			(start 0.8636 0.4064)
			(end 0.8636 0.4572)
			(stroke
				(width 0.1)
				(type default)
			)
			(layer "F.Fab")
		)
		(fp_line
			(start 1.1938 0.4064)
			(end 0.8636 0.4064)
			(stroke
				(width 0.1)
				(type default)
			)
			(layer "F.Fab")
		)
		(fp_line
			(start -1.1938 -0.4064)
			(end -0.8636 -0.4064)
			(stroke
				(width 0.1)
				(type default)
			)
			(layer "F.Fab")
		)
		(fp_line
			(start -0.8636 -0.4064)
			(end -0.8636 -0.4572)
			(stroke
				(width 0.1)
				(type default)
			)
			(layer "F.Fab")
		)
		(fp_line
			(start 0.8636 -0.4064)
			(end 1.1938 -0.4064)
			(stroke
				(width 0.1)
				(type default)
			)
			(layer "F.Fab")
		)
		(fp_line
			(start 1.1938 -0.4064)
			(end 1.1938 0.4064)
			(stroke
				(width 0.1)
				(type default)
			)
			(layer "F.Fab")
		)
		(fp_line
			(start -0.8636 -0.4572)
			(end 0.8636 -0.4572)
			(stroke
				(width 0.1)
				(type default)
			)
			(layer "F.Fab")
		)
		(fp_line
			(start 0.8636 -0.4572)
			(end 0.8636 -0.4064)
			(stroke
				(width 0.1)
				(type default)
			)
			(layer "F.Fab")
		)
		(pad "1" smd rect
			(at -0.7366 0 180)
			(size 0.7112 0.8128)
			(layers "F.Cu" "F.Mask" "F.Paste")
			(net "P0V8_PEX0")
		)
		(pad "2" smd rect
			(at 0.7366 0 180)
			(size 0.7112 0.8128)
			(layers "F.Cu" "F.Mask" "F.Paste")
			(net "GND")
		)
	)
	(footprint ""
		(layer "F.Cu")
		(at 33.11144 -261.434834)
		(property "Reference" "L91"
			(at 0 0 0)
			(layer "F.SilkS")
			(hide yes)
			(effects
				(font
					(size 1.27 1.27)
				)
			)
		)
		(property "Value" ""
			(at 0 0 0)
			(layer "F.Fab")
			(effects
				(font
					(size 1.27 1.27)
				)
			)
		)
		(duplicate_pad_numbers_are_jumpers no)
		(fp_line
			(start -1.63576 -0.8128)
			(end -1.63576 0.8128)
			(stroke
				(width 0.1524)
				(type default)
			)
			(layer "F.SilkS")
		)
		(fp_line
			(start -1.63576 -0.8128)
			(end 1.63576 -0.8128)
			(stroke
				(width 0.1524)
				(type default)
			)
			(layer "F.SilkS")
		)
		(fp_line
			(start 1.63576 -0.8128)
			(end 1.63576 0.8128)
			(stroke
				(width 0.1524)
				(type default)
			)
			(layer "F.SilkS")
		)
		(fp_line
			(start 1.63576 0.8128)
			(end -1.63576 0.8128)
			(stroke
				(width 0.1524)
				(type default)
			)
			(layer "F.SilkS")
		)
		(fp_line
			(start -1.56083 -0.738632)
			(end -1.56083 0.7366)
			(stroke
				(width 0.1)
				(type default)
			)
			(layer "F.Fab")
		)
		(fp_line
			(start -1.56083 0.7366)
			(end -1.524 0.7366)
			(stroke
				(width 0.1)
				(type default)
			)
			(layer "F.Fab")
		)
		(fp_line
			(start -1.524 0.7366)
			(end 1.524 0.7366)
			(stroke
				(width 0.1)
				(type default)
			)
			(layer "F.Fab")
		)
		(fp_line
			(start 1.524 0.7366)
			(end 1.560576 0.7366)
			(stroke
				(width 0.1)
				(type default)
			)
			(layer "F.Fab")
		)
		(fp_line
			(start 1.560576 -0.738632)
			(end -1.56083 -0.738632)
			(stroke
				(width 0.1)
				(type default)
			)
			(layer "F.Fab")
		)
		(fp_line
			(start 1.560576 0.7366)
			(end 1.560576 -0.738632)
			(stroke
				(width 0.1)
				(type default)
			)
			(layer "F.Fab")
		)
		(pad "1" smd rect
			(at -0.94996 0 180)
			(size 1.1176 1.3716)
			(layers "F.Cu" "F.Mask" "F.Paste")
			(net "P1V8_PLL0_PEX0")
		)
		(pad "2" smd rect
			(at 0.94996 0 180)
			(size 1.1176 1.3716)
			(layers "F.Cu" "F.Mask" "F.Paste")
			(net "PCEPLL3_VDDA18_PEX0")
		)
	)
	(footprint ""
		(layer "F.Cu")
		(at 145.749772 -320.900044)
		(property "Reference" "H92"
			(at -6.472174 -7.392416 0)
			(unlocked yes)
			(layer "F.SilkS")
			(effects
				(font
					(size 0.7874 0.5842)
					(thickness 0.1524)
				)
				(justify left)
			)
		)
		(property "Value" ""
			(at 0 0 0)
			(layer "F.Fab")
			(effects
				(font
					(size 1.27 1.27)
				)
			)
		)
		(duplicate_pad_numbers_are_jumpers no)
		(fp_arc
			(start 5.324856 5.97027)
			(mid -7.300568 -3.271407)
			(end 7.999984 0)
			(stroke
				(width 0.1524)
				(type default)
			)
			(layer "F.SilkS")
		)
		(fp_arc
			(start 5.515356 5.794756)
			(mid -7.352116 -3.152493)
			(end 7.999984 0)
			(stroke
				(width 0.1524)
				(type default)
			)
			(layer "B.SilkS")
		)
		(fp_arc
			(start 7.999984 0)
			(mid 7.993661 0.319405)
			(end 7.974584 0.638302)
			(stroke
				(width 0.1524)
				(type default)
			)
			(layer "B.SilkS")
		)
		(fp_circle
			(center 0 0)
			(end 7.999984 0)
			(stroke
				(width 0.1)
				(type default)
			)
			(fill no)
			(layer "B.Fab")
		)
		(fp_circle
			(center 0 0)
			(end 7.999984 0)
			(stroke
				(width 0.1)
				(type default)
			)
			(fill no)
			(layer "F.Fab")
		)
		(pad "" np_thru_hole circle
			(at 0 0)
			(size 4.5212 4.5212)
			(drill 4.5212)
			(layers "*.Cu" "*.Mask")
			(clearance 0.381)
			(thermal_gap 0.381)
		)
		(pad "2" thru_hole circle
			(at 3.6322 0)
			(size 0.762 0.762)
			(drill 0.5588)
			(layers "*.Cu" "*.Mask")
			(remove_unused_layers no)
			(net "GND")
			(clearance 0.1524)
			(thermal_gap 0.1524)
		)
		(pad "3" thru_hole circle
			(at 2.568448 -2.568448)
			(size 0.762 0.762)
			(drill 0.5588)
			(layers "*.Cu" "*.Mask")
			(remove_unused_layers no)
			(net "GND")
			(clearance 0.1524)
			(thermal_gap 0.1524)
		)
		(pad "4" thru_hole circle
			(at 0 -3.6322)
			(size 0.762 0.762)
			(drill 0.5588)
			(layers "*.Cu" "*.Mask")
			(remove_unused_layers no)
			(net "GND")
			(clearance 0.1524)
			(thermal_gap 0.1524)
		)
		(pad "5" thru_hole circle
			(at -2.568448 -2.568448)
			(size 0.762 0.762)
			(drill 0.5588)
			(layers "*.Cu" "*.Mask")
			(remove_unused_layers no)
			(net "GND")
			(clearance 0.1524)
			(thermal_gap 0.1524)
		)
		(pad "6" thru_hole circle
			(at -3.6322 0)
			(size 0.762 0.762)
			(drill 0.5588)
			(layers "*.Cu" "*.Mask")
			(remove_unused_layers no)
			(net "GND")
			(clearance 0.1524)
			(thermal_gap 0.1524)
		)
		(pad "7" thru_hole circle
			(at -2.568448 2.568448)
			(size 0.762 0.762)
			(drill 0.5588)
			(layers "*.Cu" "*.Mask")
			(remove_unused_layers no)
			(net "GND")
			(clearance 0.1524)
			(thermal_gap 0.1524)
		)
		(pad "8" thru_hole circle
			(at 0 3.6322)
			(size 0.762 0.762)
			(drill 0.5588)
			(layers "*.Cu" "*.Mask")
			(remove_unused_layers no)
			(net "GND")
			(clearance 0.1524)
			(thermal_gap 0.1524)
		)
		(pad "9" thru_hole circle
			(at 2.568448 2.568448)
			(size 0.762 0.762)
			(drill 0.5588)
			(layers "*.Cu" "*.Mask")
			(remove_unused_layers no)
			(net "GND")
			(clearance 0.1524)
			(thermal_gap 0.1524)
		)
		(zone
			(layer "F.Cu")
			(hatch none 0.5)
			(connect_pads
				(clearance 0)
			)
			(min_thickness 0.25)
			(keepout
				(tracks not_allowed)
				(vias allowed)
				(pads allowed)
				(copperpour not_allowed)
				(footprints allowed)
			)
			(placement
				(enabled no)
				(sheetname "")
			)
			(fill
				(thermal_gap 0.5)
				(thermal_bridge_width 0.5)
				(island_removal_mode 0)
			)
			(polygon
				(pts
					(arc
						(start 145.749772 -312.90006)
						(mid 137.749788 -320.900044)
						(end 145.749772 -328.900028)
					)
					(arc
						(start 145.749772 -325.649844)
						(mid 140.999972 -320.900044)
						(end 145.749772 -316.150244)
					)
				)
			)
		)
		(zone
			(layer "F.Cu")
			(hatch none 0.5)
			(connect_pads
				(clearance 0)
			)
			(min_thickness 0.25)
			(keepout
				(tracks not_allowed)
				(vias allowed)
				(pads allowed)
				(copperpour not_allowed)
				(footprints allowed)
			)
			(placement
				(enabled no)
				(sheetname "")
			)
			(fill
				(thermal_gap 0.5)
				(thermal_bridge_width 0.5)
				(island_removal_mode 0)
			)
			(polygon
				(pts
					(arc
						(start 145.749772 -312.90006)
						(mid 153.749756 -320.900044)
						(end 145.749772 -328.900028)
					)
					(arc
						(start 145.749772 -325.649844)
						(mid 150.499572 -320.900044)
						(end 145.749772 -316.150244)
					)
				)
			)
		)
		(zone
			(layers "F.Cu" "B.Cu" "In1.Cu" "In2.Cu" "In3.Cu" "In4.Cu" "In5.Cu" "In6.Cu"
				"In7.Cu" "In8.Cu" "In9.Cu" "In10.Cu" "In11.Cu" "In12.Cu" "In13.Cu" "In14.Cu"
				"In15.Cu" "In16.Cu"
			)
			(hatch none 0.5)
			(connect_pads
				(clearance 0)
			)
			(min_thickness 0.25)
			(keepout
				(tracks not_allowed)
				(vias allowed)
				(pads allowed)
				(copperpour not_allowed)
				(footprints allowed)
			)
			(placement
				(enabled no)
				(sheetname "")
			)
			(fill
				(thermal_gap 0.5)
				(thermal_bridge_width 0.5)
				(island_removal_mode 0)
			)
			(polygon
				(pts
					(arc
						(start 148.515832 -320.900044)
						(mid 142.983712 -320.900044)
						(end 148.515832 -320.900044)
					)
				)
			)
		)
		(zone
			(layer "B.Cu")
			(hatch none 0.5)
			(connect_pads
				(clearance 0)
			)
			(min_thickness 0.25)
			(keepout
				(tracks not_allowed)
				(vias allowed)
				(pads allowed)
				(copperpour not_allowed)
				(footprints allowed)
			)
			(placement
				(enabled no)
				(sheetname "")
			)
			(fill
				(thermal_gap 0.5)
				(thermal_bridge_width 0.5)
				(island_removal_mode 0)
			)
			(polygon
				(pts
					(arc
						(start 145.749772 -315.896244)
						(mid 140.745972 -320.900044)
						(end 145.749772 -325.903844)
					)
					(arc
						(start 145.749772 -325.421244)
						(mid 141.228572 -320.900044)
						(end 145.749772 -316.378844)
					)
				)
			)
		)
		(zone
			(layer "B.Cu")
			(hatch none 0.5)
			(connect_pads
				(clearance 0)
			)
			(min_thickness 0.25)
			(keepout
				(tracks not_allowed)
				(vias allowed)
				(pads allowed)
				(copperpour not_allowed)
				(footprints allowed)
			)
			(placement
				(enabled no)
				(sheetname "")
			)
			(fill
				(thermal_gap 0.5)
				(thermal_bridge_width 0.5)
				(island_removal_mode 0)
			)
			(polygon
				(pts
					(arc
						(start 145.749772 -315.896244)
						(mid 150.753572 -320.900044)
						(end 145.749772 -325.903844)
					)
					(arc
						(start 145.749772 -325.421244)
						(mid 150.270972 -320.900044)
						(end 145.749772 -316.378844)
					)
				)
			)
		)
	)
	(footprint ""
		(layer "F.Cu")
		(at 347.842586 -258.14655 180)
		(property "Reference" "PR143"
			(at 0 0 180)
			(layer "F.SilkS")
			(hide yes)
			(effects
				(font
					(size 1.27 1.27)
				)
			)
		)
		(property "Value" ""
			(at 0 0 180)
			(layer "F.Fab")
			(effects
				(font
					(size 1.27 1.27)
				)
			)
		)
		(duplicate_pad_numbers_are_jumpers no)
		(fp_line
			(start 0.7874 0.4064)
			(end -0.7874 0.4064)
			(stroke
				(width 0.1524)
				(type default)
			)
			(layer "F.SilkS")
		)
		(fp_line
			(start 0.7874 -0.4064)
			(end 0.7874 0.4064)
			(stroke
				(width 0.1524)
				(type default)
			)
			(layer "F.SilkS")
		)
		(fp_line
			(start -0.7874 0.4064)
			(end -0.7874 -0.4064)
			(stroke
				(width 0.1524)
				(type default)
			)
			(layer "F.SilkS")
		)
		(fp_line
			(start -0.7874 -0.4064)
			(end 0.7874 -0.4064)
			(stroke
				(width 0.1524)
				(type default)
			)
			(layer "F.SilkS")
		)
		(fp_line
			(start 0.67945 0.3048)
			(end 0.120396 0.3048)
			(stroke
				(width 0.1)
				(type default)
			)
			(layer "F.Fab")
		)
		(fp_line
			(start 0.67945 -0.3048)
			(end 0.67945 0.3048)
			(stroke
				(width 0.1)
				(type default)
			)
			(layer "F.Fab")
		)
		(fp_line
			(start 0.12065 -0.2794)
			(end 0.12065 -0.3048)
			(stroke
				(width 0.1)
				(type default)
			)
			(layer "F.Fab")
		)
		(fp_line
			(start 0.12065 -0.3048)
			(end 0.67945 -0.3048)
			(stroke
				(width 0.1)
				(type default)
			)
			(layer "F.Fab")
		)
		(fp_line
			(start 0.120396 0.3048)
			(end 0.120396 0.2794)
			(stroke
				(width 0.1)
				(type default)
			)
			(layer "F.Fab")
		)
		(fp_line
			(start 0.120396 0.2794)
			(end -0.12065 0.2794)
			(stroke
				(width 0.1)
				(type default)
			)
			(layer "F.Fab")
		)
		(fp_line
			(start -0.12065 0.3048)
			(end -0.67945 0.3048)
			(stroke
				(width 0.1)
				(type default)
			)
			(layer "F.Fab")
		)
		(fp_line
			(start -0.12065 0.2794)
			(end -0.12065 0.3048)
			(stroke
				(width 0.1)
				(type default)
			)
			(layer "F.Fab")
		)
		(fp_line
			(start -0.12065 -0.2794)
			(end 0.12065 -0.2794)
			(stroke
				(width 0.1)
				(type default)
			)
			(layer "F.Fab")
		)
		(fp_line
			(start -0.12065 -0.305054)
			(end -0.12065 -0.2794)
			(stroke
				(width 0.1)
				(type default)
			)
			(layer "F.Fab")
		)
		(fp_line
			(start -0.67945 0.3048)
			(end -0.67945 -0.305054)
			(stroke
				(width 0.1)
				(type default)
			)
			(layer "F.Fab")
		)
		(fp_line
			(start -0.67945 -0.305054)
			(end -0.12065 -0.305054)
			(stroke
				(width 0.1)
				(type default)
			)
			(layer "F.Fab")
		)
		(pad "1" smd circle
			(at -0.40005 0 180)
			(size 0 0)
			(layers "F.Cu" "F.Mask" "F.Paste")
			(net "P0V8_PEX2_IINSEN")
		)
		(pad "2" smd circle
			(at 0.40005 0 180)
			(size 0 0)
			(layers "F.Cu" "F.Mask" "F.Paste")
			(net "GND")
		)
	)
	(footprint ""
		(layer "F.Cu")
		(at 256.542286 -250.070874 -90)
		(property "Reference" "R1345"
			(at 0 0 270)
			(layer "F.SilkS")
			(hide yes)
			(effects
				(font
					(size 1.27 1.27)
				)
			)
		)
		(property "Value" ""
			(at 0 0 270)
			(layer "F.Fab")
			(effects
				(font
					(size 1.27 1.27)
				)
			)
		)
		(duplicate_pad_numbers_are_jumpers no)
		(fp_line
			(start -0.7874 0.4064)
			(end -0.7874 -0.4064)
			(stroke
				(width 0.1524)
				(type default)
			)
			(layer "F.SilkS")
		)
		(fp_line
			(start 0.7874 0.4064)
			(end -0.7874 0.4064)
			(stroke
				(width 0.1524)
				(type default)
			)
			(layer "F.SilkS")
		)
		(fp_line
			(start -0.7874 -0.4064)
			(end 0.7874 -0.4064)
			(stroke
				(width 0.1524)
				(type default)
			)
			(layer "F.SilkS")
		)
		(fp_line
			(start 0.7874 -0.4064)
			(end 0.7874 0.4064)
			(stroke
				(width 0.1524)
				(type default)
			)
			(layer "F.SilkS")
		)
		(fp_line
			(start -0.67945 0.3048)
			(end -0.67945 -0.305054)
			(stroke
				(width 0.1)
				(type default)
			)
			(layer "F.Fab")
		)
		(fp_line
			(start -0.12065 0.3048)
			(end -0.67945 0.3048)
			(stroke
				(width 0.1)
				(type default)
			)
			(layer "F.Fab")
		)
		(fp_line
			(start 0.120396 0.3048)
			(end 0.120396 0.2794)
			(stroke
				(width 0.1)
				(type default)
			)
			(layer "F.Fab")
		)
		(fp_line
			(start 0.67945 0.3048)
			(end 0.120396 0.3048)
			(stroke
				(width 0.1)
				(type default)
			)
			(layer "F.Fab")
		)
		(fp_line
			(start -0.12065 0.2794)
			(end -0.12065 0.3048)
			(stroke
				(width 0.1)
				(type default)
			)
			(layer "F.Fab")
		)
		(fp_line
			(start 0.120396 0.2794)
			(end -0.12065 0.2794)
			(stroke
				(width 0.1)
				(type default)
			)
			(layer "F.Fab")
		)
		(fp_line
			(start -0.12065 -0.2794)
			(end 0.12065 -0.2794)
			(stroke
				(width 0.1)
				(type default)
			)
			(layer "F.Fab")
		)
		(fp_line
			(start 0.12065 -0.2794)
			(end 0.12065 -0.3048)
			(stroke
				(width 0.1)
				(type default)
			)
			(layer "F.Fab")
		)
		(fp_line
			(start 0.12065 -0.3048)
			(end 0.67945 -0.3048)
			(stroke
				(width 0.1)
				(type default)
			)
			(layer "F.Fab")
		)
		(fp_line
			(start 0.67945 -0.3048)
			(end 0.67945 0.3048)
			(stroke
				(width 0.1)
				(type default)
			)
			(layer "F.Fab")
		)
		(fp_line
			(start -0.67945 -0.305054)
			(end -0.12065 -0.305054)
			(stroke
				(width 0.1)
				(type default)
			)
			(layer "F.Fab")
		)
		(fp_line
			(start -0.12065 -0.305054)
			(end -0.12065 -0.2794)
			(stroke
				(width 0.1)
				(type default)
			)
			(layer "F.Fab")
		)
		(pad "1" smd circle
			(at -0.40005 0 270)
			(size 0 0)
			(layers "F.Cu" "F.Mask" "F.Paste")
			(net "PEX2_MODE_SEL9")
		)
		(pad "2" smd circle
			(at 0.40005 0 270)
			(size 0 0)
			(layers "F.Cu" "F.Mask" "F.Paste")
			(net "P1V8_PEX")
		)
	)
	(footprint ""
		(layer "F.Cu")
		(at 101.703886 -219.559886)
		(property "Reference" "R849"
			(at 0 0 0)
			(layer "F.SilkS")
			(hide yes)
			(effects
				(font
					(size 1.27 1.27)
				)
			)
		)
		(property "Value" ""
			(at 0 0 0)
			(layer "F.Fab")
			(effects
				(font
					(size 1.27 1.27)
				)
			)
		)
		(duplicate_pad_numbers_are_jumpers no)
		(fp_line
			(start -0.7874 -0.4064)
			(end 0.7874 -0.4064)
			(stroke
				(width 0.1524)
				(type default)
			)
			(layer "F.SilkS")
		)
		(fp_line
			(start -0.7874 0.4064)
			(end -0.7874 -0.4064)
			(stroke
				(width 0.1524)
				(type default)
			)
			(layer "F.SilkS")
		)
		(fp_line
			(start 0.7874 -0.4064)
			(end 0.7874 0.4064)
			(stroke
				(width 0.1524)
				(type default)
			)
			(layer "F.SilkS")
		)
		(fp_line
			(start 0.7874 0.4064)
			(end -0.7874 0.4064)
			(stroke
				(width 0.1524)
				(type default)
			)
			(layer "F.SilkS")
		)
		(fp_line
			(start -0.67945 -0.305054)
			(end -0.12065 -0.305054)
			(stroke
				(width 0.1)
				(type default)
			)
			(layer "F.Fab")
		)
		(fp_line
			(start -0.67945 0.3048)
			(end -0.67945 -0.305054)
			(stroke
				(width 0.1)
				(type default)
			)
			(layer "F.Fab")
		)
		(fp_line
			(start -0.12065 -0.305054)
			(end -0.12065 -0.2794)
			(stroke
				(width 0.1)
				(type default)
			)
			(layer "F.Fab")
		)
		(fp_line
			(start -0.12065 -0.2794)
			(end 0.12065 -0.2794)
			(stroke
				(width 0.1)
				(type default)
			)
			(layer "F.Fab")
		)
		(fp_line
			(start -0.12065 0.2794)
			(end -0.12065 0.3048)
			(stroke
				(width 0.1)
				(type default)
			)
			(layer "F.Fab")
		)
		(fp_line
			(start -0.12065 0.3048)
			(end -0.67945 0.3048)
			(stroke
				(width 0.1)
				(type default)
			)
			(layer "F.Fab")
		)
		(fp_line
			(start 0.120396 0.2794)
			(end -0.12065 0.2794)
			(stroke
				(width 0.1)
				(type default)
			)
			(layer "F.Fab")
		)
		(fp_line
			(start 0.120396 0.3048)
			(end 0.120396 0.2794)
			(stroke
				(width 0.1)
				(type default)
			)
			(layer "F.Fab")
		)
		(fp_line
			(start 0.12065 -0.3048)
			(end 0.67945 -0.3048)
			(stroke
				(width 0.1)
				(type default)
			)
			(layer "F.Fab")
		)
		(fp_line
			(start 0.12065 -0.2794)
			(end 0.12065 -0.3048)
			(stroke
				(width 0.1)
				(type default)
			)
			(layer "F.Fab")
		)
		(fp_line
			(start 0.67945 -0.3048)
			(end 0.67945 0.3048)
			(stroke
				(width 0.1)
				(type default)
			)
			(layer "F.Fab")
		)
		(fp_line
			(start 0.67945 0.3048)
			(end 0.120396 0.3048)
			(stroke
				(width 0.1)
				(type default)
			)
			(layer "F.Fab")
		)
		(pad "1" smd circle
			(at -0.40005 0)
			(size 0 0)
			(layers "F.Cu" "F.Mask" "F.Paste")
			(net "P1V8_PEX_VCC")
		)
		(pad "2" smd circle
			(at 0.40005 0)
			(size 0 0)
			(layers "F.Cu" "F.Mask" "F.Paste")
			(net "PWRGD_P1V8_PEX")
		)
	)
	(footprint ""
		(layer "F.Cu")
		(at 381.340106 -259.834634 180)
		(property "Reference" "C3570"
			(at 0 0 180)
			(layer "F.SilkS")
			(hide yes)
			(effects
				(font
					(size 1.27 1.27)
				)
			)
		)
		(property "Value" ""
			(at 0 0 180)
			(layer "F.Fab")
			(effects
				(font
					(size 1.27 1.27)
				)
			)
		)
		(duplicate_pad_numbers_are_jumpers no)
		(fp_line
			(start 1.2954 0.5842)
			(end -1.2954 0.5842)
			(stroke
				(width 0.1524)
				(type default)
			)
			(layer "F.SilkS")
		)
		(fp_line
			(start 1.2954 -0.5842)
			(end 1.2954 0.5842)
			(stroke
				(width 0.1524)
				(type default)
			)
			(layer "F.SilkS")
		)
		(fp_line
			(start -1.2954 0.5842)
			(end -1.2954 -0.5842)
			(stroke
				(width 0.1524)
				(type default)
			)
			(layer "F.SilkS")
		)
		(fp_line
			(start -1.2954 -0.5842)
			(end 1.2954 -0.5842)
			(stroke
				(width 0.1524)
				(type default)
			)
			(layer "F.SilkS")
		)
		(fp_line
			(start 1.1938 0.4064)
			(end 0.8636 0.4064)
			(stroke
				(width 0.1)
				(type default)
			)
			(layer "F.Fab")
		)
		(fp_line
			(start 1.1938 -0.4064)
			(end 1.1938 0.4064)
			(stroke
				(width 0.1)
				(type default)
			)
			(layer "F.Fab")
		)
		(fp_line
			(start 0.8636 0.4572)
			(end -0.8636 0.4572)
			(stroke
				(width 0.1)
				(type default)
			)
			(layer "F.Fab")
		)
		(fp_line
			(start 0.8636 0.4064)
			(end 0.8636 0.4572)
			(stroke
				(width 0.1)
				(type default)
			)
			(layer "F.Fab")
		)
		(fp_line
			(start 0.8636 -0.4064)
			(end 1.1938 -0.4064)
			(stroke
				(width 0.1)
				(type default)
			)
			(layer "F.Fab")
		)
		(fp_line
			(start 0.8636 -0.4572)
			(end 0.8636 -0.4064)
			(stroke
				(width 0.1)
				(type default)
			)
			(layer "F.Fab")
		)
		(fp_line
			(start -0.8636 0.4572)
			(end -0.8636 0.4064)
			(stroke
				(width 0.1)
				(type default)
			)
			(layer "F.Fab")
		)
		(fp_line
			(start -0.8636 0.4064)
			(end -1.1938 0.4064)
			(stroke
				(width 0.1)
				(type default)
			)
			(layer "F.Fab")
		)
		(fp_line
			(start -0.8636 -0.4064)
			(end -0.8636 -0.4572)
			(stroke
				(width 0.1)
				(type default)
			)
			(layer "F.Fab")
		)
		(fp_line
			(start -0.8636 -0.4572)
			(end 0.8636 -0.4572)
			(stroke
				(width 0.1)
				(type default)
			)
			(layer "F.Fab")
		)
		(fp_line
			(start -1.1938 0.4064)
			(end -1.1938 -0.4064)
			(stroke
				(width 0.1)
				(type default)
			)
			(layer "F.Fab")
		)
		(fp_line
			(start -1.1938 -0.4064)
			(end -0.8636 -0.4064)
			(stroke
				(width 0.1)
				(type default)
			)
			(layer "F.Fab")
		)
		(pad "1" smd rect
			(at -0.7366 0 90)
			(size 0.7112 0.8128)
			(layers "F.Cu" "F.Mask" "F.Paste")
			(net "PCEPLL3_VDDA18_PEX3_R")
		)
		(pad "2" smd rect
			(at 0.7366 0 90)
			(size 0.7112 0.8128)
			(layers "F.Cu" "F.Mask" "F.Paste")
			(net "GND")
		)
	)
	(footprint ""
		(layer "F.Cu")
		(at 215.551512 -231.416606 -90)
		(property "Reference" "R4555"
			(at 0 0 270)
			(layer "F.SilkS")
			(hide yes)
			(effects
				(font
					(size 1.27 1.27)
				)
			)
		)
		(property "Value" ""
			(at 0 0 270)
			(layer "F.Fab")
			(effects
				(font
					(size 1.27 1.27)
				)
			)
		)
		(duplicate_pad_numbers_are_jumpers no)
		(fp_line
			(start -0.7874 0.4064)
			(end -0.7874 -0.4064)
			(stroke
				(width 0.1524)
				(type default)
			)
			(layer "F.SilkS")
		)
		(fp_line
			(start 0.7874 0.4064)
			(end -0.7874 0.4064)
			(stroke
				(width 0.1524)
				(type default)
			)
			(layer "F.SilkS")
		)
		(fp_line
			(start -0.7874 -0.4064)
			(end 0.7874 -0.4064)
			(stroke
				(width 0.1524)
				(type default)
			)
			(layer "F.SilkS")
		)
		(fp_line
			(start 0.7874 -0.4064)
			(end 0.7874 0.4064)
			(stroke
				(width 0.1524)
				(type default)
			)
			(layer "F.SilkS")
		)
		(fp_line
			(start -0.67945 0.3048)
			(end -0.67945 -0.305054)
			(stroke
				(width 0.1)
				(type default)
			)
			(layer "F.Fab")
		)
		(fp_line
			(start -0.12065 0.3048)
			(end -0.67945 0.3048)
			(stroke
				(width 0.1)
				(type default)
			)
			(layer "F.Fab")
		)
		(fp_line
			(start 0.120396 0.3048)
			(end 0.120396 0.2794)
			(stroke
				(width 0.1)
				(type default)
			)
			(layer "F.Fab")
		)
		(fp_line
			(start 0.67945 0.3048)
			(end 0.120396 0.3048)
			(stroke
				(width 0.1)
				(type default)
			)
			(layer "F.Fab")
		)
		(fp_line
			(start -0.12065 0.2794)
			(end -0.12065 0.3048)
			(stroke
				(width 0.1)
				(type default)
			)
			(layer "F.Fab")
		)
		(fp_line
			(start 0.120396 0.2794)
			(end -0.12065 0.2794)
			(stroke
				(width 0.1)
				(type default)
			)
			(layer "F.Fab")
		)
		(fp_line
			(start -0.12065 -0.2794)
			(end 0.12065 -0.2794)
			(stroke
				(width 0.1)
				(type default)
			)
			(layer "F.Fab")
		)
		(fp_line
			(start 0.12065 -0.2794)
			(end 0.12065 -0.3048)
			(stroke
				(width 0.1)
				(type default)
			)
			(layer "F.Fab")
		)
		(fp_line
			(start 0.12065 -0.3048)
			(end 0.67945 -0.3048)
			(stroke
				(width 0.1)
				(type default)
			)
			(layer "F.Fab")
		)
		(fp_line
			(start 0.67945 -0.3048)
			(end 0.67945 0.3048)
			(stroke
				(width 0.1)
				(type default)
			)
			(layer "F.Fab")
		)
		(fp_line
			(start -0.67945 -0.305054)
			(end -0.12065 -0.305054)
			(stroke
				(width 0.1)
				(type default)
			)
			(layer "F.Fab")
		)
		(fp_line
			(start -0.12065 -0.305054)
			(end -0.12065 -0.2794)
			(stroke
				(width 0.1)
				(type default)
			)
			(layer "F.Fab")
		)
		(pad "1" smd circle
			(at -0.40005 0 270)
			(size 0 0)
			(layers "F.Cu" "F.Mask" "F.Paste")
			(net "GND")
		)
		(pad "2" smd circle
			(at 0.40005 0 270)
			(size 0 0)
			(layers "F.Cu" "F.Mask" "F.Paste")
			(net "BOARD_ID2")
		)
	)
	(footprint ""
		(layer "F.Cu")
		(at 272.798286 -252.356874 -90)
		(property "Reference" "R1357"
			(at 0 0 270)
			(layer "F.SilkS")
			(hide yes)
			(effects
				(font
					(size 1.27 1.27)
				)
			)
		)
		(property "Value" ""
			(at 0 0 270)
			(layer "F.Fab")
			(effects
				(font
					(size 1.27 1.27)
				)
			)
		)
		(duplicate_pad_numbers_are_jumpers no)
		(fp_line
			(start -0.7874 0.4064)
			(end -0.7874 -0.4064)
			(stroke
				(width 0.1524)
				(type default)
			)
			(layer "F.SilkS")
		)
		(fp_line
			(start 0.7874 0.4064)
			(end -0.7874 0.4064)
			(stroke
				(width 0.1524)
				(type default)
			)
			(layer "F.SilkS")
		)
		(fp_line
			(start -0.7874 -0.4064)
			(end 0.7874 -0.4064)
			(stroke
				(width 0.1524)
				(type default)
			)
			(layer "F.SilkS")
		)
		(fp_line
			(start 0.7874 -0.4064)
			(end 0.7874 0.4064)
			(stroke
				(width 0.1524)
				(type default)
			)
			(layer "F.SilkS")
		)
		(fp_line
			(start -0.67945 0.3048)
			(end -0.67945 -0.305054)
			(stroke
				(width 0.1)
				(type default)
			)
			(layer "F.Fab")
		)
		(fp_line
			(start -0.12065 0.3048)
			(end -0.67945 0.3048)
			(stroke
				(width 0.1)
				(type default)
			)
			(layer "F.Fab")
		)
		(fp_line
			(start 0.120396 0.3048)
			(end 0.120396 0.2794)
			(stroke
				(width 0.1)
				(type default)
			)
			(layer "F.Fab")
		)
		(fp_line
			(start 0.67945 0.3048)
			(end 0.120396 0.3048)
			(stroke
				(width 0.1)
				(type default)
			)
			(layer "F.Fab")
		)
		(fp_line
			(start -0.12065 0.2794)
			(end -0.12065 0.3048)
			(stroke
				(width 0.1)
				(type default)
			)
			(layer "F.Fab")
		)
		(fp_line
			(start 0.120396 0.2794)
			(end -0.12065 0.2794)
			(stroke
				(width 0.1)
				(type default)
			)
			(layer "F.Fab")
		)
		(fp_line
			(start -0.12065 -0.2794)
			(end 0.12065 -0.2794)
			(stroke
				(width 0.1)
				(type default)
			)
			(layer "F.Fab")
		)
		(fp_line
			(start 0.12065 -0.2794)
			(end 0.12065 -0.3048)
			(stroke
				(width 0.1)
				(type default)
			)
			(layer "F.Fab")
		)
		(fp_line
			(start 0.12065 -0.3048)
			(end 0.67945 -0.3048)
			(stroke
				(width 0.1)
				(type default)
			)
			(layer "F.Fab")
		)
		(fp_line
			(start 0.67945 -0.3048)
			(end 0.67945 0.3048)
			(stroke
				(width 0.1)
				(type default)
			)
			(layer "F.Fab")
		)
		(fp_line
			(start -0.67945 -0.305054)
			(end -0.12065 -0.305054)
			(stroke
				(width 0.1)
				(type default)
			)
			(layer "F.Fab")
		)
		(fp_line
			(start -0.12065 -0.305054)
			(end -0.12065 -0.2794)
			(stroke
				(width 0.1)
				(type default)
			)
			(layer "F.Fab")
		)
		(pad "1" smd circle
			(at -0.40005 0 270)
			(size 0 0)
			(layers "F.Cu" "F.Mask" "F.Paste")
			(net "GND")
		)
		(pad "2" smd circle
			(at 0.40005 0 270)
			(size 0 0)
			(layers "F.Cu" "F.Mask" "F.Paste")
			(net "PEX2_MODE_SEL1")
		)
	)
	(footprint ""
		(layer "F.Cu")
		(at 206.623158 -77.563472)
		(property "Reference" "R4309"
			(at 0 0 0)
			(layer "F.SilkS")
			(hide yes)
			(effects
				(font
					(size 1.27 1.27)
				)
			)
		)
		(property "Value" ""
			(at 0 0 0)
			(layer "F.Fab")
			(effects
				(font
					(size 1.27 1.27)
				)
			)
		)
		(duplicate_pad_numbers_are_jumpers no)
		(fp_line
			(start -0.7874 -0.4064)
			(end 0.7874 -0.4064)
			(stroke
				(width 0.1524)
				(type default)
			)
			(layer "F.SilkS")
		)
		(fp_line
			(start -0.7874 0.4064)
			(end -0.7874 -0.4064)
			(stroke
				(width 0.1524)
				(type default)
			)
			(layer "F.SilkS")
		)
		(fp_line
			(start 0.7874 -0.4064)
			(end 0.7874 0.4064)
			(stroke
				(width 0.1524)
				(type default)
			)
			(layer "F.SilkS")
		)
		(fp_line
			(start 0.7874 0.4064)
			(end -0.7874 0.4064)
			(stroke
				(width 0.1524)
				(type default)
			)
			(layer "F.SilkS")
		)
		(fp_line
			(start -0.67945 -0.305054)
			(end -0.12065 -0.305054)
			(stroke
				(width 0.1)
				(type default)
			)
			(layer "F.Fab")
		)
		(fp_line
			(start -0.67945 0.3048)
			(end -0.67945 -0.305054)
			(stroke
				(width 0.1)
				(type default)
			)
			(layer "F.Fab")
		)
		(fp_line
			(start -0.12065 -0.305054)
			(end -0.12065 -0.2794)
			(stroke
				(width 0.1)
				(type default)
			)
			(layer "F.Fab")
		)
		(fp_line
			(start -0.12065 -0.2794)
			(end 0.12065 -0.2794)
			(stroke
				(width 0.1)
				(type default)
			)
			(layer "F.Fab")
		)
		(fp_line
			(start -0.12065 0.2794)
			(end -0.12065 0.3048)
			(stroke
				(width 0.1)
				(type default)
			)
			(layer "F.Fab")
		)
		(fp_line
			(start -0.12065 0.3048)
			(end -0.67945 0.3048)
			(stroke
				(width 0.1)
				(type default)
			)
			(layer "F.Fab")
		)
		(fp_line
			(start 0.120396 0.2794)
			(end -0.12065 0.2794)
			(stroke
				(width 0.1)
				(type default)
			)
			(layer "F.Fab")
		)
		(fp_line
			(start 0.120396 0.3048)
			(end 0.120396 0.2794)
			(stroke
				(width 0.1)
				(type default)
			)
			(layer "F.Fab")
		)
		(fp_line
			(start 0.12065 -0.3048)
			(end 0.67945 -0.3048)
			(stroke
				(width 0.1)
				(type default)
			)
			(layer "F.Fab")
		)
		(fp_line
			(start 0.12065 -0.2794)
			(end 0.12065 -0.3048)
			(stroke
				(width 0.1)
				(type default)
			)
			(layer "F.Fab")
		)
		(fp_line
			(start 0.67945 -0.3048)
			(end 0.67945 0.3048)
			(stroke
				(width 0.1)
				(type default)
			)
			(layer "F.Fab")
		)
		(fp_line
			(start 0.67945 0.3048)
			(end 0.120396 0.3048)
			(stroke
				(width 0.1)
				(type default)
			)
			(layer "F.Fab")
		)
		(pad "1" smd circle
			(at -0.40005 0)
			(size 0 0)
			(layers "F.Cu" "F.Mask" "F.Paste")
			(net "SSD7_LED_R")
		)
		(pad "2" smd circle
			(at 0.40005 0)
			(size 0 0)
			(layers "F.Cu" "F.Mask" "F.Paste")
			(net "SSD7_LED")
		)
	)
	(footprint ""
		(layer "F.Cu")
		(at 327.533 -210.185)
		(property "Reference" "R4159"
			(at 0 0 0)
			(layer "F.SilkS")
			(hide yes)
			(effects
				(font
					(size 1.27 1.27)
				)
			)
		)
		(property "Value" ""
			(at 0 0 0)
			(layer "F.Fab")
			(effects
				(font
					(size 1.27 1.27)
				)
			)
		)
		(duplicate_pad_numbers_are_jumpers no)
		(fp_line
			(start -0.7874 -0.4064)
			(end 0.7874 -0.4064)
			(stroke
				(width 0.1524)
				(type default)
			)
			(layer "F.SilkS")
		)
		(fp_line
			(start -0.7874 0.4064)
			(end -0.7874 -0.4064)
			(stroke
				(width 0.1524)
				(type default)
			)
			(layer "F.SilkS")
		)
		(fp_line
			(start 0.7874 -0.4064)
			(end 0.7874 0.4064)
			(stroke
				(width 0.1524)
				(type default)
			)
			(layer "F.SilkS")
		)
		(fp_line
			(start 0.7874 0.4064)
			(end -0.7874 0.4064)
			(stroke
				(width 0.1524)
				(type default)
			)
			(layer "F.SilkS")
		)
		(fp_line
			(start -0.67945 -0.305054)
			(end -0.12065 -0.305054)
			(stroke
				(width 0.1)
				(type default)
			)
			(layer "F.Fab")
		)
		(fp_line
			(start -0.67945 0.3048)
			(end -0.67945 -0.305054)
			(stroke
				(width 0.1)
				(type default)
			)
			(layer "F.Fab")
		)
		(fp_line
			(start -0.12065 -0.305054)
			(end -0.12065 -0.2794)
			(stroke
				(width 0.1)
				(type default)
			)
			(layer "F.Fab")
		)
		(fp_line
			(start -0.12065 -0.2794)
			(end 0.12065 -0.2794)
			(stroke
				(width 0.1)
				(type default)
			)
			(layer "F.Fab")
		)
		(fp_line
			(start -0.12065 0.2794)
			(end -0.12065 0.3048)
			(stroke
				(width 0.1)
				(type default)
			)
			(layer "F.Fab")
		)
		(fp_line
			(start -0.12065 0.3048)
			(end -0.67945 0.3048)
			(stroke
				(width 0.1)
				(type default)
			)
			(layer "F.Fab")
		)
		(fp_line
			(start 0.120396 0.2794)
			(end -0.12065 0.2794)
			(stroke
				(width 0.1)
				(type default)
			)
			(layer "F.Fab")
		)
		(fp_line
			(start 0.120396 0.3048)
			(end 0.120396 0.2794)
			(stroke
				(width 0.1)
				(type default)
			)
			(layer "F.Fab")
		)
		(fp_line
			(start 0.12065 -0.3048)
			(end 0.67945 -0.3048)
			(stroke
				(width 0.1)
				(type default)
			)
			(layer "F.Fab")
		)
		(fp_line
			(start 0.12065 -0.2794)
			(end 0.12065 -0.3048)
			(stroke
				(width 0.1)
				(type default)
			)
			(layer "F.Fab")
		)
		(fp_line
			(start 0.67945 -0.3048)
			(end 0.67945 0.3048)
			(stroke
				(width 0.1)
				(type default)
			)
			(layer "F.Fab")
		)
		(fp_line
			(start 0.67945 0.3048)
			(end 0.120396 0.3048)
			(stroke
				(width 0.1)
				(type default)
			)
			(layer "F.Fab")
		)
		(pad "1" smd circle
			(at -0.40005 0)
			(size 0 0)
			(layers "F.Cu" "F.Mask" "F.Paste")
			(net "PRSNT_SSD12_FPGA_R_N")
		)
		(pad "2" smd circle
			(at 0.40005 0)
			(size 0 0)
			(layers "F.Cu" "F.Mask" "F.Paste")
			(net "PRSNT_SSD12_FPGA_N")
		)
	)
	(footprint ""
		(layer "F.Cu")
		(at 336.042 -181.991)
		(property "Reference" "R4724"
			(at 0 0 0)
			(layer "F.SilkS")
			(hide yes)
			(effects
				(font
					(size 1.27 1.27)
				)
			)
		)
		(property "Value" ""
			(at 0 0 0)
			(layer "F.Fab")
			(effects
				(font
					(size 1.27 1.27)
				)
			)
		)
		(duplicate_pad_numbers_are_jumpers no)
		(fp_line
			(start -0.7874 -0.4064)
			(end 0.7874 -0.4064)
			(stroke
				(width 0.1524)
				(type default)
			)
			(layer "F.SilkS")
		)
		(fp_line
			(start -0.7874 0.4064)
			(end -0.7874 -0.4064)
			(stroke
				(width 0.1524)
				(type default)
			)
			(layer "F.SilkS")
		)
		(fp_line
			(start 0.7874 -0.4064)
			(end 0.7874 0.4064)
			(stroke
				(width 0.1524)
				(type default)
			)
			(layer "F.SilkS")
		)
		(fp_line
			(start 0.7874 0.4064)
			(end -0.7874 0.4064)
			(stroke
				(width 0.1524)
				(type default)
			)
			(layer "F.SilkS")
		)
		(fp_line
			(start -0.67945 -0.305054)
			(end -0.12065 -0.305054)
			(stroke
				(width 0.1)
				(type default)
			)
			(layer "F.Fab")
		)
		(fp_line
			(start -0.67945 0.3048)
			(end -0.67945 -0.305054)
			(stroke
				(width 0.1)
				(type default)
			)
			(layer "F.Fab")
		)
		(fp_line
			(start -0.12065 -0.305054)
			(end -0.12065 -0.2794)
			(stroke
				(width 0.1)
				(type default)
			)
			(layer "F.Fab")
		)
		(fp_line
			(start -0.12065 -0.2794)
			(end 0.12065 -0.2794)
			(stroke
				(width 0.1)
				(type default)
			)
			(layer "F.Fab")
		)
		(fp_line
			(start -0.12065 0.2794)
			(end -0.12065 0.3048)
			(stroke
				(width 0.1)
				(type default)
			)
			(layer "F.Fab")
		)
		(fp_line
			(start -0.12065 0.3048)
			(end -0.67945 0.3048)
			(stroke
				(width 0.1)
				(type default)
			)
			(layer "F.Fab")
		)
		(fp_line
			(start 0.120396 0.2794)
			(end -0.12065 0.2794)
			(stroke
				(width 0.1)
				(type default)
			)
			(layer "F.Fab")
		)
		(fp_line
			(start 0.120396 0.3048)
			(end 0.120396 0.2794)
			(stroke
				(width 0.1)
				(type default)
			)
			(layer "F.Fab")
		)
		(fp_line
			(start 0.12065 -0.3048)
			(end 0.67945 -0.3048)
			(stroke
				(width 0.1)
				(type default)
			)
			(layer "F.Fab")
		)
		(fp_line
			(start 0.12065 -0.2794)
			(end 0.12065 -0.3048)
			(stroke
				(width 0.1)
				(type default)
			)
			(layer "F.Fab")
		)
		(fp_line
			(start 0.67945 -0.3048)
			(end 0.67945 0.3048)
			(stroke
				(width 0.1)
				(type default)
			)
			(layer "F.Fab")
		)
		(fp_line
			(start 0.67945 0.3048)
			(end 0.120396 0.3048)
			(stroke
				(width 0.1)
				(type default)
			)
			(layer "F.Fab")
		)
		(pad "1" smd circle
			(at -0.40005 0)
			(size 0 0)
			(layers "F.Cu" "F.Mask" "F.Paste")
			(net "P3V3_AUX")
		)
		(pad "2" smd circle
			(at 0.40005 0)
			(size 0 0)
			(layers "F.Cu" "F.Mask" "F.Paste")
			(net "SSD8_PEX_PWR_EN_R")
		)
	)
	(footprint ""
		(layer "F.Cu")
		(at 244.8433 -185.429652 -90)
		(property "Reference" "R3153"
			(at 0 0 270)
			(layer "F.SilkS")
			(hide yes)
			(effects
				(font
					(size 1.27 1.27)
				)
			)
		)
		(property "Value" ""
			(at 0 0 270)
			(layer "F.Fab")
			(effects
				(font
					(size 1.27 1.27)
				)
			)
		)
		(duplicate_pad_numbers_are_jumpers no)
		(fp_line
			(start -0.7874 0.4064)
			(end -0.7874 -0.4064)
			(stroke
				(width 0.1524)
				(type default)
			)
			(layer "F.SilkS")
		)
		(fp_line
			(start 0.7874 0.4064)
			(end -0.7874 0.4064)
			(stroke
				(width 0.1524)
				(type default)
			)
			(layer "F.SilkS")
		)
		(fp_line
			(start -0.7874 -0.4064)
			(end 0.7874 -0.4064)
			(stroke
				(width 0.1524)
				(type default)
			)
			(layer "F.SilkS")
		)
		(fp_line
			(start 0.7874 -0.4064)
			(end 0.7874 0.4064)
			(stroke
				(width 0.1524)
				(type default)
			)
			(layer "F.SilkS")
		)
		(fp_line
			(start -0.67945 0.3048)
			(end -0.67945 -0.305054)
			(stroke
				(width 0.1)
				(type default)
			)
			(layer "F.Fab")
		)
		(fp_line
			(start -0.12065 0.3048)
			(end -0.67945 0.3048)
			(stroke
				(width 0.1)
				(type default)
			)
			(layer "F.Fab")
		)
		(fp_line
			(start 0.120396 0.3048)
			(end 0.120396 0.2794)
			(stroke
				(width 0.1)
				(type default)
			)
			(layer "F.Fab")
		)
		(fp_line
			(start 0.67945 0.3048)
			(end 0.120396 0.3048)
			(stroke
				(width 0.1)
				(type default)
			)
			(layer "F.Fab")
		)
		(fp_line
			(start -0.12065 0.2794)
			(end -0.12065 0.3048)
			(stroke
				(width 0.1)
				(type default)
			)
			(layer "F.Fab")
		)
		(fp_line
			(start 0.120396 0.2794)
			(end -0.12065 0.2794)
			(stroke
				(width 0.1)
				(type default)
			)
			(layer "F.Fab")
		)
		(fp_line
			(start -0.12065 -0.2794)
			(end 0.12065 -0.2794)
			(stroke
				(width 0.1)
				(type default)
			)
			(layer "F.Fab")
		)
		(fp_line
			(start 0.12065 -0.2794)
			(end 0.12065 -0.3048)
			(stroke
				(width 0.1)
				(type default)
			)
			(layer "F.Fab")
		)
		(fp_line
			(start 0.12065 -0.3048)
			(end 0.67945 -0.3048)
			(stroke
				(width 0.1)
				(type default)
			)
			(layer "F.Fab")
		)
		(fp_line
			(start 0.67945 -0.3048)
			(end 0.67945 0.3048)
			(stroke
				(width 0.1)
				(type default)
			)
			(layer "F.Fab")
		)
		(fp_line
			(start -0.67945 -0.305054)
			(end -0.12065 -0.305054)
			(stroke
				(width 0.1)
				(type default)
			)
			(layer "F.Fab")
		)
		(fp_line
			(start -0.12065 -0.305054)
			(end -0.12065 -0.2794)
			(stroke
				(width 0.1)
				(type default)
			)
			(layer "F.Fab")
		)
		(pad "1" smd circle
			(at -0.40005 0 270)
			(size 0 0)
			(layers "F.Cu" "F.Mask" "F.Paste")
			(net "PWRGD_P1V2_AUX_DLY")
		)
		(pad "2" smd circle
			(at 0.40005 0 270)
			(size 0 0)
			(layers "F.Cu" "F.Mask" "F.Paste")
			(net "PWRGD_P1V2_AUX_RST")
		)
	)
	(footprint ""
		(layer "F.Cu")
		(at 258.44373 -43.85691)
		(property "Reference" "R597"
			(at 0 0 0)
			(layer "F.SilkS")
			(hide yes)
			(effects
				(font
					(size 1.27 1.27)
				)
			)
		)
		(property "Value" ""
			(at 0 0 0)
			(layer "F.Fab")
			(effects
				(font
					(size 1.27 1.27)
				)
			)
		)
		(duplicate_pad_numbers_are_jumpers no)
		(fp_line
			(start -0.7874 -0.4064)
			(end 0.7874 -0.4064)
			(stroke
				(width 0.1524)
				(type default)
			)
			(layer "F.SilkS")
		)
		(fp_line
			(start -0.7874 0.4064)
			(end -0.7874 -0.4064)
			(stroke
				(width 0.1524)
				(type default)
			)
			(layer "F.SilkS")
		)
		(fp_line
			(start 0.7874 -0.4064)
			(end 0.7874 0.4064)
			(stroke
				(width 0.1524)
				(type default)
			)
			(layer "F.SilkS")
		)
		(fp_line
			(start 0.7874 0.4064)
			(end -0.7874 0.4064)
			(stroke
				(width 0.1524)
				(type default)
			)
			(layer "F.SilkS")
		)
		(fp_line
			(start -0.67945 -0.305054)
			(end -0.12065 -0.305054)
			(stroke
				(width 0.1)
				(type default)
			)
			(layer "F.Fab")
		)
		(fp_line
			(start -0.67945 0.3048)
			(end -0.67945 -0.305054)
			(stroke
				(width 0.1)
				(type default)
			)
			(layer "F.Fab")
		)
		(fp_line
			(start -0.12065 -0.305054)
			(end -0.12065 -0.2794)
			(stroke
				(width 0.1)
				(type default)
			)
			(layer "F.Fab")
		)
		(fp_line
			(start -0.12065 -0.2794)
			(end 0.12065 -0.2794)
			(stroke
				(width 0.1)
				(type default)
			)
			(layer "F.Fab")
		)
		(fp_line
			(start -0.12065 0.2794)
			(end -0.12065 0.3048)
			(stroke
				(width 0.1)
				(type default)
			)
			(layer "F.Fab")
		)
		(fp_line
			(start -0.12065 0.3048)
			(end -0.67945 0.3048)
			(stroke
				(width 0.1)
				(type default)
			)
			(layer "F.Fab")
		)
		(fp_line
			(start 0.120396 0.2794)
			(end -0.12065 0.2794)
			(stroke
				(width 0.1)
				(type default)
			)
			(layer "F.Fab")
		)
		(fp_line
			(start 0.120396 0.3048)
			(end 0.120396 0.2794)
			(stroke
				(width 0.1)
				(type default)
			)
			(layer "F.Fab")
		)
		(fp_line
			(start 0.12065 -0.3048)
			(end 0.67945 -0.3048)
			(stroke
				(width 0.1)
				(type default)
			)
			(layer "F.Fab")
		)
		(fp_line
			(start 0.12065 -0.2794)
			(end 0.12065 -0.3048)
			(stroke
				(width 0.1)
				(type default)
			)
			(layer "F.Fab")
		)
		(fp_line
			(start 0.67945 -0.3048)
			(end 0.67945 0.3048)
			(stroke
				(width 0.1)
				(type default)
			)
			(layer "F.Fab")
		)
		(fp_line
			(start 0.67945 0.3048)
			(end 0.120396 0.3048)
			(stroke
				(width 0.1)
				(type default)
			)
			(layer "F.Fab")
		)
		(pad "1" smd circle
			(at -0.40005 0)
			(size 0 0)
			(layers "F.Cu" "F.Mask" "F.Paste")
			(net "SSD8_ADC_A1")
		)
		(pad "2" smd circle
			(at 0.40005 0)
			(size 0 0)
			(layers "F.Cu" "F.Mask" "F.Paste")
			(net "GND")
		)
	)
	(footprint ""
		(layer "F.Cu")
		(at 386.90804 -155.3464 180)
		(property "Reference" "R320"
			(at 0 0 180)
			(layer "F.SilkS")
			(hide yes)
			(effects
				(font
					(size 1.27 1.27)
				)
			)
		)
		(property "Value" ""
			(at 0 0 180)
			(layer "F.Fab")
			(effects
				(font
					(size 1.27 1.27)
				)
			)
		)
		(duplicate_pad_numbers_are_jumpers no)
		(fp_line
			(start 0.7874 0.4064)
			(end -0.7874 0.4064)
			(stroke
				(width 0.1524)
				(type default)
			)
			(layer "F.SilkS")
		)
		(fp_line
			(start 0.7874 -0.4064)
			(end 0.7874 0.4064)
			(stroke
				(width 0.1524)
				(type default)
			)
			(layer "F.SilkS")
		)
		(fp_line
			(start -0.7874 0.4064)
			(end -0.7874 -0.4064)
			(stroke
				(width 0.1524)
				(type default)
			)
			(layer "F.SilkS")
		)
		(fp_line
			(start -0.7874 -0.4064)
			(end 0.7874 -0.4064)
			(stroke
				(width 0.1524)
				(type default)
			)
			(layer "F.SilkS")
		)
		(fp_line
			(start 0.67945 0.3048)
			(end 0.120396 0.3048)
			(stroke
				(width 0.1)
				(type default)
			)
			(layer "F.Fab")
		)
		(fp_line
			(start 0.67945 -0.3048)
			(end 0.67945 0.3048)
			(stroke
				(width 0.1)
				(type default)
			)
			(layer "F.Fab")
		)
		(fp_line
			(start 0.12065 -0.2794)
			(end 0.12065 -0.3048)
			(stroke
				(width 0.1)
				(type default)
			)
			(layer "F.Fab")
		)
		(fp_line
			(start 0.12065 -0.3048)
			(end 0.67945 -0.3048)
			(stroke
				(width 0.1)
				(type default)
			)
			(layer "F.Fab")
		)
		(fp_line
			(start 0.120396 0.3048)
			(end 0.120396 0.2794)
			(stroke
				(width 0.1)
				(type default)
			)
			(layer "F.Fab")
		)
		(fp_line
			(start 0.120396 0.2794)
			(end -0.12065 0.2794)
			(stroke
				(width 0.1)
				(type default)
			)
			(layer "F.Fab")
		)
		(fp_line
			(start -0.12065 0.3048)
			(end -0.67945 0.3048)
			(stroke
				(width 0.1)
				(type default)
			)
			(layer "F.Fab")
		)
		(fp_line
			(start -0.12065 0.2794)
			(end -0.12065 0.3048)
			(stroke
				(width 0.1)
				(type default)
			)
			(layer "F.Fab")
		)
		(fp_line
			(start -0.12065 -0.2794)
			(end 0.12065 -0.2794)
			(stroke
				(width 0.1)
				(type default)
			)
			(layer "F.Fab")
		)
		(fp_line
			(start -0.12065 -0.305054)
			(end -0.12065 -0.2794)
			(stroke
				(width 0.1)
				(type default)
			)
			(layer "F.Fab")
		)
		(fp_line
			(start -0.67945 0.3048)
			(end -0.67945 -0.305054)
			(stroke
				(width 0.1)
				(type default)
			)
			(layer "F.Fab")
		)
		(fp_line
			(start -0.67945 -0.305054)
			(end -0.12065 -0.305054)
			(stroke
				(width 0.1)
				(type default)
			)
			(layer "F.Fab")
		)
		(pad "1" smd circle
			(at -0.40005 0 180)
			(size 0 0)
			(layers "F.Cu" "F.Mask" "F.Paste")
			(net "NIC6_CLK")
		)
		(pad "2" smd circle
			(at 0.40005 0 180)
			(size 0 0)
			(layers "F.Cu" "F.Mask" "F.Paste")
			(net "GND")
		)
	)
	(footprint ""
		(layer "F.Cu")
		(at 13.0175 -310.384952)
		(property "Reference" "PC209"
			(at 0 0 0)
			(layer "F.SilkS")
			(hide yes)
			(effects
				(font
					(size 1.27 1.27)
				)
			)
		)
		(property "Value" ""
			(at 0 0 0)
			(layer "F.Fab")
			(effects
				(font
					(size 1.27 1.27)
				)
			)
		)
		(duplicate_pad_numbers_are_jumpers no)
		(fp_line
			(start -1.524 -0.762)
			(end 1.524 -0.762)
			(stroke
				(width 0.1524)
				(type default)
			)
			(layer "F.SilkS")
		)
		(fp_line
			(start -1.524 0.762)
			(end -1.524 -0.762)
			(stroke
				(width 0.1524)
				(type default)
			)
			(layer "F.SilkS")
		)
		(fp_line
			(start 1.524 -0.762)
			(end 1.524 0.762)
			(stroke
				(width 0.1524)
				(type default)
			)
			(layer "F.SilkS")
		)
		(fp_line
			(start 1.524 0.762)
			(end -1.524 0.762)
			(stroke
				(width 0.1524)
				(type default)
			)
			(layer "F.SilkS")
		)
		(fp_line
			(start -1.1049 -0.724916)
			(end -1.1049 0.724916)
			(stroke
				(width 0.1)
				(type default)
			)
			(layer "F.Fab")
		)
		(fp_line
			(start -1.1049 0.724916)
			(end 1.1049 0.724916)
			(stroke
				(width 0.1)
				(type default)
			)
			(layer "F.Fab")
		)
		(fp_line
			(start 1.1049 -0.724916)
			(end -1.1049 -0.724916)
			(stroke
				(width 0.1)
				(type default)
			)
			(layer "F.Fab")
		)
		(fp_line
			(start 1.1049 0.724916)
			(end 1.1049 -0.724916)
			(stroke
				(width 0.1)
				(type default)
			)
			(layer "F.Fab")
		)
		(pad "1" smd rect
			(at -0.889 0 180)
			(size 1.016 1.27)
			(layers "F.Cu" "F.Mask" "F.Paste")
			(net "SW_P12V_P1V25_PEX0_FLT")
		)
		(pad "2" smd rect
			(at 0.889 0 180)
			(size 1.016 1.27)
			(layers "F.Cu" "F.Mask" "F.Paste")
			(net "GND")
		)
	)
	(footprint ""
		(layer "F.Cu")
		(at 357.746808 -154.256994)
		(property "Reference" "PC830"
			(at 0 0 0)
			(layer "F.SilkS")
			(hide yes)
			(effects
				(font
					(size 1.27 1.27)
				)
			)
		)
		(property "Value" ""
			(at 0 0 0)
			(layer "F.Fab")
			(effects
				(font
					(size 1.27 1.27)
				)
			)
		)
		(duplicate_pad_numbers_are_jumpers no)
		(fp_line
			(start -1.2954 -0.5842)
			(end 1.2954 -0.5842)
			(stroke
				(width 0.1524)
				(type default)
			)
			(layer "F.SilkS")
		)
		(fp_line
			(start -1.2954 0.5842)
			(end -1.2954 -0.5842)
			(stroke
				(width 0.1524)
				(type default)
			)
			(layer "F.SilkS")
		)
		(fp_line
			(start 1.2954 -0.5842)
			(end 1.2954 0.5842)
			(stroke
				(width 0.1524)
				(type default)
			)
			(layer "F.SilkS")
		)
		(fp_line
			(start 1.2954 0.5842)
			(end -1.2954 0.5842)
			(stroke
				(width 0.1524)
				(type default)
			)
			(layer "F.SilkS")
		)
		(fp_line
			(start -1.1938 -0.4064)
			(end -0.8636 -0.4064)
			(stroke
				(width 0.1)
				(type default)
			)
			(layer "F.Fab")
		)
		(fp_line
			(start -1.1938 0.4064)
			(end -1.1938 -0.4064)
			(stroke
				(width 0.1)
				(type default)
			)
			(layer "F.Fab")
		)
		(fp_line
			(start -0.8636 -0.4572)
			(end 0.8636 -0.4572)
			(stroke
				(width 0.1)
				(type default)
			)
			(layer "F.Fab")
		)
		(fp_line
			(start -0.8636 -0.4064)
			(end -0.8636 -0.4572)
			(stroke
				(width 0.1)
				(type default)
			)
			(layer "F.Fab")
		)
		(fp_line
			(start -0.8636 0.4064)
			(end -1.1938 0.4064)
			(stroke
				(width 0.1)
				(type default)
			)
			(layer "F.Fab")
		)
		(fp_line
			(start -0.8636 0.4572)
			(end -0.8636 0.4064)
			(stroke
				(width 0.1)
				(type default)
			)
			(layer "F.Fab")
		)
		(fp_line
			(start 0.8636 -0.4572)
			(end 0.8636 -0.4064)
			(stroke
				(width 0.1)
				(type default)
			)
			(layer "F.Fab")
		)
		(fp_line
			(start 0.8636 -0.4064)
			(end 1.1938 -0.4064)
			(stroke
				(width 0.1)
				(type default)
			)
			(layer "F.Fab")
		)
		(fp_line
			(start 0.8636 0.4064)
			(end 0.8636 0.4572)
			(stroke
				(width 0.1)
				(type default)
			)
			(layer "F.Fab")
		)
		(fp_line
			(start 0.8636 0.4572)
			(end -0.8636 0.4572)
			(stroke
				(width 0.1)
				(type default)
			)
			(layer "F.Fab")
		)
		(fp_line
			(start 1.1938 -0.4064)
			(end 1.1938 0.4064)
			(stroke
				(width 0.1)
				(type default)
			)
			(layer "F.Fab")
		)
		(fp_line
			(start 1.1938 0.4064)
			(end 0.8636 0.4064)
			(stroke
				(width 0.1)
				(type default)
			)
			(layer "F.Fab")
		)
		(pad "1" smd rect
			(at -0.7366 0 270)
			(size 0.7112 0.8128)
			(layers "F.Cu" "F.Mask" "F.Paste")
			(net "GND")
		)
		(pad "2" smd rect
			(at 0.7366 0 270)
			(size 0.7112 0.8128)
			(layers "F.Cu" "F.Mask" "F.Paste")
			(net "P12V_NIC6_CO_AVIN_PD")
		)
	)
	(footprint ""
		(layer "F.Cu")
		(at 3.047746 -34.890456 90)
		(property "Reference" "R1643"
			(at 0 0 90)
			(layer "F.SilkS")
			(hide yes)
			(effects
				(font
					(size 1.27 1.27)
				)
			)
		)
		(property "Value" ""
			(at 0 0 90)
			(layer "F.Fab")
			(effects
				(font
					(size 1.27 1.27)
				)
			)
		)
		(duplicate_pad_numbers_are_jumpers no)
		(fp_line
			(start 0.7874 -0.4064)
			(end 0.7874 0.4064)
			(stroke
				(width 0.1524)
				(type default)
			)
			(layer "F.SilkS")
		)
		(fp_line
			(start -0.7874 -0.4064)
			(end 0.7874 -0.4064)
			(stroke
				(width 0.1524)
				(type default)
			)
			(layer "F.SilkS")
		)
		(fp_line
			(start 0.7874 0.4064)
			(end -0.7874 0.4064)
			(stroke
				(width 0.1524)
				(type default)
			)
			(layer "F.SilkS")
		)
		(fp_line
			(start -0.7874 0.4064)
			(end -0.7874 -0.4064)
			(stroke
				(width 0.1524)
				(type default)
			)
			(layer "F.SilkS")
		)
		(fp_line
			(start -0.12065 -0.305054)
			(end -0.12065 -0.2794)
			(stroke
				(width 0.1)
				(type default)
			)
			(layer "F.Fab")
		)
		(fp_line
			(start -0.67945 -0.305054)
			(end -0.12065 -0.305054)
			(stroke
				(width 0.1)
				(type default)
			)
			(layer "F.Fab")
		)
		(fp_line
			(start 0.67945 -0.3048)
			(end 0.67945 0.3048)
			(stroke
				(width 0.1)
				(type default)
			)
			(layer "F.Fab")
		)
		(fp_line
			(start 0.12065 -0.3048)
			(end 0.67945 -0.3048)
			(stroke
				(width 0.1)
				(type default)
			)
			(layer "F.Fab")
		)
		(fp_line
			(start 0.12065 -0.2794)
			(end 0.12065 -0.3048)
			(stroke
				(width 0.1)
				(type default)
			)
			(layer "F.Fab")
		)
		(fp_line
			(start -0.12065 -0.2794)
			(end 0.12065 -0.2794)
			(stroke
				(width 0.1)
				(type default)
			)
			(layer "F.Fab")
		)
		(fp_line
			(start 0.120396 0.2794)
			(end -0.12065 0.2794)
			(stroke
				(width 0.1)
				(type default)
			)
			(layer "F.Fab")
		)
		(fp_line
			(start -0.12065 0.2794)
			(end -0.12065 0.3048)
			(stroke
				(width 0.1)
				(type default)
			)
			(layer "F.Fab")
		)
		(fp_line
			(start 0.67945 0.3048)
			(end 0.120396 0.3048)
			(stroke
				(width 0.1)
				(type default)
			)
			(layer "F.Fab")
		)
		(fp_line
			(start 0.120396 0.3048)
			(end 0.120396 0.2794)
			(stroke
				(width 0.1)
				(type default)
			)
			(layer "F.Fab")
		)
		(fp_line
			(start -0.12065 0.3048)
			(end -0.67945 0.3048)
			(stroke
				(width 0.1)
				(type default)
			)
			(layer "F.Fab")
		)
		(fp_line
			(start -0.67945 0.3048)
			(end -0.67945 -0.305054)
			(stroke
				(width 0.1)
				(type default)
			)
			(layer "F.Fab")
		)
		(pad "1" smd circle
			(at -0.40005 0 90)
			(size 0 0)
			(layers "F.Cu" "F.Mask" "F.Paste")
			(net "SMB_BIC_I2C9_MUX0_SSD0_R_SCL")
		)
		(pad "2" smd circle
			(at 0.40005 0 90)
			(size 0 0)
			(layers "F.Cu" "F.Mask" "F.Paste")
			(net "SMB_ISO_SSD0_SCL")
		)
	)
	(footprint ""
		(layer "F.Cu")
		(at 73.96099 -37.951156)
		(property "Reference" "Q136"
			(at -0.09779 -1.874774 0)
			(unlocked yes)
			(layer "F.SilkS")
			(effects
				(font
					(size 0.7874 0.5842)
					(thickness 0.1524)
				)
			)
		)
		(property "Value" ""
			(at 0 0 0)
			(layer "F.Fab")
			(effects
				(font
					(size 1.27 1.27)
				)
			)
		)
		(duplicate_pad_numbers_are_jumpers no)
		(fp_line
			(start -1.376172 -1.199896)
			(end -0.508 -1.199896)
			(stroke
				(width 0.1524)
				(type default)
			)
			(layer "F.SilkS")
		)
		(fp_line
			(start -1.376172 1.199896)
			(end -1.376172 -1.199896)
			(stroke
				(width 0.1524)
				(type default)
			)
			(layer "F.SilkS")
		)
		(fp_line
			(start -0.508 -1.199896)
			(end 0 -0.762)
			(stroke
				(width 0.1524)
				(type default)
			)
			(layer "F.SilkS")
		)
		(fp_line
			(start 0 -0.762)
			(end 0.508 -1.199896)
			(stroke
				(width 0.1524)
				(type default)
			)
			(layer "F.SilkS")
		)
		(fp_line
			(start 0.508 -1.199896)
			(end 1.376172 -1.199896)
			(stroke
				(width 0.1524)
				(type default)
			)
			(layer "F.SilkS")
		)
		(fp_line
			(start 1.376172 -1.199896)
			(end 1.376172 1.199896)
			(stroke
				(width 0.1524)
				(type default)
			)
			(layer "F.SilkS")
		)
		(fp_line
			(start 1.376172 1.199896)
			(end -1.376172 1.199896)
			(stroke
				(width 0.1524)
				(type default)
			)
			(layer "F.SilkS")
		)
		(fp_poly
			(pts
				(xy -1.64084 -1.123188) (xy -1.91008 -1.931416) (xy -2.449068 -1.392428)
			)
			(stroke
				(width 0)
				(type default)
			)
			(fill yes)
			(layer "F.SilkS")
		)
		(fp_line
			(start -0.674878 -1.100074)
			(end 0.674878 -1.100074)
			(stroke
				(width 0.1)
				(type default)
			)
			(layer "F.Fab")
		)
		(fp_line
			(start -0.674878 1.100074)
			(end -0.674878 -1.100074)
			(stroke
				(width 0.1)
				(type default)
			)
			(layer "F.Fab")
		)
		(fp_line
			(start 0.674878 -1.100074)
			(end 0.674878 1.100074)
			(stroke
				(width 0.1)
				(type default)
			)
			(layer "F.Fab")
		)
		(fp_line
			(start 0.674878 1.100074)
			(end -0.674878 1.100074)
			(stroke
				(width 0.1)
				(type default)
			)
			(layer "F.Fab")
		)
		(fp_poly
			(pts
				(xy -1.4605 -0.7493) (xy -2.2225 -1.1303) (xy -2.2225 -0.3683)
			)
			(stroke
				(width 0)
				(type default)
			)
			(fill yes)
			(layer "F.Fab")
		)
		(pad "1" smd rect
			(at -0.899922 -0.750062 270)
			(size 0.6096 0.6096)
			(layers "F.Cu" "F.Mask" "F.Paste")
			(net "GND")
		)
		(pad "2" smd rect
			(at -0.899922 0 270)
			(size 0.4064 0.6096)
			(layers "F.Cu" "F.Mask" "F.Paste")
			(net "P3V3_SSD3_PG_G1")
		)
		(pad "3" smd rect
			(at -0.899922 0.750062 270)
			(size 0.6096 0.6096)
			(layers "F.Cu" "F.Mask" "F.Paste")
			(net "PWRGD_P3V3_SSD3_D")
		)
		(pad "4" smd rect
			(at 0.899922 0.750062 270)
			(size 0.6096 0.6096)
			(layers "F.Cu" "F.Mask" "F.Paste")
			(net "GND")
		)
		(pad "5" smd rect
			(at 0.899922 0 270)
			(size 0.4064 0.6096)
			(layers "F.Cu" "F.Mask" "F.Paste")
			(net "P3V3_SSD3_PG_G2")
		)
		(pad "6" smd rect
			(at 0.899922 -0.750062 270)
			(size 0.6096 0.6096)
			(layers "F.Cu" "F.Mask" "F.Paste")
			(net "P3V3_SSD3_PG_G2")
		)
	)
	(footprint ""
		(layer "F.Cu")
		(at 217.235786 -215.254586 180)
		(property "Reference" "R1505"
			(at 0 0 180)
			(layer "F.SilkS")
			(hide yes)
			(effects
				(font
					(size 1.27 1.27)
				)
			)
		)
		(property "Value" ""
			(at 0 0 180)
			(layer "F.Fab")
			(effects
				(font
					(size 1.27 1.27)
				)
			)
		)
		(duplicate_pad_numbers_are_jumpers no)
		(fp_line
			(start 0.7874 0.4064)
			(end -0.7874 0.4064)
			(stroke
				(width 0.1524)
				(type default)
			)
			(layer "F.SilkS")
		)
		(fp_line
			(start 0.7874 -0.4064)
			(end 0.7874 0.4064)
			(stroke
				(width 0.1524)
				(type default)
			)
			(layer "F.SilkS")
		)
		(fp_line
			(start -0.7874 0.4064)
			(end -0.7874 -0.4064)
			(stroke
				(width 0.1524)
				(type default)
			)
			(layer "F.SilkS")
		)
		(fp_line
			(start -0.7874 -0.4064)
			(end 0.7874 -0.4064)
			(stroke
				(width 0.1524)
				(type default)
			)
			(layer "F.SilkS")
		)
		(fp_line
			(start 0.67945 0.3048)
			(end 0.120396 0.3048)
			(stroke
				(width 0.1)
				(type default)
			)
			(layer "F.Fab")
		)
		(fp_line
			(start 0.67945 -0.3048)
			(end 0.67945 0.3048)
			(stroke
				(width 0.1)
				(type default)
			)
			(layer "F.Fab")
		)
		(fp_line
			(start 0.12065 -0.2794)
			(end 0.12065 -0.3048)
			(stroke
				(width 0.1)
				(type default)
			)
			(layer "F.Fab")
		)
		(fp_line
			(start 0.12065 -0.3048)
			(end 0.67945 -0.3048)
			(stroke
				(width 0.1)
				(type default)
			)
			(layer "F.Fab")
		)
		(fp_line
			(start 0.120396 0.3048)
			(end 0.120396 0.2794)
			(stroke
				(width 0.1)
				(type default)
			)
			(layer "F.Fab")
		)
		(fp_line
			(start 0.120396 0.2794)
			(end -0.12065 0.2794)
			(stroke
				(width 0.1)
				(type default)
			)
			(layer "F.Fab")
		)
		(fp_line
			(start -0.12065 0.3048)
			(end -0.67945 0.3048)
			(stroke
				(width 0.1)
				(type default)
			)
			(layer "F.Fab")
		)
		(fp_line
			(start -0.12065 0.2794)
			(end -0.12065 0.3048)
			(stroke
				(width 0.1)
				(type default)
			)
			(layer "F.Fab")
		)
		(fp_line
			(start -0.12065 -0.2794)
			(end 0.12065 -0.2794)
			(stroke
				(width 0.1)
				(type default)
			)
			(layer "F.Fab")
		)
		(fp_line
			(start -0.12065 -0.305054)
			(end -0.12065 -0.2794)
			(stroke
				(width 0.1)
				(type default)
			)
			(layer "F.Fab")
		)
		(fp_line
			(start -0.67945 0.3048)
			(end -0.67945 -0.305054)
			(stroke
				(width 0.1)
				(type default)
			)
			(layer "F.Fab")
		)
		(fp_line
			(start -0.67945 -0.305054)
			(end -0.12065 -0.305054)
			(stroke
				(width 0.1)
				(type default)
			)
			(layer "F.Fab")
		)
		(pad "1" smd circle
			(at -0.40005 0 180)
			(size 0 0)
			(layers "F.Cu" "F.Mask" "F.Paste")
			(net "SMB_NIC7_SDA")
		)
		(pad "2" smd circle
			(at 0.40005 0 180)
			(size 0 0)
			(layers "F.Cu" "F.Mask" "F.Paste")
			(net "SMB_NIC7_R_SDA")
		)
	)
	(footprint ""
		(layer "F.Cu")
		(at 435.055772 -356.244906 90)
		(property "Reference" "C801"
			(at 0 0 90)
			(layer "F.SilkS")
			(hide yes)
			(effects
				(font
					(size 1.27 1.27)
				)
			)
		)
		(property "Value" ""
			(at 0 0 90)
			(layer "F.Fab")
			(effects
				(font
					(size 1.27 1.27)
				)
			)
		)
		(duplicate_pad_numbers_are_jumpers no)
		(fp_line
			(start 0.299974 -0.150114)
			(end 0.299974 0.150114)
			(stroke
				(width 0.1)
				(type default)
			)
			(layer "F.Fab")
		)
		(fp_line
			(start -0.299974 -0.150114)
			(end 0.299974 -0.150114)
			(stroke
				(width 0.1)
				(type default)
			)
			(layer "F.Fab")
		)
		(fp_line
			(start 0.299974 0.150114)
			(end -0.299974 0.150114)
			(stroke
				(width 0.1)
				(type default)
			)
			(layer "F.Fab")
		)
		(fp_line
			(start -0.299974 0.150114)
			(end -0.299974 -0.150114)
			(stroke
				(width 0.1)
				(type default)
			)
			(layer "F.Fab")
		)
		(pad "1" smd rect
			(at -0.2667 0 90)
			(size 0.3048 0.381)
			(layers "F.Cu" "F.Mask" "F.Paste")
			(net "P5E_PEX3_STN7_TX_DN<124>")
		)
		(pad "2" smd rect
			(at 0.2667 0 90)
			(size 0.3048 0.381)
			(layers "F.Cu" "F.Mask" "F.Paste")
			(net "P5E_PEX3_STN7_TX_C_DN<124>")
		)
	)
	(footprint ""
		(layer "F.Cu")
		(at 186.5376 -408.0764 180)
		(property "Reference" "R4416"
			(at 0 0 180)
			(layer "F.SilkS")
			(hide yes)
			(effects
				(font
					(size 1.27 1.27)
				)
			)
		)
		(property "Value" ""
			(at 0 0 180)
			(layer "F.Fab")
			(effects
				(font
					(size 1.27 1.27)
				)
			)
		)
		(duplicate_pad_numbers_are_jumpers no)
		(fp_line
			(start 0.7874 0.4064)
			(end -0.7874 0.4064)
			(stroke
				(width 0.1524)
				(type default)
			)
			(layer "F.SilkS")
		)
		(fp_line
			(start 0.7874 -0.4064)
			(end 0.7874 0.4064)
			(stroke
				(width 0.1524)
				(type default)
			)
			(layer "F.SilkS")
		)
		(fp_line
			(start -0.7874 0.4064)
			(end -0.7874 -0.4064)
			(stroke
				(width 0.1524)
				(type default)
			)
			(layer "F.SilkS")
		)
		(fp_line
			(start -0.7874 -0.4064)
			(end 0.7874 -0.4064)
			(stroke
				(width 0.1524)
				(type default)
			)
			(layer "F.SilkS")
		)
		(fp_line
			(start 0.67945 0.3048)
			(end 0.120396 0.3048)
			(stroke
				(width 0.1)
				(type default)
			)
			(layer "F.Fab")
		)
		(fp_line
			(start 0.67945 -0.3048)
			(end 0.67945 0.3048)
			(stroke
				(width 0.1)
				(type default)
			)
			(layer "F.Fab")
		)
		(fp_line
			(start 0.12065 -0.2794)
			(end 0.12065 -0.3048)
			(stroke
				(width 0.1)
				(type default)
			)
			(layer "F.Fab")
		)
		(fp_line
			(start 0.12065 -0.3048)
			(end 0.67945 -0.3048)
			(stroke
				(width 0.1)
				(type default)
			)
			(layer "F.Fab")
		)
		(fp_line
			(start 0.120396 0.3048)
			(end 0.120396 0.2794)
			(stroke
				(width 0.1)
				(type default)
			)
			(layer "F.Fab")
		)
		(fp_line
			(start 0.120396 0.2794)
			(end -0.12065 0.2794)
			(stroke
				(width 0.1)
				(type default)
			)
			(layer "F.Fab")
		)
		(fp_line
			(start -0.12065 0.3048)
			(end -0.67945 0.3048)
			(stroke
				(width 0.1)
				(type default)
			)
			(layer "F.Fab")
		)
		(fp_line
			(start -0.12065 0.2794)
			(end -0.12065 0.3048)
			(stroke
				(width 0.1)
				(type default)
			)
			(layer "F.Fab")
		)
		(fp_line
			(start -0.12065 -0.2794)
			(end 0.12065 -0.2794)
			(stroke
				(width 0.1)
				(type default)
			)
			(layer "F.Fab")
		)
		(fp_line
			(start -0.12065 -0.305054)
			(end -0.12065 -0.2794)
			(stroke
				(width 0.1)
				(type default)
			)
			(layer "F.Fab")
		)
		(fp_line
			(start -0.67945 0.3048)
			(end -0.67945 -0.305054)
			(stroke
				(width 0.1)
				(type default)
			)
			(layer "F.Fab")
		)
		(fp_line
			(start -0.67945 -0.305054)
			(end -0.12065 -0.305054)
			(stroke
				(width 0.1)
				(type default)
			)
			(layer "F.Fab")
		)
		(pad "1" smd circle
			(at -0.40005 0 180)
			(size 0 0)
			(layers "F.Cu" "F.Mask" "F.Paste")
			(net "A_P12V_AUX_FPH_GATE")
		)
		(pad "2" smd circle
			(at 0.40005 0 180)
			(size 0 0)
			(layers "F.Cu" "F.Mask" "F.Paste")
			(net "P3V3_AUX")
		)
	)
	(footprint ""
		(layer "F.Cu")
		(at 399.14322 -356.244906 90)
		(property "Reference" "C748"
			(at 0 0 90)
			(layer "F.SilkS")
			(hide yes)
			(effects
				(font
					(size 1.27 1.27)
				)
			)
		)
		(property "Value" ""
			(at 0 0 90)
			(layer "F.Fab")
			(effects
				(font
					(size 1.27 1.27)
				)
			)
		)
		(duplicate_pad_numbers_are_jumpers no)
		(fp_line
			(start 0.299974 -0.150114)
			(end 0.299974 0.150114)
			(stroke
				(width 0.1)
				(type default)
			)
			(layer "F.Fab")
		)
		(fp_line
			(start -0.299974 -0.150114)
			(end 0.299974 -0.150114)
			(stroke
				(width 0.1)
				(type default)
			)
			(layer "F.Fab")
		)
		(fp_line
			(start 0.299974 0.150114)
			(end -0.299974 0.150114)
			(stroke
				(width 0.1)
				(type default)
			)
			(layer "F.Fab")
		)
		(fp_line
			(start -0.299974 0.150114)
			(end -0.299974 -0.150114)
			(stroke
				(width 0.1)
				(type default)
			)
			(layer "F.Fab")
		)
		(pad "1" smd rect
			(at -0.2667 0 90)
			(size 0.3048 0.381)
			(layers "F.Cu" "F.Mask" "F.Paste")
			(net "P5E_PEX3_STN5_TX_DP<86>")
		)
		(pad "2" smd rect
			(at 0.2667 0 90)
			(size 0.3048 0.381)
			(layers "F.Cu" "F.Mask" "F.Paste")
			(net "P5E_PEX3_STN5_TX_C_DP<86>")
		)
	)
	(footprint ""
		(layer "F.Cu")
		(at 127.274828 -251.759974 -90)
		(property "Reference" "PR73"
			(at 0 0 270)
			(layer "F.SilkS")
			(hide yes)
			(effects
				(font
					(size 1.27 1.27)
				)
			)
		)
		(property "Value" ""
			(at 0 0 270)
			(layer "F.Fab")
			(effects
				(font
					(size 1.27 1.27)
				)
			)
		)
		(duplicate_pad_numbers_are_jumpers no)
		(fp_line
			(start -0.7874 0.4064)
			(end -0.7874 -0.4064)
			(stroke
				(width 0.1524)
				(type default)
			)
			(layer "F.SilkS")
		)
		(fp_line
			(start 0.7874 0.4064)
			(end -0.7874 0.4064)
			(stroke
				(width 0.1524)
				(type default)
			)
			(layer "F.SilkS")
		)
		(fp_line
			(start -0.7874 -0.4064)
			(end 0.7874 -0.4064)
			(stroke
				(width 0.1524)
				(type default)
			)
			(layer "F.SilkS")
		)
		(fp_line
			(start 0.7874 -0.4064)
			(end 0.7874 0.4064)
			(stroke
				(width 0.1524)
				(type default)
			)
			(layer "F.SilkS")
		)
		(fp_line
			(start -0.67945 0.3048)
			(end -0.67945 -0.305054)
			(stroke
				(width 0.1)
				(type default)
			)
			(layer "F.Fab")
		)
		(fp_line
			(start -0.12065 0.3048)
			(end -0.67945 0.3048)
			(stroke
				(width 0.1)
				(type default)
			)
			(layer "F.Fab")
		)
		(fp_line
			(start 0.120396 0.3048)
			(end 0.120396 0.2794)
			(stroke
				(width 0.1)
				(type default)
			)
			(layer "F.Fab")
		)
		(fp_line
			(start 0.67945 0.3048)
			(end 0.120396 0.3048)
			(stroke
				(width 0.1)
				(type default)
			)
			(layer "F.Fab")
		)
		(fp_line
			(start -0.12065 0.2794)
			(end -0.12065 0.3048)
			(stroke
				(width 0.1)
				(type default)
			)
			(layer "F.Fab")
		)
		(fp_line
			(start 0.120396 0.2794)
			(end -0.12065 0.2794)
			(stroke
				(width 0.1)
				(type default)
			)
			(layer "F.Fab")
		)
		(fp_line
			(start -0.12065 -0.2794)
			(end 0.12065 -0.2794)
			(stroke
				(width 0.1)
				(type default)
			)
			(layer "F.Fab")
		)
		(fp_line
			(start 0.12065 -0.2794)
			(end 0.12065 -0.3048)
			(stroke
				(width 0.1)
				(type default)
			)
			(layer "F.Fab")
		)
		(fp_line
			(start 0.12065 -0.3048)
			(end 0.67945 -0.3048)
			(stroke
				(width 0.1)
				(type default)
			)
			(layer "F.Fab")
		)
		(fp_line
			(start 0.67945 -0.3048)
			(end 0.67945 0.3048)
			(stroke
				(width 0.1)
				(type default)
			)
			(layer "F.Fab")
		)
		(fp_line
			(start -0.67945 -0.305054)
			(end -0.12065 -0.305054)
			(stroke
				(width 0.1)
				(type default)
			)
			(layer "F.Fab")
		)
		(fp_line
			(start -0.12065 -0.305054)
			(end -0.12065 -0.2794)
			(stroke
				(width 0.1)
				(type default)
			)
			(layer "F.Fab")
		)
		(pad "1" smd circle
			(at -0.40005 0 270)
			(size 0 0)
			(layers "F.Cu" "F.Mask" "F.Paste")
			(net "SMB_PJP1_SDA")
		)
		(pad "2" smd circle
			(at 0.40005 0 270)
			(size 0 0)
			(layers "F.Cu" "F.Mask" "F.Paste")
			(net "SMB_BIC_I2C6_MUX_VR_R_SDA")
		)
	)
	(footprint ""
		(layer "F.Cu")
		(at 148.570442 -252.356874 -90)
		(property "Reference" "R1297"
			(at 0 0 270)
			(layer "F.SilkS")
			(hide yes)
			(effects
				(font
					(size 1.27 1.27)
				)
			)
		)
		(property "Value" ""
			(at 0 0 270)
			(layer "F.Fab")
			(effects
				(font
					(size 1.27 1.27)
				)
			)
		)
		(duplicate_pad_numbers_are_jumpers no)
		(fp_line
			(start -0.7874 0.4064)
			(end -0.7874 -0.4064)
			(stroke
				(width 0.1524)
				(type default)
			)
			(layer "F.SilkS")
		)
		(fp_line
			(start 0.7874 0.4064)
			(end -0.7874 0.4064)
			(stroke
				(width 0.1524)
				(type default)
			)
			(layer "F.SilkS")
		)
		(fp_line
			(start -0.7874 -0.4064)
			(end 0.7874 -0.4064)
			(stroke
				(width 0.1524)
				(type default)
			)
			(layer "F.SilkS")
		)
		(fp_line
			(start 0.7874 -0.4064)
			(end 0.7874 0.4064)
			(stroke
				(width 0.1524)
				(type default)
			)
			(layer "F.SilkS")
		)
		(fp_line
			(start -0.67945 0.3048)
			(end -0.67945 -0.305054)
			(stroke
				(width 0.1)
				(type default)
			)
			(layer "F.Fab")
		)
		(fp_line
			(start -0.12065 0.3048)
			(end -0.67945 0.3048)
			(stroke
				(width 0.1)
				(type default)
			)
			(layer "F.Fab")
		)
		(fp_line
			(start 0.120396 0.3048)
			(end 0.120396 0.2794)
			(stroke
				(width 0.1)
				(type default)
			)
			(layer "F.Fab")
		)
		(fp_line
			(start 0.67945 0.3048)
			(end 0.120396 0.3048)
			(stroke
				(width 0.1)
				(type default)
			)
			(layer "F.Fab")
		)
		(fp_line
			(start -0.12065 0.2794)
			(end -0.12065 0.3048)
			(stroke
				(width 0.1)
				(type default)
			)
			(layer "F.Fab")
		)
		(fp_line
			(start 0.120396 0.2794)
			(end -0.12065 0.2794)
			(stroke
				(width 0.1)
				(type default)
			)
			(layer "F.Fab")
		)
		(fp_line
			(start -0.12065 -0.2794)
			(end 0.12065 -0.2794)
			(stroke
				(width 0.1)
				(type default)
			)
			(layer "F.Fab")
		)
		(fp_line
			(start 0.12065 -0.2794)
			(end 0.12065 -0.3048)
			(stroke
				(width 0.1)
				(type default)
			)
			(layer "F.Fab")
		)
		(fp_line
			(start 0.12065 -0.3048)
			(end 0.67945 -0.3048)
			(stroke
				(width 0.1)
				(type default)
			)
			(layer "F.Fab")
		)
		(fp_line
			(start 0.67945 -0.3048)
			(end 0.67945 0.3048)
			(stroke
				(width 0.1)
				(type default)
			)
			(layer "F.Fab")
		)
		(fp_line
			(start -0.67945 -0.305054)
			(end -0.12065 -0.305054)
			(stroke
				(width 0.1)
				(type default)
			)
			(layer "F.Fab")
		)
		(fp_line
			(start -0.12065 -0.305054)
			(end -0.12065 -0.2794)
			(stroke
				(width 0.1)
				(type default)
			)
			(layer "F.Fab")
		)
		(pad "1" smd circle
			(at -0.40005 0 270)
			(size 0 0)
			(layers "F.Cu" "F.Mask" "F.Paste")
			(net "GND")
		)
		(pad "2" smd circle
			(at 0.40005 0 270)
			(size 0 0)
			(layers "F.Cu" "F.Mask" "F.Paste")
			(net "PEX1_MODE_SEL8")
		)
	)
	(footprint ""
		(layer "F.Cu")
		(at 193.207386 -81.09966)
		(property "Reference" "Q4"
			(at -1.996186 -1.70307 0)
			(unlocked yes)
			(layer "F.SilkS")
			(effects
				(font
					(size 0.7874 0.5842)
					(thickness 0.1524)
				)
				(justify left)
			)
		)
		(property "Value" ""
			(at 0 0 0)
			(layer "F.Fab")
			(effects
				(font
					(size 1.27 1.27)
				)
			)
		)
		(duplicate_pad_numbers_are_jumpers no)
		(fp_line
			(start -1.38176 -1.100074)
			(end -1.38176 1.100074)
			(stroke
				(width 0.1524)
				(type default)
			)
			(layer "F.SilkS")
		)
		(fp_line
			(start -1.38176 1.100074)
			(end 1.38176 1.100074)
			(stroke
				(width 0.1524)
				(type default)
			)
			(layer "F.SilkS")
		)
		(fp_line
			(start -0.592074 -1.100074)
			(end -1.38176 -1.100074)
			(stroke
				(width 0.1524)
				(type default)
			)
			(layer "F.SilkS")
		)
		(fp_line
			(start 0 -0.508)
			(end -0.592074 -1.100074)
			(stroke
				(width 0.1524)
				(type default)
			)
			(layer "F.SilkS")
		)
		(fp_line
			(start 0.592074 -1.100074)
			(end 0 -0.508)
			(stroke
				(width 0.1524)
				(type default)
			)
			(layer "F.SilkS")
		)
		(fp_line
			(start 1.38176 -1.100074)
			(end 0.592074 -1.100074)
			(stroke
				(width 0.1524)
				(type default)
			)
			(layer "F.SilkS")
		)
		(fp_line
			(start 1.38176 1.100074)
			(end 1.38176 -1.100074)
			(stroke
				(width 0.1524)
				(type default)
			)
			(layer "F.SilkS")
		)
		(fp_poly
			(pts
				(xy -1.9431 -0.870204) (xy -1.50241 -0.649986) (xy -1.9431 -0.429768)
			)
			(stroke
				(width 0)
				(type default)
			)
			(fill yes)
			(layer "F.SilkS")
		)
		(fp_line
			(start -0.674878 -1.100074)
			(end -0.674878 1.100074)
			(stroke
				(width 0.1)
				(type default)
			)
			(layer "F.Fab")
		)
		(fp_line
			(start -0.674878 1.100074)
			(end 0.674878 1.100074)
			(stroke
				(width 0.1)
				(type default)
			)
			(layer "F.Fab")
		)
		(fp_line
			(start 0.674878 -1.100074)
			(end -0.674878 -1.100074)
			(stroke
				(width 0.1)
				(type default)
			)
			(layer "F.Fab")
		)
		(fp_line
			(start 0.674878 1.100074)
			(end 0.674878 -1.100074)
			(stroke
				(width 0.1)
				(type default)
			)
			(layer "F.Fab")
		)
		(fp_poly
			(pts
				(xy -1.9431 -0.870204) (xy -1.50241 -0.649986) (xy -1.9431 -0.429768)
			)
			(stroke
				(width 0)
				(type default)
			)
			(fill yes)
			(layer "F.Fab")
		)
		(pad "1" smd rect
			(at -0.94996 -0.649986 270)
			(size 0.4318 0.6096)
			(layers "F.Cu" "F.Mask" "F.Paste")
			(net "GND")
		)
		(pad "2" smd rect
			(at -0.94996 0 270)
			(size 0.4318 0.6096)
			(layers "F.Cu" "F.Mask" "F.Paste")
			(net "HP_NIC3_HSC_PWRGD_N")
		)
		(pad "3" smd rect
			(at -0.94996 0.649986 270)
			(size 0.4318 0.6096)
			(layers "F.Cu" "F.Mask" "F.Paste")
			(net "HP_NIC3_HSC_PWRGD_N")
		)
		(pad "4" smd rect
			(at 0.94996 0.649986 270)
			(size 0.4318 0.6096)
			(layers "F.Cu" "F.Mask" "F.Paste")
			(net "GND")
		)
		(pad "5" smd rect
			(at 0.94996 0 270)
			(size 0.4318 0.6096)
			(layers "F.Cu" "F.Mask" "F.Paste")
			(net "PWRGD_P12V_NIC3_R")
		)
		(pad "6" smd rect
			(at 0.94996 -0.649986 270)
			(size 0.4318 0.6096)
			(layers "F.Cu" "F.Mask" "F.Paste")
			(net "HP_NIC3_PWRGD_R")
		)
	)
	(footprint ""
		(layer "F.Cu")
		(at 230.377746 -118.984268 -90)
		(property "Reference" "PC631"
			(at 0 0 270)
			(layer "F.SilkS")
			(hide yes)
			(effects
				(font
					(size 1.27 1.27)
				)
			)
		)
		(property "Value" ""
			(at 0 0 270)
			(layer "F.Fab")
			(effects
				(font
					(size 1.27 1.27)
				)
			)
		)
		(duplicate_pad_numbers_are_jumpers no)
		(fp_line
			(start -1.2954 0.5842)
			(end -1.2954 -0.5842)
			(stroke
				(width 0.1524)
				(type default)
			)
			(layer "F.SilkS")
		)
		(fp_line
			(start 1.2954 0.5842)
			(end -1.2954 0.5842)
			(stroke
				(width 0.1524)
				(type default)
			)
			(layer "F.SilkS")
		)
		(fp_line
			(start -1.2954 -0.5842)
			(end 1.2954 -0.5842)
			(stroke
				(width 0.1524)
				(type default)
			)
			(layer "F.SilkS")
		)
		(fp_line
			(start 1.2954 -0.5842)
			(end 1.2954 0.5842)
			(stroke
				(width 0.1524)
				(type default)
			)
			(layer "F.SilkS")
		)
		(fp_line
			(start -0.8636 0.4572)
			(end -0.8636 0.4064)
			(stroke
				(width 0.1)
				(type default)
			)
			(layer "F.Fab")
		)
		(fp_line
			(start 0.8636 0.4572)
			(end -0.8636 0.4572)
			(stroke
				(width 0.1)
				(type default)
			)
			(layer "F.Fab")
		)
		(fp_line
			(start -1.1938 0.4064)
			(end -1.1938 -0.4064)
			(stroke
				(width 0.1)
				(type default)
			)
			(layer "F.Fab")
		)
		(fp_line
			(start -0.8636 0.4064)
			(end -1.1938 0.4064)
			(stroke
				(width 0.1)
				(type default)
			)
			(layer "F.Fab")
		)
		(fp_line
			(start 0.8636 0.4064)
			(end 0.8636 0.4572)
			(stroke
				(width 0.1)
				(type default)
			)
			(layer "F.Fab")
		)
		(fp_line
			(start 1.1938 0.4064)
			(end 0.8636 0.4064)
			(stroke
				(width 0.1)
				(type default)
			)
			(layer "F.Fab")
		)
		(fp_line
			(start -1.1938 -0.4064)
			(end -0.8636 -0.4064)
			(stroke
				(width 0.1)
				(type default)
			)
			(layer "F.Fab")
		)
		(fp_line
			(start -0.8636 -0.4064)
			(end -0.8636 -0.4572)
			(stroke
				(width 0.1)
				(type default)
			)
			(layer "F.Fab")
		)
		(fp_line
			(start 0.8636 -0.4064)
			(end 1.1938 -0.4064)
			(stroke
				(width 0.1)
				(type default)
			)
			(layer "F.Fab")
		)
		(fp_line
			(start 1.1938 -0.4064)
			(end 1.1938 0.4064)
			(stroke
				(width 0.1)
				(type default)
			)
			(layer "F.Fab")
		)
		(fp_line
			(start -0.8636 -0.4572)
			(end 0.8636 -0.4572)
			(stroke
				(width 0.1)
				(type default)
			)
			(layer "F.Fab")
		)
		(fp_line
			(start 0.8636 -0.4572)
			(end 0.8636 -0.4064)
			(stroke
				(width 0.1)
				(type default)
			)
			(layer "F.Fab")
		)
		(pad "1" smd rect
			(at -0.7366 0 180)
			(size 0.7112 0.8128)
			(layers "F.Cu" "F.Mask" "F.Paste")
			(net "GND")
		)
		(pad "2" smd rect
			(at 0.7366 0 180)
			(size 0.7112 0.8128)
			(layers "F.Cu" "F.Mask" "F.Paste")
			(net "P12V_NIC3_CO_AVIN_PD")
		)
	)
	(footprint ""
		(layer "F.Cu")
		(at 122.88139 -262.04672 180)
		(property "Reference" "PC49"
			(at 0 0 180)
			(layer "F.SilkS")
			(hide yes)
			(effects
				(font
					(size 1.27 1.27)
				)
			)
		)
		(property "Value" ""
			(at 0 0 180)
			(layer "F.Fab")
			(effects
				(font
					(size 1.27 1.27)
				)
			)
		)
		(duplicate_pad_numbers_are_jumpers no)
		(fp_line
			(start 0.7874 0.4064)
			(end -0.7874 0.4064)
			(stroke
				(width 0.1524)
				(type default)
			)
			(layer "F.SilkS")
		)
		(fp_line
			(start 0.7874 -0.4064)
			(end 0.7874 0.4064)
			(stroke
				(width 0.1524)
				(type default)
			)
			(layer "F.SilkS")
		)
		(fp_line
			(start -0.7874 0.4064)
			(end -0.7874 -0.4064)
			(stroke
				(width 0.1524)
				(type default)
			)
			(layer "F.SilkS")
		)
		(fp_line
			(start -0.7874 -0.4064)
			(end 0.7874 -0.4064)
			(stroke
				(width 0.1524)
				(type default)
			)
			(layer "F.SilkS")
		)
		(fp_line
			(start 0.67945 0.3048)
			(end 0.120396 0.3048)
			(stroke
				(width 0.1)
				(type default)
			)
			(layer "F.Fab")
		)
		(fp_line
			(start 0.67945 -0.3048)
			(end 0.67945 0.3048)
			(stroke
				(width 0.1)
				(type default)
			)
			(layer "F.Fab")
		)
		(fp_line
			(start 0.12065 -0.2794)
			(end 0.12065 -0.3048)
			(stroke
				(width 0.1)
				(type default)
			)
			(layer "F.Fab")
		)
		(fp_line
			(start 0.12065 -0.3048)
			(end 0.67945 -0.3048)
			(stroke
				(width 0.1)
				(type default)
			)
			(layer "F.Fab")
		)
		(fp_line
			(start 0.120396 0.3048)
			(end 0.120396 0.2794)
			(stroke
				(width 0.1)
				(type default)
			)
			(layer "F.Fab")
		)
		(fp_line
			(start 0.120396 0.2794)
			(end -0.12065 0.2794)
			(stroke
				(width 0.1)
				(type default)
			)
			(layer "F.Fab")
		)
		(fp_line
			(start -0.12065 0.3048)
			(end -0.67945 0.3048)
			(stroke
				(width 0.1)
				(type default)
			)
			(layer "F.Fab")
		)
		(fp_line
			(start -0.12065 0.2794)
			(end -0.12065 0.3048)
			(stroke
				(width 0.1)
				(type default)
			)
			(layer "F.Fab")
		)
		(fp_line
			(start -0.12065 -0.2794)
			(end 0.12065 -0.2794)
			(stroke
				(width 0.1)
				(type default)
			)
			(layer "F.Fab")
		)
		(fp_line
			(start -0.12065 -0.305054)
			(end -0.12065 -0.2794)
			(stroke
				(width 0.1)
				(type default)
			)
			(layer "F.Fab")
		)
		(fp_line
			(start -0.67945 0.3048)
			(end -0.67945 -0.305054)
			(stroke
				(width 0.1)
				(type default)
			)
			(layer "F.Fab")
		)
		(fp_line
			(start -0.67945 -0.305054)
			(end -0.12065 -0.305054)
			(stroke
				(width 0.1)
				(type default)
			)
			(layer "F.Fab")
		)
		(pad "1" smd circle
			(at -0.40005 0 180)
			(size 0 0)
			(layers "F.Cu" "F.Mask" "F.Paste")
			(net "P0V8_PEX0_VSEN0")
		)
		(pad "2" smd circle
			(at 0.40005 0 180)
			(size 0 0)
			(layers "F.Cu" "F.Mask" "F.Paste")
			(net "SH_P0V8_PEX0_RGND0")
		)
	)
	(footprint ""
		(layer "F.Cu")
		(at 231.844596 -274.487386)
		(property "Reference" "R784"
			(at 0 0 0)
			(layer "F.SilkS")
			(hide yes)
			(effects
				(font
					(size 1.27 1.27)
				)
			)
		)
		(property "Value" ""
			(at 0 0 0)
			(layer "F.Fab")
			(effects
				(font
					(size 1.27 1.27)
				)
			)
		)
		(duplicate_pad_numbers_are_jumpers no)
		(fp_line
			(start -0.7874 -0.4064)
			(end 0.7874 -0.4064)
			(stroke
				(width 0.1524)
				(type default)
			)
			(layer "F.SilkS")
		)
		(fp_line
			(start -0.7874 0.4064)
			(end -0.7874 -0.4064)
			(stroke
				(width 0.1524)
				(type default)
			)
			(layer "F.SilkS")
		)
		(fp_line
			(start 0.7874 -0.4064)
			(end 0.7874 0.4064)
			(stroke
				(width 0.1524)
				(type default)
			)
			(layer "F.SilkS")
		)
		(fp_line
			(start 0.7874 0.4064)
			(end -0.7874 0.4064)
			(stroke
				(width 0.1524)
				(type default)
			)
			(layer "F.SilkS")
		)
		(fp_line
			(start -0.67945 -0.305054)
			(end -0.12065 -0.305054)
			(stroke
				(width 0.1)
				(type default)
			)
			(layer "F.Fab")
		)
		(fp_line
			(start -0.67945 0.3048)
			(end -0.67945 -0.305054)
			(stroke
				(width 0.1)
				(type default)
			)
			(layer "F.Fab")
		)
		(fp_line
			(start -0.12065 -0.305054)
			(end -0.12065 -0.2794)
			(stroke
				(width 0.1)
				(type default)
			)
			(layer "F.Fab")
		)
		(fp_line
			(start -0.12065 -0.2794)
			(end 0.12065 -0.2794)
			(stroke
				(width 0.1)
				(type default)
			)
			(layer "F.Fab")
		)
		(fp_line
			(start -0.12065 0.2794)
			(end -0.12065 0.3048)
			(stroke
				(width 0.1)
				(type default)
			)
			(layer "F.Fab")
		)
		(fp_line
			(start -0.12065 0.3048)
			(end -0.67945 0.3048)
			(stroke
				(width 0.1)
				(type default)
			)
			(layer "F.Fab")
		)
		(fp_line
			(start 0.120396 0.2794)
			(end -0.12065 0.2794)
			(stroke
				(width 0.1)
				(type default)
			)
			(layer "F.Fab")
		)
		(fp_line
			(start 0.120396 0.3048)
			(end 0.120396 0.2794)
			(stroke
				(width 0.1)
				(type default)
			)
			(layer "F.Fab")
		)
		(fp_line
			(start 0.12065 -0.3048)
			(end 0.67945 -0.3048)
			(stroke
				(width 0.1)
				(type default)
			)
			(layer "F.Fab")
		)
		(fp_line
			(start 0.12065 -0.2794)
			(end 0.12065 -0.3048)
			(stroke
				(width 0.1)
				(type default)
			)
			(layer "F.Fab")
		)
		(fp_line
			(start 0.67945 -0.3048)
			(end 0.67945 0.3048)
			(stroke
				(width 0.1)
				(type default)
			)
			(layer "F.Fab")
		)
		(fp_line
			(start 0.67945 0.3048)
			(end 0.120396 0.3048)
			(stroke
				(width 0.1)
				(type default)
			)
			(layer "F.Fab")
		)
		(pad "1" smd circle
			(at -0.40005 0)
			(size 0 0)
			(layers "F.Cu" "F.Mask" "F.Paste")
			(net "PEX1_P1V25_ADC_A1")
		)
		(pad "2" smd circle
			(at 0.40005 0)
			(size 0 0)
			(layers "F.Cu" "F.Mask" "F.Paste")
			(net "GND")
		)
	)
	(footprint ""
		(layer "F.Cu")
		(at 146.18208 -289.790632 180)
		(property "Reference" "C3223"
			(at 0 0 180)
			(layer "F.SilkS")
			(hide yes)
			(effects
				(font
					(size 1.27 1.27)
				)
			)
		)
		(property "Value" ""
			(at 0 0 180)
			(layer "F.Fab")
			(effects
				(font
					(size 1.27 1.27)
				)
			)
		)
		(duplicate_pad_numbers_are_jumpers no)
		(fp_line
			(start 1.2954 0.5842)
			(end -1.2954 0.5842)
			(stroke
				(width 0.1524)
				(type default)
			)
			(layer "F.SilkS")
		)
		(fp_line
			(start 1.2954 -0.5842)
			(end 1.2954 0.5842)
			(stroke
				(width 0.1524)
				(type default)
			)
			(layer "F.SilkS")
		)
		(fp_line
			(start -1.2954 0.5842)
			(end -1.2954 -0.5842)
			(stroke
				(width 0.1524)
				(type default)
			)
			(layer "F.SilkS")
		)
		(fp_line
			(start -1.2954 -0.5842)
			(end 1.2954 -0.5842)
			(stroke
				(width 0.1524)
				(type default)
			)
			(layer "F.SilkS")
		)
		(fp_line
			(start 1.1938 0.4064)
			(end 0.8636 0.4064)
			(stroke
				(width 0.1)
				(type default)
			)
			(layer "F.Fab")
		)
		(fp_line
			(start 1.1938 -0.4064)
			(end 1.1938 0.4064)
			(stroke
				(width 0.1)
				(type default)
			)
			(layer "F.Fab")
		)
		(fp_line
			(start 0.8636 0.4572)
			(end -0.8636 0.4572)
			(stroke
				(width 0.1)
				(type default)
			)
			(layer "F.Fab")
		)
		(fp_line
			(start 0.8636 0.4064)
			(end 0.8636 0.4572)
			(stroke
				(width 0.1)
				(type default)
			)
			(layer "F.Fab")
		)
		(fp_line
			(start 0.8636 -0.4064)
			(end 1.1938 -0.4064)
			(stroke
				(width 0.1)
				(type default)
			)
			(layer "F.Fab")
		)
		(fp_line
			(start 0.8636 -0.4572)
			(end 0.8636 -0.4064)
			(stroke
				(width 0.1)
				(type default)
			)
			(layer "F.Fab")
		)
		(fp_line
			(start -0.8636 0.4572)
			(end -0.8636 0.4064)
			(stroke
				(width 0.1)
				(type default)
			)
			(layer "F.Fab")
		)
		(fp_line
			(start -0.8636 0.4064)
			(end -1.1938 0.4064)
			(stroke
				(width 0.1)
				(type default)
			)
			(layer "F.Fab")
		)
		(fp_line
			(start -0.8636 -0.4064)
			(end -0.8636 -0.4572)
			(stroke
				(width 0.1)
				(type default)
			)
			(layer "F.Fab")
		)
		(fp_line
			(start -0.8636 -0.4572)
			(end 0.8636 -0.4572)
			(stroke
				(width 0.1)
				(type default)
			)
			(layer "F.Fab")
		)
		(fp_line
			(start -1.1938 0.4064)
			(end -1.1938 -0.4064)
			(stroke
				(width 0.1)
				(type default)
			)
			(layer "F.Fab")
		)
		(fp_line
			(start -1.1938 -0.4064)
			(end -0.8636 -0.4064)
			(stroke
				(width 0.1)
				(type default)
			)
			(layer "F.Fab")
		)
		(pad "1" smd rect
			(at -0.7366 0 90)
			(size 0.7112 0.8128)
			(layers "F.Cu" "F.Mask" "F.Paste")
			(net "PCEPLL4_VDDA18_PEX1_R")
		)
		(pad "2" smd rect
			(at 0.7366 0 90)
			(size 0.7112 0.8128)
			(layers "F.Cu" "F.Mask" "F.Paste")
			(net "GND")
		)
	)
	(footprint ""
		(layer "F.Cu")
		(at 267.519658 -206.897986 90)
		(property "Reference" "C3991"
			(at 0 0 90)
			(layer "F.SilkS")
			(hide yes)
			(effects
				(font
					(size 1.27 1.27)
				)
			)
		)
		(property "Value" ""
			(at 0 0 90)
			(layer "F.Fab")
			(effects
				(font
					(size 1.27 1.27)
				)
			)
		)
		(duplicate_pad_numbers_are_jumpers no)
		(fp_line
			(start 1.2954 -0.5842)
			(end 1.2954 0.5842)
			(stroke
				(width 0.1524)
				(type default)
			)
			(layer "F.SilkS")
		)
		(fp_line
			(start -1.2954 -0.5842)
			(end 1.2954 -0.5842)
			(stroke
				(width 0.1524)
				(type default)
			)
			(layer "F.SilkS")
		)
		(fp_line
			(start 1.2954 0.5842)
			(end -1.2954 0.5842)
			(stroke
				(width 0.1524)
				(type default)
			)
			(layer "F.SilkS")
		)
		(fp_line
			(start -1.2954 0.5842)
			(end -1.2954 -0.5842)
			(stroke
				(width 0.1524)
				(type default)
			)
			(layer "F.SilkS")
		)
		(fp_line
			(start 0.8636 -0.4572)
			(end 0.8636 -0.4064)
			(stroke
				(width 0.1)
				(type default)
			)
			(layer "F.Fab")
		)
		(fp_line
			(start -0.8636 -0.4572)
			(end 0.8636 -0.4572)
			(stroke
				(width 0.1)
				(type default)
			)
			(layer "F.Fab")
		)
		(fp_line
			(start 1.1938 -0.4064)
			(end 1.1938 0.4064)
			(stroke
				(width 0.1)
				(type default)
			)
			(layer "F.Fab")
		)
		(fp_line
			(start 0.8636 -0.4064)
			(end 1.1938 -0.4064)
			(stroke
				(width 0.1)
				(type default)
			)
			(layer "F.Fab")
		)
		(fp_line
			(start -0.8636 -0.4064)
			(end -0.8636 -0.4572)
			(stroke
				(width 0.1)
				(type default)
			)
			(layer "F.Fab")
		)
		(fp_line
			(start -1.1938 -0.4064)
			(end -0.8636 -0.4064)
			(stroke
				(width 0.1)
				(type default)
			)
			(layer "F.Fab")
		)
		(fp_line
			(start 1.1938 0.4064)
			(end 0.8636 0.4064)
			(stroke
				(width 0.1)
				(type default)
			)
			(layer "F.Fab")
		)
		(fp_line
			(start 0.8636 0.4064)
			(end 0.8636 0.4572)
			(stroke
				(width 0.1)
				(type default)
			)
			(layer "F.Fab")
		)
		(fp_line
			(start -0.8636 0.4064)
			(end -1.1938 0.4064)
			(stroke
				(width 0.1)
				(type default)
			)
			(layer "F.Fab")
		)
		(fp_line
			(start -1.1938 0.4064)
			(end -1.1938 -0.4064)
			(stroke
				(width 0.1)
				(type default)
			)
			(layer "F.Fab")
		)
		(fp_line
			(start 0.8636 0.4572)
			(end -0.8636 0.4572)
			(stroke
				(width 0.1)
				(type default)
			)
			(layer "F.Fab")
		)
		(fp_line
			(start -0.8636 0.4572)
			(end -0.8636 0.4064)
			(stroke
				(width 0.1)
				(type default)
			)
			(layer "F.Fab")
		)
		(pad "1" smd rect
			(at -0.7366 0)
			(size 0.7112 0.8128)
			(layers "F.Cu" "F.Mask" "F.Paste")
			(net "GND")
		)
		(pad "2" smd rect
			(at 0.7366 0)
			(size 0.7112 0.8128)
			(layers "F.Cu" "F.Mask" "F.Paste")
			(net "P3V3_AUX_JTAG")
		)
	)
	(footprint ""
		(layer "F.Cu")
		(at 288.915094 -59.546236 90)
		(property "Reference" "C2897"
			(at 0 0 90)
			(layer "F.SilkS")
			(hide yes)
			(effects
				(font
					(size 1.27 1.27)
				)
			)
		)
		(property "Value" ""
			(at 0 0 90)
			(layer "F.Fab")
			(effects
				(font
					(size 1.27 1.27)
				)
			)
		)
		(duplicate_pad_numbers_are_jumpers no)
		(fp_line
			(start 0.7874 -0.4064)
			(end 0.7874 0.4064)
			(stroke
				(width 0.1524)
				(type default)
			)
			(layer "F.SilkS")
		)
		(fp_line
			(start -0.7874 -0.4064)
			(end 0.7874 -0.4064)
			(stroke
				(width 0.1524)
				(type default)
			)
			(layer "F.SilkS")
		)
		(fp_line
			(start 0.7874 0.4064)
			(end -0.7874 0.4064)
			(stroke
				(width 0.1524)
				(type default)
			)
			(layer "F.SilkS")
		)
		(fp_line
			(start -0.7874 0.4064)
			(end -0.7874 -0.4064)
			(stroke
				(width 0.1524)
				(type default)
			)
			(layer "F.SilkS")
		)
		(fp_line
			(start -0.12065 -0.305054)
			(end -0.12065 -0.2794)
			(stroke
				(width 0.1)
				(type default)
			)
			(layer "F.Fab")
		)
		(fp_line
			(start -0.67945 -0.305054)
			(end -0.12065 -0.305054)
			(stroke
				(width 0.1)
				(type default)
			)
			(layer "F.Fab")
		)
		(fp_line
			(start 0.67945 -0.3048)
			(end 0.67945 0.3048)
			(stroke
				(width 0.1)
				(type default)
			)
			(layer "F.Fab")
		)
		(fp_line
			(start 0.12065 -0.3048)
			(end 0.67945 -0.3048)
			(stroke
				(width 0.1)
				(type default)
			)
			(layer "F.Fab")
		)
		(fp_line
			(start 0.12065 -0.2794)
			(end 0.12065 -0.3048)
			(stroke
				(width 0.1)
				(type default)
			)
			(layer "F.Fab")
		)
		(fp_line
			(start -0.12065 -0.2794)
			(end 0.12065 -0.2794)
			(stroke
				(width 0.1)
				(type default)
			)
			(layer "F.Fab")
		)
		(fp_line
			(start 0.120396 0.2794)
			(end -0.12065 0.2794)
			(stroke
				(width 0.1)
				(type default)
			)
			(layer "F.Fab")
		)
		(fp_line
			(start -0.12065 0.2794)
			(end -0.12065 0.3048)
			(stroke
				(width 0.1)
				(type default)
			)
			(layer "F.Fab")
		)
		(fp_line
			(start 0.67945 0.3048)
			(end 0.120396 0.3048)
			(stroke
				(width 0.1)
				(type default)
			)
			(layer "F.Fab")
		)
		(fp_line
			(start 0.120396 0.3048)
			(end 0.120396 0.2794)
			(stroke
				(width 0.1)
				(type default)
			)
			(layer "F.Fab")
		)
		(fp_line
			(start -0.12065 0.3048)
			(end -0.67945 0.3048)
			(stroke
				(width 0.1)
				(type default)
			)
			(layer "F.Fab")
		)
		(fp_line
			(start -0.67945 0.3048)
			(end -0.67945 -0.305054)
			(stroke
				(width 0.1)
				(type default)
			)
			(layer "F.Fab")
		)
		(pad "1" smd circle
			(at -0.40005 0 90)
			(size 0 0)
			(layers "F.Cu" "F.Mask" "F.Paste")
			(net "SSD10_AUX_P3V3_EN_R")
		)
		(pad "2" smd circle
			(at 0.40005 0 90)
			(size 0 0)
			(layers "F.Cu" "F.Mask" "F.Paste")
			(net "GND")
		)
	)
	(footprint ""
		(layer "F.Cu")
		(at 291.194998 -104.830372 180)
		(property "Reference" "R275"
			(at 0 0 180)
			(layer "F.SilkS")
			(hide yes)
			(effects
				(font
					(size 1.27 1.27)
				)
			)
		)
		(property "Value" ""
			(at 0 0 180)
			(layer "F.Fab")
			(effects
				(font
					(size 1.27 1.27)
				)
			)
		)
		(duplicate_pad_numbers_are_jumpers no)
		(fp_line
			(start 0.7874 0.4064)
			(end -0.7874 0.4064)
			(stroke
				(width 0.1524)
				(type default)
			)
			(layer "F.SilkS")
		)
		(fp_line
			(start 0.7874 -0.4064)
			(end 0.7874 0.4064)
			(stroke
				(width 0.1524)
				(type default)
			)
			(layer "F.SilkS")
		)
		(fp_line
			(start -0.7874 0.4064)
			(end -0.7874 -0.4064)
			(stroke
				(width 0.1524)
				(type default)
			)
			(layer "F.SilkS")
		)
		(fp_line
			(start -0.7874 -0.4064)
			(end 0.7874 -0.4064)
			(stroke
				(width 0.1524)
				(type default)
			)
			(layer "F.SilkS")
		)
		(fp_line
			(start 0.67945 0.3048)
			(end 0.120396 0.3048)
			(stroke
				(width 0.1)
				(type default)
			)
			(layer "F.Fab")
		)
		(fp_line
			(start 0.67945 -0.3048)
			(end 0.67945 0.3048)
			(stroke
				(width 0.1)
				(type default)
			)
			(layer "F.Fab")
		)
		(fp_line
			(start 0.12065 -0.2794)
			(end 0.12065 -0.3048)
			(stroke
				(width 0.1)
				(type default)
			)
			(layer "F.Fab")
		)
		(fp_line
			(start 0.12065 -0.3048)
			(end 0.67945 -0.3048)
			(stroke
				(width 0.1)
				(type default)
			)
			(layer "F.Fab")
		)
		(fp_line
			(start 0.120396 0.3048)
			(end 0.120396 0.2794)
			(stroke
				(width 0.1)
				(type default)
			)
			(layer "F.Fab")
		)
		(fp_line
			(start 0.120396 0.2794)
			(end -0.12065 0.2794)
			(stroke
				(width 0.1)
				(type default)
			)
			(layer "F.Fab")
		)
		(fp_line
			(start -0.12065 0.3048)
			(end -0.67945 0.3048)
			(stroke
				(width 0.1)
				(type default)
			)
			(layer "F.Fab")
		)
		(fp_line
			(start -0.12065 0.2794)
			(end -0.12065 0.3048)
			(stroke
				(width 0.1)
				(type default)
			)
			(layer "F.Fab")
		)
		(fp_line
			(start -0.12065 -0.2794)
			(end 0.12065 -0.2794)
			(stroke
				(width 0.1)
				(type default)
			)
			(layer "F.Fab")
		)
		(fp_line
			(start -0.12065 -0.305054)
			(end -0.12065 -0.2794)
			(stroke
				(width 0.1)
				(type default)
			)
			(layer "F.Fab")
		)
		(fp_line
			(start -0.67945 0.3048)
			(end -0.67945 -0.305054)
			(stroke
				(width 0.1)
				(type default)
			)
			(layer "F.Fab")
		)
		(fp_line
			(start -0.67945 -0.305054)
			(end -0.12065 -0.305054)
			(stroke
				(width 0.1)
				(type default)
			)
			(layer "F.Fab")
		)
		(pad "1" smd circle
			(at -0.40005 0 180)
			(size 0 0)
			(layers "F.Cu" "F.Mask" "F.Paste")
			(net "CLK_50M_NIC5_RBT_REF")
		)
		(pad "2" smd circle
			(at 0.40005 0 180)
			(size 0 0)
			(layers "F.Cu" "F.Mask" "F.Paste")
			(net "GND")
		)
	)
	(footprint ""
		(layer "F.Cu")
		(at 365.506 -211.963 180)
		(property "Reference" "R4623"
			(at 0 0 180)
			(layer "F.SilkS")
			(hide yes)
			(effects
				(font
					(size 1.27 1.27)
				)
			)
		)
		(property "Value" ""
			(at 0 0 180)
			(layer "F.Fab")
			(effects
				(font
					(size 1.27 1.27)
				)
			)
		)
		(duplicate_pad_numbers_are_jumpers no)
		(fp_line
			(start 0.7874 0.4064)
			(end -0.7874 0.4064)
			(stroke
				(width 0.1524)
				(type default)
			)
			(layer "F.SilkS")
		)
		(fp_line
			(start 0.7874 -0.4064)
			(end 0.7874 0.4064)
			(stroke
				(width 0.1524)
				(type default)
			)
			(layer "F.SilkS")
		)
		(fp_line
			(start -0.7874 0.4064)
			(end -0.7874 -0.4064)
			(stroke
				(width 0.1524)
				(type default)
			)
			(layer "F.SilkS")
		)
		(fp_line
			(start -0.7874 -0.4064)
			(end 0.7874 -0.4064)
			(stroke
				(width 0.1524)
				(type default)
			)
			(layer "F.SilkS")
		)
		(fp_line
			(start 0.67945 0.3048)
			(end 0.120396 0.3048)
			(stroke
				(width 0.1)
				(type default)
			)
			(layer "F.Fab")
		)
		(fp_line
			(start 0.67945 -0.3048)
			(end 0.67945 0.3048)
			(stroke
				(width 0.1)
				(type default)
			)
			(layer "F.Fab")
		)
		(fp_line
			(start 0.12065 -0.2794)
			(end 0.12065 -0.3048)
			(stroke
				(width 0.1)
				(type default)
			)
			(layer "F.Fab")
		)
		(fp_line
			(start 0.12065 -0.3048)
			(end 0.67945 -0.3048)
			(stroke
				(width 0.1)
				(type default)
			)
			(layer "F.Fab")
		)
		(fp_line
			(start 0.120396 0.3048)
			(end 0.120396 0.2794)
			(stroke
				(width 0.1)
				(type default)
			)
			(layer "F.Fab")
		)
		(fp_line
			(start 0.120396 0.2794)
			(end -0.12065 0.2794)
			(stroke
				(width 0.1)
				(type default)
			)
			(layer "F.Fab")
		)
		(fp_line
			(start -0.12065 0.3048)
			(end -0.67945 0.3048)
			(stroke
				(width 0.1)
				(type default)
			)
			(layer "F.Fab")
		)
		(fp_line
			(start -0.12065 0.2794)
			(end -0.12065 0.3048)
			(stroke
				(width 0.1)
				(type default)
			)
			(layer "F.Fab")
		)
		(fp_line
			(start -0.12065 -0.2794)
			(end 0.12065 -0.2794)
			(stroke
				(width 0.1)
				(type default)
			)
			(layer "F.Fab")
		)
		(fp_line
			(start -0.12065 -0.305054)
			(end -0.12065 -0.2794)
			(stroke
				(width 0.1)
				(type default)
			)
			(layer "F.Fab")
		)
		(fp_line
			(start -0.67945 0.3048)
			(end -0.67945 -0.305054)
			(stroke
				(width 0.1)
				(type default)
			)
			(layer "F.Fab")
		)
		(fp_line
			(start -0.67945 -0.305054)
			(end -0.12065 -0.305054)
			(stroke
				(width 0.1)
				(type default)
			)
			(layer "F.Fab")
		)
		(pad "1" smd circle
			(at -0.40005 0 180)
			(size 0 0)
			(layers "F.Cu" "F.Mask" "F.Paste")
			(net "PRSNT_SSD0_FPGA_PCA9555_N")
		)
		(pad "2" smd circle
			(at 0.40005 0 180)
			(size 0 0)
			(layers "F.Cu" "F.Mask" "F.Paste")
			(net "PRSNT_SSD0_FPGA_R_N")
		)
	)
	(footprint ""
		(layer "F.Cu")
		(at 366.955578 -89.499694 180)
		(property "Reference" "R1630"
			(at 0 0 180)
			(layer "F.SilkS")
			(hide yes)
			(effects
				(font
					(size 1.27 1.27)
				)
			)
		)
		(property "Value" ""
			(at 0 0 180)
			(layer "F.Fab")
			(effects
				(font
					(size 1.27 1.27)
				)
			)
		)
		(duplicate_pad_numbers_are_jumpers no)
		(fp_line
			(start 0.7874 0.4064)
			(end -0.7874 0.4064)
			(stroke
				(width 0.1524)
				(type default)
			)
			(layer "F.SilkS")
		)
		(fp_line
			(start 0.7874 -0.4064)
			(end 0.7874 0.4064)
			(stroke
				(width 0.1524)
				(type default)
			)
			(layer "F.SilkS")
		)
		(fp_line
			(start -0.7874 0.4064)
			(end -0.7874 -0.4064)
			(stroke
				(width 0.1524)
				(type default)
			)
			(layer "F.SilkS")
		)
		(fp_line
			(start -0.7874 -0.4064)
			(end 0.7874 -0.4064)
			(stroke
				(width 0.1524)
				(type default)
			)
			(layer "F.SilkS")
		)
		(fp_line
			(start 0.67945 0.3048)
			(end 0.120396 0.3048)
			(stroke
				(width 0.1)
				(type default)
			)
			(layer "F.Fab")
		)
		(fp_line
			(start 0.67945 -0.3048)
			(end 0.67945 0.3048)
			(stroke
				(width 0.1)
				(type default)
			)
			(layer "F.Fab")
		)
		(fp_line
			(start 0.12065 -0.2794)
			(end 0.12065 -0.3048)
			(stroke
				(width 0.1)
				(type default)
			)
			(layer "F.Fab")
		)
		(fp_line
			(start 0.12065 -0.3048)
			(end 0.67945 -0.3048)
			(stroke
				(width 0.1)
				(type default)
			)
			(layer "F.Fab")
		)
		(fp_line
			(start 0.120396 0.3048)
			(end 0.120396 0.2794)
			(stroke
				(width 0.1)
				(type default)
			)
			(layer "F.Fab")
		)
		(fp_line
			(start 0.120396 0.2794)
			(end -0.12065 0.2794)
			(stroke
				(width 0.1)
				(type default)
			)
			(layer "F.Fab")
		)
		(fp_line
			(start -0.12065 0.3048)
			(end -0.67945 0.3048)
			(stroke
				(width 0.1)
				(type default)
			)
			(layer "F.Fab")
		)
		(fp_line
			(start -0.12065 0.2794)
			(end -0.12065 0.3048)
			(stroke
				(width 0.1)
				(type default)
			)
			(layer "F.Fab")
		)
		(fp_line
			(start -0.12065 -0.2794)
			(end 0.12065 -0.2794)
			(stroke
				(width 0.1)
				(type default)
			)
			(layer "F.Fab")
		)
		(fp_line
			(start -0.12065 -0.305054)
			(end -0.12065 -0.2794)
			(stroke
				(width 0.1)
				(type default)
			)
			(layer "F.Fab")
		)
		(fp_line
			(start -0.67945 0.3048)
			(end -0.67945 -0.305054)
			(stroke
				(width 0.1)
				(type default)
			)
			(layer "F.Fab")
		)
		(fp_line
			(start -0.67945 -0.305054)
			(end -0.12065 -0.305054)
			(stroke
				(width 0.1)
				(type default)
			)
			(layer "F.Fab")
		)
		(pad "1" smd circle
			(at -0.40005 0 180)
			(size 0 0)
			(layers "F.Cu" "F.Mask" "F.Paste")
			(net "SMB_BIC_I2C9_MUX1_SSD15_R_SCL")
		)
		(pad "2" smd circle
			(at 0.40005 0 180)
			(size 0 0)
			(layers "F.Cu" "F.Mask" "F.Paste")
			(net "SMB_BIC_I2C9_MUX1_SSD15_SCL")
		)
	)
	(footprint ""
		(layer "F.Cu")
		(at 16.445738 -394.128752 -90)
		(property "Reference" "R6755"
			(at 0 0 270)
			(layer "F.SilkS")
			(hide yes)
			(effects
				(font
					(size 1.27 1.27)
				)
			)
		)
		(property "Value" ""
			(at 0 0 270)
			(layer "F.Fab")
			(effects
				(font
					(size 1.27 1.27)
				)
			)
		)
		(duplicate_pad_numbers_are_jumpers no)
		(fp_line
			(start -0.7874 0.4064)
			(end -0.7874 -0.4064)
			(stroke
				(width 0.1524)
				(type default)
			)
			(layer "F.SilkS")
		)
		(fp_line
			(start 0.7874 0.4064)
			(end -0.7874 0.4064)
			(stroke
				(width 0.1524)
				(type default)
			)
			(layer "F.SilkS")
		)
		(fp_line
			(start -0.7874 -0.4064)
			(end 0.7874 -0.4064)
			(stroke
				(width 0.1524)
				(type default)
			)
			(layer "F.SilkS")
		)
		(fp_line
			(start 0.7874 -0.4064)
			(end 0.7874 0.4064)
			(stroke
				(width 0.1524)
				(type default)
			)
			(layer "F.SilkS")
		)
		(fp_line
			(start -0.67945 0.3048)
			(end -0.67945 -0.305054)
			(stroke
				(width 0.1)
				(type default)
			)
			(layer "F.Fab")
		)
		(fp_line
			(start -0.12065 0.3048)
			(end -0.67945 0.3048)
			(stroke
				(width 0.1)
				(type default)
			)
			(layer "F.Fab")
		)
		(fp_line
			(start 0.120396 0.3048)
			(end 0.120396 0.2794)
			(stroke
				(width 0.1)
				(type default)
			)
			(layer "F.Fab")
		)
		(fp_line
			(start 0.67945 0.3048)
			(end 0.120396 0.3048)
			(stroke
				(width 0.1)
				(type default)
			)
			(layer "F.Fab")
		)
		(fp_line
			(start -0.12065 0.2794)
			(end -0.12065 0.3048)
			(stroke
				(width 0.1)
				(type default)
			)
			(layer "F.Fab")
		)
		(fp_line
			(start 0.120396 0.2794)
			(end -0.12065 0.2794)
			(stroke
				(width 0.1)
				(type default)
			)
			(layer "F.Fab")
		)
		(fp_line
			(start -0.12065 -0.2794)
			(end 0.12065 -0.2794)
			(stroke
				(width 0.1)
				(type default)
			)
			(layer "F.Fab")
		)
		(fp_line
			(start 0.12065 -0.2794)
			(end 0.12065 -0.3048)
			(stroke
				(width 0.1)
				(type default)
			)
			(layer "F.Fab")
		)
		(fp_line
			(start 0.12065 -0.3048)
			(end 0.67945 -0.3048)
			(stroke
				(width 0.1)
				(type default)
			)
			(layer "F.Fab")
		)
		(fp_line
			(start 0.67945 -0.3048)
			(end 0.67945 0.3048)
			(stroke
				(width 0.1)
				(type default)
			)
			(layer "F.Fab")
		)
		(fp_line
			(start -0.67945 -0.305054)
			(end -0.12065 -0.305054)
			(stroke
				(width 0.1)
				(type default)
			)
			(layer "F.Fab")
		)
		(fp_line
			(start -0.12065 -0.305054)
			(end -0.12065 -0.2794)
			(stroke
				(width 0.1)
				(type default)
			)
			(layer "F.Fab")
		)
		(pad "1" smd circle
			(at -0.40005 0 270)
			(size 0 0)
			(layers "F.Cu" "F.Mask" "F.Paste")
			(net "P3V3_USB_8042")
		)
		(pad "2" smd circle
			(at 0.40005 0 270)
			(size 0 0)
			(layers "F.Cu" "F.Mask" "F.Paste")
			(net "BIC_USB_8042_HUB_PWRCTL2")
		)
	)
	(footprint ""
		(layer "F.Cu")
		(at 228.197156 -274.768056 180)
		(property "Reference" "R788"
			(at 0 0 180)
			(layer "F.SilkS")
			(hide yes)
			(effects
				(font
					(size 1.27 1.27)
				)
			)
		)
		(property "Value" ""
			(at 0 0 180)
			(layer "F.Fab")
			(effects
				(font
					(size 1.27 1.27)
				)
			)
		)
		(duplicate_pad_numbers_are_jumpers no)
		(fp_line
			(start 0.7874 0.4064)
			(end -0.7874 0.4064)
			(stroke
				(width 0.1524)
				(type default)
			)
			(layer "F.SilkS")
		)
		(fp_line
			(start 0.7874 -0.4064)
			(end 0.7874 0.4064)
			(stroke
				(width 0.1524)
				(type default)
			)
			(layer "F.SilkS")
		)
		(fp_line
			(start -0.7874 0.4064)
			(end -0.7874 -0.4064)
			(stroke
				(width 0.1524)
				(type default)
			)
			(layer "F.SilkS")
		)
		(fp_line
			(start -0.7874 -0.4064)
			(end 0.7874 -0.4064)
			(stroke
				(width 0.1524)
				(type default)
			)
			(layer "F.SilkS")
		)
		(fp_line
			(start 0.67945 0.3048)
			(end 0.120396 0.3048)
			(stroke
				(width 0.1)
				(type default)
			)
			(layer "F.Fab")
		)
		(fp_line
			(start 0.67945 -0.3048)
			(end 0.67945 0.3048)
			(stroke
				(width 0.1)
				(type default)
			)
			(layer "F.Fab")
		)
		(fp_line
			(start 0.12065 -0.2794)
			(end 0.12065 -0.3048)
			(stroke
				(width 0.1)
				(type default)
			)
			(layer "F.Fab")
		)
		(fp_line
			(start 0.12065 -0.3048)
			(end 0.67945 -0.3048)
			(stroke
				(width 0.1)
				(type default)
			)
			(layer "F.Fab")
		)
		(fp_line
			(start 0.120396 0.3048)
			(end 0.120396 0.2794)
			(stroke
				(width 0.1)
				(type default)
			)
			(layer "F.Fab")
		)
		(fp_line
			(start 0.120396 0.2794)
			(end -0.12065 0.2794)
			(stroke
				(width 0.1)
				(type default)
			)
			(layer "F.Fab")
		)
		(fp_line
			(start -0.12065 0.3048)
			(end -0.67945 0.3048)
			(stroke
				(width 0.1)
				(type default)
			)
			(layer "F.Fab")
		)
		(fp_line
			(start -0.12065 0.2794)
			(end -0.12065 0.3048)
			(stroke
				(width 0.1)
				(type default)
			)
			(layer "F.Fab")
		)
		(fp_line
			(start -0.12065 -0.2794)
			(end 0.12065 -0.2794)
			(stroke
				(width 0.1)
				(type default)
			)
			(layer "F.Fab")
		)
		(fp_line
			(start -0.12065 -0.305054)
			(end -0.12065 -0.2794)
			(stroke
				(width 0.1)
				(type default)
			)
			(layer "F.Fab")
		)
		(fp_line
			(start -0.67945 0.3048)
			(end -0.67945 -0.305054)
			(stroke
				(width 0.1)
				(type default)
			)
			(layer "F.Fab")
		)
		(fp_line
			(start -0.67945 -0.305054)
			(end -0.12065 -0.305054)
			(stroke
				(width 0.1)
				(type default)
			)
			(layer "F.Fab")
		)
		(pad "1" smd circle
			(at -0.40005 0 180)
			(size 0 0)
			(layers "F.Cu" "F.Mask" "F.Paste")
			(net "P1V25_PEX1_R")
		)
		(pad "2" smd circle
			(at 0.40005 0 180)
			(size 0 0)
			(layers "F.Cu" "F.Mask" "F.Paste")
			(net "P12V_PEX1_P1V25_VIN_P")
		)
	)
	(footprint ""
		(layer "F.Cu")
		(at 216.74709 -54.3941)
		(property "Reference" "PU37"
			(at -1.670812 2.939034 0)
			(unlocked yes)
			(layer "F.SilkS")
			(effects
				(font
					(size 0.7874 0.5842)
					(thickness 0.1524)
				)
				(justify left)
			)
		)
		(property "Value" ""
			(at 0 0 0)
			(layer "F.Fab")
			(effects
				(font
					(size 1.27 1.27)
				)
			)
		)
		(duplicate_pad_numbers_are_jumpers no)
		(fp_line
			(start -1.943608 -1.549908)
			(end 1.943608 -1.549908)
			(stroke
				(width 0.1524)
				(type default)
			)
			(layer "F.SilkS")
		)
		(fp_line
			(start -1.943608 1.549908)
			(end -1.943608 -1.549908)
			(stroke
				(width 0.1524)
				(type default)
			)
			(layer "F.SilkS")
		)
		(fp_line
			(start 1.943608 -1.549908)
			(end 1.943608 1.549908)
			(stroke
				(width 0.1524)
				(type default)
			)
			(layer "F.SilkS")
		)
		(fp_line
			(start 1.943608 1.549908)
			(end -1.943608 1.549908)
			(stroke
				(width 0.1524)
				(type default)
			)
			(layer "F.SilkS")
		)
		(fp_poly
			(pts
				(xy -2.019808 -1.549908) (xy -1.257808 -1.549908) (xy -1.257808 -1.880108) (xy -2.019808 -1.880108)
			)
			(stroke
				(width 0)
				(type default)
			)
			(fill yes)
			(layer "F.SilkS")
		)
		(fp_line
			(start -1.549908 -1.549908)
			(end 1.549908 -1.549908)
			(stroke
				(width 0.1)
				(type default)
			)
			(layer "F.Fab")
		)
		(fp_line
			(start -1.549908 1.549908)
			(end -1.549908 -1.549908)
			(stroke
				(width 0.1)
				(type default)
			)
			(layer "F.Fab")
		)
		(fp_line
			(start 1.549908 -1.549908)
			(end 1.549908 1.549908)
			(stroke
				(width 0.1)
				(type default)
			)
			(layer "F.Fab")
		)
		(fp_line
			(start 1.549908 1.549908)
			(end -1.549908 1.549908)
			(stroke
				(width 0.1)
				(type default)
			)
			(layer "F.Fab")
		)
		(fp_poly
			(pts
				(xy -2.019808 -1.549908) (xy -1.257808 -1.549908) (xy -1.257808 -1.880108) (xy -2.019808 -1.880108)
			)
			(stroke
				(width 0)
				(type default)
			)
			(fill yes)
			(layer "F.Fab")
		)
		(pad "1" smd rect
			(at -1.500124 -1.249934 270)
			(size 0.2794 0.6096)
			(layers "F.Cu" "F.Mask" "F.Paste")
			(net "P12V_SSD7_R")
		)
		(pad "2" smd rect
			(at -1.500124 -0.750062 270)
			(size 0.2794 0.6096)
			(layers "F.Cu" "F.Mask" "F.Paste")
			(net "P12V_SSD7_R")
		)
		(pad "3" smd rect
			(at -1.500124 -0.249936 270)
			(size 0.2794 0.6096)
			(layers "F.Cu" "F.Mask" "F.Paste")
			(net "P12V_SSD7_R")
		)
		(pad "4" smd rect
			(at -1.500124 0.249936 270)
			(size 0.2794 0.6096)
			(layers "F.Cu" "F.Mask" "F.Paste")
			(net "P12V_SSD7_R")
		)
		(pad "5" smd rect
			(at -1.500124 0.750062 270)
			(size 0.2794 0.6096)
			(layers "F.Cu" "F.Mask" "F.Paste")
			(net "P12V_SSD7_R")
		)
		(pad "6" smd rect
			(at -1.500124 1.249934 270)
			(size 0.2794 0.6096)
			(layers "F.Cu" "F.Mask" "F.Paste")
			(net "GND")
		)
		(pad "7" smd rect
			(at 1.500124 1.249934 270)
			(size 0.2794 0.6096)
			(layers "F.Cu" "F.Mask" "F.Paste")
			(net "P12V_SSD7_SS")
		)
		(pad "8" smd rect
			(at 1.500124 0.750062 270)
			(size 0.2794 0.6096)
			(layers "F.Cu" "F.Mask" "F.Paste")
			(net "PWRGD_P12V_SSD7")
		)
		(pad "9" smd rect
			(at 1.500124 0.249936 270)
			(size 0.2794 0.6096)
			(layers "F.Cu" "F.Mask" "F.Paste")
			(net "P12V_SSD7_OCP")
		)
		(pad "10" smd rect
			(at 1.500124 -0.249936 270)
			(size 0.2794 0.6096)
			(layers "F.Cu" "F.Mask" "F.Paste")
			(net "P5V_AUX")
		)
		(pad "11" smd rect
			(at 1.500124 -0.750062 270)
			(size 0.2794 0.6096)
			(layers "F.Cu" "F.Mask" "F.Paste")
			(net "SSD7_PWR_EN_R")
		)
		(pad "12" smd rect
			(at 1.500124 -1.249934 270)
			(size 0.2794 0.6096)
			(layers "F.Cu" "F.Mask" "F.Paste")
			(net "P12V_AUX")
		)
		(pad "13" smd rect
			(at 0 0)
			(size 1.9812 2.7178)
			(layers "F.Cu" "F.Mask" "F.Paste")
			(net "P12V_AUX")
		)
		(zone
			(layer "F.Cu")
			(hatch none 0.5)
			(connect_pads
				(clearance 0)
			)
			(min_thickness 0.25)
			(keepout
				(tracks not_allowed)
				(vias allowed)
				(pads allowed)
				(copperpour not_allowed)
				(footprints allowed)
			)
			(placement
				(enabled no)
				(sheetname "")
			)
			(fill
				(thermal_gap 0.5)
				(thermal_bridge_width 0.5)
				(island_removal_mode 0)
			)
			(polygon
				(pts
					(xy 217.89009 -55.9435) (xy 217.89009 -55.8165) (xy 217.89009 -52.8447) (xy 217.89009 -52.844192)
					(xy 215.60409 -52.844192) (xy 215.60409 -52.8447) (xy 215.60409 -52.9717) (xy 215.60409 -54.3941)
					(xy 215.70569 -54.3941) (xy 215.70569 -52.9717) (xy 217.78849 -52.9717) (xy 217.78849 -55.8165)
					(xy 215.70569 -55.8165) (xy 215.70569 -54.4195) (xy 215.60409 -54.4195) (xy 215.60409 -55.8165)
					(xy 215.60409 -55.9435) (xy 215.60409 -55.944008) (xy 217.89009 -55.944008)
				)
			)
		)
	)
	(footprint ""
		(layer "F.Cu")
		(at 410.184092 -343.952322 90)
		(property "Reference" "C825"
			(at 0 0 90)
			(layer "F.SilkS")
			(hide yes)
			(effects
				(font
					(size 1.27 1.27)
				)
			)
		)
		(property "Value" ""
			(at 0 0 90)
			(layer "F.Fab")
			(effects
				(font
					(size 1.27 1.27)
				)
			)
		)
		(duplicate_pad_numbers_are_jumpers no)
		(fp_line
			(start 0.299974 -0.150114)
			(end 0.299974 0.150114)
			(stroke
				(width 0.1)
				(type default)
			)
			(layer "F.Fab")
		)
		(fp_line
			(start -0.299974 -0.150114)
			(end 0.299974 -0.150114)
			(stroke
				(width 0.1)
				(type default)
			)
			(layer "F.Fab")
		)
		(fp_line
			(start 0.299974 0.150114)
			(end -0.299974 0.150114)
			(stroke
				(width 0.1)
				(type default)
			)
			(layer "F.Fab")
		)
		(fp_line
			(start -0.299974 0.150114)
			(end -0.299974 -0.150114)
			(stroke
				(width 0.1)
				(type default)
			)
			(layer "F.Fab")
		)
		(pad "1" smd rect
			(at -0.2667 0 90)
			(size 0.3048 0.381)
			(layers "F.Cu" "F.Mask" "F.Paste")
			(net "P5E_PEX3_STN7_TX_DN<112>")
		)
		(pad "2" smd rect
			(at 0.2667 0 90)
			(size 0.3048 0.381)
			(layers "F.Cu" "F.Mask" "F.Paste")
			(net "P5E_PEX3_STN7_TX_C_DN<112>")
		)
	)
	(footprint ""
		(layer "F.Cu")
		(at 20.659598 -61.612526)
		(property "Reference" "PD21"
			(at -3.7084 -2.733548 0)
			(unlocked yes)
			(layer "F.SilkS")
			(effects
				(font
					(size 0.7874 0.5842)
					(thickness 0.1524)
				)
				(justify left)
			)
		)
		(property "Value" ""
			(at 0 0 0)
			(layer "F.Fab")
			(effects
				(font
					(size 1.27 1.27)
				)
			)
		)
		(duplicate_pad_numbers_are_jumpers no)
		(fp_line
			(start -3.656584 -1.970024)
			(end -3.656584 1.970024)
			(stroke
				(width 0.1524)
				(type default)
			)
			(layer "F.SilkS")
		)
		(fp_line
			(start -3.656584 1.970024)
			(end 4.240784 1.970024)
			(stroke
				(width 0.1524)
				(type default)
			)
			(layer "F.SilkS")
		)
		(fp_line
			(start 4.240784 -1.970024)
			(end -3.656584 -1.970024)
			(stroke
				(width 0.1524)
				(type default)
			)
			(layer "F.SilkS")
		)
		(fp_line
			(start 4.240784 1.970024)
			(end 4.240784 -1.970024)
			(stroke
				(width 0.1524)
				(type default)
			)
			(layer "F.SilkS")
		)
		(fp_poly
			(pts
				(xy 3.580384 1.970024) (xy 3.580384 -1.970024) (xy 4.240784 -1.970024) (xy 4.240784 1.970024)
			)
			(stroke
				(width 0)
				(type default)
			)
			(fill yes)
			(layer "F.SilkS")
		)
		(fp_line
			(start -2.3749 -1.970024)
			(end -2.3749 1.970024)
			(stroke
				(width 0.1)
				(type default)
			)
			(layer "F.Fab")
		)
		(fp_line
			(start -2.3749 1.970024)
			(end 2.3749 1.970024)
			(stroke
				(width 0.1)
				(type default)
			)
			(layer "F.Fab")
		)
		(fp_line
			(start 2.3749 -1.970024)
			(end -2.3749 -1.970024)
			(stroke
				(width 0.1)
				(type default)
			)
			(layer "F.Fab")
		)
		(fp_line
			(start 2.3749 1.970024)
			(end 2.3749 -1.970024)
			(stroke
				(width 0.1)
				(type default)
			)
			(layer "F.Fab")
		)
		(fp_text user "+"
			(at -4.9784 -0.23495 0)
			(unlocked yes)
			(layer "F.Fab")
			(effects
				(font
					(size 1.905 1.4224)
					(thickness 0.1524)
				)
				(justify left)
			)
		)
		(fp_text user "-"
			(at 4.1656 -0.23495 0)
			(unlocked yes)
			(layer "F.Fab")
			(effects
				(font
					(size 1.905 1.4224)
					(thickness 0.1524)
				)
				(justify left)
			)
		)
		(pad "A" smd rect
			(at -2.450084 0)
			(size 2.159 2.2606)
			(layers "F.Cu" "F.Mask" "F.Paste")
			(net "GND")
		)
		(pad "C" smd rect
			(at 2.450084 0)
			(size 2.159 2.2606)
			(layers "F.Cu" "F.Mask" "F.Paste")
			(net "P12V_AUX")
		)
	)
	(footprint ""
		(layer "F.Cu")
		(at 440.258708 -111.227108 90)
		(property "Reference" "PC824"
			(at 0 0 90)
			(layer "F.SilkS")
			(hide yes)
			(effects
				(font
					(size 1.27 1.27)
				)
			)
		)
		(property "Value" ""
			(at 0 0 90)
			(layer "F.Fab")
			(effects
				(font
					(size 1.27 1.27)
				)
			)
		)
		(duplicate_pad_numbers_are_jumpers no)
		(fp_line
			(start 1.524 -0.762)
			(end 1.524 0.762)
			(stroke
				(width 0.1524)
				(type default)
			)
			(layer "F.SilkS")
		)
		(fp_line
			(start -1.524 -0.762)
			(end 1.524 -0.762)
			(stroke
				(width 0.1524)
				(type default)
			)
			(layer "F.SilkS")
		)
		(fp_line
			(start 1.524 0.762)
			(end -1.524 0.762)
			(stroke
				(width 0.1524)
				(type default)
			)
			(layer "F.SilkS")
		)
		(fp_line
			(start -1.524 0.762)
			(end -1.524 -0.762)
			(stroke
				(width 0.1524)
				(type default)
			)
			(layer "F.SilkS")
		)
		(fp_line
			(start 1.1049 -0.724916)
			(end -1.1049 -0.724916)
			(stroke
				(width 0.1)
				(type default)
			)
			(layer "F.Fab")
		)
		(fp_line
			(start -1.1049 -0.724916)
			(end -1.1049 0.724916)
			(stroke
				(width 0.1)
				(type default)
			)
			(layer "F.Fab")
		)
		(fp_line
			(start 1.1049 0.724916)
			(end 1.1049 -0.724916)
			(stroke
				(width 0.1)
				(type default)
			)
			(layer "F.Fab")
		)
		(fp_line
			(start -1.1049 0.724916)
			(end 1.1049 0.724916)
			(stroke
				(width 0.1)
				(type default)
			)
			(layer "F.Fab")
		)
		(pad "1" smd rect
			(at -0.889 0 270)
			(size 1.016 1.27)
			(layers "F.Cu" "F.Mask" "F.Paste")
			(net "P12V_NIC7_R")
		)
		(pad "2" smd rect
			(at 0.889 0 270)
			(size 1.016 1.27)
			(layers "F.Cu" "F.Mask" "F.Paste")
			(net "GND")
		)
	)
	(footprint ""
		(layer "F.Cu")
		(at 324.913244 -350.098614 90)
		(property "Reference" "C537"
			(at 0 0 90)
			(layer "F.SilkS")
			(hide yes)
			(effects
				(font
					(size 1.27 1.27)
				)
			)
		)
		(property "Value" ""
			(at 0 0 90)
			(layer "F.Fab")
			(effects
				(font
					(size 1.27 1.27)
				)
			)
		)
		(duplicate_pad_numbers_are_jumpers no)
		(fp_line
			(start 0.299974 -0.150114)
			(end 0.299974 0.150114)
			(stroke
				(width 0.1)
				(type default)
			)
			(layer "F.Fab")
		)
		(fp_line
			(start -0.299974 -0.150114)
			(end 0.299974 -0.150114)
			(stroke
				(width 0.1)
				(type default)
			)
			(layer "F.Fab")
		)
		(fp_line
			(start 0.299974 0.150114)
			(end -0.299974 0.150114)
			(stroke
				(width 0.1)
				(type default)
			)
			(layer "F.Fab")
		)
		(fp_line
			(start -0.299974 0.150114)
			(end -0.299974 -0.150114)
			(stroke
				(width 0.1)
				(type default)
			)
			(layer "F.Fab")
		)
		(pad "1" smd rect
			(at -0.2667 0 90)
			(size 0.3048 0.381)
			(layers "F.Cu" "F.Mask" "F.Paste")
			(net "P5E_PEX2_STN5_TX_DP<86>")
		)
		(pad "2" smd rect
			(at 0.2667 0 90)
			(size 0.3048 0.381)
			(layers "F.Cu" "F.Mask" "F.Paste")
			(net "P5E_PEX2_STN5_TX_C_DP<86>")
		)
	)
	(footprint ""
		(layer "F.Cu")
		(at 371.690392 -236.953298)
		(property "Reference" "R6404"
			(at 0 0 0)
			(layer "F.SilkS")
			(hide yes)
			(effects
				(font
					(size 1.27 1.27)
				)
			)
		)
		(property "Value" ""
			(at 0 0 0)
			(layer "F.Fab")
			(effects
				(font
					(size 1.27 1.27)
				)
			)
		)
		(duplicate_pad_numbers_are_jumpers no)
		(fp_line
			(start -0.7874 -0.4064)
			(end 0.7874 -0.4064)
			(stroke
				(width 0.1524)
				(type default)
			)
			(layer "F.SilkS")
		)
		(fp_line
			(start -0.7874 0.4064)
			(end -0.7874 -0.4064)
			(stroke
				(width 0.1524)
				(type default)
			)
			(layer "F.SilkS")
		)
		(fp_line
			(start 0.7874 -0.4064)
			(end 0.7874 0.4064)
			(stroke
				(width 0.1524)
				(type default)
			)
			(layer "F.SilkS")
		)
		(fp_line
			(start 0.7874 0.4064)
			(end -0.7874 0.4064)
			(stroke
				(width 0.1524)
				(type default)
			)
			(layer "F.SilkS")
		)
		(fp_line
			(start -0.67945 -0.305054)
			(end -0.12065 -0.305054)
			(stroke
				(width 0.1)
				(type default)
			)
			(layer "F.Fab")
		)
		(fp_line
			(start -0.67945 0.3048)
			(end -0.67945 -0.305054)
			(stroke
				(width 0.1)
				(type default)
			)
			(layer "F.Fab")
		)
		(fp_line
			(start -0.12065 -0.305054)
			(end -0.12065 -0.2794)
			(stroke
				(width 0.1)
				(type default)
			)
			(layer "F.Fab")
		)
		(fp_line
			(start -0.12065 -0.2794)
			(end 0.12065 -0.2794)
			(stroke
				(width 0.1)
				(type default)
			)
			(layer "F.Fab")
		)
		(fp_line
			(start -0.12065 0.2794)
			(end -0.12065 0.3048)
			(stroke
				(width 0.1)
				(type default)
			)
			(layer "F.Fab")
		)
		(fp_line
			(start -0.12065 0.3048)
			(end -0.67945 0.3048)
			(stroke
				(width 0.1)
				(type default)
			)
			(layer "F.Fab")
		)
		(fp_line
			(start 0.120396 0.2794)
			(end -0.12065 0.2794)
			(stroke
				(width 0.1)
				(type default)
			)
			(layer "F.Fab")
		)
		(fp_line
			(start 0.120396 0.3048)
			(end 0.120396 0.2794)
			(stroke
				(width 0.1)
				(type default)
			)
			(layer "F.Fab")
		)
		(fp_line
			(start 0.12065 -0.3048)
			(end 0.67945 -0.3048)
			(stroke
				(width 0.1)
				(type default)
			)
			(layer "F.Fab")
		)
		(fp_line
			(start 0.12065 -0.2794)
			(end 0.12065 -0.3048)
			(stroke
				(width 0.1)
				(type default)
			)
			(layer "F.Fab")
		)
		(fp_line
			(start 0.67945 -0.3048)
			(end 0.67945 0.3048)
			(stroke
				(width 0.1)
				(type default)
			)
			(layer "F.Fab")
		)
		(fp_line
			(start 0.67945 0.3048)
			(end 0.120396 0.3048)
			(stroke
				(width 0.1)
				(type default)
			)
			(layer "F.Fab")
		)
		(pad "1" smd circle
			(at -0.40005 0)
			(size 0 0)
			(layers "F.Cu" "F.Mask" "F.Paste")
			(net "PWRGD_P5V_AUX_BUF")
		)
		(pad "2" smd circle
			(at 0.40005 0)
			(size 0 0)
			(layers "F.Cu" "F.Mask" "F.Paste")
			(net "PWRGD_P5V_AUX_BUF_R")
		)
	)
	(footprint ""
		(layer "F.Cu")
		(at 117.119654 -320.820034 90)
		(property "Reference" "C4217"
			(at 0 0 90)
			(layer "F.SilkS")
			(hide yes)
			(effects
				(font
					(size 1.27 1.27)
				)
			)
		)
		(property "Value" ""
			(at 0 0 90)
			(layer "F.Fab")
			(effects
				(font
					(size 1.27 1.27)
				)
			)
		)
		(duplicate_pad_numbers_are_jumpers no)
		(fp_line
			(start 1.2954 -0.5842)
			(end 1.2954 0.5842)
			(stroke
				(width 0.1524)
				(type default)
			)
			(layer "F.SilkS")
		)
		(fp_line
			(start -1.2954 -0.5842)
			(end 1.2954 -0.5842)
			(stroke
				(width 0.1524)
				(type default)
			)
			(layer "F.SilkS")
		)
		(fp_line
			(start 1.2954 0.5842)
			(end -1.2954 0.5842)
			(stroke
				(width 0.1524)
				(type default)
			)
			(layer "F.SilkS")
		)
		(fp_line
			(start -1.2954 0.5842)
			(end -1.2954 -0.5842)
			(stroke
				(width 0.1524)
				(type default)
			)
			(layer "F.SilkS")
		)
		(fp_line
			(start 0.8636 -0.4572)
			(end 0.8636 -0.4064)
			(stroke
				(width 0.1)
				(type default)
			)
			(layer "F.Fab")
		)
		(fp_line
			(start -0.8636 -0.4572)
			(end 0.8636 -0.4572)
			(stroke
				(width 0.1)
				(type default)
			)
			(layer "F.Fab")
		)
		(fp_line
			(start 1.1938 -0.4064)
			(end 1.1938 0.4064)
			(stroke
				(width 0.1)
				(type default)
			)
			(layer "F.Fab")
		)
		(fp_line
			(start 0.8636 -0.4064)
			(end 1.1938 -0.4064)
			(stroke
				(width 0.1)
				(type default)
			)
			(layer "F.Fab")
		)
		(fp_line
			(start -0.8636 -0.4064)
			(end -0.8636 -0.4572)
			(stroke
				(width 0.1)
				(type default)
			)
			(layer "F.Fab")
		)
		(fp_line
			(start -1.1938 -0.4064)
			(end -0.8636 -0.4064)
			(stroke
				(width 0.1)
				(type default)
			)
			(layer "F.Fab")
		)
		(fp_line
			(start 1.1938 0.4064)
			(end 0.8636 0.4064)
			(stroke
				(width 0.1)
				(type default)
			)
			(layer "F.Fab")
		)
		(fp_line
			(start 0.8636 0.4064)
			(end 0.8636 0.4572)
			(stroke
				(width 0.1)
				(type default)
			)
			(layer "F.Fab")
		)
		(fp_line
			(start -0.8636 0.4064)
			(end -1.1938 0.4064)
			(stroke
				(width 0.1)
				(type default)
			)
			(layer "F.Fab")
		)
		(fp_line
			(start -1.1938 0.4064)
			(end -1.1938 -0.4064)
			(stroke
				(width 0.1)
				(type default)
			)
			(layer "F.Fab")
		)
		(fp_line
			(start 0.8636 0.4572)
			(end -0.8636 0.4572)
			(stroke
				(width 0.1)
				(type default)
			)
			(layer "F.Fab")
		)
		(fp_line
			(start -0.8636 0.4572)
			(end -0.8636 0.4064)
			(stroke
				(width 0.1)
				(type default)
			)
			(layer "F.Fab")
		)
		(pad "1" smd rect
			(at -0.7366 0)
			(size 0.7112 0.8128)
			(layers "F.Cu" "F.Mask" "F.Paste")
			(net "P0V8_SERDES_VDDA_PEX0_C11")
		)
		(pad "2" smd rect
			(at 0.7366 0)
			(size 0.7112 0.8128)
			(layers "F.Cu" "F.Mask" "F.Paste")
			(net "GND")
		)
	)
	(footprint ""
		(layer "F.Cu")
		(at 374.015 -246.888)
		(property "Reference" "C2607"
			(at 0 0 0)
			(layer "F.SilkS")
			(hide yes)
			(effects
				(font
					(size 1.27 1.27)
				)
			)
		)
		(property "Value" ""
			(at 0 0 0)
			(layer "F.Fab")
			(effects
				(font
					(size 1.27 1.27)
				)
			)
		)
		(duplicate_pad_numbers_are_jumpers no)
		(fp_line
			(start -0.7874 -0.4064)
			(end 0.7874 -0.4064)
			(stroke
				(width 0.1524)
				(type default)
			)
			(layer "F.SilkS")
		)
		(fp_line
			(start -0.7874 0.4064)
			(end -0.7874 -0.4064)
			(stroke
				(width 0.1524)
				(type default)
			)
			(layer "F.SilkS")
		)
		(fp_line
			(start 0.7874 -0.4064)
			(end 0.7874 0.4064)
			(stroke
				(width 0.1524)
				(type default)
			)
			(layer "F.SilkS")
		)
		(fp_line
			(start 0.7874 0.4064)
			(end -0.7874 0.4064)
			(stroke
				(width 0.1524)
				(type default)
			)
			(layer "F.SilkS")
		)
		(fp_line
			(start -0.67945 -0.305054)
			(end -0.12065 -0.305054)
			(stroke
				(width 0.1)
				(type default)
			)
			(layer "F.Fab")
		)
		(fp_line
			(start -0.67945 0.3048)
			(end -0.67945 -0.305054)
			(stroke
				(width 0.1)
				(type default)
			)
			(layer "F.Fab")
		)
		(fp_line
			(start -0.12065 -0.305054)
			(end -0.12065 -0.2794)
			(stroke
				(width 0.1)
				(type default)
			)
			(layer "F.Fab")
		)
		(fp_line
			(start -0.12065 -0.2794)
			(end 0.12065 -0.2794)
			(stroke
				(width 0.1)
				(type default)
			)
			(layer "F.Fab")
		)
		(fp_line
			(start -0.12065 0.2794)
			(end -0.12065 0.3048)
			(stroke
				(width 0.1)
				(type default)
			)
			(layer "F.Fab")
		)
		(fp_line
			(start -0.12065 0.3048)
			(end -0.67945 0.3048)
			(stroke
				(width 0.1)
				(type default)
			)
			(layer "F.Fab")
		)
		(fp_line
			(start 0.120396 0.2794)
			(end -0.12065 0.2794)
			(stroke
				(width 0.1)
				(type default)
			)
			(layer "F.Fab")
		)
		(fp_line
			(start 0.120396 0.3048)
			(end 0.120396 0.2794)
			(stroke
				(width 0.1)
				(type default)
			)
			(layer "F.Fab")
		)
		(fp_line
			(start 0.12065 -0.3048)
			(end 0.67945 -0.3048)
			(stroke
				(width 0.1)
				(type default)
			)
			(layer "F.Fab")
		)
		(fp_line
			(start 0.12065 -0.2794)
			(end 0.12065 -0.3048)
			(stroke
				(width 0.1)
				(type default)
			)
			(layer "F.Fab")
		)
		(fp_line
			(start 0.67945 -0.3048)
			(end 0.67945 0.3048)
			(stroke
				(width 0.1)
				(type default)
			)
			(layer "F.Fab")
		)
		(fp_line
			(start 0.67945 0.3048)
			(end 0.120396 0.3048)
			(stroke
				(width 0.1)
				(type default)
			)
			(layer "F.Fab")
		)
		(pad "1" smd circle
			(at -0.40005 0)
			(size 0 0)
			(layers "F.Cu" "F.Mask" "F.Paste")
			(net "GND")
		)
		(pad "2" smd circle
			(at 0.40005 0)
			(size 0 0)
			(layers "F.Cu" "F.Mask" "F.Paste")
			(net "P1V8_PEX")
		)
	)
	(footprint ""
		(layer "F.Cu")
		(at 334.990186 -10.534142 -90)
		(property "Reference" "R1710"
			(at 0 0 270)
			(layer "F.SilkS")
			(hide yes)
			(effects
				(font
					(size 1.27 1.27)
				)
			)
		)
		(property "Value" ""
			(at 0 0 270)
			(layer "F.Fab")
			(effects
				(font
					(size 1.27 1.27)
				)
			)
		)
		(duplicate_pad_numbers_are_jumpers no)
		(fp_line
			(start -0.7874 0.4064)
			(end -0.7874 -0.4064)
			(stroke
				(width 0.1524)
				(type default)
			)
			(layer "F.SilkS")
		)
		(fp_line
			(start 0.7874 0.4064)
			(end -0.7874 0.4064)
			(stroke
				(width 0.1524)
				(type default)
			)
			(layer "F.SilkS")
		)
		(fp_line
			(start -0.7874 -0.4064)
			(end 0.7874 -0.4064)
			(stroke
				(width 0.1524)
				(type default)
			)
			(layer "F.SilkS")
		)
		(fp_line
			(start 0.7874 -0.4064)
			(end 0.7874 0.4064)
			(stroke
				(width 0.1524)
				(type default)
			)
			(layer "F.SilkS")
		)
		(fp_line
			(start -0.67945 0.3048)
			(end -0.67945 -0.305054)
			(stroke
				(width 0.1)
				(type default)
			)
			(layer "F.Fab")
		)
		(fp_line
			(start -0.12065 0.3048)
			(end -0.67945 0.3048)
			(stroke
				(width 0.1)
				(type default)
			)
			(layer "F.Fab")
		)
		(fp_line
			(start 0.120396 0.3048)
			(end 0.120396 0.2794)
			(stroke
				(width 0.1)
				(type default)
			)
			(layer "F.Fab")
		)
		(fp_line
			(start 0.67945 0.3048)
			(end 0.120396 0.3048)
			(stroke
				(width 0.1)
				(type default)
			)
			(layer "F.Fab")
		)
		(fp_line
			(start -0.12065 0.2794)
			(end -0.12065 0.3048)
			(stroke
				(width 0.1)
				(type default)
			)
			(layer "F.Fab")
		)
		(fp_line
			(start 0.120396 0.2794)
			(end -0.12065 0.2794)
			(stroke
				(width 0.1)
				(type default)
			)
			(layer "F.Fab")
		)
		(fp_line
			(start -0.12065 -0.2794)
			(end 0.12065 -0.2794)
			(stroke
				(width 0.1)
				(type default)
			)
			(layer "F.Fab")
		)
		(fp_line
			(start 0.12065 -0.2794)
			(end 0.12065 -0.3048)
			(stroke
				(width 0.1)
				(type default)
			)
			(layer "F.Fab")
		)
		(fp_line
			(start 0.12065 -0.3048)
			(end 0.67945 -0.3048)
			(stroke
				(width 0.1)
				(type default)
			)
			(layer "F.Fab")
		)
		(fp_line
			(start 0.67945 -0.3048)
			(end 0.67945 0.3048)
			(stroke
				(width 0.1)
				(type default)
			)
			(layer "F.Fab")
		)
		(fp_line
			(start -0.67945 -0.305054)
			(end -0.12065 -0.305054)
			(stroke
				(width 0.1)
				(type default)
			)
			(layer "F.Fab")
		)
		(fp_line
			(start -0.12065 -0.305054)
			(end -0.12065 -0.2794)
			(stroke
				(width 0.1)
				(type default)
			)
			(layer "F.Fab")
		)
		(pad "1" smd circle
			(at -0.40005 0 270)
			(size 0 0)
			(layers "F.Cu" "F.Mask" "F.Paste")
			(net "SMB_ISO_SSD11_R_SDA")
		)
		(pad "2" smd circle
			(at 0.40005 0 270)
			(size 0 0)
			(layers "F.Cu" "F.Mask" "F.Paste")
			(net "SMB_ISO_SSD11_SDA")
		)
	)
	(footprint ""
		(layer "F.Cu")
		(at 266.702286 -250.070874 -90)
		(property "Reference" "R1347"
			(at 0 0 270)
			(layer "F.SilkS")
			(hide yes)
			(effects
				(font
					(size 1.27 1.27)
				)
			)
		)
		(property "Value" ""
			(at 0 0 270)
			(layer "F.Fab")
			(effects
				(font
					(size 1.27 1.27)
				)
			)
		)
		(duplicate_pad_numbers_are_jumpers no)
		(fp_line
			(start -0.7874 0.4064)
			(end -0.7874 -0.4064)
			(stroke
				(width 0.1524)
				(type default)
			)
			(layer "F.SilkS")
		)
		(fp_line
			(start 0.7874 0.4064)
			(end -0.7874 0.4064)
			(stroke
				(width 0.1524)
				(type default)
			)
			(layer "F.SilkS")
		)
		(fp_line
			(start -0.7874 -0.4064)
			(end 0.7874 -0.4064)
			(stroke
				(width 0.1524)
				(type default)
			)
			(layer "F.SilkS")
		)
		(fp_line
			(start 0.7874 -0.4064)
			(end 0.7874 0.4064)
			(stroke
				(width 0.1524)
				(type default)
			)
			(layer "F.SilkS")
		)
		(fp_line
			(start -0.67945 0.3048)
			(end -0.67945 -0.305054)
			(stroke
				(width 0.1)
				(type default)
			)
			(layer "F.Fab")
		)
		(fp_line
			(start -0.12065 0.3048)
			(end -0.67945 0.3048)
			(stroke
				(width 0.1)
				(type default)
			)
			(layer "F.Fab")
		)
		(fp_line
			(start 0.120396 0.3048)
			(end 0.120396 0.2794)
			(stroke
				(width 0.1)
				(type default)
			)
			(layer "F.Fab")
		)
		(fp_line
			(start 0.67945 0.3048)
			(end 0.120396 0.3048)
			(stroke
				(width 0.1)
				(type default)
			)
			(layer "F.Fab")
		)
		(fp_line
			(start -0.12065 0.2794)
			(end -0.12065 0.3048)
			(stroke
				(width 0.1)
				(type default)
			)
			(layer "F.Fab")
		)
		(fp_line
			(start 0.120396 0.2794)
			(end -0.12065 0.2794)
			(stroke
				(width 0.1)
				(type default)
			)
			(layer "F.Fab")
		)
		(fp_line
			(start -0.12065 -0.2794)
			(end 0.12065 -0.2794)
			(stroke
				(width 0.1)
				(type default)
			)
			(layer "F.Fab")
		)
		(fp_line
			(start 0.12065 -0.2794)
			(end 0.12065 -0.3048)
			(stroke
				(width 0.1)
				(type default)
			)
			(layer "F.Fab")
		)
		(fp_line
			(start 0.12065 -0.3048)
			(end 0.67945 -0.3048)
			(stroke
				(width 0.1)
				(type default)
			)
			(layer "F.Fab")
		)
		(fp_line
			(start 0.67945 -0.3048)
			(end 0.67945 0.3048)
			(stroke
				(width 0.1)
				(type default)
			)
			(layer "F.Fab")
		)
		(fp_line
			(start -0.67945 -0.305054)
			(end -0.12065 -0.305054)
			(stroke
				(width 0.1)
				(type default)
			)
			(layer "F.Fab")
		)
		(fp_line
			(start -0.12065 -0.305054)
			(end -0.12065 -0.2794)
			(stroke
				(width 0.1)
				(type default)
			)
			(layer "F.Fab")
		)
		(pad "1" smd circle
			(at -0.40005 0 270)
			(size 0 0)
			(layers "F.Cu" "F.Mask" "F.Paste")
			(net "PEX2_MODE_SEL11")
		)
		(pad "2" smd circle
			(at 0.40005 0 270)
			(size 0 0)
			(layers "F.Cu" "F.Mask" "F.Paste")
			(net "P1V8_PEX")
		)
	)
	(footprint ""
		(layer "F.Cu")
		(at 131.642612 -162.003994 -90)
		(property "Reference" "C841"
			(at 0 0 270)
			(layer "F.SilkS")
			(hide yes)
			(effects
				(font
					(size 1.27 1.27)
				)
			)
		)
		(property "Value" ""
			(at 0 0 270)
			(layer "F.Fab")
			(effects
				(font
					(size 1.27 1.27)
				)
			)
		)
		(duplicate_pad_numbers_are_jumpers no)
		(fp_line
			(start -0.7874 0.4064)
			(end -0.7874 -0.4064)
			(stroke
				(width 0.1524)
				(type default)
			)
			(layer "F.SilkS")
		)
		(fp_line
			(start 0.7874 0.4064)
			(end -0.7874 0.4064)
			(stroke
				(width 0.1524)
				(type default)
			)
			(layer "F.SilkS")
		)
		(fp_line
			(start -0.7874 -0.4064)
			(end 0.7874 -0.4064)
			(stroke
				(width 0.1524)
				(type default)
			)
			(layer "F.SilkS")
		)
		(fp_line
			(start 0.7874 -0.4064)
			(end 0.7874 0.4064)
			(stroke
				(width 0.1524)
				(type default)
			)
			(layer "F.SilkS")
		)
		(fp_line
			(start -0.67945 0.3048)
			(end -0.67945 -0.305054)
			(stroke
				(width 0.1)
				(type default)
			)
			(layer "F.Fab")
		)
		(fp_line
			(start -0.12065 0.3048)
			(end -0.67945 0.3048)
			(stroke
				(width 0.1)
				(type default)
			)
			(layer "F.Fab")
		)
		(fp_line
			(start 0.120396 0.3048)
			(end 0.120396 0.2794)
			(stroke
				(width 0.1)
				(type default)
			)
			(layer "F.Fab")
		)
		(fp_line
			(start 0.67945 0.3048)
			(end 0.120396 0.3048)
			(stroke
				(width 0.1)
				(type default)
			)
			(layer "F.Fab")
		)
		(fp_line
			(start -0.12065 0.2794)
			(end -0.12065 0.3048)
			(stroke
				(width 0.1)
				(type default)
			)
			(layer "F.Fab")
		)
		(fp_line
			(start 0.120396 0.2794)
			(end -0.12065 0.2794)
			(stroke
				(width 0.1)
				(type default)
			)
			(layer "F.Fab")
		)
		(fp_line
			(start -0.12065 -0.2794)
			(end 0.12065 -0.2794)
			(stroke
				(width 0.1)
				(type default)
			)
			(layer "F.Fab")
		)
		(fp_line
			(start 0.12065 -0.2794)
			(end 0.12065 -0.3048)
			(stroke
				(width 0.1)
				(type default)
			)
			(layer "F.Fab")
		)
		(fp_line
			(start 0.12065 -0.3048)
			(end 0.67945 -0.3048)
			(stroke
				(width 0.1)
				(type default)
			)
			(layer "F.Fab")
		)
		(fp_line
			(start 0.67945 -0.3048)
			(end 0.67945 0.3048)
			(stroke
				(width 0.1)
				(type default)
			)
			(layer "F.Fab")
		)
		(fp_line
			(start -0.67945 -0.305054)
			(end -0.12065 -0.305054)
			(stroke
				(width 0.1)
				(type default)
			)
			(layer "F.Fab")
		)
		(fp_line
			(start -0.12065 -0.305054)
			(end -0.12065 -0.2794)
			(stroke
				(width 0.1)
				(type default)
			)
			(layer "F.Fab")
		)
		(pad "1" smd circle
			(at -0.40005 0 270)
			(size 0 0)
			(layers "F.Cu" "F.Mask" "F.Paste")
			(net "GND")
		)
		(pad "2" smd circle
			(at 0.40005 0 270)
			(size 0 0)
			(layers "F.Cu" "F.Mask" "F.Paste")
			(net "P12V_NIC2_CO_EN")
		)
	)
	(footprint ""
		(layer "F.Cu")
		(at 77.569568 -5.564632)
		(property "Reference" "U416"
			(at -1.471168 3.229102 0)
			(unlocked yes)
			(layer "F.SilkS")
			(effects
				(font
					(size 0.7874 0.5842)
					(thickness 0.1524)
				)
				(justify left)
			)
		)
		(property "Value" ""
			(at 0 0 0)
			(layer "F.Fab")
			(effects
				(font
					(size 1.27 1.27)
				)
			)
		)
		(duplicate_pad_numbers_are_jumpers no)
		(fp_line
			(start -3.447796 -2.500122)
			(end -3.447796 2.500122)
			(stroke
				(width 0.1524)
				(type default)
			)
			(layer "F.SilkS")
		)
		(fp_line
			(start -3.447796 2.500122)
			(end 3.447796 2.500122)
			(stroke
				(width 0.1524)
				(type default)
			)
			(layer "F.SilkS")
		)
		(fp_line
			(start -1.484122 -2.500122)
			(end -3.447796 -2.500122)
			(stroke
				(width 0.1524)
				(type default)
			)
			(layer "F.SilkS")
		)
		(fp_line
			(start 0 -1.016)
			(end -1.484122 -2.500122)
			(stroke
				(width 0.1524)
				(type default)
			)
			(layer "F.SilkS")
		)
		(fp_line
			(start 1.484122 -2.500122)
			(end 0 -1.016)
			(stroke
				(width 0.1524)
				(type default)
			)
			(layer "F.SilkS")
		)
		(fp_line
			(start 3.447796 -2.500122)
			(end 1.484122 -2.500122)
			(stroke
				(width 0.1524)
				(type default)
			)
			(layer "F.SilkS")
		)
		(fp_line
			(start 3.447796 2.500122)
			(end 3.447796 -2.500122)
			(stroke
				(width 0.1524)
				(type default)
			)
			(layer "F.SilkS")
		)
		(fp_poly
			(pts
				(xy -3.910838 -3.106928) (xy -4.62915 -2.388616) (xy -3.551682 -2.02946)
			)
			(stroke
				(width 0)
				(type default)
			)
			(fill yes)
			(layer "F.SilkS")
		)
		(fp_line
			(start -1.999996 -2.500122)
			(end -1.999996 2.500122)
			(stroke
				(width 0.1)
				(type default)
			)
			(layer "F.Fab")
		)
		(fp_line
			(start -1.999996 2.500122)
			(end 1.999996 2.500122)
			(stroke
				(width 0.1)
				(type default)
			)
			(layer "F.Fab")
		)
		(fp_line
			(start 1.999996 -2.500122)
			(end -1.999996 -2.500122)
			(stroke
				(width 0.1)
				(type default)
			)
			(layer "F.Fab")
		)
		(fp_line
			(start 1.999996 2.500122)
			(end 1.999996 -2.500122)
			(stroke
				(width 0.1)
				(type default)
			)
			(layer "F.Fab")
		)
		(fp_poly
			(pts
				(xy -4.5974 -2.413) (xy -4.5974 -1.397) (xy -3.5814 -1.905)
			)
			(stroke
				(width 0)
				(type default)
			)
			(fill yes)
			(layer "F.Fab")
		)
		(pad "1" smd rect
			(at -2.649982 -1.905 270)
			(size 0.6096 1.3208)
			(layers "F.Cu" "F.Mask" "F.Paste")
			(net "SMB_LM75_2_SDA")
		)
		(pad "2" smd rect
			(at -2.649982 -0.635 270)
			(size 0.6096 1.3208)
			(layers "F.Cu" "F.Mask" "F.Paste")
			(net "SMB_LM75_2_SCL")
		)
		(pad "3" smd rect
			(at -2.649982 0.635 270)
			(size 0.6096 1.3208)
			(layers "F.Cu" "F.Mask" "F.Paste")
			(net "Net_408")
		)
		(pad "4" smd rect
			(at -2.649982 1.905 270)
			(size 0.6096 1.3208)
			(layers "F.Cu" "F.Mask" "F.Paste")
			(net "GND")
		)
		(pad "5" smd rect
			(at 2.649982 1.905 270)
			(size 0.6096 1.3208)
			(layers "F.Cu" "F.Mask" "F.Paste")
			(net "LM75_2_A2")
		)
		(pad "6" smd rect
			(at 2.649982 0.635 270)
			(size 0.6096 1.3208)
			(layers "F.Cu" "F.Mask" "F.Paste")
			(net "LM75_2_A1")
		)
		(pad "7" smd rect
			(at 2.649982 -0.635 270)
			(size 0.6096 1.3208)
			(layers "F.Cu" "F.Mask" "F.Paste")
			(net "LM75_2_A0")
		)
		(pad "8" smd rect
			(at 2.649982 -1.905 270)
			(size 0.6096 1.3208)
			(layers "F.Cu" "F.Mask" "F.Paste")
			(net "P3V3_AUX")
		)
	)
	(footprint ""
		(layer "F.Cu")
		(at 20.434554 -30.94609 180)
		(property "Reference" "C69"
			(at 0 0 180)
			(layer "F.SilkS")
			(hide yes)
			(effects
				(font
					(size 1.27 1.27)
				)
			)
		)
		(property "Value" ""
			(at 0 0 180)
			(layer "F.Fab")
			(effects
				(font
					(size 1.27 1.27)
				)
			)
		)
		(duplicate_pad_numbers_are_jumpers no)
		(fp_line
			(start 0.299974 0.150114)
			(end -0.299974 0.150114)
			(stroke
				(width 0.1)
				(type default)
			)
			(layer "F.Fab")
		)
		(fp_line
			(start 0.299974 -0.150114)
			(end 0.299974 0.150114)
			(stroke
				(width 0.1)
				(type default)
			)
			(layer "F.Fab")
		)
		(fp_line
			(start -0.299974 0.150114)
			(end -0.299974 -0.150114)
			(stroke
				(width 0.1)
				(type default)
			)
			(layer "F.Fab")
		)
		(fp_line
			(start -0.299974 -0.150114)
			(end 0.299974 -0.150114)
			(stroke
				(width 0.1)
				(type default)
			)
			(layer "F.Fab")
		)
		(pad "1" smd rect
			(at -0.2667 0 180)
			(size 0.3048 0.381)
			(layers "F.Cu" "F.Mask" "F.Paste")
			(net "P5E_PEX0_STN2_TX_DP<45>")
		)
		(pad "2" smd rect
			(at 0.2667 0 180)
			(size 0.3048 0.381)
			(layers "F.Cu" "F.Mask" "F.Paste")
			(net "P5E_PEX0_STN2_TX_C_DP<45>")
		)
	)
	(footprint ""
		(layer "F.Cu")
		(at 320.019934 -289.230816 -90)
		(property "Reference" "R3979"
			(at 0 0 270)
			(layer "F.SilkS")
			(hide yes)
			(effects
				(font
					(size 1.27 1.27)
				)
			)
		)
		(property "Value" ""
			(at 0 0 270)
			(layer "F.Fab")
			(effects
				(font
					(size 1.27 1.27)
				)
			)
		)
		(duplicate_pad_numbers_are_jumpers no)
		(fp_line
			(start -0.7874 0.4064)
			(end -0.7874 -0.4064)
			(stroke
				(width 0.1524)
				(type default)
			)
			(layer "F.SilkS")
		)
		(fp_line
			(start 0.7874 0.4064)
			(end -0.7874 0.4064)
			(stroke
				(width 0.1524)
				(type default)
			)
			(layer "F.SilkS")
		)
		(fp_line
			(start -0.7874 -0.4064)
			(end 0.7874 -0.4064)
			(stroke
				(width 0.1524)
				(type default)
			)
			(layer "F.SilkS")
		)
		(fp_line
			(start 0.7874 -0.4064)
			(end 0.7874 0.4064)
			(stroke
				(width 0.1524)
				(type default)
			)
			(layer "F.SilkS")
		)
		(fp_line
			(start -0.67945 0.3048)
			(end -0.67945 -0.305054)
			(stroke
				(width 0.1)
				(type default)
			)
			(layer "F.Fab")
		)
		(fp_line
			(start -0.12065 0.3048)
			(end -0.67945 0.3048)
			(stroke
				(width 0.1)
				(type default)
			)
			(layer "F.Fab")
		)
		(fp_line
			(start 0.120396 0.3048)
			(end 0.120396 0.2794)
			(stroke
				(width 0.1)
				(type default)
			)
			(layer "F.Fab")
		)
		(fp_line
			(start 0.67945 0.3048)
			(end 0.120396 0.3048)
			(stroke
				(width 0.1)
				(type default)
			)
			(layer "F.Fab")
		)
		(fp_line
			(start -0.12065 0.2794)
			(end -0.12065 0.3048)
			(stroke
				(width 0.1)
				(type default)
			)
			(layer "F.Fab")
		)
		(fp_line
			(start 0.120396 0.2794)
			(end -0.12065 0.2794)
			(stroke
				(width 0.1)
				(type default)
			)
			(layer "F.Fab")
		)
		(fp_line
			(start -0.12065 -0.2794)
			(end 0.12065 -0.2794)
			(stroke
				(width 0.1)
				(type default)
			)
			(layer "F.Fab")
		)
		(fp_line
			(start 0.12065 -0.2794)
			(end 0.12065 -0.3048)
			(stroke
				(width 0.1)
				(type default)
			)
			(layer "F.Fab")
		)
		(fp_line
			(start 0.12065 -0.3048)
			(end 0.67945 -0.3048)
			(stroke
				(width 0.1)
				(type default)
			)
			(layer "F.Fab")
		)
		(fp_line
			(start 0.67945 -0.3048)
			(end 0.67945 0.3048)
			(stroke
				(width 0.1)
				(type default)
			)
			(layer "F.Fab")
		)
		(fp_line
			(start -0.67945 -0.305054)
			(end -0.12065 -0.305054)
			(stroke
				(width 0.1)
				(type default)
			)
			(layer "F.Fab")
		)
		(fp_line
			(start -0.12065 -0.305054)
			(end -0.12065 -0.2794)
			(stroke
				(width 0.1)
				(type default)
			)
			(layer "F.Fab")
		)
		(pad "1" smd circle
			(at -0.40005 0 270)
			(size 0 0)
			(layers "F.Cu" "F.Mask" "F.Paste")
			(net "SMB_PEX2_HOST_LS_SDA")
		)
		(pad "2" smd circle
			(at 0.40005 0 270)
			(size 0 0)
			(layers "F.Cu" "F.Mask" "F.Paste")
			(net "P3V3_AUX")
		)
	)
	(footprint ""
		(layer "F.Cu")
		(at 123.71324 -136.328404 180)
		(property "Reference" "PC325"
			(at 0 0 180)
			(layer "F.SilkS")
			(hide yes)
			(effects
				(font
					(size 1.27 1.27)
				)
			)
		)
		(property "Value" ""
			(at 0 0 180)
			(layer "F.Fab")
			(effects
				(font
					(size 1.27 1.27)
				)
			)
		)
		(duplicate_pad_numbers_are_jumpers no)
		(fp_line
			(start 0.7874 0.4064)
			(end -0.7874 0.4064)
			(stroke
				(width 0.1524)
				(type default)
			)
			(layer "F.SilkS")
		)
		(fp_line
			(start 0.7874 -0.4064)
			(end 0.7874 0.4064)
			(stroke
				(width 0.1524)
				(type default)
			)
			(layer "F.SilkS")
		)
		(fp_line
			(start -0.7874 0.4064)
			(end -0.7874 -0.4064)
			(stroke
				(width 0.1524)
				(type default)
			)
			(layer "F.SilkS")
		)
		(fp_line
			(start -0.7874 -0.4064)
			(end 0.7874 -0.4064)
			(stroke
				(width 0.1524)
				(type default)
			)
			(layer "F.SilkS")
		)
		(fp_line
			(start 0.67945 0.3048)
			(end 0.120396 0.3048)
			(stroke
				(width 0.1)
				(type default)
			)
			(layer "F.Fab")
		)
		(fp_line
			(start 0.67945 -0.3048)
			(end 0.67945 0.3048)
			(stroke
				(width 0.1)
				(type default)
			)
			(layer "F.Fab")
		)
		(fp_line
			(start 0.12065 -0.2794)
			(end 0.12065 -0.3048)
			(stroke
				(width 0.1)
				(type default)
			)
			(layer "F.Fab")
		)
		(fp_line
			(start 0.12065 -0.3048)
			(end 0.67945 -0.3048)
			(stroke
				(width 0.1)
				(type default)
			)
			(layer "F.Fab")
		)
		(fp_line
			(start 0.120396 0.3048)
			(end 0.120396 0.2794)
			(stroke
				(width 0.1)
				(type default)
			)
			(layer "F.Fab")
		)
		(fp_line
			(start 0.120396 0.2794)
			(end -0.12065 0.2794)
			(stroke
				(width 0.1)
				(type default)
			)
			(layer "F.Fab")
		)
		(fp_line
			(start -0.12065 0.3048)
			(end -0.67945 0.3048)
			(stroke
				(width 0.1)
				(type default)
			)
			(layer "F.Fab")
		)
		(fp_line
			(start -0.12065 0.2794)
			(end -0.12065 0.3048)
			(stroke
				(width 0.1)
				(type default)
			)
			(layer "F.Fab")
		)
		(fp_line
			(start -0.12065 -0.2794)
			(end 0.12065 -0.2794)
			(stroke
				(width 0.1)
				(type default)
			)
			(layer "F.Fab")
		)
		(fp_line
			(start -0.12065 -0.305054)
			(end -0.12065 -0.2794)
			(stroke
				(width 0.1)
				(type default)
			)
			(layer "F.Fab")
		)
		(fp_line
			(start -0.67945 0.3048)
			(end -0.67945 -0.305054)
			(stroke
				(width 0.1)
				(type default)
			)
			(layer "F.Fab")
		)
		(fp_line
			(start -0.67945 -0.305054)
			(end -0.12065 -0.305054)
			(stroke
				(width 0.1)
				(type default)
			)
			(layer "F.Fab")
		)
		(pad "1" smd circle
			(at -0.40005 0 180)
			(size 0 0)
			(layers "F.Cu" "F.Mask" "F.Paste")
			(net "P5V_AUX")
		)
		(pad "2" smd circle
			(at 0.40005 0 180)
			(size 0 0)
			(layers "F.Cu" "F.Mask" "F.Paste")
			(net "GND")
		)
	)
	(footprint ""
		(layer "F.Cu")
		(at 121.441972 -121.103136)
		(property "Reference" "PC596"
			(at 0 0 0)
			(layer "F.SilkS")
			(hide yes)
			(effects
				(font
					(size 1.27 1.27)
				)
			)
		)
		(property "Value" ""
			(at 0 0 0)
			(layer "F.Fab")
			(effects
				(font
					(size 1.27 1.27)
				)
			)
		)
		(duplicate_pad_numbers_are_jumpers no)
		(fp_line
			(start -0.7874 -0.4064)
			(end 0.7874 -0.4064)
			(stroke
				(width 0.1524)
				(type default)
			)
			(layer "F.SilkS")
		)
		(fp_line
			(start -0.7874 0.4064)
			(end -0.7874 -0.4064)
			(stroke
				(width 0.1524)
				(type default)
			)
			(layer "F.SilkS")
		)
		(fp_line
			(start 0.7874 -0.4064)
			(end 0.7874 0.4064)
			(stroke
				(width 0.1524)
				(type default)
			)
			(layer "F.SilkS")
		)
		(fp_line
			(start 0.7874 0.4064)
			(end -0.7874 0.4064)
			(stroke
				(width 0.1524)
				(type default)
			)
			(layer "F.SilkS")
		)
		(fp_line
			(start -0.67945 -0.305054)
			(end -0.12065 -0.305054)
			(stroke
				(width 0.1)
				(type default)
			)
			(layer "F.Fab")
		)
		(fp_line
			(start -0.67945 0.3048)
			(end -0.67945 -0.305054)
			(stroke
				(width 0.1)
				(type default)
			)
			(layer "F.Fab")
		)
		(fp_line
			(start -0.12065 -0.305054)
			(end -0.12065 -0.2794)
			(stroke
				(width 0.1)
				(type default)
			)
			(layer "F.Fab")
		)
		(fp_line
			(start -0.12065 -0.2794)
			(end 0.12065 -0.2794)
			(stroke
				(width 0.1)
				(type default)
			)
			(layer "F.Fab")
		)
		(fp_line
			(start -0.12065 0.2794)
			(end -0.12065 0.3048)
			(stroke
				(width 0.1)
				(type default)
			)
			(layer "F.Fab")
		)
		(fp_line
			(start -0.12065 0.3048)
			(end -0.67945 0.3048)
			(stroke
				(width 0.1)
				(type default)
			)
			(layer "F.Fab")
		)
		(fp_line
			(start 0.120396 0.2794)
			(end -0.12065 0.2794)
			(stroke
				(width 0.1)
				(type default)
			)
			(layer "F.Fab")
		)
		(fp_line
			(start 0.120396 0.3048)
			(end 0.120396 0.2794)
			(stroke
				(width 0.1)
				(type default)
			)
			(layer "F.Fab")
		)
		(fp_line
			(start 0.12065 -0.3048)
			(end 0.67945 -0.3048)
			(stroke
				(width 0.1)
				(type default)
			)
			(layer "F.Fab")
		)
		(fp_line
			(start 0.12065 -0.2794)
			(end 0.12065 -0.3048)
			(stroke
				(width 0.1)
				(type default)
			)
			(layer "F.Fab")
		)
		(fp_line
			(start 0.67945 -0.3048)
			(end 0.67945 0.3048)
			(stroke
				(width 0.1)
				(type default)
			)
			(layer "F.Fab")
		)
		(fp_line
			(start 0.67945 0.3048)
			(end 0.120396 0.3048)
			(stroke
				(width 0.1)
				(type default)
			)
			(layer "F.Fab")
		)
		(pad "1" smd circle
			(at -0.40005 0)
			(size 0 0)
			(layers "F.Cu" "F.Mask" "F.Paste")
			(net "P3V3_CO_MODE")
		)
		(pad "2" smd circle
			(at 0.40005 0)
			(size 0 0)
			(layers "F.Cu" "F.Mask" "F.Paste")
			(net "GND")
		)
	)
	(footprint ""
		(layer "F.Cu")
		(at 306.160932 -37.951156)
		(property "Reference" "Q227"
			(at 2.12344 -1.925574 0)
			(unlocked yes)
			(layer "F.SilkS")
			(effects
				(font
					(size 0.7874 0.5842)
					(thickness 0.1524)
				)
			)
		)
		(property "Value" ""
			(at 0 0 0)
			(layer "F.Fab")
			(effects
				(font
					(size 1.27 1.27)
				)
			)
		)
		(duplicate_pad_numbers_are_jumpers no)
		(fp_line
			(start -1.376172 -1.199896)
			(end -0.508 -1.199896)
			(stroke
				(width 0.1524)
				(type default)
			)
			(layer "F.SilkS")
		)
		(fp_line
			(start -1.376172 1.199896)
			(end -1.376172 -1.199896)
			(stroke
				(width 0.1524)
				(type default)
			)
			(layer "F.SilkS")
		)
		(fp_line
			(start -0.508 -1.199896)
			(end 0 -0.762)
			(stroke
				(width 0.1524)
				(type default)
			)
			(layer "F.SilkS")
		)
		(fp_line
			(start 0 -0.762)
			(end 0.508 -1.199896)
			(stroke
				(width 0.1524)
				(type default)
			)
			(layer "F.SilkS")
		)
		(fp_line
			(start 0.508 -1.199896)
			(end 1.376172 -1.199896)
			(stroke
				(width 0.1524)
				(type default)
			)
			(layer "F.SilkS")
		)
		(fp_line
			(start 1.376172 -1.199896)
			(end 1.376172 1.199896)
			(stroke
				(width 0.1524)
				(type default)
			)
			(layer "F.SilkS")
		)
		(fp_line
			(start 1.376172 1.199896)
			(end -1.376172 1.199896)
			(stroke
				(width 0.1524)
				(type default)
			)
			(layer "F.SilkS")
		)
		(fp_poly
			(pts
				(xy -1.462278 -0.9652) (xy -1.731772 -1.773428) (xy -2.270506 -1.234694)
			)
			(stroke
				(width 0)
				(type default)
			)
			(fill yes)
			(layer "F.SilkS")
		)
		(fp_line
			(start -0.674878 -1.100074)
			(end 0.674878 -1.100074)
			(stroke
				(width 0.1)
				(type default)
			)
			(layer "F.Fab")
		)
		(fp_line
			(start -0.674878 1.100074)
			(end -0.674878 -1.100074)
			(stroke
				(width 0.1)
				(type default)
			)
			(layer "F.Fab")
		)
		(fp_line
			(start 0.674878 -1.100074)
			(end 0.674878 1.100074)
			(stroke
				(width 0.1)
				(type default)
			)
			(layer "F.Fab")
		)
		(fp_line
			(start 0.674878 1.100074)
			(end -0.674878 1.100074)
			(stroke
				(width 0.1)
				(type default)
			)
			(layer "F.Fab")
		)
		(fp_poly
			(pts
				(xy -1.4605 -0.7493) (xy -2.2225 -1.1303) (xy -2.2225 -0.3683)
			)
			(stroke
				(width 0)
				(type default)
			)
			(fill yes)
			(layer "F.Fab")
		)
		(pad "1" smd rect
			(at -0.899922 -0.750062 270)
			(size 0.6096 0.6096)
			(layers "F.Cu" "F.Mask" "F.Paste")
			(net "GND")
		)
		(pad "2" smd rect
			(at -0.899922 0 270)
			(size 0.4064 0.6096)
			(layers "F.Cu" "F.Mask" "F.Paste")
			(net "P3V3_SSD11_PG_G1")
		)
		(pad "3" smd rect
			(at -0.899922 0.750062 270)
			(size 0.6096 0.6096)
			(layers "F.Cu" "F.Mask" "F.Paste")
			(net "PWRGD_P3V3_SSD11_D")
		)
		(pad "4" smd rect
			(at 0.899922 0.750062 270)
			(size 0.6096 0.6096)
			(layers "F.Cu" "F.Mask" "F.Paste")
			(net "GND")
		)
		(pad "5" smd rect
			(at 0.899922 0 270)
			(size 0.4064 0.6096)
			(layers "F.Cu" "F.Mask" "F.Paste")
			(net "P3V3_SSD11_PG_G2")
		)
		(pad "6" smd rect
			(at 0.899922 -0.750062 270)
			(size 0.6096 0.6096)
			(layers "F.Cu" "F.Mask" "F.Paste")
			(net "P3V3_SSD11_PG_G2")
		)
	)
	(footprint ""
		(layer "F.Cu")
		(at 136.445244 -98.100642 180)
		(property "Reference" "R1574"
			(at 0 0 180)
			(layer "F.SilkS")
			(hide yes)
			(effects
				(font
					(size 1.27 1.27)
				)
			)
		)
		(property "Value" ""
			(at 0 0 180)
			(layer "F.Fab")
			(effects
				(font
					(size 1.27 1.27)
				)
			)
		)
		(duplicate_pad_numbers_are_jumpers no)
		(fp_line
			(start 0.7874 0.4064)
			(end -0.7874 0.4064)
			(stroke
				(width 0.1524)
				(type default)
			)
			(layer "F.SilkS")
		)
		(fp_line
			(start 0.7874 -0.4064)
			(end 0.7874 0.4064)
			(stroke
				(width 0.1524)
				(type default)
			)
			(layer "F.SilkS")
		)
		(fp_line
			(start -0.7874 0.4064)
			(end -0.7874 -0.4064)
			(stroke
				(width 0.1524)
				(type default)
			)
			(layer "F.SilkS")
		)
		(fp_line
			(start -0.7874 -0.4064)
			(end 0.7874 -0.4064)
			(stroke
				(width 0.1524)
				(type default)
			)
			(layer "F.SilkS")
		)
		(fp_line
			(start 0.67945 0.3048)
			(end 0.120396 0.3048)
			(stroke
				(width 0.1)
				(type default)
			)
			(layer "F.Fab")
		)
		(fp_line
			(start 0.67945 -0.3048)
			(end 0.67945 0.3048)
			(stroke
				(width 0.1)
				(type default)
			)
			(layer "F.Fab")
		)
		(fp_line
			(start 0.12065 -0.2794)
			(end 0.12065 -0.3048)
			(stroke
				(width 0.1)
				(type default)
			)
			(layer "F.Fab")
		)
		(fp_line
			(start 0.12065 -0.3048)
			(end 0.67945 -0.3048)
			(stroke
				(width 0.1)
				(type default)
			)
			(layer "F.Fab")
		)
		(fp_line
			(start 0.120396 0.3048)
			(end 0.120396 0.2794)
			(stroke
				(width 0.1)
				(type default)
			)
			(layer "F.Fab")
		)
		(fp_line
			(start 0.120396 0.2794)
			(end -0.12065 0.2794)
			(stroke
				(width 0.1)
				(type default)
			)
			(layer "F.Fab")
		)
		(fp_line
			(start -0.12065 0.3048)
			(end -0.67945 0.3048)
			(stroke
				(width 0.1)
				(type default)
			)
			(layer "F.Fab")
		)
		(fp_line
			(start -0.12065 0.2794)
			(end -0.12065 0.3048)
			(stroke
				(width 0.1)
				(type default)
			)
			(layer "F.Fab")
		)
		(fp_line
			(start -0.12065 -0.2794)
			(end 0.12065 -0.2794)
			(stroke
				(width 0.1)
				(type default)
			)
			(layer "F.Fab")
		)
		(fp_line
			(start -0.12065 -0.305054)
			(end -0.12065 -0.2794)
			(stroke
				(width 0.1)
				(type default)
			)
			(layer "F.Fab")
		)
		(fp_line
			(start -0.67945 0.3048)
			(end -0.67945 -0.305054)
			(stroke
				(width 0.1)
				(type default)
			)
			(layer "F.Fab")
		)
		(fp_line
			(start -0.67945 -0.305054)
			(end -0.12065 -0.305054)
			(stroke
				(width 0.1)
				(type default)
			)
			(layer "F.Fab")
		)
		(pad "1" smd circle
			(at -0.40005 0 180)
			(size 0 0)
			(layers "F.Cu" "F.Mask" "F.Paste")
			(net "SMB_BIC_I2C9_SSD_MUX_R_SCL")
		)
		(pad "2" smd circle
			(at 0.40005 0 180)
			(size 0 0)
			(layers "F.Cu" "F.Mask" "F.Paste")
			(net "SMB_BIC_I2C9_SSD_MUX0_SCL")
		)
	)
	(footprint ""
		(layer "F.Cu")
		(at 31.754318 -48.21809)
		(property "Reference" "PD62"
			(at -3.306318 2.24536 0)
			(unlocked yes)
			(layer "F.SilkS")
			(effects
				(font
					(size 0.7874 0.5842)
					(thickness 0.1524)
				)
				(justify left)
			)
		)
		(property "Value" ""
			(at 0 0 0)
			(layer "F.Fab")
			(effects
				(font
					(size 1.27 1.27)
				)
			)
		)
		(duplicate_pad_numbers_are_jumpers no)
		(fp_line
			(start -3.400044 -1.459992)
			(end 4.107942 -1.459992)
			(stroke
				(width 0.1524)
				(type default)
			)
			(layer "F.SilkS")
		)
		(fp_line
			(start -3.400044 1.459992)
			(end -3.400044 -1.459992)
			(stroke
				(width 0.1524)
				(type default)
			)
			(layer "F.SilkS")
		)
		(fp_line
			(start 4.107942 -1.459992)
			(end 4.107942 1.459992)
			(stroke
				(width 0.1524)
				(type default)
			)
			(layer "F.SilkS")
		)
		(fp_line
			(start 4.107942 1.459992)
			(end -3.400044 1.459992)
			(stroke
				(width 0.1524)
				(type default)
			)
			(layer "F.SilkS")
		)
		(fp_poly
			(pts
				(xy 4.107942 -1.459992) (xy 4.107942 1.459992) (xy 3.308096 1.459992) (xy 3.308096 -1.459992)
			)
			(stroke
				(width 0)
				(type default)
			)
			(fill yes)
			(layer "F.SilkS")
		)
		(fp_line
			(start -2.29997 -1.459992)
			(end 2.29997 -1.459992)
			(stroke
				(width 0.1)
				(type default)
			)
			(layer "F.Fab")
		)
		(fp_line
			(start -2.29997 1.459992)
			(end -2.29997 -1.459992)
			(stroke
				(width 0.1)
				(type default)
			)
			(layer "F.Fab")
		)
		(fp_line
			(start 2.29997 -1.459992)
			(end 2.29997 1.459992)
			(stroke
				(width 0.1)
				(type default)
			)
			(layer "F.Fab")
		)
		(fp_line
			(start 2.29997 1.459992)
			(end -2.29997 1.459992)
			(stroke
				(width 0.1)
				(type default)
			)
			(layer "F.Fab")
		)
		(fp_text user "+"
			(at -4.7752 -0.12065 0)
			(unlocked yes)
			(layer "F.SilkS")
			(effects
				(font
					(size 1.905 1.4224)
					(thickness 0.1524)
				)
				(justify left)
			)
		)
		(fp_text user "-"
			(at 5.4102 0.29845 180)
			(unlocked yes)
			(layer "F.SilkS")
			(effects
				(font
					(size 1.905 1.4224)
					(thickness 0.1524)
				)
				(justify left)
			)
		)
		(fp_text user "+"
			(at -4.7752 -0.12065 0)
			(unlocked yes)
			(layer "F.Fab")
			(effects
				(font
					(size 1.905 1.4224)
					(thickness 0.1524)
				)
				(justify left)
			)
		)
		(fp_text user "-"
			(at 5.4102 0.29845 180)
			(unlocked yes)
			(layer "F.Fab")
			(effects
				(font
					(size 1.905 1.4224)
					(thickness 0.1524)
				)
				(justify left)
			)
		)
		(pad "A" smd rect
			(at -1.999996 0 90)
			(size 1.7018 2.5146)
			(layers "F.Cu" "F.Mask" "F.Paste")
			(net "GND")
		)
		(pad "C" smd rect
			(at 1.999996 0 90)
			(size 1.7018 2.5146)
			(layers "F.Cu" "F.Mask" "F.Paste")
			(net "P3V3_SSD1")
		)
	)
	(footprint ""
		(layer "F.Cu")
		(at 162.160712 -350.098614 90)
		(property "Reference" "C2512"
			(at 0 0 90)
			(layer "F.SilkS")
			(hide yes)
			(effects
				(font
					(size 1.27 1.27)
				)
			)
		)
		(property "Value" ""
			(at 0 0 90)
			(layer "F.Fab")
			(effects
				(font
					(size 1.27 1.27)
				)
			)
		)
		(duplicate_pad_numbers_are_jumpers no)
		(fp_line
			(start 0.299974 -0.150114)
			(end 0.299974 0.150114)
			(stroke
				(width 0.1)
				(type default)
			)
			(layer "F.Fab")
		)
		(fp_line
			(start -0.299974 -0.150114)
			(end 0.299974 -0.150114)
			(stroke
				(width 0.1)
				(type default)
			)
			(layer "F.Fab")
		)
		(fp_line
			(start 0.299974 0.150114)
			(end -0.299974 0.150114)
			(stroke
				(width 0.1)
				(type default)
			)
			(layer "F.Fab")
		)
		(fp_line
			(start -0.299974 0.150114)
			(end -0.299974 -0.150114)
			(stroke
				(width 0.1)
				(type default)
			)
			(layer "F.Fab")
		)
		(pad "1" smd rect
			(at -0.2667 0 90)
			(size 0.3048 0.381)
			(layers "F.Cu" "F.Mask" "F.Paste")
			(net "P5E_PEX1_STN4_TX_DP<79>")
		)
		(pad "2" smd rect
			(at 0.2667 0 90)
			(size 0.3048 0.381)
			(layers "F.Cu" "F.Mask" "F.Paste")
			(net "P5E_PEX1_STN4_TX_C_DP<79>")
		)
	)
	(footprint ""
		(layer "F.Cu")
		(at 172.947838 -40.037258 90)
		(property "Reference" "U369"
			(at 0.399542 2.313432 90)
			(unlocked yes)
			(layer "F.SilkS")
			(effects
				(font
					(size 0.7874 0.5842)
					(thickness 0.1524)
				)
			)
		)
		(property "Value" ""
			(at 0 0 90)
			(layer "F.Fab")
			(effects
				(font
					(size 1.27 1.27)
				)
			)
		)
		(duplicate_pad_numbers_are_jumpers no)
		(fp_line
			(start -1.949958 -1.610106)
			(end 1.949958 -1.610106)
			(stroke
				(width 0.1524)
				(type default)
			)
			(layer "F.SilkS")
		)
		(fp_line
			(start 1.949958 -1.560068)
			(end 1.949958 1.610106)
			(stroke
				(width 0.1524)
				(type default)
			)
			(layer "F.SilkS")
		)
		(fp_line
			(start 1.949958 1.610106)
			(end -1.949958 1.610106)
			(stroke
				(width 0.1524)
				(type default)
			)
			(layer "F.SilkS")
		)
		(fp_line
			(start -1.949958 1.610106)
			(end -1.949958 -1.610106)
			(stroke
				(width 0.1524)
				(type default)
			)
			(layer "F.SilkS")
		)
		(fp_line
			(start 0.750062 -1.560068)
			(end 0.750062 1.560068)
			(stroke
				(width 0.1)
				(type default)
			)
			(layer "F.Fab")
		)
		(fp_line
			(start -0.750062 -1.560068)
			(end 0.750062 -1.560068)
			(stroke
				(width 0.1)
				(type default)
			)
			(layer "F.Fab")
		)
		(fp_line
			(start 0.750062 1.560068)
			(end -0.750062 1.560068)
			(stroke
				(width 0.1)
				(type default)
			)
			(layer "F.Fab")
		)
		(fp_line
			(start -0.750062 1.560068)
			(end -0.750062 -1.560068)
			(stroke
				(width 0.1)
				(type default)
			)
			(layer "F.Fab")
		)
		(pad "D" smd rect
			(at 1.100074 0)
			(size 1.016 1.4224)
			(layers "F.Cu" "F.Mask" "F.Paste")
			(net "SSD6_AUX_P3V3_EN")
		)
		(pad "G" smd rect
			(at -1.100074 -0.94996)
			(size 1.016 1.4224)
			(layers "F.Cu" "F.Mask" "F.Paste")
			(net "PRSNT_SSD6_R1_N")
		)
		(pad "S" smd rect
			(at -1.100074 0.94996)
			(size 1.016 1.4224)
			(layers "F.Cu" "F.Mask" "F.Paste")
			(net "GND")
		)
	)
	(footprint ""
		(layer "F.Cu")
		(at 386.899912 -151.279352 180)
		(property "Reference" "R322"
			(at 0 0 180)
			(layer "F.SilkS")
			(hide yes)
			(effects
				(font
					(size 1.27 1.27)
				)
			)
		)
		(property "Value" ""
			(at 0 0 180)
			(layer "F.Fab")
			(effects
				(font
					(size 1.27 1.27)
				)
			)
		)
		(duplicate_pad_numbers_are_jumpers no)
		(fp_line
			(start 0.7874 0.4064)
			(end -0.7874 0.4064)
			(stroke
				(width 0.1524)
				(type default)
			)
			(layer "F.SilkS")
		)
		(fp_line
			(start 0.7874 -0.4064)
			(end 0.7874 0.4064)
			(stroke
				(width 0.1524)
				(type default)
			)
			(layer "F.SilkS")
		)
		(fp_line
			(start -0.7874 0.4064)
			(end -0.7874 -0.4064)
			(stroke
				(width 0.1524)
				(type default)
			)
			(layer "F.SilkS")
		)
		(fp_line
			(start -0.7874 -0.4064)
			(end 0.7874 -0.4064)
			(stroke
				(width 0.1524)
				(type default)
			)
			(layer "F.SilkS")
		)
		(fp_line
			(start 0.67945 0.3048)
			(end 0.120396 0.3048)
			(stroke
				(width 0.1)
				(type default)
			)
			(layer "F.Fab")
		)
		(fp_line
			(start 0.67945 -0.3048)
			(end 0.67945 0.3048)
			(stroke
				(width 0.1)
				(type default)
			)
			(layer "F.Fab")
		)
		(fp_line
			(start 0.12065 -0.2794)
			(end 0.12065 -0.3048)
			(stroke
				(width 0.1)
				(type default)
			)
			(layer "F.Fab")
		)
		(fp_line
			(start 0.12065 -0.3048)
			(end 0.67945 -0.3048)
			(stroke
				(width 0.1)
				(type default)
			)
			(layer "F.Fab")
		)
		(fp_line
			(start 0.120396 0.3048)
			(end 0.120396 0.2794)
			(stroke
				(width 0.1)
				(type default)
			)
			(layer "F.Fab")
		)
		(fp_line
			(start 0.120396 0.2794)
			(end -0.12065 0.2794)
			(stroke
				(width 0.1)
				(type default)
			)
			(layer "F.Fab")
		)
		(fp_line
			(start -0.12065 0.3048)
			(end -0.67945 0.3048)
			(stroke
				(width 0.1)
				(type default)
			)
			(layer "F.Fab")
		)
		(fp_line
			(start -0.12065 0.2794)
			(end -0.12065 0.3048)
			(stroke
				(width 0.1)
				(type default)
			)
			(layer "F.Fab")
		)
		(fp_line
			(start -0.12065 -0.2794)
			(end 0.12065 -0.2794)
			(stroke
				(width 0.1)
				(type default)
			)
			(layer "F.Fab")
		)
		(fp_line
			(start -0.12065 -0.305054)
			(end -0.12065 -0.2794)
			(stroke
				(width 0.1)
				(type default)
			)
			(layer "F.Fab")
		)
		(fp_line
			(start -0.67945 0.3048)
			(end -0.67945 -0.305054)
			(stroke
				(width 0.1)
				(type default)
			)
			(layer "F.Fab")
		)
		(fp_line
			(start -0.67945 -0.305054)
			(end -0.12065 -0.305054)
			(stroke
				(width 0.1)
				(type default)
			)
			(layer "F.Fab")
		)
		(pad "1" smd circle
			(at -0.40005 0 180)
			(size 0 0)
			(layers "F.Cu" "F.Mask" "F.Paste")
			(net "NCSI_NIC6_RXD0")
		)
		(pad "2" smd circle
			(at 0.40005 0 180)
			(size 0 0)
			(layers "F.Cu" "F.Mask" "F.Paste")
			(net "GND")
		)
	)
	(footprint ""
		(layer "F.Cu")
		(at 145.697956 -198.2978)
		(property "Reference" "R6642"
			(at 0 0 0)
			(layer "F.SilkS")
			(hide yes)
			(effects
				(font
					(size 1.27 1.27)
				)
			)
		)
		(property "Value" ""
			(at 0 0 0)
			(layer "F.Fab")
			(effects
				(font
					(size 1.27 1.27)
				)
			)
		)
		(duplicate_pad_numbers_are_jumpers no)
		(fp_line
			(start -0.7874 -0.4064)
			(end 0.7874 -0.4064)
			(stroke
				(width 0.1524)
				(type default)
			)
			(layer "F.SilkS")
		)
		(fp_line
			(start -0.7874 0.4064)
			(end -0.7874 -0.4064)
			(stroke
				(width 0.1524)
				(type default)
			)
			(layer "F.SilkS")
		)
		(fp_line
			(start 0.7874 -0.4064)
			(end 0.7874 0.4064)
			(stroke
				(width 0.1524)
				(type default)
			)
			(layer "F.SilkS")
		)
		(fp_line
			(start 0.7874 0.4064)
			(end -0.7874 0.4064)
			(stroke
				(width 0.1524)
				(type default)
			)
			(layer "F.SilkS")
		)
		(fp_line
			(start -0.67945 -0.305054)
			(end -0.12065 -0.305054)
			(stroke
				(width 0.1)
				(type default)
			)
			(layer "F.Fab")
		)
		(fp_line
			(start -0.67945 0.3048)
			(end -0.67945 -0.305054)
			(stroke
				(width 0.1)
				(type default)
			)
			(layer "F.Fab")
		)
		(fp_line
			(start -0.12065 -0.305054)
			(end -0.12065 -0.2794)
			(stroke
				(width 0.1)
				(type default)
			)
			(layer "F.Fab")
		)
		(fp_line
			(start -0.12065 -0.2794)
			(end 0.12065 -0.2794)
			(stroke
				(width 0.1)
				(type default)
			)
			(layer "F.Fab")
		)
		(fp_line
			(start -0.12065 0.2794)
			(end -0.12065 0.3048)
			(stroke
				(width 0.1)
				(type default)
			)
			(layer "F.Fab")
		)
		(fp_line
			(start -0.12065 0.3048)
			(end -0.67945 0.3048)
			(stroke
				(width 0.1)
				(type default)
			)
			(layer "F.Fab")
		)
		(fp_line
			(start 0.120396 0.2794)
			(end -0.12065 0.2794)
			(stroke
				(width 0.1)
				(type default)
			)
			(layer "F.Fab")
		)
		(fp_line
			(start 0.120396 0.3048)
			(end 0.120396 0.2794)
			(stroke
				(width 0.1)
				(type default)
			)
			(layer "F.Fab")
		)
		(fp_line
			(start 0.12065 -0.3048)
			(end 0.67945 -0.3048)
			(stroke
				(width 0.1)
				(type default)
			)
			(layer "F.Fab")
		)
		(fp_line
			(start 0.12065 -0.2794)
			(end 0.12065 -0.3048)
			(stroke
				(width 0.1)
				(type default)
			)
			(layer "F.Fab")
		)
		(fp_line
			(start 0.67945 -0.3048)
			(end 0.67945 0.3048)
			(stroke
				(width 0.1)
				(type default)
			)
			(layer "F.Fab")
		)
		(fp_line
			(start 0.67945 0.3048)
			(end 0.120396 0.3048)
			(stroke
				(width 0.1)
				(type default)
			)
			(layer "F.Fab")
		)
		(pad "1" smd circle
			(at -0.40005 0)
			(size 0 0)
			(layers "F.Cu" "F.Mask" "F.Paste")
			(net "UART_PEX1_CLI_RX")
		)
		(pad "2" smd circle
			(at 0.40005 0)
			(size 0 0)
			(layers "F.Cu" "F.Mask" "F.Paste")
			(net "UART_PEX1_CLI_R_RX")
		)
	)
	(footprint ""
		(layer "F.Cu")
		(at 205.578964 -308.323488 135)
		(property "Reference" "R1321"
			(at 0 0 135)
			(layer "F.SilkS")
			(hide yes)
			(effects
				(font
					(size 1.27 1.27)
				)
			)
		)
		(property "Value" ""
			(at 0 0 135)
			(layer "F.Fab")
			(effects
				(font
					(size 1.27 1.27)
				)
			)
		)
		(duplicate_pad_numbers_are_jumpers no)
		(fp_line
			(start 0.787389 -0.406267)
			(end 0.787389 0.406267)
			(stroke
				(width 0.1524)
				(type default)
			)
			(layer "F.SilkS")
		)
		(fp_line
			(start 0.787389 0.406267)
			(end -0.787389 0.406267)
			(stroke
				(width 0.1524)
				(type default)
			)
			(layer "F.SilkS")
		)
		(fp_line
			(start -0.787389 -0.406267)
			(end 0.787389 -0.406267)
			(stroke
				(width 0.1524)
				(type default)
			)
			(layer "F.SilkS")
		)
		(fp_line
			(start -0.787389 0.406267)
			(end -0.787389 -0.406267)
			(stroke
				(width 0.1524)
				(type default)
			)
			(layer "F.SilkS")
		)
		(fp_line
			(start 0.679446 -0.30479)
			(end 0.679446 0.30479)
			(stroke
				(width 0.1)
				(type default)
			)
			(layer "F.Fab")
		)
		(fp_line
			(start 0.120515 -0.30479)
			(end 0.679446 -0.30479)
			(stroke
				(width 0.1)
				(type default)
			)
			(layer "F.Fab")
		)
		(fp_line
			(start 0.120695 -0.279466)
			(end 0.120515 -0.30479)
			(stroke
				(width 0.1)
				(type default)
			)
			(layer "F.Fab")
		)
		(fp_line
			(start 0.679446 0.30479)
			(end 0.120515 0.30479)
			(stroke
				(width 0.1)
				(type default)
			)
			(layer "F.Fab")
		)
		(fp_line
			(start -0.120695 -0.304969)
			(end -0.120695 -0.279466)
			(stroke
				(width 0.1)
				(type default)
			)
			(layer "F.Fab")
		)
		(fp_line
			(start -0.120695 -0.279466)
			(end 0.120695 -0.279466)
			(stroke
				(width 0.1)
				(type default)
			)
			(layer "F.Fab")
		)
		(fp_line
			(start 0.120335 0.279466)
			(end -0.120695 0.279466)
			(stroke
				(width 0.1)
				(type default)
			)
			(layer "F.Fab")
		)
		(fp_line
			(start 0.120515 0.30479)
			(end 0.120335 0.279466)
			(stroke
				(width 0.1)
				(type default)
			)
			(layer "F.Fab")
		)
		(fp_line
			(start -0.679446 -0.305149)
			(end -0.120695 -0.304969)
			(stroke
				(width 0.1)
				(type default)
			)
			(layer "F.Fab")
		)
		(fp_line
			(start -0.120695 0.279466)
			(end -0.120515 0.30479)
			(stroke
				(width 0.1)
				(type default)
			)
			(layer "F.Fab")
		)
		(fp_line
			(start -0.120515 0.30479)
			(end -0.679446 0.30479)
			(stroke
				(width 0.1)
				(type default)
			)
			(layer "F.Fab")
		)
		(fp_line
			(start -0.679446 0.30479)
			(end -0.679446 -0.305149)
			(stroke
				(width 0.1)
				(type default)
			)
			(layer "F.Fab")
		)
		(pad "1" smd circle
			(at -0.40005 0 135)
			(size 0 0)
			(layers "F.Cu" "F.Mask" "F.Paste")
			(net "GND")
		)
		(pad "2" smd circle
			(at 0.40005 0 135)
			(size 0 0)
			(layers "F.Cu" "F.Mask" "F.Paste")
			(net "PEX1_SPARE7")
		)
	)
	(footprint ""
		(layer "F.Cu")
		(at 356.17531 -252.416564 90)
		(property "Reference" "R837"
			(at 0 0 90)
			(layer "F.SilkS")
			(hide yes)
			(effects
				(font
					(size 1.27 1.27)
				)
			)
		)
		(property "Value" ""
			(at 0 0 90)
			(layer "F.Fab")
			(effects
				(font
					(size 1.27 1.27)
				)
			)
		)
		(duplicate_pad_numbers_are_jumpers no)
		(fp_line
			(start 0.7874 -0.4064)
			(end 0.7874 0.4064)
			(stroke
				(width 0.1524)
				(type default)
			)
			(layer "F.SilkS")
		)
		(fp_line
			(start -0.7874 -0.4064)
			(end 0.7874 -0.4064)
			(stroke
				(width 0.1524)
				(type default)
			)
			(layer "F.SilkS")
		)
		(fp_line
			(start 0.7874 0.4064)
			(end -0.7874 0.4064)
			(stroke
				(width 0.1524)
				(type default)
			)
			(layer "F.SilkS")
		)
		(fp_line
			(start -0.7874 0.4064)
			(end -0.7874 -0.4064)
			(stroke
				(width 0.1524)
				(type default)
			)
			(layer "F.SilkS")
		)
		(fp_line
			(start -0.12065 -0.305054)
			(end -0.12065 -0.2794)
			(stroke
				(width 0.1)
				(type default)
			)
			(layer "F.Fab")
		)
		(fp_line
			(start -0.67945 -0.305054)
			(end -0.12065 -0.305054)
			(stroke
				(width 0.1)
				(type default)
			)
			(layer "F.Fab")
		)
		(fp_line
			(start 0.67945 -0.3048)
			(end 0.67945 0.3048)
			(stroke
				(width 0.1)
				(type default)
			)
			(layer "F.Fab")
		)
		(fp_line
			(start 0.12065 -0.3048)
			(end 0.67945 -0.3048)
			(stroke
				(width 0.1)
				(type default)
			)
			(layer "F.Fab")
		)
		(fp_line
			(start 0.12065 -0.2794)
			(end 0.12065 -0.3048)
			(stroke
				(width 0.1)
				(type default)
			)
			(layer "F.Fab")
		)
		(fp_line
			(start -0.12065 -0.2794)
			(end 0.12065 -0.2794)
			(stroke
				(width 0.1)
				(type default)
			)
			(layer "F.Fab")
		)
		(fp_line
			(start 0.120396 0.2794)
			(end -0.12065 0.2794)
			(stroke
				(width 0.1)
				(type default)
			)
			(layer "F.Fab")
		)
		(fp_line
			(start -0.12065 0.2794)
			(end -0.12065 0.3048)
			(stroke
				(width 0.1)
				(type default)
			)
			(layer "F.Fab")
		)
		(fp_line
			(start 0.67945 0.3048)
			(end 0.120396 0.3048)
			(stroke
				(width 0.1)
				(type default)
			)
			(layer "F.Fab")
		)
		(fp_line
			(start 0.120396 0.3048)
			(end 0.120396 0.2794)
			(stroke
				(width 0.1)
				(type default)
			)
			(layer "F.Fab")
		)
		(fp_line
			(start -0.12065 0.3048)
			(end -0.67945 0.3048)
			(stroke
				(width 0.1)
				(type default)
			)
			(layer "F.Fab")
		)
		(fp_line
			(start -0.67945 0.3048)
			(end -0.67945 -0.305054)
			(stroke
				(width 0.1)
				(type default)
			)
			(layer "F.Fab")
		)
		(pad "1" smd circle
			(at -0.40005 0 90)
			(size 0 0)
			(layers "F.Cu" "F.Mask" "F.Paste")
			(net "SMB_BIC_I2C6_MUX_VR_R_SDA")
		)
		(pad "2" smd circle
			(at 0.40005 0 90)
			(size 0 0)
			(layers "F.Cu" "F.Mask" "F.Paste")
			(net "SMB_VR_P0V8_PEX2_SDA")
		)
	)
	(footprint ""
		(layer "F.Cu")
		(at 102.987094 -397.512286 90)
		(property "Reference" "R5443"
			(at 0 0 90)
			(layer "F.SilkS")
			(hide yes)
			(effects
				(font
					(size 1.27 1.27)
				)
			)
		)
		(property "Value" ""
			(at 0 0 90)
			(layer "F.Fab")
			(effects
				(font
					(size 1.27 1.27)
				)
			)
		)
		(duplicate_pad_numbers_are_jumpers no)
		(fp_line
			(start 0.7874 -0.4064)
			(end 0.7874 0.4064)
			(stroke
				(width 0.1524)
				(type default)
			)
			(layer "F.SilkS")
		)
		(fp_line
			(start -0.7874 -0.4064)
			(end 0.7874 -0.4064)
			(stroke
				(width 0.1524)
				(type default)
			)
			(layer "F.SilkS")
		)
		(fp_line
			(start 0.7874 0.4064)
			(end -0.7874 0.4064)
			(stroke
				(width 0.1524)
				(type default)
			)
			(layer "F.SilkS")
		)
		(fp_line
			(start -0.7874 0.4064)
			(end -0.7874 -0.4064)
			(stroke
				(width 0.1524)
				(type default)
			)
			(layer "F.SilkS")
		)
		(fp_line
			(start -0.12065 -0.305054)
			(end -0.12065 -0.2794)
			(stroke
				(width 0.1)
				(type default)
			)
			(layer "F.Fab")
		)
		(fp_line
			(start -0.67945 -0.305054)
			(end -0.12065 -0.305054)
			(stroke
				(width 0.1)
				(type default)
			)
			(layer "F.Fab")
		)
		(fp_line
			(start 0.67945 -0.3048)
			(end 0.67945 0.3048)
			(stroke
				(width 0.1)
				(type default)
			)
			(layer "F.Fab")
		)
		(fp_line
			(start 0.12065 -0.3048)
			(end 0.67945 -0.3048)
			(stroke
				(width 0.1)
				(type default)
			)
			(layer "F.Fab")
		)
		(fp_line
			(start 0.12065 -0.2794)
			(end 0.12065 -0.3048)
			(stroke
				(width 0.1)
				(type default)
			)
			(layer "F.Fab")
		)
		(fp_line
			(start -0.12065 -0.2794)
			(end 0.12065 -0.2794)
			(stroke
				(width 0.1)
				(type default)
			)
			(layer "F.Fab")
		)
		(fp_line
			(start 0.120396 0.2794)
			(end -0.12065 0.2794)
			(stroke
				(width 0.1)
				(type default)
			)
			(layer "F.Fab")
		)
		(fp_line
			(start -0.12065 0.2794)
			(end -0.12065 0.3048)
			(stroke
				(width 0.1)
				(type default)
			)
			(layer "F.Fab")
		)
		(fp_line
			(start 0.67945 0.3048)
			(end 0.120396 0.3048)
			(stroke
				(width 0.1)
				(type default)
			)
			(layer "F.Fab")
		)
		(fp_line
			(start 0.120396 0.3048)
			(end 0.120396 0.2794)
			(stroke
				(width 0.1)
				(type default)
			)
			(layer "F.Fab")
		)
		(fp_line
			(start -0.12065 0.3048)
			(end -0.67945 0.3048)
			(stroke
				(width 0.1)
				(type default)
			)
			(layer "F.Fab")
		)
		(fp_line
			(start -0.67945 0.3048)
			(end -0.67945 -0.305054)
			(stroke
				(width 0.1)
				(type default)
			)
			(layer "F.Fab")
		)
		(pad "1" smd circle
			(at -0.40005 0 90)
			(size 0 0)
			(layers "F.Cu" "F.Mask" "F.Paste")
			(net "BIC_USB_HUB_TEST")
		)
		(pad "2" smd circle
			(at 0.40005 0 90)
			(size 0 0)
			(layers "F.Cu" "F.Mask" "F.Paste")
			(net "GND")
		)
	)
	(footprint ""
		(layer "F.Cu")
		(at 184.491884 -196.122798 180)
		(property "Reference" "R469"
			(at 0 0 180)
			(layer "F.SilkS")
			(hide yes)
			(effects
				(font
					(size 1.27 1.27)
				)
			)
		)
		(property "Value" ""
			(at 0 0 180)
			(layer "F.Fab")
			(effects
				(font
					(size 1.27 1.27)
				)
			)
		)
		(duplicate_pad_numbers_are_jumpers no)
		(fp_line
			(start 0.7874 0.4064)
			(end -0.7874 0.4064)
			(stroke
				(width 0.1524)
				(type default)
			)
			(layer "F.SilkS")
		)
		(fp_line
			(start 0.7874 -0.4064)
			(end 0.7874 0.4064)
			(stroke
				(width 0.1524)
				(type default)
			)
			(layer "F.SilkS")
		)
		(fp_line
			(start -0.7874 0.4064)
			(end -0.7874 -0.4064)
			(stroke
				(width 0.1524)
				(type default)
			)
			(layer "F.SilkS")
		)
		(fp_line
			(start -0.7874 -0.4064)
			(end 0.7874 -0.4064)
			(stroke
				(width 0.1524)
				(type default)
			)
			(layer "F.SilkS")
		)
		(fp_line
			(start 0.67945 0.3048)
			(end 0.120396 0.3048)
			(stroke
				(width 0.1)
				(type default)
			)
			(layer "F.Fab")
		)
		(fp_line
			(start 0.67945 -0.3048)
			(end 0.67945 0.3048)
			(stroke
				(width 0.1)
				(type default)
			)
			(layer "F.Fab")
		)
		(fp_line
			(start 0.12065 -0.2794)
			(end 0.12065 -0.3048)
			(stroke
				(width 0.1)
				(type default)
			)
			(layer "F.Fab")
		)
		(fp_line
			(start 0.12065 -0.3048)
			(end 0.67945 -0.3048)
			(stroke
				(width 0.1)
				(type default)
			)
			(layer "F.Fab")
		)
		(fp_line
			(start 0.120396 0.3048)
			(end 0.120396 0.2794)
			(stroke
				(width 0.1)
				(type default)
			)
			(layer "F.Fab")
		)
		(fp_line
			(start 0.120396 0.2794)
			(end -0.12065 0.2794)
			(stroke
				(width 0.1)
				(type default)
			)
			(layer "F.Fab")
		)
		(fp_line
			(start -0.12065 0.3048)
			(end -0.67945 0.3048)
			(stroke
				(width 0.1)
				(type default)
			)
			(layer "F.Fab")
		)
		(fp_line
			(start -0.12065 0.2794)
			(end -0.12065 0.3048)
			(stroke
				(width 0.1)
				(type default)
			)
			(layer "F.Fab")
		)
		(fp_line
			(start -0.12065 -0.2794)
			(end 0.12065 -0.2794)
			(stroke
				(width 0.1)
				(type default)
			)
			(layer "F.Fab")
		)
		(fp_line
			(start -0.12065 -0.305054)
			(end -0.12065 -0.2794)
			(stroke
				(width 0.1)
				(type default)
			)
			(layer "F.Fab")
		)
		(fp_line
			(start -0.67945 0.3048)
			(end -0.67945 -0.305054)
			(stroke
				(width 0.1)
				(type default)
			)
			(layer "F.Fab")
		)
		(fp_line
			(start -0.67945 -0.305054)
			(end -0.12065 -0.305054)
			(stroke
				(width 0.1)
				(type default)
			)
			(layer "F.Fab")
		)
		(pad "1" smd circle
			(at -0.40005 0 180)
			(size 0 0)
			(layers "F.Cu" "F.Mask" "F.Paste")
			(net "SPI_BIC1_CS0_R1_N")
		)
		(pad "2" smd circle
			(at 0.40005 0 180)
			(size 0 0)
			(layers "F.Cu" "F.Mask" "F.Paste")
			(net "SPI_BIC1_CS0_R2_N")
		)
	)
	(footprint ""
		(layer "F.Cu")
		(at 193.250312 -343.952322 90)
		(property "Reference" "C372"
			(at 0 0 90)
			(layer "F.SilkS")
			(hide yes)
			(effects
				(font
					(size 1.27 1.27)
				)
			)
		)
		(property "Value" ""
			(at 0 0 90)
			(layer "F.Fab")
			(effects
				(font
					(size 1.27 1.27)
				)
			)
		)
		(duplicate_pad_numbers_are_jumpers no)
		(fp_line
			(start 0.299974 -0.150114)
			(end 0.299974 0.150114)
			(stroke
				(width 0.1)
				(type default)
			)
			(layer "F.Fab")
		)
		(fp_line
			(start -0.299974 -0.150114)
			(end 0.299974 -0.150114)
			(stroke
				(width 0.1)
				(type default)
			)
			(layer "F.Fab")
		)
		(fp_line
			(start 0.299974 0.150114)
			(end -0.299974 0.150114)
			(stroke
				(width 0.1)
				(type default)
			)
			(layer "F.Fab")
		)
		(fp_line
			(start -0.299974 0.150114)
			(end -0.299974 -0.150114)
			(stroke
				(width 0.1)
				(type default)
			)
			(layer "F.Fab")
		)
		(pad "1" smd rect
			(at -0.2667 0 90)
			(size 0.3048 0.381)
			(layers "F.Cu" "F.Mask" "F.Paste")
			(net "P5E_PEX1_STN7_TX_DP<127>")
		)
		(pad "2" smd rect
			(at 0.2667 0 90)
			(size 0.3048 0.381)
			(layers "F.Cu" "F.Mask" "F.Paste")
			(net "P5E_PEX1_STN7_TX_C_DP<127>")
		)
	)
	(footprint ""
		(layer "F.Cu")
		(at 129.217166 -118.343426 90)
		(property "Reference" "R5964"
			(at 0 0 90)
			(layer "F.SilkS")
			(hide yes)
			(effects
				(font
					(size 1.27 1.27)
				)
			)
		)
		(property "Value" ""
			(at 0 0 90)
			(layer "F.Fab")
			(effects
				(font
					(size 1.27 1.27)
				)
			)
		)
		(duplicate_pad_numbers_are_jumpers no)
		(fp_line
			(start 0.7874 -0.4064)
			(end 0.7874 0.4064)
			(stroke
				(width 0.1524)
				(type default)
			)
			(layer "F.SilkS")
		)
		(fp_line
			(start -0.7874 -0.4064)
			(end 0.7874 -0.4064)
			(stroke
				(width 0.1524)
				(type default)
			)
			(layer "F.SilkS")
		)
		(fp_line
			(start 0.7874 0.4064)
			(end -0.7874 0.4064)
			(stroke
				(width 0.1524)
				(type default)
			)
			(layer "F.SilkS")
		)
		(fp_line
			(start -0.7874 0.4064)
			(end -0.7874 -0.4064)
			(stroke
				(width 0.1524)
				(type default)
			)
			(layer "F.SilkS")
		)
		(fp_line
			(start -0.12065 -0.305054)
			(end -0.12065 -0.2794)
			(stroke
				(width 0.1)
				(type default)
			)
			(layer "F.Fab")
		)
		(fp_line
			(start -0.67945 -0.305054)
			(end -0.12065 -0.305054)
			(stroke
				(width 0.1)
				(type default)
			)
			(layer "F.Fab")
		)
		(fp_line
			(start 0.67945 -0.3048)
			(end 0.67945 0.3048)
			(stroke
				(width 0.1)
				(type default)
			)
			(layer "F.Fab")
		)
		(fp_line
			(start 0.12065 -0.3048)
			(end 0.67945 -0.3048)
			(stroke
				(width 0.1)
				(type default)
			)
			(layer "F.Fab")
		)
		(fp_line
			(start 0.12065 -0.2794)
			(end 0.12065 -0.3048)
			(stroke
				(width 0.1)
				(type default)
			)
			(layer "F.Fab")
		)
		(fp_line
			(start -0.12065 -0.2794)
			(end 0.12065 -0.2794)
			(stroke
				(width 0.1)
				(type default)
			)
			(layer "F.Fab")
		)
		(fp_line
			(start 0.120396 0.2794)
			(end -0.12065 0.2794)
			(stroke
				(width 0.1)
				(type default)
			)
			(layer "F.Fab")
		)
		(fp_line
			(start -0.12065 0.2794)
			(end -0.12065 0.3048)
			(stroke
				(width 0.1)
				(type default)
			)
			(layer "F.Fab")
		)
		(fp_line
			(start 0.67945 0.3048)
			(end 0.120396 0.3048)
			(stroke
				(width 0.1)
				(type default)
			)
			(layer "F.Fab")
		)
		(fp_line
			(start 0.120396 0.3048)
			(end 0.120396 0.2794)
			(stroke
				(width 0.1)
				(type default)
			)
			(layer "F.Fab")
		)
		(fp_line
			(start -0.12065 0.3048)
			(end -0.67945 0.3048)
			(stroke
				(width 0.1)
				(type default)
			)
			(layer "F.Fab")
		)
		(fp_line
			(start -0.67945 0.3048)
			(end -0.67945 -0.305054)
			(stroke
				(width 0.1)
				(type default)
			)
			(layer "F.Fab")
		)
		(pad "1" smd circle
			(at -0.40005 0 90)
			(size 0 0)
			(layers "F.Cu" "F.Mask" "F.Paste")
			(net "P3V3_NIC2_PG_G1")
		)
		(pad "2" smd circle
			(at 0.40005 0 90)
			(size 0 0)
			(layers "F.Cu" "F.Mask" "F.Paste")
			(net "GND")
		)
	)
	(footprint ""
		(layer "F.Cu")
		(at 31.86684 -52.543456 180)
		(property "Reference" "PC512"
			(at 0 0 180)
			(layer "F.SilkS")
			(hide yes)
			(effects
				(font
					(size 1.27 1.27)
				)
			)
		)
		(property "Value" ""
			(at 0 0 180)
			(layer "F.Fab")
			(effects
				(font
					(size 1.27 1.27)
				)
			)
		)
		(duplicate_pad_numbers_are_jumpers no)
		(fp_line
			(start 0.7874 0.4064)
			(end -0.7874 0.4064)
			(stroke
				(width 0.1524)
				(type default)
			)
			(layer "F.SilkS")
		)
		(fp_line
			(start 0.7874 -0.4064)
			(end 0.7874 0.4064)
			(stroke
				(width 0.1524)
				(type default)
			)
			(layer "F.SilkS")
		)
		(fp_line
			(start -0.7874 0.4064)
			(end -0.7874 -0.4064)
			(stroke
				(width 0.1524)
				(type default)
			)
			(layer "F.SilkS")
		)
		(fp_line
			(start -0.7874 -0.4064)
			(end 0.7874 -0.4064)
			(stroke
				(width 0.1524)
				(type default)
			)
			(layer "F.SilkS")
		)
		(fp_line
			(start 0.67945 0.3048)
			(end 0.120396 0.3048)
			(stroke
				(width 0.1)
				(type default)
			)
			(layer "F.Fab")
		)
		(fp_line
			(start 0.67945 -0.3048)
			(end 0.67945 0.3048)
			(stroke
				(width 0.1)
				(type default)
			)
			(layer "F.Fab")
		)
		(fp_line
			(start 0.12065 -0.2794)
			(end 0.12065 -0.3048)
			(stroke
				(width 0.1)
				(type default)
			)
			(layer "F.Fab")
		)
		(fp_line
			(start 0.12065 -0.3048)
			(end 0.67945 -0.3048)
			(stroke
				(width 0.1)
				(type default)
			)
			(layer "F.Fab")
		)
		(fp_line
			(start 0.120396 0.3048)
			(end 0.120396 0.2794)
			(stroke
				(width 0.1)
				(type default)
			)
			(layer "F.Fab")
		)
		(fp_line
			(start 0.120396 0.2794)
			(end -0.12065 0.2794)
			(stroke
				(width 0.1)
				(type default)
			)
			(layer "F.Fab")
		)
		(fp_line
			(start -0.12065 0.3048)
			(end -0.67945 0.3048)
			(stroke
				(width 0.1)
				(type default)
			)
			(layer "F.Fab")
		)
		(fp_line
			(start -0.12065 0.2794)
			(end -0.12065 0.3048)
			(stroke
				(width 0.1)
				(type default)
			)
			(layer "F.Fab")
		)
		(fp_line
			(start -0.12065 -0.2794)
			(end 0.12065 -0.2794)
			(stroke
				(width 0.1)
				(type default)
			)
			(layer "F.Fab")
		)
		(fp_line
			(start -0.12065 -0.305054)
			(end -0.12065 -0.2794)
			(stroke
				(width 0.1)
				(type default)
			)
			(layer "F.Fab")
		)
		(fp_line
			(start -0.67945 0.3048)
			(end -0.67945 -0.305054)
			(stroke
				(width 0.1)
				(type default)
			)
			(layer "F.Fab")
		)
		(fp_line
			(start -0.67945 -0.305054)
			(end -0.12065 -0.305054)
			(stroke
				(width 0.1)
				(type default)
			)
			(layer "F.Fab")
		)
		(pad "1" smd circle
			(at -0.40005 0 180)
			(size 0 0)
			(layers "F.Cu" "F.Mask" "F.Paste")
			(net "P3V3_SSD1")
		)
		(pad "2" smd circle
			(at 0.40005 0 180)
			(size 0 0)
			(layers "F.Cu" "F.Mask" "F.Paste")
			(net "GND")
		)
	)
	(footprint ""
		(layer "F.Cu")
		(at 98.434398 -34.546286 180)
		(property "Reference" "C89"
			(at 0 0 180)
			(layer "F.SilkS")
			(hide yes)
			(effects
				(font
					(size 1.27 1.27)
				)
			)
		)
		(property "Value" ""
			(at 0 0 180)
			(layer "F.Fab")
			(effects
				(font
					(size 1.27 1.27)
				)
			)
		)
		(duplicate_pad_numbers_are_jumpers no)
		(fp_line
			(start 0.299974 0.150114)
			(end -0.299974 0.150114)
			(stroke
				(width 0.1)
				(type default)
			)
			(layer "F.Fab")
		)
		(fp_line
			(start 0.299974 -0.150114)
			(end 0.299974 0.150114)
			(stroke
				(width 0.1)
				(type default)
			)
			(layer "F.Fab")
		)
		(fp_line
			(start -0.299974 0.150114)
			(end -0.299974 -0.150114)
			(stroke
				(width 0.1)
				(type default)
			)
			(layer "F.Fab")
		)
		(fp_line
			(start -0.299974 -0.150114)
			(end 0.299974 -0.150114)
			(stroke
				(width 0.1)
				(type default)
			)
			(layer "F.Fab")
		)
		(pad "1" smd rect
			(at -0.2667 0 180)
			(size 0.3048 0.381)
			(layers "F.Cu" "F.Mask" "F.Paste")
			(net "P5E_PEX0_STN2_TX_DP<35>")
		)
		(pad "2" smd rect
			(at 0.2667 0 180)
			(size 0.3048 0.381)
			(layers "F.Cu" "F.Mask" "F.Paste")
			(net "P5E_PEX0_STN2_TX_C_DP<35>")
		)
	)
	(footprint ""
		(layer "F.Cu")
		(at 356.479094 -59.577986 -90)
		(property "Reference" "R895"
			(at 0 0 270)
			(layer "F.SilkS")
			(hide yes)
			(effects
				(font
					(size 1.27 1.27)
				)
			)
		)
		(property "Value" ""
			(at 0 0 270)
			(layer "F.Fab")
			(effects
				(font
					(size 1.27 1.27)
				)
			)
		)
		(duplicate_pad_numbers_are_jumpers no)
		(fp_line
			(start -0.7874 0.4064)
			(end -0.7874 -0.4064)
			(stroke
				(width 0.1524)
				(type default)
			)
			(layer "F.SilkS")
		)
		(fp_line
			(start 0.7874 0.4064)
			(end -0.7874 0.4064)
			(stroke
				(width 0.1524)
				(type default)
			)
			(layer "F.SilkS")
		)
		(fp_line
			(start -0.7874 -0.4064)
			(end 0.7874 -0.4064)
			(stroke
				(width 0.1524)
				(type default)
			)
			(layer "F.SilkS")
		)
		(fp_line
			(start 0.7874 -0.4064)
			(end 0.7874 0.4064)
			(stroke
				(width 0.1524)
				(type default)
			)
			(layer "F.SilkS")
		)
		(fp_line
			(start -0.67945 0.3048)
			(end -0.67945 -0.305054)
			(stroke
				(width 0.1)
				(type default)
			)
			(layer "F.Fab")
		)
		(fp_line
			(start -0.12065 0.3048)
			(end -0.67945 0.3048)
			(stroke
				(width 0.1)
				(type default)
			)
			(layer "F.Fab")
		)
		(fp_line
			(start 0.120396 0.3048)
			(end 0.120396 0.2794)
			(stroke
				(width 0.1)
				(type default)
			)
			(layer "F.Fab")
		)
		(fp_line
			(start 0.67945 0.3048)
			(end 0.120396 0.3048)
			(stroke
				(width 0.1)
				(type default)
			)
			(layer "F.Fab")
		)
		(fp_line
			(start -0.12065 0.2794)
			(end -0.12065 0.3048)
			(stroke
				(width 0.1)
				(type default)
			)
			(layer "F.Fab")
		)
		(fp_line
			(start 0.120396 0.2794)
			(end -0.12065 0.2794)
			(stroke
				(width 0.1)
				(type default)
			)
			(layer "F.Fab")
		)
		(fp_line
			(start -0.12065 -0.2794)
			(end 0.12065 -0.2794)
			(stroke
				(width 0.1)
				(type default)
			)
			(layer "F.Fab")
		)
		(fp_line
			(start 0.12065 -0.2794)
			(end 0.12065 -0.3048)
			(stroke
				(width 0.1)
				(type default)
			)
			(layer "F.Fab")
		)
		(fp_line
			(start 0.12065 -0.3048)
			(end 0.67945 -0.3048)
			(stroke
				(width 0.1)
				(type default)
			)
			(layer "F.Fab")
		)
		(fp_line
			(start 0.67945 -0.3048)
			(end 0.67945 0.3048)
			(stroke
				(width 0.1)
				(type default)
			)
			(layer "F.Fab")
		)
		(fp_line
			(start -0.67945 -0.305054)
			(end -0.12065 -0.305054)
			(stroke
				(width 0.1)
				(type default)
			)
			(layer "F.Fab")
		)
		(fp_line
			(start -0.12065 -0.305054)
			(end -0.12065 -0.2794)
			(stroke
				(width 0.1)
				(type default)
			)
			(layer "F.Fab")
		)
		(pad "1" smd circle
			(at -0.40005 0 270)
			(size 0 0)
			(layers "F.Cu" "F.Mask" "F.Paste")
			(net "P3V3_SSD12")
		)
		(pad "2" smd circle
			(at 0.40005 0 270)
			(size 0 0)
			(layers "F.Cu" "F.Mask" "F.Paste")
			(net "PWRGD_P3V3_SSD12")
		)
	)
	(footprint ""
		(layer "F.Cu")
		(at 239.260126 -51.89728 90)
		(property "Reference" "PU62"
			(at -1.509014 3.019552 90)
			(unlocked yes)
			(layer "F.SilkS")
			(effects
				(font
					(size 0.7874 0.5842)
					(thickness 0.1524)
				)
				(justify left)
			)
		)
		(property "Value" ""
			(at 0 0 90)
			(layer "F.Fab")
			(effects
				(font
					(size 1.27 1.27)
				)
			)
		)
		(duplicate_pad_numbers_are_jumpers no)
		(fp_line
			(start 1.943608 -1.549908)
			(end 1.943608 1.549908)
			(stroke
				(width 0.1524)
				(type default)
			)
			(layer "F.SilkS")
		)
		(fp_line
			(start -1.943608 -1.549908)
			(end 1.943608 -1.549908)
			(stroke
				(width 0.1524)
				(type default)
			)
			(layer "F.SilkS")
		)
		(fp_line
			(start 1.943608 1.549908)
			(end -1.943608 1.549908)
			(stroke
				(width 0.1524)
				(type default)
			)
			(layer "F.SilkS")
		)
		(fp_line
			(start -1.943608 1.549908)
			(end -1.943608 -1.549908)
			(stroke
				(width 0.1524)
				(type default)
			)
			(layer "F.SilkS")
		)
		(fp_poly
			(pts
				(xy -2.019808 -1.549908) (xy -1.257808 -1.549908) (xy -1.257808 -1.880108) (xy -2.019808 -1.880108)
			)
			(stroke
				(width 0)
				(type default)
			)
			(fill yes)
			(layer "F.SilkS")
		)
		(fp_line
			(start 1.549908 -1.549908)
			(end 1.549908 1.549908)
			(stroke
				(width 0.1)
				(type default)
			)
			(layer "F.Fab")
		)
		(fp_line
			(start -1.549908 -1.549908)
			(end 1.549908 -1.549908)
			(stroke
				(width 0.1)
				(type default)
			)
			(layer "F.Fab")
		)
		(fp_line
			(start 1.549908 1.549908)
			(end -1.549908 1.549908)
			(stroke
				(width 0.1)
				(type default)
			)
			(layer "F.Fab")
		)
		(fp_line
			(start -1.549908 1.549908)
			(end -1.549908 -1.549908)
			(stroke
				(width 0.1)
				(type default)
			)
			(layer "F.Fab")
		)
		(fp_poly
			(pts
				(xy -2.019808 -1.549908) (xy -1.257808 -1.549908) (xy -1.257808 -1.880108) (xy -2.019808 -1.880108)
			)
			(stroke
				(width 0)
				(type default)
			)
			(fill yes)
			(layer "F.Fab")
		)
		(pad "1" smd rect
			(at -1.500124 -1.249934)
			(size 0.2794 0.6096)
			(layers "F.Cu" "F.Mask" "F.Paste")
			(net "P3V3_SSD8")
		)
		(pad "2" smd rect
			(at -1.500124 -0.750062)
			(size 0.2794 0.6096)
			(layers "F.Cu" "F.Mask" "F.Paste")
			(net "P3V3_SSD8")
		)
		(pad "3" smd rect
			(at -1.500124 -0.249936)
			(size 0.2794 0.6096)
			(layers "F.Cu" "F.Mask" "F.Paste")
			(net "P3V3_SSD8")
		)
		(pad "4" smd rect
			(at -1.500124 0.249936)
			(size 0.2794 0.6096)
			(layers "F.Cu" "F.Mask" "F.Paste")
			(net "P3V3_SSD8")
		)
		(pad "5" smd rect
			(at -1.500124 0.750062)
			(size 0.2794 0.6096)
			(layers "F.Cu" "F.Mask" "F.Paste")
			(net "P3V3_SSD8")
		)
		(pad "6" smd rect
			(at -1.500124 1.249934)
			(size 0.2794 0.6096)
			(layers "F.Cu" "F.Mask" "F.Paste")
			(net "GND")
		)
		(pad "7" smd rect
			(at 1.500124 1.249934)
			(size 0.2794 0.6096)
			(layers "F.Cu" "F.Mask" "F.Paste")
			(net "P3V3_SSD8_SS")
		)
		(pad "8" smd rect
			(at 1.500124 0.750062)
			(size 0.2794 0.6096)
			(layers "F.Cu" "F.Mask" "F.Paste")
			(net "PWRGD_P3V3_SSD8")
		)
		(pad "9" smd rect
			(at 1.500124 0.249936)
			(size 0.2794 0.6096)
			(layers "F.Cu" "F.Mask" "F.Paste")
			(net "P3V3_SSD8_OCP")
		)
		(pad "10" smd rect
			(at 1.500124 -0.249936)
			(size 0.2794 0.6096)
			(layers "F.Cu" "F.Mask" "F.Paste")
			(net "P5V_AUX")
		)
		(pad "11" smd rect
			(at 1.500124 -0.750062)
			(size 0.2794 0.6096)
			(layers "F.Cu" "F.Mask" "F.Paste")
			(net "SSD8_AUX_P3V3_EN_R")
		)
		(pad "12" smd rect
			(at 1.500124 -1.249934)
			(size 0.2794 0.6096)
			(layers "F.Cu" "F.Mask" "F.Paste")
			(net "P3V3_AUX")
		)
		(pad "13" smd rect
			(at 0 0 90)
			(size 1.9812 2.7178)
			(layers "F.Cu" "F.Mask" "F.Paste")
			(net "P3V3_AUX")
		)
		(zone
			(layer "F.Cu")
			(hatch none 0.5)
			(connect_pads
				(clearance 0)
			)
			(min_thickness 0.25)
			(keepout
				(tracks not_allowed)
				(vias allowed)
				(pads allowed)
				(copperpour not_allowed)
				(footprints allowed)
			)
			(placement
				(enabled no)
				(sheetname "")
			)
			(fill
				(thermal_gap 0.5)
				(thermal_bridge_width 0.5)
				(island_removal_mode 0)
			)
			(polygon
				(pts
					(xy 237.710726 -53.04028) (xy 237.837726 -53.04028) (xy 240.809526 -53.04028) (xy 240.810034 -53.04028)
					(xy 240.810034 -50.75428) (xy 240.809526 -50.75428) (xy 240.682526 -50.75428) (xy 239.260126 -50.75428)
					(xy 239.260126 -50.85588) (xy 240.682526 -50.85588) (xy 240.682526 -52.93868) (xy 237.837726 -52.93868)
					(xy 237.837726 -50.85588) (xy 239.234726 -50.85588) (xy 239.234726 -50.75428) (xy 237.837726 -50.75428)
					(xy 237.710726 -50.75428) (xy 237.710218 -50.75428) (xy 237.710218 -53.04028)
				)
			)
		)
	)
	(footprint ""
		(layer "F.Cu")
		(at 238.742474 -257.975862 -90)
		(property "Reference" "R6523"
			(at 0 0 270)
			(layer "F.SilkS")
			(hide yes)
			(effects
				(font
					(size 1.27 1.27)
				)
			)
		)
		(property "Value" ""
			(at 0 0 270)
			(layer "F.Fab")
			(effects
				(font
					(size 1.27 1.27)
				)
			)
		)
		(duplicate_pad_numbers_are_jumpers no)
		(fp_line
			(start -0.7874 0.4064)
			(end -0.7874 -0.4064)
			(stroke
				(width 0.1524)
				(type default)
			)
			(layer "F.SilkS")
		)
		(fp_line
			(start 0.7874 0.4064)
			(end -0.7874 0.4064)
			(stroke
				(width 0.1524)
				(type default)
			)
			(layer "F.SilkS")
		)
		(fp_line
			(start -0.7874 -0.4064)
			(end 0.7874 -0.4064)
			(stroke
				(width 0.1524)
				(type default)
			)
			(layer "F.SilkS")
		)
		(fp_line
			(start 0.7874 -0.4064)
			(end 0.7874 0.4064)
			(stroke
				(width 0.1524)
				(type default)
			)
			(layer "F.SilkS")
		)
		(fp_line
			(start -0.67945 0.3048)
			(end -0.67945 -0.305054)
			(stroke
				(width 0.1)
				(type default)
			)
			(layer "F.Fab")
		)
		(fp_line
			(start -0.12065 0.3048)
			(end -0.67945 0.3048)
			(stroke
				(width 0.1)
				(type default)
			)
			(layer "F.Fab")
		)
		(fp_line
			(start 0.120396 0.3048)
			(end 0.120396 0.2794)
			(stroke
				(width 0.1)
				(type default)
			)
			(layer "F.Fab")
		)
		(fp_line
			(start 0.67945 0.3048)
			(end 0.120396 0.3048)
			(stroke
				(width 0.1)
				(type default)
			)
			(layer "F.Fab")
		)
		(fp_line
			(start -0.12065 0.2794)
			(end -0.12065 0.3048)
			(stroke
				(width 0.1)
				(type default)
			)
			(layer "F.Fab")
		)
		(fp_line
			(start 0.120396 0.2794)
			(end -0.12065 0.2794)
			(stroke
				(width 0.1)
				(type default)
			)
			(layer "F.Fab")
		)
		(fp_line
			(start -0.12065 -0.2794)
			(end 0.12065 -0.2794)
			(stroke
				(width 0.1)
				(type default)
			)
			(layer "F.Fab")
		)
		(fp_line
			(start 0.12065 -0.2794)
			(end 0.12065 -0.3048)
			(stroke
				(width 0.1)
				(type default)
			)
			(layer "F.Fab")
		)
		(fp_line
			(start 0.12065 -0.3048)
			(end 0.67945 -0.3048)
			(stroke
				(width 0.1)
				(type default)
			)
			(layer "F.Fab")
		)
		(fp_line
			(start 0.67945 -0.3048)
			(end 0.67945 0.3048)
			(stroke
				(width 0.1)
				(type default)
			)
			(layer "F.Fab")
		)
		(fp_line
			(start -0.67945 -0.305054)
			(end -0.12065 -0.305054)
			(stroke
				(width 0.1)
				(type default)
			)
			(layer "F.Fab")
		)
		(fp_line
			(start -0.12065 -0.305054)
			(end -0.12065 -0.2794)
			(stroke
				(width 0.1)
				(type default)
			)
			(layer "F.Fab")
		)
		(pad "1" smd circle
			(at -0.40005 0 270)
			(size 0 0)
			(layers "F.Cu" "F.Mask" "F.Paste")
			(net "P1V25_SERDES_VDDPLL_PEX2")
		)
		(pad "2" smd circle
			(at 0.40005 0 270)
			(size 0 0)
			(layers "F.Cu" "F.Mask" "F.Paste")
			(net "P1V25_SERDES_VDDPLL_PEX2_C2")
		)
	)
	(footprint ""
		(layer "F.Cu")
		(at 138.508486 -257.102102)
		(property "Reference" "Q14"
			(at -3.74142 -0.768604 0)
			(unlocked yes)
			(layer "F.SilkS")
			(effects
				(font
					(size 0.7874 0.5842)
					(thickness 0.1524)
				)
			)
		)
		(property "Value" ""
			(at 0 0 0)
			(layer "F.Fab")
			(effects
				(font
					(size 1.27 1.27)
				)
			)
		)
		(duplicate_pad_numbers_are_jumpers no)
		(fp_line
			(start -1.376172 -1.199896)
			(end -0.508 -1.199896)
			(stroke
				(width 0.1524)
				(type default)
			)
			(layer "F.SilkS")
		)
		(fp_line
			(start -1.376172 1.199896)
			(end -1.376172 -1.199896)
			(stroke
				(width 0.1524)
				(type default)
			)
			(layer "F.SilkS")
		)
		(fp_line
			(start -0.508 -1.199896)
			(end 0 -0.762)
			(stroke
				(width 0.1524)
				(type default)
			)
			(layer "F.SilkS")
		)
		(fp_line
			(start 0 -0.762)
			(end 0.508 -1.199896)
			(stroke
				(width 0.1524)
				(type default)
			)
			(layer "F.SilkS")
		)
		(fp_line
			(start 0.508 -1.199896)
			(end 1.376172 -1.199896)
			(stroke
				(width 0.1524)
				(type default)
			)
			(layer "F.SilkS")
		)
		(fp_line
			(start 1.376172 -1.199896)
			(end 1.376172 1.199896)
			(stroke
				(width 0.1524)
				(type default)
			)
			(layer "F.SilkS")
		)
		(fp_line
			(start 1.376172 1.199896)
			(end -1.376172 1.199896)
			(stroke
				(width 0.1524)
				(type default)
			)
			(layer "F.SilkS")
		)
		(fp_poly
			(pts
				(xy -1.4605 -0.7493) (xy -2.2225 -1.1303) (xy -2.2225 -0.3683)
			)
			(stroke
				(width 0)
				(type default)
			)
			(fill yes)
			(layer "F.SilkS")
		)
		(fp_line
			(start -0.674878 -1.100074)
			(end 0.674878 -1.100074)
			(stroke
				(width 0.1)
				(type default)
			)
			(layer "F.Fab")
		)
		(fp_line
			(start -0.674878 1.100074)
			(end -0.674878 -1.100074)
			(stroke
				(width 0.1)
				(type default)
			)
			(layer "F.Fab")
		)
		(fp_line
			(start 0.674878 -1.100074)
			(end 0.674878 1.100074)
			(stroke
				(width 0.1)
				(type default)
			)
			(layer "F.Fab")
		)
		(fp_line
			(start 0.674878 1.100074)
			(end -0.674878 1.100074)
			(stroke
				(width 0.1)
				(type default)
			)
			(layer "F.Fab")
		)
		(fp_poly
			(pts
				(xy -1.4605 -0.7493) (xy -2.2225 -1.1303) (xy -2.2225 -0.3683)
			)
			(stroke
				(width 0)
				(type default)
			)
			(fill yes)
			(layer "F.Fab")
		)
		(pad "1" smd rect
			(at -0.899922 -0.750062 270)
			(size 0.6096 0.6096)
			(layers "F.Cu" "F.Mask" "F.Paste")
			(net "GND")
		)
		(pad "2" smd rect
			(at -0.899922 0 270)
			(size 0.4064 0.6096)
			(layers "F.Cu" "F.Mask" "F.Paste")
			(net "PEX1_SYS_ERR_R_N")
		)
		(pad "3" smd rect
			(at -0.899922 0.750062 270)
			(size 0.6096 0.6096)
			(layers "F.Cu" "F.Mask" "F.Paste")
			(net "PEX1_SYS_ERR_3V3_N")
		)
		(pad "4" smd rect
			(at 0.899922 0.750062 270)
			(size 0.6096 0.6096)
			(layers "F.Cu" "F.Mask" "F.Paste")
			(net "GND")
		)
		(pad "5" smd rect
			(at 0.899922 0 270)
			(size 0.4064 0.6096)
			(layers "F.Cu" "F.Mask" "F.Paste")
			(net "PEX1_SYS_ERR_N_G")
		)
		(pad "6" smd rect
			(at 0.899922 -0.750062 270)
			(size 0.6096 0.6096)
			(layers "F.Cu" "F.Mask" "F.Paste")
			(net "PEX1_SYS_ERR_N_G")
		)
	)
	(footprint ""
		(layer "F.Cu")
		(at 350.888554 -277.639272 180)
		(property "Reference" "PC190"
			(at 0 0 180)
			(layer "F.SilkS")
			(hide yes)
			(effects
				(font
					(size 1.27 1.27)
				)
			)
		)
		(property "Value" ""
			(at 0 0 180)
			(layer "F.Fab")
			(effects
				(font
					(size 1.27 1.27)
				)
			)
		)
		(duplicate_pad_numbers_are_jumpers no)
		(fp_line
			(start 1.524 0.762)
			(end -1.524 0.762)
			(stroke
				(width 0.1524)
				(type default)
			)
			(layer "F.SilkS")
		)
		(fp_line
			(start 1.524 -0.762)
			(end 1.524 0.762)
			(stroke
				(width 0.1524)
				(type default)
			)
			(layer "F.SilkS")
		)
		(fp_line
			(start -1.524 0.762)
			(end -1.524 -0.762)
			(stroke
				(width 0.1524)
				(type default)
			)
			(layer "F.SilkS")
		)
		(fp_line
			(start -1.524 -0.762)
			(end 1.524 -0.762)
			(stroke
				(width 0.1524)
				(type default)
			)
			(layer "F.SilkS")
		)
		(fp_line
			(start 1.1049 0.724916)
			(end 1.1049 -0.724916)
			(stroke
				(width 0.1)
				(type default)
			)
			(layer "F.Fab")
		)
		(fp_line
			(start 1.1049 -0.724916)
			(end -1.1049 -0.724916)
			(stroke
				(width 0.1)
				(type default)
			)
			(layer "F.Fab")
		)
		(fp_line
			(start -1.1049 0.724916)
			(end 1.1049 0.724916)
			(stroke
				(width 0.1)
				(type default)
			)
			(layer "F.Fab")
		)
		(fp_line
			(start -1.1049 -0.724916)
			(end -1.1049 0.724916)
			(stroke
				(width 0.1)
				(type default)
			)
			(layer "F.Fab")
		)
		(pad "1" smd rect
			(at -0.889 0)
			(size 1.016 1.27)
			(layers "F.Cu" "F.Mask" "F.Paste")
			(net "SW_P12V_P0V8_PEX3_FLT")
		)
		(pad "2" smd rect
			(at 0.889 0)
			(size 1.016 1.27)
			(layers "F.Cu" "F.Mask" "F.Paste")
			(net "GND")
		)
	)
	(footprint ""
		(layer "F.Cu")
		(at 280.137616 -405.074374 -90)
		(property "Reference" "R1816"
			(at 0 0 270)
			(layer "F.SilkS")
			(hide yes)
			(effects
				(font
					(size 1.27 1.27)
				)
			)
		)
		(property "Value" ""
			(at 0 0 270)
			(layer "F.Fab")
			(effects
				(font
					(size 1.27 1.27)
				)
			)
		)
		(duplicate_pad_numbers_are_jumpers no)
		(fp_line
			(start -0.7874 0.4064)
			(end -0.7874 -0.4064)
			(stroke
				(width 0.1524)
				(type default)
			)
			(layer "F.SilkS")
		)
		(fp_line
			(start 0.7874 0.4064)
			(end -0.7874 0.4064)
			(stroke
				(width 0.1524)
				(type default)
			)
			(layer "F.SilkS")
		)
		(fp_line
			(start -0.7874 -0.4064)
			(end 0.7874 -0.4064)
			(stroke
				(width 0.1524)
				(type default)
			)
			(layer "F.SilkS")
		)
		(fp_line
			(start 0.7874 -0.4064)
			(end 0.7874 0.4064)
			(stroke
				(width 0.1524)
				(type default)
			)
			(layer "F.SilkS")
		)
		(fp_line
			(start -0.67945 0.3048)
			(end -0.67945 -0.305054)
			(stroke
				(width 0.1)
				(type default)
			)
			(layer "F.Fab")
		)
		(fp_line
			(start -0.12065 0.3048)
			(end -0.67945 0.3048)
			(stroke
				(width 0.1)
				(type default)
			)
			(layer "F.Fab")
		)
		(fp_line
			(start 0.120396 0.3048)
			(end 0.120396 0.2794)
			(stroke
				(width 0.1)
				(type default)
			)
			(layer "F.Fab")
		)
		(fp_line
			(start 0.67945 0.3048)
			(end 0.120396 0.3048)
			(stroke
				(width 0.1)
				(type default)
			)
			(layer "F.Fab")
		)
		(fp_line
			(start -0.12065 0.2794)
			(end -0.12065 0.3048)
			(stroke
				(width 0.1)
				(type default)
			)
			(layer "F.Fab")
		)
		(fp_line
			(start 0.120396 0.2794)
			(end -0.12065 0.2794)
			(stroke
				(width 0.1)
				(type default)
			)
			(layer "F.Fab")
		)
		(fp_line
			(start -0.12065 -0.2794)
			(end 0.12065 -0.2794)
			(stroke
				(width 0.1)
				(type default)
			)
			(layer "F.Fab")
		)
		(fp_line
			(start 0.12065 -0.2794)
			(end 0.12065 -0.3048)
			(stroke
				(width 0.1)
				(type default)
			)
			(layer "F.Fab")
		)
		(fp_line
			(start 0.12065 -0.3048)
			(end 0.67945 -0.3048)
			(stroke
				(width 0.1)
				(type default)
			)
			(layer "F.Fab")
		)
		(fp_line
			(start 0.67945 -0.3048)
			(end 0.67945 0.3048)
			(stroke
				(width 0.1)
				(type default)
			)
			(layer "F.Fab")
		)
		(fp_line
			(start -0.67945 -0.305054)
			(end -0.12065 -0.305054)
			(stroke
				(width 0.1)
				(type default)
			)
			(layer "F.Fab")
		)
		(fp_line
			(start -0.12065 -0.305054)
			(end -0.12065 -0.2794)
			(stroke
				(width 0.1)
				(type default)
			)
			(layer "F.Fab")
		)
		(pad "1" smd circle
			(at -0.40005 0 270)
			(size 0 0)
			(layers "F.Cu" "F.Mask" "F.Paste")
			(net "MB_BIC_MON_BUF")
		)
		(pad "2" smd circle
			(at 0.40005 0 270)
			(size 0 0)
			(layers "F.Cu" "F.Mask" "F.Paste")
			(net "MB_BIC_MON_BUF_R")
		)
	)
	(footprint ""
		(layer "F.Cu")
		(at 231.764586 -112.205516 180)
		(property "Reference" "PC599"
			(at 0 0 180)
			(layer "F.SilkS")
			(hide yes)
			(effects
				(font
					(size 1.27 1.27)
				)
			)
		)
		(property "Value" ""
			(at 0 0 180)
			(layer "F.Fab")
			(effects
				(font
					(size 1.27 1.27)
				)
			)
		)
		(duplicate_pad_numbers_are_jumpers no)
		(fp_line
			(start 0.7874 0.4064)
			(end -0.7874 0.4064)
			(stroke
				(width 0.1524)
				(type default)
			)
			(layer "F.SilkS")
		)
		(fp_line
			(start 0.7874 -0.4064)
			(end 0.7874 0.4064)
			(stroke
				(width 0.1524)
				(type default)
			)
			(layer "F.SilkS")
		)
		(fp_line
			(start -0.7874 0.4064)
			(end -0.7874 -0.4064)
			(stroke
				(width 0.1524)
				(type default)
			)
			(layer "F.SilkS")
		)
		(fp_line
			(start -0.7874 -0.4064)
			(end 0.7874 -0.4064)
			(stroke
				(width 0.1524)
				(type default)
			)
			(layer "F.SilkS")
		)
		(fp_line
			(start 0.67945 0.3048)
			(end 0.120396 0.3048)
			(stroke
				(width 0.1)
				(type default)
			)
			(layer "F.Fab")
		)
		(fp_line
			(start 0.67945 -0.3048)
			(end 0.67945 0.3048)
			(stroke
				(width 0.1)
				(type default)
			)
			(layer "F.Fab")
		)
		(fp_line
			(start 0.12065 -0.2794)
			(end 0.12065 -0.3048)
			(stroke
				(width 0.1)
				(type default)
			)
			(layer "F.Fab")
		)
		(fp_line
			(start 0.12065 -0.3048)
			(end 0.67945 -0.3048)
			(stroke
				(width 0.1)
				(type default)
			)
			(layer "F.Fab")
		)
		(fp_line
			(start 0.120396 0.3048)
			(end 0.120396 0.2794)
			(stroke
				(width 0.1)
				(type default)
			)
			(layer "F.Fab")
		)
		(fp_line
			(start 0.120396 0.2794)
			(end -0.12065 0.2794)
			(stroke
				(width 0.1)
				(type default)
			)
			(layer "F.Fab")
		)
		(fp_line
			(start -0.12065 0.3048)
			(end -0.67945 0.3048)
			(stroke
				(width 0.1)
				(type default)
			)
			(layer "F.Fab")
		)
		(fp_line
			(start -0.12065 0.2794)
			(end -0.12065 0.3048)
			(stroke
				(width 0.1)
				(type default)
			)
			(layer "F.Fab")
		)
		(fp_line
			(start -0.12065 -0.2794)
			(end 0.12065 -0.2794)
			(stroke
				(width 0.1)
				(type default)
			)
			(layer "F.Fab")
		)
		(fp_line
			(start -0.12065 -0.305054)
			(end -0.12065 -0.2794)
			(stroke
				(width 0.1)
				(type default)
			)
			(layer "F.Fab")
		)
		(fp_line
			(start -0.67945 0.3048)
			(end -0.67945 -0.305054)
			(stroke
				(width 0.1)
				(type default)
			)
			(layer "F.Fab")
		)
		(fp_line
			(start -0.67945 -0.305054)
			(end -0.12065 -0.305054)
			(stroke
				(width 0.1)
				(type default)
			)
			(layer "F.Fab")
		)
		(pad "1" smd circle
			(at -0.40005 0 180)
			(size 0 0)
			(layers "F.Cu" "F.Mask" "F.Paste")
			(net "P12V_AUX")
		)
		(pad "2" smd circle
			(at 0.40005 0 180)
			(size 0 0)
			(layers "F.Cu" "F.Mask" "F.Paste")
			(net "GND")
		)
	)
	(footprint ""
		(layer "F.Cu")
		(at 334.095852 -113.547398 90)
		(property "Reference" "PR7025"
			(at 0 0 90)
			(layer "F.SilkS")
			(hide yes)
			(effects
				(font
					(size 1.27 1.27)
				)
			)
		)
		(property "Value" ""
			(at 0 0 90)
			(layer "F.Fab")
			(effects
				(font
					(size 1.27 1.27)
				)
			)
		)
		(duplicate_pad_numbers_are_jumpers no)
		(fp_line
			(start 0.7874 -0.4064)
			(end 0.7874 0.4064)
			(stroke
				(width 0.1524)
				(type default)
			)
			(layer "F.SilkS")
		)
		(fp_line
			(start -0.7874 -0.4064)
			(end 0.7874 -0.4064)
			(stroke
				(width 0.1524)
				(type default)
			)
			(layer "F.SilkS")
		)
		(fp_line
			(start 0.7874 0.4064)
			(end -0.7874 0.4064)
			(stroke
				(width 0.1524)
				(type default)
			)
			(layer "F.SilkS")
		)
		(fp_line
			(start -0.7874 0.4064)
			(end -0.7874 -0.4064)
			(stroke
				(width 0.1524)
				(type default)
			)
			(layer "F.SilkS")
		)
		(fp_line
			(start -0.12065 -0.305054)
			(end -0.12065 -0.2794)
			(stroke
				(width 0.1)
				(type default)
			)
			(layer "F.Fab")
		)
		(fp_line
			(start -0.67945 -0.305054)
			(end -0.12065 -0.305054)
			(stroke
				(width 0.1)
				(type default)
			)
			(layer "F.Fab")
		)
		(fp_line
			(start 0.67945 -0.3048)
			(end 0.67945 0.3048)
			(stroke
				(width 0.1)
				(type default)
			)
			(layer "F.Fab")
		)
		(fp_line
			(start 0.12065 -0.3048)
			(end 0.67945 -0.3048)
			(stroke
				(width 0.1)
				(type default)
			)
			(layer "F.Fab")
		)
		(fp_line
			(start 0.12065 -0.2794)
			(end 0.12065 -0.3048)
			(stroke
				(width 0.1)
				(type default)
			)
			(layer "F.Fab")
		)
		(fp_line
			(start -0.12065 -0.2794)
			(end 0.12065 -0.2794)
			(stroke
				(width 0.1)
				(type default)
			)
			(layer "F.Fab")
		)
		(fp_line
			(start 0.120396 0.2794)
			(end -0.12065 0.2794)
			(stroke
				(width 0.1)
				(type default)
			)
			(layer "F.Fab")
		)
		(fp_line
			(start -0.12065 0.2794)
			(end -0.12065 0.3048)
			(stroke
				(width 0.1)
				(type default)
			)
			(layer "F.Fab")
		)
		(fp_line
			(start 0.67945 0.3048)
			(end 0.120396 0.3048)
			(stroke
				(width 0.1)
				(type default)
			)
			(layer "F.Fab")
		)
		(fp_line
			(start 0.120396 0.3048)
			(end 0.120396 0.2794)
			(stroke
				(width 0.1)
				(type default)
			)
			(layer "F.Fab")
		)
		(fp_line
			(start -0.12065 0.3048)
			(end -0.67945 0.3048)
			(stroke
				(width 0.1)
				(type default)
			)
			(layer "F.Fab")
		)
		(fp_line
			(start -0.67945 0.3048)
			(end -0.67945 -0.305054)
			(stroke
				(width 0.1)
				(type default)
			)
			(layer "F.Fab")
		)
		(pad "1" smd circle
			(at -0.40005 0 90)
			(size 0 0)
			(layers "F.Cu" "F.Mask" "F.Paste")
			(net "P12V_NIC5_R")
		)
		(pad "2" smd circle
			(at 0.40005 0 90)
			(size 0 0)
			(layers "F.Cu" "F.Mask" "F.Paste")
			(net "P12V_NIC5_CO_AVIN_PD")
		)
	)
	(footprint ""
		(layer "F.Cu")
		(at 193.83883 -402.663152 -90)
		(property "Reference" "C2844"
			(at 0 0 270)
			(layer "F.SilkS")
			(hide yes)
			(effects
				(font
					(size 1.27 1.27)
				)
			)
		)
		(property "Value" ""
			(at 0 0 270)
			(layer "F.Fab")
			(effects
				(font
					(size 1.27 1.27)
				)
			)
		)
		(duplicate_pad_numbers_are_jumpers no)
		(fp_line
			(start -0.7874 0.4064)
			(end -0.7874 -0.4064)
			(stroke
				(width 0.1524)
				(type default)
			)
			(layer "F.SilkS")
		)
		(fp_line
			(start 0.7874 0.4064)
			(end -0.7874 0.4064)
			(stroke
				(width 0.1524)
				(type default)
			)
			(layer "F.SilkS")
		)
		(fp_line
			(start -0.7874 -0.4064)
			(end 0.7874 -0.4064)
			(stroke
				(width 0.1524)
				(type default)
			)
			(layer "F.SilkS")
		)
		(fp_line
			(start 0.7874 -0.4064)
			(end 0.7874 0.4064)
			(stroke
				(width 0.1524)
				(type default)
			)
			(layer "F.SilkS")
		)
		(fp_line
			(start -0.67945 0.3048)
			(end -0.67945 -0.305054)
			(stroke
				(width 0.1)
				(type default)
			)
			(layer "F.Fab")
		)
		(fp_line
			(start -0.12065 0.3048)
			(end -0.67945 0.3048)
			(stroke
				(width 0.1)
				(type default)
			)
			(layer "F.Fab")
		)
		(fp_line
			(start 0.120396 0.3048)
			(end 0.120396 0.2794)
			(stroke
				(width 0.1)
				(type default)
			)
			(layer "F.Fab")
		)
		(fp_line
			(start 0.67945 0.3048)
			(end 0.120396 0.3048)
			(stroke
				(width 0.1)
				(type default)
			)
			(layer "F.Fab")
		)
		(fp_line
			(start -0.12065 0.2794)
			(end -0.12065 0.3048)
			(stroke
				(width 0.1)
				(type default)
			)
			(layer "F.Fab")
		)
		(fp_line
			(start 0.120396 0.2794)
			(end -0.12065 0.2794)
			(stroke
				(width 0.1)
				(type default)
			)
			(layer "F.Fab")
		)
		(fp_line
			(start -0.12065 -0.2794)
			(end 0.12065 -0.2794)
			(stroke
				(width 0.1)
				(type default)
			)
			(layer "F.Fab")
		)
		(fp_line
			(start 0.12065 -0.2794)
			(end 0.12065 -0.3048)
			(stroke
				(width 0.1)
				(type default)
			)
			(layer "F.Fab")
		)
		(fp_line
			(start 0.12065 -0.3048)
			(end 0.67945 -0.3048)
			(stroke
				(width 0.1)
				(type default)
			)
			(layer "F.Fab")
		)
		(fp_line
			(start 0.67945 -0.3048)
			(end 0.67945 0.3048)
			(stroke
				(width 0.1)
				(type default)
			)
			(layer "F.Fab")
		)
		(fp_line
			(start -0.67945 -0.305054)
			(end -0.12065 -0.305054)
			(stroke
				(width 0.1)
				(type default)
			)
			(layer "F.Fab")
		)
		(fp_line
			(start -0.12065 -0.305054)
			(end -0.12065 -0.2794)
			(stroke
				(width 0.1)
				(type default)
			)
			(layer "F.Fab")
		)
		(pad "1" smd circle
			(at -0.40005 0 270)
			(size 0 0)
			(layers "F.Cu" "F.Mask" "F.Paste")
			(net "FM_UV_LT6700_VS")
		)
		(pad "2" smd circle
			(at 0.40005 0 270)
			(size 0 0)
			(layers "F.Cu" "F.Mask" "F.Paste")
			(net "GND")
		)
	)
	(footprint ""
		(layer "F.Cu")
		(at 147.854416 -48.21809)
		(property "Reference" "PD63"
			(at -3.328416 2.19456 0)
			(unlocked yes)
			(layer "F.SilkS")
			(effects
				(font
					(size 0.7874 0.5842)
					(thickness 0.1524)
				)
				(justify left)
			)
		)
		(property "Value" ""
			(at 0 0 0)
			(layer "F.Fab")
			(effects
				(font
					(size 1.27 1.27)
				)
			)
		)
		(duplicate_pad_numbers_are_jumpers no)
		(fp_line
			(start -3.400044 -1.459992)
			(end 4.107942 -1.459992)
			(stroke
				(width 0.1524)
				(type default)
			)
			(layer "F.SilkS")
		)
		(fp_line
			(start -3.400044 1.459992)
			(end -3.400044 -1.459992)
			(stroke
				(width 0.1524)
				(type default)
			)
			(layer "F.SilkS")
		)
		(fp_line
			(start 4.107942 -1.459992)
			(end 4.107942 1.459992)
			(stroke
				(width 0.1524)
				(type default)
			)
			(layer "F.SilkS")
		)
		(fp_line
			(start 4.107942 1.459992)
			(end -3.400044 1.459992)
			(stroke
				(width 0.1524)
				(type default)
			)
			(layer "F.SilkS")
		)
		(fp_poly
			(pts
				(xy 4.107942 -1.459992) (xy 4.107942 1.459992) (xy 3.308096 1.459992) (xy 3.308096 -1.459992)
			)
			(stroke
				(width 0)
				(type default)
			)
			(fill yes)
			(layer "F.SilkS")
		)
		(fp_line
			(start -2.29997 -1.459992)
			(end 2.29997 -1.459992)
			(stroke
				(width 0.1)
				(type default)
			)
			(layer "F.Fab")
		)
		(fp_line
			(start -2.29997 1.459992)
			(end -2.29997 -1.459992)
			(stroke
				(width 0.1)
				(type default)
			)
			(layer "F.Fab")
		)
		(fp_line
			(start 2.29997 -1.459992)
			(end 2.29997 1.459992)
			(stroke
				(width 0.1)
				(type default)
			)
			(layer "F.Fab")
		)
		(fp_line
			(start 2.29997 1.459992)
			(end -2.29997 1.459992)
			(stroke
				(width 0.1)
				(type default)
			)
			(layer "F.Fab")
		)
		(fp_text user "+"
			(at -4.7752 -0.12065 0)
			(unlocked yes)
			(layer "F.SilkS")
			(effects
				(font
					(size 1.905 1.4224)
					(thickness 0.1524)
				)
				(justify left)
			)
		)
		(fp_text user "-"
			(at 5.4102 0.29845 180)
			(unlocked yes)
			(layer "F.SilkS")
			(effects
				(font
					(size 1.905 1.4224)
					(thickness 0.1524)
				)
				(justify left)
			)
		)
		(fp_text user "+"
			(at -4.7752 -0.12065 0)
			(unlocked yes)
			(layer "F.Fab")
			(effects
				(font
					(size 1.905 1.4224)
					(thickness 0.1524)
				)
				(justify left)
			)
		)
		(fp_text user "-"
			(at 5.4102 0.29845 180)
			(unlocked yes)
			(layer "F.Fab")
			(effects
				(font
					(size 1.905 1.4224)
					(thickness 0.1524)
				)
				(justify left)
			)
		)
		(pad "A" smd rect
			(at -1.999996 0 90)
			(size 1.7018 2.5146)
			(layers "F.Cu" "F.Mask" "F.Paste")
			(net "GND")
		)
		(pad "C" smd rect
			(at 1.999996 0 90)
			(size 1.7018 2.5146)
			(layers "F.Cu" "F.Mask" "F.Paste")
			(net "P3V3_SSD5")
		)
	)
	(footprint ""
		(layer "F.Cu")
		(at 252.99543 -92.096336 -90)
		(property "Reference" "R1067"
			(at 0 0 270)
			(layer "F.SilkS")
			(hide yes)
			(effects
				(font
					(size 1.27 1.27)
				)
			)
		)
		(property "Value" ""
			(at 0 0 270)
			(layer "F.Fab")
			(effects
				(font
					(size 1.27 1.27)
				)
			)
		)
		(duplicate_pad_numbers_are_jumpers no)
		(fp_line
			(start -0.7874 0.4064)
			(end -0.7874 -0.4064)
			(stroke
				(width 0.1524)
				(type default)
			)
			(layer "F.SilkS")
		)
		(fp_line
			(start 0.7874 0.4064)
			(end -0.7874 0.4064)
			(stroke
				(width 0.1524)
				(type default)
			)
			(layer "F.SilkS")
		)
		(fp_line
			(start -0.7874 -0.4064)
			(end 0.7874 -0.4064)
			(stroke
				(width 0.1524)
				(type default)
			)
			(layer "F.SilkS")
		)
		(fp_line
			(start 0.7874 -0.4064)
			(end 0.7874 0.4064)
			(stroke
				(width 0.1524)
				(type default)
			)
			(layer "F.SilkS")
		)
		(fp_line
			(start -0.67945 0.3048)
			(end -0.67945 -0.305054)
			(stroke
				(width 0.1)
				(type default)
			)
			(layer "F.Fab")
		)
		(fp_line
			(start -0.12065 0.3048)
			(end -0.67945 0.3048)
			(stroke
				(width 0.1)
				(type default)
			)
			(layer "F.Fab")
		)
		(fp_line
			(start 0.120396 0.3048)
			(end 0.120396 0.2794)
			(stroke
				(width 0.1)
				(type default)
			)
			(layer "F.Fab")
		)
		(fp_line
			(start 0.67945 0.3048)
			(end 0.120396 0.3048)
			(stroke
				(width 0.1)
				(type default)
			)
			(layer "F.Fab")
		)
		(fp_line
			(start -0.12065 0.2794)
			(end -0.12065 0.3048)
			(stroke
				(width 0.1)
				(type default)
			)
			(layer "F.Fab")
		)
		(fp_line
			(start 0.120396 0.2794)
			(end -0.12065 0.2794)
			(stroke
				(width 0.1)
				(type default)
			)
			(layer "F.Fab")
		)
		(fp_line
			(start -0.12065 -0.2794)
			(end 0.12065 -0.2794)
			(stroke
				(width 0.1)
				(type default)
			)
			(layer "F.Fab")
		)
		(fp_line
			(start 0.12065 -0.2794)
			(end 0.12065 -0.3048)
			(stroke
				(width 0.1)
				(type default)
			)
			(layer "F.Fab")
		)
		(fp_line
			(start 0.12065 -0.3048)
			(end 0.67945 -0.3048)
			(stroke
				(width 0.1)
				(type default)
			)
			(layer "F.Fab")
		)
		(fp_line
			(start 0.67945 -0.3048)
			(end 0.67945 0.3048)
			(stroke
				(width 0.1)
				(type default)
			)
			(layer "F.Fab")
		)
		(fp_line
			(start -0.67945 -0.305054)
			(end -0.12065 -0.305054)
			(stroke
				(width 0.1)
				(type default)
			)
			(layer "F.Fab")
		)
		(fp_line
			(start -0.12065 -0.305054)
			(end -0.12065 -0.2794)
			(stroke
				(width 0.1)
				(type default)
			)
			(layer "F.Fab")
		)
		(pad "1" smd circle
			(at -0.40005 0 270)
			(size 0 0)
			(layers "F.Cu" "F.Mask" "F.Paste")
			(net "GND")
		)
		(pad "2" smd circle
			(at 0.40005 0 270)
			(size 0 0)
			(layers "F.Cu" "F.Mask" "F.Paste")
			(net "PD_CK440_SBI_DATA_IN")
		)
	)
	(footprint ""
		(layer "F.Cu")
		(at 138.985244 -99.243642)
		(property "Reference" "R1613"
			(at 0 0 0)
			(layer "F.SilkS")
			(hide yes)
			(effects
				(font
					(size 1.27 1.27)
				)
			)
		)
		(property "Value" ""
			(at 0 0 0)
			(layer "F.Fab")
			(effects
				(font
					(size 1.27 1.27)
				)
			)
		)
		(duplicate_pad_numbers_are_jumpers no)
		(fp_line
			(start -0.7874 -0.4064)
			(end 0.7874 -0.4064)
			(stroke
				(width 0.1524)
				(type default)
			)
			(layer "F.SilkS")
		)
		(fp_line
			(start -0.7874 0.4064)
			(end -0.7874 -0.4064)
			(stroke
				(width 0.1524)
				(type default)
			)
			(layer "F.SilkS")
		)
		(fp_line
			(start 0.7874 -0.4064)
			(end 0.7874 0.4064)
			(stroke
				(width 0.1524)
				(type default)
			)
			(layer "F.SilkS")
		)
		(fp_line
			(start 0.7874 0.4064)
			(end -0.7874 0.4064)
			(stroke
				(width 0.1524)
				(type default)
			)
			(layer "F.SilkS")
		)
		(fp_line
			(start -0.67945 -0.305054)
			(end -0.12065 -0.305054)
			(stroke
				(width 0.1)
				(type default)
			)
			(layer "F.Fab")
		)
		(fp_line
			(start -0.67945 0.3048)
			(end -0.67945 -0.305054)
			(stroke
				(width 0.1)
				(type default)
			)
			(layer "F.Fab")
		)
		(fp_line
			(start -0.12065 -0.305054)
			(end -0.12065 -0.2794)
			(stroke
				(width 0.1)
				(type default)
			)
			(layer "F.Fab")
		)
		(fp_line
			(start -0.12065 -0.2794)
			(end 0.12065 -0.2794)
			(stroke
				(width 0.1)
				(type default)
			)
			(layer "F.Fab")
		)
		(fp_line
			(start -0.12065 0.2794)
			(end -0.12065 0.3048)
			(stroke
				(width 0.1)
				(type default)
			)
			(layer "F.Fab")
		)
		(fp_line
			(start -0.12065 0.3048)
			(end -0.67945 0.3048)
			(stroke
				(width 0.1)
				(type default)
			)
			(layer "F.Fab")
		)
		(fp_line
			(start 0.120396 0.2794)
			(end -0.12065 0.2794)
			(stroke
				(width 0.1)
				(type default)
			)
			(layer "F.Fab")
		)
		(fp_line
			(start 0.120396 0.3048)
			(end 0.120396 0.2794)
			(stroke
				(width 0.1)
				(type default)
			)
			(layer "F.Fab")
		)
		(fp_line
			(start 0.12065 -0.3048)
			(end 0.67945 -0.3048)
			(stroke
				(width 0.1)
				(type default)
			)
			(layer "F.Fab")
		)
		(fp_line
			(start 0.12065 -0.2794)
			(end 0.12065 -0.3048)
			(stroke
				(width 0.1)
				(type default)
			)
			(layer "F.Fab")
		)
		(fp_line
			(start 0.67945 -0.3048)
			(end 0.67945 0.3048)
			(stroke
				(width 0.1)
				(type default)
			)
			(layer "F.Fab")
		)
		(fp_line
			(start 0.67945 0.3048)
			(end 0.120396 0.3048)
			(stroke
				(width 0.1)
				(type default)
			)
			(layer "F.Fab")
		)
		(pad "1" smd circle
			(at -0.40005 0)
			(size 0 0)
			(layers "F.Cu" "F.Mask" "F.Paste")
			(net "SMB_BIC_I2C9_SSD_MUX_R_SDA")
		)
		(pad "2" smd circle
			(at 0.40005 0)
			(size 0 0)
			(layers "F.Cu" "F.Mask" "F.Paste")
			(net "SMB_BIC_I2C9_SSD_MUX1_SDA")
		)
	)
	(footprint ""
		(layer "F.Cu")
		(at 91.624658 -115.835176 90)
		(property "Reference" "PU79"
			(at 1.70434 -3.349244 0)
			(unlocked yes)
			(layer "F.SilkS")
			(effects
				(font
					(size 0.7874 0.5842)
					(thickness 0.1524)
				)
			)
		)
		(property "Value" ""
			(at 0 0 90)
			(layer "F.Fab")
			(effects
				(font
					(size 1.27 1.27)
				)
			)
		)
		(duplicate_pad_numbers_are_jumpers no)
		(fp_line
			(start 1.239774 -1.495298)
			(end 1.239774 1.495298)
			(stroke
				(width 0.1524)
				(type default)
			)
			(layer "F.SilkS")
		)
		(fp_line
			(start -1.239774 -1.495298)
			(end 1.239774 -1.495298)
			(stroke
				(width 0.1524)
				(type default)
			)
			(layer "F.SilkS")
		)
		(fp_line
			(start 1.239774 1.495298)
			(end -1.239774 1.495298)
			(stroke
				(width 0.1524)
				(type default)
			)
			(layer "F.SilkS")
		)
		(fp_line
			(start -1.239774 1.495298)
			(end -1.239774 -1.495298)
			(stroke
				(width 0.1524)
				(type default)
			)
			(layer "F.SilkS")
		)
		(fp_poly
			(pts
				(xy -1.790954 -1.360932) (xy -2.50952 -0.64262) (xy -1.431798 -0.283464)
			)
			(stroke
				(width 0)
				(type default)
			)
			(fill yes)
			(layer "F.SilkS")
		)
		(fp_line
			(start 0.8001 -1.050036)
			(end 0.8001 1.050036)
			(stroke
				(width 0.1)
				(type default)
			)
			(layer "F.Fab")
		)
		(fp_line
			(start -0.8001 -1.050036)
			(end 0.8001 -1.050036)
			(stroke
				(width 0.1)
				(type default)
			)
			(layer "F.Fab")
		)
		(fp_line
			(start 0.8001 1.050036)
			(end -0.8001 1.050036)
			(stroke
				(width 0.1)
				(type default)
			)
			(layer "F.Fab")
		)
		(fp_line
			(start -0.8001 1.050036)
			(end -0.8001 -1.050036)
			(stroke
				(width 0.1)
				(type default)
			)
			(layer "F.Fab")
		)
		(fp_poly
			(pts
				(xy -2.458974 -0.508) (xy -2.458974 0.508) (xy -1.442974 0)
			)
			(stroke
				(width 0)
				(type default)
			)
			(fill yes)
			(layer "F.Fab")
		)
		(pad "1_2" smd circle
			(at -0.374904 0 180)
			(size 0 0)
			(layers "F.Cu" "F.Mask" "F.Paste")
			(net "P3V3_AUX")
		)
		(pad "3" smd rect
			(at -0.499872 0.999998 90)
			(size 0.254 0.7112)
			(layers "F.Cu" "F.Mask" "F.Paste")
			(net "GND")
		)
		(pad "4" smd rect
			(at 0 0.999998 90)
			(size 0.254 0.7112)
			(layers "F.Cu" "F.Mask" "F.Paste")
			(net "P3V3_NIC1_CO_ILIMIT")
		)
		(pad "5" smd rect
			(at 0.499872 0.999998 90)
			(size 0.254 0.7112)
			(layers "F.Cu" "F.Mask" "F.Paste")
			(net "P3V3_NIC1_CO_MODE")
		)
		(pad "6_7" smd circle
			(at 0.374904 0)
			(size 0 0)
			(layers "F.Cu" "F.Mask" "F.Paste")
			(net "P3V3_NIC1")
		)
		(pad "8" smd rect
			(at 0.499872 -0.999998 90)
			(size 0.254 0.7112)
			(layers "F.Cu" "F.Mask" "F.Paste")
			(net "P3V3_NIC1_CO_GATE")
		)
		(pad "9" smd rect
			(at 0 -0.999998 90)
			(size 0.254 0.7112)
			(layers "F.Cu" "F.Mask" "F.Paste")
			(net "P3V3_NIC1_CO_EN")
		)
		(pad "10" smd rect
			(at -0.499872 -0.999998 90)
			(size 0.254 0.7112)
			(layers "F.Cu" "F.Mask" "F.Paste")
			(net "P3V3_NIC1_CO_DV_DT")
		)
	)
	(footprint ""
		(layer "F.Cu")
		(at 380.717044 -308.852062 -135)
		(property "Reference" "R1462"
			(at 0 0 225)
			(layer "F.SilkS")
			(hide yes)
			(effects
				(font
					(size 1.27 1.27)
				)
			)
		)
		(property "Value" ""
			(at 0 0 225)
			(layer "F.Fab")
			(effects
				(font
					(size 1.27 1.27)
				)
			)
		)
		(duplicate_pad_numbers_are_jumpers no)
		(fp_line
			(start 0.787389 0.406267)
			(end -0.787389 0.406267)
			(stroke
				(width 0.1524)
				(type default)
			)
			(layer "F.SilkS")
		)
		(fp_line
			(start 0.787389 -0.406267)
			(end 0.787389 0.406267)
			(stroke
				(width 0.1524)
				(type default)
			)
			(layer "F.SilkS")
		)
		(fp_line
			(start -0.787389 0.406267)
			(end -0.787389 -0.406267)
			(stroke
				(width 0.1524)
				(type default)
			)
			(layer "F.SilkS")
		)
		(fp_line
			(start -0.787389 -0.406267)
			(end 0.787389 -0.406267)
			(stroke
				(width 0.1524)
				(type default)
			)
			(layer "F.SilkS")
		)
		(fp_line
			(start 0.679446 0.30479)
			(end 0.120515 0.30479)
			(stroke
				(width 0.1)
				(type default)
			)
			(layer "F.Fab")
		)
		(fp_line
			(start 0.120515 0.30479)
			(end 0.120335 0.279466)
			(stroke
				(width 0.1)
				(type default)
			)
			(layer "F.Fab")
		)
		(fp_line
			(start 0.120335 0.279466)
			(end -0.120695 0.279466)
			(stroke
				(width 0.1)
				(type default)
			)
			(layer "F.Fab")
		)
		(fp_line
			(start 0.679446 -0.30479)
			(end 0.679446 0.30479)
			(stroke
				(width 0.1)
				(type default)
			)
			(layer "F.Fab")
		)
		(fp_line
			(start -0.120515 0.30479)
			(end -0.679446 0.30479)
			(stroke
				(width 0.1)
				(type default)
			)
			(layer "F.Fab")
		)
		(fp_line
			(start -0.120695 0.279466)
			(end -0.120515 0.30479)
			(stroke
				(width 0.1)
				(type default)
			)
			(layer "F.Fab")
		)
		(fp_line
			(start 0.120695 -0.279466)
			(end 0.120515 -0.30479)
			(stroke
				(width 0.1)
				(type default)
			)
			(layer "F.Fab")
		)
		(fp_line
			(start 0.120515 -0.30479)
			(end 0.679446 -0.30479)
			(stroke
				(width 0.1)
				(type default)
			)
			(layer "F.Fab")
		)
		(fp_line
			(start -0.679446 0.30479)
			(end -0.679446 -0.305149)
			(stroke
				(width 0.1)
				(type default)
			)
			(layer "F.Fab")
		)
		(fp_line
			(start -0.120695 -0.279466)
			(end 0.120695 -0.279466)
			(stroke
				(width 0.1)
				(type default)
			)
			(layer "F.Fab")
		)
		(fp_line
			(start -0.120695 -0.304969)
			(end -0.120695 -0.279466)
			(stroke
				(width 0.1)
				(type default)
			)
			(layer "F.Fab")
		)
		(fp_line
			(start -0.679446 -0.305149)
			(end -0.120695 -0.304969)
			(stroke
				(width 0.1)
				(type default)
			)
			(layer "F.Fab")
		)
		(pad "1" smd circle
			(at -0.40005 0 225)
			(size 0 0)
			(layers "F.Cu" "F.Mask" "F.Paste")
			(net "PU_PEX3_ATPG_MODE_L")
		)
		(pad "2" smd circle
			(at 0.40005 0 225)
			(size 0 0)
			(layers "F.Cu" "F.Mask" "F.Paste")
			(net "P1V8_PEX")
		)
	)
	(footprint ""
		(layer "F.Cu")
		(at 73.289922 -72.766682 90)
		(property "Reference" "PR6910"
			(at 0 0 90)
			(layer "F.SilkS")
			(hide yes)
			(effects
				(font
					(size 1.27 1.27)
				)
			)
		)
		(property "Value" ""
			(at 0 0 90)
			(layer "F.Fab")
			(effects
				(font
					(size 1.27 1.27)
				)
			)
		)
		(duplicate_pad_numbers_are_jumpers no)
		(fp_line
			(start 0.7874 -0.4064)
			(end 0.7874 0.4064)
			(stroke
				(width 0.1524)
				(type default)
			)
			(layer "F.SilkS")
		)
		(fp_line
			(start -0.7874 -0.4064)
			(end 0.7874 -0.4064)
			(stroke
				(width 0.1524)
				(type default)
			)
			(layer "F.SilkS")
		)
		(fp_line
			(start 0.7874 0.4064)
			(end -0.7874 0.4064)
			(stroke
				(width 0.1524)
				(type default)
			)
			(layer "F.SilkS")
		)
		(fp_line
			(start -0.7874 0.4064)
			(end -0.7874 -0.4064)
			(stroke
				(width 0.1524)
				(type default)
			)
			(layer "F.SilkS")
		)
		(fp_line
			(start -0.12065 -0.305054)
			(end -0.12065 -0.2794)
			(stroke
				(width 0.1)
				(type default)
			)
			(layer "F.Fab")
		)
		(fp_line
			(start -0.67945 -0.305054)
			(end -0.12065 -0.305054)
			(stroke
				(width 0.1)
				(type default)
			)
			(layer "F.Fab")
		)
		(fp_line
			(start 0.67945 -0.3048)
			(end 0.67945 0.3048)
			(stroke
				(width 0.1)
				(type default)
			)
			(layer "F.Fab")
		)
		(fp_line
			(start 0.12065 -0.3048)
			(end 0.67945 -0.3048)
			(stroke
				(width 0.1)
				(type default)
			)
			(layer "F.Fab")
		)
		(fp_line
			(start 0.12065 -0.2794)
			(end 0.12065 -0.3048)
			(stroke
				(width 0.1)
				(type default)
			)
			(layer "F.Fab")
		)
		(fp_line
			(start -0.12065 -0.2794)
			(end 0.12065 -0.2794)
			(stroke
				(width 0.1)
				(type default)
			)
			(layer "F.Fab")
		)
		(fp_line
			(start 0.120396 0.2794)
			(end -0.12065 0.2794)
			(stroke
				(width 0.1)
				(type default)
			)
			(layer "F.Fab")
		)
		(fp_line
			(start -0.12065 0.2794)
			(end -0.12065 0.3048)
			(stroke
				(width 0.1)
				(type default)
			)
			(layer "F.Fab")
		)
		(fp_line
			(start 0.67945 0.3048)
			(end 0.120396 0.3048)
			(stroke
				(width 0.1)
				(type default)
			)
			(layer "F.Fab")
		)
		(fp_line
			(start 0.120396 0.3048)
			(end 0.120396 0.2794)
			(stroke
				(width 0.1)
				(type default)
			)
			(layer "F.Fab")
		)
		(fp_line
			(start -0.12065 0.3048)
			(end -0.67945 0.3048)
			(stroke
				(width 0.1)
				(type default)
			)
			(layer "F.Fab")
		)
		(fp_line
			(start -0.67945 0.3048)
			(end -0.67945 -0.305054)
			(stroke
				(width 0.1)
				(type default)
			)
			(layer "F.Fab")
		)
		(pad "1" smd circle
			(at -0.40005 0 90)
			(size 0 0)
			(layers "F.Cu" "F.Mask" "F.Paste")
			(net "P12V_SSD2_CO_ILIMIT")
		)
		(pad "2" smd circle
			(at 0.40005 0 90)
			(size 0 0)
			(layers "F.Cu" "F.Mask" "F.Paste")
			(net "GND")
		)
	)
	(footprint ""
		(layer "F.Cu")
		(at 214.310976 -367.019586 180)
		(property "Reference" "PR34"
			(at 0 0 180)
			(layer "F.SilkS")
			(hide yes)
			(effects
				(font
					(size 1.27 1.27)
				)
			)
		)
		(property "Value" ""
			(at 0 0 180)
			(layer "F.Fab")
			(effects
				(font
					(size 1.27 1.27)
				)
			)
		)
		(duplicate_pad_numbers_are_jumpers no)
		(fp_line
			(start 0.7874 0.4064)
			(end -0.7874 0.4064)
			(stroke
				(width 0.1524)
				(type default)
			)
			(layer "F.SilkS")
		)
		(fp_line
			(start 0.7874 -0.4064)
			(end 0.7874 0.4064)
			(stroke
				(width 0.1524)
				(type default)
			)
			(layer "F.SilkS")
		)
		(fp_line
			(start -0.7874 0.4064)
			(end -0.7874 -0.4064)
			(stroke
				(width 0.1524)
				(type default)
			)
			(layer "F.SilkS")
		)
		(fp_line
			(start -0.7874 -0.4064)
			(end 0.7874 -0.4064)
			(stroke
				(width 0.1524)
				(type default)
			)
			(layer "F.SilkS")
		)
		(fp_line
			(start 0.67945 0.3048)
			(end 0.120396 0.3048)
			(stroke
				(width 0.1)
				(type default)
			)
			(layer "F.Fab")
		)
		(fp_line
			(start 0.67945 -0.3048)
			(end 0.67945 0.3048)
			(stroke
				(width 0.1)
				(type default)
			)
			(layer "F.Fab")
		)
		(fp_line
			(start 0.12065 -0.2794)
			(end 0.12065 -0.3048)
			(stroke
				(width 0.1)
				(type default)
			)
			(layer "F.Fab")
		)
		(fp_line
			(start 0.12065 -0.3048)
			(end 0.67945 -0.3048)
			(stroke
				(width 0.1)
				(type default)
			)
			(layer "F.Fab")
		)
		(fp_line
			(start 0.120396 0.3048)
			(end 0.120396 0.2794)
			(stroke
				(width 0.1)
				(type default)
			)
			(layer "F.Fab")
		)
		(fp_line
			(start 0.120396 0.2794)
			(end -0.12065 0.2794)
			(stroke
				(width 0.1)
				(type default)
			)
			(layer "F.Fab")
		)
		(fp_line
			(start -0.12065 0.3048)
			(end -0.67945 0.3048)
			(stroke
				(width 0.1)
				(type default)
			)
			(layer "F.Fab")
		)
		(fp_line
			(start -0.12065 0.2794)
			(end -0.12065 0.3048)
			(stroke
				(width 0.1)
				(type default)
			)
			(layer "F.Fab")
		)
		(fp_line
			(start -0.12065 -0.2794)
			(end 0.12065 -0.2794)
			(stroke
				(width 0.1)
				(type default)
			)
			(layer "F.Fab")
		)
		(fp_line
			(start -0.12065 -0.305054)
			(end -0.12065 -0.2794)
			(stroke
				(width 0.1)
				(type default)
			)
			(layer "F.Fab")
		)
		(fp_line
			(start -0.67945 0.3048)
			(end -0.67945 -0.305054)
			(stroke
				(width 0.1)
				(type default)
			)
			(layer "F.Fab")
		)
		(fp_line
			(start -0.67945 -0.305054)
			(end -0.12065 -0.305054)
			(stroke
				(width 0.1)
				(type default)
			)
			(layer "F.Fab")
		)
		(pad "1" smd circle
			(at -0.40005 0 180)
			(size 0 0)
			(layers "F.Cu" "F.Mask" "F.Paste")
			(net "HSC_CS_1")
		)
		(pad "2" smd circle
			(at 0.40005 0 180)
			(size 0 0)
			(layers "F.Cu" "F.Mask" "F.Paste")
			(net "AGND_HSC")
		)
	)
	(footprint ""
		(layer "F.Cu")
		(at 155.380436 -133.129782)
		(property "Reference" "C249"
			(at 0 0 0)
			(layer "F.SilkS")
			(hide yes)
			(effects
				(font
					(size 1.27 1.27)
				)
			)
		)
		(property "Value" ""
			(at 0 0 0)
			(layer "F.Fab")
			(effects
				(font
					(size 1.27 1.27)
				)
			)
		)
		(duplicate_pad_numbers_are_jumpers no)
		(fp_line
			(start -0.299974 -0.150114)
			(end 0.299974 -0.150114)
			(stroke
				(width 0.1)
				(type default)
			)
			(layer "F.Fab")
		)
		(fp_line
			(start -0.299974 0.150114)
			(end -0.299974 -0.150114)
			(stroke
				(width 0.1)
				(type default)
			)
			(layer "F.Fab")
		)
		(fp_line
			(start 0.299974 -0.150114)
			(end 0.299974 0.150114)
			(stroke
				(width 0.1)
				(type default)
			)
			(layer "F.Fab")
		)
		(fp_line
			(start 0.299974 0.150114)
			(end -0.299974 0.150114)
			(stroke
				(width 0.1)
				(type default)
			)
			(layer "F.Fab")
		)
		(pad "1" smd rect
			(at -0.2667 0)
			(size 0.3048 0.381)
			(layers "F.Cu" "F.Mask" "F.Paste")
			(net "P5E_PEX1_STN1_TX_DP<29>")
		)
		(pad "2" smd rect
			(at 0.2667 0)
			(size 0.3048 0.381)
			(layers "F.Cu" "F.Mask" "F.Paste")
			(net "P5E_PEX1_STN1_TX_C_DP<29>")
		)
	)
	(footprint ""
		(layer "F.Cu")
		(at 284.226 -83.566 180)
		(property "Reference" "R486"
			(at 0 0 180)
			(layer "F.SilkS")
			(hide yes)
			(effects
				(font
					(size 1.27 1.27)
				)
			)
		)
		(property "Value" ""
			(at 0 0 180)
			(layer "F.Fab")
			(effects
				(font
					(size 1.27 1.27)
				)
			)
		)
		(duplicate_pad_numbers_are_jumpers no)
		(fp_line
			(start 0.7874 0.4064)
			(end -0.7874 0.4064)
			(stroke
				(width 0.1524)
				(type default)
			)
			(layer "F.SilkS")
		)
		(fp_line
			(start 0.7874 -0.4064)
			(end 0.7874 0.4064)
			(stroke
				(width 0.1524)
				(type default)
			)
			(layer "F.SilkS")
		)
		(fp_line
			(start -0.7874 0.4064)
			(end -0.7874 -0.4064)
			(stroke
				(width 0.1524)
				(type default)
			)
			(layer "F.SilkS")
		)
		(fp_line
			(start -0.7874 -0.4064)
			(end 0.7874 -0.4064)
			(stroke
				(width 0.1524)
				(type default)
			)
			(layer "F.SilkS")
		)
		(fp_line
			(start 0.67945 0.3048)
			(end 0.120396 0.3048)
			(stroke
				(width 0.1)
				(type default)
			)
			(layer "F.Fab")
		)
		(fp_line
			(start 0.67945 -0.3048)
			(end 0.67945 0.3048)
			(stroke
				(width 0.1)
				(type default)
			)
			(layer "F.Fab")
		)
		(fp_line
			(start 0.12065 -0.2794)
			(end 0.12065 -0.3048)
			(stroke
				(width 0.1)
				(type default)
			)
			(layer "F.Fab")
		)
		(fp_line
			(start 0.12065 -0.3048)
			(end 0.67945 -0.3048)
			(stroke
				(width 0.1)
				(type default)
			)
			(layer "F.Fab")
		)
		(fp_line
			(start 0.120396 0.3048)
			(end 0.120396 0.2794)
			(stroke
				(width 0.1)
				(type default)
			)
			(layer "F.Fab")
		)
		(fp_line
			(start 0.120396 0.2794)
			(end -0.12065 0.2794)
			(stroke
				(width 0.1)
				(type default)
			)
			(layer "F.Fab")
		)
		(fp_line
			(start -0.12065 0.3048)
			(end -0.67945 0.3048)
			(stroke
				(width 0.1)
				(type default)
			)
			(layer "F.Fab")
		)
		(fp_line
			(start -0.12065 0.2794)
			(end -0.12065 0.3048)
			(stroke
				(width 0.1)
				(type default)
			)
			(layer "F.Fab")
		)
		(fp_line
			(start -0.12065 -0.2794)
			(end 0.12065 -0.2794)
			(stroke
				(width 0.1)
				(type default)
			)
			(layer "F.Fab")
		)
		(fp_line
			(start -0.12065 -0.305054)
			(end -0.12065 -0.2794)
			(stroke
				(width 0.1)
				(type default)
			)
			(layer "F.Fab")
		)
		(fp_line
			(start -0.67945 0.3048)
			(end -0.67945 -0.305054)
			(stroke
				(width 0.1)
				(type default)
			)
			(layer "F.Fab")
		)
		(fp_line
			(start -0.67945 -0.305054)
			(end -0.12065 -0.305054)
			(stroke
				(width 0.1)
				(type default)
			)
			(layer "F.Fab")
		)
		(pad "1" smd circle
			(at -0.40005 0 180)
			(size 0 0)
			(layers "F.Cu" "F.Mask" "F.Paste")
			(net "BB_FRU_A2")
		)
		(pad "2" smd circle
			(at 0.40005 0 180)
			(size 0 0)
			(layers "F.Cu" "F.Mask" "F.Paste")
			(net "P3V3_AUX")
		)
	)
	(footprint ""
		(layer "F.Cu")
		(at 411.108652 -158.080202 90)
		(property "Reference" "R2477"
			(at 0 0 90)
			(layer "F.SilkS")
			(hide yes)
			(effects
				(font
					(size 1.27 1.27)
				)
			)
		)
		(property "Value" ""
			(at 0 0 90)
			(layer "F.Fab")
			(effects
				(font
					(size 1.27 1.27)
				)
			)
		)
		(duplicate_pad_numbers_are_jumpers no)
		(fp_line
			(start 0.7874 -0.4064)
			(end 0.7874 0.4064)
			(stroke
				(width 0.1524)
				(type default)
			)
			(layer "F.SilkS")
		)
		(fp_line
			(start -0.7874 -0.4064)
			(end 0.7874 -0.4064)
			(stroke
				(width 0.1524)
				(type default)
			)
			(layer "F.SilkS")
		)
		(fp_line
			(start 0.7874 0.4064)
			(end -0.7874 0.4064)
			(stroke
				(width 0.1524)
				(type default)
			)
			(layer "F.SilkS")
		)
		(fp_line
			(start -0.7874 0.4064)
			(end -0.7874 -0.4064)
			(stroke
				(width 0.1524)
				(type default)
			)
			(layer "F.SilkS")
		)
		(fp_line
			(start -0.12065 -0.305054)
			(end -0.12065 -0.2794)
			(stroke
				(width 0.1)
				(type default)
			)
			(layer "F.Fab")
		)
		(fp_line
			(start -0.67945 -0.305054)
			(end -0.12065 -0.305054)
			(stroke
				(width 0.1)
				(type default)
			)
			(layer "F.Fab")
		)
		(fp_line
			(start 0.67945 -0.3048)
			(end 0.67945 0.3048)
			(stroke
				(width 0.1)
				(type default)
			)
			(layer "F.Fab")
		)
		(fp_line
			(start 0.12065 -0.3048)
			(end 0.67945 -0.3048)
			(stroke
				(width 0.1)
				(type default)
			)
			(layer "F.Fab")
		)
		(fp_line
			(start 0.12065 -0.2794)
			(end 0.12065 -0.3048)
			(stroke
				(width 0.1)
				(type default)
			)
			(layer "F.Fab")
		)
		(fp_line
			(start -0.12065 -0.2794)
			(end 0.12065 -0.2794)
			(stroke
				(width 0.1)
				(type default)
			)
			(layer "F.Fab")
		)
		(fp_line
			(start 0.120396 0.2794)
			(end -0.12065 0.2794)
			(stroke
				(width 0.1)
				(type default)
			)
			(layer "F.Fab")
		)
		(fp_line
			(start -0.12065 0.2794)
			(end -0.12065 0.3048)
			(stroke
				(width 0.1)
				(type default)
			)
			(layer "F.Fab")
		)
		(fp_line
			(start 0.67945 0.3048)
			(end 0.120396 0.3048)
			(stroke
				(width 0.1)
				(type default)
			)
			(layer "F.Fab")
		)
		(fp_line
			(start 0.120396 0.3048)
			(end 0.120396 0.2794)
			(stroke
				(width 0.1)
				(type default)
			)
			(layer "F.Fab")
		)
		(fp_line
			(start -0.12065 0.3048)
			(end -0.67945 0.3048)
			(stroke
				(width 0.1)
				(type default)
			)
			(layer "F.Fab")
		)
		(fp_line
			(start -0.67945 0.3048)
			(end -0.67945 -0.305054)
			(stroke
				(width 0.1)
				(type default)
			)
			(layer "F.Fab")
		)
		(pad "1" smd circle
			(at -0.40005 0 90)
			(size 0 0)
			(layers "F.Cu" "F.Mask" "F.Paste")
			(net "P3V3_NIC7")
		)
		(pad "2" smd circle
			(at 0.40005 0 90)
			(size 0 0)
			(layers "F.Cu" "F.Mask" "F.Paste")
			(net "NIC7_PWRBRK_N")
		)
	)
	(footprint ""
		(layer "F.Cu")
		(at 170.59529 -35.48253)
		(property "Reference" "U389"
			(at -2.54762 1.09093 90)
			(unlocked yes)
			(layer "F.SilkS")
			(effects
				(font
					(size 0.7874 0.5842)
					(thickness 0.1524)
				)
				(justify left)
			)
		)
		(property "Value" ""
			(at 0 0 0)
			(layer "F.Fab")
			(effects
				(font
					(size 1.27 1.27)
				)
			)
		)
		(duplicate_pad_numbers_are_jumpers no)
		(fp_line
			(start -1.3462 -1.1938)
			(end -1.3462 1.1684)
			(stroke
				(width 0.1524)
				(type default)
			)
			(layer "F.SilkS")
		)
		(fp_line
			(start -1.3462 1.1938)
			(end 1.3462 1.1938)
			(stroke
				(width 0.1524)
				(type default)
			)
			(layer "F.SilkS")
		)
		(fp_line
			(start 1.3462 -1.1938)
			(end -1.3462 -1.1938)
			(stroke
				(width 0.1524)
				(type default)
			)
			(layer "F.SilkS")
		)
		(fp_line
			(start 1.3462 1.1938)
			(end 1.3462 -1.1938)
			(stroke
				(width 0.1524)
				(type default)
			)
			(layer "F.SilkS")
		)
		(fp_poly
			(pts
				(xy -1.447038 -0.760476) (xy -2.052066 -0.457962) (xy -2.052066 -1.06299)
			)
			(stroke
				(width 0)
				(type default)
			)
			(fill yes)
			(layer "F.SilkS")
		)
		(fp_line
			(start -0.674878 -1.124966)
			(end -0.674878 1.124966)
			(stroke
				(width 0.1)
				(type default)
			)
			(layer "F.Fab")
		)
		(fp_line
			(start -0.674878 1.124966)
			(end 0.674878 1.124966)
			(stroke
				(width 0.1)
				(type default)
			)
			(layer "F.Fab")
		)
		(fp_line
			(start 0.674878 -1.124966)
			(end -0.674878 -1.124966)
			(stroke
				(width 0.1)
				(type default)
			)
			(layer "F.Fab")
		)
		(fp_line
			(start 0.674878 1.124966)
			(end 0.674878 -1.124966)
			(stroke
				(width 0.1)
				(type default)
			)
			(layer "F.Fab")
		)
		(fp_poly
			(pts
				(xy -1.447038 -0.760476) (xy -2.052066 -0.457962) (xy -2.052066 -1.06299)
			)
			(stroke
				(width 0)
				(type default)
			)
			(fill yes)
			(layer "F.Fab")
		)
		(pad "1" smd rect
			(at -0.899922 -0.750062)
			(size 0.6096 0.6096)
			(layers "F.Cu" "F.Mask" "F.Paste")
			(net "PWRGD_P3V3_SSD6_R")
		)
		(pad "2" smd rect
			(at -0.899922 0 90)
			(size 0.4064 0.6096)
			(layers "F.Cu" "F.Mask" "F.Paste")
			(net "RST_SMB_SSD6_N")
		)
		(pad "3" smd rect
			(at -0.899922 0.750062)
			(size 0.6096 0.6096)
			(layers "F.Cu" "F.Mask" "F.Paste")
			(net "GND")
		)
		(pad "4" smd rect
			(at 0.899922 0.750062)
			(size 0.6096 0.6096)
			(layers "F.Cu" "F.Mask" "F.Paste")
			(net "RST_SMB_SSD6_ISO_N")
		)
		(pad "5" smd rect
			(at 0.899922 -0.750062)
			(size 0.6096 0.6096)
			(layers "F.Cu" "F.Mask" "F.Paste")
			(net "P3V3_AUX")
		)
	)
	(footprint ""
		(layer "F.Cu")
		(at 248.241058 -115.695476)
		(property "Reference" "PU119"
			(at -1.048258 2.209546 0)
			(unlocked yes)
			(layer "F.SilkS")
			(effects
				(font
					(size 0.7874 0.5842)
					(thickness 0.1524)
				)
			)
		)
		(property "Value" ""
			(at 0 0 0)
			(layer "F.Fab")
			(effects
				(font
					(size 1.27 1.27)
				)
			)
		)
		(duplicate_pad_numbers_are_jumpers no)
		(fp_line
			(start -1.239774 -1.495298)
			(end 1.239774 -1.495298)
			(stroke
				(width 0.1524)
				(type default)
			)
			(layer "F.SilkS")
		)
		(fp_line
			(start -1.239774 1.495298)
			(end -1.239774 -1.495298)
			(stroke
				(width 0.1524)
				(type default)
			)
			(layer "F.SilkS")
		)
		(fp_line
			(start 1.239774 -1.495298)
			(end 1.239774 1.495298)
			(stroke
				(width 0.1524)
				(type default)
			)
			(layer "F.SilkS")
		)
		(fp_line
			(start 1.239774 1.495298)
			(end -1.239774 1.495298)
			(stroke
				(width 0.1524)
				(type default)
			)
			(layer "F.SilkS")
		)
		(fp_poly
			(pts
				(xy -1.795272 -1.757934) (xy -2.513838 -1.039622) (xy -1.436116 -0.680466)
			)
			(stroke
				(width 0)
				(type default)
			)
			(fill yes)
			(layer "F.SilkS")
		)
		(fp_line
			(start -0.8001 -1.050036)
			(end 0.8001 -1.050036)
			(stroke
				(width 0.1)
				(type default)
			)
			(layer "F.Fab")
		)
		(fp_line
			(start -0.8001 1.050036)
			(end -0.8001 -1.050036)
			(stroke
				(width 0.1)
				(type default)
			)
			(layer "F.Fab")
		)
		(fp_line
			(start 0.8001 -1.050036)
			(end 0.8001 1.050036)
			(stroke
				(width 0.1)
				(type default)
			)
			(layer "F.Fab")
		)
		(fp_line
			(start 0.8001 1.050036)
			(end -0.8001 1.050036)
			(stroke
				(width 0.1)
				(type default)
			)
			(layer "F.Fab")
		)
		(fp_poly
			(pts
				(xy -2.458974 -0.508) (xy -2.458974 0.508) (xy -1.442974 0)
			)
			(stroke
				(width 0)
				(type default)
			)
			(fill yes)
			(layer "F.Fab")
		)
		(pad "1_2" smd circle
			(at -0.374904 0 90)
			(size 0 0)
			(layers "F.Cu" "F.Mask" "F.Paste")
			(net "P3V3_AUX")
		)
		(pad "3" smd rect
			(at -0.499872 0.999998)
			(size 0.254 0.7112)
			(layers "F.Cu" "F.Mask" "F.Paste")
			(net "GND")
		)
		(pad "4" smd rect
			(at 0 0.999998)
			(size 0.254 0.7112)
			(layers "F.Cu" "F.Mask" "F.Paste")
			(net "P3V3_NIC4_CO_ILIMIT")
		)
		(pad "5" smd rect
			(at 0.499872 0.999998)
			(size 0.254 0.7112)
			(layers "F.Cu" "F.Mask" "F.Paste")
			(net "P3V3_NIC4_CO_MODE")
		)
		(pad "6_7" smd circle
			(at 0.374904 0 270)
			(size 0 0)
			(layers "F.Cu" "F.Mask" "F.Paste")
			(net "P3V3_NIC4")
		)
		(pad "8" smd rect
			(at 0.499872 -0.999998)
			(size 0.254 0.7112)
			(layers "F.Cu" "F.Mask" "F.Paste")
			(net "P3V3_NIC4_CO_GATE")
		)
		(pad "9" smd rect
			(at 0 -0.999998)
			(size 0.254 0.7112)
			(layers "F.Cu" "F.Mask" "F.Paste")
			(net "P3V3_NIC4_CO_EN")
		)
		(pad "10" smd rect
			(at -0.499872 -0.999998)
			(size 0.254 0.7112)
			(layers "F.Cu" "F.Mask" "F.Paste")
			(net "P3V3_NIC4_CO_DV_DT")
		)
	)
	(footprint ""
		(layer "F.Cu")
		(at 159.910018 -412.090108)
		(property "Reference" "J5"
			(at -6.04647 3.572764 90)
			(unlocked yes)
			(layer "F.SilkS")
			(effects
				(font
					(size 2.032 1.524)
					(thickness 0.1524)
				)
				(justify left)
			)
		)
		(property "Value" ""
			(at 0 0 0)
			(layer "F.Fab")
			(effects
				(font
					(size 1.27 1.27)
				)
			)
		)
		(duplicate_pad_numbers_are_jumpers no)
		(fp_line
			(start -4.249928 -16.999966)
			(end 24.45004 -16.999966)
			(stroke
				(width 0.1524)
				(type default)
			)
			(layer "F.SilkS")
		)
		(fp_line
			(start -4.249928 46.019212)
			(end -4.249928 -16.999966)
			(stroke
				(width 0.1524)
				(type default)
			)
			(layer "F.SilkS")
		)
		(fp_line
			(start -4.249928 50.099976)
			(end -4.249928 47.08398)
			(stroke
				(width 0.1524)
				(type default)
			)
			(layer "F.SilkS")
		)
		(fp_line
			(start -1.249934 -13.999972)
			(end -1.249934 46.009814)
			(stroke
				(width 0.1524)
				(type default)
			)
			(layer "F.SilkS")
		)
		(fp_line
			(start -1.249934 -6.500114)
			(end 21.450046 -6.500114)
			(stroke
				(width 0.1524)
				(type default)
			)
			(layer "F.SilkS")
		)
		(fp_line
			(start -1.249934 47.099982)
			(end 6.63702 47.099982)
			(stroke
				(width 0.1524)
				(type default)
			)
			(layer "F.SilkS")
		)
		(fp_line
			(start 8.785352 47.099982)
			(end 15.282672 47.099982)
			(stroke
				(width 0.1524)
				(type default)
			)
			(layer "F.SilkS")
		)
		(fp_line
			(start 13.587984 50.099976)
			(end -4.249928 50.099976)
			(stroke
				(width 0.1524)
				(type default)
			)
			(layer "F.SilkS")
		)
		(fp_line
			(start 17.618964 47.099982)
			(end 21.450046 47.099982)
			(stroke
				(width 0.1524)
				(type default)
			)
			(layer "F.SilkS")
		)
		(fp_line
			(start 21.450046 -13.999972)
			(end -1.249934 -13.999972)
			(stroke
				(width 0.1524)
				(type default)
			)
			(layer "F.SilkS")
		)
		(fp_line
			(start 21.450046 47.099982)
			(end 21.450046 -13.999972)
			(stroke
				(width 0.1524)
				(type default)
			)
			(layer "F.SilkS")
		)
		(fp_line
			(start 22.40153 50.099976)
			(end 16.362934 50.099976)
			(stroke
				(width 0.1524)
				(type default)
			)
			(layer "F.SilkS")
		)
		(fp_line
			(start 24.45004 -16.999966)
			(end 24.45004 50.099976)
			(stroke
				(width 0.1524)
				(type default)
			)
			(layer "F.SilkS")
		)
		(fp_poly
			(pts
				(xy -2.413 -0.508) (xy -2.413 0.508) (xy -1.397 0)
			)
			(stroke
				(width 0)
				(type default)
			)
			(fill yes)
			(layer "F.SilkS")
		)
		(fp_line
			(start -4.249928 -16.999966)
			(end 24.45004 -16.999966)
			(stroke
				(width 0.1524)
				(type default)
			)
			(layer "B.SilkS")
		)
		(fp_line
			(start -4.249928 50.099976)
			(end -4.249928 -16.999966)
			(stroke
				(width 0.1524)
				(type default)
			)
			(layer "B.SilkS")
		)
		(fp_line
			(start 24.45004 -16.999966)
			(end 24.45004 50.099976)
			(stroke
				(width 0.1524)
				(type default)
			)
			(layer "B.SilkS")
		)
		(fp_line
			(start 24.45004 50.099976)
			(end -4.249928 50.099976)
			(stroke
				(width 0.1524)
				(type default)
			)
			(layer "B.SilkS")
		)
		(fp_line
			(start -4.249928 -16.999966)
			(end 24.45004 -16.999966)
			(stroke
				(width 0.1)
				(type default)
			)
			(layer "B.Fab")
		)
		(fp_line
			(start -4.249928 50.099976)
			(end -4.249928 -16.999966)
			(stroke
				(width 0.1)
				(type default)
			)
			(layer "B.Fab")
		)
		(fp_line
			(start 24.45004 -16.999966)
			(end 24.45004 50.099976)
			(stroke
				(width 0.1)
				(type default)
			)
			(layer "B.Fab")
		)
		(fp_line
			(start 24.45004 50.099976)
			(end -4.249928 50.099976)
			(stroke
				(width 0.1)
				(type default)
			)
			(layer "B.Fab")
		)
		(fp_line
			(start -1.249934 -13.999972)
			(end -1.249934 47.099982)
			(stroke
				(width 0.1)
				(type default)
			)
			(layer "F.Fab")
		)
		(fp_line
			(start -1.249934 47.099982)
			(end 21.450046 47.099982)
			(stroke
				(width 0.1)
				(type default)
			)
			(layer "F.Fab")
		)
		(fp_line
			(start 21.450046 -13.999972)
			(end -1.249934 -13.999972)
			(stroke
				(width 0.1)
				(type default)
			)
			(layer "F.Fab")
		)
		(fp_line
			(start 21.450046 47.099982)
			(end 21.450046 -13.999972)
			(stroke
				(width 0.1)
				(type default)
			)
			(layer "F.Fab")
		)
		(fp_poly
			(pts
				(xy -2.413 -0.508) (xy -2.413 0.508) (xy -1.397 0)
			)
			(stroke
				(width 0)
				(type default)
			)
			(fill yes)
			(layer "F.Fab")
		)
		(fp_text user "PRESS-FIT"
			(at 23.10257 41.843198 90)
			(unlocked yes)
			(layer "F.SilkS")
			(effects
				(font
					(size 1.905 1.4224)
					(thickness 0.1524)
				)
				(justify left)
			)
		)
		(fp_text user "PRESS-FIT"
			(at -5.52069 28.794202 90)
			(unlocked yes)
			(layer "B.SilkS")
			(effects
				(font
					(size 1.905 1.4224)
					(thickness 0.1524)
				)
				(justify left mirror)
			)
		)
		(fp_text user "PRESS-FIT"
			(at 18.326862 48.74895 0)
			(unlocked yes)
			(layer "B.Fab")
			(effects
				(font
					(size 1.905 1.4224)
					(thickness 0.1524)
				)
				(justify left mirror)
			)
		)
		(fp_text user "PRESS-FIT"
			(at 1.5875 48.73625 0)
			(unlocked yes)
			(layer "F.Fab")
			(effects
				(font
					(size 1.905 1.4224)
					(thickness 0.1524)
				)
				(justify left)
			)
		)
		(pad "A1" thru_hole rect
			(at 0 0 180)
			(size 0.71628 0.71628)
			(drill 0.30988)
			(layers "*.Cu" "*.Mask")
			(remove_unused_layers no)
			(net "GPU_FPGA_EROT_RECOV_R_N")
			(clearance 0.0508)
			(thermal_gap 0.0508)
			(padstack
				(mode front_inner_back)
				(layer "Inner"
					(shape circle)
					(size 0.71628 0.71628)
					(clearance 0.0508)
				)
				(layer "B.Cu"
					(shape rect)
					(size 0.71628 0.71628)
					(clearance 0.0508)
				)
			)
		)
		(pad "A2" thru_hole circle
			(at 2.199894 0.199898 180)
			(size 0.906272 0.906272)
			(drill 0.499872)
			(layers "*.Cu" "*.Mask")
			(remove_unused_layers no)
			(net "GND")
			(clearance 0.0508)
			(thermal_gap 0.0508)
		)
		(pad "A3" thru_hole circle
			(at 4.400042 0 180)
			(size 0.71628 0.71628)
			(drill 0.30988)
			(layers "*.Cu" "*.Mask")
			(remove_unused_layers no)
			(net "PRSNT_GPU_HMC_N")
			(clearance 0.0508)
			(thermal_gap 0.0508)
		)
		(pad "A4" thru_hole circle
			(at 6.599936 0.199898 180)
			(size 0.906272 0.906272)
			(drill 0.499872)
			(layers "*.Cu" "*.Mask")
			(remove_unused_layers no)
			(net "GND")
			(clearance 0.0508)
			(thermal_gap 0.0508)
		)
		(pad "A5" thru_hole circle
			(at 8.800084 0 180)
			(size 0.71628 0.71628)
			(drill 0.30988)
			(layers "*.Cu" "*.Mask")
			(remove_unused_layers no)
			(net "GPU_BASE_HMC_READY")
			(clearance 0.0508)
			(thermal_gap 0.0508)
		)
		(pad "A6" thru_hole circle
			(at 10.999978 0.199898 180)
			(size 0.906272 0.906272)
			(drill 0.499872)
			(layers "*.Cu" "*.Mask")
			(remove_unused_layers no)
			(net "GND")
			(clearance 0.0508)
			(thermal_gap 0.0508)
		)
		(pad "A7" thru_hole circle
			(at 13.199872 0 180)
			(size 0.71628 0.71628)
			(drill 0.30988)
			(layers "*.Cu" "*.Mask")
			(remove_unused_layers no)
			(net "GPU_BASE_STBY_EN_R")
			(clearance 0.0508)
			(thermal_gap 0.0508)
		)
		(pad "A8" thru_hole circle
			(at 15.40002 0.199898 180)
			(size 0.906272 0.906272)
			(drill 0.499872)
			(layers "*.Cu" "*.Mask")
			(remove_unused_layers no)
			(net "GND")
			(clearance 0.0508)
			(thermal_gap 0.0508)
		)
		(pad "A9" thru_hole circle
			(at 17.599914 0 180)
			(size 0.71628 0.71628)
			(drill 0.30988)
			(layers "*.Cu" "*.Mask")
			(remove_unused_layers no)
			(net "Net_40")
			(clearance 0.0508)
			(thermal_gap 0.0508)
		)
		(pad "A10" thru_hole circle
			(at 19.800062 0.199898 180)
			(size 0.906272 0.906272)
			(drill 0.499872)
			(layers "*.Cu" "*.Mask")
			(remove_unused_layers no)
			(net "GND")
			(clearance 0.0508)
			(thermal_gap 0.0508)
		)
		(pad "B1" thru_hole circle
			(at 0 1.299972 180)
			(size 0.906272 0.906272)
			(drill 0.499872)
			(layers "*.Cu" "*.Mask")
			(remove_unused_layers no)
			(net "GND")
			(clearance 0.0508)
			(thermal_gap 0.0508)
		)
		(pad "B3" thru_hole circle
			(at 4.400042 1.299972 180)
			(size 0.906272 0.906272)
			(drill 0.499872)
			(layers "*.Cu" "*.Mask")
			(remove_unused_layers no)
			(net "GND")
			(clearance 0.0508)
			(thermal_gap 0.0508)
		)
		(pad "B5" thru_hole circle
			(at 8.800084 1.299972 180)
			(size 0.906272 0.906272)
			(drill 0.499872)
			(layers "*.Cu" "*.Mask")
			(remove_unused_layers no)
			(net "GND")
			(clearance 0.0508)
			(thermal_gap 0.0508)
		)
		(pad "B7" thru_hole circle
			(at 13.199872 1.299972 180)
			(size 0.906272 0.906272)
			(drill 0.499872)
			(layers "*.Cu" "*.Mask")
			(remove_unused_layers no)
			(net "GND")
			(clearance 0.0508)
			(thermal_gap 0.0508)
		)
		(pad "B9" thru_hole circle
			(at 17.599914 1.299972 180)
			(size 0.906272 0.906272)
			(drill 0.499872)
			(layers "*.Cu" "*.Mask")
			(remove_unused_layers no)
			(net "GND")
			(clearance 0.0508)
			(thermal_gap 0.0508)
		)
		(pad "B10" thru_hole circle
			(at 19.800062 1.500124 180)
			(size 0.71628 0.71628)
			(drill 0.30988)
			(layers "*.Cu" "*.Mask")
			(remove_unused_layers no)
			(net "Net_8845")
			(clearance 0.0508)
			(thermal_gap 0.0508)
		)
		(pad "C9" thru_hole circle
			(at 17.599914 2.599944 180)
			(size 0.71628 0.71628)
			(drill 0.30988)
			(layers "*.Cu" "*.Mask")
			(remove_unused_layers no)
			(net "SMB_GPU2_ALERT_N")
			(clearance 0.0508)
			(thermal_gap 0.0508)
		)
		(pad "C10" thru_hole circle
			(at 19.800062 2.800096 180)
			(size 0.71628 0.71628)
			(drill 0.30988)
			(layers "*.Cu" "*.Mask")
			(remove_unused_layers no)
			(net "Net_8844")
			(clearance 0.0508)
			(thermal_gap 0.0508)
		)
		(pad "D2" thru_hole circle
			(at 2.199894 4.100068 180)
			(size 0.906272 0.906272)
			(drill 0.499872)
			(layers "*.Cu" "*.Mask")
			(remove_unused_layers no)
			(net "GND")
			(clearance 0.0508)
			(thermal_gap 0.0508)
		)
		(pad "D4" thru_hole circle
			(at 6.599936 4.100068 180)
			(size 0.906272 0.906272)
			(drill 0.499872)
			(layers "*.Cu" "*.Mask")
			(remove_unused_layers no)
			(net "GND")
			(clearance 0.0508)
			(thermal_gap 0.0508)
		)
		(pad "D6" thru_hole circle
			(at 10.999978 4.100068 180)
			(size 0.906272 0.906272)
			(drill 0.499872)
			(layers "*.Cu" "*.Mask")
			(remove_unused_layers no)
			(net "GND")
			(clearance 0.0508)
			(thermal_gap 0.0508)
		)
		(pad "D8" thru_hole circle
			(at 15.40002 4.100068 180)
			(size 0.906272 0.906272)
			(drill 0.499872)
			(layers "*.Cu" "*.Mask")
			(remove_unused_layers no)
			(net "GND")
			(clearance 0.0508)
			(thermal_gap 0.0508)
		)
		(pad "D9" thru_hole circle
			(at 17.599914 3.899916 180)
			(size 0.71628 0.71628)
			(drill 0.30988)
			(layers "*.Cu" "*.Mask")
			(remove_unused_layers no)
			(net "GPU_RSVD_PARTNER2")
			(clearance 0.0508)
			(thermal_gap 0.0508)
		)
		(pad "D10" thru_hole circle
			(at 19.800062 4.100068 180)
			(size 0.906272 0.906272)
			(drill 0.499872)
			(layers "*.Cu" "*.Mask")
			(remove_unused_layers no)
			(net "GND")
			(clearance 0.0508)
			(thermal_gap 0.0508)
		)
		(pad "E1" thru_hole circle
			(at 0 5.199888 180)
			(size 0.906272 0.906272)
			(drill 0.499872)
			(layers "*.Cu" "*.Mask")
			(remove_unused_layers no)
			(net "GND")
			(clearance 0.0508)
			(thermal_gap 0.0508)
		)
		(pad "E3" thru_hole circle
			(at 4.400042 5.199888 180)
			(size 0.906272 0.906272)
			(drill 0.499872)
			(layers "*.Cu" "*.Mask")
			(remove_unused_layers no)
			(net "GND")
			(clearance 0.0508)
			(thermal_gap 0.0508)
		)
		(pad "E5" thru_hole circle
			(at 8.800084 5.199888 180)
			(size 0.906272 0.906272)
			(drill 0.499872)
			(layers "*.Cu" "*.Mask")
			(remove_unused_layers no)
			(net "GND")
			(clearance 0.0508)
			(thermal_gap 0.0508)
		)
		(pad "E7" thru_hole circle
			(at 13.199872 5.199888 180)
			(size 0.906272 0.906272)
			(drill 0.499872)
			(layers "*.Cu" "*.Mask")
			(remove_unused_layers no)
			(net "GND")
			(clearance 0.0508)
			(thermal_gap 0.0508)
		)
		(pad "E9" thru_hole circle
			(at 17.599914 5.199888 180)
			(size 0.906272 0.906272)
			(drill 0.499872)
			(layers "*.Cu" "*.Mask")
			(remove_unused_layers no)
			(net "GND")
			(clearance 0.0508)
			(thermal_gap 0.0508)
		)
		(pad "E10" thru_hole circle
			(at 19.800062 5.40004 180)
			(size 0.71628 0.71628)
			(drill 0.30988)
			(layers "*.Cu" "*.Mask")
			(remove_unused_layers no)
			(net "Net_8843")
			(clearance 0.0508)
			(thermal_gap 0.0508)
		)
		(pad "F9" thru_hole circle
			(at 17.599914 6.500114 180)
			(size 0.71628 0.71628)
			(drill 0.30988)
			(layers "*.Cu" "*.Mask")
			(remove_unused_layers no)
			(net "SMB_GPU1_ALERT_N")
			(clearance 0.0508)
			(thermal_gap 0.0508)
		)
		(pad "F10" thru_hole circle
			(at 19.800062 6.700012 180)
			(size 0.71628 0.71628)
			(drill 0.30988)
			(layers "*.Cu" "*.Mask")
			(remove_unused_layers no)
			(net "Net_8842")
			(clearance 0.0508)
			(thermal_gap 0.0508)
		)
		(pad "G2" thru_hole circle
			(at 2.199894 7.999984 180)
			(size 0.906272 0.906272)
			(drill 0.499872)
			(layers "*.Cu" "*.Mask")
			(remove_unused_layers no)
			(net "GND")
			(clearance 0.0508)
			(thermal_gap 0.0508)
		)
		(pad "G4" thru_hole circle
			(at 6.599936 7.999984 180)
			(size 0.906272 0.906272)
			(drill 0.499872)
			(layers "*.Cu" "*.Mask")
			(remove_unused_layers no)
			(net "GND")
			(clearance 0.0508)
			(thermal_gap 0.0508)
		)
		(pad "G6" thru_hole circle
			(at 10.999978 7.999984 180)
			(size 0.906272 0.906272)
			(drill 0.499872)
			(layers "*.Cu" "*.Mask")
			(remove_unused_layers no)
			(net "GND")
			(clearance 0.0508)
			(thermal_gap 0.0508)
		)
		(pad "G8" thru_hole circle
			(at 15.40002 7.999984 180)
			(size 0.906272 0.906272)
			(drill 0.499872)
			(layers "*.Cu" "*.Mask")
			(remove_unused_layers no)
			(net "GND")
			(clearance 0.0508)
			(thermal_gap 0.0508)
		)
		(pad "G9" thru_hole circle
			(at 17.599914 7.800086 180)
			(size 0.71628 0.71628)
			(drill 0.30988)
			(layers "*.Cu" "*.Mask")
			(remove_unused_layers no)
			(net "GPU_RSVD_PARTNER1")
			(clearance 0.0508)
			(thermal_gap 0.0508)
		)
		(pad "G10" thru_hole circle
			(at 19.800062 7.999984 180)
			(size 0.906272 0.906272)
			(drill 0.499872)
			(layers "*.Cu" "*.Mask")
			(remove_unused_layers no)
			(net "GND")
			(clearance 0.0508)
			(thermal_gap 0.0508)
		)
		(pad "H1" thru_hole circle
			(at 0 9.100058 180)
			(size 0.906272 0.906272)
			(drill 0.499872)
			(layers "*.Cu" "*.Mask")
			(remove_unused_layers no)
			(net "GND")
			(clearance 0.0508)
			(thermal_gap 0.0508)
		)
		(pad "H3" thru_hole circle
			(at 4.400042 9.100058 180)
			(size 0.906272 0.906272)
			(drill 0.499872)
			(layers "*.Cu" "*.Mask")
			(remove_unused_layers no)
			(net "GND")
			(clearance 0.0508)
			(thermal_gap 0.0508)
		)
		(pad "H5" thru_hole circle
			(at 8.800084 9.100058 180)
			(size 0.906272 0.906272)
			(drill 0.499872)
			(layers "*.Cu" "*.Mask")
			(remove_unused_layers no)
			(net "GND")
			(clearance 0.0508)
			(thermal_gap 0.0508)
		)
		(pad "H7" thru_hole circle
			(at 13.199872 9.100058 180)
			(size 0.906272 0.906272)
			(drill 0.499872)
			(layers "*.Cu" "*.Mask")
			(remove_unused_layers no)
			(net "GND")
			(clearance 0.0508)
			(thermal_gap 0.0508)
		)
		(pad "H9" thru_hole circle
			(at 17.599914 9.100058 180)
			(size 0.906272 0.906272)
			(drill 0.499872)
			(layers "*.Cu" "*.Mask")
			(remove_unused_layers no)
			(net "GND")
			(clearance 0.0508)
			(thermal_gap 0.0508)
		)
		(pad "H10" thru_hole circle
			(at 19.800062 9.299956 180)
			(size 0.71628 0.71628)
			(drill 0.30988)
			(layers "*.Cu" "*.Mask")
			(remove_unused_layers no)
			(net "GPU_FPGA_BOOT_EN_R")
			(clearance 0.0508)
			(thermal_gap 0.0508)
		)
		(pad "I9" thru_hole circle
			(at 17.599914 10.40003 180)
			(size 0.71628 0.71628)
			(drill 0.30988)
			(layers "*.Cu" "*.Mask")
			(remove_unused_layers no)
			(net "Net_8841")
			(clearance 0.0508)
			(thermal_gap 0.0508)
		)
		(pad "I10" thru_hole circle
			(at 19.800062 10.599928 180)
			(size 0.71628 0.71628)
			(drill 0.30988)
			(layers "*.Cu" "*.Mask")
			(remove_unused_layers no)
			(net "GPU_RSVD_PARTNER0")
			(clearance 0.0508)
			(thermal_gap 0.0508)
		)
		(pad "J2" thru_hole circle
			(at 2.199894 11.8999 180)
			(size 0.906272 0.906272)
			(drill 0.499872)
			(layers "*.Cu" "*.Mask")
			(remove_unused_layers no)
			(net "GND")
			(clearance 0.0508)
			(thermal_gap 0.0508)
		)
		(pad "J4" thru_hole circle
			(at 6.599936 11.8999 180)
			(size 0.906272 0.906272)
			(drill 0.499872)
			(layers "*.Cu" "*.Mask")
			(remove_unused_layers no)
			(net "GND")
			(clearance 0.0508)
			(thermal_gap 0.0508)
		)
		(pad "J6" thru_hole circle
			(at 10.999978 11.8999 180)
			(size 0.906272 0.906272)
			(drill 0.499872)
			(layers "*.Cu" "*.Mask")
			(remove_unused_layers no)
			(net "GND")
			(clearance 0.0508)
			(thermal_gap 0.0508)
		)
		(pad "J8" thru_hole circle
			(at 15.40002 11.8999 180)
			(size 0.906272 0.906272)
			(drill 0.499872)
			(layers "*.Cu" "*.Mask")
			(remove_unused_layers no)
			(net "GND")
			(clearance 0.0508)
			(thermal_gap 0.0508)
		)
		(pad "J9" thru_hole circle
			(at 17.599914 11.700002 180)
			(size 0.71628 0.71628)
			(drill 0.30988)
			(layers "*.Cu" "*.Mask")
			(remove_unused_layers no)
			(net "Net_8840")
			(clearance 0.0508)
			(thermal_gap 0.0508)
		)
		(pad "J10" thru_hole circle
			(at 19.800062 11.8999 180)
			(size 0.906272 0.906272)
			(drill 0.499872)
			(layers "*.Cu" "*.Mask")
			(remove_unused_layers no)
			(net "GND")
			(clearance 0.0508)
			(thermal_gap 0.0508)
		)
		(pad "K1" thru_hole circle
			(at 0 12.999974 180)
			(size 0.906272 0.906272)
			(drill 0.499872)
			(layers "*.Cu" "*.Mask")
			(remove_unused_layers no)
			(net "GND")
			(clearance 0.0508)
			(thermal_gap 0.0508)
		)
		(pad "K3" thru_hole circle
			(at 4.400042 12.999974 180)
			(size 0.906272 0.906272)
			(drill 0.499872)
			(layers "*.Cu" "*.Mask")
			(remove_unused_layers no)
			(net "GND")
			(clearance 0.0508)
			(thermal_gap 0.0508)
		)
		(pad "K5" thru_hole circle
			(at 8.800084 12.999974 180)
			(size 0.906272 0.906272)
			(drill 0.499872)
			(layers "*.Cu" "*.Mask")
			(remove_unused_layers no)
			(net "GND")
			(clearance 0.0508)
			(thermal_gap 0.0508)
		)
		(pad "K7" thru_hole circle
			(at 13.199872 12.999974 180)
			(size 0.906272 0.906272)
			(drill 0.499872)
			(layers "*.Cu" "*.Mask")
			(remove_unused_layers no)
			(net "GND")
			(clearance 0.0508)
			(thermal_gap 0.0508)
		)
		(pad "K9" thru_hole circle
			(at 17.599914 12.999974 180)
			(size 0.906272 0.906272)
			(drill 0.499872)
			(layers "*.Cu" "*.Mask")
			(remove_unused_layers no)
			(net "GND")
			(clearance 0.0508)
			(thermal_gap 0.0508)
		)
		(pad "K10" thru_hole circle
			(at 19.800062 13.199872 180)
			(size 0.71628 0.71628)
			(drill 0.30988)
			(layers "*.Cu" "*.Mask")
			(remove_unused_layers no)
			(net "Net_8839")
			(clearance 0.0508)
			(thermal_gap 0.0508)
		)
		(pad "L9" thru_hole circle
			(at 17.599914 14.299946 180)
			(size 0.71628 0.71628)
			(drill 0.30988)
			(layers "*.Cu" "*.Mask")
			(remove_unused_layers no)
			(net "Net_8837")
			(clearance 0.0508)
			(thermal_gap 0.0508)
		)
		(pad "L10" thru_hole circle
			(at 19.800062 14.500098 180)
			(size 0.71628 0.71628)
			(drill 0.30988)
			(layers "*.Cu" "*.Mask")
			(remove_unused_layers no)
			(net "Net_8838")
			(clearance 0.0508)
			(thermal_gap 0.0508)
		)
		(pad "M1_2" thru_hole circle
			(at 2.199894 15.80007 180)
			(size 0.906272 0.906272)
			(drill 0.499872)
			(layers "*.Cu" "*.Mask")
			(remove_unused_layers no)
			(net "GND")
			(clearance 0.0508)
			(thermal_gap 0.0508)
		)
		(pad "M1_4" thru_hole circle
			(at 6.599936 15.80007 180)
			(size 0.906272 0.906272)
			(drill 0.499872)
			(layers "*.Cu" "*.Mask")
			(remove_unused_layers no)
			(net "GND")
			(clearance 0.0508)
			(thermal_gap 0.0508)
		)
		(pad "M1_6" thru_hole circle
			(at 10.999978 15.80007 180)
			(size 0.906272 0.906272)
			(drill 0.499872)
			(layers "*.Cu" "*.Mask")
			(remove_unused_layers no)
			(net "GND")
			(clearance 0.0508)
			(thermal_gap 0.0508)
		)
		(pad "M1_8" thru_hole circle
			(at 15.40002 15.80007 180)
			(size 0.906272 0.906272)
			(drill 0.499872)
			(layers "*.Cu" "*.Mask")
			(remove_unused_layers no)
			(net "GND")
			(clearance 0.0508)
			(thermal_gap 0.0508)
		)
		(pad "M1_10" thru_hole circle
			(at 19.800062 15.80007 180)
			(size 0.906272 0.906272)
			(drill 0.499872)
			(layers "*.Cu" "*.Mask")
			(remove_unused_layers no)
			(net "GND")
			(clearance 0.0508)
			(thermal_gap 0.0508)
		)
		(pad "M2_2" thru_hole circle
			(at 2.199894 26.2001 180)
			(size 0.906272 0.906272)
			(drill 0.499872)
			(layers "*.Cu" "*.Mask")
			(remove_unused_layers no)
			(net "GND")
			(clearance 0.0508)
			(thermal_gap 0.0508)
		)
		(pad "M2_4" thru_hole circle
			(at 6.599936 26.2001 180)
			(size 0.906272 0.906272)
			(drill 0.499872)
			(layers "*.Cu" "*.Mask")
			(remove_unused_layers no)
			(net "GND")
			(clearance 0.0508)
			(thermal_gap 0.0508)
		)
		(pad "M2_6" thru_hole circle
			(at 10.999978 26.2001 180)
			(size 0.906272 0.906272)
			(drill 0.499872)
			(layers "*.Cu" "*.Mask")
			(remove_unused_layers no)
			(net "GND")
			(clearance 0.0508)
			(thermal_gap 0.0508)
		)
		(pad "M2_8" thru_hole circle
			(at 15.40002 26.2001 180)
			(size 0.906272 0.906272)
			(drill 0.499872)
			(layers "*.Cu" "*.Mask")
			(remove_unused_layers no)
			(net "GND")
			(clearance 0.0508)
			(thermal_gap 0.0508)
		)
		(pad "M2_10" thru_hole circle
			(at 19.800062 26.2001 180)
			(size 0.906272 0.906272)
			(drill 0.499872)
			(layers "*.Cu" "*.Mask")
			(remove_unused_layers no)
			(net "GND")
			(clearance 0.0508)
			(thermal_gap 0.0508)
		)
		(pad "M9" thru_hole circle
			(at 17.599914 15.599918 180)
			(size 0.71628 0.71628)
			(drill 0.30988)
			(layers "*.Cu" "*.Mask")
			(remove_unused_layers no)
			(net "Net_8836")
			(clearance 0.0508)
			(thermal_gap 0.0508)
		)
		(pad "N1_1" thru_hole circle
			(at 0 16.89989 180)
			(size 0.906272 0.906272)
			(drill 0.499872)
			(layers "*.Cu" "*.Mask")
			(remove_unused_layers no)
			(net "GND")
			(clearance 0.0508)
			(thermal_gap 0.0508)
		)
		(pad "N1_3" thru_hole circle
			(at 4.400042 16.89989 180)
			(size 0.906272 0.906272)
			(drill 0.499872)
			(layers "*.Cu" "*.Mask")
			(remove_unused_layers no)
			(net "GND")
			(clearance 0.0508)
			(thermal_gap 0.0508)
		)
		(pad "N1_5" thru_hole circle
			(at 8.800084 16.89989 180)
			(size 0.906272 0.906272)
			(drill 0.499872)
			(layers "*.Cu" "*.Mask")
			(remove_unused_layers no)
			(net "GND")
			(clearance 0.0508)
			(thermal_gap 0.0508)
		)
		(pad "N1_7" thru_hole circle
			(at 13.199872 16.89989 180)
			(size 0.906272 0.906272)
			(drill 0.499872)
			(layers "*.Cu" "*.Mask")
			(remove_unused_layers no)
			(net "GND")
			(clearance 0.0508)
			(thermal_gap 0.0508)
		)
		(pad "N1_9" thru_hole circle
			(at 17.599914 16.89989 180)
			(size 0.906272 0.906272)
			(drill 0.499872)
			(layers "*.Cu" "*.Mask")
			(remove_unused_layers no)
			(net "GND")
			(clearance 0.0508)
			(thermal_gap 0.0508)
		)
		(pad "N2_1" thru_hole circle
			(at 0 27.29992 180)
			(size 0.906272 0.906272)
			(drill 0.499872)
			(layers "*.Cu" "*.Mask")
			(remove_unused_layers no)
			(net "GND")
			(clearance 0.0508)
			(thermal_gap 0.0508)
		)
		(pad "N2_3" thru_hole circle
			(at 4.400042 27.29992 180)
			(size 0.906272 0.906272)
			(drill 0.499872)
			(layers "*.Cu" "*.Mask")
			(remove_unused_layers no)
			(net "GND")
			(clearance 0.0508)
			(thermal_gap 0.0508)
		)
		(pad "N2_5" thru_hole circle
			(at 8.800084 27.29992 180)
			(size 0.906272 0.906272)
			(drill 0.499872)
			(layers "*.Cu" "*.Mask")
			(remove_unused_layers no)
			(net "GND")
			(clearance 0.0508)
			(thermal_gap 0.0508)
		)
		(pad "N2_7" thru_hole circle
			(at 13.199872 27.29992 180)
			(size 0.906272 0.906272)
			(drill 0.499872)
			(layers "*.Cu" "*.Mask")
			(remove_unused_layers no)
			(net "GND")
			(clearance 0.0508)
			(thermal_gap 0.0508)
		)
		(pad "N2_9" thru_hole circle
			(at 17.599914 27.29992 180)
			(size 0.906272 0.906272)
			(drill 0.499872)
			(layers "*.Cu" "*.Mask")
			(remove_unused_layers no)
			(net "GND")
			(clearance 0.0508)
			(thermal_gap 0.0508)
		)
		(pad "N10" thru_hole circle
			(at 19.800062 27.500072 180)
			(size 0.71628 0.71628)
			(drill 0.30988)
			(layers "*.Cu" "*.Mask")
			(remove_unused_layers no)
			(net "Net_8835")
			(clearance 0.0508)
			(thermal_gap 0.0508)
		)
		(pad "O9" thru_hole circle
			(at 17.599914 28.599892 180)
			(size 0.71628 0.71628)
			(drill 0.30988)
			(layers "*.Cu" "*.Mask")
			(remove_unused_layers no)
			(net "Net_8833")
			(clearance 0.0508)
			(thermal_gap 0.0508)
		)
		(pad "O10" thru_hole circle
			(at 19.800062 28.800044 180)
			(size 0.71628 0.71628)
			(drill 0.30988)
			(layers "*.Cu" "*.Mask")
			(remove_unused_layers no)
			(net "Net_8834")
			(clearance 0.0508)
			(thermal_gap 0.0508)
		)
		(pad "P2" thru_hole circle
			(at 2.199894 30.100016 180)
			(size 0.906272 0.906272)
			(drill 0.499872)
			(layers "*.Cu" "*.Mask")
			(remove_unused_layers no)
			(net "GND")
			(clearance 0.0508)
			(thermal_gap 0.0508)
		)
		(pad "P4" thru_hole circle
			(at 6.599936 30.100016 180)
			(size 0.906272 0.906272)
			(drill 0.499872)
			(layers "*.Cu" "*.Mask")
			(remove_unused_layers no)
			(net "GND")
			(clearance 0.0508)
			(thermal_gap 0.0508)
		)
		(pad "P6" thru_hole circle
			(at 10.999978 30.100016 180)
			(size 0.906272 0.906272)
			(drill 0.499872)
			(layers "*.Cu" "*.Mask")
			(remove_unused_layers no)
			(net "GND")
			(clearance 0.0508)
			(thermal_gap 0.0508)
		)
		(pad "P8" thru_hole circle
			(at 15.40002 30.100016 180)
			(size 0.906272 0.906272)
			(drill 0.499872)
			(layers "*.Cu" "*.Mask")
			(remove_unused_layers no)
			(net "GND")
			(clearance 0.0508)
			(thermal_gap 0.0508)
		)
		(pad "P9" thru_hole circle
			(at 17.599914 29.900118 180)
			(size 0.71628 0.71628)
			(drill 0.30988)
			(layers "*.Cu" "*.Mask")
			(remove_unused_layers no)
			(net "Net_8832")
			(clearance 0.0508)
			(thermal_gap 0.0508)
		)
		(pad "P10" thru_hole circle
			(at 19.800062 30.100016 180)
			(size 0.906272 0.906272)
			(drill 0.499872)
			(layers "*.Cu" "*.Mask")
			(remove_unused_layers no)
			(net "GND")
			(clearance 0.0508)
			(thermal_gap 0.0508)
		)
		(pad "Q1" thru_hole circle
			(at 0 31.20009 180)
			(size 0.906272 0.906272)
			(drill 0.499872)
			(layers "*.Cu" "*.Mask")
			(remove_unused_layers no)
			(net "GND")
			(clearance 0.0508)
			(thermal_gap 0.0508)
		)
		(pad "Q3" thru_hole circle
			(at 4.400042 31.20009 180)
			(size 0.906272 0.906272)
			(drill 0.499872)
			(layers "*.Cu" "*.Mask")
			(remove_unused_layers no)
			(net "GND")
			(clearance 0.0508)
			(thermal_gap 0.0508)
		)
		(pad "Q5" thru_hole circle
			(at 8.800084 31.20009 180)
			(size 0.906272 0.906272)
			(drill 0.499872)
			(layers "*.Cu" "*.Mask")
			(remove_unused_layers no)
			(net "GND")
			(clearance 0.0508)
			(thermal_gap 0.0508)
		)
		(pad "Q7" thru_hole circle
			(at 13.199872 31.20009 180)
			(size 0.906272 0.906272)
			(drill 0.499872)
			(layers "*.Cu" "*.Mask")
			(remove_unused_layers no)
			(net "GND")
			(clearance 0.0508)
			(thermal_gap 0.0508)
		)
		(pad "Q9" thru_hole circle
			(at 17.599914 31.20009 180)
			(size 0.906272 0.906272)
			(drill 0.499872)
			(layers "*.Cu" "*.Mask")
			(remove_unused_layers no)
			(net "GND")
			(clearance 0.0508)
			(thermal_gap 0.0508)
		)
		(pad "Q10" thru_hole circle
			(at 19.800062 31.399988 180)
			(size 0.71628 0.71628)
			(drill 0.30988)
			(layers "*.Cu" "*.Mask")
			(remove_unused_layers no)
			(net "Net_8831")
			(clearance 0.0508)
			(thermal_gap 0.0508)
		)
		(pad "R9" thru_hole circle
			(at 17.599914 32.500062 180)
			(size 0.71628 0.71628)
			(drill 0.30988)
			(layers "*.Cu" "*.Mask")
			(remove_unused_layers no)
			(net "Net_8829")
			(clearance 0.0508)
			(thermal_gap 0.0508)
		)
		(pad "R10" thru_hole circle
			(at 19.800062 32.69996 180)
			(size 0.71628 0.71628)
			(drill 0.30988)
			(layers "*.Cu" "*.Mask")
			(remove_unused_layers no)
			(net "Net_8830")
			(clearance 0.0508)
			(thermal_gap 0.0508)
		)
		(pad "S2" thru_hole circle
			(at 2.199894 33.999932 180)
			(size 0.906272 0.906272)
			(drill 0.499872)
			(layers "*.Cu" "*.Mask")
			(remove_unused_layers no)
			(net "GND")
			(clearance 0.0508)
			(thermal_gap 0.0508)
		)
		(pad "S4" thru_hole circle
			(at 6.599936 33.999932 180)
			(size 0.906272 0.906272)
			(drill 0.499872)
			(layers "*.Cu" "*.Mask")
			(remove_unused_layers no)
			(net "GND")
			(clearance 0.0508)
			(thermal_gap 0.0508)
		)
		(pad "S6" thru_hole circle
			(at 10.999978 33.999932 180)
			(size 0.906272 0.906272)
			(drill 0.499872)
			(layers "*.Cu" "*.Mask")
			(remove_unused_layers no)
			(net "GND")
			(clearance 0.0508)
			(thermal_gap 0.0508)
		)
		(pad "S8" thru_hole circle
			(at 15.40002 33.999932 180)
			(size 0.906272 0.906272)
			(drill 0.499872)
			(layers "*.Cu" "*.Mask")
			(remove_unused_layers no)
			(net "GND")
			(clearance 0.0508)
			(thermal_gap 0.0508)
		)
		(pad "S9" thru_hole circle
			(at 17.599914 33.800034 180)
			(size 0.71628 0.71628)
			(drill 0.30988)
			(layers "*.Cu" "*.Mask")
			(remove_unused_layers no)
			(net "Net_8828")
			(clearance 0.0508)
			(thermal_gap 0.0508)
		)
		(pad "S10" thru_hole circle
			(at 19.800062 33.999932 180)
			(size 0.906272 0.906272)
			(drill 0.499872)
			(layers "*.Cu" "*.Mask")
			(remove_unused_layers no)
			(net "GND")
			(clearance 0.0508)
			(thermal_gap 0.0508)
		)
		(pad "T1" thru_hole circle
			(at 0 35.100006 180)
			(size 0.906272 0.906272)
			(drill 0.499872)
			(layers "*.Cu" "*.Mask")
			(remove_unused_layers no)
			(net "GND")
			(clearance 0.0508)
			(thermal_gap 0.0508)
		)
		(pad "T3" thru_hole circle
			(at 4.400042 35.100006 180)
			(size 0.906272 0.906272)
			(drill 0.499872)
			(layers "*.Cu" "*.Mask")
			(remove_unused_layers no)
			(net "GND")
			(clearance 0.0508)
			(thermal_gap 0.0508)
		)
		(pad "T5" thru_hole circle
			(at 8.800084 35.100006 180)
			(size 0.906272 0.906272)
			(drill 0.499872)
			(layers "*.Cu" "*.Mask")
			(remove_unused_layers no)
			(net "GND")
			(clearance 0.0508)
			(thermal_gap 0.0508)
		)
		(pad "T7" thru_hole circle
			(at 13.199872 35.100006 180)
			(size 0.906272 0.906272)
			(drill 0.499872)
			(layers "*.Cu" "*.Mask")
			(remove_unused_layers no)
			(net "GND")
			(clearance 0.0508)
			(thermal_gap 0.0508)
		)
		(pad "T9" thru_hole circle
			(at 17.599914 35.100006 180)
			(size 0.906272 0.906272)
			(drill 0.499872)
			(layers "*.Cu" "*.Mask")
			(remove_unused_layers no)
			(net "GND")
			(clearance 0.0508)
			(thermal_gap 0.0508)
		)
		(pad "T10" thru_hole circle
			(at 19.800062 35.299904 180)
			(size 0.71628 0.71628)
			(drill 0.30988)
			(layers "*.Cu" "*.Mask")
			(remove_unused_layers no)
			(net "Net_8827")
			(clearance 0.0508)
			(thermal_gap 0.0508)
		)
		(pad "U9" thru_hole circle
			(at 17.599914 36.399978 180)
			(size 0.71628 0.71628)
			(drill 0.30988)
			(layers "*.Cu" "*.Mask")
			(remove_unused_layers no)
			(net "Net_8825")
			(clearance 0.0508)
			(thermal_gap 0.0508)
		)
		(pad "U10" thru_hole circle
			(at 19.800062 36.599876 180)
			(size 0.71628 0.71628)
			(drill 0.30988)
			(layers "*.Cu" "*.Mask")
			(remove_unused_layers no)
			(net "Net_8826")
			(clearance 0.0508)
			(thermal_gap 0.0508)
		)
		(pad "V2" thru_hole circle
			(at 2.199894 37.900102 180)
			(size 0.906272 0.906272)
			(drill 0.499872)
			(layers "*.Cu" "*.Mask")
			(remove_unused_layers no)
			(net "GND")
			(clearance 0.0508)
			(thermal_gap 0.0508)
		)
		(pad "V4" thru_hole circle
			(at 6.599936 37.900102 180)
			(size 0.906272 0.906272)
			(drill 0.499872)
			(layers "*.Cu" "*.Mask")
			(remove_unused_layers no)
			(net "GND")
			(clearance 0.0508)
			(thermal_gap 0.0508)
		)
		(pad "V6" thru_hole circle
			(at 10.999978 37.900102 180)
			(size 0.906272 0.906272)
			(drill 0.499872)
			(layers "*.Cu" "*.Mask")
			(remove_unused_layers no)
			(net "GND")
			(clearance 0.0508)
			(thermal_gap 0.0508)
		)
		(pad "V8" thru_hole circle
			(at 15.40002 37.900102 180)
			(size 0.906272 0.906272)
			(drill 0.499872)
			(layers "*.Cu" "*.Mask")
			(remove_unused_layers no)
			(net "GND")
			(clearance 0.0508)
			(thermal_gap 0.0508)
		)
		(pad "V9" thru_hole circle
			(at 17.599914 37.69995 180)
			(size 0.71628 0.71628)
			(drill 0.30988)
			(layers "*.Cu" "*.Mask")
			(remove_unused_layers no)
			(net "Net_8824")
			(clearance 0.0508)
			(thermal_gap 0.0508)
		)
		(pad "V10" thru_hole circle
			(at 19.800062 37.900102 180)
			(size 0.906272 0.906272)
			(drill 0.499872)
			(layers "*.Cu" "*.Mask")
			(remove_unused_layers no)
			(net "GND")
			(clearance 0.0508)
			(thermal_gap 0.0508)
		)
		(pad "W1" thru_hole circle
			(at 0 38.999922 180)
			(size 0.906272 0.906272)
			(drill 0.499872)
			(layers "*.Cu" "*.Mask")
			(remove_unused_layers no)
			(net "GND")
			(clearance 0.0508)
			(thermal_gap 0.0508)
		)
		(pad "W3" thru_hole circle
			(at 4.400042 38.999922 180)
			(size 0.906272 0.906272)
			(drill 0.499872)
			(layers "*.Cu" "*.Mask")
			(remove_unused_layers no)
			(net "GND")
			(clearance 0.0508)
			(thermal_gap 0.0508)
		)
		(pad "W5" thru_hole circle
			(at 8.800084 38.999922 180)
			(size 0.906272 0.906272)
			(drill 0.499872)
			(layers "*.Cu" "*.Mask")
			(remove_unused_layers no)
			(net "GND")
			(clearance 0.0508)
			(thermal_gap 0.0508)
		)
		(pad "W7" thru_hole circle
			(at 13.199872 38.999922 180)
			(size 0.906272 0.906272)
			(drill 0.499872)
			(layers "*.Cu" "*.Mask")
			(remove_unused_layers no)
			(net "GND")
			(clearance 0.0508)
			(thermal_gap 0.0508)
		)
		(pad "W9" thru_hole circle
			(at 17.599914 38.999922 180)
			(size 0.906272 0.906272)
			(drill 0.499872)
			(layers "*.Cu" "*.Mask")
			(remove_unused_layers no)
			(net "GND")
			(clearance 0.0508)
			(thermal_gap 0.0508)
		)
		(pad "W10" thru_hole circle
			(at 19.800062 39.200074 180)
			(size 0.71628 0.71628)
			(drill 0.30988)
			(layers "*.Cu" "*.Mask")
			(remove_unused_layers no)
			(net "Net_8823")
			(clearance 0.0508)
			(thermal_gap 0.0508)
		)
		(pad "X9" thru_hole circle
			(at 17.599914 40.299894 180)
			(size 0.71628 0.71628)
			(drill 0.30988)
			(layers "*.Cu" "*.Mask")
			(remove_unused_layers no)
			(net "Net_8821")
			(clearance 0.0508)
			(thermal_gap 0.0508)
		)
		(pad "X10" thru_hole circle
			(at 19.800062 40.500046 180)
			(size 0.71628 0.71628)
			(drill 0.30988)
			(layers "*.Cu" "*.Mask")
			(remove_unused_layers no)
			(net "Net_8822")
			(clearance 0.0508)
			(thermal_gap 0.0508)
		)
		(pad "Y2" thru_hole circle
			(at 2.199894 41.800018 180)
			(size 0.906272 0.906272)
			(drill 0.499872)
			(layers "*.Cu" "*.Mask")
			(remove_unused_layers no)
			(net "GND")
			(clearance 0.0508)
			(thermal_gap 0.0508)
		)
		(pad "Y4" thru_hole circle
			(at 6.599936 41.800018 180)
			(size 0.906272 0.906272)
			(drill 0.499872)
			(layers "*.Cu" "*.Mask")
			(remove_unused_layers no)
			(net "GND")
			(clearance 0.0508)
			(thermal_gap 0.0508)
		)
		(pad "Y6" thru_hole circle
			(at 10.999978 41.800018 180)
			(size 0.906272 0.906272)
			(drill 0.499872)
			(layers "*.Cu" "*.Mask")
			(remove_unused_layers no)
			(net "GND")
			(clearance 0.0508)
			(thermal_gap 0.0508)
		)
		(pad "Y8" thru_hole circle
			(at 15.40002 41.800018 180)
			(size 0.906272 0.906272)
			(drill 0.499872)
			(layers "*.Cu" "*.Mask")
			(remove_unused_layers no)
			(net "GND")
			(clearance 0.0508)
			(thermal_gap 0.0508)
		)
		(pad "Y9" thru_hole circle
			(at 17.599914 41.60012 180)
			(size 0.71628 0.71628)
			(drill 0.30988)
			(layers "*.Cu" "*.Mask")
			(remove_unused_layers no)
			(net "Net_8820")
			(clearance 0.0508)
			(thermal_gap 0.0508)
		)
		(pad "Y10" thru_hole circle
			(at 19.800062 41.800018 180)
			(size 0.906272 0.906272)
			(drill 0.499872)
			(layers "*.Cu" "*.Mask")
			(remove_unused_layers no)
			(net "GND")
			(clearance 0.0508)
			(thermal_gap 0.0508)
		)
		(pad "Z1" thru_hole circle
			(at 0 42.900092 180)
			(size 0.906272 0.906272)
			(drill 0.499872)
			(layers "*.Cu" "*.Mask")
			(remove_unused_layers no)
			(net "GND")
			(clearance 0.0508)
			(thermal_gap 0.0508)
		)
		(pad "Z2" thru_hole circle
			(at 2.199894 43.09999 180)
			(size 0.71628 0.71628)
			(drill 0.30988)
			(layers "*.Cu" "*.Mask")
			(remove_unused_layers no)
			(net "GPU_FPGA_EROT_FATALERR_N")
			(clearance 0.0508)
			(thermal_gap 0.0508)
		)
		(pad "Z3" thru_hole circle
			(at 4.400042 42.900092 180)
			(size 0.906272 0.906272)
			(drill 0.499872)
			(layers "*.Cu" "*.Mask")
			(remove_unused_layers no)
			(net "GND")
			(clearance 0.0508)
			(thermal_gap 0.0508)
		)
		(pad "Z4" thru_hole circle
			(at 6.599936 43.09999 180)
			(size 0.71628 0.71628)
			(drill 0.30988)
			(layers "*.Cu" "*.Mask")
			(remove_unused_layers no)
			(net "GPU_3V3IO_RSVD0_FFU")
			(clearance 0.0508)
			(thermal_gap 0.0508)
		)
		(pad "Z5" thru_hole circle
			(at 8.800084 42.900092 180)
			(size 0.906272 0.906272)
			(drill 0.499872)
			(layers "*.Cu" "*.Mask")
			(remove_unused_layers no)
			(net "GND")
			(clearance 0.0508)
			(thermal_gap 0.0508)
		)
		(pad "Z6" thru_hole circle
			(at 10.999978 43.09999 180)
			(size 0.71628 0.71628)
			(drill 0.30988)
			(layers "*.Cu" "*.Mask")
			(remove_unused_layers no)
			(net "GPU_3V3IO_RSVD1_FFU")
			(clearance 0.0508)
			(thermal_gap 0.0508)
		)
		(pad "Z7" thru_hole circle
			(at 13.199872 42.900092 180)
			(size 0.906272 0.906272)
			(drill 0.499872)
			(layers "*.Cu" "*.Mask")
			(remove_unused_layers no)
			(net "GND")
			(clearance 0.0508)
			(thermal_gap 0.0508)
		)
		(pad "Z8" thru_hole circle
			(at 15.40002 43.09999 180)
			(size 0.71628 0.71628)
			(drill 0.30988)
			(layers "*.Cu" "*.Mask")
			(remove_unused_layers no)
			(net "PRSNT_GPU_A3_N")
			(clearance 0.0508)
			(thermal_gap 0.0508)
		)
		(pad "Z9" thru_hole circle
			(at 17.599914 42.900092 180)
			(size 0.906272 0.906272)
			(drill 0.499872)
			(layers "*.Cu" "*.Mask")
			(remove_unused_layers no)
			(net "GND")
			(clearance 0.0508)
			(thermal_gap 0.0508)
		)
		(pad "Z10" thru_hole circle
			(at 19.800062 43.09999 180)
			(size 0.71628 0.71628)
			(drill 0.30988)
			(layers "*.Cu" "*.Mask")
			(remove_unused_layers no)
			(net "RST_GPU_FPGA_EROT_R_N")
			(clearance 0.0508)
			(thermal_gap 0.0508)
		)
		(zone
			(layer "B.Cu")
			(hatch none 0.5)
			(connect_pads
				(clearance 0)
			)
			(min_thickness 0.25)
			(keepout
				(tracks allowed)
				(vias not_allowed)
				(pads allowed)
				(copperpour not_allowed)
				(footprints allowed)
			)
			(placement
				(enabled no)
				(sheetname "")
			)
			(fill
				(thermal_gap 0.5)
				(thermal_bridge_width 0.5)
				(island_removal_mode 0)
			)
			(polygon
				(pts
					(xy 159.392874 -394.665708) (xy 180.220874 -394.665708) (xy 180.220874 -412.50743) (xy 159.392874 -412.50743)
				)
			)
		)
		(zone
			(layer "B.Cu")
			(hatch none 0.5)
			(connect_pads
				(clearance 0)
			)
			(min_thickness 0.25)
			(keepout
				(tracks allowed)
				(vias not_allowed)
				(pads allowed)
				(copperpour not_allowed)
				(footprints allowed)
			)
			(placement
				(enabled no)
				(sheetname "")
			)
			(fill
				(thermal_gap 0.5)
				(thermal_bridge_width 0.5)
				(island_removal_mode 0)
			)
			(polygon
				(pts
					(xy 159.392874 -368.572796) (xy 180.220874 -368.572796) (xy 180.220874 -386.414518) (xy 159.392874 -386.414518)
				)
			)
		)
	)
	(footprint ""
		(layer "F.Cu")
		(at 21.290026 -72.766682 90)
		(property "Reference" "PR6905"
			(at 0 0 90)
			(layer "F.SilkS")
			(hide yes)
			(effects
				(font
					(size 1.27 1.27)
				)
			)
		)
		(property "Value" ""
			(at 0 0 90)
			(layer "F.Fab")
			(effects
				(font
					(size 1.27 1.27)
				)
			)
		)
		(duplicate_pad_numbers_are_jumpers no)
		(fp_line
			(start 0.7874 -0.4064)
			(end 0.7874 0.4064)
			(stroke
				(width 0.1524)
				(type default)
			)
			(layer "F.SilkS")
		)
		(fp_line
			(start -0.7874 -0.4064)
			(end 0.7874 -0.4064)
			(stroke
				(width 0.1524)
				(type default)
			)
			(layer "F.SilkS")
		)
		(fp_line
			(start 0.7874 0.4064)
			(end -0.7874 0.4064)
			(stroke
				(width 0.1524)
				(type default)
			)
			(layer "F.SilkS")
		)
		(fp_line
			(start -0.7874 0.4064)
			(end -0.7874 -0.4064)
			(stroke
				(width 0.1524)
				(type default)
			)
			(layer "F.SilkS")
		)
		(fp_line
			(start -0.12065 -0.305054)
			(end -0.12065 -0.2794)
			(stroke
				(width 0.1)
				(type default)
			)
			(layer "F.Fab")
		)
		(fp_line
			(start -0.67945 -0.305054)
			(end -0.12065 -0.305054)
			(stroke
				(width 0.1)
				(type default)
			)
			(layer "F.Fab")
		)
		(fp_line
			(start 0.67945 -0.3048)
			(end 0.67945 0.3048)
			(stroke
				(width 0.1)
				(type default)
			)
			(layer "F.Fab")
		)
		(fp_line
			(start 0.12065 -0.3048)
			(end 0.67945 -0.3048)
			(stroke
				(width 0.1)
				(type default)
			)
			(layer "F.Fab")
		)
		(fp_line
			(start 0.12065 -0.2794)
			(end 0.12065 -0.3048)
			(stroke
				(width 0.1)
				(type default)
			)
			(layer "F.Fab")
		)
		(fp_line
			(start -0.12065 -0.2794)
			(end 0.12065 -0.2794)
			(stroke
				(width 0.1)
				(type default)
			)
			(layer "F.Fab")
		)
		(fp_line
			(start 0.120396 0.2794)
			(end -0.12065 0.2794)
			(stroke
				(width 0.1)
				(type default)
			)
			(layer "F.Fab")
		)
		(fp_line
			(start -0.12065 0.2794)
			(end -0.12065 0.3048)
			(stroke
				(width 0.1)
				(type default)
			)
			(layer "F.Fab")
		)
		(fp_line
			(start 0.67945 0.3048)
			(end 0.120396 0.3048)
			(stroke
				(width 0.1)
				(type default)
			)
			(layer "F.Fab")
		)
		(fp_line
			(start 0.120396 0.3048)
			(end 0.120396 0.2794)
			(stroke
				(width 0.1)
				(type default)
			)
			(layer "F.Fab")
		)
		(fp_line
			(start -0.12065 0.3048)
			(end -0.67945 0.3048)
			(stroke
				(width 0.1)
				(type default)
			)
			(layer "F.Fab")
		)
		(fp_line
			(start -0.67945 0.3048)
			(end -0.67945 -0.305054)
			(stroke
				(width 0.1)
				(type default)
			)
			(layer "F.Fab")
		)
		(pad "1" smd circle
			(at -0.40005 0 90)
			(size 0 0)
			(layers "F.Cu" "F.Mask" "F.Paste")
			(net "P12V_SSD0_CO_ILIMIT")
		)
		(pad "2" smd circle
			(at 0.40005 0 90)
			(size 0 0)
			(layers "F.Cu" "F.Mask" "F.Paste")
			(net "GND")
		)
	)
	(footprint ""
		(layer "F.Cu")
		(at 224.851976 -375.122186)
		(property "Reference" "PR37"
			(at 0 0 0)
			(layer "F.SilkS")
			(hide yes)
			(effects
				(font
					(size 1.27 1.27)
				)
			)
		)
		(property "Value" ""
			(at 0 0 0)
			(layer "F.Fab")
			(effects
				(font
					(size 1.27 1.27)
				)
			)
		)
		(duplicate_pad_numbers_are_jumpers no)
		(fp_line
			(start -0.7874 -0.4064)
			(end 0.7874 -0.4064)
			(stroke
				(width 0.1524)
				(type default)
			)
			(layer "F.SilkS")
		)
		(fp_line
			(start -0.7874 0.4064)
			(end -0.7874 -0.4064)
			(stroke
				(width 0.1524)
				(type default)
			)
			(layer "F.SilkS")
		)
		(fp_line
			(start 0.7874 -0.4064)
			(end 0.7874 0.4064)
			(stroke
				(width 0.1524)
				(type default)
			)
			(layer "F.SilkS")
		)
		(fp_line
			(start 0.7874 0.4064)
			(end -0.7874 0.4064)
			(stroke
				(width 0.1524)
				(type default)
			)
			(layer "F.SilkS")
		)
		(fp_line
			(start -0.67945 -0.305054)
			(end -0.12065 -0.305054)
			(stroke
				(width 0.1)
				(type default)
			)
			(layer "F.Fab")
		)
		(fp_line
			(start -0.67945 0.3048)
			(end -0.67945 -0.305054)
			(stroke
				(width 0.1)
				(type default)
			)
			(layer "F.Fab")
		)
		(fp_line
			(start -0.12065 -0.305054)
			(end -0.12065 -0.2794)
			(stroke
				(width 0.1)
				(type default)
			)
			(layer "F.Fab")
		)
		(fp_line
			(start -0.12065 -0.2794)
			(end 0.12065 -0.2794)
			(stroke
				(width 0.1)
				(type default)
			)
			(layer "F.Fab")
		)
		(fp_line
			(start -0.12065 0.2794)
			(end -0.12065 0.3048)
			(stroke
				(width 0.1)
				(type default)
			)
			(layer "F.Fab")
		)
		(fp_line
			(start -0.12065 0.3048)
			(end -0.67945 0.3048)
			(stroke
				(width 0.1)
				(type default)
			)
			(layer "F.Fab")
		)
		(fp_line
			(start 0.120396 0.2794)
			(end -0.12065 0.2794)
			(stroke
				(width 0.1)
				(type default)
			)
			(layer "F.Fab")
		)
		(fp_line
			(start 0.120396 0.3048)
			(end 0.120396 0.2794)
			(stroke
				(width 0.1)
				(type default)
			)
			(layer "F.Fab")
		)
		(fp_line
			(start 0.12065 -0.3048)
			(end 0.67945 -0.3048)
			(stroke
				(width 0.1)
				(type default)
			)
			(layer "F.Fab")
		)
		(fp_line
			(start 0.12065 -0.2794)
			(end 0.12065 -0.3048)
			(stroke
				(width 0.1)
				(type default)
			)
			(layer "F.Fab")
		)
		(fp_line
			(start 0.67945 -0.3048)
			(end 0.67945 0.3048)
			(stroke
				(width 0.1)
				(type default)
			)
			(layer "F.Fab")
		)
		(fp_line
			(start 0.67945 0.3048)
			(end 0.120396 0.3048)
			(stroke
				(width 0.1)
				(type default)
			)
			(layer "F.Fab")
		)
		(pad "1" smd circle
			(at -0.40005 0)
			(size 0 0)
			(layers "F.Cu" "F.Mask" "F.Paste")
			(net "HSC_SCREF")
		)
		(pad "2" smd circle
			(at 0.40005 0)
			(size 0 0)
			(layers "F.Cu" "F.Mask" "F.Paste")
			(net "HSC_SCREF_2")
		)
	)
	(footprint ""
		(layer "F.Cu")
		(at 244.447314 -274.768056 180)
		(property "Reference" "R799"
			(at 0 0 180)
			(layer "F.SilkS")
			(hide yes)
			(effects
				(font
					(size 1.27 1.27)
				)
			)
		)
		(property "Value" ""
			(at 0 0 180)
			(layer "F.Fab")
			(effects
				(font
					(size 1.27 1.27)
				)
			)
		)
		(duplicate_pad_numbers_are_jumpers no)
		(fp_line
			(start 0.7874 0.4064)
			(end -0.7874 0.4064)
			(stroke
				(width 0.1524)
				(type default)
			)
			(layer "F.SilkS")
		)
		(fp_line
			(start 0.7874 -0.4064)
			(end 0.7874 0.4064)
			(stroke
				(width 0.1524)
				(type default)
			)
			(layer "F.SilkS")
		)
		(fp_line
			(start -0.7874 0.4064)
			(end -0.7874 -0.4064)
			(stroke
				(width 0.1524)
				(type default)
			)
			(layer "F.SilkS")
		)
		(fp_line
			(start -0.7874 -0.4064)
			(end 0.7874 -0.4064)
			(stroke
				(width 0.1524)
				(type default)
			)
			(layer "F.SilkS")
		)
		(fp_line
			(start 0.67945 0.3048)
			(end 0.120396 0.3048)
			(stroke
				(width 0.1)
				(type default)
			)
			(layer "F.Fab")
		)
		(fp_line
			(start 0.67945 -0.3048)
			(end 0.67945 0.3048)
			(stroke
				(width 0.1)
				(type default)
			)
			(layer "F.Fab")
		)
		(fp_line
			(start 0.12065 -0.2794)
			(end 0.12065 -0.3048)
			(stroke
				(width 0.1)
				(type default)
			)
			(layer "F.Fab")
		)
		(fp_line
			(start 0.12065 -0.3048)
			(end 0.67945 -0.3048)
			(stroke
				(width 0.1)
				(type default)
			)
			(layer "F.Fab")
		)
		(fp_line
			(start 0.120396 0.3048)
			(end 0.120396 0.2794)
			(stroke
				(width 0.1)
				(type default)
			)
			(layer "F.Fab")
		)
		(fp_line
			(start 0.120396 0.2794)
			(end -0.12065 0.2794)
			(stroke
				(width 0.1)
				(type default)
			)
			(layer "F.Fab")
		)
		(fp_line
			(start -0.12065 0.3048)
			(end -0.67945 0.3048)
			(stroke
				(width 0.1)
				(type default)
			)
			(layer "F.Fab")
		)
		(fp_line
			(start -0.12065 0.2794)
			(end -0.12065 0.3048)
			(stroke
				(width 0.1)
				(type default)
			)
			(layer "F.Fab")
		)
		(fp_line
			(start -0.12065 -0.2794)
			(end 0.12065 -0.2794)
			(stroke
				(width 0.1)
				(type default)
			)
			(layer "F.Fab")
		)
		(fp_line
			(start -0.12065 -0.305054)
			(end -0.12065 -0.2794)
			(stroke
				(width 0.1)
				(type default)
			)
			(layer "F.Fab")
		)
		(fp_line
			(start -0.67945 0.3048)
			(end -0.67945 -0.305054)
			(stroke
				(width 0.1)
				(type default)
			)
			(layer "F.Fab")
		)
		(fp_line
			(start -0.67945 -0.305054)
			(end -0.12065 -0.305054)
			(stroke
				(width 0.1)
				(type default)
			)
			(layer "F.Fab")
		)
		(pad "1" smd circle
			(at -0.40005 0 180)
			(size 0 0)
			(layers "F.Cu" "F.Mask" "F.Paste")
			(net "P1V25_PEX2_R")
		)
		(pad "2" smd circle
			(at 0.40005 0 180)
			(size 0 0)
			(layers "F.Cu" "F.Mask" "F.Paste")
			(net "P12V_PEX2_P1V25_VIN_P")
		)
	)
	(footprint ""
		(layer "F.Cu")
		(at 250.309888 -279.476708 180)
		(property "Reference" "PR6617"
			(at 0 0 180)
			(layer "F.SilkS")
			(hide yes)
			(effects
				(font
					(size 1.27 1.27)
				)
			)
		)
		(property "Value" ""
			(at 0 0 180)
			(layer "F.Fab")
			(effects
				(font
					(size 1.27 1.27)
				)
			)
		)
		(duplicate_pad_numbers_are_jumpers no)
		(fp_line
			(start 0.7874 0.4064)
			(end -0.7874 0.4064)
			(stroke
				(width 0.1524)
				(type default)
			)
			(layer "F.SilkS")
		)
		(fp_line
			(start 0.7874 -0.4064)
			(end 0.7874 0.4064)
			(stroke
				(width 0.1524)
				(type default)
			)
			(layer "F.SilkS")
		)
		(fp_line
			(start -0.7874 0.4064)
			(end -0.7874 -0.4064)
			(stroke
				(width 0.1524)
				(type default)
			)
			(layer "F.SilkS")
		)
		(fp_line
			(start -0.7874 -0.4064)
			(end 0.7874 -0.4064)
			(stroke
				(width 0.1524)
				(type default)
			)
			(layer "F.SilkS")
		)
		(fp_line
			(start 0.67945 0.3048)
			(end 0.120396 0.3048)
			(stroke
				(width 0.1)
				(type default)
			)
			(layer "F.Fab")
		)
		(fp_line
			(start 0.67945 -0.3048)
			(end 0.67945 0.3048)
			(stroke
				(width 0.1)
				(type default)
			)
			(layer "F.Fab")
		)
		(fp_line
			(start 0.12065 -0.2794)
			(end 0.12065 -0.3048)
			(stroke
				(width 0.1)
				(type default)
			)
			(layer "F.Fab")
		)
		(fp_line
			(start 0.12065 -0.3048)
			(end 0.67945 -0.3048)
			(stroke
				(width 0.1)
				(type default)
			)
			(layer "F.Fab")
		)
		(fp_line
			(start 0.120396 0.3048)
			(end 0.120396 0.2794)
			(stroke
				(width 0.1)
				(type default)
			)
			(layer "F.Fab")
		)
		(fp_line
			(start 0.120396 0.2794)
			(end -0.12065 0.2794)
			(stroke
				(width 0.1)
				(type default)
			)
			(layer "F.Fab")
		)
		(fp_line
			(start -0.12065 0.3048)
			(end -0.67945 0.3048)
			(stroke
				(width 0.1)
				(type default)
			)
			(layer "F.Fab")
		)
		(fp_line
			(start -0.12065 0.2794)
			(end -0.12065 0.3048)
			(stroke
				(width 0.1)
				(type default)
			)
			(layer "F.Fab")
		)
		(fp_line
			(start -0.12065 -0.2794)
			(end 0.12065 -0.2794)
			(stroke
				(width 0.1)
				(type default)
			)
			(layer "F.Fab")
		)
		(fp_line
			(start -0.12065 -0.305054)
			(end -0.12065 -0.2794)
			(stroke
				(width 0.1)
				(type default)
			)
			(layer "F.Fab")
		)
		(fp_line
			(start -0.67945 0.3048)
			(end -0.67945 -0.305054)
			(stroke
				(width 0.1)
				(type default)
			)
			(layer "F.Fab")
		)
		(fp_line
			(start -0.67945 -0.305054)
			(end -0.12065 -0.305054)
			(stroke
				(width 0.1)
				(type default)
			)
			(layer "F.Fab")
		)
		(pad "1" smd circle
			(at -0.40005 0 180)
			(size 0 0)
			(layers "F.Cu" "F.Mask" "F.Paste")
			(net "SMB_LTC4282_TEMP_SDA")
		)
		(pad "2" smd circle
			(at 0.40005 0 180)
			(size 0 0)
			(layers "F.Cu" "F.Mask" "F.Paste")
			(net "SMB_BIC_I2C6_MUX_PEX_ADC_R_SDA")
		)
	)
	(footprint ""
		(layer "F.Cu")
		(at 79.314802 -81.36001 -90)
		(property "Reference" "R102"
			(at 0 0 270)
			(layer "F.SilkS")
			(hide yes)
			(effects
				(font
					(size 1.27 1.27)
				)
			)
		)
		(property "Value" ""
			(at 0 0 270)
			(layer "F.Fab")
			(effects
				(font
					(size 1.27 1.27)
				)
			)
		)
		(duplicate_pad_numbers_are_jumpers no)
		(fp_line
			(start -0.7874 0.4064)
			(end -0.7874 -0.4064)
			(stroke
				(width 0.1524)
				(type default)
			)
			(layer "F.SilkS")
		)
		(fp_line
			(start 0.7874 0.4064)
			(end -0.7874 0.4064)
			(stroke
				(width 0.1524)
				(type default)
			)
			(layer "F.SilkS")
		)
		(fp_line
			(start -0.7874 -0.4064)
			(end 0.7874 -0.4064)
			(stroke
				(width 0.1524)
				(type default)
			)
			(layer "F.SilkS")
		)
		(fp_line
			(start 0.7874 -0.4064)
			(end 0.7874 0.4064)
			(stroke
				(width 0.1524)
				(type default)
			)
			(layer "F.SilkS")
		)
		(fp_line
			(start -0.67945 0.3048)
			(end -0.67945 -0.305054)
			(stroke
				(width 0.1)
				(type default)
			)
			(layer "F.Fab")
		)
		(fp_line
			(start -0.12065 0.3048)
			(end -0.67945 0.3048)
			(stroke
				(width 0.1)
				(type default)
			)
			(layer "F.Fab")
		)
		(fp_line
			(start 0.120396 0.3048)
			(end 0.120396 0.2794)
			(stroke
				(width 0.1)
				(type default)
			)
			(layer "F.Fab")
		)
		(fp_line
			(start 0.67945 0.3048)
			(end 0.120396 0.3048)
			(stroke
				(width 0.1)
				(type default)
			)
			(layer "F.Fab")
		)
		(fp_line
			(start -0.12065 0.2794)
			(end -0.12065 0.3048)
			(stroke
				(width 0.1)
				(type default)
			)
			(layer "F.Fab")
		)
		(fp_line
			(start 0.120396 0.2794)
			(end -0.12065 0.2794)
			(stroke
				(width 0.1)
				(type default)
			)
			(layer "F.Fab")
		)
		(fp_line
			(start -0.12065 -0.2794)
			(end 0.12065 -0.2794)
			(stroke
				(width 0.1)
				(type default)
			)
			(layer "F.Fab")
		)
		(fp_line
			(start 0.12065 -0.2794)
			(end 0.12065 -0.3048)
			(stroke
				(width 0.1)
				(type default)
			)
			(layer "F.Fab")
		)
		(fp_line
			(start 0.12065 -0.3048)
			(end 0.67945 -0.3048)
			(stroke
				(width 0.1)
				(type default)
			)
			(layer "F.Fab")
		)
		(fp_line
			(start 0.67945 -0.3048)
			(end 0.67945 0.3048)
			(stroke
				(width 0.1)
				(type default)
			)
			(layer "F.Fab")
		)
		(fp_line
			(start -0.67945 -0.305054)
			(end -0.12065 -0.305054)
			(stroke
				(width 0.1)
				(type default)
			)
			(layer "F.Fab")
		)
		(fp_line
			(start -0.12065 -0.305054)
			(end -0.12065 -0.2794)
			(stroke
				(width 0.1)
				(type default)
			)
			(layer "F.Fab")
		)
		(pad "1" smd circle
			(at -0.40005 0 270)
			(size 0 0)
			(layers "F.Cu" "F.Mask" "F.Paste")
			(net "HP_NIC1_PWRGD_R")
		)
		(pad "2" smd circle
			(at 0.40005 0 270)
			(size 0 0)
			(layers "F.Cu" "F.Mask" "F.Paste")
			(net "HP_NIC1_PWRGD")
		)
	)
	(footprint ""
		(layer "F.Cu")
		(at 242.110768 8.076692 180)
		(property "Reference" "DE11T_1"
			(at 2.614168 3.147822 0)
			(unlocked yes)
			(layer "F.SilkS")
			(effects
				(font
					(size 0.7874 0.5842)
					(thickness 0.1524)
				)
				(justify left)
			)
		)
		(property "Value" ""
			(at 0 0 180)
			(layer "F.Fab")
			(effects
				(font
					(size 1.27 1.27)
				)
			)
		)
		(duplicate_pad_numbers_are_jumpers no)
		(fp_line
			(start 1.2192 2.1082)
			(end -1.2192 2.1082)
			(stroke
				(width 0.1524)
				(type default)
			)
			(layer "F.SilkS")
		)
		(fp_line
			(start 1.2192 -2.1082)
			(end 1.2192 2.1082)
			(stroke
				(width 0.1524)
				(type default)
			)
			(layer "F.SilkS")
		)
		(fp_line
			(start -1.2192 2.1082)
			(end -1.2192 -2.1082)
			(stroke
				(width 0.1524)
				(type default)
			)
			(layer "F.SilkS")
		)
		(fp_line
			(start -1.2192 -2.1082)
			(end 1.2192 -2.1082)
			(stroke
				(width 0.1524)
				(type default)
			)
			(layer "F.SilkS")
		)
		(pad "" np_thru_hole circle
			(at -2.8829 -1.27 90)
			(size 1.0414 1.0414)
			(drill 1.0414)
			(layers "*.Cu" "*.Mask")
			(clearance 0.381)
			(thermal_gap 0.381)
		)
		(pad "" np_thru_hole circle
			(at -2.8829 1.27 90)
			(size 1.0414 1.0414)
			(drill 1.0414)
			(layers "*.Cu" "*.Mask")
			(clearance 0.381)
			(thermal_gap 0.381)
		)
		(pad "" np_thru_hole circle
			(at 3.4671 -1.27 90)
			(size 1.0414 1.0414)
			(drill 1.0414)
			(layers "*.Cu" "*.Mask")
			(clearance 0.381)
			(thermal_gap 0.381)
		)
		(pad "" np_thru_hole circle
			(at 3.4671 1.27 90)
			(size 1.0414 1.0414)
			(drill 1.0414)
			(layers "*.Cu" "*.Mask")
			(clearance 0.381)
			(thermal_gap 0.381)
		)
		(pad "1" smd rect
			(at 0.8255 -0.249936 90)
			(size 0.3048 0.508)
			(layers "F.Cu" "F.Mask" "F.Paste")
			(net "85_10INCH_TOP_DN")
		)
		(pad "2" smd rect
			(at 0.8255 0.249936 90)
			(size 0.3048 0.508)
			(layers "F.Cu" "F.Mask" "F.Paste")
			(net "85_10INCH_TOP_DP")
		)
		(pad "3" smd circle
			(at 0 0 180)
			(size 0 0)
			(layers "F.Cu" "F.Mask" "F.Paste")
			(net "COUPON_GND2")
		)
		(zone
			(layer "F.Cu")
			(hatch none 0.5)
			(connect_pads
				(clearance 0)
			)
			(min_thickness 0.25)
			(keepout
				(tracks not_allowed)
				(vias allowed)
				(pads allowed)
				(copperpour not_allowed)
				(footprints allowed)
			)
			(placement
				(enabled no)
				(sheetname "")
			)
			(fill
				(thermal_gap 0.5)
				(thermal_bridge_width 0.5)
				(island_removal_mode 0)
			)
			(polygon
				(pts
					(xy 240.993168 8.625332) (xy 240.993168 8.529828) (xy 241.590068 8.529828) (xy 241.590068 8.123428)
					(xy 240.993168 8.123428) (xy 240.993168 8.029956) (xy 241.590068 8.029956) (xy 241.590068 7.623556)
					(xy 240.993168 7.623556) (xy 240.993168 7.528052) (xy 241.691668 7.528052) (xy 241.691668 8.625332)
				)
			)
		)
		(zone
			(layers "F.Cu" "B.Cu" "In1.Cu" "In2.Cu" "In3.Cu" "In4.Cu" "In5.Cu" "In6.Cu"
				"In7.Cu" "In8.Cu" "In9.Cu" "In10.Cu" "In11.Cu" "In12.Cu" "In13.Cu" "In14.Cu"
				"In15.Cu" "In16.Cu"
			)
			(hatch none 0.5)
			(connect_pads
				(clearance 0)
			)
			(min_thickness 0.25)
			(keepout
				(tracks not_allowed)
				(vias allowed)
				(pads allowed)
				(copperpour not_allowed)
				(footprints allowed)
			)
			(placement
				(enabled no)
				(sheetname "")
			)
			(fill
				(thermal_gap 0.5)
				(thermal_bridge_width 0.5)
				(island_removal_mode 0)
			)
			(polygon
				(pts
					(arc
						(start 239.570768 6.806692)
						(mid 237.716568 6.806692)
						(end 239.570768 6.806692)
					)
				)
			)
		)
		(zone
			(layers "F.Cu" "B.Cu" "In1.Cu" "In2.Cu" "In3.Cu" "In4.Cu" "In5.Cu" "In6.Cu"
				"In7.Cu" "In8.Cu" "In9.Cu" "In10.Cu" "In11.Cu" "In12.Cu" "In13.Cu" "In14.Cu"
				"In15.Cu" "In16.Cu"
			)
			(hatch none 0.5)
			(connect_pads
				(clearance 0)
			)
			(min_thickness 0.25)
			(keepout
				(tracks not_allowed)
				(vias allowed)
				(pads allowed)
				(copperpour not_allowed)
				(footprints allowed)
			)
			(placement
				(enabled no)
				(sheetname "")
			)
			(fill
				(thermal_gap 0.5)
				(thermal_bridge_width 0.5)
				(island_removal_mode 0)
			)
			(polygon
				(pts
					(arc
						(start 239.570768 9.346692)
						(mid 237.716568 9.346692)
						(end 239.570768 9.346692)
					)
				)
			)
		)
		(zone
			(layers "F.Cu" "B.Cu" "In1.Cu" "In2.Cu" "In3.Cu" "In4.Cu" "In5.Cu" "In6.Cu"
				"In7.Cu" "In8.Cu" "In9.Cu" "In10.Cu" "In11.Cu" "In12.Cu" "In13.Cu" "In14.Cu"
				"In15.Cu" "In16.Cu"
			)
			(hatch none 0.5)
			(connect_pads
				(clearance 0)
			)
			(min_thickness 0.25)
			(keepout
				(tracks not_allowed)
				(vias allowed)
				(pads allowed)
				(copperpour not_allowed)
				(footprints allowed)
			)
			(placement
				(enabled no)
				(sheetname "")
			)
			(fill
				(thermal_gap 0.5)
				(thermal_bridge_width 0.5)
				(island_removal_mode 0)
			)
			(polygon
				(pts
					(arc
						(start 245.920768 6.806692)
						(mid 244.066568 6.806692)
						(end 245.920768 6.806692)
					)
				)
			)
		)
		(zone
			(layers "F.Cu" "B.Cu" "In1.Cu" "In2.Cu" "In3.Cu" "In4.Cu" "In5.Cu" "In6.Cu"
				"In7.Cu" "In8.Cu" "In9.Cu" "In10.Cu" "In11.Cu" "In12.Cu" "In13.Cu" "In14.Cu"
				"In15.Cu" "In16.Cu"
			)
			(hatch none 0.5)
			(connect_pads
				(clearance 0)
			)
			(min_thickness 0.25)
			(keepout
				(tracks not_allowed)
				(vias allowed)
				(pads allowed)
				(copperpour not_allowed)
				(footprints allowed)
			)
			(placement
				(enabled no)
				(sheetname "")
			)
			(fill
				(thermal_gap 0.5)
				(thermal_bridge_width 0.5)
				(island_removal_mode 0)
			)
			(polygon
				(pts
					(arc
						(start 245.920768 9.346692)
						(mid 244.066568 9.346692)
						(end 245.920768 9.346692)
					)
				)
			)
		)
	)
	(footprint ""
		(layer "F.Cu")
		(at 1.66624 -393.474194 90)
		(property "Reference" "C4475"
			(at 0 0 90)
			(layer "F.SilkS")
			(hide yes)
			(effects
				(font
					(size 1.27 1.27)
				)
			)
		)
		(property "Value" ""
			(at 0 0 90)
			(layer "F.Fab")
			(effects
				(font
					(size 1.27 1.27)
				)
			)
		)
		(duplicate_pad_numbers_are_jumpers no)
		(fp_line
			(start 0.7874 -0.4064)
			(end 0.7874 0.4064)
			(stroke
				(width 0.1524)
				(type default)
			)
			(layer "F.SilkS")
		)
		(fp_line
			(start -0.7874 -0.4064)
			(end 0.7874 -0.4064)
			(stroke
				(width 0.1524)
				(type default)
			)
			(layer "F.SilkS")
		)
		(fp_line
			(start 0.7874 0.4064)
			(end -0.7874 0.4064)
			(stroke
				(width 0.1524)
				(type default)
			)
			(layer "F.SilkS")
		)
		(fp_line
			(start -0.7874 0.4064)
			(end -0.7874 -0.4064)
			(stroke
				(width 0.1524)
				(type default)
			)
			(layer "F.SilkS")
		)
		(fp_line
			(start -0.12065 -0.305054)
			(end -0.12065 -0.2794)
			(stroke
				(width 0.1)
				(type default)
			)
			(layer "F.Fab")
		)
		(fp_line
			(start -0.67945 -0.305054)
			(end -0.12065 -0.305054)
			(stroke
				(width 0.1)
				(type default)
			)
			(layer "F.Fab")
		)
		(fp_line
			(start 0.67945 -0.3048)
			(end 0.67945 0.3048)
			(stroke
				(width 0.1)
				(type default)
			)
			(layer "F.Fab")
		)
		(fp_line
			(start 0.12065 -0.3048)
			(end 0.67945 -0.3048)
			(stroke
				(width 0.1)
				(type default)
			)
			(layer "F.Fab")
		)
		(fp_line
			(start 0.12065 -0.2794)
			(end 0.12065 -0.3048)
			(stroke
				(width 0.1)
				(type default)
			)
			(layer "F.Fab")
		)
		(fp_line
			(start -0.12065 -0.2794)
			(end 0.12065 -0.2794)
			(stroke
				(width 0.1)
				(type default)
			)
			(layer "F.Fab")
		)
		(fp_line
			(start 0.120396 0.2794)
			(end -0.12065 0.2794)
			(stroke
				(width 0.1)
				(type default)
			)
			(layer "F.Fab")
		)
		(fp_line
			(start -0.12065 0.2794)
			(end -0.12065 0.3048)
			(stroke
				(width 0.1)
				(type default)
			)
			(layer "F.Fab")
		)
		(fp_line
			(start 0.67945 0.3048)
			(end 0.120396 0.3048)
			(stroke
				(width 0.1)
				(type default)
			)
			(layer "F.Fab")
		)
		(fp_line
			(start 0.120396 0.3048)
			(end 0.120396 0.2794)
			(stroke
				(width 0.1)
				(type default)
			)
			(layer "F.Fab")
		)
		(fp_line
			(start -0.12065 0.3048)
			(end -0.67945 0.3048)
			(stroke
				(width 0.1)
				(type default)
			)
			(layer "F.Fab")
		)
		(fp_line
			(start -0.67945 0.3048)
			(end -0.67945 -0.305054)
			(stroke
				(width 0.1)
				(type default)
			)
			(layer "F.Fab")
		)
		(pad "1" smd circle
			(at -0.40005 0 90)
			(size 0 0)
			(layers "F.Cu" "F.Mask" "F.Paste")
			(net "BIC_USB_8042_HUB_GRSTZ")
		)
		(pad "2" smd circle
			(at 0.40005 0 90)
			(size 0 0)
			(layers "F.Cu" "F.Mask" "F.Paste")
			(net "GND")
		)
	)
	(footprint ""
		(layer "F.Cu")
		(at 270.980662 -356.244906 90)
		(property "Reference" "C609"
			(at 0 0 90)
			(layer "F.SilkS")
			(hide yes)
			(effects
				(font
					(size 1.27 1.27)
				)
			)
		)
		(property "Value" ""
			(at 0 0 90)
			(layer "F.Fab")
			(effects
				(font
					(size 1.27 1.27)
				)
			)
		)
		(duplicate_pad_numbers_are_jumpers no)
		(fp_line
			(start 0.299974 -0.150114)
			(end 0.299974 0.150114)
			(stroke
				(width 0.1)
				(type default)
			)
			(layer "F.Fab")
		)
		(fp_line
			(start -0.299974 -0.150114)
			(end 0.299974 -0.150114)
			(stroke
				(width 0.1)
				(type default)
			)
			(layer "F.Fab")
		)
		(fp_line
			(start 0.299974 0.150114)
			(end -0.299974 0.150114)
			(stroke
				(width 0.1)
				(type default)
			)
			(layer "F.Fab")
		)
		(fp_line
			(start -0.299974 0.150114)
			(end -0.299974 -0.150114)
			(stroke
				(width 0.1)
				(type default)
			)
			(layer "F.Fab")
		)
		(pad "1" smd rect
			(at -0.2667 0 90)
			(size 0.3048 0.381)
			(layers "F.Cu" "F.Mask" "F.Paste")
			(net "P5E_PEX2_STN7_TX_DP<114>")
		)
		(pad "2" smd rect
			(at 0.2667 0 90)
			(size 0.3048 0.381)
			(layers "F.Cu" "F.Mask" "F.Paste")
			(net "P5E_PEX2_STN7_TX_C_DP<114>")
		)
	)
	(footprint ""
		(layer "F.Cu")
		(at 99.97948 -384.777742 -90)
		(property "Reference" "R6728"
			(at 0 0 270)
			(layer "F.SilkS")
			(hide yes)
			(effects
				(font
					(size 1.27 1.27)
				)
			)
		)
		(property "Value" ""
			(at 0 0 270)
			(layer "F.Fab")
			(effects
				(font
					(size 1.27 1.27)
				)
			)
		)
		(duplicate_pad_numbers_are_jumpers no)
		(fp_line
			(start -0.7874 0.4064)
			(end -0.7874 -0.4064)
			(stroke
				(width 0.1524)
				(type default)
			)
			(layer "F.SilkS")
		)
		(fp_line
			(start 0.7874 0.4064)
			(end -0.7874 0.4064)
			(stroke
				(width 0.1524)
				(type default)
			)
			(layer "F.SilkS")
		)
		(fp_line
			(start 0.008636 -0.4064)
			(end 0.7874 -0.4064)
			(stroke
				(width 0.1524)
				(type default)
			)
			(layer "F.SilkS")
		)
		(fp_line
			(start -0.67945 0.3048)
			(end -0.67945 -0.305054)
			(stroke
				(width 0.1)
				(type default)
			)
			(layer "F.Fab")
		)
		(fp_line
			(start -0.12065 0.3048)
			(end -0.67945 0.3048)
			(stroke
				(width 0.1)
				(type default)
			)
			(layer "F.Fab")
		)
		(fp_line
			(start 0.120396 0.3048)
			(end 0.120396 0.2794)
			(stroke
				(width 0.1)
				(type default)
			)
			(layer "F.Fab")
		)
		(fp_line
			(start 0.67945 0.3048)
			(end 0.120396 0.3048)
			(stroke
				(width 0.1)
				(type default)
			)
			(layer "F.Fab")
		)
		(fp_line
			(start -0.12065 0.2794)
			(end -0.12065 0.3048)
			(stroke
				(width 0.1)
				(type default)
			)
			(layer "F.Fab")
		)
		(fp_line
			(start 0.120396 0.2794)
			(end -0.12065 0.2794)
			(stroke
				(width 0.1)
				(type default)
			)
			(layer "F.Fab")
		)
		(fp_line
			(start -0.12065 -0.2794)
			(end 0.12065 -0.2794)
			(stroke
				(width 0.1)
				(type default)
			)
			(layer "F.Fab")
		)
		(fp_line
			(start 0.12065 -0.2794)
			(end 0.12065 -0.3048)
			(stroke
				(width 0.1)
				(type default)
			)
			(layer "F.Fab")
		)
		(fp_line
			(start 0.12065 -0.3048)
			(end 0.67945 -0.3048)
			(stroke
				(width 0.1)
				(type default)
			)
			(layer "F.Fab")
		)
		(fp_line
			(start 0.67945 -0.3048)
			(end 0.67945 0.3048)
			(stroke
				(width 0.1)
				(type default)
			)
			(layer "F.Fab")
		)
		(fp_line
			(start -0.67945 -0.305054)
			(end -0.12065 -0.305054)
			(stroke
				(width 0.1)
				(type default)
			)
			(layer "F.Fab")
		)
		(fp_line
			(start -0.12065 -0.305054)
			(end -0.12065 -0.2794)
			(stroke
				(width 0.1)
				(type default)
			)
			(layer "F.Fab")
		)
		(pad "1" smd rect
			(at -0.40005 0 90)
			(size 0.4572 0.508)
			(layers "F.Cu" "F.Mask" "F.Paste")
			(net "USB2_MB_BMC_DN")
		)
		(pad "2" smd rect
			(at 0.40005 0 90)
			(size 0.4572 0.508)
			(layers "F.Cu" "F.Mask" "F.Paste")
			(net "USB2_MB_BMC_USB8042_DN")
		)
	)
	(footprint ""
		(layer "F.Cu")
		(at 175.0949 -96.702372 180)
		(property "Reference" "R200"
			(at 0 0 180)
			(layer "F.SilkS")
			(hide yes)
			(effects
				(font
					(size 1.27 1.27)
				)
			)
		)
		(property "Value" ""
			(at 0 0 180)
			(layer "F.Fab")
			(effects
				(font
					(size 1.27 1.27)
				)
			)
		)
		(duplicate_pad_numbers_are_jumpers no)
		(fp_line
			(start 0.7874 0.4064)
			(end -0.7874 0.4064)
			(stroke
				(width 0.1524)
				(type default)
			)
			(layer "F.SilkS")
		)
		(fp_line
			(start 0.7874 -0.4064)
			(end 0.7874 0.4064)
			(stroke
				(width 0.1524)
				(type default)
			)
			(layer "F.SilkS")
		)
		(fp_line
			(start -0.7874 0.4064)
			(end -0.7874 -0.4064)
			(stroke
				(width 0.1524)
				(type default)
			)
			(layer "F.SilkS")
		)
		(fp_line
			(start -0.7874 -0.4064)
			(end 0.7874 -0.4064)
			(stroke
				(width 0.1524)
				(type default)
			)
			(layer "F.SilkS")
		)
		(fp_line
			(start 0.67945 0.3048)
			(end 0.120396 0.3048)
			(stroke
				(width 0.1)
				(type default)
			)
			(layer "F.Fab")
		)
		(fp_line
			(start 0.67945 -0.3048)
			(end 0.67945 0.3048)
			(stroke
				(width 0.1)
				(type default)
			)
			(layer "F.Fab")
		)
		(fp_line
			(start 0.12065 -0.2794)
			(end 0.12065 -0.3048)
			(stroke
				(width 0.1)
				(type default)
			)
			(layer "F.Fab")
		)
		(fp_line
			(start 0.12065 -0.3048)
			(end 0.67945 -0.3048)
			(stroke
				(width 0.1)
				(type default)
			)
			(layer "F.Fab")
		)
		(fp_line
			(start 0.120396 0.3048)
			(end 0.120396 0.2794)
			(stroke
				(width 0.1)
				(type default)
			)
			(layer "F.Fab")
		)
		(fp_line
			(start 0.120396 0.2794)
			(end -0.12065 0.2794)
			(stroke
				(width 0.1)
				(type default)
			)
			(layer "F.Fab")
		)
		(fp_line
			(start -0.12065 0.3048)
			(end -0.67945 0.3048)
			(stroke
				(width 0.1)
				(type default)
			)
			(layer "F.Fab")
		)
		(fp_line
			(start -0.12065 0.2794)
			(end -0.12065 0.3048)
			(stroke
				(width 0.1)
				(type default)
			)
			(layer "F.Fab")
		)
		(fp_line
			(start -0.12065 -0.2794)
			(end 0.12065 -0.2794)
			(stroke
				(width 0.1)
				(type default)
			)
			(layer "F.Fab")
		)
		(fp_line
			(start -0.12065 -0.305054)
			(end -0.12065 -0.2794)
			(stroke
				(width 0.1)
				(type default)
			)
			(layer "F.Fab")
		)
		(fp_line
			(start -0.67945 0.3048)
			(end -0.67945 -0.305054)
			(stroke
				(width 0.1)
				(type default)
			)
			(layer "F.Fab")
		)
		(fp_line
			(start -0.67945 -0.305054)
			(end -0.12065 -0.305054)
			(stroke
				(width 0.1)
				(type default)
			)
			(layer "F.Fab")
		)
		(pad "1" smd circle
			(at -0.40005 0 180)
			(size 0 0)
			(layers "F.Cu" "F.Mask" "F.Paste")
			(net "RST_NIC3_PERST2_R_N")
		)
		(pad "2" smd circle
			(at 0.40005 0 180)
			(size 0 0)
			(layers "F.Cu" "F.Mask" "F.Paste")
			(net "RST_HP_NIC3_BUF_N")
		)
	)
	(footprint ""
		(layer "F.Cu")
		(at 140.074142 -177.929286 180)
		(property "Reference" "R1102"
			(at 0 0 180)
			(layer "F.SilkS")
			(hide yes)
			(effects
				(font
					(size 1.27 1.27)
				)
			)
		)
		(property "Value" ""
			(at 0 0 180)
			(layer "F.Fab")
			(effects
				(font
					(size 1.27 1.27)
				)
			)
		)
		(duplicate_pad_numbers_are_jumpers no)
		(fp_line
			(start -0.7874 -0.4064)
			(end 0.7874 -0.4064)
			(stroke
				(width 0.1524)
				(type default)
			)
			(layer "F.SilkS")
		)
		(fp_line
			(start 0.67945 0.3048)
			(end 0.120396 0.3048)
			(stroke
				(width 0.1)
				(type default)
			)
			(layer "F.Fab")
		)
		(fp_line
			(start 0.67945 -0.3048)
			(end 0.67945 0.3048)
			(stroke
				(width 0.1)
				(type default)
			)
			(layer "F.Fab")
		)
		(fp_line
			(start 0.12065 -0.2794)
			(end 0.12065 -0.3048)
			(stroke
				(width 0.1)
				(type default)
			)
			(layer "F.Fab")
		)
		(fp_line
			(start 0.12065 -0.3048)
			(end 0.67945 -0.3048)
			(stroke
				(width 0.1)
				(type default)
			)
			(layer "F.Fab")
		)
		(fp_line
			(start 0.120396 0.3048)
			(end 0.120396 0.2794)
			(stroke
				(width 0.1)
				(type default)
			)
			(layer "F.Fab")
		)
		(fp_line
			(start 0.120396 0.2794)
			(end -0.12065 0.2794)
			(stroke
				(width 0.1)
				(type default)
			)
			(layer "F.Fab")
		)
		(fp_line
			(start -0.12065 0.3048)
			(end -0.67945 0.3048)
			(stroke
				(width 0.1)
				(type default)
			)
			(layer "F.Fab")
		)
		(fp_line
			(start -0.12065 0.2794)
			(end -0.12065 0.3048)
			(stroke
				(width 0.1)
				(type default)
			)
			(layer "F.Fab")
		)
		(fp_line
			(start -0.12065 -0.2794)
			(end 0.12065 -0.2794)
			(stroke
				(width 0.1)
				(type default)
			)
			(layer "F.Fab")
		)
		(fp_line
			(start -0.12065 -0.305054)
			(end -0.12065 -0.2794)
			(stroke
				(width 0.1)
				(type default)
			)
			(layer "F.Fab")
		)
		(fp_line
			(start -0.67945 0.3048)
			(end -0.67945 -0.305054)
			(stroke
				(width 0.1)
				(type default)
			)
			(layer "F.Fab")
		)
		(fp_line
			(start -0.67945 -0.305054)
			(end -0.12065 -0.305054)
			(stroke
				(width 0.1)
				(type default)
			)
			(layer "F.Fab")
		)
		(pad "1" smd circle
			(at -0.40005 0 180)
			(size 0 0)
			(layers "F.Cu" "F.Mask" "F.Paste")
			(net "CLK_100M_DB2000QL_NIC4_R_DP")
		)
		(pad "2" smd circle
			(at 0.40005 0 180)
			(size 0 0)
			(layers "F.Cu" "F.Mask" "F.Paste")
			(net "CLK_100M_DB2000QL_NIC4_DP")
		)
	)
	(footprint ""
		(layer "F.Cu")
		(at 356.511098 -61.386974)
		(property "Reference" "R4499"
			(at 0 0 0)
			(layer "F.SilkS")
			(hide yes)
			(effects
				(font
					(size 1.27 1.27)
				)
			)
		)
		(property "Value" ""
			(at 0 0 0)
			(layer "F.Fab")
			(effects
				(font
					(size 1.27 1.27)
				)
			)
		)
		(duplicate_pad_numbers_are_jumpers no)
		(fp_line
			(start -0.7874 -0.4064)
			(end 0.7874 -0.4064)
			(stroke
				(width 0.1524)
				(type default)
			)
			(layer "F.SilkS")
		)
		(fp_line
			(start -0.7874 0.4064)
			(end -0.7874 -0.4064)
			(stroke
				(width 0.1524)
				(type default)
			)
			(layer "F.SilkS")
		)
		(fp_line
			(start 0.7874 -0.4064)
			(end 0.7874 0.4064)
			(stroke
				(width 0.1524)
				(type default)
			)
			(layer "F.SilkS")
		)
		(fp_line
			(start 0.7874 0.4064)
			(end -0.7874 0.4064)
			(stroke
				(width 0.1524)
				(type default)
			)
			(layer "F.SilkS")
		)
		(fp_line
			(start -0.67945 -0.305054)
			(end -0.12065 -0.305054)
			(stroke
				(width 0.1)
				(type default)
			)
			(layer "F.Fab")
		)
		(fp_line
			(start -0.67945 0.3048)
			(end -0.67945 -0.305054)
			(stroke
				(width 0.1)
				(type default)
			)
			(layer "F.Fab")
		)
		(fp_line
			(start -0.12065 -0.305054)
			(end -0.12065 -0.2794)
			(stroke
				(width 0.1)
				(type default)
			)
			(layer "F.Fab")
		)
		(fp_line
			(start -0.12065 -0.2794)
			(end 0.12065 -0.2794)
			(stroke
				(width 0.1)
				(type default)
			)
			(layer "F.Fab")
		)
		(fp_line
			(start -0.12065 0.2794)
			(end -0.12065 0.3048)
			(stroke
				(width 0.1)
				(type default)
			)
			(layer "F.Fab")
		)
		(fp_line
			(start -0.12065 0.3048)
			(end -0.67945 0.3048)
			(stroke
				(width 0.1)
				(type default)
			)
			(layer "F.Fab")
		)
		(fp_line
			(start 0.120396 0.2794)
			(end -0.12065 0.2794)
			(stroke
				(width 0.1)
				(type default)
			)
			(layer "F.Fab")
		)
		(fp_line
			(start 0.120396 0.3048)
			(end 0.120396 0.2794)
			(stroke
				(width 0.1)
				(type default)
			)
			(layer "F.Fab")
		)
		(fp_line
			(start 0.12065 -0.3048)
			(end 0.67945 -0.3048)
			(stroke
				(width 0.1)
				(type default)
			)
			(layer "F.Fab")
		)
		(fp_line
			(start 0.12065 -0.2794)
			(end 0.12065 -0.3048)
			(stroke
				(width 0.1)
				(type default)
			)
			(layer "F.Fab")
		)
		(fp_line
			(start 0.67945 -0.3048)
			(end 0.67945 0.3048)
			(stroke
				(width 0.1)
				(type default)
			)
			(layer "F.Fab")
		)
		(fp_line
			(start 0.67945 0.3048)
			(end 0.120396 0.3048)
			(stroke
				(width 0.1)
				(type default)
			)
			(layer "F.Fab")
		)
		(pad "1" smd circle
			(at -0.40005 0)
			(size 0 0)
			(layers "F.Cu" "F.Mask" "F.Paste")
			(net "PWRGD_P3V3_SSD12")
		)
		(pad "2" smd circle
			(at 0.40005 0)
			(size 0 0)
			(layers "F.Cu" "F.Mask" "F.Paste")
			(net "PWRGD_P3V3_SSD12_R")
		)
	)
	(footprint ""
		(layer "F.Cu")
		(at 162.61461 -66.32194 90)
		(property "Reference" "R5971"
			(at 0 0 90)
			(layer "F.SilkS")
			(hide yes)
			(effects
				(font
					(size 1.27 1.27)
				)
			)
		)
		(property "Value" ""
			(at 0 0 90)
			(layer "F.Fab")
			(effects
				(font
					(size 1.27 1.27)
				)
			)
		)
		(duplicate_pad_numbers_are_jumpers no)
		(fp_line
			(start 0.7874 -0.4064)
			(end 0.7874 0.4064)
			(stroke
				(width 0.1524)
				(type default)
			)
			(layer "F.SilkS")
		)
		(fp_line
			(start -0.7874 -0.4064)
			(end 0.7874 -0.4064)
			(stroke
				(width 0.1524)
				(type default)
			)
			(layer "F.SilkS")
		)
		(fp_line
			(start 0.7874 0.4064)
			(end -0.7874 0.4064)
			(stroke
				(width 0.1524)
				(type default)
			)
			(layer "F.SilkS")
		)
		(fp_line
			(start -0.7874 0.4064)
			(end -0.7874 -0.4064)
			(stroke
				(width 0.1524)
				(type default)
			)
			(layer "F.SilkS")
		)
		(fp_line
			(start -0.12065 -0.305054)
			(end -0.12065 -0.2794)
			(stroke
				(width 0.1)
				(type default)
			)
			(layer "F.Fab")
		)
		(fp_line
			(start -0.67945 -0.305054)
			(end -0.12065 -0.305054)
			(stroke
				(width 0.1)
				(type default)
			)
			(layer "F.Fab")
		)
		(fp_line
			(start 0.67945 -0.3048)
			(end 0.67945 0.3048)
			(stroke
				(width 0.1)
				(type default)
			)
			(layer "F.Fab")
		)
		(fp_line
			(start 0.12065 -0.3048)
			(end 0.67945 -0.3048)
			(stroke
				(width 0.1)
				(type default)
			)
			(layer "F.Fab")
		)
		(fp_line
			(start 0.12065 -0.2794)
			(end 0.12065 -0.3048)
			(stroke
				(width 0.1)
				(type default)
			)
			(layer "F.Fab")
		)
		(fp_line
			(start -0.12065 -0.2794)
			(end 0.12065 -0.2794)
			(stroke
				(width 0.1)
				(type default)
			)
			(layer "F.Fab")
		)
		(fp_line
			(start 0.120396 0.2794)
			(end -0.12065 0.2794)
			(stroke
				(width 0.1)
				(type default)
			)
			(layer "F.Fab")
		)
		(fp_line
			(start -0.12065 0.2794)
			(end -0.12065 0.3048)
			(stroke
				(width 0.1)
				(type default)
			)
			(layer "F.Fab")
		)
		(fp_line
			(start 0.67945 0.3048)
			(end 0.120396 0.3048)
			(stroke
				(width 0.1)
				(type default)
			)
			(layer "F.Fab")
		)
		(fp_line
			(start 0.120396 0.3048)
			(end 0.120396 0.2794)
			(stroke
				(width 0.1)
				(type default)
			)
			(layer "F.Fab")
		)
		(fp_line
			(start -0.12065 0.3048)
			(end -0.67945 0.3048)
			(stroke
				(width 0.1)
				(type default)
			)
			(layer "F.Fab")
		)
		(fp_line
			(start -0.67945 0.3048)
			(end -0.67945 -0.305054)
			(stroke
				(width 0.1)
				(type default)
			)
			(layer "F.Fab")
		)
		(pad "1" smd circle
			(at -0.40005 0 90)
			(size 0 0)
			(layers "F.Cu" "F.Mask" "F.Paste")
			(net "SSD5_PWR_EN_R")
		)
		(pad "2" smd circle
			(at 0.40005 0 90)
			(size 0 0)
			(layers "F.Cu" "F.Mask" "F.Paste")
			(net "P12V_SSD5_CO_EN")
		)
	)
	(footprint ""
		(layer "F.Cu")
		(at 22.84603 -46.4439 180)
		(property "Reference" "U51"
			(at 0.24003 -2.40157 0)
			(unlocked yes)
			(layer "F.SilkS")
			(effects
				(font
					(size 0.7874 0.5842)
					(thickness 0.1524)
				)
			)
		)
		(property "Value" ""
			(at 0 0 180)
			(layer "F.Fab")
			(effects
				(font
					(size 1.27 1.27)
				)
			)
		)
		(duplicate_pad_numbers_are_jumpers no)
		(fp_line
			(start 1.500124 1.500124)
			(end 1.004062 1.500124)
			(stroke
				(width 0.1524)
				(type default)
			)
			(layer "F.SilkS")
		)
		(fp_line
			(start 1.500124 1.004062)
			(end 1.500124 1.500124)
			(stroke
				(width 0.1524)
				(type default)
			)
			(layer "F.SilkS")
		)
		(fp_line
			(start 1.500124 -1.500124)
			(end 1.500124 -1.004062)
			(stroke
				(width 0.1524)
				(type default)
			)
			(layer "F.SilkS")
		)
		(fp_line
			(start 1.004062 -1.500124)
			(end 1.500124 -1.500124)
			(stroke
				(width 0.1524)
				(type default)
			)
			(layer "F.SilkS")
		)
		(fp_line
			(start -1.004062 1.500124)
			(end -1.500124 1.500124)
			(stroke
				(width 0.1524)
				(type default)
			)
			(layer "F.SilkS")
		)
		(fp_line
			(start -1.500124 1.500124)
			(end -1.500124 1.004062)
			(stroke
				(width 0.1524)
				(type default)
			)
			(layer "F.SilkS")
		)
		(fp_line
			(start -1.500124 -1.004062)
			(end -1.500124 -1.500124)
			(stroke
				(width 0.1524)
				(type default)
			)
			(layer "F.SilkS")
		)
		(fp_line
			(start -1.500124 -1.500124)
			(end -1.004062 -1.500124)
			(stroke
				(width 0.1524)
				(type default)
			)
			(layer "F.SilkS")
		)
		(fp_poly
			(pts
				(xy -1.947164 -2.341372) (xy -2.66573 -1.622806) (xy -1.588008 -1.26365)
			)
			(stroke
				(width 0)
				(type default)
			)
			(fill yes)
			(layer "F.SilkS")
		)
		(fp_line
			(start 1.500124 1.500124)
			(end -1.500124 1.500124)
			(stroke
				(width 0.1)
				(type default)
			)
			(layer "F.Fab")
		)
		(fp_line
			(start 1.500124 -1.500124)
			(end 1.500124 1.500124)
			(stroke
				(width 0.1)
				(type default)
			)
			(layer "F.Fab")
		)
		(fp_line
			(start -1.500124 1.500124)
			(end -1.500124 -1.500124)
			(stroke
				(width 0.1)
				(type default)
			)
			(layer "F.Fab")
		)
		(fp_line
			(start -1.500124 -1.500124)
			(end 1.500124 -1.500124)
			(stroke
				(width 0.1)
				(type default)
			)
			(layer "F.Fab")
		)
		(fp_poly
			(pts
				(xy -2.847848 -1.258062) (xy -2.847848 -0.242062) (xy -1.831848 -0.750062)
			)
			(stroke
				(width 0)
				(type default)
			)
			(fill yes)
			(layer "F.Fab")
		)
		(pad "1" smd rect
			(at -1.400048 -0.750062 90)
			(size 0.2286 0.6096)
			(layers "F.Cu" "F.Mask" "F.Paste")
			(net "SSD0_ADC_A1")
		)
		(pad "2" smd rect
			(at -1.400048 -0.249936 90)
			(size 0.2286 0.6096)
			(layers "F.Cu" "F.Mask" "F.Paste")
			(net "SSD0_ADC_A0")
		)
		(pad "3" smd rect
			(at -1.400048 0.249936 90)
			(size 0.2286 0.6096)
			(layers "F.Cu" "F.Mask" "F.Paste")
			(net "SSD0_ADC_ALERT_N")
		)
		(pad "4" smd rect
			(at -1.400048 0.750062 90)
			(size 0.2286 0.6096)
			(layers "F.Cu" "F.Mask" "F.Paste")
			(net "SMB_SSD0_ADC_SDA")
		)
		(pad "5" smd rect
			(at -0.750062 1.400048 180)
			(size 0.2286 0.6096)
			(layers "F.Cu" "F.Mask" "F.Paste")
			(net "SMB_SSD0_ADC_SCL")
		)
		(pad "6" smd rect
			(at -0.249936 1.400048 180)
			(size 0.2286 0.6096)
			(layers "F.Cu" "F.Mask" "F.Paste")
			(net "Net_4609")
		)
		(pad "7" smd rect
			(at 0.249936 1.400048 180)
			(size 0.2286 0.6096)
			(layers "F.Cu" "F.Mask" "F.Paste")
			(net "Net_4610")
		)
		(pad "8" smd rect
			(at 0.750062 1.400048 180)
			(size 0.2286 0.6096)
			(layers "F.Cu" "F.Mask" "F.Paste")
			(net "Net_4611")
		)
		(pad "9" smd rect
			(at 1.400048 0.750062 90)
			(size 0.2286 0.6096)
			(layers "F.Cu" "F.Mask" "F.Paste")
			(net "P3V3_AUX")
		)
		(pad "10" smd rect
			(at 1.400048 0.249936 90)
			(size 0.2286 0.6096)
			(layers "F.Cu" "F.Mask" "F.Paste")
			(net "GND")
		)
		(pad "11" smd rect
			(at 1.400048 -0.249936 90)
			(size 0.2286 0.6096)
			(layers "F.Cu" "F.Mask" "F.Paste")
			(net "P12V_SSD0_R")
		)
		(pad "12" smd rect
			(at 1.400048 -0.750062 90)
			(size 0.2286 0.6096)
			(layers "F.Cu" "F.Mask" "F.Paste")
			(net "P12V_SSD0_VIN_N")
		)
		(pad "13" smd rect
			(at 0.750062 -1.400048 180)
			(size 0.2286 0.6096)
			(layers "F.Cu" "F.Mask" "F.Paste")
			(net "P12V_SSD0_VIN_P")
		)
		(pad "14" smd rect
			(at 0.249936 -1.400048 180)
			(size 0.2286 0.6096)
			(layers "F.Cu" "F.Mask" "F.Paste")
			(net "Net_4612")
		)
		(pad "15" smd rect
			(at -0.249936 -1.400048 180)
			(size 0.2286 0.6096)
			(layers "F.Cu" "F.Mask" "F.Paste")
			(net "Net_4613")
		)
		(pad "16" smd rect
			(at -0.750062 -1.400048 180)
			(size 0.2286 0.6096)
			(layers "F.Cu" "F.Mask" "F.Paste")
			(net "Net_4614")
		)
		(pad "TH" smd rect
			(at 0 0 180)
			(size 1.7018 1.7018)
			(layers "F.Cu" "F.Mask" "F.Paste")
			(net "GND")
		)
		(zone
			(layer "F.Cu")
			(hatch none 0.5)
			(connect_pads
				(clearance 0)
			)
			(min_thickness 0.25)
			(keepout
				(tracks not_allowed)
				(vias allowed)
				(pads allowed)
				(copperpour not_allowed)
				(footprints allowed)
			)
			(placement
				(enabled no)
				(sheetname "")
			)
			(fill
				(thermal_gap 0.5)
				(thermal_bridge_width 0.5)
				(island_removal_mode 0)
			)
			(polygon
				(pts
					(xy 23.890478 -46.4185) (xy 23.890478 -45.399452) (xy 21.801582 -45.399452) (xy 21.801582 -47.488348)
					(xy 23.890478 -47.488348) (xy 23.890478 -46.4439) (xy 23.74773 -46.4439) (xy 23.74773 -47.3456)
					(xy 21.94433 -47.3456) (xy 21.94433 -45.5422) (xy 23.74773 -45.5422) (xy 23.74773 -46.4185)
				)
			)
		)
	)
	(footprint ""
		(layer "F.Cu")
		(at 363.474 -206.883)
		(property "Reference" "R4599"
			(at 0 0 0)
			(layer "F.SilkS")
			(hide yes)
			(effects
				(font
					(size 1.27 1.27)
				)
			)
		)
		(property "Value" ""
			(at 0 0 0)
			(layer "F.Fab")
			(effects
				(font
					(size 1.27 1.27)
				)
			)
		)
		(duplicate_pad_numbers_are_jumpers no)
		(fp_line
			(start -0.7874 -0.4064)
			(end 0.7874 -0.4064)
			(stroke
				(width 0.1524)
				(type default)
			)
			(layer "F.SilkS")
		)
		(fp_line
			(start -0.7874 0.4064)
			(end -0.7874 -0.4064)
			(stroke
				(width 0.1524)
				(type default)
			)
			(layer "F.SilkS")
		)
		(fp_line
			(start 0.7874 -0.4064)
			(end 0.7874 0.4064)
			(stroke
				(width 0.1524)
				(type default)
			)
			(layer "F.SilkS")
		)
		(fp_line
			(start 0.7874 0.4064)
			(end -0.7874 0.4064)
			(stroke
				(width 0.1524)
				(type default)
			)
			(layer "F.SilkS")
		)
		(fp_line
			(start -0.67945 -0.305054)
			(end -0.12065 -0.305054)
			(stroke
				(width 0.1)
				(type default)
			)
			(layer "F.Fab")
		)
		(fp_line
			(start -0.67945 0.3048)
			(end -0.67945 -0.305054)
			(stroke
				(width 0.1)
				(type default)
			)
			(layer "F.Fab")
		)
		(fp_line
			(start -0.12065 -0.305054)
			(end -0.12065 -0.2794)
			(stroke
				(width 0.1)
				(type default)
			)
			(layer "F.Fab")
		)
		(fp_line
			(start -0.12065 -0.2794)
			(end 0.12065 -0.2794)
			(stroke
				(width 0.1)
				(type default)
			)
			(layer "F.Fab")
		)
		(fp_line
			(start -0.12065 0.2794)
			(end -0.12065 0.3048)
			(stroke
				(width 0.1)
				(type default)
			)
			(layer "F.Fab")
		)
		(fp_line
			(start -0.12065 0.3048)
			(end -0.67945 0.3048)
			(stroke
				(width 0.1)
				(type default)
			)
			(layer "F.Fab")
		)
		(fp_line
			(start 0.120396 0.2794)
			(end -0.12065 0.2794)
			(stroke
				(width 0.1)
				(type default)
			)
			(layer "F.Fab")
		)
		(fp_line
			(start 0.120396 0.3048)
			(end 0.120396 0.2794)
			(stroke
				(width 0.1)
				(type default)
			)
			(layer "F.Fab")
		)
		(fp_line
			(start 0.12065 -0.3048)
			(end 0.67945 -0.3048)
			(stroke
				(width 0.1)
				(type default)
			)
			(layer "F.Fab")
		)
		(fp_line
			(start 0.12065 -0.2794)
			(end 0.12065 -0.3048)
			(stroke
				(width 0.1)
				(type default)
			)
			(layer "F.Fab")
		)
		(fp_line
			(start 0.67945 -0.3048)
			(end 0.67945 0.3048)
			(stroke
				(width 0.1)
				(type default)
			)
			(layer "F.Fab")
		)
		(fp_line
			(start 0.67945 0.3048)
			(end 0.120396 0.3048)
			(stroke
				(width 0.1)
				(type default)
			)
			(layer "F.Fab")
		)
		(pad "1" smd circle
			(at -0.40005 0)
			(size 0 0)
			(layers "F.Cu" "F.Mask" "F.Paste")
			(net "P3V3_AUX")
		)
		(pad "2" smd circle
			(at 0.40005 0)
			(size 0 0)
			(layers "F.Cu" "F.Mask" "F.Paste")
			(net "SSD1_PEX_PWR_EN_R")
		)
	)
	(footprint ""
		(layer "F.Cu")
		(at 249.20575 -83.431888)
		(property "Reference" "R1062"
			(at 0 0 0)
			(layer "F.SilkS")
			(hide yes)
			(effects
				(font
					(size 1.27 1.27)
				)
			)
		)
		(property "Value" ""
			(at 0 0 0)
			(layer "F.Fab")
			(effects
				(font
					(size 1.27 1.27)
				)
			)
		)
		(duplicate_pad_numbers_are_jumpers no)
		(fp_line
			(start -0.7874 -0.4064)
			(end 0.7874 -0.4064)
			(stroke
				(width 0.1524)
				(type default)
			)
			(layer "F.SilkS")
		)
		(fp_line
			(start -0.7874 0.4064)
			(end -0.7874 -0.4064)
			(stroke
				(width 0.1524)
				(type default)
			)
			(layer "F.SilkS")
		)
		(fp_line
			(start 0.7874 -0.4064)
			(end 0.7874 0.4064)
			(stroke
				(width 0.1524)
				(type default)
			)
			(layer "F.SilkS")
		)
		(fp_line
			(start 0.7874 0.4064)
			(end -0.7874 0.4064)
			(stroke
				(width 0.1524)
				(type default)
			)
			(layer "F.SilkS")
		)
		(fp_line
			(start -0.67945 -0.305054)
			(end -0.12065 -0.305054)
			(stroke
				(width 0.1)
				(type default)
			)
			(layer "F.Fab")
		)
		(fp_line
			(start -0.67945 0.3048)
			(end -0.67945 -0.305054)
			(stroke
				(width 0.1)
				(type default)
			)
			(layer "F.Fab")
		)
		(fp_line
			(start -0.12065 -0.305054)
			(end -0.12065 -0.2794)
			(stroke
				(width 0.1)
				(type default)
			)
			(layer "F.Fab")
		)
		(fp_line
			(start -0.12065 -0.2794)
			(end 0.12065 -0.2794)
			(stroke
				(width 0.1)
				(type default)
			)
			(layer "F.Fab")
		)
		(fp_line
			(start -0.12065 0.2794)
			(end -0.12065 0.3048)
			(stroke
				(width 0.1)
				(type default)
			)
			(layer "F.Fab")
		)
		(fp_line
			(start -0.12065 0.3048)
			(end -0.67945 0.3048)
			(stroke
				(width 0.1)
				(type default)
			)
			(layer "F.Fab")
		)
		(fp_line
			(start 0.120396 0.2794)
			(end -0.12065 0.2794)
			(stroke
				(width 0.1)
				(type default)
			)
			(layer "F.Fab")
		)
		(fp_line
			(start 0.120396 0.3048)
			(end 0.120396 0.2794)
			(stroke
				(width 0.1)
				(type default)
			)
			(layer "F.Fab")
		)
		(fp_line
			(start 0.12065 -0.3048)
			(end 0.67945 -0.3048)
			(stroke
				(width 0.1)
				(type default)
			)
			(layer "F.Fab")
		)
		(fp_line
			(start 0.12065 -0.2794)
			(end 0.12065 -0.3048)
			(stroke
				(width 0.1)
				(type default)
			)
			(layer "F.Fab")
		)
		(fp_line
			(start 0.67945 -0.3048)
			(end 0.67945 0.3048)
			(stroke
				(width 0.1)
				(type default)
			)
			(layer "F.Fab")
		)
		(fp_line
			(start 0.67945 0.3048)
			(end 0.120396 0.3048)
			(stroke
				(width 0.1)
				(type default)
			)
			(layer "F.Fab")
		)
		(pad "1" smd circle
			(at -0.40005 0)
			(size 0 0)
			(layers "F.Cu" "F.Mask" "F.Paste")
			(net "GND")
		)
		(pad "2" smd circle
			(at 0.40005 0)
			(size 0 0)
			(layers "F.Cu" "F.Mask" "F.Paste")
			(net "CLK_CK440_SMB_ADDR0")
		)
	)
	(footprint ""
		(layer "F.Cu")
		(at 168.684194 -29.222954 -90)
		(property "Reference" "PC928"
			(at 0 0 270)
			(layer "F.SilkS")
			(hide yes)
			(effects
				(font
					(size 1.27 1.27)
				)
			)
		)
		(property "Value" ""
			(at 0 0 270)
			(layer "F.Fab")
			(effects
				(font
					(size 1.27 1.27)
				)
			)
		)
		(duplicate_pad_numbers_are_jumpers no)
		(fp_line
			(start -0.7874 0.4064)
			(end -0.7874 -0.4064)
			(stroke
				(width 0.1524)
				(type default)
			)
			(layer "F.SilkS")
		)
		(fp_line
			(start 0.7874 0.4064)
			(end -0.7874 0.4064)
			(stroke
				(width 0.1524)
				(type default)
			)
			(layer "F.SilkS")
		)
		(fp_line
			(start -0.7874 -0.4064)
			(end 0.7874 -0.4064)
			(stroke
				(width 0.1524)
				(type default)
			)
			(layer "F.SilkS")
		)
		(fp_line
			(start 0.7874 -0.4064)
			(end 0.7874 0.4064)
			(stroke
				(width 0.1524)
				(type default)
			)
			(layer "F.SilkS")
		)
		(fp_line
			(start -0.67945 0.3048)
			(end -0.67945 -0.305054)
			(stroke
				(width 0.1)
				(type default)
			)
			(layer "F.Fab")
		)
		(fp_line
			(start -0.12065 0.3048)
			(end -0.67945 0.3048)
			(stroke
				(width 0.1)
				(type default)
			)
			(layer "F.Fab")
		)
		(fp_line
			(start 0.120396 0.3048)
			(end 0.120396 0.2794)
			(stroke
				(width 0.1)
				(type default)
			)
			(layer "F.Fab")
		)
		(fp_line
			(start 0.67945 0.3048)
			(end 0.120396 0.3048)
			(stroke
				(width 0.1)
				(type default)
			)
			(layer "F.Fab")
		)
		(fp_line
			(start -0.12065 0.2794)
			(end -0.12065 0.3048)
			(stroke
				(width 0.1)
				(type default)
			)
			(layer "F.Fab")
		)
		(fp_line
			(start 0.120396 0.2794)
			(end -0.12065 0.2794)
			(stroke
				(width 0.1)
				(type default)
			)
			(layer "F.Fab")
		)
		(fp_line
			(start -0.12065 -0.2794)
			(end 0.12065 -0.2794)
			(stroke
				(width 0.1)
				(type default)
			)
			(layer "F.Fab")
		)
		(fp_line
			(start 0.12065 -0.2794)
			(end 0.12065 -0.3048)
			(stroke
				(width 0.1)
				(type default)
			)
			(layer "F.Fab")
		)
		(fp_line
			(start 0.12065 -0.3048)
			(end 0.67945 -0.3048)
			(stroke
				(width 0.1)
				(type default)
			)
			(layer "F.Fab")
		)
		(fp_line
			(start 0.67945 -0.3048)
			(end 0.67945 0.3048)
			(stroke
				(width 0.1)
				(type default)
			)
			(layer "F.Fab")
		)
		(fp_line
			(start -0.67945 -0.305054)
			(end -0.12065 -0.305054)
			(stroke
				(width 0.1)
				(type default)
			)
			(layer "F.Fab")
		)
		(fp_line
			(start -0.12065 -0.305054)
			(end -0.12065 -0.2794)
			(stroke
				(width 0.1)
				(type default)
			)
			(layer "F.Fab")
		)
		(pad "1" smd circle
			(at -0.40005 0 270)
			(size 0 0)
			(layers "F.Cu" "F.Mask" "F.Paste")
			(net "P3V3_AUX")
		)
		(pad "2" smd circle
			(at 0.40005 0 270)
			(size 0 0)
			(layers "F.Cu" "F.Mask" "F.Paste")
			(net "GND")
		)
	)
	(footprint ""
		(layer "F.Cu")
		(at 363.474 -200.787 180)
		(property "Reference" "R4674"
			(at 0 0 180)
			(layer "F.SilkS")
			(hide yes)
			(effects
				(font
					(size 1.27 1.27)
				)
			)
		)
		(property "Value" ""
			(at 0 0 180)
			(layer "F.Fab")
			(effects
				(font
					(size 1.27 1.27)
				)
			)
		)
		(duplicate_pad_numbers_are_jumpers no)
		(fp_line
			(start 0.7874 0.4064)
			(end -0.7874 0.4064)
			(stroke
				(width 0.1524)
				(type default)
			)
			(layer "F.SilkS")
		)
		(fp_line
			(start 0.7874 -0.4064)
			(end 0.7874 0.4064)
			(stroke
				(width 0.1524)
				(type default)
			)
			(layer "F.SilkS")
		)
		(fp_line
			(start -0.7874 0.4064)
			(end -0.7874 -0.4064)
			(stroke
				(width 0.1524)
				(type default)
			)
			(layer "F.SilkS")
		)
		(fp_line
			(start -0.7874 -0.4064)
			(end 0.7874 -0.4064)
			(stroke
				(width 0.1524)
				(type default)
			)
			(layer "F.SilkS")
		)
		(fp_line
			(start 0.67945 0.3048)
			(end 0.120396 0.3048)
			(stroke
				(width 0.1)
				(type default)
			)
			(layer "F.Fab")
		)
		(fp_line
			(start 0.67945 -0.3048)
			(end 0.67945 0.3048)
			(stroke
				(width 0.1)
				(type default)
			)
			(layer "F.Fab")
		)
		(fp_line
			(start 0.12065 -0.2794)
			(end 0.12065 -0.3048)
			(stroke
				(width 0.1)
				(type default)
			)
			(layer "F.Fab")
		)
		(fp_line
			(start 0.12065 -0.3048)
			(end 0.67945 -0.3048)
			(stroke
				(width 0.1)
				(type default)
			)
			(layer "F.Fab")
		)
		(fp_line
			(start 0.120396 0.3048)
			(end 0.120396 0.2794)
			(stroke
				(width 0.1)
				(type default)
			)
			(layer "F.Fab")
		)
		(fp_line
			(start 0.120396 0.2794)
			(end -0.12065 0.2794)
			(stroke
				(width 0.1)
				(type default)
			)
			(layer "F.Fab")
		)
		(fp_line
			(start -0.12065 0.3048)
			(end -0.67945 0.3048)
			(stroke
				(width 0.1)
				(type default)
			)
			(layer "F.Fab")
		)
		(fp_line
			(start -0.12065 0.2794)
			(end -0.12065 0.3048)
			(stroke
				(width 0.1)
				(type default)
			)
			(layer "F.Fab")
		)
		(fp_line
			(start -0.12065 -0.2794)
			(end 0.12065 -0.2794)
			(stroke
				(width 0.1)
				(type default)
			)
			(layer "F.Fab")
		)
		(fp_line
			(start -0.12065 -0.305054)
			(end -0.12065 -0.2794)
			(stroke
				(width 0.1)
				(type default)
			)
			(layer "F.Fab")
		)
		(fp_line
			(start -0.67945 0.3048)
			(end -0.67945 -0.305054)
			(stroke
				(width 0.1)
				(type default)
			)
			(layer "F.Fab")
		)
		(fp_line
			(start -0.67945 -0.305054)
			(end -0.12065 -0.305054)
			(stroke
				(width 0.1)
				(type default)
			)
			(layer "F.Fab")
		)
		(pad "1" smd circle
			(at -0.40005 0 180)
			(size 0 0)
			(layers "F.Cu" "F.Mask" "F.Paste")
			(net "SSD4_PEX_PWR_EN_R")
		)
		(pad "2" smd circle
			(at 0.40005 0 180)
			(size 0 0)
			(layers "F.Cu" "F.Mask" "F.Paste")
			(net "GND")
		)
	)
	(footprint ""
		(layer "F.Cu")
		(at 291.194998 -101.782372 180)
		(property "Reference" "R276"
			(at 0 0 180)
			(layer "F.SilkS")
			(hide yes)
			(effects
				(font
					(size 1.27 1.27)
				)
			)
		)
		(property "Value" ""
			(at 0 0 180)
			(layer "F.Fab")
			(effects
				(font
					(size 1.27 1.27)
				)
			)
		)
		(duplicate_pad_numbers_are_jumpers no)
		(fp_line
			(start 0.7874 0.4064)
			(end -0.7874 0.4064)
			(stroke
				(width 0.1524)
				(type default)
			)
			(layer "F.SilkS")
		)
		(fp_line
			(start 0.7874 -0.4064)
			(end 0.7874 0.4064)
			(stroke
				(width 0.1524)
				(type default)
			)
			(layer "F.SilkS")
		)
		(fp_line
			(start -0.7874 0.4064)
			(end -0.7874 -0.4064)
			(stroke
				(width 0.1524)
				(type default)
			)
			(layer "F.SilkS")
		)
		(fp_line
			(start -0.7874 -0.4064)
			(end 0.7874 -0.4064)
			(stroke
				(width 0.1524)
				(type default)
			)
			(layer "F.SilkS")
		)
		(fp_line
			(start 0.67945 0.3048)
			(end 0.120396 0.3048)
			(stroke
				(width 0.1)
				(type default)
			)
			(layer "F.Fab")
		)
		(fp_line
			(start 0.67945 -0.3048)
			(end 0.67945 0.3048)
			(stroke
				(width 0.1)
				(type default)
			)
			(layer "F.Fab")
		)
		(fp_line
			(start 0.12065 -0.2794)
			(end 0.12065 -0.3048)
			(stroke
				(width 0.1)
				(type default)
			)
			(layer "F.Fab")
		)
		(fp_line
			(start 0.12065 -0.3048)
			(end 0.67945 -0.3048)
			(stroke
				(width 0.1)
				(type default)
			)
			(layer "F.Fab")
		)
		(fp_line
			(start 0.120396 0.3048)
			(end 0.120396 0.2794)
			(stroke
				(width 0.1)
				(type default)
			)
			(layer "F.Fab")
		)
		(fp_line
			(start 0.120396 0.2794)
			(end -0.12065 0.2794)
			(stroke
				(width 0.1)
				(type default)
			)
			(layer "F.Fab")
		)
		(fp_line
			(start -0.12065 0.3048)
			(end -0.67945 0.3048)
			(stroke
				(width 0.1)
				(type default)
			)
			(layer "F.Fab")
		)
		(fp_line
			(start -0.12065 0.2794)
			(end -0.12065 0.3048)
			(stroke
				(width 0.1)
				(type default)
			)
			(layer "F.Fab")
		)
		(fp_line
			(start -0.12065 -0.2794)
			(end 0.12065 -0.2794)
			(stroke
				(width 0.1)
				(type default)
			)
			(layer "F.Fab")
		)
		(fp_line
			(start -0.12065 -0.305054)
			(end -0.12065 -0.2794)
			(stroke
				(width 0.1)
				(type default)
			)
			(layer "F.Fab")
		)
		(fp_line
			(start -0.67945 0.3048)
			(end -0.67945 -0.305054)
			(stroke
				(width 0.1)
				(type default)
			)
			(layer "F.Fab")
		)
		(fp_line
			(start -0.67945 -0.305054)
			(end -0.12065 -0.305054)
			(stroke
				(width 0.1)
				(type default)
			)
			(layer "F.Fab")
		)
		(pad "1" smd circle
			(at -0.40005 0 180)
			(size 0 0)
			(layers "F.Cu" "F.Mask" "F.Paste")
			(net "NCSI_NIC5_TX_EN")
		)
		(pad "2" smd circle
			(at 0.40005 0 180)
			(size 0 0)
			(layers "F.Cu" "F.Mask" "F.Paste")
			(net "GND")
		)
	)
	(footprint ""
		(layer "F.Cu")
		(at 228.578664 -204.44206 -90)
		(property "Reference" "R5296"
			(at 0 0 270)
			(layer "F.SilkS")
			(hide yes)
			(effects
				(font
					(size 1.27 1.27)
				)
			)
		)
		(property "Value" ""
			(at 0 0 270)
			(layer "F.Fab")
			(effects
				(font
					(size 1.27 1.27)
				)
			)
		)
		(duplicate_pad_numbers_are_jumpers no)
		(fp_line
			(start -0.7874 0.4064)
			(end -0.7874 -0.4064)
			(stroke
				(width 0.1524)
				(type default)
			)
			(layer "F.SilkS")
		)
		(fp_line
			(start 0.7874 0.4064)
			(end -0.7874 0.4064)
			(stroke
				(width 0.1524)
				(type default)
			)
			(layer "F.SilkS")
		)
		(fp_line
			(start -0.7874 -0.4064)
			(end 0.7874 -0.4064)
			(stroke
				(width 0.1524)
				(type default)
			)
			(layer "F.SilkS")
		)
		(fp_line
			(start 0.7874 -0.4064)
			(end 0.7874 0.4064)
			(stroke
				(width 0.1524)
				(type default)
			)
			(layer "F.SilkS")
		)
		(fp_line
			(start -0.67945 0.3048)
			(end -0.67945 -0.305054)
			(stroke
				(width 0.1)
				(type default)
			)
			(layer "F.Fab")
		)
		(fp_line
			(start -0.12065 0.3048)
			(end -0.67945 0.3048)
			(stroke
				(width 0.1)
				(type default)
			)
			(layer "F.Fab")
		)
		(fp_line
			(start 0.120396 0.3048)
			(end 0.120396 0.2794)
			(stroke
				(width 0.1)
				(type default)
			)
			(layer "F.Fab")
		)
		(fp_line
			(start 0.67945 0.3048)
			(end 0.120396 0.3048)
			(stroke
				(width 0.1)
				(type default)
			)
			(layer "F.Fab")
		)
		(fp_line
			(start -0.12065 0.2794)
			(end -0.12065 0.3048)
			(stroke
				(width 0.1)
				(type default)
			)
			(layer "F.Fab")
		)
		(fp_line
			(start 0.120396 0.2794)
			(end -0.12065 0.2794)
			(stroke
				(width 0.1)
				(type default)
			)
			(layer "F.Fab")
		)
		(fp_line
			(start -0.12065 -0.2794)
			(end 0.12065 -0.2794)
			(stroke
				(width 0.1)
				(type default)
			)
			(layer "F.Fab")
		)
		(fp_line
			(start 0.12065 -0.2794)
			(end 0.12065 -0.3048)
			(stroke
				(width 0.1)
				(type default)
			)
			(layer "F.Fab")
		)
		(fp_line
			(start 0.12065 -0.3048)
			(end 0.67945 -0.3048)
			(stroke
				(width 0.1)
				(type default)
			)
			(layer "F.Fab")
		)
		(fp_line
			(start 0.67945 -0.3048)
			(end 0.67945 0.3048)
			(stroke
				(width 0.1)
				(type default)
			)
			(layer "F.Fab")
		)
		(fp_line
			(start -0.67945 -0.305054)
			(end -0.12065 -0.305054)
			(stroke
				(width 0.1)
				(type default)
			)
			(layer "F.Fab")
		)
		(fp_line
			(start -0.12065 -0.305054)
			(end -0.12065 -0.2794)
			(stroke
				(width 0.1)
				(type default)
			)
			(layer "F.Fab")
		)
		(pad "1" smd circle
			(at -0.40005 0 270)
			(size 0 0)
			(layers "F.Cu" "F.Mask" "F.Paste")
			(net "BIC_SEL_FLASH_SW3")
		)
		(pad "2" smd circle
			(at 0.40005 0 270)
			(size 0 0)
			(layers "F.Cu" "F.Mask" "F.Paste")
			(net "BIC_SEL_FLASH_SW3_R")
		)
	)
	(footprint ""
		(layer "F.Cu")
		(at 339.752686 -93.11894 -90)
		(property "Reference" "R1184"
			(at 0 0 270)
			(layer "F.SilkS")
			(hide yes)
			(effects
				(font
					(size 1.27 1.27)
				)
			)
		)
		(property "Value" ""
			(at 0 0 270)
			(layer "F.Fab")
			(effects
				(font
					(size 1.27 1.27)
				)
			)
		)
		(duplicate_pad_numbers_are_jumpers no)
		(fp_line
			(start -0.7874 -0.4064)
			(end 0.7874 -0.4064)
			(stroke
				(width 0.1524)
				(type default)
			)
			(layer "F.SilkS")
		)
		(fp_line
			(start -0.67945 0.3048)
			(end -0.67945 -0.305054)
			(stroke
				(width 0.1)
				(type default)
			)
			(layer "F.Fab")
		)
		(fp_line
			(start -0.12065 0.3048)
			(end -0.67945 0.3048)
			(stroke
				(width 0.1)
				(type default)
			)
			(layer "F.Fab")
		)
		(fp_line
			(start 0.120396 0.3048)
			(end 0.120396 0.2794)
			(stroke
				(width 0.1)
				(type default)
			)
			(layer "F.Fab")
		)
		(fp_line
			(start 0.67945 0.3048)
			(end 0.120396 0.3048)
			(stroke
				(width 0.1)
				(type default)
			)
			(layer "F.Fab")
		)
		(fp_line
			(start -0.12065 0.2794)
			(end -0.12065 0.3048)
			(stroke
				(width 0.1)
				(type default)
			)
			(layer "F.Fab")
		)
		(fp_line
			(start 0.120396 0.2794)
			(end -0.12065 0.2794)
			(stroke
				(width 0.1)
				(type default)
			)
			(layer "F.Fab")
		)
		(fp_line
			(start -0.12065 -0.2794)
			(end 0.12065 -0.2794)
			(stroke
				(width 0.1)
				(type default)
			)
			(layer "F.Fab")
		)
		(fp_line
			(start 0.12065 -0.2794)
			(end 0.12065 -0.3048)
			(stroke
				(width 0.1)
				(type default)
			)
			(layer "F.Fab")
		)
		(fp_line
			(start 0.12065 -0.3048)
			(end 0.67945 -0.3048)
			(stroke
				(width 0.1)
				(type default)
			)
			(layer "F.Fab")
		)
		(fp_line
			(start 0.67945 -0.3048)
			(end 0.67945 0.3048)
			(stroke
				(width 0.1)
				(type default)
			)
			(layer "F.Fab")
		)
		(fp_line
			(start -0.67945 -0.305054)
			(end -0.12065 -0.305054)
			(stroke
				(width 0.1)
				(type default)
			)
			(layer "F.Fab")
		)
		(fp_line
			(start -0.12065 -0.305054)
			(end -0.12065 -0.2794)
			(stroke
				(width 0.1)
				(type default)
			)
			(layer "F.Fab")
		)
		(pad "1" smd circle
			(at -0.40005 0 270)
			(size 0 0)
			(layers "F.Cu" "F.Mask" "F.Paste")
			(net "CLK_100M_DB800ZL_SSD15_R_DP")
		)
		(pad "2" smd circle
			(at 0.40005 0 270)
			(size 0 0)
			(layers "F.Cu" "F.Mask" "F.Paste")
			(net "CLK_100M_DB800ZL_SSD15_DP")
		)
	)
	(footprint ""
		(layer "F.Cu")
		(at 59.799982 -407.960068 180)
		(property "Reference" "J63"
			(at 0.047498 -11.476228 0)
			(unlocked yes)
			(layer "F.SilkS")
			(effects
				(font
					(size 0.7874 0.5842)
					(thickness 0.1524)
				)
			)
		)
		(property "Value" ""
			(at 0 0 180)
			(layer "F.Fab")
			(effects
				(font
					(size 1.27 1.27)
				)
			)
		)
		(duplicate_pad_numbers_are_jumpers no)
		(fp_line
			(start 3.525012 21.310092)
			(end 3.525012 -10.489946)
			(stroke
				(width 0.1524)
				(type default)
			)
			(layer "F.SilkS")
		)
		(fp_line
			(start 3.525012 -10.489946)
			(end -3.525012 -10.489946)
			(stroke
				(width 0.1524)
				(type default)
			)
			(layer "F.SilkS")
		)
		(fp_line
			(start -3.525012 21.310092)
			(end 3.525012 21.310092)
			(stroke
				(width 0.1524)
				(type default)
			)
			(layer "F.SilkS")
		)
		(fp_line
			(start -3.525012 10.6299)
			(end 3.525012 10.6299)
			(stroke
				(width 0.1524)
				(type default)
			)
			(layer "F.SilkS")
		)
		(fp_line
			(start -3.525012 -10.489946)
			(end -3.525012 21.310092)
			(stroke
				(width 0.1524)
				(type default)
			)
			(layer "F.SilkS")
		)
		(fp_line
			(start 3.525012 21.310092)
			(end 3.525012 -10.489946)
			(stroke
				(width 0.1)
				(type default)
			)
			(layer "F.Fab")
		)
		(fp_line
			(start 3.525012 -10.489946)
			(end -3.525012 -10.489946)
			(stroke
				(width 0.1)
				(type default)
			)
			(layer "F.Fab")
		)
		(fp_line
			(start -3.525012 21.310092)
			(end 3.525012 21.310092)
			(stroke
				(width 0.1)
				(type default)
			)
			(layer "F.Fab")
		)
		(fp_line
			(start -3.525012 -10.489946)
			(end -3.525012 21.310092)
			(stroke
				(width 0.1)
				(type default)
			)
			(layer "F.Fab")
		)
		(pad "" np_thru_hole circle
			(at 0 -6.620002 180)
			(size 3.175 3.175)
			(drill 3.175)
			(layers "*.Cu" "*.Mask")
			(clearance 0.381)
			(thermal_gap 0.381)
		)
		(pad "" np_thru_hole circle
			(at 0 0 180)
			(size 0 0)
			(drill 3.175)
			(layers "*.Cu" "*.Mask")
			(clearance 0)
		)
		(pad "" np_thru_hole circle
			(at 0 5.130038 180)
			(size 3.175 3.175)
			(drill 3.175)
			(layers "*.Cu" "*.Mask")
			(clearance 0.381)
			(thermal_gap 0.381)
		)
		(zone
			(layers "F.Cu" "B.Cu" "In1.Cu" "In2.Cu" "In3.Cu" "In4.Cu" "In5.Cu" "In6.Cu"
				"In7.Cu" "In8.Cu" "In9.Cu" "In10.Cu" "In11.Cu" "In12.Cu" "In13.Cu" "In14.Cu"
				"In15.Cu" "In16.Cu"
			)
			(hatch none 0.5)
			(connect_pads
				(clearance 0)
			)
			(min_thickness 0.25)
			(keepout
				(tracks not_allowed)
				(vias allowed)
				(pads allowed)
				(copperpour not_allowed)
				(footprints allowed)
			)
			(placement
				(enabled no)
				(sheetname "")
			)
			(fill
				(thermal_gap 0.5)
				(thermal_bridge_width 0.5)
				(island_removal_mode 0)
			)
			(polygon
				(pts
					(arc
						(start 61.895482 -413.090106)
						(mid 57.704482 -413.090106)
						(end 61.895482 -413.090106)
					)
				)
			)
		)
		(zone
			(layers "F.Cu" "B.Cu" "In1.Cu" "In2.Cu" "In3.Cu" "In4.Cu" "In5.Cu" "In6.Cu"
				"In7.Cu" "In8.Cu" "In9.Cu" "In10.Cu" "In11.Cu" "In12.Cu" "In13.Cu" "In14.Cu"
				"In15.Cu" "In16.Cu"
			)
			(hatch none 0.5)
			(connect_pads
				(clearance 0)
			)
			(min_thickness 0.25)
			(keepout
				(tracks not_allowed)
				(vias allowed)
				(pads allowed)
				(copperpour not_allowed)
				(footprints allowed)
			)
			(placement
				(enabled no)
				(sheetname "")
			)
			(fill
				(thermal_gap 0.5)
				(thermal_bridge_width 0.5)
				(island_removal_mode 0)
			)
			(polygon
				(pts
					(arc
						(start 61.895482 -401.340066)
						(mid 57.704482 -401.340066)
						(end 61.895482 -401.340066)
					)
				)
			)
		)
		(zone
			(layers "F.Cu" "B.Cu" "In1.Cu" "In2.Cu" "In3.Cu" "In4.Cu" "In5.Cu" "In6.Cu"
				"In7.Cu" "In8.Cu" "In9.Cu" "In10.Cu" "In11.Cu" "In12.Cu" "In13.Cu" "In14.Cu"
				"In15.Cu" "In16.Cu"
			)
			(hatch none 0.5)
			(connect_pads
				(clearance 0)
			)
			(min_thickness 0.25)
			(keepout
				(tracks not_allowed)
				(vias allowed)
				(pads allowed)
				(copperpour not_allowed)
				(footprints allowed)
			)
			(placement
				(enabled no)
				(sheetname "")
			)
			(fill
				(thermal_gap 0.5)
				(thermal_bridge_width 0.5)
				(island_removal_mode 0)
			)
			(polygon
				(pts
					(arc
						(start 63.419482 -407.960068)
						(mid 56.180482 -407.960068)
						(end 63.419482 -407.960068)
					)
				)
			)
		)
	)
	(footprint ""
		(layer "F.Cu")
		(at 27.390344 -250.070874 -90)
		(property "Reference" "R1157"
			(at 0 0 270)
			(layer "F.SilkS")
			(hide yes)
			(effects
				(font
					(size 1.27 1.27)
				)
			)
		)
		(property "Value" ""
			(at 0 0 270)
			(layer "F.Fab")
			(effects
				(font
					(size 1.27 1.27)
				)
			)
		)
		(duplicate_pad_numbers_are_jumpers no)
		(fp_line
			(start -0.7874 0.4064)
			(end -0.7874 -0.4064)
			(stroke
				(width 0.1524)
				(type default)
			)
			(layer "F.SilkS")
		)
		(fp_line
			(start 0.7874 0.4064)
			(end -0.7874 0.4064)
			(stroke
				(width 0.1524)
				(type default)
			)
			(layer "F.SilkS")
		)
		(fp_line
			(start -0.7874 -0.4064)
			(end 0.7874 -0.4064)
			(stroke
				(width 0.1524)
				(type default)
			)
			(layer "F.SilkS")
		)
		(fp_line
			(start 0.7874 -0.4064)
			(end 0.7874 0.4064)
			(stroke
				(width 0.1524)
				(type default)
			)
			(layer "F.SilkS")
		)
		(fp_line
			(start -0.67945 0.3048)
			(end -0.67945 -0.305054)
			(stroke
				(width 0.1)
				(type default)
			)
			(layer "F.Fab")
		)
		(fp_line
			(start -0.12065 0.3048)
			(end -0.67945 0.3048)
			(stroke
				(width 0.1)
				(type default)
			)
			(layer "F.Fab")
		)
		(fp_line
			(start 0.120396 0.3048)
			(end 0.120396 0.2794)
			(stroke
				(width 0.1)
				(type default)
			)
			(layer "F.Fab")
		)
		(fp_line
			(start 0.67945 0.3048)
			(end 0.120396 0.3048)
			(stroke
				(width 0.1)
				(type default)
			)
			(layer "F.Fab")
		)
		(fp_line
			(start -0.12065 0.2794)
			(end -0.12065 0.3048)
			(stroke
				(width 0.1)
				(type default)
			)
			(layer "F.Fab")
		)
		(fp_line
			(start 0.120396 0.2794)
			(end -0.12065 0.2794)
			(stroke
				(width 0.1)
				(type default)
			)
			(layer "F.Fab")
		)
		(fp_line
			(start -0.12065 -0.2794)
			(end 0.12065 -0.2794)
			(stroke
				(width 0.1)
				(type default)
			)
			(layer "F.Fab")
		)
		(fp_line
			(start 0.12065 -0.2794)
			(end 0.12065 -0.3048)
			(stroke
				(width 0.1)
				(type default)
			)
			(layer "F.Fab")
		)
		(fp_line
			(start 0.12065 -0.3048)
			(end 0.67945 -0.3048)
			(stroke
				(width 0.1)
				(type default)
			)
			(layer "F.Fab")
		)
		(fp_line
			(start 0.67945 -0.3048)
			(end 0.67945 0.3048)
			(stroke
				(width 0.1)
				(type default)
			)
			(layer "F.Fab")
		)
		(fp_line
			(start -0.67945 -0.305054)
			(end -0.12065 -0.305054)
			(stroke
				(width 0.1)
				(type default)
			)
			(layer "F.Fab")
		)
		(fp_line
			(start -0.12065 -0.305054)
			(end -0.12065 -0.2794)
			(stroke
				(width 0.1)
				(type default)
			)
			(layer "F.Fab")
		)
		(pad "1" smd circle
			(at -0.40005 0 270)
			(size 0 0)
			(layers "F.Cu" "F.Mask" "F.Paste")
			(net "PEX0_MODE_SEL5")
		)
		(pad "2" smd circle
			(at 0.40005 0 270)
			(size 0 0)
			(layers "F.Cu" "F.Mask" "F.Paste")
			(net "P1V8_PEX")
		)
	)
	(footprint ""
		(layer "F.Cu")
		(at 457.935838 -312.795158)
		(property "Reference" "PC265"
			(at 0 0 0)
			(layer "F.SilkS")
			(hide yes)
			(effects
				(font
					(size 1.27 1.27)
				)
			)
		)
		(property "Value" ""
			(at 0 0 0)
			(layer "F.Fab")
			(effects
				(font
					(size 1.27 1.27)
				)
			)
		)
		(duplicate_pad_numbers_are_jumpers no)
		(fp_line
			(start -1.524 -0.762)
			(end 1.524 -0.762)
			(stroke
				(width 0.1524)
				(type default)
			)
			(layer "F.SilkS")
		)
		(fp_line
			(start -1.524 0.762)
			(end -1.524 -0.762)
			(stroke
				(width 0.1524)
				(type default)
			)
			(layer "F.SilkS")
		)
		(fp_line
			(start 1.524 -0.762)
			(end 1.524 0.762)
			(stroke
				(width 0.1524)
				(type default)
			)
			(layer "F.SilkS")
		)
		(fp_line
			(start 1.524 0.762)
			(end -1.524 0.762)
			(stroke
				(width 0.1524)
				(type default)
			)
			(layer "F.SilkS")
		)
		(fp_line
			(start -1.1049 -0.724916)
			(end -1.1049 0.724916)
			(stroke
				(width 0.1)
				(type default)
			)
			(layer "F.Fab")
		)
		(fp_line
			(start -1.1049 0.724916)
			(end 1.1049 0.724916)
			(stroke
				(width 0.1)
				(type default)
			)
			(layer "F.Fab")
		)
		(fp_line
			(start 1.1049 -0.724916)
			(end -1.1049 -0.724916)
			(stroke
				(width 0.1)
				(type default)
			)
			(layer "F.Fab")
		)
		(fp_line
			(start 1.1049 0.724916)
			(end 1.1049 -0.724916)
			(stroke
				(width 0.1)
				(type default)
			)
			(layer "F.Fab")
		)
		(pad "1" smd rect
			(at -0.889 0 180)
			(size 1.016 1.27)
			(layers "F.Cu" "F.Mask" "F.Paste")
			(net "SW_P12V_P1V25_PEX3_FLT")
		)
		(pad "2" smd rect
			(at 0.889 0 180)
			(size 1.016 1.27)
			(layers "F.Cu" "F.Mask" "F.Paste")
			(net "GND")
		)
	)
	(footprint ""
		(layer "F.Cu")
		(at 207.473804 -298.885102 -90)
		(property "Reference" "R4015"
			(at 0 0 270)
			(layer "F.SilkS")
			(hide yes)
			(effects
				(font
					(size 1.27 1.27)
				)
			)
		)
		(property "Value" ""
			(at 0 0 270)
			(layer "F.Fab")
			(effects
				(font
					(size 1.27 1.27)
				)
			)
		)
		(duplicate_pad_numbers_are_jumpers no)
		(fp_line
			(start -0.7874 0.4064)
			(end -0.7874 -0.4064)
			(stroke
				(width 0.1524)
				(type default)
			)
			(layer "F.SilkS")
		)
		(fp_line
			(start 0.7874 0.4064)
			(end -0.7874 0.4064)
			(stroke
				(width 0.1524)
				(type default)
			)
			(layer "F.SilkS")
		)
		(fp_line
			(start -0.7874 -0.4064)
			(end 0.7874 -0.4064)
			(stroke
				(width 0.1524)
				(type default)
			)
			(layer "F.SilkS")
		)
		(fp_line
			(start 0.7874 -0.4064)
			(end 0.7874 0.4064)
			(stroke
				(width 0.1524)
				(type default)
			)
			(layer "F.SilkS")
		)
		(fp_line
			(start -0.67945 0.3048)
			(end -0.67945 -0.305054)
			(stroke
				(width 0.1)
				(type default)
			)
			(layer "F.Fab")
		)
		(fp_line
			(start -0.12065 0.3048)
			(end -0.67945 0.3048)
			(stroke
				(width 0.1)
				(type default)
			)
			(layer "F.Fab")
		)
		(fp_line
			(start 0.120396 0.3048)
			(end 0.120396 0.2794)
			(stroke
				(width 0.1)
				(type default)
			)
			(layer "F.Fab")
		)
		(fp_line
			(start 0.67945 0.3048)
			(end 0.120396 0.3048)
			(stroke
				(width 0.1)
				(type default)
			)
			(layer "F.Fab")
		)
		(fp_line
			(start -0.12065 0.2794)
			(end -0.12065 0.3048)
			(stroke
				(width 0.1)
				(type default)
			)
			(layer "F.Fab")
		)
		(fp_line
			(start 0.120396 0.2794)
			(end -0.12065 0.2794)
			(stroke
				(width 0.1)
				(type default)
			)
			(layer "F.Fab")
		)
		(fp_line
			(start -0.12065 -0.2794)
			(end 0.12065 -0.2794)
			(stroke
				(width 0.1)
				(type default)
			)
			(layer "F.Fab")
		)
		(fp_line
			(start 0.12065 -0.2794)
			(end 0.12065 -0.3048)
			(stroke
				(width 0.1)
				(type default)
			)
			(layer "F.Fab")
		)
		(fp_line
			(start 0.12065 -0.3048)
			(end 0.67945 -0.3048)
			(stroke
				(width 0.1)
				(type default)
			)
			(layer "F.Fab")
		)
		(fp_line
			(start 0.67945 -0.3048)
			(end 0.67945 0.3048)
			(stroke
				(width 0.1)
				(type default)
			)
			(layer "F.Fab")
		)
		(fp_line
			(start -0.67945 -0.305054)
			(end -0.12065 -0.305054)
			(stroke
				(width 0.1)
				(type default)
			)
			(layer "F.Fab")
		)
		(fp_line
			(start -0.12065 -0.305054)
			(end -0.12065 -0.2794)
			(stroke
				(width 0.1)
				(type default)
			)
			(layer "F.Fab")
		)
		(pad "1" smd circle
			(at -0.40005 0 270)
			(size 0 0)
			(layers "F.Cu" "F.Mask" "F.Paste")
			(net "P1V8_PEX")
		)
		(pad "2" smd circle
			(at 0.40005 0 270)
			(size 0 0)
			(layers "F.Cu" "F.Mask" "F.Paste")
			(net "I2C_PEX1_HOST_R_SCL")
		)
	)
	(footprint ""
		(layer "F.Cu")
		(at 278.105616 -405.074374 90)
		(property "Reference" "R1819"
			(at 0 0 90)
			(layer "F.SilkS")
			(hide yes)
			(effects
				(font
					(size 1.27 1.27)
				)
			)
		)
		(property "Value" ""
			(at 0 0 90)
			(layer "F.Fab")
			(effects
				(font
					(size 1.27 1.27)
				)
			)
		)
		(duplicate_pad_numbers_are_jumpers no)
		(fp_line
			(start 0.7874 -0.4064)
			(end 0.7874 0.4064)
			(stroke
				(width 0.1524)
				(type default)
			)
			(layer "F.SilkS")
		)
		(fp_line
			(start -0.7874 -0.4064)
			(end 0.7874 -0.4064)
			(stroke
				(width 0.1524)
				(type default)
			)
			(layer "F.SilkS")
		)
		(fp_line
			(start 0.7874 0.4064)
			(end -0.7874 0.4064)
			(stroke
				(width 0.1524)
				(type default)
			)
			(layer "F.SilkS")
		)
		(fp_line
			(start -0.7874 0.4064)
			(end -0.7874 -0.4064)
			(stroke
				(width 0.1524)
				(type default)
			)
			(layer "F.SilkS")
		)
		(fp_line
			(start -0.12065 -0.305054)
			(end -0.12065 -0.2794)
			(stroke
				(width 0.1)
				(type default)
			)
			(layer "F.Fab")
		)
		(fp_line
			(start -0.67945 -0.305054)
			(end -0.12065 -0.305054)
			(stroke
				(width 0.1)
				(type default)
			)
			(layer "F.Fab")
		)
		(fp_line
			(start 0.67945 -0.3048)
			(end 0.67945 0.3048)
			(stroke
				(width 0.1)
				(type default)
			)
			(layer "F.Fab")
		)
		(fp_line
			(start 0.12065 -0.3048)
			(end 0.67945 -0.3048)
			(stroke
				(width 0.1)
				(type default)
			)
			(layer "F.Fab")
		)
		(fp_line
			(start 0.12065 -0.2794)
			(end 0.12065 -0.3048)
			(stroke
				(width 0.1)
				(type default)
			)
			(layer "F.Fab")
		)
		(fp_line
			(start -0.12065 -0.2794)
			(end 0.12065 -0.2794)
			(stroke
				(width 0.1)
				(type default)
			)
			(layer "F.Fab")
		)
		(fp_line
			(start 0.120396 0.2794)
			(end -0.12065 0.2794)
			(stroke
				(width 0.1)
				(type default)
			)
			(layer "F.Fab")
		)
		(fp_line
			(start -0.12065 0.2794)
			(end -0.12065 0.3048)
			(stroke
				(width 0.1)
				(type default)
			)
			(layer "F.Fab")
		)
		(fp_line
			(start 0.67945 0.3048)
			(end 0.120396 0.3048)
			(stroke
				(width 0.1)
				(type default)
			)
			(layer "F.Fab")
		)
		(fp_line
			(start 0.120396 0.3048)
			(end 0.120396 0.2794)
			(stroke
				(width 0.1)
				(type default)
			)
			(layer "F.Fab")
		)
		(fp_line
			(start -0.12065 0.3048)
			(end -0.67945 0.3048)
			(stroke
				(width 0.1)
				(type default)
			)
			(layer "F.Fab")
		)
		(fp_line
			(start -0.67945 0.3048)
			(end -0.67945 -0.305054)
			(stroke
				(width 0.1)
				(type default)
			)
			(layer "F.Fab")
		)
		(pad "1" smd circle
			(at -0.40005 0 90)
			(size 0 0)
			(layers "F.Cu" "F.Mask" "F.Paste")
			(net "BIC_SYS_READY_R_N")
		)
		(pad "2" smd circle
			(at 0.40005 0 90)
			(size 0 0)
			(layers "F.Cu" "F.Mask" "F.Paste")
			(net "BIC_SYS_READY_R1_N")
		)
	)
	(footprint ""
		(layer "F.Cu")
		(at 155.380436 -121.919746)
		(property "Reference" "C257"
			(at 0 0 0)
			(layer "F.SilkS")
			(hide yes)
			(effects
				(font
					(size 1.27 1.27)
				)
			)
		)
		(property "Value" ""
			(at 0 0 0)
			(layer "F.Fab")
			(effects
				(font
					(size 1.27 1.27)
				)
			)
		)
		(duplicate_pad_numbers_are_jumpers no)
		(fp_line
			(start -0.299974 -0.150114)
			(end 0.299974 -0.150114)
			(stroke
				(width 0.1)
				(type default)
			)
			(layer "F.Fab")
		)
		(fp_line
			(start -0.299974 0.150114)
			(end -0.299974 -0.150114)
			(stroke
				(width 0.1)
				(type default)
			)
			(layer "F.Fab")
		)
		(fp_line
			(start 0.299974 -0.150114)
			(end 0.299974 0.150114)
			(stroke
				(width 0.1)
				(type default)
			)
			(layer "F.Fab")
		)
		(fp_line
			(start 0.299974 0.150114)
			(end -0.299974 0.150114)
			(stroke
				(width 0.1)
				(type default)
			)
			(layer "F.Fab")
		)
		(pad "1" smd rect
			(at -0.2667 0)
			(size 0.3048 0.381)
			(layers "F.Cu" "F.Mask" "F.Paste")
			(net "P5E_PEX1_STN1_TX_DP<25>")
		)
		(pad "2" smd rect
			(at 0.2667 0)
			(size 0.3048 0.381)
			(layers "F.Cu" "F.Mask" "F.Paste")
			(net "P5E_PEX1_STN1_TX_C_DP<25>")
		)
	)
	(footprint ""
		(layer "F.Cu")
		(at 124.149612 -158.828994 180)
		(property "Reference" "R5832"
			(at 0 0 180)
			(layer "F.SilkS")
			(hide yes)
			(effects
				(font
					(size 1.27 1.27)
				)
			)
		)
		(property "Value" ""
			(at 0 0 180)
			(layer "F.Fab")
			(effects
				(font
					(size 1.27 1.27)
				)
			)
		)
		(duplicate_pad_numbers_are_jumpers no)
		(fp_line
			(start 0.7874 0.4064)
			(end -0.7874 0.4064)
			(stroke
				(width 0.1524)
				(type default)
			)
			(layer "F.SilkS")
		)
		(fp_line
			(start 0.7874 -0.4064)
			(end 0.7874 0.4064)
			(stroke
				(width 0.1524)
				(type default)
			)
			(layer "F.SilkS")
		)
		(fp_line
			(start -0.7874 0.4064)
			(end -0.7874 -0.4064)
			(stroke
				(width 0.1524)
				(type default)
			)
			(layer "F.SilkS")
		)
		(fp_line
			(start -0.7874 -0.4064)
			(end 0.7874 -0.4064)
			(stroke
				(width 0.1524)
				(type default)
			)
			(layer "F.SilkS")
		)
		(fp_line
			(start 0.67945 0.3048)
			(end 0.120396 0.3048)
			(stroke
				(width 0.1)
				(type default)
			)
			(layer "F.Fab")
		)
		(fp_line
			(start 0.67945 -0.3048)
			(end 0.67945 0.3048)
			(stroke
				(width 0.1)
				(type default)
			)
			(layer "F.Fab")
		)
		(fp_line
			(start 0.12065 -0.2794)
			(end 0.12065 -0.3048)
			(stroke
				(width 0.1)
				(type default)
			)
			(layer "F.Fab")
		)
		(fp_line
			(start 0.12065 -0.3048)
			(end 0.67945 -0.3048)
			(stroke
				(width 0.1)
				(type default)
			)
			(layer "F.Fab")
		)
		(fp_line
			(start 0.120396 0.3048)
			(end 0.120396 0.2794)
			(stroke
				(width 0.1)
				(type default)
			)
			(layer "F.Fab")
		)
		(fp_line
			(start 0.120396 0.2794)
			(end -0.12065 0.2794)
			(stroke
				(width 0.1)
				(type default)
			)
			(layer "F.Fab")
		)
		(fp_line
			(start -0.12065 0.3048)
			(end -0.67945 0.3048)
			(stroke
				(width 0.1)
				(type default)
			)
			(layer "F.Fab")
		)
		(fp_line
			(start -0.12065 0.2794)
			(end -0.12065 0.3048)
			(stroke
				(width 0.1)
				(type default)
			)
			(layer "F.Fab")
		)
		(fp_line
			(start -0.12065 -0.2794)
			(end 0.12065 -0.2794)
			(stroke
				(width 0.1)
				(type default)
			)
			(layer "F.Fab")
		)
		(fp_line
			(start -0.12065 -0.305054)
			(end -0.12065 -0.2794)
			(stroke
				(width 0.1)
				(type default)
			)
			(layer "F.Fab")
		)
		(fp_line
			(start -0.67945 0.3048)
			(end -0.67945 -0.305054)
			(stroke
				(width 0.1)
				(type default)
			)
			(layer "F.Fab")
		)
		(fp_line
			(start -0.67945 -0.305054)
			(end -0.12065 -0.305054)
			(stroke
				(width 0.1)
				(type default)
			)
			(layer "F.Fab")
		)
		(pad "1" smd circle
			(at -0.40005 0 180)
			(size 0 0)
			(layers "F.Cu" "F.Mask" "F.Paste")
			(net "PWRGD_P12V_NIC2_CO")
		)
		(pad "2" smd circle
			(at 0.40005 0 180)
			(size 0 0)
			(layers "F.Cu" "F.Mask" "F.Paste")
			(net "PWRGD_P12V_NIC2_R")
		)
	)
	(footprint ""
		(layer "F.Cu")
		(at 380.48946 -343.952322 90)
		(property "Reference" "C786"
			(at 0 0 90)
			(layer "F.SilkS")
			(hide yes)
			(effects
				(font
					(size 1.27 1.27)
				)
			)
		)
		(property "Value" ""
			(at 0 0 90)
			(layer "F.Fab")
			(effects
				(font
					(size 1.27 1.27)
				)
			)
		)
		(duplicate_pad_numbers_are_jumpers no)
		(fp_line
			(start 0.299974 -0.150114)
			(end 0.299974 0.150114)
			(stroke
				(width 0.1)
				(type default)
			)
			(layer "F.Fab")
		)
		(fp_line
			(start -0.299974 -0.150114)
			(end 0.299974 -0.150114)
			(stroke
				(width 0.1)
				(type default)
			)
			(layer "F.Fab")
		)
		(fp_line
			(start 0.299974 0.150114)
			(end -0.299974 0.150114)
			(stroke
				(width 0.1)
				(type default)
			)
			(layer "F.Fab")
		)
		(fp_line
			(start -0.299974 0.150114)
			(end -0.299974 -0.150114)
			(stroke
				(width 0.1)
				(type default)
			)
			(layer "F.Fab")
		)
		(pad "1" smd rect
			(at -0.2667 0 90)
			(size 0.3048 0.381)
			(layers "F.Cu" "F.Mask" "F.Paste")
			(net "P5E_PEX3_STN6_TX_DP<99>")
		)
		(pad "2" smd rect
			(at 0.2667 0 90)
			(size 0.3048 0.381)
			(layers "F.Cu" "F.Mask" "F.Paste")
			(net "P5E_PEX3_STN6_TX_C_DP<99>")
		)
	)
	(footprint ""
		(layer "F.Cu")
		(at 168.55948 -22.955504 90)
		(property "Reference" "R1672"
			(at 0 0 90)
			(layer "F.SilkS")
			(hide yes)
			(effects
				(font
					(size 1.27 1.27)
				)
			)
		)
		(property "Value" ""
			(at 0 0 90)
			(layer "F.Fab")
			(effects
				(font
					(size 1.27 1.27)
				)
			)
		)
		(duplicate_pad_numbers_are_jumpers no)
		(fp_line
			(start 0.7874 -0.4064)
			(end 0.7874 0.4064)
			(stroke
				(width 0.1524)
				(type default)
			)
			(layer "F.SilkS")
		)
		(fp_line
			(start -0.7874 -0.4064)
			(end 0.7874 -0.4064)
			(stroke
				(width 0.1524)
				(type default)
			)
			(layer "F.SilkS")
		)
		(fp_line
			(start 0.7874 0.4064)
			(end -0.7874 0.4064)
			(stroke
				(width 0.1524)
				(type default)
			)
			(layer "F.SilkS")
		)
		(fp_line
			(start -0.7874 0.4064)
			(end -0.7874 -0.4064)
			(stroke
				(width 0.1524)
				(type default)
			)
			(layer "F.SilkS")
		)
		(fp_line
			(start -0.12065 -0.305054)
			(end -0.12065 -0.2794)
			(stroke
				(width 0.1)
				(type default)
			)
			(layer "F.Fab")
		)
		(fp_line
			(start -0.67945 -0.305054)
			(end -0.12065 -0.305054)
			(stroke
				(width 0.1)
				(type default)
			)
			(layer "F.Fab")
		)
		(fp_line
			(start 0.67945 -0.3048)
			(end 0.67945 0.3048)
			(stroke
				(width 0.1)
				(type default)
			)
			(layer "F.Fab")
		)
		(fp_line
			(start 0.12065 -0.3048)
			(end 0.67945 -0.3048)
			(stroke
				(width 0.1)
				(type default)
			)
			(layer "F.Fab")
		)
		(fp_line
			(start 0.12065 -0.2794)
			(end 0.12065 -0.3048)
			(stroke
				(width 0.1)
				(type default)
			)
			(layer "F.Fab")
		)
		(fp_line
			(start -0.12065 -0.2794)
			(end 0.12065 -0.2794)
			(stroke
				(width 0.1)
				(type default)
			)
			(layer "F.Fab")
		)
		(fp_line
			(start 0.120396 0.2794)
			(end -0.12065 0.2794)
			(stroke
				(width 0.1)
				(type default)
			)
			(layer "F.Fab")
		)
		(fp_line
			(start -0.12065 0.2794)
			(end -0.12065 0.3048)
			(stroke
				(width 0.1)
				(type default)
			)
			(layer "F.Fab")
		)
		(fp_line
			(start 0.67945 0.3048)
			(end 0.120396 0.3048)
			(stroke
				(width 0.1)
				(type default)
			)
			(layer "F.Fab")
		)
		(fp_line
			(start 0.120396 0.3048)
			(end 0.120396 0.2794)
			(stroke
				(width 0.1)
				(type default)
			)
			(layer "F.Fab")
		)
		(fp_line
			(start -0.12065 0.3048)
			(end -0.67945 0.3048)
			(stroke
				(width 0.1)
				(type default)
			)
			(layer "F.Fab")
		)
		(fp_line
			(start -0.67945 0.3048)
			(end -0.67945 -0.305054)
			(stroke
				(width 0.1)
				(type default)
			)
			(layer "F.Fab")
		)
		(pad "1" smd circle
			(at -0.40005 0 90)
			(size 0 0)
			(layers "F.Cu" "F.Mask" "F.Paste")
			(net "SMB_BIC_I2C9_MUX0_SSD5_R_SCL")
		)
		(pad "2" smd circle
			(at 0.40005 0 90)
			(size 0 0)
			(layers "F.Cu" "F.Mask" "F.Paste")
			(net "SMB_ISO_SSD5_SCL")
		)
	)
	(footprint ""
		(layer "F.Cu")
		(at 231.844596 -277.535386)
		(property "Reference" "R783"
			(at 0 0 0)
			(layer "F.SilkS")
			(hide yes)
			(effects
				(font
					(size 1.27 1.27)
				)
			)
		)
		(property "Value" ""
			(at 0 0 0)
			(layer "F.Fab")
			(effects
				(font
					(size 1.27 1.27)
				)
			)
		)
		(duplicate_pad_numbers_are_jumpers no)
		(fp_line
			(start -0.7874 -0.4064)
			(end 0.7874 -0.4064)
			(stroke
				(width 0.1524)
				(type default)
			)
			(layer "F.SilkS")
		)
		(fp_line
			(start -0.7874 0.4064)
			(end -0.7874 -0.4064)
			(stroke
				(width 0.1524)
				(type default)
			)
			(layer "F.SilkS")
		)
		(fp_line
			(start 0.7874 -0.4064)
			(end 0.7874 0.4064)
			(stroke
				(width 0.1524)
				(type default)
			)
			(layer "F.SilkS")
		)
		(fp_line
			(start 0.7874 0.4064)
			(end -0.7874 0.4064)
			(stroke
				(width 0.1524)
				(type default)
			)
			(layer "F.SilkS")
		)
		(fp_line
			(start -0.67945 -0.305054)
			(end -0.12065 -0.305054)
			(stroke
				(width 0.1)
				(type default)
			)
			(layer "F.Fab")
		)
		(fp_line
			(start -0.67945 0.3048)
			(end -0.67945 -0.305054)
			(stroke
				(width 0.1)
				(type default)
			)
			(layer "F.Fab")
		)
		(fp_line
			(start -0.12065 -0.305054)
			(end -0.12065 -0.2794)
			(stroke
				(width 0.1)
				(type default)
			)
			(layer "F.Fab")
		)
		(fp_line
			(start -0.12065 -0.2794)
			(end 0.12065 -0.2794)
			(stroke
				(width 0.1)
				(type default)
			)
			(layer "F.Fab")
		)
		(fp_line
			(start -0.12065 0.2794)
			(end -0.12065 0.3048)
			(stroke
				(width 0.1)
				(type default)
			)
			(layer "F.Fab")
		)
		(fp_line
			(start -0.12065 0.3048)
			(end -0.67945 0.3048)
			(stroke
				(width 0.1)
				(type default)
			)
			(layer "F.Fab")
		)
		(fp_line
			(start 0.120396 0.2794)
			(end -0.12065 0.2794)
			(stroke
				(width 0.1)
				(type default)
			)
			(layer "F.Fab")
		)
		(fp_line
			(start 0.120396 0.3048)
			(end 0.120396 0.2794)
			(stroke
				(width 0.1)
				(type default)
			)
			(layer "F.Fab")
		)
		(fp_line
			(start 0.12065 -0.3048)
			(end 0.67945 -0.3048)
			(stroke
				(width 0.1)
				(type default)
			)
			(layer "F.Fab")
		)
		(fp_line
			(start 0.12065 -0.2794)
			(end 0.12065 -0.3048)
			(stroke
				(width 0.1)
				(type default)
			)
			(layer "F.Fab")
		)
		(fp_line
			(start 0.67945 -0.3048)
			(end 0.67945 0.3048)
			(stroke
				(width 0.1)
				(type default)
			)
			(layer "F.Fab")
		)
		(fp_line
			(start 0.67945 0.3048)
			(end 0.120396 0.3048)
			(stroke
				(width 0.1)
				(type default)
			)
			(layer "F.Fab")
		)
		(pad "1" smd circle
			(at -0.40005 0)
			(size 0 0)
			(layers "F.Cu" "F.Mask" "F.Paste")
			(net "PEX1_P1V25_ADC_ALERT_N")
		)
		(pad "2" smd circle
			(at 0.40005 0)
			(size 0 0)
			(layers "F.Cu" "F.Mask" "F.Paste")
			(net "PEX_ADC_ALERT_N")
		)
	)
	(footprint ""
		(layer "F.Cu")
		(at 407.696162 -390.990836)
		(property "Reference" "R1853"
			(at 0 0 0)
			(layer "F.SilkS")
			(hide yes)
			(effects
				(font
					(size 1.27 1.27)
				)
			)
		)
		(property "Value" ""
			(at 0 0 0)
			(layer "F.Fab")
			(effects
				(font
					(size 1.27 1.27)
				)
			)
		)
		(duplicate_pad_numbers_are_jumpers no)
		(fp_line
			(start -0.7874 -0.4064)
			(end 0.7874 -0.4064)
			(stroke
				(width 0.1524)
				(type default)
			)
			(layer "F.SilkS")
		)
		(fp_line
			(start -0.7874 0.4064)
			(end -0.7874 -0.4064)
			(stroke
				(width 0.1524)
				(type default)
			)
			(layer "F.SilkS")
		)
		(fp_line
			(start 0.7874 -0.4064)
			(end 0.7874 0.4064)
			(stroke
				(width 0.1524)
				(type default)
			)
			(layer "F.SilkS")
		)
		(fp_line
			(start 0.7874 0.4064)
			(end -0.7874 0.4064)
			(stroke
				(width 0.1524)
				(type default)
			)
			(layer "F.SilkS")
		)
		(fp_line
			(start -0.67945 -0.305054)
			(end -0.12065 -0.305054)
			(stroke
				(width 0.1)
				(type default)
			)
			(layer "F.Fab")
		)
		(fp_line
			(start -0.67945 0.3048)
			(end -0.67945 -0.305054)
			(stroke
				(width 0.1)
				(type default)
			)
			(layer "F.Fab")
		)
		(fp_line
			(start -0.12065 -0.305054)
			(end -0.12065 -0.2794)
			(stroke
				(width 0.1)
				(type default)
			)
			(layer "F.Fab")
		)
		(fp_line
			(start -0.12065 -0.2794)
			(end 0.12065 -0.2794)
			(stroke
				(width 0.1)
				(type default)
			)
			(layer "F.Fab")
		)
		(fp_line
			(start -0.12065 0.2794)
			(end -0.12065 0.3048)
			(stroke
				(width 0.1)
				(type default)
			)
			(layer "F.Fab")
		)
		(fp_line
			(start -0.12065 0.3048)
			(end -0.67945 0.3048)
			(stroke
				(width 0.1)
				(type default)
			)
			(layer "F.Fab")
		)
		(fp_line
			(start 0.120396 0.2794)
			(end -0.12065 0.2794)
			(stroke
				(width 0.1)
				(type default)
			)
			(layer "F.Fab")
		)
		(fp_line
			(start 0.120396 0.3048)
			(end 0.120396 0.2794)
			(stroke
				(width 0.1)
				(type default)
			)
			(layer "F.Fab")
		)
		(fp_line
			(start 0.12065 -0.3048)
			(end 0.67945 -0.3048)
			(stroke
				(width 0.1)
				(type default)
			)
			(layer "F.Fab")
		)
		(fp_line
			(start 0.12065 -0.2794)
			(end 0.12065 -0.3048)
			(stroke
				(width 0.1)
				(type default)
			)
			(layer "F.Fab")
		)
		(fp_line
			(start 0.67945 -0.3048)
			(end 0.67945 0.3048)
			(stroke
				(width 0.1)
				(type default)
			)
			(layer "F.Fab")
		)
		(fp_line
			(start 0.67945 0.3048)
			(end 0.120396 0.3048)
			(stroke
				(width 0.1)
				(type default)
			)
			(layer "F.Fab")
		)
		(pad "1" smd circle
			(at -0.40005 0)
			(size 0 0)
			(layers "F.Cu" "F.Mask" "F.Paste")
			(net "GPU_BB_RSVD_1_R")
		)
		(pad "2" smd circle
			(at 0.40005 0)
			(size 0 0)
			(layers "F.Cu" "F.Mask" "F.Paste")
			(net "GPU_BB_RSVD_1")
		)
	)
	(footprint ""
		(layer "F.Cu")
		(at 203.849732 -300.60265 90)
		(property "Reference" "R6392"
			(at 0 0 90)
			(layer "F.SilkS")
			(hide yes)
			(effects
				(font
					(size 1.27 1.27)
				)
			)
		)
		(property "Value" ""
			(at 0 0 90)
			(layer "F.Fab")
			(effects
				(font
					(size 1.27 1.27)
				)
			)
		)
		(duplicate_pad_numbers_are_jumpers no)
		(fp_line
			(start 0.7874 -0.4064)
			(end 0.7874 0.4064)
			(stroke
				(width 0.1524)
				(type default)
			)
			(layer "F.SilkS")
		)
		(fp_line
			(start -0.7874 -0.4064)
			(end 0.7874 -0.4064)
			(stroke
				(width 0.1524)
				(type default)
			)
			(layer "F.SilkS")
		)
		(fp_line
			(start 0.7874 0.4064)
			(end -0.7874 0.4064)
			(stroke
				(width 0.1524)
				(type default)
			)
			(layer "F.SilkS")
		)
		(fp_line
			(start -0.7874 0.4064)
			(end -0.7874 -0.4064)
			(stroke
				(width 0.1524)
				(type default)
			)
			(layer "F.SilkS")
		)
		(fp_line
			(start -0.12065 -0.305054)
			(end -0.12065 -0.2794)
			(stroke
				(width 0.1)
				(type default)
			)
			(layer "F.Fab")
		)
		(fp_line
			(start -0.67945 -0.305054)
			(end -0.12065 -0.305054)
			(stroke
				(width 0.1)
				(type default)
			)
			(layer "F.Fab")
		)
		(fp_line
			(start 0.67945 -0.3048)
			(end 0.67945 0.3048)
			(stroke
				(width 0.1)
				(type default)
			)
			(layer "F.Fab")
		)
		(fp_line
			(start 0.12065 -0.3048)
			(end 0.67945 -0.3048)
			(stroke
				(width 0.1)
				(type default)
			)
			(layer "F.Fab")
		)
		(fp_line
			(start 0.12065 -0.2794)
			(end 0.12065 -0.3048)
			(stroke
				(width 0.1)
				(type default)
			)
			(layer "F.Fab")
		)
		(fp_line
			(start -0.12065 -0.2794)
			(end 0.12065 -0.2794)
			(stroke
				(width 0.1)
				(type default)
			)
			(layer "F.Fab")
		)
		(fp_line
			(start 0.120396 0.2794)
			(end -0.12065 0.2794)
			(stroke
				(width 0.1)
				(type default)
			)
			(layer "F.Fab")
		)
		(fp_line
			(start -0.12065 0.2794)
			(end -0.12065 0.3048)
			(stroke
				(width 0.1)
				(type default)
			)
			(layer "F.Fab")
		)
		(fp_line
			(start 0.67945 0.3048)
			(end 0.120396 0.3048)
			(stroke
				(width 0.1)
				(type default)
			)
			(layer "F.Fab")
		)
		(fp_line
			(start 0.120396 0.3048)
			(end 0.120396 0.2794)
			(stroke
				(width 0.1)
				(type default)
			)
			(layer "F.Fab")
		)
		(fp_line
			(start -0.12065 0.3048)
			(end -0.67945 0.3048)
			(stroke
				(width 0.1)
				(type default)
			)
			(layer "F.Fab")
		)
		(fp_line
			(start -0.67945 0.3048)
			(end -0.67945 -0.305054)
			(stroke
				(width 0.1)
				(type default)
			)
			(layer "F.Fab")
		)
		(pad "1" smd circle
			(at -0.40005 0 90)
			(size 0 0)
			(layers "F.Cu" "F.Mask" "F.Paste")
			(net "RST_PEX1_S1_PERST_N")
		)
		(pad "2" smd circle
			(at 0.40005 0 90)
			(size 0 0)
			(layers "F.Cu" "F.Mask" "F.Paste")
			(net "RST_PEX1_S1_PERST_R_N")
		)
	)
	(footprint ""
		(layer "F.Cu")
		(at 392.467338 -246.313198 180)
		(property "Reference" "R6614"
			(at 0 0 180)
			(layer "F.SilkS")
			(hide yes)
			(effects
				(font
					(size 1.27 1.27)
				)
			)
		)
		(property "Value" ""
			(at 0 0 180)
			(layer "F.Fab")
			(effects
				(font
					(size 1.27 1.27)
				)
			)
		)
		(duplicate_pad_numbers_are_jumpers no)
		(fp_line
			(start 0.7874 0.4064)
			(end -0.7874 0.4064)
			(stroke
				(width 0.1524)
				(type default)
			)
			(layer "F.SilkS")
		)
		(fp_line
			(start 0.7874 -0.4064)
			(end 0.7874 0.4064)
			(stroke
				(width 0.1524)
				(type default)
			)
			(layer "F.SilkS")
		)
		(fp_line
			(start -0.7874 0.4064)
			(end -0.7874 -0.4064)
			(stroke
				(width 0.1524)
				(type default)
			)
			(layer "F.SilkS")
		)
		(fp_line
			(start -0.7874 -0.4064)
			(end 0.7874 -0.4064)
			(stroke
				(width 0.1524)
				(type default)
			)
			(layer "F.SilkS")
		)
		(fp_line
			(start 0.67945 0.3048)
			(end 0.120396 0.3048)
			(stroke
				(width 0.1)
				(type default)
			)
			(layer "F.Fab")
		)
		(fp_line
			(start 0.67945 -0.3048)
			(end 0.67945 0.3048)
			(stroke
				(width 0.1)
				(type default)
			)
			(layer "F.Fab")
		)
		(fp_line
			(start 0.12065 -0.2794)
			(end 0.12065 -0.3048)
			(stroke
				(width 0.1)
				(type default)
			)
			(layer "F.Fab")
		)
		(fp_line
			(start 0.12065 -0.3048)
			(end 0.67945 -0.3048)
			(stroke
				(width 0.1)
				(type default)
			)
			(layer "F.Fab")
		)
		(fp_line
			(start 0.120396 0.3048)
			(end 0.120396 0.2794)
			(stroke
				(width 0.1)
				(type default)
			)
			(layer "F.Fab")
		)
		(fp_line
			(start 0.120396 0.2794)
			(end -0.12065 0.2794)
			(stroke
				(width 0.1)
				(type default)
			)
			(layer "F.Fab")
		)
		(fp_line
			(start -0.12065 0.3048)
			(end -0.67945 0.3048)
			(stroke
				(width 0.1)
				(type default)
			)
			(layer "F.Fab")
		)
		(fp_line
			(start -0.12065 0.2794)
			(end -0.12065 0.3048)
			(stroke
				(width 0.1)
				(type default)
			)
			(layer "F.Fab")
		)
		(fp_line
			(start -0.12065 -0.2794)
			(end 0.12065 -0.2794)
			(stroke
				(width 0.1)
				(type default)
			)
			(layer "F.Fab")
		)
		(fp_line
			(start -0.12065 -0.305054)
			(end -0.12065 -0.2794)
			(stroke
				(width 0.1)
				(type default)
			)
			(layer "F.Fab")
		)
		(fp_line
			(start -0.67945 0.3048)
			(end -0.67945 -0.305054)
			(stroke
				(width 0.1)
				(type default)
			)
			(layer "F.Fab")
		)
		(fp_line
			(start -0.67945 -0.305054)
			(end -0.12065 -0.305054)
			(stroke
				(width 0.1)
				(type default)
			)
			(layer "F.Fab")
		)
		(pad "1" smd circle
			(at -0.40005 0 180)
			(size 0 0)
			(layers "F.Cu" "F.Mask" "F.Paste")
			(net "UART_PEX1_SDB_BUF_R_TX")
		)
		(pad "2" smd circle
			(at 0.40005 0 180)
			(size 0 0)
			(layers "F.Cu" "F.Mask" "F.Paste")
			(net "UART_PEX1_SDB_BUF_R1_TX")
		)
	)
	(footprint ""
		(layer "F.Cu")
		(at 228.783134 -254.18542 -90)
		(property "Reference" "C4299"
			(at 0 0 270)
			(layer "F.SilkS")
			(hide yes)
			(effects
				(font
					(size 1.27 1.27)
				)
			)
		)
		(property "Value" ""
			(at 0 0 270)
			(layer "F.Fab")
			(effects
				(font
					(size 1.27 1.27)
				)
			)
		)
		(duplicate_pad_numbers_are_jumpers no)
		(fp_line
			(start -1.2954 0.5842)
			(end -1.2954 -0.5842)
			(stroke
				(width 0.1524)
				(type default)
			)
			(layer "F.SilkS")
		)
		(fp_line
			(start 1.2954 0.5842)
			(end -1.2954 0.5842)
			(stroke
				(width 0.1524)
				(type default)
			)
			(layer "F.SilkS")
		)
		(fp_line
			(start -1.2954 -0.5842)
			(end 1.2954 -0.5842)
			(stroke
				(width 0.1524)
				(type default)
			)
			(layer "F.SilkS")
		)
		(fp_line
			(start 1.2954 -0.5842)
			(end 1.2954 0.5842)
			(stroke
				(width 0.1524)
				(type default)
			)
			(layer "F.SilkS")
		)
		(fp_line
			(start -0.8636 0.4572)
			(end -0.8636 0.4064)
			(stroke
				(width 0.1)
				(type default)
			)
			(layer "F.Fab")
		)
		(fp_line
			(start 0.8636 0.4572)
			(end -0.8636 0.4572)
			(stroke
				(width 0.1)
				(type default)
			)
			(layer "F.Fab")
		)
		(fp_line
			(start -1.1938 0.4064)
			(end -1.1938 -0.4064)
			(stroke
				(width 0.1)
				(type default)
			)
			(layer "F.Fab")
		)
		(fp_line
			(start -0.8636 0.4064)
			(end -1.1938 0.4064)
			(stroke
				(width 0.1)
				(type default)
			)
			(layer "F.Fab")
		)
		(fp_line
			(start 0.8636 0.4064)
			(end 0.8636 0.4572)
			(stroke
				(width 0.1)
				(type default)
			)
			(layer "F.Fab")
		)
		(fp_line
			(start 1.1938 0.4064)
			(end 0.8636 0.4064)
			(stroke
				(width 0.1)
				(type default)
			)
			(layer "F.Fab")
		)
		(fp_line
			(start -1.1938 -0.4064)
			(end -0.8636 -0.4064)
			(stroke
				(width 0.1)
				(type default)
			)
			(layer "F.Fab")
		)
		(fp_line
			(start -0.8636 -0.4064)
			(end -0.8636 -0.4572)
			(stroke
				(width 0.1)
				(type default)
			)
			(layer "F.Fab")
		)
		(fp_line
			(start 0.8636 -0.4064)
			(end 1.1938 -0.4064)
			(stroke
				(width 0.1)
				(type default)
			)
			(layer "F.Fab")
		)
		(fp_line
			(start 1.1938 -0.4064)
			(end 1.1938 0.4064)
			(stroke
				(width 0.1)
				(type default)
			)
			(layer "F.Fab")
		)
		(fp_line
			(start -0.8636 -0.4572)
			(end 0.8636 -0.4572)
			(stroke
				(width 0.1)
				(type default)
			)
			(layer "F.Fab")
		)
		(fp_line
			(start 0.8636 -0.4572)
			(end 0.8636 -0.4064)
			(stroke
				(width 0.1)
				(type default)
			)
			(layer "F.Fab")
		)
		(pad "1" smd rect
			(at -0.7366 0 180)
			(size 0.7112 0.8128)
			(layers "F.Cu" "F.Mask" "F.Paste")
			(net "P1V25_SERDES_VDDPLL_PEX1_C9")
		)
		(pad "2" smd rect
			(at 0.7366 0 180)
			(size 0.7112 0.8128)
			(layers "F.Cu" "F.Mask" "F.Paste")
			(net "GND")
		)
	)
	(footprint ""
		(layer "F.Cu")
		(at 211.892388 -28.225242 180)
		(property "Reference" "C307"
			(at 0 0 180)
			(layer "F.SilkS")
			(hide yes)
			(effects
				(font
					(size 1.27 1.27)
				)
			)
		)
		(property "Value" ""
			(at 0 0 180)
			(layer "F.Fab")
			(effects
				(font
					(size 1.27 1.27)
				)
			)
		)
		(duplicate_pad_numbers_are_jumpers no)
		(fp_line
			(start 0.299974 0.150114)
			(end -0.299974 0.150114)
			(stroke
				(width 0.1)
				(type default)
			)
			(layer "F.Fab")
		)
		(fp_line
			(start 0.299974 -0.150114)
			(end 0.299974 0.150114)
			(stroke
				(width 0.1)
				(type default)
			)
			(layer "F.Fab")
		)
		(fp_line
			(start -0.299974 0.150114)
			(end -0.299974 -0.150114)
			(stroke
				(width 0.1)
				(type default)
			)
			(layer "F.Fab")
		)
		(fp_line
			(start -0.299974 -0.150114)
			(end 0.299974 -0.150114)
			(stroke
				(width 0.1)
				(type default)
			)
			(layer "F.Fab")
		)
		(pad "1" smd rect
			(at -0.2667 0 180)
			(size 0.3048 0.381)
			(layers "F.Cu" "F.Mask" "F.Paste")
			(net "P5E_PEX1_STN2_TX_DN<32>")
		)
		(pad "2" smd rect
			(at 0.2667 0 180)
			(size 0.3048 0.381)
			(layers "F.Cu" "F.Mask" "F.Paste")
			(net "P5E_PEX1_STN2_TX_C_DN<32>")
		)
	)
	(footprint ""
		(layer "F.Cu")
		(at 217.235786 -218.302586 180)
		(property "Reference" "R1500"
			(at 0 0 180)
			(layer "F.SilkS")
			(hide yes)
			(effects
				(font
					(size 1.27 1.27)
				)
			)
		)
		(property "Value" ""
			(at 0 0 180)
			(layer "F.Fab")
			(effects
				(font
					(size 1.27 1.27)
				)
			)
		)
		(duplicate_pad_numbers_are_jumpers no)
		(fp_line
			(start 0.7874 0.4064)
			(end -0.7874 0.4064)
			(stroke
				(width 0.1524)
				(type default)
			)
			(layer "F.SilkS")
		)
		(fp_line
			(start 0.7874 -0.4064)
			(end 0.7874 0.4064)
			(stroke
				(width 0.1524)
				(type default)
			)
			(layer "F.SilkS")
		)
		(fp_line
			(start -0.7874 0.4064)
			(end -0.7874 -0.4064)
			(stroke
				(width 0.1524)
				(type default)
			)
			(layer "F.SilkS")
		)
		(fp_line
			(start -0.7874 -0.4064)
			(end 0.7874 -0.4064)
			(stroke
				(width 0.1524)
				(type default)
			)
			(layer "F.SilkS")
		)
		(fp_line
			(start 0.67945 0.3048)
			(end 0.120396 0.3048)
			(stroke
				(width 0.1)
				(type default)
			)
			(layer "F.Fab")
		)
		(fp_line
			(start 0.67945 -0.3048)
			(end 0.67945 0.3048)
			(stroke
				(width 0.1)
				(type default)
			)
			(layer "F.Fab")
		)
		(fp_line
			(start 0.12065 -0.2794)
			(end 0.12065 -0.3048)
			(stroke
				(width 0.1)
				(type default)
			)
			(layer "F.Fab")
		)
		(fp_line
			(start 0.12065 -0.3048)
			(end 0.67945 -0.3048)
			(stroke
				(width 0.1)
				(type default)
			)
			(layer "F.Fab")
		)
		(fp_line
			(start 0.120396 0.3048)
			(end 0.120396 0.2794)
			(stroke
				(width 0.1)
				(type default)
			)
			(layer "F.Fab")
		)
		(fp_line
			(start 0.120396 0.2794)
			(end -0.12065 0.2794)
			(stroke
				(width 0.1)
				(type default)
			)
			(layer "F.Fab")
		)
		(fp_line
			(start -0.12065 0.3048)
			(end -0.67945 0.3048)
			(stroke
				(width 0.1)
				(type default)
			)
			(layer "F.Fab")
		)
		(fp_line
			(start -0.12065 0.2794)
			(end -0.12065 0.3048)
			(stroke
				(width 0.1)
				(type default)
			)
			(layer "F.Fab")
		)
		(fp_line
			(start -0.12065 -0.2794)
			(end 0.12065 -0.2794)
			(stroke
				(width 0.1)
				(type default)
			)
			(layer "F.Fab")
		)
		(fp_line
			(start -0.12065 -0.305054)
			(end -0.12065 -0.2794)
			(stroke
				(width 0.1)
				(type default)
			)
			(layer "F.Fab")
		)
		(fp_line
			(start -0.67945 0.3048)
			(end -0.67945 -0.305054)
			(stroke
				(width 0.1)
				(type default)
			)
			(layer "F.Fab")
		)
		(fp_line
			(start -0.67945 -0.305054)
			(end -0.12065 -0.305054)
			(stroke
				(width 0.1)
				(type default)
			)
			(layer "F.Fab")
		)
		(pad "1" smd circle
			(at -0.40005 0 180)
			(size 0 0)
			(layers "F.Cu" "F.Mask" "F.Paste")
			(net "SMB_NIC5_SCL")
		)
		(pad "2" smd circle
			(at 0.40005 0 180)
			(size 0 0)
			(layers "F.Cu" "F.Mask" "F.Paste")
			(net "SMB_NIC5_R_SCL")
		)
	)
	(footprint ""
		(layer "F.Cu")
		(at 363.501432 -55.78475 -90)
		(property "Reference" "PD39"
			(at 4.07035 2.159762 90)
			(unlocked yes)
			(layer "F.SilkS")
			(effects
				(font
					(size 0.7874 0.5842)
					(thickness 0.1524)
				)
				(justify left)
			)
		)
		(property "Value" ""
			(at 0 0 270)
			(layer "F.Fab")
			(effects
				(font
					(size 1.27 1.27)
				)
			)
		)
		(duplicate_pad_numbers_are_jumpers no)
		(fp_line
			(start -3.400044 1.459992)
			(end -3.400044 -1.459992)
			(stroke
				(width 0.1524)
				(type default)
			)
			(layer "F.SilkS")
		)
		(fp_line
			(start 4.107942 1.459992)
			(end -3.400044 1.459992)
			(stroke
				(width 0.1524)
				(type default)
			)
			(layer "F.SilkS")
		)
		(fp_line
			(start -3.400044 -1.459992)
			(end 4.107942 -1.459992)
			(stroke
				(width 0.1524)
				(type default)
			)
			(layer "F.SilkS")
		)
		(fp_line
			(start 4.107942 -1.459992)
			(end 4.107942 1.459992)
			(stroke
				(width 0.1524)
				(type default)
			)
			(layer "F.SilkS")
		)
		(fp_poly
			(pts
				(xy 4.107942 -1.459992) (xy 4.107942 1.459992) (xy 3.308096 1.459992) (xy 3.308096 -1.459992)
			)
			(stroke
				(width 0)
				(type default)
			)
			(fill yes)
			(layer "F.SilkS")
		)
		(fp_line
			(start -2.29997 1.459992)
			(end -2.29997 -1.459992)
			(stroke
				(width 0.1)
				(type default)
			)
			(layer "F.Fab")
		)
		(fp_line
			(start 2.29997 1.459992)
			(end -2.29997 1.459992)
			(stroke
				(width 0.1)
				(type default)
			)
			(layer "F.Fab")
		)
		(fp_line
			(start -2.29997 -1.459992)
			(end 2.29997 -1.459992)
			(stroke
				(width 0.1)
				(type default)
			)
			(layer "F.Fab")
		)
		(fp_line
			(start 2.29997 -1.459992)
			(end 2.29997 1.459992)
			(stroke
				(width 0.1)
				(type default)
			)
			(layer "F.Fab")
		)
		(fp_text user "-"
			(at 5.4102 0.29845 90)
			(unlocked yes)
			(layer "F.SilkS")
			(effects
				(font
					(size 1.905 1.4224)
					(thickness 0.1524)
				)
				(justify left)
			)
		)
		(fp_text user "+"
			(at -4.7752 -0.12065 270)
			(unlocked yes)
			(layer "F.SilkS")
			(effects
				(font
					(size 1.905 1.4224)
					(thickness 0.1524)
				)
				(justify left)
			)
		)
		(fp_text user "-"
			(at 5.4102 0.29845 90)
			(unlocked yes)
			(layer "F.Fab")
			(effects
				(font
					(size 1.905 1.4224)
					(thickness 0.1524)
				)
				(justify left)
			)
		)
		(fp_text user "+"
			(at -4.7752 -0.12065 270)
			(unlocked yes)
			(layer "F.Fab")
			(effects
				(font
					(size 1.905 1.4224)
					(thickness 0.1524)
				)
				(justify left)
			)
		)
		(pad "A" smd rect
			(at -1.999996 0)
			(size 1.7018 2.5146)
			(layers "F.Cu" "F.Mask" "F.Paste")
			(net "GND")
		)
		(pad "C" smd rect
			(at 1.999996 0)
			(size 1.7018 2.5146)
			(layers "F.Cu" "F.Mask" "F.Paste")
			(net "P12V_SSD12_R")
		)
	)
	(footprint ""
		(layer "F.Cu")
		(at 353.594162 -34.248852)
		(property "Reference" "R5699"
			(at 0 0 0)
			(layer "F.SilkS")
			(hide yes)
			(effects
				(font
					(size 1.27 1.27)
				)
			)
		)
		(property "Value" ""
			(at 0 0 0)
			(layer "F.Fab")
			(effects
				(font
					(size 1.27 1.27)
				)
			)
		)
		(duplicate_pad_numbers_are_jumpers no)
		(fp_line
			(start -0.7874 -0.4064)
			(end 0.7874 -0.4064)
			(stroke
				(width 0.1524)
				(type default)
			)
			(layer "F.SilkS")
		)
		(fp_line
			(start -0.7874 0.4064)
			(end -0.7874 -0.4064)
			(stroke
				(width 0.1524)
				(type default)
			)
			(layer "F.SilkS")
		)
		(fp_line
			(start 0.7874 -0.4064)
			(end 0.7874 0.4064)
			(stroke
				(width 0.1524)
				(type default)
			)
			(layer "F.SilkS")
		)
		(fp_line
			(start 0.7874 0.4064)
			(end -0.7874 0.4064)
			(stroke
				(width 0.1524)
				(type default)
			)
			(layer "F.SilkS")
		)
		(fp_line
			(start -0.67945 -0.305054)
			(end -0.12065 -0.305054)
			(stroke
				(width 0.1)
				(type default)
			)
			(layer "F.Fab")
		)
		(fp_line
			(start -0.67945 0.3048)
			(end -0.67945 -0.305054)
			(stroke
				(width 0.1)
				(type default)
			)
			(layer "F.Fab")
		)
		(fp_line
			(start -0.12065 -0.305054)
			(end -0.12065 -0.2794)
			(stroke
				(width 0.1)
				(type default)
			)
			(layer "F.Fab")
		)
		(fp_line
			(start -0.12065 -0.2794)
			(end 0.12065 -0.2794)
			(stroke
				(width 0.1)
				(type default)
			)
			(layer "F.Fab")
		)
		(fp_line
			(start -0.12065 0.2794)
			(end -0.12065 0.3048)
			(stroke
				(width 0.1)
				(type default)
			)
			(layer "F.Fab")
		)
		(fp_line
			(start -0.12065 0.3048)
			(end -0.67945 0.3048)
			(stroke
				(width 0.1)
				(type default)
			)
			(layer "F.Fab")
		)
		(fp_line
			(start 0.120396 0.2794)
			(end -0.12065 0.2794)
			(stroke
				(width 0.1)
				(type default)
			)
			(layer "F.Fab")
		)
		(fp_line
			(start 0.120396 0.3048)
			(end 0.120396 0.2794)
			(stroke
				(width 0.1)
				(type default)
			)
			(layer "F.Fab")
		)
		(fp_line
			(start 0.12065 -0.3048)
			(end 0.67945 -0.3048)
			(stroke
				(width 0.1)
				(type default)
			)
			(layer "F.Fab")
		)
		(fp_line
			(start 0.12065 -0.2794)
			(end 0.12065 -0.3048)
			(stroke
				(width 0.1)
				(type default)
			)
			(layer "F.Fab")
		)
		(fp_line
			(start 0.67945 -0.3048)
			(end 0.67945 0.3048)
			(stroke
				(width 0.1)
				(type default)
			)
			(layer "F.Fab")
		)
		(fp_line
			(start 0.67945 0.3048)
			(end 0.120396 0.3048)
			(stroke
				(width 0.1)
				(type default)
			)
			(layer "F.Fab")
		)
		(pad "1" smd circle
			(at -0.40005 0)
			(size 0 0)
			(layers "F.Cu" "F.Mask" "F.Paste")
			(net "RST_SMB_SSD12_ISO_N")
		)
		(pad "2" smd circle
			(at 0.40005 0)
			(size 0 0)
			(layers "F.Cu" "F.Mask" "F.Paste")
			(net "P3V3_SSD12")
		)
	)
	(footprint ""
		(layer "F.Cu")
		(at 330.63434 -30.03169 180)
		(property "Reference" "C516"
			(at 0 0 180)
			(layer "F.SilkS")
			(hide yes)
			(effects
				(font
					(size 1.27 1.27)
				)
			)
		)
		(property "Value" ""
			(at 0 0 180)
			(layer "F.Fab")
			(effects
				(font
					(size 1.27 1.27)
				)
			)
		)
		(duplicate_pad_numbers_are_jumpers no)
		(fp_line
			(start 0.299974 0.150114)
			(end -0.299974 0.150114)
			(stroke
				(width 0.1)
				(type default)
			)
			(layer "F.Fab")
		)
		(fp_line
			(start 0.299974 -0.150114)
			(end 0.299974 0.150114)
			(stroke
				(width 0.1)
				(type default)
			)
			(layer "F.Fab")
		)
		(fp_line
			(start -0.299974 0.150114)
			(end -0.299974 -0.150114)
			(stroke
				(width 0.1)
				(type default)
			)
			(layer "F.Fab")
		)
		(fp_line
			(start -0.299974 -0.150114)
			(end 0.299974 -0.150114)
			(stroke
				(width 0.1)
				(type default)
			)
			(layer "F.Fab")
		)
		(pad "1" smd rect
			(at -0.2667 0 180)
			(size 0.3048 0.381)
			(layers "F.Cu" "F.Mask" "F.Paste")
			(net "P5E_PEX2_STN2_TX_DN<33>")
		)
		(pad "2" smd rect
			(at 0.2667 0 180)
			(size 0.3048 0.381)
			(layers "F.Cu" "F.Mask" "F.Paste")
			(net "P5E_PEX2_STN2_TX_C_DN<33>")
		)
	)
	(footprint ""
		(layer "F.Cu")
		(at 310.443626 -43.85691)
		(property "Reference" "R619"
			(at 0 0 0)
			(layer "F.SilkS")
			(hide yes)
			(effects
				(font
					(size 1.27 1.27)
				)
			)
		)
		(property "Value" ""
			(at 0 0 0)
			(layer "F.Fab")
			(effects
				(font
					(size 1.27 1.27)
				)
			)
		)
		(duplicate_pad_numbers_are_jumpers no)
		(fp_line
			(start -0.7874 -0.4064)
			(end 0.7874 -0.4064)
			(stroke
				(width 0.1524)
				(type default)
			)
			(layer "F.SilkS")
		)
		(fp_line
			(start -0.7874 0.4064)
			(end -0.7874 -0.4064)
			(stroke
				(width 0.1524)
				(type default)
			)
			(layer "F.SilkS")
		)
		(fp_line
			(start 0.7874 -0.4064)
			(end 0.7874 0.4064)
			(stroke
				(width 0.1524)
				(type default)
			)
			(layer "F.SilkS")
		)
		(fp_line
			(start 0.7874 0.4064)
			(end -0.7874 0.4064)
			(stroke
				(width 0.1524)
				(type default)
			)
			(layer "F.SilkS")
		)
		(fp_line
			(start -0.67945 -0.305054)
			(end -0.12065 -0.305054)
			(stroke
				(width 0.1)
				(type default)
			)
			(layer "F.Fab")
		)
		(fp_line
			(start -0.67945 0.3048)
			(end -0.67945 -0.305054)
			(stroke
				(width 0.1)
				(type default)
			)
			(layer "F.Fab")
		)
		(fp_line
			(start -0.12065 -0.305054)
			(end -0.12065 -0.2794)
			(stroke
				(width 0.1)
				(type default)
			)
			(layer "F.Fab")
		)
		(fp_line
			(start -0.12065 -0.2794)
			(end 0.12065 -0.2794)
			(stroke
				(width 0.1)
				(type default)
			)
			(layer "F.Fab")
		)
		(fp_line
			(start -0.12065 0.2794)
			(end -0.12065 0.3048)
			(stroke
				(width 0.1)
				(type default)
			)
			(layer "F.Fab")
		)
		(fp_line
			(start -0.12065 0.3048)
			(end -0.67945 0.3048)
			(stroke
				(width 0.1)
				(type default)
			)
			(layer "F.Fab")
		)
		(fp_line
			(start 0.120396 0.2794)
			(end -0.12065 0.2794)
			(stroke
				(width 0.1)
				(type default)
			)
			(layer "F.Fab")
		)
		(fp_line
			(start 0.120396 0.3048)
			(end 0.120396 0.2794)
			(stroke
				(width 0.1)
				(type default)
			)
			(layer "F.Fab")
		)
		(fp_line
			(start 0.12065 -0.3048)
			(end 0.67945 -0.3048)
			(stroke
				(width 0.1)
				(type default)
			)
			(layer "F.Fab")
		)
		(fp_line
			(start 0.12065 -0.2794)
			(end 0.12065 -0.3048)
			(stroke
				(width 0.1)
				(type default)
			)
			(layer "F.Fab")
		)
		(fp_line
			(start 0.67945 -0.3048)
			(end 0.67945 0.3048)
			(stroke
				(width 0.1)
				(type default)
			)
			(layer "F.Fab")
		)
		(fp_line
			(start 0.67945 0.3048)
			(end 0.120396 0.3048)
			(stroke
				(width 0.1)
				(type default)
			)
			(layer "F.Fab")
		)
		(pad "1" smd circle
			(at -0.40005 0)
			(size 0 0)
			(layers "F.Cu" "F.Mask" "F.Paste")
			(net "SSD10_ADC_A1")
		)
		(pad "2" smd circle
			(at 0.40005 0)
			(size 0 0)
			(layers "F.Cu" "F.Mask" "F.Paste")
			(net "GND")
		)
	)
	(footprint ""
		(layer "F.Cu")
		(at 350.380554 -86.073234)
		(property "Reference" "R1594"
			(at 0 0 0)
			(layer "F.SilkS")
			(hide yes)
			(effects
				(font
					(size 1.27 1.27)
				)
			)
		)
		(property "Value" ""
			(at 0 0 0)
			(layer "F.Fab")
			(effects
				(font
					(size 1.27 1.27)
				)
			)
		)
		(duplicate_pad_numbers_are_jumpers no)
		(fp_line
			(start -0.7874 -0.4064)
			(end 0.7874 -0.4064)
			(stroke
				(width 0.1524)
				(type default)
			)
			(layer "F.SilkS")
		)
		(fp_line
			(start -0.7874 0.4064)
			(end -0.7874 -0.4064)
			(stroke
				(width 0.1524)
				(type default)
			)
			(layer "F.SilkS")
		)
		(fp_line
			(start 0.7874 -0.4064)
			(end 0.7874 0.4064)
			(stroke
				(width 0.1524)
				(type default)
			)
			(layer "F.SilkS")
		)
		(fp_line
			(start 0.7874 0.4064)
			(end -0.7874 0.4064)
			(stroke
				(width 0.1524)
				(type default)
			)
			(layer "F.SilkS")
		)
		(fp_line
			(start -0.67945 -0.305054)
			(end -0.12065 -0.305054)
			(stroke
				(width 0.1)
				(type default)
			)
			(layer "F.Fab")
		)
		(fp_line
			(start -0.67945 0.3048)
			(end -0.67945 -0.305054)
			(stroke
				(width 0.1)
				(type default)
			)
			(layer "F.Fab")
		)
		(fp_line
			(start -0.12065 -0.305054)
			(end -0.12065 -0.2794)
			(stroke
				(width 0.1)
				(type default)
			)
			(layer "F.Fab")
		)
		(fp_line
			(start -0.12065 -0.2794)
			(end 0.12065 -0.2794)
			(stroke
				(width 0.1)
				(type default)
			)
			(layer "F.Fab")
		)
		(fp_line
			(start -0.12065 0.2794)
			(end -0.12065 0.3048)
			(stroke
				(width 0.1)
				(type default)
			)
			(layer "F.Fab")
		)
		(fp_line
			(start -0.12065 0.3048)
			(end -0.67945 0.3048)
			(stroke
				(width 0.1)
				(type default)
			)
			(layer "F.Fab")
		)
		(fp_line
			(start 0.120396 0.2794)
			(end -0.12065 0.2794)
			(stroke
				(width 0.1)
				(type default)
			)
			(layer "F.Fab")
		)
		(fp_line
			(start 0.120396 0.3048)
			(end 0.120396 0.2794)
			(stroke
				(width 0.1)
				(type default)
			)
			(layer "F.Fab")
		)
		(fp_line
			(start 0.12065 -0.3048)
			(end 0.67945 -0.3048)
			(stroke
				(width 0.1)
				(type default)
			)
			(layer "F.Fab")
		)
		(fp_line
			(start 0.12065 -0.2794)
			(end 0.12065 -0.3048)
			(stroke
				(width 0.1)
				(type default)
			)
			(layer "F.Fab")
		)
		(fp_line
			(start 0.67945 -0.3048)
			(end 0.67945 0.3048)
			(stroke
				(width 0.1)
				(type default)
			)
			(layer "F.Fab")
		)
		(fp_line
			(start 0.67945 0.3048)
			(end 0.120396 0.3048)
			(stroke
				(width 0.1)
				(type default)
			)
			(layer "F.Fab")
		)
		(pad "1" smd circle
			(at -0.40005 0)
			(size 0 0)
			(layers "F.Cu" "F.Mask" "F.Paste")
			(net "P3V3_AUX")
		)
		(pad "2" smd circle
			(at 0.40005 0)
			(size 0 0)
			(layers "F.Cu" "F.Mask" "F.Paste")
			(net "SMB_BIC_I2C9_MUX1_SSD9_R_SCL")
		)
	)
	(footprint ""
		(layer "F.Cu")
		(at 7.613396 -140.392404 180)
		(property "Reference" "PC314"
			(at 0 0 180)
			(layer "F.SilkS")
			(hide yes)
			(effects
				(font
					(size 1.27 1.27)
				)
			)
		)
		(property "Value" ""
			(at 0 0 180)
			(layer "F.Fab")
			(effects
				(font
					(size 1.27 1.27)
				)
			)
		)
		(duplicate_pad_numbers_are_jumpers no)
		(fp_line
			(start 0.7874 0.4064)
			(end -0.7874 0.4064)
			(stroke
				(width 0.1524)
				(type default)
			)
			(layer "F.SilkS")
		)
		(fp_line
			(start 0.7874 -0.4064)
			(end 0.7874 0.4064)
			(stroke
				(width 0.1524)
				(type default)
			)
			(layer "F.SilkS")
		)
		(fp_line
			(start -0.7874 0.4064)
			(end -0.7874 -0.4064)
			(stroke
				(width 0.1524)
				(type default)
			)
			(layer "F.SilkS")
		)
		(fp_line
			(start -0.7874 -0.4064)
			(end 0.7874 -0.4064)
			(stroke
				(width 0.1524)
				(type default)
			)
			(layer "F.SilkS")
		)
		(fp_line
			(start 0.67945 0.3048)
			(end 0.120396 0.3048)
			(stroke
				(width 0.1)
				(type default)
			)
			(layer "F.Fab")
		)
		(fp_line
			(start 0.67945 -0.3048)
			(end 0.67945 0.3048)
			(stroke
				(width 0.1)
				(type default)
			)
			(layer "F.Fab")
		)
		(fp_line
			(start 0.12065 -0.2794)
			(end 0.12065 -0.3048)
			(stroke
				(width 0.1)
				(type default)
			)
			(layer "F.Fab")
		)
		(fp_line
			(start 0.12065 -0.3048)
			(end 0.67945 -0.3048)
			(stroke
				(width 0.1)
				(type default)
			)
			(layer "F.Fab")
		)
		(fp_line
			(start 0.120396 0.3048)
			(end 0.120396 0.2794)
			(stroke
				(width 0.1)
				(type default)
			)
			(layer "F.Fab")
		)
		(fp_line
			(start 0.120396 0.2794)
			(end -0.12065 0.2794)
			(stroke
				(width 0.1)
				(type default)
			)
			(layer "F.Fab")
		)
		(fp_line
			(start -0.12065 0.3048)
			(end -0.67945 0.3048)
			(stroke
				(width 0.1)
				(type default)
			)
			(layer "F.Fab")
		)
		(fp_line
			(start -0.12065 0.2794)
			(end -0.12065 0.3048)
			(stroke
				(width 0.1)
				(type default)
			)
			(layer "F.Fab")
		)
		(fp_line
			(start -0.12065 -0.2794)
			(end 0.12065 -0.2794)
			(stroke
				(width 0.1)
				(type default)
			)
			(layer "F.Fab")
		)
		(fp_line
			(start -0.12065 -0.305054)
			(end -0.12065 -0.2794)
			(stroke
				(width 0.1)
				(type default)
			)
			(layer "F.Fab")
		)
		(fp_line
			(start -0.67945 0.3048)
			(end -0.67945 -0.305054)
			(stroke
				(width 0.1)
				(type default)
			)
			(layer "F.Fab")
		)
		(fp_line
			(start -0.67945 -0.305054)
			(end -0.12065 -0.305054)
			(stroke
				(width 0.1)
				(type default)
			)
			(layer "F.Fab")
		)
		(pad "1" smd circle
			(at -0.40005 0 180)
			(size 0 0)
			(layers "F.Cu" "F.Mask" "F.Paste")
			(net "P12V_NIC0_SS")
		)
		(pad "2" smd circle
			(at 0.40005 0 180)
			(size 0 0)
			(layers "F.Cu" "F.Mask" "F.Paste")
			(net "GND")
		)
	)
	(footprint ""
		(layer "F.Cu")
		(at 125.295152 -59.577986 90)
		(property "Reference" "PC507"
			(at 0 0 90)
			(layer "F.SilkS")
			(hide yes)
			(effects
				(font
					(size 1.27 1.27)
				)
			)
		)
		(property "Value" ""
			(at 0 0 90)
			(layer "F.Fab")
			(effects
				(font
					(size 1.27 1.27)
				)
			)
		)
		(duplicate_pad_numbers_are_jumpers no)
		(fp_line
			(start 0.7874 -0.4064)
			(end 0.7874 0.4064)
			(stroke
				(width 0.1524)
				(type default)
			)
			(layer "F.SilkS")
		)
		(fp_line
			(start -0.7874 -0.4064)
			(end 0.7874 -0.4064)
			(stroke
				(width 0.1524)
				(type default)
			)
			(layer "F.SilkS")
		)
		(fp_line
			(start 0.7874 0.4064)
			(end -0.7874 0.4064)
			(stroke
				(width 0.1524)
				(type default)
			)
			(layer "F.SilkS")
		)
		(fp_line
			(start -0.7874 0.4064)
			(end -0.7874 -0.4064)
			(stroke
				(width 0.1524)
				(type default)
			)
			(layer "F.SilkS")
		)
		(fp_line
			(start -0.12065 -0.305054)
			(end -0.12065 -0.2794)
			(stroke
				(width 0.1)
				(type default)
			)
			(layer "F.Fab")
		)
		(fp_line
			(start -0.67945 -0.305054)
			(end -0.12065 -0.305054)
			(stroke
				(width 0.1)
				(type default)
			)
			(layer "F.Fab")
		)
		(fp_line
			(start 0.67945 -0.3048)
			(end 0.67945 0.3048)
			(stroke
				(width 0.1)
				(type default)
			)
			(layer "F.Fab")
		)
		(fp_line
			(start 0.12065 -0.3048)
			(end 0.67945 -0.3048)
			(stroke
				(width 0.1)
				(type default)
			)
			(layer "F.Fab")
		)
		(fp_line
			(start 0.12065 -0.2794)
			(end 0.12065 -0.3048)
			(stroke
				(width 0.1)
				(type default)
			)
			(layer "F.Fab")
		)
		(fp_line
			(start -0.12065 -0.2794)
			(end 0.12065 -0.2794)
			(stroke
				(width 0.1)
				(type default)
			)
			(layer "F.Fab")
		)
		(fp_line
			(start 0.120396 0.2794)
			(end -0.12065 0.2794)
			(stroke
				(width 0.1)
				(type default)
			)
			(layer "F.Fab")
		)
		(fp_line
			(start -0.12065 0.2794)
			(end -0.12065 0.3048)
			(stroke
				(width 0.1)
				(type default)
			)
			(layer "F.Fab")
		)
		(fp_line
			(start 0.67945 0.3048)
			(end 0.120396 0.3048)
			(stroke
				(width 0.1)
				(type default)
			)
			(layer "F.Fab")
		)
		(fp_line
			(start 0.120396 0.3048)
			(end 0.120396 0.2794)
			(stroke
				(width 0.1)
				(type default)
			)
			(layer "F.Fab")
		)
		(fp_line
			(start -0.12065 0.3048)
			(end -0.67945 0.3048)
			(stroke
				(width 0.1)
				(type default)
			)
			(layer "F.Fab")
		)
		(fp_line
			(start -0.67945 0.3048)
			(end -0.67945 -0.305054)
			(stroke
				(width 0.1)
				(type default)
			)
			(layer "F.Fab")
		)
		(pad "1" smd circle
			(at -0.40005 0 90)
			(size 0 0)
			(layers "F.Cu" "F.Mask" "F.Paste")
			(net "P3V3_SSD4_SS")
		)
		(pad "2" smd circle
			(at 0.40005 0 90)
			(size 0 0)
			(layers "F.Cu" "F.Mask" "F.Paste")
			(net "GND")
		)
	)
	(footprint ""
		(layer "F.Cu")
		(at 108.412788 -308.56809 -90)
		(property "Reference" "C4199"
			(at 0 0 270)
			(layer "F.SilkS")
			(hide yes)
			(effects
				(font
					(size 1.27 1.27)
				)
			)
		)
		(property "Value" ""
			(at 0 0 270)
			(layer "F.Fab")
			(effects
				(font
					(size 1.27 1.27)
				)
			)
		)
		(duplicate_pad_numbers_are_jumpers no)
		(fp_line
			(start -1.2954 0.5842)
			(end -1.2954 -0.5842)
			(stroke
				(width 0.1524)
				(type default)
			)
			(layer "F.SilkS")
		)
		(fp_line
			(start 1.2954 0.5842)
			(end -1.2954 0.5842)
			(stroke
				(width 0.1524)
				(type default)
			)
			(layer "F.SilkS")
		)
		(fp_line
			(start -1.2954 -0.5842)
			(end 1.2954 -0.5842)
			(stroke
				(width 0.1524)
				(type default)
			)
			(layer "F.SilkS")
		)
		(fp_line
			(start 1.2954 -0.5842)
			(end 1.2954 0.5842)
			(stroke
				(width 0.1524)
				(type default)
			)
			(layer "F.SilkS")
		)
		(fp_line
			(start -0.8636 0.4572)
			(end -0.8636 0.4064)
			(stroke
				(width 0.1)
				(type default)
			)
			(layer "F.Fab")
		)
		(fp_line
			(start 0.8636 0.4572)
			(end -0.8636 0.4572)
			(stroke
				(width 0.1)
				(type default)
			)
			(layer "F.Fab")
		)
		(fp_line
			(start -1.1938 0.4064)
			(end -1.1938 -0.4064)
			(stroke
				(width 0.1)
				(type default)
			)
			(layer "F.Fab")
		)
		(fp_line
			(start -0.8636 0.4064)
			(end -1.1938 0.4064)
			(stroke
				(width 0.1)
				(type default)
			)
			(layer "F.Fab")
		)
		(fp_line
			(start 0.8636 0.4064)
			(end 0.8636 0.4572)
			(stroke
				(width 0.1)
				(type default)
			)
			(layer "F.Fab")
		)
		(fp_line
			(start 1.1938 0.4064)
			(end 0.8636 0.4064)
			(stroke
				(width 0.1)
				(type default)
			)
			(layer "F.Fab")
		)
		(fp_line
			(start -1.1938 -0.4064)
			(end -0.8636 -0.4064)
			(stroke
				(width 0.1)
				(type default)
			)
			(layer "F.Fab")
		)
		(fp_line
			(start -0.8636 -0.4064)
			(end -0.8636 -0.4572)
			(stroke
				(width 0.1)
				(type default)
			)
			(layer "F.Fab")
		)
		(fp_line
			(start 0.8636 -0.4064)
			(end 1.1938 -0.4064)
			(stroke
				(width 0.1)
				(type default)
			)
			(layer "F.Fab")
		)
		(fp_line
			(start 1.1938 -0.4064)
			(end 1.1938 0.4064)
			(stroke
				(width 0.1)
				(type default)
			)
			(layer "F.Fab")
		)
		(fp_line
			(start -0.8636 -0.4572)
			(end 0.8636 -0.4572)
			(stroke
				(width 0.1)
				(type default)
			)
			(layer "F.Fab")
		)
		(fp_line
			(start 0.8636 -0.4572)
			(end 0.8636 -0.4064)
			(stroke
				(width 0.1)
				(type default)
			)
			(layer "F.Fab")
		)
		(pad "1" smd rect
			(at -0.7366 0 180)
			(size 0.7112 0.8128)
			(layers "F.Cu" "F.Mask" "F.Paste")
			(net "P0V8_PEX0")
		)
		(pad "2" smd rect
			(at 0.7366 0 180)
			(size 0.7112 0.8128)
			(layers "F.Cu" "F.Mask" "F.Paste")
			(net "GND")
		)
	)
	(footprint ""
		(layer "F.Cu")
		(at 208.487264 -300.650402 -90)
		(property "Reference" "R3932"
			(at 0 0 270)
			(layer "F.SilkS")
			(hide yes)
			(effects
				(font
					(size 1.27 1.27)
				)
			)
		)
		(property "Value" ""
			(at 0 0 270)
			(layer "F.Fab")
			(effects
				(font
					(size 1.27 1.27)
				)
			)
		)
		(duplicate_pad_numbers_are_jumpers no)
		(fp_line
			(start -0.7874 0.4064)
			(end -0.7874 -0.4064)
			(stroke
				(width 0.1524)
				(type default)
			)
			(layer "F.SilkS")
		)
		(fp_line
			(start 0.7874 0.4064)
			(end -0.7874 0.4064)
			(stroke
				(width 0.1524)
				(type default)
			)
			(layer "F.SilkS")
		)
		(fp_line
			(start -0.7874 -0.4064)
			(end 0.7874 -0.4064)
			(stroke
				(width 0.1524)
				(type default)
			)
			(layer "F.SilkS")
		)
		(fp_line
			(start 0.7874 -0.4064)
			(end 0.7874 0.4064)
			(stroke
				(width 0.1524)
				(type default)
			)
			(layer "F.SilkS")
		)
		(fp_line
			(start -0.67945 0.3048)
			(end -0.67945 -0.305054)
			(stroke
				(width 0.1)
				(type default)
			)
			(layer "F.Fab")
		)
		(fp_line
			(start -0.12065 0.3048)
			(end -0.67945 0.3048)
			(stroke
				(width 0.1)
				(type default)
			)
			(layer "F.Fab")
		)
		(fp_line
			(start 0.120396 0.3048)
			(end 0.120396 0.2794)
			(stroke
				(width 0.1)
				(type default)
			)
			(layer "F.Fab")
		)
		(fp_line
			(start 0.67945 0.3048)
			(end 0.120396 0.3048)
			(stroke
				(width 0.1)
				(type default)
			)
			(layer "F.Fab")
		)
		(fp_line
			(start -0.12065 0.2794)
			(end -0.12065 0.3048)
			(stroke
				(width 0.1)
				(type default)
			)
			(layer "F.Fab")
		)
		(fp_line
			(start 0.120396 0.2794)
			(end -0.12065 0.2794)
			(stroke
				(width 0.1)
				(type default)
			)
			(layer "F.Fab")
		)
		(fp_line
			(start -0.12065 -0.2794)
			(end 0.12065 -0.2794)
			(stroke
				(width 0.1)
				(type default)
			)
			(layer "F.Fab")
		)
		(fp_line
			(start 0.12065 -0.2794)
			(end 0.12065 -0.3048)
			(stroke
				(width 0.1)
				(type default)
			)
			(layer "F.Fab")
		)
		(fp_line
			(start 0.12065 -0.3048)
			(end 0.67945 -0.3048)
			(stroke
				(width 0.1)
				(type default)
			)
			(layer "F.Fab")
		)
		(fp_line
			(start 0.67945 -0.3048)
			(end 0.67945 0.3048)
			(stroke
				(width 0.1)
				(type default)
			)
			(layer "F.Fab")
		)
		(fp_line
			(start -0.67945 -0.305054)
			(end -0.12065 -0.305054)
			(stroke
				(width 0.1)
				(type default)
			)
			(layer "F.Fab")
		)
		(fp_line
			(start -0.12065 -0.305054)
			(end -0.12065 -0.2794)
			(stroke
				(width 0.1)
				(type default)
			)
			(layer "F.Fab")
		)
		(pad "1" smd circle
			(at -0.40005 0 270)
			(size 0 0)
			(layers "F.Cu" "F.Mask" "F.Paste")
			(net "I2C0_PEX1_SHPC_SCL")
		)
		(pad "2" smd circle
			(at 0.40005 0 270)
			(size 0 0)
			(layers "F.Cu" "F.Mask" "F.Paste")
			(net "I2C_PEX1_HOST_SCL")
		)
	)
	(footprint ""
		(layer "F.Cu")
		(at 390.73074 -350.098614 90)
		(property "Reference" "C759"
			(at 0 0 90)
			(layer "F.SilkS")
			(hide yes)
			(effects
				(font
					(size 1.27 1.27)
				)
			)
		)
		(property "Value" ""
			(at 0 0 90)
			(layer "F.Fab")
			(effects
				(font
					(size 1.27 1.27)
				)
			)
		)
		(duplicate_pad_numbers_are_jumpers no)
		(fp_line
			(start 0.299974 -0.150114)
			(end 0.299974 0.150114)
			(stroke
				(width 0.1)
				(type default)
			)
			(layer "F.Fab")
		)
		(fp_line
			(start -0.299974 -0.150114)
			(end 0.299974 -0.150114)
			(stroke
				(width 0.1)
				(type default)
			)
			(layer "F.Fab")
		)
		(fp_line
			(start 0.299974 0.150114)
			(end -0.299974 0.150114)
			(stroke
				(width 0.1)
				(type default)
			)
			(layer "F.Fab")
		)
		(fp_line
			(start -0.299974 0.150114)
			(end -0.299974 -0.150114)
			(stroke
				(width 0.1)
				(type default)
			)
			(layer "F.Fab")
		)
		(pad "1" smd rect
			(at -0.2667 0 90)
			(size 0.3048 0.381)
			(layers "F.Cu" "F.Mask" "F.Paste")
			(net "P5E_PEX3_STN5_TX_DN<81>")
		)
		(pad "2" smd rect
			(at 0.2667 0 90)
			(size 0.3048 0.381)
			(layers "F.Cu" "F.Mask" "F.Paste")
			(net "P5E_PEX3_STN5_TX_C_DN<81>")
		)
	)
	(footprint ""
		(layer "F.Cu")
		(at 328.022204 -356.244906 90)
		(property "Reference" "C533"
			(at 0 0 90)
			(layer "F.SilkS")
			(hide yes)
			(effects
				(font
					(size 1.27 1.27)
				)
			)
		)
		(property "Value" ""
			(at 0 0 90)
			(layer "F.Fab")
			(effects
				(font
					(size 1.27 1.27)
				)
			)
		)
		(duplicate_pad_numbers_are_jumpers no)
		(fp_line
			(start 0.299974 -0.150114)
			(end 0.299974 0.150114)
			(stroke
				(width 0.1)
				(type default)
			)
			(layer "F.Fab")
		)
		(fp_line
			(start -0.299974 -0.150114)
			(end 0.299974 -0.150114)
			(stroke
				(width 0.1)
				(type default)
			)
			(layer "F.Fab")
		)
		(fp_line
			(start 0.299974 0.150114)
			(end -0.299974 0.150114)
			(stroke
				(width 0.1)
				(type default)
			)
			(layer "F.Fab")
		)
		(fp_line
			(start -0.299974 0.150114)
			(end -0.299974 -0.150114)
			(stroke
				(width 0.1)
				(type default)
			)
			(layer "F.Fab")
		)
		(pad "1" smd rect
			(at -0.2667 0 90)
			(size 0.3048 0.381)
			(layers "F.Cu" "F.Mask" "F.Paste")
			(net "P5E_PEX2_STN5_TX_DP<88>")
		)
		(pad "2" smd rect
			(at 0.2667 0 90)
			(size 0.3048 0.381)
			(layers "F.Cu" "F.Mask" "F.Paste")
			(net "P5E_PEX2_STN5_TX_C_DP<88>")
		)
	)
	(footprint ""
		(layer "F.Cu")
		(at 369.495578 -84.927694 180)
		(property "Reference" "R1605"
			(at 0 0 180)
			(layer "F.SilkS")
			(hide yes)
			(effects
				(font
					(size 1.27 1.27)
				)
			)
		)
		(property "Value" ""
			(at 0 0 180)
			(layer "F.Fab")
			(effects
				(font
					(size 1.27 1.27)
				)
			)
		)
		(duplicate_pad_numbers_are_jumpers no)
		(fp_line
			(start 0.7874 0.4064)
			(end -0.7874 0.4064)
			(stroke
				(width 0.1524)
				(type default)
			)
			(layer "F.SilkS")
		)
		(fp_line
			(start 0.7874 -0.4064)
			(end 0.7874 0.4064)
			(stroke
				(width 0.1524)
				(type default)
			)
			(layer "F.SilkS")
		)
		(fp_line
			(start -0.7874 0.4064)
			(end -0.7874 -0.4064)
			(stroke
				(width 0.1524)
				(type default)
			)
			(layer "F.SilkS")
		)
		(fp_line
			(start -0.7874 -0.4064)
			(end 0.7874 -0.4064)
			(stroke
				(width 0.1524)
				(type default)
			)
			(layer "F.SilkS")
		)
		(fp_line
			(start 0.67945 0.3048)
			(end 0.120396 0.3048)
			(stroke
				(width 0.1)
				(type default)
			)
			(layer "F.Fab")
		)
		(fp_line
			(start 0.67945 -0.3048)
			(end 0.67945 0.3048)
			(stroke
				(width 0.1)
				(type default)
			)
			(layer "F.Fab")
		)
		(fp_line
			(start 0.12065 -0.2794)
			(end 0.12065 -0.3048)
			(stroke
				(width 0.1)
				(type default)
			)
			(layer "F.Fab")
		)
		(fp_line
			(start 0.12065 -0.3048)
			(end 0.67945 -0.3048)
			(stroke
				(width 0.1)
				(type default)
			)
			(layer "F.Fab")
		)
		(fp_line
			(start 0.120396 0.3048)
			(end 0.120396 0.2794)
			(stroke
				(width 0.1)
				(type default)
			)
			(layer "F.Fab")
		)
		(fp_line
			(start 0.120396 0.2794)
			(end -0.12065 0.2794)
			(stroke
				(width 0.1)
				(type default)
			)
			(layer "F.Fab")
		)
		(fp_line
			(start -0.12065 0.3048)
			(end -0.67945 0.3048)
			(stroke
				(width 0.1)
				(type default)
			)
			(layer "F.Fab")
		)
		(fp_line
			(start -0.12065 0.2794)
			(end -0.12065 0.3048)
			(stroke
				(width 0.1)
				(type default)
			)
			(layer "F.Fab")
		)
		(fp_line
			(start -0.12065 -0.2794)
			(end 0.12065 -0.2794)
			(stroke
				(width 0.1)
				(type default)
			)
			(layer "F.Fab")
		)
		(fp_line
			(start -0.12065 -0.305054)
			(end -0.12065 -0.2794)
			(stroke
				(width 0.1)
				(type default)
			)
			(layer "F.Fab")
		)
		(fp_line
			(start -0.67945 0.3048)
			(end -0.67945 -0.305054)
			(stroke
				(width 0.1)
				(type default)
			)
			(layer "F.Fab")
		)
		(fp_line
			(start -0.67945 -0.305054)
			(end -0.12065 -0.305054)
			(stroke
				(width 0.1)
				(type default)
			)
			(layer "F.Fab")
		)
		(pad "1" smd circle
			(at -0.40005 0 180)
			(size 0 0)
			(layers "F.Cu" "F.Mask" "F.Paste")
			(net "P3V3_AUX")
		)
		(pad "2" smd circle
			(at 0.40005 0 180)
			(size 0 0)
			(layers "F.Cu" "F.Mask" "F.Paste")
			(net "SMB_BIC_I2C9_MUX1_SSD13_R_SCL")
		)
	)
	(footprint ""
		(layer "F.Cu")
		(at 381.254 -209.55)
		(property "Reference" "R4633"
			(at 0 0 0)
			(layer "F.SilkS")
			(hide yes)
			(effects
				(font
					(size 1.27 1.27)
				)
			)
		)
		(property "Value" ""
			(at 0 0 0)
			(layer "F.Fab")
			(effects
				(font
					(size 1.27 1.27)
				)
			)
		)
		(duplicate_pad_numbers_are_jumpers no)
		(fp_line
			(start -0.7874 -0.4064)
			(end 0.7874 -0.4064)
			(stroke
				(width 0.1524)
				(type default)
			)
			(layer "F.SilkS")
		)
		(fp_line
			(start -0.7874 0.4064)
			(end -0.7874 -0.4064)
			(stroke
				(width 0.1524)
				(type default)
			)
			(layer "F.SilkS")
		)
		(fp_line
			(start 0.7874 -0.4064)
			(end 0.7874 0.4064)
			(stroke
				(width 0.1524)
				(type default)
			)
			(layer "F.SilkS")
		)
		(fp_line
			(start 0.7874 0.4064)
			(end -0.7874 0.4064)
			(stroke
				(width 0.1524)
				(type default)
			)
			(layer "F.SilkS")
		)
		(fp_line
			(start -0.67945 -0.305054)
			(end -0.12065 -0.305054)
			(stroke
				(width 0.1)
				(type default)
			)
			(layer "F.Fab")
		)
		(fp_line
			(start -0.67945 0.3048)
			(end -0.67945 -0.305054)
			(stroke
				(width 0.1)
				(type default)
			)
			(layer "F.Fab")
		)
		(fp_line
			(start -0.12065 -0.305054)
			(end -0.12065 -0.2794)
			(stroke
				(width 0.1)
				(type default)
			)
			(layer "F.Fab")
		)
		(fp_line
			(start -0.12065 -0.2794)
			(end 0.12065 -0.2794)
			(stroke
				(width 0.1)
				(type default)
			)
			(layer "F.Fab")
		)
		(fp_line
			(start -0.12065 0.2794)
			(end -0.12065 0.3048)
			(stroke
				(width 0.1)
				(type default)
			)
			(layer "F.Fab")
		)
		(fp_line
			(start -0.12065 0.3048)
			(end -0.67945 0.3048)
			(stroke
				(width 0.1)
				(type default)
			)
			(layer "F.Fab")
		)
		(fp_line
			(start 0.120396 0.2794)
			(end -0.12065 0.2794)
			(stroke
				(width 0.1)
				(type default)
			)
			(layer "F.Fab")
		)
		(fp_line
			(start 0.120396 0.3048)
			(end 0.120396 0.2794)
			(stroke
				(width 0.1)
				(type default)
			)
			(layer "F.Fab")
		)
		(fp_line
			(start 0.12065 -0.3048)
			(end 0.67945 -0.3048)
			(stroke
				(width 0.1)
				(type default)
			)
			(layer "F.Fab")
		)
		(fp_line
			(start 0.12065 -0.2794)
			(end 0.12065 -0.3048)
			(stroke
				(width 0.1)
				(type default)
			)
			(layer "F.Fab")
		)
		(fp_line
			(start 0.67945 -0.3048)
			(end 0.67945 0.3048)
			(stroke
				(width 0.1)
				(type default)
			)
			(layer "F.Fab")
		)
		(fp_line
			(start 0.67945 0.3048)
			(end 0.120396 0.3048)
			(stroke
				(width 0.1)
				(type default)
			)
			(layer "F.Fab")
		)
		(pad "1" smd circle
			(at -0.40005 0)
			(size 0 0)
			(layers "F.Cu" "F.Mask" "F.Paste")
			(net "RST_PEX_NIC0_PERST_N")
		)
		(pad "2" smd circle
			(at 0.40005 0)
			(size 0 0)
			(layers "F.Cu" "F.Mask" "F.Paste")
			(net "RST_PEX_NIC0_PERST_R_N")
		)
	)
	(footprint ""
		(layer "F.Cu")
		(at 58.890916 -55.663846 90)
		(property "Reference" "PU59"
			(at -1.120394 3.012186 90)
			(unlocked yes)
			(layer "F.SilkS")
			(effects
				(font
					(size 0.7874 0.5842)
					(thickness 0.1524)
				)
				(justify left)
			)
		)
		(property "Value" ""
			(at 0 0 90)
			(layer "F.Fab")
			(effects
				(font
					(size 1.27 1.27)
				)
			)
		)
		(duplicate_pad_numbers_are_jumpers no)
		(fp_line
			(start 1.943608 -1.549908)
			(end 1.943608 1.549908)
			(stroke
				(width 0.1524)
				(type default)
			)
			(layer "F.SilkS")
		)
		(fp_line
			(start -1.943608 -1.549908)
			(end 1.943608 -1.549908)
			(stroke
				(width 0.1524)
				(type default)
			)
			(layer "F.SilkS")
		)
		(fp_line
			(start 1.943608 1.549908)
			(end -1.943608 1.549908)
			(stroke
				(width 0.1524)
				(type default)
			)
			(layer "F.SilkS")
		)
		(fp_line
			(start -1.943608 1.549908)
			(end -1.943608 -1.549908)
			(stroke
				(width 0.1524)
				(type default)
			)
			(layer "F.SilkS")
		)
		(fp_poly
			(pts
				(xy -2.019808 -1.549908) (xy -1.257808 -1.549908) (xy -1.257808 -1.880108) (xy -2.019808 -1.880108)
			)
			(stroke
				(width 0)
				(type default)
			)
			(fill yes)
			(layer "F.SilkS")
		)
		(fp_line
			(start 1.549908 -1.549908)
			(end 1.549908 1.549908)
			(stroke
				(width 0.1)
				(type default)
			)
			(layer "F.Fab")
		)
		(fp_line
			(start -1.549908 -1.549908)
			(end 1.549908 -1.549908)
			(stroke
				(width 0.1)
				(type default)
			)
			(layer "F.Fab")
		)
		(fp_line
			(start 1.549908 1.549908)
			(end -1.549908 1.549908)
			(stroke
				(width 0.1)
				(type default)
			)
			(layer "F.Fab")
		)
		(fp_line
			(start -1.549908 1.549908)
			(end -1.549908 -1.549908)
			(stroke
				(width 0.1)
				(type default)
			)
			(layer "F.Fab")
		)
		(fp_poly
			(pts
				(xy -2.019808 -1.549908) (xy -1.257808 -1.549908) (xy -1.257808 -1.880108) (xy -2.019808 -1.880108)
			)
			(stroke
				(width 0)
				(type default)
			)
			(fill yes)
			(layer "F.Fab")
		)
		(pad "1" smd rect
			(at -1.500124 -1.249934)
			(size 0.2794 0.6096)
			(layers "F.Cu" "F.Mask" "F.Paste")
			(net "P3V3_SSD2")
		)
		(pad "2" smd rect
			(at -1.500124 -0.750062)
			(size 0.2794 0.6096)
			(layers "F.Cu" "F.Mask" "F.Paste")
			(net "P3V3_SSD2")
		)
		(pad "3" smd rect
			(at -1.500124 -0.249936)
			(size 0.2794 0.6096)
			(layers "F.Cu" "F.Mask" "F.Paste")
			(net "P3V3_SSD2")
		)
		(pad "4" smd rect
			(at -1.500124 0.249936)
			(size 0.2794 0.6096)
			(layers "F.Cu" "F.Mask" "F.Paste")
			(net "P3V3_SSD2")
		)
		(pad "5" smd rect
			(at -1.500124 0.750062)
			(size 0.2794 0.6096)
			(layers "F.Cu" "F.Mask" "F.Paste")
			(net "P3V3_SSD2")
		)
		(pad "6" smd rect
			(at -1.500124 1.249934)
			(size 0.2794 0.6096)
			(layers "F.Cu" "F.Mask" "F.Paste")
			(net "GND")
		)
		(pad "7" smd rect
			(at 1.500124 1.249934)
			(size 0.2794 0.6096)
			(layers "F.Cu" "F.Mask" "F.Paste")
			(net "P3V3_SSD2_SS")
		)
		(pad "8" smd rect
			(at 1.500124 0.750062)
			(size 0.2794 0.6096)
			(layers "F.Cu" "F.Mask" "F.Paste")
			(net "PWRGD_P3V3_SSD2")
		)
		(pad "9" smd rect
			(at 1.500124 0.249936)
			(size 0.2794 0.6096)
			(layers "F.Cu" "F.Mask" "F.Paste")
			(net "P3V3_SSD2_OCP")
		)
		(pad "10" smd rect
			(at 1.500124 -0.249936)
			(size 0.2794 0.6096)
			(layers "F.Cu" "F.Mask" "F.Paste")
			(net "P5V_AUX")
		)
		(pad "11" smd rect
			(at 1.500124 -0.750062)
			(size 0.2794 0.6096)
			(layers "F.Cu" "F.Mask" "F.Paste")
			(net "SSD2_AUX_P3V3_EN_R")
		)
		(pad "12" smd rect
			(at 1.500124 -1.249934)
			(size 0.2794 0.6096)
			(layers "F.Cu" "F.Mask" "F.Paste")
			(net "P3V3_AUX")
		)
		(pad "13" smd rect
			(at 0 0 90)
			(size 1.9812 2.7178)
			(layers "F.Cu" "F.Mask" "F.Paste")
			(net "P3V3_AUX")
		)
		(zone
			(layer "F.Cu")
			(hatch none 0.5)
			(connect_pads
				(clearance 0)
			)
			(min_thickness 0.25)
			(keepout
				(tracks not_allowed)
				(vias allowed)
				(pads allowed)
				(copperpour not_allowed)
				(footprints allowed)
			)
			(placement
				(enabled no)
				(sheetname "")
			)
			(fill
				(thermal_gap 0.5)
				(thermal_bridge_width 0.5)
				(island_removal_mode 0)
			)
			(polygon
				(pts
					(xy 57.341516 -56.806846) (xy 57.468516 -56.806846) (xy 60.440316 -56.806846) (xy 60.440824 -56.806846)
					(xy 60.440824 -54.520846) (xy 60.440316 -54.520846) (xy 60.313316 -54.520846) (xy 58.890916 -54.520846)
					(xy 58.890916 -54.622446) (xy 60.313316 -54.622446) (xy 60.313316 -56.705246) (xy 57.468516 -56.705246)
					(xy 57.468516 -54.622446) (xy 58.865516 -54.622446) (xy 58.865516 -54.520846) (xy 57.468516 -54.520846)
					(xy 57.341516 -54.520846) (xy 57.341008 -54.520846) (xy 57.341008 -56.806846)
				)
			)
		)
	)
	(footprint ""
		(layer "F.Cu")
		(at 214.614506 -66.32194 90)
		(property "Reference" "R5981"
			(at 0 0 90)
			(layer "F.SilkS")
			(hide yes)
			(effects
				(font
					(size 1.27 1.27)
				)
			)
		)
		(property "Value" ""
			(at 0 0 90)
			(layer "F.Fab")
			(effects
				(font
					(size 1.27 1.27)
				)
			)
		)
		(duplicate_pad_numbers_are_jumpers no)
		(fp_line
			(start 0.7874 -0.4064)
			(end 0.7874 0.4064)
			(stroke
				(width 0.1524)
				(type default)
			)
			(layer "F.SilkS")
		)
		(fp_line
			(start -0.7874 -0.4064)
			(end 0.7874 -0.4064)
			(stroke
				(width 0.1524)
				(type default)
			)
			(layer "F.SilkS")
		)
		(fp_line
			(start 0.7874 0.4064)
			(end -0.7874 0.4064)
			(stroke
				(width 0.1524)
				(type default)
			)
			(layer "F.SilkS")
		)
		(fp_line
			(start -0.7874 0.4064)
			(end -0.7874 -0.4064)
			(stroke
				(width 0.1524)
				(type default)
			)
			(layer "F.SilkS")
		)
		(fp_line
			(start -0.12065 -0.305054)
			(end -0.12065 -0.2794)
			(stroke
				(width 0.1)
				(type default)
			)
			(layer "F.Fab")
		)
		(fp_line
			(start -0.67945 -0.305054)
			(end -0.12065 -0.305054)
			(stroke
				(width 0.1)
				(type default)
			)
			(layer "F.Fab")
		)
		(fp_line
			(start 0.67945 -0.3048)
			(end 0.67945 0.3048)
			(stroke
				(width 0.1)
				(type default)
			)
			(layer "F.Fab")
		)
		(fp_line
			(start 0.12065 -0.3048)
			(end 0.67945 -0.3048)
			(stroke
				(width 0.1)
				(type default)
			)
			(layer "F.Fab")
		)
		(fp_line
			(start 0.12065 -0.2794)
			(end 0.12065 -0.3048)
			(stroke
				(width 0.1)
				(type default)
			)
			(layer "F.Fab")
		)
		(fp_line
			(start -0.12065 -0.2794)
			(end 0.12065 -0.2794)
			(stroke
				(width 0.1)
				(type default)
			)
			(layer "F.Fab")
		)
		(fp_line
			(start 0.120396 0.2794)
			(end -0.12065 0.2794)
			(stroke
				(width 0.1)
				(type default)
			)
			(layer "F.Fab")
		)
		(fp_line
			(start -0.12065 0.2794)
			(end -0.12065 0.3048)
			(stroke
				(width 0.1)
				(type default)
			)
			(layer "F.Fab")
		)
		(fp_line
			(start 0.67945 0.3048)
			(end 0.120396 0.3048)
			(stroke
				(width 0.1)
				(type default)
			)
			(layer "F.Fab")
		)
		(fp_line
			(start 0.120396 0.3048)
			(end 0.120396 0.2794)
			(stroke
				(width 0.1)
				(type default)
			)
			(layer "F.Fab")
		)
		(fp_line
			(start -0.12065 0.3048)
			(end -0.67945 0.3048)
			(stroke
				(width 0.1)
				(type default)
			)
			(layer "F.Fab")
		)
		(fp_line
			(start -0.67945 0.3048)
			(end -0.67945 -0.305054)
			(stroke
				(width 0.1)
				(type default)
			)
			(layer "F.Fab")
		)
		(pad "1" smd circle
			(at -0.40005 0 90)
			(size 0 0)
			(layers "F.Cu" "F.Mask" "F.Paste")
			(net "SSD7_PWR_EN_R")
		)
		(pad "2" smd circle
			(at 0.40005 0 90)
			(size 0 0)
			(layers "F.Cu" "F.Mask" "F.Paste")
			(net "P12V_SSD7_CO_EN")
		)
	)
	(footprint ""
		(layer "F.Cu")
		(at 112.311942 -108.737654 180)
		(property "Reference" "C840"
			(at 0 0 180)
			(layer "F.SilkS")
			(hide yes)
			(effects
				(font
					(size 1.27 1.27)
				)
			)
		)
		(property "Value" ""
			(at 0 0 180)
			(layer "F.Fab")
			(effects
				(font
					(size 1.27 1.27)
				)
			)
		)
		(duplicate_pad_numbers_are_jumpers no)
		(fp_line
			(start 0.7874 0.4064)
			(end -0.7874 0.4064)
			(stroke
				(width 0.1524)
				(type default)
			)
			(layer "F.SilkS")
		)
		(fp_line
			(start 0.7874 -0.4064)
			(end 0.7874 0.4064)
			(stroke
				(width 0.1524)
				(type default)
			)
			(layer "F.SilkS")
		)
		(fp_line
			(start -0.7874 0.4064)
			(end -0.7874 -0.4064)
			(stroke
				(width 0.1524)
				(type default)
			)
			(layer "F.SilkS")
		)
		(fp_line
			(start -0.7874 -0.4064)
			(end 0.7874 -0.4064)
			(stroke
				(width 0.1524)
				(type default)
			)
			(layer "F.SilkS")
		)
		(fp_line
			(start 0.67945 0.3048)
			(end 0.120396 0.3048)
			(stroke
				(width 0.1)
				(type default)
			)
			(layer "F.Fab")
		)
		(fp_line
			(start 0.67945 -0.3048)
			(end 0.67945 0.3048)
			(stroke
				(width 0.1)
				(type default)
			)
			(layer "F.Fab")
		)
		(fp_line
			(start 0.12065 -0.2794)
			(end 0.12065 -0.3048)
			(stroke
				(width 0.1)
				(type default)
			)
			(layer "F.Fab")
		)
		(fp_line
			(start 0.12065 -0.3048)
			(end 0.67945 -0.3048)
			(stroke
				(width 0.1)
				(type default)
			)
			(layer "F.Fab")
		)
		(fp_line
			(start 0.120396 0.3048)
			(end 0.120396 0.2794)
			(stroke
				(width 0.1)
				(type default)
			)
			(layer "F.Fab")
		)
		(fp_line
			(start 0.120396 0.2794)
			(end -0.12065 0.2794)
			(stroke
				(width 0.1)
				(type default)
			)
			(layer "F.Fab")
		)
		(fp_line
			(start -0.12065 0.3048)
			(end -0.67945 0.3048)
			(stroke
				(width 0.1)
				(type default)
			)
			(layer "F.Fab")
		)
		(fp_line
			(start -0.12065 0.2794)
			(end -0.12065 0.3048)
			(stroke
				(width 0.1)
				(type default)
			)
			(layer "F.Fab")
		)
		(fp_line
			(start -0.12065 -0.2794)
			(end 0.12065 -0.2794)
			(stroke
				(width 0.1)
				(type default)
			)
			(layer "F.Fab")
		)
		(fp_line
			(start -0.12065 -0.305054)
			(end -0.12065 -0.2794)
			(stroke
				(width 0.1)
				(type default)
			)
			(layer "F.Fab")
		)
		(fp_line
			(start -0.67945 0.3048)
			(end -0.67945 -0.305054)
			(stroke
				(width 0.1)
				(type default)
			)
			(layer "F.Fab")
		)
		(fp_line
			(start -0.67945 -0.305054)
			(end -0.12065 -0.305054)
			(stroke
				(width 0.1)
				(type default)
			)
			(layer "F.Fab")
		)
		(pad "1" smd circle
			(at -0.40005 0 180)
			(size 0 0)
			(layers "F.Cu" "F.Mask" "F.Paste")
			(net "GND")
		)
		(pad "2" smd circle
			(at 0.40005 0 180)
			(size 0 0)
			(layers "F.Cu" "F.Mask" "F.Paste")
			(net "P12V_NIC1_CO_EN")
		)
	)
	(footprint ""
		(layer "F.Cu")
		(at 345.057476 -313.620404)
		(property "Reference" "R5794"
			(at 0 0 0)
			(layer "F.SilkS")
			(hide yes)
			(effects
				(font
					(size 1.27 1.27)
				)
			)
		)
		(property "Value" ""
			(at 0 0 0)
			(layer "F.Fab")
			(effects
				(font
					(size 1.27 1.27)
				)
			)
		)
		(duplicate_pad_numbers_are_jumpers no)
		(fp_line
			(start -2.576322 -1.1303)
			(end 2.576322 -1.1303)
			(stroke
				(width 0.1524)
				(type default)
			)
			(layer "F.SilkS")
		)
		(fp_line
			(start -2.576322 1.1303)
			(end -2.576322 -1.1303)
			(stroke
				(width 0.1524)
				(type default)
			)
			(layer "F.SilkS")
		)
		(fp_line
			(start 2.576322 -1.1303)
			(end 2.576322 1.1303)
			(stroke
				(width 0.1524)
				(type default)
			)
			(layer "F.SilkS")
		)
		(fp_line
			(start 2.576322 1.1303)
			(end -2.576322 1.1303)
			(stroke
				(width 0.1524)
				(type default)
			)
			(layer "F.SilkS")
		)
		(fp_line
			(start -1.649984 -0.899922)
			(end -1.649984 0.899922)
			(stroke
				(width 0.1)
				(type default)
			)
			(layer "F.Fab")
		)
		(fp_line
			(start -1.649984 0.899922)
			(end 1.649984 0.899922)
			(stroke
				(width 0.1)
				(type default)
			)
			(layer "F.Fab")
		)
		(fp_line
			(start 1.649984 -0.899922)
			(end -1.649984 -0.899922)
			(stroke
				(width 0.1)
				(type default)
			)
			(layer "F.Fab")
		)
		(fp_line
			(start 1.649984 0.899922)
			(end 1.649984 -0.899922)
			(stroke
				(width 0.1)
				(type default)
			)
			(layer "F.Fab")
		)
		(pad "1A" smd rect
			(at -1.700022 0)
			(size 1.4986 2.0066)
			(layers "F.Cu" "F.Mask" "F.Paste")
			(net "P0V8_PEX2")
		)
		(pad "1B" smd rect
			(at -1.077722 0)
			(size 0.254 0.508)
			(layers "F.Cu" "F.Mask" "F.Paste")
			(net "P0V8_PEX2")
		)
		(pad "2A" smd rect
			(at 1.700022 0)
			(size 1.4986 2.0066)
			(layers "F.Cu" "F.Mask" "F.Paste")
			(net "P0V8_SERDES_VDDA_PEX2")
		)
		(pad "2B" smd rect
			(at 1.077722 0)
			(size 0.254 0.508)
			(layers "F.Cu" "F.Mask" "F.Paste")
			(net "P0V8_SERDES_VDDA_PEX2")
		)
	)
	(footprint ""
		(layer "F.Cu")
		(at 352.319844 -146.606768 180)
		(property "Reference" "R4845"
			(at 0 0 180)
			(layer "F.SilkS")
			(hide yes)
			(effects
				(font
					(size 1.27 1.27)
				)
			)
		)
		(property "Value" ""
			(at 0 0 180)
			(layer "F.Fab")
			(effects
				(font
					(size 1.27 1.27)
				)
			)
		)
		(duplicate_pad_numbers_are_jumpers no)
		(fp_line
			(start 0.7874 0.4064)
			(end -0.7874 0.4064)
			(stroke
				(width 0.1524)
				(type default)
			)
			(layer "F.SilkS")
		)
		(fp_line
			(start 0.7874 -0.4064)
			(end 0.7874 0.4064)
			(stroke
				(width 0.1524)
				(type default)
			)
			(layer "F.SilkS")
		)
		(fp_line
			(start -0.7874 0.4064)
			(end -0.7874 -0.4064)
			(stroke
				(width 0.1524)
				(type default)
			)
			(layer "F.SilkS")
		)
		(fp_line
			(start -0.7874 -0.4064)
			(end 0.7874 -0.4064)
			(stroke
				(width 0.1524)
				(type default)
			)
			(layer "F.SilkS")
		)
		(fp_line
			(start 0.67945 0.3048)
			(end 0.120396 0.3048)
			(stroke
				(width 0.1)
				(type default)
			)
			(layer "F.Fab")
		)
		(fp_line
			(start 0.67945 -0.3048)
			(end 0.67945 0.3048)
			(stroke
				(width 0.1)
				(type default)
			)
			(layer "F.Fab")
		)
		(fp_line
			(start 0.12065 -0.2794)
			(end 0.12065 -0.3048)
			(stroke
				(width 0.1)
				(type default)
			)
			(layer "F.Fab")
		)
		(fp_line
			(start 0.12065 -0.3048)
			(end 0.67945 -0.3048)
			(stroke
				(width 0.1)
				(type default)
			)
			(layer "F.Fab")
		)
		(fp_line
			(start 0.120396 0.3048)
			(end 0.120396 0.2794)
			(stroke
				(width 0.1)
				(type default)
			)
			(layer "F.Fab")
		)
		(fp_line
			(start 0.120396 0.2794)
			(end -0.12065 0.2794)
			(stroke
				(width 0.1)
				(type default)
			)
			(layer "F.Fab")
		)
		(fp_line
			(start -0.12065 0.3048)
			(end -0.67945 0.3048)
			(stroke
				(width 0.1)
				(type default)
			)
			(layer "F.Fab")
		)
		(fp_line
			(start -0.12065 0.2794)
			(end -0.12065 0.3048)
			(stroke
				(width 0.1)
				(type default)
			)
			(layer "F.Fab")
		)
		(fp_line
			(start -0.12065 -0.2794)
			(end 0.12065 -0.2794)
			(stroke
				(width 0.1)
				(type default)
			)
			(layer "F.Fab")
		)
		(fp_line
			(start -0.12065 -0.305054)
			(end -0.12065 -0.2794)
			(stroke
				(width 0.1)
				(type default)
			)
			(layer "F.Fab")
		)
		(fp_line
			(start -0.67945 0.3048)
			(end -0.67945 -0.305054)
			(stroke
				(width 0.1)
				(type default)
			)
			(layer "F.Fab")
		)
		(fp_line
			(start -0.67945 -0.305054)
			(end -0.12065 -0.305054)
			(stroke
				(width 0.1)
				(type default)
			)
			(layer "F.Fab")
		)
		(pad "1" smd circle
			(at -0.40005 0 180)
			(size 0 0)
			(layers "F.Cu" "F.Mask" "F.Paste")
			(net "GND")
		)
		(pad "2" smd circle
			(at 0.40005 0 180)
			(size 0 0)
			(layers "F.Cu" "F.Mask" "F.Paste")
			(net "PCA9555_1_PEX3_A0")
		)
	)
	(footprint ""
		(layer "F.Cu")
		(at 58.11901 -59.574684 90)
		(property "Reference" "PC517"
			(at 0 0 90)
			(layer "F.SilkS")
			(hide yes)
			(effects
				(font
					(size 1.27 1.27)
				)
			)
		)
		(property "Value" ""
			(at 0 0 90)
			(layer "F.Fab")
			(effects
				(font
					(size 1.27 1.27)
				)
			)
		)
		(duplicate_pad_numbers_are_jumpers no)
		(fp_line
			(start 0.7874 -0.4064)
			(end 0.7874 0.4064)
			(stroke
				(width 0.1524)
				(type default)
			)
			(layer "F.SilkS")
		)
		(fp_line
			(start -0.7874 -0.4064)
			(end 0.7874 -0.4064)
			(stroke
				(width 0.1524)
				(type default)
			)
			(layer "F.SilkS")
		)
		(fp_line
			(start 0.7874 0.4064)
			(end -0.7874 0.4064)
			(stroke
				(width 0.1524)
				(type default)
			)
			(layer "F.SilkS")
		)
		(fp_line
			(start -0.7874 0.4064)
			(end -0.7874 -0.4064)
			(stroke
				(width 0.1524)
				(type default)
			)
			(layer "F.SilkS")
		)
		(fp_line
			(start -0.12065 -0.305054)
			(end -0.12065 -0.2794)
			(stroke
				(width 0.1)
				(type default)
			)
			(layer "F.Fab")
		)
		(fp_line
			(start -0.67945 -0.305054)
			(end -0.12065 -0.305054)
			(stroke
				(width 0.1)
				(type default)
			)
			(layer "F.Fab")
		)
		(fp_line
			(start 0.67945 -0.3048)
			(end 0.67945 0.3048)
			(stroke
				(width 0.1)
				(type default)
			)
			(layer "F.Fab")
		)
		(fp_line
			(start 0.12065 -0.3048)
			(end 0.67945 -0.3048)
			(stroke
				(width 0.1)
				(type default)
			)
			(layer "F.Fab")
		)
		(fp_line
			(start 0.12065 -0.2794)
			(end 0.12065 -0.3048)
			(stroke
				(width 0.1)
				(type default)
			)
			(layer "F.Fab")
		)
		(fp_line
			(start -0.12065 -0.2794)
			(end 0.12065 -0.2794)
			(stroke
				(width 0.1)
				(type default)
			)
			(layer "F.Fab")
		)
		(fp_line
			(start 0.120396 0.2794)
			(end -0.12065 0.2794)
			(stroke
				(width 0.1)
				(type default)
			)
			(layer "F.Fab")
		)
		(fp_line
			(start -0.12065 0.2794)
			(end -0.12065 0.3048)
			(stroke
				(width 0.1)
				(type default)
			)
			(layer "F.Fab")
		)
		(fp_line
			(start 0.67945 0.3048)
			(end 0.120396 0.3048)
			(stroke
				(width 0.1)
				(type default)
			)
			(layer "F.Fab")
		)
		(fp_line
			(start 0.120396 0.3048)
			(end 0.120396 0.2794)
			(stroke
				(width 0.1)
				(type default)
			)
			(layer "F.Fab")
		)
		(fp_line
			(start -0.12065 0.3048)
			(end -0.67945 0.3048)
			(stroke
				(width 0.1)
				(type default)
			)
			(layer "F.Fab")
		)
		(fp_line
			(start -0.67945 0.3048)
			(end -0.67945 -0.305054)
			(stroke
				(width 0.1)
				(type default)
			)
			(layer "F.Fab")
		)
		(pad "1" smd circle
			(at -0.40005 0 90)
			(size 0 0)
			(layers "F.Cu" "F.Mask" "F.Paste")
			(net "P5V_AUX")
		)
		(pad "2" smd circle
			(at 0.40005 0 90)
			(size 0 0)
			(layers "F.Cu" "F.Mask" "F.Paste")
			(net "GND")
		)
	)
	(footprint ""
		(layer "F.Cu")
		(at 168.164256 -166.302944 90)
		(property "Reference" "R148"
			(at 0 0 90)
			(layer "F.SilkS")
			(hide yes)
			(effects
				(font
					(size 1.27 1.27)
				)
			)
		)
		(property "Value" ""
			(at 0 0 90)
			(layer "F.Fab")
			(effects
				(font
					(size 1.27 1.27)
				)
			)
		)
		(duplicate_pad_numbers_are_jumpers no)
		(fp_line
			(start 0.7874 -0.4064)
			(end 0.7874 0.4064)
			(stroke
				(width 0.1524)
				(type default)
			)
			(layer "F.SilkS")
		)
		(fp_line
			(start -0.7874 -0.4064)
			(end 0.7874 -0.4064)
			(stroke
				(width 0.1524)
				(type default)
			)
			(layer "F.SilkS")
		)
		(fp_line
			(start 0.7874 0.4064)
			(end -0.7874 0.4064)
			(stroke
				(width 0.1524)
				(type default)
			)
			(layer "F.SilkS")
		)
		(fp_line
			(start -0.7874 0.4064)
			(end -0.7874 -0.4064)
			(stroke
				(width 0.1524)
				(type default)
			)
			(layer "F.SilkS")
		)
		(fp_line
			(start -0.12065 -0.305054)
			(end -0.12065 -0.2794)
			(stroke
				(width 0.1)
				(type default)
			)
			(layer "F.Fab")
		)
		(fp_line
			(start -0.67945 -0.305054)
			(end -0.12065 -0.305054)
			(stroke
				(width 0.1)
				(type default)
			)
			(layer "F.Fab")
		)
		(fp_line
			(start 0.67945 -0.3048)
			(end 0.67945 0.3048)
			(stroke
				(width 0.1)
				(type default)
			)
			(layer "F.Fab")
		)
		(fp_line
			(start 0.12065 -0.3048)
			(end 0.67945 -0.3048)
			(stroke
				(width 0.1)
				(type default)
			)
			(layer "F.Fab")
		)
		(fp_line
			(start 0.12065 -0.2794)
			(end 0.12065 -0.3048)
			(stroke
				(width 0.1)
				(type default)
			)
			(layer "F.Fab")
		)
		(fp_line
			(start -0.12065 -0.2794)
			(end 0.12065 -0.2794)
			(stroke
				(width 0.1)
				(type default)
			)
			(layer "F.Fab")
		)
		(fp_line
			(start 0.120396 0.2794)
			(end -0.12065 0.2794)
			(stroke
				(width 0.1)
				(type default)
			)
			(layer "F.Fab")
		)
		(fp_line
			(start -0.12065 0.2794)
			(end -0.12065 0.3048)
			(stroke
				(width 0.1)
				(type default)
			)
			(layer "F.Fab")
		)
		(fp_line
			(start 0.67945 0.3048)
			(end 0.120396 0.3048)
			(stroke
				(width 0.1)
				(type default)
			)
			(layer "F.Fab")
		)
		(fp_line
			(start 0.120396 0.3048)
			(end 0.120396 0.2794)
			(stroke
				(width 0.1)
				(type default)
			)
			(layer "F.Fab")
		)
		(fp_line
			(start -0.12065 0.3048)
			(end -0.67945 0.3048)
			(stroke
				(width 0.1)
				(type default)
			)
			(layer "F.Fab")
		)
		(fp_line
			(start -0.67945 0.3048)
			(end -0.67945 -0.305054)
			(stroke
				(width 0.1)
				(type default)
			)
			(layer "F.Fab")
		)
		(pad "1" smd circle
			(at -0.40005 0 90)
			(size 0 0)
			(layers "F.Cu" "F.Mask" "F.Paste")
			(net "RST_NIC2_PERST1_R_N")
		)
		(pad "2" smd circle
			(at 0.40005 0 90)
			(size 0 0)
			(layers "F.Cu" "F.Mask" "F.Paste")
			(net "RST_HP_NIC2_BUF_N")
		)
	)
	(footprint ""
		(layer "F.Cu")
		(at 243.986812 -310.568848)
		(property "Reference" "R846"
			(at 0 0 0)
			(layer "F.SilkS")
			(hide yes)
			(effects
				(font
					(size 1.27 1.27)
				)
			)
		)
		(property "Value" ""
			(at 0 0 0)
			(layer "F.Fab")
			(effects
				(font
					(size 1.27 1.27)
				)
			)
		)
		(duplicate_pad_numbers_are_jumpers no)
		(fp_line
			(start -0.7874 -0.4064)
			(end 0.7874 -0.4064)
			(stroke
				(width 0.1524)
				(type default)
			)
			(layer "F.SilkS")
		)
		(fp_line
			(start -0.7874 0.4064)
			(end -0.7874 -0.4064)
			(stroke
				(width 0.1524)
				(type default)
			)
			(layer "F.SilkS")
		)
		(fp_line
			(start 0.7874 -0.4064)
			(end 0.7874 0.4064)
			(stroke
				(width 0.1524)
				(type default)
			)
			(layer "F.SilkS")
		)
		(fp_line
			(start 0.7874 0.4064)
			(end -0.7874 0.4064)
			(stroke
				(width 0.1524)
				(type default)
			)
			(layer "F.SilkS")
		)
		(fp_line
			(start -0.67945 -0.305054)
			(end -0.12065 -0.305054)
			(stroke
				(width 0.1)
				(type default)
			)
			(layer "F.Fab")
		)
		(fp_line
			(start -0.67945 0.3048)
			(end -0.67945 -0.305054)
			(stroke
				(width 0.1)
				(type default)
			)
			(layer "F.Fab")
		)
		(fp_line
			(start -0.12065 -0.305054)
			(end -0.12065 -0.2794)
			(stroke
				(width 0.1)
				(type default)
			)
			(layer "F.Fab")
		)
		(fp_line
			(start -0.12065 -0.2794)
			(end 0.12065 -0.2794)
			(stroke
				(width 0.1)
				(type default)
			)
			(layer "F.Fab")
		)
		(fp_line
			(start -0.12065 0.2794)
			(end -0.12065 0.3048)
			(stroke
				(width 0.1)
				(type default)
			)
			(layer "F.Fab")
		)
		(fp_line
			(start -0.12065 0.3048)
			(end -0.67945 0.3048)
			(stroke
				(width 0.1)
				(type default)
			)
			(layer "F.Fab")
		)
		(fp_line
			(start 0.120396 0.2794)
			(end -0.12065 0.2794)
			(stroke
				(width 0.1)
				(type default)
			)
			(layer "F.Fab")
		)
		(fp_line
			(start 0.120396 0.3048)
			(end 0.120396 0.2794)
			(stroke
				(width 0.1)
				(type default)
			)
			(layer "F.Fab")
		)
		(fp_line
			(start 0.12065 -0.3048)
			(end 0.67945 -0.3048)
			(stroke
				(width 0.1)
				(type default)
			)
			(layer "F.Fab")
		)
		(fp_line
			(start 0.12065 -0.2794)
			(end 0.12065 -0.3048)
			(stroke
				(width 0.1)
				(type default)
			)
			(layer "F.Fab")
		)
		(fp_line
			(start 0.67945 -0.3048)
			(end 0.67945 0.3048)
			(stroke
				(width 0.1)
				(type default)
			)
			(layer "F.Fab")
		)
		(fp_line
			(start 0.67945 0.3048)
			(end 0.120396 0.3048)
			(stroke
				(width 0.1)
				(type default)
			)
			(layer "F.Fab")
		)
		(pad "1" smd circle
			(at -0.40005 0)
			(size 0 0)
			(layers "F.Cu" "F.Mask" "F.Paste")
			(net "P1V25_PEX2_EN")
		)
		(pad "2" smd circle
			(at 0.40005 0)
			(size 0 0)
			(layers "F.Cu" "F.Mask" "F.Paste")
			(net "PWR_EN_PEX_R")
		)
	)
	(footprint ""
		(layer "F.Cu")
		(at 10.11047 -124.963428 180)
		(property "Reference" "R4474"
			(at 0 0 180)
			(layer "F.SilkS")
			(hide yes)
			(effects
				(font
					(size 1.27 1.27)
				)
			)
		)
		(property "Value" ""
			(at 0 0 180)
			(layer "F.Fab")
			(effects
				(font
					(size 1.27 1.27)
				)
			)
		)
		(duplicate_pad_numbers_are_jumpers no)
		(fp_line
			(start 0.7874 0.4064)
			(end -0.7874 0.4064)
			(stroke
				(width 0.1524)
				(type default)
			)
			(layer "F.SilkS")
		)
		(fp_line
			(start 0.7874 -0.4064)
			(end 0.7874 0.4064)
			(stroke
				(width 0.1524)
				(type default)
			)
			(layer "F.SilkS")
		)
		(fp_line
			(start -0.7874 0.4064)
			(end -0.7874 -0.4064)
			(stroke
				(width 0.1524)
				(type default)
			)
			(layer "F.SilkS")
		)
		(fp_line
			(start -0.7874 -0.4064)
			(end 0.7874 -0.4064)
			(stroke
				(width 0.1524)
				(type default)
			)
			(layer "F.SilkS")
		)
		(fp_line
			(start 0.67945 0.3048)
			(end 0.120396 0.3048)
			(stroke
				(width 0.1)
				(type default)
			)
			(layer "F.Fab")
		)
		(fp_line
			(start 0.67945 -0.3048)
			(end 0.67945 0.3048)
			(stroke
				(width 0.1)
				(type default)
			)
			(layer "F.Fab")
		)
		(fp_line
			(start 0.12065 -0.2794)
			(end 0.12065 -0.3048)
			(stroke
				(width 0.1)
				(type default)
			)
			(layer "F.Fab")
		)
		(fp_line
			(start 0.12065 -0.3048)
			(end 0.67945 -0.3048)
			(stroke
				(width 0.1)
				(type default)
			)
			(layer "F.Fab")
		)
		(fp_line
			(start 0.120396 0.3048)
			(end 0.120396 0.2794)
			(stroke
				(width 0.1)
				(type default)
			)
			(layer "F.Fab")
		)
		(fp_line
			(start 0.120396 0.2794)
			(end -0.12065 0.2794)
			(stroke
				(width 0.1)
				(type default)
			)
			(layer "F.Fab")
		)
		(fp_line
			(start -0.12065 0.3048)
			(end -0.67945 0.3048)
			(stroke
				(width 0.1)
				(type default)
			)
			(layer "F.Fab")
		)
		(fp_line
			(start -0.12065 0.2794)
			(end -0.12065 0.3048)
			(stroke
				(width 0.1)
				(type default)
			)
			(layer "F.Fab")
		)
		(fp_line
			(start -0.12065 -0.2794)
			(end 0.12065 -0.2794)
			(stroke
				(width 0.1)
				(type default)
			)
			(layer "F.Fab")
		)
		(fp_line
			(start -0.12065 -0.305054)
			(end -0.12065 -0.2794)
			(stroke
				(width 0.1)
				(type default)
			)
			(layer "F.Fab")
		)
		(fp_line
			(start -0.67945 0.3048)
			(end -0.67945 -0.305054)
			(stroke
				(width 0.1)
				(type default)
			)
			(layer "F.Fab")
		)
		(fp_line
			(start -0.67945 -0.305054)
			(end -0.12065 -0.305054)
			(stroke
				(width 0.1)
				(type default)
			)
			(layer "F.Fab")
		)
		(pad "1" smd circle
			(at -0.40005 0 180)
			(size 0 0)
			(layers "F.Cu" "F.Mask" "F.Paste")
			(net "PWRGD_P3V3_NIC0")
		)
		(pad "2" smd circle
			(at 0.40005 0 180)
			(size 0 0)
			(layers "F.Cu" "F.Mask" "F.Paste")
			(net "PWRGD_P3V3_NIC0_R")
		)
	)
	(footprint ""
		(layer "F.Cu")
		(at 257.558286 -252.356874 -90)
		(property "Reference" "R1363"
			(at 0 0 270)
			(layer "F.SilkS")
			(hide yes)
			(effects
				(font
					(size 1.27 1.27)
				)
			)
		)
		(property "Value" ""
			(at 0 0 270)
			(layer "F.Fab")
			(effects
				(font
					(size 1.27 1.27)
				)
			)
		)
		(duplicate_pad_numbers_are_jumpers no)
		(fp_line
			(start -0.7874 0.4064)
			(end -0.7874 -0.4064)
			(stroke
				(width 0.1524)
				(type default)
			)
			(layer "F.SilkS")
		)
		(fp_line
			(start 0.7874 0.4064)
			(end -0.7874 0.4064)
			(stroke
				(width 0.1524)
				(type default)
			)
			(layer "F.SilkS")
		)
		(fp_line
			(start -0.7874 -0.4064)
			(end 0.7874 -0.4064)
			(stroke
				(width 0.1524)
				(type default)
			)
			(layer "F.SilkS")
		)
		(fp_line
			(start 0.7874 -0.4064)
			(end 0.7874 0.4064)
			(stroke
				(width 0.1524)
				(type default)
			)
			(layer "F.SilkS")
		)
		(fp_line
			(start -0.67945 0.3048)
			(end -0.67945 -0.305054)
			(stroke
				(width 0.1)
				(type default)
			)
			(layer "F.Fab")
		)
		(fp_line
			(start -0.12065 0.3048)
			(end -0.67945 0.3048)
			(stroke
				(width 0.1)
				(type default)
			)
			(layer "F.Fab")
		)
		(fp_line
			(start 0.120396 0.3048)
			(end 0.120396 0.2794)
			(stroke
				(width 0.1)
				(type default)
			)
			(layer "F.Fab")
		)
		(fp_line
			(start 0.67945 0.3048)
			(end 0.120396 0.3048)
			(stroke
				(width 0.1)
				(type default)
			)
			(layer "F.Fab")
		)
		(fp_line
			(start -0.12065 0.2794)
			(end -0.12065 0.3048)
			(stroke
				(width 0.1)
				(type default)
			)
			(layer "F.Fab")
		)
		(fp_line
			(start 0.120396 0.2794)
			(end -0.12065 0.2794)
			(stroke
				(width 0.1)
				(type default)
			)
			(layer "F.Fab")
		)
		(fp_line
			(start -0.12065 -0.2794)
			(end 0.12065 -0.2794)
			(stroke
				(width 0.1)
				(type default)
			)
			(layer "F.Fab")
		)
		(fp_line
			(start 0.12065 -0.2794)
			(end 0.12065 -0.3048)
			(stroke
				(width 0.1)
				(type default)
			)
			(layer "F.Fab")
		)
		(fp_line
			(start 0.12065 -0.3048)
			(end 0.67945 -0.3048)
			(stroke
				(width 0.1)
				(type default)
			)
			(layer "F.Fab")
		)
		(fp_line
			(start 0.67945 -0.3048)
			(end 0.67945 0.3048)
			(stroke
				(width 0.1)
				(type default)
			)
			(layer "F.Fab")
		)
		(fp_line
			(start -0.67945 -0.305054)
			(end -0.12065 -0.305054)
			(stroke
				(width 0.1)
				(type default)
			)
			(layer "F.Fab")
		)
		(fp_line
			(start -0.12065 -0.305054)
			(end -0.12065 -0.2794)
			(stroke
				(width 0.1)
				(type default)
			)
			(layer "F.Fab")
		)
		(pad "1" smd circle
			(at -0.40005 0 270)
			(size 0 0)
			(layers "F.Cu" "F.Mask" "F.Paste")
			(net "GND")
		)
		(pad "2" smd circle
			(at 0.40005 0 270)
			(size 0 0)
			(layers "F.Cu" "F.Mask" "F.Paste")
			(net "PEX2_MODE_SEL7")
		)
	)
	(footprint ""
		(layer "F.Cu")
		(at 378.826776 -53.697124 -90)
		(property "Reference" "PC556"
			(at 0 0 270)
			(layer "F.SilkS")
			(hide yes)
			(effects
				(font
					(size 1.27 1.27)
				)
			)
		)
		(property "Value" ""
			(at 0 0 270)
			(layer "F.Fab")
			(effects
				(font
					(size 1.27 1.27)
				)
			)
		)
		(duplicate_pad_numbers_are_jumpers no)
		(fp_line
			(start -0.7874 0.4064)
			(end -0.7874 -0.4064)
			(stroke
				(width 0.1524)
				(type default)
			)
			(layer "F.SilkS")
		)
		(fp_line
			(start 0.7874 0.4064)
			(end -0.7874 0.4064)
			(stroke
				(width 0.1524)
				(type default)
			)
			(layer "F.SilkS")
		)
		(fp_line
			(start -0.7874 -0.4064)
			(end 0.7874 -0.4064)
			(stroke
				(width 0.1524)
				(type default)
			)
			(layer "F.SilkS")
		)
		(fp_line
			(start 0.7874 -0.4064)
			(end 0.7874 0.4064)
			(stroke
				(width 0.1524)
				(type default)
			)
			(layer "F.SilkS")
		)
		(fp_line
			(start -0.67945 0.3048)
			(end -0.67945 -0.305054)
			(stroke
				(width 0.1)
				(type default)
			)
			(layer "F.Fab")
		)
		(fp_line
			(start -0.12065 0.3048)
			(end -0.67945 0.3048)
			(stroke
				(width 0.1)
				(type default)
			)
			(layer "F.Fab")
		)
		(fp_line
			(start 0.120396 0.3048)
			(end 0.120396 0.2794)
			(stroke
				(width 0.1)
				(type default)
			)
			(layer "F.Fab")
		)
		(fp_line
			(start 0.67945 0.3048)
			(end 0.120396 0.3048)
			(stroke
				(width 0.1)
				(type default)
			)
			(layer "F.Fab")
		)
		(fp_line
			(start -0.12065 0.2794)
			(end -0.12065 0.3048)
			(stroke
				(width 0.1)
				(type default)
			)
			(layer "F.Fab")
		)
		(fp_line
			(start 0.120396 0.2794)
			(end -0.12065 0.2794)
			(stroke
				(width 0.1)
				(type default)
			)
			(layer "F.Fab")
		)
		(fp_line
			(start -0.12065 -0.2794)
			(end 0.12065 -0.2794)
			(stroke
				(width 0.1)
				(type default)
			)
			(layer "F.Fab")
		)
		(fp_line
			(start 0.12065 -0.2794)
			(end 0.12065 -0.3048)
			(stroke
				(width 0.1)
				(type default)
			)
			(layer "F.Fab")
		)
		(fp_line
			(start 0.12065 -0.3048)
			(end 0.67945 -0.3048)
			(stroke
				(width 0.1)
				(type default)
			)
			(layer "F.Fab")
		)
		(fp_line
			(start 0.67945 -0.3048)
			(end 0.67945 0.3048)
			(stroke
				(width 0.1)
				(type default)
			)
			(layer "F.Fab")
		)
		(fp_line
			(start -0.67945 -0.305054)
			(end -0.12065 -0.305054)
			(stroke
				(width 0.1)
				(type default)
			)
			(layer "F.Fab")
		)
		(fp_line
			(start -0.12065 -0.305054)
			(end -0.12065 -0.2794)
			(stroke
				(width 0.1)
				(type default)
			)
			(layer "F.Fab")
		)
		(pad "1" smd circle
			(at -0.40005 0 270)
			(size 0 0)
			(layers "F.Cu" "F.Mask" "F.Paste")
			(net "P3V3_AUX")
		)
		(pad "2" smd circle
			(at 0.40005 0 270)
			(size 0 0)
			(layers "F.Cu" "F.Mask" "F.Paste")
			(net "GND")
		)
	)
	(footprint ""
		(layer "F.Cu")
		(at 334.518 -201.168 -90)
		(property "Reference" "R4119"
			(at 0 0 270)
			(layer "F.SilkS")
			(hide yes)
			(effects
				(font
					(size 1.27 1.27)
				)
			)
		)
		(property "Value" ""
			(at 0 0 270)
			(layer "F.Fab")
			(effects
				(font
					(size 1.27 1.27)
				)
			)
		)
		(duplicate_pad_numbers_are_jumpers no)
		(fp_line
			(start -0.7874 0.4064)
			(end -0.7874 -0.4064)
			(stroke
				(width 0.1524)
				(type default)
			)
			(layer "F.SilkS")
		)
		(fp_line
			(start 0.7874 0.4064)
			(end -0.7874 0.4064)
			(stroke
				(width 0.1524)
				(type default)
			)
			(layer "F.SilkS")
		)
		(fp_line
			(start -0.7874 -0.4064)
			(end 0.7874 -0.4064)
			(stroke
				(width 0.1524)
				(type default)
			)
			(layer "F.SilkS")
		)
		(fp_line
			(start 0.7874 -0.4064)
			(end 0.7874 0.4064)
			(stroke
				(width 0.1524)
				(type default)
			)
			(layer "F.SilkS")
		)
		(fp_line
			(start -0.67945 0.3048)
			(end -0.67945 -0.305054)
			(stroke
				(width 0.1)
				(type default)
			)
			(layer "F.Fab")
		)
		(fp_line
			(start -0.12065 0.3048)
			(end -0.67945 0.3048)
			(stroke
				(width 0.1)
				(type default)
			)
			(layer "F.Fab")
		)
		(fp_line
			(start 0.120396 0.3048)
			(end 0.120396 0.2794)
			(stroke
				(width 0.1)
				(type default)
			)
			(layer "F.Fab")
		)
		(fp_line
			(start 0.67945 0.3048)
			(end 0.120396 0.3048)
			(stroke
				(width 0.1)
				(type default)
			)
			(layer "F.Fab")
		)
		(fp_line
			(start -0.12065 0.2794)
			(end -0.12065 0.3048)
			(stroke
				(width 0.1)
				(type default)
			)
			(layer "F.Fab")
		)
		(fp_line
			(start 0.120396 0.2794)
			(end -0.12065 0.2794)
			(stroke
				(width 0.1)
				(type default)
			)
			(layer "F.Fab")
		)
		(fp_line
			(start -0.12065 -0.2794)
			(end 0.12065 -0.2794)
			(stroke
				(width 0.1)
				(type default)
			)
			(layer "F.Fab")
		)
		(fp_line
			(start 0.12065 -0.2794)
			(end 0.12065 -0.3048)
			(stroke
				(width 0.1)
				(type default)
			)
			(layer "F.Fab")
		)
		(fp_line
			(start 0.12065 -0.3048)
			(end 0.67945 -0.3048)
			(stroke
				(width 0.1)
				(type default)
			)
			(layer "F.Fab")
		)
		(fp_line
			(start 0.67945 -0.3048)
			(end 0.67945 0.3048)
			(stroke
				(width 0.1)
				(type default)
			)
			(layer "F.Fab")
		)
		(fp_line
			(start -0.67945 -0.305054)
			(end -0.12065 -0.305054)
			(stroke
				(width 0.1)
				(type default)
			)
			(layer "F.Fab")
		)
		(fp_line
			(start -0.12065 -0.305054)
			(end -0.12065 -0.2794)
			(stroke
				(width 0.1)
				(type default)
			)
			(layer "F.Fab")
		)
		(pad "1" smd circle
			(at -0.40005 0 270)
			(size 0 0)
			(layers "F.Cu" "F.Mask" "F.Paste")
			(net "SSD9_PWR_EN")
		)
		(pad "2" smd circle
			(at 0.40005 0 270)
			(size 0 0)
			(layers "F.Cu" "F.Mask" "F.Paste")
			(net "SSD9_PWR_EN_R")
		)
	)
	(footprint ""
		(layer "F.Cu")
		(at 347.92031 -260.290564)
		(property "Reference" "PR129"
			(at 0 0 0)
			(layer "F.SilkS")
			(hide yes)
			(effects
				(font
					(size 1.27 1.27)
				)
			)
		)
		(property "Value" ""
			(at 0 0 0)
			(layer "F.Fab")
			(effects
				(font
					(size 1.27 1.27)
				)
			)
		)
		(duplicate_pad_numbers_are_jumpers no)
		(fp_line
			(start -0.7874 -0.4064)
			(end 0.7874 -0.4064)
			(stroke
				(width 0.1524)
				(type default)
			)
			(layer "F.SilkS")
		)
		(fp_line
			(start -0.7874 0.4064)
			(end -0.7874 -0.4064)
			(stroke
				(width 0.1524)
				(type default)
			)
			(layer "F.SilkS")
		)
		(fp_line
			(start 0.7874 -0.4064)
			(end 0.7874 0.4064)
			(stroke
				(width 0.1524)
				(type default)
			)
			(layer "F.SilkS")
		)
		(fp_line
			(start 0.7874 0.4064)
			(end -0.7874 0.4064)
			(stroke
				(width 0.1524)
				(type default)
			)
			(layer "F.SilkS")
		)
		(fp_line
			(start -0.67945 -0.305054)
			(end -0.12065 -0.305054)
			(stroke
				(width 0.1)
				(type default)
			)
			(layer "F.Fab")
		)
		(fp_line
			(start -0.67945 0.3048)
			(end -0.67945 -0.305054)
			(stroke
				(width 0.1)
				(type default)
			)
			(layer "F.Fab")
		)
		(fp_line
			(start -0.12065 -0.305054)
			(end -0.12065 -0.2794)
			(stroke
				(width 0.1)
				(type default)
			)
			(layer "F.Fab")
		)
		(fp_line
			(start -0.12065 -0.2794)
			(end 0.12065 -0.2794)
			(stroke
				(width 0.1)
				(type default)
			)
			(layer "F.Fab")
		)
		(fp_line
			(start -0.12065 0.2794)
			(end -0.12065 0.3048)
			(stroke
				(width 0.1)
				(type default)
			)
			(layer "F.Fab")
		)
		(fp_line
			(start -0.12065 0.3048)
			(end -0.67945 0.3048)
			(stroke
				(width 0.1)
				(type default)
			)
			(layer "F.Fab")
		)
		(fp_line
			(start 0.120396 0.2794)
			(end -0.12065 0.2794)
			(stroke
				(width 0.1)
				(type default)
			)
			(layer "F.Fab")
		)
		(fp_line
			(start 0.120396 0.3048)
			(end 0.120396 0.2794)
			(stroke
				(width 0.1)
				(type default)
			)
			(layer "F.Fab")
		)
		(fp_line
			(start 0.12065 -0.3048)
			(end 0.67945 -0.3048)
			(stroke
				(width 0.1)
				(type default)
			)
			(layer "F.Fab")
		)
		(fp_line
			(start 0.12065 -0.2794)
			(end 0.12065 -0.3048)
			(stroke
				(width 0.1)
				(type default)
			)
			(layer "F.Fab")
		)
		(fp_line
			(start 0.67945 -0.3048)
			(end 0.67945 0.3048)
			(stroke
				(width 0.1)
				(type default)
			)
			(layer "F.Fab")
		)
		(fp_line
			(start 0.67945 0.3048)
			(end 0.120396 0.3048)
			(stroke
				(width 0.1)
				(type default)
			)
			(layer "F.Fab")
		)
		(pad "1" smd circle
			(at -0.40005 0)
			(size 0 0)
			(layers "F.Cu" "F.Mask" "F.Paste")
			(net "SH_P0V8_PEX3_VSEN3_R")
		)
		(pad "2" smd circle
			(at 0.40005 0)
			(size 0 0)
			(layers "F.Cu" "F.Mask" "F.Paste")
			(net "P0V8_PEX3_VSEN3")
		)
	)
	(footprint ""
		(layer "F.Cu")
		(at 99.8855 -27.092148 -90)
		(property "Reference" "R5737"
			(at 0 0 270)
			(layer "F.SilkS")
			(hide yes)
			(effects
				(font
					(size 1.27 1.27)
				)
			)
		)
		(property "Value" ""
			(at 0 0 270)
			(layer "F.Fab")
			(effects
				(font
					(size 1.27 1.27)
				)
			)
		)
		(duplicate_pad_numbers_are_jumpers no)
		(fp_line
			(start -0.7874 0.4064)
			(end -0.7874 -0.4064)
			(stroke
				(width 0.1524)
				(type default)
			)
			(layer "F.SilkS")
		)
		(fp_line
			(start 0.7874 0.4064)
			(end -0.7874 0.4064)
			(stroke
				(width 0.1524)
				(type default)
			)
			(layer "F.SilkS")
		)
		(fp_line
			(start -0.7874 -0.4064)
			(end 0.7874 -0.4064)
			(stroke
				(width 0.1524)
				(type default)
			)
			(layer "F.SilkS")
		)
		(fp_line
			(start 0.7874 -0.4064)
			(end 0.7874 0.4064)
			(stroke
				(width 0.1524)
				(type default)
			)
			(layer "F.SilkS")
		)
		(fp_line
			(start -0.67945 0.3048)
			(end -0.67945 -0.305054)
			(stroke
				(width 0.1)
				(type default)
			)
			(layer "F.Fab")
		)
		(fp_line
			(start -0.12065 0.3048)
			(end -0.67945 0.3048)
			(stroke
				(width 0.1)
				(type default)
			)
			(layer "F.Fab")
		)
		(fp_line
			(start 0.120396 0.3048)
			(end 0.120396 0.2794)
			(stroke
				(width 0.1)
				(type default)
			)
			(layer "F.Fab")
		)
		(fp_line
			(start 0.67945 0.3048)
			(end 0.120396 0.3048)
			(stroke
				(width 0.1)
				(type default)
			)
			(layer "F.Fab")
		)
		(fp_line
			(start -0.12065 0.2794)
			(end -0.12065 0.3048)
			(stroke
				(width 0.1)
				(type default)
			)
			(layer "F.Fab")
		)
		(fp_line
			(start 0.120396 0.2794)
			(end -0.12065 0.2794)
			(stroke
				(width 0.1)
				(type default)
			)
			(layer "F.Fab")
		)
		(fp_line
			(start -0.12065 -0.2794)
			(end 0.12065 -0.2794)
			(stroke
				(width 0.1)
				(type default)
			)
			(layer "F.Fab")
		)
		(fp_line
			(start 0.12065 -0.2794)
			(end 0.12065 -0.3048)
			(stroke
				(width 0.1)
				(type default)
			)
			(layer "F.Fab")
		)
		(fp_line
			(start 0.12065 -0.3048)
			(end 0.67945 -0.3048)
			(stroke
				(width 0.1)
				(type default)
			)
			(layer "F.Fab")
		)
		(fp_line
			(start 0.67945 -0.3048)
			(end 0.67945 0.3048)
			(stroke
				(width 0.1)
				(type default)
			)
			(layer "F.Fab")
		)
		(fp_line
			(start -0.67945 -0.305054)
			(end -0.12065 -0.305054)
			(stroke
				(width 0.1)
				(type default)
			)
			(layer "F.Fab")
		)
		(fp_line
			(start -0.12065 -0.305054)
			(end -0.12065 -0.2794)
			(stroke
				(width 0.1)
				(type default)
			)
			(layer "F.Fab")
		)
		(pad "1" smd circle
			(at -0.40005 0 270)
			(size 0 0)
			(layers "F.Cu" "F.Mask" "F.Paste")
			(net "P3V3_SSD3")
		)
		(pad "2" smd circle
			(at 0.40005 0 270)
			(size 0 0)
			(layers "F.Cu" "F.Mask" "F.Paste")
			(net "SSD3_LED_ISO_N")
		)
	)
	(footprint ""
		(layer "F.Cu")
		(at 50.481992 -37.025072)
		(property "Reference" "R5661"
			(at 0 0 0)
			(layer "F.SilkS")
			(hide yes)
			(effects
				(font
					(size 1.27 1.27)
				)
			)
		)
		(property "Value" ""
			(at 0 0 0)
			(layer "F.Fab")
			(effects
				(font
					(size 1.27 1.27)
				)
			)
		)
		(duplicate_pad_numbers_are_jumpers no)
		(fp_line
			(start -0.7874 -0.4064)
			(end 0.7874 -0.4064)
			(stroke
				(width 0.1524)
				(type default)
			)
			(layer "F.SilkS")
		)
		(fp_line
			(start -0.7874 0.4064)
			(end -0.7874 -0.4064)
			(stroke
				(width 0.1524)
				(type default)
			)
			(layer "F.SilkS")
		)
		(fp_line
			(start 0.7874 -0.4064)
			(end 0.7874 0.4064)
			(stroke
				(width 0.1524)
				(type default)
			)
			(layer "F.SilkS")
		)
		(fp_line
			(start 0.7874 0.4064)
			(end -0.7874 0.4064)
			(stroke
				(width 0.1524)
				(type default)
			)
			(layer "F.SilkS")
		)
		(fp_line
			(start -0.67945 -0.305054)
			(end -0.12065 -0.305054)
			(stroke
				(width 0.1)
				(type default)
			)
			(layer "F.Fab")
		)
		(fp_line
			(start -0.67945 0.3048)
			(end -0.67945 -0.305054)
			(stroke
				(width 0.1)
				(type default)
			)
			(layer "F.Fab")
		)
		(fp_line
			(start -0.12065 -0.305054)
			(end -0.12065 -0.2794)
			(stroke
				(width 0.1)
				(type default)
			)
			(layer "F.Fab")
		)
		(fp_line
			(start -0.12065 -0.2794)
			(end 0.12065 -0.2794)
			(stroke
				(width 0.1)
				(type default)
			)
			(layer "F.Fab")
		)
		(fp_line
			(start -0.12065 0.2794)
			(end -0.12065 0.3048)
			(stroke
				(width 0.1)
				(type default)
			)
			(layer "F.Fab")
		)
		(fp_line
			(start -0.12065 0.3048)
			(end -0.67945 0.3048)
			(stroke
				(width 0.1)
				(type default)
			)
			(layer "F.Fab")
		)
		(fp_line
			(start 0.120396 0.2794)
			(end -0.12065 0.2794)
			(stroke
				(width 0.1)
				(type default)
			)
			(layer "F.Fab")
		)
		(fp_line
			(start 0.120396 0.3048)
			(end 0.120396 0.2794)
			(stroke
				(width 0.1)
				(type default)
			)
			(layer "F.Fab")
		)
		(fp_line
			(start 0.12065 -0.3048)
			(end 0.67945 -0.3048)
			(stroke
				(width 0.1)
				(type default)
			)
			(layer "F.Fab")
		)
		(fp_line
			(start 0.12065 -0.2794)
			(end 0.12065 -0.3048)
			(stroke
				(width 0.1)
				(type default)
			)
			(layer "F.Fab")
		)
		(fp_line
			(start 0.67945 -0.3048)
			(end 0.67945 0.3048)
			(stroke
				(width 0.1)
				(type default)
			)
			(layer "F.Fab")
		)
		(fp_line
			(start 0.67945 0.3048)
			(end 0.120396 0.3048)
			(stroke
				(width 0.1)
				(type default)
			)
			(layer "F.Fab")
		)
		(pad "1" smd circle
			(at -0.40005 0)
			(size 0 0)
			(layers "F.Cu" "F.Mask" "F.Paste")
			(net "RST_SMB_SSD_R_N")
		)
		(pad "2" smd circle
			(at 0.40005 0)
			(size 0 0)
			(layers "F.Cu" "F.Mask" "F.Paste")
			(net "RST_SMB_SSD2_N")
		)
	)
	(footprint ""
		(layer "F.Cu")
		(at 268.402816 -90.462354)
		(property "Reference" "R1053"
			(at 0 0 0)
			(layer "F.SilkS")
			(hide yes)
			(effects
				(font
					(size 1.27 1.27)
				)
			)
		)
		(property "Value" ""
			(at 0 0 0)
			(layer "F.Fab")
			(effects
				(font
					(size 1.27 1.27)
				)
			)
		)
		(duplicate_pad_numbers_are_jumpers no)
		(fp_line
			(start -0.7874 -0.4064)
			(end 0.7874 -0.4064)
			(stroke
				(width 0.1524)
				(type default)
			)
			(layer "F.SilkS")
		)
		(fp_line
			(start -0.7874 0.4064)
			(end -0.7874 -0.4064)
			(stroke
				(width 0.1524)
				(type default)
			)
			(layer "F.SilkS")
		)
		(fp_line
			(start 0.7874 -0.4064)
			(end 0.7874 0.4064)
			(stroke
				(width 0.1524)
				(type default)
			)
			(layer "F.SilkS")
		)
		(fp_line
			(start 0.7874 0.4064)
			(end -0.7874 0.4064)
			(stroke
				(width 0.1524)
				(type default)
			)
			(layer "F.SilkS")
		)
		(fp_line
			(start -0.67945 -0.305054)
			(end -0.12065 -0.305054)
			(stroke
				(width 0.1)
				(type default)
			)
			(layer "F.Fab")
		)
		(fp_line
			(start -0.67945 0.3048)
			(end -0.67945 -0.305054)
			(stroke
				(width 0.1)
				(type default)
			)
			(layer "F.Fab")
		)
		(fp_line
			(start -0.12065 -0.305054)
			(end -0.12065 -0.2794)
			(stroke
				(width 0.1)
				(type default)
			)
			(layer "F.Fab")
		)
		(fp_line
			(start -0.12065 -0.2794)
			(end 0.12065 -0.2794)
			(stroke
				(width 0.1)
				(type default)
			)
			(layer "F.Fab")
		)
		(fp_line
			(start -0.12065 0.2794)
			(end -0.12065 0.3048)
			(stroke
				(width 0.1)
				(type default)
			)
			(layer "F.Fab")
		)
		(fp_line
			(start -0.12065 0.3048)
			(end -0.67945 0.3048)
			(stroke
				(width 0.1)
				(type default)
			)
			(layer "F.Fab")
		)
		(fp_line
			(start 0.120396 0.2794)
			(end -0.12065 0.2794)
			(stroke
				(width 0.1)
				(type default)
			)
			(layer "F.Fab")
		)
		(fp_line
			(start 0.120396 0.3048)
			(end 0.120396 0.2794)
			(stroke
				(width 0.1)
				(type default)
			)
			(layer "F.Fab")
		)
		(fp_line
			(start 0.12065 -0.3048)
			(end 0.67945 -0.3048)
			(stroke
				(width 0.1)
				(type default)
			)
			(layer "F.Fab")
		)
		(fp_line
			(start 0.12065 -0.2794)
			(end 0.12065 -0.3048)
			(stroke
				(width 0.1)
				(type default)
			)
			(layer "F.Fab")
		)
		(fp_line
			(start 0.67945 -0.3048)
			(end 0.67945 0.3048)
			(stroke
				(width 0.1)
				(type default)
			)
			(layer "F.Fab")
		)
		(fp_line
			(start 0.67945 0.3048)
			(end 0.120396 0.3048)
			(stroke
				(width 0.1)
				(type default)
			)
			(layer "F.Fab")
		)
		(pad "1" smd circle
			(at -0.40005 0)
			(size 0 0)
			(layers "F.Cu" "F.Mask" "F.Paste")
			(net "FM_CK440_MXCK_25M_100M")
		)
		(pad "2" smd circle
			(at 0.40005 0)
			(size 0 0)
			(layers "F.Cu" "F.Mask" "F.Paste")
			(net "P3V3")
		)
	)
	(footprint ""
		(layer "F.Cu")
		(at 10.11047 -123.947428 180)
		(property "Reference" "PR241"
			(at 0 0 180)
			(layer "F.SilkS")
			(hide yes)
			(effects
				(font
					(size 1.27 1.27)
				)
			)
		)
		(property "Value" ""
			(at 0 0 180)
			(layer "F.Fab")
			(effects
				(font
					(size 1.27 1.27)
				)
			)
		)
		(duplicate_pad_numbers_are_jumpers no)
		(fp_line
			(start 0.7874 0.4064)
			(end -0.7874 0.4064)
			(stroke
				(width 0.1524)
				(type default)
			)
			(layer "F.SilkS")
		)
		(fp_line
			(start 0.7874 -0.4064)
			(end 0.7874 0.4064)
			(stroke
				(width 0.1524)
				(type default)
			)
			(layer "F.SilkS")
		)
		(fp_line
			(start -0.7874 0.4064)
			(end -0.7874 -0.4064)
			(stroke
				(width 0.1524)
				(type default)
			)
			(layer "F.SilkS")
		)
		(fp_line
			(start -0.7874 -0.4064)
			(end 0.7874 -0.4064)
			(stroke
				(width 0.1524)
				(type default)
			)
			(layer "F.SilkS")
		)
		(fp_line
			(start 0.67945 0.3048)
			(end 0.120396 0.3048)
			(stroke
				(width 0.1)
				(type default)
			)
			(layer "F.Fab")
		)
		(fp_line
			(start 0.67945 -0.3048)
			(end 0.67945 0.3048)
			(stroke
				(width 0.1)
				(type default)
			)
			(layer "F.Fab")
		)
		(fp_line
			(start 0.12065 -0.2794)
			(end 0.12065 -0.3048)
			(stroke
				(width 0.1)
				(type default)
			)
			(layer "F.Fab")
		)
		(fp_line
			(start 0.12065 -0.3048)
			(end 0.67945 -0.3048)
			(stroke
				(width 0.1)
				(type default)
			)
			(layer "F.Fab")
		)
		(fp_line
			(start 0.120396 0.3048)
			(end 0.120396 0.2794)
			(stroke
				(width 0.1)
				(type default)
			)
			(layer "F.Fab")
		)
		(fp_line
			(start 0.120396 0.2794)
			(end -0.12065 0.2794)
			(stroke
				(width 0.1)
				(type default)
			)
			(layer "F.Fab")
		)
		(fp_line
			(start -0.12065 0.3048)
			(end -0.67945 0.3048)
			(stroke
				(width 0.1)
				(type default)
			)
			(layer "F.Fab")
		)
		(fp_line
			(start -0.12065 0.2794)
			(end -0.12065 0.3048)
			(stroke
				(width 0.1)
				(type default)
			)
			(layer "F.Fab")
		)
		(fp_line
			(start -0.12065 -0.2794)
			(end 0.12065 -0.2794)
			(stroke
				(width 0.1)
				(type default)
			)
			(layer "F.Fab")
		)
		(fp_line
			(start -0.12065 -0.305054)
			(end -0.12065 -0.2794)
			(stroke
				(width 0.1)
				(type default)
			)
			(layer "F.Fab")
		)
		(fp_line
			(start -0.67945 0.3048)
			(end -0.67945 -0.305054)
			(stroke
				(width 0.1)
				(type default)
			)
			(layer "F.Fab")
		)
		(fp_line
			(start -0.67945 -0.305054)
			(end -0.12065 -0.305054)
			(stroke
				(width 0.1)
				(type default)
			)
			(layer "F.Fab")
		)
		(pad "1" smd circle
			(at -0.40005 0 180)
			(size 0 0)
			(layers "F.Cu" "F.Mask" "F.Paste")
			(net "P3V3_NIC0_OCP")
		)
		(pad "2" smd circle
			(at 0.40005 0 180)
			(size 0 0)
			(layers "F.Cu" "F.Mask" "F.Paste")
			(net "GND")
		)
	)
	(footprint ""
		(layer "F.Cu")
		(at 310.659272 -22.955504 90)
		(property "Reference" "R1713"
			(at 0 0 90)
			(layer "F.SilkS")
			(hide yes)
			(effects
				(font
					(size 1.27 1.27)
				)
			)
		)
		(property "Value" ""
			(at 0 0 90)
			(layer "F.Fab")
			(effects
				(font
					(size 1.27 1.27)
				)
			)
		)
		(duplicate_pad_numbers_are_jumpers no)
		(fp_line
			(start 0.7874 -0.4064)
			(end 0.7874 0.4064)
			(stroke
				(width 0.1524)
				(type default)
			)
			(layer "F.SilkS")
		)
		(fp_line
			(start -0.7874 -0.4064)
			(end 0.7874 -0.4064)
			(stroke
				(width 0.1524)
				(type default)
			)
			(layer "F.SilkS")
		)
		(fp_line
			(start 0.7874 0.4064)
			(end -0.7874 0.4064)
			(stroke
				(width 0.1524)
				(type default)
			)
			(layer "F.SilkS")
		)
		(fp_line
			(start -0.7874 0.4064)
			(end -0.7874 -0.4064)
			(stroke
				(width 0.1524)
				(type default)
			)
			(layer "F.SilkS")
		)
		(fp_line
			(start -0.12065 -0.305054)
			(end -0.12065 -0.2794)
			(stroke
				(width 0.1)
				(type default)
			)
			(layer "F.Fab")
		)
		(fp_line
			(start -0.67945 -0.305054)
			(end -0.12065 -0.305054)
			(stroke
				(width 0.1)
				(type default)
			)
			(layer "F.Fab")
		)
		(fp_line
			(start 0.67945 -0.3048)
			(end 0.67945 0.3048)
			(stroke
				(width 0.1)
				(type default)
			)
			(layer "F.Fab")
		)
		(fp_line
			(start 0.12065 -0.3048)
			(end 0.67945 -0.3048)
			(stroke
				(width 0.1)
				(type default)
			)
			(layer "F.Fab")
		)
		(fp_line
			(start 0.12065 -0.2794)
			(end 0.12065 -0.3048)
			(stroke
				(width 0.1)
				(type default)
			)
			(layer "F.Fab")
		)
		(fp_line
			(start -0.12065 -0.2794)
			(end 0.12065 -0.2794)
			(stroke
				(width 0.1)
				(type default)
			)
			(layer "F.Fab")
		)
		(fp_line
			(start 0.120396 0.2794)
			(end -0.12065 0.2794)
			(stroke
				(width 0.1)
				(type default)
			)
			(layer "F.Fab")
		)
		(fp_line
			(start -0.12065 0.2794)
			(end -0.12065 0.3048)
			(stroke
				(width 0.1)
				(type default)
			)
			(layer "F.Fab")
		)
		(fp_line
			(start 0.67945 0.3048)
			(end 0.120396 0.3048)
			(stroke
				(width 0.1)
				(type default)
			)
			(layer "F.Fab")
		)
		(fp_line
			(start 0.120396 0.3048)
			(end 0.120396 0.2794)
			(stroke
				(width 0.1)
				(type default)
			)
			(layer "F.Fab")
		)
		(fp_line
			(start -0.12065 0.3048)
			(end -0.67945 0.3048)
			(stroke
				(width 0.1)
				(type default)
			)
			(layer "F.Fab")
		)
		(fp_line
			(start -0.67945 0.3048)
			(end -0.67945 -0.305054)
			(stroke
				(width 0.1)
				(type default)
			)
			(layer "F.Fab")
		)
		(pad "1" smd circle
			(at -0.40005 0 90)
			(size 0 0)
			(layers "F.Cu" "F.Mask" "F.Paste")
			(net "SMB_BIC_I2C9_MUX1_SSD10_R_SCL")
		)
		(pad "2" smd circle
			(at 0.40005 0 90)
			(size 0 0)
			(layers "F.Cu" "F.Mask" "F.Paste")
			(net "SMB_ISO_SSD10_SCL")
		)
	)
	(footprint ""
		(layer "F.Cu")
		(at 50.396648 -350.098614 90)
		(property "Reference" "C161"
			(at 0 0 90)
			(layer "F.SilkS")
			(hide yes)
			(effects
				(font
					(size 1.27 1.27)
				)
			)
		)
		(property "Value" ""
			(at 0 0 90)
			(layer "F.Fab")
			(effects
				(font
					(size 1.27 1.27)
				)
			)
		)
		(duplicate_pad_numbers_are_jumpers no)
		(fp_line
			(start 0.299974 -0.150114)
			(end 0.299974 0.150114)
			(stroke
				(width 0.1)
				(type default)
			)
			(layer "F.Fab")
		)
		(fp_line
			(start -0.299974 -0.150114)
			(end 0.299974 -0.150114)
			(stroke
				(width 0.1)
				(type default)
			)
			(layer "F.Fab")
		)
		(fp_line
			(start 0.299974 0.150114)
			(end -0.299974 0.150114)
			(stroke
				(width 0.1)
				(type default)
			)
			(layer "F.Fab")
		)
		(fp_line
			(start -0.299974 0.150114)
			(end -0.299974 -0.150114)
			(stroke
				(width 0.1)
				(type default)
			)
			(layer "F.Fab")
		)
		(pad "1" smd rect
			(at -0.2667 0 90)
			(size 0.3048 0.381)
			(layers "F.Cu" "F.Mask" "F.Paste")
			(net "P5E_PEX0_STN7_TX_DP<127>")
		)
		(pad "2" smd rect
			(at 0.2667 0 90)
			(size 0.3048 0.381)
			(layers "F.Cu" "F.Mask" "F.Paste")
			(net "P5E_PEX0_STN7_TX_C_DP<127>")
		)
	)
	(footprint ""
		(layer "F.Cu")
		(at 108.839 -85.979)
		(property "Reference" "U115"
			(at -3.7846 -4.03733 0)
			(unlocked yes)
			(layer "F.SilkS")
			(effects
				(font
					(size 0.7874 0.5842)
					(thickness 0.1524)
				)
				(justify left)
			)
		)
		(property "Value" ""
			(at 0 0 0)
			(layer "F.Fab")
			(effects
				(font
					(size 1.27 1.27)
				)
			)
		)
		(duplicate_pad_numbers_are_jumpers no)
		(fp_line
			(start -2.999994 -2.999994)
			(end -2.999994 -2.4384)
			(stroke
				(width 0.1524)
				(type default)
			)
			(layer "F.SilkS")
		)
		(fp_line
			(start -2.999994 2.4384)
			(end -2.999994 2.999994)
			(stroke
				(width 0.1524)
				(type default)
			)
			(layer "F.SilkS")
		)
		(fp_line
			(start -2.999994 2.999994)
			(end -2.4384 2.999994)
			(stroke
				(width 0.1524)
				(type default)
			)
			(layer "F.SilkS")
		)
		(fp_line
			(start -2.4384 -2.999994)
			(end -2.999994 -2.999994)
			(stroke
				(width 0.1524)
				(type default)
			)
			(layer "F.SilkS")
		)
		(fp_line
			(start 2.4384 2.999994)
			(end 2.999994 2.999994)
			(stroke
				(width 0.1524)
				(type default)
			)
			(layer "F.SilkS")
		)
		(fp_line
			(start 2.999994 -2.999994)
			(end 2.4384 -2.999994)
			(stroke
				(width 0.1524)
				(type default)
			)
			(layer "F.SilkS")
		)
		(fp_line
			(start 2.999994 -2.4384)
			(end 2.999994 -2.999994)
			(stroke
				(width 0.1524)
				(type default)
			)
			(layer "F.SilkS")
		)
		(fp_line
			(start 2.999994 2.999994)
			(end 2.999994 2.4384)
			(stroke
				(width 0.1524)
				(type default)
			)
			(layer "F.SilkS")
		)
		(fp_poly
			(pts
				(xy -4.318 -1.815338) (xy -4.318 -2.584704) (xy -3.548634 -2.199894)
			)
			(stroke
				(width 0)
				(type default)
			)
			(fill yes)
			(layer "F.SilkS")
		)
		(fp_line
			(start -2.999994 -2.999994)
			(end -2.999994 2.999994)
			(stroke
				(width 0.1)
				(type default)
			)
			(layer "F.Fab")
		)
		(fp_line
			(start -2.999994 2.999994)
			(end 2.999994 2.999994)
			(stroke
				(width 0.1)
				(type default)
			)
			(layer "F.Fab")
		)
		(fp_line
			(start 2.999994 -2.999994)
			(end -2.999994 -2.999994)
			(stroke
				(width 0.1)
				(type default)
			)
			(layer "F.Fab")
		)
		(fp_line
			(start 2.999994 2.999994)
			(end 2.999994 -2.999994)
			(stroke
				(width 0.1)
				(type default)
			)
			(layer "F.Fab")
		)
		(fp_poly
			(pts
				(xy -4.318 -1.815338) (xy -4.318 -2.584704) (xy -3.548634 -2.199894)
			)
			(stroke
				(width 0)
				(type default)
			)
			(fill yes)
			(layer "F.Fab")
		)
		(pad "1" smd circle
			(at -2.949956 -2.199894 270)
			(size 0 0)
			(layers "F.Cu" "F.Mask" "F.Paste")
			(net "FM_CLK_EN_R")
		)
		(pad "2" smd circle
			(at -2.949956 -1.800098 270)
			(size 0 0)
			(layers "F.Cu" "F.Mask" "F.Paste")
			(net "GND")
		)
		(pad "3" smd circle
			(at -2.949956 -1.400048 270)
			(size 0 0)
			(layers "F.Cu" "F.Mask" "F.Paste")
			(net "P3V3_VDDAR_9ZXL0851_0_7")
		)
		(pad "4" smd circle
			(at -2.949956 -0.999998 270)
			(size 0 0)
			(layers "F.Cu" "F.Mask" "F.Paste")
			(net "CLK_100M_CK440Q_1_DB800ZL_R_DP")
		)
		(pad "5" smd circle
			(at -2.949956 -0.599948 270)
			(size 0 0)
			(layers "F.Cu" "F.Mask" "F.Paste")
			(net "CLK_100M_CK440Q_1_DB800ZL_R_DN")
		)
		(pad "6" smd circle
			(at -2.949956 -0.199898 270)
			(size 0 0)
			(layers "F.Cu" "F.Mask" "F.Paste")
			(net "SMB_BMC_9ZXL0851_0_7_SDA")
		)
		(pad "7" smd circle
			(at -2.949956 0.199898 270)
			(size 0 0)
			(layers "F.Cu" "F.Mask" "F.Paste")
			(net "SMB_BMC_9ZXL0851_0_7_SCL")
		)
		(pad "8" smd circle
			(at -2.949956 0.599948 270)
			(size 0 0)
			(layers "F.Cu" "F.Mask" "F.Paste")
			(net "Net_4340")
		)
		(pad "9" smd circle
			(at -2.949956 0.999998 270)
			(size 0 0)
			(layers "F.Cu" "F.Mask" "F.Paste")
			(net "Net_4339")
		)
		(pad "10" smd circle
			(at -2.949956 1.400048 270)
			(size 0 0)
			(layers "F.Cu" "F.Mask" "F.Paste")
			(net "P3V3_VDD_9ZXL0851_0_7")
		)
		(pad "11" smd circle
			(at -2.949956 1.800098 270)
			(size 0 0)
			(layers "F.Cu" "F.Mask" "F.Paste")
			(net "SSD0_CLK_EN_R_N")
		)
		(pad "12" smd circle
			(at -2.949956 2.199894 270)
			(size 0 0)
			(layers "F.Cu" "F.Mask" "F.Paste")
			(net "Net_4341")
		)
		(pad "13" smd circle
			(at -2.199894 2.949956)
			(size 0 0)
			(layers "F.Cu" "F.Mask" "F.Paste")
			(net "CLK_100M_DB800ZL_SSD0_DP")
		)
		(pad "14" smd circle
			(at -1.800098 2.949956)
			(size 0 0)
			(layers "F.Cu" "F.Mask" "F.Paste")
			(net "CLK_100M_DB800ZL_SSD0_DN")
		)
		(pad "15" smd circle
			(at -1.400048 2.949956)
			(size 0 0)
			(layers "F.Cu" "F.Mask" "F.Paste")
			(net "P3V3_VDD_9ZXL0851_0_7")
		)
		(pad "16" smd circle
			(at -0.999998 2.949956)
			(size 0 0)
			(layers "F.Cu" "F.Mask" "F.Paste")
			(net "CLK_100M_DB800ZL_SSD1_DP")
		)
		(pad "17" smd circle
			(at -0.599948 2.949956)
			(size 0 0)
			(layers "F.Cu" "F.Mask" "F.Paste")
			(net "CLK_100M_DB800ZL_SSD1_DN")
		)
		(pad "18" smd circle
			(at -0.199898 2.949956)
			(size 0 0)
			(layers "F.Cu" "F.Mask" "F.Paste")
			(net "SSD1_CLK_EN_R_N")
		)
		(pad "19" smd circle
			(at 0.199898 2.949956)
			(size 0 0)
			(layers "F.Cu" "F.Mask" "F.Paste")
			(net "P3V3_VDD_9ZXL0851_0_7")
		)
		(pad "20" smd circle
			(at 0.599948 2.949956)
			(size 0 0)
			(layers "F.Cu" "F.Mask" "F.Paste")
			(net "Net_4342")
		)
		(pad "21" smd circle
			(at 0.999998 2.949956)
			(size 0 0)
			(layers "F.Cu" "F.Mask" "F.Paste")
			(net "CLK_100M_DB800ZL_SSD2_DP")
		)
		(pad "22" smd circle
			(at 1.400048 2.949956)
			(size 0 0)
			(layers "F.Cu" "F.Mask" "F.Paste")
			(net "CLK_100M_DB800ZL_SSD2_DN")
		)
		(pad "23" smd circle
			(at 1.800098 2.949956)
			(size 0 0)
			(layers "F.Cu" "F.Mask" "F.Paste")
			(net "SSD2_CLK_EN_R_N")
		)
		(pad "24" smd circle
			(at 2.199894 2.949956)
			(size 0 0)
			(layers "F.Cu" "F.Mask" "F.Paste")
			(net "SSD3_CLK_EN_R_N")
		)
		(pad "25" smd circle
			(at 2.949956 2.199894 90)
			(size 0 0)
			(layers "F.Cu" "F.Mask" "F.Paste")
			(net "CLK_100M_DB800ZL_SSD3_DP")
		)
		(pad "26" smd circle
			(at 2.949956 1.800098 90)
			(size 0 0)
			(layers "F.Cu" "F.Mask" "F.Paste")
			(net "CLK_100M_DB800ZL_SSD3_DN")
		)
		(pad "27" smd circle
			(at 2.949956 1.400048 90)
			(size 0 0)
			(layers "F.Cu" "F.Mask" "F.Paste")
			(net "P3V3_VDD_9ZXL0851_0_7")
		)
		(pad "28" smd circle
			(at 2.949956 0.999998 90)
			(size 0 0)
			(layers "F.Cu" "F.Mask" "F.Paste")
			(net "CLK_100M_DB800ZL_SSD4_DP")
		)
		(pad "29" smd circle
			(at 2.949956 0.599948 90)
			(size 0 0)
			(layers "F.Cu" "F.Mask" "F.Paste")
			(net "CLK_100M_DB800ZL_SSD4_DN")
		)
		(pad "30" smd circle
			(at 2.949956 0.199898 90)
			(size 0 0)
			(layers "F.Cu" "F.Mask" "F.Paste")
			(net "SSD4_CLK_EN_R_N")
		)
		(pad "31" smd circle
			(at 2.949956 -0.199898 90)
			(size 0 0)
			(layers "F.Cu" "F.Mask" "F.Paste")
			(net "SSD5_CLK_EN_R_N")
		)
		(pad "32" smd circle
			(at 2.949956 -0.599948 90)
			(size 0 0)
			(layers "F.Cu" "F.Mask" "F.Paste")
			(net "CLK_100M_DB800ZL_SSD5_DP")
		)
		(pad "33" smd circle
			(at 2.949956 -0.999998 90)
			(size 0 0)
			(layers "F.Cu" "F.Mask" "F.Paste")
			(net "CLK_100M_DB800ZL_SSD5_DN")
		)
		(pad "34" smd circle
			(at 2.949956 -1.400048 90)
			(size 0 0)
			(layers "F.Cu" "F.Mask" "F.Paste")
			(net "P3V3_VDD_9ZXL0851_0_7")
		)
		(pad "35" smd circle
			(at 2.949956 -1.800098 90)
			(size 0 0)
			(layers "F.Cu" "F.Mask" "F.Paste")
			(net "CLK_100M_DB800ZL_SSD6_DP")
		)
		(pad "36" smd circle
			(at 2.949956 -2.199894 90)
			(size 0 0)
			(layers "F.Cu" "F.Mask" "F.Paste")
			(net "CLK_100M_DB800ZL_SSD6_DN")
		)
		(pad "37" smd circle
			(at 2.199894 -2.949956 180)
			(size 0 0)
			(layers "F.Cu" "F.Mask" "F.Paste")
			(net "SSD6_CLK_EN_R_N")
		)
		(pad "38" smd circle
			(at 1.800098 -2.949956 180)
			(size 0 0)
			(layers "F.Cu" "F.Mask" "F.Paste")
			(net "P3V3_VDD_9ZXL0851_0_7")
		)
		(pad "39" smd circle
			(at 1.400048 -2.949956 180)
			(size 0 0)
			(layers "F.Cu" "F.Mask" "F.Paste")
			(net "CLK_100M_DB800ZL_SSD7_DP")
		)
		(pad "40" smd circle
			(at 0.999998 -2.949956 180)
			(size 0 0)
			(layers "F.Cu" "F.Mask" "F.Paste")
			(net "CLK_100M_DB800ZL_SSD7_DN")
		)
		(pad "41" smd circle
			(at 0.599948 -2.949956 180)
			(size 0 0)
			(layers "F.Cu" "F.Mask" "F.Paste")
			(net "SSD7_CLK_EN_R_N")
		)
		(pad "42" smd circle
			(at 0.199898 -2.949956 180)
			(size 0 0)
			(layers "F.Cu" "F.Mask" "F.Paste")
			(net "P3V3_VDD_9ZXL0851_0_7")
		)
		(pad "43" smd circle
			(at -0.199898 -2.949956 180)
			(size 0 0)
			(layers "F.Cu" "F.Mask" "F.Paste")
			(net "Net_4343")
		)
		(pad "44" smd circle
			(at -0.599948 -2.949956 180)
			(size 0 0)
			(layers "F.Cu" "F.Mask" "F.Paste")
			(net "P3V3_VDDAR_9ZXL0851_0_7")
		)
		(pad "45" smd circle
			(at -0.999998 -2.949956 180)
			(size 0 0)
			(layers "F.Cu" "F.Mask" "F.Paste")
			(net "Net_4344")
		)
		(pad "46" smd circle
			(at -1.400048 -2.949956 180)
			(size 0 0)
			(layers "F.Cu" "F.Mask" "F.Paste")
			(net "Net_4345")
		)
		(pad "47" smd circle
			(at -1.800098 -2.949956 180)
			(size 0 0)
			(layers "F.Cu" "F.Mask" "F.Paste")
			(net "PU_9ZXL0851_0_7_100M")
		)
		(pad "48" smd circle
			(at -2.199894 -2.949956 180)
			(size 0 0)
			(layers "F.Cu" "F.Mask" "F.Paste")
			(net "PU_9ZXL0851_0_7_HBW")
		)
		(pad "49" smd rect
			(at 0 0)
			(size 4.2164 4.2164)
			(layers "F.Cu" "F.Mask" "F.Paste")
			(net "GND")
		)
		(zone
			(layer "F.Cu")
			(hatch none 0.5)
			(connect_pads
				(clearance 0)
			)
			(min_thickness 0.25)
			(keepout
				(tracks not_allowed)
				(vias allowed)
				(pads allowed)
				(copperpour not_allowed)
				(footprints allowed)
			)
			(placement
				(enabled no)
				(sheetname "")
			)
			(fill
				(thermal_gap 0.5)
				(thermal_bridge_width 0.5)
				(island_removal_mode 0)
			)
			(polygon
				(pts
					(xy 106.3752 -86.9442) (xy 106.3752 -83.5152) (xy 111.3028 -83.5152) (xy 111.3028 -88.4428) (xy 106.3752 -88.4428)
					(xy 106.3752 -86.9696) (xy 106.68 -86.9696) (xy 106.68 -88.138) (xy 110.998 -88.138) (xy 110.998 -83.82)
					(xy 106.68 -83.82) (xy 106.68 -86.9442)
				)
			)
		)
	)
	(footprint ""
		(layer "F.Cu")
		(at 145.593562 -237.971838 -90)
		(property "Reference" "C4419"
			(at 0 0 270)
			(layer "F.SilkS")
			(hide yes)
			(effects
				(font
					(size 1.27 1.27)
				)
			)
		)
		(property "Value" ""
			(at 0 0 270)
			(layer "F.Fab")
			(effects
				(font
					(size 1.27 1.27)
				)
			)
		)
		(duplicate_pad_numbers_are_jumpers no)
		(fp_line
			(start -0.7874 0.4064)
			(end -0.7874 -0.4064)
			(stroke
				(width 0.1524)
				(type default)
			)
			(layer "F.SilkS")
		)
		(fp_line
			(start 0.7874 0.4064)
			(end -0.7874 0.4064)
			(stroke
				(width 0.1524)
				(type default)
			)
			(layer "F.SilkS")
		)
		(fp_line
			(start -0.7874 -0.4064)
			(end 0.7874 -0.4064)
			(stroke
				(width 0.1524)
				(type default)
			)
			(layer "F.SilkS")
		)
		(fp_line
			(start 0.7874 -0.4064)
			(end 0.7874 0.4064)
			(stroke
				(width 0.1524)
				(type default)
			)
			(layer "F.SilkS")
		)
		(fp_line
			(start -0.67945 0.3048)
			(end -0.67945 -0.305054)
			(stroke
				(width 0.1)
				(type default)
			)
			(layer "F.Fab")
		)
		(fp_line
			(start -0.12065 0.3048)
			(end -0.67945 0.3048)
			(stroke
				(width 0.1)
				(type default)
			)
			(layer "F.Fab")
		)
		(fp_line
			(start 0.120396 0.3048)
			(end 0.120396 0.2794)
			(stroke
				(width 0.1)
				(type default)
			)
			(layer "F.Fab")
		)
		(fp_line
			(start 0.67945 0.3048)
			(end 0.120396 0.3048)
			(stroke
				(width 0.1)
				(type default)
			)
			(layer "F.Fab")
		)
		(fp_line
			(start -0.12065 0.2794)
			(end -0.12065 0.3048)
			(stroke
				(width 0.1)
				(type default)
			)
			(layer "F.Fab")
		)
		(fp_line
			(start 0.120396 0.2794)
			(end -0.12065 0.2794)
			(stroke
				(width 0.1)
				(type default)
			)
			(layer "F.Fab")
		)
		(fp_line
			(start -0.12065 -0.2794)
			(end 0.12065 -0.2794)
			(stroke
				(width 0.1)
				(type default)
			)
			(layer "F.Fab")
		)
		(fp_line
			(start 0.12065 -0.2794)
			(end 0.12065 -0.3048)
			(stroke
				(width 0.1)
				(type default)
			)
			(layer "F.Fab")
		)
		(fp_line
			(start 0.12065 -0.3048)
			(end 0.67945 -0.3048)
			(stroke
				(width 0.1)
				(type default)
			)
			(layer "F.Fab")
		)
		(fp_line
			(start 0.67945 -0.3048)
			(end 0.67945 0.3048)
			(stroke
				(width 0.1)
				(type default)
			)
			(layer "F.Fab")
		)
		(fp_line
			(start -0.67945 -0.305054)
			(end -0.12065 -0.305054)
			(stroke
				(width 0.1)
				(type default)
			)
			(layer "F.Fab")
		)
		(fp_line
			(start -0.12065 -0.305054)
			(end -0.12065 -0.2794)
			(stroke
				(width 0.1)
				(type default)
			)
			(layer "F.Fab")
		)
		(pad "1" smd circle
			(at -0.40005 0 270)
			(size 0 0)
			(layers "F.Cu" "F.Mask" "F.Paste")
			(net "P5V_AUX")
		)
		(pad "2" smd circle
			(at 0.40005 0 270)
			(size 0 0)
			(layers "F.Cu" "F.Mask" "F.Paste")
			(net "GND")
		)
	)
	(footprint ""
		(layer "F.Cu")
		(at 232.784142 -29.222954 -90)
		(property "Reference" "PC938"
			(at 0 0 270)
			(layer "F.SilkS")
			(hide yes)
			(effects
				(font
					(size 1.27 1.27)
				)
			)
		)
		(property "Value" ""
			(at 0 0 270)
			(layer "F.Fab")
			(effects
				(font
					(size 1.27 1.27)
				)
			)
		)
		(duplicate_pad_numbers_are_jumpers no)
		(fp_line
			(start -0.7874 0.4064)
			(end -0.7874 -0.4064)
			(stroke
				(width 0.1524)
				(type default)
			)
			(layer "F.SilkS")
		)
		(fp_line
			(start 0.7874 0.4064)
			(end -0.7874 0.4064)
			(stroke
				(width 0.1524)
				(type default)
			)
			(layer "F.SilkS")
		)
		(fp_line
			(start -0.7874 -0.4064)
			(end 0.7874 -0.4064)
			(stroke
				(width 0.1524)
				(type default)
			)
			(layer "F.SilkS")
		)
		(fp_line
			(start 0.7874 -0.4064)
			(end 0.7874 0.4064)
			(stroke
				(width 0.1524)
				(type default)
			)
			(layer "F.SilkS")
		)
		(fp_line
			(start -0.67945 0.3048)
			(end -0.67945 -0.305054)
			(stroke
				(width 0.1)
				(type default)
			)
			(layer "F.Fab")
		)
		(fp_line
			(start -0.12065 0.3048)
			(end -0.67945 0.3048)
			(stroke
				(width 0.1)
				(type default)
			)
			(layer "F.Fab")
		)
		(fp_line
			(start 0.120396 0.3048)
			(end 0.120396 0.2794)
			(stroke
				(width 0.1)
				(type default)
			)
			(layer "F.Fab")
		)
		(fp_line
			(start 0.67945 0.3048)
			(end 0.120396 0.3048)
			(stroke
				(width 0.1)
				(type default)
			)
			(layer "F.Fab")
		)
		(fp_line
			(start -0.12065 0.2794)
			(end -0.12065 0.3048)
			(stroke
				(width 0.1)
				(type default)
			)
			(layer "F.Fab")
		)
		(fp_line
			(start 0.120396 0.2794)
			(end -0.12065 0.2794)
			(stroke
				(width 0.1)
				(type default)
			)
			(layer "F.Fab")
		)
		(fp_line
			(start -0.12065 -0.2794)
			(end 0.12065 -0.2794)
			(stroke
				(width 0.1)
				(type default)
			)
			(layer "F.Fab")
		)
		(fp_line
			(start 0.12065 -0.2794)
			(end 0.12065 -0.3048)
			(stroke
				(width 0.1)
				(type default)
			)
			(layer "F.Fab")
		)
		(fp_line
			(start 0.12065 -0.3048)
			(end 0.67945 -0.3048)
			(stroke
				(width 0.1)
				(type default)
			)
			(layer "F.Fab")
		)
		(fp_line
			(start 0.67945 -0.3048)
			(end 0.67945 0.3048)
			(stroke
				(width 0.1)
				(type default)
			)
			(layer "F.Fab")
		)
		(fp_line
			(start -0.67945 -0.305054)
			(end -0.12065 -0.305054)
			(stroke
				(width 0.1)
				(type default)
			)
			(layer "F.Fab")
		)
		(fp_line
			(start -0.12065 -0.305054)
			(end -0.12065 -0.2794)
			(stroke
				(width 0.1)
				(type default)
			)
			(layer "F.Fab")
		)
		(pad "1" smd circle
			(at -0.40005 0 270)
			(size 0 0)
			(layers "F.Cu" "F.Mask" "F.Paste")
			(net "P3V3_AUX")
		)
		(pad "2" smd circle
			(at 0.40005 0 270)
			(size 0 0)
			(layers "F.Cu" "F.Mask" "F.Paste")
			(net "GND")
		)
	)
	(footprint ""
		(layer "F.Cu")
		(at 480.844098 -550.674794 180)
		(property "Reference" "JPEX2_FW1"
			(at -4.0259 -1.402334 0)
			(unlocked yes)
			(layer "B.SilkS")
			(effects
				(font
					(size 0.7874 0.5842)
					(thickness 0.1524)
				)
				(justify mirror)
			)
		)
		(property "Value" ""
			(at 0 0 180)
			(layer "F.Fab")
			(effects
				(font
					(size 1.27 1.27)
				)
			)
		)
		(duplicate_pad_numbers_are_jumpers no)
		(pad "1" thru_hole circle
			(at 0 0 180)
			(size 0.4572 0.4572)
			(drill 0.2032)
			(layers "*.Cu" "*.Mask")
			(remove_unused_layers no)
			(net "Net_9088")
			(clearance 0.127)
			(thermal_gap 0.127)
			(padstack
				(mode front_inner_back)
				(layer "Inner"
					(shape circle)
					(size 0.4572 0.4572)
					(clearance 0.127)
				)
				(layer "B.Cu"
					(shape circle)
					(size 0.508 0.508)
					(clearance 0.1016)
				)
			)
		)
	)
	(footprint ""
		(layer "F.Cu")
		(at 369.011454 -9.955022)
		(property "Reference" "R5809"
			(at 0 0 0)
			(layer "F.SilkS")
			(hide yes)
			(effects
				(font
					(size 1.27 1.27)
				)
			)
		)
		(property "Value" ""
			(at 0 0 0)
			(layer "F.Fab")
			(effects
				(font
					(size 1.27 1.27)
				)
			)
		)
		(duplicate_pad_numbers_are_jumpers no)
		(fp_line
			(start -0.7874 -0.4064)
			(end 0.7874 -0.4064)
			(stroke
				(width 0.1524)
				(type default)
			)
			(layer "F.SilkS")
		)
		(fp_line
			(start -0.7874 0.4064)
			(end -0.7874 -0.4064)
			(stroke
				(width 0.1524)
				(type default)
			)
			(layer "F.SilkS")
		)
		(fp_line
			(start 0.7874 -0.4064)
			(end 0.7874 0.4064)
			(stroke
				(width 0.1524)
				(type default)
			)
			(layer "F.SilkS")
		)
		(fp_line
			(start 0.7874 0.4064)
			(end -0.7874 0.4064)
			(stroke
				(width 0.1524)
				(type default)
			)
			(layer "F.SilkS")
		)
		(fp_line
			(start -0.67945 -0.305054)
			(end -0.12065 -0.305054)
			(stroke
				(width 0.1)
				(type default)
			)
			(layer "F.Fab")
		)
		(fp_line
			(start -0.67945 0.3048)
			(end -0.67945 -0.305054)
			(stroke
				(width 0.1)
				(type default)
			)
			(layer "F.Fab")
		)
		(fp_line
			(start -0.12065 -0.305054)
			(end -0.12065 -0.2794)
			(stroke
				(width 0.1)
				(type default)
			)
			(layer "F.Fab")
		)
		(fp_line
			(start -0.12065 -0.2794)
			(end 0.12065 -0.2794)
			(stroke
				(width 0.1)
				(type default)
			)
			(layer "F.Fab")
		)
		(fp_line
			(start -0.12065 0.2794)
			(end -0.12065 0.3048)
			(stroke
				(width 0.1)
				(type default)
			)
			(layer "F.Fab")
		)
		(fp_line
			(start -0.12065 0.3048)
			(end -0.67945 0.3048)
			(stroke
				(width 0.1)
				(type default)
			)
			(layer "F.Fab")
		)
		(fp_line
			(start 0.120396 0.2794)
			(end -0.12065 0.2794)
			(stroke
				(width 0.1)
				(type default)
			)
			(layer "F.Fab")
		)
		(fp_line
			(start 0.120396 0.3048)
			(end 0.120396 0.2794)
			(stroke
				(width 0.1)
				(type default)
			)
			(layer "F.Fab")
		)
		(fp_line
			(start 0.12065 -0.3048)
			(end 0.67945 -0.3048)
			(stroke
				(width 0.1)
				(type default)
			)
			(layer "F.Fab")
		)
		(fp_line
			(start 0.12065 -0.2794)
			(end 0.12065 -0.3048)
			(stroke
				(width 0.1)
				(type default)
			)
			(layer "F.Fab")
		)
		(fp_line
			(start 0.67945 -0.3048)
			(end 0.67945 0.3048)
			(stroke
				(width 0.1)
				(type default)
			)
			(layer "F.Fab")
		)
		(fp_line
			(start 0.67945 0.3048)
			(end 0.120396 0.3048)
			(stroke
				(width 0.1)
				(type default)
			)
			(layer "F.Fab")
		)
		(pad "1" smd circle
			(at -0.40005 0)
			(size 0 0)
			(layers "F.Cu" "F.Mask" "F.Paste")
			(net "SMB_BIC_I2C6_MUX_THERMAL_R2_SCL")
		)
		(pad "2" smd circle
			(at 0.40005 0)
			(size 0 0)
			(layers "F.Cu" "F.Mask" "F.Paste")
			(net "SMB_LM75_2_SCL")
		)
	)
	(footprint ""
		(layer "F.Cu")
		(at 249.992388 -32.739584 180)
		(property "Reference" "C489"
			(at 0 0 180)
			(layer "F.SilkS")
			(hide yes)
			(effects
				(font
					(size 1.27 1.27)
				)
			)
		)
		(property "Value" ""
			(at 0 0 180)
			(layer "F.Fab")
			(effects
				(font
					(size 1.27 1.27)
				)
			)
		)
		(duplicate_pad_numbers_are_jumpers no)
		(fp_line
			(start 0.299974 0.150114)
			(end -0.299974 0.150114)
			(stroke
				(width 0.1)
				(type default)
			)
			(layer "F.Fab")
		)
		(fp_line
			(start 0.299974 -0.150114)
			(end 0.299974 0.150114)
			(stroke
				(width 0.1)
				(type default)
			)
			(layer "F.Fab")
		)
		(fp_line
			(start -0.299974 0.150114)
			(end -0.299974 -0.150114)
			(stroke
				(width 0.1)
				(type default)
			)
			(layer "F.Fab")
		)
		(fp_line
			(start -0.299974 -0.150114)
			(end 0.299974 -0.150114)
			(stroke
				(width 0.1)
				(type default)
			)
			(layer "F.Fab")
		)
		(pad "1" smd rect
			(at -0.2667 0 180)
			(size 0.3048 0.381)
			(layers "F.Cu" "F.Mask" "F.Paste")
			(net "P5E_PEX2_STN2_TX_DP<46>")
		)
		(pad "2" smd rect
			(at 0.2667 0 180)
			(size 0.3048 0.381)
			(layers "F.Cu" "F.Mask" "F.Paste")
			(net "P5E_PEX2_STN2_TX_C_DP<46>")
		)
	)
	(footprint ""
		(layer "F.Cu")
		(at 143.490442 -250.070874 -90)
		(property "Reference" "R1274"
			(at 0 0 270)
			(layer "F.SilkS")
			(hide yes)
			(effects
				(font
					(size 1.27 1.27)
				)
			)
		)
		(property "Value" ""
			(at 0 0 270)
			(layer "F.Fab")
			(effects
				(font
					(size 1.27 1.27)
				)
			)
		)
		(duplicate_pad_numbers_are_jumpers no)
		(fp_line
			(start -0.7874 0.4064)
			(end -0.7874 -0.4064)
			(stroke
				(width 0.1524)
				(type default)
			)
			(layer "F.SilkS")
		)
		(fp_line
			(start 0.7874 0.4064)
			(end -0.7874 0.4064)
			(stroke
				(width 0.1524)
				(type default)
			)
			(layer "F.SilkS")
		)
		(fp_line
			(start -0.7874 -0.4064)
			(end 0.7874 -0.4064)
			(stroke
				(width 0.1524)
				(type default)
			)
			(layer "F.SilkS")
		)
		(fp_line
			(start 0.7874 -0.4064)
			(end 0.7874 0.4064)
			(stroke
				(width 0.1524)
				(type default)
			)
			(layer "F.SilkS")
		)
		(fp_line
			(start -0.67945 0.3048)
			(end -0.67945 -0.305054)
			(stroke
				(width 0.1)
				(type default)
			)
			(layer "F.Fab")
		)
		(fp_line
			(start -0.12065 0.3048)
			(end -0.67945 0.3048)
			(stroke
				(width 0.1)
				(type default)
			)
			(layer "F.Fab")
		)
		(fp_line
			(start 0.120396 0.3048)
			(end 0.120396 0.2794)
			(stroke
				(width 0.1)
				(type default)
			)
			(layer "F.Fab")
		)
		(fp_line
			(start 0.67945 0.3048)
			(end 0.120396 0.3048)
			(stroke
				(width 0.1)
				(type default)
			)
			(layer "F.Fab")
		)
		(fp_line
			(start -0.12065 0.2794)
			(end -0.12065 0.3048)
			(stroke
				(width 0.1)
				(type default)
			)
			(layer "F.Fab")
		)
		(fp_line
			(start 0.120396 0.2794)
			(end -0.12065 0.2794)
			(stroke
				(width 0.1)
				(type default)
			)
			(layer "F.Fab")
		)
		(fp_line
			(start -0.12065 -0.2794)
			(end 0.12065 -0.2794)
			(stroke
				(width 0.1)
				(type default)
			)
			(layer "F.Fab")
		)
		(fp_line
			(start 0.12065 -0.2794)
			(end 0.12065 -0.3048)
			(stroke
				(width 0.1)
				(type default)
			)
			(layer "F.Fab")
		)
		(fp_line
			(start 0.12065 -0.3048)
			(end 0.67945 -0.3048)
			(stroke
				(width 0.1)
				(type default)
			)
			(layer "F.Fab")
		)
		(fp_line
			(start 0.67945 -0.3048)
			(end 0.67945 0.3048)
			(stroke
				(width 0.1)
				(type default)
			)
			(layer "F.Fab")
		)
		(fp_line
			(start -0.67945 -0.305054)
			(end -0.12065 -0.305054)
			(stroke
				(width 0.1)
				(type default)
			)
			(layer "F.Fab")
		)
		(fp_line
			(start -0.12065 -0.305054)
			(end -0.12065 -0.2794)
			(stroke
				(width 0.1)
				(type default)
			)
			(layer "F.Fab")
		)
		(pad "1" smd circle
			(at -0.40005 0 270)
			(size 0 0)
			(layers "F.Cu" "F.Mask" "F.Paste")
			(net "PEX1_MODE_SEL5")
		)
		(pad "2" smd circle
			(at 0.40005 0 270)
			(size 0 0)
			(layers "F.Cu" "F.Mask" "F.Paste")
			(net "P1V8_PEX")
		)
	)
	(footprint ""
		(layer "F.Cu")
		(at 108.496354 -79.822294 90)
		(property "Reference" "R1139"
			(at 0 0 90)
			(layer "F.SilkS")
			(hide yes)
			(effects
				(font
					(size 1.27 1.27)
				)
			)
		)
		(property "Value" ""
			(at 0 0 90)
			(layer "F.Fab")
			(effects
				(font
					(size 1.27 1.27)
				)
			)
		)
		(duplicate_pad_numbers_are_jumpers no)
		(fp_line
			(start 0.7874 0.4064)
			(end -0.7874 0.4064)
			(stroke
				(width 0.1524)
				(type default)
			)
			(layer "F.SilkS")
		)
		(fp_line
			(start -0.12065 -0.305054)
			(end -0.12065 -0.2794)
			(stroke
				(width 0.1)
				(type default)
			)
			(layer "F.Fab")
		)
		(fp_line
			(start -0.67945 -0.305054)
			(end -0.12065 -0.305054)
			(stroke
				(width 0.1)
				(type default)
			)
			(layer "F.Fab")
		)
		(fp_line
			(start 0.67945 -0.3048)
			(end 0.67945 0.3048)
			(stroke
				(width 0.1)
				(type default)
			)
			(layer "F.Fab")
		)
		(fp_line
			(start 0.12065 -0.3048)
			(end 0.67945 -0.3048)
			(stroke
				(width 0.1)
				(type default)
			)
			(layer "F.Fab")
		)
		(fp_line
			(start 0.12065 -0.2794)
			(end 0.12065 -0.3048)
			(stroke
				(width 0.1)
				(type default)
			)
			(layer "F.Fab")
		)
		(fp_line
			(start -0.12065 -0.2794)
			(end 0.12065 -0.2794)
			(stroke
				(width 0.1)
				(type default)
			)
			(layer "F.Fab")
		)
		(fp_line
			(start 0.120396 0.2794)
			(end -0.12065 0.2794)
			(stroke
				(width 0.1)
				(type default)
			)
			(layer "F.Fab")
		)
		(fp_line
			(start -0.12065 0.2794)
			(end -0.12065 0.3048)
			(stroke
				(width 0.1)
				(type default)
			)
			(layer "F.Fab")
		)
		(fp_line
			(start 0.67945 0.3048)
			(end 0.120396 0.3048)
			(stroke
				(width 0.1)
				(type default)
			)
			(layer "F.Fab")
		)
		(fp_line
			(start 0.120396 0.3048)
			(end 0.120396 0.2794)
			(stroke
				(width 0.1)
				(type default)
			)
			(layer "F.Fab")
		)
		(fp_line
			(start -0.12065 0.3048)
			(end -0.67945 0.3048)
			(stroke
				(width 0.1)
				(type default)
			)
			(layer "F.Fab")
		)
		(fp_line
			(start -0.67945 0.3048)
			(end -0.67945 -0.305054)
			(stroke
				(width 0.1)
				(type default)
			)
			(layer "F.Fab")
		)
		(pad "1" smd circle
			(at -0.40005 0 90)
			(size 0 0)
			(layers "F.Cu" "F.Mask" "F.Paste")
			(net "CLK_100M_DB800ZL_SSD1_R_DN")
		)
		(pad "2" smd circle
			(at 0.40005 0 90)
			(size 0 0)
			(layers "F.Cu" "F.Mask" "F.Paste")
			(net "CLK_100M_DB800ZL_SSD1_DN")
		)
	)
	(footprint ""
		(layer "F.Cu")
		(at 235.690664 -206.51216 -90)
		(property "Reference" "R5501"
			(at 0 0 270)
			(layer "F.SilkS")
			(hide yes)
			(effects
				(font
					(size 1.27 1.27)
				)
			)
		)
		(property "Value" ""
			(at 0 0 270)
			(layer "F.Fab")
			(effects
				(font
					(size 1.27 1.27)
				)
			)
		)
		(duplicate_pad_numbers_are_jumpers no)
		(fp_line
			(start -0.7874 0.4064)
			(end -0.7874 -0.4064)
			(stroke
				(width 0.1524)
				(type default)
			)
			(layer "F.SilkS")
		)
		(fp_line
			(start 0.7874 0.4064)
			(end -0.7874 0.4064)
			(stroke
				(width 0.1524)
				(type default)
			)
			(layer "F.SilkS")
		)
		(fp_line
			(start -0.7874 -0.4064)
			(end 0.7874 -0.4064)
			(stroke
				(width 0.1524)
				(type default)
			)
			(layer "F.SilkS")
		)
		(fp_line
			(start 0.7874 -0.4064)
			(end 0.7874 0.4064)
			(stroke
				(width 0.1524)
				(type default)
			)
			(layer "F.SilkS")
		)
		(fp_line
			(start -0.67945 0.3048)
			(end -0.67945 -0.305054)
			(stroke
				(width 0.1)
				(type default)
			)
			(layer "F.Fab")
		)
		(fp_line
			(start -0.12065 0.3048)
			(end -0.67945 0.3048)
			(stroke
				(width 0.1)
				(type default)
			)
			(layer "F.Fab")
		)
		(fp_line
			(start 0.120396 0.3048)
			(end 0.120396 0.2794)
			(stroke
				(width 0.1)
				(type default)
			)
			(layer "F.Fab")
		)
		(fp_line
			(start 0.67945 0.3048)
			(end 0.120396 0.3048)
			(stroke
				(width 0.1)
				(type default)
			)
			(layer "F.Fab")
		)
		(fp_line
			(start -0.12065 0.2794)
			(end -0.12065 0.3048)
			(stroke
				(width 0.1)
				(type default)
			)
			(layer "F.Fab")
		)
		(fp_line
			(start 0.120396 0.2794)
			(end -0.12065 0.2794)
			(stroke
				(width 0.1)
				(type default)
			)
			(layer "F.Fab")
		)
		(fp_line
			(start -0.12065 -0.2794)
			(end 0.12065 -0.2794)
			(stroke
				(width 0.1)
				(type default)
			)
			(layer "F.Fab")
		)
		(fp_line
			(start 0.12065 -0.2794)
			(end 0.12065 -0.3048)
			(stroke
				(width 0.1)
				(type default)
			)
			(layer "F.Fab")
		)
		(fp_line
			(start 0.12065 -0.3048)
			(end 0.67945 -0.3048)
			(stroke
				(width 0.1)
				(type default)
			)
			(layer "F.Fab")
		)
		(fp_line
			(start 0.67945 -0.3048)
			(end 0.67945 0.3048)
			(stroke
				(width 0.1)
				(type default)
			)
			(layer "F.Fab")
		)
		(fp_line
			(start -0.67945 -0.305054)
			(end -0.12065 -0.305054)
			(stroke
				(width 0.1)
				(type default)
			)
			(layer "F.Fab")
		)
		(fp_line
			(start -0.12065 -0.305054)
			(end -0.12065 -0.2794)
			(stroke
				(width 0.1)
				(type default)
			)
			(layer "F.Fab")
		)
		(pad "1" smd circle
			(at -0.40005 0 270)
			(size 0 0)
			(layers "F.Cu" "F.Mask" "F.Paste")
			(net "RST_BIC_EXTRST_N")
		)
		(pad "2" smd circle
			(at 0.40005 0 270)
			(size 0 0)
			(layers "F.Cu" "F.Mask" "F.Paste")
			(net "RST_BIC_SRST_BIC_N")
		)
	)
	(footprint ""
		(layer "F.Cu")
		(at 95.946976 -55.63489 90)
		(property "Reference" "PC393"
			(at 0 0 90)
			(layer "F.SilkS")
			(hide yes)
			(effects
				(font
					(size 1.27 1.27)
				)
			)
		)
		(property "Value" ""
			(at 0 0 90)
			(layer "F.Fab")
			(effects
				(font
					(size 1.27 1.27)
				)
			)
		)
		(duplicate_pad_numbers_are_jumpers no)
		(fp_line
			(start 1.524 -0.762)
			(end 1.524 0.762)
			(stroke
				(width 0.1524)
				(type default)
			)
			(layer "F.SilkS")
		)
		(fp_line
			(start -1.524 -0.762)
			(end 1.524 -0.762)
			(stroke
				(width 0.1524)
				(type default)
			)
			(layer "F.SilkS")
		)
		(fp_line
			(start 1.524 0.762)
			(end -1.524 0.762)
			(stroke
				(width 0.1524)
				(type default)
			)
			(layer "F.SilkS")
		)
		(fp_line
			(start -1.524 0.762)
			(end -1.524 -0.762)
			(stroke
				(width 0.1524)
				(type default)
			)
			(layer "F.SilkS")
		)
		(fp_line
			(start 1.1049 -0.724916)
			(end -1.1049 -0.724916)
			(stroke
				(width 0.1)
				(type default)
			)
			(layer "F.Fab")
		)
		(fp_line
			(start -1.1049 -0.724916)
			(end -1.1049 0.724916)
			(stroke
				(width 0.1)
				(type default)
			)
			(layer "F.Fab")
		)
		(fp_line
			(start 1.1049 0.724916)
			(end 1.1049 -0.724916)
			(stroke
				(width 0.1)
				(type default)
			)
			(layer "F.Fab")
		)
		(fp_line
			(start -1.1049 0.724916)
			(end 1.1049 0.724916)
			(stroke
				(width 0.1)
				(type default)
			)
			(layer "F.Fab")
		)
		(pad "1" smd rect
			(at -0.889 0 270)
			(size 1.016 1.27)
			(layers "F.Cu" "F.Mask" "F.Paste")
			(net "P12V_SSD3_R")
		)
		(pad "2" smd rect
			(at 0.889 0 270)
			(size 1.016 1.27)
			(layers "F.Cu" "F.Mask" "F.Paste")
			(net "GND")
		)
	)
	(footprint ""
		(layer "F.Cu")
		(at 255.856486 -17.419574 180)
		(property "Reference" "R1688"
			(at 0 0 180)
			(layer "F.SilkS")
			(hide yes)
			(effects
				(font
					(size 1.27 1.27)
				)
			)
		)
		(property "Value" ""
			(at 0 0 180)
			(layer "F.Fab")
			(effects
				(font
					(size 1.27 1.27)
				)
			)
		)
		(duplicate_pad_numbers_are_jumpers no)
		(fp_line
			(start 0.7874 0.4064)
			(end -0.7874 0.4064)
			(stroke
				(width 0.1524)
				(type default)
			)
			(layer "F.SilkS")
		)
		(fp_line
			(start 0.7874 -0.4064)
			(end 0.7874 0.4064)
			(stroke
				(width 0.1524)
				(type default)
			)
			(layer "F.SilkS")
		)
		(fp_line
			(start -0.7874 0.4064)
			(end -0.7874 -0.4064)
			(stroke
				(width 0.1524)
				(type default)
			)
			(layer "F.SilkS")
		)
		(fp_line
			(start -0.7874 -0.4064)
			(end 0.7874 -0.4064)
			(stroke
				(width 0.1524)
				(type default)
			)
			(layer "F.SilkS")
		)
		(fp_line
			(start 0.67945 0.3048)
			(end 0.120396 0.3048)
			(stroke
				(width 0.1)
				(type default)
			)
			(layer "F.Fab")
		)
		(fp_line
			(start 0.67945 -0.3048)
			(end 0.67945 0.3048)
			(stroke
				(width 0.1)
				(type default)
			)
			(layer "F.Fab")
		)
		(fp_line
			(start 0.12065 -0.2794)
			(end 0.12065 -0.3048)
			(stroke
				(width 0.1)
				(type default)
			)
			(layer "F.Fab")
		)
		(fp_line
			(start 0.12065 -0.3048)
			(end 0.67945 -0.3048)
			(stroke
				(width 0.1)
				(type default)
			)
			(layer "F.Fab")
		)
		(fp_line
			(start 0.120396 0.3048)
			(end 0.120396 0.2794)
			(stroke
				(width 0.1)
				(type default)
			)
			(layer "F.Fab")
		)
		(fp_line
			(start 0.120396 0.2794)
			(end -0.12065 0.2794)
			(stroke
				(width 0.1)
				(type default)
			)
			(layer "F.Fab")
		)
		(fp_line
			(start -0.12065 0.3048)
			(end -0.67945 0.3048)
			(stroke
				(width 0.1)
				(type default)
			)
			(layer "F.Fab")
		)
		(fp_line
			(start -0.12065 0.2794)
			(end -0.12065 0.3048)
			(stroke
				(width 0.1)
				(type default)
			)
			(layer "F.Fab")
		)
		(fp_line
			(start -0.12065 -0.2794)
			(end 0.12065 -0.2794)
			(stroke
				(width 0.1)
				(type default)
			)
			(layer "F.Fab")
		)
		(fp_line
			(start -0.12065 -0.305054)
			(end -0.12065 -0.2794)
			(stroke
				(width 0.1)
				(type default)
			)
			(layer "F.Fab")
		)
		(fp_line
			(start -0.67945 0.3048)
			(end -0.67945 -0.305054)
			(stroke
				(width 0.1)
				(type default)
			)
			(layer "F.Fab")
		)
		(fp_line
			(start -0.67945 -0.305054)
			(end -0.12065 -0.305054)
			(stroke
				(width 0.1)
				(type default)
			)
			(layer "F.Fab")
		)
		(pad "1" smd circle
			(at -0.40005 0 180)
			(size 0 0)
			(layers "F.Cu" "F.Mask" "F.Paste")
			(net "P3V3_SSD8")
		)
		(pad "2" smd circle
			(at 0.40005 0 180)
			(size 0 0)
			(layers "F.Cu" "F.Mask" "F.Paste")
			(net "SMB_ISO_SSD8_SCL")
		)
	)
	(footprint ""
		(layer "F.Cu")
		(at 206.117698 -304.036476 90)
		(property "Reference" "R1315"
			(at 0 0 90)
			(layer "F.SilkS")
			(hide yes)
			(effects
				(font
					(size 1.27 1.27)
				)
			)
		)
		(property "Value" ""
			(at 0 0 90)
			(layer "F.Fab")
			(effects
				(font
					(size 1.27 1.27)
				)
			)
		)
		(duplicate_pad_numbers_are_jumpers no)
		(fp_line
			(start 0.7874 -0.4064)
			(end 0.7874 0.4064)
			(stroke
				(width 0.1524)
				(type default)
			)
			(layer "F.SilkS")
		)
		(fp_line
			(start -0.7874 -0.4064)
			(end 0.7874 -0.4064)
			(stroke
				(width 0.1524)
				(type default)
			)
			(layer "F.SilkS")
		)
		(fp_line
			(start 0.7874 0.4064)
			(end -0.7874 0.4064)
			(stroke
				(width 0.1524)
				(type default)
			)
			(layer "F.SilkS")
		)
		(fp_line
			(start -0.7874 0.4064)
			(end -0.7874 -0.4064)
			(stroke
				(width 0.1524)
				(type default)
			)
			(layer "F.SilkS")
		)
		(fp_line
			(start -0.12065 -0.305054)
			(end -0.12065 -0.2794)
			(stroke
				(width 0.1)
				(type default)
			)
			(layer "F.Fab")
		)
		(fp_line
			(start -0.67945 -0.305054)
			(end -0.12065 -0.305054)
			(stroke
				(width 0.1)
				(type default)
			)
			(layer "F.Fab")
		)
		(fp_line
			(start 0.67945 -0.3048)
			(end 0.67945 0.3048)
			(stroke
				(width 0.1)
				(type default)
			)
			(layer "F.Fab")
		)
		(fp_line
			(start 0.12065 -0.3048)
			(end 0.67945 -0.3048)
			(stroke
				(width 0.1)
				(type default)
			)
			(layer "F.Fab")
		)
		(fp_line
			(start 0.12065 -0.2794)
			(end 0.12065 -0.3048)
			(stroke
				(width 0.1)
				(type default)
			)
			(layer "F.Fab")
		)
		(fp_line
			(start -0.12065 -0.2794)
			(end 0.12065 -0.2794)
			(stroke
				(width 0.1)
				(type default)
			)
			(layer "F.Fab")
		)
		(fp_line
			(start 0.120396 0.2794)
			(end -0.12065 0.2794)
			(stroke
				(width 0.1)
				(type default)
			)
			(layer "F.Fab")
		)
		(fp_line
			(start -0.12065 0.2794)
			(end -0.12065 0.3048)
			(stroke
				(width 0.1)
				(type default)
			)
			(layer "F.Fab")
		)
		(fp_line
			(start 0.67945 0.3048)
			(end 0.120396 0.3048)
			(stroke
				(width 0.1)
				(type default)
			)
			(layer "F.Fab")
		)
		(fp_line
			(start 0.120396 0.3048)
			(end 0.120396 0.2794)
			(stroke
				(width 0.1)
				(type default)
			)
			(layer "F.Fab")
		)
		(fp_line
			(start -0.12065 0.3048)
			(end -0.67945 0.3048)
			(stroke
				(width 0.1)
				(type default)
			)
			(layer "F.Fab")
		)
		(fp_line
			(start -0.67945 0.3048)
			(end -0.67945 -0.305054)
			(stroke
				(width 0.1)
				(type default)
			)
			(layer "F.Fab")
		)
		(pad "1" smd circle
			(at -0.40005 0 90)
			(size 0 0)
			(layers "F.Cu" "F.Mask" "F.Paste")
			(net "GND")
		)
		(pad "2" smd circle
			(at 0.40005 0 90)
			(size 0 0)
			(layers "F.Cu" "F.Mask" "F.Paste")
			(net "PEX1_SPARE3")
		)
	)
	(footprint ""
		(layer "F.Cu")
		(at 238.019336 -47.197264 180)
		(property "Reference" "PC549"
			(at 0 0 180)
			(layer "F.SilkS")
			(hide yes)
			(effects
				(font
					(size 1.27 1.27)
				)
			)
		)
		(property "Value" ""
			(at 0 0 180)
			(layer "F.Fab")
			(effects
				(font
					(size 1.27 1.27)
				)
			)
		)
		(duplicate_pad_numbers_are_jumpers no)
		(fp_line
			(start 1.524 0.762)
			(end -1.524 0.762)
			(stroke
				(width 0.1524)
				(type default)
			)
			(layer "F.SilkS")
		)
		(fp_line
			(start 1.524 -0.762)
			(end 1.524 0.762)
			(stroke
				(width 0.1524)
				(type default)
			)
			(layer "F.SilkS")
		)
		(fp_line
			(start -1.524 0.762)
			(end -1.524 -0.762)
			(stroke
				(width 0.1524)
				(type default)
			)
			(layer "F.SilkS")
		)
		(fp_line
			(start -1.524 -0.762)
			(end 1.524 -0.762)
			(stroke
				(width 0.1524)
				(type default)
			)
			(layer "F.SilkS")
		)
		(fp_line
			(start 1.1049 0.724916)
			(end 1.1049 -0.724916)
			(stroke
				(width 0.1)
				(type default)
			)
			(layer "F.Fab")
		)
		(fp_line
			(start 1.1049 -0.724916)
			(end -1.1049 -0.724916)
			(stroke
				(width 0.1)
				(type default)
			)
			(layer "F.Fab")
		)
		(fp_line
			(start -1.1049 0.724916)
			(end 1.1049 0.724916)
			(stroke
				(width 0.1)
				(type default)
			)
			(layer "F.Fab")
		)
		(fp_line
			(start -1.1049 -0.724916)
			(end -1.1049 0.724916)
			(stroke
				(width 0.1)
				(type default)
			)
			(layer "F.Fab")
		)
		(pad "1" smd rect
			(at -0.889 0)
			(size 1.016 1.27)
			(layers "F.Cu" "F.Mask" "F.Paste")
			(net "P3V3_SSD8")
		)
		(pad "2" smd rect
			(at 0.889 0)
			(size 1.016 1.27)
			(layers "F.Cu" "F.Mask" "F.Paste")
			(net "GND")
		)
	)
	(footprint ""
		(layer "F.Cu")
		(at 221.562422 -22.937216 90)
		(property "Reference" "R1684"
			(at 0 0 90)
			(layer "F.SilkS")
			(hide yes)
			(effects
				(font
					(size 1.27 1.27)
				)
			)
		)
		(property "Value" ""
			(at 0 0 90)
			(layer "F.Fab")
			(effects
				(font
					(size 1.27 1.27)
				)
			)
		)
		(duplicate_pad_numbers_are_jumpers no)
		(fp_line
			(start 0.7874 -0.4064)
			(end 0.7874 0.4064)
			(stroke
				(width 0.1524)
				(type default)
			)
			(layer "F.SilkS")
		)
		(fp_line
			(start -0.7874 -0.4064)
			(end 0.7874 -0.4064)
			(stroke
				(width 0.1524)
				(type default)
			)
			(layer "F.SilkS")
		)
		(fp_line
			(start 0.7874 0.4064)
			(end -0.7874 0.4064)
			(stroke
				(width 0.1524)
				(type default)
			)
			(layer "F.SilkS")
		)
		(fp_line
			(start -0.7874 0.4064)
			(end -0.7874 -0.4064)
			(stroke
				(width 0.1524)
				(type default)
			)
			(layer "F.SilkS")
		)
		(fp_line
			(start -0.12065 -0.305054)
			(end -0.12065 -0.2794)
			(stroke
				(width 0.1)
				(type default)
			)
			(layer "F.Fab")
		)
		(fp_line
			(start -0.67945 -0.305054)
			(end -0.12065 -0.305054)
			(stroke
				(width 0.1)
				(type default)
			)
			(layer "F.Fab")
		)
		(fp_line
			(start 0.67945 -0.3048)
			(end 0.67945 0.3048)
			(stroke
				(width 0.1)
				(type default)
			)
			(layer "F.Fab")
		)
		(fp_line
			(start 0.12065 -0.3048)
			(end 0.67945 -0.3048)
			(stroke
				(width 0.1)
				(type default)
			)
			(layer "F.Fab")
		)
		(fp_line
			(start 0.12065 -0.2794)
			(end 0.12065 -0.3048)
			(stroke
				(width 0.1)
				(type default)
			)
			(layer "F.Fab")
		)
		(fp_line
			(start -0.12065 -0.2794)
			(end 0.12065 -0.2794)
			(stroke
				(width 0.1)
				(type default)
			)
			(layer "F.Fab")
		)
		(fp_line
			(start 0.120396 0.2794)
			(end -0.12065 0.2794)
			(stroke
				(width 0.1)
				(type default)
			)
			(layer "F.Fab")
		)
		(fp_line
			(start -0.12065 0.2794)
			(end -0.12065 0.3048)
			(stroke
				(width 0.1)
				(type default)
			)
			(layer "F.Fab")
		)
		(fp_line
			(start 0.67945 0.3048)
			(end 0.120396 0.3048)
			(stroke
				(width 0.1)
				(type default)
			)
			(layer "F.Fab")
		)
		(fp_line
			(start 0.120396 0.3048)
			(end 0.120396 0.2794)
			(stroke
				(width 0.1)
				(type default)
			)
			(layer "F.Fab")
		)
		(fp_line
			(start -0.12065 0.3048)
			(end -0.67945 0.3048)
			(stroke
				(width 0.1)
				(type default)
			)
			(layer "F.Fab")
		)
		(fp_line
			(start -0.67945 0.3048)
			(end -0.67945 -0.305054)
			(stroke
				(width 0.1)
				(type default)
			)
			(layer "F.Fab")
		)
		(pad "1" smd circle
			(at -0.40005 0 90)
			(size 0 0)
			(layers "F.Cu" "F.Mask" "F.Paste")
			(net "SMB_BIC_I2C9_MUX0_SSD7_R_SDA")
		)
		(pad "2" smd circle
			(at 0.40005 0 90)
			(size 0 0)
			(layers "F.Cu" "F.Mask" "F.Paste")
			(net "SMB_ISO_SSD7_SDA")
		)
	)
	(footprint ""
		(layer "F.Cu")
		(at 269.204694 -140.85697 180)
		(property "Reference" "R237"
			(at 0 0 180)
			(layer "F.SilkS")
			(hide yes)
			(effects
				(font
					(size 1.27 1.27)
				)
			)
		)
		(property "Value" ""
			(at 0 0 180)
			(layer "F.Fab")
			(effects
				(font
					(size 1.27 1.27)
				)
			)
		)
		(duplicate_pad_numbers_are_jumpers no)
		(fp_line
			(start 0.7874 0.4064)
			(end -0.7874 0.4064)
			(stroke
				(width 0.1524)
				(type default)
			)
			(layer "F.SilkS")
		)
		(fp_line
			(start 0.7874 -0.4064)
			(end 0.7874 0.4064)
			(stroke
				(width 0.1524)
				(type default)
			)
			(layer "F.SilkS")
		)
		(fp_line
			(start -0.7874 0.4064)
			(end -0.7874 -0.4064)
			(stroke
				(width 0.1524)
				(type default)
			)
			(layer "F.SilkS")
		)
		(fp_line
			(start -0.7874 -0.4064)
			(end 0.7874 -0.4064)
			(stroke
				(width 0.1524)
				(type default)
			)
			(layer "F.SilkS")
		)
		(fp_line
			(start 0.67945 0.3048)
			(end 0.120396 0.3048)
			(stroke
				(width 0.1)
				(type default)
			)
			(layer "F.Fab")
		)
		(fp_line
			(start 0.67945 -0.3048)
			(end 0.67945 0.3048)
			(stroke
				(width 0.1)
				(type default)
			)
			(layer "F.Fab")
		)
		(fp_line
			(start 0.12065 -0.2794)
			(end 0.12065 -0.3048)
			(stroke
				(width 0.1)
				(type default)
			)
			(layer "F.Fab")
		)
		(fp_line
			(start 0.12065 -0.3048)
			(end 0.67945 -0.3048)
			(stroke
				(width 0.1)
				(type default)
			)
			(layer "F.Fab")
		)
		(fp_line
			(start 0.120396 0.3048)
			(end 0.120396 0.2794)
			(stroke
				(width 0.1)
				(type default)
			)
			(layer "F.Fab")
		)
		(fp_line
			(start 0.120396 0.2794)
			(end -0.12065 0.2794)
			(stroke
				(width 0.1)
				(type default)
			)
			(layer "F.Fab")
		)
		(fp_line
			(start -0.12065 0.3048)
			(end -0.67945 0.3048)
			(stroke
				(width 0.1)
				(type default)
			)
			(layer "F.Fab")
		)
		(fp_line
			(start -0.12065 0.2794)
			(end -0.12065 0.3048)
			(stroke
				(width 0.1)
				(type default)
			)
			(layer "F.Fab")
		)
		(fp_line
			(start -0.12065 -0.2794)
			(end 0.12065 -0.2794)
			(stroke
				(width 0.1)
				(type default)
			)
			(layer "F.Fab")
		)
		(fp_line
			(start -0.12065 -0.305054)
			(end -0.12065 -0.2794)
			(stroke
				(width 0.1)
				(type default)
			)
			(layer "F.Fab")
		)
		(fp_line
			(start -0.67945 0.3048)
			(end -0.67945 -0.305054)
			(stroke
				(width 0.1)
				(type default)
			)
			(layer "F.Fab")
		)
		(fp_line
			(start -0.67945 -0.305054)
			(end -0.12065 -0.305054)
			(stroke
				(width 0.1)
				(type default)
			)
			(layer "F.Fab")
		)
		(pad "1" smd circle
			(at -0.40005 0 180)
			(size 0 0)
			(layers "F.Cu" "F.Mask" "F.Paste")
			(net "NIC4_BIF2_N")
		)
		(pad "2" smd circle
			(at 0.40005 0 180)
			(size 0 0)
			(layers "F.Cu" "F.Mask" "F.Paste")
			(net "P3V3_AUX")
		)
	)
	(footprint ""
		(layer "F.Cu")
		(at 167.16248 -22.955504 -90)
		(property "Reference" "C2721"
			(at 0 0 270)
			(layer "F.SilkS")
			(hide yes)
			(effects
				(font
					(size 1.27 1.27)
				)
			)
		)
		(property "Value" ""
			(at 0 0 270)
			(layer "F.Fab")
			(effects
				(font
					(size 1.27 1.27)
				)
			)
		)
		(duplicate_pad_numbers_are_jumpers no)
		(fp_line
			(start -0.7874 0.4064)
			(end -0.7874 -0.4064)
			(stroke
				(width 0.1524)
				(type default)
			)
			(layer "F.SilkS")
		)
		(fp_line
			(start 0.7874 0.4064)
			(end -0.7874 0.4064)
			(stroke
				(width 0.1524)
				(type default)
			)
			(layer "F.SilkS")
		)
		(fp_line
			(start -0.7874 -0.4064)
			(end 0.7874 -0.4064)
			(stroke
				(width 0.1524)
				(type default)
			)
			(layer "F.SilkS")
		)
		(fp_line
			(start 0.7874 -0.4064)
			(end 0.7874 0.4064)
			(stroke
				(width 0.1524)
				(type default)
			)
			(layer "F.SilkS")
		)
		(fp_line
			(start -0.67945 0.3048)
			(end -0.67945 -0.305054)
			(stroke
				(width 0.1)
				(type default)
			)
			(layer "F.Fab")
		)
		(fp_line
			(start -0.12065 0.3048)
			(end -0.67945 0.3048)
			(stroke
				(width 0.1)
				(type default)
			)
			(layer "F.Fab")
		)
		(fp_line
			(start 0.120396 0.3048)
			(end 0.120396 0.2794)
			(stroke
				(width 0.1)
				(type default)
			)
			(layer "F.Fab")
		)
		(fp_line
			(start 0.67945 0.3048)
			(end 0.120396 0.3048)
			(stroke
				(width 0.1)
				(type default)
			)
			(layer "F.Fab")
		)
		(fp_line
			(start -0.12065 0.2794)
			(end -0.12065 0.3048)
			(stroke
				(width 0.1)
				(type default)
			)
			(layer "F.Fab")
		)
		(fp_line
			(start 0.120396 0.2794)
			(end -0.12065 0.2794)
			(stroke
				(width 0.1)
				(type default)
			)
			(layer "F.Fab")
		)
		(fp_line
			(start -0.12065 -0.2794)
			(end 0.12065 -0.2794)
			(stroke
				(width 0.1)
				(type default)
			)
			(layer "F.Fab")
		)
		(fp_line
			(start 0.12065 -0.2794)
			(end 0.12065 -0.3048)
			(stroke
				(width 0.1)
				(type default)
			)
			(layer "F.Fab")
		)
		(fp_line
			(start 0.12065 -0.3048)
			(end 0.67945 -0.3048)
			(stroke
				(width 0.1)
				(type default)
			)
			(layer "F.Fab")
		)
		(fp_line
			(start 0.67945 -0.3048)
			(end 0.67945 0.3048)
			(stroke
				(width 0.1)
				(type default)
			)
			(layer "F.Fab")
		)
		(fp_line
			(start -0.67945 -0.305054)
			(end -0.12065 -0.305054)
			(stroke
				(width 0.1)
				(type default)
			)
			(layer "F.Fab")
		)
		(fp_line
			(start -0.12065 -0.305054)
			(end -0.12065 -0.2794)
			(stroke
				(width 0.1)
				(type default)
			)
			(layer "F.Fab")
		)
		(pad "1" smd circle
			(at -0.40005 0 270)
			(size 0 0)
			(layers "F.Cu" "F.Mask" "F.Paste")
			(net "GND")
		)
		(pad "2" smd circle
			(at 0.40005 0 270)
			(size 0 0)
			(layers "F.Cu" "F.Mask" "F.Paste")
			(net "P3V3_AUX")
		)
	)
	(footprint ""
		(layer "F.Cu")
		(at 338.074 -141.859 180)
		(property "Reference" "R4837"
			(at 0 0 180)
			(layer "F.SilkS")
			(hide yes)
			(effects
				(font
					(size 1.27 1.27)
				)
			)
		)
		(property "Value" ""
			(at 0 0 180)
			(layer "F.Fab")
			(effects
				(font
					(size 1.27 1.27)
				)
			)
		)
		(duplicate_pad_numbers_are_jumpers no)
		(fp_line
			(start 0.7874 0.4064)
			(end -0.7874 0.4064)
			(stroke
				(width 0.1524)
				(type default)
			)
			(layer "F.SilkS")
		)
		(fp_line
			(start 0.7874 -0.4064)
			(end 0.7874 0.4064)
			(stroke
				(width 0.1524)
				(type default)
			)
			(layer "F.SilkS")
		)
		(fp_line
			(start -0.7874 0.4064)
			(end -0.7874 -0.4064)
			(stroke
				(width 0.1524)
				(type default)
			)
			(layer "F.SilkS")
		)
		(fp_line
			(start -0.7874 -0.4064)
			(end 0.7874 -0.4064)
			(stroke
				(width 0.1524)
				(type default)
			)
			(layer "F.SilkS")
		)
		(fp_line
			(start 0.67945 0.3048)
			(end 0.120396 0.3048)
			(stroke
				(width 0.1)
				(type default)
			)
			(layer "F.Fab")
		)
		(fp_line
			(start 0.67945 -0.3048)
			(end 0.67945 0.3048)
			(stroke
				(width 0.1)
				(type default)
			)
			(layer "F.Fab")
		)
		(fp_line
			(start 0.12065 -0.2794)
			(end 0.12065 -0.3048)
			(stroke
				(width 0.1)
				(type default)
			)
			(layer "F.Fab")
		)
		(fp_line
			(start 0.12065 -0.3048)
			(end 0.67945 -0.3048)
			(stroke
				(width 0.1)
				(type default)
			)
			(layer "F.Fab")
		)
		(fp_line
			(start 0.120396 0.3048)
			(end 0.120396 0.2794)
			(stroke
				(width 0.1)
				(type default)
			)
			(layer "F.Fab")
		)
		(fp_line
			(start 0.120396 0.2794)
			(end -0.12065 0.2794)
			(stroke
				(width 0.1)
				(type default)
			)
			(layer "F.Fab")
		)
		(fp_line
			(start -0.12065 0.3048)
			(end -0.67945 0.3048)
			(stroke
				(width 0.1)
				(type default)
			)
			(layer "F.Fab")
		)
		(fp_line
			(start -0.12065 0.2794)
			(end -0.12065 0.3048)
			(stroke
				(width 0.1)
				(type default)
			)
			(layer "F.Fab")
		)
		(fp_line
			(start -0.12065 -0.2794)
			(end 0.12065 -0.2794)
			(stroke
				(width 0.1)
				(type default)
			)
			(layer "F.Fab")
		)
		(fp_line
			(start -0.12065 -0.305054)
			(end -0.12065 -0.2794)
			(stroke
				(width 0.1)
				(type default)
			)
			(layer "F.Fab")
		)
		(fp_line
			(start -0.67945 0.3048)
			(end -0.67945 -0.305054)
			(stroke
				(width 0.1)
				(type default)
			)
			(layer "F.Fab")
		)
		(fp_line
			(start -0.67945 -0.305054)
			(end -0.12065 -0.305054)
			(stroke
				(width 0.1)
				(type default)
			)
			(layer "F.Fab")
		)
		(pad "1" smd circle
			(at -0.40005 0 180)
			(size 0 0)
			(layers "F.Cu" "F.Mask" "F.Paste")
			(net "RST_PEX_SSD15_PERST_N")
		)
		(pad "2" smd circle
			(at 0.40005 0 180)
			(size 0 0)
			(layers "F.Cu" "F.Mask" "F.Paste")
			(net "RST_PEX_SSD15_PERST_R_N")
		)
	)
	(footprint ""
		(layer "F.Cu")
		(at 426.543724 -46.90491)
		(property "Reference" "R662"
			(at 0 0 0)
			(layer "F.SilkS")
			(hide yes)
			(effects
				(font
					(size 1.27 1.27)
				)
			)
		)
		(property "Value" ""
			(at 0 0 0)
			(layer "F.Fab")
			(effects
				(font
					(size 1.27 1.27)
				)
			)
		)
		(duplicate_pad_numbers_are_jumpers no)
		(fp_line
			(start -0.7874 -0.4064)
			(end 0.7874 -0.4064)
			(stroke
				(width 0.1524)
				(type default)
			)
			(layer "F.SilkS")
		)
		(fp_line
			(start -0.7874 0.4064)
			(end -0.7874 -0.4064)
			(stroke
				(width 0.1524)
				(type default)
			)
			(layer "F.SilkS")
		)
		(fp_line
			(start 0.7874 -0.4064)
			(end 0.7874 0.4064)
			(stroke
				(width 0.1524)
				(type default)
			)
			(layer "F.SilkS")
		)
		(fp_line
			(start 0.7874 0.4064)
			(end -0.7874 0.4064)
			(stroke
				(width 0.1524)
				(type default)
			)
			(layer "F.SilkS")
		)
		(fp_line
			(start -0.67945 -0.305054)
			(end -0.12065 -0.305054)
			(stroke
				(width 0.1)
				(type default)
			)
			(layer "F.Fab")
		)
		(fp_line
			(start -0.67945 0.3048)
			(end -0.67945 -0.305054)
			(stroke
				(width 0.1)
				(type default)
			)
			(layer "F.Fab")
		)
		(fp_line
			(start -0.12065 -0.305054)
			(end -0.12065 -0.2794)
			(stroke
				(width 0.1)
				(type default)
			)
			(layer "F.Fab")
		)
		(fp_line
			(start -0.12065 -0.2794)
			(end 0.12065 -0.2794)
			(stroke
				(width 0.1)
				(type default)
			)
			(layer "F.Fab")
		)
		(fp_line
			(start -0.12065 0.2794)
			(end -0.12065 0.3048)
			(stroke
				(width 0.1)
				(type default)
			)
			(layer "F.Fab")
		)
		(fp_line
			(start -0.12065 0.3048)
			(end -0.67945 0.3048)
			(stroke
				(width 0.1)
				(type default)
			)
			(layer "F.Fab")
		)
		(fp_line
			(start 0.120396 0.2794)
			(end -0.12065 0.2794)
			(stroke
				(width 0.1)
				(type default)
			)
			(layer "F.Fab")
		)
		(fp_line
			(start 0.120396 0.3048)
			(end 0.120396 0.2794)
			(stroke
				(width 0.1)
				(type default)
			)
			(layer "F.Fab")
		)
		(fp_line
			(start 0.12065 -0.3048)
			(end 0.67945 -0.3048)
			(stroke
				(width 0.1)
				(type default)
			)
			(layer "F.Fab")
		)
		(fp_line
			(start 0.12065 -0.2794)
			(end 0.12065 -0.3048)
			(stroke
				(width 0.1)
				(type default)
			)
			(layer "F.Fab")
		)
		(fp_line
			(start 0.67945 -0.3048)
			(end 0.67945 0.3048)
			(stroke
				(width 0.1)
				(type default)
			)
			(layer "F.Fab")
		)
		(fp_line
			(start 0.67945 0.3048)
			(end 0.120396 0.3048)
			(stroke
				(width 0.1)
				(type default)
			)
			(layer "F.Fab")
		)
		(pad "1" smd circle
			(at -0.40005 0)
			(size 0 0)
			(layers "F.Cu" "F.Mask" "F.Paste")
			(net "SSD14_ADC_ALERT_N")
		)
		(pad "2" smd circle
			(at 0.40005 0)
			(size 0 0)
			(layers "F.Cu" "F.Mask" "F.Paste")
			(net "SSD_8_15_ADC_ALERT_N")
		)
	)
	(footprint ""
		(layer "F.Cu")
		(at 16.706596 -255.046734 -90)
		(property "Reference" "R6465"
			(at 0 0 270)
			(layer "F.SilkS")
			(hide yes)
			(effects
				(font
					(size 1.27 1.27)
				)
			)
		)
		(property "Value" ""
			(at 0 0 270)
			(layer "F.Fab")
			(effects
				(font
					(size 1.27 1.27)
				)
			)
		)
		(duplicate_pad_numbers_are_jumpers no)
		(fp_line
			(start -0.7874 0.4064)
			(end -0.7874 -0.4064)
			(stroke
				(width 0.1524)
				(type default)
			)
			(layer "F.SilkS")
		)
		(fp_line
			(start 0.7874 0.4064)
			(end -0.7874 0.4064)
			(stroke
				(width 0.1524)
				(type default)
			)
			(layer "F.SilkS")
		)
		(fp_line
			(start -0.7874 -0.4064)
			(end 0.7874 -0.4064)
			(stroke
				(width 0.1524)
				(type default)
			)
			(layer "F.SilkS")
		)
		(fp_line
			(start 0.7874 -0.4064)
			(end 0.7874 0.4064)
			(stroke
				(width 0.1524)
				(type default)
			)
			(layer "F.SilkS")
		)
		(fp_line
			(start -0.67945 0.3048)
			(end -0.67945 -0.305054)
			(stroke
				(width 0.1)
				(type default)
			)
			(layer "F.Fab")
		)
		(fp_line
			(start -0.12065 0.3048)
			(end -0.67945 0.3048)
			(stroke
				(width 0.1)
				(type default)
			)
			(layer "F.Fab")
		)
		(fp_line
			(start 0.120396 0.3048)
			(end 0.120396 0.2794)
			(stroke
				(width 0.1)
				(type default)
			)
			(layer "F.Fab")
		)
		(fp_line
			(start 0.67945 0.3048)
			(end 0.120396 0.3048)
			(stroke
				(width 0.1)
				(type default)
			)
			(layer "F.Fab")
		)
		(fp_line
			(start -0.12065 0.2794)
			(end -0.12065 0.3048)
			(stroke
				(width 0.1)
				(type default)
			)
			(layer "F.Fab")
		)
		(fp_line
			(start 0.120396 0.2794)
			(end -0.12065 0.2794)
			(stroke
				(width 0.1)
				(type default)
			)
			(layer "F.Fab")
		)
		(fp_line
			(start -0.12065 -0.2794)
			(end 0.12065 -0.2794)
			(stroke
				(width 0.1)
				(type default)
			)
			(layer "F.Fab")
		)
		(fp_line
			(start 0.12065 -0.2794)
			(end 0.12065 -0.3048)
			(stroke
				(width 0.1)
				(type default)
			)
			(layer "F.Fab")
		)
		(fp_line
			(start 0.12065 -0.3048)
			(end 0.67945 -0.3048)
			(stroke
				(width 0.1)
				(type default)
			)
			(layer "F.Fab")
		)
		(fp_line
			(start 0.67945 -0.3048)
			(end 0.67945 0.3048)
			(stroke
				(width 0.1)
				(type default)
			)
			(layer "F.Fab")
		)
		(fp_line
			(start -0.67945 -0.305054)
			(end -0.12065 -0.305054)
			(stroke
				(width 0.1)
				(type default)
			)
			(layer "F.Fab")
		)
		(fp_line
			(start -0.12065 -0.305054)
			(end -0.12065 -0.2794)
			(stroke
				(width 0.1)
				(type default)
			)
			(layer "F.Fab")
		)
		(pad "1" smd circle
			(at -0.40005 0 270)
			(size 0 0)
			(layers "F.Cu" "F.Mask" "F.Paste")
			(net "P1V25_SERDES_VDDPLL_PEX0")
		)
		(pad "2" smd circle
			(at 0.40005 0 270)
			(size 0 0)
			(layers "F.Cu" "F.Mask" "F.Paste")
			(net "P1V25_SERDES_VDDPLL_PEX0_C4")
		)
	)
	(footprint ""
		(layer "F.Cu")
		(at 376.312684 -88.8238)
		(property "Reference" "R1743"
			(at 0 0 0)
			(layer "F.SilkS")
			(hide yes)
			(effects
				(font
					(size 1.27 1.27)
				)
			)
		)
		(property "Value" ""
			(at 0 0 0)
			(layer "F.Fab")
			(effects
				(font
					(size 1.27 1.27)
				)
			)
		)
		(duplicate_pad_numbers_are_jumpers no)
		(fp_line
			(start -0.7874 -0.4064)
			(end 0.7874 -0.4064)
			(stroke
				(width 0.1524)
				(type default)
			)
			(layer "F.SilkS")
		)
		(fp_line
			(start -0.7874 0.4064)
			(end -0.7874 -0.4064)
			(stroke
				(width 0.1524)
				(type default)
			)
			(layer "F.SilkS")
		)
		(fp_line
			(start 0.7874 -0.4064)
			(end 0.7874 0.4064)
			(stroke
				(width 0.1524)
				(type default)
			)
			(layer "F.SilkS")
		)
		(fp_line
			(start 0.7874 0.4064)
			(end -0.7874 0.4064)
			(stroke
				(width 0.1524)
				(type default)
			)
			(layer "F.SilkS")
		)
		(fp_line
			(start -0.67945 -0.305054)
			(end -0.12065 -0.305054)
			(stroke
				(width 0.1)
				(type default)
			)
			(layer "F.Fab")
		)
		(fp_line
			(start -0.67945 0.3048)
			(end -0.67945 -0.305054)
			(stroke
				(width 0.1)
				(type default)
			)
			(layer "F.Fab")
		)
		(fp_line
			(start -0.12065 -0.305054)
			(end -0.12065 -0.2794)
			(stroke
				(width 0.1)
				(type default)
			)
			(layer "F.Fab")
		)
		(fp_line
			(start -0.12065 -0.2794)
			(end 0.12065 -0.2794)
			(stroke
				(width 0.1)
				(type default)
			)
			(layer "F.Fab")
		)
		(fp_line
			(start -0.12065 0.2794)
			(end -0.12065 0.3048)
			(stroke
				(width 0.1)
				(type default)
			)
			(layer "F.Fab")
		)
		(fp_line
			(start -0.12065 0.3048)
			(end -0.67945 0.3048)
			(stroke
				(width 0.1)
				(type default)
			)
			(layer "F.Fab")
		)
		(fp_line
			(start 0.120396 0.2794)
			(end -0.12065 0.2794)
			(stroke
				(width 0.1)
				(type default)
			)
			(layer "F.Fab")
		)
		(fp_line
			(start 0.120396 0.3048)
			(end 0.120396 0.2794)
			(stroke
				(width 0.1)
				(type default)
			)
			(layer "F.Fab")
		)
		(fp_line
			(start 0.12065 -0.3048)
			(end 0.67945 -0.3048)
			(stroke
				(width 0.1)
				(type default)
			)
			(layer "F.Fab")
		)
		(fp_line
			(start 0.12065 -0.2794)
			(end 0.12065 -0.3048)
			(stroke
				(width 0.1)
				(type default)
			)
			(layer "F.Fab")
		)
		(fp_line
			(start 0.67945 -0.3048)
			(end 0.67945 0.3048)
			(stroke
				(width 0.1)
				(type default)
			)
			(layer "F.Fab")
		)
		(fp_line
			(start 0.67945 0.3048)
			(end 0.120396 0.3048)
			(stroke
				(width 0.1)
				(type default)
			)
			(layer "F.Fab")
		)
		(pad "1" smd circle
			(at -0.40005 0)
			(size 0 0)
			(layers "F.Cu" "F.Mask" "F.Paste")
			(net "P3V3_AUX")
		)
		(pad "2" smd circle
			(at 0.40005 0)
			(size 0 0)
			(layers "F.Cu" "F.Mask" "F.Paste")
			(net "SMB_BIC_I2C6_MUX_NIC_ADC_R_SDA")
		)
	)
	(footprint ""
		(layer "F.Cu")
		(at 226.977702 -258.012184 -90)
		(property "Reference" "R6500"
			(at 0 0 270)
			(layer "F.SilkS")
			(hide yes)
			(effects
				(font
					(size 1.27 1.27)
				)
			)
		)
		(property "Value" ""
			(at 0 0 270)
			(layer "F.Fab")
			(effects
				(font
					(size 1.27 1.27)
				)
			)
		)
		(duplicate_pad_numbers_are_jumpers no)
		(fp_line
			(start -0.7874 0.4064)
			(end -0.7874 -0.4064)
			(stroke
				(width 0.1524)
				(type default)
			)
			(layer "F.SilkS")
		)
		(fp_line
			(start 0.7874 0.4064)
			(end -0.7874 0.4064)
			(stroke
				(width 0.1524)
				(type default)
			)
			(layer "F.SilkS")
		)
		(fp_line
			(start -0.7874 -0.4064)
			(end 0.7874 -0.4064)
			(stroke
				(width 0.1524)
				(type default)
			)
			(layer "F.SilkS")
		)
		(fp_line
			(start 0.7874 -0.4064)
			(end 0.7874 0.4064)
			(stroke
				(width 0.1524)
				(type default)
			)
			(layer "F.SilkS")
		)
		(fp_line
			(start -0.67945 0.3048)
			(end -0.67945 -0.305054)
			(stroke
				(width 0.1)
				(type default)
			)
			(layer "F.Fab")
		)
		(fp_line
			(start -0.12065 0.3048)
			(end -0.67945 0.3048)
			(stroke
				(width 0.1)
				(type default)
			)
			(layer "F.Fab")
		)
		(fp_line
			(start 0.120396 0.3048)
			(end 0.120396 0.2794)
			(stroke
				(width 0.1)
				(type default)
			)
			(layer "F.Fab")
		)
		(fp_line
			(start 0.67945 0.3048)
			(end 0.120396 0.3048)
			(stroke
				(width 0.1)
				(type default)
			)
			(layer "F.Fab")
		)
		(fp_line
			(start -0.12065 0.2794)
			(end -0.12065 0.3048)
			(stroke
				(width 0.1)
				(type default)
			)
			(layer "F.Fab")
		)
		(fp_line
			(start 0.120396 0.2794)
			(end -0.12065 0.2794)
			(stroke
				(width 0.1)
				(type default)
			)
			(layer "F.Fab")
		)
		(fp_line
			(start -0.12065 -0.2794)
			(end 0.12065 -0.2794)
			(stroke
				(width 0.1)
				(type default)
			)
			(layer "F.Fab")
		)
		(fp_line
			(start 0.12065 -0.2794)
			(end 0.12065 -0.3048)
			(stroke
				(width 0.1)
				(type default)
			)
			(layer "F.Fab")
		)
		(fp_line
			(start 0.12065 -0.3048)
			(end 0.67945 -0.3048)
			(stroke
				(width 0.1)
				(type default)
			)
			(layer "F.Fab")
		)
		(fp_line
			(start 0.67945 -0.3048)
			(end 0.67945 0.3048)
			(stroke
				(width 0.1)
				(type default)
			)
			(layer "F.Fab")
		)
		(fp_line
			(start -0.67945 -0.305054)
			(end -0.12065 -0.305054)
			(stroke
				(width 0.1)
				(type default)
			)
			(layer "F.Fab")
		)
		(fp_line
			(start -0.12065 -0.305054)
			(end -0.12065 -0.2794)
			(stroke
				(width 0.1)
				(type default)
			)
			(layer "F.Fab")
		)
		(pad "1" smd circle
			(at -0.40005 0 270)
			(size 0 0)
			(layers "F.Cu" "F.Mask" "F.Paste")
			(net "P1V25_SERDES_VDDPLL_PEX1")
		)
		(pad "2" smd circle
			(at 0.40005 0 270)
			(size 0 0)
			(layers "F.Cu" "F.Mask" "F.Paste")
			(net "P1V25_SERDES_VDDPLL_PEX1_C7")
		)
	)
	(footprint ""
		(layer "F.Cu")
		(at 410.184092 -350.098614 90)
		(property "Reference" "C2440"
			(at 0 0 90)
			(layer "F.SilkS")
			(hide yes)
			(effects
				(font
					(size 1.27 1.27)
				)
			)
		)
		(property "Value" ""
			(at 0 0 90)
			(layer "F.Fab")
			(effects
				(font
					(size 1.27 1.27)
				)
			)
		)
		(duplicate_pad_numbers_are_jumpers no)
		(fp_line
			(start 0.299974 -0.150114)
			(end 0.299974 0.150114)
			(stroke
				(width 0.1)
				(type default)
			)
			(layer "F.Fab")
		)
		(fp_line
			(start -0.299974 -0.150114)
			(end 0.299974 -0.150114)
			(stroke
				(width 0.1)
				(type default)
			)
			(layer "F.Fab")
		)
		(fp_line
			(start 0.299974 0.150114)
			(end -0.299974 0.150114)
			(stroke
				(width 0.1)
				(type default)
			)
			(layer "F.Fab")
		)
		(fp_line
			(start -0.299974 0.150114)
			(end -0.299974 -0.150114)
			(stroke
				(width 0.1)
				(type default)
			)
			(layer "F.Fab")
		)
		(pad "1" smd rect
			(at -0.2667 0 90)
			(size 0.3048 0.381)
			(layers "F.Cu" "F.Mask" "F.Paste")
			(net "P5E_PEX3_STN4_TX_DN<79>")
		)
		(pad "2" smd rect
			(at 0.2667 0 90)
			(size 0.3048 0.381)
			(layers "F.Cu" "F.Mask" "F.Paste")
			(net "P5E_PEX3_STN4_TX_C_DN<79>")
		)
	)
	(footprint ""
		(layer "F.Cu")
		(at 317.51524 -20.72513)
		(property "Reference" "H122"
			(at 1.556512 -2.603754 0)
			(unlocked yes)
			(layer "B.SilkS")
			(effects
				(font
					(size 0.7874 0.5842)
					(thickness 0.1524)
				)
				(justify left mirror)
			)
		)
		(property "Value" ""
			(at 0 0 0)
			(layer "F.Fab")
			(effects
				(font
					(size 1.27 1.27)
				)
			)
		)
		(duplicate_pad_numbers_are_jumpers no)
		(pad "1" thru_hole rect
			(at 0 0)
			(size 4.2164 5.0038)
			(drill 2.0066
				(offset 0.099822 0)
			)
			(layers "*.Cu" "*.Mask")
			(remove_unused_layers no)
			(net "Net_8541")
			(clearance -0.8509)
			(padstack
				(mode front_inner_back)
				(layer "Inner"
					(shape circle)
					(size 4.0132 4.0132)
					(clearance -0.7493)
				)
				(layer "B.Cu"
					(shape circle)
					(size 4.0132 4.0132)
					(clearance -0.7493)
				)
			)
		)
	)
	(footprint ""
		(layer "F.Cu")
		(at 71.90994 -412.090108)
		(property "Reference" "J11"
			(at -5.90423 3.675888 90)
			(unlocked yes)
			(layer "F.SilkS")
			(effects
				(font
					(size 2.032 1.524)
					(thickness 0.1524)
				)
				(justify left)
			)
		)
		(property "Value" ""
			(at 0 0 0)
			(layer "F.Fab")
			(effects
				(font
					(size 1.27 1.27)
				)
			)
		)
		(duplicate_pad_numbers_are_jumpers no)
		(fp_line
			(start -4.249928 -16.999966)
			(end 24.45004 -16.999966)
			(stroke
				(width 0.1524)
				(type default)
			)
			(layer "F.SilkS")
		)
		(fp_line
			(start -4.249928 50.099976)
			(end -4.249928 -16.999966)
			(stroke
				(width 0.1524)
				(type default)
			)
			(layer "F.SilkS")
		)
		(fp_line
			(start -1.249934 -13.999972)
			(end -1.249934 47.099982)
			(stroke
				(width 0.1524)
				(type default)
			)
			(layer "F.SilkS")
		)
		(fp_line
			(start -1.249934 -6.500114)
			(end 21.450046 -6.500114)
			(stroke
				(width 0.1524)
				(type default)
			)
			(layer "F.SilkS")
		)
		(fp_line
			(start -1.249934 47.099982)
			(end 21.450046 47.099982)
			(stroke
				(width 0.1524)
				(type default)
			)
			(layer "F.SilkS")
		)
		(fp_line
			(start 21.450046 -13.999972)
			(end -1.249934 -13.999972)
			(stroke
				(width 0.1524)
				(type default)
			)
			(layer "F.SilkS")
		)
		(fp_line
			(start 21.450046 47.099982)
			(end 21.450046 -13.999972)
			(stroke
				(width 0.1524)
				(type default)
			)
			(layer "F.SilkS")
		)
		(fp_line
			(start 24.45004 -16.999966)
			(end 24.45004 50.099976)
			(stroke
				(width 0.1524)
				(type default)
			)
			(layer "F.SilkS")
		)
		(fp_line
			(start 24.45004 50.099976)
			(end -4.249928 50.099976)
			(stroke
				(width 0.1524)
				(type default)
			)
			(layer "F.SilkS")
		)
		(fp_poly
			(pts
				(xy -2.413 -0.508) (xy -2.413 0.508) (xy -1.397 0)
			)
			(stroke
				(width 0)
				(type default)
			)
			(fill yes)
			(layer "F.SilkS")
		)
		(fp_line
			(start -4.249928 -16.999966)
			(end 24.45004 -16.999966)
			(stroke
				(width 0.1524)
				(type default)
			)
			(layer "B.SilkS")
		)
		(fp_line
			(start -4.249928 50.099976)
			(end -4.249928 -16.999966)
			(stroke
				(width 0.1524)
				(type default)
			)
			(layer "B.SilkS")
		)
		(fp_line
			(start 24.45004 -16.999966)
			(end 24.45004 24.530812)
			(stroke
				(width 0.1524)
				(type default)
			)
			(layer "B.SilkS")
		)
		(fp_line
			(start 24.45004 26.255218)
			(end 24.45004 27.00909)
			(stroke
				(width 0.1524)
				(type default)
			)
			(layer "B.SilkS")
		)
		(fp_line
			(start 24.45004 27.810206)
			(end 24.45004 50.099976)
			(stroke
				(width 0.1524)
				(type default)
			)
			(layer "B.SilkS")
		)
		(fp_line
			(start 24.45004 50.099976)
			(end -4.249928 50.099976)
			(stroke
				(width 0.1524)
				(type default)
			)
			(layer "B.SilkS")
		)
		(fp_line
			(start -4.249928 -16.999966)
			(end 24.45004 -16.999966)
			(stroke
				(width 0.1)
				(type default)
			)
			(layer "B.Fab")
		)
		(fp_line
			(start -4.249928 50.099976)
			(end -4.249928 -16.999966)
			(stroke
				(width 0.1)
				(type default)
			)
			(layer "B.Fab")
		)
		(fp_line
			(start 24.45004 -16.999966)
			(end 24.45004 50.099976)
			(stroke
				(width 0.1)
				(type default)
			)
			(layer "B.Fab")
		)
		(fp_line
			(start 24.45004 50.099976)
			(end -4.249928 50.099976)
			(stroke
				(width 0.1)
				(type default)
			)
			(layer "B.Fab")
		)
		(fp_line
			(start -1.249934 -13.999972)
			(end -1.249934 47.099982)
			(stroke
				(width 0.1)
				(type default)
			)
			(layer "F.Fab")
		)
		(fp_line
			(start -1.249934 47.099982)
			(end 21.450046 47.099982)
			(stroke
				(width 0.1)
				(type default)
			)
			(layer "F.Fab")
		)
		(fp_line
			(start 21.450046 -13.999972)
			(end -1.249934 -13.999972)
			(stroke
				(width 0.1)
				(type default)
			)
			(layer "F.Fab")
		)
		(fp_line
			(start 21.450046 47.099982)
			(end 21.450046 -13.999972)
			(stroke
				(width 0.1)
				(type default)
			)
			(layer "F.Fab")
		)
		(fp_poly
			(pts
				(xy -2.413 -0.508) (xy -2.413 0.508) (xy -1.397 0)
			)
			(stroke
				(width 0)
				(type default)
			)
			(fill yes)
			(layer "F.Fab")
		)
		(fp_text user "PRESS-FIT"
			(at 23.163276 41.452546 90)
			(unlocked yes)
			(layer "F.SilkS")
			(effects
				(font
					(size 1.905 1.4224)
					(thickness 0.1524)
				)
				(justify left)
			)
		)
		(fp_text user "PRESS-FIT"
			(at -6.025134 28.893516 90)
			(unlocked yes)
			(layer "B.SilkS")
			(effects
				(font
					(size 1.905 1.4224)
					(thickness 0.1524)
				)
				(justify left mirror)
			)
		)
		(fp_text user "PRESS-FIT"
			(at 18.326862 48.74895 0)
			(unlocked yes)
			(layer "B.Fab")
			(effects
				(font
					(size 1.905 1.4224)
					(thickness 0.1524)
				)
				(justify left mirror)
			)
		)
		(fp_text user "PRESS-FIT"
			(at 1.5875 48.73625 0)
			(unlocked yes)
			(layer "F.Fab")
			(effects
				(font
					(size 1.905 1.4224)
					(thickness 0.1524)
				)
				(justify left)
			)
		)
		(pad "A1" thru_hole rect
			(at 0 0 180)
			(size 0.71628 0.71628)
			(drill 0.30988)
			(layers "*.Cu" "*.Mask")
			(remove_unused_layers no)
			(net "RST_MB_PERST_2_N")
			(clearance 0.0508)
			(thermal_gap 0.0508)
			(padstack
				(mode front_inner_back)
				(layer "Inner"
					(shape circle)
					(size 0.71628 0.71628)
					(clearance 0.0508)
				)
				(layer "B.Cu"
					(shape rect)
					(size 0.71628 0.71628)
					(clearance 0.0508)
				)
			)
		)
		(pad "A2" thru_hole circle
			(at 2.199894 0.199898 180)
			(size 0.906272 0.906272)
			(drill 0.499872)
			(layers "*.Cu" "*.Mask")
			(remove_unused_layers no)
			(net "GND")
			(clearance 0.0508)
			(thermal_gap 0.0508)
		)
		(pad "A3" thru_hole circle
			(at 4.400042 0 180)
			(size 0.71628 0.71628)
			(drill 0.30988)
			(layers "*.Cu" "*.Mask")
			(remove_unused_layers no)
			(net "GPU_HGX_DETECT_R_N")
			(clearance 0.0508)
			(thermal_gap 0.0508)
		)
		(pad "A4" thru_hole circle
			(at 6.599936 0.199898 180)
			(size 0.906272 0.906272)
			(drill 0.499872)
			(layers "*.Cu" "*.Mask")
			(remove_unused_layers no)
			(net "GND")
			(clearance 0.0508)
			(thermal_gap 0.0508)
		)
		(pad "A5" thru_hole circle
			(at 8.800084 0 180)
			(size 0.71628 0.71628)
			(drill 0.30988)
			(layers "*.Cu" "*.Mask")
			(remove_unused_layers no)
			(net "RST_MB_PERST_1_N")
			(clearance 0.0508)
			(thermal_gap 0.0508)
		)
		(pad "A6" thru_hole circle
			(at 10.999978 0.199898 180)
			(size 0.906272 0.906272)
			(drill 0.499872)
			(layers "*.Cu" "*.Mask")
			(remove_unused_layers no)
			(net "GND")
			(clearance 0.0508)
			(thermal_gap 0.0508)
		)
		(pad "A7" thru_hole circle
			(at 13.199872 0 180)
			(size 0.71628 0.71628)
			(drill 0.30988)
			(layers "*.Cu" "*.Mask")
			(remove_unused_layers no)
			(net "PRSNT_SWB_C_N")
			(clearance 0.0508)
			(thermal_gap 0.0508)
		)
		(pad "A8" thru_hole circle
			(at 15.40002 0.199898 180)
			(size 0.906272 0.906272)
			(drill 0.499872)
			(layers "*.Cu" "*.Mask")
			(remove_unused_layers no)
			(net "GND")
			(clearance 0.0508)
			(thermal_gap 0.0508)
		)
		(pad "A9" thru_hole circle
			(at 17.599914 0 180)
			(size 0.71628 0.71628)
			(drill 0.30988)
			(layers "*.Cu" "*.Mask")
			(remove_unused_layers no)
			(net "RST_GPU_FPGA_PEX_RST_N")
			(clearance 0.0508)
			(thermal_gap 0.0508)
		)
		(pad "A10" thru_hole circle
			(at 19.800062 0.199898 180)
			(size 0.906272 0.906272)
			(drill 0.499872)
			(layers "*.Cu" "*.Mask")
			(remove_unused_layers no)
			(net "GND")
			(clearance 0.0508)
			(thermal_gap 0.0508)
		)
		(pad "B1" thru_hole circle
			(at 0 1.299972 180)
			(size 0.906272 0.906272)
			(drill 0.499872)
			(layers "*.Cu" "*.Mask")
			(remove_unused_layers no)
			(net "GND")
			(clearance 0.0508)
			(thermal_gap 0.0508)
		)
		(pad "B3" thru_hole circle
			(at 4.400042 1.299972 180)
			(size 0.906272 0.906272)
			(drill 0.499872)
			(layers "*.Cu" "*.Mask")
			(remove_unused_layers no)
			(net "GND")
			(clearance 0.0508)
			(thermal_gap 0.0508)
		)
		(pad "B5" thru_hole circle
			(at 8.800084 1.299972 180)
			(size 0.906272 0.906272)
			(drill 0.499872)
			(layers "*.Cu" "*.Mask")
			(remove_unused_layers no)
			(net "GND")
			(clearance 0.0508)
			(thermal_gap 0.0508)
		)
		(pad "B7" thru_hole circle
			(at 13.199872 1.299972 180)
			(size 0.906272 0.906272)
			(drill 0.499872)
			(layers "*.Cu" "*.Mask")
			(remove_unused_layers no)
			(net "GND")
			(clearance 0.0508)
			(thermal_gap 0.0508)
		)
		(pad "B9" thru_hole circle
			(at 17.599914 1.299972 180)
			(size 0.906272 0.906272)
			(drill 0.499872)
			(layers "*.Cu" "*.Mask")
			(remove_unused_layers no)
			(net "GND")
			(clearance 0.0508)
			(thermal_gap 0.0508)
		)
		(pad "C9" thru_hole circle
			(at 17.599914 2.599944 180)
			(size 0.71628 0.71628)
			(drill 0.30988)
			(layers "*.Cu" "*.Mask")
			(remove_unused_layers no)
			(net "GPU_THERM_OVERT_R_N")
			(clearance 0.0508)
			(thermal_gap 0.0508)
		)
		(pad "D2" thru_hole circle
			(at 2.199894 4.100068 180)
			(size 0.906272 0.906272)
			(drill 0.499872)
			(layers "*.Cu" "*.Mask")
			(remove_unused_layers no)
			(net "GND")
			(clearance 0.0508)
			(thermal_gap 0.0508)
		)
		(pad "D4" thru_hole circle
			(at 6.599936 4.100068 180)
			(size 0.906272 0.906272)
			(drill 0.499872)
			(layers "*.Cu" "*.Mask")
			(remove_unused_layers no)
			(net "GND")
			(clearance 0.0508)
			(thermal_gap 0.0508)
		)
		(pad "D6" thru_hole circle
			(at 10.999978 4.100068 180)
			(size 0.906272 0.906272)
			(drill 0.499872)
			(layers "*.Cu" "*.Mask")
			(remove_unused_layers no)
			(net "GND")
			(clearance 0.0508)
			(thermal_gap 0.0508)
		)
		(pad "D8" thru_hole circle
			(at 15.40002 4.100068 180)
			(size 0.906272 0.906272)
			(drill 0.499872)
			(layers "*.Cu" "*.Mask")
			(remove_unused_layers no)
			(net "GND")
			(clearance 0.0508)
			(thermal_gap 0.0508)
		)
		(pad "D9" thru_hole circle
			(at 17.599914 3.899916 180)
			(size 0.71628 0.71628)
			(drill 0.30988)
			(layers "*.Cu" "*.Mask")
			(remove_unused_layers no)
			(net "GPU_PEX_STRAP0")
			(clearance 0.0508)
			(thermal_gap 0.0508)
		)
		(pad "D10" thru_hole circle
			(at 19.800062 4.100068 180)
			(size 0.906272 0.906272)
			(drill 0.499872)
			(layers "*.Cu" "*.Mask")
			(remove_unused_layers no)
			(net "GND")
			(clearance 0.0508)
			(thermal_gap 0.0508)
		)
		(pad "E1" thru_hole circle
			(at 0 5.199888 180)
			(size 0.906272 0.906272)
			(drill 0.499872)
			(layers "*.Cu" "*.Mask")
			(remove_unused_layers no)
			(net "GND")
			(clearance 0.0508)
			(thermal_gap 0.0508)
		)
		(pad "E3" thru_hole circle
			(at 4.400042 5.199888 180)
			(size 0.906272 0.906272)
			(drill 0.499872)
			(layers "*.Cu" "*.Mask")
			(remove_unused_layers no)
			(net "GND")
			(clearance 0.0508)
			(thermal_gap 0.0508)
		)
		(pad "E5" thru_hole circle
			(at 8.800084 5.199888 180)
			(size 0.906272 0.906272)
			(drill 0.499872)
			(layers "*.Cu" "*.Mask")
			(remove_unused_layers no)
			(net "GND")
			(clearance 0.0508)
			(thermal_gap 0.0508)
		)
		(pad "E7" thru_hole circle
			(at 13.199872 5.199888 180)
			(size 0.906272 0.906272)
			(drill 0.499872)
			(layers "*.Cu" "*.Mask")
			(remove_unused_layers no)
			(net "GND")
			(clearance 0.0508)
			(thermal_gap 0.0508)
		)
		(pad "E9" thru_hole circle
			(at 17.599914 5.199888 180)
			(size 0.906272 0.906272)
			(drill 0.499872)
			(layers "*.Cu" "*.Mask")
			(remove_unused_layers no)
			(net "GND")
			(clearance 0.0508)
			(thermal_gap 0.0508)
		)
		(pad "F9" thru_hole circle
			(at 17.599914 6.500114 180)
			(size 0.71628 0.71628)
			(drill 0.30988)
			(layers "*.Cu" "*.Mask")
			(remove_unused_layers no)
			(net "GPU_PWR_BRAKE_N")
			(clearance 0.0508)
			(thermal_gap 0.0508)
		)
		(pad "G2" thru_hole circle
			(at 2.199894 7.999984 180)
			(size 0.906272 0.906272)
			(drill 0.499872)
			(layers "*.Cu" "*.Mask")
			(remove_unused_layers no)
			(net "GND")
			(clearance 0.0508)
			(thermal_gap 0.0508)
		)
		(pad "G4" thru_hole circle
			(at 6.599936 7.999984 180)
			(size 0.906272 0.906272)
			(drill 0.499872)
			(layers "*.Cu" "*.Mask")
			(remove_unused_layers no)
			(net "GND")
			(clearance 0.0508)
			(thermal_gap 0.0508)
		)
		(pad "G6" thru_hole circle
			(at 10.999978 7.999984 180)
			(size 0.906272 0.906272)
			(drill 0.499872)
			(layers "*.Cu" "*.Mask")
			(remove_unused_layers no)
			(net "GND")
			(clearance 0.0508)
			(thermal_gap 0.0508)
		)
		(pad "G8" thru_hole circle
			(at 15.40002 7.999984 180)
			(size 0.906272 0.906272)
			(drill 0.499872)
			(layers "*.Cu" "*.Mask")
			(remove_unused_layers no)
			(net "GND")
			(clearance 0.0508)
			(thermal_gap 0.0508)
		)
		(pad "G9" thru_hole circle
			(at 17.599914 7.800086 180)
			(size 0.71628 0.71628)
			(drill 0.30988)
			(layers "*.Cu" "*.Mask")
			(remove_unused_layers no)
			(net "GPU_BASE_ID0")
			(clearance 0.0508)
			(thermal_gap 0.0508)
		)
		(pad "G10" thru_hole circle
			(at 19.800062 7.999984 180)
			(size 0.906272 0.906272)
			(drill 0.499872)
			(layers "*.Cu" "*.Mask")
			(remove_unused_layers no)
			(net "GND")
			(clearance 0.0508)
			(thermal_gap 0.0508)
		)
		(pad "H1" thru_hole circle
			(at 0 9.100058 180)
			(size 0.906272 0.906272)
			(drill 0.499872)
			(layers "*.Cu" "*.Mask")
			(remove_unused_layers no)
			(net "GND")
			(clearance 0.0508)
			(thermal_gap 0.0508)
		)
		(pad "H3" thru_hole circle
			(at 4.400042 9.100058 180)
			(size 0.906272 0.906272)
			(drill 0.499872)
			(layers "*.Cu" "*.Mask")
			(remove_unused_layers no)
			(net "GND")
			(clearance 0.0508)
			(thermal_gap 0.0508)
		)
		(pad "H5" thru_hole circle
			(at 8.800084 9.100058 180)
			(size 0.906272 0.906272)
			(drill 0.499872)
			(layers "*.Cu" "*.Mask")
			(remove_unused_layers no)
			(net "GND")
			(clearance 0.0508)
			(thermal_gap 0.0508)
		)
		(pad "H7" thru_hole circle
			(at 13.199872 9.100058 180)
			(size 0.906272 0.906272)
			(drill 0.499872)
			(layers "*.Cu" "*.Mask")
			(remove_unused_layers no)
			(net "GND")
			(clearance 0.0508)
			(thermal_gap 0.0508)
		)
		(pad "H9" thru_hole circle
			(at 17.599914 9.100058 180)
			(size 0.906272 0.906272)
			(drill 0.499872)
			(layers "*.Cu" "*.Mask")
			(remove_unused_layers no)
			(net "GND")
			(clearance 0.0508)
			(thermal_gap 0.0508)
		)
		(pad "H10" thru_hole circle
			(at 19.800062 9.299956 180)
			(size 0.71628 0.71628)
			(drill 0.30988)
			(layers "*.Cu" "*.Mask")
			(remove_unused_layers no)
			(net "GPU_BASE_FPGA_READY_R")
			(clearance 0.0508)
			(thermal_gap 0.0508)
		)
		(pad "I9" thru_hole circle
			(at 17.599914 10.40003 180)
			(size 0.71628 0.71628)
			(drill 0.30988)
			(layers "*.Cu" "*.Mask")
			(remove_unused_layers no)
			(net "TP_CLK_100M_MB_2_DN")
			(clearance 0.0508)
			(thermal_gap 0.0508)
		)
		(pad "I10" thru_hole circle
			(at 19.800062 10.599928 180)
			(size 0.71628 0.71628)
			(drill 0.30988)
			(layers "*.Cu" "*.Mask")
			(remove_unused_layers no)
			(net "GPU_PEX_STRAP1")
			(clearance 0.0508)
			(thermal_gap 0.0508)
		)
		(pad "J2" thru_hole circle
			(at 2.199894 11.8999 180)
			(size 0.906272 0.906272)
			(drill 0.499872)
			(layers "*.Cu" "*.Mask")
			(remove_unused_layers no)
			(net "GND")
			(clearance 0.0508)
			(thermal_gap 0.0508)
		)
		(pad "J4" thru_hole circle
			(at 6.599936 11.8999 180)
			(size 0.906272 0.906272)
			(drill 0.499872)
			(layers "*.Cu" "*.Mask")
			(remove_unused_layers no)
			(net "GND")
			(clearance 0.0508)
			(thermal_gap 0.0508)
		)
		(pad "J6" thru_hole circle
			(at 10.999978 11.8999 180)
			(size 0.906272 0.906272)
			(drill 0.499872)
			(layers "*.Cu" "*.Mask")
			(remove_unused_layers no)
			(net "GND")
			(clearance 0.0508)
			(thermal_gap 0.0508)
		)
		(pad "J8" thru_hole circle
			(at 15.40002 11.8999 180)
			(size 0.906272 0.906272)
			(drill 0.499872)
			(layers "*.Cu" "*.Mask")
			(remove_unused_layers no)
			(net "GND")
			(clearance 0.0508)
			(thermal_gap 0.0508)
		)
		(pad "J9" thru_hole circle
			(at 17.599914 11.700002 180)
			(size 0.71628 0.71628)
			(drill 0.30988)
			(layers "*.Cu" "*.Mask")
			(remove_unused_layers no)
			(net "TP_CLK_100M_MB_2_DP")
			(clearance 0.0508)
			(thermal_gap 0.0508)
		)
		(pad "J10" thru_hole circle
			(at 19.800062 11.8999 180)
			(size 0.906272 0.906272)
			(drill 0.499872)
			(layers "*.Cu" "*.Mask")
			(remove_unused_layers no)
			(net "GND")
			(clearance 0.0508)
			(thermal_gap 0.0508)
		)
		(pad "K1" thru_hole circle
			(at 0 12.999974 180)
			(size 0.906272 0.906272)
			(drill 0.499872)
			(layers "*.Cu" "*.Mask")
			(remove_unused_layers no)
			(net "GND")
			(clearance 0.0508)
			(thermal_gap 0.0508)
		)
		(pad "K3" thru_hole circle
			(at 4.400042 12.999974 180)
			(size 0.906272 0.906272)
			(drill 0.499872)
			(layers "*.Cu" "*.Mask")
			(remove_unused_layers no)
			(net "GND")
			(clearance 0.0508)
			(thermal_gap 0.0508)
		)
		(pad "K5" thru_hole circle
			(at 8.800084 12.999974 180)
			(size 0.906272 0.906272)
			(drill 0.499872)
			(layers "*.Cu" "*.Mask")
			(remove_unused_layers no)
			(net "GND")
			(clearance 0.0508)
			(thermal_gap 0.0508)
		)
		(pad "K7" thru_hole circle
			(at 13.199872 12.999974 180)
			(size 0.906272 0.906272)
			(drill 0.499872)
			(layers "*.Cu" "*.Mask")
			(remove_unused_layers no)
			(net "GND")
			(clearance 0.0508)
			(thermal_gap 0.0508)
		)
		(pad "K9" thru_hole circle
			(at 17.599914 12.999974 180)
			(size 0.906272 0.906272)
			(drill 0.499872)
			(layers "*.Cu" "*.Mask")
			(remove_unused_layers no)
			(net "GND")
			(clearance 0.0508)
			(thermal_gap 0.0508)
		)
		(pad "K10" thru_hole circle
			(at 19.800062 13.199872 180)
			(size 0.71628 0.71628)
			(drill 0.30988)
			(layers "*.Cu" "*.Mask")
			(remove_unused_layers no)
			(net "CLK_100M_GPU_FPGA_REF_DN")
			(clearance 0.0508)
			(thermal_gap 0.0508)
		)
		(pad "L9" thru_hole circle
			(at 17.599914 14.299946 180)
			(size 0.71628 0.71628)
			(drill 0.30988)
			(layers "*.Cu" "*.Mask")
			(remove_unused_layers no)
			(net "USB2_MB_BMC_DN")
			(clearance 0.0508)
			(thermal_gap 0.0508)
		)
		(pad "L10" thru_hole circle
			(at 19.800062 14.500098 180)
			(size 0.71628 0.71628)
			(drill 0.30988)
			(layers "*.Cu" "*.Mask")
			(remove_unused_layers no)
			(net "CLK_100M_GPU_FPGA_REF_DP")
			(clearance 0.0508)
			(thermal_gap 0.0508)
		)
		(pad "M1_2" thru_hole circle
			(at 2.199894 15.80007 180)
			(size 0.906272 0.906272)
			(drill 0.499872)
			(layers "*.Cu" "*.Mask")
			(remove_unused_layers no)
			(net "GND")
			(clearance 0.0508)
			(thermal_gap 0.0508)
		)
		(pad "M1_4" thru_hole circle
			(at 6.599936 15.80007 180)
			(size 0.906272 0.906272)
			(drill 0.499872)
			(layers "*.Cu" "*.Mask")
			(remove_unused_layers no)
			(net "GND")
			(clearance 0.0508)
			(thermal_gap 0.0508)
		)
		(pad "M1_6" thru_hole circle
			(at 10.999978 15.80007 180)
			(size 0.906272 0.906272)
			(drill 0.499872)
			(layers "*.Cu" "*.Mask")
			(remove_unused_layers no)
			(net "GND")
			(clearance 0.0508)
			(thermal_gap 0.0508)
		)
		(pad "M1_8" thru_hole circle
			(at 15.40002 15.80007 180)
			(size 0.906272 0.906272)
			(drill 0.499872)
			(layers "*.Cu" "*.Mask")
			(remove_unused_layers no)
			(net "GND")
			(clearance 0.0508)
			(thermal_gap 0.0508)
		)
		(pad "M1_10" thru_hole circle
			(at 19.800062 15.80007 180)
			(size 0.906272 0.906272)
			(drill 0.499872)
			(layers "*.Cu" "*.Mask")
			(remove_unused_layers no)
			(net "GND")
			(clearance 0.0508)
			(thermal_gap 0.0508)
		)
		(pad "M2_2" thru_hole circle
			(at 2.199894 26.2001 180)
			(size 0.906272 0.906272)
			(drill 0.499872)
			(layers "*.Cu" "*.Mask")
			(remove_unused_layers no)
			(net "GND")
			(clearance 0.0508)
			(thermal_gap 0.0508)
		)
		(pad "M2_4" thru_hole circle
			(at 6.599936 26.2001 180)
			(size 0.906272 0.906272)
			(drill 0.499872)
			(layers "*.Cu" "*.Mask")
			(remove_unused_layers no)
			(net "GND")
			(clearance 0.0508)
			(thermal_gap 0.0508)
		)
		(pad "M2_6" thru_hole circle
			(at 10.999978 26.2001 180)
			(size 0.906272 0.906272)
			(drill 0.499872)
			(layers "*.Cu" "*.Mask")
			(remove_unused_layers no)
			(net "GND")
			(clearance 0.0508)
			(thermal_gap 0.0508)
		)
		(pad "M2_8" thru_hole circle
			(at 15.40002 26.2001 180)
			(size 0.906272 0.906272)
			(drill 0.499872)
			(layers "*.Cu" "*.Mask")
			(remove_unused_layers no)
			(net "GND")
			(clearance 0.0508)
			(thermal_gap 0.0508)
		)
		(pad "M2_10" thru_hole circle
			(at 19.800062 26.2001 180)
			(size 0.906272 0.906272)
			(drill 0.499872)
			(layers "*.Cu" "*.Mask")
			(remove_unused_layers no)
			(net "GND")
			(clearance 0.0508)
			(thermal_gap 0.0508)
		)
		(pad "M9" thru_hole circle
			(at 17.599914 15.599918 180)
			(size 0.71628 0.71628)
			(drill 0.30988)
			(layers "*.Cu" "*.Mask")
			(remove_unused_layers no)
			(net "USB2_MB_BMC_DP")
			(clearance 0.0508)
			(thermal_gap 0.0508)
		)
		(pad "N1_1" thru_hole circle
			(at 0 16.89989 180)
			(size 0.906272 0.906272)
			(drill 0.499872)
			(layers "*.Cu" "*.Mask")
			(remove_unused_layers no)
			(net "GND")
			(clearance 0.0508)
			(thermal_gap 0.0508)
		)
		(pad "N1_3" thru_hole circle
			(at 4.400042 16.89989 180)
			(size 0.906272 0.906272)
			(drill 0.499872)
			(layers "*.Cu" "*.Mask")
			(remove_unused_layers no)
			(net "GND")
			(clearance 0.0508)
			(thermal_gap 0.0508)
		)
		(pad "N1_5" thru_hole circle
			(at 8.800084 16.89989 180)
			(size 0.906272 0.906272)
			(drill 0.499872)
			(layers "*.Cu" "*.Mask")
			(remove_unused_layers no)
			(net "GND")
			(clearance 0.0508)
			(thermal_gap 0.0508)
		)
		(pad "N1_7" thru_hole circle
			(at 13.199872 16.89989 180)
			(size 0.906272 0.906272)
			(drill 0.499872)
			(layers "*.Cu" "*.Mask")
			(remove_unused_layers no)
			(net "GND")
			(clearance 0.0508)
			(thermal_gap 0.0508)
		)
		(pad "N1_9" thru_hole circle
			(at 17.599914 16.89989 180)
			(size 0.906272 0.906272)
			(drill 0.499872)
			(layers "*.Cu" "*.Mask")
			(remove_unused_layers no)
			(net "GND")
			(clearance 0.0508)
			(thermal_gap 0.0508)
		)
		(pad "N2_1" thru_hole circle
			(at 0 27.29992 180)
			(size 0.906272 0.906272)
			(drill 0.499872)
			(layers "*.Cu" "*.Mask")
			(remove_unused_layers no)
			(net "GND")
			(clearance 0.0508)
			(thermal_gap 0.0508)
		)
		(pad "N2_3" thru_hole circle
			(at 4.400042 27.29992 180)
			(size 0.906272 0.906272)
			(drill 0.499872)
			(layers "*.Cu" "*.Mask")
			(remove_unused_layers no)
			(net "GND")
			(clearance 0.0508)
			(thermal_gap 0.0508)
		)
		(pad "N2_5" thru_hole circle
			(at 8.800084 27.29992 180)
			(size 0.906272 0.906272)
			(drill 0.499872)
			(layers "*.Cu" "*.Mask")
			(remove_unused_layers no)
			(net "GND")
			(clearance 0.0508)
			(thermal_gap 0.0508)
		)
		(pad "N2_7" thru_hole circle
			(at 13.199872 27.29992 180)
			(size 0.906272 0.906272)
			(drill 0.499872)
			(layers "*.Cu" "*.Mask")
			(remove_unused_layers no)
			(net "GND")
			(clearance 0.0508)
			(thermal_gap 0.0508)
		)
		(pad "N2_9" thru_hole circle
			(at 17.599914 27.29992 180)
			(size 0.906272 0.906272)
			(drill 0.499872)
			(layers "*.Cu" "*.Mask")
			(remove_unused_layers no)
			(net "GND")
			(clearance 0.0508)
			(thermal_gap 0.0508)
		)
		(pad "N10" thru_hole circle
			(at 19.800062 27.500072 180)
			(size 0.71628 0.71628)
			(drill 0.30988)
			(layers "*.Cu" "*.Mask")
			(remove_unused_layers no)
			(net "CLK_100M_MB_1_DN")
			(clearance 0.0508)
			(thermal_gap 0.0508)
		)
		(pad "O9" thru_hole circle
			(at 17.599914 28.599892 180)
			(size 0.71628 0.71628)
			(drill 0.30988)
			(layers "*.Cu" "*.Mask")
			(remove_unused_layers no)
			(net "CLK_100M_MB_0_DN")
			(clearance 0.0508)
			(thermal_gap 0.0508)
		)
		(pad "O10" thru_hole circle
			(at 19.800062 28.800044 180)
			(size 0.71628 0.71628)
			(drill 0.30988)
			(layers "*.Cu" "*.Mask")
			(remove_unused_layers no)
			(net "CLK_100M_MB_1_DP")
			(clearance 0.0508)
			(thermal_gap 0.0508)
		)
		(pad "P2" thru_hole circle
			(at 2.199894 30.100016 180)
			(size 0.906272 0.906272)
			(drill 0.499872)
			(layers "*.Cu" "*.Mask")
			(remove_unused_layers no)
			(net "GND")
			(clearance 0.0508)
			(thermal_gap 0.0508)
		)
		(pad "P4" thru_hole circle
			(at 6.599936 30.100016 180)
			(size 0.906272 0.906272)
			(drill 0.499872)
			(layers "*.Cu" "*.Mask")
			(remove_unused_layers no)
			(net "GND")
			(clearance 0.0508)
			(thermal_gap 0.0508)
		)
		(pad "P6" thru_hole circle
			(at 10.999978 30.100016 180)
			(size 0.906272 0.906272)
			(drill 0.499872)
			(layers "*.Cu" "*.Mask")
			(remove_unused_layers no)
			(net "GND")
			(clearance 0.0508)
			(thermal_gap 0.0508)
		)
		(pad "P8" thru_hole circle
			(at 15.40002 30.100016 180)
			(size 0.906272 0.906272)
			(drill 0.499872)
			(layers "*.Cu" "*.Mask")
			(remove_unused_layers no)
			(net "GND")
			(clearance 0.0508)
			(thermal_gap 0.0508)
		)
		(pad "P9" thru_hole circle
			(at 17.599914 29.900118 180)
			(size 0.71628 0.71628)
			(drill 0.30988)
			(layers "*.Cu" "*.Mask")
			(remove_unused_layers no)
			(net "CLK_100M_MB_0_DP")
			(clearance 0.0508)
			(thermal_gap 0.0508)
		)
		(pad "P10" thru_hole circle
			(at 19.800062 30.100016 180)
			(size 0.906272 0.906272)
			(drill 0.499872)
			(layers "*.Cu" "*.Mask")
			(remove_unused_layers no)
			(net "GND")
			(clearance 0.0508)
			(thermal_gap 0.0508)
		)
		(pad "Q1" thru_hole circle
			(at 0 31.20009 180)
			(size 0.906272 0.906272)
			(drill 0.499872)
			(layers "*.Cu" "*.Mask")
			(remove_unused_layers no)
			(net "GND")
			(clearance 0.0508)
			(thermal_gap 0.0508)
		)
		(pad "Q3" thru_hole circle
			(at 4.400042 31.20009 180)
			(size 0.906272 0.906272)
			(drill 0.499872)
			(layers "*.Cu" "*.Mask")
			(remove_unused_layers no)
			(net "GND")
			(clearance 0.0508)
			(thermal_gap 0.0508)
		)
		(pad "Q5" thru_hole circle
			(at 8.800084 31.20009 180)
			(size 0.906272 0.906272)
			(drill 0.499872)
			(layers "*.Cu" "*.Mask")
			(remove_unused_layers no)
			(net "GND")
			(clearance 0.0508)
			(thermal_gap 0.0508)
		)
		(pad "Q7" thru_hole circle
			(at 13.199872 31.20009 180)
			(size 0.906272 0.906272)
			(drill 0.499872)
			(layers "*.Cu" "*.Mask")
			(remove_unused_layers no)
			(net "GND")
			(clearance 0.0508)
			(thermal_gap 0.0508)
		)
		(pad "Q9" thru_hole circle
			(at 17.599914 31.20009 180)
			(size 0.906272 0.906272)
			(drill 0.499872)
			(layers "*.Cu" "*.Mask")
			(remove_unused_layers no)
			(net "GND")
			(clearance 0.0508)
			(thermal_gap 0.0508)
		)
		(pad "Q10" thru_hole circle
			(at 19.800062 31.399988 180)
			(size 0.71628 0.71628)
			(drill 0.30988)
			(layers "*.Cu" "*.Mask")
			(remove_unused_layers no)
			(net "SMB_GPU_1_SCL")
			(clearance 0.0508)
			(thermal_gap 0.0508)
		)
		(pad "R9" thru_hole circle
			(at 17.599914 32.500062 180)
			(size 0.71628 0.71628)
			(drill 0.30988)
			(layers "*.Cu" "*.Mask")
			(remove_unused_layers no)
			(net "SMB_GPU_2_SCL")
			(clearance 0.0508)
			(thermal_gap 0.0508)
		)
		(pad "R10" thru_hole circle
			(at 19.800062 32.69996 180)
			(size 0.71628 0.71628)
			(drill 0.30988)
			(layers "*.Cu" "*.Mask")
			(remove_unused_layers no)
			(net "SMB_GPU_1_SDA")
			(clearance 0.0508)
			(thermal_gap 0.0508)
		)
		(pad "S2" thru_hole circle
			(at 2.199894 33.999932 180)
			(size 0.906272 0.906272)
			(drill 0.499872)
			(layers "*.Cu" "*.Mask")
			(remove_unused_layers no)
			(net "GND")
			(clearance 0.0508)
			(thermal_gap 0.0508)
		)
		(pad "S4" thru_hole circle
			(at 6.599936 33.999932 180)
			(size 0.906272 0.906272)
			(drill 0.499872)
			(layers "*.Cu" "*.Mask")
			(remove_unused_layers no)
			(net "GND")
			(clearance 0.0508)
			(thermal_gap 0.0508)
		)
		(pad "S6" thru_hole circle
			(at 10.999978 33.999932 180)
			(size 0.906272 0.906272)
			(drill 0.499872)
			(layers "*.Cu" "*.Mask")
			(remove_unused_layers no)
			(net "GND")
			(clearance 0.0508)
			(thermal_gap 0.0508)
		)
		(pad "S8" thru_hole circle
			(at 15.40002 33.999932 180)
			(size 0.906272 0.906272)
			(drill 0.499872)
			(layers "*.Cu" "*.Mask")
			(remove_unused_layers no)
			(net "GND")
			(clearance 0.0508)
			(thermal_gap 0.0508)
		)
		(pad "S9" thru_hole circle
			(at 17.599914 33.800034 180)
			(size 0.71628 0.71628)
			(drill 0.30988)
			(layers "*.Cu" "*.Mask")
			(remove_unused_layers no)
			(net "SMB_GPU_2_SDA")
			(clearance 0.0508)
			(thermal_gap 0.0508)
		)
		(pad "S10" thru_hole circle
			(at 19.800062 33.999932 180)
			(size 0.906272 0.906272)
			(drill 0.499872)
			(layers "*.Cu" "*.Mask")
			(remove_unused_layers no)
			(net "GND")
			(clearance 0.0508)
			(thermal_gap 0.0508)
		)
		(pad "T1" thru_hole circle
			(at 0 35.100006 180)
			(size 0.906272 0.906272)
			(drill 0.499872)
			(layers "*.Cu" "*.Mask")
			(remove_unused_layers no)
			(net "GND")
			(clearance 0.0508)
			(thermal_gap 0.0508)
		)
		(pad "T3" thru_hole circle
			(at 4.400042 35.100006 180)
			(size 0.906272 0.906272)
			(drill 0.499872)
			(layers "*.Cu" "*.Mask")
			(remove_unused_layers no)
			(net "GND")
			(clearance 0.0508)
			(thermal_gap 0.0508)
		)
		(pad "T5" thru_hole circle
			(at 8.800084 35.100006 180)
			(size 0.906272 0.906272)
			(drill 0.499872)
			(layers "*.Cu" "*.Mask")
			(remove_unused_layers no)
			(net "GND")
			(clearance 0.0508)
			(thermal_gap 0.0508)
		)
		(pad "T7" thru_hole circle
			(at 13.199872 35.100006 180)
			(size 0.906272 0.906272)
			(drill 0.499872)
			(layers "*.Cu" "*.Mask")
			(remove_unused_layers no)
			(net "GND")
			(clearance 0.0508)
			(thermal_gap 0.0508)
		)
		(pad "T9" thru_hole circle
			(at 17.599914 35.100006 180)
			(size 0.906272 0.906272)
			(drill 0.499872)
			(layers "*.Cu" "*.Mask")
			(remove_unused_layers no)
			(net "GND")
			(clearance 0.0508)
			(thermal_gap 0.0508)
		)
		(pad "T10" thru_hole circle
			(at 19.800062 35.299904 180)
			(size 0.71628 0.71628)
			(drill 0.30988)
			(layers "*.Cu" "*.Mask")
			(remove_unused_layers no)
			(net "Net_619")
			(clearance 0.0508)
			(thermal_gap 0.0508)
		)
		(pad "U9" thru_hole circle
			(at 17.599914 36.399978 180)
			(size 0.71628 0.71628)
			(drill 0.30988)
			(layers "*.Cu" "*.Mask")
			(remove_unused_layers no)
			(net "Net_620")
			(clearance 0.0508)
			(thermal_gap 0.0508)
		)
		(pad "U10" thru_hole circle
			(at 19.800062 36.599876 180)
			(size 0.71628 0.71628)
			(drill 0.30988)
			(layers "*.Cu" "*.Mask")
			(remove_unused_layers no)
			(net "Net_621")
			(clearance 0.0508)
			(thermal_gap 0.0508)
		)
		(pad "V2" thru_hole circle
			(at 2.199894 37.900102 180)
			(size 0.906272 0.906272)
			(drill 0.499872)
			(layers "*.Cu" "*.Mask")
			(remove_unused_layers no)
			(net "GND")
			(clearance 0.0508)
			(thermal_gap 0.0508)
		)
		(pad "V4" thru_hole circle
			(at 6.599936 37.900102 180)
			(size 0.906272 0.906272)
			(drill 0.499872)
			(layers "*.Cu" "*.Mask")
			(remove_unused_layers no)
			(net "GND")
			(clearance 0.0508)
			(thermal_gap 0.0508)
		)
		(pad "V6" thru_hole circle
			(at 10.999978 37.900102 180)
			(size 0.906272 0.906272)
			(drill 0.499872)
			(layers "*.Cu" "*.Mask")
			(remove_unused_layers no)
			(net "GND")
			(clearance 0.0508)
			(thermal_gap 0.0508)
		)
		(pad "V8" thru_hole circle
			(at 15.40002 37.900102 180)
			(size 0.906272 0.906272)
			(drill 0.499872)
			(layers "*.Cu" "*.Mask")
			(remove_unused_layers no)
			(net "GND")
			(clearance 0.0508)
			(thermal_gap 0.0508)
		)
		(pad "V9" thru_hole circle
			(at 17.599914 37.69995 180)
			(size 0.71628 0.71628)
			(drill 0.30988)
			(layers "*.Cu" "*.Mask")
			(remove_unused_layers no)
			(net "Net_624")
			(clearance 0.0508)
			(thermal_gap 0.0508)
		)
		(pad "V10" thru_hole circle
			(at 19.800062 37.900102 180)
			(size 0.906272 0.906272)
			(drill 0.499872)
			(layers "*.Cu" "*.Mask")
			(remove_unused_layers no)
			(net "GND")
			(clearance 0.0508)
			(thermal_gap 0.0508)
		)
		(pad "W1" thru_hole circle
			(at 0 38.999922 180)
			(size 0.906272 0.906272)
			(drill 0.499872)
			(layers "*.Cu" "*.Mask")
			(remove_unused_layers no)
			(net "GND")
			(clearance 0.0508)
			(thermal_gap 0.0508)
		)
		(pad "W3" thru_hole circle
			(at 4.400042 38.999922 180)
			(size 0.906272 0.906272)
			(drill 0.499872)
			(layers "*.Cu" "*.Mask")
			(remove_unused_layers no)
			(net "GND")
			(clearance 0.0508)
			(thermal_gap 0.0508)
		)
		(pad "W5" thru_hole circle
			(at 8.800084 38.999922 180)
			(size 0.906272 0.906272)
			(drill 0.499872)
			(layers "*.Cu" "*.Mask")
			(remove_unused_layers no)
			(net "GND")
			(clearance 0.0508)
			(thermal_gap 0.0508)
		)
		(pad "W7" thru_hole circle
			(at 13.199872 38.999922 180)
			(size 0.906272 0.906272)
			(drill 0.499872)
			(layers "*.Cu" "*.Mask")
			(remove_unused_layers no)
			(net "GND")
			(clearance 0.0508)
			(thermal_gap 0.0508)
		)
		(pad "W9" thru_hole circle
			(at 17.599914 38.999922 180)
			(size 0.906272 0.906272)
			(drill 0.499872)
			(layers "*.Cu" "*.Mask")
			(remove_unused_layers no)
			(net "GND")
			(clearance 0.0508)
			(thermal_gap 0.0508)
		)
		(pad "W10" thru_hole circle
			(at 19.800062 39.200074 180)
			(size 0.71628 0.71628)
			(drill 0.30988)
			(layers "*.Cu" "*.Mask")
			(remove_unused_layers no)
			(net "Net_618")
			(clearance 0.0508)
			(thermal_gap 0.0508)
		)
		(pad "X9" thru_hole circle
			(at 17.599914 40.299894 180)
			(size 0.71628 0.71628)
			(drill 0.30988)
			(layers "*.Cu" "*.Mask")
			(remove_unused_layers no)
			(net "Net_625")
			(clearance 0.0508)
			(thermal_gap 0.0508)
		)
		(pad "X10" thru_hole circle
			(at 19.800062 40.500046 180)
			(size 0.71628 0.71628)
			(drill 0.30988)
			(layers "*.Cu" "*.Mask")
			(remove_unused_layers no)
			(net "Net_622")
			(clearance 0.0508)
			(thermal_gap 0.0508)
		)
		(pad "Y2" thru_hole circle
			(at 2.199894 41.800018 180)
			(size 0.906272 0.906272)
			(drill 0.499872)
			(layers "*.Cu" "*.Mask")
			(remove_unused_layers no)
			(net "GND")
			(clearance 0.0508)
			(thermal_gap 0.0508)
		)
		(pad "Y4" thru_hole circle
			(at 6.599936 41.800018 180)
			(size 0.906272 0.906272)
			(drill 0.499872)
			(layers "*.Cu" "*.Mask")
			(remove_unused_layers no)
			(net "GND")
			(clearance 0.0508)
			(thermal_gap 0.0508)
		)
		(pad "Y6" thru_hole circle
			(at 10.999978 41.800018 180)
			(size 0.906272 0.906272)
			(drill 0.499872)
			(layers "*.Cu" "*.Mask")
			(remove_unused_layers no)
			(net "GND")
			(clearance 0.0508)
			(thermal_gap 0.0508)
		)
		(pad "Y8" thru_hole circle
			(at 15.40002 41.800018 180)
			(size 0.906272 0.906272)
			(drill 0.499872)
			(layers "*.Cu" "*.Mask")
			(remove_unused_layers no)
			(net "GND")
			(clearance 0.0508)
			(thermal_gap 0.0508)
		)
		(pad "Y9" thru_hole circle
			(at 17.599914 41.60012 180)
			(size 0.71628 0.71628)
			(drill 0.30988)
			(layers "*.Cu" "*.Mask")
			(remove_unused_layers no)
			(net "Net_623")
			(clearance 0.0508)
			(thermal_gap 0.0508)
		)
		(pad "Y10" thru_hole circle
			(at 19.800062 41.800018 180)
			(size 0.906272 0.906272)
			(drill 0.499872)
			(layers "*.Cu" "*.Mask")
			(remove_unused_layers no)
			(net "GND")
			(clearance 0.0508)
			(thermal_gap 0.0508)
		)
		(pad "Z1" thru_hole circle
			(at 0 42.900092 180)
			(size 0.906272 0.906272)
			(drill 0.499872)
			(layers "*.Cu" "*.Mask")
			(remove_unused_layers no)
			(net "GND")
			(clearance 0.0508)
			(thermal_gap 0.0508)
		)
		(pad "Z2" thru_hole circle
			(at 2.199894 43.09999 180)
			(size 0.71628 0.71628)
			(drill 0.30988)
			(layers "*.Cu" "*.Mask")
			(remove_unused_layers no)
			(net "PRSNT_GPU_D_R_N")
			(clearance 0.0508)
			(thermal_gap 0.0508)
		)
		(pad "Z3" thru_hole circle
			(at 4.400042 42.900092 180)
			(size 0.906272 0.906272)
			(drill 0.499872)
			(layers "*.Cu" "*.Mask")
			(remove_unused_layers no)
			(net "GND")
			(clearance 0.0508)
			(thermal_gap 0.0508)
		)
		(pad "Z4" thru_hole circle
			(at 6.599936 43.09999 180)
			(size 0.71628 0.71628)
			(drill 0.30988)
			(layers "*.Cu" "*.Mask")
			(remove_unused_layers no)
			(net "GPU_BASE_PWR_EN")
			(clearance 0.0508)
			(thermal_gap 0.0508)
		)
		(pad "Z5" thru_hole circle
			(at 8.800084 42.900092 180)
			(size 0.906272 0.906272)
			(drill 0.499872)
			(layers "*.Cu" "*.Mask")
			(remove_unused_layers no)
			(net "GND")
			(clearance 0.0508)
			(thermal_gap 0.0508)
		)
		(pad "Z6" thru_hole circle
			(at 10.999978 43.09999 180)
			(size 0.71628 0.71628)
			(drill 0.30988)
			(layers "*.Cu" "*.Mask")
			(remove_unused_layers no)
			(net "GPU_BASE_PWR_GD_R")
			(clearance 0.0508)
			(thermal_gap 0.0508)
		)
		(pad "Z7" thru_hole circle
			(at 13.199872 42.900092 180)
			(size 0.906272 0.906272)
			(drill 0.499872)
			(layers "*.Cu" "*.Mask")
			(remove_unused_layers no)
			(net "GND")
			(clearance 0.0508)
			(thermal_gap 0.0508)
		)
		(pad "Z8" thru_hole circle
			(at 15.40002 43.09999 180)
			(size 0.71628 0.71628)
			(drill 0.30988)
			(layers "*.Cu" "*.Mask")
			(remove_unused_layers no)
			(net "GPU_BASE_ID1")
			(clearance 0.0508)
			(thermal_gap 0.0508)
		)
		(pad "Z9" thru_hole circle
			(at 17.599914 42.900092 180)
			(size 0.906272 0.906272)
			(drill 0.499872)
			(layers "*.Cu" "*.Mask")
			(remove_unused_layers no)
			(net "GND")
			(clearance 0.0508)
			(thermal_gap 0.0508)
		)
		(pad "Z10" thru_hole circle
			(at 19.800062 43.09999 180)
			(size 0.71628 0.71628)
			(drill 0.30988)
			(layers "*.Cu" "*.Mask")
			(remove_unused_layers no)
			(net "RST_MB_PERST_0_N")
			(clearance 0.0508)
			(thermal_gap 0.0508)
		)
		(zone
			(layer "B.Cu")
			(hatch none 0.5)
			(connect_pads
				(clearance 0)
			)
			(min_thickness 0.25)
			(keepout
				(tracks allowed)
				(vias not_allowed)
				(pads allowed)
				(copperpour not_allowed)
				(footprints allowed)
			)
			(placement
				(enabled no)
				(sheetname "")
			)
			(fill
				(thermal_gap 0.5)
				(thermal_bridge_width 0.5)
				(island_removal_mode 0)
			)
			(polygon
				(pts
					(xy 71.392796 -394.665708) (xy 92.220796 -394.665708) (xy 92.220796 -412.50743) (xy 71.392796 -412.50743)
				)
			)
		)
		(zone
			(layer "B.Cu")
			(hatch none 0.5)
			(connect_pads
				(clearance 0)
			)
			(min_thickness 0.25)
			(keepout
				(tracks allowed)
				(vias not_allowed)
				(pads allowed)
				(copperpour not_allowed)
				(footprints allowed)
			)
			(placement
				(enabled no)
				(sheetname "")
			)
			(fill
				(thermal_gap 0.5)
				(thermal_bridge_width 0.5)
				(island_removal_mode 0)
			)
			(polygon
				(pts
					(xy 71.392796 -368.572796) (xy 92.220796 -368.572796) (xy 92.220796 -386.414518) (xy 71.392796 -386.414518)
				)
			)
		)
	)
	(footprint ""
		(layer "F.Cu")
		(at 238.324898 -85.151468 90)
		(property "Reference" "R1017"
			(at 0 0 90)
			(layer "F.SilkS")
			(hide yes)
			(effects
				(font
					(size 1.27 1.27)
				)
			)
		)
		(property "Value" ""
			(at 0 0 90)
			(layer "F.Fab")
			(effects
				(font
					(size 1.27 1.27)
				)
			)
		)
		(duplicate_pad_numbers_are_jumpers no)
		(fp_line
			(start -0.7874 -0.4064)
			(end -0.020066 -0.4064)
			(stroke
				(width 0.1524)
				(type default)
			)
			(layer "F.SilkS")
		)
		(fp_line
			(start 0.7874 0.4064)
			(end 0.001524 0.4064)
			(stroke
				(width 0.1524)
				(type default)
			)
			(layer "F.SilkS")
		)
		(fp_line
			(start -0.12065 -0.305054)
			(end -0.12065 -0.2794)
			(stroke
				(width 0.1)
				(type default)
			)
			(layer "F.Fab")
		)
		(fp_line
			(start -0.67945 -0.305054)
			(end -0.12065 -0.305054)
			(stroke
				(width 0.1)
				(type default)
			)
			(layer "F.Fab")
		)
		(fp_line
			(start 0.67945 -0.3048)
			(end 0.67945 0.3048)
			(stroke
				(width 0.1)
				(type default)
			)
			(layer "F.Fab")
		)
		(fp_line
			(start 0.12065 -0.3048)
			(end 0.67945 -0.3048)
			(stroke
				(width 0.1)
				(type default)
			)
			(layer "F.Fab")
		)
		(fp_line
			(start 0.12065 -0.2794)
			(end 0.12065 -0.3048)
			(stroke
				(width 0.1)
				(type default)
			)
			(layer "F.Fab")
		)
		(fp_line
			(start -0.12065 -0.2794)
			(end 0.12065 -0.2794)
			(stroke
				(width 0.1)
				(type default)
			)
			(layer "F.Fab")
		)
		(fp_line
			(start 0.120396 0.2794)
			(end -0.12065 0.2794)
			(stroke
				(width 0.1)
				(type default)
			)
			(layer "F.Fab")
		)
		(fp_line
			(start -0.12065 0.2794)
			(end -0.12065 0.3048)
			(stroke
				(width 0.1)
				(type default)
			)
			(layer "F.Fab")
		)
		(fp_line
			(start 0.67945 0.3048)
			(end 0.120396 0.3048)
			(stroke
				(width 0.1)
				(type default)
			)
			(layer "F.Fab")
		)
		(fp_line
			(start 0.120396 0.3048)
			(end 0.120396 0.2794)
			(stroke
				(width 0.1)
				(type default)
			)
			(layer "F.Fab")
		)
		(fp_line
			(start -0.12065 0.3048)
			(end -0.67945 0.3048)
			(stroke
				(width 0.1)
				(type default)
			)
			(layer "F.Fab")
		)
		(fp_line
			(start -0.67945 0.3048)
			(end -0.67945 -0.305054)
			(stroke
				(width 0.1)
				(type default)
			)
			(layer "F.Fab")
		)
		(pad "1" smd rect
			(at -0.40005 0 270)
			(size 0.4572 0.508)
			(layers "F.Cu" "F.Mask" "F.Paste")
			(net "USB2_FT4232_CLI_R_DN")
		)
		(pad "2" smd rect
			(at 0.40005 0 270)
			(size 0.4572 0.508)
			(layers "F.Cu" "F.Mask" "F.Paste")
			(net "USB2_FT4232_CLI_DN")
		)
	)
	(footprint ""
		(layer "F.Cu")
		(at 206.96809 -289.230816 90)
		(property "Reference" "R3939"
			(at 0 0 90)
			(layer "F.SilkS")
			(hide yes)
			(effects
				(font
					(size 1.27 1.27)
				)
			)
		)
		(property "Value" ""
			(at 0 0 90)
			(layer "F.Fab")
			(effects
				(font
					(size 1.27 1.27)
				)
			)
		)
		(duplicate_pad_numbers_are_jumpers no)
		(fp_line
			(start 0.7874 -0.4064)
			(end 0.7874 0.4064)
			(stroke
				(width 0.1524)
				(type default)
			)
			(layer "F.SilkS")
		)
		(fp_line
			(start -0.7874 -0.4064)
			(end 0.7874 -0.4064)
			(stroke
				(width 0.1524)
				(type default)
			)
			(layer "F.SilkS")
		)
		(fp_line
			(start 0.7874 0.4064)
			(end -0.7874 0.4064)
			(stroke
				(width 0.1524)
				(type default)
			)
			(layer "F.SilkS")
		)
		(fp_line
			(start -0.7874 0.4064)
			(end -0.7874 -0.4064)
			(stroke
				(width 0.1524)
				(type default)
			)
			(layer "F.SilkS")
		)
		(fp_line
			(start -0.12065 -0.305054)
			(end -0.12065 -0.2794)
			(stroke
				(width 0.1)
				(type default)
			)
			(layer "F.Fab")
		)
		(fp_line
			(start -0.67945 -0.305054)
			(end -0.12065 -0.305054)
			(stroke
				(width 0.1)
				(type default)
			)
			(layer "F.Fab")
		)
		(fp_line
			(start 0.67945 -0.3048)
			(end 0.67945 0.3048)
			(stroke
				(width 0.1)
				(type default)
			)
			(layer "F.Fab")
		)
		(fp_line
			(start 0.12065 -0.3048)
			(end 0.67945 -0.3048)
			(stroke
				(width 0.1)
				(type default)
			)
			(layer "F.Fab")
		)
		(fp_line
			(start 0.12065 -0.2794)
			(end 0.12065 -0.3048)
			(stroke
				(width 0.1)
				(type default)
			)
			(layer "F.Fab")
		)
		(fp_line
			(start -0.12065 -0.2794)
			(end 0.12065 -0.2794)
			(stroke
				(width 0.1)
				(type default)
			)
			(layer "F.Fab")
		)
		(fp_line
			(start 0.120396 0.2794)
			(end -0.12065 0.2794)
			(stroke
				(width 0.1)
				(type default)
			)
			(layer "F.Fab")
		)
		(fp_line
			(start -0.12065 0.2794)
			(end -0.12065 0.3048)
			(stroke
				(width 0.1)
				(type default)
			)
			(layer "F.Fab")
		)
		(fp_line
			(start 0.67945 0.3048)
			(end 0.120396 0.3048)
			(stroke
				(width 0.1)
				(type default)
			)
			(layer "F.Fab")
		)
		(fp_line
			(start 0.120396 0.3048)
			(end 0.120396 0.2794)
			(stroke
				(width 0.1)
				(type default)
			)
			(layer "F.Fab")
		)
		(fp_line
			(start -0.12065 0.3048)
			(end -0.67945 0.3048)
			(stroke
				(width 0.1)
				(type default)
			)
			(layer "F.Fab")
		)
		(fp_line
			(start -0.67945 0.3048)
			(end -0.67945 -0.305054)
			(stroke
				(width 0.1)
				(type default)
			)
			(layer "F.Fab")
		)
		(pad "1" smd circle
			(at -0.40005 0 90)
			(size 0 0)
			(layers "F.Cu" "F.Mask" "F.Paste")
			(net "SMB_PEX1_FPGA_SCL")
		)
		(pad "2" smd circle
			(at 0.40005 0 90)
			(size 0 0)
			(layers "F.Cu" "F.Mask" "F.Paste")
			(net "SMB_PEX1_HOST_LS_SCL")
		)
	)
	(footprint ""
		(layer "F.Cu")
		(at 381.587756 -288.419032)
		(property "Reference" "C3577"
			(at 0 0 0)
			(layer "F.SilkS")
			(hide yes)
			(effects
				(font
					(size 1.27 1.27)
				)
			)
		)
		(property "Value" ""
			(at 0 0 0)
			(layer "F.Fab")
			(effects
				(font
					(size 1.27 1.27)
				)
			)
		)
		(duplicate_pad_numbers_are_jumpers no)
		(fp_line
			(start -1.2954 -0.5842)
			(end 1.2954 -0.5842)
			(stroke
				(width 0.1524)
				(type default)
			)
			(layer "F.SilkS")
		)
		(fp_line
			(start -1.2954 0.5842)
			(end -1.2954 -0.5842)
			(stroke
				(width 0.1524)
				(type default)
			)
			(layer "F.SilkS")
		)
		(fp_line
			(start 1.2954 -0.5842)
			(end 1.2954 0.5842)
			(stroke
				(width 0.1524)
				(type default)
			)
			(layer "F.SilkS")
		)
		(fp_line
			(start 1.2954 0.5842)
			(end -1.2954 0.5842)
			(stroke
				(width 0.1524)
				(type default)
			)
			(layer "F.SilkS")
		)
		(fp_line
			(start -1.1938 -0.4064)
			(end -0.8636 -0.4064)
			(stroke
				(width 0.1)
				(type default)
			)
			(layer "F.Fab")
		)
		(fp_line
			(start -1.1938 0.4064)
			(end -1.1938 -0.4064)
			(stroke
				(width 0.1)
				(type default)
			)
			(layer "F.Fab")
		)
		(fp_line
			(start -0.8636 -0.4572)
			(end 0.8636 -0.4572)
			(stroke
				(width 0.1)
				(type default)
			)
			(layer "F.Fab")
		)
		(fp_line
			(start -0.8636 -0.4064)
			(end -0.8636 -0.4572)
			(stroke
				(width 0.1)
				(type default)
			)
			(layer "F.Fab")
		)
		(fp_line
			(start -0.8636 0.4064)
			(end -1.1938 0.4064)
			(stroke
				(width 0.1)
				(type default)
			)
			(layer "F.Fab")
		)
		(fp_line
			(start -0.8636 0.4572)
			(end -0.8636 0.4064)
			(stroke
				(width 0.1)
				(type default)
			)
			(layer "F.Fab")
		)
		(fp_line
			(start 0.8636 -0.4572)
			(end 0.8636 -0.4064)
			(stroke
				(width 0.1)
				(type default)
			)
			(layer "F.Fab")
		)
		(fp_line
			(start 0.8636 -0.4064)
			(end 1.1938 -0.4064)
			(stroke
				(width 0.1)
				(type default)
			)
			(layer "F.Fab")
		)
		(fp_line
			(start 0.8636 0.4064)
			(end 0.8636 0.4572)
			(stroke
				(width 0.1)
				(type default)
			)
			(layer "F.Fab")
		)
		(fp_line
			(start 0.8636 0.4572)
			(end -0.8636 0.4572)
			(stroke
				(width 0.1)
				(type default)
			)
			(layer "F.Fab")
		)
		(fp_line
			(start 1.1938 -0.4064)
			(end 1.1938 0.4064)
			(stroke
				(width 0.1)
				(type default)
			)
			(layer "F.Fab")
		)
		(fp_line
			(start 1.1938 0.4064)
			(end 0.8636 0.4064)
			(stroke
				(width 0.1)
				(type default)
			)
			(layer "F.Fab")
		)
		(pad "1" smd rect
			(at -0.7366 0 270)
			(size 0.7112 0.8128)
			(layers "F.Cu" "F.Mask" "F.Paste")
			(net "PCEPLL6_VDDA18_PEX3")
		)
		(pad "2" smd rect
			(at 0.7366 0 270)
			(size 0.7112 0.8128)
			(layers "F.Cu" "F.Mask" "F.Paste")
			(net "GND")
		)
	)
	(footprint ""
		(layer "F.Cu")
		(at 134.366 -282.421584 -90)
		(property "Reference" "PC113"
			(at 0 0 270)
			(layer "F.SilkS")
			(hide yes)
			(effects
				(font
					(size 1.27 1.27)
				)
			)
		)
		(property "Value" ""
			(at 0 0 270)
			(layer "F.Fab")
			(effects
				(font
					(size 1.27 1.27)
				)
			)
		)
		(duplicate_pad_numbers_are_jumpers no)
		(fp_line
			(start -0.7874 0.4064)
			(end -0.7874 -0.4064)
			(stroke
				(width 0.1524)
				(type default)
			)
			(layer "F.SilkS")
		)
		(fp_line
			(start 0.7874 0.4064)
			(end -0.7874 0.4064)
			(stroke
				(width 0.1524)
				(type default)
			)
			(layer "F.SilkS")
		)
		(fp_line
			(start -0.7874 -0.4064)
			(end 0.7874 -0.4064)
			(stroke
				(width 0.1524)
				(type default)
			)
			(layer "F.SilkS")
		)
		(fp_line
			(start 0.7874 -0.4064)
			(end 0.7874 0.4064)
			(stroke
				(width 0.1524)
				(type default)
			)
			(layer "F.SilkS")
		)
		(fp_line
			(start -0.67945 0.3048)
			(end -0.67945 -0.305054)
			(stroke
				(width 0.1)
				(type default)
			)
			(layer "F.Fab")
		)
		(fp_line
			(start -0.12065 0.3048)
			(end -0.67945 0.3048)
			(stroke
				(width 0.1)
				(type default)
			)
			(layer "F.Fab")
		)
		(fp_line
			(start 0.120396 0.3048)
			(end 0.120396 0.2794)
			(stroke
				(width 0.1)
				(type default)
			)
			(layer "F.Fab")
		)
		(fp_line
			(start 0.67945 0.3048)
			(end 0.120396 0.3048)
			(stroke
				(width 0.1)
				(type default)
			)
			(layer "F.Fab")
		)
		(fp_line
			(start -0.12065 0.2794)
			(end -0.12065 0.3048)
			(stroke
				(width 0.1)
				(type default)
			)
			(layer "F.Fab")
		)
		(fp_line
			(start 0.120396 0.2794)
			(end -0.12065 0.2794)
			(stroke
				(width 0.1)
				(type default)
			)
			(layer "F.Fab")
		)
		(fp_line
			(start -0.12065 -0.2794)
			(end 0.12065 -0.2794)
			(stroke
				(width 0.1)
				(type default)
			)
			(layer "F.Fab")
		)
		(fp_line
			(start 0.12065 -0.2794)
			(end 0.12065 -0.3048)
			(stroke
				(width 0.1)
				(type default)
			)
			(layer "F.Fab")
		)
		(fp_line
			(start 0.12065 -0.3048)
			(end 0.67945 -0.3048)
			(stroke
				(width 0.1)
				(type default)
			)
			(layer "F.Fab")
		)
		(fp_line
			(start 0.67945 -0.3048)
			(end 0.67945 0.3048)
			(stroke
				(width 0.1)
				(type default)
			)
			(layer "F.Fab")
		)
		(fp_line
			(start -0.67945 -0.305054)
			(end -0.12065 -0.305054)
			(stroke
				(width 0.1)
				(type default)
			)
			(layer "F.Fab")
		)
		(fp_line
			(start -0.12065 -0.305054)
			(end -0.12065 -0.2794)
			(stroke
				(width 0.1)
				(type default)
			)
			(layer "F.Fab")
		)
		(pad "1" smd circle
			(at -0.40005 0 270)
			(size 0 0)
			(layers "F.Cu" "F.Mask" "F.Paste")
			(net "P0V8_PEX1_VCC2")
		)
		(pad "2" smd circle
			(at 0.40005 0 270)
			(size 0 0)
			(layers "F.Cu" "F.Mask" "F.Paste")
			(net "GND")
		)
	)
	(footprint ""
		(layer "F.Cu")
		(at 6.119114 -59.574684 90)
		(property "Reference" "PC541"
			(at 0 0 90)
			(layer "F.SilkS")
			(hide yes)
			(effects
				(font
					(size 1.27 1.27)
				)
			)
		)
		(property "Value" ""
			(at 0 0 90)
			(layer "F.Fab")
			(effects
				(font
					(size 1.27 1.27)
				)
			)
		)
		(duplicate_pad_numbers_are_jumpers no)
		(fp_line
			(start 0.7874 -0.4064)
			(end 0.7874 0.4064)
			(stroke
				(width 0.1524)
				(type default)
			)
			(layer "F.SilkS")
		)
		(fp_line
			(start -0.7874 -0.4064)
			(end 0.7874 -0.4064)
			(stroke
				(width 0.1524)
				(type default)
			)
			(layer "F.SilkS")
		)
		(fp_line
			(start 0.7874 0.4064)
			(end -0.7874 0.4064)
			(stroke
				(width 0.1524)
				(type default)
			)
			(layer "F.SilkS")
		)
		(fp_line
			(start -0.7874 0.4064)
			(end -0.7874 -0.4064)
			(stroke
				(width 0.1524)
				(type default)
			)
			(layer "F.SilkS")
		)
		(fp_line
			(start -0.12065 -0.305054)
			(end -0.12065 -0.2794)
			(stroke
				(width 0.1)
				(type default)
			)
			(layer "F.Fab")
		)
		(fp_line
			(start -0.67945 -0.305054)
			(end -0.12065 -0.305054)
			(stroke
				(width 0.1)
				(type default)
			)
			(layer "F.Fab")
		)
		(fp_line
			(start 0.67945 -0.3048)
			(end 0.67945 0.3048)
			(stroke
				(width 0.1)
				(type default)
			)
			(layer "F.Fab")
		)
		(fp_line
			(start 0.12065 -0.3048)
			(end 0.67945 -0.3048)
			(stroke
				(width 0.1)
				(type default)
			)
			(layer "F.Fab")
		)
		(fp_line
			(start 0.12065 -0.2794)
			(end 0.12065 -0.3048)
			(stroke
				(width 0.1)
				(type default)
			)
			(layer "F.Fab")
		)
		(fp_line
			(start -0.12065 -0.2794)
			(end 0.12065 -0.2794)
			(stroke
				(width 0.1)
				(type default)
			)
			(layer "F.Fab")
		)
		(fp_line
			(start 0.120396 0.2794)
			(end -0.12065 0.2794)
			(stroke
				(width 0.1)
				(type default)
			)
			(layer "F.Fab")
		)
		(fp_line
			(start -0.12065 0.2794)
			(end -0.12065 0.3048)
			(stroke
				(width 0.1)
				(type default)
			)
			(layer "F.Fab")
		)
		(fp_line
			(start 0.67945 0.3048)
			(end 0.120396 0.3048)
			(stroke
				(width 0.1)
				(type default)
			)
			(layer "F.Fab")
		)
		(fp_line
			(start 0.120396 0.3048)
			(end 0.120396 0.2794)
			(stroke
				(width 0.1)
				(type default)
			)
			(layer "F.Fab")
		)
		(fp_line
			(start -0.12065 0.3048)
			(end -0.67945 0.3048)
			(stroke
				(width 0.1)
				(type default)
			)
			(layer "F.Fab")
		)
		(fp_line
			(start -0.67945 0.3048)
			(end -0.67945 -0.305054)
			(stroke
				(width 0.1)
				(type default)
			)
			(layer "F.Fab")
		)
		(pad "1" smd circle
			(at -0.40005 0 90)
			(size 0 0)
			(layers "F.Cu" "F.Mask" "F.Paste")
			(net "P5V_AUX")
		)
		(pad "2" smd circle
			(at 0.40005 0 90)
			(size 0 0)
			(layers "F.Cu" "F.Mask" "F.Paste")
			(net "GND")
		)
	)
	(footprint ""
		(layer "F.Cu")
		(at 248.94159 -378.393706 -90)
		(property "Reference" "PR6602"
			(at 0 0 270)
			(layer "F.SilkS")
			(hide yes)
			(effects
				(font
					(size 1.27 1.27)
				)
			)
		)
		(property "Value" ""
			(at 0 0 270)
			(layer "F.Fab")
			(effects
				(font
					(size 1.27 1.27)
				)
			)
		)
		(duplicate_pad_numbers_are_jumpers no)
		(fp_line
			(start -3.9878 3.5814)
			(end -3.9878 -3.5814)
			(stroke
				(width 0.1524)
				(type default)
			)
			(layer "F.SilkS")
		)
		(fp_line
			(start 3.9878 3.5814)
			(end -3.9878 3.5814)
			(stroke
				(width 0.1524)
				(type default)
			)
			(layer "F.SilkS")
		)
		(fp_line
			(start -3.9878 -3.5814)
			(end 3.9878 -3.5814)
			(stroke
				(width 0.1524)
				(type default)
			)
			(layer "F.SilkS")
		)
		(fp_line
			(start 3.9878 -3.5814)
			(end 3.9878 3.5814)
			(stroke
				(width 0.1524)
				(type default)
			)
			(layer "F.SilkS")
		)
		(fp_line
			(start -3.5306 3.353054)
			(end -3.5306 -3.353054)
			(stroke
				(width 0.1)
				(type default)
			)
			(layer "F.Fab")
		)
		(fp_line
			(start 3.5306 3.353054)
			(end -3.5306 3.353054)
			(stroke
				(width 0.1)
				(type default)
			)
			(layer "F.Fab")
		)
		(fp_line
			(start -3.5306 -3.353054)
			(end 3.5306 -3.353054)
			(stroke
				(width 0.1)
				(type default)
			)
			(layer "F.Fab")
		)
		(fp_line
			(start 3.5306 -3.353054)
			(end 3.5306 3.353054)
			(stroke
				(width 0.1)
				(type default)
			)
			(layer "F.Fab")
		)
		(pad "1A" smd rect
			(at -2.249932 0 90)
			(size 3.2004 6.858)
			(layers "F.Cu" "F.Mask" "F.Paste")
			(net "P12V_STBY")
		)
		(pad "1B" smd rect
			(at -0.776732 0 270)
			(size 0.254 0.508)
			(layers "F.Cu" "F.Mask" "F.Paste")
			(net "P12V_HSC_SENSE2_R1_P")
		)
		(pad "2A" smd rect
			(at 2.249932 0 90)
			(size 3.2004 6.858)
			(layers "F.Cu" "F.Mask" "F.Paste")
			(net "P12V_STBY_R2")
		)
		(pad "2B" smd rect
			(at 0.776732 0 270)
			(size 0.254 0.508)
			(layers "F.Cu" "F.Mask" "F.Paste")
			(net "P12V_HSC_SENSE2_R1_N")
		)
	)
	(footprint ""
		(layer "F.Cu")
		(at 223.445832 -102.356666 -90)
		(property "Reference" "PU28"
			(at 1.75641 2.251964 90)
			(unlocked yes)
			(layer "F.SilkS")
			(effects
				(font
					(size 0.7874 0.5842)
					(thickness 0.1524)
				)
				(justify left)
			)
		)
		(property "Value" ""
			(at 0 0 270)
			(layer "F.Fab")
			(effects
				(font
					(size 1.27 1.27)
				)
			)
		)
		(duplicate_pad_numbers_are_jumpers no)
		(fp_line
			(start -1.943608 1.549908)
			(end -1.943608 -1.549908)
			(stroke
				(width 0.1524)
				(type default)
			)
			(layer "F.SilkS")
		)
		(fp_line
			(start 1.943608 1.549908)
			(end -1.943608 1.549908)
			(stroke
				(width 0.1524)
				(type default)
			)
			(layer "F.SilkS")
		)
		(fp_line
			(start -1.943608 -1.549908)
			(end 1.943608 -1.549908)
			(stroke
				(width 0.1524)
				(type default)
			)
			(layer "F.SilkS")
		)
		(fp_line
			(start 1.943608 -1.549908)
			(end 1.943608 1.549908)
			(stroke
				(width 0.1524)
				(type default)
			)
			(layer "F.SilkS")
		)
		(fp_poly
			(pts
				(xy -2.019808 -1.549908) (xy -1.257808 -1.549908) (xy -1.257808 -1.880108) (xy -2.019808 -1.880108)
			)
			(stroke
				(width 0)
				(type default)
			)
			(fill yes)
			(layer "F.SilkS")
		)
		(fp_line
			(start -1.549908 1.549908)
			(end -1.549908 -1.549908)
			(stroke
				(width 0.1)
				(type default)
			)
			(layer "F.Fab")
		)
		(fp_line
			(start 1.549908 1.549908)
			(end -1.549908 1.549908)
			(stroke
				(width 0.1)
				(type default)
			)
			(layer "F.Fab")
		)
		(fp_line
			(start -1.549908 -1.549908)
			(end 1.549908 -1.549908)
			(stroke
				(width 0.1)
				(type default)
			)
			(layer "F.Fab")
		)
		(fp_line
			(start 1.549908 -1.549908)
			(end 1.549908 1.549908)
			(stroke
				(width 0.1)
				(type default)
			)
			(layer "F.Fab")
		)
		(fp_poly
			(pts
				(xy -2.019808 -1.549908) (xy -1.257808 -1.549908) (xy -1.257808 -1.880108) (xy -2.019808 -1.880108)
			)
			(stroke
				(width 0)
				(type default)
			)
			(fill yes)
			(layer "F.Fab")
		)
		(pad "1" smd rect
			(at -1.500124 -1.249934 180)
			(size 0.2794 0.6096)
			(layers "F.Cu" "F.Mask" "F.Paste")
			(net "P12V_NIC3_R")
		)
		(pad "2" smd rect
			(at -1.500124 -0.750062 180)
			(size 0.2794 0.6096)
			(layers "F.Cu" "F.Mask" "F.Paste")
			(net "P12V_NIC3_R")
		)
		(pad "3" smd rect
			(at -1.500124 -0.249936 180)
			(size 0.2794 0.6096)
			(layers "F.Cu" "F.Mask" "F.Paste")
			(net "P12V_NIC3_R")
		)
		(pad "4" smd rect
			(at -1.500124 0.249936 180)
			(size 0.2794 0.6096)
			(layers "F.Cu" "F.Mask" "F.Paste")
			(net "P12V_NIC3_R")
		)
		(pad "5" smd rect
			(at -1.500124 0.750062 180)
			(size 0.2794 0.6096)
			(layers "F.Cu" "F.Mask" "F.Paste")
			(net "P12V_NIC3_R")
		)
		(pad "6" smd rect
			(at -1.500124 1.249934 180)
			(size 0.2794 0.6096)
			(layers "F.Cu" "F.Mask" "F.Paste")
			(net "GND")
		)
		(pad "7" smd rect
			(at 1.500124 1.249934 180)
			(size 0.2794 0.6096)
			(layers "F.Cu" "F.Mask" "F.Paste")
			(net "P12V_NIC3_SS")
		)
		(pad "8" smd rect
			(at 1.500124 0.750062 180)
			(size 0.2794 0.6096)
			(layers "F.Cu" "F.Mask" "F.Paste")
			(net "PWRGD_P12V_NIC3")
		)
		(pad "9" smd rect
			(at 1.500124 0.249936 180)
			(size 0.2794 0.6096)
			(layers "F.Cu" "F.Mask" "F.Paste")
			(net "P12V_NIC3_OCP")
		)
		(pad "10" smd rect
			(at 1.500124 -0.249936 180)
			(size 0.2794 0.6096)
			(layers "F.Cu" "F.Mask" "F.Paste")
			(net "P5V_AUX")
		)
		(pad "11" smd rect
			(at 1.500124 -0.750062 180)
			(size 0.2794 0.6096)
			(layers "F.Cu" "F.Mask" "F.Paste")
			(net "P12V_NIC3_EN_R")
		)
		(pad "12" smd rect
			(at 1.500124 -1.249934 180)
			(size 0.2794 0.6096)
			(layers "F.Cu" "F.Mask" "F.Paste")
			(net "P12V_AUX")
		)
		(pad "13" smd rect
			(at 0 0 270)
			(size 1.9812 2.7178)
			(layers "F.Cu" "F.Mask" "F.Paste")
			(net "P12V_AUX")
		)
		(zone
			(layer "F.Cu")
			(hatch none 0.5)
			(connect_pads
				(clearance 0)
			)
			(min_thickness 0.25)
			(keepout
				(tracks not_allowed)
				(vias allowed)
				(pads allowed)
				(copperpour not_allowed)
				(footprints allowed)
			)
			(placement
				(enabled no)
				(sheetname "")
			)
			(fill
				(thermal_gap 0.5)
				(thermal_bridge_width 0.5)
				(island_removal_mode 0)
			)
			(polygon
				(pts
					(xy 224.995232 -101.213666) (xy 224.868232 -101.213666) (xy 221.896432 -101.213666) (xy 221.895924 -101.213666)
					(xy 221.895924 -103.499666) (xy 221.896432 -103.499666) (xy 222.023432 -103.499666) (xy 223.445832 -103.499666)
					(xy 223.445832 -103.398066) (xy 222.023432 -103.398066) (xy 222.023432 -101.315266) (xy 224.868232 -101.315266)
					(xy 224.868232 -103.398066) (xy 223.471232 -103.398066) (xy 223.471232 -103.499666) (xy 224.868232 -103.499666)
					(xy 224.995232 -103.499666) (xy 224.99574 -103.499666) (xy 224.99574 -101.213666)
				)
			)
		)
	)
	(footprint ""
		(layer "F.Cu")
		(at 346.075 -181.229)
		(property "Reference" "U347"
			(at -1.4478 -4.613148 0)
			(unlocked yes)
			(layer "F.SilkS")
			(effects
				(font
					(size 0.7874 0.5842)
					(thickness 0.1524)
				)
				(justify left)
			)
		)
		(property "Value" ""
			(at 0 0 0)
			(layer "F.Fab")
			(effects
				(font
					(size 1.27 1.27)
				)
			)
		)
		(duplicate_pad_numbers_are_jumpers no)
		(fp_line
			(start -2.097532 -3.949954)
			(end -2.097532 3.949954)
			(stroke
				(width 0.1524)
				(type default)
			)
			(layer "F.SilkS")
		)
		(fp_line
			(start -2.097532 3.949954)
			(end 2.097532 3.949954)
			(stroke
				(width 0.1524)
				(type default)
			)
			(layer "F.SilkS")
		)
		(fp_line
			(start -1.409954 -3.949954)
			(end -2.097532 -3.949954)
			(stroke
				(width 0.1524)
				(type default)
			)
			(layer "F.SilkS")
		)
		(fp_line
			(start 0 -2.54)
			(end -1.409954 -3.949954)
			(stroke
				(width 0.1524)
				(type default)
			)
			(layer "F.SilkS")
		)
		(fp_line
			(start 1.409954 -3.949954)
			(end 0 -2.54)
			(stroke
				(width 0.1524)
				(type default)
			)
			(layer "F.SilkS")
		)
		(fp_line
			(start 2.097532 -3.949954)
			(end 1.409954 -3.949954)
			(stroke
				(width 0.1524)
				(type default)
			)
			(layer "F.SilkS")
		)
		(fp_line
			(start 2.097532 3.949954)
			(end 2.097532 -3.949954)
			(stroke
				(width 0.1524)
				(type default)
			)
			(layer "F.SilkS")
		)
		(fp_poly
			(pts
				(xy -4.7498 -4.182872) (xy -4.7498 -3.166872) (xy -3.7338 -3.674872)
			)
			(stroke
				(width 0)
				(type default)
			)
			(fill yes)
			(layer "F.SilkS")
		)
		(fp_line
			(start -2.249932 -3.949954)
			(end -2.249932 3.949954)
			(stroke
				(width 0.1)
				(type default)
			)
			(layer "F.Fab")
		)
		(fp_line
			(start -2.249932 3.949954)
			(end 2.249932 3.949954)
			(stroke
				(width 0.1)
				(type default)
			)
			(layer "F.Fab")
		)
		(fp_line
			(start 2.249932 -3.949954)
			(end -2.249932 -3.949954)
			(stroke
				(width 0.1)
				(type default)
			)
			(layer "F.Fab")
		)
		(fp_line
			(start 2.249932 3.949954)
			(end 2.249932 -3.949954)
			(stroke
				(width 0.1)
				(type default)
			)
			(layer "F.Fab")
		)
		(fp_poly
			(pts
				(xy -4.7498 -4.182872) (xy -4.7498 -3.166872) (xy -3.7338 -3.674872)
			)
			(stroke
				(width 0)
				(type default)
			)
			(fill yes)
			(layer "F.Fab")
		)
		(pad "1" smd rect
			(at -2.925064 -3.674872 270)
			(size 0.6096 1.3716)
			(layers "F.Cu" "F.Mask" "F.Paste")
			(net "PEX2_PCA9555_0_INT_N")
		)
		(pad "2" smd rect
			(at -2.925064 -2.925064 270)
			(size 0.4064 1.3716)
			(layers "F.Cu" "F.Mask" "F.Paste")
			(net "PCA9555_0_PEX2_A1")
		)
		(pad "3" smd rect
			(at -2.925064 -2.275078 270)
			(size 0.4064 1.3716)
			(layers "F.Cu" "F.Mask" "F.Paste")
			(net "PCA9555_0_PEX2_A2")
		)
		(pad "4" smd rect
			(at -2.925064 -1.625092 270)
			(size 0.4064 1.3716)
			(layers "F.Cu" "F.Mask" "F.Paste")
			(net "PRSNT_SSD8_FPGA_PCA9555_N")
		)
		(pad "5" smd rect
			(at -2.925064 -0.975106 270)
			(size 0.4064 1.3716)
			(layers "F.Cu" "F.Mask" "F.Paste")
			(net "SSD8_PEX_PWR_EN")
		)
		(pad "6" smd rect
			(at -2.925064 -0.32512 270)
			(size 0.4064 1.3716)
			(layers "F.Cu" "F.Mask" "F.Paste")
			(net "RST_PEX_SSD8_PERST_N")
		)
		(pad "7" smd rect
			(at -2.925064 0.32512 270)
			(size 0.4064 1.3716)
			(layers "F.Cu" "F.Mask" "F.Paste")
			(net "Net_1175")
		)
		(pad "8" smd rect
			(at -2.925064 0.975106 270)
			(size 0.4064 1.3716)
			(layers "F.Cu" "F.Mask" "F.Paste")
			(net "PRSNT_SSD9_FPGA_PCA9555_N")
		)
		(pad "9" smd rect
			(at -2.925064 1.625092 270)
			(size 0.4064 1.3716)
			(layers "F.Cu" "F.Mask" "F.Paste")
			(net "SSD9_PEX_PWR_EN")
		)
		(pad "10" smd rect
			(at -2.925064 2.275078 270)
			(size 0.4064 1.3716)
			(layers "F.Cu" "F.Mask" "F.Paste")
			(net "RST_PEX_SSD9_PERST_N")
		)
		(pad "11" smd rect
			(at -2.925064 2.925064 270)
			(size 0.4064 1.3716)
			(layers "F.Cu" "F.Mask" "F.Paste")
			(net "Net_1176")
		)
		(pad "12" smd rect
			(at -2.925064 3.674872 270)
			(size 0.6096 1.3716)
			(layers "F.Cu" "F.Mask" "F.Paste")
			(net "GND")
		)
		(pad "13" smd rect
			(at 2.925064 3.674872 270)
			(size 0.6096 1.3716)
			(layers "F.Cu" "F.Mask" "F.Paste")
			(net "PRSNT_NIC4_FPGA_PCA9555_N")
		)
		(pad "14" smd rect
			(at 2.925064 2.925064 270)
			(size 0.4064 1.3716)
			(layers "F.Cu" "F.Mask" "F.Paste")
			(net "NIC4_PEX_PWR_EN")
		)
		(pad "15" smd rect
			(at 2.925064 2.275078 270)
			(size 0.4064 1.3716)
			(layers "F.Cu" "F.Mask" "F.Paste")
			(net "RST_PEX_NIC4_PERST_N")
		)
		(pad "16" smd rect
			(at 2.925064 1.625092 270)
			(size 0.4064 1.3716)
			(layers "F.Cu" "F.Mask" "F.Paste")
			(net "Net_1177")
		)
		(pad "17" smd rect
			(at 2.925064 0.975106 270)
			(size 0.4064 1.3716)
			(layers "F.Cu" "F.Mask" "F.Paste")
			(net "Net_8976")
		)
		(pad "18" smd rect
			(at 2.925064 0.32512 270)
			(size 0.4064 1.3716)
			(layers "F.Cu" "F.Mask" "F.Paste")
			(net "Net_8975")
		)
		(pad "19" smd rect
			(at 2.925064 -0.32512 270)
			(size 0.4064 1.3716)
			(layers "F.Cu" "F.Mask" "F.Paste")
			(net "Net_8974")
		)
		(pad "20" smd rect
			(at 2.925064 -0.975106 270)
			(size 0.4064 1.3716)
			(layers "F.Cu" "F.Mask" "F.Paste")
			(net "Net_8973")
		)
		(pad "21" smd rect
			(at 2.925064 -1.625092 270)
			(size 0.4064 1.3716)
			(layers "F.Cu" "F.Mask" "F.Paste")
			(net "PCA9555_0_PEX2_A0")
		)
		(pad "22" smd rect
			(at 2.925064 -2.275078 270)
			(size 0.4064 1.3716)
			(layers "F.Cu" "F.Mask" "F.Paste")
			(net "SMB_PEX2_PCA9555_SCL")
		)
		(pad "23" smd rect
			(at 2.925064 -2.925064 270)
			(size 0.4064 1.3716)
			(layers "F.Cu" "F.Mask" "F.Paste")
			(net "SMB_PEX2_PCA9555_SDA")
		)
		(pad "24" smd rect
			(at 2.925064 -3.674872 270)
			(size 0.6096 1.3716)
			(layers "F.Cu" "F.Mask" "F.Paste")
			(net "P3V3_AUX")
		)
	)
	(footprint ""
		(layer "F.Cu")
		(at 234.152694 -257.975862 -90)
		(property "Reference" "R6532"
			(at 0 0 270)
			(layer "F.SilkS")
			(hide yes)
			(effects
				(font
					(size 1.27 1.27)
				)
			)
		)
		(property "Value" ""
			(at 0 0 270)
			(layer "F.Fab")
			(effects
				(font
					(size 1.27 1.27)
				)
			)
		)
		(duplicate_pad_numbers_are_jumpers no)
		(fp_line
			(start -0.7874 0.4064)
			(end -0.7874 -0.4064)
			(stroke
				(width 0.1524)
				(type default)
			)
			(layer "F.SilkS")
		)
		(fp_line
			(start 0.7874 0.4064)
			(end -0.7874 0.4064)
			(stroke
				(width 0.1524)
				(type default)
			)
			(layer "F.SilkS")
		)
		(fp_line
			(start -0.7874 -0.4064)
			(end 0.7874 -0.4064)
			(stroke
				(width 0.1524)
				(type default)
			)
			(layer "F.SilkS")
		)
		(fp_line
			(start 0.7874 -0.4064)
			(end 0.7874 0.4064)
			(stroke
				(width 0.1524)
				(type default)
			)
			(layer "F.SilkS")
		)
		(fp_line
			(start -0.67945 0.3048)
			(end -0.67945 -0.305054)
			(stroke
				(width 0.1)
				(type default)
			)
			(layer "F.Fab")
		)
		(fp_line
			(start -0.12065 0.3048)
			(end -0.67945 0.3048)
			(stroke
				(width 0.1)
				(type default)
			)
			(layer "F.Fab")
		)
		(fp_line
			(start 0.120396 0.3048)
			(end 0.120396 0.2794)
			(stroke
				(width 0.1)
				(type default)
			)
			(layer "F.Fab")
		)
		(fp_line
			(start 0.67945 0.3048)
			(end 0.120396 0.3048)
			(stroke
				(width 0.1)
				(type default)
			)
			(layer "F.Fab")
		)
		(fp_line
			(start -0.12065 0.2794)
			(end -0.12065 0.3048)
			(stroke
				(width 0.1)
				(type default)
			)
			(layer "F.Fab")
		)
		(fp_line
			(start 0.120396 0.2794)
			(end -0.12065 0.2794)
			(stroke
				(width 0.1)
				(type default)
			)
			(layer "F.Fab")
		)
		(fp_line
			(start -0.12065 -0.2794)
			(end 0.12065 -0.2794)
			(stroke
				(width 0.1)
				(type default)
			)
			(layer "F.Fab")
		)
		(fp_line
			(start 0.12065 -0.2794)
			(end 0.12065 -0.3048)
			(stroke
				(width 0.1)
				(type default)
			)
			(layer "F.Fab")
		)
		(fp_line
			(start 0.12065 -0.3048)
			(end 0.67945 -0.3048)
			(stroke
				(width 0.1)
				(type default)
			)
			(layer "F.Fab")
		)
		(fp_line
			(start 0.67945 -0.3048)
			(end 0.67945 0.3048)
			(stroke
				(width 0.1)
				(type default)
			)
			(layer "F.Fab")
		)
		(fp_line
			(start -0.67945 -0.305054)
			(end -0.12065 -0.305054)
			(stroke
				(width 0.1)
				(type default)
			)
			(layer "F.Fab")
		)
		(fp_line
			(start -0.12065 -0.305054)
			(end -0.12065 -0.2794)
			(stroke
				(width 0.1)
				(type default)
			)
			(layer "F.Fab")
		)
		(pad "1" smd circle
			(at -0.40005 0 270)
			(size 0 0)
			(layers "F.Cu" "F.Mask" "F.Paste")
			(net "P1V25_SERDES_VDDPLL_PEX2")
		)
		(pad "2" smd circle
			(at 0.40005 0 270)
			(size 0 0)
			(layers "F.Cu" "F.Mask" "F.Paste")
			(net "P1V25_SERDES_VDDPLL_PEX2_C9")
		)
	)
	(footprint ""
		(layer "F.Cu")
		(at 471.418412 -555.019972 180)
		(property "Reference" "SCREW_SSD11_1"
			(at -5.6007 -1.402334 0)
			(unlocked yes)
			(layer "B.SilkS")
			(effects
				(font
					(size 0.7874 0.5842)
					(thickness 0.1524)
				)
				(justify mirror)
			)
		)
		(property "Value" ""
			(at 0 0 180)
			(layer "F.Fab")
			(effects
				(font
					(size 1.27 1.27)
				)
			)
		)
		(duplicate_pad_numbers_are_jumpers no)
		(pad "1" thru_hole circle
			(at 0 0 180)
			(size 0.4572 0.4572)
			(drill 0.2032)
			(layers "*.Cu" "*.Mask")
			(remove_unused_layers no)
			(net "Net_9152")
			(clearance 0.127)
			(thermal_gap 0.127)
			(padstack
				(mode front_inner_back)
				(layer "Inner"
					(shape circle)
					(size 0.4572 0.4572)
					(clearance 0.127)
				)
				(layer "B.Cu"
					(shape circle)
					(size 0.508 0.508)
					(clearance 0.1016)
				)
			)
		)
	)
	(footprint ""
		(layer "F.Cu")
		(at 127.947166 -112.755426 90)
		(property "Reference" "R5960"
			(at 0 0 90)
			(layer "F.SilkS")
			(hide yes)
			(effects
				(font
					(size 1.27 1.27)
				)
			)
		)
		(property "Value" ""
			(at 0 0 90)
			(layer "F.Fab")
			(effects
				(font
					(size 1.27 1.27)
				)
			)
		)
		(duplicate_pad_numbers_are_jumpers no)
		(fp_line
			(start 0.7874 -0.4064)
			(end 0.7874 0.4064)
			(stroke
				(width 0.1524)
				(type default)
			)
			(layer "F.SilkS")
		)
		(fp_line
			(start -0.7874 -0.4064)
			(end 0.7874 -0.4064)
			(stroke
				(width 0.1524)
				(type default)
			)
			(layer "F.SilkS")
		)
		(fp_line
			(start 0.7874 0.4064)
			(end -0.7874 0.4064)
			(stroke
				(width 0.1524)
				(type default)
			)
			(layer "F.SilkS")
		)
		(fp_line
			(start -0.7874 0.4064)
			(end -0.7874 -0.4064)
			(stroke
				(width 0.1524)
				(type default)
			)
			(layer "F.SilkS")
		)
		(fp_line
			(start -0.12065 -0.305054)
			(end -0.12065 -0.2794)
			(stroke
				(width 0.1)
				(type default)
			)
			(layer "F.Fab")
		)
		(fp_line
			(start -0.67945 -0.305054)
			(end -0.12065 -0.305054)
			(stroke
				(width 0.1)
				(type default)
			)
			(layer "F.Fab")
		)
		(fp_line
			(start 0.67945 -0.3048)
			(end 0.67945 0.3048)
			(stroke
				(width 0.1)
				(type default)
			)
			(layer "F.Fab")
		)
		(fp_line
			(start 0.12065 -0.3048)
			(end 0.67945 -0.3048)
			(stroke
				(width 0.1)
				(type default)
			)
			(layer "F.Fab")
		)
		(fp_line
			(start 0.12065 -0.2794)
			(end 0.12065 -0.3048)
			(stroke
				(width 0.1)
				(type default)
			)
			(layer "F.Fab")
		)
		(fp_line
			(start -0.12065 -0.2794)
			(end 0.12065 -0.2794)
			(stroke
				(width 0.1)
				(type default)
			)
			(layer "F.Fab")
		)
		(fp_line
			(start 0.120396 0.2794)
			(end -0.12065 0.2794)
			(stroke
				(width 0.1)
				(type default)
			)
			(layer "F.Fab")
		)
		(fp_line
			(start -0.12065 0.2794)
			(end -0.12065 0.3048)
			(stroke
				(width 0.1)
				(type default)
			)
			(layer "F.Fab")
		)
		(fp_line
			(start 0.67945 0.3048)
			(end 0.120396 0.3048)
			(stroke
				(width 0.1)
				(type default)
			)
			(layer "F.Fab")
		)
		(fp_line
			(start 0.120396 0.3048)
			(end 0.120396 0.2794)
			(stroke
				(width 0.1)
				(type default)
			)
			(layer "F.Fab")
		)
		(fp_line
			(start -0.12065 0.3048)
			(end -0.67945 0.3048)
			(stroke
				(width 0.1)
				(type default)
			)
			(layer "F.Fab")
		)
		(fp_line
			(start -0.67945 0.3048)
			(end -0.67945 -0.305054)
			(stroke
				(width 0.1)
				(type default)
			)
			(layer "F.Fab")
		)
		(pad "1" smd circle
			(at -0.40005 0 90)
			(size 0 0)
			(layers "F.Cu" "F.Mask" "F.Paste")
			(net "P5V_AUX")
		)
		(pad "2" smd circle
			(at 0.40005 0 90)
			(size 0 0)
			(layers "F.Cu" "F.Mask" "F.Paste")
			(net "P3V3_NIC2_PG_G2")
		)
	)
	(footprint ""
		(layer "F.Cu")
		(at 38.79088 -142.892018)
		(property "Reference" "R30"
			(at 0 0 0)
			(layer "F.SilkS")
			(hide yes)
			(effects
				(font
					(size 1.27 1.27)
				)
			)
		)
		(property "Value" ""
			(at 0 0 0)
			(layer "F.Fab")
			(effects
				(font
					(size 1.27 1.27)
				)
			)
		)
		(duplicate_pad_numbers_are_jumpers no)
		(fp_line
			(start -0.7874 -0.4064)
			(end 0.7874 -0.4064)
			(stroke
				(width 0.1524)
				(type default)
			)
			(layer "F.SilkS")
		)
		(fp_line
			(start -0.7874 0.4064)
			(end -0.7874 -0.4064)
			(stroke
				(width 0.1524)
				(type default)
			)
			(layer "F.SilkS")
		)
		(fp_line
			(start 0.7874 -0.4064)
			(end 0.7874 0.4064)
			(stroke
				(width 0.1524)
				(type default)
			)
			(layer "F.SilkS")
		)
		(fp_line
			(start 0.7874 0.4064)
			(end -0.7874 0.4064)
			(stroke
				(width 0.1524)
				(type default)
			)
			(layer "F.SilkS")
		)
		(fp_line
			(start -0.67945 -0.305054)
			(end -0.12065 -0.305054)
			(stroke
				(width 0.1)
				(type default)
			)
			(layer "F.Fab")
		)
		(fp_line
			(start -0.67945 0.3048)
			(end -0.67945 -0.305054)
			(stroke
				(width 0.1)
				(type default)
			)
			(layer "F.Fab")
		)
		(fp_line
			(start -0.12065 -0.305054)
			(end -0.12065 -0.2794)
			(stroke
				(width 0.1)
				(type default)
			)
			(layer "F.Fab")
		)
		(fp_line
			(start -0.12065 -0.2794)
			(end 0.12065 -0.2794)
			(stroke
				(width 0.1)
				(type default)
			)
			(layer "F.Fab")
		)
		(fp_line
			(start -0.12065 0.2794)
			(end -0.12065 0.3048)
			(stroke
				(width 0.1)
				(type default)
			)
			(layer "F.Fab")
		)
		(fp_line
			(start -0.12065 0.3048)
			(end -0.67945 0.3048)
			(stroke
				(width 0.1)
				(type default)
			)
			(layer "F.Fab")
		)
		(fp_line
			(start 0.120396 0.2794)
			(end -0.12065 0.2794)
			(stroke
				(width 0.1)
				(type default)
			)
			(layer "F.Fab")
		)
		(fp_line
			(start 0.120396 0.3048)
			(end 0.120396 0.2794)
			(stroke
				(width 0.1)
				(type default)
			)
			(layer "F.Fab")
		)
		(fp_line
			(start 0.12065 -0.3048)
			(end 0.67945 -0.3048)
			(stroke
				(width 0.1)
				(type default)
			)
			(layer "F.Fab")
		)
		(fp_line
			(start 0.12065 -0.2794)
			(end 0.12065 -0.3048)
			(stroke
				(width 0.1)
				(type default)
			)
			(layer "F.Fab")
		)
		(fp_line
			(start 0.67945 -0.3048)
			(end 0.67945 0.3048)
			(stroke
				(width 0.1)
				(type default)
			)
			(layer "F.Fab")
		)
		(fp_line
			(start 0.67945 0.3048)
			(end 0.120396 0.3048)
			(stroke
				(width 0.1)
				(type default)
			)
			(layer "F.Fab")
		)
		(pad "1" smd circle
			(at -0.40005 0)
			(size 0 0)
			(layers "F.Cu" "F.Mask" "F.Paste")
			(net "NIC0_BIF0_N")
		)
		(pad "2" smd circle
			(at 0.40005 0)
			(size 0 0)
			(layers "F.Cu" "F.Mask" "F.Paste")
			(net "GND")
		)
	)
	(footprint ""
		(layer "F.Cu")
		(at 298.961302 -343.952322 90)
		(property "Reference" "C2369"
			(at 0 0 90)
			(layer "F.SilkS")
			(hide yes)
			(effects
				(font
					(size 1.27 1.27)
				)
			)
		)
		(property "Value" ""
			(at 0 0 90)
			(layer "F.Fab")
			(effects
				(font
					(size 1.27 1.27)
				)
			)
		)
		(duplicate_pad_numbers_are_jumpers no)
		(fp_line
			(start 0.299974 -0.150114)
			(end 0.299974 0.150114)
			(stroke
				(width 0.1)
				(type default)
			)
			(layer "F.Fab")
		)
		(fp_line
			(start -0.299974 -0.150114)
			(end 0.299974 -0.150114)
			(stroke
				(width 0.1)
				(type default)
			)
			(layer "F.Fab")
		)
		(fp_line
			(start 0.299974 0.150114)
			(end -0.299974 0.150114)
			(stroke
				(width 0.1)
				(type default)
			)
			(layer "F.Fab")
		)
		(fp_line
			(start -0.299974 0.150114)
			(end -0.299974 -0.150114)
			(stroke
				(width 0.1)
				(type default)
			)
			(layer "F.Fab")
		)
		(pad "1" smd rect
			(at -0.2667 0 90)
			(size 0.3048 0.381)
			(layers "F.Cu" "F.Mask" "F.Paste")
			(net "P5E_PEX2_STN4_TX_DP<65>")
		)
		(pad "2" smd rect
			(at 0.2667 0 90)
			(size 0.3048 0.381)
			(layers "F.Cu" "F.Mask" "F.Paste")
			(net "P5E_PEX2_STN4_TX_C_DP<65>")
		)
	)
	(footprint ""
		(layer "F.Cu")
		(at 92.387166 -300.650402 -90)
		(property "Reference" "R3884"
			(at 0 0 270)
			(layer "F.SilkS")
			(hide yes)
			(effects
				(font
					(size 1.27 1.27)
				)
			)
		)
		(property "Value" ""
			(at 0 0 270)
			(layer "F.Fab")
			(effects
				(font
					(size 1.27 1.27)
				)
			)
		)
		(duplicate_pad_numbers_are_jumpers no)
		(fp_line
			(start -0.7874 0.4064)
			(end -0.7874 -0.4064)
			(stroke
				(width 0.1524)
				(type default)
			)
			(layer "F.SilkS")
		)
		(fp_line
			(start 0.7874 0.4064)
			(end -0.7874 0.4064)
			(stroke
				(width 0.1524)
				(type default)
			)
			(layer "F.SilkS")
		)
		(fp_line
			(start -0.7874 -0.4064)
			(end 0.7874 -0.4064)
			(stroke
				(width 0.1524)
				(type default)
			)
			(layer "F.SilkS")
		)
		(fp_line
			(start 0.7874 -0.4064)
			(end 0.7874 0.4064)
			(stroke
				(width 0.1524)
				(type default)
			)
			(layer "F.SilkS")
		)
		(fp_line
			(start -0.67945 0.3048)
			(end -0.67945 -0.305054)
			(stroke
				(width 0.1)
				(type default)
			)
			(layer "F.Fab")
		)
		(fp_line
			(start -0.12065 0.3048)
			(end -0.67945 0.3048)
			(stroke
				(width 0.1)
				(type default)
			)
			(layer "F.Fab")
		)
		(fp_line
			(start 0.120396 0.3048)
			(end 0.120396 0.2794)
			(stroke
				(width 0.1)
				(type default)
			)
			(layer "F.Fab")
		)
		(fp_line
			(start 0.67945 0.3048)
			(end 0.120396 0.3048)
			(stroke
				(width 0.1)
				(type default)
			)
			(layer "F.Fab")
		)
		(fp_line
			(start -0.12065 0.2794)
			(end -0.12065 0.3048)
			(stroke
				(width 0.1)
				(type default)
			)
			(layer "F.Fab")
		)
		(fp_line
			(start 0.120396 0.2794)
			(end -0.12065 0.2794)
			(stroke
				(width 0.1)
				(type default)
			)
			(layer "F.Fab")
		)
		(fp_line
			(start -0.12065 -0.2794)
			(end 0.12065 -0.2794)
			(stroke
				(width 0.1)
				(type default)
			)
			(layer "F.Fab")
		)
		(fp_line
			(start 0.12065 -0.2794)
			(end 0.12065 -0.3048)
			(stroke
				(width 0.1)
				(type default)
			)
			(layer "F.Fab")
		)
		(fp_line
			(start 0.12065 -0.3048)
			(end 0.67945 -0.3048)
			(stroke
				(width 0.1)
				(type default)
			)
			(layer "F.Fab")
		)
		(fp_line
			(start 0.67945 -0.3048)
			(end 0.67945 0.3048)
			(stroke
				(width 0.1)
				(type default)
			)
			(layer "F.Fab")
		)
		(fp_line
			(start -0.67945 -0.305054)
			(end -0.12065 -0.305054)
			(stroke
				(width 0.1)
				(type default)
			)
			(layer "F.Fab")
		)
		(fp_line
			(start -0.12065 -0.305054)
			(end -0.12065 -0.2794)
			(stroke
				(width 0.1)
				(type default)
			)
			(layer "F.Fab")
		)
		(pad "1" smd circle
			(at -0.40005 0 270)
			(size 0 0)
			(layers "F.Cu" "F.Mask" "F.Paste")
			(net "I2C0_PEX0_SHPC_SCL")
		)
		(pad "2" smd circle
			(at 0.40005 0 270)
			(size 0 0)
			(layers "F.Cu" "F.Mask" "F.Paste")
			(net "I2C_PEX0_HOST_SCL")
		)
	)
	(footprint ""
		(layer "F.Cu")
		(at 174.164244 -140.6398 180)
		(property "Reference" "R140"
			(at 0 0 180)
			(layer "F.SilkS")
			(hide yes)
			(effects
				(font
					(size 1.27 1.27)
				)
			)
		)
		(property "Value" ""
			(at 0 0 180)
			(layer "F.Fab")
			(effects
				(font
					(size 1.27 1.27)
				)
			)
		)
		(duplicate_pad_numbers_are_jumpers no)
		(fp_line
			(start 0.7874 0.4064)
			(end -0.7874 0.4064)
			(stroke
				(width 0.1524)
				(type default)
			)
			(layer "F.SilkS")
		)
		(fp_line
			(start 0.7874 -0.4064)
			(end 0.7874 0.4064)
			(stroke
				(width 0.1524)
				(type default)
			)
			(layer "F.SilkS")
		)
		(fp_line
			(start -0.7874 0.4064)
			(end -0.7874 -0.4064)
			(stroke
				(width 0.1524)
				(type default)
			)
			(layer "F.SilkS")
		)
		(fp_line
			(start -0.7874 -0.4064)
			(end 0.7874 -0.4064)
			(stroke
				(width 0.1524)
				(type default)
			)
			(layer "F.SilkS")
		)
		(fp_line
			(start 0.67945 0.3048)
			(end 0.120396 0.3048)
			(stroke
				(width 0.1)
				(type default)
			)
			(layer "F.Fab")
		)
		(fp_line
			(start 0.67945 -0.3048)
			(end 0.67945 0.3048)
			(stroke
				(width 0.1)
				(type default)
			)
			(layer "F.Fab")
		)
		(fp_line
			(start 0.12065 -0.2794)
			(end 0.12065 -0.3048)
			(stroke
				(width 0.1)
				(type default)
			)
			(layer "F.Fab")
		)
		(fp_line
			(start 0.12065 -0.3048)
			(end 0.67945 -0.3048)
			(stroke
				(width 0.1)
				(type default)
			)
			(layer "F.Fab")
		)
		(fp_line
			(start 0.120396 0.3048)
			(end 0.120396 0.2794)
			(stroke
				(width 0.1)
				(type default)
			)
			(layer "F.Fab")
		)
		(fp_line
			(start 0.120396 0.2794)
			(end -0.12065 0.2794)
			(stroke
				(width 0.1)
				(type default)
			)
			(layer "F.Fab")
		)
		(fp_line
			(start -0.12065 0.3048)
			(end -0.67945 0.3048)
			(stroke
				(width 0.1)
				(type default)
			)
			(layer "F.Fab")
		)
		(fp_line
			(start -0.12065 0.2794)
			(end -0.12065 0.3048)
			(stroke
				(width 0.1)
				(type default)
			)
			(layer "F.Fab")
		)
		(fp_line
			(start -0.12065 -0.2794)
			(end 0.12065 -0.2794)
			(stroke
				(width 0.1)
				(type default)
			)
			(layer "F.Fab")
		)
		(fp_line
			(start -0.12065 -0.305054)
			(end -0.12065 -0.2794)
			(stroke
				(width 0.1)
				(type default)
			)
			(layer "F.Fab")
		)
		(fp_line
			(start -0.67945 0.3048)
			(end -0.67945 -0.305054)
			(stroke
				(width 0.1)
				(type default)
			)
			(layer "F.Fab")
		)
		(fp_line
			(start -0.67945 -0.305054)
			(end -0.12065 -0.305054)
			(stroke
				(width 0.1)
				(type default)
			)
			(layer "F.Fab")
		)
		(pad "1" smd circle
			(at -0.40005 0 180)
			(size 0 0)
			(layers "F.Cu" "F.Mask" "F.Paste")
			(net "RST_SMB_NIC2_MUX_ISO_N")
		)
		(pad "2" smd circle
			(at 0.40005 0 180)
			(size 0 0)
			(layers "F.Cu" "F.Mask" "F.Paste")
			(net "GND")
		)
	)
	(footprint ""
		(layer "F.Cu")
		(at 51.062382 -22.955504 -90)
		(property "Reference" "C2713"
			(at 0 0 270)
			(layer "F.SilkS")
			(hide yes)
			(effects
				(font
					(size 1.27 1.27)
				)
			)
		)
		(property "Value" ""
			(at 0 0 270)
			(layer "F.Fab")
			(effects
				(font
					(size 1.27 1.27)
				)
			)
		)
		(duplicate_pad_numbers_are_jumpers no)
		(fp_line
			(start -0.7874 0.4064)
			(end -0.7874 -0.4064)
			(stroke
				(width 0.1524)
				(type default)
			)
			(layer "F.SilkS")
		)
		(fp_line
			(start 0.7874 0.4064)
			(end -0.7874 0.4064)
			(stroke
				(width 0.1524)
				(type default)
			)
			(layer "F.SilkS")
		)
		(fp_line
			(start -0.7874 -0.4064)
			(end 0.7874 -0.4064)
			(stroke
				(width 0.1524)
				(type default)
			)
			(layer "F.SilkS")
		)
		(fp_line
			(start 0.7874 -0.4064)
			(end 0.7874 0.4064)
			(stroke
				(width 0.1524)
				(type default)
			)
			(layer "F.SilkS")
		)
		(fp_line
			(start -0.67945 0.3048)
			(end -0.67945 -0.305054)
			(stroke
				(width 0.1)
				(type default)
			)
			(layer "F.Fab")
		)
		(fp_line
			(start -0.12065 0.3048)
			(end -0.67945 0.3048)
			(stroke
				(width 0.1)
				(type default)
			)
			(layer "F.Fab")
		)
		(fp_line
			(start 0.120396 0.3048)
			(end 0.120396 0.2794)
			(stroke
				(width 0.1)
				(type default)
			)
			(layer "F.Fab")
		)
		(fp_line
			(start 0.67945 0.3048)
			(end 0.120396 0.3048)
			(stroke
				(width 0.1)
				(type default)
			)
			(layer "F.Fab")
		)
		(fp_line
			(start -0.12065 0.2794)
			(end -0.12065 0.3048)
			(stroke
				(width 0.1)
				(type default)
			)
			(layer "F.Fab")
		)
		(fp_line
			(start 0.120396 0.2794)
			(end -0.12065 0.2794)
			(stroke
				(width 0.1)
				(type default)
			)
			(layer "F.Fab")
		)
		(fp_line
			(start -0.12065 -0.2794)
			(end 0.12065 -0.2794)
			(stroke
				(width 0.1)
				(type default)
			)
			(layer "F.Fab")
		)
		(fp_line
			(start 0.12065 -0.2794)
			(end 0.12065 -0.3048)
			(stroke
				(width 0.1)
				(type default)
			)
			(layer "F.Fab")
		)
		(fp_line
			(start 0.12065 -0.3048)
			(end 0.67945 -0.3048)
			(stroke
				(width 0.1)
				(type default)
			)
			(layer "F.Fab")
		)
		(fp_line
			(start 0.67945 -0.3048)
			(end 0.67945 0.3048)
			(stroke
				(width 0.1)
				(type default)
			)
			(layer "F.Fab")
		)
		(fp_line
			(start -0.67945 -0.305054)
			(end -0.12065 -0.305054)
			(stroke
				(width 0.1)
				(type default)
			)
			(layer "F.Fab")
		)
		(fp_line
			(start -0.12065 -0.305054)
			(end -0.12065 -0.2794)
			(stroke
				(width 0.1)
				(type default)
			)
			(layer "F.Fab")
		)
		(pad "1" smd circle
			(at -0.40005 0 270)
			(size 0 0)
			(layers "F.Cu" "F.Mask" "F.Paste")
			(net "GND")
		)
		(pad "2" smd circle
			(at 0.40005 0 270)
			(size 0 0)
			(layers "F.Cu" "F.Mask" "F.Paste")
			(net "P3V3_AUX")
		)
	)
	(footprint ""
		(layer "F.Cu")
		(at 211.958936 -188.652404 90)
		(property "Reference" "R5416"
			(at 0 0 90)
			(layer "F.SilkS")
			(hide yes)
			(effects
				(font
					(size 1.27 1.27)
				)
			)
		)
		(property "Value" ""
			(at 0 0 90)
			(layer "F.Fab")
			(effects
				(font
					(size 1.27 1.27)
				)
			)
		)
		(duplicate_pad_numbers_are_jumpers no)
		(fp_line
			(start 0.7874 -0.4064)
			(end 0.7874 0.4064)
			(stroke
				(width 0.1524)
				(type default)
			)
			(layer "F.SilkS")
		)
		(fp_line
			(start -0.7874 -0.4064)
			(end 0.7874 -0.4064)
			(stroke
				(width 0.1524)
				(type default)
			)
			(layer "F.SilkS")
		)
		(fp_line
			(start 0.7874 0.4064)
			(end -0.7874 0.4064)
			(stroke
				(width 0.1524)
				(type default)
			)
			(layer "F.SilkS")
		)
		(fp_line
			(start -0.7874 0.4064)
			(end -0.7874 -0.4064)
			(stroke
				(width 0.1524)
				(type default)
			)
			(layer "F.SilkS")
		)
		(fp_line
			(start -0.12065 -0.305054)
			(end -0.12065 -0.2794)
			(stroke
				(width 0.1)
				(type default)
			)
			(layer "F.Fab")
		)
		(fp_line
			(start -0.67945 -0.305054)
			(end -0.12065 -0.305054)
			(stroke
				(width 0.1)
				(type default)
			)
			(layer "F.Fab")
		)
		(fp_line
			(start 0.67945 -0.3048)
			(end 0.67945 0.3048)
			(stroke
				(width 0.1)
				(type default)
			)
			(layer "F.Fab")
		)
		(fp_line
			(start 0.12065 -0.3048)
			(end 0.67945 -0.3048)
			(stroke
				(width 0.1)
				(type default)
			)
			(layer "F.Fab")
		)
		(fp_line
			(start 0.12065 -0.2794)
			(end 0.12065 -0.3048)
			(stroke
				(width 0.1)
				(type default)
			)
			(layer "F.Fab")
		)
		(fp_line
			(start -0.12065 -0.2794)
			(end 0.12065 -0.2794)
			(stroke
				(width 0.1)
				(type default)
			)
			(layer "F.Fab")
		)
		(fp_line
			(start 0.120396 0.2794)
			(end -0.12065 0.2794)
			(stroke
				(width 0.1)
				(type default)
			)
			(layer "F.Fab")
		)
		(fp_line
			(start -0.12065 0.2794)
			(end -0.12065 0.3048)
			(stroke
				(width 0.1)
				(type default)
			)
			(layer "F.Fab")
		)
		(fp_line
			(start 0.67945 0.3048)
			(end 0.120396 0.3048)
			(stroke
				(width 0.1)
				(type default)
			)
			(layer "F.Fab")
		)
		(fp_line
			(start 0.120396 0.3048)
			(end 0.120396 0.2794)
			(stroke
				(width 0.1)
				(type default)
			)
			(layer "F.Fab")
		)
		(fp_line
			(start -0.12065 0.3048)
			(end -0.67945 0.3048)
			(stroke
				(width 0.1)
				(type default)
			)
			(layer "F.Fab")
		)
		(fp_line
			(start -0.67945 0.3048)
			(end -0.67945 -0.305054)
			(stroke
				(width 0.1)
				(type default)
			)
			(layer "F.Fab")
		)
		(pad "1" smd circle
			(at -0.40005 0 90)
			(size 0 0)
			(layers "F.Cu" "F.Mask" "F.Paste")
			(net "BIC_SEL_FLASH_SW2_R")
		)
		(pad "2" smd circle
			(at 0.40005 0 90)
			(size 0 0)
			(layers "F.Cu" "F.Mask" "F.Paste")
			(net "GND")
		)
	)
	(footprint ""
		(layer "F.Cu")
		(at 288.181542 -158.8516)
		(property "Reference" "R251"
			(at 0 0 0)
			(layer "F.SilkS")
			(hide yes)
			(effects
				(font
					(size 1.27 1.27)
				)
			)
		)
		(property "Value" ""
			(at 0 0 0)
			(layer "F.Fab")
			(effects
				(font
					(size 1.27 1.27)
				)
			)
		)
		(duplicate_pad_numbers_are_jumpers no)
		(fp_line
			(start -0.7874 -0.4064)
			(end 0.7874 -0.4064)
			(stroke
				(width 0.1524)
				(type default)
			)
			(layer "F.SilkS")
		)
		(fp_line
			(start -0.7874 0.4064)
			(end -0.7874 -0.4064)
			(stroke
				(width 0.1524)
				(type default)
			)
			(layer "F.SilkS")
		)
		(fp_line
			(start 0.7874 -0.4064)
			(end 0.7874 0.4064)
			(stroke
				(width 0.1524)
				(type default)
			)
			(layer "F.SilkS")
		)
		(fp_line
			(start 0.7874 0.4064)
			(end -0.7874 0.4064)
			(stroke
				(width 0.1524)
				(type default)
			)
			(layer "F.SilkS")
		)
		(fp_line
			(start -0.67945 -0.305054)
			(end -0.12065 -0.305054)
			(stroke
				(width 0.1)
				(type default)
			)
			(layer "F.Fab")
		)
		(fp_line
			(start -0.67945 0.3048)
			(end -0.67945 -0.305054)
			(stroke
				(width 0.1)
				(type default)
			)
			(layer "F.Fab")
		)
		(fp_line
			(start -0.12065 -0.305054)
			(end -0.12065 -0.2794)
			(stroke
				(width 0.1)
				(type default)
			)
			(layer "F.Fab")
		)
		(fp_line
			(start -0.12065 -0.2794)
			(end 0.12065 -0.2794)
			(stroke
				(width 0.1)
				(type default)
			)
			(layer "F.Fab")
		)
		(fp_line
			(start -0.12065 0.2794)
			(end -0.12065 0.3048)
			(stroke
				(width 0.1)
				(type default)
			)
			(layer "F.Fab")
		)
		(fp_line
			(start -0.12065 0.3048)
			(end -0.67945 0.3048)
			(stroke
				(width 0.1)
				(type default)
			)
			(layer "F.Fab")
		)
		(fp_line
			(start 0.120396 0.2794)
			(end -0.12065 0.2794)
			(stroke
				(width 0.1)
				(type default)
			)
			(layer "F.Fab")
		)
		(fp_line
			(start 0.120396 0.3048)
			(end 0.120396 0.2794)
			(stroke
				(width 0.1)
				(type default)
			)
			(layer "F.Fab")
		)
		(fp_line
			(start 0.12065 -0.3048)
			(end 0.67945 -0.3048)
			(stroke
				(width 0.1)
				(type default)
			)
			(layer "F.Fab")
		)
		(fp_line
			(start 0.12065 -0.2794)
			(end 0.12065 -0.3048)
			(stroke
				(width 0.1)
				(type default)
			)
			(layer "F.Fab")
		)
		(fp_line
			(start 0.67945 -0.3048)
			(end 0.67945 0.3048)
			(stroke
				(width 0.1)
				(type default)
			)
			(layer "F.Fab")
		)
		(fp_line
			(start 0.67945 0.3048)
			(end 0.120396 0.3048)
			(stroke
				(width 0.1)
				(type default)
			)
			(layer "F.Fab")
		)
		(pad "1" smd circle
			(at -0.40005 0)
			(size 0 0)
			(layers "F.Cu" "F.Mask" "F.Paste")
			(net "RST_NIC4_PERST2_R_N")
		)
		(pad "2" smd circle
			(at 0.40005 0)
			(size 0 0)
			(layers "F.Cu" "F.Mask" "F.Paste")
			(net "RST_HP_NIC4_BUF_N")
		)
	)
	(footprint ""
		(layer "F.Cu")
		(at 112.67186 -130.946144)
		(property "Reference" "PC299"
			(at 0 0 0)
			(layer "F.SilkS")
			(hide yes)
			(effects
				(font
					(size 1.27 1.27)
				)
			)
		)
		(property "Value" ""
			(at 0 0 0)
			(layer "F.Fab")
			(effects
				(font
					(size 1.27 1.27)
				)
			)
		)
		(duplicate_pad_numbers_are_jumpers no)
		(fp_line
			(start -1.524 -0.762)
			(end 1.524 -0.762)
			(stroke
				(width 0.1524)
				(type default)
			)
			(layer "F.SilkS")
		)
		(fp_line
			(start -1.524 0.762)
			(end -1.524 -0.762)
			(stroke
				(width 0.1524)
				(type default)
			)
			(layer "F.SilkS")
		)
		(fp_line
			(start 1.524 -0.762)
			(end 1.524 0.762)
			(stroke
				(width 0.1524)
				(type default)
			)
			(layer "F.SilkS")
		)
		(fp_line
			(start 1.524 0.762)
			(end -1.524 0.762)
			(stroke
				(width 0.1524)
				(type default)
			)
			(layer "F.SilkS")
		)
		(fp_line
			(start -1.1049 -0.724916)
			(end -1.1049 0.724916)
			(stroke
				(width 0.1)
				(type default)
			)
			(layer "F.Fab")
		)
		(fp_line
			(start -1.1049 0.724916)
			(end 1.1049 0.724916)
			(stroke
				(width 0.1)
				(type default)
			)
			(layer "F.Fab")
		)
		(fp_line
			(start 1.1049 -0.724916)
			(end -1.1049 -0.724916)
			(stroke
				(width 0.1)
				(type default)
			)
			(layer "F.Fab")
		)
		(fp_line
			(start 1.1049 0.724916)
			(end 1.1049 -0.724916)
			(stroke
				(width 0.1)
				(type default)
			)
			(layer "F.Fab")
		)
		(pad "1" smd rect
			(at -0.889 0 180)
			(size 1.016 1.27)
			(layers "F.Cu" "F.Mask" "F.Paste")
			(net "GND")
		)
		(pad "2" smd rect
			(at 0.889 0 180)
			(size 1.016 1.27)
			(layers "F.Cu" "F.Mask" "F.Paste")
			(net "P3V3_AUX")
		)
	)
	(footprint ""
		(layer "F.Cu")
		(at 30.081982 -286.590232 180)
		(property "Reference" "C3061"
			(at 0 0 180)
			(layer "F.SilkS")
			(hide yes)
			(effects
				(font
					(size 1.27 1.27)
				)
			)
		)
		(property "Value" ""
			(at 0 0 180)
			(layer "F.Fab")
			(effects
				(font
					(size 1.27 1.27)
				)
			)
		)
		(duplicate_pad_numbers_are_jumpers no)
		(fp_line
			(start 1.2954 0.5842)
			(end -1.2954 0.5842)
			(stroke
				(width 0.1524)
				(type default)
			)
			(layer "F.SilkS")
		)
		(fp_line
			(start 1.2954 -0.5842)
			(end 1.2954 0.5842)
			(stroke
				(width 0.1524)
				(type default)
			)
			(layer "F.SilkS")
		)
		(fp_line
			(start -1.2954 0.5842)
			(end -1.2954 -0.5842)
			(stroke
				(width 0.1524)
				(type default)
			)
			(layer "F.SilkS")
		)
		(fp_line
			(start -1.2954 -0.5842)
			(end 1.2954 -0.5842)
			(stroke
				(width 0.1524)
				(type default)
			)
			(layer "F.SilkS")
		)
		(fp_line
			(start 1.1938 0.4064)
			(end 0.8636 0.4064)
			(stroke
				(width 0.1)
				(type default)
			)
			(layer "F.Fab")
		)
		(fp_line
			(start 1.1938 -0.4064)
			(end 1.1938 0.4064)
			(stroke
				(width 0.1)
				(type default)
			)
			(layer "F.Fab")
		)
		(fp_line
			(start 0.8636 0.4572)
			(end -0.8636 0.4572)
			(stroke
				(width 0.1)
				(type default)
			)
			(layer "F.Fab")
		)
		(fp_line
			(start 0.8636 0.4064)
			(end 0.8636 0.4572)
			(stroke
				(width 0.1)
				(type default)
			)
			(layer "F.Fab")
		)
		(fp_line
			(start 0.8636 -0.4064)
			(end 1.1938 -0.4064)
			(stroke
				(width 0.1)
				(type default)
			)
			(layer "F.Fab")
		)
		(fp_line
			(start 0.8636 -0.4572)
			(end 0.8636 -0.4064)
			(stroke
				(width 0.1)
				(type default)
			)
			(layer "F.Fab")
		)
		(fp_line
			(start -0.8636 0.4572)
			(end -0.8636 0.4064)
			(stroke
				(width 0.1)
				(type default)
			)
			(layer "F.Fab")
		)
		(fp_line
			(start -0.8636 0.4064)
			(end -1.1938 0.4064)
			(stroke
				(width 0.1)
				(type default)
			)
			(layer "F.Fab")
		)
		(fp_line
			(start -0.8636 -0.4064)
			(end -0.8636 -0.4572)
			(stroke
				(width 0.1)
				(type default)
			)
			(layer "F.Fab")
		)
		(fp_line
			(start -0.8636 -0.4572)
			(end 0.8636 -0.4572)
			(stroke
				(width 0.1)
				(type default)
			)
			(layer "F.Fab")
		)
		(fp_line
			(start -1.1938 0.4064)
			(end -1.1938 -0.4064)
			(stroke
				(width 0.1)
				(type default)
			)
			(layer "F.Fab")
		)
		(fp_line
			(start -1.1938 -0.4064)
			(end -0.8636 -0.4064)
			(stroke
				(width 0.1)
				(type default)
			)
			(layer "F.Fab")
		)
		(pad "1" smd rect
			(at -0.7366 0 90)
			(size 0.7112 0.8128)
			(layers "F.Cu" "F.Mask" "F.Paste")
			(net "PCEPLL6_VDDA18_PEX0_R")
		)
		(pad "2" smd rect
			(at 0.7366 0 90)
			(size 0.7112 0.8128)
			(layers "F.Cu" "F.Mask" "F.Paste")
			(net "GND")
		)
	)
	(footprint ""
		(layer "F.Cu")
		(at 369.555776 -152.71115 90)
		(property "Reference" "R751"
			(at 0 0 90)
			(layer "F.SilkS")
			(hide yes)
			(effects
				(font
					(size 1.27 1.27)
				)
			)
		)
		(property "Value" ""
			(at 0 0 90)
			(layer "F.Fab")
			(effects
				(font
					(size 1.27 1.27)
				)
			)
		)
		(duplicate_pad_numbers_are_jumpers no)
		(fp_line
			(start 0.7874 -0.4064)
			(end 0.7874 0.4064)
			(stroke
				(width 0.1524)
				(type default)
			)
			(layer "F.SilkS")
		)
		(fp_line
			(start -0.7874 -0.4064)
			(end 0.7874 -0.4064)
			(stroke
				(width 0.1524)
				(type default)
			)
			(layer "F.SilkS")
		)
		(fp_line
			(start 0.7874 0.4064)
			(end -0.7874 0.4064)
			(stroke
				(width 0.1524)
				(type default)
			)
			(layer "F.SilkS")
		)
		(fp_line
			(start -0.7874 0.4064)
			(end -0.7874 -0.4064)
			(stroke
				(width 0.1524)
				(type default)
			)
			(layer "F.SilkS")
		)
		(fp_line
			(start -0.12065 -0.305054)
			(end -0.12065 -0.2794)
			(stroke
				(width 0.1)
				(type default)
			)
			(layer "F.Fab")
		)
		(fp_line
			(start -0.67945 -0.305054)
			(end -0.12065 -0.305054)
			(stroke
				(width 0.1)
				(type default)
			)
			(layer "F.Fab")
		)
		(fp_line
			(start 0.67945 -0.3048)
			(end 0.67945 0.3048)
			(stroke
				(width 0.1)
				(type default)
			)
			(layer "F.Fab")
		)
		(fp_line
			(start 0.12065 -0.3048)
			(end 0.67945 -0.3048)
			(stroke
				(width 0.1)
				(type default)
			)
			(layer "F.Fab")
		)
		(fp_line
			(start 0.12065 -0.2794)
			(end 0.12065 -0.3048)
			(stroke
				(width 0.1)
				(type default)
			)
			(layer "F.Fab")
		)
		(fp_line
			(start -0.12065 -0.2794)
			(end 0.12065 -0.2794)
			(stroke
				(width 0.1)
				(type default)
			)
			(layer "F.Fab")
		)
		(fp_line
			(start 0.120396 0.2794)
			(end -0.12065 0.2794)
			(stroke
				(width 0.1)
				(type default)
			)
			(layer "F.Fab")
		)
		(fp_line
			(start -0.12065 0.2794)
			(end -0.12065 0.3048)
			(stroke
				(width 0.1)
				(type default)
			)
			(layer "F.Fab")
		)
		(fp_line
			(start 0.67945 0.3048)
			(end 0.120396 0.3048)
			(stroke
				(width 0.1)
				(type default)
			)
			(layer "F.Fab")
		)
		(fp_line
			(start 0.120396 0.3048)
			(end 0.120396 0.2794)
			(stroke
				(width 0.1)
				(type default)
			)
			(layer "F.Fab")
		)
		(fp_line
			(start -0.12065 0.3048)
			(end -0.67945 0.3048)
			(stroke
				(width 0.1)
				(type default)
			)
			(layer "F.Fab")
		)
		(fp_line
			(start -0.67945 0.3048)
			(end -0.67945 -0.305054)
			(stroke
				(width 0.1)
				(type default)
			)
			(layer "F.Fab")
		)
		(pad "1" smd circle
			(at -0.40005 0 90)
			(size 0 0)
			(layers "F.Cu" "F.Mask" "F.Paste")
			(net "NIC6_ADC_A1")
		)
		(pad "2" smd circle
			(at 0.40005 0 90)
			(size 0 0)
			(layers "F.Cu" "F.Mask" "F.Paste")
			(net "GND")
		)
	)
	(footprint ""
		(layer "F.Cu")
		(at 17.006316 -305.19751)
		(property "Reference" "PJ10"
			(at 1.504696 -0.114808 0)
			(unlocked yes)
			(layer "F.SilkS")
			(effects
				(font
					(size 0.7874 0.5842)
					(thickness 0.1524)
				)
				(justify left)
			)
		)
		(property "Value" ""
			(at 0 0 0)
			(layer "F.Fab")
			(effects
				(font
					(size 1.27 1.27)
				)
			)
		)
		(duplicate_pad_numbers_are_jumpers no)
		(pad "1" smd circle
			(at -0.40005 0 90)
			(size 0 0)
			(layers "F.Cu" "F.Mask" "F.Paste")
			(net "SH_P1V25_PEX0_FB_N")
		)
		(pad "2" smd rect
			(at 0.40005 0 180)
			(size 0.4572 0.508)
			(layers "F.Cu" "F.Mask" "F.Paste")
			(net "GND")
		)
		(zone
			(layer "F.Cu")
			(hatch none 0.5)
			(connect_pads
				(clearance 0)
			)
			(min_thickness 0.25)
			(keepout
				(tracks allowed)
				(vias not_allowed)
				(pads allowed)
				(copperpour not_allowed)
				(footprints allowed)
			)
			(placement
				(enabled no)
				(sheetname "")
			)
			(fill
				(thermal_gap 0.5)
				(thermal_bridge_width 0.5)
				(island_removal_mode 0)
			)
			(polygon
				(pts
					(xy 16.320516 -304.89271) (xy 17.692116 -304.89271) (xy 17.692116 -305.50231) (xy 16.320516 -305.50231)
				)
			)
		)
	)
	(footprint ""
		(layer "F.Cu")
		(at 460.611982 -109.626654 180)
		(property "Reference" "R962"
			(at 0 0 180)
			(layer "F.SilkS")
			(hide yes)
			(effects
				(font
					(size 1.27 1.27)
				)
			)
		)
		(property "Value" ""
			(at 0 0 180)
			(layer "F.Fab")
			(effects
				(font
					(size 1.27 1.27)
				)
			)
		)
		(duplicate_pad_numbers_are_jumpers no)
		(fp_line
			(start 0.7874 0.4064)
			(end -0.7874 0.4064)
			(stroke
				(width 0.1524)
				(type default)
			)
			(layer "F.SilkS")
		)
		(fp_line
			(start 0.7874 -0.4064)
			(end 0.7874 0.4064)
			(stroke
				(width 0.1524)
				(type default)
			)
			(layer "F.SilkS")
		)
		(fp_line
			(start -0.7874 0.4064)
			(end -0.7874 -0.4064)
			(stroke
				(width 0.1524)
				(type default)
			)
			(layer "F.SilkS")
		)
		(fp_line
			(start -0.7874 -0.4064)
			(end 0.7874 -0.4064)
			(stroke
				(width 0.1524)
				(type default)
			)
			(layer "F.SilkS")
		)
		(fp_line
			(start 0.67945 0.3048)
			(end 0.120396 0.3048)
			(stroke
				(width 0.1)
				(type default)
			)
			(layer "F.Fab")
		)
		(fp_line
			(start 0.67945 -0.3048)
			(end 0.67945 0.3048)
			(stroke
				(width 0.1)
				(type default)
			)
			(layer "F.Fab")
		)
		(fp_line
			(start 0.12065 -0.2794)
			(end 0.12065 -0.3048)
			(stroke
				(width 0.1)
				(type default)
			)
			(layer "F.Fab")
		)
		(fp_line
			(start 0.12065 -0.3048)
			(end 0.67945 -0.3048)
			(stroke
				(width 0.1)
				(type default)
			)
			(layer "F.Fab")
		)
		(fp_line
			(start 0.120396 0.3048)
			(end 0.120396 0.2794)
			(stroke
				(width 0.1)
				(type default)
			)
			(layer "F.Fab")
		)
		(fp_line
			(start 0.120396 0.2794)
			(end -0.12065 0.2794)
			(stroke
				(width 0.1)
				(type default)
			)
			(layer "F.Fab")
		)
		(fp_line
			(start -0.12065 0.3048)
			(end -0.67945 0.3048)
			(stroke
				(width 0.1)
				(type default)
			)
			(layer "F.Fab")
		)
		(fp_line
			(start -0.12065 0.2794)
			(end -0.12065 0.3048)
			(stroke
				(width 0.1)
				(type default)
			)
			(layer "F.Fab")
		)
		(fp_line
			(start -0.12065 -0.2794)
			(end 0.12065 -0.2794)
			(stroke
				(width 0.1)
				(type default)
			)
			(layer "F.Fab")
		)
		(fp_line
			(start -0.12065 -0.305054)
			(end -0.12065 -0.2794)
			(stroke
				(width 0.1)
				(type default)
			)
			(layer "F.Fab")
		)
		(fp_line
			(start -0.67945 0.3048)
			(end -0.67945 -0.305054)
			(stroke
				(width 0.1)
				(type default)
			)
			(layer "F.Fab")
		)
		(fp_line
			(start -0.67945 -0.305054)
			(end -0.12065 -0.305054)
			(stroke
				(width 0.1)
				(type default)
			)
			(layer "F.Fab")
		)
		(pad "1" smd circle
			(at -0.40005 0 180)
			(size 0 0)
			(layers "F.Cu" "F.Mask" "F.Paste")
			(net "GND")
		)
		(pad "2" smd circle
			(at 0.40005 0 180)
			(size 0 0)
			(layers "F.Cu" "F.Mask" "F.Paste")
			(net "P12V_NIC7_CO_EN")
		)
	)
	(footprint ""
		(layer "F.Cu")
		(at 392.092434 -28.225242 180)
		(property "Reference" "C713"
			(at 0 0 180)
			(layer "F.SilkS")
			(hide yes)
			(effects
				(font
					(size 1.27 1.27)
				)
			)
		)
		(property "Value" ""
			(at 0 0 180)
			(layer "F.Fab")
			(effects
				(font
					(size 1.27 1.27)
				)
			)
		)
		(duplicate_pad_numbers_are_jumpers no)
		(fp_line
			(start 0.299974 0.150114)
			(end -0.299974 0.150114)
			(stroke
				(width 0.1)
				(type default)
			)
			(layer "F.Fab")
		)
		(fp_line
			(start 0.299974 -0.150114)
			(end 0.299974 0.150114)
			(stroke
				(width 0.1)
				(type default)
			)
			(layer "F.Fab")
		)
		(fp_line
			(start -0.299974 0.150114)
			(end -0.299974 -0.150114)
			(stroke
				(width 0.1)
				(type default)
			)
			(layer "F.Fab")
		)
		(fp_line
			(start -0.299974 -0.150114)
			(end 0.299974 -0.150114)
			(stroke
				(width 0.1)
				(type default)
			)
			(layer "F.Fab")
		)
		(pad "1" smd rect
			(at -0.2667 0 180)
			(size 0.3048 0.381)
			(layers "F.Cu" "F.Mask" "F.Paste")
			(net "P5E_PEX3_STN2_TX_DN<40>")
		)
		(pad "2" smd rect
			(at 0.2667 0 180)
			(size 0.3048 0.381)
			(layers "F.Cu" "F.Mask" "F.Paste")
			(net "P5E_PEX3_STN2_TX_C_DN<40>")
		)
	)
	(footprint ""
		(layer "F.Cu")
		(at 278.325326 -42.849038 180)
		(property "Reference" "R612"
			(at 0 0 180)
			(layer "F.SilkS")
			(hide yes)
			(effects
				(font
					(size 1.27 1.27)
				)
			)
		)
		(property "Value" ""
			(at 0 0 180)
			(layer "F.Fab")
			(effects
				(font
					(size 1.27 1.27)
				)
			)
		)
		(duplicate_pad_numbers_are_jumpers no)
		(fp_line
			(start 0.7874 0.4064)
			(end -0.7874 0.4064)
			(stroke
				(width 0.1524)
				(type default)
			)
			(layer "F.SilkS")
		)
		(fp_line
			(start 0.7874 -0.4064)
			(end 0.7874 0.4064)
			(stroke
				(width 0.1524)
				(type default)
			)
			(layer "F.SilkS")
		)
		(fp_line
			(start -0.7874 0.4064)
			(end -0.7874 -0.4064)
			(stroke
				(width 0.1524)
				(type default)
			)
			(layer "F.SilkS")
		)
		(fp_line
			(start -0.7874 -0.4064)
			(end 0.7874 -0.4064)
			(stroke
				(width 0.1524)
				(type default)
			)
			(layer "F.SilkS")
		)
		(fp_line
			(start 0.67945 0.3048)
			(end 0.120396 0.3048)
			(stroke
				(width 0.1)
				(type default)
			)
			(layer "F.Fab")
		)
		(fp_line
			(start 0.67945 -0.3048)
			(end 0.67945 0.3048)
			(stroke
				(width 0.1)
				(type default)
			)
			(layer "F.Fab")
		)
		(fp_line
			(start 0.12065 -0.2794)
			(end 0.12065 -0.3048)
			(stroke
				(width 0.1)
				(type default)
			)
			(layer "F.Fab")
		)
		(fp_line
			(start 0.12065 -0.3048)
			(end 0.67945 -0.3048)
			(stroke
				(width 0.1)
				(type default)
			)
			(layer "F.Fab")
		)
		(fp_line
			(start 0.120396 0.3048)
			(end 0.120396 0.2794)
			(stroke
				(width 0.1)
				(type default)
			)
			(layer "F.Fab")
		)
		(fp_line
			(start 0.120396 0.2794)
			(end -0.12065 0.2794)
			(stroke
				(width 0.1)
				(type default)
			)
			(layer "F.Fab")
		)
		(fp_line
			(start -0.12065 0.3048)
			(end -0.67945 0.3048)
			(stroke
				(width 0.1)
				(type default)
			)
			(layer "F.Fab")
		)
		(fp_line
			(start -0.12065 0.2794)
			(end -0.12065 0.3048)
			(stroke
				(width 0.1)
				(type default)
			)
			(layer "F.Fab")
		)
		(fp_line
			(start -0.12065 -0.2794)
			(end 0.12065 -0.2794)
			(stroke
				(width 0.1)
				(type default)
			)
			(layer "F.Fab")
		)
		(fp_line
			(start -0.12065 -0.305054)
			(end -0.12065 -0.2794)
			(stroke
				(width 0.1)
				(type default)
			)
			(layer "F.Fab")
		)
		(fp_line
			(start -0.67945 0.3048)
			(end -0.67945 -0.305054)
			(stroke
				(width 0.1)
				(type default)
			)
			(layer "F.Fab")
		)
		(fp_line
			(start -0.67945 -0.305054)
			(end -0.12065 -0.305054)
			(stroke
				(width 0.1)
				(type default)
			)
			(layer "F.Fab")
		)
		(pad "1" smd circle
			(at -0.40005 0 180)
			(size 0 0)
			(layers "F.Cu" "F.Mask" "F.Paste")
			(net "P12V_SSD9_R")
		)
		(pad "2" smd circle
			(at 0.40005 0 180)
			(size 0 0)
			(layers "F.Cu" "F.Mask" "F.Paste")
			(net "P12V_SSD9_VIN_P")
		)
	)
	(footprint ""
		(layer "F.Cu")
		(at 175.510952 -356.244906 90)
		(property "Reference" "C389"
			(at 0 0 90)
			(layer "F.SilkS")
			(hide yes)
			(effects
				(font
					(size 1.27 1.27)
				)
			)
		)
		(property "Value" ""
			(at 0 0 90)
			(layer "F.Fab")
			(effects
				(font
					(size 1.27 1.27)
				)
			)
		)
		(duplicate_pad_numbers_are_jumpers no)
		(fp_line
			(start 0.299974 -0.150114)
			(end 0.299974 0.150114)
			(stroke
				(width 0.1)
				(type default)
			)
			(layer "F.Fab")
		)
		(fp_line
			(start -0.299974 -0.150114)
			(end 0.299974 -0.150114)
			(stroke
				(width 0.1)
				(type default)
			)
			(layer "F.Fab")
		)
		(fp_line
			(start 0.299974 0.150114)
			(end -0.299974 0.150114)
			(stroke
				(width 0.1)
				(type default)
			)
			(layer "F.Fab")
		)
		(fp_line
			(start -0.299974 0.150114)
			(end -0.299974 -0.150114)
			(stroke
				(width 0.1)
				(type default)
			)
			(layer "F.Fab")
		)
		(pad "1" smd rect
			(at -0.2667 0 90)
			(size 0.3048 0.381)
			(layers "F.Cu" "F.Mask" "F.Paste")
			(net "P5E_PEX1_STN7_TX_DN<119>")
		)
		(pad "2" smd rect
			(at 0.2667 0 90)
			(size 0.3048 0.381)
			(layers "F.Cu" "F.Mask" "F.Paste")
			(net "P5E_PEX1_STN7_TX_C_DN<119>")
		)
	)
	(footprint ""
		(layer "F.Cu")
		(at 16.359632 -146.642328 -90)
		(property "Reference" "C409"
			(at 0 0 270)
			(layer "F.SilkS")
			(hide yes)
			(effects
				(font
					(size 1.27 1.27)
				)
			)
		)
		(property "Value" ""
			(at 0 0 270)
			(layer "F.Fab")
			(effects
				(font
					(size 1.27 1.27)
				)
			)
		)
		(duplicate_pad_numbers_are_jumpers no)
		(fp_line
			(start -0.7874 0.4064)
			(end -0.7874 -0.4064)
			(stroke
				(width 0.1524)
				(type default)
			)
			(layer "F.SilkS")
		)
		(fp_line
			(start 0.7874 0.4064)
			(end -0.7874 0.4064)
			(stroke
				(width 0.1524)
				(type default)
			)
			(layer "F.SilkS")
		)
		(fp_line
			(start -0.7874 -0.4064)
			(end 0.7874 -0.4064)
			(stroke
				(width 0.1524)
				(type default)
			)
			(layer "F.SilkS")
		)
		(fp_line
			(start 0.7874 -0.4064)
			(end 0.7874 0.4064)
			(stroke
				(width 0.1524)
				(type default)
			)
			(layer "F.SilkS")
		)
		(fp_line
			(start -0.67945 0.3048)
			(end -0.67945 -0.305054)
			(stroke
				(width 0.1)
				(type default)
			)
			(layer "F.Fab")
		)
		(fp_line
			(start -0.12065 0.3048)
			(end -0.67945 0.3048)
			(stroke
				(width 0.1)
				(type default)
			)
			(layer "F.Fab")
		)
		(fp_line
			(start 0.120396 0.3048)
			(end 0.120396 0.2794)
			(stroke
				(width 0.1)
				(type default)
			)
			(layer "F.Fab")
		)
		(fp_line
			(start 0.67945 0.3048)
			(end 0.120396 0.3048)
			(stroke
				(width 0.1)
				(type default)
			)
			(layer "F.Fab")
		)
		(fp_line
			(start -0.12065 0.2794)
			(end -0.12065 0.3048)
			(stroke
				(width 0.1)
				(type default)
			)
			(layer "F.Fab")
		)
		(fp_line
			(start 0.120396 0.2794)
			(end -0.12065 0.2794)
			(stroke
				(width 0.1)
				(type default)
			)
			(layer "F.Fab")
		)
		(fp_line
			(start -0.12065 -0.2794)
			(end 0.12065 -0.2794)
			(stroke
				(width 0.1)
				(type default)
			)
			(layer "F.Fab")
		)
		(fp_line
			(start 0.12065 -0.2794)
			(end 0.12065 -0.3048)
			(stroke
				(width 0.1)
				(type default)
			)
			(layer "F.Fab")
		)
		(fp_line
			(start 0.12065 -0.3048)
			(end 0.67945 -0.3048)
			(stroke
				(width 0.1)
				(type default)
			)
			(layer "F.Fab")
		)
		(fp_line
			(start 0.67945 -0.3048)
			(end 0.67945 0.3048)
			(stroke
				(width 0.1)
				(type default)
			)
			(layer "F.Fab")
		)
		(fp_line
			(start -0.67945 -0.305054)
			(end -0.12065 -0.305054)
			(stroke
				(width 0.1)
				(type default)
			)
			(layer "F.Fab")
		)
		(fp_line
			(start -0.12065 -0.305054)
			(end -0.12065 -0.2794)
			(stroke
				(width 0.1)
				(type default)
			)
			(layer "F.Fab")
		)
		(pad "1" smd circle
			(at -0.40005 0 270)
			(size 0 0)
			(layers "F.Cu" "F.Mask" "F.Paste")
			(net "P3V3_AUX")
		)
		(pad "2" smd circle
			(at 0.40005 0 270)
			(size 0 0)
			(layers "F.Cu" "F.Mask" "F.Paste")
			(net "GND")
		)
	)
	(footprint ""
		(layer "F.Cu")
		(at 257.172968 -347.68409)
		(property "Reference" "R6648"
			(at 0 0 0)
			(layer "F.SilkS")
			(hide yes)
			(effects
				(font
					(size 1.27 1.27)
				)
			)
		)
		(property "Value" ""
			(at 0 0 0)
			(layer "F.Fab")
			(effects
				(font
					(size 1.27 1.27)
				)
			)
		)
		(duplicate_pad_numbers_are_jumpers no)
		(fp_line
			(start -0.7874 -0.4064)
			(end 0.7874 -0.4064)
			(stroke
				(width 0.1524)
				(type default)
			)
			(layer "F.SilkS")
		)
		(fp_line
			(start -0.7874 0.4064)
			(end -0.7874 -0.4064)
			(stroke
				(width 0.1524)
				(type default)
			)
			(layer "F.SilkS")
		)
		(fp_line
			(start 0.7874 -0.4064)
			(end 0.7874 0.4064)
			(stroke
				(width 0.1524)
				(type default)
			)
			(layer "F.SilkS")
		)
		(fp_line
			(start 0.7874 0.4064)
			(end -0.7874 0.4064)
			(stroke
				(width 0.1524)
				(type default)
			)
			(layer "F.SilkS")
		)
		(fp_line
			(start -0.67945 -0.305054)
			(end -0.12065 -0.305054)
			(stroke
				(width 0.1)
				(type default)
			)
			(layer "F.Fab")
		)
		(fp_line
			(start -0.67945 0.3048)
			(end -0.67945 -0.305054)
			(stroke
				(width 0.1)
				(type default)
			)
			(layer "F.Fab")
		)
		(fp_line
			(start -0.12065 -0.305054)
			(end -0.12065 -0.2794)
			(stroke
				(width 0.1)
				(type default)
			)
			(layer "F.Fab")
		)
		(fp_line
			(start -0.12065 -0.2794)
			(end 0.12065 -0.2794)
			(stroke
				(width 0.1)
				(type default)
			)
			(layer "F.Fab")
		)
		(fp_line
			(start -0.12065 0.2794)
			(end -0.12065 0.3048)
			(stroke
				(width 0.1)
				(type default)
			)
			(layer "F.Fab")
		)
		(fp_line
			(start -0.12065 0.3048)
			(end -0.67945 0.3048)
			(stroke
				(width 0.1)
				(type default)
			)
			(layer "F.Fab")
		)
		(fp_line
			(start 0.120396 0.2794)
			(end -0.12065 0.2794)
			(stroke
				(width 0.1)
				(type default)
			)
			(layer "F.Fab")
		)
		(fp_line
			(start 0.120396 0.3048)
			(end 0.120396 0.2794)
			(stroke
				(width 0.1)
				(type default)
			)
			(layer "F.Fab")
		)
		(fp_line
			(start 0.12065 -0.3048)
			(end 0.67945 -0.3048)
			(stroke
				(width 0.1)
				(type default)
			)
			(layer "F.Fab")
		)
		(fp_line
			(start 0.12065 -0.2794)
			(end 0.12065 -0.3048)
			(stroke
				(width 0.1)
				(type default)
			)
			(layer "F.Fab")
		)
		(fp_line
			(start 0.67945 -0.3048)
			(end 0.67945 0.3048)
			(stroke
				(width 0.1)
				(type default)
			)
			(layer "F.Fab")
		)
		(fp_line
			(start 0.67945 0.3048)
			(end 0.120396 0.3048)
			(stroke
				(width 0.1)
				(type default)
			)
			(layer "F.Fab")
		)
		(pad "1" smd circle
			(at -0.40005 0)
			(size 0 0)
			(layers "F.Cu" "F.Mask" "F.Paste")
			(net "HSC_CSOUT")
		)
		(pad "2" smd circle
			(at 0.40005 0)
			(size 0 0)
			(layers "F.Cu" "F.Mask" "F.Paste")
			(net "A_HSC_LOW")
		)
	)
	(footprint ""
		(layer "F.Cu")
		(at 404.861268 -365.268256 -90)
		(property "Reference" "C4452"
			(at 0 0 270)
			(layer "F.SilkS")
			(hide yes)
			(effects
				(font
					(size 1.27 1.27)
				)
			)
		)
		(property "Value" ""
			(at 0 0 270)
			(layer "F.Fab")
			(effects
				(font
					(size 1.27 1.27)
				)
			)
		)
		(duplicate_pad_numbers_are_jumpers no)
		(fp_line
			(start -0.299974 0.150114)
			(end -0.299974 -0.150114)
			(stroke
				(width 0.1)
				(type default)
			)
			(layer "F.Fab")
		)
		(fp_line
			(start 0.299974 0.150114)
			(end -0.299974 0.150114)
			(stroke
				(width 0.1)
				(type default)
			)
			(layer "F.Fab")
		)
		(fp_line
			(start -0.299974 -0.150114)
			(end 0.299974 -0.150114)
			(stroke
				(width 0.1)
				(type default)
			)
			(layer "F.Fab")
		)
		(fp_line
			(start 0.299974 -0.150114)
			(end 0.299974 0.150114)
			(stroke
				(width 0.1)
				(type default)
			)
			(layer "F.Fab")
		)
		(pad "1" smd rect
			(at -0.2667 0 270)
			(size 0.3048 0.381)
			(layers "F.Cu" "F.Mask" "F.Paste")
			(net "GPU_3V3IO_RSVD1_ISO")
		)
		(pad "2" smd rect
			(at 0.2667 0 270)
			(size 0.3048 0.381)
			(layers "F.Cu" "F.Mask" "F.Paste")
			(net "GND")
		)
	)
	(footprint ""
		(layer "F.Cu")
		(at 203.838048 -291.102034 180)
		(property "Reference" "R6391"
			(at 0 0 180)
			(layer "F.SilkS")
			(hide yes)
			(effects
				(font
					(size 1.27 1.27)
				)
			)
		)
		(property "Value" ""
			(at 0 0 180)
			(layer "F.Fab")
			(effects
				(font
					(size 1.27 1.27)
				)
			)
		)
		(duplicate_pad_numbers_are_jumpers no)
		(fp_line
			(start 0.7874 0.4064)
			(end -0.7874 0.4064)
			(stroke
				(width 0.1524)
				(type default)
			)
			(layer "F.SilkS")
		)
		(fp_line
			(start 0.7874 -0.4064)
			(end 0.7874 0.4064)
			(stroke
				(width 0.1524)
				(type default)
			)
			(layer "F.SilkS")
		)
		(fp_line
			(start -0.7874 0.4064)
			(end -0.7874 -0.4064)
			(stroke
				(width 0.1524)
				(type default)
			)
			(layer "F.SilkS")
		)
		(fp_line
			(start -0.7874 -0.4064)
			(end 0.7874 -0.4064)
			(stroke
				(width 0.1524)
				(type default)
			)
			(layer "F.SilkS")
		)
		(fp_line
			(start 0.67945 0.3048)
			(end 0.120396 0.3048)
			(stroke
				(width 0.1)
				(type default)
			)
			(layer "F.Fab")
		)
		(fp_line
			(start 0.67945 -0.3048)
			(end 0.67945 0.3048)
			(stroke
				(width 0.1)
				(type default)
			)
			(layer "F.Fab")
		)
		(fp_line
			(start 0.12065 -0.2794)
			(end 0.12065 -0.3048)
			(stroke
				(width 0.1)
				(type default)
			)
			(layer "F.Fab")
		)
		(fp_line
			(start 0.12065 -0.3048)
			(end 0.67945 -0.3048)
			(stroke
				(width 0.1)
				(type default)
			)
			(layer "F.Fab")
		)
		(fp_line
			(start 0.120396 0.3048)
			(end 0.120396 0.2794)
			(stroke
				(width 0.1)
				(type default)
			)
			(layer "F.Fab")
		)
		(fp_line
			(start 0.120396 0.2794)
			(end -0.12065 0.2794)
			(stroke
				(width 0.1)
				(type default)
			)
			(layer "F.Fab")
		)
		(fp_line
			(start -0.12065 0.3048)
			(end -0.67945 0.3048)
			(stroke
				(width 0.1)
				(type default)
			)
			(layer "F.Fab")
		)
		(fp_line
			(start -0.12065 0.2794)
			(end -0.12065 0.3048)
			(stroke
				(width 0.1)
				(type default)
			)
			(layer "F.Fab")
		)
		(fp_line
			(start -0.12065 -0.2794)
			(end 0.12065 -0.2794)
			(stroke
				(width 0.1)
				(type default)
			)
			(layer "F.Fab")
		)
		(fp_line
			(start -0.12065 -0.305054)
			(end -0.12065 -0.2794)
			(stroke
				(width 0.1)
				(type default)
			)
			(layer "F.Fab")
		)
		(fp_line
			(start -0.67945 0.3048)
			(end -0.67945 -0.305054)
			(stroke
				(width 0.1)
				(type default)
			)
			(layer "F.Fab")
		)
		(fp_line
			(start -0.67945 -0.305054)
			(end -0.12065 -0.305054)
			(stroke
				(width 0.1)
				(type default)
			)
			(layer "F.Fab")
		)
		(pad "1" smd circle
			(at -0.40005 0 180)
			(size 0 0)
			(layers "F.Cu" "F.Mask" "F.Paste")
			(net "GND")
		)
		(pad "2" smd circle
			(at 0.40005 0 180)
			(size 0 0)
			(layers "F.Cu" "F.Mask" "F.Paste")
			(net "RST_PEX1_PERST_R_N")
		)
	)
	(footprint ""
		(layer "F.Cu")
		(at 358.013 -221.488)
		(property "Reference" "R3647"
			(at 0 0 0)
			(layer "F.SilkS")
			(hide yes)
			(effects
				(font
					(size 1.27 1.27)
				)
			)
		)
		(property "Value" ""
			(at 0 0 0)
			(layer "F.Fab")
			(effects
				(font
					(size 1.27 1.27)
				)
			)
		)
		(duplicate_pad_numbers_are_jumpers no)
		(fp_line
			(start -0.7874 -0.4064)
			(end 0.7874 -0.4064)
			(stroke
				(width 0.1524)
				(type default)
			)
			(layer "F.SilkS")
		)
		(fp_line
			(start -0.7874 0.4064)
			(end -0.7874 -0.4064)
			(stroke
				(width 0.1524)
				(type default)
			)
			(layer "F.SilkS")
		)
		(fp_line
			(start 0.7874 -0.4064)
			(end 0.7874 0.4064)
			(stroke
				(width 0.1524)
				(type default)
			)
			(layer "F.SilkS")
		)
		(fp_line
			(start 0.7874 0.4064)
			(end -0.7874 0.4064)
			(stroke
				(width 0.1524)
				(type default)
			)
			(layer "F.SilkS")
		)
		(fp_line
			(start -0.67945 -0.305054)
			(end -0.12065 -0.305054)
			(stroke
				(width 0.1)
				(type default)
			)
			(layer "F.Fab")
		)
		(fp_line
			(start -0.67945 0.3048)
			(end -0.67945 -0.305054)
			(stroke
				(width 0.1)
				(type default)
			)
			(layer "F.Fab")
		)
		(fp_line
			(start -0.12065 -0.305054)
			(end -0.12065 -0.2794)
			(stroke
				(width 0.1)
				(type default)
			)
			(layer "F.Fab")
		)
		(fp_line
			(start -0.12065 -0.2794)
			(end 0.12065 -0.2794)
			(stroke
				(width 0.1)
				(type default)
			)
			(layer "F.Fab")
		)
		(fp_line
			(start -0.12065 0.2794)
			(end -0.12065 0.3048)
			(stroke
				(width 0.1)
				(type default)
			)
			(layer "F.Fab")
		)
		(fp_line
			(start -0.12065 0.3048)
			(end -0.67945 0.3048)
			(stroke
				(width 0.1)
				(type default)
			)
			(layer "F.Fab")
		)
		(fp_line
			(start 0.120396 0.2794)
			(end -0.12065 0.2794)
			(stroke
				(width 0.1)
				(type default)
			)
			(layer "F.Fab")
		)
		(fp_line
			(start 0.120396 0.3048)
			(end 0.120396 0.2794)
			(stroke
				(width 0.1)
				(type default)
			)
			(layer "F.Fab")
		)
		(fp_line
			(start 0.12065 -0.3048)
			(end 0.67945 -0.3048)
			(stroke
				(width 0.1)
				(type default)
			)
			(layer "F.Fab")
		)
		(fp_line
			(start 0.12065 -0.2794)
			(end 0.12065 -0.3048)
			(stroke
				(width 0.1)
				(type default)
			)
			(layer "F.Fab")
		)
		(fp_line
			(start 0.67945 -0.3048)
			(end 0.67945 0.3048)
			(stroke
				(width 0.1)
				(type default)
			)
			(layer "F.Fab")
		)
		(fp_line
			(start 0.67945 0.3048)
			(end 0.120396 0.3048)
			(stroke
				(width 0.1)
				(type default)
			)
			(layer "F.Fab")
		)
		(pad "1" smd circle
			(at -0.40005 0)
			(size 0 0)
			(layers "F.Cu" "F.Mask" "F.Paste")
			(net "RST_NIC5_PERST_N")
		)
		(pad "2" smd circle
			(at 0.40005 0)
			(size 0 0)
			(layers "F.Cu" "F.Mask" "F.Paste")
			(net "RST_NIC5_PERST_R_N")
		)
	)
	(footprint ""
		(layer "F.Cu")
		(at 302.838612 -22.867366 90)
		(property "Reference" "C3947"
			(at 0 0 90)
			(layer "F.SilkS")
			(hide yes)
			(effects
				(font
					(size 1.27 1.27)
				)
			)
		)
		(property "Value" ""
			(at 0 0 90)
			(layer "F.Fab")
			(effects
				(font
					(size 1.27 1.27)
				)
			)
		)
		(duplicate_pad_numbers_are_jumpers no)
		(fp_line
			(start 0.7874 -0.4064)
			(end 0.7874 0.4064)
			(stroke
				(width 0.1524)
				(type default)
			)
			(layer "F.SilkS")
		)
		(fp_line
			(start -0.7874 -0.4064)
			(end 0.7874 -0.4064)
			(stroke
				(width 0.1524)
				(type default)
			)
			(layer "F.SilkS")
		)
		(fp_line
			(start 0.7874 0.4064)
			(end -0.7874 0.4064)
			(stroke
				(width 0.1524)
				(type default)
			)
			(layer "F.SilkS")
		)
		(fp_line
			(start -0.7874 0.4064)
			(end -0.7874 -0.4064)
			(stroke
				(width 0.1524)
				(type default)
			)
			(layer "F.SilkS")
		)
		(fp_line
			(start -0.12065 -0.305054)
			(end -0.12065 -0.2794)
			(stroke
				(width 0.1)
				(type default)
			)
			(layer "F.Fab")
		)
		(fp_line
			(start -0.67945 -0.305054)
			(end -0.12065 -0.305054)
			(stroke
				(width 0.1)
				(type default)
			)
			(layer "F.Fab")
		)
		(fp_line
			(start 0.67945 -0.3048)
			(end 0.67945 0.3048)
			(stroke
				(width 0.1)
				(type default)
			)
			(layer "F.Fab")
		)
		(fp_line
			(start 0.12065 -0.3048)
			(end 0.67945 -0.3048)
			(stroke
				(width 0.1)
				(type default)
			)
			(layer "F.Fab")
		)
		(fp_line
			(start 0.12065 -0.2794)
			(end 0.12065 -0.3048)
			(stroke
				(width 0.1)
				(type default)
			)
			(layer "F.Fab")
		)
		(fp_line
			(start -0.12065 -0.2794)
			(end 0.12065 -0.2794)
			(stroke
				(width 0.1)
				(type default)
			)
			(layer "F.Fab")
		)
		(fp_line
			(start 0.120396 0.2794)
			(end -0.12065 0.2794)
			(stroke
				(width 0.1)
				(type default)
			)
			(layer "F.Fab")
		)
		(fp_line
			(start -0.12065 0.2794)
			(end -0.12065 0.3048)
			(stroke
				(width 0.1)
				(type default)
			)
			(layer "F.Fab")
		)
		(fp_line
			(start 0.67945 0.3048)
			(end 0.120396 0.3048)
			(stroke
				(width 0.1)
				(type default)
			)
			(layer "F.Fab")
		)
		(fp_line
			(start 0.120396 0.3048)
			(end 0.120396 0.2794)
			(stroke
				(width 0.1)
				(type default)
			)
			(layer "F.Fab")
		)
		(fp_line
			(start -0.12065 0.3048)
			(end -0.67945 0.3048)
			(stroke
				(width 0.1)
				(type default)
			)
			(layer "F.Fab")
		)
		(fp_line
			(start -0.67945 0.3048)
			(end -0.67945 -0.305054)
			(stroke
				(width 0.1)
				(type default)
			)
			(layer "F.Fab")
		)
		(pad "1" smd circle
			(at -0.40005 0 90)
			(size 0 0)
			(layers "F.Cu" "F.Mask" "F.Paste")
			(net "P12V_SSD10")
		)
		(pad "2" smd circle
			(at 0.40005 0 90)
			(size 0 0)
			(layers "F.Cu" "F.Mask" "F.Paste")
			(net "GND")
		)
	)
	(footprint ""
		(layer "F.Cu")
		(at 215.075516 -121.255028)
		(property "Reference" "PC337"
			(at 0 0 0)
			(layer "F.SilkS")
			(hide yes)
			(effects
				(font
					(size 1.27 1.27)
				)
			)
		)
		(property "Value" ""
			(at 0 0 0)
			(layer "F.Fab")
			(effects
				(font
					(size 1.27 1.27)
				)
			)
		)
		(duplicate_pad_numbers_are_jumpers no)
		(fp_line
			(start -0.7874 -0.4064)
			(end 0.7874 -0.4064)
			(stroke
				(width 0.1524)
				(type default)
			)
			(layer "F.SilkS")
		)
		(fp_line
			(start -0.7874 0.4064)
			(end -0.7874 -0.4064)
			(stroke
				(width 0.1524)
				(type default)
			)
			(layer "F.SilkS")
		)
		(fp_line
			(start 0.7874 -0.4064)
			(end 0.7874 0.4064)
			(stroke
				(width 0.1524)
				(type default)
			)
			(layer "F.SilkS")
		)
		(fp_line
			(start 0.7874 0.4064)
			(end -0.7874 0.4064)
			(stroke
				(width 0.1524)
				(type default)
			)
			(layer "F.SilkS")
		)
		(fp_line
			(start -0.67945 -0.305054)
			(end -0.12065 -0.305054)
			(stroke
				(width 0.1)
				(type default)
			)
			(layer "F.Fab")
		)
		(fp_line
			(start -0.67945 0.3048)
			(end -0.67945 -0.305054)
			(stroke
				(width 0.1)
				(type default)
			)
			(layer "F.Fab")
		)
		(fp_line
			(start -0.12065 -0.305054)
			(end -0.12065 -0.2794)
			(stroke
				(width 0.1)
				(type default)
			)
			(layer "F.Fab")
		)
		(fp_line
			(start -0.12065 -0.2794)
			(end 0.12065 -0.2794)
			(stroke
				(width 0.1)
				(type default)
			)
			(layer "F.Fab")
		)
		(fp_line
			(start -0.12065 0.2794)
			(end -0.12065 0.3048)
			(stroke
				(width 0.1)
				(type default)
			)
			(layer "F.Fab")
		)
		(fp_line
			(start -0.12065 0.3048)
			(end -0.67945 0.3048)
			(stroke
				(width 0.1)
				(type default)
			)
			(layer "F.Fab")
		)
		(fp_line
			(start 0.120396 0.2794)
			(end -0.12065 0.2794)
			(stroke
				(width 0.1)
				(type default)
			)
			(layer "F.Fab")
		)
		(fp_line
			(start 0.120396 0.3048)
			(end 0.120396 0.2794)
			(stroke
				(width 0.1)
				(type default)
			)
			(layer "F.Fab")
		)
		(fp_line
			(start 0.12065 -0.3048)
			(end 0.67945 -0.3048)
			(stroke
				(width 0.1)
				(type default)
			)
			(layer "F.Fab")
		)
		(fp_line
			(start 0.12065 -0.2794)
			(end 0.12065 -0.3048)
			(stroke
				(width 0.1)
				(type default)
			)
			(layer "F.Fab")
		)
		(fp_line
			(start 0.67945 -0.3048)
			(end 0.67945 0.3048)
			(stroke
				(width 0.1)
				(type default)
			)
			(layer "F.Fab")
		)
		(fp_line
			(start 0.67945 0.3048)
			(end 0.120396 0.3048)
			(stroke
				(width 0.1)
				(type default)
			)
			(layer "F.Fab")
		)
		(pad "1" smd circle
			(at -0.40005 0)
			(size 0 0)
			(layers "F.Cu" "F.Mask" "F.Paste")
			(net "P5V_AUX")
		)
		(pad "2" smd circle
			(at 0.40005 0)
			(size 0 0)
			(layers "F.Cu" "F.Mask" "F.Paste")
			(net "GND")
		)
	)
	(footprint ""
		(layer "F.Cu")
		(at 17.947132 -55.63489 90)
		(property "Reference" "PC357"
			(at 0 0 90)
			(layer "F.SilkS")
			(hide yes)
			(effects
				(font
					(size 1.27 1.27)
				)
			)
		)
		(property "Value" ""
			(at 0 0 90)
			(layer "F.Fab")
			(effects
				(font
					(size 1.27 1.27)
				)
			)
		)
		(duplicate_pad_numbers_are_jumpers no)
		(fp_line
			(start 1.524 -0.762)
			(end 1.524 0.762)
			(stroke
				(width 0.1524)
				(type default)
			)
			(layer "F.SilkS")
		)
		(fp_line
			(start -1.524 -0.762)
			(end 1.524 -0.762)
			(stroke
				(width 0.1524)
				(type default)
			)
			(layer "F.SilkS")
		)
		(fp_line
			(start 1.524 0.762)
			(end -1.524 0.762)
			(stroke
				(width 0.1524)
				(type default)
			)
			(layer "F.SilkS")
		)
		(fp_line
			(start -1.524 0.762)
			(end -1.524 -0.762)
			(stroke
				(width 0.1524)
				(type default)
			)
			(layer "F.SilkS")
		)
		(fp_line
			(start 1.1049 -0.724916)
			(end -1.1049 -0.724916)
			(stroke
				(width 0.1)
				(type default)
			)
			(layer "F.Fab")
		)
		(fp_line
			(start -1.1049 -0.724916)
			(end -1.1049 0.724916)
			(stroke
				(width 0.1)
				(type default)
			)
			(layer "F.Fab")
		)
		(fp_line
			(start 1.1049 0.724916)
			(end 1.1049 -0.724916)
			(stroke
				(width 0.1)
				(type default)
			)
			(layer "F.Fab")
		)
		(fp_line
			(start -1.1049 0.724916)
			(end 1.1049 0.724916)
			(stroke
				(width 0.1)
				(type default)
			)
			(layer "F.Fab")
		)
		(pad "1" smd rect
			(at -0.889 0 270)
			(size 1.016 1.27)
			(layers "F.Cu" "F.Mask" "F.Paste")
			(net "P12V_SSD0_R")
		)
		(pad "2" smd rect
			(at 0.889 0 270)
			(size 1.016 1.27)
			(layers "F.Cu" "F.Mask" "F.Paste")
			(net "GND")
		)
	)
	(footprint ""
		(layer "F.Cu")
		(at 270.990822 -142.892018)
		(property "Reference" "R234"
			(at 0 0 0)
			(layer "F.SilkS")
			(hide yes)
			(effects
				(font
					(size 1.27 1.27)
				)
			)
		)
		(property "Value" ""
			(at 0 0 0)
			(layer "F.Fab")
			(effects
				(font
					(size 1.27 1.27)
				)
			)
		)
		(duplicate_pad_numbers_are_jumpers no)
		(fp_line
			(start -0.7874 -0.4064)
			(end 0.7874 -0.4064)
			(stroke
				(width 0.1524)
				(type default)
			)
			(layer "F.SilkS")
		)
		(fp_line
			(start -0.7874 0.4064)
			(end -0.7874 -0.4064)
			(stroke
				(width 0.1524)
				(type default)
			)
			(layer "F.SilkS")
		)
		(fp_line
			(start 0.7874 -0.4064)
			(end 0.7874 0.4064)
			(stroke
				(width 0.1524)
				(type default)
			)
			(layer "F.SilkS")
		)
		(fp_line
			(start 0.7874 0.4064)
			(end -0.7874 0.4064)
			(stroke
				(width 0.1524)
				(type default)
			)
			(layer "F.SilkS")
		)
		(fp_line
			(start -0.67945 -0.305054)
			(end -0.12065 -0.305054)
			(stroke
				(width 0.1)
				(type default)
			)
			(layer "F.Fab")
		)
		(fp_line
			(start -0.67945 0.3048)
			(end -0.67945 -0.305054)
			(stroke
				(width 0.1)
				(type default)
			)
			(layer "F.Fab")
		)
		(fp_line
			(start -0.12065 -0.305054)
			(end -0.12065 -0.2794)
			(stroke
				(width 0.1)
				(type default)
			)
			(layer "F.Fab")
		)
		(fp_line
			(start -0.12065 -0.2794)
			(end 0.12065 -0.2794)
			(stroke
				(width 0.1)
				(type default)
			)
			(layer "F.Fab")
		)
		(fp_line
			(start -0.12065 0.2794)
			(end -0.12065 0.3048)
			(stroke
				(width 0.1)
				(type default)
			)
			(layer "F.Fab")
		)
		(fp_line
			(start -0.12065 0.3048)
			(end -0.67945 0.3048)
			(stroke
				(width 0.1)
				(type default)
			)
			(layer "F.Fab")
		)
		(fp_line
			(start 0.120396 0.2794)
			(end -0.12065 0.2794)
			(stroke
				(width 0.1)
				(type default)
			)
			(layer "F.Fab")
		)
		(fp_line
			(start 0.120396 0.3048)
			(end 0.120396 0.2794)
			(stroke
				(width 0.1)
				(type default)
			)
			(layer "F.Fab")
		)
		(fp_line
			(start 0.12065 -0.3048)
			(end 0.67945 -0.3048)
			(stroke
				(width 0.1)
				(type default)
			)
			(layer "F.Fab")
		)
		(fp_line
			(start 0.12065 -0.2794)
			(end 0.12065 -0.3048)
			(stroke
				(width 0.1)
				(type default)
			)
			(layer "F.Fab")
		)
		(fp_line
			(start 0.67945 -0.3048)
			(end 0.67945 0.3048)
			(stroke
				(width 0.1)
				(type default)
			)
			(layer "F.Fab")
		)
		(fp_line
			(start 0.67945 0.3048)
			(end 0.120396 0.3048)
			(stroke
				(width 0.1)
				(type default)
			)
			(layer "F.Fab")
		)
		(pad "1" smd circle
			(at -0.40005 0)
			(size 0 0)
			(layers "F.Cu" "F.Mask" "F.Paste")
			(net "NIC4_BIF0_N")
		)
		(pad "2" smd circle
			(at 0.40005 0)
			(size 0 0)
			(layers "F.Cu" "F.Mask" "F.Paste")
			(net "GND")
		)
	)
	(footprint ""
		(layer "F.Cu")
		(at 256.19329 -77.279754 90)
		(property "Reference" "R1065"
			(at 0 0 90)
			(layer "F.SilkS")
			(hide yes)
			(effects
				(font
					(size 1.27 1.27)
				)
			)
		)
		(property "Value" ""
			(at 0 0 90)
			(layer "F.Fab")
			(effects
				(font
					(size 1.27 1.27)
				)
			)
		)
		(duplicate_pad_numbers_are_jumpers no)
		(fp_line
			(start 0.7874 -0.4064)
			(end 0.7874 0.4064)
			(stroke
				(width 0.1524)
				(type default)
			)
			(layer "F.SilkS")
		)
		(fp_line
			(start -0.7874 -0.4064)
			(end 0.7874 -0.4064)
			(stroke
				(width 0.1524)
				(type default)
			)
			(layer "F.SilkS")
		)
		(fp_line
			(start 0.7874 0.4064)
			(end -0.7874 0.4064)
			(stroke
				(width 0.1524)
				(type default)
			)
			(layer "F.SilkS")
		)
		(fp_line
			(start -0.7874 0.4064)
			(end -0.7874 -0.4064)
			(stroke
				(width 0.1524)
				(type default)
			)
			(layer "F.SilkS")
		)
		(fp_line
			(start -0.12065 -0.305054)
			(end -0.12065 -0.2794)
			(stroke
				(width 0.1)
				(type default)
			)
			(layer "F.Fab")
		)
		(fp_line
			(start -0.67945 -0.305054)
			(end -0.12065 -0.305054)
			(stroke
				(width 0.1)
				(type default)
			)
			(layer "F.Fab")
		)
		(fp_line
			(start 0.67945 -0.3048)
			(end 0.67945 0.3048)
			(stroke
				(width 0.1)
				(type default)
			)
			(layer "F.Fab")
		)
		(fp_line
			(start 0.12065 -0.3048)
			(end 0.67945 -0.3048)
			(stroke
				(width 0.1)
				(type default)
			)
			(layer "F.Fab")
		)
		(fp_line
			(start 0.12065 -0.2794)
			(end 0.12065 -0.3048)
			(stroke
				(width 0.1)
				(type default)
			)
			(layer "F.Fab")
		)
		(fp_line
			(start -0.12065 -0.2794)
			(end 0.12065 -0.2794)
			(stroke
				(width 0.1)
				(type default)
			)
			(layer "F.Fab")
		)
		(fp_line
			(start 0.120396 0.2794)
			(end -0.12065 0.2794)
			(stroke
				(width 0.1)
				(type default)
			)
			(layer "F.Fab")
		)
		(fp_line
			(start -0.12065 0.2794)
			(end -0.12065 0.3048)
			(stroke
				(width 0.1)
				(type default)
			)
			(layer "F.Fab")
		)
		(fp_line
			(start 0.67945 0.3048)
			(end 0.120396 0.3048)
			(stroke
				(width 0.1)
				(type default)
			)
			(layer "F.Fab")
		)
		(fp_line
			(start 0.120396 0.3048)
			(end 0.120396 0.2794)
			(stroke
				(width 0.1)
				(type default)
			)
			(layer "F.Fab")
		)
		(fp_line
			(start -0.12065 0.3048)
			(end -0.67945 0.3048)
			(stroke
				(width 0.1)
				(type default)
			)
			(layer "F.Fab")
		)
		(fp_line
			(start -0.67945 0.3048)
			(end -0.67945 -0.305054)
			(stroke
				(width 0.1)
				(type default)
			)
			(layer "F.Fab")
		)
		(pad "1" smd circle
			(at -0.40005 0 90)
			(size 0 0)
			(layers "F.Cu" "F.Mask" "F.Paste")
			(net "GND")
		)
		(pad "2" smd circle
			(at 0.40005 0 90)
			(size 0 0)
			(layers "F.Cu" "F.Mask" "F.Paste")
			(net "FM_CLK_EN_R")
		)
	)
	(footprint ""
		(layer "F.Cu")
		(at 452.316596 -307.260752 90)
		(property "Reference" "PC277"
			(at 0 0 90)
			(layer "F.SilkS")
			(hide yes)
			(effects
				(font
					(size 1.27 1.27)
				)
			)
		)
		(property "Value" ""
			(at 0 0 90)
			(layer "F.Fab")
			(effects
				(font
					(size 1.27 1.27)
				)
			)
		)
		(duplicate_pad_numbers_are_jumpers no)
		(fp_line
			(start 0.7874 -0.4064)
			(end 0.7874 0.4064)
			(stroke
				(width 0.1524)
				(type default)
			)
			(layer "F.SilkS")
		)
		(fp_line
			(start -0.7874 -0.4064)
			(end 0.7874 -0.4064)
			(stroke
				(width 0.1524)
				(type default)
			)
			(layer "F.SilkS")
		)
		(fp_line
			(start 0.7874 0.4064)
			(end -0.7874 0.4064)
			(stroke
				(width 0.1524)
				(type default)
			)
			(layer "F.SilkS")
		)
		(fp_line
			(start -0.7874 0.4064)
			(end -0.7874 -0.4064)
			(stroke
				(width 0.1524)
				(type default)
			)
			(layer "F.SilkS")
		)
		(fp_line
			(start -0.12065 -0.305054)
			(end -0.12065 -0.2794)
			(stroke
				(width 0.1)
				(type default)
			)
			(layer "F.Fab")
		)
		(fp_line
			(start -0.67945 -0.305054)
			(end -0.12065 -0.305054)
			(stroke
				(width 0.1)
				(type default)
			)
			(layer "F.Fab")
		)
		(fp_line
			(start 0.67945 -0.3048)
			(end 0.67945 0.3048)
			(stroke
				(width 0.1)
				(type default)
			)
			(layer "F.Fab")
		)
		(fp_line
			(start 0.12065 -0.3048)
			(end 0.67945 -0.3048)
			(stroke
				(width 0.1)
				(type default)
			)
			(layer "F.Fab")
		)
		(fp_line
			(start 0.12065 -0.2794)
			(end 0.12065 -0.3048)
			(stroke
				(width 0.1)
				(type default)
			)
			(layer "F.Fab")
		)
		(fp_line
			(start -0.12065 -0.2794)
			(end 0.12065 -0.2794)
			(stroke
				(width 0.1)
				(type default)
			)
			(layer "F.Fab")
		)
		(fp_line
			(start 0.120396 0.2794)
			(end -0.12065 0.2794)
			(stroke
				(width 0.1)
				(type default)
			)
			(layer "F.Fab")
		)
		(fp_line
			(start -0.12065 0.2794)
			(end -0.12065 0.3048)
			(stroke
				(width 0.1)
				(type default)
			)
			(layer "F.Fab")
		)
		(fp_line
			(start 0.67945 0.3048)
			(end 0.120396 0.3048)
			(stroke
				(width 0.1)
				(type default)
			)
			(layer "F.Fab")
		)
		(fp_line
			(start 0.120396 0.3048)
			(end 0.120396 0.2794)
			(stroke
				(width 0.1)
				(type default)
			)
			(layer "F.Fab")
		)
		(fp_line
			(start -0.12065 0.3048)
			(end -0.67945 0.3048)
			(stroke
				(width 0.1)
				(type default)
			)
			(layer "F.Fab")
		)
		(fp_line
			(start -0.67945 0.3048)
			(end -0.67945 -0.305054)
			(stroke
				(width 0.1)
				(type default)
			)
			(layer "F.Fab")
		)
		(pad "1" smd circle
			(at -0.40005 0 90)
			(size 0 0)
			(layers "F.Cu" "F.Mask" "F.Paste")
			(net "P1V25_PEX3_VCC")
		)
		(pad "2" smd circle
			(at 0.40005 0 90)
			(size 0 0)
			(layers "F.Cu" "F.Mask" "F.Paste")
			(net "GND")
		)
	)
	(footprint ""
		(layer "F.Cu")
		(at 151.398478 -137.259314 -90)
		(property "Reference" "C883"
			(at 0 0 270)
			(layer "F.SilkS")
			(hide yes)
			(effects
				(font
					(size 1.27 1.27)
				)
			)
		)
		(property "Value" ""
			(at 0 0 270)
			(layer "F.Fab")
			(effects
				(font
					(size 1.27 1.27)
				)
			)
		)
		(duplicate_pad_numbers_are_jumpers no)
		(fp_line
			(start -0.7874 0.4064)
			(end -0.7874 -0.4064)
			(stroke
				(width 0.1524)
				(type default)
			)
			(layer "F.SilkS")
		)
		(fp_line
			(start 0.7874 0.4064)
			(end -0.7874 0.4064)
			(stroke
				(width 0.1524)
				(type default)
			)
			(layer "F.SilkS")
		)
		(fp_line
			(start -0.7874 -0.4064)
			(end 0.7874 -0.4064)
			(stroke
				(width 0.1524)
				(type default)
			)
			(layer "F.SilkS")
		)
		(fp_line
			(start 0.7874 -0.4064)
			(end 0.7874 0.4064)
			(stroke
				(width 0.1524)
				(type default)
			)
			(layer "F.SilkS")
		)
		(fp_line
			(start -0.67945 0.3048)
			(end -0.67945 -0.305054)
			(stroke
				(width 0.1)
				(type default)
			)
			(layer "F.Fab")
		)
		(fp_line
			(start -0.12065 0.3048)
			(end -0.67945 0.3048)
			(stroke
				(width 0.1)
				(type default)
			)
			(layer "F.Fab")
		)
		(fp_line
			(start 0.120396 0.3048)
			(end 0.120396 0.2794)
			(stroke
				(width 0.1)
				(type default)
			)
			(layer "F.Fab")
		)
		(fp_line
			(start 0.67945 0.3048)
			(end 0.120396 0.3048)
			(stroke
				(width 0.1)
				(type default)
			)
			(layer "F.Fab")
		)
		(fp_line
			(start -0.12065 0.2794)
			(end -0.12065 0.3048)
			(stroke
				(width 0.1)
				(type default)
			)
			(layer "F.Fab")
		)
		(fp_line
			(start 0.120396 0.2794)
			(end -0.12065 0.2794)
			(stroke
				(width 0.1)
				(type default)
			)
			(layer "F.Fab")
		)
		(fp_line
			(start -0.12065 -0.2794)
			(end 0.12065 -0.2794)
			(stroke
				(width 0.1)
				(type default)
			)
			(layer "F.Fab")
		)
		(fp_line
			(start 0.12065 -0.2794)
			(end 0.12065 -0.3048)
			(stroke
				(width 0.1)
				(type default)
			)
			(layer "F.Fab")
		)
		(fp_line
			(start 0.12065 -0.3048)
			(end 0.67945 -0.3048)
			(stroke
				(width 0.1)
				(type default)
			)
			(layer "F.Fab")
		)
		(fp_line
			(start 0.67945 -0.3048)
			(end 0.67945 0.3048)
			(stroke
				(width 0.1)
				(type default)
			)
			(layer "F.Fab")
		)
		(fp_line
			(start -0.67945 -0.305054)
			(end -0.12065 -0.305054)
			(stroke
				(width 0.1)
				(type default)
			)
			(layer "F.Fab")
		)
		(fp_line
			(start -0.12065 -0.305054)
			(end -0.12065 -0.2794)
			(stroke
				(width 0.1)
				(type default)
			)
			(layer "F.Fab")
		)
		(pad "1" smd circle
			(at -0.40005 0 270)
			(size 0 0)
			(layers "F.Cu" "F.Mask" "F.Paste")
			(net "P3V3_NIC2")
		)
		(pad "2" smd circle
			(at 0.40005 0 270)
			(size 0 0)
			(layers "F.Cu" "F.Mask" "F.Paste")
			(net "GND")
		)
	)
	(footprint ""
		(layer "F.Cu")
		(at 24.482044 -37.025072)
		(property "Reference" "R5649"
			(at 0 0 0)
			(layer "F.SilkS")
			(hide yes)
			(effects
				(font
					(size 1.27 1.27)
				)
			)
		)
		(property "Value" ""
			(at 0 0 0)
			(layer "F.Fab")
			(effects
				(font
					(size 1.27 1.27)
				)
			)
		)
		(duplicate_pad_numbers_are_jumpers no)
		(fp_line
			(start -0.7874 -0.4064)
			(end 0.7874 -0.4064)
			(stroke
				(width 0.1524)
				(type default)
			)
			(layer "F.SilkS")
		)
		(fp_line
			(start -0.7874 0.4064)
			(end -0.7874 -0.4064)
			(stroke
				(width 0.1524)
				(type default)
			)
			(layer "F.SilkS")
		)
		(fp_line
			(start 0.7874 -0.4064)
			(end 0.7874 0.4064)
			(stroke
				(width 0.1524)
				(type default)
			)
			(layer "F.SilkS")
		)
		(fp_line
			(start 0.7874 0.4064)
			(end -0.7874 0.4064)
			(stroke
				(width 0.1524)
				(type default)
			)
			(layer "F.SilkS")
		)
		(fp_line
			(start -0.67945 -0.305054)
			(end -0.12065 -0.305054)
			(stroke
				(width 0.1)
				(type default)
			)
			(layer "F.Fab")
		)
		(fp_line
			(start -0.67945 0.3048)
			(end -0.67945 -0.305054)
			(stroke
				(width 0.1)
				(type default)
			)
			(layer "F.Fab")
		)
		(fp_line
			(start -0.12065 -0.305054)
			(end -0.12065 -0.2794)
			(stroke
				(width 0.1)
				(type default)
			)
			(layer "F.Fab")
		)
		(fp_line
			(start -0.12065 -0.2794)
			(end 0.12065 -0.2794)
			(stroke
				(width 0.1)
				(type default)
			)
			(layer "F.Fab")
		)
		(fp_line
			(start -0.12065 0.2794)
			(end -0.12065 0.3048)
			(stroke
				(width 0.1)
				(type default)
			)
			(layer "F.Fab")
		)
		(fp_line
			(start -0.12065 0.3048)
			(end -0.67945 0.3048)
			(stroke
				(width 0.1)
				(type default)
			)
			(layer "F.Fab")
		)
		(fp_line
			(start 0.120396 0.2794)
			(end -0.12065 0.2794)
			(stroke
				(width 0.1)
				(type default)
			)
			(layer "F.Fab")
		)
		(fp_line
			(start 0.120396 0.3048)
			(end 0.120396 0.2794)
			(stroke
				(width 0.1)
				(type default)
			)
			(layer "F.Fab")
		)
		(fp_line
			(start 0.12065 -0.3048)
			(end 0.67945 -0.3048)
			(stroke
				(width 0.1)
				(type default)
			)
			(layer "F.Fab")
		)
		(fp_line
			(start 0.12065 -0.2794)
			(end 0.12065 -0.3048)
			(stroke
				(width 0.1)
				(type default)
			)
			(layer "F.Fab")
		)
		(fp_line
			(start 0.67945 -0.3048)
			(end 0.67945 0.3048)
			(stroke
				(width 0.1)
				(type default)
			)
			(layer "F.Fab")
		)
		(fp_line
			(start 0.67945 0.3048)
			(end 0.120396 0.3048)
			(stroke
				(width 0.1)
				(type default)
			)
			(layer "F.Fab")
		)
		(pad "1" smd circle
			(at -0.40005 0)
			(size 0 0)
			(layers "F.Cu" "F.Mask" "F.Paste")
			(net "RST_SMB_SSD_R_N")
		)
		(pad "2" smd circle
			(at 0.40005 0)
			(size 0 0)
			(layers "F.Cu" "F.Mask" "F.Paste")
			(net "RST_SMB_SSD1_N")
		)
	)
	(footprint ""
		(layer "F.Cu")
		(at 471.057986 -527.794474 180)
		(property "Reference" "J57_12"
			(at -2.8448 -1.402334 0)
			(unlocked yes)
			(layer "B.SilkS")
			(effects
				(font
					(size 0.7874 0.5842)
					(thickness 0.1524)
				)
				(justify mirror)
			)
		)
		(property "Value" ""
			(at 0 0 180)
			(layer "F.Fab")
			(effects
				(font
					(size 1.27 1.27)
				)
			)
		)
		(duplicate_pad_numbers_are_jumpers no)
		(pad "1" thru_hole circle
			(at 0 0 180)
			(size 0.4572 0.4572)
			(drill 0.2032)
			(layers "*.Cu" "*.Mask")
			(remove_unused_layers no)
			(net "Net_2680")
			(clearance 0.127)
			(thermal_gap 0.127)
			(padstack
				(mode front_inner_back)
				(layer "Inner"
					(shape circle)
					(size 0.4572 0.4572)
					(clearance 0.127)
				)
				(layer "B.Cu"
					(shape circle)
					(size 0.508 0.508)
					(clearance 0.1016)
				)
			)
		)
	)
	(footprint ""
		(layer "F.Cu")
		(at 247.553988 -307.484272)
		(property "Reference" "PJ14"
			(at 0 0 0)
			(layer "F.SilkS")
			(hide yes)
			(effects
				(font
					(size 1.27 1.27)
				)
			)
		)
		(property "Value" ""
			(at 0 0 0)
			(layer "F.Fab")
			(effects
				(font
					(size 1.27 1.27)
				)
			)
		)
		(duplicate_pad_numbers_are_jumpers no)
		(pad "1" smd circle
			(at -0.40005 0 90)
			(size 0 0)
			(layers "F.Cu" "F.Mask" "F.Paste")
			(net "SH_P1V25_PEX2_FB_N")
		)
		(pad "2" smd rect
			(at 0.40005 0 180)
			(size 0.4572 0.508)
			(layers "F.Cu" "F.Mask" "F.Paste")
			(net "GND")
		)
		(zone
			(layer "F.Cu")
			(hatch none 0.5)
			(connect_pads
				(clearance 0)
			)
			(min_thickness 0.25)
			(keepout
				(tracks allowed)
				(vias not_allowed)
				(pads allowed)
				(copperpour not_allowed)
				(footprints allowed)
			)
			(placement
				(enabled no)
				(sheetname "")
			)
			(fill
				(thermal_gap 0.5)
				(thermal_bridge_width 0.5)
				(island_removal_mode 0)
			)
			(polygon
				(pts
					(xy 246.868188 -307.179472) (xy 248.239788 -307.179472) (xy 248.239788 -307.789072) (xy 246.868188 -307.789072)
				)
			)
		)
	)
	(footprint ""
		(layer "F.Cu")
		(at 220.36786 -54.067456)
		(property "Reference" "PR222"
			(at 0 0 0)
			(layer "F.SilkS")
			(hide yes)
			(effects
				(font
					(size 1.27 1.27)
				)
			)
		)
		(property "Value" ""
			(at 0 0 0)
			(layer "F.Fab")
			(effects
				(font
					(size 1.27 1.27)
				)
			)
		)
		(duplicate_pad_numbers_are_jumpers no)
		(fp_line
			(start -0.7874 -0.4064)
			(end 0.7874 -0.4064)
			(stroke
				(width 0.1524)
				(type default)
			)
			(layer "F.SilkS")
		)
		(fp_line
			(start -0.7874 0.4064)
			(end -0.7874 -0.4064)
			(stroke
				(width 0.1524)
				(type default)
			)
			(layer "F.SilkS")
		)
		(fp_line
			(start 0.7874 -0.4064)
			(end 0.7874 0.4064)
			(stroke
				(width 0.1524)
				(type default)
			)
			(layer "F.SilkS")
		)
		(fp_line
			(start 0.7874 0.4064)
			(end -0.7874 0.4064)
			(stroke
				(width 0.1524)
				(type default)
			)
			(layer "F.SilkS")
		)
		(fp_line
			(start -0.67945 -0.305054)
			(end -0.12065 -0.305054)
			(stroke
				(width 0.1)
				(type default)
			)
			(layer "F.Fab")
		)
		(fp_line
			(start -0.67945 0.3048)
			(end -0.67945 -0.305054)
			(stroke
				(width 0.1)
				(type default)
			)
			(layer "F.Fab")
		)
		(fp_line
			(start -0.12065 -0.305054)
			(end -0.12065 -0.2794)
			(stroke
				(width 0.1)
				(type default)
			)
			(layer "F.Fab")
		)
		(fp_line
			(start -0.12065 -0.2794)
			(end 0.12065 -0.2794)
			(stroke
				(width 0.1)
				(type default)
			)
			(layer "F.Fab")
		)
		(fp_line
			(start -0.12065 0.2794)
			(end -0.12065 0.3048)
			(stroke
				(width 0.1)
				(type default)
			)
			(layer "F.Fab")
		)
		(fp_line
			(start -0.12065 0.3048)
			(end -0.67945 0.3048)
			(stroke
				(width 0.1)
				(type default)
			)
			(layer "F.Fab")
		)
		(fp_line
			(start 0.120396 0.2794)
			(end -0.12065 0.2794)
			(stroke
				(width 0.1)
				(type default)
			)
			(layer "F.Fab")
		)
		(fp_line
			(start 0.120396 0.3048)
			(end 0.120396 0.2794)
			(stroke
				(width 0.1)
				(type default)
			)
			(layer "F.Fab")
		)
		(fp_line
			(start 0.12065 -0.3048)
			(end 0.67945 -0.3048)
			(stroke
				(width 0.1)
				(type default)
			)
			(layer "F.Fab")
		)
		(fp_line
			(start 0.12065 -0.2794)
			(end 0.12065 -0.3048)
			(stroke
				(width 0.1)
				(type default)
			)
			(layer "F.Fab")
		)
		(fp_line
			(start 0.67945 -0.3048)
			(end 0.67945 0.3048)
			(stroke
				(width 0.1)
				(type default)
			)
			(layer "F.Fab")
		)
		(fp_line
			(start 0.67945 0.3048)
			(end 0.120396 0.3048)
			(stroke
				(width 0.1)
				(type default)
			)
			(layer "F.Fab")
		)
		(pad "1" smd circle
			(at -0.40005 0)
			(size 0 0)
			(layers "F.Cu" "F.Mask" "F.Paste")
			(net "P12V_SSD7_OCP")
		)
		(pad "2" smd circle
			(at 0.40005 0)
			(size 0 0)
			(layers "F.Cu" "F.Mask" "F.Paste")
			(net "GND")
		)
	)
	(footprint ""
		(layer "F.Cu")
		(at 204.595984 -310.509412 135)
		(property "Reference" "R1305"
			(at 0 0 135)
			(layer "F.SilkS")
			(hide yes)
			(effects
				(font
					(size 1.27 1.27)
				)
			)
		)
		(property "Value" ""
			(at 0 0 135)
			(layer "F.Fab")
			(effects
				(font
					(size 1.27 1.27)
				)
			)
		)
		(duplicate_pad_numbers_are_jumpers no)
		(fp_line
			(start 0.787389 -0.406267)
			(end 0.787389 0.406267)
			(stroke
				(width 0.1524)
				(type default)
			)
			(layer "F.SilkS")
		)
		(fp_line
			(start 0.787389 0.406267)
			(end -0.787389 0.406267)
			(stroke
				(width 0.1524)
				(type default)
			)
			(layer "F.SilkS")
		)
		(fp_line
			(start -0.787389 -0.406267)
			(end 0.787389 -0.406267)
			(stroke
				(width 0.1524)
				(type default)
			)
			(layer "F.SilkS")
		)
		(fp_line
			(start -0.787389 0.406267)
			(end -0.787389 -0.406267)
			(stroke
				(width 0.1524)
				(type default)
			)
			(layer "F.SilkS")
		)
		(fp_line
			(start 0.679446 -0.30479)
			(end 0.679446 0.30479)
			(stroke
				(width 0.1)
				(type default)
			)
			(layer "F.Fab")
		)
		(fp_line
			(start 0.120515 -0.30479)
			(end 0.679446 -0.30479)
			(stroke
				(width 0.1)
				(type default)
			)
			(layer "F.Fab")
		)
		(fp_line
			(start 0.120695 -0.279466)
			(end 0.120515 -0.30479)
			(stroke
				(width 0.1)
				(type default)
			)
			(layer "F.Fab")
		)
		(fp_line
			(start 0.679446 0.30479)
			(end 0.120515 0.30479)
			(stroke
				(width 0.1)
				(type default)
			)
			(layer "F.Fab")
		)
		(fp_line
			(start -0.120695 -0.304969)
			(end -0.120695 -0.279466)
			(stroke
				(width 0.1)
				(type default)
			)
			(layer "F.Fab")
		)
		(fp_line
			(start -0.120695 -0.279466)
			(end 0.120695 -0.279466)
			(stroke
				(width 0.1)
				(type default)
			)
			(layer "F.Fab")
		)
		(fp_line
			(start 0.120335 0.279466)
			(end -0.120695 0.279466)
			(stroke
				(width 0.1)
				(type default)
			)
			(layer "F.Fab")
		)
		(fp_line
			(start 0.120515 0.30479)
			(end 0.120335 0.279466)
			(stroke
				(width 0.1)
				(type default)
			)
			(layer "F.Fab")
		)
		(fp_line
			(start -0.679446 -0.305149)
			(end -0.120695 -0.304969)
			(stroke
				(width 0.1)
				(type default)
			)
			(layer "F.Fab")
		)
		(fp_line
			(start -0.120695 0.279466)
			(end -0.120515 0.30479)
			(stroke
				(width 0.1)
				(type default)
			)
			(layer "F.Fab")
		)
		(fp_line
			(start -0.120515 0.30479)
			(end -0.679446 0.30479)
			(stroke
				(width 0.1)
				(type default)
			)
			(layer "F.Fab")
		)
		(fp_line
			(start -0.679446 0.30479)
			(end -0.679446 -0.305149)
			(stroke
				(width 0.1)
				(type default)
			)
			(layer "F.Fab")
		)
		(pad "1" smd circle
			(at -0.40005 0 135)
			(size 0 0)
			(layers "F.Cu" "F.Mask" "F.Paste")
			(net "PEX1_SPARE2")
		)
		(pad "2" smd circle
			(at 0.40005 0 135)
			(size 0 0)
			(layers "F.Cu" "F.Mask" "F.Paste")
			(net "P1V8_PEX")
		)
	)
	(footprint ""
		(layer "F.Cu")
		(at 32.31769 -115.336574 90)
		(property "Reference" "R43"
			(at 0 0 90)
			(layer "F.SilkS")
			(hide yes)
			(effects
				(font
					(size 1.27 1.27)
				)
			)
		)
		(property "Value" ""
			(at 0 0 90)
			(layer "F.Fab")
			(effects
				(font
					(size 1.27 1.27)
				)
			)
		)
		(duplicate_pad_numbers_are_jumpers no)
		(fp_line
			(start 0.7874 -0.4064)
			(end 0.7874 0.4064)
			(stroke
				(width 0.1524)
				(type default)
			)
			(layer "F.SilkS")
		)
		(fp_line
			(start -0.7874 -0.4064)
			(end 0.7874 -0.4064)
			(stroke
				(width 0.1524)
				(type default)
			)
			(layer "F.SilkS")
		)
		(fp_line
			(start 0.7874 0.4064)
			(end -0.7874 0.4064)
			(stroke
				(width 0.1524)
				(type default)
			)
			(layer "F.SilkS")
		)
		(fp_line
			(start -0.7874 0.4064)
			(end -0.7874 -0.4064)
			(stroke
				(width 0.1524)
				(type default)
			)
			(layer "F.SilkS")
		)
		(fp_line
			(start -0.12065 -0.305054)
			(end -0.12065 -0.2794)
			(stroke
				(width 0.1)
				(type default)
			)
			(layer "F.Fab")
		)
		(fp_line
			(start -0.67945 -0.305054)
			(end -0.12065 -0.305054)
			(stroke
				(width 0.1)
				(type default)
			)
			(layer "F.Fab")
		)
		(fp_line
			(start 0.67945 -0.3048)
			(end 0.67945 0.3048)
			(stroke
				(width 0.1)
				(type default)
			)
			(layer "F.Fab")
		)
		(fp_line
			(start 0.12065 -0.3048)
			(end 0.67945 -0.3048)
			(stroke
				(width 0.1)
				(type default)
			)
			(layer "F.Fab")
		)
		(fp_line
			(start 0.12065 -0.2794)
			(end 0.12065 -0.3048)
			(stroke
				(width 0.1)
				(type default)
			)
			(layer "F.Fab")
		)
		(fp_line
			(start -0.12065 -0.2794)
			(end 0.12065 -0.2794)
			(stroke
				(width 0.1)
				(type default)
			)
			(layer "F.Fab")
		)
		(fp_line
			(start 0.120396 0.2794)
			(end -0.12065 0.2794)
			(stroke
				(width 0.1)
				(type default)
			)
			(layer "F.Fab")
		)
		(fp_line
			(start -0.12065 0.2794)
			(end -0.12065 0.3048)
			(stroke
				(width 0.1)
				(type default)
			)
			(layer "F.Fab")
		)
		(fp_line
			(start 0.67945 0.3048)
			(end 0.120396 0.3048)
			(stroke
				(width 0.1)
				(type default)
			)
			(layer "F.Fab")
		)
		(fp_line
			(start 0.120396 0.3048)
			(end 0.120396 0.2794)
			(stroke
				(width 0.1)
				(type default)
			)
			(layer "F.Fab")
		)
		(fp_line
			(start -0.12065 0.3048)
			(end -0.67945 0.3048)
			(stroke
				(width 0.1)
				(type default)
			)
			(layer "F.Fab")
		)
		(fp_line
			(start -0.67945 0.3048)
			(end -0.67945 -0.305054)
			(stroke
				(width 0.1)
				(type default)
			)
			(layer "F.Fab")
		)
		(pad "1" smd circle
			(at -0.40005 0 90)
			(size 0 0)
			(layers "F.Cu" "F.Mask" "F.Paste")
			(net "PRSNT_NIC0_R_N")
		)
		(pad "2" smd circle
			(at 0.40005 0 90)
			(size 0 0)
			(layers "F.Cu" "F.Mask" "F.Paste")
			(net "PRSNT_NIC0_N")
		)
	)
	(footprint ""
		(layer "F.Cu")
		(at 240.86439 -253.983998 -90)
		(property "Reference" "C4343"
			(at 0 0 270)
			(layer "F.SilkS")
			(hide yes)
			(effects
				(font
					(size 1.27 1.27)
				)
			)
		)
		(property "Value" ""
			(at 0 0 270)
			(layer "F.Fab")
			(effects
				(font
					(size 1.27 1.27)
				)
			)
		)
		(duplicate_pad_numbers_are_jumpers no)
		(fp_line
			(start -1.524 0.762)
			(end -1.524 -0.762)
			(stroke
				(width 0.1524)
				(type default)
			)
			(layer "F.SilkS")
		)
		(fp_line
			(start 1.524 0.762)
			(end -1.524 0.762)
			(stroke
				(width 0.1524)
				(type default)
			)
			(layer "F.SilkS")
		)
		(fp_line
			(start -1.524 -0.762)
			(end 1.524 -0.762)
			(stroke
				(width 0.1524)
				(type default)
			)
			(layer "F.SilkS")
		)
		(fp_line
			(start 1.524 -0.762)
			(end 1.524 0.762)
			(stroke
				(width 0.1524)
				(type default)
			)
			(layer "F.SilkS")
		)
		(fp_line
			(start -1.1049 0.724916)
			(end 1.1049 0.724916)
			(stroke
				(width 0.1)
				(type default)
			)
			(layer "F.Fab")
		)
		(fp_line
			(start 1.1049 0.724916)
			(end 1.1049 -0.724916)
			(stroke
				(width 0.1)
				(type default)
			)
			(layer "F.Fab")
		)
		(fp_line
			(start -1.1049 -0.724916)
			(end -1.1049 0.724916)
			(stroke
				(width 0.1)
				(type default)
			)
			(layer "F.Fab")
		)
		(fp_line
			(start 1.1049 -0.724916)
			(end -1.1049 -0.724916)
			(stroke
				(width 0.1)
				(type default)
			)
			(layer "F.Fab")
		)
		(pad "1" smd rect
			(at -0.889 0 90)
			(size 1.016 1.27)
			(layers "F.Cu" "F.Mask" "F.Paste")
			(net "P1V25_SERDES_VDDPLL_PEX2_C5")
		)
		(pad "2" smd rect
			(at 0.889 0 90)
			(size 1.016 1.27)
			(layers "F.Cu" "F.Mask" "F.Paste")
			(net "GND")
		)
		(zone
			(layer "F.Cu")
			(hatch none 0.5)
			(connect_pads
				(clearance 0)
			)
			(min_thickness 0.25)
			(keepout
				(tracks not_allowed)
				(vias allowed)
				(pads allowed)
				(copperpour not_allowed)
				(footprints allowed)
			)
			(placement
				(enabled no)
				(sheetname "")
			)
			(fill
				(thermal_gap 0.5)
				(thermal_bridge_width 0.5)
				(island_removal_mode 0)
			)
			(polygon
				(pts
					(xy 241.589306 -254.314198) (xy 240.139474 -254.314198) (xy 240.139474 -253.653798) (xy 241.589306 -253.653798)
				)
			)
		)
	)
	(footprint ""
		(layer "F.Cu")
		(at 13.387578 -275.505164 180)
		(property "Reference" "U87"
			(at -0.61976 -4.369562 0)
			(unlocked yes)
			(layer "F.SilkS")
			(effects
				(font
					(size 0.7874 0.5842)
					(thickness 0.1524)
				)
			)
		)
		(property "Value" ""
			(at 0 0 180)
			(layer "F.Fab")
			(effects
				(font
					(size 1.27 1.27)
				)
			)
		)
		(duplicate_pad_numbers_are_jumpers no)
		(fp_line
			(start 1.500124 1.500124)
			(end 1.004062 1.500124)
			(stroke
				(width 0.1524)
				(type default)
			)
			(layer "F.SilkS")
		)
		(fp_line
			(start 1.500124 1.004062)
			(end 1.500124 1.500124)
			(stroke
				(width 0.1524)
				(type default)
			)
			(layer "F.SilkS")
		)
		(fp_line
			(start 1.500124 -1.500124)
			(end 1.500124 -1.004062)
			(stroke
				(width 0.1524)
				(type default)
			)
			(layer "F.SilkS")
		)
		(fp_line
			(start 1.004062 -1.500124)
			(end 1.500124 -1.500124)
			(stroke
				(width 0.1524)
				(type default)
			)
			(layer "F.SilkS")
		)
		(fp_line
			(start -1.004062 1.500124)
			(end -1.500124 1.500124)
			(stroke
				(width 0.1524)
				(type default)
			)
			(layer "F.SilkS")
		)
		(fp_line
			(start -1.500124 1.500124)
			(end -1.500124 1.004062)
			(stroke
				(width 0.1524)
				(type default)
			)
			(layer "F.SilkS")
		)
		(fp_line
			(start -1.500124 -1.004062)
			(end -1.500124 -1.500124)
			(stroke
				(width 0.1524)
				(type default)
			)
			(layer "F.SilkS")
		)
		(fp_line
			(start -1.500124 -1.500124)
			(end -1.004062 -1.500124)
			(stroke
				(width 0.1524)
				(type default)
			)
			(layer "F.SilkS")
		)
		(fp_poly
			(pts
				(xy -1.954276 -2.075942) (xy -2.672588 -1.357376) (xy -1.59512 -0.99822)
			)
			(stroke
				(width 0)
				(type default)
			)
			(fill yes)
			(layer "F.SilkS")
		)
		(fp_line
			(start 1.500124 1.500124)
			(end -1.500124 1.500124)
			(stroke
				(width 0.1)
				(type default)
			)
			(layer "F.Fab")
		)
		(fp_line
			(start 1.500124 -1.500124)
			(end 1.500124 1.500124)
			(stroke
				(width 0.1)
				(type default)
			)
			(layer "F.Fab")
		)
		(fp_line
			(start -1.500124 1.500124)
			(end -1.500124 -1.500124)
			(stroke
				(width 0.1)
				(type default)
			)
			(layer "F.Fab")
		)
		(fp_line
			(start -1.500124 -1.500124)
			(end 1.500124 -1.500124)
			(stroke
				(width 0.1)
				(type default)
			)
			(layer "F.Fab")
		)
		(fp_poly
			(pts
				(xy -2.847848 -1.258062) (xy -2.847848 -0.242062) (xy -1.831848 -0.750062)
			)
			(stroke
				(width 0)
				(type default)
			)
			(fill yes)
			(layer "F.Fab")
		)
		(pad "1" smd rect
			(at -1.400048 -0.750062 90)
			(size 0.2286 0.6096)
			(layers "F.Cu" "F.Mask" "F.Paste")
			(net "PEX0_P1V25_ADC_A1")
		)
		(pad "2" smd rect
			(at -1.400048 -0.249936 90)
			(size 0.2286 0.6096)
			(layers "F.Cu" "F.Mask" "F.Paste")
			(net "PEX0_P1V25_ADC_A0")
		)
		(pad "3" smd rect
			(at -1.400048 0.249936 90)
			(size 0.2286 0.6096)
			(layers "F.Cu" "F.Mask" "F.Paste")
			(net "PEX0_P1V25_ADC_ALERT_N")
		)
		(pad "4" smd rect
			(at -1.400048 0.750062 90)
			(size 0.2286 0.6096)
			(layers "F.Cu" "F.Mask" "F.Paste")
			(net "SMB_PEX0_P1V25_ADC_SDA")
		)
		(pad "5" smd rect
			(at -0.750062 1.400048 180)
			(size 0.2286 0.6096)
			(layers "F.Cu" "F.Mask" "F.Paste")
			(net "SMB_PEX0_P1V25_ADC_SCL")
		)
		(pad "6" smd rect
			(at -0.249936 1.400048 180)
			(size 0.2286 0.6096)
			(layers "F.Cu" "F.Mask" "F.Paste")
			(net "Net_8618")
		)
		(pad "7" smd rect
			(at 0.249936 1.400048 180)
			(size 0.2286 0.6096)
			(layers "F.Cu" "F.Mask" "F.Paste")
			(net "Net_8617")
		)
		(pad "8" smd rect
			(at 0.750062 1.400048 180)
			(size 0.2286 0.6096)
			(layers "F.Cu" "F.Mask" "F.Paste")
			(net "Net_8616")
		)
		(pad "9" smd rect
			(at 1.400048 0.750062 90)
			(size 0.2286 0.6096)
			(layers "F.Cu" "F.Mask" "F.Paste")
			(net "P3V3_AUX")
		)
		(pad "10" smd rect
			(at 1.400048 0.249936 90)
			(size 0.2286 0.6096)
			(layers "F.Cu" "F.Mask" "F.Paste")
			(net "GND")
		)
		(pad "11" smd rect
			(at 1.400048 -0.249936 90)
			(size 0.2286 0.6096)
			(layers "F.Cu" "F.Mask" "F.Paste")
			(net "P1V25_PEX0_R")
		)
		(pad "12" smd rect
			(at 1.400048 -0.750062 90)
			(size 0.2286 0.6096)
			(layers "F.Cu" "F.Mask" "F.Paste")
			(net "P12V_PEX0_P1V25_VIN_N")
		)
		(pad "13" smd rect
			(at 0.750062 -1.400048 180)
			(size 0.2286 0.6096)
			(layers "F.Cu" "F.Mask" "F.Paste")
			(net "P12V_PEX0_P1V25_VIN_P")
		)
		(pad "14" smd rect
			(at 0.249936 -1.400048 180)
			(size 0.2286 0.6096)
			(layers "F.Cu" "F.Mask" "F.Paste")
			(net "Net_8615")
		)
		(pad "15" smd rect
			(at -0.249936 -1.400048 180)
			(size 0.2286 0.6096)
			(layers "F.Cu" "F.Mask" "F.Paste")
			(net "Net_8614")
		)
		(pad "16" smd rect
			(at -0.750062 -1.400048 180)
			(size 0.2286 0.6096)
			(layers "F.Cu" "F.Mask" "F.Paste")
			(net "Net_8613")
		)
		(pad "TH" smd rect
			(at 0 0 180)
			(size 1.7018 1.7018)
			(layers "F.Cu" "F.Mask" "F.Paste")
			(net "GND")
		)
	)
	(footprint ""
		(layer "F.Cu")
		(at 11.732768 -162.003994 90)
		(property "Reference" "PC615"
			(at 0 0 90)
			(layer "F.SilkS")
			(hide yes)
			(effects
				(font
					(size 1.27 1.27)
				)
			)
		)
		(property "Value" ""
			(at 0 0 90)
			(layer "F.Fab")
			(effects
				(font
					(size 1.27 1.27)
				)
			)
		)
		(duplicate_pad_numbers_are_jumpers no)
		(fp_line
			(start 0.7874 -0.4064)
			(end 0.7874 0.4064)
			(stroke
				(width 0.1524)
				(type default)
			)
			(layer "F.SilkS")
		)
		(fp_line
			(start -0.7874 -0.4064)
			(end 0.7874 -0.4064)
			(stroke
				(width 0.1524)
				(type default)
			)
			(layer "F.SilkS")
		)
		(fp_line
			(start 0.7874 0.4064)
			(end -0.7874 0.4064)
			(stroke
				(width 0.1524)
				(type default)
			)
			(layer "F.SilkS")
		)
		(fp_line
			(start -0.7874 0.4064)
			(end -0.7874 -0.4064)
			(stroke
				(width 0.1524)
				(type default)
			)
			(layer "F.SilkS")
		)
		(fp_line
			(start -0.12065 -0.305054)
			(end -0.12065 -0.2794)
			(stroke
				(width 0.1)
				(type default)
			)
			(layer "F.Fab")
		)
		(fp_line
			(start -0.67945 -0.305054)
			(end -0.12065 -0.305054)
			(stroke
				(width 0.1)
				(type default)
			)
			(layer "F.Fab")
		)
		(fp_line
			(start 0.67945 -0.3048)
			(end 0.67945 0.3048)
			(stroke
				(width 0.1)
				(type default)
			)
			(layer "F.Fab")
		)
		(fp_line
			(start 0.12065 -0.3048)
			(end 0.67945 -0.3048)
			(stroke
				(width 0.1)
				(type default)
			)
			(layer "F.Fab")
		)
		(fp_line
			(start 0.12065 -0.2794)
			(end 0.12065 -0.3048)
			(stroke
				(width 0.1)
				(type default)
			)
			(layer "F.Fab")
		)
		(fp_line
			(start -0.12065 -0.2794)
			(end 0.12065 -0.2794)
			(stroke
				(width 0.1)
				(type default)
			)
			(layer "F.Fab")
		)
		(fp_line
			(start 0.120396 0.2794)
			(end -0.12065 0.2794)
			(stroke
				(width 0.1)
				(type default)
			)
			(layer "F.Fab")
		)
		(fp_line
			(start -0.12065 0.2794)
			(end -0.12065 0.3048)
			(stroke
				(width 0.1)
				(type default)
			)
			(layer "F.Fab")
		)
		(fp_line
			(start 0.67945 0.3048)
			(end 0.120396 0.3048)
			(stroke
				(width 0.1)
				(type default)
			)
			(layer "F.Fab")
		)
		(fp_line
			(start 0.120396 0.3048)
			(end 0.120396 0.2794)
			(stroke
				(width 0.1)
				(type default)
			)
			(layer "F.Fab")
		)
		(fp_line
			(start -0.12065 0.3048)
			(end -0.67945 0.3048)
			(stroke
				(width 0.1)
				(type default)
			)
			(layer "F.Fab")
		)
		(fp_line
			(start -0.67945 0.3048)
			(end -0.67945 -0.305054)
			(stroke
				(width 0.1)
				(type default)
			)
			(layer "F.Fab")
		)
		(pad "1" smd circle
			(at -0.40005 0 90)
			(size 0 0)
			(layers "F.Cu" "F.Mask" "F.Paste")
			(net "P12V_NIC0_CO_ISET_R")
		)
		(pad "2" smd circle
			(at 0.40005 0 90)
			(size 0 0)
			(layers "F.Cu" "F.Mask" "F.Paste")
			(net "GND")
		)
	)
	(footprint ""
		(layer "F.Cu")
		(at 118.969028 -356.244906 90)
		(property "Reference" "C347"
			(at 0 0 90)
			(layer "F.SilkS")
			(hide yes)
			(effects
				(font
					(size 1.27 1.27)
				)
			)
		)
		(property "Value" ""
			(at 0 0 90)
			(layer "F.Fab")
			(effects
				(font
					(size 1.27 1.27)
				)
			)
		)
		(duplicate_pad_numbers_are_jumpers no)
		(fp_line
			(start 0.299974 -0.150114)
			(end 0.299974 0.150114)
			(stroke
				(width 0.1)
				(type default)
			)
			(layer "F.Fab")
		)
		(fp_line
			(start -0.299974 -0.150114)
			(end 0.299974 -0.150114)
			(stroke
				(width 0.1)
				(type default)
			)
			(layer "F.Fab")
		)
		(fp_line
			(start 0.299974 0.150114)
			(end -0.299974 0.150114)
			(stroke
				(width 0.1)
				(type default)
			)
			(layer "F.Fab")
		)
		(fp_line
			(start -0.299974 0.150114)
			(end -0.299974 -0.150114)
			(stroke
				(width 0.1)
				(type default)
			)
			(layer "F.Fab")
		)
		(pad "1" smd rect
			(at -0.2667 0 90)
			(size 0.3048 0.381)
			(layers "F.Cu" "F.Mask" "F.Paste")
			(net "P5E_PEX1_STN6_TX_DN<108>")
		)
		(pad "2" smd rect
			(at 0.2667 0 90)
			(size 0.3048 0.381)
			(layers "F.Cu" "F.Mask" "F.Paste")
			(net "P5E_PEX1_STN6_TX_C_DN<108>")
		)
	)
	(footprint ""
		(layer "F.Cu")
		(at 89.713308 -104.267508 -90)
		(property "Reference" "R701"
			(at 0 0 270)
			(layer "F.SilkS")
			(hide yes)
			(effects
				(font
					(size 1.27 1.27)
				)
			)
		)
		(property "Value" ""
			(at 0 0 270)
			(layer "F.Fab")
			(effects
				(font
					(size 1.27 1.27)
				)
			)
		)
		(duplicate_pad_numbers_are_jumpers no)
		(fp_line
			(start -0.7874 0.4064)
			(end -0.7874 -0.4064)
			(stroke
				(width 0.1524)
				(type default)
			)
			(layer "F.SilkS")
		)
		(fp_line
			(start 0.7874 0.4064)
			(end -0.7874 0.4064)
			(stroke
				(width 0.1524)
				(type default)
			)
			(layer "F.SilkS")
		)
		(fp_line
			(start -0.7874 -0.4064)
			(end 0.7874 -0.4064)
			(stroke
				(width 0.1524)
				(type default)
			)
			(layer "F.SilkS")
		)
		(fp_line
			(start 0.7874 -0.4064)
			(end 0.7874 0.4064)
			(stroke
				(width 0.1524)
				(type default)
			)
			(layer "F.SilkS")
		)
		(fp_line
			(start -0.67945 0.3048)
			(end -0.67945 -0.305054)
			(stroke
				(width 0.1)
				(type default)
			)
			(layer "F.Fab")
		)
		(fp_line
			(start -0.12065 0.3048)
			(end -0.67945 0.3048)
			(stroke
				(width 0.1)
				(type default)
			)
			(layer "F.Fab")
		)
		(fp_line
			(start 0.120396 0.3048)
			(end 0.120396 0.2794)
			(stroke
				(width 0.1)
				(type default)
			)
			(layer "F.Fab")
		)
		(fp_line
			(start 0.67945 0.3048)
			(end 0.120396 0.3048)
			(stroke
				(width 0.1)
				(type default)
			)
			(layer "F.Fab")
		)
		(fp_line
			(start -0.12065 0.2794)
			(end -0.12065 0.3048)
			(stroke
				(width 0.1)
				(type default)
			)
			(layer "F.Fab")
		)
		(fp_line
			(start 0.120396 0.2794)
			(end -0.12065 0.2794)
			(stroke
				(width 0.1)
				(type default)
			)
			(layer "F.Fab")
		)
		(fp_line
			(start -0.12065 -0.2794)
			(end 0.12065 -0.2794)
			(stroke
				(width 0.1)
				(type default)
			)
			(layer "F.Fab")
		)
		(fp_line
			(start 0.12065 -0.2794)
			(end 0.12065 -0.3048)
			(stroke
				(width 0.1)
				(type default)
			)
			(layer "F.Fab")
		)
		(fp_line
			(start 0.12065 -0.3048)
			(end 0.67945 -0.3048)
			(stroke
				(width 0.1)
				(type default)
			)
			(layer "F.Fab")
		)
		(fp_line
			(start 0.67945 -0.3048)
			(end 0.67945 0.3048)
			(stroke
				(width 0.1)
				(type default)
			)
			(layer "F.Fab")
		)
		(fp_line
			(start -0.67945 -0.305054)
			(end -0.12065 -0.305054)
			(stroke
				(width 0.1)
				(type default)
			)
			(layer "F.Fab")
		)
		(fp_line
			(start -0.12065 -0.305054)
			(end -0.12065 -0.2794)
			(stroke
				(width 0.1)
				(type default)
			)
			(layer "F.Fab")
		)
		(pad "1" smd circle
			(at -0.40005 0 270)
			(size 0 0)
			(layers "F.Cu" "F.Mask" "F.Paste")
			(net "P12V_NIC1")
		)
		(pad "2" smd circle
			(at 0.40005 0 270)
			(size 0 0)
			(layers "F.Cu" "F.Mask" "F.Paste")
			(net "P12V_NIC1_VIN_N")
		)
	)
	(footprint ""
		(layer "F.Cu")
		(at 378.453396 -300.992032)
		(property "Reference" "L137"
			(at 0 0 0)
			(layer "F.SilkS")
			(hide yes)
			(effects
				(font
					(size 1.27 1.27)
				)
			)
		)
		(property "Value" ""
			(at 0 0 0)
			(layer "F.Fab")
			(effects
				(font
					(size 1.27 1.27)
				)
			)
		)
		(duplicate_pad_numbers_are_jumpers no)
		(fp_line
			(start -1.63576 -0.8128)
			(end -1.63576 0.8128)
			(stroke
				(width 0.1524)
				(type default)
			)
			(layer "F.SilkS")
		)
		(fp_line
			(start -1.63576 -0.8128)
			(end 1.63576 -0.8128)
			(stroke
				(width 0.1524)
				(type default)
			)
			(layer "F.SilkS")
		)
		(fp_line
			(start 1.63576 -0.8128)
			(end 1.63576 0.8128)
			(stroke
				(width 0.1524)
				(type default)
			)
			(layer "F.SilkS")
		)
		(fp_line
			(start 1.63576 0.8128)
			(end -1.63576 0.8128)
			(stroke
				(width 0.1524)
				(type default)
			)
			(layer "F.SilkS")
		)
		(fp_line
			(start -1.56083 -0.738632)
			(end -1.56083 0.7366)
			(stroke
				(width 0.1)
				(type default)
			)
			(layer "F.Fab")
		)
		(fp_line
			(start -1.56083 0.7366)
			(end -1.524 0.7366)
			(stroke
				(width 0.1)
				(type default)
			)
			(layer "F.Fab")
		)
		(fp_line
			(start -1.524 0.7366)
			(end 1.524 0.7366)
			(stroke
				(width 0.1)
				(type default)
			)
			(layer "F.Fab")
		)
		(fp_line
			(start 1.524 0.7366)
			(end 1.560576 0.7366)
			(stroke
				(width 0.1)
				(type default)
			)
			(layer "F.Fab")
		)
		(fp_line
			(start 1.560576 -0.738632)
			(end -1.56083 -0.738632)
			(stroke
				(width 0.1)
				(type default)
			)
			(layer "F.Fab")
		)
		(fp_line
			(start 1.560576 0.7366)
			(end 1.560576 -0.738632)
			(stroke
				(width 0.1)
				(type default)
			)
			(layer "F.Fab")
		)
		(pad "1" smd rect
			(at -0.94996 0 180)
			(size 1.1176 1.3716)
			(layers "F.Cu" "F.Mask" "F.Paste")
			(net "P1V8_PLL0_PEX3")
		)
		(pad "2" smd rect
			(at 0.94996 0 180)
			(size 1.1176 1.3716)
			(layers "F.Cu" "F.Mask" "F.Paste")
			(net "PCEPLL1_VDDA18_PEX3")
		)
	)
	(footprint ""
		(layer "F.Cu")
		(at 404.18004 -142.9512)
		(property "Reference" "R315"
			(at 0 0 0)
			(layer "F.SilkS")
			(hide yes)
			(effects
				(font
					(size 1.27 1.27)
				)
			)
		)
		(property "Value" ""
			(at 0 0 0)
			(layer "F.Fab")
			(effects
				(font
					(size 1.27 1.27)
				)
			)
		)
		(duplicate_pad_numbers_are_jumpers no)
		(fp_line
			(start -0.7874 -0.4064)
			(end 0.7874 -0.4064)
			(stroke
				(width 0.1524)
				(type default)
			)
			(layer "F.SilkS")
		)
		(fp_line
			(start -0.7874 0.4064)
			(end -0.7874 -0.4064)
			(stroke
				(width 0.1524)
				(type default)
			)
			(layer "F.SilkS")
		)
		(fp_line
			(start 0.7874 -0.4064)
			(end 0.7874 0.4064)
			(stroke
				(width 0.1524)
				(type default)
			)
			(layer "F.SilkS")
		)
		(fp_line
			(start 0.7874 0.4064)
			(end -0.7874 0.4064)
			(stroke
				(width 0.1524)
				(type default)
			)
			(layer "F.SilkS")
		)
		(fp_line
			(start -0.67945 -0.305054)
			(end -0.12065 -0.305054)
			(stroke
				(width 0.1)
				(type default)
			)
			(layer "F.Fab")
		)
		(fp_line
			(start -0.67945 0.3048)
			(end -0.67945 -0.305054)
			(stroke
				(width 0.1)
				(type default)
			)
			(layer "F.Fab")
		)
		(fp_line
			(start -0.12065 -0.305054)
			(end -0.12065 -0.2794)
			(stroke
				(width 0.1)
				(type default)
			)
			(layer "F.Fab")
		)
		(fp_line
			(start -0.12065 -0.2794)
			(end 0.12065 -0.2794)
			(stroke
				(width 0.1)
				(type default)
			)
			(layer "F.Fab")
		)
		(fp_line
			(start -0.12065 0.2794)
			(end -0.12065 0.3048)
			(stroke
				(width 0.1)
				(type default)
			)
			(layer "F.Fab")
		)
		(fp_line
			(start -0.12065 0.3048)
			(end -0.67945 0.3048)
			(stroke
				(width 0.1)
				(type default)
			)
			(layer "F.Fab")
		)
		(fp_line
			(start 0.120396 0.2794)
			(end -0.12065 0.2794)
			(stroke
				(width 0.1)
				(type default)
			)
			(layer "F.Fab")
		)
		(fp_line
			(start 0.120396 0.3048)
			(end 0.120396 0.2794)
			(stroke
				(width 0.1)
				(type default)
			)
			(layer "F.Fab")
		)
		(fp_line
			(start 0.12065 -0.3048)
			(end 0.67945 -0.3048)
			(stroke
				(width 0.1)
				(type default)
			)
			(layer "F.Fab")
		)
		(fp_line
			(start 0.12065 -0.2794)
			(end 0.12065 -0.3048)
			(stroke
				(width 0.1)
				(type default)
			)
			(layer "F.Fab")
		)
		(fp_line
			(start 0.67945 -0.3048)
			(end 0.67945 0.3048)
			(stroke
				(width 0.1)
				(type default)
			)
			(layer "F.Fab")
		)
		(fp_line
			(start 0.67945 0.3048)
			(end 0.120396 0.3048)
			(stroke
				(width 0.1)
				(type default)
			)
			(layer "F.Fab")
		)
		(pad "1" smd circle
			(at -0.40005 0)
			(size 0 0)
			(layers "F.Cu" "F.Mask" "F.Paste")
			(net "SMB_NIC6_LS_SCL")
		)
		(pad "2" smd circle
			(at 0.40005 0)
			(size 0 0)
			(layers "F.Cu" "F.Mask" "F.Paste")
			(net "P3V3_NIC6")
		)
	)
	(footprint ""
		(layer "F.Cu")
		(at 461.600042 -407.599896)
		(property "Reference" "H61"
			(at -4.831842 -5.20573 0)
			(unlocked yes)
			(layer "F.SilkS")
			(effects
				(font
					(size 0.7874 0.5842)
					(thickness 0.1524)
				)
				(justify left)
			)
		)
		(property "Value" ""
			(at 0 0 0)
			(layer "F.Fab")
			(effects
				(font
					(size 1.27 1.27)
				)
			)
		)
		(duplicate_pad_numbers_are_jumpers no)
		(pad "1" thru_hole circle
			(at 0 0)
			(size 10.0076 10.0076)
			(drill 5.6134)
			(layers "*.Cu" "*.Mask")
			(remove_unused_layers no)
			(net "GND")
			(clearance -1.9431)
		)
	)
	(footprint ""
		(layer "F.Cu")
		(at 146.538442 -250.070874 -90)
		(property "Reference" "R1269"
			(at 0 0 270)
			(layer "F.SilkS")
			(hide yes)
			(effects
				(font
					(size 1.27 1.27)
				)
			)
		)
		(property "Value" ""
			(at 0 0 270)
			(layer "F.Fab")
			(effects
				(font
					(size 1.27 1.27)
				)
			)
		)
		(duplicate_pad_numbers_are_jumpers no)
		(fp_line
			(start -0.7874 0.4064)
			(end -0.7874 -0.4064)
			(stroke
				(width 0.1524)
				(type default)
			)
			(layer "F.SilkS")
		)
		(fp_line
			(start 0.7874 0.4064)
			(end -0.7874 0.4064)
			(stroke
				(width 0.1524)
				(type default)
			)
			(layer "F.SilkS")
		)
		(fp_line
			(start -0.7874 -0.4064)
			(end 0.7874 -0.4064)
			(stroke
				(width 0.1524)
				(type default)
			)
			(layer "F.SilkS")
		)
		(fp_line
			(start 0.7874 -0.4064)
			(end 0.7874 0.4064)
			(stroke
				(width 0.1524)
				(type default)
			)
			(layer "F.SilkS")
		)
		(fp_line
			(start -0.67945 0.3048)
			(end -0.67945 -0.305054)
			(stroke
				(width 0.1)
				(type default)
			)
			(layer "F.Fab")
		)
		(fp_line
			(start -0.12065 0.3048)
			(end -0.67945 0.3048)
			(stroke
				(width 0.1)
				(type default)
			)
			(layer "F.Fab")
		)
		(fp_line
			(start 0.120396 0.3048)
			(end 0.120396 0.2794)
			(stroke
				(width 0.1)
				(type default)
			)
			(layer "F.Fab")
		)
		(fp_line
			(start 0.67945 0.3048)
			(end 0.120396 0.3048)
			(stroke
				(width 0.1)
				(type default)
			)
			(layer "F.Fab")
		)
		(fp_line
			(start -0.12065 0.2794)
			(end -0.12065 0.3048)
			(stroke
				(width 0.1)
				(type default)
			)
			(layer "F.Fab")
		)
		(fp_line
			(start 0.120396 0.2794)
			(end -0.12065 0.2794)
			(stroke
				(width 0.1)
				(type default)
			)
			(layer "F.Fab")
		)
		(fp_line
			(start -0.12065 -0.2794)
			(end 0.12065 -0.2794)
			(stroke
				(width 0.1)
				(type default)
			)
			(layer "F.Fab")
		)
		(fp_line
			(start 0.12065 -0.2794)
			(end 0.12065 -0.3048)
			(stroke
				(width 0.1)
				(type default)
			)
			(layer "F.Fab")
		)
		(fp_line
			(start 0.12065 -0.3048)
			(end 0.67945 -0.3048)
			(stroke
				(width 0.1)
				(type default)
			)
			(layer "F.Fab")
		)
		(fp_line
			(start 0.67945 -0.3048)
			(end 0.67945 0.3048)
			(stroke
				(width 0.1)
				(type default)
			)
			(layer "F.Fab")
		)
		(fp_line
			(start -0.67945 -0.305054)
			(end -0.12065 -0.305054)
			(stroke
				(width 0.1)
				(type default)
			)
			(layer "F.Fab")
		)
		(fp_line
			(start -0.12065 -0.305054)
			(end -0.12065 -0.2794)
			(stroke
				(width 0.1)
				(type default)
			)
			(layer "F.Fab")
		)
		(pad "1" smd circle
			(at -0.40005 0 270)
			(size 0 0)
			(layers "F.Cu" "F.Mask" "F.Paste")
			(net "PEX1_MODE_SEL0")
		)
		(pad "2" smd circle
			(at 0.40005 0 270)
			(size 0 0)
			(layers "F.Cu" "F.Mask" "F.Paste")
			(net "P1V8_PEX")
		)
	)
	(footprint ""
		(layer "F.Cu")
		(at 410.637482 -190.246508 -90)
		(property "Reference" "R6440"
			(at 0 0 270)
			(layer "F.SilkS")
			(hide yes)
			(effects
				(font
					(size 1.27 1.27)
				)
			)
		)
		(property "Value" ""
			(at 0 0 270)
			(layer "F.Fab")
			(effects
				(font
					(size 1.27 1.27)
				)
			)
		)
		(duplicate_pad_numbers_are_jumpers no)
		(fp_line
			(start -0.7874 0.4064)
			(end -0.7874 -0.4064)
			(stroke
				(width 0.1524)
				(type default)
			)
			(layer "F.SilkS")
		)
		(fp_line
			(start 0.7874 0.4064)
			(end -0.7874 0.4064)
			(stroke
				(width 0.1524)
				(type default)
			)
			(layer "F.SilkS")
		)
		(fp_line
			(start -0.7874 -0.4064)
			(end 0.7874 -0.4064)
			(stroke
				(width 0.1524)
				(type default)
			)
			(layer "F.SilkS")
		)
		(fp_line
			(start 0.7874 -0.4064)
			(end 0.7874 0.4064)
			(stroke
				(width 0.1524)
				(type default)
			)
			(layer "F.SilkS")
		)
		(fp_line
			(start -0.67945 0.3048)
			(end -0.67945 -0.305054)
			(stroke
				(width 0.1)
				(type default)
			)
			(layer "F.Fab")
		)
		(fp_line
			(start -0.12065 0.3048)
			(end -0.67945 0.3048)
			(stroke
				(width 0.1)
				(type default)
			)
			(layer "F.Fab")
		)
		(fp_line
			(start 0.120396 0.3048)
			(end 0.120396 0.2794)
			(stroke
				(width 0.1)
				(type default)
			)
			(layer "F.Fab")
		)
		(fp_line
			(start 0.67945 0.3048)
			(end 0.120396 0.3048)
			(stroke
				(width 0.1)
				(type default)
			)
			(layer "F.Fab")
		)
		(fp_line
			(start -0.12065 0.2794)
			(end -0.12065 0.3048)
			(stroke
				(width 0.1)
				(type default)
			)
			(layer "F.Fab")
		)
		(fp_line
			(start 0.120396 0.2794)
			(end -0.12065 0.2794)
			(stroke
				(width 0.1)
				(type default)
			)
			(layer "F.Fab")
		)
		(fp_line
			(start -0.12065 -0.2794)
			(end 0.12065 -0.2794)
			(stroke
				(width 0.1)
				(type default)
			)
			(layer "F.Fab")
		)
		(fp_line
			(start 0.12065 -0.2794)
			(end 0.12065 -0.3048)
			(stroke
				(width 0.1)
				(type default)
			)
			(layer "F.Fab")
		)
		(fp_line
			(start 0.12065 -0.3048)
			(end 0.67945 -0.3048)
			(stroke
				(width 0.1)
				(type default)
			)
			(layer "F.Fab")
		)
		(fp_line
			(start 0.67945 -0.3048)
			(end 0.67945 0.3048)
			(stroke
				(width 0.1)
				(type default)
			)
			(layer "F.Fab")
		)
		(fp_line
			(start -0.67945 -0.305054)
			(end -0.12065 -0.305054)
			(stroke
				(width 0.1)
				(type default)
			)
			(layer "F.Fab")
		)
		(fp_line
			(start -0.12065 -0.305054)
			(end -0.12065 -0.2794)
			(stroke
				(width 0.1)
				(type default)
			)
			(layer "F.Fab")
		)
		(pad "1" smd circle
			(at -0.40005 0 270)
			(size 0 0)
			(layers "F.Cu" "F.Mask" "F.Paste")
			(net "FPGA_PEX2_MODE_SEL1_ISO")
		)
		(pad "2" smd circle
			(at 0.40005 0 270)
			(size 0 0)
			(layers "F.Cu" "F.Mask" "F.Paste")
			(net "PEX2_MODE_SEL1")
		)
	)
	(footprint ""
		(layer "F.Cu")
		(at 338.074 -185.039 180)
		(property "Reference" "R4762"
			(at 0 0 180)
			(layer "F.SilkS")
			(hide yes)
			(effects
				(font
					(size 1.27 1.27)
				)
			)
		)
		(property "Value" ""
			(at 0 0 180)
			(layer "F.Fab")
			(effects
				(font
					(size 1.27 1.27)
				)
			)
		)
		(duplicate_pad_numbers_are_jumpers no)
		(fp_line
			(start 0.7874 0.4064)
			(end -0.7874 0.4064)
			(stroke
				(width 0.1524)
				(type default)
			)
			(layer "F.SilkS")
		)
		(fp_line
			(start 0.7874 -0.4064)
			(end 0.7874 0.4064)
			(stroke
				(width 0.1524)
				(type default)
			)
			(layer "F.SilkS")
		)
		(fp_line
			(start -0.7874 0.4064)
			(end -0.7874 -0.4064)
			(stroke
				(width 0.1524)
				(type default)
			)
			(layer "F.SilkS")
		)
		(fp_line
			(start -0.7874 -0.4064)
			(end 0.7874 -0.4064)
			(stroke
				(width 0.1524)
				(type default)
			)
			(layer "F.SilkS")
		)
		(fp_line
			(start 0.67945 0.3048)
			(end 0.120396 0.3048)
			(stroke
				(width 0.1)
				(type default)
			)
			(layer "F.Fab")
		)
		(fp_line
			(start 0.67945 -0.3048)
			(end 0.67945 0.3048)
			(stroke
				(width 0.1)
				(type default)
			)
			(layer "F.Fab")
		)
		(fp_line
			(start 0.12065 -0.2794)
			(end 0.12065 -0.3048)
			(stroke
				(width 0.1)
				(type default)
			)
			(layer "F.Fab")
		)
		(fp_line
			(start 0.12065 -0.3048)
			(end 0.67945 -0.3048)
			(stroke
				(width 0.1)
				(type default)
			)
			(layer "F.Fab")
		)
		(fp_line
			(start 0.120396 0.3048)
			(end 0.120396 0.2794)
			(stroke
				(width 0.1)
				(type default)
			)
			(layer "F.Fab")
		)
		(fp_line
			(start 0.120396 0.2794)
			(end -0.12065 0.2794)
			(stroke
				(width 0.1)
				(type default)
			)
			(layer "F.Fab")
		)
		(fp_line
			(start -0.12065 0.3048)
			(end -0.67945 0.3048)
			(stroke
				(width 0.1)
				(type default)
			)
			(layer "F.Fab")
		)
		(fp_line
			(start -0.12065 0.2794)
			(end -0.12065 0.3048)
			(stroke
				(width 0.1)
				(type default)
			)
			(layer "F.Fab")
		)
		(fp_line
			(start -0.12065 -0.2794)
			(end 0.12065 -0.2794)
			(stroke
				(width 0.1)
				(type default)
			)
			(layer "F.Fab")
		)
		(fp_line
			(start -0.12065 -0.305054)
			(end -0.12065 -0.2794)
			(stroke
				(width 0.1)
				(type default)
			)
			(layer "F.Fab")
		)
		(fp_line
			(start -0.67945 0.3048)
			(end -0.67945 -0.305054)
			(stroke
				(width 0.1)
				(type default)
			)
			(layer "F.Fab")
		)
		(fp_line
			(start -0.67945 -0.305054)
			(end -0.12065 -0.305054)
			(stroke
				(width 0.1)
				(type default)
			)
			(layer "F.Fab")
		)
		(pad "1" smd circle
			(at -0.40005 0 180)
			(size 0 0)
			(layers "F.Cu" "F.Mask" "F.Paste")
			(net "GND")
		)
		(pad "2" smd circle
			(at 0.40005 0 180)
			(size 0 0)
			(layers "F.Cu" "F.Mask" "F.Paste")
			(net "PCA9555_0_PEX2_A1")
		)
	)
	(footprint ""
		(layer "F.Cu")
		(at 465.766658 -534.632662 180)
		(property "Reference" "SCREW_SSD10_1"
			(at -5.6007 -1.402334 0)
			(unlocked yes)
			(layer "B.SilkS")
			(effects
				(font
					(size 0.7874 0.5842)
					(thickness 0.1524)
				)
				(justify mirror)
			)
		)
		(property "Value" ""
			(at 0 0 180)
			(layer "F.Fab")
			(effects
				(font
					(size 1.27 1.27)
				)
			)
		)
		(duplicate_pad_numbers_are_jumpers no)
		(pad "1" thru_hole circle
			(at 0 0 180)
			(size 0.4572 0.4572)
			(drill 0.2032)
			(layers "*.Cu" "*.Mask")
			(remove_unused_layers no)
			(net "Net_9154")
			(clearance 0.127)
			(thermal_gap 0.127)
			(padstack
				(mode front_inner_back)
				(layer "Inner"
					(shape circle)
					(size 0.4572 0.4572)
					(clearance 0.127)
				)
				(layer "B.Cu"
					(shape circle)
					(size 0.508 0.508)
					(clearance 0.1016)
				)
			)
		)
	)
	(footprint ""
		(layer "F.Cu")
		(at 56.901842 -32.849312 90)
		(property "Reference" "R5662"
			(at 0 0 90)
			(layer "F.SilkS")
			(hide yes)
			(effects
				(font
					(size 1.27 1.27)
				)
			)
		)
		(property "Value" ""
			(at 0 0 90)
			(layer "F.Fab")
			(effects
				(font
					(size 1.27 1.27)
				)
			)
		)
		(duplicate_pad_numbers_are_jumpers no)
		(fp_line
			(start 0.7874 -0.4064)
			(end 0.7874 0.4064)
			(stroke
				(width 0.1524)
				(type default)
			)
			(layer "F.SilkS")
		)
		(fp_line
			(start -0.7874 -0.4064)
			(end 0.7874 -0.4064)
			(stroke
				(width 0.1524)
				(type default)
			)
			(layer "F.SilkS")
		)
		(fp_line
			(start 0.7874 0.4064)
			(end -0.7874 0.4064)
			(stroke
				(width 0.1524)
				(type default)
			)
			(layer "F.SilkS")
		)
		(fp_line
			(start -0.7874 0.4064)
			(end -0.7874 -0.4064)
			(stroke
				(width 0.1524)
				(type default)
			)
			(layer "F.SilkS")
		)
		(fp_line
			(start -0.12065 -0.305054)
			(end -0.12065 -0.2794)
			(stroke
				(width 0.1)
				(type default)
			)
			(layer "F.Fab")
		)
		(fp_line
			(start -0.67945 -0.305054)
			(end -0.12065 -0.305054)
			(stroke
				(width 0.1)
				(type default)
			)
			(layer "F.Fab")
		)
		(fp_line
			(start 0.67945 -0.3048)
			(end 0.67945 0.3048)
			(stroke
				(width 0.1)
				(type default)
			)
			(layer "F.Fab")
		)
		(fp_line
			(start 0.12065 -0.3048)
			(end 0.67945 -0.3048)
			(stroke
				(width 0.1)
				(type default)
			)
			(layer "F.Fab")
		)
		(fp_line
			(start 0.12065 -0.2794)
			(end 0.12065 -0.3048)
			(stroke
				(width 0.1)
				(type default)
			)
			(layer "F.Fab")
		)
		(fp_line
			(start -0.12065 -0.2794)
			(end 0.12065 -0.2794)
			(stroke
				(width 0.1)
				(type default)
			)
			(layer "F.Fab")
		)
		(fp_line
			(start 0.120396 0.2794)
			(end -0.12065 0.2794)
			(stroke
				(width 0.1)
				(type default)
			)
			(layer "F.Fab")
		)
		(fp_line
			(start -0.12065 0.2794)
			(end -0.12065 0.3048)
			(stroke
				(width 0.1)
				(type default)
			)
			(layer "F.Fab")
		)
		(fp_line
			(start 0.67945 0.3048)
			(end 0.120396 0.3048)
			(stroke
				(width 0.1)
				(type default)
			)
			(layer "F.Fab")
		)
		(fp_line
			(start 0.120396 0.3048)
			(end 0.120396 0.2794)
			(stroke
				(width 0.1)
				(type default)
			)
			(layer "F.Fab")
		)
		(fp_line
			(start -0.12065 0.3048)
			(end -0.67945 0.3048)
			(stroke
				(width 0.1)
				(type default)
			)
			(layer "F.Fab")
		)
		(fp_line
			(start -0.67945 0.3048)
			(end -0.67945 -0.305054)
			(stroke
				(width 0.1)
				(type default)
			)
			(layer "F.Fab")
		)
		(pad "1" smd circle
			(at -0.40005 0 90)
			(size 0 0)
			(layers "F.Cu" "F.Mask" "F.Paste")
			(net "RST_SMB_SSD2_ISO_R_N")
		)
		(pad "2" smd circle
			(at 0.40005 0 90)
			(size 0 0)
			(layers "F.Cu" "F.Mask" "F.Paste")
			(net "RST_SMB_SSD2_ISO_N")
		)
	)
	(footprint ""
		(layer "F.Cu")
		(at 358.013 -218.44)
		(property "Reference" "R4087"
			(at 0 0 0)
			(layer "F.SilkS")
			(hide yes)
			(effects
				(font
					(size 1.27 1.27)
				)
			)
		)
		(property "Value" ""
			(at 0 0 0)
			(layer "F.Fab")
			(effects
				(font
					(size 1.27 1.27)
				)
			)
		)
		(duplicate_pad_numbers_are_jumpers no)
		(fp_line
			(start -0.7874 -0.4064)
			(end 0.7874 -0.4064)
			(stroke
				(width 0.1524)
				(type default)
			)
			(layer "F.SilkS")
		)
		(fp_line
			(start -0.7874 0.4064)
			(end -0.7874 -0.4064)
			(stroke
				(width 0.1524)
				(type default)
			)
			(layer "F.SilkS")
		)
		(fp_line
			(start 0.7874 -0.4064)
			(end 0.7874 0.4064)
			(stroke
				(width 0.1524)
				(type default)
			)
			(layer "F.SilkS")
		)
		(fp_line
			(start 0.7874 0.4064)
			(end -0.7874 0.4064)
			(stroke
				(width 0.1524)
				(type default)
			)
			(layer "F.SilkS")
		)
		(fp_line
			(start -0.67945 -0.305054)
			(end -0.12065 -0.305054)
			(stroke
				(width 0.1)
				(type default)
			)
			(layer "F.Fab")
		)
		(fp_line
			(start -0.67945 0.3048)
			(end -0.67945 -0.305054)
			(stroke
				(width 0.1)
				(type default)
			)
			(layer "F.Fab")
		)
		(fp_line
			(start -0.12065 -0.305054)
			(end -0.12065 -0.2794)
			(stroke
				(width 0.1)
				(type default)
			)
			(layer "F.Fab")
		)
		(fp_line
			(start -0.12065 -0.2794)
			(end 0.12065 -0.2794)
			(stroke
				(width 0.1)
				(type default)
			)
			(layer "F.Fab")
		)
		(fp_line
			(start -0.12065 0.2794)
			(end -0.12065 0.3048)
			(stroke
				(width 0.1)
				(type default)
			)
			(layer "F.Fab")
		)
		(fp_line
			(start -0.12065 0.3048)
			(end -0.67945 0.3048)
			(stroke
				(width 0.1)
				(type default)
			)
			(layer "F.Fab")
		)
		(fp_line
			(start 0.120396 0.2794)
			(end -0.12065 0.2794)
			(stroke
				(width 0.1)
				(type default)
			)
			(layer "F.Fab")
		)
		(fp_line
			(start 0.120396 0.3048)
			(end 0.120396 0.2794)
			(stroke
				(width 0.1)
				(type default)
			)
			(layer "F.Fab")
		)
		(fp_line
			(start 0.12065 -0.3048)
			(end 0.67945 -0.3048)
			(stroke
				(width 0.1)
				(type default)
			)
			(layer "F.Fab")
		)
		(fp_line
			(start 0.12065 -0.2794)
			(end 0.12065 -0.3048)
			(stroke
				(width 0.1)
				(type default)
			)
			(layer "F.Fab")
		)
		(fp_line
			(start 0.67945 -0.3048)
			(end 0.67945 0.3048)
			(stroke
				(width 0.1)
				(type default)
			)
			(layer "F.Fab")
		)
		(fp_line
			(start 0.67945 0.3048)
			(end 0.120396 0.3048)
			(stroke
				(width 0.1)
				(type default)
			)
			(layer "F.Fab")
		)
		(pad "1" smd circle
			(at -0.40005 0)
			(size 0 0)
			(layers "F.Cu" "F.Mask" "F.Paste")
			(net "NIC6_CLK_EN_N")
		)
		(pad "2" smd circle
			(at 0.40005 0)
			(size 0 0)
			(layers "F.Cu" "F.Mask" "F.Paste")
			(net "NIC6_CLK_EN_R_N")
		)
	)
	(footprint ""
		(layer "F.Cu")
		(at 112.311942 -110.515654)
		(property "Reference" "PC616"
			(at 0 0 0)
			(layer "F.SilkS")
			(hide yes)
			(effects
				(font
					(size 1.27 1.27)
				)
			)
		)
		(property "Value" ""
			(at 0 0 0)
			(layer "F.Fab")
			(effects
				(font
					(size 1.27 1.27)
				)
			)
		)
		(duplicate_pad_numbers_are_jumpers no)
		(fp_line
			(start -0.7874 -0.4064)
			(end 0.7874 -0.4064)
			(stroke
				(width 0.1524)
				(type default)
			)
			(layer "F.SilkS")
		)
		(fp_line
			(start -0.7874 0.4064)
			(end -0.7874 -0.4064)
			(stroke
				(width 0.1524)
				(type default)
			)
			(layer "F.SilkS")
		)
		(fp_line
			(start 0.7874 -0.4064)
			(end 0.7874 0.4064)
			(stroke
				(width 0.1524)
				(type default)
			)
			(layer "F.SilkS")
		)
		(fp_line
			(start 0.7874 0.4064)
			(end -0.7874 0.4064)
			(stroke
				(width 0.1524)
				(type default)
			)
			(layer "F.SilkS")
		)
		(fp_line
			(start -0.67945 -0.305054)
			(end -0.12065 -0.305054)
			(stroke
				(width 0.1)
				(type default)
			)
			(layer "F.Fab")
		)
		(fp_line
			(start -0.67945 0.3048)
			(end -0.67945 -0.305054)
			(stroke
				(width 0.1)
				(type default)
			)
			(layer "F.Fab")
		)
		(fp_line
			(start -0.12065 -0.305054)
			(end -0.12065 -0.2794)
			(stroke
				(width 0.1)
				(type default)
			)
			(layer "F.Fab")
		)
		(fp_line
			(start -0.12065 -0.2794)
			(end 0.12065 -0.2794)
			(stroke
				(width 0.1)
				(type default)
			)
			(layer "F.Fab")
		)
		(fp_line
			(start -0.12065 0.2794)
			(end -0.12065 0.3048)
			(stroke
				(width 0.1)
				(type default)
			)
			(layer "F.Fab")
		)
		(fp_line
			(start -0.12065 0.3048)
			(end -0.67945 0.3048)
			(stroke
				(width 0.1)
				(type default)
			)
			(layer "F.Fab")
		)
		(fp_line
			(start 0.120396 0.2794)
			(end -0.12065 0.2794)
			(stroke
				(width 0.1)
				(type default)
			)
			(layer "F.Fab")
		)
		(fp_line
			(start 0.120396 0.3048)
			(end 0.120396 0.2794)
			(stroke
				(width 0.1)
				(type default)
			)
			(layer "F.Fab")
		)
		(fp_line
			(start 0.12065 -0.3048)
			(end 0.67945 -0.3048)
			(stroke
				(width 0.1)
				(type default)
			)
			(layer "F.Fab")
		)
		(fp_line
			(start 0.12065 -0.2794)
			(end 0.12065 -0.3048)
			(stroke
				(width 0.1)
				(type default)
			)
			(layer "F.Fab")
		)
		(fp_line
			(start 0.67945 -0.3048)
			(end 0.67945 0.3048)
			(stroke
				(width 0.1)
				(type default)
			)
			(layer "F.Fab")
		)
		(fp_line
			(start 0.67945 0.3048)
			(end 0.120396 0.3048)
			(stroke
				(width 0.1)
				(type default)
			)
			(layer "F.Fab")
		)
		(pad "1" smd circle
			(at -0.40005 0)
			(size 0 0)
			(layers "F.Cu" "F.Mask" "F.Paste")
			(net "P12V_NIC1_CO_TIMER")
		)
		(pad "2" smd circle
			(at 0.40005 0)
			(size 0 0)
			(layers "F.Cu" "F.Mask" "F.Paste")
			(net "GND")
		)
	)
	(footprint ""
		(layer "F.Cu")
		(at 220.710506 -18.61439 90)
		(property "Reference" "U133"
			(at -1.44399 2.302764 90)
			(unlocked yes)
			(layer "F.SilkS")
			(effects
				(font
					(size 0.7874 0.5842)
					(thickness 0.1524)
				)
				(justify left)
			)
		)
		(property "Value" ""
			(at 0 0 90)
			(layer "F.Fab")
			(effects
				(font
					(size 1.27 1.27)
				)
			)
		)
		(duplicate_pad_numbers_are_jumpers no)
		(fp_line
			(start 1.463548 -1.549908)
			(end 1.463548 1.549908)
			(stroke
				(width 0.1524)
				(type default)
			)
			(layer "F.SilkS")
		)
		(fp_line
			(start 0.762 -1.549908)
			(end 1.463548 -1.549908)
			(stroke
				(width 0.1524)
				(type default)
			)
			(layer "F.SilkS")
		)
		(fp_line
			(start -0.787908 -1.549908)
			(end 0 -0.762)
			(stroke
				(width 0.1524)
				(type default)
			)
			(layer "F.SilkS")
		)
		(fp_line
			(start -1.463548 -1.549908)
			(end -0.787908 -1.549908)
			(stroke
				(width 0.1524)
				(type default)
			)
			(layer "F.SilkS")
		)
		(fp_line
			(start 0 -0.762)
			(end 0.762 -1.549908)
			(stroke
				(width 0.1524)
				(type default)
			)
			(layer "F.SilkS")
		)
		(fp_line
			(start 1.463548 1.549908)
			(end -1.463548 1.549908)
			(stroke
				(width 0.1524)
				(type default)
			)
			(layer "F.SilkS")
		)
		(fp_line
			(start -1.463548 1.549908)
			(end -1.463548 -1.549908)
			(stroke
				(width 0.1524)
				(type default)
			)
			(layer "F.SilkS")
		)
		(fp_poly
			(pts
				(xy -3.4798 -1.359916) (xy -2.86004 -1.050036) (xy -3.4798 -0.740156)
			)
			(stroke
				(width 0)
				(type default)
			)
			(fill yes)
			(layer "F.SilkS")
		)
		(fp_line
			(start 1.549908 -1.549908)
			(end 1.549908 1.549908)
			(stroke
				(width 0.1)
				(type default)
			)
			(layer "F.Fab")
		)
		(fp_line
			(start -1.549908 -1.549908)
			(end 1.549908 -1.549908)
			(stroke
				(width 0.1)
				(type default)
			)
			(layer "F.Fab")
		)
		(fp_line
			(start 1.549908 1.549908)
			(end -1.549908 1.549908)
			(stroke
				(width 0.1)
				(type default)
			)
			(layer "F.Fab")
		)
		(fp_line
			(start -1.549908 1.549908)
			(end -1.549908 -1.549908)
			(stroke
				(width 0.1)
				(type default)
			)
			(layer "F.Fab")
		)
		(fp_poly
			(pts
				(xy -3.4798 -1.359916) (xy -2.86004 -1.050036) (xy -3.4798 -0.740156)
			)
			(stroke
				(width 0)
				(type default)
			)
			(fill yes)
			(layer "F.Fab")
		)
		(pad "1" smd rect
			(at -2.175002 -1.050036 180)
			(size 0.6096 1.1684)
			(layers "F.Cu" "F.Mask" "F.Paste")
			(net "P3V3_SSD7")
		)
		(pad "2" smd rect
			(at -2.175002 -0.32512 180)
			(size 0.4318 1.1684)
			(layers "F.Cu" "F.Mask" "F.Paste")
			(net "SMB_ISO_SSD7_SCL")
		)
		(pad "3" smd rect
			(at -2.175002 0.32512 180)
			(size 0.4318 1.1684)
			(layers "F.Cu" "F.Mask" "F.Paste")
			(net "SMB_ISO_SSD7_SDA")
		)
		(pad "4" smd rect
			(at -2.175002 1.050036 180)
			(size 0.6096 1.1684)
			(layers "F.Cu" "F.Mask" "F.Paste")
			(net "GND")
		)
		(pad "5" smd rect
			(at 2.175002 1.050036 180)
			(size 0.6096 1.1684)
			(layers "F.Cu" "F.Mask" "F.Paste")
			(net "SMB_SSD7_ISO_EN")
		)
		(pad "6" smd rect
			(at 2.175002 0.32512 180)
			(size 0.4318 1.1684)
			(layers "F.Cu" "F.Mask" "F.Paste")
			(net "SMB_BIC_I2C9_MUX0_SSD7_R_SDA")
		)
		(pad "7" smd rect
			(at 2.175002 -0.32512 180)
			(size 0.4318 1.1684)
			(layers "F.Cu" "F.Mask" "F.Paste")
			(net "SMB_BIC_I2C9_MUX0_SSD7_R_SCL")
		)
		(pad "8" smd rect
			(at 2.175002 -1.050036 180)
			(size 0.6096 1.1684)
			(layers "F.Cu" "F.Mask" "F.Paste")
			(net "P3V3_AUX")
		)
	)
	(footprint ""
		(layer "F.Cu")
		(at 253.376938 -124.008134 90)
		(property "Reference" "PD53"
			(at -3.358134 2.300732 90)
			(unlocked yes)
			(layer "F.SilkS")
			(effects
				(font
					(size 0.7874 0.5842)
					(thickness 0.1524)
				)
				(justify left)
			)
		)
		(property "Value" ""
			(at 0 0 90)
			(layer "F.Fab")
			(effects
				(font
					(size 1.27 1.27)
				)
			)
		)
		(duplicate_pad_numbers_are_jumpers no)
		(fp_line
			(start 4.107942 -1.459992)
			(end 4.107942 1.459992)
			(stroke
				(width 0.1524)
				(type default)
			)
			(layer "F.SilkS")
		)
		(fp_line
			(start -3.400044 -1.459992)
			(end 4.107942 -1.459992)
			(stroke
				(width 0.1524)
				(type default)
			)
			(layer "F.SilkS")
		)
		(fp_line
			(start 4.107942 1.459992)
			(end -3.400044 1.459992)
			(stroke
				(width 0.1524)
				(type default)
			)
			(layer "F.SilkS")
		)
		(fp_line
			(start -3.400044 1.459992)
			(end -3.400044 -1.459992)
			(stroke
				(width 0.1524)
				(type default)
			)
			(layer "F.SilkS")
		)
		(fp_poly
			(pts
				(xy 4.107942 -1.459992) (xy 4.107942 1.459992) (xy 3.308096 1.459992) (xy 3.308096 -1.459992)
			)
			(stroke
				(width 0)
				(type default)
			)
			(fill yes)
			(layer "F.SilkS")
		)
		(fp_line
			(start 2.29997 -1.459992)
			(end 2.29997 1.459992)
			(stroke
				(width 0.1)
				(type default)
			)
			(layer "F.Fab")
		)
		(fp_line
			(start -2.29997 -1.459992)
			(end 2.29997 -1.459992)
			(stroke
				(width 0.1)
				(type default)
			)
			(layer "F.Fab")
		)
		(fp_line
			(start 2.29997 1.459992)
			(end -2.29997 1.459992)
			(stroke
				(width 0.1)
				(type default)
			)
			(layer "F.Fab")
		)
		(fp_line
			(start -2.29997 1.459992)
			(end -2.29997 -1.459992)
			(stroke
				(width 0.1)
				(type default)
			)
			(layer "F.Fab")
		)
		(fp_text user "+"
			(at -4.7752 -0.12065 90)
			(unlocked yes)
			(layer "F.SilkS")
			(effects
				(font
					(size 1.905 1.4224)
					(thickness 0.1524)
				)
				(justify left)
			)
		)
		(fp_text user "-"
			(at 5.4102 0.29845 270)
			(unlocked yes)
			(layer "F.SilkS")
			(effects
				(font
					(size 1.905 1.4224)
					(thickness 0.1524)
				)
				(justify left)
			)
		)
		(fp_text user "+"
			(at -4.7752 -0.12065 90)
			(unlocked yes)
			(layer "F.Fab")
			(effects
				(font
					(size 1.905 1.4224)
					(thickness 0.1524)
				)
				(justify left)
			)
		)
		(fp_text user "-"
			(at 5.4102 0.29845 270)
			(unlocked yes)
			(layer "F.Fab")
			(effects
				(font
					(size 1.905 1.4224)
					(thickness 0.1524)
				)
				(justify left)
			)
		)
		(pad "A" smd rect
			(at -1.999996 0 180)
			(size 1.7018 2.5146)
			(layers "F.Cu" "F.Mask" "F.Paste")
			(net "GND")
		)
		(pad "C" smd rect
			(at 1.999996 0 180)
			(size 1.7018 2.5146)
			(layers "F.Cu" "F.Mask" "F.Paste")
			(net "P3V3_NIC4")
		)
	)
	(footprint ""
		(layer "F.Cu")
		(at 324.913244 -356.244906 90)
		(property "Reference" "C563"
			(at 0 0 90)
			(layer "F.SilkS")
			(hide yes)
			(effects
				(font
					(size 1.27 1.27)
				)
			)
		)
		(property "Value" ""
			(at 0 0 90)
			(layer "F.Fab")
			(effects
				(font
					(size 1.27 1.27)
				)
			)
		)
		(duplicate_pad_numbers_are_jumpers no)
		(fp_line
			(start 0.299974 -0.150114)
			(end 0.299974 0.150114)
			(stroke
				(width 0.1)
				(type default)
			)
			(layer "F.Fab")
		)
		(fp_line
			(start -0.299974 -0.150114)
			(end 0.299974 -0.150114)
			(stroke
				(width 0.1)
				(type default)
			)
			(layer "F.Fab")
		)
		(fp_line
			(start 0.299974 0.150114)
			(end -0.299974 0.150114)
			(stroke
				(width 0.1)
				(type default)
			)
			(layer "F.Fab")
		)
		(fp_line
			(start -0.299974 0.150114)
			(end -0.299974 -0.150114)
			(stroke
				(width 0.1)
				(type default)
			)
			(layer "F.Fab")
		)
		(pad "1" smd rect
			(at -0.2667 0 90)
			(size 0.3048 0.381)
			(layers "F.Cu" "F.Mask" "F.Paste")
			(net "P5E_PEX2_STN6_TX_DP<105>")
		)
		(pad "2" smd rect
			(at 0.2667 0 90)
			(size 0.3048 0.381)
			(layers "F.Cu" "F.Mask" "F.Paste")
			(net "P5E_PEX2_STN6_TX_C_DP<105>")
		)
	)
	(footprint ""
		(layer "F.Cu")
		(at 31.007304 -257.439414 -90)
		(property "Reference" "C3020"
			(at 0 0 270)
			(layer "F.SilkS")
			(hide yes)
			(effects
				(font
					(size 1.27 1.27)
				)
			)
		)
		(property "Value" ""
			(at 0 0 270)
			(layer "F.Fab")
			(effects
				(font
					(size 1.27 1.27)
				)
			)
		)
		(duplicate_pad_numbers_are_jumpers no)
		(fp_line
			(start -0.299974 0.150114)
			(end -0.299974 -0.150114)
			(stroke
				(width 0.1)
				(type default)
			)
			(layer "F.Fab")
		)
		(fp_line
			(start 0.299974 0.150114)
			(end -0.299974 0.150114)
			(stroke
				(width 0.1)
				(type default)
			)
			(layer "F.Fab")
		)
		(fp_line
			(start -0.299974 -0.150114)
			(end 0.299974 -0.150114)
			(stroke
				(width 0.1)
				(type default)
			)
			(layer "F.Fab")
		)
		(fp_line
			(start 0.299974 -0.150114)
			(end 0.299974 0.150114)
			(stroke
				(width 0.1)
				(type default)
			)
			(layer "F.Fab")
		)
		(pad "1" smd rect
			(at -0.2667 0 270)
			(size 0.3048 0.381)
			(layers "F.Cu" "F.Mask" "F.Paste")
			(net "P1V8_PLL0_PEX0")
		)
		(pad "2" smd rect
			(at 0.2667 0 270)
			(size 0.3048 0.381)
			(layers "F.Cu" "F.Mask" "F.Paste")
			(net "GND")
		)
	)
	(footprint ""
		(layer "F.Cu")
		(at 384.938524 -119.198898)
		(property "Reference" "C680"
			(at 0 0 0)
			(layer "F.SilkS")
			(hide yes)
			(effects
				(font
					(size 1.27 1.27)
				)
			)
		)
		(property "Value" ""
			(at 0 0 0)
			(layer "F.Fab")
			(effects
				(font
					(size 1.27 1.27)
				)
			)
		)
		(duplicate_pad_numbers_are_jumpers no)
		(fp_line
			(start -0.299974 -0.150114)
			(end 0.299974 -0.150114)
			(stroke
				(width 0.1)
				(type default)
			)
			(layer "F.Fab")
		)
		(fp_line
			(start -0.299974 0.150114)
			(end -0.299974 -0.150114)
			(stroke
				(width 0.1)
				(type default)
			)
			(layer "F.Fab")
		)
		(fp_line
			(start 0.299974 -0.150114)
			(end 0.299974 0.150114)
			(stroke
				(width 0.1)
				(type default)
			)
			(layer "F.Fab")
		)
		(fp_line
			(start 0.299974 0.150114)
			(end -0.299974 0.150114)
			(stroke
				(width 0.1)
				(type default)
			)
			(layer "F.Fab")
		)
		(pad "1" smd rect
			(at -0.2667 0)
			(size 0.3048 0.381)
			(layers "F.Cu" "F.Mask" "F.Paste")
			(net "P5E_PEX3_STN1_TX_DP<24>")
		)
		(pad "2" smd rect
			(at 0.2667 0)
			(size 0.3048 0.381)
			(layers "F.Cu" "F.Mask" "F.Paste")
			(net "P5E_PEX3_STN1_TX_C_DP<24>")
		)
	)
	(footprint ""
		(layer "F.Cu")
		(at 376.312684 -86.5378)
		(property "Reference" "R1745"
			(at 0 0 0)
			(layer "F.SilkS")
			(hide yes)
			(effects
				(font
					(size 1.27 1.27)
				)
			)
		)
		(property "Value" ""
			(at 0 0 0)
			(layer "F.Fab")
			(effects
				(font
					(size 1.27 1.27)
				)
			)
		)
		(duplicate_pad_numbers_are_jumpers no)
		(fp_line
			(start -0.7874 -0.4064)
			(end 0.7874 -0.4064)
			(stroke
				(width 0.1524)
				(type default)
			)
			(layer "F.SilkS")
		)
		(fp_line
			(start -0.7874 0.4064)
			(end -0.7874 -0.4064)
			(stroke
				(width 0.1524)
				(type default)
			)
			(layer "F.SilkS")
		)
		(fp_line
			(start 0.7874 -0.4064)
			(end 0.7874 0.4064)
			(stroke
				(width 0.1524)
				(type default)
			)
			(layer "F.SilkS")
		)
		(fp_line
			(start 0.7874 0.4064)
			(end -0.7874 0.4064)
			(stroke
				(width 0.1524)
				(type default)
			)
			(layer "F.SilkS")
		)
		(fp_line
			(start -0.67945 -0.305054)
			(end -0.12065 -0.305054)
			(stroke
				(width 0.1)
				(type default)
			)
			(layer "F.Fab")
		)
		(fp_line
			(start -0.67945 0.3048)
			(end -0.67945 -0.305054)
			(stroke
				(width 0.1)
				(type default)
			)
			(layer "F.Fab")
		)
		(fp_line
			(start -0.12065 -0.305054)
			(end -0.12065 -0.2794)
			(stroke
				(width 0.1)
				(type default)
			)
			(layer "F.Fab")
		)
		(fp_line
			(start -0.12065 -0.2794)
			(end 0.12065 -0.2794)
			(stroke
				(width 0.1)
				(type default)
			)
			(layer "F.Fab")
		)
		(fp_line
			(start -0.12065 0.2794)
			(end -0.12065 0.3048)
			(stroke
				(width 0.1)
				(type default)
			)
			(layer "F.Fab")
		)
		(fp_line
			(start -0.12065 0.3048)
			(end -0.67945 0.3048)
			(stroke
				(width 0.1)
				(type default)
			)
			(layer "F.Fab")
		)
		(fp_line
			(start 0.120396 0.2794)
			(end -0.12065 0.2794)
			(stroke
				(width 0.1)
				(type default)
			)
			(layer "F.Fab")
		)
		(fp_line
			(start 0.120396 0.3048)
			(end 0.120396 0.2794)
			(stroke
				(width 0.1)
				(type default)
			)
			(layer "F.Fab")
		)
		(fp_line
			(start 0.12065 -0.3048)
			(end 0.67945 -0.3048)
			(stroke
				(width 0.1)
				(type default)
			)
			(layer "F.Fab")
		)
		(fp_line
			(start 0.12065 -0.2794)
			(end 0.12065 -0.3048)
			(stroke
				(width 0.1)
				(type default)
			)
			(layer "F.Fab")
		)
		(fp_line
			(start 0.67945 -0.3048)
			(end 0.67945 0.3048)
			(stroke
				(width 0.1)
				(type default)
			)
			(layer "F.Fab")
		)
		(fp_line
			(start 0.67945 0.3048)
			(end 0.120396 0.3048)
			(stroke
				(width 0.1)
				(type default)
			)
			(layer "F.Fab")
		)
		(pad "1" smd circle
			(at -0.40005 0)
			(size 0 0)
			(layers "F.Cu" "F.Mask" "F.Paste")
			(net "P3V3_AUX")
		)
		(pad "2" smd circle
			(at 0.40005 0)
			(size 0 0)
			(layers "F.Cu" "F.Mask" "F.Paste")
			(net "SMB_BIC_I2C6_MUX_PEX_ADC_R_SDA")
		)
	)
	(footprint ""
		(layer "F.Cu")
		(at 219.711524 -71.458074 -90)
		(property "Reference" "PD104"
			(at 4.300474 -2.692146 90)
			(unlocked yes)
			(layer "F.SilkS")
			(effects
				(font
					(size 0.7874 0.5842)
					(thickness 0.1524)
				)
				(justify left)
			)
		)
		(property "Value" ""
			(at 0 0 270)
			(layer "F.Fab")
			(effects
				(font
					(size 1.27 1.27)
				)
			)
		)
		(duplicate_pad_numbers_are_jumpers no)
		(fp_line
			(start -3.656584 1.970024)
			(end 4.240784 1.970024)
			(stroke
				(width 0.1524)
				(type default)
			)
			(layer "F.SilkS")
		)
		(fp_line
			(start 4.240784 1.970024)
			(end 4.240784 -1.970024)
			(stroke
				(width 0.1524)
				(type default)
			)
			(layer "F.SilkS")
		)
		(fp_line
			(start -3.656584 -1.970024)
			(end -3.656584 1.970024)
			(stroke
				(width 0.1524)
				(type default)
			)
			(layer "F.SilkS")
		)
		(fp_line
			(start 4.240784 -1.970024)
			(end -3.656584 -1.970024)
			(stroke
				(width 0.1524)
				(type default)
			)
			(layer "F.SilkS")
		)
		(fp_poly
			(pts
				(xy 3.580384 1.970024) (xy 3.580384 -1.970024) (xy 4.240784 -1.970024) (xy 4.240784 1.970024)
			)
			(stroke
				(width 0)
				(type default)
			)
			(fill yes)
			(layer "F.SilkS")
		)
		(fp_line
			(start -2.3749 1.970024)
			(end 2.3749 1.970024)
			(stroke
				(width 0.1)
				(type default)
			)
			(layer "F.Fab")
		)
		(fp_line
			(start 2.3749 1.970024)
			(end 2.3749 -1.970024)
			(stroke
				(width 0.1)
				(type default)
			)
			(layer "F.Fab")
		)
		(fp_line
			(start -2.3749 -1.970024)
			(end -2.3749 1.970024)
			(stroke
				(width 0.1)
				(type default)
			)
			(layer "F.Fab")
		)
		(fp_line
			(start 2.3749 -1.970024)
			(end -2.3749 -1.970024)
			(stroke
				(width 0.1)
				(type default)
			)
			(layer "F.Fab")
		)
		(fp_text user "+"
			(at -4.9784 -0.23495 270)
			(unlocked yes)
			(layer "F.Fab")
			(effects
				(font
					(size 1.905 1.4224)
					(thickness 0.1524)
				)
				(justify left)
			)
		)
		(fp_text user "-"
			(at 4.1656 -0.23495 270)
			(unlocked yes)
			(layer "F.Fab")
			(effects
				(font
					(size 1.905 1.4224)
					(thickness 0.1524)
				)
				(justify left)
			)
		)
		(pad "A" smd rect
			(at -2.450084 0 270)
			(size 2.159 2.2606)
			(layers "F.Cu" "F.Mask" "F.Paste")
			(net "GND")
		)
		(pad "C" smd rect
			(at 2.450084 0 270)
			(size 2.159 2.2606)
			(layers "F.Cu" "F.Mask" "F.Paste")
			(net "P12V_AUX")
		)
	)
	(footprint ""
		(layer "F.Cu")
		(at 405.247348 -36.686998 90)
		(property "Reference" "C3674"
			(at 0 0 90)
			(layer "F.SilkS")
			(hide yes)
			(effects
				(font
					(size 1.27 1.27)
				)
			)
		)
		(property "Value" ""
			(at 0 0 90)
			(layer "F.Fab")
			(effects
				(font
					(size 1.27 1.27)
				)
			)
		)
		(duplicate_pad_numbers_are_jumpers no)
		(fp_line
			(start 0.7874 -0.4064)
			(end 0.7874 0.4064)
			(stroke
				(width 0.1524)
				(type default)
			)
			(layer "F.SilkS")
		)
		(fp_line
			(start -0.7874 -0.4064)
			(end 0.7874 -0.4064)
			(stroke
				(width 0.1524)
				(type default)
			)
			(layer "F.SilkS")
		)
		(fp_line
			(start 0.7874 0.4064)
			(end -0.7874 0.4064)
			(stroke
				(width 0.1524)
				(type default)
			)
			(layer "F.SilkS")
		)
		(fp_line
			(start -0.7874 0.4064)
			(end -0.7874 -0.4064)
			(stroke
				(width 0.1524)
				(type default)
			)
			(layer "F.SilkS")
		)
		(fp_line
			(start -0.12065 -0.305054)
			(end -0.12065 -0.2794)
			(stroke
				(width 0.1)
				(type default)
			)
			(layer "F.Fab")
		)
		(fp_line
			(start -0.67945 -0.305054)
			(end -0.12065 -0.305054)
			(stroke
				(width 0.1)
				(type default)
			)
			(layer "F.Fab")
		)
		(fp_line
			(start 0.67945 -0.3048)
			(end 0.67945 0.3048)
			(stroke
				(width 0.1)
				(type default)
			)
			(layer "F.Fab")
		)
		(fp_line
			(start 0.12065 -0.3048)
			(end 0.67945 -0.3048)
			(stroke
				(width 0.1)
				(type default)
			)
			(layer "F.Fab")
		)
		(fp_line
			(start 0.12065 -0.2794)
			(end 0.12065 -0.3048)
			(stroke
				(width 0.1)
				(type default)
			)
			(layer "F.Fab")
		)
		(fp_line
			(start -0.12065 -0.2794)
			(end 0.12065 -0.2794)
			(stroke
				(width 0.1)
				(type default)
			)
			(layer "F.Fab")
		)
		(fp_line
			(start 0.120396 0.2794)
			(end -0.12065 0.2794)
			(stroke
				(width 0.1)
				(type default)
			)
			(layer "F.Fab")
		)
		(fp_line
			(start -0.12065 0.2794)
			(end -0.12065 0.3048)
			(stroke
				(width 0.1)
				(type default)
			)
			(layer "F.Fab")
		)
		(fp_line
			(start 0.67945 0.3048)
			(end 0.120396 0.3048)
			(stroke
				(width 0.1)
				(type default)
			)
			(layer "F.Fab")
		)
		(fp_line
			(start 0.120396 0.3048)
			(end 0.120396 0.2794)
			(stroke
				(width 0.1)
				(type default)
			)
			(layer "F.Fab")
		)
		(fp_line
			(start -0.12065 0.3048)
			(end -0.67945 0.3048)
			(stroke
				(width 0.1)
				(type default)
			)
			(layer "F.Fab")
		)
		(fp_line
			(start -0.67945 0.3048)
			(end -0.67945 -0.305054)
			(stroke
				(width 0.1)
				(type default)
			)
			(layer "F.Fab")
		)
		(pad "1" smd circle
			(at -0.40005 0 90)
			(size 0 0)
			(layers "F.Cu" "F.Mask" "F.Paste")
			(net "P3V3_AUX")
		)
		(pad "2" smd circle
			(at 0.40005 0 90)
			(size 0 0)
			(layers "F.Cu" "F.Mask" "F.Paste")
			(net "GND")
		)
	)
	(footprint ""
		(layer "F.Cu")
		(at 26.930096 -290.805108 -90)
		(property "Reference" "C3063"
			(at 0 0 270)
			(layer "F.SilkS")
			(hide yes)
			(effects
				(font
					(size 1.27 1.27)
				)
			)
		)
		(property "Value" ""
			(at 0 0 270)
			(layer "F.Fab")
			(effects
				(font
					(size 1.27 1.27)
				)
			)
		)
		(duplicate_pad_numbers_are_jumpers no)
		(fp_line
			(start -1.2954 0.5842)
			(end -1.2954 -0.5842)
			(stroke
				(width 0.1524)
				(type default)
			)
			(layer "F.SilkS")
		)
		(fp_line
			(start 1.2954 0.5842)
			(end -1.2954 0.5842)
			(stroke
				(width 0.1524)
				(type default)
			)
			(layer "F.SilkS")
		)
		(fp_line
			(start -1.2954 -0.5842)
			(end 1.2954 -0.5842)
			(stroke
				(width 0.1524)
				(type default)
			)
			(layer "F.SilkS")
		)
		(fp_line
			(start 1.2954 -0.5842)
			(end 1.2954 0.5842)
			(stroke
				(width 0.1524)
				(type default)
			)
			(layer "F.SilkS")
		)
		(fp_line
			(start -0.8636 0.4572)
			(end -0.8636 0.4064)
			(stroke
				(width 0.1)
				(type default)
			)
			(layer "F.Fab")
		)
		(fp_line
			(start 0.8636 0.4572)
			(end -0.8636 0.4572)
			(stroke
				(width 0.1)
				(type default)
			)
			(layer "F.Fab")
		)
		(fp_line
			(start -1.1938 0.4064)
			(end -1.1938 -0.4064)
			(stroke
				(width 0.1)
				(type default)
			)
			(layer "F.Fab")
		)
		(fp_line
			(start -0.8636 0.4064)
			(end -1.1938 0.4064)
			(stroke
				(width 0.1)
				(type default)
			)
			(layer "F.Fab")
		)
		(fp_line
			(start 0.8636 0.4064)
			(end 0.8636 0.4572)
			(stroke
				(width 0.1)
				(type default)
			)
			(layer "F.Fab")
		)
		(fp_line
			(start 1.1938 0.4064)
			(end 0.8636 0.4064)
			(stroke
				(width 0.1)
				(type default)
			)
			(layer "F.Fab")
		)
		(fp_line
			(start -1.1938 -0.4064)
			(end -0.8636 -0.4064)
			(stroke
				(width 0.1)
				(type default)
			)
			(layer "F.Fab")
		)
		(fp_line
			(start -0.8636 -0.4064)
			(end -0.8636 -0.4572)
			(stroke
				(width 0.1)
				(type default)
			)
			(layer "F.Fab")
		)
		(fp_line
			(start 0.8636 -0.4064)
			(end 1.1938 -0.4064)
			(stroke
				(width 0.1)
				(type default)
			)
			(layer "F.Fab")
		)
		(fp_line
			(start 1.1938 -0.4064)
			(end 1.1938 0.4064)
			(stroke
				(width 0.1)
				(type default)
			)
			(layer "F.Fab")
		)
		(fp_line
			(start -0.8636 -0.4572)
			(end 0.8636 -0.4572)
			(stroke
				(width 0.1)
				(type default)
			)
			(layer "F.Fab")
		)
		(fp_line
			(start 0.8636 -0.4572)
			(end 0.8636 -0.4064)
			(stroke
				(width 0.1)
				(type default)
			)
			(layer "F.Fab")
		)
		(pad "1" smd rect
			(at -0.7366 0 180)
			(size 0.7112 0.8128)
			(layers "F.Cu" "F.Mask" "F.Paste")
			(net "P1V8_PLL0_PEX0")
		)
		(pad "2" smd rect
			(at 0.7366 0 180)
			(size 0.7112 0.8128)
			(layers "F.Cu" "F.Mask" "F.Paste")
			(net "GND")
		)
	)
	(footprint ""
		(layer "F.Cu")
		(at 378.852684 -89.9668 180)
		(property "Reference" "R1759"
			(at 0 0 180)
			(layer "F.SilkS")
			(hide yes)
			(effects
				(font
					(size 1.27 1.27)
				)
			)
		)
		(property "Value" ""
			(at 0 0 180)
			(layer "F.Fab")
			(effects
				(font
					(size 1.27 1.27)
				)
			)
		)
		(duplicate_pad_numbers_are_jumpers no)
		(fp_line
			(start 0.7874 0.4064)
			(end -0.7874 0.4064)
			(stroke
				(width 0.1524)
				(type default)
			)
			(layer "F.SilkS")
		)
		(fp_line
			(start 0.7874 -0.4064)
			(end 0.7874 0.4064)
			(stroke
				(width 0.1524)
				(type default)
			)
			(layer "F.SilkS")
		)
		(fp_line
			(start -0.7874 0.4064)
			(end -0.7874 -0.4064)
			(stroke
				(width 0.1524)
				(type default)
			)
			(layer "F.SilkS")
		)
		(fp_line
			(start -0.7874 -0.4064)
			(end 0.7874 -0.4064)
			(stroke
				(width 0.1524)
				(type default)
			)
			(layer "F.SilkS")
		)
		(fp_line
			(start 0.67945 0.3048)
			(end 0.120396 0.3048)
			(stroke
				(width 0.1)
				(type default)
			)
			(layer "F.Fab")
		)
		(fp_line
			(start 0.67945 -0.3048)
			(end 0.67945 0.3048)
			(stroke
				(width 0.1)
				(type default)
			)
			(layer "F.Fab")
		)
		(fp_line
			(start 0.12065 -0.2794)
			(end 0.12065 -0.3048)
			(stroke
				(width 0.1)
				(type default)
			)
			(layer "F.Fab")
		)
		(fp_line
			(start 0.12065 -0.3048)
			(end 0.67945 -0.3048)
			(stroke
				(width 0.1)
				(type default)
			)
			(layer "F.Fab")
		)
		(fp_line
			(start 0.120396 0.3048)
			(end 0.120396 0.2794)
			(stroke
				(width 0.1)
				(type default)
			)
			(layer "F.Fab")
		)
		(fp_line
			(start 0.120396 0.2794)
			(end -0.12065 0.2794)
			(stroke
				(width 0.1)
				(type default)
			)
			(layer "F.Fab")
		)
		(fp_line
			(start -0.12065 0.3048)
			(end -0.67945 0.3048)
			(stroke
				(width 0.1)
				(type default)
			)
			(layer "F.Fab")
		)
		(fp_line
			(start -0.12065 0.2794)
			(end -0.12065 0.3048)
			(stroke
				(width 0.1)
				(type default)
			)
			(layer "F.Fab")
		)
		(fp_line
			(start -0.12065 -0.2794)
			(end 0.12065 -0.2794)
			(stroke
				(width 0.1)
				(type default)
			)
			(layer "F.Fab")
		)
		(fp_line
			(start -0.12065 -0.305054)
			(end -0.12065 -0.2794)
			(stroke
				(width 0.1)
				(type default)
			)
			(layer "F.Fab")
		)
		(fp_line
			(start -0.67945 0.3048)
			(end -0.67945 -0.305054)
			(stroke
				(width 0.1)
				(type default)
			)
			(layer "F.Fab")
		)
		(fp_line
			(start -0.67945 -0.305054)
			(end -0.12065 -0.305054)
			(stroke
				(width 0.1)
				(type default)
			)
			(layer "F.Fab")
		)
		(pad "1" smd circle
			(at -0.40005 0 180)
			(size 0 0)
			(layers "F.Cu" "F.Mask" "F.Paste")
			(net "BIC_I2C6_MUX_A1")
		)
		(pad "2" smd circle
			(at 0.40005 0 180)
			(size 0 0)
			(layers "F.Cu" "F.Mask" "F.Paste")
			(net "GND")
		)
	)
	(footprint ""
		(layer "F.Cu")
		(at 376.809 -190.627)
		(property "Reference" "R4656"
			(at 0 0 0)
			(layer "F.SilkS")
			(hide yes)
			(effects
				(font
					(size 1.27 1.27)
				)
			)
		)
		(property "Value" ""
			(at 0 0 0)
			(layer "F.Fab")
			(effects
				(font
					(size 1.27 1.27)
				)
			)
		)
		(duplicate_pad_numbers_are_jumpers no)
		(fp_line
			(start -0.7874 -0.4064)
			(end 0.7874 -0.4064)
			(stroke
				(width 0.1524)
				(type default)
			)
			(layer "F.SilkS")
		)
		(fp_line
			(start -0.7874 0.4064)
			(end -0.7874 -0.4064)
			(stroke
				(width 0.1524)
				(type default)
			)
			(layer "F.SilkS")
		)
		(fp_line
			(start 0.7874 -0.4064)
			(end 0.7874 0.4064)
			(stroke
				(width 0.1524)
				(type default)
			)
			(layer "F.SilkS")
		)
		(fp_line
			(start 0.7874 0.4064)
			(end -0.7874 0.4064)
			(stroke
				(width 0.1524)
				(type default)
			)
			(layer "F.SilkS")
		)
		(fp_line
			(start -0.67945 -0.305054)
			(end -0.12065 -0.305054)
			(stroke
				(width 0.1)
				(type default)
			)
			(layer "F.Fab")
		)
		(fp_line
			(start -0.67945 0.3048)
			(end -0.67945 -0.305054)
			(stroke
				(width 0.1)
				(type default)
			)
			(layer "F.Fab")
		)
		(fp_line
			(start -0.12065 -0.305054)
			(end -0.12065 -0.2794)
			(stroke
				(width 0.1)
				(type default)
			)
			(layer "F.Fab")
		)
		(fp_line
			(start -0.12065 -0.2794)
			(end 0.12065 -0.2794)
			(stroke
				(width 0.1)
				(type default)
			)
			(layer "F.Fab")
		)
		(fp_line
			(start -0.12065 0.2794)
			(end -0.12065 0.3048)
			(stroke
				(width 0.1)
				(type default)
			)
			(layer "F.Fab")
		)
		(fp_line
			(start -0.12065 0.3048)
			(end -0.67945 0.3048)
			(stroke
				(width 0.1)
				(type default)
			)
			(layer "F.Fab")
		)
		(fp_line
			(start 0.120396 0.2794)
			(end -0.12065 0.2794)
			(stroke
				(width 0.1)
				(type default)
			)
			(layer "F.Fab")
		)
		(fp_line
			(start 0.120396 0.3048)
			(end 0.120396 0.2794)
			(stroke
				(width 0.1)
				(type default)
			)
			(layer "F.Fab")
		)
		(fp_line
			(start 0.12065 -0.3048)
			(end 0.67945 -0.3048)
			(stroke
				(width 0.1)
				(type default)
			)
			(layer "F.Fab")
		)
		(fp_line
			(start 0.12065 -0.2794)
			(end 0.12065 -0.3048)
			(stroke
				(width 0.1)
				(type default)
			)
			(layer "F.Fab")
		)
		(fp_line
			(start 0.67945 -0.3048)
			(end 0.67945 0.3048)
			(stroke
				(width 0.1)
				(type default)
			)
			(layer "F.Fab")
		)
		(fp_line
			(start 0.67945 0.3048)
			(end 0.120396 0.3048)
			(stroke
				(width 0.1)
				(type default)
			)
			(layer "F.Fab")
		)
		(pad "1" smd circle
			(at -0.40005 0)
			(size 0 0)
			(layers "F.Cu" "F.Mask" "F.Paste")
			(net "GND")
		)
		(pad "2" smd circle
			(at 0.40005 0)
			(size 0 0)
			(layers "F.Cu" "F.Mask" "F.Paste")
			(net "PCA9555_1_PEX0_A0")
		)
	)
	(footprint ""
		(layer "F.Cu")
		(at 32.709104 -26.03373)
		(property "Reference" "R4054"
			(at 0 0 0)
			(layer "F.SilkS")
			(hide yes)
			(effects
				(font
					(size 1.27 1.27)
				)
			)
		)
		(property "Value" ""
			(at 0 0 0)
			(layer "F.Fab")
			(effects
				(font
					(size 1.27 1.27)
				)
			)
		)
		(duplicate_pad_numbers_are_jumpers no)
		(fp_line
			(start -0.7874 -0.4064)
			(end 0.7874 -0.4064)
			(stroke
				(width 0.1524)
				(type default)
			)
			(layer "F.SilkS")
		)
		(fp_line
			(start -0.7874 0.4064)
			(end -0.7874 -0.4064)
			(stroke
				(width 0.1524)
				(type default)
			)
			(layer "F.SilkS")
		)
		(fp_line
			(start 0.7874 -0.4064)
			(end 0.7874 0.4064)
			(stroke
				(width 0.1524)
				(type default)
			)
			(layer "F.SilkS")
		)
		(fp_line
			(start 0.7874 0.4064)
			(end -0.7874 0.4064)
			(stroke
				(width 0.1524)
				(type default)
			)
			(layer "F.SilkS")
		)
		(fp_line
			(start -0.67945 -0.305054)
			(end -0.12065 -0.305054)
			(stroke
				(width 0.1)
				(type default)
			)
			(layer "F.Fab")
		)
		(fp_line
			(start -0.67945 0.3048)
			(end -0.67945 -0.305054)
			(stroke
				(width 0.1)
				(type default)
			)
			(layer "F.Fab")
		)
		(fp_line
			(start -0.12065 -0.305054)
			(end -0.12065 -0.2794)
			(stroke
				(width 0.1)
				(type default)
			)
			(layer "F.Fab")
		)
		(fp_line
			(start -0.12065 -0.2794)
			(end 0.12065 -0.2794)
			(stroke
				(width 0.1)
				(type default)
			)
			(layer "F.Fab")
		)
		(fp_line
			(start -0.12065 0.2794)
			(end -0.12065 0.3048)
			(stroke
				(width 0.1)
				(type default)
			)
			(layer "F.Fab")
		)
		(fp_line
			(start -0.12065 0.3048)
			(end -0.67945 0.3048)
			(stroke
				(width 0.1)
				(type default)
			)
			(layer "F.Fab")
		)
		(fp_line
			(start 0.120396 0.2794)
			(end -0.12065 0.2794)
			(stroke
				(width 0.1)
				(type default)
			)
			(layer "F.Fab")
		)
		(fp_line
			(start 0.120396 0.3048)
			(end 0.120396 0.2794)
			(stroke
				(width 0.1)
				(type default)
			)
			(layer "F.Fab")
		)
		(fp_line
			(start 0.12065 -0.3048)
			(end 0.67945 -0.3048)
			(stroke
				(width 0.1)
				(type default)
			)
			(layer "F.Fab")
		)
		(fp_line
			(start 0.12065 -0.2794)
			(end 0.12065 -0.3048)
			(stroke
				(width 0.1)
				(type default)
			)
			(layer "F.Fab")
		)
		(fp_line
			(start 0.67945 -0.3048)
			(end 0.67945 0.3048)
			(stroke
				(width 0.1)
				(type default)
			)
			(layer "F.Fab")
		)
		(fp_line
			(start 0.67945 0.3048)
			(end 0.120396 0.3048)
			(stroke
				(width 0.1)
				(type default)
			)
			(layer "F.Fab")
		)
		(pad "1" smd circle
			(at -0.40005 0)
			(size 0 0)
			(layers "F.Cu" "F.Mask" "F.Paste")
			(net "P3V3_AUX")
		)
		(pad "2" smd circle
			(at 0.40005 0)
			(size 0 0)
			(layers "F.Cu" "F.Mask" "F.Paste")
			(net "PRSNT_SSD1_R_N")
		)
	)
	(footprint ""
		(layer "F.Cu")
		(at 9.1059 -394.13942 -90)
		(property "Reference" "R6739"
			(at 0 0 270)
			(layer "F.SilkS")
			(hide yes)
			(effects
				(font
					(size 1.27 1.27)
				)
			)
		)
		(property "Value" ""
			(at 0 0 270)
			(layer "F.Fab")
			(effects
				(font
					(size 1.27 1.27)
				)
			)
		)
		(duplicate_pad_numbers_are_jumpers no)
		(fp_line
			(start -0.7874 0.4064)
			(end -0.7874 -0.4064)
			(stroke
				(width 0.1524)
				(type default)
			)
			(layer "F.SilkS")
		)
		(fp_line
			(start 0.7874 0.4064)
			(end -0.7874 0.4064)
			(stroke
				(width 0.1524)
				(type default)
			)
			(layer "F.SilkS")
		)
		(fp_line
			(start -0.7874 -0.4064)
			(end 0.7874 -0.4064)
			(stroke
				(width 0.1524)
				(type default)
			)
			(layer "F.SilkS")
		)
		(fp_line
			(start 0.7874 -0.4064)
			(end 0.7874 0.4064)
			(stroke
				(width 0.1524)
				(type default)
			)
			(layer "F.SilkS")
		)
		(fp_line
			(start -0.67945 0.3048)
			(end -0.67945 -0.305054)
			(stroke
				(width 0.1)
				(type default)
			)
			(layer "F.Fab")
		)
		(fp_line
			(start -0.12065 0.3048)
			(end -0.67945 0.3048)
			(stroke
				(width 0.1)
				(type default)
			)
			(layer "F.Fab")
		)
		(fp_line
			(start 0.120396 0.3048)
			(end 0.120396 0.2794)
			(stroke
				(width 0.1)
				(type default)
			)
			(layer "F.Fab")
		)
		(fp_line
			(start 0.67945 0.3048)
			(end 0.120396 0.3048)
			(stroke
				(width 0.1)
				(type default)
			)
			(layer "F.Fab")
		)
		(fp_line
			(start -0.12065 0.2794)
			(end -0.12065 0.3048)
			(stroke
				(width 0.1)
				(type default)
			)
			(layer "F.Fab")
		)
		(fp_line
			(start 0.120396 0.2794)
			(end -0.12065 0.2794)
			(stroke
				(width 0.1)
				(type default)
			)
			(layer "F.Fab")
		)
		(fp_line
			(start -0.12065 -0.2794)
			(end 0.12065 -0.2794)
			(stroke
				(width 0.1)
				(type default)
			)
			(layer "F.Fab")
		)
		(fp_line
			(start 0.12065 -0.2794)
			(end 0.12065 -0.3048)
			(stroke
				(width 0.1)
				(type default)
			)
			(layer "F.Fab")
		)
		(fp_line
			(start 0.12065 -0.3048)
			(end 0.67945 -0.3048)
			(stroke
				(width 0.1)
				(type default)
			)
			(layer "F.Fab")
		)
		(fp_line
			(start 0.67945 -0.3048)
			(end 0.67945 0.3048)
			(stroke
				(width 0.1)
				(type default)
			)
			(layer "F.Fab")
		)
		(fp_line
			(start -0.67945 -0.305054)
			(end -0.12065 -0.305054)
			(stroke
				(width 0.1)
				(type default)
			)
			(layer "F.Fab")
		)
		(fp_line
			(start -0.12065 -0.305054)
			(end -0.12065 -0.2794)
			(stroke
				(width 0.1)
				(type default)
			)
			(layer "F.Fab")
		)
		(pad "1" smd circle
			(at -0.40005 0 270)
			(size 0 0)
			(layers "F.Cu" "F.Mask" "F.Paste")
			(net "GND")
		)
		(pad "2" smd circle
			(at 0.40005 0 270)
			(size 0 0)
			(layers "F.Cu" "F.Mask" "F.Paste")
			(net "BIC_USB_8042_HUB_HS_SUSPEND")
		)
	)
	(footprint ""
		(layer "F.Cu")
		(at 33.040066 -259.834634 180)
		(property "Reference" "C3048"
			(at 0 0 180)
			(layer "F.SilkS")
			(hide yes)
			(effects
				(font
					(size 1.27 1.27)
				)
			)
		)
		(property "Value" ""
			(at 0 0 180)
			(layer "F.Fab")
			(effects
				(font
					(size 1.27 1.27)
				)
			)
		)
		(duplicate_pad_numbers_are_jumpers no)
		(fp_line
			(start 1.2954 0.5842)
			(end -1.2954 0.5842)
			(stroke
				(width 0.1524)
				(type default)
			)
			(layer "F.SilkS")
		)
		(fp_line
			(start 1.2954 -0.5842)
			(end 1.2954 0.5842)
			(stroke
				(width 0.1524)
				(type default)
			)
			(layer "F.SilkS")
		)
		(fp_line
			(start -1.2954 0.5842)
			(end -1.2954 -0.5842)
			(stroke
				(width 0.1524)
				(type default)
			)
			(layer "F.SilkS")
		)
		(fp_line
			(start -1.2954 -0.5842)
			(end 1.2954 -0.5842)
			(stroke
				(width 0.1524)
				(type default)
			)
			(layer "F.SilkS")
		)
		(fp_line
			(start 1.1938 0.4064)
			(end 0.8636 0.4064)
			(stroke
				(width 0.1)
				(type default)
			)
			(layer "F.Fab")
		)
		(fp_line
			(start 1.1938 -0.4064)
			(end 1.1938 0.4064)
			(stroke
				(width 0.1)
				(type default)
			)
			(layer "F.Fab")
		)
		(fp_line
			(start 0.8636 0.4572)
			(end -0.8636 0.4572)
			(stroke
				(width 0.1)
				(type default)
			)
			(layer "F.Fab")
		)
		(fp_line
			(start 0.8636 0.4064)
			(end 0.8636 0.4572)
			(stroke
				(width 0.1)
				(type default)
			)
			(layer "F.Fab")
		)
		(fp_line
			(start 0.8636 -0.4064)
			(end 1.1938 -0.4064)
			(stroke
				(width 0.1)
				(type default)
			)
			(layer "F.Fab")
		)
		(fp_line
			(start 0.8636 -0.4572)
			(end 0.8636 -0.4064)
			(stroke
				(width 0.1)
				(type default)
			)
			(layer "F.Fab")
		)
		(fp_line
			(start -0.8636 0.4572)
			(end -0.8636 0.4064)
			(stroke
				(width 0.1)
				(type default)
			)
			(layer "F.Fab")
		)
		(fp_line
			(start -0.8636 0.4064)
			(end -1.1938 0.4064)
			(stroke
				(width 0.1)
				(type default)
			)
			(layer "F.Fab")
		)
		(fp_line
			(start -0.8636 -0.4064)
			(end -0.8636 -0.4572)
			(stroke
				(width 0.1)
				(type default)
			)
			(layer "F.Fab")
		)
		(fp_line
			(start -0.8636 -0.4572)
			(end 0.8636 -0.4572)
			(stroke
				(width 0.1)
				(type default)
			)
			(layer "F.Fab")
		)
		(fp_line
			(start -1.1938 0.4064)
			(end -1.1938 -0.4064)
			(stroke
				(width 0.1)
				(type default)
			)
			(layer "F.Fab")
		)
		(fp_line
			(start -1.1938 -0.4064)
			(end -0.8636 -0.4064)
			(stroke
				(width 0.1)
				(type default)
			)
			(layer "F.Fab")
		)
		(pad "1" smd rect
			(at -0.7366 0 90)
			(size 0.7112 0.8128)
			(layers "F.Cu" "F.Mask" "F.Paste")
			(net "PCEPLL3_VDDA18_PEX0_R")
		)
		(pad "2" smd rect
			(at 0.7366 0 90)
			(size 0.7112 0.8128)
			(layers "F.Cu" "F.Mask" "F.Paste")
			(net "GND")
		)
	)
	(footprint ""
		(layer "F.Cu")
		(at 232.334054 -109.40415)
		(property "Reference" "PD80"
			(at 1.345946 2.72542 0)
			(unlocked yes)
			(layer "F.SilkS")
			(effects
				(font
					(size 0.7874 0.5842)
					(thickness 0.1524)
				)
				(justify left)
			)
		)
		(property "Value" ""
			(at 0 0 0)
			(layer "F.Fab")
			(effects
				(font
					(size 1.27 1.27)
				)
			)
		)
		(duplicate_pad_numbers_are_jumpers no)
		(fp_line
			(start -3.656584 -1.970024)
			(end -3.656584 1.970024)
			(stroke
				(width 0.1524)
				(type default)
			)
			(layer "F.SilkS")
		)
		(fp_line
			(start -3.656584 1.970024)
			(end 4.240784 1.970024)
			(stroke
				(width 0.1524)
				(type default)
			)
			(layer "F.SilkS")
		)
		(fp_line
			(start 4.240784 -1.970024)
			(end -3.656584 -1.970024)
			(stroke
				(width 0.1524)
				(type default)
			)
			(layer "F.SilkS")
		)
		(fp_line
			(start 4.240784 1.970024)
			(end 4.240784 -1.970024)
			(stroke
				(width 0.1524)
				(type default)
			)
			(layer "F.SilkS")
		)
		(fp_poly
			(pts
				(xy 3.580384 1.970024) (xy 3.580384 -1.970024) (xy 4.240784 -1.970024) (xy 4.240784 1.970024)
			)
			(stroke
				(width 0)
				(type default)
			)
			(fill yes)
			(layer "F.SilkS")
		)
		(fp_line
			(start -2.3749 -1.970024)
			(end -2.3749 1.970024)
			(stroke
				(width 0.1)
				(type default)
			)
			(layer "F.Fab")
		)
		(fp_line
			(start -2.3749 1.970024)
			(end 2.3749 1.970024)
			(stroke
				(width 0.1)
				(type default)
			)
			(layer "F.Fab")
		)
		(fp_line
			(start 2.3749 -1.970024)
			(end -2.3749 -1.970024)
			(stroke
				(width 0.1)
				(type default)
			)
			(layer "F.Fab")
		)
		(fp_line
			(start 2.3749 1.970024)
			(end 2.3749 -1.970024)
			(stroke
				(width 0.1)
				(type default)
			)
			(layer "F.Fab")
		)
		(fp_text user "+"
			(at -4.9784 -0.23495 0)
			(unlocked yes)
			(layer "F.Fab")
			(effects
				(font
					(size 1.905 1.4224)
					(thickness 0.1524)
				)
				(justify left)
			)
		)
		(fp_text user "-"
			(at 4.1656 -0.23495 0)
			(unlocked yes)
			(layer "F.Fab")
			(effects
				(font
					(size 1.905 1.4224)
					(thickness 0.1524)
				)
				(justify left)
			)
		)
		(pad "A" smd rect
			(at -2.450084 0)
			(size 2.159 2.2606)
			(layers "F.Cu" "F.Mask" "F.Paste")
			(net "GND")
		)
		(pad "C" smd rect
			(at 2.450084 0)
			(size 2.159 2.2606)
			(layers "F.Cu" "F.Mask" "F.Paste")
			(net "P12V_AUX")
		)
	)
	(footprint ""
		(layer "F.Cu")
		(at 351.26168 -284.834838 90)
		(property "Reference" "PC172"
			(at 0 0 90)
			(layer "F.SilkS")
			(hide yes)
			(effects
				(font
					(size 1.27 1.27)
				)
			)
		)
		(property "Value" ""
			(at 0 0 90)
			(layer "F.Fab")
			(effects
				(font
					(size 1.27 1.27)
				)
			)
		)
		(duplicate_pad_numbers_are_jumpers no)
		(fp_line
			(start 0.7874 -0.4064)
			(end 0.7874 0.4064)
			(stroke
				(width 0.1524)
				(type default)
			)
			(layer "F.SilkS")
		)
		(fp_line
			(start -0.7874 -0.4064)
			(end 0.7874 -0.4064)
			(stroke
				(width 0.1524)
				(type default)
			)
			(layer "F.SilkS")
		)
		(fp_line
			(start 0.7874 0.4064)
			(end -0.7874 0.4064)
			(stroke
				(width 0.1524)
				(type default)
			)
			(layer "F.SilkS")
		)
		(fp_line
			(start -0.7874 0.4064)
			(end -0.7874 -0.4064)
			(stroke
				(width 0.1524)
				(type default)
			)
			(layer "F.SilkS")
		)
		(fp_line
			(start -0.12065 -0.305054)
			(end -0.12065 -0.2794)
			(stroke
				(width 0.1)
				(type default)
			)
			(layer "F.Fab")
		)
		(fp_line
			(start -0.67945 -0.305054)
			(end -0.12065 -0.305054)
			(stroke
				(width 0.1)
				(type default)
			)
			(layer "F.Fab")
		)
		(fp_line
			(start 0.67945 -0.3048)
			(end 0.67945 0.3048)
			(stroke
				(width 0.1)
				(type default)
			)
			(layer "F.Fab")
		)
		(fp_line
			(start 0.12065 -0.3048)
			(end 0.67945 -0.3048)
			(stroke
				(width 0.1)
				(type default)
			)
			(layer "F.Fab")
		)
		(fp_line
			(start 0.12065 -0.2794)
			(end 0.12065 -0.3048)
			(stroke
				(width 0.1)
				(type default)
			)
			(layer "F.Fab")
		)
		(fp_line
			(start -0.12065 -0.2794)
			(end 0.12065 -0.2794)
			(stroke
				(width 0.1)
				(type default)
			)
			(layer "F.Fab")
		)
		(fp_line
			(start 0.120396 0.2794)
			(end -0.12065 0.2794)
			(stroke
				(width 0.1)
				(type default)
			)
			(layer "F.Fab")
		)
		(fp_line
			(start -0.12065 0.2794)
			(end -0.12065 0.3048)
			(stroke
				(width 0.1)
				(type default)
			)
			(layer "F.Fab")
		)
		(fp_line
			(start 0.67945 0.3048)
			(end 0.120396 0.3048)
			(stroke
				(width 0.1)
				(type default)
			)
			(layer "F.Fab")
		)
		(fp_line
			(start 0.120396 0.3048)
			(end 0.120396 0.2794)
			(stroke
				(width 0.1)
				(type default)
			)
			(layer "F.Fab")
		)
		(fp_line
			(start -0.12065 0.3048)
			(end -0.67945 0.3048)
			(stroke
				(width 0.1)
				(type default)
			)
			(layer "F.Fab")
		)
		(fp_line
			(start -0.67945 0.3048)
			(end -0.67945 -0.305054)
			(stroke
				(width 0.1)
				(type default)
			)
			(layer "F.Fab")
		)
		(pad "1" smd circle
			(at -0.40005 0 90)
			(size 0 0)
			(layers "F.Cu" "F.Mask" "F.Paste")
			(net "SW_P12V_P0V8_PEX3_FLT")
		)
		(pad "2" smd circle
			(at 0.40005 0 90)
			(size 0 0)
			(layers "F.Cu" "F.Mask" "F.Paste")
			(net "GND")
		)
	)
	(footprint ""
		(layer "F.Cu")
		(at 351.155 -234.061 -90)
		(property "Reference" "R3592"
			(at 0 0 270)
			(layer "F.SilkS")
			(hide yes)
			(effects
				(font
					(size 1.27 1.27)
				)
			)
		)
		(property "Value" ""
			(at 0 0 270)
			(layer "F.Fab")
			(effects
				(font
					(size 1.27 1.27)
				)
			)
		)
		(duplicate_pad_numbers_are_jumpers no)
		(fp_line
			(start -0.7874 0.4064)
			(end -0.7874 -0.4064)
			(stroke
				(width 0.1524)
				(type default)
			)
			(layer "F.SilkS")
		)
		(fp_line
			(start 0.7874 0.4064)
			(end -0.7874 0.4064)
			(stroke
				(width 0.1524)
				(type default)
			)
			(layer "F.SilkS")
		)
		(fp_line
			(start -0.7874 -0.4064)
			(end 0.7874 -0.4064)
			(stroke
				(width 0.1524)
				(type default)
			)
			(layer "F.SilkS")
		)
		(fp_line
			(start 0.7874 -0.4064)
			(end 0.7874 0.4064)
			(stroke
				(width 0.1524)
				(type default)
			)
			(layer "F.SilkS")
		)
		(fp_line
			(start -0.67945 0.3048)
			(end -0.67945 -0.305054)
			(stroke
				(width 0.1)
				(type default)
			)
			(layer "F.Fab")
		)
		(fp_line
			(start -0.12065 0.3048)
			(end -0.67945 0.3048)
			(stroke
				(width 0.1)
				(type default)
			)
			(layer "F.Fab")
		)
		(fp_line
			(start 0.120396 0.3048)
			(end 0.120396 0.2794)
			(stroke
				(width 0.1)
				(type default)
			)
			(layer "F.Fab")
		)
		(fp_line
			(start 0.67945 0.3048)
			(end 0.120396 0.3048)
			(stroke
				(width 0.1)
				(type default)
			)
			(layer "F.Fab")
		)
		(fp_line
			(start -0.12065 0.2794)
			(end -0.12065 0.3048)
			(stroke
				(width 0.1)
				(type default)
			)
			(layer "F.Fab")
		)
		(fp_line
			(start 0.120396 0.2794)
			(end -0.12065 0.2794)
			(stroke
				(width 0.1)
				(type default)
			)
			(layer "F.Fab")
		)
		(fp_line
			(start -0.12065 -0.2794)
			(end 0.12065 -0.2794)
			(stroke
				(width 0.1)
				(type default)
			)
			(layer "F.Fab")
		)
		(fp_line
			(start 0.12065 -0.2794)
			(end 0.12065 -0.3048)
			(stroke
				(width 0.1)
				(type default)
			)
			(layer "F.Fab")
		)
		(fp_line
			(start 0.12065 -0.3048)
			(end 0.67945 -0.3048)
			(stroke
				(width 0.1)
				(type default)
			)
			(layer "F.Fab")
		)
		(fp_line
			(start 0.67945 -0.3048)
			(end 0.67945 0.3048)
			(stroke
				(width 0.1)
				(type default)
			)
			(layer "F.Fab")
		)
		(fp_line
			(start -0.67945 -0.305054)
			(end -0.12065 -0.305054)
			(stroke
				(width 0.1)
				(type default)
			)
			(layer "F.Fab")
		)
		(fp_line
			(start -0.12065 -0.305054)
			(end -0.12065 -0.2794)
			(stroke
				(width 0.1)
				(type default)
			)
			(layer "F.Fab")
		)
		(pad "1" smd circle
			(at -0.40005 0 270)
			(size 0 0)
			(layers "F.Cu" "F.Mask" "F.Paste")
			(net "SSD7_PWR_EN_R")
		)
		(pad "2" smd circle
			(at 0.40005 0 270)
			(size 0 0)
			(layers "F.Cu" "F.Mask" "F.Paste")
			(net "SSD7_PWR_EN")
		)
	)
	(footprint ""
		(layer "F.Cu")
		(at 126.210314 -125.979428)
		(property "Reference" "R882"
			(at 0 0 0)
			(layer "F.SilkS")
			(hide yes)
			(effects
				(font
					(size 1.27 1.27)
				)
			)
		)
		(property "Value" ""
			(at 0 0 0)
			(layer "F.Fab")
			(effects
				(font
					(size 1.27 1.27)
				)
			)
		)
		(duplicate_pad_numbers_are_jumpers no)
		(fp_line
			(start -0.7874 -0.4064)
			(end 0.7874 -0.4064)
			(stroke
				(width 0.1524)
				(type default)
			)
			(layer "F.SilkS")
		)
		(fp_line
			(start -0.7874 0.4064)
			(end -0.7874 -0.4064)
			(stroke
				(width 0.1524)
				(type default)
			)
			(layer "F.SilkS")
		)
		(fp_line
			(start 0.7874 -0.4064)
			(end 0.7874 0.4064)
			(stroke
				(width 0.1524)
				(type default)
			)
			(layer "F.SilkS")
		)
		(fp_line
			(start 0.7874 0.4064)
			(end -0.7874 0.4064)
			(stroke
				(width 0.1524)
				(type default)
			)
			(layer "F.SilkS")
		)
		(fp_line
			(start -0.67945 -0.305054)
			(end -0.12065 -0.305054)
			(stroke
				(width 0.1)
				(type default)
			)
			(layer "F.Fab")
		)
		(fp_line
			(start -0.67945 0.3048)
			(end -0.67945 -0.305054)
			(stroke
				(width 0.1)
				(type default)
			)
			(layer "F.Fab")
		)
		(fp_line
			(start -0.12065 -0.305054)
			(end -0.12065 -0.2794)
			(stroke
				(width 0.1)
				(type default)
			)
			(layer "F.Fab")
		)
		(fp_line
			(start -0.12065 -0.2794)
			(end 0.12065 -0.2794)
			(stroke
				(width 0.1)
				(type default)
			)
			(layer "F.Fab")
		)
		(fp_line
			(start -0.12065 0.2794)
			(end -0.12065 0.3048)
			(stroke
				(width 0.1)
				(type default)
			)
			(layer "F.Fab")
		)
		(fp_line
			(start -0.12065 0.3048)
			(end -0.67945 0.3048)
			(stroke
				(width 0.1)
				(type default)
			)
			(layer "F.Fab")
		)
		(fp_line
			(start 0.120396 0.2794)
			(end -0.12065 0.2794)
			(stroke
				(width 0.1)
				(type default)
			)
			(layer "F.Fab")
		)
		(fp_line
			(start 0.120396 0.3048)
			(end 0.120396 0.2794)
			(stroke
				(width 0.1)
				(type default)
			)
			(layer "F.Fab")
		)
		(fp_line
			(start 0.12065 -0.3048)
			(end 0.67945 -0.3048)
			(stroke
				(width 0.1)
				(type default)
			)
			(layer "F.Fab")
		)
		(fp_line
			(start 0.12065 -0.2794)
			(end 0.12065 -0.3048)
			(stroke
				(width 0.1)
				(type default)
			)
			(layer "F.Fab")
		)
		(fp_line
			(start 0.67945 -0.3048)
			(end 0.67945 0.3048)
			(stroke
				(width 0.1)
				(type default)
			)
			(layer "F.Fab")
		)
		(fp_line
			(start 0.67945 0.3048)
			(end 0.120396 0.3048)
			(stroke
				(width 0.1)
				(type default)
			)
			(layer "F.Fab")
		)
		(pad "1" smd circle
			(at -0.40005 0)
			(size 0 0)
			(layers "F.Cu" "F.Mask" "F.Paste")
			(net "P3V3_NIC2")
		)
		(pad "2" smd circle
			(at 0.40005 0)
			(size 0 0)
			(layers "F.Cu" "F.Mask" "F.Paste")
			(net "PWRGD_P3V3_NIC2")
		)
	)
	(footprint ""
		(layer "F.Cu")
		(at 361.89031 -255.210564 180)
		(property "Reference" "R835"
			(at 0 0 180)
			(layer "F.SilkS")
			(hide yes)
			(effects
				(font
					(size 1.27 1.27)
				)
			)
		)
		(property "Value" ""
			(at 0 0 180)
			(layer "F.Fab")
			(effects
				(font
					(size 1.27 1.27)
				)
			)
		)
		(duplicate_pad_numbers_are_jumpers no)
		(fp_line
			(start 0.7874 0.4064)
			(end -0.7874 0.4064)
			(stroke
				(width 0.1524)
				(type default)
			)
			(layer "F.SilkS")
		)
		(fp_line
			(start 0.7874 -0.4064)
			(end 0.7874 0.4064)
			(stroke
				(width 0.1524)
				(type default)
			)
			(layer "F.SilkS")
		)
		(fp_line
			(start -0.7874 0.4064)
			(end -0.7874 -0.4064)
			(stroke
				(width 0.1524)
				(type default)
			)
			(layer "F.SilkS")
		)
		(fp_line
			(start -0.7874 -0.4064)
			(end 0.7874 -0.4064)
			(stroke
				(width 0.1524)
				(type default)
			)
			(layer "F.SilkS")
		)
		(fp_line
			(start 0.67945 0.3048)
			(end 0.120396 0.3048)
			(stroke
				(width 0.1)
				(type default)
			)
			(layer "F.Fab")
		)
		(fp_line
			(start 0.67945 -0.3048)
			(end 0.67945 0.3048)
			(stroke
				(width 0.1)
				(type default)
			)
			(layer "F.Fab")
		)
		(fp_line
			(start 0.12065 -0.2794)
			(end 0.12065 -0.3048)
			(stroke
				(width 0.1)
				(type default)
			)
			(layer "F.Fab")
		)
		(fp_line
			(start 0.12065 -0.3048)
			(end 0.67945 -0.3048)
			(stroke
				(width 0.1)
				(type default)
			)
			(layer "F.Fab")
		)
		(fp_line
			(start 0.120396 0.3048)
			(end 0.120396 0.2794)
			(stroke
				(width 0.1)
				(type default)
			)
			(layer "F.Fab")
		)
		(fp_line
			(start 0.120396 0.2794)
			(end -0.12065 0.2794)
			(stroke
				(width 0.1)
				(type default)
			)
			(layer "F.Fab")
		)
		(fp_line
			(start -0.12065 0.3048)
			(end -0.67945 0.3048)
			(stroke
				(width 0.1)
				(type default)
			)
			(layer "F.Fab")
		)
		(fp_line
			(start -0.12065 0.2794)
			(end -0.12065 0.3048)
			(stroke
				(width 0.1)
				(type default)
			)
			(layer "F.Fab")
		)
		(fp_line
			(start -0.12065 -0.2794)
			(end 0.12065 -0.2794)
			(stroke
				(width 0.1)
				(type default)
			)
			(layer "F.Fab")
		)
		(fp_line
			(start -0.12065 -0.305054)
			(end -0.12065 -0.2794)
			(stroke
				(width 0.1)
				(type default)
			)
			(layer "F.Fab")
		)
		(fp_line
			(start -0.67945 0.3048)
			(end -0.67945 -0.305054)
			(stroke
				(width 0.1)
				(type default)
			)
			(layer "F.Fab")
		)
		(fp_line
			(start -0.67945 -0.305054)
			(end -0.12065 -0.305054)
			(stroke
				(width 0.1)
				(type default)
			)
			(layer "F.Fab")
		)
		(pad "1" smd circle
			(at -0.40005 0 180)
			(size 0 0)
			(layers "F.Cu" "F.Mask" "F.Paste")
			(net "PWR_EN_PEX_R")
		)
		(pad "2" smd circle
			(at 0.40005 0 180)
			(size 0 0)
			(layers "F.Cu" "F.Mask" "F.Paste")
			(net "FM_P0V8_PEX2_EN_R")
		)
	)
	(footprint ""
		(layer "F.Cu")
		(at 329.454764 -202.265534)
		(property "Reference" "R4404"
			(at 0 0 0)
			(layer "F.SilkS")
			(hide yes)
			(effects
				(font
					(size 1.27 1.27)
				)
			)
		)
		(property "Value" ""
			(at 0 0 0)
			(layer "F.Fab")
			(effects
				(font
					(size 1.27 1.27)
				)
			)
		)
		(duplicate_pad_numbers_are_jumpers no)
		(fp_line
			(start -0.7874 -0.4064)
			(end 0.7874 -0.4064)
			(stroke
				(width 0.1524)
				(type default)
			)
			(layer "F.SilkS")
		)
		(fp_line
			(start -0.7874 0.4064)
			(end -0.7874 -0.4064)
			(stroke
				(width 0.1524)
				(type default)
			)
			(layer "F.SilkS")
		)
		(fp_line
			(start 0.7874 -0.4064)
			(end 0.7874 0.4064)
			(stroke
				(width 0.1524)
				(type default)
			)
			(layer "F.SilkS")
		)
		(fp_line
			(start 0.7874 0.4064)
			(end -0.7874 0.4064)
			(stroke
				(width 0.1524)
				(type default)
			)
			(layer "F.SilkS")
		)
		(fp_line
			(start -0.67945 -0.305054)
			(end -0.12065 -0.305054)
			(stroke
				(width 0.1)
				(type default)
			)
			(layer "F.Fab")
		)
		(fp_line
			(start -0.67945 0.3048)
			(end -0.67945 -0.305054)
			(stroke
				(width 0.1)
				(type default)
			)
			(layer "F.Fab")
		)
		(fp_line
			(start -0.12065 -0.305054)
			(end -0.12065 -0.2794)
			(stroke
				(width 0.1)
				(type default)
			)
			(layer "F.Fab")
		)
		(fp_line
			(start -0.12065 -0.2794)
			(end 0.12065 -0.2794)
			(stroke
				(width 0.1)
				(type default)
			)
			(layer "F.Fab")
		)
		(fp_line
			(start -0.12065 0.2794)
			(end -0.12065 0.3048)
			(stroke
				(width 0.1)
				(type default)
			)
			(layer "F.Fab")
		)
		(fp_line
			(start -0.12065 0.3048)
			(end -0.67945 0.3048)
			(stroke
				(width 0.1)
				(type default)
			)
			(layer "F.Fab")
		)
		(fp_line
			(start 0.120396 0.2794)
			(end -0.12065 0.2794)
			(stroke
				(width 0.1)
				(type default)
			)
			(layer "F.Fab")
		)
		(fp_line
			(start 0.120396 0.3048)
			(end 0.120396 0.2794)
			(stroke
				(width 0.1)
				(type default)
			)
			(layer "F.Fab")
		)
		(fp_line
			(start 0.12065 -0.3048)
			(end 0.67945 -0.3048)
			(stroke
				(width 0.1)
				(type default)
			)
			(layer "F.Fab")
		)
		(fp_line
			(start 0.12065 -0.2794)
			(end 0.12065 -0.3048)
			(stroke
				(width 0.1)
				(type default)
			)
			(layer "F.Fab")
		)
		(fp_line
			(start 0.67945 -0.3048)
			(end 0.67945 0.3048)
			(stroke
				(width 0.1)
				(type default)
			)
			(layer "F.Fab")
		)
		(fp_line
			(start 0.67945 0.3048)
			(end 0.120396 0.3048)
			(stroke
				(width 0.1)
				(type default)
			)
			(layer "F.Fab")
		)
		(pad "1" smd circle
			(at -0.40005 0)
			(size 0 0)
			(layers "F.Cu" "F.Mask" "F.Paste")
			(net "P3V3_AUX")
		)
		(pad "2" smd circle
			(at 0.40005 0)
			(size 0 0)
			(layers "F.Cu" "F.Mask" "F.Paste")
			(net "PU_CLK_25M_FPGA_EN")
		)
	)
	(footprint ""
		(layer "F.Cu")
		(at 210.658202 -224.24009 90)
		(property "Reference" "U302"
			(at 2.20726 -1.230376 90)
			(unlocked yes)
			(layer "F.SilkS")
			(effects
				(font
					(size 0.7874 0.5842)
					(thickness 0.1524)
				)
				(justify left)
			)
		)
		(property "Value" ""
			(at 0 0 90)
			(layer "F.Fab")
			(effects
				(font
					(size 1.27 1.27)
				)
			)
		)
		(duplicate_pad_numbers_are_jumpers no)
		(fp_line
			(start 1.684274 -1.074928)
			(end 1.684274 1.074928)
			(stroke
				(width 0.1524)
				(type default)
			)
			(layer "F.SilkS")
		)
		(fp_line
			(start 0.381 -1.074928)
			(end 1.684274 -1.074928)
			(stroke
				(width 0.1524)
				(type default)
			)
			(layer "F.SilkS")
		)
		(fp_line
			(start -0.381 -1.074928)
			(end 0 -0.625094)
			(stroke
				(width 0.1524)
				(type default)
			)
			(layer "F.SilkS")
		)
		(fp_line
			(start -1.684274 -1.074928)
			(end -0.381 -1.074928)
			(stroke
				(width 0.1524)
				(type default)
			)
			(layer "F.SilkS")
		)
		(fp_line
			(start 0 -0.625094)
			(end 0.381 -1.074928)
			(stroke
				(width 0.1524)
				(type default)
			)
			(layer "F.SilkS")
		)
		(fp_line
			(start 1.684274 1.074928)
			(end -1.684274 1.074928)
			(stroke
				(width 0.1524)
				(type default)
			)
			(layer "F.SilkS")
		)
		(fp_line
			(start -1.684274 1.074928)
			(end -1.684274 -1.074928)
			(stroke
				(width 0.1524)
				(type default)
			)
			(layer "F.SilkS")
		)
		(fp_poly
			(pts
				(xy -2.637282 -0.903986) (xy -2.637282 -0.395986) (xy -1.875282 -0.649986)
			)
			(stroke
				(width 0)
				(type default)
			)
			(fill yes)
			(layer "F.SilkS")
		)
		(fp_line
			(start 0.700024 -1.074928)
			(end -0.700024 -1.074928)
			(stroke
				(width 0.1)
				(type default)
			)
			(layer "F.Fab")
		)
		(fp_line
			(start -0.700024 -1.074928)
			(end -0.700024 1.074928)
			(stroke
				(width 0.1)
				(type default)
			)
			(layer "F.Fab")
		)
		(fp_line
			(start 0.700024 1.074928)
			(end 0.700024 -1.074928)
			(stroke
				(width 0.1)
				(type default)
			)
			(layer "F.Fab")
		)
		(fp_line
			(start -0.700024 1.074928)
			(end 0.700024 1.074928)
			(stroke
				(width 0.1)
				(type default)
			)
			(layer "F.Fab")
		)
		(fp_poly
			(pts
				(xy -2.637282 -0.903986) (xy -2.637282 -0.395986) (xy -1.875282 -0.649986)
			)
			(stroke
				(width 0)
				(type default)
			)
			(fill yes)
			(layer "F.Fab")
		)
		(pad "1" smd rect
			(at -1.100074 -0.649986)
			(size 0.4064 0.9144)
			(layers "F.Cu" "F.Mask" "F.Paste")
			(net "BUF_UART_MB_BIC_TX_EN")
		)
		(pad "2" smd rect
			(at -1.100074 0)
			(size 0.4064 0.9144)
			(layers "F.Cu" "F.Mask" "F.Paste")
			(net "UART_MB_BIC_R_TX")
		)
		(pad "3" smd rect
			(at -1.100074 0.649986)
			(size 0.4064 0.9144)
			(layers "F.Cu" "F.Mask" "F.Paste")
			(net "GND")
		)
		(pad "4" smd rect
			(at 1.100074 0.649986)
			(size 0.4064 0.9144)
			(layers "F.Cu" "F.Mask" "F.Paste")
			(net "UART_MB_BIC_TX_BUF")
		)
		(pad "5" smd rect
			(at 1.100074 -0.649986)
			(size 0.4064 0.9144)
			(layers "F.Cu" "F.Mask" "F.Paste")
			(net "P3V3_AUX")
		)
	)
	(footprint ""
		(layer "F.Cu")
		(at 256.681986 -38.041072 180)
		(property "Reference" "R6085"
			(at 0 0 180)
			(layer "F.SilkS")
			(hide yes)
			(effects
				(font
					(size 1.27 1.27)
				)
			)
		)
		(property "Value" ""
			(at 0 0 180)
			(layer "F.Fab")
			(effects
				(font
					(size 1.27 1.27)
				)
			)
		)
		(duplicate_pad_numbers_are_jumpers no)
		(fp_line
			(start 0.7874 0.4064)
			(end -0.7874 0.4064)
			(stroke
				(width 0.1524)
				(type default)
			)
			(layer "F.SilkS")
		)
		(fp_line
			(start 0.7874 -0.4064)
			(end 0.7874 0.4064)
			(stroke
				(width 0.1524)
				(type default)
			)
			(layer "F.SilkS")
		)
		(fp_line
			(start -0.7874 0.4064)
			(end -0.7874 -0.4064)
			(stroke
				(width 0.1524)
				(type default)
			)
			(layer "F.SilkS")
		)
		(fp_line
			(start -0.7874 -0.4064)
			(end 0.7874 -0.4064)
			(stroke
				(width 0.1524)
				(type default)
			)
			(layer "F.SilkS")
		)
		(fp_line
			(start 0.67945 0.3048)
			(end 0.120396 0.3048)
			(stroke
				(width 0.1)
				(type default)
			)
			(layer "F.Fab")
		)
		(fp_line
			(start 0.67945 -0.3048)
			(end 0.67945 0.3048)
			(stroke
				(width 0.1)
				(type default)
			)
			(layer "F.Fab")
		)
		(fp_line
			(start 0.12065 -0.2794)
			(end 0.12065 -0.3048)
			(stroke
				(width 0.1)
				(type default)
			)
			(layer "F.Fab")
		)
		(fp_line
			(start 0.12065 -0.3048)
			(end 0.67945 -0.3048)
			(stroke
				(width 0.1)
				(type default)
			)
			(layer "F.Fab")
		)
		(fp_line
			(start 0.120396 0.3048)
			(end 0.120396 0.2794)
			(stroke
				(width 0.1)
				(type default)
			)
			(layer "F.Fab")
		)
		(fp_line
			(start 0.120396 0.2794)
			(end -0.12065 0.2794)
			(stroke
				(width 0.1)
				(type default)
			)
			(layer "F.Fab")
		)
		(fp_line
			(start -0.12065 0.3048)
			(end -0.67945 0.3048)
			(stroke
				(width 0.1)
				(type default)
			)
			(layer "F.Fab")
		)
		(fp_line
			(start -0.12065 0.2794)
			(end -0.12065 0.3048)
			(stroke
				(width 0.1)
				(type default)
			)
			(layer "F.Fab")
		)
		(fp_line
			(start -0.12065 -0.2794)
			(end 0.12065 -0.2794)
			(stroke
				(width 0.1)
				(type default)
			)
			(layer "F.Fab")
		)
		(fp_line
			(start -0.12065 -0.305054)
			(end -0.12065 -0.2794)
			(stroke
				(width 0.1)
				(type default)
			)
			(layer "F.Fab")
		)
		(fp_line
			(start -0.67945 0.3048)
			(end -0.67945 -0.305054)
			(stroke
				(width 0.1)
				(type default)
			)
			(layer "F.Fab")
		)
		(fp_line
			(start -0.67945 -0.305054)
			(end -0.12065 -0.305054)
			(stroke
				(width 0.1)
				(type default)
			)
			(layer "F.Fab")
		)
		(pad "1" smd circle
			(at -0.40005 0 180)
			(size 0 0)
			(layers "F.Cu" "F.Mask" "F.Paste")
			(net "P5V_AUX")
		)
		(pad "2" smd circle
			(at 0.40005 0 180)
			(size 0 0)
			(layers "F.Cu" "F.Mask" "F.Paste")
			(net "P3V3_SSD9_PG_G2")
		)
	)
	(footprint ""
		(layer "F.Cu")
		(at 92.436442 -343.952322 90)
		(property "Reference" "C157"
			(at 0 0 90)
			(layer "F.SilkS")
			(hide yes)
			(effects
				(font
					(size 1.27 1.27)
				)
			)
		)
		(property "Value" ""
			(at 0 0 90)
			(layer "F.Fab")
			(effects
				(font
					(size 1.27 1.27)
				)
			)
		)
		(duplicate_pad_numbers_are_jumpers no)
		(fp_line
			(start 0.299974 -0.150114)
			(end 0.299974 0.150114)
			(stroke
				(width 0.1)
				(type default)
			)
			(layer "F.Fab")
		)
		(fp_line
			(start -0.299974 -0.150114)
			(end 0.299974 -0.150114)
			(stroke
				(width 0.1)
				(type default)
			)
			(layer "F.Fab")
		)
		(fp_line
			(start 0.299974 0.150114)
			(end -0.299974 0.150114)
			(stroke
				(width 0.1)
				(type default)
			)
			(layer "F.Fab")
		)
		(fp_line
			(start -0.299974 0.150114)
			(end -0.299974 -0.150114)
			(stroke
				(width 0.1)
				(type default)
			)
			(layer "F.Fab")
		)
		(pad "1" smd rect
			(at -0.2667 0 90)
			(size 0.3048 0.381)
			(layers "F.Cu" "F.Mask" "F.Paste")
			(net "P5E_PEX0_STN6_TX_DP<97>")
		)
		(pad "2" smd rect
			(at 0.2667 0 90)
			(size 0.3048 0.381)
			(layers "F.Cu" "F.Mask" "F.Paste")
			(net "P5E_PEX0_STN6_TX_C_DP<97>")
		)
	)
	(footprint ""
		(layer "F.Cu")
		(at 135.754872 -22.867366 90)
		(property "Reference" "C3902"
			(at 0 0 90)
			(layer "F.SilkS")
			(hide yes)
			(effects
				(font
					(size 1.27 1.27)
				)
			)
		)
		(property "Value" ""
			(at 0 0 90)
			(layer "F.Fab")
			(effects
				(font
					(size 1.27 1.27)
				)
			)
		)
		(duplicate_pad_numbers_are_jumpers no)
		(fp_line
			(start 0.7874 -0.4064)
			(end 0.7874 0.4064)
			(stroke
				(width 0.1524)
				(type default)
			)
			(layer "F.SilkS")
		)
		(fp_line
			(start -0.7874 -0.4064)
			(end 0.7874 -0.4064)
			(stroke
				(width 0.1524)
				(type default)
			)
			(layer "F.SilkS")
		)
		(fp_line
			(start 0.7874 0.4064)
			(end -0.7874 0.4064)
			(stroke
				(width 0.1524)
				(type default)
			)
			(layer "F.SilkS")
		)
		(fp_line
			(start -0.7874 0.4064)
			(end -0.7874 -0.4064)
			(stroke
				(width 0.1524)
				(type default)
			)
			(layer "F.SilkS")
		)
		(fp_line
			(start -0.12065 -0.305054)
			(end -0.12065 -0.2794)
			(stroke
				(width 0.1)
				(type default)
			)
			(layer "F.Fab")
		)
		(fp_line
			(start -0.67945 -0.305054)
			(end -0.12065 -0.305054)
			(stroke
				(width 0.1)
				(type default)
			)
			(layer "F.Fab")
		)
		(fp_line
			(start 0.67945 -0.3048)
			(end 0.67945 0.3048)
			(stroke
				(width 0.1)
				(type default)
			)
			(layer "F.Fab")
		)
		(fp_line
			(start 0.12065 -0.3048)
			(end 0.67945 -0.3048)
			(stroke
				(width 0.1)
				(type default)
			)
			(layer "F.Fab")
		)
		(fp_line
			(start 0.12065 -0.2794)
			(end 0.12065 -0.3048)
			(stroke
				(width 0.1)
				(type default)
			)
			(layer "F.Fab")
		)
		(fp_line
			(start -0.12065 -0.2794)
			(end 0.12065 -0.2794)
			(stroke
				(width 0.1)
				(type default)
			)
			(layer "F.Fab")
		)
		(fp_line
			(start 0.120396 0.2794)
			(end -0.12065 0.2794)
			(stroke
				(width 0.1)
				(type default)
			)
			(layer "F.Fab")
		)
		(fp_line
			(start -0.12065 0.2794)
			(end -0.12065 0.3048)
			(stroke
				(width 0.1)
				(type default)
			)
			(layer "F.Fab")
		)
		(fp_line
			(start 0.67945 0.3048)
			(end 0.120396 0.3048)
			(stroke
				(width 0.1)
				(type default)
			)
			(layer "F.Fab")
		)
		(fp_line
			(start 0.120396 0.3048)
			(end 0.120396 0.2794)
			(stroke
				(width 0.1)
				(type default)
			)
			(layer "F.Fab")
		)
		(fp_line
			(start -0.12065 0.3048)
			(end -0.67945 0.3048)
			(stroke
				(width 0.1)
				(type default)
			)
			(layer "F.Fab")
		)
		(fp_line
			(start -0.67945 0.3048)
			(end -0.67945 -0.305054)
			(stroke
				(width 0.1)
				(type default)
			)
			(layer "F.Fab")
		)
		(pad "1" smd circle
			(at -0.40005 0 90)
			(size 0 0)
			(layers "F.Cu" "F.Mask" "F.Paste")
			(net "P12V_SSD4")
		)
		(pad "2" smd circle
			(at 0.40005 0 90)
			(size 0 0)
			(layers "F.Cu" "F.Mask" "F.Paste")
			(net "GND")
		)
	)
	(footprint ""
		(layer "F.Cu")
		(at 63.6778 -117.566186)
		(property "Reference" "R92"
			(at 0 0 0)
			(layer "F.SilkS")
			(hide yes)
			(effects
				(font
					(size 1.27 1.27)
				)
			)
		)
		(property "Value" ""
			(at 0 0 0)
			(layer "F.Fab")
			(effects
				(font
					(size 1.27 1.27)
				)
			)
		)
		(duplicate_pad_numbers_are_jumpers no)
		(fp_line
			(start -0.7874 -0.4064)
			(end 0.7874 -0.4064)
			(stroke
				(width 0.1524)
				(type default)
			)
			(layer "F.SilkS")
		)
		(fp_line
			(start -0.7874 0.4064)
			(end -0.7874 -0.4064)
			(stroke
				(width 0.1524)
				(type default)
			)
			(layer "F.SilkS")
		)
		(fp_line
			(start 0.7874 -0.4064)
			(end 0.7874 0.4064)
			(stroke
				(width 0.1524)
				(type default)
			)
			(layer "F.SilkS")
		)
		(fp_line
			(start 0.7874 0.4064)
			(end -0.7874 0.4064)
			(stroke
				(width 0.1524)
				(type default)
			)
			(layer "F.SilkS")
		)
		(fp_line
			(start -0.67945 -0.305054)
			(end -0.12065 -0.305054)
			(stroke
				(width 0.1)
				(type default)
			)
			(layer "F.Fab")
		)
		(fp_line
			(start -0.67945 0.3048)
			(end -0.67945 -0.305054)
			(stroke
				(width 0.1)
				(type default)
			)
			(layer "F.Fab")
		)
		(fp_line
			(start -0.12065 -0.305054)
			(end -0.12065 -0.2794)
			(stroke
				(width 0.1)
				(type default)
			)
			(layer "F.Fab")
		)
		(fp_line
			(start -0.12065 -0.2794)
			(end 0.12065 -0.2794)
			(stroke
				(width 0.1)
				(type default)
			)
			(layer "F.Fab")
		)
		(fp_line
			(start -0.12065 0.2794)
			(end -0.12065 0.3048)
			(stroke
				(width 0.1)
				(type default)
			)
			(layer "F.Fab")
		)
		(fp_line
			(start -0.12065 0.3048)
			(end -0.67945 0.3048)
			(stroke
				(width 0.1)
				(type default)
			)
			(layer "F.Fab")
		)
		(fp_line
			(start 0.120396 0.2794)
			(end -0.12065 0.2794)
			(stroke
				(width 0.1)
				(type default)
			)
			(layer "F.Fab")
		)
		(fp_line
			(start 0.120396 0.3048)
			(end 0.120396 0.2794)
			(stroke
				(width 0.1)
				(type default)
			)
			(layer "F.Fab")
		)
		(fp_line
			(start 0.12065 -0.3048)
			(end 0.67945 -0.3048)
			(stroke
				(width 0.1)
				(type default)
			)
			(layer "F.Fab")
		)
		(fp_line
			(start 0.12065 -0.2794)
			(end 0.12065 -0.3048)
			(stroke
				(width 0.1)
				(type default)
			)
			(layer "F.Fab")
		)
		(fp_line
			(start 0.67945 -0.3048)
			(end 0.67945 0.3048)
			(stroke
				(width 0.1)
				(type default)
			)
			(layer "F.Fab")
		)
		(fp_line
			(start 0.67945 0.3048)
			(end 0.120396 0.3048)
			(stroke
				(width 0.1)
				(type default)
			)
			(layer "F.Fab")
		)
		(pad "1" smd circle
			(at -0.40005 0)
			(size 0 0)
			(layers "F.Cu" "F.Mask" "F.Paste")
			(net "PRSNT_NIC1_N")
		)
		(pad "2" smd circle
			(at 0.40005 0)
			(size 0 0)
			(layers "F.Cu" "F.Mask" "F.Paste")
			(net "PRSNTB2_NIC1_N")
		)
	)
	(footprint ""
		(layer "F.Cu")
		(at 211.558886 -231.150922 90)
		(property "Reference" "R1548"
			(at 0 0 90)
			(layer "F.SilkS")
			(hide yes)
			(effects
				(font
					(size 1.27 1.27)
				)
			)
		)
		(property "Value" ""
			(at 0 0 90)
			(layer "F.Fab")
			(effects
				(font
					(size 1.27 1.27)
				)
			)
		)
		(duplicate_pad_numbers_are_jumpers no)
		(fp_line
			(start 0.7874 -0.4064)
			(end 0.7874 0.4064)
			(stroke
				(width 0.1524)
				(type default)
			)
			(layer "F.SilkS")
		)
		(fp_line
			(start -0.7874 -0.4064)
			(end 0.7874 -0.4064)
			(stroke
				(width 0.1524)
				(type default)
			)
			(layer "F.SilkS")
		)
		(fp_line
			(start 0.7874 0.4064)
			(end -0.7874 0.4064)
			(stroke
				(width 0.1524)
				(type default)
			)
			(layer "F.SilkS")
		)
		(fp_line
			(start -0.7874 0.4064)
			(end -0.7874 -0.4064)
			(stroke
				(width 0.1524)
				(type default)
			)
			(layer "F.SilkS")
		)
		(fp_line
			(start -0.12065 -0.305054)
			(end -0.12065 -0.2794)
			(stroke
				(width 0.1)
				(type default)
			)
			(layer "F.Fab")
		)
		(fp_line
			(start -0.67945 -0.305054)
			(end -0.12065 -0.305054)
			(stroke
				(width 0.1)
				(type default)
			)
			(layer "F.Fab")
		)
		(fp_line
			(start 0.67945 -0.3048)
			(end 0.67945 0.3048)
			(stroke
				(width 0.1)
				(type default)
			)
			(layer "F.Fab")
		)
		(fp_line
			(start 0.12065 -0.3048)
			(end 0.67945 -0.3048)
			(stroke
				(width 0.1)
				(type default)
			)
			(layer "F.Fab")
		)
		(fp_line
			(start 0.12065 -0.2794)
			(end 0.12065 -0.3048)
			(stroke
				(width 0.1)
				(type default)
			)
			(layer "F.Fab")
		)
		(fp_line
			(start -0.12065 -0.2794)
			(end 0.12065 -0.2794)
			(stroke
				(width 0.1)
				(type default)
			)
			(layer "F.Fab")
		)
		(fp_line
			(start 0.120396 0.2794)
			(end -0.12065 0.2794)
			(stroke
				(width 0.1)
				(type default)
			)
			(layer "F.Fab")
		)
		(fp_line
			(start -0.12065 0.2794)
			(end -0.12065 0.3048)
			(stroke
				(width 0.1)
				(type default)
			)
			(layer "F.Fab")
		)
		(fp_line
			(start 0.67945 0.3048)
			(end 0.120396 0.3048)
			(stroke
				(width 0.1)
				(type default)
			)
			(layer "F.Fab")
		)
		(fp_line
			(start 0.120396 0.3048)
			(end 0.120396 0.2794)
			(stroke
				(width 0.1)
				(type default)
			)
			(layer "F.Fab")
		)
		(fp_line
			(start -0.12065 0.3048)
			(end -0.67945 0.3048)
			(stroke
				(width 0.1)
				(type default)
			)
			(layer "F.Fab")
		)
		(fp_line
			(start -0.67945 0.3048)
			(end -0.67945 -0.305054)
			(stroke
				(width 0.1)
				(type default)
			)
			(layer "F.Fab")
		)
		(pad "1" smd circle
			(at -0.40005 0 90)
			(size 0 0)
			(layers "F.Cu" "F.Mask" "F.Paste")
			(net "SMB_PEX_LS_R_SDA")
		)
		(pad "2" smd circle
			(at 0.40005 0 90)
			(size 0 0)
			(layers "F.Cu" "F.Mask" "F.Paste")
			(net "SMB_PEX2_SDA")
		)
	)
	(footprint ""
		(layer "F.Cu")
		(at 233.800904 -254.18542 -90)
		(property "Reference" "C4355"
			(at 0 0 270)
			(layer "F.SilkS")
			(hide yes)
			(effects
				(font
					(size 1.27 1.27)
				)
			)
		)
		(property "Value" ""
			(at 0 0 270)
			(layer "F.Fab")
			(effects
				(font
					(size 1.27 1.27)
				)
			)
		)
		(duplicate_pad_numbers_are_jumpers no)
		(fp_line
			(start -1.2954 0.5842)
			(end -1.2954 -0.5842)
			(stroke
				(width 0.1524)
				(type default)
			)
			(layer "F.SilkS")
		)
		(fp_line
			(start 1.2954 0.5842)
			(end -1.2954 0.5842)
			(stroke
				(width 0.1524)
				(type default)
			)
			(layer "F.SilkS")
		)
		(fp_line
			(start -1.2954 -0.5842)
			(end 1.2954 -0.5842)
			(stroke
				(width 0.1524)
				(type default)
			)
			(layer "F.SilkS")
		)
		(fp_line
			(start 1.2954 -0.5842)
			(end 1.2954 0.5842)
			(stroke
				(width 0.1524)
				(type default)
			)
			(layer "F.SilkS")
		)
		(fp_line
			(start -0.8636 0.4572)
			(end -0.8636 0.4064)
			(stroke
				(width 0.1)
				(type default)
			)
			(layer "F.Fab")
		)
		(fp_line
			(start 0.8636 0.4572)
			(end -0.8636 0.4572)
			(stroke
				(width 0.1)
				(type default)
			)
			(layer "F.Fab")
		)
		(fp_line
			(start -1.1938 0.4064)
			(end -1.1938 -0.4064)
			(stroke
				(width 0.1)
				(type default)
			)
			(layer "F.Fab")
		)
		(fp_line
			(start -0.8636 0.4064)
			(end -1.1938 0.4064)
			(stroke
				(width 0.1)
				(type default)
			)
			(layer "F.Fab")
		)
		(fp_line
			(start 0.8636 0.4064)
			(end 0.8636 0.4572)
			(stroke
				(width 0.1)
				(type default)
			)
			(layer "F.Fab")
		)
		(fp_line
			(start 1.1938 0.4064)
			(end 0.8636 0.4064)
			(stroke
				(width 0.1)
				(type default)
			)
			(layer "F.Fab")
		)
		(fp_line
			(start -1.1938 -0.4064)
			(end -0.8636 -0.4064)
			(stroke
				(width 0.1)
				(type default)
			)
			(layer "F.Fab")
		)
		(fp_line
			(start -0.8636 -0.4064)
			(end -0.8636 -0.4572)
			(stroke
				(width 0.1)
				(type default)
			)
			(layer "F.Fab")
		)
		(fp_line
			(start 0.8636 -0.4064)
			(end 1.1938 -0.4064)
			(stroke
				(width 0.1)
				(type default)
			)
			(layer "F.Fab")
		)
		(fp_line
			(start 1.1938 -0.4064)
			(end 1.1938 0.4064)
			(stroke
				(width 0.1)
				(type default)
			)
			(layer "F.Fab")
		)
		(fp_line
			(start -0.8636 -0.4572)
			(end 0.8636 -0.4572)
			(stroke
				(width 0.1)
				(type default)
			)
			(layer "F.Fab")
		)
		(fp_line
			(start 0.8636 -0.4572)
			(end 0.8636 -0.4064)
			(stroke
				(width 0.1)
				(type default)
			)
			(layer "F.Fab")
		)
		(pad "1" smd rect
			(at -0.7366 0 180)
			(size 0.7112 0.8128)
			(layers "F.Cu" "F.Mask" "F.Paste")
			(net "P1V25_SERDES_VDDPLL_PEX2_C9")
		)
		(pad "2" smd rect
			(at 0.7366 0 180)
			(size 0.7112 0.8128)
			(layers "F.Cu" "F.Mask" "F.Paste")
			(net "GND")
		)
	)
	(footprint ""
		(layer "F.Cu")
		(at 135.626856 -170.599862 90)
		(property "Reference" "R1096"
			(at 0 0 90)
			(layer "F.SilkS")
			(hide yes)
			(effects
				(font
					(size 1.27 1.27)
				)
			)
		)
		(property "Value" ""
			(at 0 0 90)
			(layer "F.Fab")
			(effects
				(font
					(size 1.27 1.27)
				)
			)
		)
		(duplicate_pad_numbers_are_jumpers no)
		(fp_line
			(start -0.7874 -0.4064)
			(end 0.7874 -0.4064)
			(stroke
				(width 0.1524)
				(type default)
			)
			(layer "F.SilkS")
		)
		(fp_line
			(start -0.12065 -0.305054)
			(end -0.12065 -0.2794)
			(stroke
				(width 0.1)
				(type default)
			)
			(layer "F.Fab")
		)
		(fp_line
			(start -0.67945 -0.305054)
			(end -0.12065 -0.305054)
			(stroke
				(width 0.1)
				(type default)
			)
			(layer "F.Fab")
		)
		(fp_line
			(start 0.67945 -0.3048)
			(end 0.67945 0.3048)
			(stroke
				(width 0.1)
				(type default)
			)
			(layer "F.Fab")
		)
		(fp_line
			(start 0.12065 -0.3048)
			(end 0.67945 -0.3048)
			(stroke
				(width 0.1)
				(type default)
			)
			(layer "F.Fab")
		)
		(fp_line
			(start 0.12065 -0.2794)
			(end 0.12065 -0.3048)
			(stroke
				(width 0.1)
				(type default)
			)
			(layer "F.Fab")
		)
		(fp_line
			(start -0.12065 -0.2794)
			(end 0.12065 -0.2794)
			(stroke
				(width 0.1)
				(type default)
			)
			(layer "F.Fab")
		)
		(fp_line
			(start 0.120396 0.2794)
			(end -0.12065 0.2794)
			(stroke
				(width 0.1)
				(type default)
			)
			(layer "F.Fab")
		)
		(fp_line
			(start -0.12065 0.2794)
			(end -0.12065 0.3048)
			(stroke
				(width 0.1)
				(type default)
			)
			(layer "F.Fab")
		)
		(fp_line
			(start 0.67945 0.3048)
			(end 0.120396 0.3048)
			(stroke
				(width 0.1)
				(type default)
			)
			(layer "F.Fab")
		)
		(fp_line
			(start 0.120396 0.3048)
			(end 0.120396 0.2794)
			(stroke
				(width 0.1)
				(type default)
			)
			(layer "F.Fab")
		)
		(fp_line
			(start -0.12065 0.3048)
			(end -0.67945 0.3048)
			(stroke
				(width 0.1)
				(type default)
			)
			(layer "F.Fab")
		)
		(fp_line
			(start -0.67945 0.3048)
			(end -0.67945 -0.305054)
			(stroke
				(width 0.1)
				(type default)
			)
			(layer "F.Fab")
		)
		(pad "1" smd circle
			(at -0.40005 0 90)
			(size 0 0)
			(layers "F.Cu" "F.Mask" "F.Paste")
			(net "CLK_100M_DB2000QL_NIC1_R_DP")
		)
		(pad "2" smd circle
			(at 0.40005 0 90)
			(size 0 0)
			(layers "F.Cu" "F.Mask" "F.Paste")
			(net "CLK_100M_DB2000QL_NIC1_DP")
		)
	)
	(footprint ""
		(layer "F.Cu")
		(at 123.614434 -303.698402 90)
		(property "Reference" "PC119"
			(at 0 0 90)
			(layer "F.SilkS")
			(hide yes)
			(effects
				(font
					(size 1.27 1.27)
				)
			)
		)
		(property "Value" ""
			(at 0 0 90)
			(layer "F.Fab")
			(effects
				(font
					(size 1.27 1.27)
				)
			)
		)
		(duplicate_pad_numbers_are_jumpers no)
		(fp_line
			(start -4.53898 -2.150618)
			(end -4.539742 2.152142)
			(stroke
				(width 0.1524)
				(type default)
			)
			(layer "F.SilkS")
		)
		(fp_line
			(start -4.69138 -2.150618)
			(end -4.692396 2.161032)
			(stroke
				(width 0.1524)
				(type default)
			)
			(layer "F.SilkS")
		)
		(fp_line
			(start -4.84378 -2.150618)
			(end -4.53898 -2.150618)
			(stroke
				(width 0.1524)
				(type default)
			)
			(layer "F.SilkS")
		)
		(fp_line
			(start -4.84378 -2.150618)
			(end -4.842256 2.163064)
			(stroke
				(width 0.1524)
				(type default)
			)
			(layer "F.SilkS")
		)
		(fp_line
			(start 4.53898 -2.15011)
			(end 4.53898 2.15011)
			(stroke
				(width 0.1524)
				(type default)
			)
			(layer "F.SilkS")
		)
		(fp_line
			(start -4.53898 -2.15011)
			(end 4.53898 -2.15011)
			(stroke
				(width 0.1524)
				(type default)
			)
			(layer "F.SilkS")
		)
		(fp_line
			(start 4.53898 2.15011)
			(end -4.53898 2.15011)
			(stroke
				(width 0.1524)
				(type default)
			)
			(layer "F.SilkS")
		)
		(fp_line
			(start -4.53898 2.15011)
			(end -4.53898 -2.15011)
			(stroke
				(width 0.1524)
				(type default)
			)
			(layer "F.SilkS")
		)
		(fp_line
			(start -4.83108 2.150364)
			(end -4.447794 2.149348)
			(stroke
				(width 0.1524)
				(type default)
			)
			(layer "F.SilkS")
		)
		(fp_line
			(start 3.64998 -2.15011)
			(end 3.64998 2.15011)
			(stroke
				(width 0.1)
				(type default)
			)
			(layer "F.Fab")
		)
		(fp_line
			(start -3.64998 -2.15011)
			(end 3.64998 -2.15011)
			(stroke
				(width 0.1)
				(type default)
			)
			(layer "F.Fab")
		)
		(fp_line
			(start 3.64998 2.15011)
			(end -3.64998 2.15011)
			(stroke
				(width 0.1)
				(type default)
			)
			(layer "F.Fab")
		)
		(fp_line
			(start -3.64998 2.15011)
			(end -3.64998 -2.15011)
			(stroke
				(width 0.1)
				(type default)
			)
			(layer "F.Fab")
		)
		(fp_text user "+"
			(at -4.575048 -3.013202 90)
			(unlocked yes)
			(layer "F.SilkS")
			(effects
				(font
					(size 1.905 1.4224)
					(thickness 0.1524)
				)
				(justify left)
			)
		)
		(fp_text user "-"
			(at 3.295396 -2.940304 90)
			(unlocked yes)
			(layer "F.SilkS")
			(effects
				(font
					(size 1.905 1.4224)
					(thickness 0.1524)
				)
				(justify left)
			)
		)
		(fp_text user "+"
			(at -6.214872 -0.337058 90)
			(unlocked yes)
			(layer "F.Fab")
			(effects
				(font
					(size 1.905 1.4224)
					(thickness 0.1524)
				)
				(justify left)
			)
		)
		(fp_text user "-"
			(at 4.313174 -0.094488 90)
			(unlocked yes)
			(layer "F.Fab")
			(effects
				(font
					(size 1.905 1.4224)
					(thickness 0.1524)
				)
				(justify left)
			)
		)
		(pad "1" smd rect
			(at -3.199892 0 90)
			(size 2.413 2.8194)
			(layers "F.Cu" "F.Mask" "F.Paste")
			(net "P0V8_PEX1")
		)
		(pad "2" smd rect
			(at 3.199892 0 90)
			(size 2.413 2.8194)
			(layers "F.Cu" "F.Mask" "F.Paste")
			(net "GND")
		)
	)
	(footprint ""
		(layer "F.Cu")
		(at 199.651366 -411.279594 -90)
		(property "Reference" "U444"
			(at 0.461772 -2.178558 90)
			(unlocked yes)
			(layer "F.SilkS")
			(effects
				(font
					(size 0.7874 0.5842)
					(thickness 0.1524)
				)
				(justify left)
			)
		)
		(property "Value" ""
			(at 0 0 270)
			(layer "F.Fab")
			(effects
				(font
					(size 1.27 1.27)
				)
			)
		)
		(duplicate_pad_numbers_are_jumpers no)
		(fp_line
			(start -1.868424 1.519936)
			(end 1.868424 1.519936)
			(stroke
				(width 0.1524)
				(type default)
			)
			(layer "F.SilkS")
		)
		(fp_line
			(start 1.868424 1.519936)
			(end 1.868424 -1.519936)
			(stroke
				(width 0.1524)
				(type default)
			)
			(layer "F.SilkS")
		)
		(fp_line
			(start -1.868424 -1.519936)
			(end -1.868424 1.519936)
			(stroke
				(width 0.1524)
				(type default)
			)
			(layer "F.SilkS")
		)
		(fp_line
			(start 1.868424 -1.519936)
			(end -1.868424 -1.519936)
			(stroke
				(width 0.1524)
				(type default)
			)
			(layer "F.SilkS")
		)
		(fp_line
			(start -0.700024 1.519936)
			(end 0.700024 1.519936)
			(stroke
				(width 0.1)
				(type default)
			)
			(layer "F.Fab")
		)
		(fp_line
			(start 0.700024 1.519936)
			(end 0.700024 -1.519936)
			(stroke
				(width 0.1)
				(type default)
			)
			(layer "F.Fab")
		)
		(fp_line
			(start -0.700024 -1.519936)
			(end -0.700024 1.519936)
			(stroke
				(width 0.1)
				(type default)
			)
			(layer "F.Fab")
		)
		(fp_line
			(start 0.700024 -1.519936)
			(end -0.700024 -1.519936)
			(stroke
				(width 0.1)
				(type default)
			)
			(layer "F.Fab")
		)
		(pad "1" smd rect
			(at -1.18491 -0.94996 180)
			(size 0.6096 1.0668)
			(layers "F.Cu" "F.Mask" "F.Paste")
			(net "UV_P2V5_COMP")
		)
		(pad "2" smd rect
			(at -1.18491 0.94996 180)
			(size 0.6096 1.0668)
			(layers "F.Cu" "F.Mask" "F.Paste")
			(net "GND")
		)
		(pad "3" smd rect
			(at 1.18491 0 180)
			(size 0.6096 1.0668)
			(layers "F.Cu" "F.Mask" "F.Paste")
			(net "Net_9326")
		)
	)
	(footprint ""
		(layer "F.Cu")
		(at 186.372754 -415.15919 180)
		(property "Reference" "R6778"
			(at 0 0 180)
			(layer "F.SilkS")
			(hide yes)
			(effects
				(font
					(size 1.27 1.27)
				)
			)
		)
		(property "Value" ""
			(at 0 0 180)
			(layer "F.Fab")
			(effects
				(font
					(size 1.27 1.27)
				)
			)
		)
		(duplicate_pad_numbers_are_jumpers no)
		(fp_line
			(start 0.7874 0.4064)
			(end -0.7874 0.4064)
			(stroke
				(width 0.1524)
				(type default)
			)
			(layer "F.SilkS")
		)
		(fp_line
			(start 0.7874 -0.4064)
			(end 0.7874 0.4064)
			(stroke
				(width 0.1524)
				(type default)
			)
			(layer "F.SilkS")
		)
		(fp_line
			(start -0.7874 0.4064)
			(end -0.7874 -0.4064)
			(stroke
				(width 0.1524)
				(type default)
			)
			(layer "F.SilkS")
		)
		(fp_line
			(start -0.7874 -0.4064)
			(end 0.7874 -0.4064)
			(stroke
				(width 0.1524)
				(type default)
			)
			(layer "F.SilkS")
		)
		(fp_line
			(start 0.67945 0.3048)
			(end 0.120396 0.3048)
			(stroke
				(width 0.1)
				(type default)
			)
			(layer "F.Fab")
		)
		(fp_line
			(start 0.67945 -0.3048)
			(end 0.67945 0.3048)
			(stroke
				(width 0.1)
				(type default)
			)
			(layer "F.Fab")
		)
		(fp_line
			(start 0.12065 -0.2794)
			(end 0.12065 -0.3048)
			(stroke
				(width 0.1)
				(type default)
			)
			(layer "F.Fab")
		)
		(fp_line
			(start 0.12065 -0.3048)
			(end 0.67945 -0.3048)
			(stroke
				(width 0.1)
				(type default)
			)
			(layer "F.Fab")
		)
		(fp_line
			(start 0.120396 0.3048)
			(end 0.120396 0.2794)
			(stroke
				(width 0.1)
				(type default)
			)
			(layer "F.Fab")
		)
		(fp_line
			(start 0.120396 0.2794)
			(end -0.12065 0.2794)
			(stroke
				(width 0.1)
				(type default)
			)
			(layer "F.Fab")
		)
		(fp_line
			(start -0.12065 0.3048)
			(end -0.67945 0.3048)
			(stroke
				(width 0.1)
				(type default)
			)
			(layer "F.Fab")
		)
		(fp_line
			(start -0.12065 0.2794)
			(end -0.12065 0.3048)
			(stroke
				(width 0.1)
				(type default)
			)
			(layer "F.Fab")
		)
		(fp_line
			(start -0.12065 -0.2794)
			(end 0.12065 -0.2794)
			(stroke
				(width 0.1)
				(type default)
			)
			(layer "F.Fab")
		)
		(fp_line
			(start -0.12065 -0.305054)
			(end -0.12065 -0.2794)
			(stroke
				(width 0.1)
				(type default)
			)
			(layer "F.Fab")
		)
		(fp_line
			(start -0.67945 0.3048)
			(end -0.67945 -0.305054)
			(stroke
				(width 0.1)
				(type default)
			)
			(layer "F.Fab")
		)
		(fp_line
			(start -0.67945 -0.305054)
			(end -0.12065 -0.305054)
			(stroke
				(width 0.1)
				(type default)
			)
			(layer "F.Fab")
		)
		(pad "1" smd circle
			(at -0.40005 0 180)
			(size 0 0)
			(layers "F.Cu" "F.Mask" "F.Paste")
			(net "P3V3_AUX")
		)
		(pad "2" smd circle
			(at 0.40005 0 180)
			(size 0 0)
			(layers "F.Cu" "F.Mask" "F.Paste")
			(net "HSC_UV_R_N")
		)
	)
	(footprint ""
		(layer "F.Cu")
		(at 17.792446 -29.139642 180)
		(property "Reference" "C71"
			(at 0 0 180)
			(layer "F.SilkS")
			(hide yes)
			(effects
				(font
					(size 1.27 1.27)
				)
			)
		)
		(property "Value" ""
			(at 0 0 180)
			(layer "F.Fab")
			(effects
				(font
					(size 1.27 1.27)
				)
			)
		)
		(duplicate_pad_numbers_are_jumpers no)
		(fp_line
			(start 0.299974 0.150114)
			(end -0.299974 0.150114)
			(stroke
				(width 0.1)
				(type default)
			)
			(layer "F.Fab")
		)
		(fp_line
			(start 0.299974 -0.150114)
			(end 0.299974 0.150114)
			(stroke
				(width 0.1)
				(type default)
			)
			(layer "F.Fab")
		)
		(fp_line
			(start -0.299974 0.150114)
			(end -0.299974 -0.150114)
			(stroke
				(width 0.1)
				(type default)
			)
			(layer "F.Fab")
		)
		(fp_line
			(start -0.299974 -0.150114)
			(end 0.299974 -0.150114)
			(stroke
				(width 0.1)
				(type default)
			)
			(layer "F.Fab")
		)
		(pad "1" smd rect
			(at -0.2667 0 180)
			(size 0.3048 0.381)
			(layers "F.Cu" "F.Mask" "F.Paste")
			(net "P5E_PEX0_STN2_TX_DP<44>")
		)
		(pad "2" smd rect
			(at 0.2667 0 180)
			(size 0.3048 0.381)
			(layers "F.Cu" "F.Mask" "F.Paste")
			(net "P5E_PEX0_STN2_TX_C_DP<44>")
		)
	)
	(footprint ""
		(layer "F.Cu")
		(at 350.795336 -35.48253)
		(property "Reference" "U395"
			(at -2.509266 1.24333 90)
			(unlocked yes)
			(layer "F.SilkS")
			(effects
				(font
					(size 0.7874 0.5842)
					(thickness 0.1524)
				)
				(justify left)
			)
		)
		(property "Value" ""
			(at 0 0 0)
			(layer "F.Fab")
			(effects
				(font
					(size 1.27 1.27)
				)
			)
		)
		(duplicate_pad_numbers_are_jumpers no)
		(fp_line
			(start -1.3462 -1.1938)
			(end -1.3462 1.1684)
			(stroke
				(width 0.1524)
				(type default)
			)
			(layer "F.SilkS")
		)
		(fp_line
			(start -1.3462 1.1938)
			(end 1.3462 1.1938)
			(stroke
				(width 0.1524)
				(type default)
			)
			(layer "F.SilkS")
		)
		(fp_line
			(start 1.3462 -1.1938)
			(end -1.3462 -1.1938)
			(stroke
				(width 0.1524)
				(type default)
			)
			(layer "F.SilkS")
		)
		(fp_line
			(start 1.3462 1.1938)
			(end 1.3462 -1.1938)
			(stroke
				(width 0.1524)
				(type default)
			)
			(layer "F.SilkS")
		)
		(fp_poly
			(pts
				(xy -1.447038 -0.760476) (xy -2.052066 -0.457962) (xy -2.052066 -1.06299)
			)
			(stroke
				(width 0)
				(type default)
			)
			(fill yes)
			(layer "F.SilkS")
		)
		(fp_line
			(start -0.674878 -1.124966)
			(end -0.674878 1.124966)
			(stroke
				(width 0.1)
				(type default)
			)
			(layer "F.Fab")
		)
		(fp_line
			(start -0.674878 1.124966)
			(end 0.674878 1.124966)
			(stroke
				(width 0.1)
				(type default)
			)
			(layer "F.Fab")
		)
		(fp_line
			(start 0.674878 -1.124966)
			(end -0.674878 -1.124966)
			(stroke
				(width 0.1)
				(type default)
			)
			(layer "F.Fab")
		)
		(fp_line
			(start 0.674878 1.124966)
			(end 0.674878 -1.124966)
			(stroke
				(width 0.1)
				(type default)
			)
			(layer "F.Fab")
		)
		(fp_poly
			(pts
				(xy -1.447038 -0.760476) (xy -2.052066 -0.457962) (xy -2.052066 -1.06299)
			)
			(stroke
				(width 0)
				(type default)
			)
			(fill yes)
			(layer "F.Fab")
		)
		(pad "1" smd rect
			(at -0.899922 -0.750062)
			(size 0.6096 0.6096)
			(layers "F.Cu" "F.Mask" "F.Paste")
			(net "PWRGD_P3V3_SSD12_R")
		)
		(pad "2" smd rect
			(at -0.899922 0 90)
			(size 0.4064 0.6096)
			(layers "F.Cu" "F.Mask" "F.Paste")
			(net "RST_SMB_SSD12_N")
		)
		(pad "3" smd rect
			(at -0.899922 0.750062)
			(size 0.6096 0.6096)
			(layers "F.Cu" "F.Mask" "F.Paste")
			(net "GND")
		)
		(pad "4" smd rect
			(at 0.899922 0.750062)
			(size 0.6096 0.6096)
			(layers "F.Cu" "F.Mask" "F.Paste")
			(net "RST_SMB_SSD12_ISO_N")
		)
		(pad "5" smd rect
			(at 0.899922 -0.750062)
			(size 0.6096 0.6096)
			(layers "F.Cu" "F.Mask" "F.Paste")
			(net "P3V3_AUX")
		)
	)
	(footprint ""
		(layer "F.Cu")
		(at 425.653962 -83.932268 90)
		(property "Reference" "C962"
			(at 0 0 90)
			(layer "F.SilkS")
			(hide yes)
			(effects
				(font
					(size 1.27 1.27)
				)
			)
		)
		(property "Value" ""
			(at 0 0 90)
			(layer "F.Fab")
			(effects
				(font
					(size 1.27 1.27)
				)
			)
		)
		(duplicate_pad_numbers_are_jumpers no)
		(fp_line
			(start 0.7874 -0.4064)
			(end 0.7874 0.4064)
			(stroke
				(width 0.1524)
				(type default)
			)
			(layer "F.SilkS")
		)
		(fp_line
			(start -0.7874 -0.4064)
			(end 0.7874 -0.4064)
			(stroke
				(width 0.1524)
				(type default)
			)
			(layer "F.SilkS")
		)
		(fp_line
			(start 0.7874 0.4064)
			(end -0.7874 0.4064)
			(stroke
				(width 0.1524)
				(type default)
			)
			(layer "F.SilkS")
		)
		(fp_line
			(start -0.7874 0.4064)
			(end -0.7874 -0.4064)
			(stroke
				(width 0.1524)
				(type default)
			)
			(layer "F.SilkS")
		)
		(fp_line
			(start -0.12065 -0.305054)
			(end -0.12065 -0.2794)
			(stroke
				(width 0.1)
				(type default)
			)
			(layer "F.Fab")
		)
		(fp_line
			(start -0.67945 -0.305054)
			(end -0.12065 -0.305054)
			(stroke
				(width 0.1)
				(type default)
			)
			(layer "F.Fab")
		)
		(fp_line
			(start 0.67945 -0.3048)
			(end 0.67945 0.3048)
			(stroke
				(width 0.1)
				(type default)
			)
			(layer "F.Fab")
		)
		(fp_line
			(start 0.12065 -0.3048)
			(end 0.67945 -0.3048)
			(stroke
				(width 0.1)
				(type default)
			)
			(layer "F.Fab")
		)
		(fp_line
			(start 0.12065 -0.2794)
			(end 0.12065 -0.3048)
			(stroke
				(width 0.1)
				(type default)
			)
			(layer "F.Fab")
		)
		(fp_line
			(start -0.12065 -0.2794)
			(end 0.12065 -0.2794)
			(stroke
				(width 0.1)
				(type default)
			)
			(layer "F.Fab")
		)
		(fp_line
			(start 0.120396 0.2794)
			(end -0.12065 0.2794)
			(stroke
				(width 0.1)
				(type default)
			)
			(layer "F.Fab")
		)
		(fp_line
			(start -0.12065 0.2794)
			(end -0.12065 0.3048)
			(stroke
				(width 0.1)
				(type default)
			)
			(layer "F.Fab")
		)
		(fp_line
			(start 0.67945 0.3048)
			(end 0.120396 0.3048)
			(stroke
				(width 0.1)
				(type default)
			)
			(layer "F.Fab")
		)
		(fp_line
			(start 0.120396 0.3048)
			(end 0.120396 0.2794)
			(stroke
				(width 0.1)
				(type default)
			)
			(layer "F.Fab")
		)
		(fp_line
			(start -0.12065 0.3048)
			(end -0.67945 0.3048)
			(stroke
				(width 0.1)
				(type default)
			)
			(layer "F.Fab")
		)
		(fp_line
			(start -0.67945 0.3048)
			(end -0.67945 -0.305054)
			(stroke
				(width 0.1)
				(type default)
			)
			(layer "F.Fab")
		)
		(pad "1" smd circle
			(at -0.40005 0 90)
			(size 0 0)
			(layers "F.Cu" "F.Mask" "F.Paste")
			(net "P3V3_AUX")
		)
		(pad "2" smd circle
			(at 0.40005 0 90)
			(size 0 0)
			(layers "F.Cu" "F.Mask" "F.Paste")
			(net "GND")
		)
	)
	(footprint ""
		(layer "F.Cu")
		(at 154.882596 -141.87297)
		(property "Reference" "R134"
			(at 0 0 0)
			(layer "F.SilkS")
			(hide yes)
			(effects
				(font
					(size 1.27 1.27)
				)
			)
		)
		(property "Value" ""
			(at 0 0 0)
			(layer "F.Fab")
			(effects
				(font
					(size 1.27 1.27)
				)
			)
		)
		(duplicate_pad_numbers_are_jumpers no)
		(fp_line
			(start -0.7874 -0.4064)
			(end 0.7874 -0.4064)
			(stroke
				(width 0.1524)
				(type default)
			)
			(layer "F.SilkS")
		)
		(fp_line
			(start -0.7874 0.4064)
			(end -0.7874 -0.4064)
			(stroke
				(width 0.1524)
				(type default)
			)
			(layer "F.SilkS")
		)
		(fp_line
			(start 0.7874 -0.4064)
			(end 0.7874 0.4064)
			(stroke
				(width 0.1524)
				(type default)
			)
			(layer "F.SilkS")
		)
		(fp_line
			(start 0.7874 0.4064)
			(end -0.7874 0.4064)
			(stroke
				(width 0.1524)
				(type default)
			)
			(layer "F.SilkS")
		)
		(fp_line
			(start -0.67945 -0.305054)
			(end -0.12065 -0.305054)
			(stroke
				(width 0.1)
				(type default)
			)
			(layer "F.Fab")
		)
		(fp_line
			(start -0.67945 0.3048)
			(end -0.67945 -0.305054)
			(stroke
				(width 0.1)
				(type default)
			)
			(layer "F.Fab")
		)
		(fp_line
			(start -0.12065 -0.305054)
			(end -0.12065 -0.2794)
			(stroke
				(width 0.1)
				(type default)
			)
			(layer "F.Fab")
		)
		(fp_line
			(start -0.12065 -0.2794)
			(end 0.12065 -0.2794)
			(stroke
				(width 0.1)
				(type default)
			)
			(layer "F.Fab")
		)
		(fp_line
			(start -0.12065 0.2794)
			(end -0.12065 0.3048)
			(stroke
				(width 0.1)
				(type default)
			)
			(layer "F.Fab")
		)
		(fp_line
			(start -0.12065 0.3048)
			(end -0.67945 0.3048)
			(stroke
				(width 0.1)
				(type default)
			)
			(layer "F.Fab")
		)
		(fp_line
			(start 0.120396 0.2794)
			(end -0.12065 0.2794)
			(stroke
				(width 0.1)
				(type default)
			)
			(layer "F.Fab")
		)
		(fp_line
			(start 0.120396 0.3048)
			(end 0.120396 0.2794)
			(stroke
				(width 0.1)
				(type default)
			)
			(layer "F.Fab")
		)
		(fp_line
			(start 0.12065 -0.3048)
			(end 0.67945 -0.3048)
			(stroke
				(width 0.1)
				(type default)
			)
			(layer "F.Fab")
		)
		(fp_line
			(start 0.12065 -0.2794)
			(end 0.12065 -0.3048)
			(stroke
				(width 0.1)
				(type default)
			)
			(layer "F.Fab")
		)
		(fp_line
			(start 0.67945 -0.3048)
			(end 0.67945 0.3048)
			(stroke
				(width 0.1)
				(type default)
			)
			(layer "F.Fab")
		)
		(fp_line
			(start 0.67945 0.3048)
			(end 0.120396 0.3048)
			(stroke
				(width 0.1)
				(type default)
			)
			(layer "F.Fab")
		)
		(pad "1" smd circle
			(at -0.40005 0)
			(size 0 0)
			(layers "F.Cu" "F.Mask" "F.Paste")
			(net "NIC2_BIF1_N")
		)
		(pad "2" smd circle
			(at 0.40005 0)
			(size 0 0)
			(layers "F.Cu" "F.Mask" "F.Paste")
			(net "GND")
		)
	)
	(footprint ""
		(layer "F.Cu")
		(at 367.954814 -22.867366 90)
		(property "Reference" "C3962"
			(at 0 0 90)
			(layer "F.SilkS")
			(hide yes)
			(effects
				(font
					(size 1.27 1.27)
				)
			)
		)
		(property "Value" ""
			(at 0 0 90)
			(layer "F.Fab")
			(effects
				(font
					(size 1.27 1.27)
				)
			)
		)
		(duplicate_pad_numbers_are_jumpers no)
		(fp_line
			(start 0.7874 -0.4064)
			(end 0.7874 0.4064)
			(stroke
				(width 0.1524)
				(type default)
			)
			(layer "F.SilkS")
		)
		(fp_line
			(start -0.7874 -0.4064)
			(end 0.7874 -0.4064)
			(stroke
				(width 0.1524)
				(type default)
			)
			(layer "F.SilkS")
		)
		(fp_line
			(start 0.7874 0.4064)
			(end -0.7874 0.4064)
			(stroke
				(width 0.1524)
				(type default)
			)
			(layer "F.SilkS")
		)
		(fp_line
			(start -0.7874 0.4064)
			(end -0.7874 -0.4064)
			(stroke
				(width 0.1524)
				(type default)
			)
			(layer "F.SilkS")
		)
		(fp_line
			(start -0.12065 -0.305054)
			(end -0.12065 -0.2794)
			(stroke
				(width 0.1)
				(type default)
			)
			(layer "F.Fab")
		)
		(fp_line
			(start -0.67945 -0.305054)
			(end -0.12065 -0.305054)
			(stroke
				(width 0.1)
				(type default)
			)
			(layer "F.Fab")
		)
		(fp_line
			(start 0.67945 -0.3048)
			(end 0.67945 0.3048)
			(stroke
				(width 0.1)
				(type default)
			)
			(layer "F.Fab")
		)
		(fp_line
			(start 0.12065 -0.3048)
			(end 0.67945 -0.3048)
			(stroke
				(width 0.1)
				(type default)
			)
			(layer "F.Fab")
		)
		(fp_line
			(start 0.12065 -0.2794)
			(end 0.12065 -0.3048)
			(stroke
				(width 0.1)
				(type default)
			)
			(layer "F.Fab")
		)
		(fp_line
			(start -0.12065 -0.2794)
			(end 0.12065 -0.2794)
			(stroke
				(width 0.1)
				(type default)
			)
			(layer "F.Fab")
		)
		(fp_line
			(start 0.120396 0.2794)
			(end -0.12065 0.2794)
			(stroke
				(width 0.1)
				(type default)
			)
			(layer "F.Fab")
		)
		(fp_line
			(start -0.12065 0.2794)
			(end -0.12065 0.3048)
			(stroke
				(width 0.1)
				(type default)
			)
			(layer "F.Fab")
		)
		(fp_line
			(start 0.67945 0.3048)
			(end 0.120396 0.3048)
			(stroke
				(width 0.1)
				(type default)
			)
			(layer "F.Fab")
		)
		(fp_line
			(start 0.120396 0.3048)
			(end 0.120396 0.2794)
			(stroke
				(width 0.1)
				(type default)
			)
			(layer "F.Fab")
		)
		(fp_line
			(start -0.12065 0.3048)
			(end -0.67945 0.3048)
			(stroke
				(width 0.1)
				(type default)
			)
			(layer "F.Fab")
		)
		(fp_line
			(start -0.67945 0.3048)
			(end -0.67945 -0.305054)
			(stroke
				(width 0.1)
				(type default)
			)
			(layer "F.Fab")
		)
		(pad "1" smd circle
			(at -0.40005 0 90)
			(size 0 0)
			(layers "F.Cu" "F.Mask" "F.Paste")
			(net "P12V_SSD12")
		)
		(pad "2" smd circle
			(at 0.40005 0 90)
			(size 0 0)
			(layers "F.Cu" "F.Mask" "F.Paste")
			(net "GND")
		)
	)
	(footprint ""
		(layer "F.Cu")
		(at 421.58285 -80.739742)
		(property "Reference" "R407"
			(at 0 0 0)
			(layer "F.SilkS")
			(hide yes)
			(effects
				(font
					(size 1.27 1.27)
				)
			)
		)
		(property "Value" ""
			(at 0 0 0)
			(layer "F.Fab")
			(effects
				(font
					(size 1.27 1.27)
				)
			)
		)
		(duplicate_pad_numbers_are_jumpers no)
		(fp_line
			(start -0.7874 -0.4064)
			(end 0.7874 -0.4064)
			(stroke
				(width 0.1524)
				(type default)
			)
			(layer "F.SilkS")
		)
		(fp_line
			(start -0.7874 0.4064)
			(end -0.7874 -0.4064)
			(stroke
				(width 0.1524)
				(type default)
			)
			(layer "F.SilkS")
		)
		(fp_line
			(start 0.7874 -0.4064)
			(end 0.7874 0.4064)
			(stroke
				(width 0.1524)
				(type default)
			)
			(layer "F.SilkS")
		)
		(fp_line
			(start 0.7874 0.4064)
			(end -0.7874 0.4064)
			(stroke
				(width 0.1524)
				(type default)
			)
			(layer "F.SilkS")
		)
		(fp_line
			(start -0.67945 -0.305054)
			(end -0.12065 -0.305054)
			(stroke
				(width 0.1)
				(type default)
			)
			(layer "F.Fab")
		)
		(fp_line
			(start -0.67945 0.3048)
			(end -0.67945 -0.305054)
			(stroke
				(width 0.1)
				(type default)
			)
			(layer "F.Fab")
		)
		(fp_line
			(start -0.12065 -0.305054)
			(end -0.12065 -0.2794)
			(stroke
				(width 0.1)
				(type default)
			)
			(layer "F.Fab")
		)
		(fp_line
			(start -0.12065 -0.2794)
			(end 0.12065 -0.2794)
			(stroke
				(width 0.1)
				(type default)
			)
			(layer "F.Fab")
		)
		(fp_line
			(start -0.12065 0.2794)
			(end -0.12065 0.3048)
			(stroke
				(width 0.1)
				(type default)
			)
			(layer "F.Fab")
		)
		(fp_line
			(start -0.12065 0.3048)
			(end -0.67945 0.3048)
			(stroke
				(width 0.1)
				(type default)
			)
			(layer "F.Fab")
		)
		(fp_line
			(start 0.120396 0.2794)
			(end -0.12065 0.2794)
			(stroke
				(width 0.1)
				(type default)
			)
			(layer "F.Fab")
		)
		(fp_line
			(start 0.120396 0.3048)
			(end 0.120396 0.2794)
			(stroke
				(width 0.1)
				(type default)
			)
			(layer "F.Fab")
		)
		(fp_line
			(start 0.12065 -0.3048)
			(end 0.67945 -0.3048)
			(stroke
				(width 0.1)
				(type default)
			)
			(layer "F.Fab")
		)
		(fp_line
			(start 0.12065 -0.2794)
			(end 0.12065 -0.3048)
			(stroke
				(width 0.1)
				(type default)
			)
			(layer "F.Fab")
		)
		(fp_line
			(start 0.67945 -0.3048)
			(end 0.67945 0.3048)
			(stroke
				(width 0.1)
				(type default)
			)
			(layer "F.Fab")
		)
		(fp_line
			(start 0.67945 0.3048)
			(end 0.120396 0.3048)
			(stroke
				(width 0.1)
				(type default)
			)
			(layer "F.Fab")
		)
		(pad "1" smd circle
			(at -0.40005 0)
			(size 0 0)
			(layers "F.Cu" "F.Mask" "F.Paste")
			(net "P3V3_AUX")
		)
		(pad "2" smd circle
			(at 0.40005 0)
			(size 0 0)
			(layers "F.Cu" "F.Mask" "F.Paste")
			(net "HP_NIC7_HSC_PWRGD_N")
		)
	)
	(footprint ""
		(layer "F.Cu")
		(at 384.612134 -137.2489 -90)
		(property "Reference" "C949"
			(at 0 0 270)
			(layer "F.SilkS")
			(hide yes)
			(effects
				(font
					(size 1.27 1.27)
				)
			)
		)
		(property "Value" ""
			(at 0 0 270)
			(layer "F.Fab")
			(effects
				(font
					(size 1.27 1.27)
				)
			)
		)
		(duplicate_pad_numbers_are_jumpers no)
		(fp_line
			(start -0.7874 0.4064)
			(end -0.7874 -0.4064)
			(stroke
				(width 0.1524)
				(type default)
			)
			(layer "F.SilkS")
		)
		(fp_line
			(start 0.7874 0.4064)
			(end -0.7874 0.4064)
			(stroke
				(width 0.1524)
				(type default)
			)
			(layer "F.SilkS")
		)
		(fp_line
			(start -0.7874 -0.4064)
			(end 0.7874 -0.4064)
			(stroke
				(width 0.1524)
				(type default)
			)
			(layer "F.SilkS")
		)
		(fp_line
			(start 0.7874 -0.4064)
			(end 0.7874 0.4064)
			(stroke
				(width 0.1524)
				(type default)
			)
			(layer "F.SilkS")
		)
		(fp_line
			(start -0.67945 0.3048)
			(end -0.67945 -0.305054)
			(stroke
				(width 0.1)
				(type default)
			)
			(layer "F.Fab")
		)
		(fp_line
			(start -0.12065 0.3048)
			(end -0.67945 0.3048)
			(stroke
				(width 0.1)
				(type default)
			)
			(layer "F.Fab")
		)
		(fp_line
			(start 0.120396 0.3048)
			(end 0.120396 0.2794)
			(stroke
				(width 0.1)
				(type default)
			)
			(layer "F.Fab")
		)
		(fp_line
			(start 0.67945 0.3048)
			(end 0.120396 0.3048)
			(stroke
				(width 0.1)
				(type default)
			)
			(layer "F.Fab")
		)
		(fp_line
			(start -0.12065 0.2794)
			(end -0.12065 0.3048)
			(stroke
				(width 0.1)
				(type default)
			)
			(layer "F.Fab")
		)
		(fp_line
			(start 0.120396 0.2794)
			(end -0.12065 0.2794)
			(stroke
				(width 0.1)
				(type default)
			)
			(layer "F.Fab")
		)
		(fp_line
			(start -0.12065 -0.2794)
			(end 0.12065 -0.2794)
			(stroke
				(width 0.1)
				(type default)
			)
			(layer "F.Fab")
		)
		(fp_line
			(start 0.12065 -0.2794)
			(end 0.12065 -0.3048)
			(stroke
				(width 0.1)
				(type default)
			)
			(layer "F.Fab")
		)
		(fp_line
			(start 0.12065 -0.3048)
			(end 0.67945 -0.3048)
			(stroke
				(width 0.1)
				(type default)
			)
			(layer "F.Fab")
		)
		(fp_line
			(start 0.67945 -0.3048)
			(end 0.67945 0.3048)
			(stroke
				(width 0.1)
				(type default)
			)
			(layer "F.Fab")
		)
		(fp_line
			(start -0.67945 -0.305054)
			(end -0.12065 -0.305054)
			(stroke
				(width 0.1)
				(type default)
			)
			(layer "F.Fab")
		)
		(fp_line
			(start -0.12065 -0.305054)
			(end -0.12065 -0.2794)
			(stroke
				(width 0.1)
				(type default)
			)
			(layer "F.Fab")
		)
		(pad "1" smd circle
			(at -0.40005 0 270)
			(size 0 0)
			(layers "F.Cu" "F.Mask" "F.Paste")
			(net "P3V3_NIC6")
		)
		(pad "2" smd circle
			(at 0.40005 0 270)
			(size 0 0)
			(layers "F.Cu" "F.Mask" "F.Paste")
			(net "GND")
		)
	)
	(footprint ""
		(layer "F.Cu")
		(at 80.019398 -154.304746 180)
		(property "Reference" "C3"
			(at 0 0 180)
			(layer "F.SilkS")
			(hide yes)
			(effects
				(font
					(size 1.27 1.27)
				)
			)
		)
		(property "Value" ""
			(at 0 0 180)
			(layer "F.Fab")
			(effects
				(font
					(size 1.27 1.27)
				)
			)
		)
		(duplicate_pad_numbers_are_jumpers no)
		(fp_line
			(start 0.299974 0.150114)
			(end -0.299974 0.150114)
			(stroke
				(width 0.1)
				(type default)
			)
			(layer "F.Fab")
		)
		(fp_line
			(start 0.299974 -0.150114)
			(end 0.299974 0.150114)
			(stroke
				(width 0.1)
				(type default)
			)
			(layer "F.Fab")
		)
		(fp_line
			(start -0.299974 0.150114)
			(end -0.299974 -0.150114)
			(stroke
				(width 0.1)
				(type default)
			)
			(layer "F.Fab")
		)
		(fp_line
			(start -0.299974 -0.150114)
			(end 0.299974 -0.150114)
			(stroke
				(width 0.1)
				(type default)
			)
			(layer "F.Fab")
		)
		(pad "1" smd rect
			(at -0.2667 0 180)
			(size 0.3048 0.381)
			(layers "F.Cu" "F.Mask" "F.Paste")
			(net "P5E_PEX0_STN0_TX_DN<14>")
		)
		(pad "2" smd rect
			(at 0.2667 0 180)
			(size 0.3048 0.381)
			(layers "F.Cu" "F.Mask" "F.Paste")
			(net "P5E_PEX0_STN0_TX_C_DN<14>")
		)
	)
	(footprint ""
		(layer "F.Cu")
		(at 304.634392 -33.631886 180)
		(property "Reference" "C504"
			(at 0 0 180)
			(layer "F.SilkS")
			(hide yes)
			(effects
				(font
					(size 1.27 1.27)
				)
			)
		)
		(property "Value" ""
			(at 0 0 180)
			(layer "F.Fab")
			(effects
				(font
					(size 1.27 1.27)
				)
			)
		)
		(duplicate_pad_numbers_are_jumpers no)
		(fp_line
			(start 0.299974 0.150114)
			(end -0.299974 0.150114)
			(stroke
				(width 0.1)
				(type default)
			)
			(layer "F.Fab")
		)
		(fp_line
			(start 0.299974 -0.150114)
			(end 0.299974 0.150114)
			(stroke
				(width 0.1)
				(type default)
			)
			(layer "F.Fab")
		)
		(fp_line
			(start -0.299974 0.150114)
			(end -0.299974 -0.150114)
			(stroke
				(width 0.1)
				(type default)
			)
			(layer "F.Fab")
		)
		(fp_line
			(start -0.299974 -0.150114)
			(end 0.299974 -0.150114)
			(stroke
				(width 0.1)
				(type default)
			)
			(layer "F.Fab")
		)
		(pad "1" smd rect
			(at -0.2667 0 180)
			(size 0.3048 0.381)
			(layers "F.Cu" "F.Mask" "F.Paste")
			(net "P5E_PEX2_STN2_TX_DN<39>")
		)
		(pad "2" smd rect
			(at 0.2667 0 180)
			(size 0.3048 0.381)
			(layers "F.Cu" "F.Mask" "F.Paste")
			(net "P5E_PEX2_STN2_TX_C_DN<39>")
		)
	)
	(footprint ""
		(layer "F.Cu")
		(at 45.654722 -22.867366 90)
		(property "Reference" "C3880"
			(at 0 0 90)
			(layer "F.SilkS")
			(hide yes)
			(effects
				(font
					(size 1.27 1.27)
				)
			)
		)
		(property "Value" ""
			(at 0 0 90)
			(layer "F.Fab")
			(effects
				(font
					(size 1.27 1.27)
				)
			)
		)
		(duplicate_pad_numbers_are_jumpers no)
		(fp_line
			(start 0.7874 -0.4064)
			(end 0.7874 0.4064)
			(stroke
				(width 0.1524)
				(type default)
			)
			(layer "F.SilkS")
		)
		(fp_line
			(start -0.7874 -0.4064)
			(end 0.7874 -0.4064)
			(stroke
				(width 0.1524)
				(type default)
			)
			(layer "F.SilkS")
		)
		(fp_line
			(start 0.7874 0.4064)
			(end -0.7874 0.4064)
			(stroke
				(width 0.1524)
				(type default)
			)
			(layer "F.SilkS")
		)
		(fp_line
			(start -0.7874 0.4064)
			(end -0.7874 -0.4064)
			(stroke
				(width 0.1524)
				(type default)
			)
			(layer "F.SilkS")
		)
		(fp_line
			(start -0.12065 -0.305054)
			(end -0.12065 -0.2794)
			(stroke
				(width 0.1)
				(type default)
			)
			(layer "F.Fab")
		)
		(fp_line
			(start -0.67945 -0.305054)
			(end -0.12065 -0.305054)
			(stroke
				(width 0.1)
				(type default)
			)
			(layer "F.Fab")
		)
		(fp_line
			(start 0.67945 -0.3048)
			(end 0.67945 0.3048)
			(stroke
				(width 0.1)
				(type default)
			)
			(layer "F.Fab")
		)
		(fp_line
			(start 0.12065 -0.3048)
			(end 0.67945 -0.3048)
			(stroke
				(width 0.1)
				(type default)
			)
			(layer "F.Fab")
		)
		(fp_line
			(start 0.12065 -0.2794)
			(end 0.12065 -0.3048)
			(stroke
				(width 0.1)
				(type default)
			)
			(layer "F.Fab")
		)
		(fp_line
			(start -0.12065 -0.2794)
			(end 0.12065 -0.2794)
			(stroke
				(width 0.1)
				(type default)
			)
			(layer "F.Fab")
		)
		(fp_line
			(start 0.120396 0.2794)
			(end -0.12065 0.2794)
			(stroke
				(width 0.1)
				(type default)
			)
			(layer "F.Fab")
		)
		(fp_line
			(start -0.12065 0.2794)
			(end -0.12065 0.3048)
			(stroke
				(width 0.1)
				(type default)
			)
			(layer "F.Fab")
		)
		(fp_line
			(start 0.67945 0.3048)
			(end 0.120396 0.3048)
			(stroke
				(width 0.1)
				(type default)
			)
			(layer "F.Fab")
		)
		(fp_line
			(start 0.120396 0.3048)
			(end 0.120396 0.2794)
			(stroke
				(width 0.1)
				(type default)
			)
			(layer "F.Fab")
		)
		(fp_line
			(start -0.12065 0.3048)
			(end -0.67945 0.3048)
			(stroke
				(width 0.1)
				(type default)
			)
			(layer "F.Fab")
		)
		(fp_line
			(start -0.67945 0.3048)
			(end -0.67945 -0.305054)
			(stroke
				(width 0.1)
				(type default)
			)
			(layer "F.Fab")
		)
		(pad "1" smd circle
			(at -0.40005 0 90)
			(size 0 0)
			(layers "F.Cu" "F.Mask" "F.Paste")
			(net "P12V_SSD1")
		)
		(pad "2" smd circle
			(at 0.40005 0 90)
			(size 0 0)
			(layers "F.Cu" "F.Mask" "F.Paste")
			(net "GND")
		)
	)
	(footprint ""
		(layer "F.Cu")
		(at 224.46996 -105.477056)
		(property "Reference" "PC344"
			(at 0 0 0)
			(layer "F.SilkS")
			(hide yes)
			(effects
				(font
					(size 1.27 1.27)
				)
			)
		)
		(property "Value" ""
			(at 0 0 0)
			(layer "F.Fab")
			(effects
				(font
					(size 1.27 1.27)
				)
			)
		)
		(duplicate_pad_numbers_are_jumpers no)
		(fp_line
			(start -0.7874 -0.4064)
			(end 0.7874 -0.4064)
			(stroke
				(width 0.1524)
				(type default)
			)
			(layer "F.SilkS")
		)
		(fp_line
			(start -0.7874 0.4064)
			(end -0.7874 -0.4064)
			(stroke
				(width 0.1524)
				(type default)
			)
			(layer "F.SilkS")
		)
		(fp_line
			(start 0.7874 -0.4064)
			(end 0.7874 0.4064)
			(stroke
				(width 0.1524)
				(type default)
			)
			(layer "F.SilkS")
		)
		(fp_line
			(start 0.7874 0.4064)
			(end -0.7874 0.4064)
			(stroke
				(width 0.1524)
				(type default)
			)
			(layer "F.SilkS")
		)
		(fp_line
			(start -0.67945 -0.305054)
			(end -0.12065 -0.305054)
			(stroke
				(width 0.1)
				(type default)
			)
			(layer "F.Fab")
		)
		(fp_line
			(start -0.67945 0.3048)
			(end -0.67945 -0.305054)
			(stroke
				(width 0.1)
				(type default)
			)
			(layer "F.Fab")
		)
		(fp_line
			(start -0.12065 -0.305054)
			(end -0.12065 -0.2794)
			(stroke
				(width 0.1)
				(type default)
			)
			(layer "F.Fab")
		)
		(fp_line
			(start -0.12065 -0.2794)
			(end 0.12065 -0.2794)
			(stroke
				(width 0.1)
				(type default)
			)
			(layer "F.Fab")
		)
		(fp_line
			(start -0.12065 0.2794)
			(end -0.12065 0.3048)
			(stroke
				(width 0.1)
				(type default)
			)
			(layer "F.Fab")
		)
		(fp_line
			(start -0.12065 0.3048)
			(end -0.67945 0.3048)
			(stroke
				(width 0.1)
				(type default)
			)
			(layer "F.Fab")
		)
		(fp_line
			(start 0.120396 0.2794)
			(end -0.12065 0.2794)
			(stroke
				(width 0.1)
				(type default)
			)
			(layer "F.Fab")
		)
		(fp_line
			(start 0.120396 0.3048)
			(end 0.120396 0.2794)
			(stroke
				(width 0.1)
				(type default)
			)
			(layer "F.Fab")
		)
		(fp_line
			(start 0.12065 -0.3048)
			(end 0.67945 -0.3048)
			(stroke
				(width 0.1)
				(type default)
			)
			(layer "F.Fab")
		)
		(fp_line
			(start 0.12065 -0.2794)
			(end 0.12065 -0.3048)
			(stroke
				(width 0.1)
				(type default)
			)
			(layer "F.Fab")
		)
		(fp_line
			(start 0.67945 -0.3048)
			(end 0.67945 0.3048)
			(stroke
				(width 0.1)
				(type default)
			)
			(layer "F.Fab")
		)
		(fp_line
			(start 0.67945 0.3048)
			(end 0.120396 0.3048)
			(stroke
				(width 0.1)
				(type default)
			)
			(layer "F.Fab")
		)
		(pad "1" smd circle
			(at -0.40005 0)
			(size 0 0)
			(layers "F.Cu" "F.Mask" "F.Paste")
			(net "P12V_NIC3_R")
		)
		(pad "2" smd circle
			(at 0.40005 0)
			(size 0 0)
			(layers "F.Cu" "F.Mask" "F.Paste")
			(net "GND")
		)
	)
	(footprint ""
		(layer "F.Cu")
		(at 434.071776 -24.807418)
		(property "Reference" "R456"
			(at 0 0 0)
			(layer "F.SilkS")
			(hide yes)
			(effects
				(font
					(size 1.27 1.27)
				)
			)
		)
		(property "Value" ""
			(at 0 0 0)
			(layer "F.Fab")
			(effects
				(font
					(size 1.27 1.27)
				)
			)
		)
		(duplicate_pad_numbers_are_jumpers no)
		(fp_line
			(start -0.7874 -0.4064)
			(end 0.7874 -0.4064)
			(stroke
				(width 0.1524)
				(type default)
			)
			(layer "F.SilkS")
		)
		(fp_line
			(start -0.7874 0.4064)
			(end -0.7874 -0.4064)
			(stroke
				(width 0.1524)
				(type default)
			)
			(layer "F.SilkS")
		)
		(fp_line
			(start 0.7874 -0.4064)
			(end 0.7874 0.4064)
			(stroke
				(width 0.1524)
				(type default)
			)
			(layer "F.SilkS")
		)
		(fp_line
			(start 0.7874 0.4064)
			(end -0.7874 0.4064)
			(stroke
				(width 0.1524)
				(type default)
			)
			(layer "F.SilkS")
		)
		(fp_line
			(start -0.67945 -0.305054)
			(end -0.12065 -0.305054)
			(stroke
				(width 0.1)
				(type default)
			)
			(layer "F.Fab")
		)
		(fp_line
			(start -0.67945 0.3048)
			(end -0.67945 -0.305054)
			(stroke
				(width 0.1)
				(type default)
			)
			(layer "F.Fab")
		)
		(fp_line
			(start -0.12065 -0.305054)
			(end -0.12065 -0.2794)
			(stroke
				(width 0.1)
				(type default)
			)
			(layer "F.Fab")
		)
		(fp_line
			(start -0.12065 -0.2794)
			(end 0.12065 -0.2794)
			(stroke
				(width 0.1)
				(type default)
			)
			(layer "F.Fab")
		)
		(fp_line
			(start -0.12065 0.2794)
			(end -0.12065 0.3048)
			(stroke
				(width 0.1)
				(type default)
			)
			(layer "F.Fab")
		)
		(fp_line
			(start -0.12065 0.3048)
			(end -0.67945 0.3048)
			(stroke
				(width 0.1)
				(type default)
			)
			(layer "F.Fab")
		)
		(fp_line
			(start 0.120396 0.2794)
			(end -0.12065 0.2794)
			(stroke
				(width 0.1)
				(type default)
			)
			(layer "F.Fab")
		)
		(fp_line
			(start 0.120396 0.3048)
			(end 0.120396 0.2794)
			(stroke
				(width 0.1)
				(type default)
			)
			(layer "F.Fab")
		)
		(fp_line
			(start 0.12065 -0.3048)
			(end 0.67945 -0.3048)
			(stroke
				(width 0.1)
				(type default)
			)
			(layer "F.Fab")
		)
		(fp_line
			(start 0.12065 -0.2794)
			(end 0.12065 -0.3048)
			(stroke
				(width 0.1)
				(type default)
			)
			(layer "F.Fab")
		)
		(fp_line
			(start 0.67945 -0.3048)
			(end 0.67945 0.3048)
			(stroke
				(width 0.1)
				(type default)
			)
			(layer "F.Fab")
		)
		(fp_line
			(start 0.67945 0.3048)
			(end 0.120396 0.3048)
			(stroke
				(width 0.1)
				(type default)
			)
			(layer "F.Fab")
		)
		(pad "1" smd circle
			(at -0.40005 0)
			(size 0 0)
			(layers "F.Cu" "F.Mask" "F.Paste")
			(net "P3V3_SSD15")
		)
		(pad "2" smd circle
			(at 0.40005 0)
			(size 0 0)
			(layers "F.Cu" "F.Mask" "F.Paste")
			(net "PU_CLKREQ15")
		)
	)
	(footprint ""
		(layer "F.Cu")
		(at 239.935512 -234.728004 -90)
		(property "Reference" "R6183"
			(at 0 0 270)
			(layer "F.SilkS")
			(hide yes)
			(effects
				(font
					(size 1.27 1.27)
				)
			)
		)
		(property "Value" ""
			(at 0 0 270)
			(layer "F.Fab")
			(effects
				(font
					(size 1.27 1.27)
				)
			)
		)
		(duplicate_pad_numbers_are_jumpers no)
		(fp_line
			(start -0.7874 0.4064)
			(end -0.7874 -0.4064)
			(stroke
				(width 0.1524)
				(type default)
			)
			(layer "F.SilkS")
		)
		(fp_line
			(start 0.7874 0.4064)
			(end -0.7874 0.4064)
			(stroke
				(width 0.1524)
				(type default)
			)
			(layer "F.SilkS")
		)
		(fp_line
			(start -0.7874 -0.4064)
			(end 0.7874 -0.4064)
			(stroke
				(width 0.1524)
				(type default)
			)
			(layer "F.SilkS")
		)
		(fp_line
			(start 0.7874 -0.4064)
			(end 0.7874 0.4064)
			(stroke
				(width 0.1524)
				(type default)
			)
			(layer "F.SilkS")
		)
		(fp_line
			(start -0.67945 0.3048)
			(end -0.67945 -0.305054)
			(stroke
				(width 0.1)
				(type default)
			)
			(layer "F.Fab")
		)
		(fp_line
			(start -0.12065 0.3048)
			(end -0.67945 0.3048)
			(stroke
				(width 0.1)
				(type default)
			)
			(layer "F.Fab")
		)
		(fp_line
			(start 0.120396 0.3048)
			(end 0.120396 0.2794)
			(stroke
				(width 0.1)
				(type default)
			)
			(layer "F.Fab")
		)
		(fp_line
			(start 0.67945 0.3048)
			(end 0.120396 0.3048)
			(stroke
				(width 0.1)
				(type default)
			)
			(layer "F.Fab")
		)
		(fp_line
			(start -0.12065 0.2794)
			(end -0.12065 0.3048)
			(stroke
				(width 0.1)
				(type default)
			)
			(layer "F.Fab")
		)
		(fp_line
			(start 0.120396 0.2794)
			(end -0.12065 0.2794)
			(stroke
				(width 0.1)
				(type default)
			)
			(layer "F.Fab")
		)
		(fp_line
			(start -0.12065 -0.2794)
			(end 0.12065 -0.2794)
			(stroke
				(width 0.1)
				(type default)
			)
			(layer "F.Fab")
		)
		(fp_line
			(start 0.12065 -0.2794)
			(end 0.12065 -0.3048)
			(stroke
				(width 0.1)
				(type default)
			)
			(layer "F.Fab")
		)
		(fp_line
			(start 0.12065 -0.3048)
			(end 0.67945 -0.3048)
			(stroke
				(width 0.1)
				(type default)
			)
			(layer "F.Fab")
		)
		(fp_line
			(start 0.67945 -0.3048)
			(end 0.67945 0.3048)
			(stroke
				(width 0.1)
				(type default)
			)
			(layer "F.Fab")
		)
		(fp_line
			(start -0.67945 -0.305054)
			(end -0.12065 -0.305054)
			(stroke
				(width 0.1)
				(type default)
			)
			(layer "F.Fab")
		)
		(fp_line
			(start -0.12065 -0.305054)
			(end -0.12065 -0.2794)
			(stroke
				(width 0.1)
				(type default)
			)
			(layer "F.Fab")
		)
		(pad "1" smd circle
			(at -0.40005 0 270)
			(size 0 0)
			(layers "F.Cu" "F.Mask" "F.Paste")
			(net "GND")
		)
		(pad "2" smd circle
			(at 0.40005 0 270)
			(size 0 0)
			(layers "F.Cu" "F.Mask" "F.Paste")
			(net "SSD1_PWRDIS_BIC_R")
		)
	)
	(footprint ""
		(layer "F.Cu")
		(at 324.552564 -311.197244 135)
		(property "Reference" "R1382"
			(at 0 0 135)
			(layer "F.SilkS")
			(hide yes)
			(effects
				(font
					(size 1.27 1.27)
				)
			)
		)
		(property "Value" ""
			(at 0 0 135)
			(layer "F.Fab")
			(effects
				(font
					(size 1.27 1.27)
				)
			)
		)
		(duplicate_pad_numbers_are_jumpers no)
		(fp_line
			(start 0.787389 -0.406267)
			(end 0.787389 0.406267)
			(stroke
				(width 0.1524)
				(type default)
			)
			(layer "F.SilkS")
		)
		(fp_line
			(start 0.787389 0.406267)
			(end -0.787389 0.406267)
			(stroke
				(width 0.1524)
				(type default)
			)
			(layer "F.SilkS")
		)
		(fp_line
			(start -0.787389 -0.406267)
			(end 0.787389 -0.406267)
			(stroke
				(width 0.1524)
				(type default)
			)
			(layer "F.SilkS")
		)
		(fp_line
			(start -0.787389 0.406267)
			(end -0.787389 -0.406267)
			(stroke
				(width 0.1524)
				(type default)
			)
			(layer "F.SilkS")
		)
		(fp_line
			(start 0.679446 -0.30479)
			(end 0.679446 0.30479)
			(stroke
				(width 0.1)
				(type default)
			)
			(layer "F.Fab")
		)
		(fp_line
			(start 0.120515 -0.30479)
			(end 0.679446 -0.30479)
			(stroke
				(width 0.1)
				(type default)
			)
			(layer "F.Fab")
		)
		(fp_line
			(start 0.120695 -0.279466)
			(end 0.120515 -0.30479)
			(stroke
				(width 0.1)
				(type default)
			)
			(layer "F.Fab")
		)
		(fp_line
			(start 0.679446 0.30479)
			(end 0.120515 0.30479)
			(stroke
				(width 0.1)
				(type default)
			)
			(layer "F.Fab")
		)
		(fp_line
			(start -0.120695 -0.304969)
			(end -0.120695 -0.279466)
			(stroke
				(width 0.1)
				(type default)
			)
			(layer "F.Fab")
		)
		(fp_line
			(start -0.120695 -0.279466)
			(end 0.120695 -0.279466)
			(stroke
				(width 0.1)
				(type default)
			)
			(layer "F.Fab")
		)
		(fp_line
			(start 0.120335 0.279466)
			(end -0.120695 0.279466)
			(stroke
				(width 0.1)
				(type default)
			)
			(layer "F.Fab")
		)
		(fp_line
			(start 0.120515 0.30479)
			(end 0.120335 0.279466)
			(stroke
				(width 0.1)
				(type default)
			)
			(layer "F.Fab")
		)
		(fp_line
			(start -0.679446 -0.305149)
			(end -0.120695 -0.304969)
			(stroke
				(width 0.1)
				(type default)
			)
			(layer "F.Fab")
		)
		(fp_line
			(start -0.120695 0.279466)
			(end -0.120515 0.30479)
			(stroke
				(width 0.1)
				(type default)
			)
			(layer "F.Fab")
		)
		(fp_line
			(start -0.120515 0.30479)
			(end -0.679446 0.30479)
			(stroke
				(width 0.1)
				(type default)
			)
			(layer "F.Fab")
		)
		(fp_line
			(start -0.679446 0.30479)
			(end -0.679446 -0.305149)
			(stroke
				(width 0.1)
				(type default)
			)
			(layer "F.Fab")
		)
		(pad "1" smd circle
			(at -0.40005 0 135)
			(size 0 0)
			(layers "F.Cu" "F.Mask" "F.Paste")
			(net "GND")
		)
		(pad "2" smd circle
			(at 0.40005 0 135)
			(size 0 0)
			(layers "F.Cu" "F.Mask" "F.Paste")
			(net "PEX2_SPARE5")
		)
	)
	(footprint ""
		(layer "F.Cu")
		(at 320.167 -83.058)
		(property "Reference" "C3992"
			(at 0 0 0)
			(layer "F.SilkS")
			(hide yes)
			(effects
				(font
					(size 1.27 1.27)
				)
			)
		)
		(property "Value" ""
			(at 0 0 0)
			(layer "F.Fab")
			(effects
				(font
					(size 1.27 1.27)
				)
			)
		)
		(duplicate_pad_numbers_are_jumpers no)
		(fp_line
			(start -0.7874 -0.4064)
			(end 0.7874 -0.4064)
			(stroke
				(width 0.1524)
				(type default)
			)
			(layer "F.SilkS")
		)
		(fp_line
			(start -0.7874 0.4064)
			(end -0.7874 -0.4064)
			(stroke
				(width 0.1524)
				(type default)
			)
			(layer "F.SilkS")
		)
		(fp_line
			(start 0.7874 -0.4064)
			(end 0.7874 0.4064)
			(stroke
				(width 0.1524)
				(type default)
			)
			(layer "F.SilkS")
		)
		(fp_line
			(start 0.7874 0.4064)
			(end -0.7874 0.4064)
			(stroke
				(width 0.1524)
				(type default)
			)
			(layer "F.SilkS")
		)
		(fp_line
			(start -0.67945 -0.305054)
			(end -0.12065 -0.305054)
			(stroke
				(width 0.1)
				(type default)
			)
			(layer "F.Fab")
		)
		(fp_line
			(start -0.67945 0.3048)
			(end -0.67945 -0.305054)
			(stroke
				(width 0.1)
				(type default)
			)
			(layer "F.Fab")
		)
		(fp_line
			(start -0.12065 -0.305054)
			(end -0.12065 -0.2794)
			(stroke
				(width 0.1)
				(type default)
			)
			(layer "F.Fab")
		)
		(fp_line
			(start -0.12065 -0.2794)
			(end 0.12065 -0.2794)
			(stroke
				(width 0.1)
				(type default)
			)
			(layer "F.Fab")
		)
		(fp_line
			(start -0.12065 0.2794)
			(end -0.12065 0.3048)
			(stroke
				(width 0.1)
				(type default)
			)
			(layer "F.Fab")
		)
		(fp_line
			(start -0.12065 0.3048)
			(end -0.67945 0.3048)
			(stroke
				(width 0.1)
				(type default)
			)
			(layer "F.Fab")
		)
		(fp_line
			(start 0.120396 0.2794)
			(end -0.12065 0.2794)
			(stroke
				(width 0.1)
				(type default)
			)
			(layer "F.Fab")
		)
		(fp_line
			(start 0.120396 0.3048)
			(end 0.120396 0.2794)
			(stroke
				(width 0.1)
				(type default)
			)
			(layer "F.Fab")
		)
		(fp_line
			(start 0.12065 -0.3048)
			(end 0.67945 -0.3048)
			(stroke
				(width 0.1)
				(type default)
			)
			(layer "F.Fab")
		)
		(fp_line
			(start 0.12065 -0.2794)
			(end 0.12065 -0.3048)
			(stroke
				(width 0.1)
				(type default)
			)
			(layer "F.Fab")
		)
		(fp_line
			(start 0.67945 -0.3048)
			(end 0.67945 0.3048)
			(stroke
				(width 0.1)
				(type default)
			)
			(layer "F.Fab")
		)
		(fp_line
			(start 0.67945 0.3048)
			(end 0.120396 0.3048)
			(stroke
				(width 0.1)
				(type default)
			)
			(layer "F.Fab")
		)
		(pad "1" smd circle
			(at -0.40005 0)
			(size 0 0)
			(layers "F.Cu" "F.Mask" "F.Paste")
			(net "GND")
		)
		(pad "2" smd circle
			(at 0.40005 0)
			(size 0 0)
			(layers "F.Cu" "F.Mask" "F.Paste")
			(net "P3V3_AUX")
		)
	)
	(footprint ""
		(layer "F.Cu")
		(at 398.782032 -37.025072)
		(property "Reference" "R5709"
			(at 0 0 0)
			(layer "F.SilkS")
			(hide yes)
			(effects
				(font
					(size 1.27 1.27)
				)
			)
		)
		(property "Value" ""
			(at 0 0 0)
			(layer "F.Fab")
			(effects
				(font
					(size 1.27 1.27)
				)
			)
		)
		(duplicate_pad_numbers_are_jumpers no)
		(fp_line
			(start -0.7874 -0.4064)
			(end 0.7874 -0.4064)
			(stroke
				(width 0.1524)
				(type default)
			)
			(layer "F.SilkS")
		)
		(fp_line
			(start -0.7874 0.4064)
			(end -0.7874 -0.4064)
			(stroke
				(width 0.1524)
				(type default)
			)
			(layer "F.SilkS")
		)
		(fp_line
			(start 0.7874 -0.4064)
			(end 0.7874 0.4064)
			(stroke
				(width 0.1524)
				(type default)
			)
			(layer "F.SilkS")
		)
		(fp_line
			(start 0.7874 0.4064)
			(end -0.7874 0.4064)
			(stroke
				(width 0.1524)
				(type default)
			)
			(layer "F.SilkS")
		)
		(fp_line
			(start -0.67945 -0.305054)
			(end -0.12065 -0.305054)
			(stroke
				(width 0.1)
				(type default)
			)
			(layer "F.Fab")
		)
		(fp_line
			(start -0.67945 0.3048)
			(end -0.67945 -0.305054)
			(stroke
				(width 0.1)
				(type default)
			)
			(layer "F.Fab")
		)
		(fp_line
			(start -0.12065 -0.305054)
			(end -0.12065 -0.2794)
			(stroke
				(width 0.1)
				(type default)
			)
			(layer "F.Fab")
		)
		(fp_line
			(start -0.12065 -0.2794)
			(end 0.12065 -0.2794)
			(stroke
				(width 0.1)
				(type default)
			)
			(layer "F.Fab")
		)
		(fp_line
			(start -0.12065 0.2794)
			(end -0.12065 0.3048)
			(stroke
				(width 0.1)
				(type default)
			)
			(layer "F.Fab")
		)
		(fp_line
			(start -0.12065 0.3048)
			(end -0.67945 0.3048)
			(stroke
				(width 0.1)
				(type default)
			)
			(layer "F.Fab")
		)
		(fp_line
			(start 0.120396 0.2794)
			(end -0.12065 0.2794)
			(stroke
				(width 0.1)
				(type default)
			)
			(layer "F.Fab")
		)
		(fp_line
			(start 0.120396 0.3048)
			(end 0.120396 0.2794)
			(stroke
				(width 0.1)
				(type default)
			)
			(layer "F.Fab")
		)
		(fp_line
			(start 0.12065 -0.3048)
			(end 0.67945 -0.3048)
			(stroke
				(width 0.1)
				(type default)
			)
			(layer "F.Fab")
		)
		(fp_line
			(start 0.12065 -0.2794)
			(end 0.12065 -0.3048)
			(stroke
				(width 0.1)
				(type default)
			)
			(layer "F.Fab")
		)
		(fp_line
			(start 0.67945 -0.3048)
			(end 0.67945 0.3048)
			(stroke
				(width 0.1)
				(type default)
			)
			(layer "F.Fab")
		)
		(fp_line
			(start 0.67945 0.3048)
			(end 0.120396 0.3048)
			(stroke
				(width 0.1)
				(type default)
			)
			(layer "F.Fab")
		)
		(pad "1" smd circle
			(at -0.40005 0)
			(size 0 0)
			(layers "F.Cu" "F.Mask" "F.Paste")
			(net "RST_SMB_SSD_R_N")
		)
		(pad "2" smd circle
			(at 0.40005 0)
			(size 0 0)
			(layers "F.Cu" "F.Mask" "F.Paste")
			(net "RST_SMB_SSD14_N")
		)
	)
	(footprint ""
		(layer "F.Cu")
		(at 165.269672 -356.244906 90)
		(property "Reference" "C2516"
			(at 0 0 90)
			(layer "F.SilkS")
			(hide yes)
			(effects
				(font
					(size 1.27 1.27)
				)
			)
		)
		(property "Value" ""
			(at 0 0 90)
			(layer "F.Fab")
			(effects
				(font
					(size 1.27 1.27)
				)
			)
		)
		(duplicate_pad_numbers_are_jumpers no)
		(fp_line
			(start 0.299974 -0.150114)
			(end 0.299974 0.150114)
			(stroke
				(width 0.1)
				(type default)
			)
			(layer "F.Fab")
		)
		(fp_line
			(start -0.299974 -0.150114)
			(end 0.299974 -0.150114)
			(stroke
				(width 0.1)
				(type default)
			)
			(layer "F.Fab")
		)
		(fp_line
			(start 0.299974 0.150114)
			(end -0.299974 0.150114)
			(stroke
				(width 0.1)
				(type default)
			)
			(layer "F.Fab")
		)
		(fp_line
			(start -0.299974 0.150114)
			(end -0.299974 -0.150114)
			(stroke
				(width 0.1)
				(type default)
			)
			(layer "F.Fab")
		)
		(pad "1" smd rect
			(at -0.2667 0 90)
			(size 0.3048 0.381)
			(layers "F.Cu" "F.Mask" "F.Paste")
			(net "P5E_PEX1_STN4_TX_DP<77>")
		)
		(pad "2" smd rect
			(at 0.2667 0 90)
			(size 0.3048 0.381)
			(layers "F.Cu" "F.Mask" "F.Paste")
			(net "P5E_PEX1_STN4_TX_C_DP<77>")
		)
	)
	(footprint ""
		(layer "F.Cu")
		(at 125.16739 -263.57072)
		(property "Reference" "PJ5"
			(at 0 0 0)
			(layer "F.SilkS")
			(hide yes)
			(effects
				(font
					(size 1.27 1.27)
				)
			)
		)
		(property "Value" ""
			(at 0 0 0)
			(layer "F.Fab")
			(effects
				(font
					(size 1.27 1.27)
				)
			)
		)
		(duplicate_pad_numbers_are_jumpers no)
		(pad "1" smd circle
			(at -0.7493 0 90)
			(size 0 0)
			(layers "F.Cu" "F.Mask" "F.Paste")
			(net "SH_P0V8_PEX0_VSEN0_L")
		)
		(pad "2" smd rect
			(at 0.7493 0 270)
			(size 0.7112 0.8128)
			(layers "F.Cu" "F.Mask" "F.Paste")
			(net "SH_P0V8_PEX0_VSEN0_R")
		)
		(zone
			(layer "F.Cu")
			(hatch none 0.5)
			(connect_pads
				(clearance 0)
			)
			(min_thickness 0.25)
			(keepout
				(tracks allowed)
				(vias not_allowed)
				(pads allowed)
				(copperpour not_allowed)
				(footprints allowed)
			)
			(placement
				(enabled no)
				(sheetname "")
			)
			(fill
				(thermal_gap 0.5)
				(thermal_bridge_width 0.5)
				(island_removal_mode 0)
			)
			(polygon
				(pts
					(xy 123.98629 -263.159494) (xy 126.37389 -263.159494) (xy 126.37389 -263.97712) (xy 123.98629 -263.97712)
				)
			)
		)
	)
	(footprint ""
		(layer "F.Cu")
		(at 276.922484 -44.341542 90)
		(property "Reference" "R613"
			(at 0 0 90)
			(layer "F.SilkS")
			(hide yes)
			(effects
				(font
					(size 1.27 1.27)
				)
			)
		)
		(property "Value" ""
			(at 0 0 90)
			(layer "F.Fab")
			(effects
				(font
					(size 1.27 1.27)
				)
			)
		)
		(duplicate_pad_numbers_are_jumpers no)
		(fp_line
			(start 0.7874 -0.4064)
			(end 0.7874 0.4064)
			(stroke
				(width 0.1524)
				(type default)
			)
			(layer "F.SilkS")
		)
		(fp_line
			(start -0.7874 -0.4064)
			(end 0.7874 -0.4064)
			(stroke
				(width 0.1524)
				(type default)
			)
			(layer "F.SilkS")
		)
		(fp_line
			(start 0.7874 0.4064)
			(end -0.7874 0.4064)
			(stroke
				(width 0.1524)
				(type default)
			)
			(layer "F.SilkS")
		)
		(fp_line
			(start -0.7874 0.4064)
			(end -0.7874 -0.4064)
			(stroke
				(width 0.1524)
				(type default)
			)
			(layer "F.SilkS")
		)
		(fp_line
			(start -0.12065 -0.305054)
			(end -0.12065 -0.2794)
			(stroke
				(width 0.1)
				(type default)
			)
			(layer "F.Fab")
		)
		(fp_line
			(start -0.67945 -0.305054)
			(end -0.12065 -0.305054)
			(stroke
				(width 0.1)
				(type default)
			)
			(layer "F.Fab")
		)
		(fp_line
			(start 0.67945 -0.3048)
			(end 0.67945 0.3048)
			(stroke
				(width 0.1)
				(type default)
			)
			(layer "F.Fab")
		)
		(fp_line
			(start 0.12065 -0.3048)
			(end 0.67945 -0.3048)
			(stroke
				(width 0.1)
				(type default)
			)
			(layer "F.Fab")
		)
		(fp_line
			(start 0.12065 -0.2794)
			(end 0.12065 -0.3048)
			(stroke
				(width 0.1)
				(type default)
			)
			(layer "F.Fab")
		)
		(fp_line
			(start -0.12065 -0.2794)
			(end 0.12065 -0.2794)
			(stroke
				(width 0.1)
				(type default)
			)
			(layer "F.Fab")
		)
		(fp_line
			(start 0.120396 0.2794)
			(end -0.12065 0.2794)
			(stroke
				(width 0.1)
				(type default)
			)
			(layer "F.Fab")
		)
		(fp_line
			(start -0.12065 0.2794)
			(end -0.12065 0.3048)
			(stroke
				(width 0.1)
				(type default)
			)
			(layer "F.Fab")
		)
		(fp_line
			(start 0.67945 0.3048)
			(end 0.120396 0.3048)
			(stroke
				(width 0.1)
				(type default)
			)
			(layer "F.Fab")
		)
		(fp_line
			(start 0.120396 0.3048)
			(end 0.120396 0.2794)
			(stroke
				(width 0.1)
				(type default)
			)
			(layer "F.Fab")
		)
		(fp_line
			(start -0.12065 0.3048)
			(end -0.67945 0.3048)
			(stroke
				(width 0.1)
				(type default)
			)
			(layer "F.Fab")
		)
		(fp_line
			(start -0.67945 0.3048)
			(end -0.67945 -0.305054)
			(stroke
				(width 0.1)
				(type default)
			)
			(layer "F.Fab")
		)
		(pad "1" smd circle
			(at -0.40005 0 90)
			(size 0 0)
			(layers "F.Cu" "F.Mask" "F.Paste")
			(net "P12V_SSD9")
		)
		(pad "2" smd circle
			(at 0.40005 0 90)
			(size 0 0)
			(layers "F.Cu" "F.Mask" "F.Paste")
			(net "P12V_SSD9_VIN_N")
		)
	)
	(footprint ""
		(layer "F.Cu")
		(at 283.623766 -167.742108)
		(property "Reference" "C933"
			(at 0 0 0)
			(layer "F.SilkS")
			(hide yes)
			(effects
				(font
					(size 1.27 1.27)
				)
			)
		)
		(property "Value" ""
			(at 0 0 0)
			(layer "F.Fab")
			(effects
				(font
					(size 1.27 1.27)
				)
			)
		)
		(duplicate_pad_numbers_are_jumpers no)
		(fp_line
			(start -0.7874 -0.4064)
			(end 0.7874 -0.4064)
			(stroke
				(width 0.1524)
				(type default)
			)
			(layer "F.SilkS")
		)
		(fp_line
			(start -0.7874 0.4064)
			(end -0.7874 -0.4064)
			(stroke
				(width 0.1524)
				(type default)
			)
			(layer "F.SilkS")
		)
		(fp_line
			(start 0.7874 -0.4064)
			(end 0.7874 0.4064)
			(stroke
				(width 0.1524)
				(type default)
			)
			(layer "F.SilkS")
		)
		(fp_line
			(start 0.7874 0.4064)
			(end -0.7874 0.4064)
			(stroke
				(width 0.1524)
				(type default)
			)
			(layer "F.SilkS")
		)
		(fp_line
			(start -0.67945 -0.305054)
			(end -0.12065 -0.305054)
			(stroke
				(width 0.1)
				(type default)
			)
			(layer "F.Fab")
		)
		(fp_line
			(start -0.67945 0.3048)
			(end -0.67945 -0.305054)
			(stroke
				(width 0.1)
				(type default)
			)
			(layer "F.Fab")
		)
		(fp_line
			(start -0.12065 -0.305054)
			(end -0.12065 -0.2794)
			(stroke
				(width 0.1)
				(type default)
			)
			(layer "F.Fab")
		)
		(fp_line
			(start -0.12065 -0.2794)
			(end 0.12065 -0.2794)
			(stroke
				(width 0.1)
				(type default)
			)
			(layer "F.Fab")
		)
		(fp_line
			(start -0.12065 0.2794)
			(end -0.12065 0.3048)
			(stroke
				(width 0.1)
				(type default)
			)
			(layer "F.Fab")
		)
		(fp_line
			(start -0.12065 0.3048)
			(end -0.67945 0.3048)
			(stroke
				(width 0.1)
				(type default)
			)
			(layer "F.Fab")
		)
		(fp_line
			(start 0.120396 0.2794)
			(end -0.12065 0.2794)
			(stroke
				(width 0.1)
				(type default)
			)
			(layer "F.Fab")
		)
		(fp_line
			(start 0.120396 0.3048)
			(end 0.120396 0.2794)
			(stroke
				(width 0.1)
				(type default)
			)
			(layer "F.Fab")
		)
		(fp_line
			(start 0.12065 -0.3048)
			(end 0.67945 -0.3048)
			(stroke
				(width 0.1)
				(type default)
			)
			(layer "F.Fab")
		)
		(fp_line
			(start 0.12065 -0.2794)
			(end 0.12065 -0.3048)
			(stroke
				(width 0.1)
				(type default)
			)
			(layer "F.Fab")
		)
		(fp_line
			(start 0.67945 -0.3048)
			(end 0.67945 0.3048)
			(stroke
				(width 0.1)
				(type default)
			)
			(layer "F.Fab")
		)
		(fp_line
			(start 0.67945 0.3048)
			(end 0.120396 0.3048)
			(stroke
				(width 0.1)
				(type default)
			)
			(layer "F.Fab")
		)
		(pad "1" smd circle
			(at -0.40005 0)
			(size 0 0)
			(layers "F.Cu" "F.Mask" "F.Paste")
			(net "P3V3_AUX")
		)
		(pad "2" smd circle
			(at 0.40005 0)
			(size 0 0)
			(layers "F.Cu" "F.Mask" "F.Paste")
			(net "GND")
		)
	)
	(footprint ""
		(layer "F.Cu")
		(at 427.923452 -343.952322 90)
		(property "Reference" "C808"
			(at 0 0 90)
			(layer "F.SilkS")
			(hide yes)
			(effects
				(font
					(size 1.27 1.27)
				)
			)
		)
		(property "Value" ""
			(at 0 0 90)
			(layer "F.Fab")
			(effects
				(font
					(size 1.27 1.27)
				)
			)
		)
		(duplicate_pad_numbers_are_jumpers no)
		(fp_line
			(start 0.299974 -0.150114)
			(end 0.299974 0.150114)
			(stroke
				(width 0.1)
				(type default)
			)
			(layer "F.Fab")
		)
		(fp_line
			(start -0.299974 -0.150114)
			(end 0.299974 -0.150114)
			(stroke
				(width 0.1)
				(type default)
			)
			(layer "F.Fab")
		)
		(fp_line
			(start 0.299974 0.150114)
			(end -0.299974 0.150114)
			(stroke
				(width 0.1)
				(type default)
			)
			(layer "F.Fab")
		)
		(fp_line
			(start -0.299974 0.150114)
			(end -0.299974 -0.150114)
			(stroke
				(width 0.1)
				(type default)
			)
			(layer "F.Fab")
		)
		(pad "1" smd rect
			(at -0.2667 0 90)
			(size 0.3048 0.381)
			(layers "F.Cu" "F.Mask" "F.Paste")
			(net "P5E_PEX3_STN7_TX_DP<120>")
		)
		(pad "2" smd rect
			(at 0.2667 0 90)
			(size 0.3048 0.381)
			(layers "F.Cu" "F.Mask" "F.Paste")
			(net "P5E_PEX3_STN7_TX_C_DP<120>")
		)
	)
	(footprint ""
		(layer "F.Cu")
		(at 221.081854 -257.975862 -90)
		(property "Reference" "R6491"
			(at 0 0 270)
			(layer "F.SilkS")
			(hide yes)
			(effects
				(font
					(size 1.27 1.27)
				)
			)
		)
		(property "Value" ""
			(at 0 0 270)
			(layer "F.Fab")
			(effects
				(font
					(size 1.27 1.27)
				)
			)
		)
		(duplicate_pad_numbers_are_jumpers no)
		(fp_line
			(start -0.7874 0.4064)
			(end -0.7874 -0.4064)
			(stroke
				(width 0.1524)
				(type default)
			)
			(layer "F.SilkS")
		)
		(fp_line
			(start 0.7874 0.4064)
			(end -0.7874 0.4064)
			(stroke
				(width 0.1524)
				(type default)
			)
			(layer "F.SilkS")
		)
		(fp_line
			(start -0.7874 -0.4064)
			(end 0.7874 -0.4064)
			(stroke
				(width 0.1524)
				(type default)
			)
			(layer "F.SilkS")
		)
		(fp_line
			(start 0.7874 -0.4064)
			(end 0.7874 0.4064)
			(stroke
				(width 0.1524)
				(type default)
			)
			(layer "F.SilkS")
		)
		(fp_line
			(start -0.67945 0.3048)
			(end -0.67945 -0.305054)
			(stroke
				(width 0.1)
				(type default)
			)
			(layer "F.Fab")
		)
		(fp_line
			(start -0.12065 0.3048)
			(end -0.67945 0.3048)
			(stroke
				(width 0.1)
				(type default)
			)
			(layer "F.Fab")
		)
		(fp_line
			(start 0.120396 0.3048)
			(end 0.120396 0.2794)
			(stroke
				(width 0.1)
				(type default)
			)
			(layer "F.Fab")
		)
		(fp_line
			(start 0.67945 0.3048)
			(end 0.120396 0.3048)
			(stroke
				(width 0.1)
				(type default)
			)
			(layer "F.Fab")
		)
		(fp_line
			(start -0.12065 0.2794)
			(end -0.12065 0.3048)
			(stroke
				(width 0.1)
				(type default)
			)
			(layer "F.Fab")
		)
		(fp_line
			(start 0.120396 0.2794)
			(end -0.12065 0.2794)
			(stroke
				(width 0.1)
				(type default)
			)
			(layer "F.Fab")
		)
		(fp_line
			(start -0.12065 -0.2794)
			(end 0.12065 -0.2794)
			(stroke
				(width 0.1)
				(type default)
			)
			(layer "F.Fab")
		)
		(fp_line
			(start 0.12065 -0.2794)
			(end 0.12065 -0.3048)
			(stroke
				(width 0.1)
				(type default)
			)
			(layer "F.Fab")
		)
		(fp_line
			(start 0.12065 -0.3048)
			(end 0.67945 -0.3048)
			(stroke
				(width 0.1)
				(type default)
			)
			(layer "F.Fab")
		)
		(fp_line
			(start 0.67945 -0.3048)
			(end 0.67945 0.3048)
			(stroke
				(width 0.1)
				(type default)
			)
			(layer "F.Fab")
		)
		(fp_line
			(start -0.67945 -0.305054)
			(end -0.12065 -0.305054)
			(stroke
				(width 0.1)
				(type default)
			)
			(layer "F.Fab")
		)
		(fp_line
			(start -0.12065 -0.305054)
			(end -0.12065 -0.2794)
			(stroke
				(width 0.1)
				(type default)
			)
			(layer "F.Fab")
		)
		(pad "1" smd circle
			(at -0.40005 0 270)
			(size 0 0)
			(layers "F.Cu" "F.Mask" "F.Paste")
			(net "P1V25_SERDES_VDDPLL_PEX1")
		)
		(pad "2" smd circle
			(at 0.40005 0 270)
			(size 0 0)
			(layers "F.Cu" "F.Mask" "F.Paste")
			(net "P1V25_SERDES_VDDPLL_PEX1_C0")
		)
	)
	(footprint ""
		(layer "F.Cu")
		(at 210.161886 -233.881422 -90)
		(property "Reference" "R1543"
			(at 0 0 270)
			(layer "F.SilkS")
			(hide yes)
			(effects
				(font
					(size 1.27 1.27)
				)
			)
		)
		(property "Value" ""
			(at 0 0 270)
			(layer "F.Fab")
			(effects
				(font
					(size 1.27 1.27)
				)
			)
		)
		(duplicate_pad_numbers_are_jumpers no)
		(fp_line
			(start -0.7874 0.4064)
			(end -0.7874 -0.4064)
			(stroke
				(width 0.1524)
				(type default)
			)
			(layer "F.SilkS")
		)
		(fp_line
			(start 0.7874 0.4064)
			(end -0.7874 0.4064)
			(stroke
				(width 0.1524)
				(type default)
			)
			(layer "F.SilkS")
		)
		(fp_line
			(start -0.7874 -0.4064)
			(end 0.7874 -0.4064)
			(stroke
				(width 0.1524)
				(type default)
			)
			(layer "F.SilkS")
		)
		(fp_line
			(start 0.7874 -0.4064)
			(end 0.7874 0.4064)
			(stroke
				(width 0.1524)
				(type default)
			)
			(layer "F.SilkS")
		)
		(fp_line
			(start -0.67945 0.3048)
			(end -0.67945 -0.305054)
			(stroke
				(width 0.1)
				(type default)
			)
			(layer "F.Fab")
		)
		(fp_line
			(start -0.12065 0.3048)
			(end -0.67945 0.3048)
			(stroke
				(width 0.1)
				(type default)
			)
			(layer "F.Fab")
		)
		(fp_line
			(start 0.120396 0.3048)
			(end 0.120396 0.2794)
			(stroke
				(width 0.1)
				(type default)
			)
			(layer "F.Fab")
		)
		(fp_line
			(start 0.67945 0.3048)
			(end 0.120396 0.3048)
			(stroke
				(width 0.1)
				(type default)
			)
			(layer "F.Fab")
		)
		(fp_line
			(start -0.12065 0.2794)
			(end -0.12065 0.3048)
			(stroke
				(width 0.1)
				(type default)
			)
			(layer "F.Fab")
		)
		(fp_line
			(start 0.120396 0.2794)
			(end -0.12065 0.2794)
			(stroke
				(width 0.1)
				(type default)
			)
			(layer "F.Fab")
		)
		(fp_line
			(start -0.12065 -0.2794)
			(end 0.12065 -0.2794)
			(stroke
				(width 0.1)
				(type default)
			)
			(layer "F.Fab")
		)
		(fp_line
			(start 0.12065 -0.2794)
			(end 0.12065 -0.3048)
			(stroke
				(width 0.1)
				(type default)
			)
			(layer "F.Fab")
		)
		(fp_line
			(start 0.12065 -0.3048)
			(end 0.67945 -0.3048)
			(stroke
				(width 0.1)
				(type default)
			)
			(layer "F.Fab")
		)
		(fp_line
			(start 0.67945 -0.3048)
			(end 0.67945 0.3048)
			(stroke
				(width 0.1)
				(type default)
			)
			(layer "F.Fab")
		)
		(fp_line
			(start -0.67945 -0.305054)
			(end -0.12065 -0.305054)
			(stroke
				(width 0.1)
				(type default)
			)
			(layer "F.Fab")
		)
		(fp_line
			(start -0.12065 -0.305054)
			(end -0.12065 -0.2794)
			(stroke
				(width 0.1)
				(type default)
			)
			(layer "F.Fab")
		)
		(pad "1" smd circle
			(at -0.40005 0 270)
			(size 0 0)
			(layers "F.Cu" "F.Mask" "F.Paste")
			(net "SMB_PEX_LS_R_SCL")
		)
		(pad "2" smd circle
			(at 0.40005 0 270)
			(size 0 0)
			(layers "F.Cu" "F.Mask" "F.Paste")
			(net "SMB_PEX1_SCL")
		)
	)
	(footprint ""
		(layer "F.Cu")
		(at 397.120618 -70.307454 90)
		(property "Reference" "PC889"
			(at 0 0 90)
			(layer "F.SilkS")
			(hide yes)
			(effects
				(font
					(size 1.27 1.27)
				)
			)
		)
		(property "Value" ""
			(at 0 0 90)
			(layer "F.Fab")
			(effects
				(font
					(size 1.27 1.27)
				)
			)
		)
		(duplicate_pad_numbers_are_jumpers no)
		(fp_line
			(start 0.7874 -0.4064)
			(end 0.7874 0.4064)
			(stroke
				(width 0.1524)
				(type default)
			)
			(layer "F.SilkS")
		)
		(fp_line
			(start -0.7874 -0.4064)
			(end 0.7874 -0.4064)
			(stroke
				(width 0.1524)
				(type default)
			)
			(layer "F.SilkS")
		)
		(fp_line
			(start 0.7874 0.4064)
			(end -0.7874 0.4064)
			(stroke
				(width 0.1524)
				(type default)
			)
			(layer "F.SilkS")
		)
		(fp_line
			(start -0.7874 0.4064)
			(end -0.7874 -0.4064)
			(stroke
				(width 0.1524)
				(type default)
			)
			(layer "F.SilkS")
		)
		(fp_line
			(start -0.12065 -0.305054)
			(end -0.12065 -0.2794)
			(stroke
				(width 0.1)
				(type default)
			)
			(layer "F.Fab")
		)
		(fp_line
			(start -0.67945 -0.305054)
			(end -0.12065 -0.305054)
			(stroke
				(width 0.1)
				(type default)
			)
			(layer "F.Fab")
		)
		(fp_line
			(start 0.67945 -0.3048)
			(end 0.67945 0.3048)
			(stroke
				(width 0.1)
				(type default)
			)
			(layer "F.Fab")
		)
		(fp_line
			(start 0.12065 -0.3048)
			(end 0.67945 -0.3048)
			(stroke
				(width 0.1)
				(type default)
			)
			(layer "F.Fab")
		)
		(fp_line
			(start 0.12065 -0.2794)
			(end 0.12065 -0.3048)
			(stroke
				(width 0.1)
				(type default)
			)
			(layer "F.Fab")
		)
		(fp_line
			(start -0.12065 -0.2794)
			(end 0.12065 -0.2794)
			(stroke
				(width 0.1)
				(type default)
			)
			(layer "F.Fab")
		)
		(fp_line
			(start 0.120396 0.2794)
			(end -0.12065 0.2794)
			(stroke
				(width 0.1)
				(type default)
			)
			(layer "F.Fab")
		)
		(fp_line
			(start -0.12065 0.2794)
			(end -0.12065 0.3048)
			(stroke
				(width 0.1)
				(type default)
			)
			(layer "F.Fab")
		)
		(fp_line
			(start 0.67945 0.3048)
			(end 0.120396 0.3048)
			(stroke
				(width 0.1)
				(type default)
			)
			(layer "F.Fab")
		)
		(fp_line
			(start 0.120396 0.3048)
			(end 0.120396 0.2794)
			(stroke
				(width 0.1)
				(type default)
			)
			(layer "F.Fab")
		)
		(fp_line
			(start -0.12065 0.3048)
			(end -0.67945 0.3048)
			(stroke
				(width 0.1)
				(type default)
			)
			(layer "F.Fab")
		)
		(fp_line
			(start -0.67945 0.3048)
			(end -0.67945 -0.305054)
			(stroke
				(width 0.1)
				(type default)
			)
			(layer "F.Fab")
		)
		(pad "1" smd circle
			(at -0.40005 0 90)
			(size 0 0)
			(layers "F.Cu" "F.Mask" "F.Paste")
			(net "P12V_AUX")
		)
		(pad "2" smd circle
			(at 0.40005 0 90)
			(size 0 0)
			(layers "F.Cu" "F.Mask" "F.Paste")
			(net "GND")
		)
	)
	(footprint ""
		(layer "F.Cu")
		(at 407.295096 -104.830372 180)
		(property "Reference" "R377"
			(at 0 0 180)
			(layer "F.SilkS")
			(hide yes)
			(effects
				(font
					(size 1.27 1.27)
				)
			)
		)
		(property "Value" ""
			(at 0 0 180)
			(layer "F.Fab")
			(effects
				(font
					(size 1.27 1.27)
				)
			)
		)
		(duplicate_pad_numbers_are_jumpers no)
		(fp_line
			(start 0.7874 0.4064)
			(end -0.7874 0.4064)
			(stroke
				(width 0.1524)
				(type default)
			)
			(layer "F.SilkS")
		)
		(fp_line
			(start 0.7874 -0.4064)
			(end 0.7874 0.4064)
			(stroke
				(width 0.1524)
				(type default)
			)
			(layer "F.SilkS")
		)
		(fp_line
			(start -0.7874 0.4064)
			(end -0.7874 -0.4064)
			(stroke
				(width 0.1524)
				(type default)
			)
			(layer "F.SilkS")
		)
		(fp_line
			(start -0.7874 -0.4064)
			(end 0.7874 -0.4064)
			(stroke
				(width 0.1524)
				(type default)
			)
			(layer "F.SilkS")
		)
		(fp_line
			(start 0.67945 0.3048)
			(end 0.120396 0.3048)
			(stroke
				(width 0.1)
				(type default)
			)
			(layer "F.Fab")
		)
		(fp_line
			(start 0.67945 -0.3048)
			(end 0.67945 0.3048)
			(stroke
				(width 0.1)
				(type default)
			)
			(layer "F.Fab")
		)
		(fp_line
			(start 0.12065 -0.2794)
			(end 0.12065 -0.3048)
			(stroke
				(width 0.1)
				(type default)
			)
			(layer "F.Fab")
		)
		(fp_line
			(start 0.12065 -0.3048)
			(end 0.67945 -0.3048)
			(stroke
				(width 0.1)
				(type default)
			)
			(layer "F.Fab")
		)
		(fp_line
			(start 0.120396 0.3048)
			(end 0.120396 0.2794)
			(stroke
				(width 0.1)
				(type default)
			)
			(layer "F.Fab")
		)
		(fp_line
			(start 0.120396 0.2794)
			(end -0.12065 0.2794)
			(stroke
				(width 0.1)
				(type default)
			)
			(layer "F.Fab")
		)
		(fp_line
			(start -0.12065 0.3048)
			(end -0.67945 0.3048)
			(stroke
				(width 0.1)
				(type default)
			)
			(layer "F.Fab")
		)
		(fp_line
			(start -0.12065 0.2794)
			(end -0.12065 0.3048)
			(stroke
				(width 0.1)
				(type default)
			)
			(layer "F.Fab")
		)
		(fp_line
			(start -0.12065 -0.2794)
			(end 0.12065 -0.2794)
			(stroke
				(width 0.1)
				(type default)
			)
			(layer "F.Fab")
		)
		(fp_line
			(start -0.12065 -0.305054)
			(end -0.12065 -0.2794)
			(stroke
				(width 0.1)
				(type default)
			)
			(layer "F.Fab")
		)
		(fp_line
			(start -0.67945 0.3048)
			(end -0.67945 -0.305054)
			(stroke
				(width 0.1)
				(type default)
			)
			(layer "F.Fab")
		)
		(fp_line
			(start -0.67945 -0.305054)
			(end -0.12065 -0.305054)
			(stroke
				(width 0.1)
				(type default)
			)
			(layer "F.Fab")
		)
		(pad "1" smd circle
			(at -0.40005 0 180)
			(size 0 0)
			(layers "F.Cu" "F.Mask" "F.Paste")
			(net "CLK_50M_NIC7_RBT_REF")
		)
		(pad "2" smd circle
			(at 0.40005 0 180)
			(size 0 0)
			(layers "F.Cu" "F.Mask" "F.Paste")
			(net "GND")
		)
	)
	(footprint ""
		(layer "F.Cu")
		(at 125.186948 -343.952322 90)
		(property "Reference" "C351"
			(at 0 0 90)
			(layer "F.SilkS")
			(hide yes)
			(effects
				(font
					(size 1.27 1.27)
				)
			)
		)
		(property "Value" ""
			(at 0 0 90)
			(layer "F.Fab")
			(effects
				(font
					(size 1.27 1.27)
				)
			)
		)
		(duplicate_pad_numbers_are_jumpers no)
		(fp_line
			(start 0.299974 -0.150114)
			(end 0.299974 0.150114)
			(stroke
				(width 0.1)
				(type default)
			)
			(layer "F.Fab")
		)
		(fp_line
			(start -0.299974 -0.150114)
			(end 0.299974 -0.150114)
			(stroke
				(width 0.1)
				(type default)
			)
			(layer "F.Fab")
		)
		(fp_line
			(start 0.299974 0.150114)
			(end -0.299974 0.150114)
			(stroke
				(width 0.1)
				(type default)
			)
			(layer "F.Fab")
		)
		(fp_line
			(start -0.299974 0.150114)
			(end -0.299974 -0.150114)
			(stroke
				(width 0.1)
				(type default)
			)
			(layer "F.Fab")
		)
		(pad "1" smd rect
			(at -0.2667 0 90)
			(size 0.3048 0.381)
			(layers "F.Cu" "F.Mask" "F.Paste")
			(net "P5E_PEX1_STN6_TX_DN<106>")
		)
		(pad "2" smd rect
			(at 0.2667 0 90)
			(size 0.3048 0.381)
			(layers "F.Cu" "F.Mask" "F.Paste")
			(net "P5E_PEX1_STN6_TX_C_DN<106>")
		)
	)
	(footprint ""
		(layer "F.Cu")
		(at 384.938524 -108.29544)
		(property "Reference" "C686"
			(at 0 0 0)
			(layer "F.SilkS")
			(hide yes)
			(effects
				(font
					(size 1.27 1.27)
				)
			)
		)
		(property "Value" ""
			(at 0 0 0)
			(layer "F.Fab")
			(effects
				(font
					(size 1.27 1.27)
				)
			)
		)
		(duplicate_pad_numbers_are_jumpers no)
		(fp_line
			(start -0.299974 -0.150114)
			(end 0.299974 -0.150114)
			(stroke
				(width 0.1)
				(type default)
			)
			(layer "F.Fab")
		)
		(fp_line
			(start -0.299974 0.150114)
			(end -0.299974 -0.150114)
			(stroke
				(width 0.1)
				(type default)
			)
			(layer "F.Fab")
		)
		(fp_line
			(start 0.299974 -0.150114)
			(end 0.299974 0.150114)
			(stroke
				(width 0.1)
				(type default)
			)
			(layer "F.Fab")
		)
		(fp_line
			(start 0.299974 0.150114)
			(end -0.299974 0.150114)
			(stroke
				(width 0.1)
				(type default)
			)
			(layer "F.Fab")
		)
		(pad "1" smd rect
			(at -0.2667 0)
			(size 0.3048 0.381)
			(layers "F.Cu" "F.Mask" "F.Paste")
			(net "P5E_PEX3_STN1_TX_DN<21>")
		)
		(pad "2" smd rect
			(at 0.2667 0)
			(size 0.3048 0.381)
			(layers "F.Cu" "F.Mask" "F.Paste")
			(net "P5E_PEX3_STN1_TX_C_DN<21>")
		)
	)
	(footprint ""
		(layer "F.Cu")
		(at 136.32561 -255.986534 -90)
		(property "Reference" "R6154"
			(at 0 0 270)
			(layer "F.SilkS")
			(hide yes)
			(effects
				(font
					(size 1.27 1.27)
				)
			)
		)
		(property "Value" ""
			(at 0 0 270)
			(layer "F.Fab")
			(effects
				(font
					(size 1.27 1.27)
				)
			)
		)
		(duplicate_pad_numbers_are_jumpers no)
		(fp_line
			(start -0.7874 0.4064)
			(end -0.7874 -0.4064)
			(stroke
				(width 0.1524)
				(type default)
			)
			(layer "F.SilkS")
		)
		(fp_line
			(start 0.7874 0.4064)
			(end -0.7874 0.4064)
			(stroke
				(width 0.1524)
				(type default)
			)
			(layer "F.SilkS")
		)
		(fp_line
			(start -0.7874 -0.4064)
			(end 0.7874 -0.4064)
			(stroke
				(width 0.1524)
				(type default)
			)
			(layer "F.SilkS")
		)
		(fp_line
			(start 0.7874 -0.4064)
			(end 0.7874 0.4064)
			(stroke
				(width 0.1524)
				(type default)
			)
			(layer "F.SilkS")
		)
		(fp_line
			(start -0.67945 0.3048)
			(end -0.67945 -0.305054)
			(stroke
				(width 0.1)
				(type default)
			)
			(layer "F.Fab")
		)
		(fp_line
			(start -0.12065 0.3048)
			(end -0.67945 0.3048)
			(stroke
				(width 0.1)
				(type default)
			)
			(layer "F.Fab")
		)
		(fp_line
			(start 0.120396 0.3048)
			(end 0.120396 0.2794)
			(stroke
				(width 0.1)
				(type default)
			)
			(layer "F.Fab")
		)
		(fp_line
			(start 0.67945 0.3048)
			(end 0.120396 0.3048)
			(stroke
				(width 0.1)
				(type default)
			)
			(layer "F.Fab")
		)
		(fp_line
			(start -0.12065 0.2794)
			(end -0.12065 0.3048)
			(stroke
				(width 0.1)
				(type default)
			)
			(layer "F.Fab")
		)
		(fp_line
			(start 0.120396 0.2794)
			(end -0.12065 0.2794)
			(stroke
				(width 0.1)
				(type default)
			)
			(layer "F.Fab")
		)
		(fp_line
			(start -0.12065 -0.2794)
			(end 0.12065 -0.2794)
			(stroke
				(width 0.1)
				(type default)
			)
			(layer "F.Fab")
		)
		(fp_line
			(start 0.12065 -0.2794)
			(end 0.12065 -0.3048)
			(stroke
				(width 0.1)
				(type default)
			)
			(layer "F.Fab")
		)
		(fp_line
			(start 0.12065 -0.3048)
			(end 0.67945 -0.3048)
			(stroke
				(width 0.1)
				(type default)
			)
			(layer "F.Fab")
		)
		(fp_line
			(start 0.67945 -0.3048)
			(end 0.67945 0.3048)
			(stroke
				(width 0.1)
				(type default)
			)
			(layer "F.Fab")
		)
		(fp_line
			(start -0.67945 -0.305054)
			(end -0.12065 -0.305054)
			(stroke
				(width 0.1)
				(type default)
			)
			(layer "F.Fab")
		)
		(fp_line
			(start -0.12065 -0.305054)
			(end -0.12065 -0.2794)
			(stroke
				(width 0.1)
				(type default)
			)
			(layer "F.Fab")
		)
		(pad "1" smd circle
			(at -0.40005 0 270)
			(size 0 0)
			(layers "F.Cu" "F.Mask" "F.Paste")
			(net "PEX1_SYS_ERR_R_N")
		)
		(pad "2" smd circle
			(at 0.40005 0 270)
			(size 0 0)
			(layers "F.Cu" "F.Mask" "F.Paste")
			(net "P1V8_PEX")
		)
	)
	(footprint ""
		(layer "F.Cu")
		(at 139.60221 -254.850646 180)
		(property "Reference" "D2"
			(at 1.221232 -1.72466 0)
			(unlocked yes)
			(layer "F.SilkS")
			(effects
				(font
					(size 0.7874 0.5842)
					(thickness 0.1524)
				)
				(justify left)
			)
		)
		(property "Value" ""
			(at 0 0 180)
			(layer "F.Fab")
			(effects
				(font
					(size 1.27 1.27)
				)
			)
		)
		(duplicate_pad_numbers_are_jumpers no)
		(fp_line
			(start 1.16078 0.4826)
			(end -0.64008 0.4826)
			(stroke
				(width 0.1524)
				(type default)
			)
			(layer "F.SilkS")
		)
		(fp_line
			(start 1.16078 -0.4826)
			(end 1.16078 0.4826)
			(stroke
				(width 0.1524)
				(type default)
			)
			(layer "F.SilkS")
		)
		(fp_line
			(start 1.03378 0.4826)
			(end -0.79248 0.4826)
			(stroke
				(width 0.1524)
				(type default)
			)
			(layer "F.SilkS")
		)
		(fp_line
			(start 1.03378 -0.4826)
			(end 1.03378 0.4826)
			(stroke
				(width 0.1524)
				(type default)
			)
			(layer "F.SilkS")
		)
		(fp_line
			(start 0.90678 0.4826)
			(end -0.90678 0.4826)
			(stroke
				(width 0.1524)
				(type default)
			)
			(layer "F.SilkS")
		)
		(fp_line
			(start 0.90678 -0.4826)
			(end 0.90678 0.4826)
			(stroke
				(width 0.1524)
				(type default)
			)
			(layer "F.SilkS")
		)
		(fp_line
			(start -0.64008 -0.4826)
			(end 1.16078 -0.4826)
			(stroke
				(width 0.1524)
				(type default)
			)
			(layer "F.SilkS")
		)
		(fp_line
			(start -0.79248 -0.4826)
			(end 1.03378 -0.4826)
			(stroke
				(width 0.1524)
				(type default)
			)
			(layer "F.SilkS")
		)
		(fp_line
			(start -0.89408 -0.4826)
			(end 0.90678 -0.4826)
			(stroke
				(width 0.1524)
				(type default)
			)
			(layer "F.SilkS")
		)
		(fp_line
			(start -0.90678 0.4826)
			(end -0.90678 -0.4699)
			(stroke
				(width 0.1524)
				(type default)
			)
			(layer "F.SilkS")
		)
		(fp_line
			(start 0.499872 0.249936)
			(end -0.499872 0.249936)
			(stroke
				(width 0.1)
				(type default)
			)
			(layer "F.Fab")
		)
		(fp_line
			(start 0.499872 -0.249936)
			(end 0.499872 0.249936)
			(stroke
				(width 0.1)
				(type default)
			)
			(layer "F.Fab")
		)
		(fp_line
			(start -0.499872 0.249936)
			(end -0.499872 -0.249936)
			(stroke
				(width 0.1)
				(type default)
			)
			(layer "F.Fab")
		)
		(fp_line
			(start -0.499872 -0.249936)
			(end 0.499872 -0.249936)
			(stroke
				(width 0.1)
				(type default)
			)
			(layer "F.Fab")
		)
		(pad "A" smd rect
			(at -0.47498 0 180)
			(size 0.6096 0.7112)
			(layers "F.Cu" "F.Mask" "F.Paste")
			(net "LED_PEX1_SYS_ERR_N")
		)
		(pad "C" smd rect
			(at 0.47498 0 180)
			(size 0.6096 0.7112)
			(layers "F.Cu" "F.Mask" "F.Paste")
			(net "PEX1_SYS_ERR_3V3_N")
		)
	)
	(footprint ""
		(layer "F.Cu")
		(at 336.764884 -114.833654 -90)
		(property "Reference" "PC812"
			(at 0 0 270)
			(layer "F.SilkS")
			(hide yes)
			(effects
				(font
					(size 1.27 1.27)
				)
			)
		)
		(property "Value" ""
			(at 0 0 270)
			(layer "F.Fab")
			(effects
				(font
					(size 1.27 1.27)
				)
			)
		)
		(duplicate_pad_numbers_are_jumpers no)
		(fp_line
			(start -1.2954 0.5842)
			(end -1.2954 -0.5842)
			(stroke
				(width 0.1524)
				(type default)
			)
			(layer "F.SilkS")
		)
		(fp_line
			(start 1.2954 0.5842)
			(end -1.2954 0.5842)
			(stroke
				(width 0.1524)
				(type default)
			)
			(layer "F.SilkS")
		)
		(fp_line
			(start -1.2954 -0.5842)
			(end 1.2954 -0.5842)
			(stroke
				(width 0.1524)
				(type default)
			)
			(layer "F.SilkS")
		)
		(fp_line
			(start 1.2954 -0.5842)
			(end 1.2954 0.5842)
			(stroke
				(width 0.1524)
				(type default)
			)
			(layer "F.SilkS")
		)
		(fp_line
			(start -0.8636 0.4572)
			(end -0.8636 0.4064)
			(stroke
				(width 0.1)
				(type default)
			)
			(layer "F.Fab")
		)
		(fp_line
			(start 0.8636 0.4572)
			(end -0.8636 0.4572)
			(stroke
				(width 0.1)
				(type default)
			)
			(layer "F.Fab")
		)
		(fp_line
			(start -1.1938 0.4064)
			(end -1.1938 -0.4064)
			(stroke
				(width 0.1)
				(type default)
			)
			(layer "F.Fab")
		)
		(fp_line
			(start -0.8636 0.4064)
			(end -1.1938 0.4064)
			(stroke
				(width 0.1)
				(type default)
			)
			(layer "F.Fab")
		)
		(fp_line
			(start 0.8636 0.4064)
			(end 0.8636 0.4572)
			(stroke
				(width 0.1)
				(type default)
			)
			(layer "F.Fab")
		)
		(fp_line
			(start 1.1938 0.4064)
			(end 0.8636 0.4064)
			(stroke
				(width 0.1)
				(type default)
			)
			(layer "F.Fab")
		)
		(fp_line
			(start -1.1938 -0.4064)
			(end -0.8636 -0.4064)
			(stroke
				(width 0.1)
				(type default)
			)
			(layer "F.Fab")
		)
		(fp_line
			(start -0.8636 -0.4064)
			(end -0.8636 -0.4572)
			(stroke
				(width 0.1)
				(type default)
			)
			(layer "F.Fab")
		)
		(fp_line
			(start 0.8636 -0.4064)
			(end 1.1938 -0.4064)
			(stroke
				(width 0.1)
				(type default)
			)
			(layer "F.Fab")
		)
		(fp_line
			(start 1.1938 -0.4064)
			(end 1.1938 0.4064)
			(stroke
				(width 0.1)
				(type default)
			)
			(layer "F.Fab")
		)
		(fp_line
			(start -0.8636 -0.4572)
			(end 0.8636 -0.4572)
			(stroke
				(width 0.1)
				(type default)
			)
			(layer "F.Fab")
		)
		(fp_line
			(start 0.8636 -0.4572)
			(end 0.8636 -0.4064)
			(stroke
				(width 0.1)
				(type default)
			)
			(layer "F.Fab")
		)
		(pad "1" smd rect
			(at -0.7366 0 180)
			(size 0.7112 0.8128)
			(layers "F.Cu" "F.Mask" "F.Paste")
			(net "GND")
		)
		(pad "2" smd rect
			(at 0.7366 0 180)
			(size 0.7112 0.8128)
			(layers "F.Cu" "F.Mask" "F.Paste")
			(net "P12V_NIC5_CO_AVIN_PD")
		)
	)
	(footprint ""
		(layer "F.Cu")
		(at 23.624794 -259.378958)
		(property "Reference" "R1261"
			(at 0 0 0)
			(layer "F.SilkS")
			(hide yes)
			(effects
				(font
					(size 1.27 1.27)
				)
			)
		)
		(property "Value" ""
			(at 0 0 0)
			(layer "F.Fab")
			(effects
				(font
					(size 1.27 1.27)
				)
			)
		)
		(duplicate_pad_numbers_are_jumpers no)
		(fp_line
			(start -0.7874 -0.4064)
			(end 0.7874 -0.4064)
			(stroke
				(width 0.1524)
				(type default)
			)
			(layer "F.SilkS")
		)
		(fp_line
			(start -0.7874 0.4064)
			(end -0.7874 -0.4064)
			(stroke
				(width 0.1524)
				(type default)
			)
			(layer "F.SilkS")
		)
		(fp_line
			(start 0.7874 -0.4064)
			(end 0.7874 0.4064)
			(stroke
				(width 0.1524)
				(type default)
			)
			(layer "F.SilkS")
		)
		(fp_line
			(start 0.7874 0.4064)
			(end -0.7874 0.4064)
			(stroke
				(width 0.1524)
				(type default)
			)
			(layer "F.SilkS")
		)
		(fp_line
			(start -0.67945 -0.305054)
			(end -0.12065 -0.305054)
			(stroke
				(width 0.1)
				(type default)
			)
			(layer "F.Fab")
		)
		(fp_line
			(start -0.67945 0.3048)
			(end -0.67945 -0.305054)
			(stroke
				(width 0.1)
				(type default)
			)
			(layer "F.Fab")
		)
		(fp_line
			(start -0.12065 -0.305054)
			(end -0.12065 -0.2794)
			(stroke
				(width 0.1)
				(type default)
			)
			(layer "F.Fab")
		)
		(fp_line
			(start -0.12065 -0.2794)
			(end 0.12065 -0.2794)
			(stroke
				(width 0.1)
				(type default)
			)
			(layer "F.Fab")
		)
		(fp_line
			(start -0.12065 0.2794)
			(end -0.12065 0.3048)
			(stroke
				(width 0.1)
				(type default)
			)
			(layer "F.Fab")
		)
		(fp_line
			(start -0.12065 0.3048)
			(end -0.67945 0.3048)
			(stroke
				(width 0.1)
				(type default)
			)
			(layer "F.Fab")
		)
		(fp_line
			(start 0.120396 0.2794)
			(end -0.12065 0.2794)
			(stroke
				(width 0.1)
				(type default)
			)
			(layer "F.Fab")
		)
		(fp_line
			(start 0.120396 0.3048)
			(end 0.120396 0.2794)
			(stroke
				(width 0.1)
				(type default)
			)
			(layer "F.Fab")
		)
		(fp_line
			(start 0.12065 -0.3048)
			(end 0.67945 -0.3048)
			(stroke
				(width 0.1)
				(type default)
			)
			(layer "F.Fab")
		)
		(fp_line
			(start 0.12065 -0.2794)
			(end 0.12065 -0.3048)
			(stroke
				(width 0.1)
				(type default)
			)
			(layer "F.Fab")
		)
		(fp_line
			(start 0.67945 -0.3048)
			(end 0.67945 0.3048)
			(stroke
				(width 0.1)
				(type default)
			)
			(layer "F.Fab")
		)
		(fp_line
			(start 0.67945 0.3048)
			(end 0.120396 0.3048)
			(stroke
				(width 0.1)
				(type default)
			)
			(layer "F.Fab")
		)
		(pad "1" smd circle
			(at -0.40005 0)
			(size 0 0)
			(layers "F.Cu" "F.Mask" "F.Paste")
			(net "PEX0_SYS_ERR_N_G")
		)
		(pad "2" smd circle
			(at 0.40005 0)
			(size 0 0)
			(layers "F.Cu" "F.Mask" "F.Paste")
			(net "P3V3_AUX")
		)
	)
	(footprint ""
		(layer "F.Cu")
		(at 15.804896 -119.140986 -90)
		(property "Reference" "R5855"
			(at 0 0 270)
			(layer "F.SilkS")
			(hide yes)
			(effects
				(font
					(size 1.27 1.27)
				)
			)
		)
		(property "Value" ""
			(at 0 0 270)
			(layer "F.Fab")
			(effects
				(font
					(size 1.27 1.27)
				)
			)
		)
		(duplicate_pad_numbers_are_jumpers no)
		(fp_line
			(start -0.7874 0.4064)
			(end -0.7874 -0.4064)
			(stroke
				(width 0.1524)
				(type default)
			)
			(layer "F.SilkS")
		)
		(fp_line
			(start 0.7874 0.4064)
			(end -0.7874 0.4064)
			(stroke
				(width 0.1524)
				(type default)
			)
			(layer "F.SilkS")
		)
		(fp_line
			(start -0.7874 -0.4064)
			(end 0.7874 -0.4064)
			(stroke
				(width 0.1524)
				(type default)
			)
			(layer "F.SilkS")
		)
		(fp_line
			(start 0.7874 -0.4064)
			(end 0.7874 0.4064)
			(stroke
				(width 0.1524)
				(type default)
			)
			(layer "F.SilkS")
		)
		(fp_line
			(start -0.67945 0.3048)
			(end -0.67945 -0.305054)
			(stroke
				(width 0.1)
				(type default)
			)
			(layer "F.Fab")
		)
		(fp_line
			(start -0.12065 0.3048)
			(end -0.67945 0.3048)
			(stroke
				(width 0.1)
				(type default)
			)
			(layer "F.Fab")
		)
		(fp_line
			(start 0.120396 0.3048)
			(end 0.120396 0.2794)
			(stroke
				(width 0.1)
				(type default)
			)
			(layer "F.Fab")
		)
		(fp_line
			(start 0.67945 0.3048)
			(end 0.120396 0.3048)
			(stroke
				(width 0.1)
				(type default)
			)
			(layer "F.Fab")
		)
		(fp_line
			(start -0.12065 0.2794)
			(end -0.12065 0.3048)
			(stroke
				(width 0.1)
				(type default)
			)
			(layer "F.Fab")
		)
		(fp_line
			(start 0.120396 0.2794)
			(end -0.12065 0.2794)
			(stroke
				(width 0.1)
				(type default)
			)
			(layer "F.Fab")
		)
		(fp_line
			(start -0.12065 -0.2794)
			(end 0.12065 -0.2794)
			(stroke
				(width 0.1)
				(type default)
			)
			(layer "F.Fab")
		)
		(fp_line
			(start 0.12065 -0.2794)
			(end 0.12065 -0.3048)
			(stroke
				(width 0.1)
				(type default)
			)
			(layer "F.Fab")
		)
		(fp_line
			(start 0.12065 -0.3048)
			(end 0.67945 -0.3048)
			(stroke
				(width 0.1)
				(type default)
			)
			(layer "F.Fab")
		)
		(fp_line
			(start 0.67945 -0.3048)
			(end 0.67945 0.3048)
			(stroke
				(width 0.1)
				(type default)
			)
			(layer "F.Fab")
		)
		(fp_line
			(start -0.67945 -0.305054)
			(end -0.12065 -0.305054)
			(stroke
				(width 0.1)
				(type default)
			)
			(layer "F.Fab")
		)
		(fp_line
			(start -0.12065 -0.305054)
			(end -0.12065 -0.2794)
			(stroke
				(width 0.1)
				(type default)
			)
			(layer "F.Fab")
		)
		(pad "1" smd circle
			(at -0.40005 0 270)
			(size 0 0)
			(layers "F.Cu" "F.Mask" "F.Paste")
			(net "HP_NIC0_EN")
		)
		(pad "2" smd circle
			(at 0.40005 0 270)
			(size 0 0)
			(layers "F.Cu" "F.Mask" "F.Paste")
			(net "P3V3_NIC0_CO_EN")
		)
	)
	(footprint ""
		(layer "F.Cu")
		(at 349.31731 -260.671564 90)
		(property "Reference" "PC130"
			(at 0 0 90)
			(layer "F.SilkS")
			(hide yes)
			(effects
				(font
					(size 1.27 1.27)
				)
			)
		)
		(property "Value" ""
			(at 0 0 90)
			(layer "F.Fab")
			(effects
				(font
					(size 1.27 1.27)
				)
			)
		)
		(duplicate_pad_numbers_are_jumpers no)
		(fp_line
			(start 0.7874 -0.4064)
			(end 0.7874 0.4064)
			(stroke
				(width 0.1524)
				(type default)
			)
			(layer "F.SilkS")
		)
		(fp_line
			(start -0.7874 -0.4064)
			(end 0.7874 -0.4064)
			(stroke
				(width 0.1524)
				(type default)
			)
			(layer "F.SilkS")
		)
		(fp_line
			(start 0.7874 0.4064)
			(end -0.7874 0.4064)
			(stroke
				(width 0.1524)
				(type default)
			)
			(layer "F.SilkS")
		)
		(fp_line
			(start -0.7874 0.4064)
			(end -0.7874 -0.4064)
			(stroke
				(width 0.1524)
				(type default)
			)
			(layer "F.SilkS")
		)
		(fp_line
			(start -0.12065 -0.305054)
			(end -0.12065 -0.2794)
			(stroke
				(width 0.1)
				(type default)
			)
			(layer "F.Fab")
		)
		(fp_line
			(start -0.67945 -0.305054)
			(end -0.12065 -0.305054)
			(stroke
				(width 0.1)
				(type default)
			)
			(layer "F.Fab")
		)
		(fp_line
			(start 0.67945 -0.3048)
			(end 0.67945 0.3048)
			(stroke
				(width 0.1)
				(type default)
			)
			(layer "F.Fab")
		)
		(fp_line
			(start 0.12065 -0.3048)
			(end 0.67945 -0.3048)
			(stroke
				(width 0.1)
				(type default)
			)
			(layer "F.Fab")
		)
		(fp_line
			(start 0.12065 -0.2794)
			(end 0.12065 -0.3048)
			(stroke
				(width 0.1)
				(type default)
			)
			(layer "F.Fab")
		)
		(fp_line
			(start -0.12065 -0.2794)
			(end 0.12065 -0.2794)
			(stroke
				(width 0.1)
				(type default)
			)
			(layer "F.Fab")
		)
		(fp_line
			(start 0.120396 0.2794)
			(end -0.12065 0.2794)
			(stroke
				(width 0.1)
				(type default)
			)
			(layer "F.Fab")
		)
		(fp_line
			(start -0.12065 0.2794)
			(end -0.12065 0.3048)
			(stroke
				(width 0.1)
				(type default)
			)
			(layer "F.Fab")
		)
		(fp_line
			(start 0.67945 0.3048)
			(end 0.120396 0.3048)
			(stroke
				(width 0.1)
				(type default)
			)
			(layer "F.Fab")
		)
		(fp_line
			(start 0.120396 0.3048)
			(end 0.120396 0.2794)
			(stroke
				(width 0.1)
				(type default)
			)
			(layer "F.Fab")
		)
		(fp_line
			(start -0.12065 0.3048)
			(end -0.67945 0.3048)
			(stroke
				(width 0.1)
				(type default)
			)
			(layer "F.Fab")
		)
		(fp_line
			(start -0.67945 0.3048)
			(end -0.67945 -0.305054)
			(stroke
				(width 0.1)
				(type default)
			)
			(layer "F.Fab")
		)
		(pad "1" smd circle
			(at -0.40005 0 90)
			(size 0 0)
			(layers "F.Cu" "F.Mask" "F.Paste")
			(net "P0V8_PEX3_VSEN3")
		)
		(pad "2" smd circle
			(at 0.40005 0 90)
			(size 0 0)
			(layers "F.Cu" "F.Mask" "F.Paste")
			(net "SH_P0V8_PEX3_RGND3")
		)
	)
	(footprint ""
		(layer "F.Cu")
		(at 421.589962 -72.766682 90)
		(property "Reference" "PR7094"
			(at 0 0 90)
			(layer "F.SilkS")
			(hide yes)
			(effects
				(font
					(size 1.27 1.27)
				)
			)
		)
		(property "Value" ""
			(at 0 0 90)
			(layer "F.Fab")
			(effects
				(font
					(size 1.27 1.27)
				)
			)
		)
		(duplicate_pad_numbers_are_jumpers no)
		(fp_line
			(start 0.7874 -0.4064)
			(end 0.7874 0.4064)
			(stroke
				(width 0.1524)
				(type default)
			)
			(layer "F.SilkS")
		)
		(fp_line
			(start -0.7874 -0.4064)
			(end 0.7874 -0.4064)
			(stroke
				(width 0.1524)
				(type default)
			)
			(layer "F.SilkS")
		)
		(fp_line
			(start 0.7874 0.4064)
			(end -0.7874 0.4064)
			(stroke
				(width 0.1524)
				(type default)
			)
			(layer "F.SilkS")
		)
		(fp_line
			(start -0.7874 0.4064)
			(end -0.7874 -0.4064)
			(stroke
				(width 0.1524)
				(type default)
			)
			(layer "F.SilkS")
		)
		(fp_line
			(start -0.12065 -0.305054)
			(end -0.12065 -0.2794)
			(stroke
				(width 0.1)
				(type default)
			)
			(layer "F.Fab")
		)
		(fp_line
			(start -0.67945 -0.305054)
			(end -0.12065 -0.305054)
			(stroke
				(width 0.1)
				(type default)
			)
			(layer "F.Fab")
		)
		(fp_line
			(start 0.67945 -0.3048)
			(end 0.67945 0.3048)
			(stroke
				(width 0.1)
				(type default)
			)
			(layer "F.Fab")
		)
		(fp_line
			(start 0.12065 -0.3048)
			(end 0.67945 -0.3048)
			(stroke
				(width 0.1)
				(type default)
			)
			(layer "F.Fab")
		)
		(fp_line
			(start 0.12065 -0.2794)
			(end 0.12065 -0.3048)
			(stroke
				(width 0.1)
				(type default)
			)
			(layer "F.Fab")
		)
		(fp_line
			(start -0.12065 -0.2794)
			(end 0.12065 -0.2794)
			(stroke
				(width 0.1)
				(type default)
			)
			(layer "F.Fab")
		)
		(fp_line
			(start 0.120396 0.2794)
			(end -0.12065 0.2794)
			(stroke
				(width 0.1)
				(type default)
			)
			(layer "F.Fab")
		)
		(fp_line
			(start -0.12065 0.2794)
			(end -0.12065 0.3048)
			(stroke
				(width 0.1)
				(type default)
			)
			(layer "F.Fab")
		)
		(fp_line
			(start 0.67945 0.3048)
			(end 0.120396 0.3048)
			(stroke
				(width 0.1)
				(type default)
			)
			(layer "F.Fab")
		)
		(fp_line
			(start 0.120396 0.3048)
			(end 0.120396 0.2794)
			(stroke
				(width 0.1)
				(type default)
			)
			(layer "F.Fab")
		)
		(fp_line
			(start -0.12065 0.3048)
			(end -0.67945 0.3048)
			(stroke
				(width 0.1)
				(type default)
			)
			(layer "F.Fab")
		)
		(fp_line
			(start -0.67945 0.3048)
			(end -0.67945 -0.305054)
			(stroke
				(width 0.1)
				(type default)
			)
			(layer "F.Fab")
		)
		(pad "1" smd circle
			(at -0.40005 0 90)
			(size 0 0)
			(layers "F.Cu" "F.Mask" "F.Paste")
			(net "P12V_SSD14_CO_ILIMIT")
		)
		(pad "2" smd circle
			(at 0.40005 0 90)
			(size 0 0)
			(layers "F.Cu" "F.Mask" "F.Paste")
			(net "GND")
		)
	)
	(footprint ""
		(layer "F.Cu")
		(at 324.083934 -289.230816 90)
		(property "Reference" "R3982"
			(at 0 0 90)
			(layer "F.SilkS")
			(hide yes)
			(effects
				(font
					(size 1.27 1.27)
				)
			)
		)
		(property "Value" ""
			(at 0 0 90)
			(layer "F.Fab")
			(effects
				(font
					(size 1.27 1.27)
				)
			)
		)
		(duplicate_pad_numbers_are_jumpers no)
		(fp_line
			(start 0.7874 -0.4064)
			(end 0.7874 0.4064)
			(stroke
				(width 0.1524)
				(type default)
			)
			(layer "F.SilkS")
		)
		(fp_line
			(start -0.7874 -0.4064)
			(end 0.7874 -0.4064)
			(stroke
				(width 0.1524)
				(type default)
			)
			(layer "F.SilkS")
		)
		(fp_line
			(start 0.7874 0.4064)
			(end -0.7874 0.4064)
			(stroke
				(width 0.1524)
				(type default)
			)
			(layer "F.SilkS")
		)
		(fp_line
			(start -0.7874 0.4064)
			(end -0.7874 -0.4064)
			(stroke
				(width 0.1524)
				(type default)
			)
			(layer "F.SilkS")
		)
		(fp_line
			(start -0.12065 -0.305054)
			(end -0.12065 -0.2794)
			(stroke
				(width 0.1)
				(type default)
			)
			(layer "F.Fab")
		)
		(fp_line
			(start -0.67945 -0.305054)
			(end -0.12065 -0.305054)
			(stroke
				(width 0.1)
				(type default)
			)
			(layer "F.Fab")
		)
		(fp_line
			(start 0.67945 -0.3048)
			(end 0.67945 0.3048)
			(stroke
				(width 0.1)
				(type default)
			)
			(layer "F.Fab")
		)
		(fp_line
			(start 0.12065 -0.3048)
			(end 0.67945 -0.3048)
			(stroke
				(width 0.1)
				(type default)
			)
			(layer "F.Fab")
		)
		(fp_line
			(start 0.12065 -0.2794)
			(end 0.12065 -0.3048)
			(stroke
				(width 0.1)
				(type default)
			)
			(layer "F.Fab")
		)
		(fp_line
			(start -0.12065 -0.2794)
			(end 0.12065 -0.2794)
			(stroke
				(width 0.1)
				(type default)
			)
			(layer "F.Fab")
		)
		(fp_line
			(start 0.120396 0.2794)
			(end -0.12065 0.2794)
			(stroke
				(width 0.1)
				(type default)
			)
			(layer "F.Fab")
		)
		(fp_line
			(start -0.12065 0.2794)
			(end -0.12065 0.3048)
			(stroke
				(width 0.1)
				(type default)
			)
			(layer "F.Fab")
		)
		(fp_line
			(start 0.67945 0.3048)
			(end 0.120396 0.3048)
			(stroke
				(width 0.1)
				(type default)
			)
			(layer "F.Fab")
		)
		(fp_line
			(start 0.120396 0.3048)
			(end 0.120396 0.2794)
			(stroke
				(width 0.1)
				(type default)
			)
			(layer "F.Fab")
		)
		(fp_line
			(start -0.12065 0.3048)
			(end -0.67945 0.3048)
			(stroke
				(width 0.1)
				(type default)
			)
			(layer "F.Fab")
		)
		(fp_line
			(start -0.67945 0.3048)
			(end -0.67945 -0.305054)
			(stroke
				(width 0.1)
				(type default)
			)
			(layer "F.Fab")
		)
		(pad "1" smd circle
			(at -0.40005 0 90)
			(size 0 0)
			(layers "F.Cu" "F.Mask" "F.Paste")
			(net "SMB_PEX2_PCA9555_SCL")
		)
		(pad "2" smd circle
			(at 0.40005 0 90)
			(size 0 0)
			(layers "F.Cu" "F.Mask" "F.Paste")
			(net "SMB_PEX2_HOST_LS_SCL")
		)
	)
	(footprint ""
		(layer "F.Cu")
		(at 232.409746 -119.797068 180)
		(property "Reference" "PR6898"
			(at 0 0 180)
			(layer "F.SilkS")
			(hide yes)
			(effects
				(font
					(size 1.27 1.27)
				)
			)
		)
		(property "Value" ""
			(at 0 0 180)
			(layer "F.Fab")
			(effects
				(font
					(size 1.27 1.27)
				)
			)
		)
		(duplicate_pad_numbers_are_jumpers no)
		(fp_line
			(start 0.7874 0.4064)
			(end -0.7874 0.4064)
			(stroke
				(width 0.1524)
				(type default)
			)
			(layer "F.SilkS")
		)
		(fp_line
			(start 0.7874 -0.4064)
			(end 0.7874 0.4064)
			(stroke
				(width 0.1524)
				(type default)
			)
			(layer "F.SilkS")
		)
		(fp_line
			(start -0.7874 0.4064)
			(end -0.7874 -0.4064)
			(stroke
				(width 0.1524)
				(type default)
			)
			(layer "F.SilkS")
		)
		(fp_line
			(start -0.7874 -0.4064)
			(end 0.7874 -0.4064)
			(stroke
				(width 0.1524)
				(type default)
			)
			(layer "F.SilkS")
		)
		(fp_line
			(start 0.67945 0.3048)
			(end 0.120396 0.3048)
			(stroke
				(width 0.1)
				(type default)
			)
			(layer "F.Fab")
		)
		(fp_line
			(start 0.67945 -0.3048)
			(end 0.67945 0.3048)
			(stroke
				(width 0.1)
				(type default)
			)
			(layer "F.Fab")
		)
		(fp_line
			(start 0.12065 -0.2794)
			(end 0.12065 -0.3048)
			(stroke
				(width 0.1)
				(type default)
			)
			(layer "F.Fab")
		)
		(fp_line
			(start 0.12065 -0.3048)
			(end 0.67945 -0.3048)
			(stroke
				(width 0.1)
				(type default)
			)
			(layer "F.Fab")
		)
		(fp_line
			(start 0.120396 0.3048)
			(end 0.120396 0.2794)
			(stroke
				(width 0.1)
				(type default)
			)
			(layer "F.Fab")
		)
		(fp_line
			(start 0.120396 0.2794)
			(end -0.12065 0.2794)
			(stroke
				(width 0.1)
				(type default)
			)
			(layer "F.Fab")
		)
		(fp_line
			(start -0.12065 0.3048)
			(end -0.67945 0.3048)
			(stroke
				(width 0.1)
				(type default)
			)
			(layer "F.Fab")
		)
		(fp_line
			(start -0.12065 0.2794)
			(end -0.12065 0.3048)
			(stroke
				(width 0.1)
				(type default)
			)
			(layer "F.Fab")
		)
		(fp_line
			(start -0.12065 -0.2794)
			(end 0.12065 -0.2794)
			(stroke
				(width 0.1)
				(type default)
			)
			(layer "F.Fab")
		)
		(fp_line
			(start -0.12065 -0.305054)
			(end -0.12065 -0.2794)
			(stroke
				(width 0.1)
				(type default)
			)
			(layer "F.Fab")
		)
		(fp_line
			(start -0.67945 0.3048)
			(end -0.67945 -0.305054)
			(stroke
				(width 0.1)
				(type default)
			)
			(layer "F.Fab")
		)
		(fp_line
			(start -0.67945 -0.305054)
			(end -0.12065 -0.305054)
			(stroke
				(width 0.1)
				(type default)
			)
			(layer "F.Fab")
		)
		(pad "1" smd circle
			(at -0.40005 0 180)
			(size 0 0)
			(layers "F.Cu" "F.Mask" "F.Paste")
			(net "P12V_NIC3_CO_OV_FB")
		)
		(pad "2" smd circle
			(at 0.40005 0 180)
			(size 0 0)
			(layers "F.Cu" "F.Mask" "F.Paste")
			(net "GND")
		)
	)
	(footprint ""
		(layer "F.Cu")
		(at 320.354452 -224.659698 180)
		(property "Reference" "D14"
			(at 3.743452 0.103632 0)
			(unlocked yes)
			(layer "F.SilkS")
			(effects
				(font
					(size 0.7874 0.5842)
					(thickness 0.1524)
				)
				(justify left)
			)
		)
		(property "Value" ""
			(at 0 0 180)
			(layer "F.Fab")
			(effects
				(font
					(size 1.27 1.27)
				)
			)
		)
		(duplicate_pad_numbers_are_jumpers no)
		(fp_line
			(start 1.16078 0.4826)
			(end -0.64008 0.4826)
			(stroke
				(width 0.1524)
				(type default)
			)
			(layer "F.SilkS")
		)
		(fp_line
			(start 1.16078 -0.4826)
			(end 1.16078 0.4826)
			(stroke
				(width 0.1524)
				(type default)
			)
			(layer "F.SilkS")
		)
		(fp_line
			(start 1.03378 0.4826)
			(end -0.79248 0.4826)
			(stroke
				(width 0.1524)
				(type default)
			)
			(layer "F.SilkS")
		)
		(fp_line
			(start 1.03378 -0.4826)
			(end 1.03378 0.4826)
			(stroke
				(width 0.1524)
				(type default)
			)
			(layer "F.SilkS")
		)
		(fp_line
			(start 0.90678 0.4826)
			(end -0.90678 0.4826)
			(stroke
				(width 0.1524)
				(type default)
			)
			(layer "F.SilkS")
		)
		(fp_line
			(start 0.90678 -0.4826)
			(end 0.90678 0.4826)
			(stroke
				(width 0.1524)
				(type default)
			)
			(layer "F.SilkS")
		)
		(fp_line
			(start -0.64008 -0.4826)
			(end 1.16078 -0.4826)
			(stroke
				(width 0.1524)
				(type default)
			)
			(layer "F.SilkS")
		)
		(fp_line
			(start -0.79248 -0.4826)
			(end 1.03378 -0.4826)
			(stroke
				(width 0.1524)
				(type default)
			)
			(layer "F.SilkS")
		)
		(fp_line
			(start -0.89408 -0.4826)
			(end 0.90678 -0.4826)
			(stroke
				(width 0.1524)
				(type default)
			)
			(layer "F.SilkS")
		)
		(fp_line
			(start -0.90678 0.4826)
			(end -0.90678 -0.4699)
			(stroke
				(width 0.1524)
				(type default)
			)
			(layer "F.SilkS")
		)
		(fp_line
			(start 0.499872 0.249936)
			(end -0.499872 0.249936)
			(stroke
				(width 0.1)
				(type default)
			)
			(layer "F.Fab")
		)
		(fp_line
			(start 0.499872 -0.249936)
			(end 0.499872 0.249936)
			(stroke
				(width 0.1)
				(type default)
			)
			(layer "F.Fab")
		)
		(fp_line
			(start -0.499872 0.249936)
			(end -0.499872 -0.249936)
			(stroke
				(width 0.1)
				(type default)
			)
			(layer "F.Fab")
		)
		(fp_line
			(start -0.499872 -0.249936)
			(end 0.499872 -0.249936)
			(stroke
				(width 0.1)
				(type default)
			)
			(layer "F.Fab")
		)
		(pad "A" smd rect
			(at -0.47498 0 180)
			(size 0.6096 0.7112)
			(layers "F.Cu" "F.Mask" "F.Paste")
			(net "LED_POSTCODE_R_1")
		)
		(pad "C" smd rect
			(at 0.47498 0 180)
			(size 0.6096 0.7112)
			(layers "F.Cu" "F.Mask" "F.Paste")
			(net "FPGA_DEBUG_LED_R_N")
		)
	)
	(footprint ""
		(layer "F.Cu")
		(at 243.8273 -185.429652 -90)
		(property "Reference" "R3152"
			(at 0 0 270)
			(layer "F.SilkS")
			(hide yes)
			(effects
				(font
					(size 1.27 1.27)
				)
			)
		)
		(property "Value" ""
			(at 0 0 270)
			(layer "F.Fab")
			(effects
				(font
					(size 1.27 1.27)
				)
			)
		)
		(duplicate_pad_numbers_are_jumpers no)
		(fp_line
			(start -0.7874 0.4064)
			(end -0.7874 -0.4064)
			(stroke
				(width 0.1524)
				(type default)
			)
			(layer "F.SilkS")
		)
		(fp_line
			(start 0.7874 0.4064)
			(end -0.7874 0.4064)
			(stroke
				(width 0.1524)
				(type default)
			)
			(layer "F.SilkS")
		)
		(fp_line
			(start -0.7874 -0.4064)
			(end 0.7874 -0.4064)
			(stroke
				(width 0.1524)
				(type default)
			)
			(layer "F.SilkS")
		)
		(fp_line
			(start 0.7874 -0.4064)
			(end 0.7874 0.4064)
			(stroke
				(width 0.1524)
				(type default)
			)
			(layer "F.SilkS")
		)
		(fp_line
			(start -0.67945 0.3048)
			(end -0.67945 -0.305054)
			(stroke
				(width 0.1)
				(type default)
			)
			(layer "F.Fab")
		)
		(fp_line
			(start -0.12065 0.3048)
			(end -0.67945 0.3048)
			(stroke
				(width 0.1)
				(type default)
			)
			(layer "F.Fab")
		)
		(fp_line
			(start 0.120396 0.3048)
			(end 0.120396 0.2794)
			(stroke
				(width 0.1)
				(type default)
			)
			(layer "F.Fab")
		)
		(fp_line
			(start 0.67945 0.3048)
			(end 0.120396 0.3048)
			(stroke
				(width 0.1)
				(type default)
			)
			(layer "F.Fab")
		)
		(fp_line
			(start -0.12065 0.2794)
			(end -0.12065 0.3048)
			(stroke
				(width 0.1)
				(type default)
			)
			(layer "F.Fab")
		)
		(fp_line
			(start 0.120396 0.2794)
			(end -0.12065 0.2794)
			(stroke
				(width 0.1)
				(type default)
			)
			(layer "F.Fab")
		)
		(fp_line
			(start -0.12065 -0.2794)
			(end 0.12065 -0.2794)
			(stroke
				(width 0.1)
				(type default)
			)
			(layer "F.Fab")
		)
		(fp_line
			(start 0.12065 -0.2794)
			(end 0.12065 -0.3048)
			(stroke
				(width 0.1)
				(type default)
			)
			(layer "F.Fab")
		)
		(fp_line
			(start 0.12065 -0.3048)
			(end 0.67945 -0.3048)
			(stroke
				(width 0.1)
				(type default)
			)
			(layer "F.Fab")
		)
		(fp_line
			(start 0.67945 -0.3048)
			(end 0.67945 0.3048)
			(stroke
				(width 0.1)
				(type default)
			)
			(layer "F.Fab")
		)
		(fp_line
			(start -0.67945 -0.305054)
			(end -0.12065 -0.305054)
			(stroke
				(width 0.1)
				(type default)
			)
			(layer "F.Fab")
		)
		(fp_line
			(start -0.12065 -0.305054)
			(end -0.12065 -0.2794)
			(stroke
				(width 0.1)
				(type default)
			)
			(layer "F.Fab")
		)
		(pad "1" smd circle
			(at -0.40005 0 270)
			(size 0 0)
			(layers "F.Cu" "F.Mask" "F.Paste")
			(net "PWRGD_P1V2_AUX_FPGA_R")
		)
		(pad "2" smd circle
			(at 0.40005 0 270)
			(size 0 0)
			(layers "F.Cu" "F.Mask" "F.Paste")
			(net "PWRGD_P1V2_AUX_RST")
		)
	)
	(footprint ""
		(layer "F.Cu")
		(at 5.081524 -251.312426 -90)
		(property "Reference" "C4242"
			(at 0 0 270)
			(layer "F.SilkS")
			(hide yes)
			(effects
				(font
					(size 1.27 1.27)
				)
			)
		)
		(property "Value" ""
			(at 0 0 270)
			(layer "F.Fab")
			(effects
				(font
					(size 1.27 1.27)
				)
			)
		)
		(duplicate_pad_numbers_are_jumpers no)
		(fp_line
			(start -1.2954 0.5842)
			(end -1.2954 -0.5842)
			(stroke
				(width 0.1524)
				(type default)
			)
			(layer "F.SilkS")
		)
		(fp_line
			(start 1.2954 0.5842)
			(end -1.2954 0.5842)
			(stroke
				(width 0.1524)
				(type default)
			)
			(layer "F.SilkS")
		)
		(fp_line
			(start -1.2954 -0.5842)
			(end 1.2954 -0.5842)
			(stroke
				(width 0.1524)
				(type default)
			)
			(layer "F.SilkS")
		)
		(fp_line
			(start 1.2954 -0.5842)
			(end 1.2954 0.5842)
			(stroke
				(width 0.1524)
				(type default)
			)
			(layer "F.SilkS")
		)
		(fp_line
			(start -0.8636 0.4572)
			(end -0.8636 0.4064)
			(stroke
				(width 0.1)
				(type default)
			)
			(layer "F.Fab")
		)
		(fp_line
			(start 0.8636 0.4572)
			(end -0.8636 0.4572)
			(stroke
				(width 0.1)
				(type default)
			)
			(layer "F.Fab")
		)
		(fp_line
			(start -1.1938 0.4064)
			(end -1.1938 -0.4064)
			(stroke
				(width 0.1)
				(type default)
			)
			(layer "F.Fab")
		)
		(fp_line
			(start -0.8636 0.4064)
			(end -1.1938 0.4064)
			(stroke
				(width 0.1)
				(type default)
			)
			(layer "F.Fab")
		)
		(fp_line
			(start 0.8636 0.4064)
			(end 0.8636 0.4572)
			(stroke
				(width 0.1)
				(type default)
			)
			(layer "F.Fab")
		)
		(fp_line
			(start 1.1938 0.4064)
			(end 0.8636 0.4064)
			(stroke
				(width 0.1)
				(type default)
			)
			(layer "F.Fab")
		)
		(fp_line
			(start -1.1938 -0.4064)
			(end -0.8636 -0.4064)
			(stroke
				(width 0.1)
				(type default)
			)
			(layer "F.Fab")
		)
		(fp_line
			(start -0.8636 -0.4064)
			(end -0.8636 -0.4572)
			(stroke
				(width 0.1)
				(type default)
			)
			(layer "F.Fab")
		)
		(fp_line
			(start 0.8636 -0.4064)
			(end 1.1938 -0.4064)
			(stroke
				(width 0.1)
				(type default)
			)
			(layer "F.Fab")
		)
		(fp_line
			(start 1.1938 -0.4064)
			(end 1.1938 0.4064)
			(stroke
				(width 0.1)
				(type default)
			)
			(layer "F.Fab")
		)
		(fp_line
			(start -0.8636 -0.4572)
			(end 0.8636 -0.4572)
			(stroke
				(width 0.1)
				(type default)
			)
			(layer "F.Fab")
		)
		(fp_line
			(start 0.8636 -0.4572)
			(end 0.8636 -0.4064)
			(stroke
				(width 0.1)
				(type default)
			)
			(layer "F.Fab")
		)
		(pad "1" smd rect
			(at -0.7366 0 180)
			(size 0.7112 0.8128)
			(layers "F.Cu" "F.Mask" "F.Paste")
			(net "P1V25_SERDES_VDDPLL_PEX0_C8")
		)
		(pad "2" smd rect
			(at 0.7366 0 180)
			(size 0.7112 0.8128)
			(layers "F.Cu" "F.Mask" "F.Paste")
			(net "GND")
		)
	)
	(footprint ""
		(layer "F.Cu")
		(at 219.202 -201.168)
		(property "Reference" "R1517"
			(at 0 0 0)
			(layer "F.SilkS")
			(hide yes)
			(effects
				(font
					(size 1.27 1.27)
				)
			)
		)
		(property "Value" ""
			(at 0 0 0)
			(layer "F.Fab")
			(effects
				(font
					(size 1.27 1.27)
				)
			)
		)
		(duplicate_pad_numbers_are_jumpers no)
		(fp_line
			(start -0.7874 -0.4064)
			(end 0.7874 -0.4064)
			(stroke
				(width 0.1524)
				(type default)
			)
			(layer "F.SilkS")
		)
		(fp_line
			(start -0.7874 0.4064)
			(end -0.7874 -0.4064)
			(stroke
				(width 0.1524)
				(type default)
			)
			(layer "F.SilkS")
		)
		(fp_line
			(start 0.7874 -0.4064)
			(end 0.7874 0.4064)
			(stroke
				(width 0.1524)
				(type default)
			)
			(layer "F.SilkS")
		)
		(fp_line
			(start 0.7874 0.4064)
			(end -0.7874 0.4064)
			(stroke
				(width 0.1524)
				(type default)
			)
			(layer "F.SilkS")
		)
		(fp_line
			(start -0.67945 -0.305054)
			(end -0.12065 -0.305054)
			(stroke
				(width 0.1)
				(type default)
			)
			(layer "F.Fab")
		)
		(fp_line
			(start -0.67945 0.3048)
			(end -0.67945 -0.305054)
			(stroke
				(width 0.1)
				(type default)
			)
			(layer "F.Fab")
		)
		(fp_line
			(start -0.12065 -0.305054)
			(end -0.12065 -0.2794)
			(stroke
				(width 0.1)
				(type default)
			)
			(layer "F.Fab")
		)
		(fp_line
			(start -0.12065 -0.2794)
			(end 0.12065 -0.2794)
			(stroke
				(width 0.1)
				(type default)
			)
			(layer "F.Fab")
		)
		(fp_line
			(start -0.12065 0.2794)
			(end -0.12065 0.3048)
			(stroke
				(width 0.1)
				(type default)
			)
			(layer "F.Fab")
		)
		(fp_line
			(start -0.12065 0.3048)
			(end -0.67945 0.3048)
			(stroke
				(width 0.1)
				(type default)
			)
			(layer "F.Fab")
		)
		(fp_line
			(start 0.120396 0.2794)
			(end -0.12065 0.2794)
			(stroke
				(width 0.1)
				(type default)
			)
			(layer "F.Fab")
		)
		(fp_line
			(start 0.120396 0.3048)
			(end 0.120396 0.2794)
			(stroke
				(width 0.1)
				(type default)
			)
			(layer "F.Fab")
		)
		(fp_line
			(start 0.12065 -0.3048)
			(end 0.67945 -0.3048)
			(stroke
				(width 0.1)
				(type default)
			)
			(layer "F.Fab")
		)
		(fp_line
			(start 0.12065 -0.2794)
			(end 0.12065 -0.3048)
			(stroke
				(width 0.1)
				(type default)
			)
			(layer "F.Fab")
		)
		(fp_line
			(start 0.67945 -0.3048)
			(end 0.67945 0.3048)
			(stroke
				(width 0.1)
				(type default)
			)
			(layer "F.Fab")
		)
		(fp_line
			(start 0.67945 0.3048)
			(end 0.120396 0.3048)
			(stroke
				(width 0.1)
				(type default)
			)
			(layer "F.Fab")
		)
		(pad "1" smd circle
			(at -0.40005 0)
			(size 0 0)
			(layers "F.Cu" "F.Mask" "F.Paste")
			(net "SMB_NIC5_LS_EN")
		)
		(pad "2" smd circle
			(at 0.40005 0)
			(size 0 0)
			(layers "F.Cu" "F.Mask" "F.Paste")
			(net "P3V3_NIC5")
		)
	)
	(footprint ""
		(layer "F.Cu")
		(at 46.255178 -35.876738)
		(property "Reference" "R5880"
			(at 0 0 0)
			(layer "F.SilkS")
			(hide yes)
			(effects
				(font
					(size 1.27 1.27)
				)
			)
		)
		(property "Value" ""
			(at 0 0 0)
			(layer "F.Fab")
			(effects
				(font
					(size 1.27 1.27)
				)
			)
		)
		(duplicate_pad_numbers_are_jumpers no)
		(fp_line
			(start -0.7874 -0.4064)
			(end 0.7874 -0.4064)
			(stroke
				(width 0.1524)
				(type default)
			)
			(layer "F.SilkS")
		)
		(fp_line
			(start -0.7874 0.4064)
			(end -0.7874 -0.4064)
			(stroke
				(width 0.1524)
				(type default)
			)
			(layer "F.SilkS")
		)
		(fp_line
			(start 0.7874 -0.4064)
			(end 0.7874 0.4064)
			(stroke
				(width 0.1524)
				(type default)
			)
			(layer "F.SilkS")
		)
		(fp_line
			(start 0.7874 0.4064)
			(end -0.7874 0.4064)
			(stroke
				(width 0.1524)
				(type default)
			)
			(layer "F.SilkS")
		)
		(fp_line
			(start -0.67945 -0.305054)
			(end -0.12065 -0.305054)
			(stroke
				(width 0.1)
				(type default)
			)
			(layer "F.Fab")
		)
		(fp_line
			(start -0.67945 0.3048)
			(end -0.67945 -0.305054)
			(stroke
				(width 0.1)
				(type default)
			)
			(layer "F.Fab")
		)
		(fp_line
			(start -0.12065 -0.305054)
			(end -0.12065 -0.2794)
			(stroke
				(width 0.1)
				(type default)
			)
			(layer "F.Fab")
		)
		(fp_line
			(start -0.12065 -0.2794)
			(end 0.12065 -0.2794)
			(stroke
				(width 0.1)
				(type default)
			)
			(layer "F.Fab")
		)
		(fp_line
			(start -0.12065 0.2794)
			(end -0.12065 0.3048)
			(stroke
				(width 0.1)
				(type default)
			)
			(layer "F.Fab")
		)
		(fp_line
			(start -0.12065 0.3048)
			(end -0.67945 0.3048)
			(stroke
				(width 0.1)
				(type default)
			)
			(layer "F.Fab")
		)
		(fp_line
			(start 0.120396 0.2794)
			(end -0.12065 0.2794)
			(stroke
				(width 0.1)
				(type default)
			)
			(layer "F.Fab")
		)
		(fp_line
			(start 0.120396 0.3048)
			(end 0.120396 0.2794)
			(stroke
				(width 0.1)
				(type default)
			)
			(layer "F.Fab")
		)
		(fp_line
			(start 0.12065 -0.3048)
			(end 0.67945 -0.3048)
			(stroke
				(width 0.1)
				(type default)
			)
			(layer "F.Fab")
		)
		(fp_line
			(start 0.12065 -0.2794)
			(end 0.12065 -0.3048)
			(stroke
				(width 0.1)
				(type default)
			)
			(layer "F.Fab")
		)
		(fp_line
			(start 0.67945 -0.3048)
			(end 0.67945 0.3048)
			(stroke
				(width 0.1)
				(type default)
			)
			(layer "F.Fab")
		)
		(fp_line
			(start 0.67945 0.3048)
			(end 0.120396 0.3048)
			(stroke
				(width 0.1)
				(type default)
			)
			(layer "F.Fab")
		)
		(pad "1" smd circle
			(at -0.40005 0)
			(size 0 0)
			(layers "F.Cu" "F.Mask" "F.Paste")
			(net "P3V3_AUX")
		)
		(pad "2" smd circle
			(at 0.40005 0)
			(size 0 0)
			(layers "F.Cu" "F.Mask" "F.Paste")
			(net "PWRGD_P3V3_SSD2_D")
		)
	)
	(footprint ""
		(layer "F.Cu")
		(at 36.638484 -134.008876)
		(property "Reference" "C35"
			(at 0 0 0)
			(layer "F.SilkS")
			(hide yes)
			(effects
				(font
					(size 1.27 1.27)
				)
			)
		)
		(property "Value" ""
			(at 0 0 0)
			(layer "F.Fab")
			(effects
				(font
					(size 1.27 1.27)
				)
			)
		)
		(duplicate_pad_numbers_are_jumpers no)
		(fp_line
			(start -0.299974 -0.150114)
			(end 0.299974 -0.150114)
			(stroke
				(width 0.1)
				(type default)
			)
			(layer "F.Fab")
		)
		(fp_line
			(start -0.299974 0.150114)
			(end -0.299974 -0.150114)
			(stroke
				(width 0.1)
				(type default)
			)
			(layer "F.Fab")
		)
		(fp_line
			(start 0.299974 -0.150114)
			(end 0.299974 0.150114)
			(stroke
				(width 0.1)
				(type default)
			)
			(layer "F.Fab")
		)
		(fp_line
			(start 0.299974 0.150114)
			(end -0.299974 0.150114)
			(stroke
				(width 0.1)
				(type default)
			)
			(layer "F.Fab")
		)
		(pad "1" smd rect
			(at -0.2667 0)
			(size 0.3048 0.381)
			(layers "F.Cu" "F.Mask" "F.Paste")
			(net "P5E_PEX0_STN1_TX_DP<30>")
		)
		(pad "2" smd rect
			(at 0.2667 0)
			(size 0.3048 0.381)
			(layers "F.Cu" "F.Mask" "F.Paste")
			(net "P5E_PEX0_STN1_TX_C_DP<30>")
		)
	)
	(footprint ""
		(layer "F.Cu")
		(at 16.785336 -271.184624)
		(property "Reference" "R771"
			(at 0 0 0)
			(layer "F.SilkS")
			(hide yes)
			(effects
				(font
					(size 1.27 1.27)
				)
			)
		)
		(property "Value" ""
			(at 0 0 0)
			(layer "F.Fab")
			(effects
				(font
					(size 1.27 1.27)
				)
			)
		)
		(duplicate_pad_numbers_are_jumpers no)
		(fp_line
			(start -0.7874 -0.4064)
			(end 0.7874 -0.4064)
			(stroke
				(width 0.1524)
				(type default)
			)
			(layer "F.SilkS")
		)
		(fp_line
			(start -0.7874 0.4064)
			(end -0.7874 -0.4064)
			(stroke
				(width 0.1524)
				(type default)
			)
			(layer "F.SilkS")
		)
		(fp_line
			(start 0.7874 -0.4064)
			(end 0.7874 0.4064)
			(stroke
				(width 0.1524)
				(type default)
			)
			(layer "F.SilkS")
		)
		(fp_line
			(start 0.7874 0.4064)
			(end -0.7874 0.4064)
			(stroke
				(width 0.1524)
				(type default)
			)
			(layer "F.SilkS")
		)
		(fp_line
			(start -0.67945 -0.305054)
			(end -0.12065 -0.305054)
			(stroke
				(width 0.1)
				(type default)
			)
			(layer "F.Fab")
		)
		(fp_line
			(start -0.67945 0.3048)
			(end -0.67945 -0.305054)
			(stroke
				(width 0.1)
				(type default)
			)
			(layer "F.Fab")
		)
		(fp_line
			(start -0.12065 -0.305054)
			(end -0.12065 -0.2794)
			(stroke
				(width 0.1)
				(type default)
			)
			(layer "F.Fab")
		)
		(fp_line
			(start -0.12065 -0.2794)
			(end 0.12065 -0.2794)
			(stroke
				(width 0.1)
				(type default)
			)
			(layer "F.Fab")
		)
		(fp_line
			(start -0.12065 0.2794)
			(end -0.12065 0.3048)
			(stroke
				(width 0.1)
				(type default)
			)
			(layer "F.Fab")
		)
		(fp_line
			(start -0.12065 0.3048)
			(end -0.67945 0.3048)
			(stroke
				(width 0.1)
				(type default)
			)
			(layer "F.Fab")
		)
		(fp_line
			(start 0.120396 0.2794)
			(end -0.12065 0.2794)
			(stroke
				(width 0.1)
				(type default)
			)
			(layer "F.Fab")
		)
		(fp_line
			(start 0.120396 0.3048)
			(end 0.120396 0.2794)
			(stroke
				(width 0.1)
				(type default)
			)
			(layer "F.Fab")
		)
		(fp_line
			(start 0.12065 -0.3048)
			(end 0.67945 -0.3048)
			(stroke
				(width 0.1)
				(type default)
			)
			(layer "F.Fab")
		)
		(fp_line
			(start 0.12065 -0.2794)
			(end 0.12065 -0.3048)
			(stroke
				(width 0.1)
				(type default)
			)
			(layer "F.Fab")
		)
		(fp_line
			(start 0.67945 -0.3048)
			(end 0.67945 0.3048)
			(stroke
				(width 0.1)
				(type default)
			)
			(layer "F.Fab")
		)
		(fp_line
			(start 0.67945 0.3048)
			(end 0.120396 0.3048)
			(stroke
				(width 0.1)
				(type default)
			)
			(layer "F.Fab")
		)
		(pad "1" smd circle
			(at -0.40005 0)
			(size 0 0)
			(layers "F.Cu" "F.Mask" "F.Paste")
			(net "PEX0_P1V25_ADC_A1")
		)
		(pad "2" smd circle
			(at 0.40005 0)
			(size 0 0)
			(layers "F.Cu" "F.Mask" "F.Paste")
			(net "P3V3_AUX")
		)
	)
	(footprint ""
		(layer "F.Cu")
		(at 173.854364 -48.21809)
		(property "Reference" "PD64"
			(at -3.471164 2.24536 0)
			(unlocked yes)
			(layer "F.SilkS")
			(effects
				(font
					(size 0.7874 0.5842)
					(thickness 0.1524)
				)
				(justify left)
			)
		)
		(property "Value" ""
			(at 0 0 0)
			(layer "F.Fab")
			(effects
				(font
					(size 1.27 1.27)
				)
			)
		)
		(duplicate_pad_numbers_are_jumpers no)
		(fp_line
			(start -3.400044 -1.459992)
			(end 4.107942 -1.459992)
			(stroke
				(width 0.1524)
				(type default)
			)
			(layer "F.SilkS")
		)
		(fp_line
			(start -3.400044 1.459992)
			(end -3.400044 -1.459992)
			(stroke
				(width 0.1524)
				(type default)
			)
			(layer "F.SilkS")
		)
		(fp_line
			(start 4.107942 -1.459992)
			(end 4.107942 1.459992)
			(stroke
				(width 0.1524)
				(type default)
			)
			(layer "F.SilkS")
		)
		(fp_line
			(start 4.107942 1.459992)
			(end -3.400044 1.459992)
			(stroke
				(width 0.1524)
				(type default)
			)
			(layer "F.SilkS")
		)
		(fp_poly
			(pts
				(xy 4.107942 -1.459992) (xy 4.107942 1.459992) (xy 3.308096 1.459992) (xy 3.308096 -1.459992)
			)
			(stroke
				(width 0)
				(type default)
			)
			(fill yes)
			(layer "F.SilkS")
		)
		(fp_line
			(start -2.29997 -1.459992)
			(end 2.29997 -1.459992)
			(stroke
				(width 0.1)
				(type default)
			)
			(layer "F.Fab")
		)
		(fp_line
			(start -2.29997 1.459992)
			(end -2.29997 -1.459992)
			(stroke
				(width 0.1)
				(type default)
			)
			(layer "F.Fab")
		)
		(fp_line
			(start 2.29997 -1.459992)
			(end 2.29997 1.459992)
			(stroke
				(width 0.1)
				(type default)
			)
			(layer "F.Fab")
		)
		(fp_line
			(start 2.29997 1.459992)
			(end -2.29997 1.459992)
			(stroke
				(width 0.1)
				(type default)
			)
			(layer "F.Fab")
		)
		(fp_text user "+"
			(at -4.7752 -0.12065 0)
			(unlocked yes)
			(layer "F.SilkS")
			(effects
				(font
					(size 1.905 1.4224)
					(thickness 0.1524)
				)
				(justify left)
			)
		)
		(fp_text user "-"
			(at 5.4102 0.29845 180)
			(unlocked yes)
			(layer "F.SilkS")
			(effects
				(font
					(size 1.905 1.4224)
					(thickness 0.1524)
				)
				(justify left)
			)
		)
		(fp_text user "+"
			(at -4.7752 -0.12065 0)
			(unlocked yes)
			(layer "F.Fab")
			(effects
				(font
					(size 1.905 1.4224)
					(thickness 0.1524)
				)
				(justify left)
			)
		)
		(fp_text user "-"
			(at 5.4102 0.29845 180)
			(unlocked yes)
			(layer "F.Fab")
			(effects
				(font
					(size 1.905 1.4224)
					(thickness 0.1524)
				)
				(justify left)
			)
		)
		(pad "A" smd rect
			(at -1.999996 0 90)
			(size 1.7018 2.5146)
			(layers "F.Cu" "F.Mask" "F.Paste")
			(net "GND")
		)
		(pad "C" smd rect
			(at 1.999996 0 90)
			(size 1.7018 2.5146)
			(layers "F.Cu" "F.Mask" "F.Paste")
			(net "P3V3_SSD6")
		)
	)
	(footprint ""
		(layer "F.Cu")
		(at 123.67514 -91.462606)
		(property "Reference" "R1585"
			(at 0 0 0)
			(layer "F.SilkS")
			(hide yes)
			(effects
				(font
					(size 1.27 1.27)
				)
			)
		)
		(property "Value" ""
			(at 0 0 0)
			(layer "F.Fab")
			(effects
				(font
					(size 1.27 1.27)
				)
			)
		)
		(duplicate_pad_numbers_are_jumpers no)
		(fp_line
			(start -0.7874 -0.4064)
			(end 0.7874 -0.4064)
			(stroke
				(width 0.1524)
				(type default)
			)
			(layer "F.SilkS")
		)
		(fp_line
			(start -0.7874 0.4064)
			(end -0.7874 -0.4064)
			(stroke
				(width 0.1524)
				(type default)
			)
			(layer "F.SilkS")
		)
		(fp_line
			(start 0.7874 -0.4064)
			(end 0.7874 0.4064)
			(stroke
				(width 0.1524)
				(type default)
			)
			(layer "F.SilkS")
		)
		(fp_line
			(start 0.7874 0.4064)
			(end -0.7874 0.4064)
			(stroke
				(width 0.1524)
				(type default)
			)
			(layer "F.SilkS")
		)
		(fp_line
			(start -0.67945 -0.305054)
			(end -0.12065 -0.305054)
			(stroke
				(width 0.1)
				(type default)
			)
			(layer "F.Fab")
		)
		(fp_line
			(start -0.67945 0.3048)
			(end -0.67945 -0.305054)
			(stroke
				(width 0.1)
				(type default)
			)
			(layer "F.Fab")
		)
		(fp_line
			(start -0.12065 -0.305054)
			(end -0.12065 -0.2794)
			(stroke
				(width 0.1)
				(type default)
			)
			(layer "F.Fab")
		)
		(fp_line
			(start -0.12065 -0.2794)
			(end 0.12065 -0.2794)
			(stroke
				(width 0.1)
				(type default)
			)
			(layer "F.Fab")
		)
		(fp_line
			(start -0.12065 0.2794)
			(end -0.12065 0.3048)
			(stroke
				(width 0.1)
				(type default)
			)
			(layer "F.Fab")
		)
		(fp_line
			(start -0.12065 0.3048)
			(end -0.67945 0.3048)
			(stroke
				(width 0.1)
				(type default)
			)
			(layer "F.Fab")
		)
		(fp_line
			(start 0.120396 0.2794)
			(end -0.12065 0.2794)
			(stroke
				(width 0.1)
				(type default)
			)
			(layer "F.Fab")
		)
		(fp_line
			(start 0.120396 0.3048)
			(end 0.120396 0.2794)
			(stroke
				(width 0.1)
				(type default)
			)
			(layer "F.Fab")
		)
		(fp_line
			(start 0.12065 -0.3048)
			(end 0.67945 -0.3048)
			(stroke
				(width 0.1)
				(type default)
			)
			(layer "F.Fab")
		)
		(fp_line
			(start 0.12065 -0.2794)
			(end 0.12065 -0.3048)
			(stroke
				(width 0.1)
				(type default)
			)
			(layer "F.Fab")
		)
		(fp_line
			(start 0.67945 -0.3048)
			(end 0.67945 0.3048)
			(stroke
				(width 0.1)
				(type default)
			)
			(layer "F.Fab")
		)
		(fp_line
			(start 0.67945 0.3048)
			(end 0.120396 0.3048)
			(stroke
				(width 0.1)
				(type default)
			)
			(layer "F.Fab")
		)
		(pad "1" smd circle
			(at -0.40005 0)
			(size 0 0)
			(layers "F.Cu" "F.Mask" "F.Paste")
			(net "SMB_BIC_I2C9_MUX0_SSD2_R_SCL")
		)
		(pad "2" smd circle
			(at 0.40005 0)
			(size 0 0)
			(layers "F.Cu" "F.Mask" "F.Paste")
			(net "SMB_BIC_I2C9_MUX0_SSD2_SCL")
		)
	)
	(footprint ""
		(layer "F.Cu")
		(at 154.567636 -218.02852)
		(property "Reference" "ME1"
			(at 0 0 0)
			(layer "F.SilkS")
			(hide yes)
			(effects
				(font
					(size 1.27 1.27)
				)
			)
		)
		(property "Value" ""
			(at 0 0 0)
			(layer "F.Fab")
			(effects
				(font
					(size 1.27 1.27)
				)
			)
		)
		(duplicate_pad_numbers_are_jumpers no)
		(fp_line
			(start 0.089408 -2.660396)
			(end 1.561846 -4.072636)
			(stroke
				(width 0.1)
				(type default)
			)
			(layer "F.SilkS")
		)
		(fp_line
			(start 0.089408 -2.660396)
			(end 1.561846 -4.072636)
			(stroke
				(width 0.1)
				(type default)
			)
			(layer "F.SilkS")
		)
		(fp_line
			(start 0.098806 -2.611628)
			(end 1.482344 -3.938778)
			(stroke
				(width 0.1)
				(type default)
			)
			(layer "F.SilkS")
		)
		(fp_line
			(start 0.098806 -2.611628)
			(end 1.482344 -3.938778)
			(stroke
				(width 0.1)
				(type default)
			)
			(layer "F.SilkS")
		)
		(fp_line
			(start 0.108204 -2.563114)
			(end 1.4224 -3.823716)
			(stroke
				(width 0.1)
				(type default)
			)
			(layer "F.SilkS")
		)
		(fp_line
			(start 0.108204 -2.563114)
			(end 1.4224 -3.823716)
			(stroke
				(width 0.1)
				(type default)
			)
			(layer "F.SilkS")
		)
		(fp_line
			(start 0.117602 -2.514346)
			(end 1.38557 -3.730498)
			(stroke
				(width 0.1)
				(type default)
			)
			(layer "F.SilkS")
		)
		(fp_line
			(start 0.117602 -2.514346)
			(end 1.38557 -3.730498)
			(stroke
				(width 0.1)
				(type default)
			)
			(layer "F.SilkS")
		)
		(fp_line
			(start 0.127254 -2.465832)
			(end 1.360932 -3.649218)
			(stroke
				(width 0.1)
				(type default)
			)
			(layer "F.SilkS")
		)
		(fp_line
			(start 0.127254 -2.465832)
			(end 1.360932 -3.649218)
			(stroke
				(width 0.1)
				(type default)
			)
			(layer "F.SilkS")
		)
		(fp_line
			(start 0.139954 -2.420366)
			(end 1.336548 -3.568192)
			(stroke
				(width 0.1)
				(type default)
			)
			(layer "F.SilkS")
		)
		(fp_line
			(start 0.139954 -2.420366)
			(end 1.336548 -3.568192)
			(stroke
				(width 0.1)
				(type default)
			)
			(layer "F.SilkS")
		)
		(fp_line
			(start 0.152908 -2.3749)
			(end 1.31445 -3.489198)
			(stroke
				(width 0.1)
				(type default)
			)
			(layer "F.SilkS")
		)
		(fp_line
			(start 0.152908 -2.3749)
			(end 1.31445 -3.489198)
			(stroke
				(width 0.1)
				(type default)
			)
			(layer "F.SilkS")
		)
		(fp_line
			(start 0.165608 -2.329434)
			(end 1.307592 -3.424936)
			(stroke
				(width 0.1)
				(type default)
			)
			(layer "F.SilkS")
		)
		(fp_line
			(start 0.165608 -2.329434)
			(end 1.307592 -3.424936)
			(stroke
				(width 0.1)
				(type default)
			)
			(layer "F.SilkS")
		)
		(fp_line
			(start 0.178562 -2.284222)
			(end 1.300988 -3.360674)
			(stroke
				(width 0.1)
				(type default)
			)
			(layer "F.SilkS")
		)
		(fp_line
			(start 0.178562 -2.284222)
			(end 1.300988 -3.360674)
			(stroke
				(width 0.1)
				(type default)
			)
			(layer "F.SilkS")
		)
		(fp_line
			(start 0.191516 -2.238756)
			(end 1.29413 -3.296412)
			(stroke
				(width 0.1)
				(type default)
			)
			(layer "F.SilkS")
		)
		(fp_line
			(start 0.191516 -2.238756)
			(end 1.29413 -3.296412)
			(stroke
				(width 0.1)
				(type default)
			)
			(layer "F.SilkS")
		)
		(fp_line
			(start 0.205994 -2.195068)
			(end 1.287526 -3.232404)
			(stroke
				(width 0.1)
				(type default)
			)
			(layer "F.SilkS")
		)
		(fp_line
			(start 0.205994 -2.195068)
			(end 1.287526 -3.232404)
			(stroke
				(width 0.1)
				(type default)
			)
			(layer "F.SilkS")
		)
		(fp_line
			(start 0.222504 -2.153158)
			(end 1.2827 -3.170174)
			(stroke
				(width 0.1)
				(type default)
			)
			(layer "F.SilkS")
		)
		(fp_line
			(start 0.222504 -2.153158)
			(end 1.2827 -3.170174)
			(stroke
				(width 0.1)
				(type default)
			)
			(layer "F.SilkS")
		)
		(fp_line
			(start 0.239268 -2.111502)
			(end 1.287018 -3.11658)
			(stroke
				(width 0.1)
				(type default)
			)
			(layer "F.SilkS")
		)
		(fp_line
			(start 0.239268 -2.111502)
			(end 1.287018 -3.11658)
			(stroke
				(width 0.1)
				(type default)
			)
			(layer "F.SilkS")
		)
		(fp_line
			(start 0.256032 -2.069846)
			(end 1.291082 -3.062732)
			(stroke
				(width 0.1)
				(type default)
			)
			(layer "F.SilkS")
		)
		(fp_line
			(start 0.256032 -2.069846)
			(end 1.291082 -3.062732)
			(stroke
				(width 0.1)
				(type default)
			)
			(layer "F.SilkS")
		)
		(fp_line
			(start 0.272796 -2.02819)
			(end 1.295146 -3.009138)
			(stroke
				(width 0.1)
				(type default)
			)
			(layer "F.SilkS")
		)
		(fp_line
			(start 0.272796 -2.02819)
			(end 1.295146 -3.009138)
			(stroke
				(width 0.1)
				(type default)
			)
			(layer "F.SilkS")
		)
		(fp_line
			(start 0.289306 -1.986534)
			(end 1.299464 -2.955544)
			(stroke
				(width 0.1)
				(type default)
			)
			(layer "F.SilkS")
		)
		(fp_line
			(start 0.289306 -1.986534)
			(end 1.299464 -2.955544)
			(stroke
				(width 0.1)
				(type default)
			)
			(layer "F.SilkS")
		)
		(fp_line
			(start 0.307086 -1.94564)
			(end 1.303528 -2.901696)
			(stroke
				(width 0.1)
				(type default)
			)
			(layer "F.SilkS")
		)
		(fp_line
			(start 0.307086 -1.94564)
			(end 1.303528 -2.901696)
			(stroke
				(width 0.1)
				(type default)
			)
			(layer "F.SilkS")
		)
		(fp_line
			(start 0.327914 -1.908048)
			(end 1.31318 -2.853182)
			(stroke
				(width 0.1)
				(type default)
			)
			(layer "F.SilkS")
		)
		(fp_line
			(start 0.327914 -1.908048)
			(end 1.31318 -2.853182)
			(stroke
				(width 0.1)
				(type default)
			)
			(layer "F.SilkS")
		)
		(fp_line
			(start 0.348996 -1.870456)
			(end 1.325118 -2.8067)
			(stroke
				(width 0.1)
				(type default)
			)
			(layer "F.SilkS")
		)
		(fp_line
			(start 0.348996 -1.870456)
			(end 1.325118 -2.8067)
			(stroke
				(width 0.1)
				(type default)
			)
			(layer "F.SilkS")
		)
		(fp_line
			(start 0.369824 -1.832864)
			(end 1.336802 -2.760472)
			(stroke
				(width 0.1)
				(type default)
			)
			(layer "F.SilkS")
		)
		(fp_line
			(start 0.369824 -1.832864)
			(end 1.336802 -2.760472)
			(stroke
				(width 0.1)
				(type default)
			)
			(layer "F.SilkS")
		)
		(fp_line
			(start 0.390906 -1.795272)
			(end 1.348486 -2.714244)
			(stroke
				(width 0.1)
				(type default)
			)
			(layer "F.SilkS")
		)
		(fp_line
			(start 0.390906 -1.795272)
			(end 1.348486 -2.714244)
			(stroke
				(width 0.1)
				(type default)
			)
			(layer "F.SilkS")
		)
		(fp_line
			(start 0.411988 -1.75768)
			(end 1.360424 -2.667508)
			(stroke
				(width 0.1)
				(type default)
			)
			(layer "F.SilkS")
		)
		(fp_line
			(start 0.411988 -1.75768)
			(end 1.360424 -2.667508)
			(stroke
				(width 0.1)
				(type default)
			)
			(layer "F.SilkS")
		)
		(fp_line
			(start 0.432816 -1.720088)
			(end 1.372362 -2.62128)
			(stroke
				(width 0.1)
				(type default)
			)
			(layer "F.SilkS")
		)
		(fp_line
			(start 0.432816 -1.720088)
			(end 1.372362 -2.62128)
			(stroke
				(width 0.1)
				(type default)
			)
			(layer "F.SilkS")
		)
		(fp_line
			(start 0.456184 -1.684782)
			(end 1.387856 -2.578608)
			(stroke
				(width 0.1)
				(type default)
			)
			(layer "F.SilkS")
		)
		(fp_line
			(start 0.456184 -1.684782)
			(end 1.387856 -2.578608)
			(stroke
				(width 0.1)
				(type default)
			)
			(layer "F.SilkS")
		)
		(fp_line
			(start 0.481838 -1.651762)
			(end 1.40589 -2.538222)
			(stroke
				(width 0.1)
				(type default)
			)
			(layer "F.SilkS")
		)
		(fp_line
			(start 0.481838 -1.651762)
			(end 1.40589 -2.538222)
			(stroke
				(width 0.1)
				(type default)
			)
			(layer "F.SilkS")
		)
		(fp_line
			(start 0.507746 -1.618742)
			(end 1.423924 -2.497836)
			(stroke
				(width 0.1)
				(type default)
			)
			(layer "F.SilkS")
		)
		(fp_line
			(start 0.507746 -1.618742)
			(end 1.423924 -2.497836)
			(stroke
				(width 0.1)
				(type default)
			)
			(layer "F.SilkS")
		)
		(fp_line
			(start 0.5334 -1.585722)
			(end 1.441958 -2.457196)
			(stroke
				(width 0.1)
				(type default)
			)
			(layer "F.SilkS")
		)
		(fp_line
			(start 0.5334 -1.585722)
			(end 1.441958 -2.457196)
			(stroke
				(width 0.1)
				(type default)
			)
			(layer "F.SilkS")
		)
		(fp_line
			(start 0.559054 -1.552702)
			(end 1.459992 -2.41681)
			(stroke
				(width 0.1)
				(type default)
			)
			(layer "F.SilkS")
		)
		(fp_line
			(start 0.559054 -1.552702)
			(end 1.459992 -2.41681)
			(stroke
				(width 0.1)
				(type default)
			)
			(layer "F.SilkS")
		)
		(fp_line
			(start 0.584962 -1.519682)
			(end 1.477772 -2.376424)
			(stroke
				(width 0.1)
				(type default)
			)
			(layer "F.SilkS")
		)
		(fp_line
			(start 0.584962 -1.519682)
			(end 1.477772 -2.376424)
			(stroke
				(width 0.1)
				(type default)
			)
			(layer "F.SilkS")
		)
		(fp_line
			(start 0.610616 -1.486916)
			(end 1.496568 -2.336546)
			(stroke
				(width 0.1)
				(type default)
			)
			(layer "F.SilkS")
		)
		(fp_line
			(start 0.610616 -1.486916)
			(end 1.496568 -2.336546)
			(stroke
				(width 0.1)
				(type default)
			)
			(layer "F.SilkS")
		)
		(fp_line
			(start 0.637794 -1.455166)
			(end 1.52019 -2.301494)
			(stroke
				(width 0.1)
				(type default)
			)
			(layer "F.SilkS")
		)
		(fp_line
			(start 0.637794 -1.455166)
			(end 1.52019 -2.301494)
			(stroke
				(width 0.1)
				(type default)
			)
			(layer "F.SilkS")
		)
		(fp_line
			(start 0.668274 -1.426464)
			(end 1.543558 -2.266188)
			(stroke
				(width 0.1)
				(type default)
			)
			(layer "F.SilkS")
		)
		(fp_line
			(start 0.668274 -1.426464)
			(end 1.543558 -2.266188)
			(stroke
				(width 0.1)
				(type default)
			)
			(layer "F.SilkS")
		)
		(fp_line
			(start 0.6985 -1.397762)
			(end 1.56718 -2.231136)
			(stroke
				(width 0.1)
				(type default)
			)
			(layer "F.SilkS")
		)
		(fp_line
			(start 0.6985 -1.397762)
			(end 1.56718 -2.231136)
			(stroke
				(width 0.1)
				(type default)
			)
			(layer "F.SilkS")
		)
		(fp_line
			(start 0.728726 -1.36906)
			(end 1.590802 -2.196084)
			(stroke
				(width 0.1)
				(type default)
			)
			(layer "F.SilkS")
		)
		(fp_line
			(start 0.728726 -1.36906)
			(end 1.590802 -2.196084)
			(stroke
				(width 0.1)
				(type default)
			)
			(layer "F.SilkS")
		)
		(fp_line
			(start 0.758952 -1.340358)
			(end 1.61417 -2.160778)
			(stroke
				(width 0.1)
				(type default)
			)
			(layer "F.SilkS")
		)
		(fp_line
			(start 0.758952 -1.340358)
			(end 1.61417 -2.160778)
			(stroke
				(width 0.1)
				(type default)
			)
			(layer "F.SilkS")
		)
		(fp_line
			(start 0.789178 -1.31191)
			(end 1.637792 -2.125726)
			(stroke
				(width 0.1)
				(type default)
			)
			(layer "F.SilkS")
		)
		(fp_line
			(start 0.789178 -1.31191)
			(end 1.637792 -2.125726)
			(stroke
				(width 0.1)
				(type default)
			)
			(layer "F.SilkS")
		)
		(fp_line
			(start 0.819404 -1.282954)
			(end 1.663954 -2.09296)
			(stroke
				(width 0.1)
				(type default)
			)
			(layer "F.SilkS")
		)
		(fp_line
			(start 0.819404 -1.282954)
			(end 1.663954 -2.09296)
			(stroke
				(width 0.1)
				(type default)
			)
			(layer "F.SilkS")
		)
		(fp_line
			(start 0.851408 -1.25603)
			(end 1.69291 -2.063242)
			(stroke
				(width 0.1)
				(type default)
			)
			(layer "F.SilkS")
		)
		(fp_line
			(start 0.851408 -1.25603)
			(end 1.69291 -2.063242)
			(stroke
				(width 0.1)
				(type default)
			)
			(layer "F.SilkS")
		)
		(fp_line
			(start 0.885698 -1.230884)
			(end 1.72212 -2.03327)
			(stroke
				(width 0.1)
				(type default)
			)
			(layer "F.SilkS")
		)
		(fp_line
			(start 0.885698 -1.230884)
			(end 1.72212 -2.03327)
			(stroke
				(width 0.1)
				(type default)
			)
			(layer "F.SilkS")
		)
		(fp_line
			(start 0.919734 -1.206246)
			(end 1.751076 -2.003552)
			(stroke
				(width 0.1)
				(type default)
			)
			(layer "F.SilkS")
		)
		(fp_line
			(start 0.919734 -1.206246)
			(end 1.751076 -2.003552)
			(stroke
				(width 0.1)
				(type default)
			)
			(layer "F.SilkS")
		)
		(fp_line
			(start 0.954024 -1.1811)
			(end 1.780032 -1.973834)
			(stroke
				(width 0.1)
				(type default)
			)
			(layer "F.SilkS")
		)
		(fp_line
			(start 0.954024 -1.1811)
			(end 1.780032 -1.973834)
			(stroke
				(width 0.1)
				(type default)
			)
			(layer "F.SilkS")
		)
		(fp_line
			(start 0.988314 -1.156462)
			(end 1.809242 -1.943862)
			(stroke
				(width 0.1)
				(type default)
			)
			(layer "F.SilkS")
		)
		(fp_line
			(start 0.988314 -1.156462)
			(end 1.809242 -1.943862)
			(stroke
				(width 0.1)
				(type default)
			)
			(layer "F.SilkS")
		)
		(fp_line
			(start 1.02235 -1.13157)
			(end 1.838452 -1.914144)
			(stroke
				(width 0.1)
				(type default)
			)
			(layer "F.SilkS")
		)
		(fp_line
			(start 1.02235 -1.13157)
			(end 1.838452 -1.914144)
			(stroke
				(width 0.1)
				(type default)
			)
			(layer "F.SilkS")
		)
		(fp_line
			(start 1.05664 -1.106678)
			(end 1.872488 -1.889252)
			(stroke
				(width 0.1)
				(type default)
			)
			(layer "F.SilkS")
		)
		(fp_line
			(start 1.05664 -1.106678)
			(end 1.872488 -1.889252)
			(stroke
				(width 0.1)
				(type default)
			)
			(layer "F.SilkS")
		)
		(fp_line
			(start 1.09347 -1.084326)
			(end 1.907794 -1.865376)
			(stroke
				(width 0.1)
				(type default)
			)
			(layer "F.SilkS")
		)
		(fp_line
			(start 1.09347 -1.084326)
			(end 1.907794 -1.865376)
			(stroke
				(width 0.1)
				(type default)
			)
			(layer "F.SilkS")
		)
		(fp_line
			(start 1.131824 -1.063498)
			(end 1.9431 -1.8415)
			(stroke
				(width 0.1)
				(type default)
			)
			(layer "F.SilkS")
		)
		(fp_line
			(start 1.131824 -1.063498)
			(end 1.9431 -1.8415)
			(stroke
				(width 0.1)
				(type default)
			)
			(layer "F.SilkS")
		)
		(fp_line
			(start 1.133856 -5.220462)
			(end 0.47117 -4.5847)
			(stroke
				(width 0.1)
				(type default)
			)
			(layer "F.SilkS")
		)
		(fp_line
			(start 1.133856 -5.220462)
			(end 0.47117 -4.5847)
			(stroke
				(width 0.1)
				(type default)
			)
			(layer "F.SilkS")
		)
		(fp_line
			(start 1.170178 -1.042416)
			(end 1.978406 -1.817624)
			(stroke
				(width 0.1)
				(type default)
			)
			(layer "F.SilkS")
		)
		(fp_line
			(start 1.170178 -1.042416)
			(end 1.978406 -1.817624)
			(stroke
				(width 0.1)
				(type default)
			)
			(layer "F.SilkS")
		)
		(fp_line
			(start 1.208532 -1.021334)
			(end 2.013458 -1.793748)
			(stroke
				(width 0.1)
				(type default)
			)
			(layer "F.SilkS")
		)
		(fp_line
			(start 1.208532 -1.021334)
			(end 2.013458 -1.793748)
			(stroke
				(width 0.1)
				(type default)
			)
			(layer "F.SilkS")
		)
		(fp_line
			(start 1.246886 -1.000506)
			(end 2.048764 -1.769872)
			(stroke
				(width 0.1)
				(type default)
			)
			(layer "F.SilkS")
		)
		(fp_line
			(start 1.246886 -1.000506)
			(end 2.048764 -1.769872)
			(stroke
				(width 0.1)
				(type default)
			)
			(layer "F.SilkS")
		)
		(fp_line
			(start 1.28524 -0.979424)
			(end 2.087626 -1.749298)
			(stroke
				(width 0.1)
				(type default)
			)
			(layer "F.SilkS")
		)
		(fp_line
			(start 1.28524 -0.979424)
			(end 2.087626 -1.749298)
			(stroke
				(width 0.1)
				(type default)
			)
			(layer "F.SilkS")
		)
		(fp_line
			(start 1.293368 -5.315966)
			(end 0.37465 -4.434332)
			(stroke
				(width 0.1)
				(type default)
			)
			(layer "F.SilkS")
		)
		(fp_line
			(start 1.293368 -5.315966)
			(end 0.37465 -4.434332)
			(stroke
				(width 0.1)
				(type default)
			)
			(layer "F.SilkS")
		)
		(fp_line
			(start 1.323594 -0.958596)
			(end 2.130552 -1.732788)
			(stroke
				(width 0.1)
				(type default)
			)
			(layer "F.SilkS")
		)
		(fp_line
			(start 1.323594 -0.958596)
			(end 2.130552 -1.732788)
			(stroke
				(width 0.1)
				(type default)
			)
			(layer "F.SilkS")
		)
		(fp_line
			(start 1.366266 -0.941832)
			(end 2.173478 -1.716024)
			(stroke
				(width 0.1)
				(type default)
			)
			(layer "F.SilkS")
		)
		(fp_line
			(start 1.366266 -0.941832)
			(end 2.173478 -1.716024)
			(stroke
				(width 0.1)
				(type default)
			)
			(layer "F.SilkS")
		)
		(fp_line
			(start 1.408684 -0.924814)
			(end 2.21615 -1.699514)
			(stroke
				(width 0.1)
				(type default)
			)
			(layer "F.SilkS")
		)
		(fp_line
			(start 1.408684 -0.924814)
			(end 2.21615 -1.699514)
			(stroke
				(width 0.1)
				(type default)
			)
			(layer "F.SilkS")
		)
		(fp_line
			(start 1.41224 -5.3721)
			(end 0.302768 -4.307586)
			(stroke
				(width 0.1)
				(type default)
			)
			(layer "F.SilkS")
		)
		(fp_line
			(start 1.41224 -5.3721)
			(end 0.302768 -4.307586)
			(stroke
				(width 0.1)
				(type default)
			)
			(layer "F.SilkS")
		)
		(fp_line
			(start 1.451356 -0.90805)
			(end 2.259076 -1.68275)
			(stroke
				(width 0.1)
				(type default)
			)
			(layer "F.SilkS")
		)
		(fp_line
			(start 1.451356 -0.90805)
			(end 2.259076 -1.68275)
			(stroke
				(width 0.1)
				(type default)
			)
			(layer "F.SilkS")
		)
		(fp_line
			(start 1.493774 -0.891032)
			(end 2.301748 -1.66624)
			(stroke
				(width 0.1)
				(type default)
			)
			(layer "F.SilkS")
		)
		(fp_line
			(start 1.493774 -0.891032)
			(end 2.301748 -1.66624)
			(stroke
				(width 0.1)
				(type default)
			)
			(layer "F.SilkS")
		)
		(fp_line
			(start 1.52781 -5.425186)
			(end 0.256794 -4.205732)
			(stroke
				(width 0.1)
				(type default)
			)
			(layer "F.SilkS")
		)
		(fp_line
			(start 1.52781 -5.425186)
			(end 0.256794 -4.205732)
			(stroke
				(width 0.1)
				(type default)
			)
			(layer "F.SilkS")
		)
		(fp_line
			(start 1.536446 -0.874268)
			(end 2.351024 -1.655826)
			(stroke
				(width 0.1)
				(type default)
			)
			(layer "F.SilkS")
		)
		(fp_line
			(start 1.536446 -0.874268)
			(end 2.351024 -1.655826)
			(stroke
				(width 0.1)
				(type default)
			)
			(layer "F.SilkS")
		)
		(fp_line
			(start 1.578864 -0.857504)
			(end 2.404364 -1.649222)
			(stroke
				(width 0.1)
				(type default)
			)
			(layer "F.SilkS")
		)
		(fp_line
			(start 1.578864 -0.857504)
			(end 2.404364 -1.649222)
			(stroke
				(width 0.1)
				(type default)
			)
			(layer "F.SilkS")
		)
		(fp_line
			(start 1.62306 -5.458714)
			(end 0.211328 -4.10464)
			(stroke
				(width 0.1)
				(type default)
			)
			(layer "F.SilkS")
		)
		(fp_line
			(start 1.62306 -5.458714)
			(end 0.211328 -4.10464)
			(stroke
				(width 0.1)
				(type default)
			)
			(layer "F.SilkS")
		)
		(fp_line
			(start 1.623314 -0.842264)
			(end 2.457704 -1.642618)
			(stroke
				(width 0.1)
				(type default)
			)
			(layer "F.SilkS")
		)
		(fp_line
			(start 1.623314 -0.842264)
			(end 2.457704 -1.642618)
			(stroke
				(width 0.1)
				(type default)
			)
			(layer "F.SilkS")
		)
		(fp_line
			(start 1.67005 -0.829564)
			(end 2.511044 -1.636014)
			(stroke
				(width 0.1)
				(type default)
			)
			(layer "F.SilkS")
		)
		(fp_line
			(start 1.67005 -0.829564)
			(end 2.511044 -1.636014)
			(stroke
				(width 0.1)
				(type default)
			)
			(layer "F.SilkS")
		)
		(fp_line
			(start 1.716786 -0.816356)
			(end 2.56413 -1.62941)
			(stroke
				(width 0.1)
				(type default)
			)
			(layer "F.SilkS")
		)
		(fp_line
			(start 1.716786 -0.816356)
			(end 2.56413 -1.62941)
			(stroke
				(width 0.1)
				(type default)
			)
			(layer "F.SilkS")
		)
		(fp_line
			(start 1.717802 -5.492242)
			(end 0.181356 -4.018026)
			(stroke
				(width 0.1)
				(type default)
			)
			(layer "F.SilkS")
		)
		(fp_line
			(start 1.717802 -5.492242)
			(end 0.181356 -4.018026)
			(stroke
				(width 0.1)
				(type default)
			)
			(layer "F.SilkS")
		)
		(fp_line
			(start 1.763522 -0.803656)
			(end 2.624582 -1.629664)
			(stroke
				(width 0.1)
				(type default)
			)
			(layer "F.SilkS")
		)
		(fp_line
			(start 1.763522 -0.803656)
			(end 2.624582 -1.629664)
			(stroke
				(width 0.1)
				(type default)
			)
			(layer "F.SilkS")
		)
		(fp_line
			(start 1.805686 -5.518658)
			(end 0.1524 -3.932682)
			(stroke
				(width 0.1)
				(type default)
			)
			(layer "F.SilkS")
		)
		(fp_line
			(start 1.805686 -5.518658)
			(end 0.1524 -3.932682)
			(stroke
				(width 0.1)
				(type default)
			)
			(layer "F.SilkS")
		)
		(fp_line
			(start 1.810512 -0.790956)
			(end 2.692654 -1.637284)
			(stroke
				(width 0.1)
				(type default)
			)
			(layer "F.SilkS")
		)
		(fp_line
			(start 1.810512 -0.790956)
			(end 2.692654 -1.637284)
			(stroke
				(width 0.1)
				(type default)
			)
			(layer "F.SilkS")
		)
		(fp_line
			(start 1.856994 -0.777748)
			(end 2.760726 -1.64465)
			(stroke
				(width 0.1)
				(type default)
			)
			(layer "F.SilkS")
		)
		(fp_line
			(start 1.856994 -0.777748)
			(end 2.760726 -1.64465)
			(stroke
				(width 0.1)
				(type default)
			)
			(layer "F.SilkS")
		)
		(fp_line
			(start 1.886458 -5.538216)
			(end 0.128016 -3.851402)
			(stroke
				(width 0.1)
				(type default)
			)
			(layer "F.SilkS")
		)
		(fp_line
			(start 1.886458 -5.538216)
			(end 0.128016 -3.851402)
			(stroke
				(width 0.1)
				(type default)
			)
			(layer "F.SilkS")
		)
		(fp_line
			(start 1.90373 -0.765048)
			(end 2.828544 -1.65227)
			(stroke
				(width 0.1)
				(type default)
			)
			(layer "F.SilkS")
		)
		(fp_line
			(start 1.90373 -0.765048)
			(end 2.828544 -1.65227)
			(stroke
				(width 0.1)
				(type default)
			)
			(layer "F.SilkS")
		)
		(fp_line
			(start 1.954276 -0.75565)
			(end 2.906014 -1.66878)
			(stroke
				(width 0.1)
				(type default)
			)
			(layer "F.SilkS")
		)
		(fp_line
			(start 1.954276 -0.75565)
			(end 2.906014 -1.66878)
			(stroke
				(width 0.1)
				(type default)
			)
			(layer "F.SilkS")
		)
		(fp_line
			(start 1.966722 -5.557774)
			(end 0.110236 -3.776726)
			(stroke
				(width 0.1)
				(type default)
			)
			(layer "F.SilkS")
		)
		(fp_line
			(start 1.966722 -5.557774)
			(end 0.110236 -3.776726)
			(stroke
				(width 0.1)
				(type default)
			)
			(layer "F.SilkS")
		)
		(fp_line
			(start 2.00533 -0.74676)
			(end 3.000248 -1.701546)
			(stroke
				(width 0.1)
				(type default)
			)
			(layer "F.SilkS")
		)
		(fp_line
			(start 2.00533 -0.74676)
			(end 3.000248 -1.701546)
			(stroke
				(width 0.1)
				(type default)
			)
			(layer "F.SilkS")
		)
		(fp_line
			(start 2.04597 -5.576062)
			(end 0.092456 -3.70205)
			(stroke
				(width 0.1)
				(type default)
			)
			(layer "F.SilkS")
		)
		(fp_line
			(start 2.04597 -5.576062)
			(end 0.092456 -3.70205)
			(stroke
				(width 0.1)
				(type default)
			)
			(layer "F.SilkS")
		)
		(fp_line
			(start 2.05613 -0.73787)
			(end 3.094228 -1.733804)
			(stroke
				(width 0.1)
				(type default)
			)
			(layer "F.SilkS")
		)
		(fp_line
			(start 2.05613 -0.73787)
			(end 3.094228 -1.733804)
			(stroke
				(width 0.1)
				(type default)
			)
			(layer "F.SilkS")
		)
		(fp_line
			(start 2.10693 -0.72898)
			(end 3.238246 -1.814322)
			(stroke
				(width 0.1)
				(type default)
			)
			(layer "F.SilkS")
		)
		(fp_line
			(start 2.10693 -0.72898)
			(end 3.238246 -1.814322)
			(stroke
				(width 0.1)
				(type default)
			)
			(layer "F.SilkS")
		)
		(fp_line
			(start 2.116328 -5.585968)
			(end 0.07874 -3.631184)
			(stroke
				(width 0.1)
				(type default)
			)
			(layer "F.SilkS")
		)
		(fp_line
			(start 2.116328 -5.585968)
			(end 0.07874 -3.631184)
			(stroke
				(width 0.1)
				(type default)
			)
			(layer "F.SilkS")
		)
		(fp_line
			(start 2.18694 -5.595874)
			(end 0.069342 -3.564382)
			(stroke
				(width 0.1)
				(type default)
			)
			(layer "F.SilkS")
		)
		(fp_line
			(start 2.18694 -5.595874)
			(end 0.069342 -3.564382)
			(stroke
				(width 0.1)
				(type default)
			)
			(layer "F.SilkS")
		)
		(fp_line
			(start 2.208784 -0.710946)
			(end 5.142484 -3.52552)
			(stroke
				(width 0.1)
				(type default)
			)
			(layer "F.SilkS")
		)
		(fp_line
			(start 2.208784 -0.710946)
			(end 5.142484 -3.52552)
			(stroke
				(width 0.1)
				(type default)
			)
			(layer "F.SilkS")
		)
		(fp_line
			(start 2.257552 -5.60578)
			(end 0.059944 -3.49758)
			(stroke
				(width 0.1)
				(type default)
			)
			(layer "F.SilkS")
		)
		(fp_line
			(start 2.257552 -5.60578)
			(end 0.059944 -3.49758)
			(stroke
				(width 0.1)
				(type default)
			)
			(layer "F.SilkS")
		)
		(fp_line
			(start 2.2606 -0.703326)
			(end 5.147564 -3.472942)
			(stroke
				(width 0.1)
				(type default)
			)
			(layer "F.SilkS")
		)
		(fp_line
			(start 2.2606 -0.703326)
			(end 5.147564 -3.472942)
			(stroke
				(width 0.1)
				(type default)
			)
			(layer "F.SilkS")
		)
		(fp_line
			(start 2.315464 -0.698246)
			(end 5.152898 -3.42011)
			(stroke
				(width 0.1)
				(type default)
			)
			(layer "F.SilkS")
		)
		(fp_line
			(start 2.315464 -0.698246)
			(end 5.152898 -3.42011)
			(stroke
				(width 0.1)
				(type default)
			)
			(layer "F.SilkS")
		)
		(fp_line
			(start 2.32791 -5.615686)
			(end 0.051308 -3.431794)
			(stroke
				(width 0.1)
				(type default)
			)
			(layer "F.SilkS")
		)
		(fp_line
			(start 2.32791 -5.615686)
			(end 0.051308 -3.431794)
			(stroke
				(width 0.1)
				(type default)
			)
			(layer "F.SilkS")
		)
		(fp_line
			(start 2.370328 -0.693166)
			(end 5.156708 -3.366262)
			(stroke
				(width 0.1)
				(type default)
			)
			(layer "F.SilkS")
		)
		(fp_line
			(start 2.370328 -0.693166)
			(end 5.156708 -3.366262)
			(stroke
				(width 0.1)
				(type default)
			)
			(layer "F.SilkS")
		)
		(fp_line
			(start 2.390902 -5.61848)
			(end 0.048514 -3.371342)
			(stroke
				(width 0.1)
				(type default)
			)
			(layer "F.SilkS")
		)
		(fp_line
			(start 2.390902 -5.61848)
			(end 0.048514 -3.371342)
			(stroke
				(width 0.1)
				(type default)
			)
			(layer "F.SilkS")
		)
		(fp_line
			(start 2.424938 -0.687832)
			(end 5.158994 -3.310382)
			(stroke
				(width 0.1)
				(type default)
			)
			(layer "F.SilkS")
		)
		(fp_line
			(start 2.424938 -0.687832)
			(end 5.158994 -3.310382)
			(stroke
				(width 0.1)
				(type default)
			)
			(layer "F.SilkS")
		)
		(fp_line
			(start 2.454148 -5.621274)
			(end 0.04572 -3.31089)
			(stroke
				(width 0.1)
				(type default)
			)
			(layer "F.SilkS")
		)
		(fp_line
			(start 2.454148 -5.621274)
			(end 0.04572 -3.31089)
			(stroke
				(width 0.1)
				(type default)
			)
			(layer "F.SilkS")
		)
		(fp_line
			(start 2.479802 -0.682752)
			(end 5.16001 -3.25374)
			(stroke
				(width 0.1)
				(type default)
			)
			(layer "F.SilkS")
		)
		(fp_line
			(start 2.479802 -0.682752)
			(end 5.16001 -3.25374)
			(stroke
				(width 0.1)
				(type default)
			)
			(layer "F.SilkS")
		)
		(fp_line
			(start 2.517394 -5.624322)
			(end 0.042926 -3.250438)
			(stroke
				(width 0.1)
				(type default)
			)
			(layer "F.SilkS")
		)
		(fp_line
			(start 2.517394 -5.624322)
			(end 0.042926 -3.250438)
			(stroke
				(width 0.1)
				(type default)
			)
			(layer "F.SilkS")
		)
		(fp_line
			(start 2.534666 -0.677672)
			(end 5.15747 -3.193796)
			(stroke
				(width 0.1)
				(type default)
			)
			(layer "F.SilkS")
		)
		(fp_line
			(start 2.534666 -0.677672)
			(end 5.15747 -3.193796)
			(stroke
				(width 0.1)
				(type default)
			)
			(layer "F.SilkS")
		)
		(fp_line
			(start 2.580386 -5.626862)
			(end 0.041656 -3.19151)
			(stroke
				(width 0.1)
				(type default)
			)
			(layer "F.SilkS")
		)
		(fp_line
			(start 2.580386 -5.626862)
			(end 0.041656 -3.19151)
			(stroke
				(width 0.1)
				(type default)
			)
			(layer "F.SilkS")
		)
		(fp_line
			(start 2.589276 -0.672338)
			(end 5.15493 -3.133598)
			(stroke
				(width 0.1)
				(type default)
			)
			(layer "F.SilkS")
		)
		(fp_line
			(start 2.589276 -0.672338)
			(end 5.15493 -3.133598)
			(stroke
				(width 0.1)
				(type default)
			)
			(layer "F.SilkS")
		)
		(fp_line
			(start 2.64287 -5.629148)
			(end 0.042672 -3.135122)
			(stroke
				(width 0.1)
				(type default)
			)
			(layer "F.SilkS")
		)
		(fp_line
			(start 2.64287 -5.629148)
			(end 0.042672 -3.135122)
			(stroke
				(width 0.1)
				(type default)
			)
			(layer "F.SilkS")
		)
		(fp_line
			(start 2.646426 -0.669544)
			(end 5.15239 -3.073146)
			(stroke
				(width 0.1)
				(type default)
			)
			(layer "F.SilkS")
		)
		(fp_line
			(start 2.646426 -0.669544)
			(end 5.15239 -3.073146)
			(stroke
				(width 0.1)
				(type default)
			)
			(layer "F.SilkS")
		)
		(fp_line
			(start 2.700528 -5.626862)
			(end 0.04445 -3.078734)
			(stroke
				(width 0.1)
				(type default)
			)
			(layer "F.SilkS")
		)
		(fp_line
			(start 2.700528 -5.626862)
			(end 0.04445 -3.078734)
			(stroke
				(width 0.1)
				(type default)
			)
			(layer "F.SilkS")
		)
		(fp_line
			(start 2.704846 -0.66802)
			(end 5.14985 -3.013202)
			(stroke
				(width 0.1)
				(type default)
			)
			(layer "F.SilkS")
		)
		(fp_line
			(start 2.704846 -0.66802)
			(end 5.14985 -3.013202)
			(stroke
				(width 0.1)
				(type default)
			)
			(layer "F.SilkS")
		)
		(fp_line
			(start 2.75844 -5.62483)
			(end 0.048006 -3.024632)
			(stroke
				(width 0.1)
				(type default)
			)
			(layer "F.SilkS")
		)
		(fp_line
			(start 2.75844 -5.62483)
			(end 0.048006 -3.024632)
			(stroke
				(width 0.1)
				(type default)
			)
			(layer "F.SilkS")
		)
		(fp_line
			(start 2.76352 -0.666242)
			(end 5.14731 -2.953258)
			(stroke
				(width 0.1)
				(type default)
			)
			(layer "F.SilkS")
		)
		(fp_line
			(start 2.76352 -0.666242)
			(end 5.14731 -2.953258)
			(stroke
				(width 0.1)
				(type default)
			)
			(layer "F.SilkS")
		)
		(fp_line
			(start 2.816098 -5.622544)
			(end 0.051562 -2.970276)
			(stroke
				(width 0.1)
				(type default)
			)
			(layer "F.SilkS")
		)
		(fp_line
			(start 2.816098 -5.622544)
			(end 0.051562 -2.970276)
			(stroke
				(width 0.1)
				(type default)
			)
			(layer "F.SilkS")
		)
		(fp_line
			(start 2.82194 -0.664718)
			(end 5.145024 -2.89306)
			(stroke
				(width 0.1)
				(type default)
			)
			(layer "F.SilkS")
		)
		(fp_line
			(start 2.82194 -0.664718)
			(end 5.145024 -2.89306)
			(stroke
				(width 0.1)
				(type default)
			)
			(layer "F.SilkS")
		)
		(fp_line
			(start 2.87401 -5.620258)
			(end 0.054864 -2.91592)
			(stroke
				(width 0.1)
				(type default)
			)
			(layer "F.SilkS")
		)
		(fp_line
			(start 2.87401 -5.620258)
			(end 0.054864 -2.91592)
			(stroke
				(width 0.1)
				(type default)
			)
			(layer "F.SilkS")
		)
		(fp_line
			(start 2.88036 -0.662686)
			(end 5.13588 -2.826512)
			(stroke
				(width 0.1)
				(type default)
			)
			(layer "F.SilkS")
		)
		(fp_line
			(start 2.88036 -0.662686)
			(end 5.13588 -2.826512)
			(stroke
				(width 0.1)
				(type default)
			)
			(layer "F.SilkS")
		)
		(fp_line
			(start 2.92989 -5.616194)
			(end 0.061468 -2.864358)
			(stroke
				(width 0.1)
				(type default)
			)
			(layer "F.SilkS")
		)
		(fp_line
			(start 2.92989 -5.616194)
			(end 0.061468 -2.864358)
			(stroke
				(width 0.1)
				(type default)
			)
			(layer "F.SilkS")
		)
		(fp_line
			(start 2.93878 -0.661416)
			(end 5.126736 -2.760218)
			(stroke
				(width 0.1)
				(type default)
			)
			(layer "F.SilkS")
		)
		(fp_line
			(start 2.93878 -0.661416)
			(end 5.126736 -2.760218)
			(stroke
				(width 0.1)
				(type default)
			)
			(layer "F.SilkS")
		)
		(fp_line
			(start 2.98323 -5.609336)
			(end 0.067818 -2.812542)
			(stroke
				(width 0.1)
				(type default)
			)
			(layer "F.SilkS")
		)
		(fp_line
			(start 2.98323 -5.609336)
			(end 0.067818 -2.812542)
			(stroke
				(width 0.1)
				(type default)
			)
			(layer "F.SilkS")
		)
		(fp_line
			(start 2.9972 -0.659638)
			(end 5.117592 -2.69367)
			(stroke
				(width 0.1)
				(type default)
			)
			(layer "F.SilkS")
		)
		(fp_line
			(start 2.9972 -0.659638)
			(end 5.117592 -2.69367)
			(stroke
				(width 0.1)
				(type default)
			)
			(layer "F.SilkS")
		)
		(fp_line
			(start 3.03657 -5.602732)
			(end 0.073914 -2.76098)
			(stroke
				(width 0.1)
				(type default)
			)
			(layer "F.SilkS")
		)
		(fp_line
			(start 3.03657 -5.602732)
			(end 0.073914 -2.76098)
			(stroke
				(width 0.1)
				(type default)
			)
			(layer "F.SilkS")
		)
		(fp_line
			(start 3.048 -0.651002)
			(end 5.108194 -2.627122)
			(stroke
				(width 0.1)
				(type default)
			)
			(layer "F.SilkS")
		)
		(fp_line
			(start 3.048 -0.651002)
			(end 5.108194 -2.627122)
			(stroke
				(width 0.1)
				(type default)
			)
			(layer "F.SilkS")
		)
		(fp_line
			(start 3.089656 -5.596382)
			(end 0.080264 -2.709418)
			(stroke
				(width 0.1)
				(type default)
			)
			(layer "F.SilkS")
		)
		(fp_line
			(start 3.089656 -5.596382)
			(end 0.080264 -2.709418)
			(stroke
				(width 0.1)
				(type default)
			)
			(layer "F.SilkS")
		)
		(fp_line
			(start 3.094482 -0.637286)
			(end 5.09905 -2.560574)
			(stroke
				(width 0.1)
				(type default)
			)
			(layer "F.SilkS")
		)
		(fp_line
			(start 3.094482 -0.637286)
			(end 5.09905 -2.560574)
			(stroke
				(width 0.1)
				(type default)
			)
			(layer "F.SilkS")
		)
		(fp_line
			(start 3.13944 -0.622808)
			(end 5.081524 -2.485898)
			(stroke
				(width 0.1)
				(type default)
			)
			(layer "F.SilkS")
		)
		(fp_line
			(start 3.13944 -0.622808)
			(end 5.081524 -2.485898)
			(stroke
				(width 0.1)
				(type default)
			)
			(layer "F.SilkS")
		)
		(fp_line
			(start 3.14325 -5.589778)
			(end 1.972818 -4.467098)
			(stroke
				(width 0.1)
				(type default)
			)
			(layer "F.SilkS")
		)
		(fp_line
			(start 3.14325 -5.589778)
			(end 1.972818 -4.467098)
			(stroke
				(width 0.1)
				(type default)
			)
			(layer "F.SilkS")
		)
		(fp_line
			(start 3.184144 -0.60833)
			(end 5.061966 -2.409698)
			(stroke
				(width 0.1)
				(type default)
			)
			(layer "F.SilkS")
		)
		(fp_line
			(start 3.184144 -0.60833)
			(end 5.061966 -2.409698)
			(stroke
				(width 0.1)
				(type default)
			)
			(layer "F.SilkS")
		)
		(fp_line
			(start 3.19405 -5.580888)
			(end 2.123694 -4.553966)
			(stroke
				(width 0.1)
				(type default)
			)
			(layer "F.SilkS")
		)
		(fp_line
			(start 3.19405 -5.580888)
			(end 2.123694 -4.553966)
			(stroke
				(width 0.1)
				(type default)
			)
			(layer "F.SilkS")
		)
		(fp_line
			(start 3.22834 -0.592836)
			(end 5.042408 -2.33299)
			(stroke
				(width 0.1)
				(type default)
			)
			(layer "F.SilkS")
		)
		(fp_line
			(start 3.22834 -0.592836)
			(end 5.042408 -2.33299)
			(stroke
				(width 0.1)
				(type default)
			)
			(layer "F.SilkS")
		)
		(fp_line
			(start 3.243072 -5.57022)
			(end 2.217166 -4.586224)
			(stroke
				(width 0.1)
				(type default)
			)
			(layer "F.SilkS")
		)
		(fp_line
			(start 3.243072 -5.57022)
			(end 2.217166 -4.586224)
			(stroke
				(width 0.1)
				(type default)
			)
			(layer "F.SilkS")
		)
		(fp_line
			(start 3.272536 -0.577342)
			(end 5.02285 -2.256536)
			(stroke
				(width 0.1)
				(type default)
			)
			(layer "F.SilkS")
		)
		(fp_line
			(start 3.272536 -0.577342)
			(end 5.02285 -2.256536)
			(stroke
				(width 0.1)
				(type default)
			)
			(layer "F.SilkS")
		)
		(fp_line
			(start 3.292094 -5.559552)
			(end 2.310892 -4.618228)
			(stroke
				(width 0.1)
				(type default)
			)
			(layer "F.SilkS")
		)
		(fp_line
			(start 3.292094 -5.559552)
			(end 2.310892 -4.618228)
			(stroke
				(width 0.1)
				(type default)
			)
			(layer "F.SilkS")
		)
		(fp_line
			(start 3.316224 -0.561848)
			(end 4.990338 -2.167636)
			(stroke
				(width 0.1)
				(type default)
			)
			(layer "F.SilkS")
		)
		(fp_line
			(start 3.316224 -0.561848)
			(end 4.990338 -2.167636)
			(stroke
				(width 0.1)
				(type default)
			)
			(layer "F.SilkS")
		)
		(fp_line
			(start 3.34137 -5.549138)
			(end 2.389632 -4.636262)
			(stroke
				(width 0.1)
				(type default)
			)
			(layer "F.SilkS")
		)
		(fp_line
			(start 3.34137 -5.549138)
			(end 2.389632 -4.636262)
			(stroke
				(width 0.1)
				(type default)
			)
			(layer "F.SilkS")
		)
		(fp_line
			(start 3.359912 -0.545846)
			(end 4.953254 -2.074418)
			(stroke
				(width 0.1)
				(type default)
			)
			(layer "F.SilkS")
		)
		(fp_line
			(start 3.359912 -0.545846)
			(end 4.953254 -2.074418)
			(stroke
				(width 0.1)
				(type default)
			)
			(layer "F.SilkS")
		)
		(fp_line
			(start 3.390392 -5.53847)
			(end 2.458212 -4.644136)
			(stroke
				(width 0.1)
				(type default)
			)
			(layer "F.SilkS")
		)
		(fp_line
			(start 3.390392 -5.53847)
			(end 2.458212 -4.644136)
			(stroke
				(width 0.1)
				(type default)
			)
			(layer "F.SilkS")
		)
		(fp_line
			(start 3.4036 -0.530098)
			(end 4.915916 -1.980946)
			(stroke
				(width 0.1)
				(type default)
			)
			(layer "F.SilkS")
		)
		(fp_line
			(start 3.4036 -0.530098)
			(end 4.915916 -1.980946)
			(stroke
				(width 0.1)
				(type default)
			)
			(layer "F.SilkS")
		)
		(fp_line
			(start 3.437382 -5.52577)
			(end 2.526538 -4.65201)
			(stroke
				(width 0.1)
				(type default)
			)
			(layer "F.SilkS")
		)
		(fp_line
			(start 3.437382 -5.52577)
			(end 2.526538 -4.65201)
			(stroke
				(width 0.1)
				(type default)
			)
			(layer "F.SilkS")
		)
		(fp_line
			(start 3.447034 -0.513842)
			(end 4.85267 -1.862582)
			(stroke
				(width 0.1)
				(type default)
			)
			(layer "F.SilkS")
		)
		(fp_line
			(start 3.447034 -0.513842)
			(end 4.85267 -1.862582)
			(stroke
				(width 0.1)
				(type default)
			)
			(layer "F.SilkS")
		)
		(fp_line
			(start 3.482594 -5.511292)
			(end 2.593086 -4.658106)
			(stroke
				(width 0.1)
				(type default)
			)
			(layer "F.SilkS")
		)
		(fp_line
			(start 3.482594 -5.511292)
			(end 2.593086 -4.658106)
			(stroke
				(width 0.1)
				(type default)
			)
			(layer "F.SilkS")
		)
		(fp_line
			(start 3.490468 -0.498094)
			(end 4.77901 -1.734058)
			(stroke
				(width 0.1)
				(type default)
			)
			(layer "F.SilkS")
		)
		(fp_line
			(start 3.490468 -0.498094)
			(end 4.77901 -1.734058)
			(stroke
				(width 0.1)
				(type default)
			)
			(layer "F.SilkS")
		)
		(fp_line
			(start 3.527806 -5.497068)
			(end 2.647188 -4.652264)
			(stroke
				(width 0.1)
				(type default)
			)
			(layer "F.SilkS")
		)
		(fp_line
			(start 3.527806 -5.497068)
			(end 2.647188 -4.652264)
			(stroke
				(width 0.1)
				(type default)
			)
			(layer "F.SilkS")
		)
		(fp_line
			(start 3.533648 -0.481838)
			(end 4.147312 -1.070356)
			(stroke
				(width 0.1)
				(type default)
			)
			(layer "F.SilkS")
		)
		(fp_line
			(start 3.533648 -0.481838)
			(end 4.147312 -1.070356)
			(stroke
				(width 0.1)
				(type default)
			)
			(layer "F.SilkS")
		)
		(fp_line
			(start 3.573018 -5.482844)
			(end 2.700782 -4.645914)
			(stroke
				(width 0.1)
				(type default)
			)
			(layer "F.SilkS")
		)
		(fp_line
			(start 3.573018 -5.482844)
			(end 2.700782 -4.645914)
			(stroke
				(width 0.1)
				(type default)
			)
			(layer "F.SilkS")
		)
		(fp_line
			(start 3.61823 -5.468366)
			(end 2.75463 -4.639818)
			(stroke
				(width 0.1)
				(type default)
			)
			(layer "F.SilkS")
		)
		(fp_line
			(start 3.61823 -5.468366)
			(end 2.75463 -4.639818)
			(stroke
				(width 0.1)
				(type default)
			)
			(layer "F.SilkS")
		)
		(fp_line
			(start 3.620008 -0.449072)
			(end 4.2164 -1.02108)
			(stroke
				(width 0.1)
				(type default)
			)
			(layer "F.SilkS")
		)
		(fp_line
			(start 3.620008 -0.449072)
			(end 4.2164 -1.02108)
			(stroke
				(width 0.1)
				(type default)
			)
			(layer "F.SilkS")
		)
		(fp_line
			(start 3.662426 -5.452872)
			(end 2.808478 -4.633976)
			(stroke
				(width 0.1)
				(type default)
			)
			(layer "F.SilkS")
		)
		(fp_line
			(start 3.662426 -5.452872)
			(end 2.808478 -4.633976)
			(stroke
				(width 0.1)
				(type default)
			)
			(layer "F.SilkS")
		)
		(fp_line
			(start 3.663442 -0.43307)
			(end 4.250944 -0.996696)
			(stroke
				(width 0.1)
				(type default)
			)
			(layer "F.SilkS")
		)
		(fp_line
			(start 3.663442 -0.43307)
			(end 4.250944 -0.996696)
			(stroke
				(width 0.1)
				(type default)
			)
			(layer "F.SilkS")
		)
		(fp_line
			(start 3.703828 -5.435092)
			(end 2.860548 -4.626102)
			(stroke
				(width 0.1)
				(type default)
			)
			(layer "F.SilkS")
		)
		(fp_line
			(start 3.703828 -5.435092)
			(end 2.860548 -4.626102)
			(stroke
				(width 0.1)
				(type default)
			)
			(layer "F.SilkS")
		)
		(fp_line
			(start 3.706368 -0.416814)
			(end 4.285488 -0.972058)
			(stroke
				(width 0.1)
				(type default)
			)
			(layer "F.SilkS")
		)
		(fp_line
			(start 3.706368 -0.416814)
			(end 4.285488 -0.972058)
			(stroke
				(width 0.1)
				(type default)
			)
			(layer "F.SilkS")
		)
		(fp_line
			(start 3.745484 -5.417058)
			(end 2.90449 -4.610354)
			(stroke
				(width 0.1)
				(type default)
			)
			(layer "F.SilkS")
		)
		(fp_line
			(start 3.745484 -5.417058)
			(end 2.90449 -4.610354)
			(stroke
				(width 0.1)
				(type default)
			)
			(layer "F.SilkS")
		)
		(fp_line
			(start 3.749548 -0.400304)
			(end 4.320286 -0.947674)
			(stroke
				(width 0.1)
				(type default)
			)
			(layer "F.SilkS")
		)
		(fp_line
			(start 3.749548 -0.400304)
			(end 4.320286 -0.947674)
			(stroke
				(width 0.1)
				(type default)
			)
			(layer "F.SilkS")
		)
		(fp_line
			(start 3.786886 -5.399278)
			(end 2.948432 -4.595114)
			(stroke
				(width 0.1)
				(type default)
			)
			(layer "F.SilkS")
		)
		(fp_line
			(start 3.786886 -5.399278)
			(end 2.948432 -4.595114)
			(stroke
				(width 0.1)
				(type default)
			)
			(layer "F.SilkS")
		)
		(fp_line
			(start 3.792474 -0.383794)
			(end 4.35483 -0.923036)
			(stroke
				(width 0.1)
				(type default)
			)
			(layer "F.SilkS")
		)
		(fp_line
			(start 3.792474 -0.383794)
			(end 4.35483 -0.923036)
			(stroke
				(width 0.1)
				(type default)
			)
			(layer "F.SilkS")
		)
		(fp_line
			(start 3.828288 -5.381498)
			(end 2.992628 -4.57962)
			(stroke
				(width 0.1)
				(type default)
			)
			(layer "F.SilkS")
		)
		(fp_line
			(start 3.828288 -5.381498)
			(end 2.992628 -4.57962)
			(stroke
				(width 0.1)
				(type default)
			)
			(layer "F.SilkS")
		)
		(fp_line
			(start 3.8354 -0.36703)
			(end 4.389374 -0.898398)
			(stroke
				(width 0.1)
				(type default)
			)
			(layer "F.SilkS")
		)
		(fp_line
			(start 3.8354 -0.36703)
			(end 4.389374 -0.898398)
			(stroke
				(width 0.1)
				(type default)
			)
			(layer "F.SilkS")
		)
		(fp_line
			(start 3.870198 -5.363464)
			(end 3.036824 -4.56438)
			(stroke
				(width 0.1)
				(type default)
			)
			(layer "F.SilkS")
		)
		(fp_line
			(start 3.870198 -5.363464)
			(end 3.036824 -4.56438)
			(stroke
				(width 0.1)
				(type default)
			)
			(layer "F.SilkS")
		)
		(fp_line
			(start 3.878326 -0.35052)
			(end 4.423918 -0.874014)
			(stroke
				(width 0.1)
				(type default)
			)
			(layer "F.SilkS")
		)
		(fp_line
			(start 3.878326 -0.35052)
			(end 4.423918 -0.874014)
			(stroke
				(width 0.1)
				(type default)
			)
			(layer "F.SilkS")
		)
		(fp_line
			(start 3.908552 -5.34289)
			(end 3.080766 -4.548886)
			(stroke
				(width 0.1)
				(type default)
			)
			(layer "F.SilkS")
		)
		(fp_line
			(start 3.908552 -5.34289)
			(end 3.080766 -4.548886)
			(stroke
				(width 0.1)
				(type default)
			)
			(layer "F.SilkS")
		)
		(fp_line
			(start 3.921252 -0.33401)
			(end 4.458462 -0.849376)
			(stroke
				(width 0.1)
				(type default)
			)
			(layer "F.SilkS")
		)
		(fp_line
			(start 3.921252 -0.33401)
			(end 4.458462 -0.849376)
			(stroke
				(width 0.1)
				(type default)
			)
			(layer "F.SilkS")
		)
		(fp_line
			(start 3.946652 -5.321808)
			(end 3.12039 -4.529074)
			(stroke
				(width 0.1)
				(type default)
			)
			(layer "F.SilkS")
		)
		(fp_line
			(start 3.946652 -5.321808)
			(end 3.12039 -4.529074)
			(stroke
				(width 0.1)
				(type default)
			)
			(layer "F.SilkS")
		)
		(fp_line
			(start 3.964178 -0.3175)
			(end 4.493006 -0.824738)
			(stroke
				(width 0.1)
				(type default)
			)
			(layer "F.SilkS")
		)
		(fp_line
			(start 3.964178 -0.3175)
			(end 4.493006 -0.824738)
			(stroke
				(width 0.1)
				(type default)
			)
			(layer "F.SilkS")
		)
		(fp_line
			(start 3.984752 -5.300472)
			(end 3.15722 -4.506722)
			(stroke
				(width 0.1)
				(type default)
			)
			(layer "F.SilkS")
		)
		(fp_line
			(start 3.984752 -5.300472)
			(end 3.15722 -4.506722)
			(stroke
				(width 0.1)
				(type default)
			)
			(layer "F.SilkS")
		)
		(fp_line
			(start 4.00685 -0.30099)
			(end 4.52755 -0.800608)
			(stroke
				(width 0.1)
				(type default)
			)
			(layer "F.SilkS")
		)
		(fp_line
			(start 4.00685 -0.30099)
			(end 4.52755 -0.800608)
			(stroke
				(width 0.1)
				(type default)
			)
			(layer "F.SilkS")
		)
		(fp_line
			(start 4.022852 -5.27939)
			(end 3.193796 -4.484116)
			(stroke
				(width 0.1)
				(type default)
			)
			(layer "F.SilkS")
		)
		(fp_line
			(start 4.022852 -5.27939)
			(end 3.193796 -4.484116)
			(stroke
				(width 0.1)
				(type default)
			)
			(layer "F.SilkS")
		)
		(fp_line
			(start 4.049776 -0.284226)
			(end 4.562094 -0.775716)
			(stroke
				(width 0.1)
				(type default)
			)
			(layer "F.SilkS")
		)
		(fp_line
			(start 4.049776 -0.284226)
			(end 4.562094 -0.775716)
			(stroke
				(width 0.1)
				(type default)
			)
			(layer "F.SilkS")
		)
		(fp_line
			(start 4.060952 -5.258054)
			(end 3.230372 -4.461256)
			(stroke
				(width 0.1)
				(type default)
			)
			(layer "F.SilkS")
		)
		(fp_line
			(start 4.060952 -5.258054)
			(end 3.230372 -4.461256)
			(stroke
				(width 0.1)
				(type default)
			)
			(layer "F.SilkS")
		)
		(fp_line
			(start 4.092448 -0.267462)
			(end 4.596892 -0.751332)
			(stroke
				(width 0.1)
				(type default)
			)
			(layer "F.SilkS")
		)
		(fp_line
			(start 4.092448 -0.267462)
			(end 4.596892 -0.751332)
			(stroke
				(width 0.1)
				(type default)
			)
			(layer "F.SilkS")
		)
		(fp_line
			(start 4.09829 -5.23621)
			(end 3.266948 -4.438904)
			(stroke
				(width 0.1)
				(type default)
			)
			(layer "F.SilkS")
		)
		(fp_line
			(start 4.09829 -5.23621)
			(end 3.266948 -4.438904)
			(stroke
				(width 0.1)
				(type default)
			)
			(layer "F.SilkS")
		)
		(fp_line
			(start 4.133088 -5.21208)
			(end 3.303524 -4.416044)
			(stroke
				(width 0.1)
				(type default)
			)
			(layer "F.SilkS")
		)
		(fp_line
			(start 4.133088 -5.21208)
			(end 3.303524 -4.416044)
			(stroke
				(width 0.1)
				(type default)
			)
			(layer "F.SilkS")
		)
		(fp_line
			(start 4.135374 -0.250698)
			(end 4.631436 -0.726694)
			(stroke
				(width 0.1)
				(type default)
			)
			(layer "F.SilkS")
		)
		(fp_line
			(start 4.135374 -0.250698)
			(end 4.631436 -0.726694)
			(stroke
				(width 0.1)
				(type default)
			)
			(layer "F.SilkS")
		)
		(fp_line
			(start 4.16814 -5.187696)
			(end 3.337052 -4.390644)
			(stroke
				(width 0.1)
				(type default)
			)
			(layer "F.SilkS")
		)
		(fp_line
			(start 4.16814 -5.187696)
			(end 3.337052 -4.390644)
			(stroke
				(width 0.1)
				(type default)
			)
			(layer "F.SilkS")
		)
		(fp_line
			(start 4.178046 -0.234188)
			(end 4.66598 -0.702056)
			(stroke
				(width 0.1)
				(type default)
			)
			(layer "F.SilkS")
		)
		(fp_line
			(start 4.178046 -0.234188)
			(end 4.66598 -0.702056)
			(stroke
				(width 0.1)
				(type default)
			)
			(layer "F.SilkS")
		)
		(fp_line
			(start 4.181856 -1.045718)
			(end 3.576828 -0.465582)
			(stroke
				(width 0.1)
				(type default)
			)
			(layer "F.SilkS")
		)
		(fp_line
			(start 4.181856 -1.045718)
			(end 3.576828 -0.465582)
			(stroke
				(width 0.1)
				(type default)
			)
			(layer "F.SilkS")
		)
		(fp_line
			(start 4.202938 -5.163312)
			(end 3.367532 -4.362196)
			(stroke
				(width 0.1)
				(type default)
			)
			(layer "F.SilkS")
		)
		(fp_line
			(start 4.202938 -5.163312)
			(end 3.367532 -4.362196)
			(stroke
				(width 0.1)
				(type default)
			)
			(layer "F.SilkS")
		)
		(fp_line
			(start 4.220718 -0.217678)
			(end 4.700524 -0.677926)
			(stroke
				(width 0.1)
				(type default)
			)
			(layer "F.SilkS")
		)
		(fp_line
			(start 4.220718 -0.217678)
			(end 4.700524 -0.677926)
			(stroke
				(width 0.1)
				(type default)
			)
			(layer "F.SilkS")
		)
		(fp_line
			(start 4.237736 -5.139182)
			(end 3.397504 -4.33324)
			(stroke
				(width 0.1)
				(type default)
			)
			(layer "F.SilkS")
		)
		(fp_line
			(start 4.237736 -5.139182)
			(end 3.397504 -4.33324)
			(stroke
				(width 0.1)
				(type default)
			)
			(layer "F.SilkS")
		)
		(fp_line
			(start 4.26339 -0.200406)
			(end 4.735068 -0.653034)
			(stroke
				(width 0.1)
				(type default)
			)
			(layer "F.SilkS")
		)
		(fp_line
			(start 4.26339 -0.200406)
			(end 4.735068 -0.653034)
			(stroke
				(width 0.1)
				(type default)
			)
			(layer "F.SilkS")
		)
		(fp_line
			(start 4.272534 -5.115052)
			(end 3.427984 -4.304792)
			(stroke
				(width 0.1)
				(type default)
			)
			(layer "F.SilkS")
		)
		(fp_line
			(start 4.272534 -5.115052)
			(end 3.427984 -4.304792)
			(stroke
				(width 0.1)
				(type default)
			)
			(layer "F.SilkS")
		)
		(fp_line
			(start 4.306062 -0.183896)
			(end 4.769866 -0.62865)
			(stroke
				(width 0.1)
				(type default)
			)
			(layer "F.SilkS")
		)
		(fp_line
			(start 4.306062 -0.183896)
			(end 4.769866 -0.62865)
			(stroke
				(width 0.1)
				(type default)
			)
			(layer "F.SilkS")
		)
		(fp_line
			(start 4.306316 -5.089398)
			(end 3.45821 -4.275836)
			(stroke
				(width 0.1)
				(type default)
			)
			(layer "F.SilkS")
		)
		(fp_line
			(start 4.306316 -5.089398)
			(end 3.45821 -4.275836)
			(stroke
				(width 0.1)
				(type default)
			)
			(layer "F.SilkS")
		)
		(fp_line
			(start 4.338066 -5.06222)
			(end 3.488436 -4.247388)
			(stroke
				(width 0.1)
				(type default)
			)
			(layer "F.SilkS")
		)
		(fp_line
			(start 4.338066 -5.06222)
			(end 3.488436 -4.247388)
			(stroke
				(width 0.1)
				(type default)
			)
			(layer "F.SilkS")
		)
		(fp_line
			(start 4.348734 -0.166878)
			(end 4.80441 -0.604266)
			(stroke
				(width 0.1)
				(type default)
			)
			(layer "F.SilkS")
		)
		(fp_line
			(start 4.348734 -0.166878)
			(end 4.80441 -0.604266)
			(stroke
				(width 0.1)
				(type default)
			)
			(layer "F.SilkS")
		)
		(fp_line
			(start 4.37007 -5.035296)
			(end 3.518408 -4.218432)
			(stroke
				(width 0.1)
				(type default)
			)
			(layer "F.SilkS")
		)
		(fp_line
			(start 4.37007 -5.035296)
			(end 3.518408 -4.218432)
			(stroke
				(width 0.1)
				(type default)
			)
			(layer "F.SilkS")
		)
		(fp_line
			(start 4.391406 -0.150114)
			(end 4.838954 -0.579628)
			(stroke
				(width 0.1)
				(type default)
			)
			(layer "F.SilkS")
		)
		(fp_line
			(start 4.391406 -0.150114)
			(end 4.838954 -0.579628)
			(stroke
				(width 0.1)
				(type default)
			)
			(layer "F.SilkS")
		)
		(fp_line
			(start 4.401566 -5.008118)
			(end 3.542792 -4.183888)
			(stroke
				(width 0.1)
				(type default)
			)
			(layer "F.SilkS")
		)
		(fp_line
			(start 4.401566 -5.008118)
			(end 3.542792 -4.183888)
			(stroke
				(width 0.1)
				(type default)
			)
			(layer "F.SilkS")
		)
		(fp_line
			(start 4.43357 -4.98094)
			(end 3.567176 -4.149598)
			(stroke
				(width 0.1)
				(type default)
			)
			(layer "F.SilkS")
		)
		(fp_line
			(start 4.43357 -4.98094)
			(end 3.567176 -4.149598)
			(stroke
				(width 0.1)
				(type default)
			)
			(layer "F.SilkS")
		)
		(fp_line
			(start 4.433824 -0.133604)
			(end 4.873752 -0.555244)
			(stroke
				(width 0.1)
				(type default)
			)
			(layer "F.SilkS")
		)
		(fp_line
			(start 4.433824 -0.133604)
			(end 4.873752 -0.555244)
			(stroke
				(width 0.1)
				(type default)
			)
			(layer "F.SilkS")
		)
		(fp_line
			(start 4.46532 -4.953508)
			(end 3.59156 -4.115308)
			(stroke
				(width 0.1)
				(type default)
			)
			(layer "F.SilkS")
		)
		(fp_line
			(start 4.46532 -4.953508)
			(end 3.59156 -4.115308)
			(stroke
				(width 0.1)
				(type default)
			)
			(layer "F.SilkS")
		)
		(fp_line
			(start 4.476496 -0.116332)
			(end 4.908296 -0.530352)
			(stroke
				(width 0.1)
				(type default)
			)
			(layer "F.SilkS")
		)
		(fp_line
			(start 4.476496 -0.116332)
			(end 4.908296 -0.530352)
			(stroke
				(width 0.1)
				(type default)
			)
			(layer "F.SilkS")
		)
		(fp_line
			(start 4.4958 -4.92506)
			(end 3.615944 -4.081018)
			(stroke
				(width 0.1)
				(type default)
			)
			(layer "F.SilkS")
		)
		(fp_line
			(start 4.4958 -4.92506)
			(end 3.615944 -4.081018)
			(stroke
				(width 0.1)
				(type default)
			)
			(layer "F.SilkS")
		)
		(fp_line
			(start 4.519168 -0.099822)
			(end 4.94284 -0.506222)
			(stroke
				(width 0.1)
				(type default)
			)
			(layer "F.SilkS")
		)
		(fp_line
			(start 4.519168 -0.099822)
			(end 4.94284 -0.506222)
			(stroke
				(width 0.1)
				(type default)
			)
			(layer "F.SilkS")
		)
		(fp_line
			(start 4.52374 -4.894072)
			(end 3.640328 -4.046728)
			(stroke
				(width 0.1)
				(type default)
			)
			(layer "F.SilkS")
		)
		(fp_line
			(start 4.52374 -4.894072)
			(end 3.640328 -4.046728)
			(stroke
				(width 0.1)
				(type default)
			)
			(layer "F.SilkS")
		)
		(fp_line
			(start 4.55168 -4.863338)
			(end 3.664712 -4.012438)
			(stroke
				(width 0.1)
				(type default)
			)
			(layer "F.SilkS")
		)
		(fp_line
			(start 4.55168 -4.863338)
			(end 3.664712 -4.012438)
			(stroke
				(width 0.1)
				(type default)
			)
			(layer "F.SilkS")
		)
		(fp_line
			(start 4.561586 -0.08255)
			(end 4.977384 -0.481584)
			(stroke
				(width 0.1)
				(type default)
			)
			(layer "F.SilkS")
		)
		(fp_line
			(start 4.561586 -0.08255)
			(end 4.977384 -0.481584)
			(stroke
				(width 0.1)
				(type default)
			)
			(layer "F.SilkS")
		)
		(fp_line
			(start 4.57962 -4.83235)
			(end 3.686556 -3.975608)
			(stroke
				(width 0.1)
				(type default)
			)
			(layer "F.SilkS")
		)
		(fp_line
			(start 4.57962 -4.83235)
			(end 3.686556 -3.975608)
			(stroke
				(width 0.1)
				(type default)
			)
			(layer "F.SilkS")
		)
		(fp_line
			(start 4.60756 -4.801362)
			(end 3.704844 -3.935476)
			(stroke
				(width 0.1)
				(type default)
			)
			(layer "F.SilkS")
		)
		(fp_line
			(start 4.60756 -4.801362)
			(end 3.704844 -3.935476)
			(stroke
				(width 0.1)
				(type default)
			)
			(layer "F.SilkS")
		)
		(fp_line
			(start 4.631182 -0.091948)
			(end 4.713478 -0.112776)
			(stroke
				(width 0.1)
				(type default)
			)
			(layer "F.SilkS")
		)
		(fp_line
			(start 4.631182 -0.091948)
			(end 4.713478 -0.112776)
			(stroke
				(width 0.1)
				(type default)
			)
			(layer "F.SilkS")
		)
		(fp_line
			(start 4.631182 -0.091948)
			(end 5.012182 -0.456946)
			(stroke
				(width 0.1)
				(type default)
			)
			(layer "F.SilkS")
		)
		(fp_line
			(start 4.631182 -0.091948)
			(end 5.012182 -0.456946)
			(stroke
				(width 0.1)
				(type default)
			)
			(layer "F.SilkS")
		)
		(fp_line
			(start 4.635246 -4.770374)
			(end 3.723386 -3.895598)
			(stroke
				(width 0.1)
				(type default)
			)
			(layer "F.SilkS")
		)
		(fp_line
			(start 4.635246 -4.770374)
			(end 3.723386 -3.895598)
			(stroke
				(width 0.1)
				(type default)
			)
			(layer "F.SilkS")
		)
		(fp_line
			(start 4.663186 -4.739386)
			(end 3.741928 -3.85572)
			(stroke
				(width 0.1)
				(type default)
			)
			(layer "F.SilkS")
		)
		(fp_line
			(start 4.663186 -4.739386)
			(end 3.741928 -3.85572)
			(stroke
				(width 0.1)
				(type default)
			)
			(layer "F.SilkS")
		)
		(fp_line
			(start 4.690618 -4.70789)
			(end 3.76047 -3.815588)
			(stroke
				(width 0.1)
				(type default)
			)
			(layer "F.SilkS")
		)
		(fp_line
			(start 4.690618 -4.70789)
			(end 3.76047 -3.815588)
			(stroke
				(width 0.1)
				(type default)
			)
			(layer "F.SilkS")
		)
		(fp_line
			(start 4.713478 -0.112776)
			(end 4.795266 -0.133604)
			(stroke
				(width 0.1)
				(type default)
			)
			(layer "F.SilkS")
		)
		(fp_line
			(start 4.713478 -0.112776)
			(end 4.795266 -0.133604)
			(stroke
				(width 0.1)
				(type default)
			)
			(layer "F.SilkS")
		)
		(fp_line
			(start 4.713478 -0.112776)
			(end 5.046726 -0.432562)
			(stroke
				(width 0.1)
				(type default)
			)
			(layer "F.SilkS")
		)
		(fp_line
			(start 4.713478 -0.112776)
			(end 5.046726 -0.432562)
			(stroke
				(width 0.1)
				(type default)
			)
			(layer "F.SilkS")
		)
		(fp_line
			(start 4.713732 -4.672584)
			(end 3.778758 -3.775456)
			(stroke
				(width 0.1)
				(type default)
			)
			(layer "F.SilkS")
		)
		(fp_line
			(start 4.713732 -4.672584)
			(end 3.778758 -3.775456)
			(stroke
				(width 0.1)
				(type default)
			)
			(layer "F.SilkS")
		)
		(fp_line
			(start 4.7371 -4.637278)
			(end 3.7973 -3.735578)
			(stroke
				(width 0.1)
				(type default)
			)
			(layer "F.SilkS")
		)
		(fp_line
			(start 4.7371 -4.637278)
			(end 3.7973 -3.735578)
			(stroke
				(width 0.1)
				(type default)
			)
			(layer "F.SilkS")
		)
		(fp_line
			(start 4.760214 -4.601718)
			(end 3.81 -3.689858)
			(stroke
				(width 0.1)
				(type default)
			)
			(layer "F.SilkS")
		)
		(fp_line
			(start 4.760214 -4.601718)
			(end 3.81 -3.689858)
			(stroke
				(width 0.1)
				(type default)
			)
			(layer "F.SilkS")
		)
		(fp_line
			(start 4.783582 -4.566158)
			(end 3.821938 -3.643884)
			(stroke
				(width 0.1)
				(type default)
			)
			(layer "F.SilkS")
		)
		(fp_line
			(start 4.783582 -4.566158)
			(end 3.821938 -3.643884)
			(stroke
				(width 0.1)
				(type default)
			)
			(layer "F.SilkS")
		)
		(fp_line
			(start 4.795266 -0.133604)
			(end 4.877308 -0.15494)
			(stroke
				(width 0.1)
				(type default)
			)
			(layer "F.SilkS")
		)
		(fp_line
			(start 4.795266 -0.133604)
			(end 4.877308 -0.15494)
			(stroke
				(width 0.1)
				(type default)
			)
			(layer "F.SilkS")
		)
		(fp_line
			(start 4.795266 -0.133604)
			(end 5.08127 -0.408178)
			(stroke
				(width 0.1)
				(type default)
			)
			(layer "F.SilkS")
		)
		(fp_line
			(start 4.795266 -0.133604)
			(end 5.08127 -0.408178)
			(stroke
				(width 0.1)
				(type default)
			)
			(layer "F.SilkS")
		)
		(fp_line
			(start 4.806696 -4.530852)
			(end 3.83413 -3.59791)
			(stroke
				(width 0.1)
				(type default)
			)
			(layer "F.SilkS")
		)
		(fp_line
			(start 4.806696 -4.530852)
			(end 3.83413 -3.59791)
			(stroke
				(width 0.1)
				(type default)
			)
			(layer "F.SilkS")
		)
		(fp_line
			(start 4.82981 -4.495292)
			(end 3.846068 -3.551682)
			(stroke
				(width 0.1)
				(type default)
			)
			(layer "F.SilkS")
		)
		(fp_line
			(start 4.82981 -4.495292)
			(end 3.846068 -3.551682)
			(stroke
				(width 0.1)
				(type default)
			)
			(layer "F.SilkS")
		)
		(fp_line
			(start 4.851654 -4.458462)
			(end 3.858006 -3.505454)
			(stroke
				(width 0.1)
				(type default)
			)
			(layer "F.SilkS")
		)
		(fp_line
			(start 4.851654 -4.458462)
			(end 3.858006 -3.505454)
			(stroke
				(width 0.1)
				(type default)
			)
			(layer "F.SilkS")
		)
		(fp_line
			(start 4.870958 -4.419092)
			(end 3.870198 -3.459226)
			(stroke
				(width 0.1)
				(type default)
			)
			(layer "F.SilkS")
		)
		(fp_line
			(start 4.870958 -4.419092)
			(end 3.870198 -3.459226)
			(stroke
				(width 0.1)
				(type default)
			)
			(layer "F.SilkS")
		)
		(fp_line
			(start 4.877308 -0.15494)
			(end 4.95935 -0.175514)
			(stroke
				(width 0.1)
				(type default)
			)
			(layer "F.SilkS")
		)
		(fp_line
			(start 4.877308 -0.15494)
			(end 4.95935 -0.175514)
			(stroke
				(width 0.1)
				(type default)
			)
			(layer "F.SilkS")
		)
		(fp_line
			(start 4.877308 -0.15494)
			(end 5.115814 -0.383794)
			(stroke
				(width 0.1)
				(type default)
			)
			(layer "F.SilkS")
		)
		(fp_line
			(start 4.877308 -0.15494)
			(end 5.115814 -0.383794)
			(stroke
				(width 0.1)
				(type default)
			)
			(layer "F.SilkS")
		)
		(fp_line
			(start 4.889754 -4.379722)
			(end 3.878072 -3.409188)
			(stroke
				(width 0.1)
				(type default)
			)
			(layer "F.SilkS")
		)
		(fp_line
			(start 4.889754 -4.379722)
			(end 3.878072 -3.409188)
			(stroke
				(width 0.1)
				(type default)
			)
			(layer "F.SilkS")
		)
		(fp_line
			(start 4.908804 -4.340098)
			(end 3.88239 -3.355848)
			(stroke
				(width 0.1)
				(type default)
			)
			(layer "F.SilkS")
		)
		(fp_line
			(start 4.908804 -4.340098)
			(end 3.88239 -3.355848)
			(stroke
				(width 0.1)
				(type default)
			)
			(layer "F.SilkS")
		)
		(fp_line
			(start 4.927854 -4.300728)
			(end 3.886962 -3.302254)
			(stroke
				(width 0.1)
				(type default)
			)
			(layer "F.SilkS")
		)
		(fp_line
			(start 4.927854 -4.300728)
			(end 3.886962 -3.302254)
			(stroke
				(width 0.1)
				(type default)
			)
			(layer "F.SilkS")
		)
		(fp_line
			(start 4.946904 -4.261358)
			(end 3.891534 -3.248914)
			(stroke
				(width 0.1)
				(type default)
			)
			(layer "F.SilkS")
		)
		(fp_line
			(start 4.946904 -4.261358)
			(end 3.891534 -3.248914)
			(stroke
				(width 0.1)
				(type default)
			)
			(layer "F.SilkS")
		)
		(fp_line
			(start 4.95935 -0.175514)
			(end 5.041392 -0.196596)
			(stroke
				(width 0.1)
				(type default)
			)
			(layer "F.SilkS")
		)
		(fp_line
			(start 4.95935 -0.175514)
			(end 5.041392 -0.196596)
			(stroke
				(width 0.1)
				(type default)
			)
			(layer "F.SilkS")
		)
		(fp_line
			(start 4.95935 -0.175514)
			(end 5.150612 -0.359156)
			(stroke
				(width 0.1)
				(type default)
			)
			(layer "F.SilkS")
		)
		(fp_line
			(start 4.95935 -0.175514)
			(end 5.150612 -0.359156)
			(stroke
				(width 0.1)
				(type default)
			)
			(layer "F.SilkS")
		)
		(fp_line
			(start 4.965446 -4.221226)
			(end 3.895852 -3.19532)
			(stroke
				(width 0.1)
				(type default)
			)
			(layer "F.SilkS")
		)
		(fp_line
			(start 4.965446 -4.221226)
			(end 3.895852 -3.19532)
			(stroke
				(width 0.1)
				(type default)
			)
			(layer "F.SilkS")
		)
		(fp_line
			(start 4.980686 -4.1783)
			(end 3.900424 -3.14198)
			(stroke
				(width 0.1)
				(type default)
			)
			(layer "F.SilkS")
		)
		(fp_line
			(start 4.980686 -4.1783)
			(end 3.900424 -3.14198)
			(stroke
				(width 0.1)
				(type default)
			)
			(layer "F.SilkS")
		)
		(fp_line
			(start 4.995672 -4.13512)
			(end 3.899408 -3.083306)
			(stroke
				(width 0.1)
				(type default)
			)
			(layer "F.SilkS")
		)
		(fp_line
			(start 4.995672 -4.13512)
			(end 3.899408 -3.083306)
			(stroke
				(width 0.1)
				(type default)
			)
			(layer "F.SilkS")
		)
		(fp_line
			(start 5.011166 -4.09194)
			(end 3.894328 -3.020822)
			(stroke
				(width 0.1)
				(type default)
			)
			(layer "F.SilkS")
		)
		(fp_line
			(start 5.011166 -4.09194)
			(end 3.894328 -3.020822)
			(stroke
				(width 0.1)
				(type default)
			)
			(layer "F.SilkS")
		)
		(fp_line
			(start 5.026152 -4.04876)
			(end 3.889248 -2.958084)
			(stroke
				(width 0.1)
				(type default)
			)
			(layer "F.SilkS")
		)
		(fp_line
			(start 5.026152 -4.04876)
			(end 3.889248 -2.958084)
			(stroke
				(width 0.1)
				(type default)
			)
			(layer "F.SilkS")
		)
		(fp_line
			(start 5.041392 -4.00558)
			(end 3.884168 -2.8956)
			(stroke
				(width 0.1)
				(type default)
			)
			(layer "F.SilkS")
		)
		(fp_line
			(start 5.041392 -4.00558)
			(end 3.884168 -2.8956)
			(stroke
				(width 0.1)
				(type default)
			)
			(layer "F.SilkS")
		)
		(fp_line
			(start 5.041392 -0.196596)
			(end 5.12318 -0.217678)
			(stroke
				(width 0.1)
				(type default)
			)
			(layer "F.SilkS")
		)
		(fp_line
			(start 5.041392 -0.196596)
			(end 5.12318 -0.217678)
			(stroke
				(width 0.1)
				(type default)
			)
			(layer "F.SilkS")
		)
		(fp_line
			(start 5.041392 -0.196596)
			(end 5.185156 -0.334772)
			(stroke
				(width 0.1)
				(type default)
			)
			(layer "F.SilkS")
		)
		(fp_line
			(start 5.041392 -0.196596)
			(end 5.185156 -0.334772)
			(stroke
				(width 0.1)
				(type default)
			)
			(layer "F.SilkS")
		)
		(fp_line
			(start 5.0546 -3.960622)
			(end 3.879088 -2.832862)
			(stroke
				(width 0.1)
				(type default)
			)
			(layer "F.SilkS")
		)
		(fp_line
			(start 5.0546 -3.960622)
			(end 3.879088 -2.832862)
			(stroke
				(width 0.1)
				(type default)
			)
			(layer "F.SilkS")
		)
		(fp_line
			(start 5.066284 -3.91414)
			(end 3.863086 -2.75971)
			(stroke
				(width 0.1)
				(type default)
			)
			(layer "F.SilkS")
		)
		(fp_line
			(start 5.066284 -3.91414)
			(end 3.863086 -2.75971)
			(stroke
				(width 0.1)
				(type default)
			)
			(layer "F.SilkS")
		)
		(fp_line
			(start 5.078222 -3.867658)
			(end 3.843782 -2.68351)
			(stroke
				(width 0.1)
				(type default)
			)
			(layer "F.SilkS")
		)
		(fp_line
			(start 5.078222 -3.867658)
			(end 3.843782 -2.68351)
			(stroke
				(width 0.1)
				(type default)
			)
			(layer "F.SilkS")
		)
		(fp_line
			(start 5.089652 -3.821176)
			(end 3.824478 -2.607564)
			(stroke
				(width 0.1)
				(type default)
			)
			(layer "F.SilkS")
		)
		(fp_line
			(start 5.089652 -3.821176)
			(end 3.824478 -2.607564)
			(stroke
				(width 0.1)
				(type default)
			)
			(layer "F.SilkS")
		)
		(fp_line
			(start 5.101336 -3.774694)
			(end 3.802126 -2.528316)
			(stroke
				(width 0.1)
				(type default)
			)
			(layer "F.SilkS")
		)
		(fp_line
			(start 5.101336 -3.774694)
			(end 3.802126 -2.528316)
			(stroke
				(width 0.1)
				(type default)
			)
			(layer "F.SilkS")
		)
		(fp_line
			(start 5.110734 -3.72618)
			(end 3.756406 -2.426716)
			(stroke
				(width 0.1)
				(type default)
			)
			(layer "F.SilkS")
		)
		(fp_line
			(start 5.110734 -3.72618)
			(end 3.756406 -2.426716)
			(stroke
				(width 0.1)
				(type default)
			)
			(layer "F.SilkS")
		)
		(fp_line
			(start 5.11937 -3.676396)
			(end 3.710686 -2.32537)
			(stroke
				(width 0.1)
				(type default)
			)
			(layer "F.SilkS")
		)
		(fp_line
			(start 5.11937 -3.676396)
			(end 3.710686 -2.32537)
			(stroke
				(width 0.1)
				(type default)
			)
			(layer "F.SilkS")
		)
		(fp_line
			(start 5.12318 -0.217678)
			(end 5.205222 -0.238252)
			(stroke
				(width 0.1)
				(type default)
			)
			(layer "F.SilkS")
		)
		(fp_line
			(start 5.12318 -0.217678)
			(end 5.205222 -0.238252)
			(stroke
				(width 0.1)
				(type default)
			)
			(layer "F.SilkS")
		)
		(fp_line
			(start 5.12318 -0.217678)
			(end 5.219954 -0.310388)
			(stroke
				(width 0.1)
				(type default)
			)
			(layer "F.SilkS")
		)
		(fp_line
			(start 5.12318 -0.217678)
			(end 5.219954 -0.310388)
			(stroke
				(width 0.1)
				(type default)
			)
			(layer "F.SilkS")
		)
		(fp_line
			(start 5.127498 -3.626612)
			(end 3.618992 -2.17932)
			(stroke
				(width 0.1)
				(type default)
			)
			(layer "F.SilkS")
		)
		(fp_line
			(start 5.127498 -3.626612)
			(end 3.618992 -2.17932)
			(stroke
				(width 0.1)
				(type default)
			)
			(layer "F.SilkS")
		)
		(fp_line
			(start 5.13588 -3.576828)
			(end 2.15773 -0.719836)
			(stroke
				(width 0.1)
				(type default)
			)
			(layer "F.SilkS")
		)
		(fp_line
			(start 5.13588 -3.576828)
			(end 2.15773 -0.719836)
			(stroke
				(width 0.1)
				(type default)
			)
			(layer "F.SilkS")
		)
		(fp_line
			(start 5.205222 -0.238252)
			(end 5.254752 -0.28575)
			(stroke
				(width 0.1)
				(type default)
			)
			(layer "F.SilkS")
		)
		(fp_line
			(start 5.205222 -0.238252)
			(end 5.254752 -0.28575)
			(stroke
				(width 0.1)
				(type default)
			)
			(layer "F.SilkS")
		)
		(fp_line
			(start 5.287264 -0.259588)
			(end 5.205222 -0.238252)
			(stroke
				(width 0.1)
				(type default)
			)
			(layer "F.SilkS")
		)
		(fp_line
			(start 5.287264 -0.259588)
			(end 5.205222 -0.238252)
			(stroke
				(width 0.1)
				(type default)
			)
			(layer "F.SilkS")
		)
		(fp_line
			(start 5.287264 -0.259588)
			(end 5.289296 -0.261366)
			(stroke
				(width 0.1)
				(type default)
			)
			(layer "F.SilkS")
		)
		(fp_line
			(start 5.287264 -0.259588)
			(end 5.289296 -0.261366)
			(stroke
				(width 0.1)
				(type default)
			)
			(layer "F.SilkS")
		)
		(fp_line
			(start 5.507482 -2.281682)
			(end 6.825488 -3.54584)
			(stroke
				(width 0.1)
				(type default)
			)
			(layer "F.SilkS")
		)
		(fp_line
			(start 5.507482 -2.281682)
			(end 6.825488 -3.54584)
			(stroke
				(width 0.1)
				(type default)
			)
			(layer "F.SilkS")
		)
		(fp_line
			(start 5.50799 -2.224278)
			(end 6.81355 -3.476498)
			(stroke
				(width 0.1)
				(type default)
			)
			(layer "F.SilkS")
		)
		(fp_line
			(start 5.50799 -2.224278)
			(end 6.81355 -3.476498)
			(stroke
				(width 0.1)
				(type default)
			)
			(layer "F.SilkS")
		)
		(fp_line
			(start 5.508498 -2.167128)
			(end 6.801104 -3.407156)
			(stroke
				(width 0.1)
				(type default)
			)
			(layer "F.SilkS")
		)
		(fp_line
			(start 5.508498 -2.167128)
			(end 6.801104 -3.407156)
			(stroke
				(width 0.1)
				(type default)
			)
			(layer "F.SilkS")
		)
		(fp_line
			(start 5.508752 -2.109724)
			(end 6.788912 -3.337814)
			(stroke
				(width 0.1)
				(type default)
			)
			(layer "F.SilkS")
		)
		(fp_line
			(start 5.508752 -2.109724)
			(end 6.788912 -3.337814)
			(stroke
				(width 0.1)
				(type default)
			)
			(layer "F.SilkS")
		)
		(fp_line
			(start 5.50926 -2.052574)
			(end 6.776974 -3.268472)
			(stroke
				(width 0.1)
				(type default)
			)
			(layer "F.SilkS")
		)
		(fp_line
			(start 5.50926 -2.052574)
			(end 6.776974 -3.268472)
			(stroke
				(width 0.1)
				(type default)
			)
			(layer "F.SilkS")
		)
		(fp_line
			(start 5.509768 -1.99517)
			(end 6.764782 -3.19913)
			(stroke
				(width 0.1)
				(type default)
			)
			(layer "F.SilkS")
		)
		(fp_line
			(start 5.509768 -1.99517)
			(end 6.764782 -3.19913)
			(stroke
				(width 0.1)
				(type default)
			)
			(layer "F.SilkS")
		)
		(fp_line
			(start 5.510276 -1.937766)
			(end 6.75259 -3.129534)
			(stroke
				(width 0.1)
				(type default)
			)
			(layer "F.SilkS")
		)
		(fp_line
			(start 5.510276 -1.937766)
			(end 6.75259 -3.129534)
			(stroke
				(width 0.1)
				(type default)
			)
			(layer "F.SilkS")
		)
		(fp_line
			(start 5.518912 -1.88849)
			(end 6.740144 -3.060192)
			(stroke
				(width 0.1)
				(type default)
			)
			(layer "F.SilkS")
		)
		(fp_line
			(start 5.518912 -1.88849)
			(end 6.740144 -3.060192)
			(stroke
				(width 0.1)
				(type default)
			)
			(layer "F.SilkS")
		)
		(fp_line
			(start 5.527802 -1.839214)
			(end 6.728206 -2.99085)
			(stroke
				(width 0.1)
				(type default)
			)
			(layer "F.SilkS")
		)
		(fp_line
			(start 5.527802 -1.839214)
			(end 6.728206 -2.99085)
			(stroke
				(width 0.1)
				(type default)
			)
			(layer "F.SilkS")
		)
		(fp_line
			(start 5.536438 -1.789938)
			(end 6.716014 -2.921254)
			(stroke
				(width 0.1)
				(type default)
			)
			(layer "F.SilkS")
		)
		(fp_line
			(start 5.536438 -1.789938)
			(end 6.716014 -2.921254)
			(stroke
				(width 0.1)
				(type default)
			)
			(layer "F.SilkS")
		)
		(fp_line
			(start 5.545582 -1.740916)
			(end 6.703822 -2.852166)
			(stroke
				(width 0.1)
				(type default)
			)
			(layer "F.SilkS")
		)
		(fp_line
			(start 5.545582 -1.740916)
			(end 6.703822 -2.852166)
			(stroke
				(width 0.1)
				(type default)
			)
			(layer "F.SilkS")
		)
		(fp_line
			(start 5.554218 -1.69164)
			(end 6.695186 -2.786126)
			(stroke
				(width 0.1)
				(type default)
			)
			(layer "F.SilkS")
		)
		(fp_line
			(start 5.554218 -1.69164)
			(end 6.695186 -2.786126)
			(stroke
				(width 0.1)
				(type default)
			)
			(layer "F.SilkS")
		)
		(fp_line
			(start 5.563108 -1.642364)
			(end 6.68655 -2.720086)
			(stroke
				(width 0.1)
				(type default)
			)
			(layer "F.SilkS")
		)
		(fp_line
			(start 5.563108 -1.642364)
			(end 6.68655 -2.720086)
			(stroke
				(width 0.1)
				(type default)
			)
			(layer "F.SilkS")
		)
		(fp_line
			(start 5.573522 -1.594612)
			(end 6.678168 -2.6543)
			(stroke
				(width 0.1)
				(type default)
			)
			(layer "F.SilkS")
		)
		(fp_line
			(start 5.573522 -1.594612)
			(end 6.678168 -2.6543)
			(stroke
				(width 0.1)
				(type default)
			)
			(layer "F.SilkS")
		)
		(fp_line
			(start 5.58038 -2.870962)
			(end 5.568188 -2.801366)
			(stroke
				(width 0.1)
				(type default)
			)
			(layer "F.SilkS")
		)
		(fp_line
			(start 5.58038 -2.870962)
			(end 5.568188 -2.801366)
			(stroke
				(width 0.1)
				(type default)
			)
			(layer "F.SilkS")
		)
		(fp_line
			(start 5.591048 -1.553718)
			(end 6.669532 -2.58826)
			(stroke
				(width 0.1)
				(type default)
			)
			(layer "F.SilkS")
		)
		(fp_line
			(start 5.591048 -1.553718)
			(end 6.669532 -2.58826)
			(stroke
				(width 0.1)
				(type default)
			)
			(layer "F.SilkS")
		)
		(fp_line
			(start 5.592572 -2.940304)
			(end 5.58038 -2.870962)
			(stroke
				(width 0.1)
				(type default)
			)
			(layer "F.SilkS")
		)
		(fp_line
			(start 5.592572 -2.940304)
			(end 5.58038 -2.870962)
			(stroke
				(width 0.1)
				(type default)
			)
			(layer "F.SilkS")
		)
		(fp_line
			(start 5.604764 -3.009646)
			(end 5.592572 -2.940304)
			(stroke
				(width 0.1)
				(type default)
			)
			(layer "F.SilkS")
		)
		(fp_line
			(start 5.604764 -3.009646)
			(end 5.592572 -2.940304)
			(stroke
				(width 0.1)
				(type default)
			)
			(layer "F.SilkS")
		)
		(fp_line
			(start 5.60832 -1.51257)
			(end 6.669024 -2.530094)
			(stroke
				(width 0.1)
				(type default)
			)
			(layer "F.SilkS")
		)
		(fp_line
			(start 5.60832 -1.51257)
			(end 6.669024 -2.530094)
			(stroke
				(width 0.1)
				(type default)
			)
			(layer "F.SilkS")
		)
		(fp_line
			(start 5.616956 -3.079242)
			(end 5.604764 -3.009646)
			(stroke
				(width 0.1)
				(type default)
			)
			(layer "F.SilkS")
		)
		(fp_line
			(start 5.616956 -3.079242)
			(end 5.604764 -3.009646)
			(stroke
				(width 0.1)
				(type default)
			)
			(layer "F.SilkS")
		)
		(fp_line
			(start 5.625846 -1.471676)
			(end 6.668516 -2.471928)
			(stroke
				(width 0.1)
				(type default)
			)
			(layer "F.SilkS")
		)
		(fp_line
			(start 5.625846 -1.471676)
			(end 6.668516 -2.471928)
			(stroke
				(width 0.1)
				(type default)
			)
			(layer "F.SilkS")
		)
		(fp_line
			(start 5.629148 -3.148584)
			(end 5.616956 -3.079242)
			(stroke
				(width 0.1)
				(type default)
			)
			(layer "F.SilkS")
		)
		(fp_line
			(start 5.629148 -3.148584)
			(end 5.616956 -3.079242)
			(stroke
				(width 0.1)
				(type default)
			)
			(layer "F.SilkS")
		)
		(fp_line
			(start 5.64134 -3.217926)
			(end 5.629148 -3.148584)
			(stroke
				(width 0.1)
				(type default)
			)
			(layer "F.SilkS")
		)
		(fp_line
			(start 5.64134 -3.217926)
			(end 5.629148 -3.148584)
			(stroke
				(width 0.1)
				(type default)
			)
			(layer "F.SilkS")
		)
		(fp_line
			(start 5.643118 -1.430528)
			(end 6.668008 -2.413762)
			(stroke
				(width 0.1)
				(type default)
			)
			(layer "F.SilkS")
		)
		(fp_line
			(start 5.643118 -1.430528)
			(end 6.668008 -2.413762)
			(stroke
				(width 0.1)
				(type default)
			)
			(layer "F.SilkS")
		)
		(fp_line
			(start 5.653532 -3.287268)
			(end 5.64134 -3.217926)
			(stroke
				(width 0.1)
				(type default)
			)
			(layer "F.SilkS")
		)
		(fp_line
			(start 5.653532 -3.287268)
			(end 5.64134 -3.217926)
			(stroke
				(width 0.1)
				(type default)
			)
			(layer "F.SilkS")
		)
		(fp_line
			(start 5.660644 -1.389634)
			(end 6.67004 -2.357882)
			(stroke
				(width 0.1)
				(type default)
			)
			(layer "F.SilkS")
		)
		(fp_line
			(start 5.660644 -1.389634)
			(end 6.67004 -2.357882)
			(stroke
				(width 0.1)
				(type default)
			)
			(layer "F.SilkS")
		)
		(fp_line
			(start 5.665724 -3.35661)
			(end 5.653532 -3.287268)
			(stroke
				(width 0.1)
				(type default)
			)
			(layer "F.SilkS")
		)
		(fp_line
			(start 5.665724 -3.35661)
			(end 5.653532 -3.287268)
			(stroke
				(width 0.1)
				(type default)
			)
			(layer "F.SilkS")
		)
		(fp_line
			(start 5.677662 -3.425952)
			(end 5.665724 -3.35661)
			(stroke
				(width 0.1)
				(type default)
			)
			(layer "F.SilkS")
		)
		(fp_line
			(start 5.677662 -3.425952)
			(end 5.665724 -3.35661)
			(stroke
				(width 0.1)
				(type default)
			)
			(layer "F.SilkS")
		)
		(fp_line
			(start 5.677916 -1.34874)
			(end 6.678168 -2.308352)
			(stroke
				(width 0.1)
				(type default)
			)
			(layer "F.SilkS")
		)
		(fp_line
			(start 5.677916 -1.34874)
			(end 6.678168 -2.308352)
			(stroke
				(width 0.1)
				(type default)
			)
			(layer "F.SilkS")
		)
		(fp_line
			(start 5.690108 -3.495548)
			(end 5.677662 -3.425952)
			(stroke
				(width 0.1)
				(type default)
			)
			(layer "F.SilkS")
		)
		(fp_line
			(start 5.690108 -3.495548)
			(end 5.677662 -3.425952)
			(stroke
				(width 0.1)
				(type default)
			)
			(layer "F.SilkS")
		)
		(fp_line
			(start 5.697982 -1.310132)
			(end 6.68655 -2.258568)
			(stroke
				(width 0.1)
				(type default)
			)
			(layer "F.SilkS")
		)
		(fp_line
			(start 5.697982 -1.310132)
			(end 6.68655 -2.258568)
			(stroke
				(width 0.1)
				(type default)
			)
			(layer "F.SilkS")
		)
		(fp_line
			(start 5.7023 -3.56489)
			(end 5.690108 -3.495548)
			(stroke
				(width 0.1)
				(type default)
			)
			(layer "F.SilkS")
		)
		(fp_line
			(start 5.7023 -3.56489)
			(end 5.690108 -3.495548)
			(stroke
				(width 0.1)
				(type default)
			)
			(layer "F.SilkS")
		)
		(fp_line
			(start 5.714238 -3.634232)
			(end 5.7023 -3.56489)
			(stroke
				(width 0.1)
				(type default)
			)
			(layer "F.SilkS")
		)
		(fp_line
			(start 5.714238 -3.634232)
			(end 5.7023 -3.56489)
			(stroke
				(width 0.1)
				(type default)
			)
			(layer "F.SilkS")
		)
		(fp_line
			(start 5.724398 -1.27762)
			(end 6.694932 -2.20853)
			(stroke
				(width 0.1)
				(type default)
			)
			(layer "F.SilkS")
		)
		(fp_line
			(start 5.724398 -1.27762)
			(end 6.694932 -2.20853)
			(stroke
				(width 0.1)
				(type default)
			)
			(layer "F.SilkS")
		)
		(fp_line
			(start 5.72643 -3.703828)
			(end 5.714238 -3.634232)
			(stroke
				(width 0.1)
				(type default)
			)
			(layer "F.SilkS")
		)
		(fp_line
			(start 5.72643 -3.703828)
			(end 5.714238 -3.634232)
			(stroke
				(width 0.1)
				(type default)
			)
			(layer "F.SilkS")
		)
		(fp_line
			(start 5.738876 -3.772916)
			(end 5.72643 -3.703828)
			(stroke
				(width 0.1)
				(type default)
			)
			(layer "F.SilkS")
		)
		(fp_line
			(start 5.738876 -3.772916)
			(end 5.72643 -3.703828)
			(stroke
				(width 0.1)
				(type default)
			)
			(layer "F.SilkS")
		)
		(fp_line
			(start 5.750306 -1.244854)
			(end 6.710934 -2.166366)
			(stroke
				(width 0.1)
				(type default)
			)
			(layer "F.SilkS")
		)
		(fp_line
			(start 5.750306 -1.244854)
			(end 6.710934 -2.166366)
			(stroke
				(width 0.1)
				(type default)
			)
			(layer "F.SilkS")
		)
		(fp_line
			(start 5.751068 -3.842512)
			(end 5.738876 -3.772916)
			(stroke
				(width 0.1)
				(type default)
			)
			(layer "F.SilkS")
		)
		(fp_line
			(start 5.751068 -3.842512)
			(end 5.738876 -3.772916)
			(stroke
				(width 0.1)
				(type default)
			)
			(layer "F.SilkS")
		)
		(fp_line
			(start 5.763006 -3.911854)
			(end 5.751068 -3.842512)
			(stroke
				(width 0.1)
				(type default)
			)
			(layer "F.SilkS")
		)
		(fp_line
			(start 5.763006 -3.911854)
			(end 5.751068 -3.842512)
			(stroke
				(width 0.1)
				(type default)
			)
			(layer "F.SilkS")
		)
		(fp_line
			(start 5.775198 -3.98145)
			(end 5.763006 -3.911854)
			(stroke
				(width 0.1)
				(type default)
			)
			(layer "F.SilkS")
		)
		(fp_line
			(start 5.775198 -3.98145)
			(end 5.763006 -3.911854)
			(stroke
				(width 0.1)
				(type default)
			)
			(layer "F.SilkS")
		)
		(fp_line
			(start 5.776468 -1.212342)
			(end 6.728714 -2.125726)
			(stroke
				(width 0.1)
				(type default)
			)
			(layer "F.SilkS")
		)
		(fp_line
			(start 5.776468 -1.212342)
			(end 6.728714 -2.125726)
			(stroke
				(width 0.1)
				(type default)
			)
			(layer "F.SilkS")
		)
		(fp_line
			(start 5.78739 -4.050538)
			(end 5.775198 -3.98145)
			(stroke
				(width 0.1)
				(type default)
			)
			(layer "F.SilkS")
		)
		(fp_line
			(start 5.78739 -4.050538)
			(end 5.775198 -3.98145)
			(stroke
				(width 0.1)
				(type default)
			)
			(layer "F.SilkS")
		)
		(fp_line
			(start 5.799582 -4.11988)
			(end 5.78739 -4.050538)
			(stroke
				(width 0.1)
				(type default)
			)
			(layer "F.SilkS")
		)
		(fp_line
			(start 5.799582 -4.11988)
			(end 5.78739 -4.050538)
			(stroke
				(width 0.1)
				(type default)
			)
			(layer "F.SilkS")
		)
		(fp_line
			(start 5.80263 -1.179576)
			(end 6.746494 -2.084832)
			(stroke
				(width 0.1)
				(type default)
			)
			(layer "F.SilkS")
		)
		(fp_line
			(start 5.80263 -1.179576)
			(end 6.746494 -2.084832)
			(stroke
				(width 0.1)
				(type default)
			)
			(layer "F.SilkS")
		)
		(fp_line
			(start 5.811774 -4.189476)
			(end 5.799582 -4.11988)
			(stroke
				(width 0.1)
				(type default)
			)
			(layer "F.SilkS")
		)
		(fp_line
			(start 5.811774 -4.189476)
			(end 5.799582 -4.11988)
			(stroke
				(width 0.1)
				(type default)
			)
			(layer "F.SilkS")
		)
		(fp_line
			(start 5.823966 -4.258818)
			(end 5.811774 -4.189476)
			(stroke
				(width 0.1)
				(type default)
			)
			(layer "F.SilkS")
		)
		(fp_line
			(start 5.823966 -4.258818)
			(end 5.811774 -4.189476)
			(stroke
				(width 0.1)
				(type default)
			)
			(layer "F.SilkS")
		)
		(fp_line
			(start 5.828792 -1.147064)
			(end 6.769608 -2.049272)
			(stroke
				(width 0.1)
				(type default)
			)
			(layer "F.SilkS")
		)
		(fp_line
			(start 5.828792 -1.147064)
			(end 6.769608 -2.049272)
			(stroke
				(width 0.1)
				(type default)
			)
			(layer "F.SilkS")
		)
		(fp_line
			(start 5.836158 -4.328414)
			(end 5.823966 -4.258818)
			(stroke
				(width 0.1)
				(type default)
			)
			(layer "F.SilkS")
		)
		(fp_line
			(start 5.836158 -4.328414)
			(end 5.823966 -4.258818)
			(stroke
				(width 0.1)
				(type default)
			)
			(layer "F.SilkS")
		)
		(fp_line
			(start 5.84835 -4.397502)
			(end 5.836158 -4.328414)
			(stroke
				(width 0.1)
				(type default)
			)
			(layer "F.SilkS")
		)
		(fp_line
			(start 5.84835 -4.397502)
			(end 5.836158 -4.328414)
			(stroke
				(width 0.1)
				(type default)
			)
			(layer "F.SilkS")
		)
		(fp_line
			(start 5.854954 -1.114298)
			(end 6.79704 -2.018284)
			(stroke
				(width 0.1)
				(type default)
			)
			(layer "F.SilkS")
		)
		(fp_line
			(start 5.854954 -1.114298)
			(end 6.79704 -2.018284)
			(stroke
				(width 0.1)
				(type default)
			)
			(layer "F.SilkS")
		)
		(fp_line
			(start 5.860542 -4.467098)
			(end 5.84835 -4.397502)
			(stroke
				(width 0.1)
				(type default)
			)
			(layer "F.SilkS")
		)
		(fp_line
			(start 5.860542 -4.467098)
			(end 5.84835 -4.397502)
			(stroke
				(width 0.1)
				(type default)
			)
			(layer "F.SilkS")
		)
		(fp_line
			(start 5.872734 -4.53644)
			(end 5.860542 -4.467098)
			(stroke
				(width 0.1)
				(type default)
			)
			(layer "F.SilkS")
		)
		(fp_line
			(start 5.872734 -4.53644)
			(end 5.860542 -4.467098)
			(stroke
				(width 0.1)
				(type default)
			)
			(layer "F.SilkS")
		)
		(fp_line
			(start 5.872734 -4.53644)
			(end 5.884926 -4.605782)
			(stroke
				(width 0.1)
				(type default)
			)
			(layer "F.SilkS")
		)
		(fp_line
			(start 5.872734 -4.53644)
			(end 5.884926 -4.605782)
			(stroke
				(width 0.1)
				(type default)
			)
			(layer "F.SilkS")
		)
		(fp_line
			(start 5.884926 -4.605782)
			(end 5.897118 -4.675124)
			(stroke
				(width 0.1)
				(type default)
			)
			(layer "F.SilkS")
		)
		(fp_line
			(start 5.884926 -4.605782)
			(end 5.897118 -4.675124)
			(stroke
				(width 0.1)
				(type default)
			)
			(layer "F.SilkS")
		)
		(fp_line
			(start 5.884926 -1.085342)
			(end 6.824726 -1.987042)
			(stroke
				(width 0.1)
				(type default)
			)
			(layer "F.SilkS")
		)
		(fp_line
			(start 5.884926 -1.085342)
			(end 6.824726 -1.987042)
			(stroke
				(width 0.1)
				(type default)
			)
			(layer "F.SilkS")
		)
		(fp_line
			(start 5.897118 -4.675124)
			(end 5.90931 -4.74472)
			(stroke
				(width 0.1)
				(type default)
			)
			(layer "F.SilkS")
		)
		(fp_line
			(start 5.897118 -4.675124)
			(end 5.90931 -4.74472)
			(stroke
				(width 0.1)
				(type default)
			)
			(layer "F.SilkS")
		)
		(fp_line
			(start 5.90931 -4.74472)
			(end 5.921502 -4.814062)
			(stroke
				(width 0.1)
				(type default)
			)
			(layer "F.SilkS")
		)
		(fp_line
			(start 5.90931 -4.74472)
			(end 5.921502 -4.814062)
			(stroke
				(width 0.1)
				(type default)
			)
			(layer "F.SilkS")
		)
		(fp_line
			(start 5.919978 -1.061212)
			(end 6.856222 -1.95961)
			(stroke
				(width 0.1)
				(type default)
			)
			(layer "F.SilkS")
		)
		(fp_line
			(start 5.919978 -1.061212)
			(end 6.856222 -1.95961)
			(stroke
				(width 0.1)
				(type default)
			)
			(layer "F.SilkS")
		)
		(fp_line
			(start 5.921502 -4.814062)
			(end 5.933694 -4.883404)
			(stroke
				(width 0.1)
				(type default)
			)
			(layer "F.SilkS")
		)
		(fp_line
			(start 5.921502 -4.814062)
			(end 5.933694 -4.883404)
			(stroke
				(width 0.1)
				(type default)
			)
			(layer "F.SilkS")
		)
		(fp_line
			(start 5.933694 -4.883404)
			(end 5.945886 -4.952746)
			(stroke
				(width 0.1)
				(type default)
			)
			(layer "F.SilkS")
		)
		(fp_line
			(start 5.933694 -4.883404)
			(end 5.945886 -4.952746)
			(stroke
				(width 0.1)
				(type default)
			)
			(layer "F.SilkS")
		)
		(fp_line
			(start 5.945886 -4.952746)
			(end 5.958078 -5.022088)
			(stroke
				(width 0.1)
				(type default)
			)
			(layer "F.SilkS")
		)
		(fp_line
			(start 5.945886 -4.952746)
			(end 5.958078 -5.022088)
			(stroke
				(width 0.1)
				(type default)
			)
			(layer "F.SilkS")
		)
		(fp_line
			(start 5.955284 -1.03759)
			(end 6.894068 -1.93802)
			(stroke
				(width 0.1)
				(type default)
			)
			(layer "F.SilkS")
		)
		(fp_line
			(start 5.955284 -1.03759)
			(end 6.894068 -1.93802)
			(stroke
				(width 0.1)
				(type default)
			)
			(layer "F.SilkS")
		)
		(fp_line
			(start 5.958078 -5.022088)
			(end 5.97027 -5.091684)
			(stroke
				(width 0.1)
				(type default)
			)
			(layer "F.SilkS")
		)
		(fp_line
			(start 5.958078 -5.022088)
			(end 5.97027 -5.091684)
			(stroke
				(width 0.1)
				(type default)
			)
			(layer "F.SilkS")
		)
		(fp_line
			(start 5.97027 -5.091684)
			(end 5.982208 -5.161026)
			(stroke
				(width 0.1)
				(type default)
			)
			(layer "F.SilkS")
		)
		(fp_line
			(start 5.97027 -5.091684)
			(end 5.982208 -5.161026)
			(stroke
				(width 0.1)
				(type default)
			)
			(layer "F.SilkS")
		)
		(fp_line
			(start 5.98424 -5.171694)
			(end 5.982208 -5.161026)
			(stroke
				(width 0.1)
				(type default)
			)
			(layer "F.SilkS")
		)
		(fp_line
			(start 5.98424 -5.171694)
			(end 5.982208 -5.161026)
			(stroke
				(width 0.1)
				(type default)
			)
			(layer "F.SilkS")
		)
		(fp_line
			(start 5.99059 -1.013714)
			(end 6.93166 -1.91643)
			(stroke
				(width 0.1)
				(type default)
			)
			(layer "F.SilkS")
		)
		(fp_line
			(start 5.99059 -1.013714)
			(end 6.93166 -1.91643)
			(stroke
				(width 0.1)
				(type default)
			)
			(layer "F.SilkS")
		)
		(fp_line
			(start 5.993638 -5.171694)
			(end 5.982208 -5.161026)
			(stroke
				(width 0.1)
				(type default)
			)
			(layer "F.SilkS")
		)
		(fp_line
			(start 5.993638 -5.171694)
			(end 5.982208 -5.161026)
			(stroke
				(width 0.1)
				(type default)
			)
			(layer "F.SilkS")
		)
		(fp_line
			(start 5.993638 -5.171694)
			(end 5.98424 -5.171694)
			(stroke
				(width 0.1)
				(type default)
			)
			(layer "F.SilkS")
		)
		(fp_line
			(start 5.993638 -5.171694)
			(end 5.98424 -5.171694)
			(stroke
				(width 0.1)
				(type default)
			)
			(layer "F.SilkS")
		)
		(fp_line
			(start 6.025642 -0.989584)
			(end 6.973062 -1.898396)
			(stroke
				(width 0.1)
				(type default)
			)
			(layer "F.SilkS")
		)
		(fp_line
			(start 6.025642 -0.989584)
			(end 6.973062 -1.898396)
			(stroke
				(width 0.1)
				(type default)
			)
			(layer "F.SilkS")
		)
		(fp_line
			(start 6.053582 -5.171694)
			(end 5.97027 -5.091684)
			(stroke
				(width 0.1)
				(type default)
			)
			(layer "F.SilkS")
		)
		(fp_line
			(start 6.053582 -5.171694)
			(end 5.97027 -5.091684)
			(stroke
				(width 0.1)
				(type default)
			)
			(layer "F.SilkS")
		)
		(fp_line
			(start 6.053582 -5.171694)
			(end 5.993638 -5.171694)
			(stroke
				(width 0.1)
				(type default)
			)
			(layer "F.SilkS")
		)
		(fp_line
			(start 6.053582 -5.171694)
			(end 5.993638 -5.171694)
			(stroke
				(width 0.1)
				(type default)
			)
			(layer "F.SilkS")
		)
		(fp_line
			(start 6.060948 -0.965962)
			(end 7.020306 -1.88595)
			(stroke
				(width 0.1)
				(type default)
			)
			(layer "F.SilkS")
		)
		(fp_line
			(start 6.060948 -0.965962)
			(end 7.020306 -1.88595)
			(stroke
				(width 0.1)
				(type default)
			)
			(layer "F.SilkS")
		)
		(fp_line
			(start 6.096254 -0.942086)
			(end 7.06755 -1.873504)
			(stroke
				(width 0.1)
				(type default)
			)
			(layer "F.SilkS")
		)
		(fp_line
			(start 6.096254 -0.942086)
			(end 7.06755 -1.873504)
			(stroke
				(width 0.1)
				(type default)
			)
			(layer "F.SilkS")
		)
		(fp_line
			(start 6.11378 -5.171694)
			(end 5.958078 -5.022088)
			(stroke
				(width 0.1)
				(type default)
			)
			(layer "F.SilkS")
		)
		(fp_line
			(start 6.11378 -5.171694)
			(end 5.958078 -5.022088)
			(stroke
				(width 0.1)
				(type default)
			)
			(layer "F.SilkS")
		)
		(fp_line
			(start 6.11378 -5.171694)
			(end 6.053582 -5.171694)
			(stroke
				(width 0.1)
				(type default)
			)
			(layer "F.SilkS")
		)
		(fp_line
			(start 6.11378 -5.171694)
			(end 6.053582 -5.171694)
			(stroke
				(width 0.1)
				(type default)
			)
			(layer "F.SilkS")
		)
		(fp_line
			(start 6.136132 -0.922528)
			(end 7.118604 -1.865122)
			(stroke
				(width 0.1)
				(type default)
			)
			(layer "F.SilkS")
		)
		(fp_line
			(start 6.136132 -0.922528)
			(end 7.118604 -1.865122)
			(stroke
				(width 0.1)
				(type default)
			)
			(layer "F.SilkS")
		)
		(fp_line
			(start 6.173978 -5.171694)
			(end 5.945886 -4.952746)
			(stroke
				(width 0.1)
				(type default)
			)
			(layer "F.SilkS")
		)
		(fp_line
			(start 6.173978 -5.171694)
			(end 5.945886 -4.952746)
			(stroke
				(width 0.1)
				(type default)
			)
			(layer "F.SilkS")
		)
		(fp_line
			(start 6.173978 -5.171694)
			(end 6.11378 -5.171694)
			(stroke
				(width 0.1)
				(type default)
			)
			(layer "F.SilkS")
		)
		(fp_line
			(start 6.173978 -5.171694)
			(end 6.11378 -5.171694)
			(stroke
				(width 0.1)
				(type default)
			)
			(layer "F.SilkS")
		)
		(fp_line
			(start 6.180836 -0.907796)
			(end 7.174738 -1.861058)
			(stroke
				(width 0.1)
				(type default)
			)
			(layer "F.SilkS")
		)
		(fp_line
			(start 6.180836 -0.907796)
			(end 7.174738 -1.861058)
			(stroke
				(width 0.1)
				(type default)
			)
			(layer "F.SilkS")
		)
		(fp_line
			(start 6.225794 -0.89281)
			(end 7.231126 -1.857248)
			(stroke
				(width 0.1)
				(type default)
			)
			(layer "F.SilkS")
		)
		(fp_line
			(start 6.225794 -0.89281)
			(end 7.231126 -1.857248)
			(stroke
				(width 0.1)
				(type default)
			)
			(layer "F.SilkS")
		)
		(fp_line
			(start 6.234176 -5.171694)
			(end 5.933694 -4.883404)
			(stroke
				(width 0.1)
				(type default)
			)
			(layer "F.SilkS")
		)
		(fp_line
			(start 6.234176 -5.171694)
			(end 5.933694 -4.883404)
			(stroke
				(width 0.1)
				(type default)
			)
			(layer "F.SilkS")
		)
		(fp_line
			(start 6.234176 -5.171694)
			(end 6.173978 -5.171694)
			(stroke
				(width 0.1)
				(type default)
			)
			(layer "F.SilkS")
		)
		(fp_line
			(start 6.234176 -5.171694)
			(end 6.173978 -5.171694)
			(stroke
				(width 0.1)
				(type default)
			)
			(layer "F.SilkS")
		)
		(fp_line
			(start 6.270752 -0.878332)
			(end 7.291832 -1.857756)
			(stroke
				(width 0.1)
				(type default)
			)
			(layer "F.SilkS")
		)
		(fp_line
			(start 6.270752 -0.878332)
			(end 7.291832 -1.857756)
			(stroke
				(width 0.1)
				(type default)
			)
			(layer "F.SilkS")
		)
		(fp_line
			(start 6.294374 -5.171694)
			(end 5.921502 -4.814062)
			(stroke
				(width 0.1)
				(type default)
			)
			(layer "F.SilkS")
		)
		(fp_line
			(start 6.294374 -5.171694)
			(end 5.921502 -4.814062)
			(stroke
				(width 0.1)
				(type default)
			)
			(layer "F.SilkS")
		)
		(fp_line
			(start 6.294374 -5.171694)
			(end 6.234176 -5.171694)
			(stroke
				(width 0.1)
				(type default)
			)
			(layer "F.SilkS")
		)
		(fp_line
			(start 6.294374 -5.171694)
			(end 6.234176 -5.171694)
			(stroke
				(width 0.1)
				(type default)
			)
			(layer "F.SilkS")
		)
		(fp_line
			(start 6.315456 -0.8636)
			(end 7.356348 -1.862074)
			(stroke
				(width 0.1)
				(type default)
			)
			(layer "F.SilkS")
		)
		(fp_line
			(start 6.315456 -0.8636)
			(end 7.356348 -1.862074)
			(stroke
				(width 0.1)
				(type default)
			)
			(layer "F.SilkS")
		)
		(fp_line
			(start 6.354318 -5.171694)
			(end 5.90931 -4.74472)
			(stroke
				(width 0.1)
				(type default)
			)
			(layer "F.SilkS")
		)
		(fp_line
			(start 6.354318 -5.171694)
			(end 5.90931 -4.74472)
			(stroke
				(width 0.1)
				(type default)
			)
			(layer "F.SilkS")
		)
		(fp_line
			(start 6.354318 -5.171694)
			(end 6.294374 -5.171694)
			(stroke
				(width 0.1)
				(type default)
			)
			(layer "F.SilkS")
		)
		(fp_line
			(start 6.354318 -5.171694)
			(end 6.294374 -5.171694)
			(stroke
				(width 0.1)
				(type default)
			)
			(layer "F.SilkS")
		)
		(fp_line
			(start 6.36016 -0.848868)
			(end 7.421118 -1.866392)
			(stroke
				(width 0.1)
				(type default)
			)
			(layer "F.SilkS")
		)
		(fp_line
			(start 6.36016 -0.848868)
			(end 7.421118 -1.866392)
			(stroke
				(width 0.1)
				(type default)
			)
			(layer "F.SilkS")
		)
		(fp_line
			(start 6.405118 -0.833882)
			(end 7.500366 -1.884934)
			(stroke
				(width 0.1)
				(type default)
			)
			(layer "F.SilkS")
		)
		(fp_line
			(start 6.405118 -0.833882)
			(end 7.500366 -1.884934)
			(stroke
				(width 0.1)
				(type default)
			)
			(layer "F.SilkS")
		)
		(fp_line
			(start 6.41477 -5.171694)
			(end 5.897118 -4.675124)
			(stroke
				(width 0.1)
				(type default)
			)
			(layer "F.SilkS")
		)
		(fp_line
			(start 6.41477 -5.171694)
			(end 5.897118 -4.675124)
			(stroke
				(width 0.1)
				(type default)
			)
			(layer "F.SilkS")
		)
		(fp_line
			(start 6.41477 -5.171694)
			(end 6.354318 -5.171694)
			(stroke
				(width 0.1)
				(type default)
			)
			(layer "F.SilkS")
		)
		(fp_line
			(start 6.41477 -5.171694)
			(end 6.354318 -5.171694)
			(stroke
				(width 0.1)
				(type default)
			)
			(layer "F.SilkS")
		)
		(fp_line
			(start 6.455664 -0.824738)
			(end 7.582662 -1.906016)
			(stroke
				(width 0.1)
				(type default)
			)
			(layer "F.SilkS")
		)
		(fp_line
			(start 6.455664 -0.824738)
			(end 7.582662 -1.906016)
			(stroke
				(width 0.1)
				(type default)
			)
			(layer "F.SilkS")
		)
		(fp_line
			(start 6.474714 -5.171694)
			(end 5.884926 -4.605782)
			(stroke
				(width 0.1)
				(type default)
			)
			(layer "F.SilkS")
		)
		(fp_line
			(start 6.474714 -5.171694)
			(end 5.884926 -4.605782)
			(stroke
				(width 0.1)
				(type default)
			)
			(layer "F.SilkS")
		)
		(fp_line
			(start 6.474714 -5.171694)
			(end 6.41477 -5.171694)
			(stroke
				(width 0.1)
				(type default)
			)
			(layer "F.SilkS")
		)
		(fp_line
			(start 6.474714 -5.171694)
			(end 6.41477 -5.171694)
			(stroke
				(width 0.1)
				(type default)
			)
			(layer "F.SilkS")
		)
		(fp_line
			(start 6.510528 -0.819912)
			(end 7.699756 -1.96088)
			(stroke
				(width 0.1)
				(type default)
			)
			(layer "F.SilkS")
		)
		(fp_line
			(start 6.510528 -0.819912)
			(end 7.699756 -1.96088)
			(stroke
				(width 0.1)
				(type default)
			)
			(layer "F.SilkS")
		)
		(fp_line
			(start 6.534912 -5.171694)
			(end 5.872734 -4.53644)
			(stroke
				(width 0.1)
				(type default)
			)
			(layer "F.SilkS")
		)
		(fp_line
			(start 6.534912 -5.171694)
			(end 5.872734 -4.53644)
			(stroke
				(width 0.1)
				(type default)
			)
			(layer "F.SilkS")
		)
		(fp_line
			(start 6.534912 -5.171694)
			(end 6.474714 -5.171694)
			(stroke
				(width 0.1)
				(type default)
			)
			(layer "F.SilkS")
		)
		(fp_line
			(start 6.534912 -5.171694)
			(end 6.474714 -5.171694)
			(stroke
				(width 0.1)
				(type default)
			)
			(layer "F.SilkS")
		)
		(fp_line
			(start 6.59511 -5.171694)
			(end 5.860542 -4.467098)
			(stroke
				(width 0.1)
				(type default)
			)
			(layer "F.SilkS")
		)
		(fp_line
			(start 6.59511 -5.171694)
			(end 5.860542 -4.467098)
			(stroke
				(width 0.1)
				(type default)
			)
			(layer "F.SilkS")
		)
		(fp_line
			(start 6.59511 -5.171694)
			(end 6.534912 -5.171694)
			(stroke
				(width 0.1)
				(type default)
			)
			(layer "F.SilkS")
		)
		(fp_line
			(start 6.59511 -5.171694)
			(end 6.534912 -5.171694)
			(stroke
				(width 0.1)
				(type default)
			)
			(layer "F.SilkS")
		)
		(fp_line
			(start 6.620256 -0.809498)
			(end 9.404096 -3.480054)
			(stroke
				(width 0.1)
				(type default)
			)
			(layer "F.SilkS")
		)
		(fp_line
			(start 6.620256 -0.809498)
			(end 9.404096 -3.480054)
			(stroke
				(width 0.1)
				(type default)
			)
			(layer "F.SilkS")
		)
		(fp_line
			(start 6.655308 -5.171694)
			(end 5.84835 -4.397502)
			(stroke
				(width 0.1)
				(type default)
			)
			(layer "F.SilkS")
		)
		(fp_line
			(start 6.655308 -5.171694)
			(end 5.84835 -4.397502)
			(stroke
				(width 0.1)
				(type default)
			)
			(layer "F.SilkS")
		)
		(fp_line
			(start 6.655308 -5.171694)
			(end 6.59511 -5.171694)
			(stroke
				(width 0.1)
				(type default)
			)
			(layer "F.SilkS")
		)
		(fp_line
			(start 6.655308 -5.171694)
			(end 6.59511 -5.171694)
			(stroke
				(width 0.1)
				(type default)
			)
			(layer "F.SilkS")
		)
		(fp_line
			(start 6.67512 -0.804672)
			(end 9.391904 -3.410712)
			(stroke
				(width 0.1)
				(type default)
			)
			(layer "F.SilkS")
		)
		(fp_line
			(start 6.67512 -0.804672)
			(end 9.391904 -3.410712)
			(stroke
				(width 0.1)
				(type default)
			)
			(layer "F.SilkS")
		)
		(fp_line
			(start 6.703822 -2.852166)
			(end 6.716014 -2.921254)
			(stroke
				(width 0.1)
				(type default)
			)
			(layer "F.SilkS")
		)
		(fp_line
			(start 6.703822 -2.852166)
			(end 6.716014 -2.921254)
			(stroke
				(width 0.1)
				(type default)
			)
			(layer "F.SilkS")
		)
		(fp_line
			(start 6.715506 -5.171694)
			(end 5.836158 -4.328414)
			(stroke
				(width 0.1)
				(type default)
			)
			(layer "F.SilkS")
		)
		(fp_line
			(start 6.715506 -5.171694)
			(end 5.836158 -4.328414)
			(stroke
				(width 0.1)
				(type default)
			)
			(layer "F.SilkS")
		)
		(fp_line
			(start 6.715506 -5.171694)
			(end 6.655308 -5.171694)
			(stroke
				(width 0.1)
				(type default)
			)
			(layer "F.SilkS")
		)
		(fp_line
			(start 6.715506 -5.171694)
			(end 6.655308 -5.171694)
			(stroke
				(width 0.1)
				(type default)
			)
			(layer "F.SilkS")
		)
		(fp_line
			(start 6.716014 -2.921254)
			(end 6.728206 -2.99085)
			(stroke
				(width 0.1)
				(type default)
			)
			(layer "F.SilkS")
		)
		(fp_line
			(start 6.716014 -2.921254)
			(end 6.728206 -2.99085)
			(stroke
				(width 0.1)
				(type default)
			)
			(layer "F.SilkS")
		)
		(fp_line
			(start 6.728206 -2.99085)
			(end 6.740144 -3.060192)
			(stroke
				(width 0.1)
				(type default)
			)
			(layer "F.SilkS")
		)
		(fp_line
			(start 6.728206 -2.99085)
			(end 6.740144 -3.060192)
			(stroke
				(width 0.1)
				(type default)
			)
			(layer "F.SilkS")
		)
		(fp_line
			(start 6.729984 -0.799592)
			(end 9.379712 -3.34137)
			(stroke
				(width 0.1)
				(type default)
			)
			(layer "F.SilkS")
		)
		(fp_line
			(start 6.729984 -0.799592)
			(end 9.379712 -3.34137)
			(stroke
				(width 0.1)
				(type default)
			)
			(layer "F.SilkS")
		)
		(fp_line
			(start 6.740144 -3.060192)
			(end 6.75259 -3.129534)
			(stroke
				(width 0.1)
				(type default)
			)
			(layer "F.SilkS")
		)
		(fp_line
			(start 6.740144 -3.060192)
			(end 6.75259 -3.129534)
			(stroke
				(width 0.1)
				(type default)
			)
			(layer "F.SilkS")
		)
		(fp_line
			(start 6.75259 -3.129534)
			(end 6.764782 -3.19913)
			(stroke
				(width 0.1)
				(type default)
			)
			(layer "F.SilkS")
		)
		(fp_line
			(start 6.75259 -3.129534)
			(end 6.764782 -3.19913)
			(stroke
				(width 0.1)
				(type default)
			)
			(layer "F.SilkS")
		)
		(fp_line
			(start 6.764782 -3.19913)
			(end 6.776974 -3.268472)
			(stroke
				(width 0.1)
				(type default)
			)
			(layer "F.SilkS")
		)
		(fp_line
			(start 6.764782 -3.19913)
			(end 6.776974 -3.268472)
			(stroke
				(width 0.1)
				(type default)
			)
			(layer "F.SilkS")
		)
		(fp_line
			(start 6.77545 -5.171694)
			(end 5.823966 -4.258818)
			(stroke
				(width 0.1)
				(type default)
			)
			(layer "F.SilkS")
		)
		(fp_line
			(start 6.77545 -5.171694)
			(end 5.823966 -4.258818)
			(stroke
				(width 0.1)
				(type default)
			)
			(layer "F.SilkS")
		)
		(fp_line
			(start 6.77545 -5.171694)
			(end 6.715506 -5.171694)
			(stroke
				(width 0.1)
				(type default)
			)
			(layer "F.SilkS")
		)
		(fp_line
			(start 6.77545 -5.171694)
			(end 6.715506 -5.171694)
			(stroke
				(width 0.1)
				(type default)
			)
			(layer "F.SilkS")
		)
		(fp_line
			(start 6.776974 -3.268472)
			(end 6.788912 -3.337814)
			(stroke
				(width 0.1)
				(type default)
			)
			(layer "F.SilkS")
		)
		(fp_line
			(start 6.776974 -3.268472)
			(end 6.788912 -3.337814)
			(stroke
				(width 0.1)
				(type default)
			)
			(layer "F.SilkS")
		)
		(fp_line
			(start 6.784848 -0.794258)
			(end 9.36752 -3.272028)
			(stroke
				(width 0.1)
				(type default)
			)
			(layer "F.SilkS")
		)
		(fp_line
			(start 6.784848 -0.794258)
			(end 9.36752 -3.272028)
			(stroke
				(width 0.1)
				(type default)
			)
			(layer "F.SilkS")
		)
		(fp_line
			(start 6.788912 -3.337814)
			(end 6.801104 -3.407156)
			(stroke
				(width 0.1)
				(type default)
			)
			(layer "F.SilkS")
		)
		(fp_line
			(start 6.788912 -3.337814)
			(end 6.801104 -3.407156)
			(stroke
				(width 0.1)
				(type default)
			)
			(layer "F.SilkS")
		)
		(fp_line
			(start 6.801104 -3.407156)
			(end 6.81355 -3.476498)
			(stroke
				(width 0.1)
				(type default)
			)
			(layer "F.SilkS")
		)
		(fp_line
			(start 6.801104 -3.407156)
			(end 6.81355 -3.476498)
			(stroke
				(width 0.1)
				(type default)
			)
			(layer "F.SilkS")
		)
		(fp_line
			(start 6.825488 -3.54584)
			(end 6.81355 -3.476498)
			(stroke
				(width 0.1)
				(type default)
			)
			(layer "F.SilkS")
		)
		(fp_line
			(start 6.825488 -3.54584)
			(end 6.81355 -3.476498)
			(stroke
				(width 0.1)
				(type default)
			)
			(layer "F.SilkS")
		)
		(fp_line
			(start 6.825488 -3.54584)
			(end 6.83768 -3.615436)
			(stroke
				(width 0.1)
				(type default)
			)
			(layer "F.SilkS")
		)
		(fp_line
			(start 6.825488 -3.54584)
			(end 6.83768 -3.615436)
			(stroke
				(width 0.1)
				(type default)
			)
			(layer "F.SilkS")
		)
		(fp_line
			(start 6.835648 -5.171694)
			(end 5.811774 -4.189476)
			(stroke
				(width 0.1)
				(type default)
			)
			(layer "F.SilkS")
		)
		(fp_line
			(start 6.835648 -5.171694)
			(end 5.811774 -4.189476)
			(stroke
				(width 0.1)
				(type default)
			)
			(layer "F.SilkS")
		)
		(fp_line
			(start 6.835648 -5.171694)
			(end 6.77545 -5.171694)
			(stroke
				(width 0.1)
				(type default)
			)
			(layer "F.SilkS")
		)
		(fp_line
			(start 6.835648 -5.171694)
			(end 6.77545 -5.171694)
			(stroke
				(width 0.1)
				(type default)
			)
			(layer "F.SilkS")
		)
		(fp_line
			(start 6.83768 -3.615436)
			(end 5.509514 -2.341372)
			(stroke
				(width 0.1)
				(type default)
			)
			(layer "F.SilkS")
		)
		(fp_line
			(start 6.83768 -3.615436)
			(end 5.509514 -2.341372)
			(stroke
				(width 0.1)
				(type default)
			)
			(layer "F.SilkS")
		)
		(fp_line
			(start 6.83768 -3.615436)
			(end 6.849872 -3.684778)
			(stroke
				(width 0.1)
				(type default)
			)
			(layer "F.SilkS")
		)
		(fp_line
			(start 6.83768 -3.615436)
			(end 6.849872 -3.684778)
			(stroke
				(width 0.1)
				(type default)
			)
			(layer "F.SilkS")
		)
		(fp_line
			(start 6.848348 -0.797814)
			(end 9.355328 -3.202432)
			(stroke
				(width 0.1)
				(type default)
			)
			(layer "F.SilkS")
		)
		(fp_line
			(start 6.848348 -0.797814)
			(end 9.355328 -3.202432)
			(stroke
				(width 0.1)
				(type default)
			)
			(layer "F.SilkS")
		)
		(fp_line
			(start 6.849872 -3.684778)
			(end 5.517642 -2.40665)
			(stroke
				(width 0.1)
				(type default)
			)
			(layer "F.SilkS")
		)
		(fp_line
			(start 6.849872 -3.684778)
			(end 5.517642 -2.40665)
			(stroke
				(width 0.1)
				(type default)
			)
			(layer "F.SilkS")
		)
		(fp_line
			(start 6.849872 -3.684778)
			(end 6.862318 -3.75412)
			(stroke
				(width 0.1)
				(type default)
			)
			(layer "F.SilkS")
		)
		(fp_line
			(start 6.849872 -3.684778)
			(end 6.862318 -3.75412)
			(stroke
				(width 0.1)
				(type default)
			)
			(layer "F.SilkS")
		)
		(fp_line
			(start 6.862318 -3.75412)
			(end 5.525516 -2.471928)
			(stroke
				(width 0.1)
				(type default)
			)
			(layer "F.SilkS")
		)
		(fp_line
			(start 6.862318 -3.75412)
			(end 5.525516 -2.471928)
			(stroke
				(width 0.1)
				(type default)
			)
			(layer "F.SilkS")
		)
		(fp_line
			(start 6.862318 -3.75412)
			(end 6.874256 -3.823716)
			(stroke
				(width 0.1)
				(type default)
			)
			(layer "F.SilkS")
		)
		(fp_line
			(start 6.862318 -3.75412)
			(end 6.874256 -3.823716)
			(stroke
				(width 0.1)
				(type default)
			)
			(layer "F.SilkS")
		)
		(fp_line
			(start 6.874256 -3.823716)
			(end 5.53339 -2.537206)
			(stroke
				(width 0.1)
				(type default)
			)
			(layer "F.SilkS")
		)
		(fp_line
			(start 6.874256 -3.823716)
			(end 5.53339 -2.537206)
			(stroke
				(width 0.1)
				(type default)
			)
			(layer "F.SilkS")
		)
		(fp_line
			(start 6.874256 -3.823716)
			(end 6.886448 -3.893058)
			(stroke
				(width 0.1)
				(type default)
			)
			(layer "F.SilkS")
		)
		(fp_line
			(start 6.874256 -3.823716)
			(end 6.886448 -3.893058)
			(stroke
				(width 0.1)
				(type default)
			)
			(layer "F.SilkS")
		)
		(fp_line
			(start 6.886448 -3.893058)
			(end 5.541264 -2.602738)
			(stroke
				(width 0.1)
				(type default)
			)
			(layer "F.SilkS")
		)
		(fp_line
			(start 6.886448 -3.893058)
			(end 5.541264 -2.602738)
			(stroke
				(width 0.1)
				(type default)
			)
			(layer "F.SilkS")
		)
		(fp_line
			(start 6.886448 -3.893058)
			(end 6.89864 -3.9624)
			(stroke
				(width 0.1)
				(type default)
			)
			(layer "F.SilkS")
		)
		(fp_line
			(start 6.886448 -3.893058)
			(end 6.89864 -3.9624)
			(stroke
				(width 0.1)
				(type default)
			)
			(layer "F.SilkS")
		)
		(fp_line
			(start 6.895846 -5.171694)
			(end 5.799582 -4.11988)
			(stroke
				(width 0.1)
				(type default)
			)
			(layer "F.SilkS")
		)
		(fp_line
			(start 6.895846 -5.171694)
			(end 5.799582 -4.11988)
			(stroke
				(width 0.1)
				(type default)
			)
			(layer "F.SilkS")
		)
		(fp_line
			(start 6.895846 -5.171694)
			(end 6.835648 -5.171694)
			(stroke
				(width 0.1)
				(type default)
			)
			(layer "F.SilkS")
		)
		(fp_line
			(start 6.895846 -5.171694)
			(end 6.835648 -5.171694)
			(stroke
				(width 0.1)
				(type default)
			)
			(layer "F.SilkS")
		)
		(fp_line
			(start 6.89864 -3.9624)
			(end 5.549392 -2.668016)
			(stroke
				(width 0.1)
				(type default)
			)
			(layer "F.SilkS")
		)
		(fp_line
			(start 6.89864 -3.9624)
			(end 5.549392 -2.668016)
			(stroke
				(width 0.1)
				(type default)
			)
			(layer "F.SilkS")
		)
		(fp_line
			(start 6.89864 -3.9624)
			(end 6.910832 -4.031742)
			(stroke
				(width 0.1)
				(type default)
			)
			(layer "F.SilkS")
		)
		(fp_line
			(start 6.89864 -3.9624)
			(end 6.910832 -4.031742)
			(stroke
				(width 0.1)
				(type default)
			)
			(layer "F.SilkS")
		)
		(fp_line
			(start 6.910832 -4.031742)
			(end 5.557266 -2.733294)
			(stroke
				(width 0.1)
				(type default)
			)
			(layer "F.SilkS")
		)
		(fp_line
			(start 6.910832 -4.031742)
			(end 5.557266 -2.733294)
			(stroke
				(width 0.1)
				(type default)
			)
			(layer "F.SilkS")
		)
		(fp_line
			(start 6.910832 -4.031742)
			(end 6.923024 -4.101084)
			(stroke
				(width 0.1)
				(type default)
			)
			(layer "F.SilkS")
		)
		(fp_line
			(start 6.910832 -4.031742)
			(end 6.923024 -4.101084)
			(stroke
				(width 0.1)
				(type default)
			)
			(layer "F.SilkS")
		)
		(fp_line
			(start 6.914896 -0.80391)
			(end 9.343136 -3.13309)
			(stroke
				(width 0.1)
				(type default)
			)
			(layer "F.SilkS")
		)
		(fp_line
			(start 6.914896 -0.80391)
			(end 9.343136 -3.13309)
			(stroke
				(width 0.1)
				(type default)
			)
			(layer "F.SilkS")
		)
		(fp_line
			(start 6.923024 -4.101084)
			(end 5.568188 -2.801366)
			(stroke
				(width 0.1)
				(type default)
			)
			(layer "F.SilkS")
		)
		(fp_line
			(start 6.923024 -4.101084)
			(end 5.568188 -2.801366)
			(stroke
				(width 0.1)
				(type default)
			)
			(layer "F.SilkS")
		)
		(fp_line
			(start 6.923024 -4.101084)
			(end 6.935216 -4.170426)
			(stroke
				(width 0.1)
				(type default)
			)
			(layer "F.SilkS")
		)
		(fp_line
			(start 6.923024 -4.101084)
			(end 6.935216 -4.170426)
			(stroke
				(width 0.1)
				(type default)
			)
			(layer "F.SilkS")
		)
		(fp_line
			(start 6.935216 -4.170426)
			(end 5.58038 -2.870962)
			(stroke
				(width 0.1)
				(type default)
			)
			(layer "F.SilkS")
		)
		(fp_line
			(start 6.935216 -4.170426)
			(end 5.58038 -2.870962)
			(stroke
				(width 0.1)
				(type default)
			)
			(layer "F.SilkS")
		)
		(fp_line
			(start 6.935216 -4.170426)
			(end 6.947408 -4.240022)
			(stroke
				(width 0.1)
				(type default)
			)
			(layer "F.SilkS")
		)
		(fp_line
			(start 6.935216 -4.170426)
			(end 6.947408 -4.240022)
			(stroke
				(width 0.1)
				(type default)
			)
			(layer "F.SilkS")
		)
		(fp_line
			(start 6.947408 -4.240022)
			(end 5.592572 -2.940304)
			(stroke
				(width 0.1)
				(type default)
			)
			(layer "F.SilkS")
		)
		(fp_line
			(start 6.947408 -4.240022)
			(end 5.592572 -2.940304)
			(stroke
				(width 0.1)
				(type default)
			)
			(layer "F.SilkS")
		)
		(fp_line
			(start 6.947408 -4.240022)
			(end 6.9596 -4.309364)
			(stroke
				(width 0.1)
				(type default)
			)
			(layer "F.SilkS")
		)
		(fp_line
			(start 6.947408 -4.240022)
			(end 6.9596 -4.309364)
			(stroke
				(width 0.1)
				(type default)
			)
			(layer "F.SilkS")
		)
		(fp_line
			(start 6.956044 -5.171694)
			(end 5.78739 -4.050538)
			(stroke
				(width 0.1)
				(type default)
			)
			(layer "F.SilkS")
		)
		(fp_line
			(start 6.956044 -5.171694)
			(end 5.78739 -4.050538)
			(stroke
				(width 0.1)
				(type default)
			)
			(layer "F.SilkS")
		)
		(fp_line
			(start 6.956044 -5.171694)
			(end 6.895846 -5.171694)
			(stroke
				(width 0.1)
				(type default)
			)
			(layer "F.SilkS")
		)
		(fp_line
			(start 6.956044 -5.171694)
			(end 6.895846 -5.171694)
			(stroke
				(width 0.1)
				(type default)
			)
			(layer "F.SilkS")
		)
		(fp_line
			(start 6.9596 -4.309364)
			(end 5.604764 -3.009646)
			(stroke
				(width 0.1)
				(type default)
			)
			(layer "F.SilkS")
		)
		(fp_line
			(start 6.9596 -4.309364)
			(end 5.604764 -3.009646)
			(stroke
				(width 0.1)
				(type default)
			)
			(layer "F.SilkS")
		)
		(fp_line
			(start 6.9596 -4.309364)
			(end 6.971792 -4.378706)
			(stroke
				(width 0.1)
				(type default)
			)
			(layer "F.SilkS")
		)
		(fp_line
			(start 6.9596 -4.309364)
			(end 6.971792 -4.378706)
			(stroke
				(width 0.1)
				(type default)
			)
			(layer "F.SilkS")
		)
		(fp_line
			(start 6.971792 -4.378706)
			(end 5.616956 -3.079242)
			(stroke
				(width 0.1)
				(type default)
			)
			(layer "F.SilkS")
		)
		(fp_line
			(start 6.971792 -4.378706)
			(end 5.616956 -3.079242)
			(stroke
				(width 0.1)
				(type default)
			)
			(layer "F.SilkS")
		)
		(fp_line
			(start 6.971792 -4.378706)
			(end 6.983984 -4.448302)
			(stroke
				(width 0.1)
				(type default)
			)
			(layer "F.SilkS")
		)
		(fp_line
			(start 6.971792 -4.378706)
			(end 6.983984 -4.448302)
			(stroke
				(width 0.1)
				(type default)
			)
			(layer "F.SilkS")
		)
		(fp_line
			(start 6.981444 -0.809752)
			(end 9.330944 -3.063748)
			(stroke
				(width 0.1)
				(type default)
			)
			(layer "F.SilkS")
		)
		(fp_line
			(start 6.981444 -0.809752)
			(end 9.330944 -3.063748)
			(stroke
				(width 0.1)
				(type default)
			)
			(layer "F.SilkS")
		)
		(fp_line
			(start 6.983984 -4.448302)
			(end 5.629148 -3.148584)
			(stroke
				(width 0.1)
				(type default)
			)
			(layer "F.SilkS")
		)
		(fp_line
			(start 6.983984 -4.448302)
			(end 5.629148 -3.148584)
			(stroke
				(width 0.1)
				(type default)
			)
			(layer "F.SilkS")
		)
		(fp_line
			(start 6.983984 -4.448302)
			(end 6.996176 -4.51739)
			(stroke
				(width 0.1)
				(type default)
			)
			(layer "F.SilkS")
		)
		(fp_line
			(start 6.983984 -4.448302)
			(end 6.996176 -4.51739)
			(stroke
				(width 0.1)
				(type default)
			)
			(layer "F.SilkS")
		)
		(fp_line
			(start 6.996176 -4.51739)
			(end 5.64134 -3.217926)
			(stroke
				(width 0.1)
				(type default)
			)
			(layer "F.SilkS")
		)
		(fp_line
			(start 6.996176 -4.51739)
			(end 5.64134 -3.217926)
			(stroke
				(width 0.1)
				(type default)
			)
			(layer "F.SilkS")
		)
		(fp_line
			(start 6.996176 -4.51739)
			(end 7.008368 -4.586986)
			(stroke
				(width 0.1)
				(type default)
			)
			(layer "F.SilkS")
		)
		(fp_line
			(start 6.996176 -4.51739)
			(end 7.008368 -4.586986)
			(stroke
				(width 0.1)
				(type default)
			)
			(layer "F.SilkS")
		)
		(fp_line
			(start 7.008368 -4.586986)
			(end 5.653532 -3.287268)
			(stroke
				(width 0.1)
				(type default)
			)
			(layer "F.SilkS")
		)
		(fp_line
			(start 7.008368 -4.586986)
			(end 5.653532 -3.287268)
			(stroke
				(width 0.1)
				(type default)
			)
			(layer "F.SilkS")
		)
		(fp_line
			(start 7.008368 -4.586986)
			(end 7.02056 -4.656328)
			(stroke
				(width 0.1)
				(type default)
			)
			(layer "F.SilkS")
		)
		(fp_line
			(start 7.008368 -4.586986)
			(end 7.02056 -4.656328)
			(stroke
				(width 0.1)
				(type default)
			)
			(layer "F.SilkS")
		)
		(fp_line
			(start 7.016242 -5.171694)
			(end 5.775198 -3.98145)
			(stroke
				(width 0.1)
				(type default)
			)
			(layer "F.SilkS")
		)
		(fp_line
			(start 7.016242 -5.171694)
			(end 5.775198 -3.98145)
			(stroke
				(width 0.1)
				(type default)
			)
			(layer "F.SilkS")
		)
		(fp_line
			(start 7.016242 -5.171694)
			(end 6.956044 -5.171694)
			(stroke
				(width 0.1)
				(type default)
			)
			(layer "F.SilkS")
		)
		(fp_line
			(start 7.016242 -5.171694)
			(end 6.956044 -5.171694)
			(stroke
				(width 0.1)
				(type default)
			)
			(layer "F.SilkS")
		)
		(fp_line
			(start 7.02056 -4.656328)
			(end 5.665724 -3.35661)
			(stroke
				(width 0.1)
				(type default)
			)
			(layer "F.SilkS")
		)
		(fp_line
			(start 7.02056 -4.656328)
			(end 5.665724 -3.35661)
			(stroke
				(width 0.1)
				(type default)
			)
			(layer "F.SilkS")
		)
		(fp_line
			(start 7.02056 -4.656328)
			(end 7.032752 -4.725924)
			(stroke
				(width 0.1)
				(type default)
			)
			(layer "F.SilkS")
		)
		(fp_line
			(start 7.02056 -4.656328)
			(end 7.032752 -4.725924)
			(stroke
				(width 0.1)
				(type default)
			)
			(layer "F.SilkS")
		)
		(fp_line
			(start 7.032752 -4.725924)
			(end 5.677662 -3.425952)
			(stroke
				(width 0.1)
				(type default)
			)
			(layer "F.SilkS")
		)
		(fp_line
			(start 7.032752 -4.725924)
			(end 5.677662 -3.425952)
			(stroke
				(width 0.1)
				(type default)
			)
			(layer "F.SilkS")
		)
		(fp_line
			(start 7.032752 -4.725924)
			(end 7.04469 -4.795012)
			(stroke
				(width 0.1)
				(type default)
			)
			(layer "F.SilkS")
		)
		(fp_line
			(start 7.032752 -4.725924)
			(end 7.04469 -4.795012)
			(stroke
				(width 0.1)
				(type default)
			)
			(layer "F.SilkS")
		)
		(fp_line
			(start 7.04469 -4.795012)
			(end 5.690108 -3.495548)
			(stroke
				(width 0.1)
				(type default)
			)
			(layer "F.SilkS")
		)
		(fp_line
			(start 7.04469 -4.795012)
			(end 5.690108 -3.495548)
			(stroke
				(width 0.1)
				(type default)
			)
			(layer "F.SilkS")
		)
		(fp_line
			(start 7.04469 -4.795012)
			(end 7.057136 -4.864354)
			(stroke
				(width 0.1)
				(type default)
			)
			(layer "F.SilkS")
		)
		(fp_line
			(start 7.04469 -4.795012)
			(end 7.057136 -4.864354)
			(stroke
				(width 0.1)
				(type default)
			)
			(layer "F.SilkS")
		)
		(fp_line
			(start 7.047992 -0.816102)
			(end 9.318752 -2.994406)
			(stroke
				(width 0.1)
				(type default)
			)
			(layer "F.SilkS")
		)
		(fp_line
			(start 7.047992 -0.816102)
			(end 9.318752 -2.994406)
			(stroke
				(width 0.1)
				(type default)
			)
			(layer "F.SilkS")
		)
		(fp_line
			(start 7.057136 -4.864354)
			(end 5.7023 -3.56489)
			(stroke
				(width 0.1)
				(type default)
			)
			(layer "F.SilkS")
		)
		(fp_line
			(start 7.057136 -4.864354)
			(end 5.7023 -3.56489)
			(stroke
				(width 0.1)
				(type default)
			)
			(layer "F.SilkS")
		)
		(fp_line
			(start 7.057136 -4.864354)
			(end 7.069328 -4.93395)
			(stroke
				(width 0.1)
				(type default)
			)
			(layer "F.SilkS")
		)
		(fp_line
			(start 7.057136 -4.864354)
			(end 7.069328 -4.93395)
			(stroke
				(width 0.1)
				(type default)
			)
			(layer "F.SilkS")
		)
		(fp_line
			(start 7.069328 -4.93395)
			(end 5.714238 -3.634232)
			(stroke
				(width 0.1)
				(type default)
			)
			(layer "F.SilkS")
		)
		(fp_line
			(start 7.069328 -4.93395)
			(end 5.714238 -3.634232)
			(stroke
				(width 0.1)
				(type default)
			)
			(layer "F.SilkS")
		)
		(fp_line
			(start 7.069328 -4.93395)
			(end 7.081266 -5.003292)
			(stroke
				(width 0.1)
				(type default)
			)
			(layer "F.SilkS")
		)
		(fp_line
			(start 7.069328 -4.93395)
			(end 7.081266 -5.003292)
			(stroke
				(width 0.1)
				(type default)
			)
			(layer "F.SilkS")
		)
		(fp_line
			(start 7.07644 -5.171694)
			(end 5.763006 -3.911854)
			(stroke
				(width 0.1)
				(type default)
			)
			(layer "F.SilkS")
		)
		(fp_line
			(start 7.07644 -5.171694)
			(end 5.763006 -3.911854)
			(stroke
				(width 0.1)
				(type default)
			)
			(layer "F.SilkS")
		)
		(fp_line
			(start 7.07644 -5.171694)
			(end 7.016242 -5.171694)
			(stroke
				(width 0.1)
				(type default)
			)
			(layer "F.SilkS")
		)
		(fp_line
			(start 7.07644 -5.171694)
			(end 7.016242 -5.171694)
			(stroke
				(width 0.1)
				(type default)
			)
			(layer "F.SilkS")
		)
		(fp_line
			(start 7.081266 -5.003292)
			(end 5.72643 -3.703828)
			(stroke
				(width 0.1)
				(type default)
			)
			(layer "F.SilkS")
		)
		(fp_line
			(start 7.081266 -5.003292)
			(end 5.72643 -3.703828)
			(stroke
				(width 0.1)
				(type default)
			)
			(layer "F.SilkS")
		)
		(fp_line
			(start 7.081266 -5.003292)
			(end 7.093458 -5.072888)
			(stroke
				(width 0.1)
				(type default)
			)
			(layer "F.SilkS")
		)
		(fp_line
			(start 7.081266 -5.003292)
			(end 7.093458 -5.072888)
			(stroke
				(width 0.1)
				(type default)
			)
			(layer "F.SilkS")
		)
		(fp_line
			(start 7.093458 -5.072888)
			(end 5.738876 -3.772916)
			(stroke
				(width 0.1)
				(type default)
			)
			(layer "F.SilkS")
		)
		(fp_line
			(start 7.093458 -5.072888)
			(end 5.738876 -3.772916)
			(stroke
				(width 0.1)
				(type default)
			)
			(layer "F.SilkS")
		)
		(fp_line
			(start 7.093458 -5.072888)
			(end 7.10565 -5.141976)
			(stroke
				(width 0.1)
				(type default)
			)
			(layer "F.SilkS")
		)
		(fp_line
			(start 7.093458 -5.072888)
			(end 7.10565 -5.141976)
			(stroke
				(width 0.1)
				(type default)
			)
			(layer "F.SilkS")
		)
		(fp_line
			(start 7.10565 -5.141976)
			(end 5.751068 -3.842512)
			(stroke
				(width 0.1)
				(type default)
			)
			(layer "F.SilkS")
		)
		(fp_line
			(start 7.10565 -5.141976)
			(end 5.751068 -3.842512)
			(stroke
				(width 0.1)
				(type default)
			)
			(layer "F.SilkS")
		)
		(fp_line
			(start 7.10565 -5.141976)
			(end 7.110984 -5.171694)
			(stroke
				(width 0.1)
				(type default)
			)
			(layer "F.SilkS")
		)
		(fp_line
			(start 7.10565 -5.141976)
			(end 7.110984 -5.171694)
			(stroke
				(width 0.1)
				(type default)
			)
			(layer "F.SilkS")
		)
		(fp_line
			(start 7.110984 -5.171694)
			(end 7.07644 -5.171694)
			(stroke
				(width 0.1)
				(type default)
			)
			(layer "F.SilkS")
		)
		(fp_line
			(start 7.110984 -5.171694)
			(end 7.07644 -5.171694)
			(stroke
				(width 0.1)
				(type default)
			)
			(layer "F.SilkS")
		)
		(fp_line
			(start 7.11454 -0.822198)
			(end 9.30656 -2.925064)
			(stroke
				(width 0.1)
				(type default)
			)
			(layer "F.SilkS")
		)
		(fp_line
			(start 7.11454 -0.822198)
			(end 9.30656 -2.925064)
			(stroke
				(width 0.1)
				(type default)
			)
			(layer "F.SilkS")
		)
		(fp_line
			(start 7.196582 -0.84328)
			(end 9.294368 -2.855468)
			(stroke
				(width 0.1)
				(type default)
			)
			(layer "F.SilkS")
		)
		(fp_line
			(start 7.196582 -0.84328)
			(end 9.294368 -2.855468)
			(stroke
				(width 0.1)
				(type default)
			)
			(layer "F.SilkS")
		)
		(fp_line
			(start 7.281418 -0.866648)
			(end 9.281922 -2.786126)
			(stroke
				(width 0.1)
				(type default)
			)
			(layer "F.SilkS")
		)
		(fp_line
			(start 7.281418 -0.866648)
			(end 9.281922 -2.786126)
			(stroke
				(width 0.1)
				(type default)
			)
			(layer "F.SilkS")
		)
		(fp_line
			(start 7.366 -0.890016)
			(end 9.269984 -2.716784)
			(stroke
				(width 0.1)
				(type default)
			)
			(layer "F.SilkS")
		)
		(fp_line
			(start 7.366 -0.890016)
			(end 9.269984 -2.716784)
			(stroke
				(width 0.1)
				(type default)
			)
			(layer "F.SilkS")
		)
		(fp_line
			(start 7.464298 -0.926846)
			(end 9.257792 -2.647188)
			(stroke
				(width 0.1)
				(type default)
			)
			(layer "F.SilkS")
		)
		(fp_line
			(start 7.464298 -0.926846)
			(end 9.257792 -2.647188)
			(stroke
				(width 0.1)
				(type default)
			)
			(layer "F.SilkS")
		)
		(fp_line
			(start 7.583678 -0.983488)
			(end 9.2456 -2.577592)
			(stroke
				(width 0.1)
				(type default)
			)
			(layer "F.SilkS")
		)
		(fp_line
			(start 7.583678 -0.983488)
			(end 9.2456 -2.577592)
			(stroke
				(width 0.1)
				(type default)
			)
			(layer "F.SilkS")
		)
		(fp_line
			(start 7.737348 -1.07315)
			(end 9.233408 -2.508504)
			(stroke
				(width 0.1)
				(type default)
			)
			(layer "F.SilkS")
		)
		(fp_line
			(start 7.737348 -1.07315)
			(end 9.233408 -2.508504)
			(stroke
				(width 0.1)
				(type default)
			)
			(layer "F.SilkS")
		)
		(fp_line
			(start 7.82066 -0.882904)
			(end 7.839456 -0.882904)
			(stroke
				(width 0.1)
				(type default)
			)
			(layer "F.SilkS")
		)
		(fp_line
			(start 7.82066 -0.882904)
			(end 7.839456 -0.882904)
			(stroke
				(width 0.1)
				(type default)
			)
			(layer "F.SilkS")
		)
		(fp_line
			(start 7.828788 -0.930148)
			(end 7.82066 -0.882904)
			(stroke
				(width 0.1)
				(type default)
			)
			(layer "F.SilkS")
		)
		(fp_line
			(start 7.828788 -0.930148)
			(end 7.82066 -0.882904)
			(stroke
				(width 0.1)
				(type default)
			)
			(layer "F.SilkS")
		)
		(fp_line
			(start 7.828788 -0.930148)
			(end 9.18464 -2.230882)
			(stroke
				(width 0.1)
				(type default)
			)
			(layer "F.SilkS")
		)
		(fp_line
			(start 7.828788 -0.930148)
			(end 9.18464 -2.230882)
			(stroke
				(width 0.1)
				(type default)
			)
			(layer "F.SilkS")
		)
		(fp_line
			(start 7.839456 -0.882904)
			(end 7.899908 -0.882904)
			(stroke
				(width 0.1)
				(type default)
			)
			(layer "F.SilkS")
		)
		(fp_line
			(start 7.839456 -0.882904)
			(end 7.899908 -0.882904)
			(stroke
				(width 0.1)
				(type default)
			)
			(layer "F.SilkS")
		)
		(fp_line
			(start 7.839456 -0.882904)
			(end 9.172194 -2.161286)
			(stroke
				(width 0.1)
				(type default)
			)
			(layer "F.SilkS")
		)
		(fp_line
			(start 7.839456 -0.882904)
			(end 9.172194 -2.161286)
			(stroke
				(width 0.1)
				(type default)
			)
			(layer "F.SilkS")
		)
		(fp_line
			(start 7.84098 -0.999744)
			(end 7.828788 -0.930148)
			(stroke
				(width 0.1)
				(type default)
			)
			(layer "F.SilkS")
		)
		(fp_line
			(start 7.84098 -0.999744)
			(end 7.828788 -0.930148)
			(stroke
				(width 0.1)
				(type default)
			)
			(layer "F.SilkS")
		)
		(fp_line
			(start 7.84098 -0.999744)
			(end 9.196832 -2.300224)
			(stroke
				(width 0.1)
				(type default)
			)
			(layer "F.SilkS")
		)
		(fp_line
			(start 7.84098 -0.999744)
			(end 9.196832 -2.300224)
			(stroke
				(width 0.1)
				(type default)
			)
			(layer "F.SilkS")
		)
		(fp_line
			(start 7.852918 -1.068832)
			(end 7.84098 -0.999744)
			(stroke
				(width 0.1)
				(type default)
			)
			(layer "F.SilkS")
		)
		(fp_line
			(start 7.852918 -1.068832)
			(end 7.84098 -0.999744)
			(stroke
				(width 0.1)
				(type default)
			)
			(layer "F.SilkS")
		)
		(fp_line
			(start 7.852918 -1.068832)
			(end 9.209024 -2.369566)
			(stroke
				(width 0.1)
				(type default)
			)
			(layer "F.SilkS")
		)
		(fp_line
			(start 7.852918 -1.068832)
			(end 9.209024 -2.369566)
			(stroke
				(width 0.1)
				(type default)
			)
			(layer "F.SilkS")
		)
		(fp_line
			(start 7.865364 -1.138428)
			(end 7.852918 -1.068832)
			(stroke
				(width 0.1)
				(type default)
			)
			(layer "F.SilkS")
		)
		(fp_line
			(start 7.865364 -1.138428)
			(end 7.852918 -1.068832)
			(stroke
				(width 0.1)
				(type default)
			)
			(layer "F.SilkS")
		)
		(fp_line
			(start 7.865364 -1.138428)
			(end 9.220962 -2.438908)
			(stroke
				(width 0.1)
				(type default)
			)
			(layer "F.SilkS")
		)
		(fp_line
			(start 7.865364 -1.138428)
			(end 9.220962 -2.438908)
			(stroke
				(width 0.1)
				(type default)
			)
			(layer "F.SilkS")
		)
		(fp_line
			(start 7.899908 -0.882904)
			(end 7.960106 -0.882904)
			(stroke
				(width 0.1)
				(type default)
			)
			(layer "F.SilkS")
		)
		(fp_line
			(start 7.899908 -0.882904)
			(end 7.960106 -0.882904)
			(stroke
				(width 0.1)
				(type default)
			)
			(layer "F.SilkS")
		)
		(fp_line
			(start 7.899908 -0.882904)
			(end 9.160002 -2.091944)
			(stroke
				(width 0.1)
				(type default)
			)
			(layer "F.SilkS")
		)
		(fp_line
			(start 7.899908 -0.882904)
			(end 9.160002 -2.091944)
			(stroke
				(width 0.1)
				(type default)
			)
			(layer "F.SilkS")
		)
		(fp_line
			(start 7.936484 -2.187702)
			(end 9.42848 -3.618992)
			(stroke
				(width 0.1)
				(type default)
			)
			(layer "F.SilkS")
		)
		(fp_line
			(start 7.936484 -2.187702)
			(end 9.42848 -3.618992)
			(stroke
				(width 0.1)
				(type default)
			)
			(layer "F.SilkS")
		)
		(fp_line
			(start 7.960106 -0.882904)
			(end 8.02005 -0.882904)
			(stroke
				(width 0.1)
				(type default)
			)
			(layer "F.SilkS")
		)
		(fp_line
			(start 7.960106 -0.882904)
			(end 8.02005 -0.882904)
			(stroke
				(width 0.1)
				(type default)
			)
			(layer "F.SilkS")
		)
		(fp_line
			(start 7.960106 -0.882904)
			(end 9.148064 -2.022602)
			(stroke
				(width 0.1)
				(type default)
			)
			(layer "F.SilkS")
		)
		(fp_line
			(start 7.960106 -0.882904)
			(end 9.148064 -2.022602)
			(stroke
				(width 0.1)
				(type default)
			)
			(layer "F.SilkS")
		)
		(fp_line
			(start 8.002778 -2.30886)
			(end 9.440672 -3.688334)
			(stroke
				(width 0.1)
				(type default)
			)
			(layer "F.SilkS")
		)
		(fp_line
			(start 8.002778 -2.30886)
			(end 9.440672 -3.688334)
			(stroke
				(width 0.1)
				(type default)
			)
			(layer "F.SilkS")
		)
		(fp_line
			(start 8.02005 -0.882904)
			(end 8.080248 -0.882904)
			(stroke
				(width 0.1)
				(type default)
			)
			(layer "F.SilkS")
		)
		(fp_line
			(start 8.02005 -0.882904)
			(end 8.080248 -0.882904)
			(stroke
				(width 0.1)
				(type default)
			)
			(layer "F.SilkS")
		)
		(fp_line
			(start 8.02005 -0.882904)
			(end 9.135872 -1.953006)
			(stroke
				(width 0.1)
				(type default)
			)
			(layer "F.SilkS")
		)
		(fp_line
			(start 8.02005 -0.882904)
			(end 9.135872 -1.953006)
			(stroke
				(width 0.1)
				(type default)
			)
			(layer "F.SilkS")
		)
		(fp_line
			(start 8.04799 -2.410206)
			(end 9.452864 -3.75793)
			(stroke
				(width 0.1)
				(type default)
			)
			(layer "F.SilkS")
		)
		(fp_line
			(start 8.04799 -2.410206)
			(end 9.452864 -3.75793)
			(stroke
				(width 0.1)
				(type default)
			)
			(layer "F.SilkS")
		)
		(fp_line
			(start 8.078724 -2.497328)
			(end 9.465056 -3.827526)
			(stroke
				(width 0.1)
				(type default)
			)
			(layer "F.SilkS")
		)
		(fp_line
			(start 8.078724 -2.497328)
			(end 9.465056 -3.827526)
			(stroke
				(width 0.1)
				(type default)
			)
			(layer "F.SilkS")
		)
		(fp_line
			(start 8.080248 -0.882904)
			(end 8.140446 -0.882904)
			(stroke
				(width 0.1)
				(type default)
			)
			(layer "F.SilkS")
		)
		(fp_line
			(start 8.080248 -0.882904)
			(end 8.140446 -0.882904)
			(stroke
				(width 0.1)
				(type default)
			)
			(layer "F.SilkS")
		)
		(fp_line
			(start 8.080248 -0.882904)
			(end 9.12368 -1.883664)
			(stroke
				(width 0.1)
				(type default)
			)
			(layer "F.SilkS")
		)
		(fp_line
			(start 8.080248 -0.882904)
			(end 9.12368 -1.883664)
			(stroke
				(width 0.1)
				(type default)
			)
			(layer "F.SilkS")
		)
		(fp_line
			(start 8.140446 -0.882904)
			(end 8.200644 -0.882904)
			(stroke
				(width 0.1)
				(type default)
			)
			(layer "F.SilkS")
		)
		(fp_line
			(start 8.140446 -0.882904)
			(end 8.200644 -0.882904)
			(stroke
				(width 0.1)
				(type default)
			)
			(layer "F.SilkS")
		)
		(fp_line
			(start 8.140446 -0.882904)
			(end 9.111234 -1.814322)
			(stroke
				(width 0.1)
				(type default)
			)
			(layer "F.SilkS")
		)
		(fp_line
			(start 8.140446 -0.882904)
			(end 9.111234 -1.814322)
			(stroke
				(width 0.1)
				(type default)
			)
			(layer "F.SilkS")
		)
		(fp_line
			(start 8.18261 -2.943352)
			(end 8.170418 -2.87401)
			(stroke
				(width 0.1)
				(type default)
			)
			(layer "F.SilkS")
		)
		(fp_line
			(start 8.18261 -2.943352)
			(end 8.170418 -2.87401)
			(stroke
				(width 0.1)
				(type default)
			)
			(layer "F.SilkS")
		)
		(fp_line
			(start 8.194802 -3.012694)
			(end 8.18261 -2.943352)
			(stroke
				(width 0.1)
				(type default)
			)
			(layer "F.SilkS")
		)
		(fp_line
			(start 8.194802 -3.012694)
			(end 8.18261 -2.943352)
			(stroke
				(width 0.1)
				(type default)
			)
			(layer "F.SilkS")
		)
		(fp_line
			(start 8.200644 -0.882904)
			(end 8.260842 -0.882904)
			(stroke
				(width 0.1)
				(type default)
			)
			(layer "F.SilkS")
		)
		(fp_line
			(start 8.200644 -0.882904)
			(end 8.260842 -0.882904)
			(stroke
				(width 0.1)
				(type default)
			)
			(layer "F.SilkS")
		)
		(fp_line
			(start 8.200644 -0.882904)
			(end 9.099042 -1.744726)
			(stroke
				(width 0.1)
				(type default)
			)
			(layer "F.SilkS")
		)
		(fp_line
			(start 8.200644 -0.882904)
			(end 9.099042 -1.744726)
			(stroke
				(width 0.1)
				(type default)
			)
			(layer "F.SilkS")
		)
		(fp_line
			(start 8.206994 -3.08229)
			(end 8.194802 -3.012694)
			(stroke
				(width 0.1)
				(type default)
			)
			(layer "F.SilkS")
		)
		(fp_line
			(start 8.206994 -3.08229)
			(end 8.194802 -3.012694)
			(stroke
				(width 0.1)
				(type default)
			)
			(layer "F.SilkS")
		)
		(fp_line
			(start 8.219186 -3.151378)
			(end 8.206994 -3.08229)
			(stroke
				(width 0.1)
				(type default)
			)
			(layer "F.SilkS")
		)
		(fp_line
			(start 8.219186 -3.151378)
			(end 8.206994 -3.08229)
			(stroke
				(width 0.1)
				(type default)
			)
			(layer "F.SilkS")
		)
		(fp_line
			(start 8.231378 -3.22072)
			(end 8.219186 -3.151378)
			(stroke
				(width 0.1)
				(type default)
			)
			(layer "F.SilkS")
		)
		(fp_line
			(start 8.231378 -3.22072)
			(end 8.219186 -3.151378)
			(stroke
				(width 0.1)
				(type default)
			)
			(layer "F.SilkS")
		)
		(fp_line
			(start 8.24357 -3.290316)
			(end 8.231378 -3.22072)
			(stroke
				(width 0.1)
				(type default)
			)
			(layer "F.SilkS")
		)
		(fp_line
			(start 8.24357 -3.290316)
			(end 8.231378 -3.22072)
			(stroke
				(width 0.1)
				(type default)
			)
			(layer "F.SilkS")
		)
		(fp_line
			(start 8.255762 -3.359658)
			(end 8.24357 -3.290316)
			(stroke
				(width 0.1)
				(type default)
			)
			(layer "F.SilkS")
		)
		(fp_line
			(start 8.255762 -3.359658)
			(end 8.24357 -3.290316)
			(stroke
				(width 0.1)
				(type default)
			)
			(layer "F.SilkS")
		)
		(fp_line
			(start 8.260842 -0.882904)
			(end 8.320786 -0.882904)
			(stroke
				(width 0.1)
				(type default)
			)
			(layer "F.SilkS")
		)
		(fp_line
			(start 8.260842 -0.882904)
			(end 8.320786 -0.882904)
			(stroke
				(width 0.1)
				(type default)
			)
			(layer "F.SilkS")
		)
		(fp_line
			(start 8.260842 -0.882904)
			(end 9.087104 -1.675384)
			(stroke
				(width 0.1)
				(type default)
			)
			(layer "F.SilkS")
		)
		(fp_line
			(start 8.260842 -0.882904)
			(end 9.087104 -1.675384)
			(stroke
				(width 0.1)
				(type default)
			)
			(layer "F.SilkS")
		)
		(fp_line
			(start 8.2677 -3.429)
			(end 8.255762 -3.359658)
			(stroke
				(width 0.1)
				(type default)
			)
			(layer "F.SilkS")
		)
		(fp_line
			(start 8.2677 -3.429)
			(end 8.255762 -3.359658)
			(stroke
				(width 0.1)
				(type default)
			)
			(layer "F.SilkS")
		)
		(fp_line
			(start 8.279892 -3.498342)
			(end 8.2677 -3.429)
			(stroke
				(width 0.1)
				(type default)
			)
			(layer "F.SilkS")
		)
		(fp_line
			(start 8.279892 -3.498342)
			(end 8.2677 -3.429)
			(stroke
				(width 0.1)
				(type default)
			)
			(layer "F.SilkS")
		)
		(fp_line
			(start 8.292084 -3.567684)
			(end 8.279892 -3.498342)
			(stroke
				(width 0.1)
				(type default)
			)
			(layer "F.SilkS")
		)
		(fp_line
			(start 8.292084 -3.567684)
			(end 8.279892 -3.498342)
			(stroke
				(width 0.1)
				(type default)
			)
			(layer "F.SilkS")
		)
		(fp_line
			(start 8.304276 -3.63728)
			(end 8.292084 -3.567684)
			(stroke
				(width 0.1)
				(type default)
			)
			(layer "F.SilkS")
		)
		(fp_line
			(start 8.304276 -3.63728)
			(end 8.292084 -3.567684)
			(stroke
				(width 0.1)
				(type default)
			)
			(layer "F.SilkS")
		)
		(fp_line
			(start 8.316468 -3.706368)
			(end 8.304276 -3.63728)
			(stroke
				(width 0.1)
				(type default)
			)
			(layer "F.SilkS")
		)
		(fp_line
			(start 8.316468 -3.706368)
			(end 8.304276 -3.63728)
			(stroke
				(width 0.1)
				(type default)
			)
			(layer "F.SilkS")
		)
		(fp_line
			(start 8.320786 -0.882904)
			(end 8.381238 -0.882904)
			(stroke
				(width 0.1)
				(type default)
			)
			(layer "F.SilkS")
		)
		(fp_line
			(start 8.320786 -0.882904)
			(end 8.381238 -0.882904)
			(stroke
				(width 0.1)
				(type default)
			)
			(layer "F.SilkS")
		)
		(fp_line
			(start 8.320786 -0.882904)
			(end 9.074912 -1.606296)
			(stroke
				(width 0.1)
				(type default)
			)
			(layer "F.SilkS")
		)
		(fp_line
			(start 8.320786 -0.882904)
			(end 9.074912 -1.606296)
			(stroke
				(width 0.1)
				(type default)
			)
			(layer "F.SilkS")
		)
		(fp_line
			(start 8.32866 -3.77571)
			(end 8.316468 -3.706368)
			(stroke
				(width 0.1)
				(type default)
			)
			(layer "F.SilkS")
		)
		(fp_line
			(start 8.32866 -3.77571)
			(end 8.316468 -3.706368)
			(stroke
				(width 0.1)
				(type default)
			)
			(layer "F.SilkS")
		)
		(fp_line
			(start 8.340852 -3.845306)
			(end 8.32866 -3.77571)
			(stroke
				(width 0.1)
				(type default)
			)
			(layer "F.SilkS")
		)
		(fp_line
			(start 8.340852 -3.845306)
			(end 8.32866 -3.77571)
			(stroke
				(width 0.1)
				(type default)
			)
			(layer "F.SilkS")
		)
		(fp_line
			(start 8.35279 -3.914648)
			(end 8.340852 -3.845306)
			(stroke
				(width 0.1)
				(type default)
			)
			(layer "F.SilkS")
		)
		(fp_line
			(start 8.35279 -3.914648)
			(end 8.340852 -3.845306)
			(stroke
				(width 0.1)
				(type default)
			)
			(layer "F.SilkS")
		)
		(fp_line
			(start 8.365236 -3.98399)
			(end 8.35279 -3.914648)
			(stroke
				(width 0.1)
				(type default)
			)
			(layer "F.SilkS")
		)
		(fp_line
			(start 8.365236 -3.98399)
			(end 8.35279 -3.914648)
			(stroke
				(width 0.1)
				(type default)
			)
			(layer "F.SilkS")
		)
		(fp_line
			(start 8.377174 -4.053332)
			(end 8.365236 -3.98399)
			(stroke
				(width 0.1)
				(type default)
			)
			(layer "F.SilkS")
		)
		(fp_line
			(start 8.377174 -4.053332)
			(end 8.365236 -3.98399)
			(stroke
				(width 0.1)
				(type default)
			)
			(layer "F.SilkS")
		)
		(fp_line
			(start 8.381238 -0.882904)
			(end 8.441182 -0.882904)
			(stroke
				(width 0.1)
				(type default)
			)
			(layer "F.SilkS")
		)
		(fp_line
			(start 8.381238 -0.882904)
			(end 8.441182 -0.882904)
			(stroke
				(width 0.1)
				(type default)
			)
			(layer "F.SilkS")
		)
		(fp_line
			(start 8.381238 -0.882904)
			(end 9.062466 -1.5367)
			(stroke
				(width 0.1)
				(type default)
			)
			(layer "F.SilkS")
		)
		(fp_line
			(start 8.381238 -0.882904)
			(end 9.062466 -1.5367)
			(stroke
				(width 0.1)
				(type default)
			)
			(layer "F.SilkS")
		)
		(fp_line
			(start 8.389366 -4.122674)
			(end 8.377174 -4.053332)
			(stroke
				(width 0.1)
				(type default)
			)
			(layer "F.SilkS")
		)
		(fp_line
			(start 8.389366 -4.122674)
			(end 8.377174 -4.053332)
			(stroke
				(width 0.1)
				(type default)
			)
			(layer "F.SilkS")
		)
		(fp_line
			(start 8.401558 -4.19227)
			(end 8.389366 -4.122674)
			(stroke
				(width 0.1)
				(type default)
			)
			(layer "F.SilkS")
		)
		(fp_line
			(start 8.401558 -4.19227)
			(end 8.389366 -4.122674)
			(stroke
				(width 0.1)
				(type default)
			)
			(layer "F.SilkS")
		)
		(fp_line
			(start 8.41375 -4.261612)
			(end 8.401558 -4.19227)
			(stroke
				(width 0.1)
				(type default)
			)
			(layer "F.SilkS")
		)
		(fp_line
			(start 8.41375 -4.261612)
			(end 8.401558 -4.19227)
			(stroke
				(width 0.1)
				(type default)
			)
			(layer "F.SilkS")
		)
		(fp_line
			(start 8.425942 -4.3307)
			(end 8.41375 -4.261612)
			(stroke
				(width 0.1)
				(type default)
			)
			(layer "F.SilkS")
		)
		(fp_line
			(start 8.425942 -4.3307)
			(end 8.41375 -4.261612)
			(stroke
				(width 0.1)
				(type default)
			)
			(layer "F.SilkS")
		)
		(fp_line
			(start 8.43788 -4.400296)
			(end 8.425942 -4.3307)
			(stroke
				(width 0.1)
				(type default)
			)
			(layer "F.SilkS")
		)
		(fp_line
			(start 8.43788 -4.400296)
			(end 8.425942 -4.3307)
			(stroke
				(width 0.1)
				(type default)
			)
			(layer "F.SilkS")
		)
		(fp_line
			(start 8.441182 -0.882904)
			(end 8.50138 -0.882904)
			(stroke
				(width 0.1)
				(type default)
			)
			(layer "F.SilkS")
		)
		(fp_line
			(start 8.441182 -0.882904)
			(end 8.50138 -0.882904)
			(stroke
				(width 0.1)
				(type default)
			)
			(layer "F.SilkS")
		)
		(fp_line
			(start 8.441182 -0.882904)
			(end 9.050274 -1.467104)
			(stroke
				(width 0.1)
				(type default)
			)
			(layer "F.SilkS")
		)
		(fp_line
			(start 8.441182 -0.882904)
			(end 9.050274 -1.467104)
			(stroke
				(width 0.1)
				(type default)
			)
			(layer "F.SilkS")
		)
		(fp_line
			(start 8.450326 -4.469638)
			(end 8.43788 -4.400296)
			(stroke
				(width 0.1)
				(type default)
			)
			(layer "F.SilkS")
		)
		(fp_line
			(start 8.450326 -4.469638)
			(end 8.43788 -4.400296)
			(stroke
				(width 0.1)
				(type default)
			)
			(layer "F.SilkS")
		)
		(fp_line
			(start 8.450326 -4.469638)
			(end 8.462264 -4.53898)
			(stroke
				(width 0.1)
				(type default)
			)
			(layer "F.SilkS")
		)
		(fp_line
			(start 8.450326 -4.469638)
			(end 8.462264 -4.53898)
			(stroke
				(width 0.1)
				(type default)
			)
			(layer "F.SilkS")
		)
		(fp_line
			(start 8.462264 -4.53898)
			(end 8.474456 -4.608322)
			(stroke
				(width 0.1)
				(type default)
			)
			(layer "F.SilkS")
		)
		(fp_line
			(start 8.462264 -4.53898)
			(end 8.474456 -4.608322)
			(stroke
				(width 0.1)
				(type default)
			)
			(layer "F.SilkS")
		)
		(fp_line
			(start 8.474456 -4.608322)
			(end 8.486648 -4.677664)
			(stroke
				(width 0.1)
				(type default)
			)
			(layer "F.SilkS")
		)
		(fp_line
			(start 8.474456 -4.608322)
			(end 8.486648 -4.677664)
			(stroke
				(width 0.1)
				(type default)
			)
			(layer "F.SilkS")
		)
		(fp_line
			(start 8.486648 -4.677664)
			(end 8.49884 -4.74726)
			(stroke
				(width 0.1)
				(type default)
			)
			(layer "F.SilkS")
		)
		(fp_line
			(start 8.486648 -4.677664)
			(end 8.49884 -4.74726)
			(stroke
				(width 0.1)
				(type default)
			)
			(layer "F.SilkS")
		)
		(fp_line
			(start 8.49884 -4.74726)
			(end 8.511032 -4.816602)
			(stroke
				(width 0.1)
				(type default)
			)
			(layer "F.SilkS")
		)
		(fp_line
			(start 8.49884 -4.74726)
			(end 8.511032 -4.816602)
			(stroke
				(width 0.1)
				(type default)
			)
			(layer "F.SilkS")
		)
		(fp_line
			(start 8.50138 -0.882904)
			(end 8.561578 -0.882904)
			(stroke
				(width 0.1)
				(type default)
			)
			(layer "F.SilkS")
		)
		(fp_line
			(start 8.50138 -0.882904)
			(end 8.561578 -0.882904)
			(stroke
				(width 0.1)
				(type default)
			)
			(layer "F.SilkS")
		)
		(fp_line
			(start 8.50138 -0.882904)
			(end 9.038082 -1.397762)
			(stroke
				(width 0.1)
				(type default)
			)
			(layer "F.SilkS")
		)
		(fp_line
			(start 8.50138 -0.882904)
			(end 9.038082 -1.397762)
			(stroke
				(width 0.1)
				(type default)
			)
			(layer "F.SilkS")
		)
		(fp_line
			(start 8.511032 -4.816602)
			(end 8.52297 -4.88569)
			(stroke
				(width 0.1)
				(type default)
			)
			(layer "F.SilkS")
		)
		(fp_line
			(start 8.511032 -4.816602)
			(end 8.52297 -4.88569)
			(stroke
				(width 0.1)
				(type default)
			)
			(layer "F.SilkS")
		)
		(fp_line
			(start 8.52297 -4.88569)
			(end 8.535416 -4.955286)
			(stroke
				(width 0.1)
				(type default)
			)
			(layer "F.SilkS")
		)
		(fp_line
			(start 8.52297 -4.88569)
			(end 8.535416 -4.955286)
			(stroke
				(width 0.1)
				(type default)
			)
			(layer "F.SilkS")
		)
		(fp_line
			(start 8.535416 -4.955286)
			(end 8.547608 -5.024628)
			(stroke
				(width 0.1)
				(type default)
			)
			(layer "F.SilkS")
		)
		(fp_line
			(start 8.535416 -4.955286)
			(end 8.547608 -5.024628)
			(stroke
				(width 0.1)
				(type default)
			)
			(layer "F.SilkS")
		)
		(fp_line
			(start 8.547608 -5.024628)
			(end 8.559546 -5.09397)
			(stroke
				(width 0.1)
				(type default)
			)
			(layer "F.SilkS")
		)
		(fp_line
			(start 8.547608 -5.024628)
			(end 8.559546 -5.09397)
			(stroke
				(width 0.1)
				(type default)
			)
			(layer "F.SilkS")
		)
		(fp_line
			(start 8.559546 -5.09397)
			(end 8.571738 -5.163312)
			(stroke
				(width 0.1)
				(type default)
			)
			(layer "F.SilkS")
		)
		(fp_line
			(start 8.559546 -5.09397)
			(end 8.571738 -5.163312)
			(stroke
				(width 0.1)
				(type default)
			)
			(layer "F.SilkS")
		)
		(fp_line
			(start 8.561578 -0.882904)
			(end 8.621522 -0.882904)
			(stroke
				(width 0.1)
				(type default)
			)
			(layer "F.SilkS")
		)
		(fp_line
			(start 8.561578 -0.882904)
			(end 8.621522 -0.882904)
			(stroke
				(width 0.1)
				(type default)
			)
			(layer "F.SilkS")
		)
		(fp_line
			(start 8.561578 -0.882904)
			(end 9.026144 -1.32842)
			(stroke
				(width 0.1)
				(type default)
			)
			(layer "F.SilkS")
		)
		(fp_line
			(start 8.561578 -0.882904)
			(end 9.026144 -1.32842)
			(stroke
				(width 0.1)
				(type default)
			)
			(layer "F.SilkS")
		)
		(fp_line
			(start 8.573262 -5.171694)
			(end 8.571738 -5.163312)
			(stroke
				(width 0.1)
				(type default)
			)
			(layer "F.SilkS")
		)
		(fp_line
			(start 8.573262 -5.171694)
			(end 8.571738 -5.163312)
			(stroke
				(width 0.1)
				(type default)
			)
			(layer "F.SilkS")
		)
		(fp_line
			(start 8.580374 -5.171694)
			(end 8.571738 -5.163312)
			(stroke
				(width 0.1)
				(type default)
			)
			(layer "F.SilkS")
		)
		(fp_line
			(start 8.580374 -5.171694)
			(end 8.571738 -5.163312)
			(stroke
				(width 0.1)
				(type default)
			)
			(layer "F.SilkS")
		)
		(fp_line
			(start 8.580374 -5.171694)
			(end 8.573262 -5.171694)
			(stroke
				(width 0.1)
				(type default)
			)
			(layer "F.SilkS")
		)
		(fp_line
			(start 8.580374 -5.171694)
			(end 8.573262 -5.171694)
			(stroke
				(width 0.1)
				(type default)
			)
			(layer "F.SilkS")
		)
		(fp_line
			(start 8.621522 -0.882904)
			(end 8.681974 -0.882904)
			(stroke
				(width 0.1)
				(type default)
			)
			(layer "F.SilkS")
		)
		(fp_line
			(start 8.621522 -0.882904)
			(end 8.681974 -0.882904)
			(stroke
				(width 0.1)
				(type default)
			)
			(layer "F.SilkS")
		)
		(fp_line
			(start 8.621522 -0.882904)
			(end 9.013952 -1.259078)
			(stroke
				(width 0.1)
				(type default)
			)
			(layer "F.SilkS")
		)
		(fp_line
			(start 8.621522 -0.882904)
			(end 9.013952 -1.259078)
			(stroke
				(width 0.1)
				(type default)
			)
			(layer "F.SilkS")
		)
		(fp_line
			(start 8.640572 -5.171694)
			(end 8.559546 -5.09397)
			(stroke
				(width 0.1)
				(type default)
			)
			(layer "F.SilkS")
		)
		(fp_line
			(start 8.640572 -5.171694)
			(end 8.559546 -5.09397)
			(stroke
				(width 0.1)
				(type default)
			)
			(layer "F.SilkS")
		)
		(fp_line
			(start 8.640572 -5.171694)
			(end 8.580374 -5.171694)
			(stroke
				(width 0.1)
				(type default)
			)
			(layer "F.SilkS")
		)
		(fp_line
			(start 8.640572 -5.171694)
			(end 8.580374 -5.171694)
			(stroke
				(width 0.1)
				(type default)
			)
			(layer "F.SilkS")
		)
		(fp_line
			(start 8.681974 -0.882904)
			(end 8.741918 -0.882904)
			(stroke
				(width 0.1)
				(type default)
			)
			(layer "F.SilkS")
		)
		(fp_line
			(start 8.681974 -0.882904)
			(end 8.741918 -0.882904)
			(stroke
				(width 0.1)
				(type default)
			)
			(layer "F.SilkS")
		)
		(fp_line
			(start 8.681974 -0.882904)
			(end 9.001506 -1.189482)
			(stroke
				(width 0.1)
				(type default)
			)
			(layer "F.SilkS")
		)
		(fp_line
			(start 8.681974 -0.882904)
			(end 9.001506 -1.189482)
			(stroke
				(width 0.1)
				(type default)
			)
			(layer "F.SilkS")
		)
		(fp_line
			(start 8.70077 -5.171694)
			(end 8.547608 -5.024628)
			(stroke
				(width 0.1)
				(type default)
			)
			(layer "F.SilkS")
		)
		(fp_line
			(start 8.70077 -5.171694)
			(end 8.547608 -5.024628)
			(stroke
				(width 0.1)
				(type default)
			)
			(layer "F.SilkS")
		)
		(fp_line
			(start 8.70077 -5.171694)
			(end 8.640572 -5.171694)
			(stroke
				(width 0.1)
				(type default)
			)
			(layer "F.SilkS")
		)
		(fp_line
			(start 8.70077 -5.171694)
			(end 8.640572 -5.171694)
			(stroke
				(width 0.1)
				(type default)
			)
			(layer "F.SilkS")
		)
		(fp_line
			(start 8.741918 -0.882904)
			(end 8.802116 -0.882904)
			(stroke
				(width 0.1)
				(type default)
			)
			(layer "F.SilkS")
		)
		(fp_line
			(start 8.741918 -0.882904)
			(end 8.802116 -0.882904)
			(stroke
				(width 0.1)
				(type default)
			)
			(layer "F.SilkS")
		)
		(fp_line
			(start 8.741918 -0.882904)
			(end 8.989314 -1.12014)
			(stroke
				(width 0.1)
				(type default)
			)
			(layer "F.SilkS")
		)
		(fp_line
			(start 8.741918 -0.882904)
			(end 8.989314 -1.12014)
			(stroke
				(width 0.1)
				(type default)
			)
			(layer "F.SilkS")
		)
		(fp_line
			(start 8.760968 -5.171694)
			(end 8.535416 -4.955286)
			(stroke
				(width 0.1)
				(type default)
			)
			(layer "F.SilkS")
		)
		(fp_line
			(start 8.760968 -5.171694)
			(end 8.535416 -4.955286)
			(stroke
				(width 0.1)
				(type default)
			)
			(layer "F.SilkS")
		)
		(fp_line
			(start 8.760968 -5.171694)
			(end 8.70077 -5.171694)
			(stroke
				(width 0.1)
				(type default)
			)
			(layer "F.SilkS")
		)
		(fp_line
			(start 8.760968 -5.171694)
			(end 8.70077 -5.171694)
			(stroke
				(width 0.1)
				(type default)
			)
			(layer "F.SilkS")
		)
		(fp_line
			(start 8.802116 -0.882904)
			(end 8.862314 -0.882904)
			(stroke
				(width 0.1)
				(type default)
			)
			(layer "F.SilkS")
		)
		(fp_line
			(start 8.802116 -0.882904)
			(end 8.862314 -0.882904)
			(stroke
				(width 0.1)
				(type default)
			)
			(layer "F.SilkS")
		)
		(fp_line
			(start 8.802116 -0.882904)
			(end 8.977122 -1.050798)
			(stroke
				(width 0.1)
				(type default)
			)
			(layer "F.SilkS")
		)
		(fp_line
			(start 8.802116 -0.882904)
			(end 8.977122 -1.050798)
			(stroke
				(width 0.1)
				(type default)
			)
			(layer "F.SilkS")
		)
		(fp_line
			(start 8.821166 -5.171694)
			(end 8.52297 -4.88569)
			(stroke
				(width 0.1)
				(type default)
			)
			(layer "F.SilkS")
		)
		(fp_line
			(start 8.821166 -5.171694)
			(end 8.52297 -4.88569)
			(stroke
				(width 0.1)
				(type default)
			)
			(layer "F.SilkS")
		)
		(fp_line
			(start 8.821166 -5.171694)
			(end 8.760968 -5.171694)
			(stroke
				(width 0.1)
				(type default)
			)
			(layer "F.SilkS")
		)
		(fp_line
			(start 8.821166 -5.171694)
			(end 8.760968 -5.171694)
			(stroke
				(width 0.1)
				(type default)
			)
			(layer "F.SilkS")
		)
		(fp_line
			(start 8.862314 -0.882904)
			(end 8.922512 -0.882904)
			(stroke
				(width 0.1)
				(type default)
			)
			(layer "F.SilkS")
		)
		(fp_line
			(start 8.862314 -0.882904)
			(end 8.922512 -0.882904)
			(stroke
				(width 0.1)
				(type default)
			)
			(layer "F.SilkS")
		)
		(fp_line
			(start 8.862314 -0.882904)
			(end 8.965184 -0.981456)
			(stroke
				(width 0.1)
				(type default)
			)
			(layer "F.SilkS")
		)
		(fp_line
			(start 8.862314 -0.882904)
			(end 8.965184 -0.981456)
			(stroke
				(width 0.1)
				(type default)
			)
			(layer "F.SilkS")
		)
		(fp_line
			(start 8.88111 -5.171694)
			(end 8.511032 -4.816602)
			(stroke
				(width 0.1)
				(type default)
			)
			(layer "F.SilkS")
		)
		(fp_line
			(start 8.88111 -5.171694)
			(end 8.511032 -4.816602)
			(stroke
				(width 0.1)
				(type default)
			)
			(layer "F.SilkS")
		)
		(fp_line
			(start 8.88111 -5.171694)
			(end 8.821166 -5.171694)
			(stroke
				(width 0.1)
				(type default)
			)
			(layer "F.SilkS")
		)
		(fp_line
			(start 8.88111 -5.171694)
			(end 8.821166 -5.171694)
			(stroke
				(width 0.1)
				(type default)
			)
			(layer "F.SilkS")
		)
		(fp_line
			(start 8.922512 -0.882904)
			(end 8.947658 -0.882904)
			(stroke
				(width 0.1)
				(type default)
			)
			(layer "F.SilkS")
		)
		(fp_line
			(start 8.922512 -0.882904)
			(end 8.947658 -0.882904)
			(stroke
				(width 0.1)
				(type default)
			)
			(layer "F.SilkS")
		)
		(fp_line
			(start 8.922512 -0.882904)
			(end 8.952738 -0.91186)
			(stroke
				(width 0.1)
				(type default)
			)
			(layer "F.SilkS")
		)
		(fp_line
			(start 8.922512 -0.882904)
			(end 8.952738 -0.91186)
			(stroke
				(width 0.1)
				(type default)
			)
			(layer "F.SilkS")
		)
		(fp_line
			(start 8.941308 -5.171694)
			(end 8.49884 -4.74726)
			(stroke
				(width 0.1)
				(type default)
			)
			(layer "F.SilkS")
		)
		(fp_line
			(start 8.941308 -5.171694)
			(end 8.49884 -4.74726)
			(stroke
				(width 0.1)
				(type default)
			)
			(layer "F.SilkS")
		)
		(fp_line
			(start 8.941308 -5.171694)
			(end 8.88111 -5.171694)
			(stroke
				(width 0.1)
				(type default)
			)
			(layer "F.SilkS")
		)
		(fp_line
			(start 8.941308 -5.171694)
			(end 8.88111 -5.171694)
			(stroke
				(width 0.1)
				(type default)
			)
			(layer "F.SilkS")
		)
		(fp_line
			(start 8.947658 -0.882904)
			(end 8.952738 -0.91186)
			(stroke
				(width 0.1)
				(type default)
			)
			(layer "F.SilkS")
		)
		(fp_line
			(start 8.947658 -0.882904)
			(end 8.952738 -0.91186)
			(stroke
				(width 0.1)
				(type default)
			)
			(layer "F.SilkS")
		)
		(fp_line
			(start 8.965184 -0.981456)
			(end 8.952738 -0.91186)
			(stroke
				(width 0.1)
				(type default)
			)
			(layer "F.SilkS")
		)
		(fp_line
			(start 8.965184 -0.981456)
			(end 8.952738 -0.91186)
			(stroke
				(width 0.1)
				(type default)
			)
			(layer "F.SilkS")
		)
		(fp_line
			(start 8.977122 -1.050798)
			(end 8.965184 -0.981456)
			(stroke
				(width 0.1)
				(type default)
			)
			(layer "F.SilkS")
		)
		(fp_line
			(start 8.977122 -1.050798)
			(end 8.965184 -0.981456)
			(stroke
				(width 0.1)
				(type default)
			)
			(layer "F.SilkS")
		)
		(fp_line
			(start 8.989314 -1.12014)
			(end 8.977122 -1.050798)
			(stroke
				(width 0.1)
				(type default)
			)
			(layer "F.SilkS")
		)
		(fp_line
			(start 8.989314 -1.12014)
			(end 8.977122 -1.050798)
			(stroke
				(width 0.1)
				(type default)
			)
			(layer "F.SilkS")
		)
		(fp_line
			(start 9.001506 -5.171694)
			(end 8.486648 -4.677664)
			(stroke
				(width 0.1)
				(type default)
			)
			(layer "F.SilkS")
		)
		(fp_line
			(start 9.001506 -5.171694)
			(end 8.486648 -4.677664)
			(stroke
				(width 0.1)
				(type default)
			)
			(layer "F.SilkS")
		)
		(fp_line
			(start 9.001506 -5.171694)
			(end 8.941308 -5.171694)
			(stroke
				(width 0.1)
				(type default)
			)
			(layer "F.SilkS")
		)
		(fp_line
			(start 9.001506 -5.171694)
			(end 8.941308 -5.171694)
			(stroke
				(width 0.1)
				(type default)
			)
			(layer "F.SilkS")
		)
		(fp_line
			(start 9.001506 -1.189482)
			(end 8.989314 -1.12014)
			(stroke
				(width 0.1)
				(type default)
			)
			(layer "F.SilkS")
		)
		(fp_line
			(start 9.001506 -1.189482)
			(end 8.989314 -1.12014)
			(stroke
				(width 0.1)
				(type default)
			)
			(layer "F.SilkS")
		)
		(fp_line
			(start 9.013952 -1.259078)
			(end 9.001506 -1.189482)
			(stroke
				(width 0.1)
				(type default)
			)
			(layer "F.SilkS")
		)
		(fp_line
			(start 9.013952 -1.259078)
			(end 9.001506 -1.189482)
			(stroke
				(width 0.1)
				(type default)
			)
			(layer "F.SilkS")
		)
		(fp_line
			(start 9.026144 -1.32842)
			(end 9.013952 -1.259078)
			(stroke
				(width 0.1)
				(type default)
			)
			(layer "F.SilkS")
		)
		(fp_line
			(start 9.026144 -1.32842)
			(end 9.013952 -1.259078)
			(stroke
				(width 0.1)
				(type default)
			)
			(layer "F.SilkS")
		)
		(fp_line
			(start 9.038082 -1.397762)
			(end 9.026144 -1.32842)
			(stroke
				(width 0.1)
				(type default)
			)
			(layer "F.SilkS")
		)
		(fp_line
			(start 9.038082 -1.397762)
			(end 9.026144 -1.32842)
			(stroke
				(width 0.1)
				(type default)
			)
			(layer "F.SilkS")
		)
		(fp_line
			(start 9.050274 -1.467104)
			(end 9.038082 -1.397762)
			(stroke
				(width 0.1)
				(type default)
			)
			(layer "F.SilkS")
		)
		(fp_line
			(start 9.050274 -1.467104)
			(end 9.038082 -1.397762)
			(stroke
				(width 0.1)
				(type default)
			)
			(layer "F.SilkS")
		)
		(fp_line
			(start 9.061704 -5.171694)
			(end 8.474456 -4.608322)
			(stroke
				(width 0.1)
				(type default)
			)
			(layer "F.SilkS")
		)
		(fp_line
			(start 9.061704 -5.171694)
			(end 8.474456 -4.608322)
			(stroke
				(width 0.1)
				(type default)
			)
			(layer "F.SilkS")
		)
		(fp_line
			(start 9.061704 -5.171694)
			(end 9.001506 -5.171694)
			(stroke
				(width 0.1)
				(type default)
			)
			(layer "F.SilkS")
		)
		(fp_line
			(start 9.061704 -5.171694)
			(end 9.001506 -5.171694)
			(stroke
				(width 0.1)
				(type default)
			)
			(layer "F.SilkS")
		)
		(fp_line
			(start 9.062466 -1.5367)
			(end 9.050274 -1.467104)
			(stroke
				(width 0.1)
				(type default)
			)
			(layer "F.SilkS")
		)
		(fp_line
			(start 9.062466 -1.5367)
			(end 9.050274 -1.467104)
			(stroke
				(width 0.1)
				(type default)
			)
			(layer "F.SilkS")
		)
		(fp_line
			(start 9.074912 -1.606296)
			(end 9.062466 -1.5367)
			(stroke
				(width 0.1)
				(type default)
			)
			(layer "F.SilkS")
		)
		(fp_line
			(start 9.074912 -1.606296)
			(end 9.062466 -1.5367)
			(stroke
				(width 0.1)
				(type default)
			)
			(layer "F.SilkS")
		)
		(fp_line
			(start 9.087104 -1.675384)
			(end 9.074912 -1.606296)
			(stroke
				(width 0.1)
				(type default)
			)
			(layer "F.SilkS")
		)
		(fp_line
			(start 9.087104 -1.675384)
			(end 9.074912 -1.606296)
			(stroke
				(width 0.1)
				(type default)
			)
			(layer "F.SilkS")
		)
		(fp_line
			(start 9.099042 -1.744726)
			(end 9.087104 -1.675384)
			(stroke
				(width 0.1)
				(type default)
			)
			(layer "F.SilkS")
		)
		(fp_line
			(start 9.099042 -1.744726)
			(end 9.087104 -1.675384)
			(stroke
				(width 0.1)
				(type default)
			)
			(layer "F.SilkS")
		)
		(fp_line
			(start 9.111234 -1.814322)
			(end 9.099042 -1.744726)
			(stroke
				(width 0.1)
				(type default)
			)
			(layer "F.SilkS")
		)
		(fp_line
			(start 9.111234 -1.814322)
			(end 9.099042 -1.744726)
			(stroke
				(width 0.1)
				(type default)
			)
			(layer "F.SilkS")
		)
		(fp_line
			(start 9.121902 -5.171694)
			(end 8.462264 -4.53898)
			(stroke
				(width 0.1)
				(type default)
			)
			(layer "F.SilkS")
		)
		(fp_line
			(start 9.121902 -5.171694)
			(end 8.462264 -4.53898)
			(stroke
				(width 0.1)
				(type default)
			)
			(layer "F.SilkS")
		)
		(fp_line
			(start 9.121902 -5.171694)
			(end 9.061704 -5.171694)
			(stroke
				(width 0.1)
				(type default)
			)
			(layer "F.SilkS")
		)
		(fp_line
			(start 9.121902 -5.171694)
			(end 9.061704 -5.171694)
			(stroke
				(width 0.1)
				(type default)
			)
			(layer "F.SilkS")
		)
		(fp_line
			(start 9.12368 -1.883664)
			(end 9.111234 -1.814322)
			(stroke
				(width 0.1)
				(type default)
			)
			(layer "F.SilkS")
		)
		(fp_line
			(start 9.12368 -1.883664)
			(end 9.111234 -1.814322)
			(stroke
				(width 0.1)
				(type default)
			)
			(layer "F.SilkS")
		)
		(fp_line
			(start 9.135872 -1.953006)
			(end 9.12368 -1.883664)
			(stroke
				(width 0.1)
				(type default)
			)
			(layer "F.SilkS")
		)
		(fp_line
			(start 9.135872 -1.953006)
			(end 9.12368 -1.883664)
			(stroke
				(width 0.1)
				(type default)
			)
			(layer "F.SilkS")
		)
		(fp_line
			(start 9.148064 -2.022602)
			(end 9.135872 -1.953006)
			(stroke
				(width 0.1)
				(type default)
			)
			(layer "F.SilkS")
		)
		(fp_line
			(start 9.148064 -2.022602)
			(end 9.135872 -1.953006)
			(stroke
				(width 0.1)
				(type default)
			)
			(layer "F.SilkS")
		)
		(fp_line
			(start 9.160002 -2.091944)
			(end 9.148064 -2.022602)
			(stroke
				(width 0.1)
				(type default)
			)
			(layer "F.SilkS")
		)
		(fp_line
			(start 9.160002 -2.091944)
			(end 9.148064 -2.022602)
			(stroke
				(width 0.1)
				(type default)
			)
			(layer "F.SilkS")
		)
		(fp_line
			(start 9.172194 -2.161286)
			(end 9.160002 -2.091944)
			(stroke
				(width 0.1)
				(type default)
			)
			(layer "F.SilkS")
		)
		(fp_line
			(start 9.172194 -2.161286)
			(end 9.160002 -2.091944)
			(stroke
				(width 0.1)
				(type default)
			)
			(layer "F.SilkS")
		)
		(fp_line
			(start 9.172194 -2.161286)
			(end 9.18464 -2.230882)
			(stroke
				(width 0.1)
				(type default)
			)
			(layer "F.SilkS")
		)
		(fp_line
			(start 9.172194 -2.161286)
			(end 9.18464 -2.230882)
			(stroke
				(width 0.1)
				(type default)
			)
			(layer "F.SilkS")
		)
		(fp_line
			(start 9.181846 -5.171694)
			(end 8.450326 -4.469638)
			(stroke
				(width 0.1)
				(type default)
			)
			(layer "F.SilkS")
		)
		(fp_line
			(start 9.181846 -5.171694)
			(end 8.450326 -4.469638)
			(stroke
				(width 0.1)
				(type default)
			)
			(layer "F.SilkS")
		)
		(fp_line
			(start 9.181846 -5.171694)
			(end 9.121902 -5.171694)
			(stroke
				(width 0.1)
				(type default)
			)
			(layer "F.SilkS")
		)
		(fp_line
			(start 9.181846 -5.171694)
			(end 9.121902 -5.171694)
			(stroke
				(width 0.1)
				(type default)
			)
			(layer "F.SilkS")
		)
		(fp_line
			(start 9.18464 -2.230882)
			(end 9.196832 -2.300224)
			(stroke
				(width 0.1)
				(type default)
			)
			(layer "F.SilkS")
		)
		(fp_line
			(start 9.18464 -2.230882)
			(end 9.196832 -2.300224)
			(stroke
				(width 0.1)
				(type default)
			)
			(layer "F.SilkS")
		)
		(fp_line
			(start 9.196832 -2.300224)
			(end 9.209024 -2.369566)
			(stroke
				(width 0.1)
				(type default)
			)
			(layer "F.SilkS")
		)
		(fp_line
			(start 9.196832 -2.300224)
			(end 9.209024 -2.369566)
			(stroke
				(width 0.1)
				(type default)
			)
			(layer "F.SilkS")
		)
		(fp_line
			(start 9.209024 -2.369566)
			(end 9.220962 -2.438908)
			(stroke
				(width 0.1)
				(type default)
			)
			(layer "F.SilkS")
		)
		(fp_line
			(start 9.209024 -2.369566)
			(end 9.220962 -2.438908)
			(stroke
				(width 0.1)
				(type default)
			)
			(layer "F.SilkS")
		)
		(fp_line
			(start 9.220962 -2.438908)
			(end 9.233408 -2.508504)
			(stroke
				(width 0.1)
				(type default)
			)
			(layer "F.SilkS")
		)
		(fp_line
			(start 9.220962 -2.438908)
			(end 9.233408 -2.508504)
			(stroke
				(width 0.1)
				(type default)
			)
			(layer "F.SilkS")
		)
		(fp_line
			(start 9.233408 -2.508504)
			(end 9.2456 -2.577592)
			(stroke
				(width 0.1)
				(type default)
			)
			(layer "F.SilkS")
		)
		(fp_line
			(start 9.233408 -2.508504)
			(end 9.2456 -2.577592)
			(stroke
				(width 0.1)
				(type default)
			)
			(layer "F.SilkS")
		)
		(fp_line
			(start 9.242298 -5.171694)
			(end 8.43788 -4.400296)
			(stroke
				(width 0.1)
				(type default)
			)
			(layer "F.SilkS")
		)
		(fp_line
			(start 9.242298 -5.171694)
			(end 8.43788 -4.400296)
			(stroke
				(width 0.1)
				(type default)
			)
			(layer "F.SilkS")
		)
		(fp_line
			(start 9.242298 -5.171694)
			(end 9.181846 -5.171694)
			(stroke
				(width 0.1)
				(type default)
			)
			(layer "F.SilkS")
		)
		(fp_line
			(start 9.242298 -5.171694)
			(end 9.181846 -5.171694)
			(stroke
				(width 0.1)
				(type default)
			)
			(layer "F.SilkS")
		)
		(fp_line
			(start 9.2456 -2.577592)
			(end 9.257792 -2.647188)
			(stroke
				(width 0.1)
				(type default)
			)
			(layer "F.SilkS")
		)
		(fp_line
			(start 9.2456 -2.577592)
			(end 9.257792 -2.647188)
			(stroke
				(width 0.1)
				(type default)
			)
			(layer "F.SilkS")
		)
		(fp_line
			(start 9.257792 -2.647188)
			(end 9.269984 -2.716784)
			(stroke
				(width 0.1)
				(type default)
			)
			(layer "F.SilkS")
		)
		(fp_line
			(start 9.257792 -2.647188)
			(end 9.269984 -2.716784)
			(stroke
				(width 0.1)
				(type default)
			)
			(layer "F.SilkS")
		)
		(fp_line
			(start 9.269984 -2.716784)
			(end 9.281922 -2.786126)
			(stroke
				(width 0.1)
				(type default)
			)
			(layer "F.SilkS")
		)
		(fp_line
			(start 9.269984 -2.716784)
			(end 9.281922 -2.786126)
			(stroke
				(width 0.1)
				(type default)
			)
			(layer "F.SilkS")
		)
		(fp_line
			(start 9.281922 -2.786126)
			(end 9.294368 -2.855468)
			(stroke
				(width 0.1)
				(type default)
			)
			(layer "F.SilkS")
		)
		(fp_line
			(start 9.281922 -2.786126)
			(end 9.294368 -2.855468)
			(stroke
				(width 0.1)
				(type default)
			)
			(layer "F.SilkS")
		)
		(fp_line
			(start 9.294368 -2.855468)
			(end 9.30656 -2.925064)
			(stroke
				(width 0.1)
				(type default)
			)
			(layer "F.SilkS")
		)
		(fp_line
			(start 9.294368 -2.855468)
			(end 9.30656 -2.925064)
			(stroke
				(width 0.1)
				(type default)
			)
			(layer "F.SilkS")
		)
		(fp_line
			(start 9.302242 -5.171694)
			(end 8.425942 -4.3307)
			(stroke
				(width 0.1)
				(type default)
			)
			(layer "F.SilkS")
		)
		(fp_line
			(start 9.302242 -5.171694)
			(end 8.425942 -4.3307)
			(stroke
				(width 0.1)
				(type default)
			)
			(layer "F.SilkS")
		)
		(fp_line
			(start 9.302242 -5.171694)
			(end 9.242298 -5.171694)
			(stroke
				(width 0.1)
				(type default)
			)
			(layer "F.SilkS")
		)
		(fp_line
			(start 9.302242 -5.171694)
			(end 9.242298 -5.171694)
			(stroke
				(width 0.1)
				(type default)
			)
			(layer "F.SilkS")
		)
		(fp_line
			(start 9.30656 -2.925064)
			(end 9.318752 -2.994406)
			(stroke
				(width 0.1)
				(type default)
			)
			(layer "F.SilkS")
		)
		(fp_line
			(start 9.30656 -2.925064)
			(end 9.318752 -2.994406)
			(stroke
				(width 0.1)
				(type default)
			)
			(layer "F.SilkS")
		)
		(fp_line
			(start 9.318752 -2.994406)
			(end 9.330944 -3.063748)
			(stroke
				(width 0.1)
				(type default)
			)
			(layer "F.SilkS")
		)
		(fp_line
			(start 9.318752 -2.994406)
			(end 9.330944 -3.063748)
			(stroke
				(width 0.1)
				(type default)
			)
			(layer "F.SilkS")
		)
		(fp_line
			(start 9.330944 -3.063748)
			(end 9.343136 -3.13309)
			(stroke
				(width 0.1)
				(type default)
			)
			(layer "F.SilkS")
		)
		(fp_line
			(start 9.330944 -3.063748)
			(end 9.343136 -3.13309)
			(stroke
				(width 0.1)
				(type default)
			)
			(layer "F.SilkS")
		)
		(fp_line
			(start 9.343136 -3.13309)
			(end 9.355328 -3.202432)
			(stroke
				(width 0.1)
				(type default)
			)
			(layer "F.SilkS")
		)
		(fp_line
			(start 9.343136 -3.13309)
			(end 9.355328 -3.202432)
			(stroke
				(width 0.1)
				(type default)
			)
			(layer "F.SilkS")
		)
		(fp_line
			(start 9.355328 -3.202432)
			(end 9.36752 -3.272028)
			(stroke
				(width 0.1)
				(type default)
			)
			(layer "F.SilkS")
		)
		(fp_line
			(start 9.355328 -3.202432)
			(end 9.36752 -3.272028)
			(stroke
				(width 0.1)
				(type default)
			)
			(layer "F.SilkS")
		)
		(fp_line
			(start 9.36244 -5.171694)
			(end 8.41375 -4.261612)
			(stroke
				(width 0.1)
				(type default)
			)
			(layer "F.SilkS")
		)
		(fp_line
			(start 9.36244 -5.171694)
			(end 8.41375 -4.261612)
			(stroke
				(width 0.1)
				(type default)
			)
			(layer "F.SilkS")
		)
		(fp_line
			(start 9.36244 -5.171694)
			(end 9.302242 -5.171694)
			(stroke
				(width 0.1)
				(type default)
			)
			(layer "F.SilkS")
		)
		(fp_line
			(start 9.36244 -5.171694)
			(end 9.302242 -5.171694)
			(stroke
				(width 0.1)
				(type default)
			)
			(layer "F.SilkS")
		)
		(fp_line
			(start 9.36752 -3.272028)
			(end 9.379712 -3.34137)
			(stroke
				(width 0.1)
				(type default)
			)
			(layer "F.SilkS")
		)
		(fp_line
			(start 9.36752 -3.272028)
			(end 9.379712 -3.34137)
			(stroke
				(width 0.1)
				(type default)
			)
			(layer "F.SilkS")
		)
		(fp_line
			(start 9.379712 -3.34137)
			(end 9.391904 -3.410712)
			(stroke
				(width 0.1)
				(type default)
			)
			(layer "F.SilkS")
		)
		(fp_line
			(start 9.379712 -3.34137)
			(end 9.391904 -3.410712)
			(stroke
				(width 0.1)
				(type default)
			)
			(layer "F.SilkS")
		)
		(fp_line
			(start 9.404096 -3.480054)
			(end 9.391904 -3.410712)
			(stroke
				(width 0.1)
				(type default)
			)
			(layer "F.SilkS")
		)
		(fp_line
			(start 9.404096 -3.480054)
			(end 9.391904 -3.410712)
			(stroke
				(width 0.1)
				(type default)
			)
			(layer "F.SilkS")
		)
		(fp_line
			(start 9.416288 -3.54965)
			(end 6.565392 -0.815086)
			(stroke
				(width 0.1)
				(type default)
			)
			(layer "F.SilkS")
		)
		(fp_line
			(start 9.416288 -3.54965)
			(end 6.565392 -0.815086)
			(stroke
				(width 0.1)
				(type default)
			)
			(layer "F.SilkS")
		)
		(fp_line
			(start 9.416288 -3.54965)
			(end 9.404096 -3.480054)
			(stroke
				(width 0.1)
				(type default)
			)
			(layer "F.SilkS")
		)
		(fp_line
			(start 9.416288 -3.54965)
			(end 9.404096 -3.480054)
			(stroke
				(width 0.1)
				(type default)
			)
			(layer "F.SilkS")
		)
		(fp_line
			(start 9.416288 -3.54965)
			(end 9.42848 -3.618992)
			(stroke
				(width 0.1)
				(type default)
			)
			(layer "F.SilkS")
		)
		(fp_line
			(start 9.416288 -3.54965)
			(end 9.42848 -3.618992)
			(stroke
				(width 0.1)
				(type default)
			)
			(layer "F.SilkS")
		)
		(fp_line
			(start 9.422638 -5.171694)
			(end 8.401558 -4.19227)
			(stroke
				(width 0.1)
				(type default)
			)
			(layer "F.SilkS")
		)
		(fp_line
			(start 9.422638 -5.171694)
			(end 8.401558 -4.19227)
			(stroke
				(width 0.1)
				(type default)
			)
			(layer "F.SilkS")
		)
		(fp_line
			(start 9.422638 -5.171694)
			(end 9.36244 -5.171694)
			(stroke
				(width 0.1)
				(type default)
			)
			(layer "F.SilkS")
		)
		(fp_line
			(start 9.422638 -5.171694)
			(end 9.36244 -5.171694)
			(stroke
				(width 0.1)
				(type default)
			)
			(layer "F.SilkS")
		)
		(fp_line
			(start 9.42848 -3.618992)
			(end 9.440672 -3.688334)
			(stroke
				(width 0.1)
				(type default)
			)
			(layer "F.SilkS")
		)
		(fp_line
			(start 9.42848 -3.618992)
			(end 9.440672 -3.688334)
			(stroke
				(width 0.1)
				(type default)
			)
			(layer "F.SilkS")
		)
		(fp_line
			(start 9.440672 -3.688334)
			(end 9.452864 -3.75793)
			(stroke
				(width 0.1)
				(type default)
			)
			(layer "F.SilkS")
		)
		(fp_line
			(start 9.440672 -3.688334)
			(end 9.452864 -3.75793)
			(stroke
				(width 0.1)
				(type default)
			)
			(layer "F.SilkS")
		)
		(fp_line
			(start 9.465056 -3.827526)
			(end 9.452864 -3.75793)
			(stroke
				(width 0.1)
				(type default)
			)
			(layer "F.SilkS")
		)
		(fp_line
			(start 9.465056 -3.827526)
			(end 9.452864 -3.75793)
			(stroke
				(width 0.1)
				(type default)
			)
			(layer "F.SilkS")
		)
		(fp_line
			(start 9.465056 -3.827526)
			(end 9.477248 -3.896614)
			(stroke
				(width 0.1)
				(type default)
			)
			(layer "F.SilkS")
		)
		(fp_line
			(start 9.465056 -3.827526)
			(end 9.477248 -3.896614)
			(stroke
				(width 0.1)
				(type default)
			)
			(layer "F.SilkS")
		)
		(fp_line
			(start 9.477248 -3.896614)
			(end 8.107172 -2.582418)
			(stroke
				(width 0.1)
				(type default)
			)
			(layer "F.SilkS")
		)
		(fp_line
			(start 9.477248 -3.896614)
			(end 8.107172 -2.582418)
			(stroke
				(width 0.1)
				(type default)
			)
			(layer "F.SilkS")
		)
		(fp_line
			(start 9.477248 -3.896614)
			(end 9.48944 -3.965956)
			(stroke
				(width 0.1)
				(type default)
			)
			(layer "F.SilkS")
		)
		(fp_line
			(start 9.477248 -3.896614)
			(end 9.48944 -3.965956)
			(stroke
				(width 0.1)
				(type default)
			)
			(layer "F.SilkS")
		)
		(fp_line
			(start 9.482836 -5.171694)
			(end 8.389366 -4.122674)
			(stroke
				(width 0.1)
				(type default)
			)
			(layer "F.SilkS")
		)
		(fp_line
			(start 9.482836 -5.171694)
			(end 8.389366 -4.122674)
			(stroke
				(width 0.1)
				(type default)
			)
			(layer "F.SilkS")
		)
		(fp_line
			(start 9.482836 -5.171694)
			(end 9.422638 -5.171694)
			(stroke
				(width 0.1)
				(type default)
			)
			(layer "F.SilkS")
		)
		(fp_line
			(start 9.482836 -5.171694)
			(end 9.422638 -5.171694)
			(stroke
				(width 0.1)
				(type default)
			)
			(layer "F.SilkS")
		)
		(fp_line
			(start 9.48944 -3.965956)
			(end 8.123682 -2.655824)
			(stroke
				(width 0.1)
				(type default)
			)
			(layer "F.SilkS")
		)
		(fp_line
			(start 9.48944 -3.965956)
			(end 8.123682 -2.655824)
			(stroke
				(width 0.1)
				(type default)
			)
			(layer "F.SilkS")
		)
		(fp_line
			(start 9.48944 -3.965956)
			(end 9.501632 -4.035552)
			(stroke
				(width 0.1)
				(type default)
			)
			(layer "F.SilkS")
		)
		(fp_line
			(start 9.48944 -3.965956)
			(end 9.501632 -4.035552)
			(stroke
				(width 0.1)
				(type default)
			)
			(layer "F.SilkS")
		)
		(fp_line
			(start 9.501632 -4.035552)
			(end 8.140446 -2.729738)
			(stroke
				(width 0.1)
				(type default)
			)
			(layer "F.SilkS")
		)
		(fp_line
			(start 9.501632 -4.035552)
			(end 8.140446 -2.729738)
			(stroke
				(width 0.1)
				(type default)
			)
			(layer "F.SilkS")
		)
		(fp_line
			(start 9.501632 -4.035552)
			(end 9.513824 -4.104894)
			(stroke
				(width 0.1)
				(type default)
			)
			(layer "F.SilkS")
		)
		(fp_line
			(start 9.501632 -4.035552)
			(end 9.513824 -4.104894)
			(stroke
				(width 0.1)
				(type default)
			)
			(layer "F.SilkS")
		)
		(fp_line
			(start 9.513824 -4.104894)
			(end 8.156956 -2.803398)
			(stroke
				(width 0.1)
				(type default)
			)
			(layer "F.SilkS")
		)
		(fp_line
			(start 9.513824 -4.104894)
			(end 8.156956 -2.803398)
			(stroke
				(width 0.1)
				(type default)
			)
			(layer "F.SilkS")
		)
		(fp_line
			(start 9.513824 -4.104894)
			(end 9.526016 -4.174236)
			(stroke
				(width 0.1)
				(type default)
			)
			(layer "F.SilkS")
		)
		(fp_line
			(start 9.513824 -4.104894)
			(end 9.526016 -4.174236)
			(stroke
				(width 0.1)
				(type default)
			)
			(layer "F.SilkS")
		)
		(fp_line
			(start 9.526016 -4.174236)
			(end 8.170418 -2.87401)
			(stroke
				(width 0.1)
				(type default)
			)
			(layer "F.SilkS")
		)
		(fp_line
			(start 9.526016 -4.174236)
			(end 8.170418 -2.87401)
			(stroke
				(width 0.1)
				(type default)
			)
			(layer "F.SilkS")
		)
		(fp_line
			(start 9.526016 -4.174236)
			(end 9.538208 -4.243578)
			(stroke
				(width 0.1)
				(type default)
			)
			(layer "F.SilkS")
		)
		(fp_line
			(start 9.526016 -4.174236)
			(end 9.538208 -4.243578)
			(stroke
				(width 0.1)
				(type default)
			)
			(layer "F.SilkS")
		)
		(fp_line
			(start 9.538208 -4.243578)
			(end 8.18261 -2.943352)
			(stroke
				(width 0.1)
				(type default)
			)
			(layer "F.SilkS")
		)
		(fp_line
			(start 9.538208 -4.243578)
			(end 8.18261 -2.943352)
			(stroke
				(width 0.1)
				(type default)
			)
			(layer "F.SilkS")
		)
		(fp_line
			(start 9.538208 -4.243578)
			(end 9.5504 -4.313174)
			(stroke
				(width 0.1)
				(type default)
			)
			(layer "F.SilkS")
		)
		(fp_line
			(start 9.538208 -4.243578)
			(end 9.5504 -4.313174)
			(stroke
				(width 0.1)
				(type default)
			)
			(layer "F.SilkS")
		)
		(fp_line
			(start 9.543034 -5.171694)
			(end 8.377174 -4.053332)
			(stroke
				(width 0.1)
				(type default)
			)
			(layer "F.SilkS")
		)
		(fp_line
			(start 9.543034 -5.171694)
			(end 8.377174 -4.053332)
			(stroke
				(width 0.1)
				(type default)
			)
			(layer "F.SilkS")
		)
		(fp_line
			(start 9.543034 -5.171694)
			(end 9.482836 -5.171694)
			(stroke
				(width 0.1)
				(type default)
			)
			(layer "F.SilkS")
		)
		(fp_line
			(start 9.543034 -5.171694)
			(end 9.482836 -5.171694)
			(stroke
				(width 0.1)
				(type default)
			)
			(layer "F.SilkS")
		)
		(fp_line
			(start 9.5504 -4.313174)
			(end 8.194802 -3.012694)
			(stroke
				(width 0.1)
				(type default)
			)
			(layer "F.SilkS")
		)
		(fp_line
			(start 9.5504 -4.313174)
			(end 8.194802 -3.012694)
			(stroke
				(width 0.1)
				(type default)
			)
			(layer "F.SilkS")
		)
		(fp_line
			(start 9.5504 -4.313174)
			(end 9.562592 -4.382516)
			(stroke
				(width 0.1)
				(type default)
			)
			(layer "F.SilkS")
		)
		(fp_line
			(start 9.5504 -4.313174)
			(end 9.562592 -4.382516)
			(stroke
				(width 0.1)
				(type default)
			)
			(layer "F.SilkS")
		)
		(fp_line
			(start 9.562592 -4.382516)
			(end 8.206994 -3.08229)
			(stroke
				(width 0.1)
				(type default)
			)
			(layer "F.SilkS")
		)
		(fp_line
			(start 9.562592 -4.382516)
			(end 8.206994 -3.08229)
			(stroke
				(width 0.1)
				(type default)
			)
			(layer "F.SilkS")
		)
		(fp_line
			(start 9.562592 -4.382516)
			(end 9.574784 -4.452112)
			(stroke
				(width 0.1)
				(type default)
			)
			(layer "F.SilkS")
		)
		(fp_line
			(start 9.562592 -4.382516)
			(end 9.574784 -4.452112)
			(stroke
				(width 0.1)
				(type default)
			)
			(layer "F.SilkS")
		)
		(fp_line
			(start 9.574784 -4.452112)
			(end 8.219186 -3.151378)
			(stroke
				(width 0.1)
				(type default)
			)
			(layer "F.SilkS")
		)
		(fp_line
			(start 9.574784 -4.452112)
			(end 8.219186 -3.151378)
			(stroke
				(width 0.1)
				(type default)
			)
			(layer "F.SilkS")
		)
		(fp_line
			(start 9.574784 -4.452112)
			(end 9.586976 -4.5212)
			(stroke
				(width 0.1)
				(type default)
			)
			(layer "F.SilkS")
		)
		(fp_line
			(start 9.574784 -4.452112)
			(end 9.586976 -4.5212)
			(stroke
				(width 0.1)
				(type default)
			)
			(layer "F.SilkS")
		)
		(fp_line
			(start 9.586976 -4.5212)
			(end 8.231378 -3.22072)
			(stroke
				(width 0.1)
				(type default)
			)
			(layer "F.SilkS")
		)
		(fp_line
			(start 9.586976 -4.5212)
			(end 8.231378 -3.22072)
			(stroke
				(width 0.1)
				(type default)
			)
			(layer "F.SilkS")
		)
		(fp_line
			(start 9.586976 -4.5212)
			(end 9.599168 -4.590796)
			(stroke
				(width 0.1)
				(type default)
			)
			(layer "F.SilkS")
		)
		(fp_line
			(start 9.586976 -4.5212)
			(end 9.599168 -4.590796)
			(stroke
				(width 0.1)
				(type default)
			)
			(layer "F.SilkS")
		)
		(fp_line
			(start 9.599168 -4.590796)
			(end 8.24357 -3.290316)
			(stroke
				(width 0.1)
				(type default)
			)
			(layer "F.SilkS")
		)
		(fp_line
			(start 9.599168 -4.590796)
			(end 8.24357 -3.290316)
			(stroke
				(width 0.1)
				(type default)
			)
			(layer "F.SilkS")
		)
		(fp_line
			(start 9.599168 -4.590796)
			(end 9.61136 -4.660138)
			(stroke
				(width 0.1)
				(type default)
			)
			(layer "F.SilkS")
		)
		(fp_line
			(start 9.599168 -4.590796)
			(end 9.61136 -4.660138)
			(stroke
				(width 0.1)
				(type default)
			)
			(layer "F.SilkS")
		)
		(fp_line
			(start 9.603232 -5.171694)
			(end 8.365236 -3.98399)
			(stroke
				(width 0.1)
				(type default)
			)
			(layer "F.SilkS")
		)
		(fp_line
			(start 9.603232 -5.171694)
			(end 8.365236 -3.98399)
			(stroke
				(width 0.1)
				(type default)
			)
			(layer "F.SilkS")
		)
		(fp_line
			(start 9.603232 -5.171694)
			(end 9.543034 -5.171694)
			(stroke
				(width 0.1)
				(type default)
			)
			(layer "F.SilkS")
		)
		(fp_line
			(start 9.603232 -5.171694)
			(end 9.543034 -5.171694)
			(stroke
				(width 0.1)
				(type default)
			)
			(layer "F.SilkS")
		)
		(fp_line
			(start 9.61136 -4.660138)
			(end 8.255762 -3.359658)
			(stroke
				(width 0.1)
				(type default)
			)
			(layer "F.SilkS")
		)
		(fp_line
			(start 9.61136 -4.660138)
			(end 8.255762 -3.359658)
			(stroke
				(width 0.1)
				(type default)
			)
			(layer "F.SilkS")
		)
		(fp_line
			(start 9.61136 -4.660138)
			(end 9.623552 -4.729734)
			(stroke
				(width 0.1)
				(type default)
			)
			(layer "F.SilkS")
		)
		(fp_line
			(start 9.61136 -4.660138)
			(end 9.623552 -4.729734)
			(stroke
				(width 0.1)
				(type default)
			)
			(layer "F.SilkS")
		)
		(fp_line
			(start 9.623552 -4.729734)
			(end 8.2677 -3.429)
			(stroke
				(width 0.1)
				(type default)
			)
			(layer "F.SilkS")
		)
		(fp_line
			(start 9.623552 -4.729734)
			(end 8.2677 -3.429)
			(stroke
				(width 0.1)
				(type default)
			)
			(layer "F.SilkS")
		)
		(fp_line
			(start 9.623552 -4.729734)
			(end 9.635744 -4.798822)
			(stroke
				(width 0.1)
				(type default)
			)
			(layer "F.SilkS")
		)
		(fp_line
			(start 9.623552 -4.729734)
			(end 9.635744 -4.798822)
			(stroke
				(width 0.1)
				(type default)
			)
			(layer "F.SilkS")
		)
		(fp_line
			(start 9.635744 -4.798822)
			(end 8.279892 -3.498342)
			(stroke
				(width 0.1)
				(type default)
			)
			(layer "F.SilkS")
		)
		(fp_line
			(start 9.635744 -4.798822)
			(end 8.279892 -3.498342)
			(stroke
				(width 0.1)
				(type default)
			)
			(layer "F.SilkS")
		)
		(fp_line
			(start 9.635744 -4.798822)
			(end 9.64819 -4.868418)
			(stroke
				(width 0.1)
				(type default)
			)
			(layer "F.SilkS")
		)
		(fp_line
			(start 9.635744 -4.798822)
			(end 9.64819 -4.868418)
			(stroke
				(width 0.1)
				(type default)
			)
			(layer "F.SilkS")
		)
		(fp_line
			(start 9.64819 -4.868418)
			(end 8.292084 -3.567684)
			(stroke
				(width 0.1)
				(type default)
			)
			(layer "F.SilkS")
		)
		(fp_line
			(start 9.64819 -4.868418)
			(end 8.292084 -3.567684)
			(stroke
				(width 0.1)
				(type default)
			)
			(layer "F.SilkS")
		)
		(fp_line
			(start 9.64819 -4.868418)
			(end 9.660382 -4.938014)
			(stroke
				(width 0.1)
				(type default)
			)
			(layer "F.SilkS")
		)
		(fp_line
			(start 9.64819 -4.868418)
			(end 9.660382 -4.938014)
			(stroke
				(width 0.1)
				(type default)
			)
			(layer "F.SilkS")
		)
		(fp_line
			(start 9.660382 -4.938014)
			(end 8.304276 -3.63728)
			(stroke
				(width 0.1)
				(type default)
			)
			(layer "F.SilkS")
		)
		(fp_line
			(start 9.660382 -4.938014)
			(end 8.304276 -3.63728)
			(stroke
				(width 0.1)
				(type default)
			)
			(layer "F.SilkS")
		)
		(fp_line
			(start 9.660382 -4.938014)
			(end 9.67232 -5.007356)
			(stroke
				(width 0.1)
				(type default)
			)
			(layer "F.SilkS")
		)
		(fp_line
			(start 9.660382 -4.938014)
			(end 9.67232 -5.007356)
			(stroke
				(width 0.1)
				(type default)
			)
			(layer "F.SilkS")
		)
		(fp_line
			(start 9.663176 -5.171694)
			(end 8.35279 -3.914648)
			(stroke
				(width 0.1)
				(type default)
			)
			(layer "F.SilkS")
		)
		(fp_line
			(start 9.663176 -5.171694)
			(end 8.35279 -3.914648)
			(stroke
				(width 0.1)
				(type default)
			)
			(layer "F.SilkS")
		)
		(fp_line
			(start 9.663176 -5.171694)
			(end 9.603232 -5.171694)
			(stroke
				(width 0.1)
				(type default)
			)
			(layer "F.SilkS")
		)
		(fp_line
			(start 9.663176 -5.171694)
			(end 9.603232 -5.171694)
			(stroke
				(width 0.1)
				(type default)
			)
			(layer "F.SilkS")
		)
		(fp_line
			(start 9.67232 -5.007356)
			(end 8.316468 -3.706368)
			(stroke
				(width 0.1)
				(type default)
			)
			(layer "F.SilkS")
		)
		(fp_line
			(start 9.67232 -5.007356)
			(end 8.316468 -3.706368)
			(stroke
				(width 0.1)
				(type default)
			)
			(layer "F.SilkS")
		)
		(fp_line
			(start 9.67232 -5.007356)
			(end 9.684512 -5.076698)
			(stroke
				(width 0.1)
				(type default)
			)
			(layer "F.SilkS")
		)
		(fp_line
			(start 9.67232 -5.007356)
			(end 9.684512 -5.076698)
			(stroke
				(width 0.1)
				(type default)
			)
			(layer "F.SilkS")
		)
		(fp_line
			(start 9.684512 -5.076698)
			(end 8.32866 -3.77571)
			(stroke
				(width 0.1)
				(type default)
			)
			(layer "F.SilkS")
		)
		(fp_line
			(start 9.684512 -5.076698)
			(end 8.32866 -3.77571)
			(stroke
				(width 0.1)
				(type default)
			)
			(layer "F.SilkS")
		)
		(fp_line
			(start 9.684512 -5.076698)
			(end 9.696704 -5.14604)
			(stroke
				(width 0.1)
				(type default)
			)
			(layer "F.SilkS")
		)
		(fp_line
			(start 9.684512 -5.076698)
			(end 9.696704 -5.14604)
			(stroke
				(width 0.1)
				(type default)
			)
			(layer "F.SilkS")
		)
		(fp_line
			(start 9.696704 -5.14604)
			(end 8.340852 -3.845306)
			(stroke
				(width 0.1)
				(type default)
			)
			(layer "F.SilkS")
		)
		(fp_line
			(start 9.696704 -5.14604)
			(end 8.340852 -3.845306)
			(stroke
				(width 0.1)
				(type default)
			)
			(layer "F.SilkS")
		)
		(fp_line
			(start 9.696704 -5.14604)
			(end 9.701276 -5.171694)
			(stroke
				(width 0.1)
				(type default)
			)
			(layer "F.SilkS")
		)
		(fp_line
			(start 9.696704 -5.14604)
			(end 9.701276 -5.171694)
			(stroke
				(width 0.1)
				(type default)
			)
			(layer "F.SilkS")
		)
		(fp_line
			(start 9.701276 -5.171694)
			(end 9.663176 -5.171694)
			(stroke
				(width 0.1)
				(type default)
			)
			(layer "F.SilkS")
		)
		(fp_line
			(start 9.701276 -5.171694)
			(end 9.663176 -5.171694)
			(stroke
				(width 0.1)
				(type default)
			)
			(layer "F.SilkS")
		)
		(fp_line
			(start 9.754616 -1.96977)
			(end 11.590528 -3.730752)
			(stroke
				(width 0.1)
				(type default)
			)
			(layer "F.SilkS")
		)
		(fp_line
			(start 9.754616 -1.96977)
			(end 11.590528 -3.730752)
			(stroke
				(width 0.1)
				(type default)
			)
			(layer "F.SilkS")
		)
		(fp_line
			(start 9.75614 -2.028698)
			(end 11.526012 -3.726688)
			(stroke
				(width 0.1)
				(type default)
			)
			(layer "F.SilkS")
		)
		(fp_line
			(start 9.75614 -2.028698)
			(end 11.526012 -3.726688)
			(stroke
				(width 0.1)
				(type default)
			)
			(layer "F.SilkS")
		)
		(fp_line
			(start 9.75741 -2.08788)
			(end 11.46175 -3.722878)
			(stroke
				(width 0.1)
				(type default)
			)
			(layer "F.SilkS")
		)
		(fp_line
			(start 9.75741 -2.08788)
			(end 11.46175 -3.722878)
			(stroke
				(width 0.1)
				(type default)
			)
			(layer "F.SilkS")
		)
		(fp_line
			(start 9.758172 -1.915414)
			(end 11.65479 -3.734816)
			(stroke
				(width 0.1)
				(type default)
			)
			(layer "F.SilkS")
		)
		(fp_line
			(start 9.758172 -1.915414)
			(end 11.65479 -3.734816)
			(stroke
				(width 0.1)
				(type default)
			)
			(layer "F.SilkS")
		)
		(fp_line
			(start 9.760458 -2.148332)
			(end 11.394694 -3.71602)
			(stroke
				(width 0.1)
				(type default)
			)
			(layer "F.SilkS")
		)
		(fp_line
			(start 9.760458 -2.148332)
			(end 11.394694 -3.71602)
			(stroke
				(width 0.1)
				(type default)
			)
			(layer "F.SilkS")
		)
		(fp_line
			(start 9.762998 -1.862074)
			(end 11.719052 -3.738626)
			(stroke
				(width 0.1)
				(type default)
			)
			(layer "F.SilkS")
		)
		(fp_line
			(start 9.762998 -1.862074)
			(end 11.719052 -3.738626)
			(stroke
				(width 0.1)
				(type default)
			)
			(layer "F.SilkS")
		)
		(fp_line
			(start 9.76757 -1.808988)
			(end 11.782044 -3.74142)
			(stroke
				(width 0.1)
				(type default)
			)
			(layer "F.SilkS")
		)
		(fp_line
			(start 9.76757 -1.808988)
			(end 11.782044 -3.74142)
			(stroke
				(width 0.1)
				(type default)
			)
			(layer "F.SilkS")
		)
		(fp_line
			(start 9.768586 -2.214118)
			(end 11.319002 -3.701288)
			(stroke
				(width 0.1)
				(type default)
			)
			(layer "F.SilkS")
		)
		(fp_line
			(start 9.768586 -2.214118)
			(end 11.319002 -3.701288)
			(stroke
				(width 0.1)
				(type default)
			)
			(layer "F.SilkS")
		)
		(fp_line
			(start 9.77646 -1.759712)
			(end 11.83894 -3.738372)
			(stroke
				(width 0.1)
				(type default)
			)
			(layer "F.SilkS")
		)
		(fp_line
			(start 9.77646 -1.759712)
			(end 11.83894 -3.738372)
			(stroke
				(width 0.1)
				(type default)
			)
			(layer "F.SilkS")
		)
		(fp_line
			(start 9.777222 -2.279904)
			(end 11.24331 -3.686556)
			(stroke
				(width 0.1)
				(type default)
			)
			(layer "F.SilkS")
		)
		(fp_line
			(start 9.777222 -2.279904)
			(end 11.24331 -3.686556)
			(stroke
				(width 0.1)
				(type default)
			)
			(layer "F.SilkS")
		)
		(fp_line
			(start 9.78662 -1.711706)
			(end 11.89609 -3.735324)
			(stroke
				(width 0.1)
				(type default)
			)
			(layer "F.SilkS")
		)
		(fp_line
			(start 9.78662 -1.711706)
			(end 11.89609 -3.735324)
			(stroke
				(width 0.1)
				(type default)
			)
			(layer "F.SilkS")
		)
		(fp_line
			(start 9.79043 -2.350262)
			(end 11.167872 -3.67157)
			(stroke
				(width 0.1)
				(type default)
			)
			(layer "F.SilkS")
		)
		(fp_line
			(start 9.79043 -2.350262)
			(end 11.167872 -3.67157)
			(stroke
				(width 0.1)
				(type default)
			)
			(layer "F.SilkS")
		)
		(fp_line
			(start 9.797034 -1.663954)
			(end 11.952986 -3.732276)
			(stroke
				(width 0.1)
				(type default)
			)
			(layer "F.SilkS")
		)
		(fp_line
			(start 9.797034 -1.663954)
			(end 11.952986 -3.732276)
			(stroke
				(width 0.1)
				(type default)
			)
			(layer "F.SilkS")
		)
		(fp_line
			(start 9.809988 -1.618742)
			(end 12.010136 -3.729482)
			(stroke
				(width 0.1)
				(type default)
			)
			(layer "F.SilkS")
		)
		(fp_line
			(start 9.809988 -1.618742)
			(end 12.010136 -3.729482)
			(stroke
				(width 0.1)
				(type default)
			)
			(layer "F.SilkS")
		)
		(fp_line
			(start 9.812528 -2.429256)
			(end 11.09218 -3.656838)
			(stroke
				(width 0.1)
				(type default)
			)
			(layer "F.SilkS")
		)
		(fp_line
			(start 9.812528 -2.429256)
			(end 11.09218 -3.656838)
			(stroke
				(width 0.1)
				(type default)
			)
			(layer "F.SilkS")
		)
		(fp_line
			(start 9.825228 -1.575562)
			(end 12.063984 -3.723132)
			(stroke
				(width 0.1)
				(type default)
			)
			(layer "F.SilkS")
		)
		(fp_line
			(start 9.825228 -1.575562)
			(end 12.063984 -3.723132)
			(stroke
				(width 0.1)
				(type default)
			)
			(layer "F.SilkS")
		)
		(fp_line
			(start 9.834626 -2.507996)
			(end 11.00201 -3.627882)
			(stroke
				(width 0.1)
				(type default)
			)
			(layer "F.SilkS")
		)
		(fp_line
			(start 9.834626 -2.507996)
			(end 11.00201 -3.627882)
			(stroke
				(width 0.1)
				(type default)
			)
			(layer "F.SilkS")
		)
		(fp_line
			(start 9.840214 -1.532382)
			(end 12.115038 -3.714496)
			(stroke
				(width 0.1)
				(type default)
			)
			(layer "F.SilkS")
		)
		(fp_line
			(start 9.840214 -1.532382)
			(end 12.115038 -3.714496)
			(stroke
				(width 0.1)
				(type default)
			)
			(layer "F.SilkS")
		)
		(fp_line
			(start 9.856978 -2.587244)
			(end 10.90676 -3.594354)
			(stroke
				(width 0.1)
				(type default)
			)
			(layer "F.SilkS")
		)
		(fp_line
			(start 9.856978 -2.587244)
			(end 10.90676 -3.594354)
			(stroke
				(width 0.1)
				(type default)
			)
			(layer "F.SilkS")
		)
		(fp_line
			(start 9.857232 -1.49098)
			(end 12.165838 -3.705352)
			(stroke
				(width 0.1)
				(type default)
			)
			(layer "F.SilkS")
		)
		(fp_line
			(start 9.857232 -1.49098)
			(end 12.165838 -3.705352)
			(stroke
				(width 0.1)
				(type default)
			)
			(layer "F.SilkS")
		)
		(fp_line
			(start 9.87679 -1.452118)
			(end 10.97661 -2.50698)
			(stroke
				(width 0.1)
				(type default)
			)
			(layer "F.SilkS")
		)
		(fp_line
			(start 9.87679 -1.452118)
			(end 10.97661 -2.50698)
			(stroke
				(width 0.1)
				(type default)
			)
			(layer "F.SilkS")
		)
		(fp_line
			(start 9.884664 -2.671572)
			(end 10.811764 -3.560826)
			(stroke
				(width 0.1)
				(type default)
			)
			(layer "F.SilkS")
		)
		(fp_line
			(start 9.884664 -2.671572)
			(end 10.811764 -3.560826)
			(stroke
				(width 0.1)
				(type default)
			)
			(layer "F.SilkS")
		)
		(fp_line
			(start 9.896602 -1.413256)
			(end 10.944606 -2.418588)
			(stroke
				(width 0.1)
				(type default)
			)
			(layer "F.SilkS")
		)
		(fp_line
			(start 9.896602 -1.413256)
			(end 10.944606 -2.418588)
			(stroke
				(width 0.1)
				(type default)
			)
			(layer "F.SilkS")
		)
		(fp_line
			(start 9.916922 -1.375156)
			(end 10.912856 -2.33045)
			(stroke
				(width 0.1)
				(type default)
			)
			(layer "F.SilkS")
		)
		(fp_line
			(start 9.916922 -1.375156)
			(end 10.912856 -2.33045)
			(stroke
				(width 0.1)
				(type default)
			)
			(layer "F.SilkS")
		)
		(fp_line
			(start 9.940798 -1.340358)
			(end 10.903712 -2.263902)
			(stroke
				(width 0.1)
				(type default)
			)
			(layer "F.SilkS")
		)
		(fp_line
			(start 9.940798 -1.340358)
			(end 10.903712 -2.263902)
			(stroke
				(width 0.1)
				(type default)
			)
			(layer "F.SilkS")
		)
		(fp_line
			(start 9.945116 -2.787142)
			(end 10.69721 -3.508502)
			(stroke
				(width 0.1)
				(type default)
			)
			(layer "F.SilkS")
		)
		(fp_line
			(start 9.945116 -2.787142)
			(end 10.69721 -3.508502)
			(stroke
				(width 0.1)
				(type default)
			)
			(layer "F.SilkS")
		)
		(fp_line
			(start 9.964674 -1.30556)
			(end 10.898632 -2.201418)
			(stroke
				(width 0.1)
				(type default)
			)
			(layer "F.SilkS")
		)
		(fp_line
			(start 9.964674 -1.30556)
			(end 10.898632 -2.201418)
			(stroke
				(width 0.1)
				(type default)
			)
			(layer "F.SilkS")
		)
		(fp_line
			(start 9.98855 -1.270508)
			(end 10.902442 -2.147316)
			(stroke
				(width 0.1)
				(type default)
			)
			(layer "F.SilkS")
		)
		(fp_line
			(start 9.98855 -1.270508)
			(end 10.902442 -2.147316)
			(stroke
				(width 0.1)
				(type default)
			)
			(layer "F.SilkS")
		)
		(fp_line
			(start 10.005568 -2.902966)
			(end 10.557002 -3.431794)
			(stroke
				(width 0.1)
				(type default)
			)
			(layer "F.SilkS")
		)
		(fp_line
			(start 10.005568 -2.902966)
			(end 10.557002 -3.431794)
			(stroke
				(width 0.1)
				(type default)
			)
			(layer "F.SilkS")
		)
		(fp_line
			(start 10.015982 -1.239266)
			(end 10.90803 -2.094992)
			(stroke
				(width 0.1)
				(type default)
			)
			(layer "F.SilkS")
		)
		(fp_line
			(start 10.015982 -1.239266)
			(end 10.90803 -2.094992)
			(stroke
				(width 0.1)
				(type default)
			)
			(layer "F.SilkS")
		)
		(fp_line
			(start 10.043668 -1.208278)
			(end 10.921238 -2.04978)
			(stroke
				(width 0.1)
				(type default)
			)
			(layer "F.SilkS")
		)
		(fp_line
			(start 10.043668 -1.208278)
			(end 10.921238 -2.04978)
			(stroke
				(width 0.1)
				(type default)
			)
			(layer "F.SilkS")
		)
		(fp_line
			(start 10.071608 -1.17729)
			(end 10.9347 -2.00533)
			(stroke
				(width 0.1)
				(type default)
			)
			(layer "F.SilkS")
		)
		(fp_line
			(start 10.071608 -1.17729)
			(end 10.9347 -2.00533)
			(stroke
				(width 0.1)
				(type default)
			)
			(layer "F.SilkS")
		)
		(fp_line
			(start 10.102088 -1.148588)
			(end 10.956798 -1.9685)
			(stroke
				(width 0.1)
				(type default)
			)
			(layer "F.SilkS")
		)
		(fp_line
			(start 10.102088 -1.148588)
			(end 10.956798 -1.9685)
			(stroke
				(width 0.1)
				(type default)
			)
			(layer "F.SilkS")
		)
		(fp_line
			(start 10.133584 -1.121156)
			(end 10.978642 -1.931924)
			(stroke
				(width 0.1)
				(type default)
			)
			(layer "F.SilkS")
		)
		(fp_line
			(start 10.133584 -1.121156)
			(end 10.978642 -1.931924)
			(stroke
				(width 0.1)
				(type default)
			)
			(layer "F.SilkS")
		)
		(fp_line
			(start 10.16508 -1.093724)
			(end 11.006582 -1.90119)
			(stroke
				(width 0.1)
				(type default)
			)
			(layer "F.SilkS")
		)
		(fp_line
			(start 10.16508 -1.093724)
			(end 11.006582 -1.90119)
			(stroke
				(width 0.1)
				(type default)
			)
			(layer "F.SilkS")
		)
		(fp_line
			(start 10.198354 -1.067816)
			(end 11.037062 -1.872742)
			(stroke
				(width 0.1)
				(type default)
			)
			(layer "F.SilkS")
		)
		(fp_line
			(start 10.198354 -1.067816)
			(end 11.037062 -1.872742)
			(stroke
				(width 0.1)
				(type default)
			)
			(layer "F.SilkS")
		)
		(fp_line
			(start 10.233406 -1.043686)
			(end 11.06932 -1.845818)
			(stroke
				(width 0.1)
				(type default)
			)
			(layer "F.SilkS")
		)
		(fp_line
			(start 10.233406 -1.043686)
			(end 11.06932 -1.845818)
			(stroke
				(width 0.1)
				(type default)
			)
			(layer "F.SilkS")
		)
		(fp_line
			(start 10.268458 -1.01981)
			(end 11.108182 -1.825244)
			(stroke
				(width 0.1)
				(type default)
			)
			(layer "F.SilkS")
		)
		(fp_line
			(start 10.268458 -1.01981)
			(end 11.108182 -1.825244)
			(stroke
				(width 0.1)
				(type default)
			)
			(layer "F.SilkS")
		)
		(fp_line
			(start 10.30478 -0.99695)
			(end 11.147044 -1.804924)
			(stroke
				(width 0.1)
				(type default)
			)
			(layer "F.SilkS")
		)
		(fp_line
			(start 10.30478 -0.99695)
			(end 11.147044 -1.804924)
			(stroke
				(width 0.1)
				(type default)
			)
			(layer "F.SilkS")
		)
		(fp_line
			(start 10.343388 -0.976122)
			(end 11.190478 -1.788922)
			(stroke
				(width 0.1)
				(type default)
			)
			(layer "F.SilkS")
		)
		(fp_line
			(start 10.343388 -0.976122)
			(end 11.190478 -1.788922)
			(stroke
				(width 0.1)
				(type default)
			)
			(layer "F.SilkS")
		)
		(fp_line
			(start 10.381996 -0.955548)
			(end 11.237722 -1.776476)
			(stroke
				(width 0.1)
				(type default)
			)
			(layer "F.SilkS")
		)
		(fp_line
			(start 10.381996 -0.955548)
			(end 11.237722 -1.776476)
			(stroke
				(width 0.1)
				(type default)
			)
			(layer "F.SilkS")
		)
		(fp_line
			(start 10.421366 -0.935482)
			(end 11.28522 -1.76403)
			(stroke
				(width 0.1)
				(type default)
			)
			(layer "F.SilkS")
		)
		(fp_line
			(start 10.421366 -0.935482)
			(end 11.28522 -1.76403)
			(stroke
				(width 0.1)
				(type default)
			)
			(layer "F.SilkS")
		)
		(fp_line
			(start 10.46353 -0.918464)
			(end 11.33856 -1.75768)
			(stroke
				(width 0.1)
				(type default)
			)
			(layer "F.SilkS")
		)
		(fp_line
			(start 10.46353 -0.918464)
			(end 11.33856 -1.75768)
			(stroke
				(width 0.1)
				(type default)
			)
			(layer "F.SilkS")
		)
		(fp_line
			(start 10.505694 -0.901192)
			(end 11.39444 -1.753616)
			(stroke
				(width 0.1)
				(type default)
			)
			(layer "F.SilkS")
		)
		(fp_line
			(start 10.505694 -0.901192)
			(end 11.39444 -1.753616)
			(stroke
				(width 0.1)
				(type default)
			)
			(layer "F.SilkS")
		)
		(fp_line
			(start 10.548366 -0.884682)
			(end 11.45032 -1.749552)
			(stroke
				(width 0.1)
				(type default)
			)
			(layer "F.SilkS")
		)
		(fp_line
			(start 10.548366 -0.884682)
			(end 11.45032 -1.749552)
			(stroke
				(width 0.1)
				(type default)
			)
			(layer "F.SilkS")
		)
		(fp_line
			(start 10.572496 -4.831842)
			(end 10.566146 -4.825746)
			(stroke
				(width 0.1)
				(type default)
			)
			(layer "F.SilkS")
		)
		(fp_line
			(start 10.572496 -4.831842)
			(end 10.566146 -4.825746)
			(stroke
				(width 0.1)
				(type default)
			)
			(layer "F.SilkS")
		)
		(fp_line
			(start 10.582148 -4.783328)
			(end 10.566146 -4.825746)
			(stroke
				(width 0.1)
				(type default)
			)
			(layer "F.SilkS")
		)
		(fp_line
			(start 10.582148 -4.783328)
			(end 10.566146 -4.825746)
			(stroke
				(width 0.1)
				(type default)
			)
			(layer "F.SilkS")
		)
		(fp_line
			(start 10.59434 -0.870712)
			(end 11.516614 -1.75514)
			(stroke
				(width 0.1)
				(type default)
			)
			(layer "F.SilkS")
		)
		(fp_line
			(start 10.59434 -0.870712)
			(end 11.516614 -1.75514)
			(stroke
				(width 0.1)
				(type default)
			)
			(layer "F.SilkS")
		)
		(fp_line
			(start 10.59815 -4.74091)
			(end 10.582148 -4.783328)
			(stroke
				(width 0.1)
				(type default)
			)
			(layer "F.SilkS")
		)
		(fp_line
			(start 10.59815 -4.74091)
			(end 10.582148 -4.783328)
			(stroke
				(width 0.1)
				(type default)
			)
			(layer "F.SilkS")
		)
		(fp_line
			(start 10.613898 -4.698746)
			(end 10.59815 -4.74091)
			(stroke
				(width 0.1)
				(type default)
			)
			(layer "F.SilkS")
		)
		(fp_line
			(start 10.613898 -4.698746)
			(end 10.59815 -4.74091)
			(stroke
				(width 0.1)
				(type default)
			)
			(layer "F.SilkS")
		)
		(fp_line
			(start 10.613898 -4.698746)
			(end 10.6299 -4.656074)
			(stroke
				(width 0.1)
				(type default)
			)
			(layer "F.SilkS")
		)
		(fp_line
			(start 10.613898 -4.698746)
			(end 10.6299 -4.656074)
			(stroke
				(width 0.1)
				(type default)
			)
			(layer "F.SilkS")
		)
		(fp_line
			(start 10.6299 -4.656074)
			(end 10.645902 -4.613656)
			(stroke
				(width 0.1)
				(type default)
			)
			(layer "F.SilkS")
		)
		(fp_line
			(start 10.6299 -4.656074)
			(end 10.645902 -4.613656)
			(stroke
				(width 0.1)
				(type default)
			)
			(layer "F.SilkS")
		)
		(fp_line
			(start 10.64006 -0.856996)
			(end 11.585448 -1.763522)
			(stroke
				(width 0.1)
				(type default)
			)
			(layer "F.SilkS")
		)
		(fp_line
			(start 10.64006 -0.856996)
			(end 11.585448 -1.763522)
			(stroke
				(width 0.1)
				(type default)
			)
			(layer "F.SilkS")
		)
		(fp_line
			(start 10.645902 -4.613656)
			(end 10.661904 -4.571492)
			(stroke
				(width 0.1)
				(type default)
			)
			(layer "F.SilkS")
		)
		(fp_line
			(start 10.645902 -4.613656)
			(end 10.661904 -4.571492)
			(stroke
				(width 0.1)
				(type default)
			)
			(layer "F.SilkS")
		)
		(fp_line
			(start 10.661904 -4.571492)
			(end 10.677906 -4.529074)
			(stroke
				(width 0.1)
				(type default)
			)
			(layer "F.SilkS")
		)
		(fp_line
			(start 10.661904 -4.571492)
			(end 10.677906 -4.529074)
			(stroke
				(width 0.1)
				(type default)
			)
			(layer "F.SilkS")
		)
		(fp_line
			(start 10.677906 -4.529074)
			(end 10.693908 -4.486402)
			(stroke
				(width 0.1)
				(type default)
			)
			(layer "F.SilkS")
		)
		(fp_line
			(start 10.677906 -4.529074)
			(end 10.693908 -4.486402)
			(stroke
				(width 0.1)
				(type default)
			)
			(layer "F.SilkS")
		)
		(fp_line
			(start 10.686542 -0.843534)
			(end 11.654282 -1.772158)
			(stroke
				(width 0.1)
				(type default)
			)
			(layer "F.SilkS")
		)
		(fp_line
			(start 10.686542 -0.843534)
			(end 11.654282 -1.772158)
			(stroke
				(width 0.1)
				(type default)
			)
			(layer "F.SilkS")
		)
		(fp_line
			(start 10.693908 -4.486402)
			(end 10.709656 -4.443984)
			(stroke
				(width 0.1)
				(type default)
			)
			(layer "F.SilkS")
		)
		(fp_line
			(start 10.693908 -4.486402)
			(end 10.709656 -4.443984)
			(stroke
				(width 0.1)
				(type default)
			)
			(layer "F.SilkS")
		)
		(fp_line
			(start 10.698734 -4.895088)
			(end 10.582148 -4.783328)
			(stroke
				(width 0.1)
				(type default)
			)
			(layer "F.SilkS")
		)
		(fp_line
			(start 10.698734 -4.895088)
			(end 10.582148 -4.783328)
			(stroke
				(width 0.1)
				(type default)
			)
			(layer "F.SilkS")
		)
		(fp_line
			(start 10.709656 -4.443984)
			(end 10.725658 -4.40182)
			(stroke
				(width 0.1)
				(type default)
			)
			(layer "F.SilkS")
		)
		(fp_line
			(start 10.709656 -4.443984)
			(end 10.725658 -4.40182)
			(stroke
				(width 0.1)
				(type default)
			)
			(layer "F.SilkS")
		)
		(fp_line
			(start 10.725658 -4.40182)
			(end 10.74166 -4.359402)
			(stroke
				(width 0.1)
				(type default)
			)
			(layer "F.SilkS")
		)
		(fp_line
			(start 10.725658 -4.40182)
			(end 10.74166 -4.359402)
			(stroke
				(width 0.1)
				(type default)
			)
			(layer "F.SilkS")
		)
		(fp_line
			(start 10.736072 -0.833628)
			(end 11.723116 -1.78054)
			(stroke
				(width 0.1)
				(type default)
			)
			(layer "F.SilkS")
		)
		(fp_line
			(start 10.736072 -0.833628)
			(end 11.723116 -1.78054)
			(stroke
				(width 0.1)
				(type default)
			)
			(layer "F.SilkS")
		)
		(fp_line
			(start 10.74166 -4.359402)
			(end 10.757662 -4.316984)
			(stroke
				(width 0.1)
				(type default)
			)
			(layer "F.SilkS")
		)
		(fp_line
			(start 10.74166 -4.359402)
			(end 10.757662 -4.316984)
			(stroke
				(width 0.1)
				(type default)
			)
			(layer "F.SilkS")
		)
		(fp_line
			(start 10.757662 -4.316984)
			(end 10.773664 -4.274566)
			(stroke
				(width 0.1)
				(type default)
			)
			(layer "F.SilkS")
		)
		(fp_line
			(start 10.757662 -4.316984)
			(end 10.773664 -4.274566)
			(stroke
				(width 0.1)
				(type default)
			)
			(layer "F.SilkS")
		)
		(fp_line
			(start 10.773664 -4.274566)
			(end 10.789666 -4.232148)
			(stroke
				(width 0.1)
				(type default)
			)
			(layer "F.SilkS")
		)
		(fp_line
			(start 10.773664 -4.274566)
			(end 10.789666 -4.232148)
			(stroke
				(width 0.1)
				(type default)
			)
			(layer "F.SilkS")
		)
		(fp_line
			(start 10.785602 -0.823214)
			(end 11.818112 -1.813814)
			(stroke
				(width 0.1)
				(type default)
			)
			(layer "F.SilkS")
		)
		(fp_line
			(start 10.785602 -0.823214)
			(end 11.818112 -1.813814)
			(stroke
				(width 0.1)
				(type default)
			)
			(layer "F.SilkS")
		)
		(fp_line
			(start 10.789666 -4.232148)
			(end 10.805414 -4.18973)
			(stroke
				(width 0.1)
				(type default)
			)
			(layer "F.SilkS")
		)
		(fp_line
			(start 10.789666 -4.232148)
			(end 10.805414 -4.18973)
			(stroke
				(width 0.1)
				(type default)
			)
			(layer "F.SilkS")
		)
		(fp_line
			(start 10.805414 -4.18973)
			(end 10.821416 -4.147312)
			(stroke
				(width 0.1)
				(type default)
			)
			(layer "F.SilkS")
		)
		(fp_line
			(start 10.805414 -4.18973)
			(end 10.821416 -4.147312)
			(stroke
				(width 0.1)
				(type default)
			)
			(layer "F.SilkS")
		)
		(fp_line
			(start 10.818368 -4.952492)
			(end 10.59815 -4.74091)
			(stroke
				(width 0.1)
				(type default)
			)
			(layer "F.SilkS")
		)
		(fp_line
			(start 10.818368 -4.952492)
			(end 10.59815 -4.74091)
			(stroke
				(width 0.1)
				(type default)
			)
			(layer "F.SilkS")
		)
		(fp_line
			(start 10.821416 -4.147312)
			(end 10.837418 -4.104894)
			(stroke
				(width 0.1)
				(type default)
			)
			(layer "F.SilkS")
		)
		(fp_line
			(start 10.821416 -4.147312)
			(end 10.837418 -4.104894)
			(stroke
				(width 0.1)
				(type default)
			)
			(layer "F.SilkS")
		)
		(fp_line
			(start 10.836402 -0.814324)
			(end 11.91514 -1.84912)
			(stroke
				(width 0.1)
				(type default)
			)
			(layer "F.SilkS")
		)
		(fp_line
			(start 10.836402 -0.814324)
			(end 11.91514 -1.84912)
			(stroke
				(width 0.1)
				(type default)
			)
			(layer "F.SilkS")
		)
		(fp_line
			(start 10.837418 -4.104894)
			(end 10.85342 -4.062476)
			(stroke
				(width 0.1)
				(type default)
			)
			(layer "F.SilkS")
		)
		(fp_line
			(start 10.837418 -4.104894)
			(end 10.85342 -4.062476)
			(stroke
				(width 0.1)
				(type default)
			)
			(layer "F.SilkS")
		)
		(fp_line
			(start 10.889742 -0.808228)
			(end 12.047474 -1.918462)
			(stroke
				(width 0.1)
				(type default)
			)
			(layer "F.SilkS")
		)
		(fp_line
			(start 10.889742 -0.808228)
			(end 12.047474 -1.918462)
			(stroke
				(width 0.1)
				(type default)
			)
			(layer "F.SilkS")
		)
		(fp_line
			(start 10.931144 -5.002784)
			(end 10.613898 -4.698746)
			(stroke
				(width 0.1)
				(type default)
			)
			(layer "F.SilkS")
		)
		(fp_line
			(start 10.931144 -5.002784)
			(end 10.613898 -4.698746)
			(stroke
				(width 0.1)
				(type default)
			)
			(layer "F.SilkS")
		)
		(fp_line
			(start 10.99947 -0.797814)
			(end 13.653516 -3.343402)
			(stroke
				(width 0.1)
				(type default)
			)
			(layer "F.SilkS")
		)
		(fp_line
			(start 10.99947 -0.797814)
			(end 13.653516 -3.343402)
			(stroke
				(width 0.1)
				(type default)
			)
			(layer "F.SilkS")
		)
		(fp_line
			(start 11.03503 -5.044694)
			(end 10.6299 -4.656074)
			(stroke
				(width 0.1)
				(type default)
			)
			(layer "F.SilkS")
		)
		(fp_line
			(start 11.03503 -5.044694)
			(end 10.6299 -4.656074)
			(stroke
				(width 0.1)
				(type default)
			)
			(layer "F.SilkS")
		)
		(fp_line
			(start 11.057382 -0.795274)
			(end 13.64107 -3.27406)
			(stroke
				(width 0.1)
				(type default)
			)
			(layer "F.SilkS")
		)
		(fp_line
			(start 11.057382 -0.795274)
			(end 13.64107 -3.27406)
			(stroke
				(width 0.1)
				(type default)
			)
			(layer "F.SilkS")
		)
		(fp_line
			(start 11.11504 -0.792988)
			(end 13.629132 -3.204972)
			(stroke
				(width 0.1)
				(type default)
			)
			(layer "F.SilkS")
		)
		(fp_line
			(start 11.11504 -0.792988)
			(end 13.629132 -3.204972)
			(stroke
				(width 0.1)
				(type default)
			)
			(layer "F.SilkS")
		)
		(fp_line
			(start 11.13536 -5.083048)
			(end 10.645902 -4.613656)
			(stroke
				(width 0.1)
				(type default)
			)
			(layer "F.SilkS")
		)
		(fp_line
			(start 11.13536 -5.083048)
			(end 10.645902 -4.613656)
			(stroke
				(width 0.1)
				(type default)
			)
			(layer "F.SilkS")
		)
		(fp_line
			(start 11.182096 -0.799846)
			(end 13.61694 -3.135376)
			(stroke
				(width 0.1)
				(type default)
			)
			(layer "F.SilkS")
		)
		(fp_line
			(start 11.182096 -0.799846)
			(end 13.61694 -3.135376)
			(stroke
				(width 0.1)
				(type default)
			)
			(layer "F.SilkS")
		)
		(fp_line
			(start 11.226546 -5.11302)
			(end 10.661904 -4.571492)
			(stroke
				(width 0.1)
				(type default)
			)
			(layer "F.SilkS")
		)
		(fp_line
			(start 11.226546 -5.11302)
			(end 10.661904 -4.571492)
			(stroke
				(width 0.1)
				(type default)
			)
			(layer "F.SilkS")
		)
		(fp_line
			(start 11.246612 -2.76606)
			(end 12.216638 -3.696716)
			(stroke
				(width 0.1)
				(type default)
			)
			(layer "F.SilkS")
		)
		(fp_line
			(start 11.246612 -2.76606)
			(end 12.216638 -3.696716)
			(stroke
				(width 0.1)
				(type default)
			)
			(layer "F.SilkS")
		)
		(fp_line
			(start 11.248898 -0.805942)
			(end 13.604494 -3.06578)
			(stroke
				(width 0.1)
				(type default)
			)
			(layer "F.SilkS")
		)
		(fp_line
			(start 11.248898 -0.805942)
			(end 13.604494 -3.06578)
			(stroke
				(width 0.1)
				(type default)
			)
			(layer "F.SilkS")
		)
		(fp_line
			(start 11.315446 -5.140706)
			(end 10.677906 -4.529074)
			(stroke
				(width 0.1)
				(type default)
			)
			(layer "F.SilkS")
		)
		(fp_line
			(start 11.315446 -5.140706)
			(end 10.677906 -4.529074)
			(stroke
				(width 0.1)
				(type default)
			)
			(layer "F.SilkS")
		)
		(fp_line
			(start 11.315954 -0.813054)
			(end 13.592556 -2.996692)
			(stroke
				(width 0.1)
				(type default)
			)
			(layer "F.SilkS")
		)
		(fp_line
			(start 11.315954 -0.813054)
			(end 13.592556 -2.996692)
			(stroke
				(width 0.1)
				(type default)
			)
			(layer "F.SilkS")
		)
		(fp_line
			(start 11.364722 -2.821686)
			(end 12.265914 -3.686302)
			(stroke
				(width 0.1)
				(type default)
			)
			(layer "F.SilkS")
		)
		(fp_line
			(start 11.364722 -2.821686)
			(end 12.265914 -3.686302)
			(stroke
				(width 0.1)
				(type default)
			)
			(layer "F.SilkS")
		)
		(fp_line
			(start 11.382756 -0.81915)
			(end 13.580364 -2.927096)
			(stroke
				(width 0.1)
				(type default)
			)
			(layer "F.SilkS")
		)
		(fp_line
			(start 11.382756 -0.81915)
			(end 13.580364 -2.927096)
			(stroke
				(width 0.1)
				(type default)
			)
			(layer "F.SilkS")
		)
		(fp_line
			(start 11.398758 -5.163058)
			(end 10.693908 -4.486402)
			(stroke
				(width 0.1)
				(type default)
			)
			(layer "F.SilkS")
		)
		(fp_line
			(start 11.398758 -5.163058)
			(end 10.693908 -4.486402)
			(stroke
				(width 0.1)
				(type default)
			)
			(layer "F.SilkS")
		)
		(fp_line
			(start 11.436096 -2.832354)
			(end 12.31138 -3.672078)
			(stroke
				(width 0.1)
				(type default)
			)
			(layer "F.SilkS")
		)
		(fp_line
			(start 11.436096 -2.832354)
			(end 12.31138 -3.672078)
			(stroke
				(width 0.1)
				(type default)
			)
			(layer "F.SilkS")
		)
		(fp_line
			(start 11.460734 -0.836422)
			(end 13.568172 -2.857754)
			(stroke
				(width 0.1)
				(type default)
			)
			(layer "F.SilkS")
		)
		(fp_line
			(start 11.460734 -0.836422)
			(end 13.568172 -2.857754)
			(stroke
				(width 0.1)
				(type default)
			)
			(layer "F.SilkS")
		)
		(fp_line
			(start 11.478514 -5.1816)
			(end 10.709656 -4.443984)
			(stroke
				(width 0.1)
				(type default)
			)
			(layer "F.SilkS")
		)
		(fp_line
			(start 11.478514 -5.1816)
			(end 10.709656 -4.443984)
			(stroke
				(width 0.1)
				(type default)
			)
			(layer "F.SilkS")
		)
		(fp_line
			(start 11.505184 -2.84099)
			(end 12.356592 -3.657854)
			(stroke
				(width 0.1)
				(type default)
			)
			(layer "F.SilkS")
		)
		(fp_line
			(start 11.505184 -2.84099)
			(end 12.356592 -3.657854)
			(stroke
				(width 0.1)
				(type default)
			)
			(layer "F.SilkS")
		)
		(fp_line
			(start 11.546332 -0.860552)
			(end 13.55598 -2.788412)
			(stroke
				(width 0.1)
				(type default)
			)
			(layer "F.SilkS")
		)
		(fp_line
			(start 11.546332 -0.860552)
			(end 13.55598 -2.788412)
			(stroke
				(width 0.1)
				(type default)
			)
			(layer "F.SilkS")
		)
		(fp_line
			(start 11.557762 -5.199888)
			(end 10.725658 -4.40182)
			(stroke
				(width 0.1)
				(type default)
			)
			(layer "F.SilkS")
		)
		(fp_line
			(start 11.557762 -5.199888)
			(end 10.725658 -4.40182)
			(stroke
				(width 0.1)
				(type default)
			)
			(layer "F.SilkS")
		)
		(fp_line
			(start 11.629898 -5.211572)
			(end 10.74166 -4.359402)
			(stroke
				(width 0.1)
				(type default)
			)
			(layer "F.SilkS")
		)
		(fp_line
			(start 11.629898 -5.211572)
			(end 10.74166 -4.359402)
			(stroke
				(width 0.1)
				(type default)
			)
			(layer "F.SilkS")
		)
		(fp_line
			(start 11.63193 -0.884936)
			(end 13.544042 -2.71907)
			(stroke
				(width 0.1)
				(type default)
			)
			(layer "F.SilkS")
		)
		(fp_line
			(start 11.63193 -0.884936)
			(end 13.544042 -2.71907)
			(stroke
				(width 0.1)
				(type default)
			)
			(layer "F.SilkS")
		)
		(fp_line
			(start 11.702034 -5.223002)
			(end 10.757662 -4.316984)
			(stroke
				(width 0.1)
				(type default)
			)
			(layer "F.SilkS")
		)
		(fp_line
			(start 11.702034 -5.223002)
			(end 10.757662 -4.316984)
			(stroke
				(width 0.1)
				(type default)
			)
			(layer "F.SilkS")
		)
		(fp_line
			(start 11.728704 -0.919988)
			(end 13.531596 -2.649728)
			(stroke
				(width 0.1)
				(type default)
			)
			(layer "F.SilkS")
		)
		(fp_line
			(start 11.728704 -0.919988)
			(end 13.531596 -2.649728)
			(stroke
				(width 0.1)
				(type default)
			)
			(layer "F.SilkS")
		)
		(fp_line
			(start 11.77417 -5.234178)
			(end 10.773664 -4.274566)
			(stroke
				(width 0.1)
				(type default)
			)
			(layer "F.SilkS")
		)
		(fp_line
			(start 11.77417 -5.234178)
			(end 10.773664 -4.274566)
			(stroke
				(width 0.1)
				(type default)
			)
			(layer "F.SilkS")
		)
		(fp_line
			(start 11.84021 -5.24002)
			(end 10.789666 -4.232148)
			(stroke
				(width 0.1)
				(type default)
			)
			(layer "F.SilkS")
		)
		(fp_line
			(start 11.84021 -5.24002)
			(end 10.789666 -4.232148)
			(stroke
				(width 0.1)
				(type default)
			)
			(layer "F.SilkS")
		)
		(fp_line
			(start 11.8491 -0.9779)
			(end 13.519404 -2.580386)
			(stroke
				(width 0.1)
				(type default)
			)
			(layer "F.SilkS")
		)
		(fp_line
			(start 11.8491 -0.9779)
			(end 13.519404 -2.580386)
			(stroke
				(width 0.1)
				(type default)
			)
			(layer "F.SilkS")
		)
		(fp_line
			(start 11.906504 -5.245862)
			(end 10.805414 -4.18973)
			(stroke
				(width 0.1)
				(type default)
			)
			(layer "F.SilkS")
		)
		(fp_line
			(start 11.906504 -5.245862)
			(end 10.805414 -4.18973)
			(stroke
				(width 0.1)
				(type default)
			)
			(layer "F.SilkS")
		)
		(fp_line
			(start 11.972798 -5.251958)
			(end 10.821416 -4.147312)
			(stroke
				(width 0.1)
				(type default)
			)
			(layer "F.SilkS")
		)
		(fp_line
			(start 11.972798 -5.251958)
			(end 10.821416 -4.147312)
			(stroke
				(width 0.1)
				(type default)
			)
			(layer "F.SilkS")
		)
		(fp_line
			(start 12.000738 -1.06553)
			(end 13.507466 -2.51079)
			(stroke
				(width 0.1)
				(type default)
			)
			(layer "F.SilkS")
		)
		(fp_line
			(start 12.000738 -1.06553)
			(end 13.507466 -2.51079)
			(stroke
				(width 0.1)
				(type default)
			)
			(layer "F.SilkS")
		)
		(fp_line
			(start 12.036806 -5.255514)
			(end 10.837418 -4.104894)
			(stroke
				(width 0.1)
				(type default)
			)
			(layer "F.SilkS")
		)
		(fp_line
			(start 12.036806 -5.255514)
			(end 10.837418 -4.104894)
			(stroke
				(width 0.1)
				(type default)
			)
			(layer "F.SilkS")
		)
		(fp_line
			(start 12.093956 -0.882904)
			(end 12.111228 -0.882904)
			(stroke
				(width 0.1)
				(type default)
			)
			(layer "F.SilkS")
		)
		(fp_line
			(start 12.093956 -0.882904)
			(end 12.111228 -0.882904)
			(stroke
				(width 0.1)
				(type default)
			)
			(layer "F.SilkS")
		)
		(fp_line
			(start 12.098528 -5.257038)
			(end 10.85342 -4.062476)
			(stroke
				(width 0.1)
				(type default)
			)
			(layer "F.SilkS")
		)
		(fp_line
			(start 12.098528 -5.257038)
			(end 10.85342 -4.062476)
			(stroke
				(width 0.1)
				(type default)
			)
			(layer "F.SilkS")
		)
		(fp_line
			(start 12.102592 -0.932434)
			(end 12.093956 -0.882904)
			(stroke
				(width 0.1)
				(type default)
			)
			(layer "F.SilkS")
		)
		(fp_line
			(start 12.102592 -0.932434)
			(end 12.093956 -0.882904)
			(stroke
				(width 0.1)
				(type default)
			)
			(layer "F.SilkS")
		)
		(fp_line
			(start 12.102592 -0.932434)
			(end 13.458444 -2.233422)
			(stroke
				(width 0.1)
				(type default)
			)
			(layer "F.SilkS")
		)
		(fp_line
			(start 12.102592 -0.932434)
			(end 13.458444 -2.233422)
			(stroke
				(width 0.1)
				(type default)
			)
			(layer "F.SilkS")
		)
		(fp_line
			(start 12.111228 -0.882904)
			(end 12.171172 -0.882904)
			(stroke
				(width 0.1)
				(type default)
			)
			(layer "F.SilkS")
		)
		(fp_line
			(start 12.111228 -0.882904)
			(end 12.171172 -0.882904)
			(stroke
				(width 0.1)
				(type default)
			)
			(layer "F.SilkS")
		)
		(fp_line
			(start 12.111228 -0.882904)
			(end 13.446506 -2.163826)
			(stroke
				(width 0.1)
				(type default)
			)
			(layer "F.SilkS")
		)
		(fp_line
			(start 12.111228 -0.882904)
			(end 13.446506 -2.163826)
			(stroke
				(width 0.1)
				(type default)
			)
			(layer "F.SilkS")
		)
		(fp_line
			(start 12.115038 -1.00203)
			(end 12.102592 -0.932434)
			(stroke
				(width 0.1)
				(type default)
			)
			(layer "F.SilkS")
		)
		(fp_line
			(start 12.115038 -1.00203)
			(end 12.102592 -0.932434)
			(stroke
				(width 0.1)
				(type default)
			)
			(layer "F.SilkS")
		)
		(fp_line
			(start 12.115038 -1.00203)
			(end 13.47089 -2.302764)
			(stroke
				(width 0.1)
				(type default)
			)
			(layer "F.SilkS")
		)
		(fp_line
			(start 12.115038 -1.00203)
			(end 13.47089 -2.302764)
			(stroke
				(width 0.1)
				(type default)
			)
			(layer "F.SilkS")
		)
		(fp_line
			(start 12.12723 -1.071626)
			(end 12.115038 -1.00203)
			(stroke
				(width 0.1)
				(type default)
			)
			(layer "F.SilkS")
		)
		(fp_line
			(start 12.12723 -1.071626)
			(end 12.115038 -1.00203)
			(stroke
				(width 0.1)
				(type default)
			)
			(layer "F.SilkS")
		)
		(fp_line
			(start 12.12723 -1.071626)
			(end 13.483082 -2.372106)
			(stroke
				(width 0.1)
				(type default)
			)
			(layer "F.SilkS")
		)
		(fp_line
			(start 12.12723 -1.071626)
			(end 13.483082 -2.372106)
			(stroke
				(width 0.1)
				(type default)
			)
			(layer "F.SilkS")
		)
		(fp_line
			(start 12.139676 -1.140968)
			(end 12.12723 -1.071626)
			(stroke
				(width 0.1)
				(type default)
			)
			(layer "F.SilkS")
		)
		(fp_line
			(start 12.139676 -1.140968)
			(end 12.12723 -1.071626)
			(stroke
				(width 0.1)
				(type default)
			)
			(layer "F.SilkS")
		)
		(fp_line
			(start 12.139676 -1.140968)
			(end 13.49502 -2.441448)
			(stroke
				(width 0.1)
				(type default)
			)
			(layer "F.SilkS")
		)
		(fp_line
			(start 12.139676 -1.140968)
			(end 13.49502 -2.441448)
			(stroke
				(width 0.1)
				(type default)
			)
			(layer "F.SilkS")
		)
		(fp_line
			(start 12.160504 -5.258816)
			(end 10.92708 -4.07543)
			(stroke
				(width 0.1)
				(type default)
			)
			(layer "F.SilkS")
		)
		(fp_line
			(start 12.160504 -5.258816)
			(end 10.92708 -4.07543)
			(stroke
				(width 0.1)
				(type default)
			)
			(layer "F.SilkS")
		)
		(fp_line
			(start 12.171172 -0.882904)
			(end 12.23137 -0.882904)
			(stroke
				(width 0.1)
				(type default)
			)
			(layer "F.SilkS")
		)
		(fp_line
			(start 12.171172 -0.882904)
			(end 12.23137 -0.882904)
			(stroke
				(width 0.1)
				(type default)
			)
			(layer "F.SilkS")
		)
		(fp_line
			(start 12.171172 -0.882904)
			(end 13.434314 -2.094738)
			(stroke
				(width 0.1)
				(type default)
			)
			(layer "F.SilkS")
		)
		(fp_line
			(start 12.171172 -0.882904)
			(end 13.434314 -2.094738)
			(stroke
				(width 0.1)
				(type default)
			)
			(layer "F.SilkS")
		)
		(fp_line
			(start 12.22248 -5.260594)
			(end 11.042904 -4.12877)
			(stroke
				(width 0.1)
				(type default)
			)
			(layer "F.SilkS")
		)
		(fp_line
			(start 12.22248 -5.260594)
			(end 11.042904 -4.12877)
			(stroke
				(width 0.1)
				(type default)
			)
			(layer "F.SilkS")
		)
		(fp_line
			(start 12.23137 -0.882904)
			(end 12.291568 -0.882904)
			(stroke
				(width 0.1)
				(type default)
			)
			(layer "F.SilkS")
		)
		(fp_line
			(start 12.23137 -0.882904)
			(end 12.291568 -0.882904)
			(stroke
				(width 0.1)
				(type default)
			)
			(layer "F.SilkS")
		)
		(fp_line
			(start 12.23137 -0.882904)
			(end 13.422122 -2.025396)
			(stroke
				(width 0.1)
				(type default)
			)
			(layer "F.SilkS")
		)
		(fp_line
			(start 12.23137 -0.882904)
			(end 13.422122 -2.025396)
			(stroke
				(width 0.1)
				(type default)
			)
			(layer "F.SilkS")
		)
		(fp_line
			(start 12.281408 -5.25907)
			(end 11.150092 -4.173728)
			(stroke
				(width 0.1)
				(type default)
			)
			(layer "F.SilkS")
		)
		(fp_line
			(start 12.281408 -5.25907)
			(end 11.150092 -4.173728)
			(stroke
				(width 0.1)
				(type default)
			)
			(layer "F.SilkS")
		)
		(fp_line
			(start 12.291568 -0.882904)
			(end 12.351512 -0.882904)
			(stroke
				(width 0.1)
				(type default)
			)
			(layer "F.SilkS")
		)
		(fp_line
			(start 12.291568 -0.882904)
			(end 12.351512 -0.882904)
			(stroke
				(width 0.1)
				(type default)
			)
			(layer "F.SilkS")
		)
		(fp_line
			(start 12.291568 -0.882904)
			(end 13.40993 -1.9558)
			(stroke
				(width 0.1)
				(type default)
			)
			(layer "F.SilkS")
		)
		(fp_line
			(start 12.291568 -0.882904)
			(end 13.40993 -1.9558)
			(stroke
				(width 0.1)
				(type default)
			)
			(layer "F.SilkS")
		)
		(fp_line
			(start 12.335002 -2.251964)
			(end 12.323064 -2.182622)
			(stroke
				(width 0.1)
				(type default)
			)
			(layer "F.SilkS")
		)
		(fp_line
			(start 12.335002 -2.251964)
			(end 12.323064 -2.182622)
			(stroke
				(width 0.1)
				(type default)
			)
			(layer "F.SilkS")
		)
		(fp_line
			(start 12.337542 -5.255514)
			(end 11.246358 -4.208526)
			(stroke
				(width 0.1)
				(type default)
			)
			(layer "F.SilkS")
		)
		(fp_line
			(start 12.337542 -5.255514)
			(end 11.246358 -4.208526)
			(stroke
				(width 0.1)
				(type default)
			)
			(layer "F.SilkS")
		)
		(fp_line
			(start 12.347194 -2.321306)
			(end 12.335002 -2.251964)
			(stroke
				(width 0.1)
				(type default)
			)
			(layer "F.SilkS")
		)
		(fp_line
			(start 12.347194 -2.321306)
			(end 12.335002 -2.251964)
			(stroke
				(width 0.1)
				(type default)
			)
			(layer "F.SilkS")
		)
		(fp_line
			(start 12.351512 -0.882904)
			(end 12.41171 -0.882904)
			(stroke
				(width 0.1)
				(type default)
			)
			(layer "F.SilkS")
		)
		(fp_line
			(start 12.351512 -0.882904)
			(end 12.41171 -0.882904)
			(stroke
				(width 0.1)
				(type default)
			)
			(layer "F.SilkS")
		)
		(fp_line
			(start 12.351512 -0.882904)
			(end 13.397992 -1.886458)
			(stroke
				(width 0.1)
				(type default)
			)
			(layer "F.SilkS")
		)
		(fp_line
			(start 12.351512 -0.882904)
			(end 13.397992 -1.886458)
			(stroke
				(width 0.1)
				(type default)
			)
			(layer "F.SilkS")
		)
		(fp_line
			(start 12.359386 -2.390902)
			(end 12.347194 -2.321306)
			(stroke
				(width 0.1)
				(type default)
			)
			(layer "F.SilkS")
		)
		(fp_line
			(start 12.359386 -2.390902)
			(end 12.347194 -2.321306)
			(stroke
				(width 0.1)
				(type default)
			)
			(layer "F.SilkS")
		)
		(fp_line
			(start 12.371578 -2.460244)
			(end 12.359386 -2.390902)
			(stroke
				(width 0.1)
				(type default)
			)
			(layer "F.SilkS")
		)
		(fp_line
			(start 12.371578 -2.460244)
			(end 12.359386 -2.390902)
			(stroke
				(width 0.1)
				(type default)
			)
			(layer "F.SilkS")
		)
		(fp_line
			(start 12.38377 -2.529586)
			(end 12.371578 -2.460244)
			(stroke
				(width 0.1)
				(type default)
			)
			(layer "F.SilkS")
		)
		(fp_line
			(start 12.38377 -2.529586)
			(end 12.371578 -2.460244)
			(stroke
				(width 0.1)
				(type default)
			)
			(layer "F.SilkS")
		)
		(fp_line
			(start 12.393676 -5.251704)
			(end 11.336782 -4.237736)
			(stroke
				(width 0.1)
				(type default)
			)
			(layer "F.SilkS")
		)
		(fp_line
			(start 12.393676 -5.251704)
			(end 11.336782 -4.237736)
			(stroke
				(width 0.1)
				(type default)
			)
			(layer "F.SilkS")
		)
		(fp_line
			(start 12.395962 -2.598928)
			(end 12.38377 -2.529586)
			(stroke
				(width 0.1)
				(type default)
			)
			(layer "F.SilkS")
		)
		(fp_line
			(start 12.395962 -2.598928)
			(end 12.38377 -2.529586)
			(stroke
				(width 0.1)
				(type default)
			)
			(layer "F.SilkS")
		)
		(fp_line
			(start 12.401804 -3.64363)
			(end 11.574526 -2.849626)
			(stroke
				(width 0.1)
				(type default)
			)
			(layer "F.SilkS")
		)
		(fp_line
			(start 12.401804 -3.64363)
			(end 11.574526 -2.849626)
			(stroke
				(width 0.1)
				(type default)
			)
			(layer "F.SilkS")
		)
		(fp_line
			(start 12.408154 -2.668524)
			(end 12.395962 -2.598928)
			(stroke
				(width 0.1)
				(type default)
			)
			(layer "F.SilkS")
		)
		(fp_line
			(start 12.408154 -2.668524)
			(end 12.395962 -2.598928)
			(stroke
				(width 0.1)
				(type default)
			)
			(layer "F.SilkS")
		)
		(fp_line
			(start 12.41171 -0.882904)
			(end 12.471908 -0.882904)
			(stroke
				(width 0.1)
				(type default)
			)
			(layer "F.SilkS")
		)
		(fp_line
			(start 12.41171 -0.882904)
			(end 12.471908 -0.882904)
			(stroke
				(width 0.1)
				(type default)
			)
			(layer "F.SilkS")
		)
		(fp_line
			(start 12.41171 -0.882904)
			(end 13.385546 -1.817116)
			(stroke
				(width 0.1)
				(type default)
			)
			(layer "F.SilkS")
		)
		(fp_line
			(start 12.41171 -0.882904)
			(end 13.385546 -1.817116)
			(stroke
				(width 0.1)
				(type default)
			)
			(layer "F.SilkS")
		)
		(fp_line
			(start 12.445238 -3.62712)
			(end 11.643614 -2.858262)
			(stroke
				(width 0.1)
				(type default)
			)
			(layer "F.SilkS")
		)
		(fp_line
			(start 12.445238 -3.62712)
			(end 11.643614 -2.858262)
			(stroke
				(width 0.1)
				(type default)
			)
			(layer "F.SilkS")
		)
		(fp_line
			(start 12.44981 -5.24764)
			(end 11.421364 -4.261104)
			(stroke
				(width 0.1)
				(type default)
			)
			(layer "F.SilkS")
		)
		(fp_line
			(start 12.44981 -5.24764)
			(end 11.421364 -4.261104)
			(stroke
				(width 0.1)
				(type default)
			)
			(layer "F.SilkS")
		)
		(fp_line
			(start 12.471908 -0.882904)
			(end 12.53236 -0.882904)
			(stroke
				(width 0.1)
				(type default)
			)
			(layer "F.SilkS")
		)
		(fp_line
			(start 12.471908 -0.882904)
			(end 12.53236 -0.882904)
			(stroke
				(width 0.1)
				(type default)
			)
			(layer "F.SilkS")
		)
		(fp_line
			(start 12.471908 -0.882904)
			(end 13.373354 -1.74752)
			(stroke
				(width 0.1)
				(type default)
			)
			(layer "F.SilkS")
		)
		(fp_line
			(start 12.471908 -0.882904)
			(end 13.373354 -1.74752)
			(stroke
				(width 0.1)
				(type default)
			)
			(layer "F.SilkS")
		)
		(fp_line
			(start 12.485624 -3.608324)
			(end 11.704574 -2.859278)
			(stroke
				(width 0.1)
				(type default)
			)
			(layer "F.SilkS")
		)
		(fp_line
			(start 12.485624 -3.608324)
			(end 11.704574 -2.859278)
			(stroke
				(width 0.1)
				(type default)
			)
			(layer "F.SilkS")
		)
		(fp_line
			(start 12.506198 -5.24383)
			(end 11.499596 -4.278376)
			(stroke
				(width 0.1)
				(type default)
			)
			(layer "F.SilkS")
		)
		(fp_line
			(start 12.506198 -5.24383)
			(end 11.499596 -4.278376)
			(stroke
				(width 0.1)
				(type default)
			)
			(layer "F.SilkS")
		)
		(fp_line
			(start 12.52601 -3.589274)
			(end 11.763502 -2.858008)
			(stroke
				(width 0.1)
				(type default)
			)
			(layer "F.SilkS")
		)
		(fp_line
			(start 12.52601 -3.589274)
			(end 11.763502 -2.858008)
			(stroke
				(width 0.1)
				(type default)
			)
			(layer "F.SilkS")
		)
		(fp_line
			(start 12.53236 -0.882904)
			(end 12.592558 -0.882904)
			(stroke
				(width 0.1)
				(type default)
			)
			(layer "F.SilkS")
		)
		(fp_line
			(start 12.53236 -0.882904)
			(end 12.592558 -0.882904)
			(stroke
				(width 0.1)
				(type default)
			)
			(layer "F.SilkS")
		)
		(fp_line
			(start 12.53236 -0.882904)
			(end 13.361416 -1.678178)
			(stroke
				(width 0.1)
				(type default)
			)
			(layer "F.SilkS")
		)
		(fp_line
			(start 12.53236 -0.882904)
			(end 13.361416 -1.678178)
			(stroke
				(width 0.1)
				(type default)
			)
			(layer "F.SilkS")
		)
		(fp_line
			(start 12.562078 -5.24002)
			(end 11.575542 -4.293616)
			(stroke
				(width 0.1)
				(type default)
			)
			(layer "F.SilkS")
		)
		(fp_line
			(start 12.562078 -5.24002)
			(end 11.575542 -4.293616)
			(stroke
				(width 0.1)
				(type default)
			)
			(layer "F.SilkS")
		)
		(fp_line
			(start 12.590018 -3.708654)
			(end 12.57808 -3.639312)
			(stroke
				(width 0.1)
				(type default)
			)
			(layer "F.SilkS")
		)
		(fp_line
			(start 12.590018 -3.708654)
			(end 12.57808 -3.639312)
			(stroke
				(width 0.1)
				(type default)
			)
			(layer "F.SilkS")
		)
		(fp_line
			(start 12.592558 -0.882904)
			(end 12.652502 -0.882904)
			(stroke
				(width 0.1)
				(type default)
			)
			(layer "F.SilkS")
		)
		(fp_line
			(start 12.592558 -0.882904)
			(end 12.652502 -0.882904)
			(stroke
				(width 0.1)
				(type default)
			)
			(layer "F.SilkS")
		)
		(fp_line
			(start 12.592558 -0.882904)
			(end 13.34897 -1.608836)
			(stroke
				(width 0.1)
				(type default)
			)
			(layer "F.SilkS")
		)
		(fp_line
			(start 12.592558 -0.882904)
			(end 13.34897 -1.608836)
			(stroke
				(width 0.1)
				(type default)
			)
			(layer "F.SilkS")
		)
		(fp_line
			(start 12.601956 -3.777996)
			(end 12.590018 -3.708654)
			(stroke
				(width 0.1)
				(type default)
			)
			(layer "F.SilkS")
		)
		(fp_line
			(start 12.601956 -3.777996)
			(end 12.590018 -3.708654)
			(stroke
				(width 0.1)
				(type default)
			)
			(layer "F.SilkS")
		)
		(fp_line
			(start 12.618212 -5.23621)
			(end 11.6459 -4.303268)
			(stroke
				(width 0.1)
				(type default)
			)
			(layer "F.SilkS")
		)
		(fp_line
			(start 12.618212 -5.23621)
			(end 11.6459 -4.303268)
			(stroke
				(width 0.1)
				(type default)
			)
			(layer "F.SilkS")
		)
		(fp_line
			(start 12.652502 -0.882904)
			(end 12.7127 -0.882904)
			(stroke
				(width 0.1)
				(type default)
			)
			(layer "F.SilkS")
		)
		(fp_line
			(start 12.652502 -0.882904)
			(end 12.7127 -0.882904)
			(stroke
				(width 0.1)
				(type default)
			)
			(layer "F.SilkS")
		)
		(fp_line
			(start 12.652502 -0.882904)
			(end 13.337286 -1.539494)
			(stroke
				(width 0.1)
				(type default)
			)
			(layer "F.SilkS")
		)
		(fp_line
			(start 12.652502 -0.882904)
			(end 13.337286 -1.539494)
			(stroke
				(width 0.1)
				(type default)
			)
			(layer "F.SilkS")
		)
		(fp_line
			(start 12.666726 -5.225034)
			(end 11.715242 -4.312412)
			(stroke
				(width 0.1)
				(type default)
			)
			(layer "F.SilkS")
		)
		(fp_line
			(start 12.666726 -5.225034)
			(end 11.715242 -4.312412)
			(stroke
				(width 0.1)
				(type default)
			)
			(layer "F.SilkS")
		)
		(fp_line
			(start 12.7127 -0.882904)
			(end 12.772898 -0.882904)
			(stroke
				(width 0.1)
				(type default)
			)
			(layer "F.SilkS")
		)
		(fp_line
			(start 12.7127 -0.882904)
			(end 12.772898 -0.882904)
			(stroke
				(width 0.1)
				(type default)
			)
			(layer "F.SilkS")
		)
		(fp_line
			(start 12.7127 -0.882904)
			(end 13.32484 -1.470152)
			(stroke
				(width 0.1)
				(type default)
			)
			(layer "F.SilkS")
		)
		(fp_line
			(start 12.7127 -0.882904)
			(end 13.32484 -1.470152)
			(stroke
				(width 0.1)
				(type default)
			)
			(layer "F.SilkS")
		)
		(fp_line
			(start 12.715494 -5.214112)
			(end 11.78179 -4.318254)
			(stroke
				(width 0.1)
				(type default)
			)
			(layer "F.SilkS")
		)
		(fp_line
			(start 12.715494 -5.214112)
			(end 11.78179 -4.318254)
			(stroke
				(width 0.1)
				(type default)
			)
			(layer "F.SilkS")
		)
		(fp_line
			(start 12.764008 -5.202936)
			(end 11.846306 -4.322572)
			(stroke
				(width 0.1)
				(type default)
			)
			(layer "F.SilkS")
		)
		(fp_line
			(start 12.764008 -5.202936)
			(end 11.846306 -4.322572)
			(stroke
				(width 0.1)
				(type default)
			)
			(layer "F.SilkS")
		)
		(fp_line
			(start 12.772898 -0.882904)
			(end 12.832842 -0.882904)
			(stroke
				(width 0.1)
				(type default)
			)
			(layer "F.SilkS")
		)
		(fp_line
			(start 12.772898 -0.882904)
			(end 12.832842 -0.882904)
			(stroke
				(width 0.1)
				(type default)
			)
			(layer "F.SilkS")
		)
		(fp_line
			(start 12.772898 -0.882904)
			(end 13.312394 -1.400556)
			(stroke
				(width 0.1)
				(type default)
			)
			(layer "F.SilkS")
		)
		(fp_line
			(start 12.772898 -0.882904)
			(end 13.312394 -1.400556)
			(stroke
				(width 0.1)
				(type default)
			)
			(layer "F.SilkS")
		)
		(fp_line
			(start 12.812522 -5.19176)
			(end 11.910568 -4.326636)
			(stroke
				(width 0.1)
				(type default)
			)
			(layer "F.SilkS")
		)
		(fp_line
			(start 12.812522 -5.19176)
			(end 11.910568 -4.326636)
			(stroke
				(width 0.1)
				(type default)
			)
			(layer "F.SilkS")
		)
		(fp_line
			(start 12.832842 -0.882904)
			(end 12.89304 -0.882904)
			(stroke
				(width 0.1)
				(type default)
			)
			(layer "F.SilkS")
		)
		(fp_line
			(start 12.832842 -0.882904)
			(end 12.89304 -0.882904)
			(stroke
				(width 0.1)
				(type default)
			)
			(layer "F.SilkS")
		)
		(fp_line
			(start 12.832842 -0.882904)
			(end 13.30071 -1.331468)
			(stroke
				(width 0.1)
				(type default)
			)
			(layer "F.SilkS")
		)
		(fp_line
			(start 12.832842 -0.882904)
			(end 13.30071 -1.331468)
			(stroke
				(width 0.1)
				(type default)
			)
			(layer "F.SilkS")
		)
		(fp_line
			(start 12.861036 -5.180584)
			(end 11.972036 -4.327906)
			(stroke
				(width 0.1)
				(type default)
			)
			(layer "F.SilkS")
		)
		(fp_line
			(start 12.861036 -5.180584)
			(end 11.972036 -4.327906)
			(stroke
				(width 0.1)
				(type default)
			)
			(layer "F.SilkS")
		)
		(fp_line
			(start 12.89304 -0.882904)
			(end 12.953238 -0.882904)
			(stroke
				(width 0.1)
				(type default)
			)
			(layer "F.SilkS")
		)
		(fp_line
			(start 12.89304 -0.882904)
			(end 12.953238 -0.882904)
			(stroke
				(width 0.1)
				(type default)
			)
			(layer "F.SilkS")
		)
		(fp_line
			(start 12.89304 -0.882904)
			(end 13.288264 -1.262126)
			(stroke
				(width 0.1)
				(type default)
			)
			(layer "F.SilkS")
		)
		(fp_line
			(start 12.89304 -0.882904)
			(end 13.288264 -1.262126)
			(stroke
				(width 0.1)
				(type default)
			)
			(layer "F.SilkS")
		)
		(fp_line
			(start 12.909804 -5.169408)
			(end 12.033758 -4.328922)
			(stroke
				(width 0.1)
				(type default)
			)
			(layer "F.SilkS")
		)
		(fp_line
			(start 12.909804 -5.169408)
			(end 12.033758 -4.328922)
			(stroke
				(width 0.1)
				(type default)
			)
			(layer "F.SilkS")
		)
		(fp_line
			(start 12.953238 -0.882904)
			(end 13.01369 -0.882904)
			(stroke
				(width 0.1)
				(type default)
			)
			(layer "F.SilkS")
		)
		(fp_line
			(start 12.953238 -0.882904)
			(end 13.01369 -0.882904)
			(stroke
				(width 0.1)
				(type default)
			)
			(layer "F.SilkS")
		)
		(fp_line
			(start 12.953238 -0.882904)
			(end 13.275818 -1.19253)
			(stroke
				(width 0.1)
				(type default)
			)
			(layer "F.SilkS")
		)
		(fp_line
			(start 12.953238 -0.882904)
			(end 13.275818 -1.19253)
			(stroke
				(width 0.1)
				(type default)
			)
			(layer "F.SilkS")
		)
		(fp_line
			(start 12.955778 -5.155946)
			(end 12.09421 -4.32943)
			(stroke
				(width 0.1)
				(type default)
			)
			(layer "F.SilkS")
		)
		(fp_line
			(start 12.955778 -5.155946)
			(end 12.09421 -4.32943)
			(stroke
				(width 0.1)
				(type default)
			)
			(layer "F.SilkS")
		)
		(fp_line
			(start 12.996926 -5.137658)
			(end 12.149836 -4.325112)
			(stroke
				(width 0.1)
				(type default)
			)
			(layer "F.SilkS")
		)
		(fp_line
			(start 12.996926 -5.137658)
			(end 12.149836 -4.325112)
			(stroke
				(width 0.1)
				(type default)
			)
			(layer "F.SilkS")
		)
		(fp_line
			(start 13.01369 -0.882904)
			(end 13.073634 -0.882904)
			(stroke
				(width 0.1)
				(type default)
			)
			(layer "F.SilkS")
		)
		(fp_line
			(start 13.01369 -0.882904)
			(end 13.073634 -0.882904)
			(stroke
				(width 0.1)
				(type default)
			)
			(layer "F.SilkS")
		)
		(fp_line
			(start 13.01369 -0.882904)
			(end 13.264134 -1.123188)
			(stroke
				(width 0.1)
				(type default)
			)
			(layer "F.SilkS")
		)
		(fp_line
			(start 13.01369 -0.882904)
			(end 13.264134 -1.123188)
			(stroke
				(width 0.1)
				(type default)
			)
			(layer "F.SilkS")
		)
		(fp_line
			(start 13.038074 -5.11937)
			(end 12.205462 -4.320794)
			(stroke
				(width 0.1)
				(type default)
			)
			(layer "F.SilkS")
		)
		(fp_line
			(start 13.038074 -5.11937)
			(end 12.205462 -4.320794)
			(stroke
				(width 0.1)
				(type default)
			)
			(layer "F.SilkS")
		)
		(fp_line
			(start 13.073634 -0.882904)
			(end 13.133578 -0.882904)
			(stroke
				(width 0.1)
				(type default)
			)
			(layer "F.SilkS")
		)
		(fp_line
			(start 13.073634 -0.882904)
			(end 13.133578 -0.882904)
			(stroke
				(width 0.1)
				(type default)
			)
			(layer "F.SilkS")
		)
		(fp_line
			(start 13.073634 -0.882904)
			(end 13.251942 -1.053846)
			(stroke
				(width 0.1)
				(type default)
			)
			(layer "F.SilkS")
		)
		(fp_line
			(start 13.073634 -0.882904)
			(end 13.251942 -1.053846)
			(stroke
				(width 0.1)
				(type default)
			)
			(layer "F.SilkS")
		)
		(fp_line
			(start 13.079222 -5.101336)
			(end 12.256008 -4.311396)
			(stroke
				(width 0.1)
				(type default)
			)
			(layer "F.SilkS")
		)
		(fp_line
			(start 13.079222 -5.101336)
			(end 12.256008 -4.311396)
			(stroke
				(width 0.1)
				(type default)
			)
			(layer "F.SilkS")
		)
		(fp_line
			(start 13.120116 -5.083048)
			(end 12.302998 -4.29895)
			(stroke
				(width 0.1)
				(type default)
			)
			(layer "F.SilkS")
		)
		(fp_line
			(start 13.120116 -5.083048)
			(end 12.302998 -4.29895)
			(stroke
				(width 0.1)
				(type default)
			)
			(layer "F.SilkS")
		)
		(fp_line
			(start 13.133578 -0.882904)
			(end 13.19403 -0.882904)
			(stroke
				(width 0.1)
				(type default)
			)
			(layer "F.SilkS")
		)
		(fp_line
			(start 13.133578 -0.882904)
			(end 13.19403 -0.882904)
			(stroke
				(width 0.1)
				(type default)
			)
			(layer "F.SilkS")
		)
		(fp_line
			(start 13.133578 -0.882904)
			(end 13.23975 -0.984504)
			(stroke
				(width 0.1)
				(type default)
			)
			(layer "F.SilkS")
		)
		(fp_line
			(start 13.133578 -0.882904)
			(end 13.23975 -0.984504)
			(stroke
				(width 0.1)
				(type default)
			)
			(layer "F.SilkS")
		)
		(fp_line
			(start 13.161518 -5.06476)
			(end 12.34948 -4.285742)
			(stroke
				(width 0.1)
				(type default)
			)
			(layer "F.SilkS")
		)
		(fp_line
			(start 13.161518 -5.06476)
			(end 12.34948 -4.285742)
			(stroke
				(width 0.1)
				(type default)
			)
			(layer "F.SilkS")
		)
		(fp_line
			(start 13.19403 -0.882904)
			(end 13.22197 -0.882904)
			(stroke
				(width 0.1)
				(type default)
			)
			(layer "F.SilkS")
		)
		(fp_line
			(start 13.19403 -0.882904)
			(end 13.22197 -0.882904)
			(stroke
				(width 0.1)
				(type default)
			)
			(layer "F.SilkS")
		)
		(fp_line
			(start 13.19403 -0.882904)
			(end 13.227812 -0.914908)
			(stroke
				(width 0.1)
				(type default)
			)
			(layer "F.SilkS")
		)
		(fp_line
			(start 13.19403 -0.882904)
			(end 13.227812 -0.914908)
			(stroke
				(width 0.1)
				(type default)
			)
			(layer "F.SilkS")
		)
		(fp_line
			(start 13.20292 -5.046472)
			(end 12.388596 -4.265422)
			(stroke
				(width 0.1)
				(type default)
			)
			(layer "F.SilkS")
		)
		(fp_line
			(start 13.20292 -5.046472)
			(end 12.388596 -4.265422)
			(stroke
				(width 0.1)
				(type default)
			)
			(layer "F.SilkS")
		)
		(fp_line
			(start 13.22197 -0.882904)
			(end 13.227812 -0.914908)
			(stroke
				(width 0.1)
				(type default)
			)
			(layer "F.SilkS")
		)
		(fp_line
			(start 13.22197 -0.882904)
			(end 13.227812 -0.914908)
			(stroke
				(width 0.1)
				(type default)
			)
			(layer "F.SilkS")
		)
		(fp_line
			(start 13.227812 -0.914908)
			(end 13.23975 -0.984504)
			(stroke
				(width 0.1)
				(type default)
			)
			(layer "F.SilkS")
		)
		(fp_line
			(start 13.227812 -0.914908)
			(end 13.23975 -0.984504)
			(stroke
				(width 0.1)
				(type default)
			)
			(layer "F.SilkS")
		)
		(fp_line
			(start 13.238988 -5.023612)
			(end 12.427458 -4.245102)
			(stroke
				(width 0.1)
				(type default)
			)
			(layer "F.SilkS")
		)
		(fp_line
			(start 13.238988 -5.023612)
			(end 12.427458 -4.245102)
			(stroke
				(width 0.1)
				(type default)
			)
			(layer "F.SilkS")
		)
		(fp_line
			(start 13.23975 -0.984504)
			(end 13.251942 -1.053846)
			(stroke
				(width 0.1)
				(type default)
			)
			(layer "F.SilkS")
		)
		(fp_line
			(start 13.23975 -0.984504)
			(end 13.251942 -1.053846)
			(stroke
				(width 0.1)
				(type default)
			)
			(layer "F.SilkS")
		)
		(fp_line
			(start 13.251942 -1.053846)
			(end 13.264134 -1.123188)
			(stroke
				(width 0.1)
				(type default)
			)
			(layer "F.SilkS")
		)
		(fp_line
			(start 13.251942 -1.053846)
			(end 13.264134 -1.123188)
			(stroke
				(width 0.1)
				(type default)
			)
			(layer "F.SilkS")
		)
		(fp_line
			(start 13.264134 -1.123188)
			(end 13.275818 -1.19253)
			(stroke
				(width 0.1)
				(type default)
			)
			(layer "F.SilkS")
		)
		(fp_line
			(start 13.264134 -1.123188)
			(end 13.275818 -1.19253)
			(stroke
				(width 0.1)
				(type default)
			)
			(layer "F.SilkS")
		)
		(fp_line
			(start 13.272516 -4.998212)
			(end 12.461748 -4.22021)
			(stroke
				(width 0.1)
				(type default)
			)
			(layer "F.SilkS")
		)
		(fp_line
			(start 13.272516 -4.998212)
			(end 12.461748 -4.22021)
			(stroke
				(width 0.1)
				(type default)
			)
			(layer "F.SilkS")
		)
		(fp_line
			(start 13.275818 -1.19253)
			(end 13.288264 -1.262126)
			(stroke
				(width 0.1)
				(type default)
			)
			(layer "F.SilkS")
		)
		(fp_line
			(start 13.275818 -1.19253)
			(end 13.288264 -1.262126)
			(stroke
				(width 0.1)
				(type default)
			)
			(layer "F.SilkS")
		)
		(fp_line
			(start 13.288264 -1.262126)
			(end 13.30071 -1.331468)
			(stroke
				(width 0.1)
				(type default)
			)
			(layer "F.SilkS")
		)
		(fp_line
			(start 13.288264 -1.262126)
			(end 13.30071 -1.331468)
			(stroke
				(width 0.1)
				(type default)
			)
			(layer "F.SilkS")
		)
		(fp_line
			(start 13.30071 -1.331468)
			(end 13.312394 -1.400556)
			(stroke
				(width 0.1)
				(type default)
			)
			(layer "F.SilkS")
		)
		(fp_line
			(start 13.30071 -1.331468)
			(end 13.312394 -1.400556)
			(stroke
				(width 0.1)
				(type default)
			)
			(layer "F.SilkS")
		)
		(fp_line
			(start 13.306298 -4.972812)
			(end 12.49299 -4.192524)
			(stroke
				(width 0.1)
				(type default)
			)
			(layer "F.SilkS")
		)
		(fp_line
			(start 13.306298 -4.972812)
			(end 12.49299 -4.192524)
			(stroke
				(width 0.1)
				(type default)
			)
			(layer "F.SilkS")
		)
		(fp_line
			(start 13.312394 -1.400556)
			(end 13.32484 -1.470152)
			(stroke
				(width 0.1)
				(type default)
			)
			(layer "F.SilkS")
		)
		(fp_line
			(start 13.312394 -1.400556)
			(end 13.32484 -1.470152)
			(stroke
				(width 0.1)
				(type default)
			)
			(layer "F.SilkS")
		)
		(fp_line
			(start 13.32484 -1.470152)
			(end 13.337286 -1.539494)
			(stroke
				(width 0.1)
				(type default)
			)
			(layer "F.SilkS")
		)
		(fp_line
			(start 13.32484 -1.470152)
			(end 13.337286 -1.539494)
			(stroke
				(width 0.1)
				(type default)
			)
			(layer "F.SilkS")
		)
		(fp_line
			(start 13.337286 -1.539494)
			(end 13.34897 -1.608836)
			(stroke
				(width 0.1)
				(type default)
			)
			(layer "F.SilkS")
		)
		(fp_line
			(start 13.337286 -1.539494)
			(end 13.34897 -1.608836)
			(stroke
				(width 0.1)
				(type default)
			)
			(layer "F.SilkS")
		)
		(fp_line
			(start 13.34008 -4.947412)
			(end 12.522454 -4.16306)
			(stroke
				(width 0.1)
				(type default)
			)
			(layer "F.SilkS")
		)
		(fp_line
			(start 13.34008 -4.947412)
			(end 12.522454 -4.16306)
			(stroke
				(width 0.1)
				(type default)
			)
			(layer "F.SilkS")
		)
		(fp_line
			(start 13.34897 -1.608836)
			(end 13.361416 -1.678178)
			(stroke
				(width 0.1)
				(type default)
			)
			(layer "F.SilkS")
		)
		(fp_line
			(start 13.34897 -1.608836)
			(end 13.361416 -1.678178)
			(stroke
				(width 0.1)
				(type default)
			)
			(layer "F.SilkS")
		)
		(fp_line
			(start 13.361416 -1.678178)
			(end 13.373354 -1.74752)
			(stroke
				(width 0.1)
				(type default)
			)
			(layer "F.SilkS")
		)
		(fp_line
			(start 13.361416 -1.678178)
			(end 13.373354 -1.74752)
			(stroke
				(width 0.1)
				(type default)
			)
			(layer "F.SilkS")
		)
		(fp_line
			(start 13.373354 -1.74752)
			(end 13.385546 -1.817116)
			(stroke
				(width 0.1)
				(type default)
			)
			(layer "F.SilkS")
		)
		(fp_line
			(start 13.373354 -1.74752)
			(end 13.385546 -1.817116)
			(stroke
				(width 0.1)
				(type default)
			)
			(layer "F.SilkS")
		)
		(fp_line
			(start 13.373862 -4.922012)
			(end 12.545822 -4.127754)
			(stroke
				(width 0.1)
				(type default)
			)
			(layer "F.SilkS")
		)
		(fp_line
			(start 13.373862 -4.922012)
			(end 12.545822 -4.127754)
			(stroke
				(width 0.1)
				(type default)
			)
			(layer "F.SilkS")
		)
		(fp_line
			(start 13.385546 -1.817116)
			(end 13.397992 -1.886458)
			(stroke
				(width 0.1)
				(type default)
			)
			(layer "F.SilkS")
		)
		(fp_line
			(start 13.385546 -1.817116)
			(end 13.397992 -1.886458)
			(stroke
				(width 0.1)
				(type default)
			)
			(layer "F.SilkS")
		)
		(fp_line
			(start 13.397992 -1.886458)
			(end 13.40993 -1.9558)
			(stroke
				(width 0.1)
				(type default)
			)
			(layer "F.SilkS")
		)
		(fp_line
			(start 13.397992 -1.886458)
			(end 13.40993 -1.9558)
			(stroke
				(width 0.1)
				(type default)
			)
			(layer "F.SilkS")
		)
		(fp_line
			(start 13.407136 -4.896358)
			(end 12.568936 -4.092194)
			(stroke
				(width 0.1)
				(type default)
			)
			(layer "F.SilkS")
		)
		(fp_line
			(start 13.407136 -4.896358)
			(end 12.568936 -4.092194)
			(stroke
				(width 0.1)
				(type default)
			)
			(layer "F.SilkS")
		)
		(fp_line
			(start 13.40993 -1.9558)
			(end 13.422122 -2.025396)
			(stroke
				(width 0.1)
				(type default)
			)
			(layer "F.SilkS")
		)
		(fp_line
			(start 13.40993 -1.9558)
			(end 13.422122 -2.025396)
			(stroke
				(width 0.1)
				(type default)
			)
			(layer "F.SilkS")
		)
		(fp_line
			(start 13.422122 -2.025396)
			(end 13.434314 -2.094738)
			(stroke
				(width 0.1)
				(type default)
			)
			(layer "F.SilkS")
		)
		(fp_line
			(start 13.422122 -2.025396)
			(end 13.434314 -2.094738)
			(stroke
				(width 0.1)
				(type default)
			)
			(layer "F.SilkS")
		)
		(fp_line
			(start 13.434314 -2.094738)
			(end 13.446506 -2.163826)
			(stroke
				(width 0.1)
				(type default)
			)
			(layer "F.SilkS")
		)
		(fp_line
			(start 13.434314 -2.094738)
			(end 13.446506 -2.163826)
			(stroke
				(width 0.1)
				(type default)
			)
			(layer "F.SilkS")
		)
		(fp_line
			(start 13.440664 -4.871212)
			(end 12.58443 -4.049522)
			(stroke
				(width 0.1)
				(type default)
			)
			(layer "F.SilkS")
		)
		(fp_line
			(start 13.440664 -4.871212)
			(end 12.58443 -4.049522)
			(stroke
				(width 0.1)
				(type default)
			)
			(layer "F.SilkS")
		)
		(fp_line
			(start 13.446506 -2.163826)
			(end 13.458444 -2.233422)
			(stroke
				(width 0.1)
				(type default)
			)
			(layer "F.SilkS")
		)
		(fp_line
			(start 13.446506 -2.163826)
			(end 13.458444 -2.233422)
			(stroke
				(width 0.1)
				(type default)
			)
			(layer "F.SilkS")
		)
		(fp_line
			(start 13.458444 -2.233422)
			(end 13.47089 -2.302764)
			(stroke
				(width 0.1)
				(type default)
			)
			(layer "F.SilkS")
		)
		(fp_line
			(start 13.458444 -2.233422)
			(end 13.47089 -2.302764)
			(stroke
				(width 0.1)
				(type default)
			)
			(layer "F.SilkS")
		)
		(fp_line
			(start 13.466826 -4.837938)
			(end 12.599162 -4.005834)
			(stroke
				(width 0.1)
				(type default)
			)
			(layer "F.SilkS")
		)
		(fp_line
			(start 13.466826 -4.837938)
			(end 12.599162 -4.005834)
			(stroke
				(width 0.1)
				(type default)
			)
			(layer "F.SilkS")
		)
		(fp_line
			(start 13.47089 -2.302764)
			(end 13.483082 -2.372106)
			(stroke
				(width 0.1)
				(type default)
			)
			(layer "F.SilkS")
		)
		(fp_line
			(start 13.47089 -2.302764)
			(end 13.483082 -2.372106)
			(stroke
				(width 0.1)
				(type default)
			)
			(layer "F.SilkS")
		)
		(fp_line
			(start 13.483082 -2.372106)
			(end 13.49502 -2.441448)
			(stroke
				(width 0.1)
				(type default)
			)
			(layer "F.SilkS")
		)
		(fp_line
			(start 13.483082 -2.372106)
			(end 13.49502 -2.441448)
			(stroke
				(width 0.1)
				(type default)
			)
			(layer "F.SilkS")
		)
		(fp_line
			(start 13.492226 -4.804918)
			(end 12.606782 -3.955288)
			(stroke
				(width 0.1)
				(type default)
			)
			(layer "F.SilkS")
		)
		(fp_line
			(start 13.492226 -4.804918)
			(end 12.606782 -3.955288)
			(stroke
				(width 0.1)
				(type default)
			)
			(layer "F.SilkS")
		)
		(fp_line
			(start 13.49502 -2.441448)
			(end 13.507466 -2.51079)
			(stroke
				(width 0.1)
				(type default)
			)
			(layer "F.SilkS")
		)
		(fp_line
			(start 13.49502 -2.441448)
			(end 13.507466 -2.51079)
			(stroke
				(width 0.1)
				(type default)
			)
			(layer "F.SilkS")
		)
		(fp_line
			(start 13.507466 -2.51079)
			(end 13.519404 -2.580386)
			(stroke
				(width 0.1)
				(type default)
			)
			(layer "F.SilkS")
		)
		(fp_line
			(start 13.507466 -2.51079)
			(end 13.519404 -2.580386)
			(stroke
				(width 0.1)
				(type default)
			)
			(layer "F.SilkS")
		)
		(fp_line
			(start 13.518134 -4.771898)
			(end 12.612116 -3.902964)
			(stroke
				(width 0.1)
				(type default)
			)
			(layer "F.SilkS")
		)
		(fp_line
			(start 13.518134 -4.771898)
			(end 12.612116 -3.902964)
			(stroke
				(width 0.1)
				(type default)
			)
			(layer "F.SilkS")
		)
		(fp_line
			(start 13.519404 -2.580386)
			(end 13.531596 -2.649728)
			(stroke
				(width 0.1)
				(type default)
			)
			(layer "F.SilkS")
		)
		(fp_line
			(start 13.519404 -2.580386)
			(end 13.531596 -2.649728)
			(stroke
				(width 0.1)
				(type default)
			)
			(layer "F.SilkS")
		)
		(fp_line
			(start 13.531596 -2.649728)
			(end 13.544042 -2.71907)
			(stroke
				(width 0.1)
				(type default)
			)
			(layer "F.SilkS")
		)
		(fp_line
			(start 13.531596 -2.649728)
			(end 13.544042 -2.71907)
			(stroke
				(width 0.1)
				(type default)
			)
			(layer "F.SilkS")
		)
		(fp_line
			(start 13.544042 -4.738878)
			(end 12.60856 -3.84175)
			(stroke
				(width 0.1)
				(type default)
			)
			(layer "F.SilkS")
		)
		(fp_line
			(start 13.544042 -4.738878)
			(end 12.60856 -3.84175)
			(stroke
				(width 0.1)
				(type default)
			)
			(layer "F.SilkS")
		)
		(fp_line
			(start 13.544042 -2.71907)
			(end 13.55598 -2.788412)
			(stroke
				(width 0.1)
				(type default)
			)
			(layer "F.SilkS")
		)
		(fp_line
			(start 13.544042 -2.71907)
			(end 13.55598 -2.788412)
			(stroke
				(width 0.1)
				(type default)
			)
			(layer "F.SilkS")
		)
		(fp_line
			(start 13.55598 -2.788412)
			(end 13.568172 -2.857754)
			(stroke
				(width 0.1)
				(type default)
			)
			(layer "F.SilkS")
		)
		(fp_line
			(start 13.55598 -2.788412)
			(end 13.568172 -2.857754)
			(stroke
				(width 0.1)
				(type default)
			)
			(layer "F.SilkS")
		)
		(fp_line
			(start 13.568172 -2.857754)
			(end 13.580364 -2.927096)
			(stroke
				(width 0.1)
				(type default)
			)
			(layer "F.SilkS")
		)
		(fp_line
			(start 13.568172 -2.857754)
			(end 13.580364 -2.927096)
			(stroke
				(width 0.1)
				(type default)
			)
			(layer "F.SilkS")
		)
		(fp_line
			(start 13.569442 -4.705858)
			(end 12.601956 -3.777996)
			(stroke
				(width 0.1)
				(type default)
			)
			(layer "F.SilkS")
		)
		(fp_line
			(start 13.569442 -4.705858)
			(end 12.601956 -3.777996)
			(stroke
				(width 0.1)
				(type default)
			)
			(layer "F.SilkS")
		)
		(fp_line
			(start 13.580364 -2.927096)
			(end 13.592556 -2.996692)
			(stroke
				(width 0.1)
				(type default)
			)
			(layer "F.SilkS")
		)
		(fp_line
			(start 13.580364 -2.927096)
			(end 13.592556 -2.996692)
			(stroke
				(width 0.1)
				(type default)
			)
			(layer "F.SilkS")
		)
		(fp_line
			(start 13.592556 -2.996692)
			(end 13.604494 -3.06578)
			(stroke
				(width 0.1)
				(type default)
			)
			(layer "F.SilkS")
		)
		(fp_line
			(start 13.592556 -2.996692)
			(end 13.604494 -3.06578)
			(stroke
				(width 0.1)
				(type default)
			)
			(layer "F.SilkS")
		)
		(fp_line
			(start 13.59535 -4.672838)
			(end 12.590018 -3.708654)
			(stroke
				(width 0.1)
				(type default)
			)
			(layer "F.SilkS")
		)
		(fp_line
			(start 13.59535 -4.672838)
			(end 12.590018 -3.708654)
			(stroke
				(width 0.1)
				(type default)
			)
			(layer "F.SilkS")
		)
		(fp_line
			(start 13.604494 -3.06578)
			(end 13.61694 -3.135376)
			(stroke
				(width 0.1)
				(type default)
			)
			(layer "F.SilkS")
		)
		(fp_line
			(start 13.604494 -3.06578)
			(end 13.61694 -3.135376)
			(stroke
				(width 0.1)
				(type default)
			)
			(layer "F.SilkS")
		)
		(fp_line
			(start 13.616432 -4.635246)
			(end 12.57808 -3.639312)
			(stroke
				(width 0.1)
				(type default)
			)
			(layer "F.SilkS")
		)
		(fp_line
			(start 13.616432 -4.635246)
			(end 12.57808 -3.639312)
			(stroke
				(width 0.1)
				(type default)
			)
			(layer "F.SilkS")
		)
		(fp_line
			(start 13.61694 -3.135376)
			(end 13.629132 -3.204972)
			(stroke
				(width 0.1)
				(type default)
			)
			(layer "F.SilkS")
		)
		(fp_line
			(start 13.61694 -3.135376)
			(end 13.629132 -3.204972)
			(stroke
				(width 0.1)
				(type default)
			)
			(layer "F.SilkS")
		)
		(fp_line
			(start 13.629132 -3.204972)
			(end 13.64107 -3.27406)
			(stroke
				(width 0.1)
				(type default)
			)
			(layer "F.SilkS")
		)
		(fp_line
			(start 13.629132 -3.204972)
			(end 13.64107 -3.27406)
			(stroke
				(width 0.1)
				(type default)
			)
			(layer "F.SilkS")
		)
		(fp_line
			(start 13.633196 -4.593844)
			(end 11.82116 -2.855722)
			(stroke
				(width 0.1)
				(type default)
			)
			(layer "F.SilkS")
		)
		(fp_line
			(start 13.633196 -4.593844)
			(end 11.82116 -2.855722)
			(stroke
				(width 0.1)
				(type default)
			)
			(layer "F.SilkS")
		)
		(fp_line
			(start 13.64996 -4.552442)
			(end 11.877548 -2.851912)
			(stroke
				(width 0.1)
				(type default)
			)
			(layer "F.SilkS")
		)
		(fp_line
			(start 13.64996 -4.552442)
			(end 11.877548 -2.851912)
			(stroke
				(width 0.1)
				(type default)
			)
			(layer "F.SilkS")
		)
		(fp_line
			(start 13.653516 -3.343402)
			(end 13.64107 -3.27406)
			(stroke
				(width 0.1)
				(type default)
			)
			(layer "F.SilkS")
		)
		(fp_line
			(start 13.653516 -3.343402)
			(end 13.64107 -3.27406)
			(stroke
				(width 0.1)
				(type default)
			)
			(layer "F.SilkS")
		)
		(fp_line
			(start 13.665708 -3.412998)
			(end 10.943336 -0.801624)
			(stroke
				(width 0.1)
				(type default)
			)
			(layer "F.SilkS")
		)
		(fp_line
			(start 13.665708 -3.412998)
			(end 10.943336 -0.801624)
			(stroke
				(width 0.1)
				(type default)
			)
			(layer "F.SilkS")
		)
		(fp_line
			(start 13.665708 -3.412998)
			(end 13.653516 -3.343402)
			(stroke
				(width 0.1)
				(type default)
			)
			(layer "F.SilkS")
		)
		(fp_line
			(start 13.665708 -3.412998)
			(end 13.653516 -3.343402)
			(stroke
				(width 0.1)
				(type default)
			)
			(layer "F.SilkS")
		)
		(fp_line
			(start 13.667232 -4.51104)
			(end 11.93292 -2.84734)
			(stroke
				(width 0.1)
				(type default)
			)
			(layer "F.SilkS")
		)
		(fp_line
			(start 13.667232 -4.51104)
			(end 11.93292 -2.84734)
			(stroke
				(width 0.1)
				(type default)
			)
			(layer "F.SilkS")
		)
		(fp_line
			(start 13.677646 -3.48234)
			(end 12.323064 -2.182622)
			(stroke
				(width 0.1)
				(type default)
			)
			(layer "F.SilkS")
		)
		(fp_line
			(start 13.677646 -3.48234)
			(end 12.323064 -2.182622)
			(stroke
				(width 0.1)
				(type default)
			)
			(layer "F.SilkS")
		)
		(fp_line
			(start 13.677646 -3.48234)
			(end 13.665708 -3.412998)
			(stroke
				(width 0.1)
				(type default)
			)
			(layer "F.SilkS")
		)
		(fp_line
			(start 13.677646 -3.48234)
			(end 13.665708 -3.412998)
			(stroke
				(width 0.1)
				(type default)
			)
			(layer "F.SilkS")
		)
		(fp_line
			(start 13.684504 -4.469638)
			(end 11.986006 -2.840482)
			(stroke
				(width 0.1)
				(type default)
			)
			(layer "F.SilkS")
		)
		(fp_line
			(start 13.684504 -4.469638)
			(end 11.986006 -2.840482)
			(stroke
				(width 0.1)
				(type default)
			)
			(layer "F.SilkS")
		)
		(fp_line
			(start 13.690092 -3.551682)
			(end 12.335002 -2.251964)
			(stroke
				(width 0.1)
				(type default)
			)
			(layer "F.SilkS")
		)
		(fp_line
			(start 13.690092 -3.551682)
			(end 12.335002 -2.251964)
			(stroke
				(width 0.1)
				(type default)
			)
			(layer "F.SilkS")
		)
		(fp_line
			(start 13.690092 -3.551682)
			(end 13.677646 -3.48234)
			(stroke
				(width 0.1)
				(type default)
			)
			(layer "F.SilkS")
		)
		(fp_line
			(start 13.690092 -3.551682)
			(end 13.677646 -3.48234)
			(stroke
				(width 0.1)
				(type default)
			)
			(layer "F.SilkS")
		)
		(fp_line
			(start 13.701014 -4.42849)
			(end 12.037822 -2.832862)
			(stroke
				(width 0.1)
				(type default)
			)
			(layer "F.SilkS")
		)
		(fp_line
			(start 13.701014 -4.42849)
			(end 12.037822 -2.832862)
			(stroke
				(width 0.1)
				(type default)
			)
			(layer "F.SilkS")
		)
		(fp_line
			(start 13.70203 -3.621024)
			(end 12.347194 -2.321306)
			(stroke
				(width 0.1)
				(type default)
			)
			(layer "F.SilkS")
		)
		(fp_line
			(start 13.70203 -3.621024)
			(end 12.347194 -2.321306)
			(stroke
				(width 0.1)
				(type default)
			)
			(layer "F.SilkS")
		)
		(fp_line
			(start 13.70203 -3.621024)
			(end 13.690092 -3.551682)
			(stroke
				(width 0.1)
				(type default)
			)
			(layer "F.SilkS")
		)
		(fp_line
			(start 13.70203 -3.621024)
			(end 13.690092 -3.551682)
			(stroke
				(width 0.1)
				(type default)
			)
			(layer "F.SilkS")
		)
		(fp_line
			(start 13.714222 -3.690366)
			(end 12.359386 -2.390902)
			(stroke
				(width 0.1)
				(type default)
			)
			(layer "F.SilkS")
		)
		(fp_line
			(start 13.714222 -3.690366)
			(end 12.359386 -2.390902)
			(stroke
				(width 0.1)
				(type default)
			)
			(layer "F.SilkS")
		)
		(fp_line
			(start 13.714222 -3.690366)
			(end 13.70203 -3.621024)
			(stroke
				(width 0.1)
				(type default)
			)
			(layer "F.SilkS")
		)
		(fp_line
			(start 13.714222 -3.690366)
			(end 13.70203 -3.621024)
			(stroke
				(width 0.1)
				(type default)
			)
			(layer "F.SilkS")
		)
		(fp_line
			(start 13.715238 -4.383786)
			(end 12.087352 -2.822448)
			(stroke
				(width 0.1)
				(type default)
			)
			(layer "F.SilkS")
		)
		(fp_line
			(start 13.715238 -4.383786)
			(end 12.087352 -2.822448)
			(stroke
				(width 0.1)
				(type default)
			)
			(layer "F.SilkS")
		)
		(fp_line
			(start 13.722096 -4.332732)
			(end 12.135612 -2.810764)
			(stroke
				(width 0.1)
				(type default)
			)
			(layer "F.SilkS")
		)
		(fp_line
			(start 13.722096 -4.332732)
			(end 12.135612 -2.810764)
			(stroke
				(width 0.1)
				(type default)
			)
			(layer "F.SilkS")
		)
		(fp_line
			(start 13.72616 -3.759962)
			(end 12.371578 -2.460244)
			(stroke
				(width 0.1)
				(type default)
			)
			(layer "F.SilkS")
		)
		(fp_line
			(start 13.72616 -3.759962)
			(end 12.371578 -2.460244)
			(stroke
				(width 0.1)
				(type default)
			)
			(layer "F.SilkS")
		)
		(fp_line
			(start 13.729208 -4.281932)
			(end 12.181078 -2.796794)
			(stroke
				(width 0.1)
				(type default)
			)
			(layer "F.SilkS")
		)
		(fp_line
			(start 13.729208 -4.281932)
			(end 12.181078 -2.796794)
			(stroke
				(width 0.1)
				(type default)
			)
			(layer "F.SilkS")
		)
		(fp_line
			(start 13.731494 -3.822446)
			(end 12.38377 -2.529586)
			(stroke
				(width 0.1)
				(type default)
			)
			(layer "F.SilkS")
		)
		(fp_line
			(start 13.731494 -3.822446)
			(end 12.38377 -2.529586)
			(stroke
				(width 0.1)
				(type default)
			)
			(layer "F.SilkS")
		)
		(fp_line
			(start 13.73632 -4.230878)
			(end 12.224766 -2.781046)
			(stroke
				(width 0.1)
				(type default)
			)
			(layer "F.SilkS")
		)
		(fp_line
			(start 13.73632 -4.230878)
			(end 12.224766 -2.781046)
			(stroke
				(width 0.1)
				(type default)
			)
			(layer "F.SilkS")
		)
		(fp_line
			(start 13.736574 -3.88493)
			(end 12.395962 -2.598928)
			(stroke
				(width 0.1)
				(type default)
			)
			(layer "F.SilkS")
		)
		(fp_line
			(start 13.736574 -3.88493)
			(end 12.395962 -2.598928)
			(stroke
				(width 0.1)
				(type default)
			)
			(layer "F.SilkS")
		)
		(fp_line
			(start 13.741654 -3.947668)
			(end 12.408154 -2.668524)
			(stroke
				(width 0.1)
				(type default)
			)
			(layer "F.SilkS")
		)
		(fp_line
			(start 13.741654 -3.947668)
			(end 12.408154 -2.668524)
			(stroke
				(width 0.1)
				(type default)
			)
			(layer "F.SilkS")
		)
		(fp_line
			(start 13.743178 -4.179824)
			(end 12.266422 -2.76352)
			(stroke
				(width 0.1)
				(type default)
			)
			(layer "F.SilkS")
		)
		(fp_line
			(start 13.743178 -4.179824)
			(end 12.266422 -2.76352)
			(stroke
				(width 0.1)
				(type default)
			)
			(layer "F.SilkS")
		)
		(fp_line
			(start 13.74648 -4.010152)
			(end 12.380214 -2.699512)
			(stroke
				(width 0.1)
				(type default)
			)
			(layer "F.SilkS")
		)
		(fp_line
			(start 13.74648 -4.010152)
			(end 12.380214 -2.699512)
			(stroke
				(width 0.1)
				(type default)
			)
			(layer "F.SilkS")
		)
		(fp_line
			(start 13.750036 -4.12877)
			(end 12.306046 -2.743454)
			(stroke
				(width 0.1)
				(type default)
			)
			(layer "F.SilkS")
		)
		(fp_line
			(start 13.750036 -4.12877)
			(end 12.306046 -2.743454)
			(stroke
				(width 0.1)
				(type default)
			)
			(layer "F.SilkS")
		)
		(fp_line
			(start 13.751814 -4.072636)
			(end 12.344654 -2.722626)
			(stroke
				(width 0.1)
				(type default)
			)
			(layer "F.SilkS")
		)
		(fp_line
			(start 13.751814 -4.072636)
			(end 12.344654 -2.722626)
			(stroke
				(width 0.1)
				(type default)
			)
			(layer "F.SilkS")
		)
		(fp_line
			(start 13.944854 -0.882904)
			(end 13.976096 -0.882904)
			(stroke
				(width 0.1)
				(type default)
			)
			(layer "F.SilkS")
		)
		(fp_line
			(start 13.944854 -0.882904)
			(end 13.976096 -0.882904)
			(stroke
				(width 0.1)
				(type default)
			)
			(layer "F.SilkS")
		)
		(fp_line
			(start 13.95095 -0.916178)
			(end 13.944854 -0.882904)
			(stroke
				(width 0.1)
				(type default)
			)
			(layer "F.SilkS")
		)
		(fp_line
			(start 13.95095 -0.916178)
			(end 13.944854 -0.882904)
			(stroke
				(width 0.1)
				(type default)
			)
			(layer "F.SilkS")
		)
		(fp_line
			(start 13.95095 -0.916178)
			(end 15.307056 -2.21742)
			(stroke
				(width 0.1)
				(type default)
			)
			(layer "F.SilkS")
		)
		(fp_line
			(start 13.95095 -0.916178)
			(end 15.307056 -2.21742)
			(stroke
				(width 0.1)
				(type default)
			)
			(layer "F.SilkS")
		)
		(fp_line
			(start 13.962888 -0.985774)
			(end 13.95095 -0.916178)
			(stroke
				(width 0.1)
				(type default)
			)
			(layer "F.SilkS")
		)
		(fp_line
			(start 13.962888 -0.985774)
			(end 13.95095 -0.916178)
			(stroke
				(width 0.1)
				(type default)
			)
			(layer "F.SilkS")
		)
		(fp_line
			(start 13.962888 -0.985774)
			(end 15.319248 -2.286762)
			(stroke
				(width 0.1)
				(type default)
			)
			(layer "F.SilkS")
		)
		(fp_line
			(start 13.962888 -0.985774)
			(end 15.319248 -2.286762)
			(stroke
				(width 0.1)
				(type default)
			)
			(layer "F.SilkS")
		)
		(fp_line
			(start 13.975334 -1.055116)
			(end 13.962888 -0.985774)
			(stroke
				(width 0.1)
				(type default)
			)
			(layer "F.SilkS")
		)
		(fp_line
			(start 13.975334 -1.055116)
			(end 13.962888 -0.985774)
			(stroke
				(width 0.1)
				(type default)
			)
			(layer "F.SilkS")
		)
		(fp_line
			(start 13.975334 -1.055116)
			(end 15.331186 -2.356104)
			(stroke
				(width 0.1)
				(type default)
			)
			(layer "F.SilkS")
		)
		(fp_line
			(start 13.975334 -1.055116)
			(end 15.331186 -2.356104)
			(stroke
				(width 0.1)
				(type default)
			)
			(layer "F.SilkS")
		)
		(fp_line
			(start 13.976096 -0.882904)
			(end 14.036294 -0.882904)
			(stroke
				(width 0.1)
				(type default)
			)
			(layer "F.SilkS")
		)
		(fp_line
			(start 13.976096 -0.882904)
			(end 14.036294 -0.882904)
			(stroke
				(width 0.1)
				(type default)
			)
			(layer "F.SilkS")
		)
		(fp_line
			(start 13.976096 -0.882904)
			(end 15.294864 -2.147824)
			(stroke
				(width 0.1)
				(type default)
			)
			(layer "F.SilkS")
		)
		(fp_line
			(start 13.976096 -0.882904)
			(end 15.294864 -2.147824)
			(stroke
				(width 0.1)
				(type default)
			)
			(layer "F.SilkS")
		)
		(fp_line
			(start 13.987272 -1.124458)
			(end 13.975334 -1.055116)
			(stroke
				(width 0.1)
				(type default)
			)
			(layer "F.SilkS")
		)
		(fp_line
			(start 13.987272 -1.124458)
			(end 13.975334 -1.055116)
			(stroke
				(width 0.1)
				(type default)
			)
			(layer "F.SilkS")
		)
		(fp_line
			(start 13.987272 -1.124458)
			(end 15.343632 -2.425446)
			(stroke
				(width 0.1)
				(type default)
			)
			(layer "F.SilkS")
		)
		(fp_line
			(start 13.987272 -1.124458)
			(end 15.343632 -2.425446)
			(stroke
				(width 0.1)
				(type default)
			)
			(layer "F.SilkS")
		)
		(fp_line
			(start 13.999464 -1.194054)
			(end 13.987272 -1.124458)
			(stroke
				(width 0.1)
				(type default)
			)
			(layer "F.SilkS")
		)
		(fp_line
			(start 13.999464 -1.194054)
			(end 13.987272 -1.124458)
			(stroke
				(width 0.1)
				(type default)
			)
			(layer "F.SilkS")
		)
		(fp_line
			(start 13.999464 -1.194054)
			(end 15.355824 -2.495042)
			(stroke
				(width 0.1)
				(type default)
			)
			(layer "F.SilkS")
		)
		(fp_line
			(start 13.999464 -1.194054)
			(end 15.355824 -2.495042)
			(stroke
				(width 0.1)
				(type default)
			)
			(layer "F.SilkS")
		)
		(fp_line
			(start 14.01191 -1.26365)
			(end 13.999464 -1.194054)
			(stroke
				(width 0.1)
				(type default)
			)
			(layer "F.SilkS")
		)
		(fp_line
			(start 14.01191 -1.26365)
			(end 13.999464 -1.194054)
			(stroke
				(width 0.1)
				(type default)
			)
			(layer "F.SilkS")
		)
		(fp_line
			(start 14.01191 -1.26365)
			(end 15.367762 -2.564384)
			(stroke
				(width 0.1)
				(type default)
			)
			(layer "F.SilkS")
		)
		(fp_line
			(start 14.01191 -1.26365)
			(end 15.367762 -2.564384)
			(stroke
				(width 0.1)
				(type default)
			)
			(layer "F.SilkS")
		)
		(fp_line
			(start 14.023848 -1.332738)
			(end 14.01191 -1.26365)
			(stroke
				(width 0.1)
				(type default)
			)
			(layer "F.SilkS")
		)
		(fp_line
			(start 14.023848 -1.332738)
			(end 14.01191 -1.26365)
			(stroke
				(width 0.1)
				(type default)
			)
			(layer "F.SilkS")
		)
		(fp_line
			(start 14.023848 -1.332738)
			(end 15.380208 -2.633726)
			(stroke
				(width 0.1)
				(type default)
			)
			(layer "F.SilkS")
		)
		(fp_line
			(start 14.023848 -1.332738)
			(end 15.380208 -2.633726)
			(stroke
				(width 0.1)
				(type default)
			)
			(layer "F.SilkS")
		)
		(fp_line
			(start 14.03604 -1.40208)
			(end 14.023848 -1.332738)
			(stroke
				(width 0.1)
				(type default)
			)
			(layer "F.SilkS")
		)
		(fp_line
			(start 14.03604 -1.40208)
			(end 14.023848 -1.332738)
			(stroke
				(width 0.1)
				(type default)
			)
			(layer "F.SilkS")
		)
		(fp_line
			(start 14.03604 -1.40208)
			(end 15.392654 -2.703322)
			(stroke
				(width 0.1)
				(type default)
			)
			(layer "F.SilkS")
		)
		(fp_line
			(start 14.03604 -1.40208)
			(end 15.392654 -2.703322)
			(stroke
				(width 0.1)
				(type default)
			)
			(layer "F.SilkS")
		)
		(fp_line
			(start 14.036294 -0.882904)
			(end 14.096238 -0.882904)
			(stroke
				(width 0.1)
				(type default)
			)
			(layer "F.SilkS")
		)
		(fp_line
			(start 14.036294 -0.882904)
			(end 14.096238 -0.882904)
			(stroke
				(width 0.1)
				(type default)
			)
			(layer "F.SilkS")
		)
		(fp_line
			(start 14.036294 -0.882904)
			(end 15.282418 -2.078482)
			(stroke
				(width 0.1)
				(type default)
			)
			(layer "F.SilkS")
		)
		(fp_line
			(start 14.036294 -0.882904)
			(end 15.282418 -2.078482)
			(stroke
				(width 0.1)
				(type default)
			)
			(layer "F.SilkS")
		)
		(fp_line
			(start 14.048232 -1.471676)
			(end 14.03604 -1.40208)
			(stroke
				(width 0.1)
				(type default)
			)
			(layer "F.SilkS")
		)
		(fp_line
			(start 14.048232 -1.471676)
			(end 14.03604 -1.40208)
			(stroke
				(width 0.1)
				(type default)
			)
			(layer "F.SilkS")
		)
		(fp_line
			(start 14.048232 -1.471676)
			(end 15.404592 -2.772664)
			(stroke
				(width 0.1)
				(type default)
			)
			(layer "F.SilkS")
		)
		(fp_line
			(start 14.048232 -1.471676)
			(end 15.404592 -2.772664)
			(stroke
				(width 0.1)
				(type default)
			)
			(layer "F.SilkS")
		)
		(fp_line
			(start 14.060678 -1.541018)
			(end 14.048232 -1.471676)
			(stroke
				(width 0.1)
				(type default)
			)
			(layer "F.SilkS")
		)
		(fp_line
			(start 14.060678 -1.541018)
			(end 14.048232 -1.471676)
			(stroke
				(width 0.1)
				(type default)
			)
			(layer "F.SilkS")
		)
		(fp_line
			(start 14.060678 -1.541018)
			(end 15.416784 -2.84226)
			(stroke
				(width 0.1)
				(type default)
			)
			(layer "F.SilkS")
		)
		(fp_line
			(start 14.060678 -1.541018)
			(end 15.416784 -2.84226)
			(stroke
				(width 0.1)
				(type default)
			)
			(layer "F.SilkS")
		)
		(fp_line
			(start 14.072362 -1.61036)
			(end 14.060678 -1.541018)
			(stroke
				(width 0.1)
				(type default)
			)
			(layer "F.SilkS")
		)
		(fp_line
			(start 14.072362 -1.61036)
			(end 14.060678 -1.541018)
			(stroke
				(width 0.1)
				(type default)
			)
			(layer "F.SilkS")
		)
		(fp_line
			(start 14.072362 -1.61036)
			(end 15.42923 -2.911602)
			(stroke
				(width 0.1)
				(type default)
			)
			(layer "F.SilkS")
		)
		(fp_line
			(start 14.072362 -1.61036)
			(end 15.42923 -2.911602)
			(stroke
				(width 0.1)
				(type default)
			)
			(layer "F.SilkS")
		)
		(fp_line
			(start 14.084808 -1.679702)
			(end 14.072362 -1.61036)
			(stroke
				(width 0.1)
				(type default)
			)
			(layer "F.SilkS")
		)
		(fp_line
			(start 14.084808 -1.679702)
			(end 14.072362 -1.61036)
			(stroke
				(width 0.1)
				(type default)
			)
			(layer "F.SilkS")
		)
		(fp_line
			(start 14.084808 -1.679702)
			(end 14.097254 -1.749044)
			(stroke
				(width 0.1)
				(type default)
			)
			(layer "F.SilkS")
		)
		(fp_line
			(start 14.084808 -1.679702)
			(end 14.097254 -1.749044)
			(stroke
				(width 0.1)
				(type default)
			)
			(layer "F.SilkS")
		)
		(fp_line
			(start 14.096238 -0.882904)
			(end 14.156436 -0.882904)
			(stroke
				(width 0.1)
				(type default)
			)
			(layer "F.SilkS")
		)
		(fp_line
			(start 14.096238 -0.882904)
			(end 14.156436 -0.882904)
			(stroke
				(width 0.1)
				(type default)
			)
			(layer "F.SilkS")
		)
		(fp_line
			(start 14.096238 -0.882904)
			(end 15.270226 -2.00914)
			(stroke
				(width 0.1)
				(type default)
			)
			(layer "F.SilkS")
		)
		(fp_line
			(start 14.096238 -0.882904)
			(end 15.270226 -2.00914)
			(stroke
				(width 0.1)
				(type default)
			)
			(layer "F.SilkS")
		)
		(fp_line
			(start 14.109192 -1.81864)
			(end 14.097254 -1.749044)
			(stroke
				(width 0.1)
				(type default)
			)
			(layer "F.SilkS")
		)
		(fp_line
			(start 14.109192 -1.81864)
			(end 14.097254 -1.749044)
			(stroke
				(width 0.1)
				(type default)
			)
			(layer "F.SilkS")
		)
		(fp_line
			(start 14.121384 -1.887982)
			(end 14.109192 -1.81864)
			(stroke
				(width 0.1)
				(type default)
			)
			(layer "F.SilkS")
		)
		(fp_line
			(start 14.121384 -1.887982)
			(end 14.109192 -1.81864)
			(stroke
				(width 0.1)
				(type default)
			)
			(layer "F.SilkS")
		)
		(fp_line
			(start 14.13383 -1.957324)
			(end 14.121384 -1.887982)
			(stroke
				(width 0.1)
				(type default)
			)
			(layer "F.SilkS")
		)
		(fp_line
			(start 14.13383 -1.957324)
			(end 14.121384 -1.887982)
			(stroke
				(width 0.1)
				(type default)
			)
			(layer "F.SilkS")
		)
		(fp_line
			(start 14.145768 -2.02692)
			(end 14.13383 -1.957324)
			(stroke
				(width 0.1)
				(type default)
			)
			(layer "F.SilkS")
		)
		(fp_line
			(start 14.145768 -2.02692)
			(end 14.13383 -1.957324)
			(stroke
				(width 0.1)
				(type default)
			)
			(layer "F.SilkS")
		)
		(fp_line
			(start 14.156436 -0.882904)
			(end 14.216888 -0.882904)
			(stroke
				(width 0.1)
				(type default)
			)
			(layer "F.SilkS")
		)
		(fp_line
			(start 14.156436 -0.882904)
			(end 14.216888 -0.882904)
			(stroke
				(width 0.1)
				(type default)
			)
			(layer "F.SilkS")
		)
		(fp_line
			(start 14.156436 -0.882904)
			(end 15.258288 -1.939544)
			(stroke
				(width 0.1)
				(type default)
			)
			(layer "F.SilkS")
		)
		(fp_line
			(start 14.156436 -0.882904)
			(end 15.258288 -1.939544)
			(stroke
				(width 0.1)
				(type default)
			)
			(layer "F.SilkS")
		)
		(fp_line
			(start 14.15796 -2.096262)
			(end 14.145768 -2.02692)
			(stroke
				(width 0.1)
				(type default)
			)
			(layer "F.SilkS")
		)
		(fp_line
			(start 14.15796 -2.096262)
			(end 14.145768 -2.02692)
			(stroke
				(width 0.1)
				(type default)
			)
			(layer "F.SilkS")
		)
		(fp_line
			(start 14.170406 -2.165604)
			(end 14.15796 -2.096262)
			(stroke
				(width 0.1)
				(type default)
			)
			(layer "F.SilkS")
		)
		(fp_line
			(start 14.170406 -2.165604)
			(end 14.15796 -2.096262)
			(stroke
				(width 0.1)
				(type default)
			)
			(layer "F.SilkS")
		)
		(fp_line
			(start 14.182344 -2.234946)
			(end 14.170406 -2.165604)
			(stroke
				(width 0.1)
				(type default)
			)
			(layer "F.SilkS")
		)
		(fp_line
			(start 14.182344 -2.234946)
			(end 14.170406 -2.165604)
			(stroke
				(width 0.1)
				(type default)
			)
			(layer "F.SilkS")
		)
		(fp_line
			(start 14.194282 -2.304288)
			(end 14.182344 -2.234946)
			(stroke
				(width 0.1)
				(type default)
			)
			(layer "F.SilkS")
		)
		(fp_line
			(start 14.194282 -2.304288)
			(end 14.182344 -2.234946)
			(stroke
				(width 0.1)
				(type default)
			)
			(layer "F.SilkS")
		)
		(fp_line
			(start 14.206728 -2.373884)
			(end 14.194282 -2.304288)
			(stroke
				(width 0.1)
				(type default)
			)
			(layer "F.SilkS")
		)
		(fp_line
			(start 14.206728 -2.373884)
			(end 14.194282 -2.304288)
			(stroke
				(width 0.1)
				(type default)
			)
			(layer "F.SilkS")
		)
		(fp_line
			(start 14.216888 -0.882904)
			(end 14.277086 -0.882904)
			(stroke
				(width 0.1)
				(type default)
			)
			(layer "F.SilkS")
		)
		(fp_line
			(start 14.216888 -0.882904)
			(end 14.277086 -0.882904)
			(stroke
				(width 0.1)
				(type default)
			)
			(layer "F.SilkS")
		)
		(fp_line
			(start 14.216888 -0.882904)
			(end 15.245842 -1.869948)
			(stroke
				(width 0.1)
				(type default)
			)
			(layer "F.SilkS")
		)
		(fp_line
			(start 14.216888 -0.882904)
			(end 15.245842 -1.869948)
			(stroke
				(width 0.1)
				(type default)
			)
			(layer "F.SilkS")
		)
		(fp_line
			(start 14.21892 -2.443226)
			(end 14.206728 -2.373884)
			(stroke
				(width 0.1)
				(type default)
			)
			(layer "F.SilkS")
		)
		(fp_line
			(start 14.21892 -2.443226)
			(end 14.206728 -2.373884)
			(stroke
				(width 0.1)
				(type default)
			)
			(layer "F.SilkS")
		)
		(fp_line
			(start 14.230858 -2.512314)
			(end 14.21892 -2.443226)
			(stroke
				(width 0.1)
				(type default)
			)
			(layer "F.SilkS")
		)
		(fp_line
			(start 14.230858 -2.512314)
			(end 14.21892 -2.443226)
			(stroke
				(width 0.1)
				(type default)
			)
			(layer "F.SilkS")
		)
		(fp_line
			(start 14.243304 -2.58191)
			(end 14.230858 -2.512314)
			(stroke
				(width 0.1)
				(type default)
			)
			(layer "F.SilkS")
		)
		(fp_line
			(start 14.243304 -2.58191)
			(end 14.230858 -2.512314)
			(stroke
				(width 0.1)
				(type default)
			)
			(layer "F.SilkS")
		)
		(fp_line
			(start 14.255496 -2.651506)
			(end 14.243304 -2.58191)
			(stroke
				(width 0.1)
				(type default)
			)
			(layer "F.SilkS")
		)
		(fp_line
			(start 14.255496 -2.651506)
			(end 14.243304 -2.58191)
			(stroke
				(width 0.1)
				(type default)
			)
			(layer "F.SilkS")
		)
		(fp_line
			(start 14.267434 -2.720594)
			(end 14.255496 -2.651506)
			(stroke
				(width 0.1)
				(type default)
			)
			(layer "F.SilkS")
		)
		(fp_line
			(start 14.267434 -2.720594)
			(end 14.255496 -2.651506)
			(stroke
				(width 0.1)
				(type default)
			)
			(layer "F.SilkS")
		)
		(fp_line
			(start 14.277086 -0.882904)
			(end 14.33703 -0.882904)
			(stroke
				(width 0.1)
				(type default)
			)
			(layer "F.SilkS")
		)
		(fp_line
			(start 14.277086 -0.882904)
			(end 14.33703 -0.882904)
			(stroke
				(width 0.1)
				(type default)
			)
			(layer "F.SilkS")
		)
		(fp_line
			(start 14.277086 -0.882904)
			(end 15.233396 -1.800606)
			(stroke
				(width 0.1)
				(type default)
			)
			(layer "F.SilkS")
		)
		(fp_line
			(start 14.277086 -0.882904)
			(end 15.233396 -1.800606)
			(stroke
				(width 0.1)
				(type default)
			)
			(layer "F.SilkS")
		)
		(fp_line
			(start 14.27988 -2.79019)
			(end 14.267434 -2.720594)
			(stroke
				(width 0.1)
				(type default)
			)
			(layer "F.SilkS")
		)
		(fp_line
			(start 14.27988 -2.79019)
			(end 14.267434 -2.720594)
			(stroke
				(width 0.1)
				(type default)
			)
			(layer "F.SilkS")
		)
		(fp_line
			(start 14.291818 -2.859532)
			(end 14.27988 -2.79019)
			(stroke
				(width 0.1)
				(type default)
			)
			(layer "F.SilkS")
		)
		(fp_line
			(start 14.291818 -2.859532)
			(end 14.27988 -2.79019)
			(stroke
				(width 0.1)
				(type default)
			)
			(layer "F.SilkS")
		)
		(fp_line
			(start 14.30401 -2.928874)
			(end 14.291818 -2.859532)
			(stroke
				(width 0.1)
				(type default)
			)
			(layer "F.SilkS")
		)
		(fp_line
			(start 14.30401 -2.928874)
			(end 14.291818 -2.859532)
			(stroke
				(width 0.1)
				(type default)
			)
			(layer "F.SilkS")
		)
		(fp_line
			(start 14.316456 -2.998216)
			(end 14.30401 -2.928874)
			(stroke
				(width 0.1)
				(type default)
			)
			(layer "F.SilkS")
		)
		(fp_line
			(start 14.316456 -2.998216)
			(end 14.30401 -2.928874)
			(stroke
				(width 0.1)
				(type default)
			)
			(layer "F.SilkS")
		)
		(fp_line
			(start 14.328394 -3.067558)
			(end 14.316456 -2.998216)
			(stroke
				(width 0.1)
				(type default)
			)
			(layer "F.SilkS")
		)
		(fp_line
			(start 14.328394 -3.067558)
			(end 14.316456 -2.998216)
			(stroke
				(width 0.1)
				(type default)
			)
			(layer "F.SilkS")
		)
		(fp_line
			(start 14.33703 -0.882904)
			(end 14.396974 -0.882904)
			(stroke
				(width 0.1)
				(type default)
			)
			(layer "F.SilkS")
		)
		(fp_line
			(start 14.33703 -0.882904)
			(end 14.396974 -0.882904)
			(stroke
				(width 0.1)
				(type default)
			)
			(layer "F.SilkS")
		)
		(fp_line
			(start 14.33703 -0.882904)
			(end 15.221458 -1.731518)
			(stroke
				(width 0.1)
				(type default)
			)
			(layer "F.SilkS")
		)
		(fp_line
			(start 14.33703 -0.882904)
			(end 15.221458 -1.731518)
			(stroke
				(width 0.1)
				(type default)
			)
			(layer "F.SilkS")
		)
		(fp_line
			(start 14.340586 -3.137154)
			(end 14.328394 -3.067558)
			(stroke
				(width 0.1)
				(type default)
			)
			(layer "F.SilkS")
		)
		(fp_line
			(start 14.340586 -3.137154)
			(end 14.328394 -3.067558)
			(stroke
				(width 0.1)
				(type default)
			)
			(layer "F.SilkS")
		)
		(fp_line
			(start 14.352778 -3.206496)
			(end 14.340586 -3.137154)
			(stroke
				(width 0.1)
				(type default)
			)
			(layer "F.SilkS")
		)
		(fp_line
			(start 14.352778 -3.206496)
			(end 14.340586 -3.137154)
			(stroke
				(width 0.1)
				(type default)
			)
			(layer "F.SilkS")
		)
		(fp_line
			(start 14.36497 -3.275838)
			(end 14.352778 -3.206496)
			(stroke
				(width 0.1)
				(type default)
			)
			(layer "F.SilkS")
		)
		(fp_line
			(start 14.36497 -3.275838)
			(end 14.352778 -3.206496)
			(stroke
				(width 0.1)
				(type default)
			)
			(layer "F.SilkS")
		)
		(fp_line
			(start 14.376908 -3.34518)
			(end 14.36497 -3.275838)
			(stroke
				(width 0.1)
				(type default)
			)
			(layer "F.SilkS")
		)
		(fp_line
			(start 14.376908 -3.34518)
			(end 14.36497 -3.275838)
			(stroke
				(width 0.1)
				(type default)
			)
			(layer "F.SilkS")
		)
		(fp_line
			(start 14.389354 -3.414776)
			(end 14.376908 -3.34518)
			(stroke
				(width 0.1)
				(type default)
			)
			(layer "F.SilkS")
		)
		(fp_line
			(start 14.389354 -3.414776)
			(end 14.376908 -3.34518)
			(stroke
				(width 0.1)
				(type default)
			)
			(layer "F.SilkS")
		)
		(fp_line
			(start 14.396974 -0.882904)
			(end 14.45768 -0.882904)
			(stroke
				(width 0.1)
				(type default)
			)
			(layer "F.SilkS")
		)
		(fp_line
			(start 14.396974 -0.882904)
			(end 14.45768 -0.882904)
			(stroke
				(width 0.1)
				(type default)
			)
			(layer "F.SilkS")
		)
		(fp_line
			(start 14.396974 -0.882904)
			(end 15.209266 -1.661922)
			(stroke
				(width 0.1)
				(type default)
			)
			(layer "F.SilkS")
		)
		(fp_line
			(start 14.396974 -0.882904)
			(end 15.209266 -1.661922)
			(stroke
				(width 0.1)
				(type default)
			)
			(layer "F.SilkS")
		)
		(fp_line
			(start 14.401546 -3.484118)
			(end 14.389354 -3.414776)
			(stroke
				(width 0.1)
				(type default)
			)
			(layer "F.SilkS")
		)
		(fp_line
			(start 14.401546 -3.484118)
			(end 14.389354 -3.414776)
			(stroke
				(width 0.1)
				(type default)
			)
			(layer "F.SilkS")
		)
		(fp_line
			(start 14.413484 -3.55346)
			(end 14.401546 -3.484118)
			(stroke
				(width 0.1)
				(type default)
			)
			(layer "F.SilkS")
		)
		(fp_line
			(start 14.413484 -3.55346)
			(end 14.401546 -3.484118)
			(stroke
				(width 0.1)
				(type default)
			)
			(layer "F.SilkS")
		)
		(fp_line
			(start 14.42593 -3.622802)
			(end 14.413484 -3.55346)
			(stroke
				(width 0.1)
				(type default)
			)
			(layer "F.SilkS")
		)
		(fp_line
			(start 14.42593 -3.622802)
			(end 14.413484 -3.55346)
			(stroke
				(width 0.1)
				(type default)
			)
			(layer "F.SilkS")
		)
		(fp_line
			(start 14.438376 -3.692398)
			(end 14.42593 -3.622802)
			(stroke
				(width 0.1)
				(type default)
			)
			(layer "F.SilkS")
		)
		(fp_line
			(start 14.438376 -3.692398)
			(end 14.42593 -3.622802)
			(stroke
				(width 0.1)
				(type default)
			)
			(layer "F.SilkS")
		)
		(fp_line
			(start 14.45006 -3.76174)
			(end 14.438376 -3.692398)
			(stroke
				(width 0.1)
				(type default)
			)
			(layer "F.SilkS")
		)
		(fp_line
			(start 14.45006 -3.76174)
			(end 14.438376 -3.692398)
			(stroke
				(width 0.1)
				(type default)
			)
			(layer "F.SilkS")
		)
		(fp_line
			(start 14.45768 -0.882904)
			(end 14.517624 -0.882904)
			(stroke
				(width 0.1)
				(type default)
			)
			(layer "F.SilkS")
		)
		(fp_line
			(start 14.45768 -0.882904)
			(end 14.517624 -0.882904)
			(stroke
				(width 0.1)
				(type default)
			)
			(layer "F.SilkS")
		)
		(fp_line
			(start 14.45768 -0.882904)
			(end 15.19682 -1.592326)
			(stroke
				(width 0.1)
				(type default)
			)
			(layer "F.SilkS")
		)
		(fp_line
			(start 14.45768 -0.882904)
			(end 15.19682 -1.592326)
			(stroke
				(width 0.1)
				(type default)
			)
			(layer "F.SilkS")
		)
		(fp_line
			(start 14.462506 -3.831082)
			(end 14.45006 -3.76174)
			(stroke
				(width 0.1)
				(type default)
			)
			(layer "F.SilkS")
		)
		(fp_line
			(start 14.462506 -3.831082)
			(end 14.45006 -3.76174)
			(stroke
				(width 0.1)
				(type default)
			)
			(layer "F.SilkS")
		)
		(fp_line
			(start 14.474952 -3.900424)
			(end 14.462506 -3.831082)
			(stroke
				(width 0.1)
				(type default)
			)
			(layer "F.SilkS")
		)
		(fp_line
			(start 14.474952 -3.900424)
			(end 14.462506 -3.831082)
			(stroke
				(width 0.1)
				(type default)
			)
			(layer "F.SilkS")
		)
		(fp_line
			(start 14.486636 -3.969766)
			(end 14.474952 -3.900424)
			(stroke
				(width 0.1)
				(type default)
			)
			(layer "F.SilkS")
		)
		(fp_line
			(start 14.486636 -3.969766)
			(end 14.474952 -3.900424)
			(stroke
				(width 0.1)
				(type default)
			)
			(layer "F.SilkS")
		)
		(fp_line
			(start 14.498828 -4.039362)
			(end 14.486636 -3.969766)
			(stroke
				(width 0.1)
				(type default)
			)
			(layer "F.SilkS")
		)
		(fp_line
			(start 14.498828 -4.039362)
			(end 14.486636 -3.969766)
			(stroke
				(width 0.1)
				(type default)
			)
			(layer "F.SilkS")
		)
		(fp_line
			(start 14.511274 -4.108704)
			(end 14.498828 -4.039362)
			(stroke
				(width 0.1)
				(type default)
			)
			(layer "F.SilkS")
		)
		(fp_line
			(start 14.511274 -4.108704)
			(end 14.498828 -4.039362)
			(stroke
				(width 0.1)
				(type default)
			)
			(layer "F.SilkS")
		)
		(fp_line
			(start 14.517624 -0.882904)
			(end 14.577568 -0.882904)
			(stroke
				(width 0.1)
				(type default)
			)
			(layer "F.SilkS")
		)
		(fp_line
			(start 14.517624 -0.882904)
			(end 14.577568 -0.882904)
			(stroke
				(width 0.1)
				(type default)
			)
			(layer "F.SilkS")
		)
		(fp_line
			(start 14.517624 -0.882904)
			(end 15.184882 -1.522984)
			(stroke
				(width 0.1)
				(type default)
			)
			(layer "F.SilkS")
		)
		(fp_line
			(start 14.517624 -0.882904)
			(end 15.184882 -1.522984)
			(stroke
				(width 0.1)
				(type default)
			)
			(layer "F.SilkS")
		)
		(fp_line
			(start 14.523466 -4.178046)
			(end 14.511274 -4.108704)
			(stroke
				(width 0.1)
				(type default)
			)
			(layer "F.SilkS")
		)
		(fp_line
			(start 14.523466 -4.178046)
			(end 14.511274 -4.108704)
			(stroke
				(width 0.1)
				(type default)
			)
			(layer "F.SilkS")
		)
		(fp_line
			(start 14.523466 -4.178046)
			(end 14.535404 -4.247388)
			(stroke
				(width 0.1)
				(type default)
			)
			(layer "F.SilkS")
		)
		(fp_line
			(start 14.523466 -4.178046)
			(end 14.535404 -4.247388)
			(stroke
				(width 0.1)
				(type default)
			)
			(layer "F.SilkS")
		)
		(fp_line
			(start 14.535404 -4.247388)
			(end 14.54785 -4.316984)
			(stroke
				(width 0.1)
				(type default)
			)
			(layer "F.SilkS")
		)
		(fp_line
			(start 14.535404 -4.247388)
			(end 14.54785 -4.316984)
			(stroke
				(width 0.1)
				(type default)
			)
			(layer "F.SilkS")
		)
		(fp_line
			(start 14.54785 -4.316984)
			(end 14.560042 -4.386326)
			(stroke
				(width 0.1)
				(type default)
			)
			(layer "F.SilkS")
		)
		(fp_line
			(start 14.54785 -4.316984)
			(end 14.560042 -4.386326)
			(stroke
				(width 0.1)
				(type default)
			)
			(layer "F.SilkS")
		)
		(fp_line
			(start 14.560042 -4.386326)
			(end 14.57198 -4.455668)
			(stroke
				(width 0.1)
				(type default)
			)
			(layer "F.SilkS")
		)
		(fp_line
			(start 14.560042 -4.386326)
			(end 14.57198 -4.455668)
			(stroke
				(width 0.1)
				(type default)
			)
			(layer "F.SilkS")
		)
		(fp_line
			(start 14.57198 -4.455668)
			(end 14.584426 -4.52501)
			(stroke
				(width 0.1)
				(type default)
			)
			(layer "F.SilkS")
		)
		(fp_line
			(start 14.57198 -4.455668)
			(end 14.584426 -4.52501)
			(stroke
				(width 0.1)
				(type default)
			)
			(layer "F.SilkS")
		)
		(fp_line
			(start 14.577568 -0.882904)
			(end 14.637766 -0.882904)
			(stroke
				(width 0.1)
				(type default)
			)
			(layer "F.SilkS")
		)
		(fp_line
			(start 14.577568 -0.882904)
			(end 14.637766 -0.882904)
			(stroke
				(width 0.1)
				(type default)
			)
			(layer "F.SilkS")
		)
		(fp_line
			(start 14.577568 -0.882904)
			(end 15.17269 -1.453642)
			(stroke
				(width 0.1)
				(type default)
			)
			(layer "F.SilkS")
		)
		(fp_line
			(start 14.577568 -0.882904)
			(end 15.17269 -1.453642)
			(stroke
				(width 0.1)
				(type default)
			)
			(layer "F.SilkS")
		)
		(fp_line
			(start 14.584426 -4.52501)
			(end 14.596364 -4.594352)
			(stroke
				(width 0.1)
				(type default)
			)
			(layer "F.SilkS")
		)
		(fp_line
			(start 14.584426 -4.52501)
			(end 14.596364 -4.594352)
			(stroke
				(width 0.1)
				(type default)
			)
			(layer "F.SilkS")
		)
		(fp_line
			(start 14.596364 -4.594352)
			(end 14.608556 -4.663948)
			(stroke
				(width 0.1)
				(type default)
			)
			(layer "F.SilkS")
		)
		(fp_line
			(start 14.596364 -4.594352)
			(end 14.608556 -4.663948)
			(stroke
				(width 0.1)
				(type default)
			)
			(layer "F.SilkS")
		)
		(fp_line
			(start 14.608556 -4.663948)
			(end 14.621002 -4.733036)
			(stroke
				(width 0.1)
				(type default)
			)
			(layer "F.SilkS")
		)
		(fp_line
			(start 14.608556 -4.663948)
			(end 14.621002 -4.733036)
			(stroke
				(width 0.1)
				(type default)
			)
			(layer "F.SilkS")
		)
		(fp_line
			(start 14.621002 -4.733036)
			(end 14.63294 -4.802632)
			(stroke
				(width 0.1)
				(type default)
			)
			(layer "F.SilkS")
		)
		(fp_line
			(start 14.621002 -4.733036)
			(end 14.63294 -4.802632)
			(stroke
				(width 0.1)
				(type default)
			)
			(layer "F.SilkS")
		)
		(fp_line
			(start 14.63294 -4.802632)
			(end 14.645132 -4.872228)
			(stroke
				(width 0.1)
				(type default)
			)
			(layer "F.SilkS")
		)
		(fp_line
			(start 14.63294 -4.802632)
			(end 14.645132 -4.872228)
			(stroke
				(width 0.1)
				(type default)
			)
			(layer "F.SilkS")
		)
		(fp_line
			(start 14.637766 -0.882904)
			(end 14.697964 -0.882904)
			(stroke
				(width 0.1)
				(type default)
			)
			(layer "F.SilkS")
		)
		(fp_line
			(start 14.637766 -0.882904)
			(end 14.697964 -0.882904)
			(stroke
				(width 0.1)
				(type default)
			)
			(layer "F.SilkS")
		)
		(fp_line
			(start 14.637766 -0.882904)
			(end 15.160498 -1.384046)
			(stroke
				(width 0.1)
				(type default)
			)
			(layer "F.SilkS")
		)
		(fp_line
			(start 14.637766 -0.882904)
			(end 15.160498 -1.384046)
			(stroke
				(width 0.1)
				(type default)
			)
			(layer "F.SilkS")
		)
		(fp_line
			(start 14.645132 -4.872228)
			(end 14.657324 -4.941316)
			(stroke
				(width 0.1)
				(type default)
			)
			(layer "F.SilkS")
		)
		(fp_line
			(start 14.645132 -4.872228)
			(end 14.657324 -4.941316)
			(stroke
				(width 0.1)
				(type default)
			)
			(layer "F.SilkS")
		)
		(fp_line
			(start 14.657324 -4.941316)
			(end 14.669516 -5.010912)
			(stroke
				(width 0.1)
				(type default)
			)
			(layer "F.SilkS")
		)
		(fp_line
			(start 14.657324 -4.941316)
			(end 14.669516 -5.010912)
			(stroke
				(width 0.1)
				(type default)
			)
			(layer "F.SilkS")
		)
		(fp_line
			(start 14.669516 -5.010912)
			(end 14.681454 -5.080254)
			(stroke
				(width 0.1)
				(type default)
			)
			(layer "F.SilkS")
		)
		(fp_line
			(start 14.669516 -5.010912)
			(end 14.681454 -5.080254)
			(stroke
				(width 0.1)
				(type default)
			)
			(layer "F.SilkS")
		)
		(fp_line
			(start 14.681454 -5.080254)
			(end 14.6939 -5.149596)
			(stroke
				(width 0.1)
				(type default)
			)
			(layer "F.SilkS")
		)
		(fp_line
			(start 14.681454 -5.080254)
			(end 14.6939 -5.149596)
			(stroke
				(width 0.1)
				(type default)
			)
			(layer "F.SilkS")
		)
		(fp_line
			(start 14.69771 -5.171694)
			(end 14.6939 -5.149596)
			(stroke
				(width 0.1)
				(type default)
			)
			(layer "F.SilkS")
		)
		(fp_line
			(start 14.69771 -5.171694)
			(end 14.6939 -5.149596)
			(stroke
				(width 0.1)
				(type default)
			)
			(layer "F.SilkS")
		)
		(fp_line
			(start 14.697964 -0.882904)
			(end 14.757908 -0.882904)
			(stroke
				(width 0.1)
				(type default)
			)
			(layer "F.SilkS")
		)
		(fp_line
			(start 14.697964 -0.882904)
			(end 14.757908 -0.882904)
			(stroke
				(width 0.1)
				(type default)
			)
			(layer "F.SilkS")
		)
		(fp_line
			(start 14.697964 -0.882904)
			(end 15.148052 -1.314704)
			(stroke
				(width 0.1)
				(type default)
			)
			(layer "F.SilkS")
		)
		(fp_line
			(start 14.697964 -0.882904)
			(end 15.148052 -1.314704)
			(stroke
				(width 0.1)
				(type default)
			)
			(layer "F.SilkS")
		)
		(fp_line
			(start 14.71676 -5.171694)
			(end 14.6939 -5.149596)
			(stroke
				(width 0.1)
				(type default)
			)
			(layer "F.SilkS")
		)
		(fp_line
			(start 14.71676 -5.171694)
			(end 14.6939 -5.149596)
			(stroke
				(width 0.1)
				(type default)
			)
			(layer "F.SilkS")
		)
		(fp_line
			(start 14.71676 -5.171694)
			(end 14.69771 -5.171694)
			(stroke
				(width 0.1)
				(type default)
			)
			(layer "F.SilkS")
		)
		(fp_line
			(start 14.71676 -5.171694)
			(end 14.69771 -5.171694)
			(stroke
				(width 0.1)
				(type default)
			)
			(layer "F.SilkS")
		)
		(fp_line
			(start 14.757908 -0.882904)
			(end 14.81836 -0.882904)
			(stroke
				(width 0.1)
				(type default)
			)
			(layer "F.SilkS")
		)
		(fp_line
			(start 14.757908 -0.882904)
			(end 14.81836 -0.882904)
			(stroke
				(width 0.1)
				(type default)
			)
			(layer "F.SilkS")
		)
		(fp_line
			(start 14.757908 -0.882904)
			(end 15.13586 -1.245362)
			(stroke
				(width 0.1)
				(type default)
			)
			(layer "F.SilkS")
		)
		(fp_line
			(start 14.757908 -0.882904)
			(end 15.13586 -1.245362)
			(stroke
				(width 0.1)
				(type default)
			)
			(layer "F.SilkS")
		)
		(fp_line
			(start 14.776958 -5.171694)
			(end 14.681454 -5.080254)
			(stroke
				(width 0.1)
				(type default)
			)
			(layer "F.SilkS")
		)
		(fp_line
			(start 14.776958 -5.171694)
			(end 14.681454 -5.080254)
			(stroke
				(width 0.1)
				(type default)
			)
			(layer "F.SilkS")
		)
		(fp_line
			(start 14.776958 -5.171694)
			(end 14.71676 -5.171694)
			(stroke
				(width 0.1)
				(type default)
			)
			(layer "F.SilkS")
		)
		(fp_line
			(start 14.776958 -5.171694)
			(end 14.71676 -5.171694)
			(stroke
				(width 0.1)
				(type default)
			)
			(layer "F.SilkS")
		)
		(fp_line
			(start 14.81836 -0.882904)
			(end 14.878558 -0.882904)
			(stroke
				(width 0.1)
				(type default)
			)
			(layer "F.SilkS")
		)
		(fp_line
			(start 14.81836 -0.882904)
			(end 14.878558 -0.882904)
			(stroke
				(width 0.1)
				(type default)
			)
			(layer "F.SilkS")
		)
		(fp_line
			(start 14.81836 -0.882904)
			(end 15.123922 -1.17602)
			(stroke
				(width 0.1)
				(type default)
			)
			(layer "F.SilkS")
		)
		(fp_line
			(start 14.81836 -0.882904)
			(end 15.123922 -1.17602)
			(stroke
				(width 0.1)
				(type default)
			)
			(layer "F.SilkS")
		)
		(fp_line
			(start 14.837156 -5.171694)
			(end 14.669516 -5.010912)
			(stroke
				(width 0.1)
				(type default)
			)
			(layer "F.SilkS")
		)
		(fp_line
			(start 14.837156 -5.171694)
			(end 14.669516 -5.010912)
			(stroke
				(width 0.1)
				(type default)
			)
			(layer "F.SilkS")
		)
		(fp_line
			(start 14.837156 -5.171694)
			(end 14.776958 -5.171694)
			(stroke
				(width 0.1)
				(type default)
			)
			(layer "F.SilkS")
		)
		(fp_line
			(start 14.837156 -5.171694)
			(end 14.776958 -5.171694)
			(stroke
				(width 0.1)
				(type default)
			)
			(layer "F.SilkS")
		)
		(fp_line
			(start 14.878558 -0.882904)
			(end 14.938502 -0.882904)
			(stroke
				(width 0.1)
				(type default)
			)
			(layer "F.SilkS")
		)
		(fp_line
			(start 14.878558 -0.882904)
			(end 14.938502 -0.882904)
			(stroke
				(width 0.1)
				(type default)
			)
			(layer "F.SilkS")
		)
		(fp_line
			(start 14.878558 -0.882904)
			(end 15.111476 -1.106424)
			(stroke
				(width 0.1)
				(type default)
			)
			(layer "F.SilkS")
		)
		(fp_line
			(start 14.878558 -0.882904)
			(end 15.111476 -1.106424)
			(stroke
				(width 0.1)
				(type default)
			)
			(layer "F.SilkS")
		)
		(fp_line
			(start 14.8971 -5.171694)
			(end 14.657324 -4.941316)
			(stroke
				(width 0.1)
				(type default)
			)
			(layer "F.SilkS")
		)
		(fp_line
			(start 14.8971 -5.171694)
			(end 14.657324 -4.941316)
			(stroke
				(width 0.1)
				(type default)
			)
			(layer "F.SilkS")
		)
		(fp_line
			(start 14.8971 -5.171694)
			(end 14.837156 -5.171694)
			(stroke
				(width 0.1)
				(type default)
			)
			(layer "F.SilkS")
		)
		(fp_line
			(start 14.8971 -5.171694)
			(end 14.837156 -5.171694)
			(stroke
				(width 0.1)
				(type default)
			)
			(layer "F.SilkS")
		)
		(fp_line
			(start 14.938502 -0.882904)
			(end 14.998954 -0.882904)
			(stroke
				(width 0.1)
				(type default)
			)
			(layer "F.SilkS")
		)
		(fp_line
			(start 14.938502 -0.882904)
			(end 14.998954 -0.882904)
			(stroke
				(width 0.1)
				(type default)
			)
			(layer "F.SilkS")
		)
		(fp_line
			(start 14.938502 -0.882904)
			(end 15.09903 -1.036828)
			(stroke
				(width 0.1)
				(type default)
			)
			(layer "F.SilkS")
		)
		(fp_line
			(start 14.938502 -0.882904)
			(end 15.09903 -1.036828)
			(stroke
				(width 0.1)
				(type default)
			)
			(layer "F.SilkS")
		)
		(fp_line
			(start 14.957552 -5.171694)
			(end 14.645132 -4.872228)
			(stroke
				(width 0.1)
				(type default)
			)
			(layer "F.SilkS")
		)
		(fp_line
			(start 14.957552 -5.171694)
			(end 14.645132 -4.872228)
			(stroke
				(width 0.1)
				(type default)
			)
			(layer "F.SilkS")
		)
		(fp_line
			(start 14.957552 -5.171694)
			(end 14.8971 -5.171694)
			(stroke
				(width 0.1)
				(type default)
			)
			(layer "F.SilkS")
		)
		(fp_line
			(start 14.957552 -5.171694)
			(end 14.8971 -5.171694)
			(stroke
				(width 0.1)
				(type default)
			)
			(layer "F.SilkS")
		)
		(fp_line
			(start 14.998954 -0.882904)
			(end 15.059152 -0.882904)
			(stroke
				(width 0.1)
				(type default)
			)
			(layer "F.SilkS")
		)
		(fp_line
			(start 14.998954 -0.882904)
			(end 15.059152 -0.882904)
			(stroke
				(width 0.1)
				(type default)
			)
			(layer "F.SilkS")
		)
		(fp_line
			(start 14.998954 -0.882904)
			(end 15.087092 -0.96774)
			(stroke
				(width 0.1)
				(type default)
			)
			(layer "F.SilkS")
		)
		(fp_line
			(start 14.998954 -0.882904)
			(end 15.087092 -0.96774)
			(stroke
				(width 0.1)
				(type default)
			)
			(layer "F.SilkS")
		)
		(fp_line
			(start 15.01775 -5.171694)
			(end 14.63294 -4.802632)
			(stroke
				(width 0.1)
				(type default)
			)
			(layer "F.SilkS")
		)
		(fp_line
			(start 15.01775 -5.171694)
			(end 14.63294 -4.802632)
			(stroke
				(width 0.1)
				(type default)
			)
			(layer "F.SilkS")
		)
		(fp_line
			(start 15.01775 -5.171694)
			(end 14.957552 -5.171694)
			(stroke
				(width 0.1)
				(type default)
			)
			(layer "F.SilkS")
		)
		(fp_line
			(start 15.01775 -5.171694)
			(end 14.957552 -5.171694)
			(stroke
				(width 0.1)
				(type default)
			)
			(layer "F.SilkS")
		)
		(fp_line
			(start 15.059152 -0.882904)
			(end 15.072106 -0.882904)
			(stroke
				(width 0.1)
				(type default)
			)
			(layer "F.SilkS")
		)
		(fp_line
			(start 15.059152 -0.882904)
			(end 15.072106 -0.882904)
			(stroke
				(width 0.1)
				(type default)
			)
			(layer "F.SilkS")
		)
		(fp_line
			(start 15.059152 -0.882904)
			(end 15.0749 -0.898398)
			(stroke
				(width 0.1)
				(type default)
			)
			(layer "F.SilkS")
		)
		(fp_line
			(start 15.059152 -0.882904)
			(end 15.0749 -0.898398)
			(stroke
				(width 0.1)
				(type default)
			)
			(layer "F.SilkS")
		)
		(fp_line
			(start 15.072106 -0.882904)
			(end 15.0749 -0.898398)
			(stroke
				(width 0.1)
				(type default)
			)
			(layer "F.SilkS")
		)
		(fp_line
			(start 15.072106 -0.882904)
			(end 15.0749 -0.898398)
			(stroke
				(width 0.1)
				(type default)
			)
			(layer "F.SilkS")
		)
		(fp_line
			(start 15.077694 -5.171694)
			(end 14.621002 -4.733036)
			(stroke
				(width 0.1)
				(type default)
			)
			(layer "F.SilkS")
		)
		(fp_line
			(start 15.077694 -5.171694)
			(end 14.621002 -4.733036)
			(stroke
				(width 0.1)
				(type default)
			)
			(layer "F.SilkS")
		)
		(fp_line
			(start 15.077694 -5.171694)
			(end 15.01775 -5.171694)
			(stroke
				(width 0.1)
				(type default)
			)
			(layer "F.SilkS")
		)
		(fp_line
			(start 15.077694 -5.171694)
			(end 15.01775 -5.171694)
			(stroke
				(width 0.1)
				(type default)
			)
			(layer "F.SilkS")
		)
		(fp_line
			(start 15.087092 -0.96774)
			(end 15.0749 -0.898398)
			(stroke
				(width 0.1)
				(type default)
			)
			(layer "F.SilkS")
		)
		(fp_line
			(start 15.087092 -0.96774)
			(end 15.0749 -0.898398)
			(stroke
				(width 0.1)
				(type default)
			)
			(layer "F.SilkS")
		)
		(fp_line
			(start 15.09903 -1.036828)
			(end 15.087092 -0.96774)
			(stroke
				(width 0.1)
				(type default)
			)
			(layer "F.SilkS")
		)
		(fp_line
			(start 15.09903 -1.036828)
			(end 15.087092 -0.96774)
			(stroke
				(width 0.1)
				(type default)
			)
			(layer "F.SilkS")
		)
		(fp_line
			(start 15.111476 -1.106424)
			(end 15.09903 -1.036828)
			(stroke
				(width 0.1)
				(type default)
			)
			(layer "F.SilkS")
		)
		(fp_line
			(start 15.111476 -1.106424)
			(end 15.09903 -1.036828)
			(stroke
				(width 0.1)
				(type default)
			)
			(layer "F.SilkS")
		)
		(fp_line
			(start 15.123922 -1.17602)
			(end 15.111476 -1.106424)
			(stroke
				(width 0.1)
				(type default)
			)
			(layer "F.SilkS")
		)
		(fp_line
			(start 15.123922 -1.17602)
			(end 15.111476 -1.106424)
			(stroke
				(width 0.1)
				(type default)
			)
			(layer "F.SilkS")
		)
		(fp_line
			(start 15.13586 -1.245362)
			(end 15.123922 -1.17602)
			(stroke
				(width 0.1)
				(type default)
			)
			(layer "F.SilkS")
		)
		(fp_line
			(start 15.13586 -1.245362)
			(end 15.123922 -1.17602)
			(stroke
				(width 0.1)
				(type default)
			)
			(layer "F.SilkS")
		)
		(fp_line
			(start 15.137892 -5.171694)
			(end 14.608556 -4.663948)
			(stroke
				(width 0.1)
				(type default)
			)
			(layer "F.SilkS")
		)
		(fp_line
			(start 15.137892 -5.171694)
			(end 14.608556 -4.663948)
			(stroke
				(width 0.1)
				(type default)
			)
			(layer "F.SilkS")
		)
		(fp_line
			(start 15.137892 -5.171694)
			(end 15.077694 -5.171694)
			(stroke
				(width 0.1)
				(type default)
			)
			(layer "F.SilkS")
		)
		(fp_line
			(start 15.137892 -5.171694)
			(end 15.077694 -5.171694)
			(stroke
				(width 0.1)
				(type default)
			)
			(layer "F.SilkS")
		)
		(fp_line
			(start 15.148052 -1.314704)
			(end 15.13586 -1.245362)
			(stroke
				(width 0.1)
				(type default)
			)
			(layer "F.SilkS")
		)
		(fp_line
			(start 15.148052 -1.314704)
			(end 15.13586 -1.245362)
			(stroke
				(width 0.1)
				(type default)
			)
			(layer "F.SilkS")
		)
		(fp_line
			(start 15.160498 -1.384046)
			(end 15.148052 -1.314704)
			(stroke
				(width 0.1)
				(type default)
			)
			(layer "F.SilkS")
		)
		(fp_line
			(start 15.160498 -1.384046)
			(end 15.148052 -1.314704)
			(stroke
				(width 0.1)
				(type default)
			)
			(layer "F.SilkS")
		)
		(fp_line
			(start 15.17269 -1.453642)
			(end 15.160498 -1.384046)
			(stroke
				(width 0.1)
				(type default)
			)
			(layer "F.SilkS")
		)
		(fp_line
			(start 15.17269 -1.453642)
			(end 15.160498 -1.384046)
			(stroke
				(width 0.1)
				(type default)
			)
			(layer "F.SilkS")
		)
		(fp_line
			(start 15.184882 -1.522984)
			(end 15.17269 -1.453642)
			(stroke
				(width 0.1)
				(type default)
			)
			(layer "F.SilkS")
		)
		(fp_line
			(start 15.184882 -1.522984)
			(end 15.17269 -1.453642)
			(stroke
				(width 0.1)
				(type default)
			)
			(layer "F.SilkS")
		)
		(fp_line
			(start 15.184882 -1.522984)
			(end 15.19682 -1.592326)
			(stroke
				(width 0.1)
				(type default)
			)
			(layer "F.SilkS")
		)
		(fp_line
			(start 15.184882 -1.522984)
			(end 15.19682 -1.592326)
			(stroke
				(width 0.1)
				(type default)
			)
			(layer "F.SilkS")
		)
		(fp_line
			(start 15.19682 -1.592326)
			(end 15.209266 -1.661922)
			(stroke
				(width 0.1)
				(type default)
			)
			(layer "F.SilkS")
		)
		(fp_line
			(start 15.19682 -1.592326)
			(end 15.209266 -1.661922)
			(stroke
				(width 0.1)
				(type default)
			)
			(layer "F.SilkS")
		)
		(fp_line
			(start 15.198344 -5.171694)
			(end 14.596364 -4.594352)
			(stroke
				(width 0.1)
				(type default)
			)
			(layer "F.SilkS")
		)
		(fp_line
			(start 15.198344 -5.171694)
			(end 14.596364 -4.594352)
			(stroke
				(width 0.1)
				(type default)
			)
			(layer "F.SilkS")
		)
		(fp_line
			(start 15.198344 -5.171694)
			(end 15.137892 -5.171694)
			(stroke
				(width 0.1)
				(type default)
			)
			(layer "F.SilkS")
		)
		(fp_line
			(start 15.198344 -5.171694)
			(end 15.137892 -5.171694)
			(stroke
				(width 0.1)
				(type default)
			)
			(layer "F.SilkS")
		)
		(fp_line
			(start 15.209266 -1.661922)
			(end 15.221458 -1.731518)
			(stroke
				(width 0.1)
				(type default)
			)
			(layer "F.SilkS")
		)
		(fp_line
			(start 15.209266 -1.661922)
			(end 15.221458 -1.731518)
			(stroke
				(width 0.1)
				(type default)
			)
			(layer "F.SilkS")
		)
		(fp_line
			(start 15.221458 -1.731518)
			(end 15.233396 -1.800606)
			(stroke
				(width 0.1)
				(type default)
			)
			(layer "F.SilkS")
		)
		(fp_line
			(start 15.221458 -1.731518)
			(end 15.233396 -1.800606)
			(stroke
				(width 0.1)
				(type default)
			)
			(layer "F.SilkS")
		)
		(fp_line
			(start 15.233396 -1.800606)
			(end 15.245842 -1.869948)
			(stroke
				(width 0.1)
				(type default)
			)
			(layer "F.SilkS")
		)
		(fp_line
			(start 15.233396 -1.800606)
			(end 15.245842 -1.869948)
			(stroke
				(width 0.1)
				(type default)
			)
			(layer "F.SilkS")
		)
		(fp_line
			(start 15.245842 -1.869948)
			(end 15.258288 -1.939544)
			(stroke
				(width 0.1)
				(type default)
			)
			(layer "F.SilkS")
		)
		(fp_line
			(start 15.245842 -1.869948)
			(end 15.258288 -1.939544)
			(stroke
				(width 0.1)
				(type default)
			)
			(layer "F.SilkS")
		)
		(fp_line
			(start 15.258288 -5.171694)
			(end 14.584426 -4.52501)
			(stroke
				(width 0.1)
				(type default)
			)
			(layer "F.SilkS")
		)
		(fp_line
			(start 15.258288 -5.171694)
			(end 14.584426 -4.52501)
			(stroke
				(width 0.1)
				(type default)
			)
			(layer "F.SilkS")
		)
		(fp_line
			(start 15.258288 -5.171694)
			(end 15.198344 -5.171694)
			(stroke
				(width 0.1)
				(type default)
			)
			(layer "F.SilkS")
		)
		(fp_line
			(start 15.258288 -5.171694)
			(end 15.198344 -5.171694)
			(stroke
				(width 0.1)
				(type default)
			)
			(layer "F.SilkS")
		)
		(fp_line
			(start 15.258288 -1.939544)
			(end 15.270226 -2.00914)
			(stroke
				(width 0.1)
				(type default)
			)
			(layer "F.SilkS")
		)
		(fp_line
			(start 15.258288 -1.939544)
			(end 15.270226 -2.00914)
			(stroke
				(width 0.1)
				(type default)
			)
			(layer "F.SilkS")
		)
		(fp_line
			(start 15.270226 -2.00914)
			(end 15.282418 -2.078482)
			(stroke
				(width 0.1)
				(type default)
			)
			(layer "F.SilkS")
		)
		(fp_line
			(start 15.270226 -2.00914)
			(end 15.282418 -2.078482)
			(stroke
				(width 0.1)
				(type default)
			)
			(layer "F.SilkS")
		)
		(fp_line
			(start 15.282418 -2.078482)
			(end 15.294864 -2.147824)
			(stroke
				(width 0.1)
				(type default)
			)
			(layer "F.SilkS")
		)
		(fp_line
			(start 15.282418 -2.078482)
			(end 15.294864 -2.147824)
			(stroke
				(width 0.1)
				(type default)
			)
			(layer "F.SilkS")
		)
		(fp_line
			(start 15.294864 -2.147824)
			(end 15.307056 -2.21742)
			(stroke
				(width 0.1)
				(type default)
			)
			(layer "F.SilkS")
		)
		(fp_line
			(start 15.294864 -2.147824)
			(end 15.307056 -2.21742)
			(stroke
				(width 0.1)
				(type default)
			)
			(layer "F.SilkS")
		)
		(fp_line
			(start 15.307056 -2.21742)
			(end 15.319248 -2.286762)
			(stroke
				(width 0.1)
				(type default)
			)
			(layer "F.SilkS")
		)
		(fp_line
			(start 15.307056 -2.21742)
			(end 15.319248 -2.286762)
			(stroke
				(width 0.1)
				(type default)
			)
			(layer "F.SilkS")
		)
		(fp_line
			(start 15.318486 -5.171694)
			(end 14.57198 -4.455668)
			(stroke
				(width 0.1)
				(type default)
			)
			(layer "F.SilkS")
		)
		(fp_line
			(start 15.318486 -5.171694)
			(end 14.57198 -4.455668)
			(stroke
				(width 0.1)
				(type default)
			)
			(layer "F.SilkS")
		)
		(fp_line
			(start 15.318486 -5.171694)
			(end 15.258288 -5.171694)
			(stroke
				(width 0.1)
				(type default)
			)
			(layer "F.SilkS")
		)
		(fp_line
			(start 15.318486 -5.171694)
			(end 15.258288 -5.171694)
			(stroke
				(width 0.1)
				(type default)
			)
			(layer "F.SilkS")
		)
		(fp_line
			(start 15.319248 -2.286762)
			(end 15.331186 -2.356104)
			(stroke
				(width 0.1)
				(type default)
			)
			(layer "F.SilkS")
		)
		(fp_line
			(start 15.319248 -2.286762)
			(end 15.331186 -2.356104)
			(stroke
				(width 0.1)
				(type default)
			)
			(layer "F.SilkS")
		)
		(fp_line
			(start 15.331186 -2.356104)
			(end 15.343632 -2.425446)
			(stroke
				(width 0.1)
				(type default)
			)
			(layer "F.SilkS")
		)
		(fp_line
			(start 15.331186 -2.356104)
			(end 15.343632 -2.425446)
			(stroke
				(width 0.1)
				(type default)
			)
			(layer "F.SilkS")
		)
		(fp_line
			(start 15.343632 -2.425446)
			(end 15.355824 -2.495042)
			(stroke
				(width 0.1)
				(type default)
			)
			(layer "F.SilkS")
		)
		(fp_line
			(start 15.343632 -2.425446)
			(end 15.355824 -2.495042)
			(stroke
				(width 0.1)
				(type default)
			)
			(layer "F.SilkS")
		)
		(fp_line
			(start 15.355824 -2.495042)
			(end 15.367762 -2.564384)
			(stroke
				(width 0.1)
				(type default)
			)
			(layer "F.SilkS")
		)
		(fp_line
			(start 15.355824 -2.495042)
			(end 15.367762 -2.564384)
			(stroke
				(width 0.1)
				(type default)
			)
			(layer "F.SilkS")
		)
		(fp_line
			(start 15.367762 -2.564384)
			(end 15.380208 -2.633726)
			(stroke
				(width 0.1)
				(type default)
			)
			(layer "F.SilkS")
		)
		(fp_line
			(start 15.367762 -2.564384)
			(end 15.380208 -2.633726)
			(stroke
				(width 0.1)
				(type default)
			)
			(layer "F.SilkS")
		)
		(fp_line
			(start 15.378938 -5.171694)
			(end 14.560042 -4.386326)
			(stroke
				(width 0.1)
				(type default)
			)
			(layer "F.SilkS")
		)
		(fp_line
			(start 15.378938 -5.171694)
			(end 14.560042 -4.386326)
			(stroke
				(width 0.1)
				(type default)
			)
			(layer "F.SilkS")
		)
		(fp_line
			(start 15.378938 -5.171694)
			(end 15.318486 -5.171694)
			(stroke
				(width 0.1)
				(type default)
			)
			(layer "F.SilkS")
		)
		(fp_line
			(start 15.378938 -5.171694)
			(end 15.318486 -5.171694)
			(stroke
				(width 0.1)
				(type default)
			)
			(layer "F.SilkS")
		)
		(fp_line
			(start 15.380208 -2.633726)
			(end 15.392654 -2.703322)
			(stroke
				(width 0.1)
				(type default)
			)
			(layer "F.SilkS")
		)
		(fp_line
			(start 15.380208 -2.633726)
			(end 15.392654 -2.703322)
			(stroke
				(width 0.1)
				(type default)
			)
			(layer "F.SilkS")
		)
		(fp_line
			(start 15.392654 -2.703322)
			(end 15.404592 -2.772664)
			(stroke
				(width 0.1)
				(type default)
			)
			(layer "F.SilkS")
		)
		(fp_line
			(start 15.392654 -2.703322)
			(end 15.404592 -2.772664)
			(stroke
				(width 0.1)
				(type default)
			)
			(layer "F.SilkS")
		)
		(fp_line
			(start 15.404592 -2.772664)
			(end 15.416784 -2.84226)
			(stroke
				(width 0.1)
				(type default)
			)
			(layer "F.SilkS")
		)
		(fp_line
			(start 15.404592 -2.772664)
			(end 15.416784 -2.84226)
			(stroke
				(width 0.1)
				(type default)
			)
			(layer "F.SilkS")
		)
		(fp_line
			(start 15.42923 -2.911602)
			(end 15.416784 -2.84226)
			(stroke
				(width 0.1)
				(type default)
			)
			(layer "F.SilkS")
		)
		(fp_line
			(start 15.42923 -2.911602)
			(end 15.416784 -2.84226)
			(stroke
				(width 0.1)
				(type default)
			)
			(layer "F.SilkS")
		)
		(fp_line
			(start 15.438882 -5.171694)
			(end 14.54785 -4.316984)
			(stroke
				(width 0.1)
				(type default)
			)
			(layer "F.SilkS")
		)
		(fp_line
			(start 15.438882 -5.171694)
			(end 14.54785 -4.316984)
			(stroke
				(width 0.1)
				(type default)
			)
			(layer "F.SilkS")
		)
		(fp_line
			(start 15.438882 -5.171694)
			(end 15.378938 -5.171694)
			(stroke
				(width 0.1)
				(type default)
			)
			(layer "F.SilkS")
		)
		(fp_line
			(start 15.438882 -5.171694)
			(end 15.378938 -5.171694)
			(stroke
				(width 0.1)
				(type default)
			)
			(layer "F.SilkS")
		)
		(fp_line
			(start 15.441168 -2.980944)
			(end 14.084808 -1.679702)
			(stroke
				(width 0.1)
				(type default)
			)
			(layer "F.SilkS")
		)
		(fp_line
			(start 15.441168 -2.980944)
			(end 14.084808 -1.679702)
			(stroke
				(width 0.1)
				(type default)
			)
			(layer "F.SilkS")
		)
		(fp_line
			(start 15.441168 -2.980944)
			(end 15.42923 -2.911602)
			(stroke
				(width 0.1)
				(type default)
			)
			(layer "F.SilkS")
		)
		(fp_line
			(start 15.441168 -2.980944)
			(end 15.42923 -2.911602)
			(stroke
				(width 0.1)
				(type default)
			)
			(layer "F.SilkS")
		)
		(fp_line
			(start 15.45336 -3.050286)
			(end 14.097254 -1.749044)
			(stroke
				(width 0.1)
				(type default)
			)
			(layer "F.SilkS")
		)
		(fp_line
			(start 15.45336 -3.050286)
			(end 14.097254 -1.749044)
			(stroke
				(width 0.1)
				(type default)
			)
			(layer "F.SilkS")
		)
		(fp_line
			(start 15.45336 -3.050286)
			(end 15.441168 -2.980944)
			(stroke
				(width 0.1)
				(type default)
			)
			(layer "F.SilkS")
		)
		(fp_line
			(start 15.45336 -3.050286)
			(end 15.441168 -2.980944)
			(stroke
				(width 0.1)
				(type default)
			)
			(layer "F.SilkS")
		)
		(fp_line
			(start 15.465552 -3.119882)
			(end 14.109192 -1.81864)
			(stroke
				(width 0.1)
				(type default)
			)
			(layer "F.SilkS")
		)
		(fp_line
			(start 15.465552 -3.119882)
			(end 14.109192 -1.81864)
			(stroke
				(width 0.1)
				(type default)
			)
			(layer "F.SilkS")
		)
		(fp_line
			(start 15.465552 -3.119882)
			(end 15.45336 -3.050286)
			(stroke
				(width 0.1)
				(type default)
			)
			(layer "F.SilkS")
		)
		(fp_line
			(start 15.465552 -3.119882)
			(end 15.45336 -3.050286)
			(stroke
				(width 0.1)
				(type default)
			)
			(layer "F.SilkS")
		)
		(fp_line
			(start 15.477998 -3.189224)
			(end 14.121384 -1.887982)
			(stroke
				(width 0.1)
				(type default)
			)
			(layer "F.SilkS")
		)
		(fp_line
			(start 15.477998 -3.189224)
			(end 14.121384 -1.887982)
			(stroke
				(width 0.1)
				(type default)
			)
			(layer "F.SilkS")
		)
		(fp_line
			(start 15.477998 -3.189224)
			(end 15.465552 -3.119882)
			(stroke
				(width 0.1)
				(type default)
			)
			(layer "F.SilkS")
		)
		(fp_line
			(start 15.477998 -3.189224)
			(end 15.465552 -3.119882)
			(stroke
				(width 0.1)
				(type default)
			)
			(layer "F.SilkS")
		)
		(fp_line
			(start 15.491714 -3.260344)
			(end 14.13383 -1.957324)
			(stroke
				(width 0.1)
				(type default)
			)
			(layer "F.SilkS")
		)
		(fp_line
			(start 15.491714 -3.260344)
			(end 14.13383 -1.957324)
			(stroke
				(width 0.1)
				(type default)
			)
			(layer "F.SilkS")
		)
		(fp_line
			(start 15.49908 -5.171694)
			(end 14.535404 -4.247388)
			(stroke
				(width 0.1)
				(type default)
			)
			(layer "F.SilkS")
		)
		(fp_line
			(start 15.49908 -5.171694)
			(end 14.535404 -4.247388)
			(stroke
				(width 0.1)
				(type default)
			)
			(layer "F.SilkS")
		)
		(fp_line
			(start 15.49908 -5.171694)
			(end 15.438882 -5.171694)
			(stroke
				(width 0.1)
				(type default)
			)
			(layer "F.SilkS")
		)
		(fp_line
			(start 15.49908 -5.171694)
			(end 15.438882 -5.171694)
			(stroke
				(width 0.1)
				(type default)
			)
			(layer "F.SilkS")
		)
		(fp_line
			(start 15.508478 -3.334004)
			(end 14.145768 -2.02692)
			(stroke
				(width 0.1)
				(type default)
			)
			(layer "F.SilkS")
		)
		(fp_line
			(start 15.508478 -3.334004)
			(end 14.145768 -2.02692)
			(stroke
				(width 0.1)
				(type default)
			)
			(layer "F.SilkS")
		)
		(fp_line
			(start 15.524988 -3.40741)
			(end 14.15796 -2.096262)
			(stroke
				(width 0.1)
				(type default)
			)
			(layer "F.SilkS")
		)
		(fp_line
			(start 15.524988 -3.40741)
			(end 14.15796 -2.096262)
			(stroke
				(width 0.1)
				(type default)
			)
			(layer "F.SilkS")
		)
		(fp_line
			(start 15.54099 -3.480562)
			(end 14.170406 -2.165604)
			(stroke
				(width 0.1)
				(type default)
			)
			(layer "F.SilkS")
		)
		(fp_line
			(start 15.54099 -3.480562)
			(end 14.170406 -2.165604)
			(stroke
				(width 0.1)
				(type default)
			)
			(layer "F.SilkS")
		)
		(fp_line
			(start 15.559278 -5.171694)
			(end 14.523466 -4.178046)
			(stroke
				(width 0.1)
				(type default)
			)
			(layer "F.SilkS")
		)
		(fp_line
			(start 15.559278 -5.171694)
			(end 14.523466 -4.178046)
			(stroke
				(width 0.1)
				(type default)
			)
			(layer "F.SilkS")
		)
		(fp_line
			(start 15.559278 -5.171694)
			(end 15.49908 -5.171694)
			(stroke
				(width 0.1)
				(type default)
			)
			(layer "F.SilkS")
		)
		(fp_line
			(start 15.559278 -5.171694)
			(end 15.49908 -5.171694)
			(stroke
				(width 0.1)
				(type default)
			)
			(layer "F.SilkS")
		)
		(fp_line
			(start 15.570962 -3.566922)
			(end 14.182344 -2.234946)
			(stroke
				(width 0.1)
				(type default)
			)
			(layer "F.SilkS")
		)
		(fp_line
			(start 15.570962 -3.566922)
			(end 14.182344 -2.234946)
			(stroke
				(width 0.1)
				(type default)
			)
			(layer "F.SilkS")
		)
		(fp_line
			(start 15.601442 -3.654044)
			(end 14.194282 -2.304288)
			(stroke
				(width 0.1)
				(type default)
			)
			(layer "F.SilkS")
		)
		(fp_line
			(start 15.601442 -3.654044)
			(end 14.194282 -2.304288)
			(stroke
				(width 0.1)
				(type default)
			)
			(layer "F.SilkS")
		)
		(fp_line
			(start 15.619222 -5.171694)
			(end 14.511274 -4.108704)
			(stroke
				(width 0.1)
				(type default)
			)
			(layer "F.SilkS")
		)
		(fp_line
			(start 15.619222 -5.171694)
			(end 14.511274 -4.108704)
			(stroke
				(width 0.1)
				(type default)
			)
			(layer "F.SilkS")
		)
		(fp_line
			(start 15.619222 -5.171694)
			(end 15.559278 -5.171694)
			(stroke
				(width 0.1)
				(type default)
			)
			(layer "F.SilkS")
		)
		(fp_line
			(start 15.619222 -5.171694)
			(end 15.559278 -5.171694)
			(stroke
				(width 0.1)
				(type default)
			)
			(layer "F.SilkS")
		)
		(fp_line
			(start 15.649702 -3.75793)
			(end 14.206728 -2.373884)
			(stroke
				(width 0.1)
				(type default)
			)
			(layer "F.SilkS")
		)
		(fp_line
			(start 15.649702 -3.75793)
			(end 14.206728 -2.373884)
			(stroke
				(width 0.1)
				(type default)
			)
			(layer "F.SilkS")
		)
		(fp_line
			(start 15.679166 -5.171694)
			(end 14.498828 -4.039362)
			(stroke
				(width 0.1)
				(type default)
			)
			(layer "F.SilkS")
		)
		(fp_line
			(start 15.679166 -5.171694)
			(end 14.498828 -4.039362)
			(stroke
				(width 0.1)
				(type default)
			)
			(layer "F.SilkS")
		)
		(fp_line
			(start 15.679166 -5.171694)
			(end 15.619222 -5.171694)
			(stroke
				(width 0.1)
				(type default)
			)
			(layer "F.SilkS")
		)
		(fp_line
			(start 15.679166 -5.171694)
			(end 15.619222 -5.171694)
			(stroke
				(width 0.1)
				(type default)
			)
			(layer "F.SilkS")
		)
		(fp_line
			(start 15.729458 -3.892296)
			(end 14.21892 -2.443226)
			(stroke
				(width 0.1)
				(type default)
			)
			(layer "F.SilkS")
		)
		(fp_line
			(start 15.729458 -3.892296)
			(end 14.21892 -2.443226)
			(stroke
				(width 0.1)
				(type default)
			)
			(layer "F.SilkS")
		)
		(fp_line
			(start 15.739618 -5.171694)
			(end 14.486636 -3.969766)
			(stroke
				(width 0.1)
				(type default)
			)
			(layer "F.SilkS")
		)
		(fp_line
			(start 15.739618 -5.171694)
			(end 14.486636 -3.969766)
			(stroke
				(width 0.1)
				(type default)
			)
			(layer "F.SilkS")
		)
		(fp_line
			(start 15.739618 -5.171694)
			(end 15.679166 -5.171694)
			(stroke
				(width 0.1)
				(type default)
			)
			(layer "F.SilkS")
		)
		(fp_line
			(start 15.739618 -5.171694)
			(end 15.679166 -5.171694)
			(stroke
				(width 0.1)
				(type default)
			)
			(layer "F.SilkS")
		)
		(fp_line
			(start 15.781274 -4.923028)
			(end 14.42593 -3.622802)
			(stroke
				(width 0.1)
				(type default)
			)
			(layer "F.SilkS")
		)
		(fp_line
			(start 15.781274 -4.923028)
			(end 14.42593 -3.622802)
			(stroke
				(width 0.1)
				(type default)
			)
			(layer "F.SilkS")
		)
		(fp_line
			(start 15.781274 -4.923028)
			(end 15.79372 -4.992624)
			(stroke
				(width 0.1)
				(type default)
			)
			(layer "F.SilkS")
		)
		(fp_line
			(start 15.781274 -4.923028)
			(end 15.79372 -4.992624)
			(stroke
				(width 0.1)
				(type default)
			)
			(layer "F.SilkS")
		)
		(fp_line
			(start 15.79372 -4.992624)
			(end 14.438376 -3.692398)
			(stroke
				(width 0.1)
				(type default)
			)
			(layer "F.SilkS")
		)
		(fp_line
			(start 15.79372 -4.992624)
			(end 14.438376 -3.692398)
			(stroke
				(width 0.1)
				(type default)
			)
			(layer "F.SilkS")
		)
		(fp_line
			(start 15.79372 -4.992624)
			(end 15.805658 -5.061966)
			(stroke
				(width 0.1)
				(type default)
			)
			(layer "F.SilkS")
		)
		(fp_line
			(start 15.79372 -4.992624)
			(end 15.805658 -5.061966)
			(stroke
				(width 0.1)
				(type default)
			)
			(layer "F.SilkS")
		)
		(fp_line
			(start 15.799816 -5.171694)
			(end 14.474952 -3.900424)
			(stroke
				(width 0.1)
				(type default)
			)
			(layer "F.SilkS")
		)
		(fp_line
			(start 15.799816 -5.171694)
			(end 14.474952 -3.900424)
			(stroke
				(width 0.1)
				(type default)
			)
			(layer "F.SilkS")
		)
		(fp_line
			(start 15.799816 -5.171694)
			(end 15.739618 -5.171694)
			(stroke
				(width 0.1)
				(type default)
			)
			(layer "F.SilkS")
		)
		(fp_line
			(start 15.799816 -5.171694)
			(end 15.739618 -5.171694)
			(stroke
				(width 0.1)
				(type default)
			)
			(layer "F.SilkS")
		)
		(fp_line
			(start 15.805658 -5.061966)
			(end 14.45006 -3.76174)
			(stroke
				(width 0.1)
				(type default)
			)
			(layer "F.SilkS")
		)
		(fp_line
			(start 15.805658 -5.061966)
			(end 14.45006 -3.76174)
			(stroke
				(width 0.1)
				(type default)
			)
			(layer "F.SilkS")
		)
		(fp_line
			(start 15.805658 -5.061966)
			(end 15.81785 -5.131308)
			(stroke
				(width 0.1)
				(type default)
			)
			(layer "F.SilkS")
		)
		(fp_line
			(start 15.805658 -5.061966)
			(end 15.81785 -5.131308)
			(stroke
				(width 0.1)
				(type default)
			)
			(layer "F.SilkS")
		)
		(fp_line
			(start 15.81785 -5.131308)
			(end 14.462506 -3.831082)
			(stroke
				(width 0.1)
				(type default)
			)
			(layer "F.SilkS")
		)
		(fp_line
			(start 15.81785 -5.131308)
			(end 14.462506 -3.831082)
			(stroke
				(width 0.1)
				(type default)
			)
			(layer "F.SilkS")
		)
		(fp_line
			(start 15.81785 -5.131308)
			(end 15.824962 -5.171694)
			(stroke
				(width 0.1)
				(type default)
			)
			(layer "F.SilkS")
		)
		(fp_line
			(start 15.81785 -5.131308)
			(end 15.824962 -5.171694)
			(stroke
				(width 0.1)
				(type default)
			)
			(layer "F.SilkS")
		)
		(fp_line
			(start 15.824962 -5.171694)
			(end 15.799816 -5.171694)
			(stroke
				(width 0.1)
				(type default)
			)
			(layer "F.SilkS")
		)
		(fp_line
			(start 15.824962 -5.171694)
			(end 15.799816 -5.171694)
			(stroke
				(width 0.1)
				(type default)
			)
			(layer "F.SilkS")
		)
		(fp_line
			(start 15.884652 -4.96443)
			(end 14.413484 -3.55346)
			(stroke
				(width 0.1)
				(type default)
			)
			(layer "F.SilkS")
		)
		(fp_line
			(start 15.884652 -4.96443)
			(end 14.413484 -3.55346)
			(stroke
				(width 0.1)
				(type default)
			)
			(layer "F.SilkS")
		)
		(fp_line
			(start 16.049498 -5.065268)
			(end 14.401546 -3.484118)
			(stroke
				(width 0.1)
				(type default)
			)
			(layer "F.SilkS")
		)
		(fp_line
			(start 16.049498 -5.065268)
			(end 14.401546 -3.484118)
			(stroke
				(width 0.1)
				(type default)
			)
			(layer "F.SilkS")
		)
		(fp_line
			(start 16.169132 -5.12191)
			(end 14.389354 -3.414776)
			(stroke
				(width 0.1)
				(type default)
			)
			(layer "F.SilkS")
		)
		(fp_line
			(start 16.169132 -5.12191)
			(end 14.389354 -3.414776)
			(stroke
				(width 0.1)
				(type default)
			)
			(layer "F.SilkS")
		)
		(fp_line
			(start 16.270986 -5.161788)
			(end 14.376908 -3.34518)
			(stroke
				(width 0.1)
				(type default)
			)
			(layer "F.SilkS")
		)
		(fp_line
			(start 16.270986 -5.161788)
			(end 14.376908 -3.34518)
			(stroke
				(width 0.1)
				(type default)
			)
			(layer "F.SilkS")
		)
		(fp_line
			(start 16.355568 -5.18541)
			(end 14.36497 -3.275838)
			(stroke
				(width 0.1)
				(type default)
			)
			(layer "F.SilkS")
		)
		(fp_line
			(start 16.355568 -5.18541)
			(end 14.36497 -3.275838)
			(stroke
				(width 0.1)
				(type default)
			)
			(layer "F.SilkS")
		)
		(fp_line
			(start 16.439896 -5.208778)
			(end 14.352778 -3.206496)
			(stroke
				(width 0.1)
				(type default)
			)
			(layer "F.SilkS")
		)
		(fp_line
			(start 16.439896 -5.208778)
			(end 14.352778 -3.206496)
			(stroke
				(width 0.1)
				(type default)
			)
			(layer "F.SilkS")
		)
		(fp_line
			(start 16.52397 -5.231638)
			(end 14.340586 -3.137154)
			(stroke
				(width 0.1)
				(type default)
			)
			(layer "F.SilkS")
		)
		(fp_line
			(start 16.52397 -5.231638)
			(end 14.340586 -3.137154)
			(stroke
				(width 0.1)
				(type default)
			)
			(layer "F.SilkS")
		)
		(fp_line
			(start 16.533622 -0.882904)
			(end 16.562832 -0.882904)
			(stroke
				(width 0.1)
				(type default)
			)
			(layer "F.SilkS")
		)
		(fp_line
			(start 16.533622 -0.882904)
			(end 16.562832 -0.882904)
			(stroke
				(width 0.1)
				(type default)
			)
			(layer "F.SilkS")
		)
		(fp_line
			(start 16.539718 -0.918464)
			(end 16.533622 -0.882904)
			(stroke
				(width 0.1)
				(type default)
			)
			(layer "F.SilkS")
		)
		(fp_line
			(start 16.539718 -0.918464)
			(end 16.533622 -0.882904)
			(stroke
				(width 0.1)
				(type default)
			)
			(layer "F.SilkS")
		)
		(fp_line
			(start 16.539718 -0.918464)
			(end 17.896586 -2.21996)
			(stroke
				(width 0.1)
				(type default)
			)
			(layer "F.SilkS")
		)
		(fp_line
			(start 16.539718 -0.918464)
			(end 17.896586 -2.21996)
			(stroke
				(width 0.1)
				(type default)
			)
			(layer "F.SilkS")
		)
		(fp_line
			(start 16.552164 -0.987806)
			(end 16.539718 -0.918464)
			(stroke
				(width 0.1)
				(type default)
			)
			(layer "F.SilkS")
		)
		(fp_line
			(start 16.552164 -0.987806)
			(end 16.539718 -0.918464)
			(stroke
				(width 0.1)
				(type default)
			)
			(layer "F.SilkS")
		)
		(fp_line
			(start 16.552164 -0.987806)
			(end 17.908524 -2.289048)
			(stroke
				(width 0.1)
				(type default)
			)
			(layer "F.SilkS")
		)
		(fp_line
			(start 16.552164 -0.987806)
			(end 17.908524 -2.289048)
			(stroke
				(width 0.1)
				(type default)
			)
			(layer "F.SilkS")
		)
		(fp_line
			(start 16.562832 -0.882904)
			(end 16.623284 -0.882904)
			(stroke
				(width 0.1)
				(type default)
			)
			(layer "F.SilkS")
		)
		(fp_line
			(start 16.562832 -0.882904)
			(end 16.623284 -0.882904)
			(stroke
				(width 0.1)
				(type default)
			)
			(layer "F.SilkS")
		)
		(fp_line
			(start 16.562832 -0.882904)
			(end 17.88414 -2.150364)
			(stroke
				(width 0.1)
				(type default)
			)
			(layer "F.SilkS")
		)
		(fp_line
			(start 16.562832 -0.882904)
			(end 17.88414 -2.150364)
			(stroke
				(width 0.1)
				(type default)
			)
			(layer "F.SilkS")
		)
		(fp_line
			(start 16.564356 -1.057148)
			(end 16.552164 -0.987806)
			(stroke
				(width 0.1)
				(type default)
			)
			(layer "F.SilkS")
		)
		(fp_line
			(start 16.564356 -1.057148)
			(end 16.552164 -0.987806)
			(stroke
				(width 0.1)
				(type default)
			)
			(layer "F.SilkS")
		)
		(fp_line
			(start 16.564356 -1.057148)
			(end 17.920716 -2.35839)
			(stroke
				(width 0.1)
				(type default)
			)
			(layer "F.SilkS")
		)
		(fp_line
			(start 16.564356 -1.057148)
			(end 17.920716 -2.35839)
			(stroke
				(width 0.1)
				(type default)
			)
			(layer "F.SilkS")
		)
		(fp_line
			(start 16.576294 -1.126744)
			(end 16.564356 -1.057148)
			(stroke
				(width 0.1)
				(type default)
			)
			(layer "F.SilkS")
		)
		(fp_line
			(start 16.576294 -1.126744)
			(end 16.564356 -1.057148)
			(stroke
				(width 0.1)
				(type default)
			)
			(layer "F.SilkS")
		)
		(fp_line
			(start 16.576294 -1.126744)
			(end 17.932908 -2.427732)
			(stroke
				(width 0.1)
				(type default)
			)
			(layer "F.SilkS")
		)
		(fp_line
			(start 16.576294 -1.126744)
			(end 17.932908 -2.427732)
			(stroke
				(width 0.1)
				(type default)
			)
			(layer "F.SilkS")
		)
		(fp_line
			(start 16.58874 -1.196086)
			(end 16.576294 -1.126744)
			(stroke
				(width 0.1)
				(type default)
			)
			(layer "F.SilkS")
		)
		(fp_line
			(start 16.58874 -1.196086)
			(end 16.576294 -1.126744)
			(stroke
				(width 0.1)
				(type default)
			)
			(layer "F.SilkS")
		)
		(fp_line
			(start 16.58874 -1.196086)
			(end 17.9451 -2.497328)
			(stroke
				(width 0.1)
				(type default)
			)
			(layer "F.SilkS")
		)
		(fp_line
			(start 16.58874 -1.196086)
			(end 17.9451 -2.497328)
			(stroke
				(width 0.1)
				(type default)
			)
			(layer "F.SilkS")
		)
		(fp_line
			(start 16.590772 -5.237734)
			(end 14.328394 -3.067558)
			(stroke
				(width 0.1)
				(type default)
			)
			(layer "F.SilkS")
		)
		(fp_line
			(start 16.590772 -5.237734)
			(end 14.328394 -3.067558)
			(stroke
				(width 0.1)
				(type default)
			)
			(layer "F.SilkS")
		)
		(fp_line
			(start 16.600932 -1.265428)
			(end 16.58874 -1.196086)
			(stroke
				(width 0.1)
				(type default)
			)
			(layer "F.SilkS")
		)
		(fp_line
			(start 16.600932 -1.265428)
			(end 16.58874 -1.196086)
			(stroke
				(width 0.1)
				(type default)
			)
			(layer "F.SilkS")
		)
		(fp_line
			(start 16.600932 -1.265428)
			(end 17.957038 -2.56667)
			(stroke
				(width 0.1)
				(type default)
			)
			(layer "F.SilkS")
		)
		(fp_line
			(start 16.600932 -1.265428)
			(end 17.957038 -2.56667)
			(stroke
				(width 0.1)
				(type default)
			)
			(layer "F.SilkS")
		)
		(fp_line
			(start 16.61287 -1.33477)
			(end 16.600932 -1.265428)
			(stroke
				(width 0.1)
				(type default)
			)
			(layer "F.SilkS")
		)
		(fp_line
			(start 16.61287 -1.33477)
			(end 16.600932 -1.265428)
			(stroke
				(width 0.1)
				(type default)
			)
			(layer "F.SilkS")
		)
		(fp_line
			(start 16.61287 -1.33477)
			(end 17.969484 -2.636012)
			(stroke
				(width 0.1)
				(type default)
			)
			(layer "F.SilkS")
		)
		(fp_line
			(start 16.61287 -1.33477)
			(end 17.969484 -2.636012)
			(stroke
				(width 0.1)
				(type default)
			)
			(layer "F.SilkS")
		)
		(fp_line
			(start 16.623284 -0.882904)
			(end 16.683228 -0.882904)
			(stroke
				(width 0.1)
				(type default)
			)
			(layer "F.SilkS")
		)
		(fp_line
			(start 16.623284 -0.882904)
			(end 16.683228 -0.882904)
			(stroke
				(width 0.1)
				(type default)
			)
			(layer "F.SilkS")
		)
		(fp_line
			(start 16.623284 -0.882904)
			(end 17.871948 -2.081022)
			(stroke
				(width 0.1)
				(type default)
			)
			(layer "F.SilkS")
		)
		(fp_line
			(start 16.623284 -0.882904)
			(end 17.871948 -2.081022)
			(stroke
				(width 0.1)
				(type default)
			)
			(layer "F.SilkS")
		)
		(fp_line
			(start 16.625316 -1.404366)
			(end 16.61287 -1.33477)
			(stroke
				(width 0.1)
				(type default)
			)
			(layer "F.SilkS")
		)
		(fp_line
			(start 16.625316 -1.404366)
			(end 16.61287 -1.33477)
			(stroke
				(width 0.1)
				(type default)
			)
			(layer "F.SilkS")
		)
		(fp_line
			(start 16.625316 -1.404366)
			(end 17.981676 -2.705608)
			(stroke
				(width 0.1)
				(type default)
			)
			(layer "F.SilkS")
		)
		(fp_line
			(start 16.625316 -1.404366)
			(end 17.981676 -2.705608)
			(stroke
				(width 0.1)
				(type default)
			)
			(layer "F.SilkS")
		)
		(fp_line
			(start 16.637762 -1.473962)
			(end 16.625316 -1.404366)
			(stroke
				(width 0.1)
				(type default)
			)
			(layer "F.SilkS")
		)
		(fp_line
			(start 16.637762 -1.473962)
			(end 16.625316 -1.404366)
			(stroke
				(width 0.1)
				(type default)
			)
			(layer "F.SilkS")
		)
		(fp_line
			(start 16.637762 -1.473962)
			(end 17.993614 -2.77495)
			(stroke
				(width 0.1)
				(type default)
			)
			(layer "F.SilkS")
		)
		(fp_line
			(start 16.637762 -1.473962)
			(end 17.993614 -2.77495)
			(stroke
				(width 0.1)
				(type default)
			)
			(layer "F.SilkS")
		)
		(fp_line
			(start 16.6497 -1.54305)
			(end 16.637762 -1.473962)
			(stroke
				(width 0.1)
				(type default)
			)
			(layer "F.SilkS")
		)
		(fp_line
			(start 16.6497 -1.54305)
			(end 16.637762 -1.473962)
			(stroke
				(width 0.1)
				(type default)
			)
			(layer "F.SilkS")
		)
		(fp_line
			(start 16.6497 -1.54305)
			(end 18.00606 -2.844292)
			(stroke
				(width 0.1)
				(type default)
			)
			(layer "F.SilkS")
		)
		(fp_line
			(start 16.6497 -1.54305)
			(end 18.00606 -2.844292)
			(stroke
				(width 0.1)
				(type default)
			)
			(layer "F.SilkS")
		)
		(fp_line
			(start 16.657066 -5.24383)
			(end 14.316456 -2.998216)
			(stroke
				(width 0.1)
				(type default)
			)
			(layer "F.SilkS")
		)
		(fp_line
			(start 16.657066 -5.24383)
			(end 14.316456 -2.998216)
			(stroke
				(width 0.1)
				(type default)
			)
			(layer "F.SilkS")
		)
		(fp_line
			(start 16.661892 -1.612646)
			(end 16.6497 -1.54305)
			(stroke
				(width 0.1)
				(type default)
			)
			(layer "F.SilkS")
		)
		(fp_line
			(start 16.661892 -1.612646)
			(end 16.6497 -1.54305)
			(stroke
				(width 0.1)
				(type default)
			)
			(layer "F.SilkS")
		)
		(fp_line
			(start 16.661892 -1.612646)
			(end 18.017998 -2.913634)
			(stroke
				(width 0.1)
				(type default)
			)
			(layer "F.SilkS")
		)
		(fp_line
			(start 16.661892 -1.612646)
			(end 18.017998 -2.913634)
			(stroke
				(width 0.1)
				(type default)
			)
			(layer "F.SilkS")
		)
		(fp_line
			(start 16.674084 -1.681988)
			(end 16.661892 -1.612646)
			(stroke
				(width 0.1)
				(type default)
			)
			(layer "F.SilkS")
		)
		(fp_line
			(start 16.674084 -1.681988)
			(end 16.661892 -1.612646)
			(stroke
				(width 0.1)
				(type default)
			)
			(layer "F.SilkS")
		)
		(fp_line
			(start 16.674084 -1.681988)
			(end 18.03019 -2.982976)
			(stroke
				(width 0.1)
				(type default)
			)
			(layer "F.SilkS")
		)
		(fp_line
			(start 16.674084 -1.681988)
			(end 18.03019 -2.982976)
			(stroke
				(width 0.1)
				(type default)
			)
			(layer "F.SilkS")
		)
		(fp_line
			(start 16.683228 -0.882904)
			(end 16.743426 -0.882904)
			(stroke
				(width 0.1)
				(type default)
			)
			(layer "F.SilkS")
		)
		(fp_line
			(start 16.683228 -0.882904)
			(end 16.743426 -0.882904)
			(stroke
				(width 0.1)
				(type default)
			)
			(layer "F.SilkS")
		)
		(fp_line
			(start 16.683228 -0.882904)
			(end 17.86001 -2.011426)
			(stroke
				(width 0.1)
				(type default)
			)
			(layer "F.SilkS")
		)
		(fp_line
			(start 16.683228 -0.882904)
			(end 17.86001 -2.011426)
			(stroke
				(width 0.1)
				(type default)
			)
			(layer "F.SilkS")
		)
		(fp_line
			(start 16.686276 -1.751584)
			(end 16.674084 -1.681988)
			(stroke
				(width 0.1)
				(type default)
			)
			(layer "F.SilkS")
		)
		(fp_line
			(start 16.686276 -1.751584)
			(end 16.674084 -1.681988)
			(stroke
				(width 0.1)
				(type default)
			)
			(layer "F.SilkS")
		)
		(fp_line
			(start 16.686276 -1.751584)
			(end 18.042636 -3.052572)
			(stroke
				(width 0.1)
				(type default)
			)
			(layer "F.SilkS")
		)
		(fp_line
			(start 16.686276 -1.751584)
			(end 18.042636 -3.052572)
			(stroke
				(width 0.1)
				(type default)
			)
			(layer "F.SilkS")
		)
		(fp_line
			(start 16.698214 -1.820926)
			(end 16.686276 -1.751584)
			(stroke
				(width 0.1)
				(type default)
			)
			(layer "F.SilkS")
		)
		(fp_line
			(start 16.698214 -1.820926)
			(end 16.686276 -1.751584)
			(stroke
				(width 0.1)
				(type default)
			)
			(layer "F.SilkS")
		)
		(fp_line
			(start 16.698214 -1.820926)
			(end 18.054574 -3.121914)
			(stroke
				(width 0.1)
				(type default)
			)
			(layer "F.SilkS")
		)
		(fp_line
			(start 16.698214 -1.820926)
			(end 18.054574 -3.121914)
			(stroke
				(width 0.1)
				(type default)
			)
			(layer "F.SilkS")
		)
		(fp_line
			(start 16.71066 -1.890268)
			(end 16.698214 -1.820926)
			(stroke
				(width 0.1)
				(type default)
			)
			(layer "F.SilkS")
		)
		(fp_line
			(start 16.71066 -1.890268)
			(end 16.698214 -1.820926)
			(stroke
				(width 0.1)
				(type default)
			)
			(layer "F.SilkS")
		)
		(fp_line
			(start 16.71066 -1.890268)
			(end 18.066766 -3.191002)
			(stroke
				(width 0.1)
				(type default)
			)
			(layer "F.SilkS")
		)
		(fp_line
			(start 16.71066 -1.890268)
			(end 18.066766 -3.191002)
			(stroke
				(width 0.1)
				(type default)
			)
			(layer "F.SilkS")
		)
		(fp_line
			(start 16.723106 -1.95961)
			(end 16.71066 -1.890268)
			(stroke
				(width 0.1)
				(type default)
			)
			(layer "F.SilkS")
		)
		(fp_line
			(start 16.723106 -1.95961)
			(end 16.71066 -1.890268)
			(stroke
				(width 0.1)
				(type default)
			)
			(layer "F.SilkS")
		)
		(fp_line
			(start 16.723106 -1.95961)
			(end 18.079212 -3.260598)
			(stroke
				(width 0.1)
				(type default)
			)
			(layer "F.SilkS")
		)
		(fp_line
			(start 16.723106 -1.95961)
			(end 18.079212 -3.260598)
			(stroke
				(width 0.1)
				(type default)
			)
			(layer "F.SilkS")
		)
		(fp_line
			(start 16.723868 -5.25018)
			(end 14.30401 -2.928874)
			(stroke
				(width 0.1)
				(type default)
			)
			(layer "F.SilkS")
		)
		(fp_line
			(start 16.723868 -5.25018)
			(end 14.30401 -2.928874)
			(stroke
				(width 0.1)
				(type default)
			)
			(layer "F.SilkS")
		)
		(fp_line
			(start 16.735044 -2.028952)
			(end 16.723106 -1.95961)
			(stroke
				(width 0.1)
				(type default)
			)
			(layer "F.SilkS")
		)
		(fp_line
			(start 16.735044 -2.028952)
			(end 16.723106 -1.95961)
			(stroke
				(width 0.1)
				(type default)
			)
			(layer "F.SilkS")
		)
		(fp_line
			(start 16.735044 -2.028952)
			(end 18.089372 -3.328416)
			(stroke
				(width 0.1)
				(type default)
			)
			(layer "F.SilkS")
		)
		(fp_line
			(start 16.735044 -2.028952)
			(end 18.089372 -3.328416)
			(stroke
				(width 0.1)
				(type default)
			)
			(layer "F.SilkS")
		)
		(fp_line
			(start 16.743426 -0.882904)
			(end 16.803624 -0.882904)
			(stroke
				(width 0.1)
				(type default)
			)
			(layer "F.SilkS")
		)
		(fp_line
			(start 16.743426 -0.882904)
			(end 16.803624 -0.882904)
			(stroke
				(width 0.1)
				(type default)
			)
			(layer "F.SilkS")
		)
		(fp_line
			(start 16.743426 -0.882904)
			(end 17.847564 -1.942338)
			(stroke
				(width 0.1)
				(type default)
			)
			(layer "F.SilkS")
		)
		(fp_line
			(start 16.743426 -0.882904)
			(end 17.847564 -1.942338)
			(stroke
				(width 0.1)
				(type default)
			)
			(layer "F.SilkS")
		)
		(fp_line
			(start 16.747236 -2.098548)
			(end 16.735044 -2.028952)
			(stroke
				(width 0.1)
				(type default)
			)
			(layer "F.SilkS")
		)
		(fp_line
			(start 16.747236 -2.098548)
			(end 16.735044 -2.028952)
			(stroke
				(width 0.1)
				(type default)
			)
			(layer "F.SilkS")
		)
		(fp_line
			(start 16.747236 -2.098548)
			(end 18.097246 -3.393694)
			(stroke
				(width 0.1)
				(type default)
			)
			(layer "F.SilkS")
		)
		(fp_line
			(start 16.747236 -2.098548)
			(end 18.097246 -3.393694)
			(stroke
				(width 0.1)
				(type default)
			)
			(layer "F.SilkS")
		)
		(fp_line
			(start 16.759682 -2.16789)
			(end 16.747236 -2.098548)
			(stroke
				(width 0.1)
				(type default)
			)
			(layer "F.SilkS")
		)
		(fp_line
			(start 16.759682 -2.16789)
			(end 16.747236 -2.098548)
			(stroke
				(width 0.1)
				(type default)
			)
			(layer "F.SilkS")
		)
		(fp_line
			(start 16.759682 -2.16789)
			(end 18.105374 -3.458718)
			(stroke
				(width 0.1)
				(type default)
			)
			(layer "F.SilkS")
		)
		(fp_line
			(start 16.759682 -2.16789)
			(end 18.105374 -3.458718)
			(stroke
				(width 0.1)
				(type default)
			)
			(layer "F.SilkS")
		)
		(fp_line
			(start 16.77162 -2.237232)
			(end 16.759682 -2.16789)
			(stroke
				(width 0.1)
				(type default)
			)
			(layer "F.SilkS")
		)
		(fp_line
			(start 16.77162 -2.237232)
			(end 16.759682 -2.16789)
			(stroke
				(width 0.1)
				(type default)
			)
			(layer "F.SilkS")
		)
		(fp_line
			(start 16.77162 -2.237232)
			(end 18.113248 -3.52425)
			(stroke
				(width 0.1)
				(type default)
			)
			(layer "F.SilkS")
		)
		(fp_line
			(start 16.77162 -2.237232)
			(end 18.113248 -3.52425)
			(stroke
				(width 0.1)
				(type default)
			)
			(layer "F.SilkS")
		)
		(fp_line
			(start 16.783812 -2.306828)
			(end 16.77162 -2.237232)
			(stroke
				(width 0.1)
				(type default)
			)
			(layer "F.SilkS")
		)
		(fp_line
			(start 16.783812 -2.306828)
			(end 16.77162 -2.237232)
			(stroke
				(width 0.1)
				(type default)
			)
			(layer "F.SilkS")
		)
		(fp_line
			(start 16.783812 -2.306828)
			(end 18.121122 -3.589782)
			(stroke
				(width 0.1)
				(type default)
			)
			(layer "F.SilkS")
		)
		(fp_line
			(start 16.783812 -2.306828)
			(end 18.121122 -3.589782)
			(stroke
				(width 0.1)
				(type default)
			)
			(layer "F.SilkS")
		)
		(fp_line
			(start 16.790162 -5.256022)
			(end 14.291818 -2.859532)
			(stroke
				(width 0.1)
				(type default)
			)
			(layer "F.SilkS")
		)
		(fp_line
			(start 16.790162 -5.256022)
			(end 14.291818 -2.859532)
			(stroke
				(width 0.1)
				(type default)
			)
			(layer "F.SilkS")
		)
		(fp_line
			(start 16.796258 -2.37617)
			(end 16.783812 -2.306828)
			(stroke
				(width 0.1)
				(type default)
			)
			(layer "F.SilkS")
		)
		(fp_line
			(start 16.796258 -2.37617)
			(end 16.783812 -2.306828)
			(stroke
				(width 0.1)
				(type default)
			)
			(layer "F.SilkS")
		)
		(fp_line
			(start 16.796258 -2.37617)
			(end 18.129504 -3.65506)
			(stroke
				(width 0.1)
				(type default)
			)
			(layer "F.SilkS")
		)
		(fp_line
			(start 16.796258 -2.37617)
			(end 18.129504 -3.65506)
			(stroke
				(width 0.1)
				(type default)
			)
			(layer "F.SilkS")
		)
		(fp_line
			(start 16.803624 -0.882904)
			(end 16.863568 -0.882904)
			(stroke
				(width 0.1)
				(type default)
			)
			(layer "F.SilkS")
		)
		(fp_line
			(start 16.803624 -0.882904)
			(end 16.863568 -0.882904)
			(stroke
				(width 0.1)
				(type default)
			)
			(layer "F.SilkS")
		)
		(fp_line
			(start 16.803624 -0.882904)
			(end 17.835626 -1.872742)
			(stroke
				(width 0.1)
				(type default)
			)
			(layer "F.SilkS")
		)
		(fp_line
			(start 16.803624 -0.882904)
			(end 17.835626 -1.872742)
			(stroke
				(width 0.1)
				(type default)
			)
			(layer "F.SilkS")
		)
		(fp_line
			(start 16.808196 -2.445512)
			(end 16.796258 -2.37617)
			(stroke
				(width 0.1)
				(type default)
			)
			(layer "F.SilkS")
		)
		(fp_line
			(start 16.808196 -2.445512)
			(end 16.796258 -2.37617)
			(stroke
				(width 0.1)
				(type default)
			)
			(layer "F.SilkS")
		)
		(fp_line
			(start 16.808196 -2.445512)
			(end 18.13687 -3.720338)
			(stroke
				(width 0.1)
				(type default)
			)
			(layer "F.SilkS")
		)
		(fp_line
			(start 16.808196 -2.445512)
			(end 18.13687 -3.720338)
			(stroke
				(width 0.1)
				(type default)
			)
			(layer "F.SilkS")
		)
		(fp_line
			(start 16.820134 -2.515108)
			(end 16.808196 -2.445512)
			(stroke
				(width 0.1)
				(type default)
			)
			(layer "F.SilkS")
		)
		(fp_line
			(start 16.820134 -2.515108)
			(end 16.808196 -2.445512)
			(stroke
				(width 0.1)
				(type default)
			)
			(layer "F.SilkS")
		)
		(fp_line
			(start 16.820134 -2.515108)
			(end 16.83258 -2.58445)
			(stroke
				(width 0.1)
				(type default)
			)
			(layer "F.SilkS")
		)
		(fp_line
			(start 16.820134 -2.515108)
			(end 16.83258 -2.58445)
			(stroke
				(width 0.1)
				(type default)
			)
			(layer "F.SilkS")
		)
		(fp_line
			(start 16.820134 -2.515108)
			(end 18.138394 -3.779266)
			(stroke
				(width 0.1)
				(type default)
			)
			(layer "F.SilkS")
		)
		(fp_line
			(start 16.820134 -2.515108)
			(end 18.138394 -3.779266)
			(stroke
				(width 0.1)
				(type default)
			)
			(layer "F.SilkS")
		)
		(fp_line
			(start 16.845026 -2.653792)
			(end 16.83258 -2.58445)
			(stroke
				(width 0.1)
				(type default)
			)
			(layer "F.SilkS")
		)
		(fp_line
			(start 16.845026 -2.653792)
			(end 16.83258 -2.58445)
			(stroke
				(width 0.1)
				(type default)
			)
			(layer "F.SilkS")
		)
		(fp_line
			(start 16.845026 -2.653792)
			(end 18.137378 -3.89382)
			(stroke
				(width 0.1)
				(type default)
			)
			(layer "F.SilkS")
		)
		(fp_line
			(start 16.845026 -2.653792)
			(end 18.137378 -3.89382)
			(stroke
				(width 0.1)
				(type default)
			)
			(layer "F.SilkS")
		)
		(fp_line
			(start 16.854678 -5.26034)
			(end 14.27988 -2.79019)
			(stroke
				(width 0.1)
				(type default)
			)
			(layer "F.SilkS")
		)
		(fp_line
			(start 16.854678 -5.26034)
			(end 14.27988 -2.79019)
			(stroke
				(width 0.1)
				(type default)
			)
			(layer "F.SilkS")
		)
		(fp_line
			(start 16.857218 -2.723134)
			(end 16.845026 -2.653792)
			(stroke
				(width 0.1)
				(type default)
			)
			(layer "F.SilkS")
		)
		(fp_line
			(start 16.857218 -2.723134)
			(end 16.845026 -2.653792)
			(stroke
				(width 0.1)
				(type default)
			)
			(layer "F.SilkS")
		)
		(fp_line
			(start 16.857218 -2.723134)
			(end 18.13687 -3.95097)
			(stroke
				(width 0.1)
				(type default)
			)
			(layer "F.SilkS")
		)
		(fp_line
			(start 16.857218 -2.723134)
			(end 18.13687 -3.95097)
			(stroke
				(width 0.1)
				(type default)
			)
			(layer "F.SilkS")
		)
		(fp_line
			(start 16.863568 -0.882904)
			(end 16.92402 -0.882904)
			(stroke
				(width 0.1)
				(type default)
			)
			(layer "F.SilkS")
		)
		(fp_line
			(start 16.863568 -0.882904)
			(end 16.92402 -0.882904)
			(stroke
				(width 0.1)
				(type default)
			)
			(layer "F.SilkS")
		)
		(fp_line
			(start 16.863568 -0.882904)
			(end 17.823434 -1.8034)
			(stroke
				(width 0.1)
				(type default)
			)
			(layer "F.SilkS")
		)
		(fp_line
			(start 16.863568 -0.882904)
			(end 17.823434 -1.8034)
			(stroke
				(width 0.1)
				(type default)
			)
			(layer "F.SilkS")
		)
		(fp_line
			(start 16.869156 -2.79273)
			(end 16.857218 -2.723134)
			(stroke
				(width 0.1)
				(type default)
			)
			(layer "F.SilkS")
		)
		(fp_line
			(start 16.869156 -2.79273)
			(end 16.857218 -2.723134)
			(stroke
				(width 0.1)
				(type default)
			)
			(layer "F.SilkS")
		)
		(fp_line
			(start 16.869156 -2.79273)
			(end 18.136362 -4.008374)
			(stroke
				(width 0.1)
				(type default)
			)
			(layer "F.SilkS")
		)
		(fp_line
			(start 16.869156 -2.79273)
			(end 18.136362 -4.008374)
			(stroke
				(width 0.1)
				(type default)
			)
			(layer "F.SilkS")
		)
		(fp_line
			(start 16.881602 -2.862072)
			(end 16.869156 -2.79273)
			(stroke
				(width 0.1)
				(type default)
			)
			(layer "F.SilkS")
		)
		(fp_line
			(start 16.881602 -2.862072)
			(end 16.869156 -2.79273)
			(stroke
				(width 0.1)
				(type default)
			)
			(layer "F.SilkS")
		)
		(fp_line
			(start 16.881602 -2.862072)
			(end 18.136362 -4.065524)
			(stroke
				(width 0.1)
				(type default)
			)
			(layer "F.SilkS")
		)
		(fp_line
			(start 16.881602 -2.862072)
			(end 18.136362 -4.065524)
			(stroke
				(width 0.1)
				(type default)
			)
			(layer "F.SilkS")
		)
		(fp_line
			(start 16.89354 -2.931414)
			(end 16.881602 -2.862072)
			(stroke
				(width 0.1)
				(type default)
			)
			(layer "F.SilkS")
		)
		(fp_line
			(start 16.89354 -2.931414)
			(end 16.881602 -2.862072)
			(stroke
				(width 0.1)
				(type default)
			)
			(layer "F.SilkS")
		)
		(fp_line
			(start 16.89354 -2.931414)
			(end 18.134838 -4.121912)
			(stroke
				(width 0.1)
				(type default)
			)
			(layer "F.SilkS")
		)
		(fp_line
			(start 16.89354 -2.931414)
			(end 18.134838 -4.121912)
			(stroke
				(width 0.1)
				(type default)
			)
			(layer "F.SilkS")
		)
		(fp_line
			(start 16.905732 -3.000756)
			(end 16.89354 -2.931414)
			(stroke
				(width 0.1)
				(type default)
			)
			(layer "F.SilkS")
		)
		(fp_line
			(start 16.905732 -3.000756)
			(end 16.89354 -2.931414)
			(stroke
				(width 0.1)
				(type default)
			)
			(layer "F.SilkS")
		)
		(fp_line
			(start 16.905732 -3.000756)
			(end 18.125948 -4.171188)
			(stroke
				(width 0.1)
				(type default)
			)
			(layer "F.SilkS")
		)
		(fp_line
			(start 16.905732 -3.000756)
			(end 18.125948 -4.171188)
			(stroke
				(width 0.1)
				(type default)
			)
			(layer "F.SilkS")
		)
		(fp_line
			(start 16.909796 -5.255514)
			(end 14.267434 -2.720594)
			(stroke
				(width 0.1)
				(type default)
			)
			(layer "F.SilkS")
		)
		(fp_line
			(start 16.909796 -5.255514)
			(end 14.267434 -2.720594)
			(stroke
				(width 0.1)
				(type default)
			)
			(layer "F.SilkS")
		)
		(fp_line
			(start 16.918178 -3.070352)
			(end 16.905732 -3.000756)
			(stroke
				(width 0.1)
				(type default)
			)
			(layer "F.SilkS")
		)
		(fp_line
			(start 16.918178 -3.070352)
			(end 16.905732 -3.000756)
			(stroke
				(width 0.1)
				(type default)
			)
			(layer "F.SilkS")
		)
		(fp_line
			(start 16.918178 -3.070352)
			(end 18.117058 -4.220464)
			(stroke
				(width 0.1)
				(type default)
			)
			(layer "F.SilkS")
		)
		(fp_line
			(start 16.918178 -3.070352)
			(end 18.117058 -4.220464)
			(stroke
				(width 0.1)
				(type default)
			)
			(layer "F.SilkS")
		)
		(fp_line
			(start 16.92402 -0.882904)
			(end 16.984218 -0.882904)
			(stroke
				(width 0.1)
				(type default)
			)
			(layer "F.SilkS")
		)
		(fp_line
			(start 16.92402 -0.882904)
			(end 16.984218 -0.882904)
			(stroke
				(width 0.1)
				(type default)
			)
			(layer "F.SilkS")
		)
		(fp_line
			(start 16.92402 -0.882904)
			(end 17.810988 -1.734058)
			(stroke
				(width 0.1)
				(type default)
			)
			(layer "F.SilkS")
		)
		(fp_line
			(start 16.92402 -0.882904)
			(end 17.810988 -1.734058)
			(stroke
				(width 0.1)
				(type default)
			)
			(layer "F.SilkS")
		)
		(fp_line
			(start 16.930624 -3.139694)
			(end 16.918178 -3.070352)
			(stroke
				(width 0.1)
				(type default)
			)
			(layer "F.SilkS")
		)
		(fp_line
			(start 16.930624 -3.139694)
			(end 16.918178 -3.070352)
			(stroke
				(width 0.1)
				(type default)
			)
			(layer "F.SilkS")
		)
		(fp_line
			(start 16.96466 -5.25018)
			(end 14.255496 -2.651506)
			(stroke
				(width 0.1)
				(type default)
			)
			(layer "F.SilkS")
		)
		(fp_line
			(start 16.96466 -5.25018)
			(end 14.255496 -2.651506)
			(stroke
				(width 0.1)
				(type default)
			)
			(layer "F.SilkS")
		)
		(fp_line
			(start 16.984218 -0.882904)
			(end 17.044162 -0.882904)
			(stroke
				(width 0.1)
				(type default)
			)
			(layer "F.SilkS")
		)
		(fp_line
			(start 16.984218 -0.882904)
			(end 17.044162 -0.882904)
			(stroke
				(width 0.1)
				(type default)
			)
			(layer "F.SilkS")
		)
		(fp_line
			(start 16.984218 -0.882904)
			(end 17.79905 -1.664716)
			(stroke
				(width 0.1)
				(type default)
			)
			(layer "F.SilkS")
		)
		(fp_line
			(start 16.984218 -0.882904)
			(end 17.79905 -1.664716)
			(stroke
				(width 0.1)
				(type default)
			)
			(layer "F.SilkS")
		)
		(fp_line
			(start 17.01927 -5.245354)
			(end 14.243304 -2.58191)
			(stroke
				(width 0.1)
				(type default)
			)
			(layer "F.SilkS")
		)
		(fp_line
			(start 17.01927 -5.245354)
			(end 14.243304 -2.58191)
			(stroke
				(width 0.1)
				(type default)
			)
			(layer "F.SilkS")
		)
		(fp_line
			(start 17.044162 -0.882904)
			(end 17.10436 -0.882904)
			(stroke
				(width 0.1)
				(type default)
			)
			(layer "F.SilkS")
		)
		(fp_line
			(start 17.044162 -0.882904)
			(end 17.10436 -0.882904)
			(stroke
				(width 0.1)
				(type default)
			)
			(layer "F.SilkS")
		)
		(fp_line
			(start 17.044162 -0.882904)
			(end 17.786858 -1.595374)
			(stroke
				(width 0.1)
				(type default)
			)
			(layer "F.SilkS")
		)
		(fp_line
			(start 17.044162 -0.882904)
			(end 17.786858 -1.595374)
			(stroke
				(width 0.1)
				(type default)
			)
			(layer "F.SilkS")
		)
		(fp_line
			(start 17.074388 -5.240274)
			(end 14.230858 -2.512314)
			(stroke
				(width 0.1)
				(type default)
			)
			(layer "F.SilkS")
		)
		(fp_line
			(start 17.074388 -5.240274)
			(end 14.230858 -2.512314)
			(stroke
				(width 0.1)
				(type default)
			)
			(layer "F.SilkS")
		)
		(fp_line
			(start 17.10436 -0.882904)
			(end 17.164812 -0.882904)
			(stroke
				(width 0.1)
				(type default)
			)
			(layer "F.SilkS")
		)
		(fp_line
			(start 17.10436 -0.882904)
			(end 17.164812 -0.882904)
			(stroke
				(width 0.1)
				(type default)
			)
			(layer "F.SilkS")
		)
		(fp_line
			(start 17.10436 -0.882904)
			(end 17.774666 -1.525778)
			(stroke
				(width 0.1)
				(type default)
			)
			(layer "F.SilkS")
		)
		(fp_line
			(start 17.10436 -0.882904)
			(end 17.774666 -1.525778)
			(stroke
				(width 0.1)
				(type default)
			)
			(layer "F.SilkS")
		)
		(fp_line
			(start 17.129252 -5.235194)
			(end 15.934944 -4.0894)
			(stroke
				(width 0.1)
				(type default)
			)
			(layer "F.SilkS")
		)
		(fp_line
			(start 17.129252 -5.235194)
			(end 15.934944 -4.0894)
			(stroke
				(width 0.1)
				(type default)
			)
			(layer "F.SilkS")
		)
		(fp_line
			(start 17.164812 -0.882904)
			(end 17.224756 -0.882904)
			(stroke
				(width 0.1)
				(type default)
			)
			(layer "F.SilkS")
		)
		(fp_line
			(start 17.164812 -0.882904)
			(end 17.224756 -0.882904)
			(stroke
				(width 0.1)
				(type default)
			)
			(layer "F.SilkS")
		)
		(fp_line
			(start 17.164812 -0.882904)
			(end 17.762474 -1.456436)
			(stroke
				(width 0.1)
				(type default)
			)
			(layer "F.SilkS")
		)
		(fp_line
			(start 17.164812 -0.882904)
			(end 17.762474 -1.456436)
			(stroke
				(width 0.1)
				(type default)
			)
			(layer "F.SilkS")
		)
		(fp_line
			(start 17.184116 -5.230114)
			(end 16.052292 -4.144264)
			(stroke
				(width 0.1)
				(type default)
			)
			(layer "F.SilkS")
		)
		(fp_line
			(start 17.184116 -5.230114)
			(end 16.052292 -4.144264)
			(stroke
				(width 0.1)
				(type default)
			)
			(layer "F.SilkS")
		)
		(fp_line
			(start 17.224756 -0.882904)
			(end 17.284954 -0.882904)
			(stroke
				(width 0.1)
				(type default)
			)
			(layer "F.SilkS")
		)
		(fp_line
			(start 17.224756 -0.882904)
			(end 17.284954 -0.882904)
			(stroke
				(width 0.1)
				(type default)
			)
			(layer "F.SilkS")
		)
		(fp_line
			(start 17.224756 -0.882904)
			(end 17.750536 -1.387348)
			(stroke
				(width 0.1)
				(type default)
			)
			(layer "F.SilkS")
		)
		(fp_line
			(start 17.224756 -0.882904)
			(end 17.750536 -1.387348)
			(stroke
				(width 0.1)
				(type default)
			)
			(layer "F.SilkS")
		)
		(fp_line
			(start 17.235678 -5.221986)
			(end 16.13789 -4.168648)
			(stroke
				(width 0.1)
				(type default)
			)
			(layer "F.SilkS")
		)
		(fp_line
			(start 17.235678 -5.221986)
			(end 16.13789 -4.168648)
			(stroke
				(width 0.1)
				(type default)
			)
			(layer "F.SilkS")
		)
		(fp_line
			(start 17.280636 -5.207254)
			(end 16.218154 -4.187698)
			(stroke
				(width 0.1)
				(type default)
			)
			(layer "F.SilkS")
		)
		(fp_line
			(start 17.280636 -5.207254)
			(end 16.218154 -4.187698)
			(stroke
				(width 0.1)
				(type default)
			)
			(layer "F.SilkS")
		)
		(fp_line
			(start 17.284954 -0.882904)
			(end 17.345406 -0.882904)
			(stroke
				(width 0.1)
				(type default)
			)
			(layer "F.SilkS")
		)
		(fp_line
			(start 17.284954 -0.882904)
			(end 17.345406 -0.882904)
			(stroke
				(width 0.1)
				(type default)
			)
			(layer "F.SilkS")
		)
		(fp_line
			(start 17.284954 -0.882904)
			(end 17.73809 -1.317752)
			(stroke
				(width 0.1)
				(type default)
			)
			(layer "F.SilkS")
		)
		(fp_line
			(start 17.284954 -0.882904)
			(end 17.73809 -1.317752)
			(stroke
				(width 0.1)
				(type default)
			)
			(layer "F.SilkS")
		)
		(fp_line
			(start 17.32534 -5.192522)
			(end 16.283178 -4.192524)
			(stroke
				(width 0.1)
				(type default)
			)
			(layer "F.SilkS")
		)
		(fp_line
			(start 17.32534 -5.192522)
			(end 16.283178 -4.192524)
			(stroke
				(width 0.1)
				(type default)
			)
			(layer "F.SilkS")
		)
		(fp_line
			(start 17.345406 -0.882904)
			(end 17.40535 -0.882904)
			(stroke
				(width 0.1)
				(type default)
			)
			(layer "F.SilkS")
		)
		(fp_line
			(start 17.345406 -0.882904)
			(end 17.40535 -0.882904)
			(stroke
				(width 0.1)
				(type default)
			)
			(layer "F.SilkS")
		)
		(fp_line
			(start 17.345406 -0.882904)
			(end 17.725898 -1.248156)
			(stroke
				(width 0.1)
				(type default)
			)
			(layer "F.SilkS")
		)
		(fp_line
			(start 17.345406 -0.882904)
			(end 17.725898 -1.248156)
			(stroke
				(width 0.1)
				(type default)
			)
			(layer "F.SilkS")
		)
		(fp_line
			(start 17.370044 -5.17779)
			(end 16.347948 -4.197096)
			(stroke
				(width 0.1)
				(type default)
			)
			(layer "F.SilkS")
		)
		(fp_line
			(start 17.370044 -5.17779)
			(end 16.347948 -4.197096)
			(stroke
				(width 0.1)
				(type default)
			)
			(layer "F.SilkS")
		)
		(fp_line
			(start 17.40535 -0.882904)
			(end 17.465294 -0.882904)
			(stroke
				(width 0.1)
				(type default)
			)
			(layer "F.SilkS")
		)
		(fp_line
			(start 17.40535 -0.882904)
			(end 17.465294 -0.882904)
			(stroke
				(width 0.1)
				(type default)
			)
			(layer "F.SilkS")
		)
		(fp_line
			(start 17.40535 -0.882904)
			(end 17.71396 -1.178814)
			(stroke
				(width 0.1)
				(type default)
			)
			(layer "F.SilkS")
		)
		(fp_line
			(start 17.40535 -0.882904)
			(end 17.71396 -1.178814)
			(stroke
				(width 0.1)
				(type default)
			)
			(layer "F.SilkS")
		)
		(fp_line
			(start 17.415002 -5.163058)
			(end 16.40967 -4.198366)
			(stroke
				(width 0.1)
				(type default)
			)
			(layer "F.SilkS")
		)
		(fp_line
			(start 17.415002 -5.163058)
			(end 16.40967 -4.198366)
			(stroke
				(width 0.1)
				(type default)
			)
			(layer "F.SilkS")
		)
		(fp_line
			(start 17.45996 -5.148326)
			(end 16.465804 -4.194556)
			(stroke
				(width 0.1)
				(type default)
			)
			(layer "F.SilkS")
		)
		(fp_line
			(start 17.45996 -5.148326)
			(end 16.465804 -4.194556)
			(stroke
				(width 0.1)
				(type default)
			)
			(layer "F.SilkS")
		)
		(fp_line
			(start 17.465294 -0.882904)
			(end 17.525746 -0.882904)
			(stroke
				(width 0.1)
				(type default)
			)
			(layer "F.SilkS")
		)
		(fp_line
			(start 17.465294 -0.882904)
			(end 17.525746 -0.882904)
			(stroke
				(width 0.1)
				(type default)
			)
			(layer "F.SilkS")
		)
		(fp_line
			(start 17.465294 -0.882904)
			(end 17.701514 -1.109472)
			(stroke
				(width 0.1)
				(type default)
			)
			(layer "F.SilkS")
		)
		(fp_line
			(start 17.465294 -0.882904)
			(end 17.701514 -1.109472)
			(stroke
				(width 0.1)
				(type default)
			)
			(layer "F.SilkS")
		)
		(fp_line
			(start 17.50441 -5.13334)
			(end 16.521938 -4.190746)
			(stroke
				(width 0.1)
				(type default)
			)
			(layer "F.SilkS")
		)
		(fp_line
			(start 17.50441 -5.13334)
			(end 16.521938 -4.190746)
			(stroke
				(width 0.1)
				(type default)
			)
			(layer "F.SilkS")
		)
		(fp_line
			(start 17.525746 -0.882904)
			(end 17.58569 -0.882904)
			(stroke
				(width 0.1)
				(type default)
			)
			(layer "F.SilkS")
		)
		(fp_line
			(start 17.525746 -0.882904)
			(end 17.58569 -0.882904)
			(stroke
				(width 0.1)
				(type default)
			)
			(layer "F.SilkS")
		)
		(fp_line
			(start 17.525746 -0.882904)
			(end 17.689576 -1.04013)
			(stroke
				(width 0.1)
				(type default)
			)
			(layer "F.SilkS")
		)
		(fp_line
			(start 17.525746 -0.882904)
			(end 17.689576 -1.04013)
			(stroke
				(width 0.1)
				(type default)
			)
			(layer "F.SilkS")
		)
		(fp_line
			(start 17.545558 -5.115052)
			(end 16.5735 -4.182872)
			(stroke
				(width 0.1)
				(type default)
			)
			(layer "F.SilkS")
		)
		(fp_line
			(start 17.545558 -5.115052)
			(end 16.5735 -4.182872)
			(stroke
				(width 0.1)
				(type default)
			)
			(layer "F.SilkS")
		)
		(fp_line
			(start 17.580864 -5.091176)
			(end 16.621252 -4.170426)
			(stroke
				(width 0.1)
				(type default)
			)
			(layer "F.SilkS")
		)
		(fp_line
			(start 17.580864 -5.091176)
			(end 16.621252 -4.170426)
			(stroke
				(width 0.1)
				(type default)
			)
			(layer "F.SilkS")
		)
		(fp_line
			(start 17.58569 -0.882904)
			(end 17.645634 -0.882904)
			(stroke
				(width 0.1)
				(type default)
			)
			(layer "F.SilkS")
		)
		(fp_line
			(start 17.58569 -0.882904)
			(end 17.645634 -0.882904)
			(stroke
				(width 0.1)
				(type default)
			)
			(layer "F.SilkS")
		)
		(fp_line
			(start 17.58569 -0.882904)
			(end 17.677384 -0.970788)
			(stroke
				(width 0.1)
				(type default)
			)
			(layer "F.SilkS")
		)
		(fp_line
			(start 17.58569 -0.882904)
			(end 17.677384 -0.970788)
			(stroke
				(width 0.1)
				(type default)
			)
			(layer "F.SilkS")
		)
		(fp_line
			(start 17.61617 -5.067046)
			(end 16.668242 -4.15798)
			(stroke
				(width 0.1)
				(type default)
			)
			(layer "F.SilkS")
		)
		(fp_line
			(start 17.61617 -5.067046)
			(end 16.668242 -4.15798)
			(stroke
				(width 0.1)
				(type default)
			)
			(layer "F.SilkS")
		)
		(fp_line
			(start 17.645634 -0.882904)
			(end 17.66189 -0.882904)
			(stroke
				(width 0.1)
				(type default)
			)
			(layer "F.SilkS")
		)
		(fp_line
			(start 17.645634 -0.882904)
			(end 17.66189 -0.882904)
			(stroke
				(width 0.1)
				(type default)
			)
			(layer "F.SilkS")
		)
		(fp_line
			(start 17.645634 -0.882904)
			(end 17.664938 -0.901192)
			(stroke
				(width 0.1)
				(type default)
			)
			(layer "F.SilkS")
		)
		(fp_line
			(start 17.645634 -0.882904)
			(end 17.664938 -0.901192)
			(stroke
				(width 0.1)
				(type default)
			)
			(layer "F.SilkS")
		)
		(fp_line
			(start 17.651222 -5.043424)
			(end 16.71066 -4.140962)
			(stroke
				(width 0.1)
				(type default)
			)
			(layer "F.SilkS")
		)
		(fp_line
			(start 17.651222 -5.043424)
			(end 16.71066 -4.140962)
			(stroke
				(width 0.1)
				(type default)
			)
			(layer "F.SilkS")
		)
		(fp_line
			(start 17.66189 -0.882904)
			(end 17.664938 -0.901192)
			(stroke
				(width 0.1)
				(type default)
			)
			(layer "F.SilkS")
		)
		(fp_line
			(start 17.66189 -0.882904)
			(end 17.664938 -0.901192)
			(stroke
				(width 0.1)
				(type default)
			)
			(layer "F.SilkS")
		)
		(fp_line
			(start 17.677384 -0.970788)
			(end 17.664938 -0.901192)
			(stroke
				(width 0.1)
				(type default)
			)
			(layer "F.SilkS")
		)
		(fp_line
			(start 17.677384 -0.970788)
			(end 17.664938 -0.901192)
			(stroke
				(width 0.1)
				(type default)
			)
			(layer "F.SilkS")
		)
		(fp_line
			(start 17.686274 -5.019294)
			(end 16.747998 -4.119118)
			(stroke
				(width 0.1)
				(type default)
			)
			(layer "F.SilkS")
		)
		(fp_line
			(start 17.686274 -5.019294)
			(end 16.747998 -4.119118)
			(stroke
				(width 0.1)
				(type default)
			)
			(layer "F.SilkS")
		)
		(fp_line
			(start 17.689576 -1.04013)
			(end 17.677384 -0.970788)
			(stroke
				(width 0.1)
				(type default)
			)
			(layer "F.SilkS")
		)
		(fp_line
			(start 17.689576 -1.04013)
			(end 17.677384 -0.970788)
			(stroke
				(width 0.1)
				(type default)
			)
			(layer "F.SilkS")
		)
		(fp_line
			(start 17.701514 -1.109472)
			(end 17.689576 -1.04013)
			(stroke
				(width 0.1)
				(type default)
			)
			(layer "F.SilkS")
		)
		(fp_line
			(start 17.701514 -1.109472)
			(end 17.689576 -1.04013)
			(stroke
				(width 0.1)
				(type default)
			)
			(layer "F.SilkS")
		)
		(fp_line
			(start 17.71396 -1.178814)
			(end 17.701514 -1.109472)
			(stroke
				(width 0.1)
				(type default)
			)
			(layer "F.SilkS")
		)
		(fp_line
			(start 17.71396 -1.178814)
			(end 17.701514 -1.109472)
			(stroke
				(width 0.1)
				(type default)
			)
			(layer "F.SilkS")
		)
		(fp_line
			(start 17.721834 -4.995672)
			(end 16.785844 -4.097782)
			(stroke
				(width 0.1)
				(type default)
			)
			(layer "F.SilkS")
		)
		(fp_line
			(start 17.721834 -4.995672)
			(end 16.785844 -4.097782)
			(stroke
				(width 0.1)
				(type default)
			)
			(layer "F.SilkS")
		)
		(fp_line
			(start 17.725898 -1.248156)
			(end 17.71396 -1.178814)
			(stroke
				(width 0.1)
				(type default)
			)
			(layer "F.SilkS")
		)
		(fp_line
			(start 17.725898 -1.248156)
			(end 17.71396 -1.178814)
			(stroke
				(width 0.1)
				(type default)
			)
			(layer "F.SilkS")
		)
		(fp_line
			(start 17.73809 -1.317752)
			(end 17.725898 -1.248156)
			(stroke
				(width 0.1)
				(type default)
			)
			(layer "F.SilkS")
		)
		(fp_line
			(start 17.73809 -1.317752)
			(end 17.725898 -1.248156)
			(stroke
				(width 0.1)
				(type default)
			)
			(layer "F.SilkS")
		)
		(fp_line
			(start 17.750536 -1.387348)
			(end 17.73809 -1.317752)
			(stroke
				(width 0.1)
				(type default)
			)
			(layer "F.SilkS")
		)
		(fp_line
			(start 17.750536 -1.387348)
			(end 17.73809 -1.317752)
			(stroke
				(width 0.1)
				(type default)
			)
			(layer "F.SilkS")
		)
		(fp_line
			(start 17.757394 -4.971796)
			(end 16.818102 -4.071112)
			(stroke
				(width 0.1)
				(type default)
			)
			(layer "F.SilkS")
		)
		(fp_line
			(start 17.757394 -4.971796)
			(end 16.818102 -4.071112)
			(stroke
				(width 0.1)
				(type default)
			)
			(layer "F.SilkS")
		)
		(fp_line
			(start 17.762474 -1.456436)
			(end 17.750536 -1.387348)
			(stroke
				(width 0.1)
				(type default)
			)
			(layer "F.SilkS")
		)
		(fp_line
			(start 17.762474 -1.456436)
			(end 17.750536 -1.387348)
			(stroke
				(width 0.1)
				(type default)
			)
			(layer "F.SilkS")
		)
		(fp_line
			(start 17.774666 -1.525778)
			(end 17.762474 -1.456436)
			(stroke
				(width 0.1)
				(type default)
			)
			(layer "F.SilkS")
		)
		(fp_line
			(start 17.774666 -1.525778)
			(end 17.762474 -1.456436)
			(stroke
				(width 0.1)
				(type default)
			)
			(layer "F.SilkS")
		)
		(fp_line
			(start 17.786858 -1.595374)
			(end 17.774666 -1.525778)
			(stroke
				(width 0.1)
				(type default)
			)
			(layer "F.SilkS")
		)
		(fp_line
			(start 17.786858 -1.595374)
			(end 17.774666 -1.525778)
			(stroke
				(width 0.1)
				(type default)
			)
			(layer "F.SilkS")
		)
		(fp_line
			(start 17.78762 -4.943348)
			(end 16.845788 -4.03987)
			(stroke
				(width 0.1)
				(type default)
			)
			(layer "F.SilkS")
		)
		(fp_line
			(start 17.78762 -4.943348)
			(end 16.845788 -4.03987)
			(stroke
				(width 0.1)
				(type default)
			)
			(layer "F.SilkS")
		)
		(fp_line
			(start 17.79905 -1.664716)
			(end 17.786858 -1.595374)
			(stroke
				(width 0.1)
				(type default)
			)
			(layer "F.SilkS")
		)
		(fp_line
			(start 17.79905 -1.664716)
			(end 17.786858 -1.595374)
			(stroke
				(width 0.1)
				(type default)
			)
			(layer "F.SilkS")
		)
		(fp_line
			(start 17.810988 -1.734058)
			(end 17.79905 -1.664716)
			(stroke
				(width 0.1)
				(type default)
			)
			(layer "F.SilkS")
		)
		(fp_line
			(start 17.810988 -1.734058)
			(end 17.79905 -1.664716)
			(stroke
				(width 0.1)
				(type default)
			)
			(layer "F.SilkS")
		)
		(fp_line
			(start 17.813782 -4.910836)
			(end 16.87322 -4.008882)
			(stroke
				(width 0.1)
				(type default)
			)
			(layer "F.SilkS")
		)
		(fp_line
			(start 17.813782 -4.910836)
			(end 16.87322 -4.008882)
			(stroke
				(width 0.1)
				(type default)
			)
			(layer "F.SilkS")
		)
		(fp_line
			(start 17.823434 -1.8034)
			(end 17.810988 -1.734058)
			(stroke
				(width 0.1)
				(type default)
			)
			(layer "F.SilkS")
		)
		(fp_line
			(start 17.823434 -1.8034)
			(end 17.810988 -1.734058)
			(stroke
				(width 0.1)
				(type default)
			)
			(layer "F.SilkS")
		)
		(fp_line
			(start 17.835626 -1.872742)
			(end 17.823434 -1.8034)
			(stroke
				(width 0.1)
				(type default)
			)
			(layer "F.SilkS")
		)
		(fp_line
			(start 17.835626 -1.872742)
			(end 17.823434 -1.8034)
			(stroke
				(width 0.1)
				(type default)
			)
			(layer "F.SilkS")
		)
		(fp_line
			(start 17.839944 -4.878324)
			(end 16.89735 -3.97383)
			(stroke
				(width 0.1)
				(type default)
			)
			(layer "F.SilkS")
		)
		(fp_line
			(start 17.839944 -4.878324)
			(end 16.89735 -3.97383)
			(stroke
				(width 0.1)
				(type default)
			)
			(layer "F.SilkS")
		)
		(fp_line
			(start 17.847564 -1.942338)
			(end 17.835626 -1.872742)
			(stroke
				(width 0.1)
				(type default)
			)
			(layer "F.SilkS")
		)
		(fp_line
			(start 17.847564 -1.942338)
			(end 17.835626 -1.872742)
			(stroke
				(width 0.1)
				(type default)
			)
			(layer "F.SilkS")
		)
		(fp_line
			(start 17.86001 -2.011426)
			(end 17.847564 -1.942338)
			(stroke
				(width 0.1)
				(type default)
			)
			(layer "F.SilkS")
		)
		(fp_line
			(start 17.86001 -2.011426)
			(end 17.847564 -1.942338)
			(stroke
				(width 0.1)
				(type default)
			)
			(layer "F.SilkS")
		)
		(fp_line
			(start 17.866106 -4.845558)
			(end 16.915384 -3.93319)
			(stroke
				(width 0.1)
				(type default)
			)
			(layer "F.SilkS")
		)
		(fp_line
			(start 17.866106 -4.845558)
			(end 16.915384 -3.93319)
			(stroke
				(width 0.1)
				(type default)
			)
			(layer "F.SilkS")
		)
		(fp_line
			(start 17.871948 -2.081022)
			(end 17.86001 -2.011426)
			(stroke
				(width 0.1)
				(type default)
			)
			(layer "F.SilkS")
		)
		(fp_line
			(start 17.871948 -2.081022)
			(end 17.86001 -2.011426)
			(stroke
				(width 0.1)
				(type default)
			)
			(layer "F.SilkS")
		)
		(fp_line
			(start 17.88414 -2.150364)
			(end 17.871948 -2.081022)
			(stroke
				(width 0.1)
				(type default)
			)
			(layer "F.SilkS")
		)
		(fp_line
			(start 17.88414 -2.150364)
			(end 17.871948 -2.081022)
			(stroke
				(width 0.1)
				(type default)
			)
			(layer "F.SilkS")
		)
		(fp_line
			(start 17.892268 -4.813046)
			(end 16.93291 -3.89255)
			(stroke
				(width 0.1)
				(type default)
			)
			(layer "F.SilkS")
		)
		(fp_line
			(start 17.892268 -4.813046)
			(end 16.93291 -3.89255)
			(stroke
				(width 0.1)
				(type default)
			)
			(layer "F.SilkS")
		)
		(fp_line
			(start 17.896586 -2.21996)
			(end 17.88414 -2.150364)
			(stroke
				(width 0.1)
				(type default)
			)
			(layer "F.SilkS")
		)
		(fp_line
			(start 17.896586 -2.21996)
			(end 17.88414 -2.150364)
			(stroke
				(width 0.1)
				(type default)
			)
			(layer "F.SilkS")
		)
		(fp_line
			(start 17.908524 -2.289048)
			(end 17.896586 -2.21996)
			(stroke
				(width 0.1)
				(type default)
			)
			(layer "F.SilkS")
		)
		(fp_line
			(start 17.908524 -2.289048)
			(end 17.896586 -2.21996)
			(stroke
				(width 0.1)
				(type default)
			)
			(layer "F.SilkS")
		)
		(fp_line
			(start 17.91843 -4.780534)
			(end 16.949674 -3.850894)
			(stroke
				(width 0.1)
				(type default)
			)
			(layer "F.SilkS")
		)
		(fp_line
			(start 17.91843 -4.780534)
			(end 16.949674 -3.850894)
			(stroke
				(width 0.1)
				(type default)
			)
			(layer "F.SilkS")
		)
		(fp_line
			(start 17.920716 -2.35839)
			(end 17.908524 -2.289048)
			(stroke
				(width 0.1)
				(type default)
			)
			(layer "F.SilkS")
		)
		(fp_line
			(start 17.920716 -2.35839)
			(end 17.908524 -2.289048)
			(stroke
				(width 0.1)
				(type default)
			)
			(layer "F.SilkS")
		)
		(fp_line
			(start 17.932908 -2.427732)
			(end 17.920716 -2.35839)
			(stroke
				(width 0.1)
				(type default)
			)
			(layer "F.SilkS")
		)
		(fp_line
			(start 17.932908 -2.427732)
			(end 17.920716 -2.35839)
			(stroke
				(width 0.1)
				(type default)
			)
			(layer "F.SilkS")
		)
		(fp_line
			(start 17.944846 -4.748022)
			(end 16.958056 -3.80111)
			(stroke
				(width 0.1)
				(type default)
			)
			(layer "F.SilkS")
		)
		(fp_line
			(start 17.944846 -4.748022)
			(end 16.958056 -3.80111)
			(stroke
				(width 0.1)
				(type default)
			)
			(layer "F.SilkS")
		)
		(fp_line
			(start 17.9451 -2.497328)
			(end 17.932908 -2.427732)
			(stroke
				(width 0.1)
				(type default)
			)
			(layer "F.SilkS")
		)
		(fp_line
			(start 17.9451 -2.497328)
			(end 17.932908 -2.427732)
			(stroke
				(width 0.1)
				(type default)
			)
			(layer "F.SilkS")
		)
		(fp_line
			(start 17.957038 -2.56667)
			(end 17.9451 -2.497328)
			(stroke
				(width 0.1)
				(type default)
			)
			(layer "F.SilkS")
		)
		(fp_line
			(start 17.957038 -2.56667)
			(end 17.9451 -2.497328)
			(stroke
				(width 0.1)
				(type default)
			)
			(layer "F.SilkS")
		)
		(fp_line
			(start 17.966182 -4.710176)
			(end 16.966438 -3.751326)
			(stroke
				(width 0.1)
				(type default)
			)
			(layer "F.SilkS")
		)
		(fp_line
			(start 17.966182 -4.710176)
			(end 16.966438 -3.751326)
			(stroke
				(width 0.1)
				(type default)
			)
			(layer "F.SilkS")
		)
		(fp_line
			(start 17.969484 -2.636012)
			(end 17.957038 -2.56667)
			(stroke
				(width 0.1)
				(type default)
			)
			(layer "F.SilkS")
		)
		(fp_line
			(start 17.969484 -2.636012)
			(end 17.957038 -2.56667)
			(stroke
				(width 0.1)
				(type default)
			)
			(layer "F.SilkS")
		)
		(fp_line
			(start 17.981676 -2.705608)
			(end 17.969484 -2.636012)
			(stroke
				(width 0.1)
				(type default)
			)
			(layer "F.SilkS")
		)
		(fp_line
			(start 17.981676 -2.705608)
			(end 17.969484 -2.636012)
			(stroke
				(width 0.1)
				(type default)
			)
			(layer "F.SilkS")
		)
		(fp_line
			(start 17.9832 -4.669282)
			(end 16.974566 -3.701542)
			(stroke
				(width 0.1)
				(type default)
			)
			(layer "F.SilkS")
		)
		(fp_line
			(start 17.9832 -4.669282)
			(end 16.974566 -3.701542)
			(stroke
				(width 0.1)
				(type default)
			)
			(layer "F.SilkS")
		)
		(fp_line
			(start 17.993614 -2.77495)
			(end 17.981676 -2.705608)
			(stroke
				(width 0.1)
				(type default)
			)
			(layer "F.SilkS")
		)
		(fp_line
			(start 17.993614 -2.77495)
			(end 17.981676 -2.705608)
			(stroke
				(width 0.1)
				(type default)
			)
			(layer "F.SilkS")
		)
		(fp_line
			(start 18.000472 -4.628388)
			(end 16.97736 -3.646424)
			(stroke
				(width 0.1)
				(type default)
			)
			(layer "F.SilkS")
		)
		(fp_line
			(start 18.000472 -4.628388)
			(end 16.97736 -3.646424)
			(stroke
				(width 0.1)
				(type default)
			)
			(layer "F.SilkS")
		)
		(fp_line
			(start 18.00606 -2.844292)
			(end 17.993614 -2.77495)
			(stroke
				(width 0.1)
				(type default)
			)
			(layer "F.SilkS")
		)
		(fp_line
			(start 18.00606 -2.844292)
			(end 17.993614 -2.77495)
			(stroke
				(width 0.1)
				(type default)
			)
			(layer "F.SilkS")
		)
		(fp_line
			(start 18.017998 -4.58724)
			(end 16.976598 -3.588258)
			(stroke
				(width 0.1)
				(type default)
			)
			(layer "F.SilkS")
		)
		(fp_line
			(start 18.017998 -4.58724)
			(end 16.976598 -3.588258)
			(stroke
				(width 0.1)
				(type default)
			)
			(layer "F.SilkS")
		)
		(fp_line
			(start 18.017998 -2.913634)
			(end 18.00606 -2.844292)
			(stroke
				(width 0.1)
				(type default)
			)
			(layer "F.SilkS")
		)
		(fp_line
			(start 18.017998 -2.913634)
			(end 18.00606 -2.844292)
			(stroke
				(width 0.1)
				(type default)
			)
			(layer "F.SilkS")
		)
		(fp_line
			(start 18.03019 -2.982976)
			(end 18.017998 -2.913634)
			(stroke
				(width 0.1)
				(type default)
			)
			(layer "F.SilkS")
		)
		(fp_line
			(start 18.03019 -2.982976)
			(end 18.017998 -2.913634)
			(stroke
				(width 0.1)
				(type default)
			)
			(layer "F.SilkS")
		)
		(fp_line
			(start 18.035778 -4.546346)
			(end 16.97609 -3.529838)
			(stroke
				(width 0.1)
				(type default)
			)
			(layer "F.SilkS")
		)
		(fp_line
			(start 18.035778 -4.546346)
			(end 16.97609 -3.529838)
			(stroke
				(width 0.1)
				(type default)
			)
			(layer "F.SilkS")
		)
		(fp_line
			(start 18.042636 -3.052572)
			(end 18.03019 -2.982976)
			(stroke
				(width 0.1)
				(type default)
			)
			(layer "F.SilkS")
		)
		(fp_line
			(start 18.042636 -3.052572)
			(end 18.03019 -2.982976)
			(stroke
				(width 0.1)
				(type default)
			)
			(layer "F.SilkS")
		)
		(fp_line
			(start 18.052796 -4.505198)
			(end 16.975582 -3.471672)
			(stroke
				(width 0.1)
				(type default)
			)
			(layer "F.SilkS")
		)
		(fp_line
			(start 18.052796 -4.505198)
			(end 16.975582 -3.471672)
			(stroke
				(width 0.1)
				(type default)
			)
			(layer "F.SilkS")
		)
		(fp_line
			(start 18.054574 -3.121914)
			(end 18.042636 -3.052572)
			(stroke
				(width 0.1)
				(type default)
			)
			(layer "F.SilkS")
		)
		(fp_line
			(start 18.054574 -3.121914)
			(end 18.042636 -3.052572)
			(stroke
				(width 0.1)
				(type default)
			)
			(layer "F.SilkS")
		)
		(fp_line
			(start 18.066766 -3.191002)
			(end 18.054574 -3.121914)
			(stroke
				(width 0.1)
				(type default)
			)
			(layer "F.SilkS")
		)
		(fp_line
			(start 18.066766 -3.191002)
			(end 18.054574 -3.121914)
			(stroke
				(width 0.1)
				(type default)
			)
			(layer "F.SilkS")
		)
		(fp_line
			(start 18.070068 -4.464304)
			(end 16.967708 -3.406648)
			(stroke
				(width 0.1)
				(type default)
			)
			(layer "F.SilkS")
		)
		(fp_line
			(start 18.070068 -4.464304)
			(end 16.967708 -3.406648)
			(stroke
				(width 0.1)
				(type default)
			)
			(layer "F.SilkS")
		)
		(fp_line
			(start 18.079212 -3.260598)
			(end 18.066766 -3.191002)
			(stroke
				(width 0.1)
				(type default)
			)
			(layer "F.SilkS")
		)
		(fp_line
			(start 18.079212 -3.260598)
			(end 18.066766 -3.191002)
			(stroke
				(width 0.1)
				(type default)
			)
			(layer "F.SilkS")
		)
		(fp_line
			(start 18.081752 -4.417314)
			(end 16.959326 -3.340608)
			(stroke
				(width 0.1)
				(type default)
			)
			(layer "F.SilkS")
		)
		(fp_line
			(start 18.081752 -4.417314)
			(end 16.959326 -3.340608)
			(stroke
				(width 0.1)
				(type default)
			)
			(layer "F.SilkS")
		)
		(fp_line
			(start 18.090388 -4.368038)
			(end 16.950436 -3.274568)
			(stroke
				(width 0.1)
				(type default)
			)
			(layer "F.SilkS")
		)
		(fp_line
			(start 18.090388 -4.368038)
			(end 16.950436 -3.274568)
			(stroke
				(width 0.1)
				(type default)
			)
			(layer "F.SilkS")
		)
		(fp_line
			(start 18.099532 -4.318762)
			(end 16.942308 -3.208782)
			(stroke
				(width 0.1)
				(type default)
			)
			(layer "F.SilkS")
		)
		(fp_line
			(start 18.099532 -4.318762)
			(end 16.942308 -3.208782)
			(stroke
				(width 0.1)
				(type default)
			)
			(layer "F.SilkS")
		)
		(fp_line
			(start 18.107914 -4.26974)
			(end 16.930624 -3.139694)
			(stroke
				(width 0.1)
				(type default)
			)
			(layer "F.SilkS")
		)
		(fp_line
			(start 18.107914 -4.26974)
			(end 16.930624 -3.139694)
			(stroke
				(width 0.1)
				(type default)
			)
			(layer "F.SilkS")
		)
		(fp_line
			(start 18.137632 -3.836416)
			(end 16.83258 -2.58445)
			(stroke
				(width 0.1)
				(type default)
			)
			(layer "F.SilkS")
		)
		(fp_line
			(start 18.137632 -3.836416)
			(end 16.83258 -2.58445)
			(stroke
				(width 0.1)
				(type default)
			)
			(layer "F.SilkS")
		)
		(fp_line
			(start 18.736818 -4.109466)
			(end 18.783554 -4.109466)
			(stroke
				(width 0.1)
				(type default)
			)
			(layer "F.SilkS")
		)
		(fp_line
			(start 18.736818 -4.109466)
			(end 18.783554 -4.109466)
			(stroke
				(width 0.1)
				(type default)
			)
			(layer "F.SilkS")
		)
		(fp_line
			(start 18.739612 -4.12496)
			(end 18.736818 -4.109466)
			(stroke
				(width 0.1)
				(type default)
			)
			(layer "F.SilkS")
		)
		(fp_line
			(start 18.739612 -4.12496)
			(end 18.736818 -4.109466)
			(stroke
				(width 0.1)
				(type default)
			)
			(layer "F.SilkS")
		)
		(fp_line
			(start 18.739612 -4.12496)
			(end 20.959318 -6.254496)
			(stroke
				(width 0.1)
				(type default)
			)
			(layer "F.SilkS")
		)
		(fp_line
			(start 18.739612 -4.12496)
			(end 20.959318 -6.254496)
			(stroke
				(width 0.1)
				(type default)
			)
			(layer "F.SilkS")
		)
		(fp_line
			(start 18.75155 -4.194556)
			(end 18.739612 -4.12496)
			(stroke
				(width 0.1)
				(type default)
			)
			(layer "F.SilkS")
		)
		(fp_line
			(start 18.75155 -4.194556)
			(end 18.739612 -4.12496)
			(stroke
				(width 0.1)
				(type default)
			)
			(layer "F.SilkS")
		)
		(fp_line
			(start 18.763996 -4.263898)
			(end 18.75155 -4.194556)
			(stroke
				(width 0.1)
				(type default)
			)
			(layer "F.SilkS")
		)
		(fp_line
			(start 18.763996 -4.263898)
			(end 18.75155 -4.194556)
			(stroke
				(width 0.1)
				(type default)
			)
			(layer "F.SilkS")
		)
		(fp_line
			(start 18.775934 -4.33324)
			(end 18.763996 -4.263898)
			(stroke
				(width 0.1)
				(type default)
			)
			(layer "F.SilkS")
		)
		(fp_line
			(start 18.775934 -4.33324)
			(end 18.763996 -4.263898)
			(stroke
				(width 0.1)
				(type default)
			)
			(layer "F.SilkS")
		)
		(fp_line
			(start 18.775934 -4.33324)
			(end 18.78838 -4.402836)
			(stroke
				(width 0.1)
				(type default)
			)
			(layer "F.SilkS")
		)
		(fp_line
			(start 18.775934 -4.33324)
			(end 18.78838 -4.402836)
			(stroke
				(width 0.1)
				(type default)
			)
			(layer "F.SilkS")
		)
		(fp_line
			(start 18.783554 -4.109466)
			(end 18.843498 -4.109466)
			(stroke
				(width 0.1)
				(type default)
			)
			(layer "F.SilkS")
		)
		(fp_line
			(start 18.783554 -4.109466)
			(end 18.843498 -4.109466)
			(stroke
				(width 0.1)
				(type default)
			)
			(layer "F.SilkS")
		)
		(fp_line
			(start 18.783554 -4.109466)
			(end 20.947126 -6.1849)
			(stroke
				(width 0.1)
				(type default)
			)
			(layer "F.SilkS")
		)
		(fp_line
			(start 18.783554 -4.109466)
			(end 20.947126 -6.1849)
			(stroke
				(width 0.1)
				(type default)
			)
			(layer "F.SilkS")
		)
		(fp_line
			(start 18.78838 -4.402836)
			(end 18.800572 -4.472178)
			(stroke
				(width 0.1)
				(type default)
			)
			(layer "F.SilkS")
		)
		(fp_line
			(start 18.78838 -4.402836)
			(end 18.800572 -4.472178)
			(stroke
				(width 0.1)
				(type default)
			)
			(layer "F.SilkS")
		)
		(fp_line
			(start 18.78838 -4.402836)
			(end 19.58975 -5.171694)
			(stroke
				(width 0.1)
				(type default)
			)
			(layer "F.SilkS")
		)
		(fp_line
			(start 18.78838 -4.402836)
			(end 19.58975 -5.171694)
			(stroke
				(width 0.1)
				(type default)
			)
			(layer "F.SilkS")
		)
		(fp_line
			(start 18.800572 -4.472178)
			(end 18.81251 -4.54152)
			(stroke
				(width 0.1)
				(type default)
			)
			(layer "F.SilkS")
		)
		(fp_line
			(start 18.800572 -4.472178)
			(end 18.81251 -4.54152)
			(stroke
				(width 0.1)
				(type default)
			)
			(layer "F.SilkS")
		)
		(fp_line
			(start 18.800572 -4.472178)
			(end 19.529806 -5.171694)
			(stroke
				(width 0.1)
				(type default)
			)
			(layer "F.SilkS")
		)
		(fp_line
			(start 18.800572 -4.472178)
			(end 19.529806 -5.171694)
			(stroke
				(width 0.1)
				(type default)
			)
			(layer "F.SilkS")
		)
		(fp_line
			(start 18.81251 -4.54152)
			(end 18.824956 -4.610862)
			(stroke
				(width 0.1)
				(type default)
			)
			(layer "F.SilkS")
		)
		(fp_line
			(start 18.81251 -4.54152)
			(end 18.824956 -4.610862)
			(stroke
				(width 0.1)
				(type default)
			)
			(layer "F.SilkS")
		)
		(fp_line
			(start 18.81251 -4.54152)
			(end 19.469608 -5.171694)
			(stroke
				(width 0.1)
				(type default)
			)
			(layer "F.SilkS")
		)
		(fp_line
			(start 18.81251 -4.54152)
			(end 19.469608 -5.171694)
			(stroke
				(width 0.1)
				(type default)
			)
			(layer "F.SilkS")
		)
		(fp_line
			(start 18.824956 -4.610862)
			(end 18.836894 -4.680458)
			(stroke
				(width 0.1)
				(type default)
			)
			(layer "F.SilkS")
		)
		(fp_line
			(start 18.824956 -4.610862)
			(end 18.836894 -4.680458)
			(stroke
				(width 0.1)
				(type default)
			)
			(layer "F.SilkS")
		)
		(fp_line
			(start 18.824956 -4.610862)
			(end 19.409664 -5.171694)
			(stroke
				(width 0.1)
				(type default)
			)
			(layer "F.SilkS")
		)
		(fp_line
			(start 18.824956 -4.610862)
			(end 19.409664 -5.171694)
			(stroke
				(width 0.1)
				(type default)
			)
			(layer "F.SilkS")
		)
		(fp_line
			(start 18.836894 -4.680458)
			(end 18.84934 -4.7498)
			(stroke
				(width 0.1)
				(type default)
			)
			(layer "F.SilkS")
		)
		(fp_line
			(start 18.836894 -4.680458)
			(end 18.84934 -4.7498)
			(stroke
				(width 0.1)
				(type default)
			)
			(layer "F.SilkS")
		)
		(fp_line
			(start 18.836894 -4.680458)
			(end 19.349212 -5.171694)
			(stroke
				(width 0.1)
				(type default)
			)
			(layer "F.SilkS")
		)
		(fp_line
			(start 18.836894 -4.680458)
			(end 19.349212 -5.171694)
			(stroke
				(width 0.1)
				(type default)
			)
			(layer "F.SilkS")
		)
		(fp_line
			(start 18.843498 -4.109466)
			(end 18.90395 -4.109466)
			(stroke
				(width 0.1)
				(type default)
			)
			(layer "F.SilkS")
		)
		(fp_line
			(start 18.843498 -4.109466)
			(end 18.90395 -4.109466)
			(stroke
				(width 0.1)
				(type default)
			)
			(layer "F.SilkS")
		)
		(fp_line
			(start 18.843498 -4.109466)
			(end 20.93468 -6.115558)
			(stroke
				(width 0.1)
				(type default)
			)
			(layer "F.SilkS")
		)
		(fp_line
			(start 18.843498 -4.109466)
			(end 20.93468 -6.115558)
			(stroke
				(width 0.1)
				(type default)
			)
			(layer "F.SilkS")
		)
		(fp_line
			(start 18.84934 -4.7498)
			(end 18.861532 -4.819142)
			(stroke
				(width 0.1)
				(type default)
			)
			(layer "F.SilkS")
		)
		(fp_line
			(start 18.84934 -4.7498)
			(end 18.861532 -4.819142)
			(stroke
				(width 0.1)
				(type default)
			)
			(layer "F.SilkS")
		)
		(fp_line
			(start 18.84934 -4.7498)
			(end 19.289014 -5.171694)
			(stroke
				(width 0.1)
				(type default)
			)
			(layer "F.SilkS")
		)
		(fp_line
			(start 18.84934 -4.7498)
			(end 19.289014 -5.171694)
			(stroke
				(width 0.1)
				(type default)
			)
			(layer "F.SilkS")
		)
		(fp_line
			(start 18.861532 -4.819142)
			(end 18.873978 -4.888484)
			(stroke
				(width 0.1)
				(type default)
			)
			(layer "F.SilkS")
		)
		(fp_line
			(start 18.861532 -4.819142)
			(end 18.873978 -4.888484)
			(stroke
				(width 0.1)
				(type default)
			)
			(layer "F.SilkS")
		)
		(fp_line
			(start 18.861532 -4.819142)
			(end 19.22907 -5.171694)
			(stroke
				(width 0.1)
				(type default)
			)
			(layer "F.SilkS")
		)
		(fp_line
			(start 18.861532 -4.819142)
			(end 19.22907 -5.171694)
			(stroke
				(width 0.1)
				(type default)
			)
			(layer "F.SilkS")
		)
		(fp_line
			(start 18.873978 -4.888484)
			(end 19.168872 -5.171694)
			(stroke
				(width 0.1)
				(type default)
			)
			(layer "F.SilkS")
		)
		(fp_line
			(start 18.873978 -4.888484)
			(end 19.168872 -5.171694)
			(stroke
				(width 0.1)
				(type default)
			)
			(layer "F.SilkS")
		)
		(fp_line
			(start 18.885916 -4.95808)
			(end 18.873978 -4.888484)
			(stroke
				(width 0.1)
				(type default)
			)
			(layer "F.SilkS")
		)
		(fp_line
			(start 18.885916 -4.95808)
			(end 18.873978 -4.888484)
			(stroke
				(width 0.1)
				(type default)
			)
			(layer "F.SilkS")
		)
		(fp_line
			(start 18.898108 -5.027422)
			(end 18.885916 -4.95808)
			(stroke
				(width 0.1)
				(type default)
			)
			(layer "F.SilkS")
		)
		(fp_line
			(start 18.898108 -5.027422)
			(end 18.885916 -4.95808)
			(stroke
				(width 0.1)
				(type default)
			)
			(layer "F.SilkS")
		)
		(fp_line
			(start 18.898108 -5.027422)
			(end 18.9103 -5.097018)
			(stroke
				(width 0.1)
				(type default)
			)
			(layer "F.SilkS")
		)
		(fp_line
			(start 18.898108 -5.027422)
			(end 18.9103 -5.097018)
			(stroke
				(width 0.1)
				(type default)
			)
			(layer "F.SilkS")
		)
		(fp_line
			(start 18.898108 -5.027422)
			(end 19.048476 -5.171694)
			(stroke
				(width 0.1)
				(type default)
			)
			(layer "F.SilkS")
		)
		(fp_line
			(start 18.898108 -5.027422)
			(end 19.048476 -5.171694)
			(stroke
				(width 0.1)
				(type default)
			)
			(layer "F.SilkS")
		)
		(fp_line
			(start 18.90395 -4.109466)
			(end 18.964148 -4.109466)
			(stroke
				(width 0.1)
				(type default)
			)
			(layer "F.SilkS")
		)
		(fp_line
			(start 18.90395 -4.109466)
			(end 18.964148 -4.109466)
			(stroke
				(width 0.1)
				(type default)
			)
			(layer "F.SilkS")
		)
		(fp_line
			(start 18.90395 -4.109466)
			(end 20.922742 -6.04647)
			(stroke
				(width 0.1)
				(type default)
			)
			(layer "F.SilkS")
		)
		(fp_line
			(start 18.90395 -4.109466)
			(end 20.922742 -6.04647)
			(stroke
				(width 0.1)
				(type default)
			)
			(layer "F.SilkS")
		)
		(fp_line
			(start 18.9103 -5.097018)
			(end 18.922492 -5.166106)
			(stroke
				(width 0.1)
				(type default)
			)
			(layer "F.SilkS")
		)
		(fp_line
			(start 18.9103 -5.097018)
			(end 18.922492 -5.166106)
			(stroke
				(width 0.1)
				(type default)
			)
			(layer "F.SilkS")
		)
		(fp_line
			(start 18.9103 -5.097018)
			(end 18.988278 -5.171694)
			(stroke
				(width 0.1)
				(type default)
			)
			(layer "F.SilkS")
		)
		(fp_line
			(start 18.9103 -5.097018)
			(end 18.988278 -5.171694)
			(stroke
				(width 0.1)
				(type default)
			)
			(layer "F.SilkS")
		)
		(fp_line
			(start 18.922492 -5.166106)
			(end 18.923508 -5.171694)
			(stroke
				(width 0.1)
				(type default)
			)
			(layer "F.SilkS")
		)
		(fp_line
			(start 18.922492 -5.166106)
			(end 18.923508 -5.171694)
			(stroke
				(width 0.1)
				(type default)
			)
			(layer "F.SilkS")
		)
		(fp_line
			(start 18.922492 -5.166106)
			(end 18.928334 -5.171694)
			(stroke
				(width 0.1)
				(type default)
			)
			(layer "F.SilkS")
		)
		(fp_line
			(start 18.922492 -5.166106)
			(end 18.928334 -5.171694)
			(stroke
				(width 0.1)
				(type default)
			)
			(layer "F.SilkS")
		)
		(fp_line
			(start 18.923508 -5.171694)
			(end 18.928334 -5.171694)
			(stroke
				(width 0.1)
				(type default)
			)
			(layer "F.SilkS")
		)
		(fp_line
			(start 18.923508 -5.171694)
			(end 18.928334 -5.171694)
			(stroke
				(width 0.1)
				(type default)
			)
			(layer "F.SilkS")
		)
		(fp_line
			(start 18.964148 -4.109466)
			(end 19.024092 -4.109466)
			(stroke
				(width 0.1)
				(type default)
			)
			(layer "F.SilkS")
		)
		(fp_line
			(start 18.964148 -4.109466)
			(end 19.024092 -4.109466)
			(stroke
				(width 0.1)
				(type default)
			)
			(layer "F.SilkS")
		)
		(fp_line
			(start 18.964148 -4.109466)
			(end 20.91055 -5.976874)
			(stroke
				(width 0.1)
				(type default)
			)
			(layer "F.SilkS")
		)
		(fp_line
			(start 18.964148 -4.109466)
			(end 20.91055 -5.976874)
			(stroke
				(width 0.1)
				(type default)
			)
			(layer "F.SilkS")
		)
		(fp_line
			(start 18.988278 -5.171694)
			(end 18.928334 -5.171694)
			(stroke
				(width 0.1)
				(type default)
			)
			(layer "F.SilkS")
		)
		(fp_line
			(start 18.988278 -5.171694)
			(end 18.928334 -5.171694)
			(stroke
				(width 0.1)
				(type default)
			)
			(layer "F.SilkS")
		)
		(fp_line
			(start 19.024092 -4.109466)
			(end 19.08429 -4.109466)
			(stroke
				(width 0.1)
				(type default)
			)
			(layer "F.SilkS")
		)
		(fp_line
			(start 19.024092 -4.109466)
			(end 19.08429 -4.109466)
			(stroke
				(width 0.1)
				(type default)
			)
			(layer "F.SilkS")
		)
		(fp_line
			(start 19.024092 -4.109466)
			(end 20.898104 -5.907278)
			(stroke
				(width 0.1)
				(type default)
			)
			(layer "F.SilkS")
		)
		(fp_line
			(start 19.024092 -4.109466)
			(end 20.898104 -5.907278)
			(stroke
				(width 0.1)
				(type default)
			)
			(layer "F.SilkS")
		)
		(fp_line
			(start 19.048476 -5.171694)
			(end 18.988278 -5.171694)
			(stroke
				(width 0.1)
				(type default)
			)
			(layer "F.SilkS")
		)
		(fp_line
			(start 19.048476 -5.171694)
			(end 18.988278 -5.171694)
			(stroke
				(width 0.1)
				(type default)
			)
			(layer "F.SilkS")
		)
		(fp_line
			(start 19.048476 -5.171694)
			(end 19.10842 -5.171694)
			(stroke
				(width 0.1)
				(type default)
			)
			(layer "F.SilkS")
		)
		(fp_line
			(start 19.048476 -5.171694)
			(end 19.10842 -5.171694)
			(stroke
				(width 0.1)
				(type default)
			)
			(layer "F.SilkS")
		)
		(fp_line
			(start 19.074638 -1.79197)
			(end 20.399248 -3.062478)
			(stroke
				(width 0.1)
				(type default)
			)
			(layer "F.SilkS")
		)
		(fp_line
			(start 19.074638 -1.79197)
			(end 20.399248 -3.062478)
			(stroke
				(width 0.1)
				(type default)
			)
			(layer "F.SilkS")
		)
		(fp_line
			(start 19.077178 -1.851914)
			(end 20.41144 -3.13182)
			(stroke
				(width 0.1)
				(type default)
			)
			(layer "F.SilkS")
		)
		(fp_line
			(start 19.077178 -1.851914)
			(end 20.41144 -3.13182)
			(stroke
				(width 0.1)
				(type default)
			)
			(layer "F.SilkS")
		)
		(fp_line
			(start 19.078448 -1.737868)
			(end 20.38731 -2.99339)
			(stroke
				(width 0.1)
				(type default)
			)
			(layer "F.SilkS")
		)
		(fp_line
			(start 19.078448 -1.737868)
			(end 20.38731 -2.99339)
			(stroke
				(width 0.1)
				(type default)
			)
			(layer "F.SilkS")
		)
		(fp_line
			(start 19.082258 -1.683512)
			(end 20.374864 -2.923794)
			(stroke
				(width 0.1)
				(type default)
			)
			(layer "F.SilkS")
		)
		(fp_line
			(start 19.082258 -1.683512)
			(end 20.374864 -2.923794)
			(stroke
				(width 0.1)
				(type default)
			)
			(layer "F.SilkS")
		)
		(fp_line
			(start 19.083274 -1.915668)
			(end 20.423886 -3.201416)
			(stroke
				(width 0.1)
				(type default)
			)
			(layer "F.SilkS")
		)
		(fp_line
			(start 19.083274 -1.915668)
			(end 20.423886 -3.201416)
			(stroke
				(width 0.1)
				(type default)
			)
			(layer "F.SilkS")
		)
		(fp_line
			(start 19.08429 -4.109466)
			(end 19.144234 -4.109466)
			(stroke
				(width 0.1)
				(type default)
			)
			(layer "F.SilkS")
		)
		(fp_line
			(start 19.08429 -4.109466)
			(end 19.144234 -4.109466)
			(stroke
				(width 0.1)
				(type default)
			)
			(layer "F.SilkS")
		)
		(fp_line
			(start 19.08429 -4.109466)
			(end 20.886166 -5.837936)
			(stroke
				(width 0.1)
				(type default)
			)
			(layer "F.SilkS")
		)
		(fp_line
			(start 19.08429 -4.109466)
			(end 20.886166 -5.837936)
			(stroke
				(width 0.1)
				(type default)
			)
			(layer "F.SilkS")
		)
		(fp_line
			(start 19.086068 -1.62941)
			(end 20.362926 -2.854198)
			(stroke
				(width 0.1)
				(type default)
			)
			(layer "F.SilkS")
		)
		(fp_line
			(start 19.086068 -1.62941)
			(end 20.362926 -2.854198)
			(stroke
				(width 0.1)
				(type default)
			)
			(layer "F.SilkS")
		)
		(fp_line
			(start 19.089624 -1.575308)
			(end 20.35048 -2.784856)
			(stroke
				(width 0.1)
				(type default)
			)
			(layer "F.SilkS")
		)
		(fp_line
			(start 19.089624 -1.575308)
			(end 20.35048 -2.784856)
			(stroke
				(width 0.1)
				(type default)
			)
			(layer "F.SilkS")
		)
		(fp_line
			(start 19.089878 -1.979676)
			(end 20.435824 -3.270758)
			(stroke
				(width 0.1)
				(type default)
			)
			(layer "F.SilkS")
		)
		(fp_line
			(start 19.089878 -1.979676)
			(end 20.435824 -3.270758)
			(stroke
				(width 0.1)
				(type default)
			)
			(layer "F.SilkS")
		)
		(fp_line
			(start 19.095974 -2.043176)
			(end 20.44827 -3.340354)
			(stroke
				(width 0.1)
				(type default)
			)
			(layer "F.SilkS")
		)
		(fp_line
			(start 19.095974 -2.043176)
			(end 20.44827 -3.340354)
			(stroke
				(width 0.1)
				(type default)
			)
			(layer "F.SilkS")
		)
		(fp_line
			(start 19.100292 -1.528064)
			(end 20.338288 -2.715768)
			(stroke
				(width 0.1)
				(type default)
			)
			(layer "F.SilkS")
		)
		(fp_line
			(start 19.100292 -1.528064)
			(end 20.338288 -2.715768)
			(stroke
				(width 0.1)
				(type default)
			)
			(layer "F.SilkS")
		)
		(fp_line
			(start 19.10461 -2.108962)
			(end 20.460462 -3.409442)
			(stroke
				(width 0.1)
				(type default)
			)
			(layer "F.SilkS")
		)
		(fp_line
			(start 19.10461 -2.108962)
			(end 20.460462 -3.409442)
			(stroke
				(width 0.1)
				(type default)
			)
			(layer "F.SilkS")
		)
		(fp_line
			(start 19.10842 -5.171694)
			(end 18.885916 -4.95808)
			(stroke
				(width 0.1)
				(type default)
			)
			(layer "F.SilkS")
		)
		(fp_line
			(start 19.10842 -5.171694)
			(end 18.885916 -4.95808)
			(stroke
				(width 0.1)
				(type default)
			)
			(layer "F.SilkS")
		)
		(fp_line
			(start 19.10842 -5.171694)
			(end 19.168872 -5.171694)
			(stroke
				(width 0.1)
				(type default)
			)
			(layer "F.SilkS")
		)
		(fp_line
			(start 19.10842 -5.171694)
			(end 19.168872 -5.171694)
			(stroke
				(width 0.1)
				(type default)
			)
			(layer "F.SilkS")
		)
		(fp_line
			(start 19.112738 -1.48209)
			(end 20.32635 -2.646172)
			(stroke
				(width 0.1)
				(type default)
			)
			(layer "F.SilkS")
		)
		(fp_line
			(start 19.112738 -1.48209)
			(end 20.32635 -2.646172)
			(stroke
				(width 0.1)
				(type default)
			)
			(layer "F.SilkS")
		)
		(fp_line
			(start 19.116802 -2.178304)
			(end 19.10461 -2.108962)
			(stroke
				(width 0.1)
				(type default)
			)
			(layer "F.SilkS")
		)
		(fp_line
			(start 19.116802 -2.178304)
			(end 19.10461 -2.108962)
			(stroke
				(width 0.1)
				(type default)
			)
			(layer "F.SilkS")
		)
		(fp_line
			(start 19.116802 -2.178304)
			(end 20.4724 -3.479038)
			(stroke
				(width 0.1)
				(type default)
			)
			(layer "F.SilkS")
		)
		(fp_line
			(start 19.116802 -2.178304)
			(end 20.4724 -3.479038)
			(stroke
				(width 0.1)
				(type default)
			)
			(layer "F.SilkS")
		)
		(fp_line
			(start 19.12493 -1.436116)
			(end 20.313904 -2.576576)
			(stroke
				(width 0.1)
				(type default)
			)
			(layer "F.SilkS")
		)
		(fp_line
			(start 19.12493 -1.436116)
			(end 20.313904 -2.576576)
			(stroke
				(width 0.1)
				(type default)
			)
			(layer "F.SilkS")
		)
		(fp_line
			(start 19.12874 -2.2479)
			(end 19.116802 -2.178304)
			(stroke
				(width 0.1)
				(type default)
			)
			(layer "F.SilkS")
		)
		(fp_line
			(start 19.12874 -2.2479)
			(end 19.116802 -2.178304)
			(stroke
				(width 0.1)
				(type default)
			)
			(layer "F.SilkS")
		)
		(fp_line
			(start 19.12874 -2.2479)
			(end 19.141186 -2.317242)
			(stroke
				(width 0.1)
				(type default)
			)
			(layer "F.SilkS")
		)
		(fp_line
			(start 19.12874 -2.2479)
			(end 19.141186 -2.317242)
			(stroke
				(width 0.1)
				(type default)
			)
			(layer "F.SilkS")
		)
		(fp_line
			(start 19.12874 -2.2479)
			(end 20.484846 -3.548634)
			(stroke
				(width 0.1)
				(type default)
			)
			(layer "F.SilkS")
		)
		(fp_line
			(start 19.12874 -2.2479)
			(end 20.484846 -3.548634)
			(stroke
				(width 0.1)
				(type default)
			)
			(layer "F.SilkS")
		)
		(fp_line
			(start 19.137376 -1.390396)
			(end 20.301966 -2.507234)
			(stroke
				(width 0.1)
				(type default)
			)
			(layer "F.SilkS")
		)
		(fp_line
			(start 19.137376 -1.390396)
			(end 20.301966 -2.507234)
			(stroke
				(width 0.1)
				(type default)
			)
			(layer "F.SilkS")
		)
		(fp_line
			(start 19.144234 -4.109466)
			(end 19.204686 -4.109466)
			(stroke
				(width 0.1)
				(type default)
			)
			(layer "F.SilkS")
		)
		(fp_line
			(start 19.144234 -4.109466)
			(end 19.204686 -4.109466)
			(stroke
				(width 0.1)
				(type default)
			)
			(layer "F.SilkS")
		)
		(fp_line
			(start 19.144234 -4.109466)
			(end 20.874228 -5.768594)
			(stroke
				(width 0.1)
				(type default)
			)
			(layer "F.SilkS")
		)
		(fp_line
			(start 19.144234 -4.109466)
			(end 20.874228 -5.768594)
			(stroke
				(width 0.1)
				(type default)
			)
			(layer "F.SilkS")
		)
		(fp_line
			(start 19.149822 -1.344676)
			(end 20.28952 -2.437892)
			(stroke
				(width 0.1)
				(type default)
			)
			(layer "F.SilkS")
		)
		(fp_line
			(start 19.149822 -1.344676)
			(end 20.28952 -2.437892)
			(stroke
				(width 0.1)
				(type default)
			)
			(layer "F.SilkS")
		)
		(fp_line
			(start 19.153378 -2.386584)
			(end 19.141186 -2.317242)
			(stroke
				(width 0.1)
				(type default)
			)
			(layer "F.SilkS")
		)
		(fp_line
			(start 19.153378 -2.386584)
			(end 19.141186 -2.317242)
			(stroke
				(width 0.1)
				(type default)
			)
			(layer "F.SilkS")
		)
		(fp_line
			(start 19.153378 -2.386584)
			(end 20.50923 -3.687064)
			(stroke
				(width 0.1)
				(type default)
			)
			(layer "F.SilkS")
		)
		(fp_line
			(start 19.153378 -2.386584)
			(end 20.50923 -3.687064)
			(stroke
				(width 0.1)
				(type default)
			)
			(layer "F.SilkS")
		)
		(fp_line
			(start 19.165316 -2.455926)
			(end 19.153378 -2.386584)
			(stroke
				(width 0.1)
				(type default)
			)
			(layer "F.SilkS")
		)
		(fp_line
			(start 19.165316 -2.455926)
			(end 19.153378 -2.386584)
			(stroke
				(width 0.1)
				(type default)
			)
			(layer "F.SilkS")
		)
		(fp_line
			(start 19.165316 -2.455926)
			(end 20.521422 -3.75666)
			(stroke
				(width 0.1)
				(type default)
			)
			(layer "F.SilkS")
		)
		(fp_line
			(start 19.165316 -2.455926)
			(end 20.521422 -3.75666)
			(stroke
				(width 0.1)
				(type default)
			)
			(layer "F.SilkS")
		)
		(fp_line
			(start 19.170142 -1.306322)
			(end 20.278344 -2.369312)
			(stroke
				(width 0.1)
				(type default)
			)
			(layer "F.SilkS")
		)
		(fp_line
			(start 19.170142 -1.306322)
			(end 20.278344 -2.369312)
			(stroke
				(width 0.1)
				(type default)
			)
			(layer "F.SilkS")
		)
		(fp_line
			(start 19.177762 -2.525522)
			(end 19.165316 -2.455926)
			(stroke
				(width 0.1)
				(type default)
			)
			(layer "F.SilkS")
		)
		(fp_line
			(start 19.177762 -2.525522)
			(end 19.165316 -2.455926)
			(stroke
				(width 0.1)
				(type default)
			)
			(layer "F.SilkS")
		)
		(fp_line
			(start 19.177762 -2.525522)
			(end 20.533614 -3.826256)
			(stroke
				(width 0.1)
				(type default)
			)
			(layer "F.SilkS")
		)
		(fp_line
			(start 19.177762 -2.525522)
			(end 20.533614 -3.826256)
			(stroke
				(width 0.1)
				(type default)
			)
			(layer "F.SilkS")
		)
		(fp_line
			(start 19.1897 -2.594864)
			(end 19.177762 -2.525522)
			(stroke
				(width 0.1)
				(type default)
			)
			(layer "F.SilkS")
		)
		(fp_line
			(start 19.1897 -2.594864)
			(end 19.177762 -2.525522)
			(stroke
				(width 0.1)
				(type default)
			)
			(layer "F.SilkS")
		)
		(fp_line
			(start 19.1897 -2.594864)
			(end 20.545806 -3.895344)
			(stroke
				(width 0.1)
				(type default)
			)
			(layer "F.SilkS")
		)
		(fp_line
			(start 19.1897 -2.594864)
			(end 20.545806 -3.895344)
			(stroke
				(width 0.1)
				(type default)
			)
			(layer "F.SilkS")
		)
		(fp_line
			(start 19.190462 -1.267968)
			(end 20.270216 -2.303526)
			(stroke
				(width 0.1)
				(type default)
			)
			(layer "F.SilkS")
		)
		(fp_line
			(start 19.190462 -1.267968)
			(end 20.270216 -2.303526)
			(stroke
				(width 0.1)
				(type default)
			)
			(layer "F.SilkS")
		)
		(fp_line
			(start 19.201892 -2.663952)
			(end 19.1897 -2.594864)
			(stroke
				(width 0.1)
				(type default)
			)
			(layer "F.SilkS")
		)
		(fp_line
			(start 19.201892 -2.663952)
			(end 19.1897 -2.594864)
			(stroke
				(width 0.1)
				(type default)
			)
			(layer "F.SilkS")
		)
		(fp_line
			(start 19.201892 -2.663952)
			(end 20.557744 -3.96494)
			(stroke
				(width 0.1)
				(type default)
			)
			(layer "F.SilkS")
		)
		(fp_line
			(start 19.201892 -2.663952)
			(end 20.557744 -3.96494)
			(stroke
				(width 0.1)
				(type default)
			)
			(layer "F.SilkS")
		)
		(fp_line
			(start 19.204686 -4.109466)
			(end 19.264884 -4.109466)
			(stroke
				(width 0.1)
				(type default)
			)
			(layer "F.SilkS")
		)
		(fp_line
			(start 19.204686 -4.109466)
			(end 19.264884 -4.109466)
			(stroke
				(width 0.1)
				(type default)
			)
			(layer "F.SilkS")
		)
		(fp_line
			(start 19.204686 -4.109466)
			(end 20.861782 -5.699252)
			(stroke
				(width 0.1)
				(type default)
			)
			(layer "F.SilkS")
		)
		(fp_line
			(start 19.204686 -4.109466)
			(end 20.861782 -5.699252)
			(stroke
				(width 0.1)
				(type default)
			)
			(layer "F.SilkS")
		)
		(fp_line
			(start 19.210782 -1.229868)
			(end 20.26285 -2.239264)
			(stroke
				(width 0.1)
				(type default)
			)
			(layer "F.SilkS")
		)
		(fp_line
			(start 19.210782 -1.229868)
			(end 20.26285 -2.239264)
			(stroke
				(width 0.1)
				(type default)
			)
			(layer "F.SilkS")
		)
		(fp_line
			(start 19.21383 -2.733548)
			(end 19.201892 -2.663952)
			(stroke
				(width 0.1)
				(type default)
			)
			(layer "F.SilkS")
		)
		(fp_line
			(start 19.21383 -2.733548)
			(end 19.201892 -2.663952)
			(stroke
				(width 0.1)
				(type default)
			)
			(layer "F.SilkS")
		)
		(fp_line
			(start 19.21383 -2.733548)
			(end 20.57019 -4.034282)
			(stroke
				(width 0.1)
				(type default)
			)
			(layer "F.SilkS")
		)
		(fp_line
			(start 19.21383 -2.733548)
			(end 20.57019 -4.034282)
			(stroke
				(width 0.1)
				(type default)
			)
			(layer "F.SilkS")
		)
		(fp_line
			(start 19.226276 -2.80289)
			(end 19.21383 -2.733548)
			(stroke
				(width 0.1)
				(type default)
			)
			(layer "F.SilkS")
		)
		(fp_line
			(start 19.226276 -2.80289)
			(end 19.21383 -2.733548)
			(stroke
				(width 0.1)
				(type default)
			)
			(layer "F.SilkS")
		)
		(fp_line
			(start 19.226276 -2.80289)
			(end 20.582382 -4.103878)
			(stroke
				(width 0.1)
				(type default)
			)
			(layer "F.SilkS")
		)
		(fp_line
			(start 19.226276 -2.80289)
			(end 20.582382 -4.103878)
			(stroke
				(width 0.1)
				(type default)
			)
			(layer "F.SilkS")
		)
		(fp_line
			(start 19.22907 -5.171694)
			(end 19.168872 -5.171694)
			(stroke
				(width 0.1)
				(type default)
			)
			(layer "F.SilkS")
		)
		(fp_line
			(start 19.22907 -5.171694)
			(end 19.168872 -5.171694)
			(stroke
				(width 0.1)
				(type default)
			)
			(layer "F.SilkS")
		)
		(fp_line
			(start 19.230848 -1.191514)
			(end 20.263358 -2.181606)
			(stroke
				(width 0.1)
				(type default)
			)
			(layer "F.SilkS")
		)
		(fp_line
			(start 19.230848 -1.191514)
			(end 20.263358 -2.181606)
			(stroke
				(width 0.1)
				(type default)
			)
			(layer "F.SilkS")
		)
		(fp_line
			(start 19.238468 -2.872232)
			(end 19.226276 -2.80289)
			(stroke
				(width 0.1)
				(type default)
			)
			(layer "F.SilkS")
		)
		(fp_line
			(start 19.238468 -2.872232)
			(end 19.226276 -2.80289)
			(stroke
				(width 0.1)
				(type default)
			)
			(layer "F.SilkS")
		)
		(fp_line
			(start 19.238468 -2.872232)
			(end 21.635466 -5.171694)
			(stroke
				(width 0.1)
				(type default)
			)
			(layer "F.SilkS")
		)
		(fp_line
			(start 19.238468 -2.872232)
			(end 21.635466 -5.171694)
			(stroke
				(width 0.1)
				(type default)
			)
			(layer "F.SilkS")
		)
		(fp_line
			(start 19.250406 -2.941574)
			(end 19.238468 -2.872232)
			(stroke
				(width 0.1)
				(type default)
			)
			(layer "F.SilkS")
		)
		(fp_line
			(start 19.250406 -2.941574)
			(end 19.238468 -2.872232)
			(stroke
				(width 0.1)
				(type default)
			)
			(layer "F.SilkS")
		)
		(fp_line
			(start 19.25193 -1.153922)
			(end 20.265136 -2.125726)
			(stroke
				(width 0.1)
				(type default)
			)
			(layer "F.SilkS")
		)
		(fp_line
			(start 19.25193 -1.153922)
			(end 20.265136 -2.125726)
			(stroke
				(width 0.1)
				(type default)
			)
			(layer "F.SilkS")
		)
		(fp_line
			(start 19.262852 -3.01117)
			(end 19.250406 -2.941574)
			(stroke
				(width 0.1)
				(type default)
			)
			(layer "F.SilkS")
		)
		(fp_line
			(start 19.262852 -3.01117)
			(end 19.250406 -2.941574)
			(stroke
				(width 0.1)
				(type default)
			)
			(layer "F.SilkS")
		)
		(fp_line
			(start 19.264884 -4.109466)
			(end 19.324828 -4.109466)
			(stroke
				(width 0.1)
				(type default)
			)
			(layer "F.SilkS")
		)
		(fp_line
			(start 19.264884 -4.109466)
			(end 19.324828 -4.109466)
			(stroke
				(width 0.1)
				(type default)
			)
			(layer "F.SilkS")
		)
		(fp_line
			(start 19.264884 -4.109466)
			(end 20.84959 -5.629656)
			(stroke
				(width 0.1)
				(type default)
			)
			(layer "F.SilkS")
		)
		(fp_line
			(start 19.264884 -4.109466)
			(end 20.84959 -5.629656)
			(stroke
				(width 0.1)
				(type default)
			)
			(layer "F.SilkS")
		)
		(fp_line
			(start 19.27479 -3.080512)
			(end 19.262852 -3.01117)
			(stroke
				(width 0.1)
				(type default)
			)
			(layer "F.SilkS")
		)
		(fp_line
			(start 19.27479 -3.080512)
			(end 19.262852 -3.01117)
			(stroke
				(width 0.1)
				(type default)
			)
			(layer "F.SilkS")
		)
		(fp_line
			(start 19.279616 -1.122934)
			(end 20.274534 -2.077212)
			(stroke
				(width 0.1)
				(type default)
			)
			(layer "F.SilkS")
		)
		(fp_line
			(start 19.279616 -1.122934)
			(end 20.274534 -2.077212)
			(stroke
				(width 0.1)
				(type default)
			)
			(layer "F.SilkS")
		)
		(fp_line
			(start 19.286982 -3.149854)
			(end 19.27479 -3.080512)
			(stroke
				(width 0.1)
				(type default)
			)
			(layer "F.SilkS")
		)
		(fp_line
			(start 19.286982 -3.149854)
			(end 19.27479 -3.080512)
			(stroke
				(width 0.1)
				(type default)
			)
			(layer "F.SilkS")
		)
		(fp_line
			(start 19.289014 -5.171694)
			(end 19.22907 -5.171694)
			(stroke
				(width 0.1)
				(type default)
			)
			(layer "F.SilkS")
		)
		(fp_line
			(start 19.289014 -5.171694)
			(end 19.22907 -5.171694)
			(stroke
				(width 0.1)
				(type default)
			)
			(layer "F.SilkS")
		)
		(fp_line
			(start 19.299428 -3.218942)
			(end 19.286982 -3.149854)
			(stroke
				(width 0.1)
				(type default)
			)
			(layer "F.SilkS")
		)
		(fp_line
			(start 19.299428 -3.218942)
			(end 19.286982 -3.149854)
			(stroke
				(width 0.1)
				(type default)
			)
			(layer "F.SilkS")
		)
		(fp_line
			(start 19.307556 -1.091946)
			(end 20.287488 -2.031746)
			(stroke
				(width 0.1)
				(type default)
			)
			(layer "F.SilkS")
		)
		(fp_line
			(start 19.307556 -1.091946)
			(end 20.287488 -2.031746)
			(stroke
				(width 0.1)
				(type default)
			)
			(layer "F.SilkS")
		)
		(fp_line
			(start 19.311366 -3.288538)
			(end 19.299428 -3.218942)
			(stroke
				(width 0.1)
				(type default)
			)
			(layer "F.SilkS")
		)
		(fp_line
			(start 19.311366 -3.288538)
			(end 19.299428 -3.218942)
			(stroke
				(width 0.1)
				(type default)
			)
			(layer "F.SilkS")
		)
		(fp_line
			(start 19.323558 -3.358134)
			(end 19.311366 -3.288538)
			(stroke
				(width 0.1)
				(type default)
			)
			(layer "F.SilkS")
		)
		(fp_line
			(start 19.323558 -3.358134)
			(end 19.311366 -3.288538)
			(stroke
				(width 0.1)
				(type default)
			)
			(layer "F.SilkS")
		)
		(fp_line
			(start 19.324828 -4.109466)
			(end 19.385026 -4.109466)
			(stroke
				(width 0.1)
				(type default)
			)
			(layer "F.SilkS")
		)
		(fp_line
			(start 19.324828 -4.109466)
			(end 19.385026 -4.109466)
			(stroke
				(width 0.1)
				(type default)
			)
			(layer "F.SilkS")
		)
		(fp_line
			(start 19.324828 -4.109466)
			(end 20.837144 -5.560314)
			(stroke
				(width 0.1)
				(type default)
			)
			(layer "F.SilkS")
		)
		(fp_line
			(start 19.324828 -4.109466)
			(end 20.837144 -5.560314)
			(stroke
				(width 0.1)
				(type default)
			)
			(layer "F.SilkS")
		)
		(fp_line
			(start 19.335496 -1.061212)
			(end 20.307046 -1.992884)
			(stroke
				(width 0.1)
				(type default)
			)
			(layer "F.SilkS")
		)
		(fp_line
			(start 19.335496 -1.061212)
			(end 20.307046 -1.992884)
			(stroke
				(width 0.1)
				(type default)
			)
			(layer "F.SilkS")
		)
		(fp_line
			(start 19.33575 -3.427476)
			(end 19.323558 -3.358134)
			(stroke
				(width 0.1)
				(type default)
			)
			(layer "F.SilkS")
		)
		(fp_line
			(start 19.33575 -3.427476)
			(end 19.323558 -3.358134)
			(stroke
				(width 0.1)
				(type default)
			)
			(layer "F.SilkS")
		)
		(fp_line
			(start 19.347942 -3.496564)
			(end 19.33575 -3.427476)
			(stroke
				(width 0.1)
				(type default)
			)
			(layer "F.SilkS")
		)
		(fp_line
			(start 19.347942 -3.496564)
			(end 19.33575 -3.427476)
			(stroke
				(width 0.1)
				(type default)
			)
			(layer "F.SilkS")
		)
		(fp_line
			(start 19.349212 -5.171694)
			(end 19.289014 -5.171694)
			(stroke
				(width 0.1)
				(type default)
			)
			(layer "F.SilkS")
		)
		(fp_line
			(start 19.349212 -5.171694)
			(end 19.289014 -5.171694)
			(stroke
				(width 0.1)
				(type default)
			)
			(layer "F.SilkS")
		)
		(fp_line
			(start 19.35988 -3.56616)
			(end 19.347942 -3.496564)
			(stroke
				(width 0.1)
				(type default)
			)
			(layer "F.SilkS")
		)
		(fp_line
			(start 19.35988 -3.56616)
			(end 19.347942 -3.496564)
			(stroke
				(width 0.1)
				(type default)
			)
			(layer "F.SilkS")
		)
		(fp_line
			(start 19.363436 -1.030224)
			(end 20.332446 -1.959356)
			(stroke
				(width 0.1)
				(type default)
			)
			(layer "F.SilkS")
		)
		(fp_line
			(start 19.363436 -1.030224)
			(end 20.332446 -1.959356)
			(stroke
				(width 0.1)
				(type default)
			)
			(layer "F.SilkS")
		)
		(fp_line
			(start 19.372326 -3.635502)
			(end 19.35988 -3.56616)
			(stroke
				(width 0.1)
				(type default)
			)
			(layer "F.SilkS")
		)
		(fp_line
			(start 19.372326 -3.635502)
			(end 19.35988 -3.56616)
			(stroke
				(width 0.1)
				(type default)
			)
			(layer "F.SilkS")
		)
		(fp_line
			(start 19.384518 -3.704844)
			(end 19.372326 -3.635502)
			(stroke
				(width 0.1)
				(type default)
			)
			(layer "F.SilkS")
		)
		(fp_line
			(start 19.384518 -3.704844)
			(end 19.372326 -3.635502)
			(stroke
				(width 0.1)
				(type default)
			)
			(layer "F.SilkS")
		)
		(fp_line
			(start 19.385026 -4.109466)
			(end 19.445478 -4.109466)
			(stroke
				(width 0.1)
				(type default)
			)
			(layer "F.SilkS")
		)
		(fp_line
			(start 19.385026 -4.109466)
			(end 19.445478 -4.109466)
			(stroke
				(width 0.1)
				(type default)
			)
			(layer "F.SilkS")
		)
		(fp_line
			(start 19.385026 -4.109466)
			(end 20.825206 -5.490972)
			(stroke
				(width 0.1)
				(type default)
			)
			(layer "F.SilkS")
		)
		(fp_line
			(start 19.385026 -4.109466)
			(end 20.825206 -5.490972)
			(stroke
				(width 0.1)
				(type default)
			)
			(layer "F.SilkS")
		)
		(fp_line
			(start 19.392646 -1.000252)
			(end 20.362164 -1.9304)
			(stroke
				(width 0.1)
				(type default)
			)
			(layer "F.SilkS")
		)
		(fp_line
			(start 19.392646 -1.000252)
			(end 20.362164 -1.9304)
			(stroke
				(width 0.1)
				(type default)
			)
			(layer "F.SilkS")
		)
		(fp_line
			(start 19.396456 -3.774186)
			(end 19.384518 -3.704844)
			(stroke
				(width 0.1)
				(type default)
			)
			(layer "F.SilkS")
		)
		(fp_line
			(start 19.396456 -3.774186)
			(end 19.384518 -3.704844)
			(stroke
				(width 0.1)
				(type default)
			)
			(layer "F.SilkS")
		)
		(fp_line
			(start 19.408902 -3.843528)
			(end 19.396456 -3.774186)
			(stroke
				(width 0.1)
				(type default)
			)
			(layer "F.SilkS")
		)
		(fp_line
			(start 19.408902 -3.843528)
			(end 19.396456 -3.774186)
			(stroke
				(width 0.1)
				(type default)
			)
			(layer "F.SilkS")
		)
		(fp_line
			(start 19.409664 -5.171694)
			(end 19.349212 -5.171694)
			(stroke
				(width 0.1)
				(type default)
			)
			(layer "F.SilkS")
		)
		(fp_line
			(start 19.409664 -5.171694)
			(end 19.349212 -5.171694)
			(stroke
				(width 0.1)
				(type default)
			)
			(layer "F.SilkS")
		)
		(fp_line
			(start 19.42084 -3.913124)
			(end 19.408902 -3.843528)
			(stroke
				(width 0.1)
				(type default)
			)
			(layer "F.SilkS")
		)
		(fp_line
			(start 19.42084 -3.913124)
			(end 19.408902 -3.843528)
			(stroke
				(width 0.1)
				(type default)
			)
			(layer "F.SilkS")
		)
		(fp_line
			(start 19.42084 -3.913124)
			(end 20.776184 -5.21335)
			(stroke
				(width 0.1)
				(type default)
			)
			(layer "F.SilkS")
		)
		(fp_line
			(start 19.42084 -3.913124)
			(end 20.776184 -5.21335)
			(stroke
				(width 0.1)
				(type default)
			)
			(layer "F.SilkS")
		)
		(fp_line
			(start 19.42846 -0.976884)
			(end 20.400772 -1.909572)
			(stroke
				(width 0.1)
				(type default)
			)
			(layer "F.SilkS")
		)
		(fp_line
			(start 19.42846 -0.976884)
			(end 20.400772 -1.909572)
			(stroke
				(width 0.1)
				(type default)
			)
			(layer "F.SilkS")
		)
		(fp_line
			(start 19.433032 -3.982466)
			(end 19.42084 -3.913124)
			(stroke
				(width 0.1)
				(type default)
			)
			(layer "F.SilkS")
		)
		(fp_line
			(start 19.433032 -3.982466)
			(end 19.42084 -3.913124)
			(stroke
				(width 0.1)
				(type default)
			)
			(layer "F.SilkS")
		)
		(fp_line
			(start 19.445478 -4.109466)
			(end 19.455384 -4.109466)
			(stroke
				(width 0.1)
				(type default)
			)
			(layer "F.SilkS")
		)
		(fp_line
			(start 19.445478 -4.109466)
			(end 19.455384 -4.109466)
			(stroke
				(width 0.1)
				(type default)
			)
			(layer "F.SilkS")
		)
		(fp_line
			(start 19.445478 -4.109466)
			(end 20.81276 -5.421376)
			(stroke
				(width 0.1)
				(type default)
			)
			(layer "F.SilkS")
		)
		(fp_line
			(start 19.445478 -4.109466)
			(end 20.81276 -5.421376)
			(stroke
				(width 0.1)
				(type default)
			)
			(layer "F.SilkS")
		)
		(fp_line
			(start 19.445478 -4.051554)
			(end 19.433032 -3.982466)
			(stroke
				(width 0.1)
				(type default)
			)
			(layer "F.SilkS")
		)
		(fp_line
			(start 19.445478 -4.051554)
			(end 19.433032 -3.982466)
			(stroke
				(width 0.1)
				(type default)
			)
			(layer "F.SilkS")
		)
		(fp_line
			(start 19.455384 -4.109466)
			(end 19.445478 -4.051554)
			(stroke
				(width 0.1)
				(type default)
			)
			(layer "F.SilkS")
		)
		(fp_line
			(start 19.455384 -4.109466)
			(end 19.445478 -4.051554)
			(stroke
				(width 0.1)
				(type default)
			)
			(layer "F.SilkS")
		)
		(fp_line
			(start 19.46402 -0.953516)
			(end 20.442428 -1.892046)
			(stroke
				(width 0.1)
				(type default)
			)
			(layer "F.SilkS")
		)
		(fp_line
			(start 19.46402 -0.953516)
			(end 20.442428 -1.892046)
			(stroke
				(width 0.1)
				(type default)
			)
			(layer "F.SilkS")
		)
		(fp_line
			(start 19.469608 -5.171694)
			(end 19.409664 -5.171694)
			(stroke
				(width 0.1)
				(type default)
			)
			(layer "F.SilkS")
		)
		(fp_line
			(start 19.469608 -5.171694)
			(end 19.409664 -5.171694)
			(stroke
				(width 0.1)
				(type default)
			)
			(layer "F.SilkS")
		)
		(fp_line
			(start 19.500088 -0.930148)
			(end 20.491704 -1.881378)
			(stroke
				(width 0.1)
				(type default)
			)
			(layer "F.SilkS")
		)
		(fp_line
			(start 19.500088 -0.930148)
			(end 20.491704 -1.881378)
			(stroke
				(width 0.1)
				(type default)
			)
			(layer "F.SilkS")
		)
		(fp_line
			(start 19.529806 -5.171694)
			(end 19.469608 -5.171694)
			(stroke
				(width 0.1)
				(type default)
			)
			(layer "F.SilkS")
		)
		(fp_line
			(start 19.529806 -5.171694)
			(end 19.469608 -5.171694)
			(stroke
				(width 0.1)
				(type default)
			)
			(layer "F.SilkS")
		)
		(fp_line
			(start 19.536156 -0.906526)
			(end 20.545044 -1.874774)
			(stroke
				(width 0.1)
				(type default)
			)
			(layer "F.SilkS")
		)
		(fp_line
			(start 19.536156 -0.906526)
			(end 20.545044 -1.874774)
			(stroke
				(width 0.1)
				(type default)
			)
			(layer "F.SilkS")
		)
		(fp_line
			(start 19.574002 -0.88519)
			(end 20.60194 -1.871726)
			(stroke
				(width 0.1)
				(type default)
			)
			(layer "F.SilkS")
		)
		(fp_line
			(start 19.574002 -0.88519)
			(end 20.60194 -1.871726)
			(stroke
				(width 0.1)
				(type default)
			)
			(layer "F.SilkS")
		)
		(fp_line
			(start 19.58975 -5.171694)
			(end 19.529806 -5.171694)
			(stroke
				(width 0.1)
				(type default)
			)
			(layer "F.SilkS")
		)
		(fp_line
			(start 19.58975 -5.171694)
			(end 19.529806 -5.171694)
			(stroke
				(width 0.1)
				(type default)
			)
			(layer "F.SilkS")
		)
		(fp_line
			(start 19.58975 -5.171694)
			(end 19.641566 -5.171694)
			(stroke
				(width 0.1)
				(type default)
			)
			(layer "F.SilkS")
		)
		(fp_line
			(start 19.58975 -5.171694)
			(end 19.641566 -5.171694)
			(stroke
				(width 0.1)
				(type default)
			)
			(layer "F.SilkS")
		)
		(fp_line
			(start 19.617944 -0.870458)
			(end 20.669504 -1.878838)
			(stroke
				(width 0.1)
				(type default)
			)
			(layer "F.SilkS")
		)
		(fp_line
			(start 19.617944 -0.870458)
			(end 20.669504 -1.878838)
			(stroke
				(width 0.1)
				(type default)
			)
			(layer "F.SilkS")
		)
		(fp_line
			(start 19.641566 -5.171694)
			(end 19.651726 -5.23113)
			(stroke
				(width 0.1)
				(type default)
			)
			(layer "F.SilkS")
		)
		(fp_line
			(start 19.641566 -5.171694)
			(end 19.651726 -5.23113)
			(stroke
				(width 0.1)
				(type default)
			)
			(layer "F.SilkS")
		)
		(fp_line
			(start 19.662902 -0.855218)
			(end 20.738084 -1.886966)
			(stroke
				(width 0.1)
				(type default)
			)
			(layer "F.SilkS")
		)
		(fp_line
			(start 19.662902 -0.855218)
			(end 20.738084 -1.886966)
			(stroke
				(width 0.1)
				(type default)
			)
			(layer "F.SilkS")
		)
		(fp_line
			(start 19.664172 -5.300472)
			(end 19.651726 -5.23113)
			(stroke
				(width 0.1)
				(type default)
			)
			(layer "F.SilkS")
		)
		(fp_line
			(start 19.664172 -5.300472)
			(end 19.651726 -5.23113)
			(stroke
				(width 0.1)
				(type default)
			)
			(layer "F.SilkS")
		)
		(fp_line
			(start 19.676364 -5.370068)
			(end 19.664172 -5.300472)
			(stroke
				(width 0.1)
				(type default)
			)
			(layer "F.SilkS")
		)
		(fp_line
			(start 19.676364 -5.370068)
			(end 19.664172 -5.300472)
			(stroke
				(width 0.1)
				(type default)
			)
			(layer "F.SilkS")
		)
		(fp_line
			(start 19.688302 -5.439156)
			(end 19.676364 -5.370068)
			(stroke
				(width 0.1)
				(type default)
			)
			(layer "F.SilkS")
		)
		(fp_line
			(start 19.688302 -5.439156)
			(end 19.676364 -5.370068)
			(stroke
				(width 0.1)
				(type default)
			)
			(layer "F.SilkS")
		)
		(fp_line
			(start 19.700748 -5.508752)
			(end 19.688302 -5.439156)
			(stroke
				(width 0.1)
				(type default)
			)
			(layer "F.SilkS")
		)
		(fp_line
			(start 19.700748 -5.508752)
			(end 19.688302 -5.439156)
			(stroke
				(width 0.1)
				(type default)
			)
			(layer "F.SilkS")
		)
		(fp_line
			(start 19.707352 -0.840486)
			(end 20.828 -1.915414)
			(stroke
				(width 0.1)
				(type default)
			)
			(layer "F.SilkS")
		)
		(fp_line
			(start 19.707352 -0.840486)
			(end 20.828 -1.915414)
			(stroke
				(width 0.1)
				(type default)
			)
			(layer "F.SilkS")
		)
		(fp_line
			(start 19.712686 -5.578094)
			(end 19.700748 -5.508752)
			(stroke
				(width 0.1)
				(type default)
			)
			(layer "F.SilkS")
		)
		(fp_line
			(start 19.712686 -5.578094)
			(end 19.700748 -5.508752)
			(stroke
				(width 0.1)
				(type default)
			)
			(layer "F.SilkS")
		)
		(fp_line
			(start 19.725132 -5.647436)
			(end 19.712686 -5.578094)
			(stroke
				(width 0.1)
				(type default)
			)
			(layer "F.SilkS")
		)
		(fp_line
			(start 19.725132 -5.647436)
			(end 19.712686 -5.578094)
			(stroke
				(width 0.1)
				(type default)
			)
			(layer "F.SilkS")
		)
		(fp_line
			(start 19.737324 -5.716778)
			(end 19.725132 -5.647436)
			(stroke
				(width 0.1)
				(type default)
			)
			(layer "F.SilkS")
		)
		(fp_line
			(start 19.737324 -5.716778)
			(end 19.725132 -5.647436)
			(stroke
				(width 0.1)
				(type default)
			)
			(layer "F.SilkS")
		)
		(fp_line
			(start 19.749262 -5.786374)
			(end 19.737324 -5.716778)
			(stroke
				(width 0.1)
				(type default)
			)
			(layer "F.SilkS")
		)
		(fp_line
			(start 19.749262 -5.786374)
			(end 19.737324 -5.716778)
			(stroke
				(width 0.1)
				(type default)
			)
			(layer "F.SilkS")
		)
		(fp_line
			(start 19.751802 -0.825246)
			(end 20.932902 -1.95834)
			(stroke
				(width 0.1)
				(type default)
			)
			(layer "F.SilkS")
		)
		(fp_line
			(start 19.751802 -0.825246)
			(end 20.932902 -1.95834)
			(stroke
				(width 0.1)
				(type default)
			)
			(layer "F.SilkS")
		)
		(fp_line
			(start 19.761708 -5.85597)
			(end 19.749262 -5.786374)
			(stroke
				(width 0.1)
				(type default)
			)
			(layer "F.SilkS")
		)
		(fp_line
			(start 19.761708 -5.85597)
			(end 19.749262 -5.786374)
			(stroke
				(width 0.1)
				(type default)
			)
			(layer "F.SilkS")
		)
		(fp_line
			(start 19.773646 -5.925058)
			(end 19.761708 -5.85597)
			(stroke
				(width 0.1)
				(type default)
			)
			(layer "F.SilkS")
		)
		(fp_line
			(start 19.773646 -5.925058)
			(end 19.761708 -5.85597)
			(stroke
				(width 0.1)
				(type default)
			)
			(layer "F.SilkS")
		)
		(fp_line
			(start 19.785838 -5.9944)
			(end 19.773646 -5.925058)
			(stroke
				(width 0.1)
				(type default)
			)
			(layer "F.SilkS")
		)
		(fp_line
			(start 19.785838 -5.9944)
			(end 19.773646 -5.925058)
			(stroke
				(width 0.1)
				(type default)
			)
			(layer "F.SilkS")
		)
		(fp_line
			(start 19.798284 -6.063996)
			(end 19.785838 -5.9944)
			(stroke
				(width 0.1)
				(type default)
			)
			(layer "F.SilkS")
		)
		(fp_line
			(start 19.798284 -6.063996)
			(end 19.785838 -5.9944)
			(stroke
				(width 0.1)
				(type default)
			)
			(layer "F.SilkS")
		)
		(fp_line
			(start 19.798284 -6.063996)
			(end 19.810222 -6.133338)
			(stroke
				(width 0.1)
				(type default)
			)
			(layer "F.SilkS")
		)
		(fp_line
			(start 19.798284 -6.063996)
			(end 19.810222 -6.133338)
			(stroke
				(width 0.1)
				(type default)
			)
			(layer "F.SilkS")
		)
		(fp_line
			(start 19.801078 -0.815086)
			(end 21.08327 -2.044954)
			(stroke
				(width 0.1)
				(type default)
			)
			(layer "F.SilkS")
		)
		(fp_line
			(start 19.801078 -0.815086)
			(end 21.08327 -2.044954)
			(stroke
				(width 0.1)
				(type default)
			)
			(layer "F.SilkS")
		)
		(fp_line
			(start 19.810222 -6.133338)
			(end 19.822668 -6.20268)
			(stroke
				(width 0.1)
				(type default)
			)
			(layer "F.SilkS")
		)
		(fp_line
			(start 19.810222 -6.133338)
			(end 19.822668 -6.20268)
			(stroke
				(width 0.1)
				(type default)
			)
			(layer "F.SilkS")
		)
		(fp_line
			(start 19.822668 -6.20268)
			(end 19.834606 -6.272022)
			(stroke
				(width 0.1)
				(type default)
			)
			(layer "F.SilkS")
		)
		(fp_line
			(start 19.822668 -6.20268)
			(end 19.834606 -6.272022)
			(stroke
				(width 0.1)
				(type default)
			)
			(layer "F.SilkS")
		)
		(fp_line
			(start 19.835114 -6.274308)
			(end 19.834606 -6.272022)
			(stroke
				(width 0.1)
				(type default)
			)
			(layer "F.SilkS")
		)
		(fp_line
			(start 19.835114 -6.274308)
			(end 19.834606 -6.272022)
			(stroke
				(width 0.1)
				(type default)
			)
			(layer "F.SilkS")
		)
		(fp_line
			(start 19.838924 -6.276086)
			(end 19.834606 -6.272022)
			(stroke
				(width 0.1)
				(type default)
			)
			(layer "F.SilkS")
		)
		(fp_line
			(start 19.838924 -6.276086)
			(end 19.834606 -6.272022)
			(stroke
				(width 0.1)
				(type default)
			)
			(layer "F.SilkS")
		)
		(fp_line
			(start 19.838924 -6.276086)
			(end 19.835114 -6.274308)
			(stroke
				(width 0.1)
				(type default)
			)
			(layer "F.SilkS")
		)
		(fp_line
			(start 19.838924 -6.276086)
			(end 19.835114 -6.274308)
			(stroke
				(width 0.1)
				(type default)
			)
			(layer "F.SilkS")
		)
		(fp_line
			(start 19.855434 -0.809498)
			(end 21.299932 -2.195068)
			(stroke
				(width 0.1)
				(type default)
			)
			(layer "F.SilkS")
		)
		(fp_line
			(start 19.855434 -0.809498)
			(end 21.299932 -2.195068)
			(stroke
				(width 0.1)
				(type default)
			)
			(layer "F.SilkS")
		)
		(fp_line
			(start 19.910044 -0.80391)
			(end 21.273516 -2.11201)
			(stroke
				(width 0.1)
				(type default)
			)
			(layer "F.SilkS")
		)
		(fp_line
			(start 19.910044 -0.80391)
			(end 21.273516 -2.11201)
			(stroke
				(width 0.1)
				(type default)
			)
			(layer "F.SilkS")
		)
		(fp_line
			(start 19.95424 -6.329172)
			(end 19.822668 -6.20268)
			(stroke
				(width 0.1)
				(type default)
			)
			(layer "F.SilkS")
		)
		(fp_line
			(start 19.95424 -6.329172)
			(end 19.822668 -6.20268)
			(stroke
				(width 0.1)
				(type default)
			)
			(layer "F.SilkS")
		)
		(fp_line
			(start 19.95424 -6.329172)
			(end 19.838924 -6.276086)
			(stroke
				(width 0.1)
				(type default)
			)
			(layer "F.SilkS")
		)
		(fp_line
			(start 19.95424 -6.329172)
			(end 19.838924 -6.276086)
			(stroke
				(width 0.1)
				(type default)
			)
			(layer "F.SilkS")
		)
		(fp_line
			(start 19.964654 -0.798576)
			(end 21.2471 -2.028952)
			(stroke
				(width 0.1)
				(type default)
			)
			(layer "F.SilkS")
		)
		(fp_line
			(start 19.964654 -0.798576)
			(end 21.2471 -2.028952)
			(stroke
				(width 0.1)
				(type default)
			)
			(layer "F.SilkS")
		)
		(fp_line
			(start 20.01901 -0.792988)
			(end 21.220684 -1.946148)
			(stroke
				(width 0.1)
				(type default)
			)
			(layer "F.SilkS")
		)
		(fp_line
			(start 20.01901 -0.792988)
			(end 21.220684 -1.946148)
			(stroke
				(width 0.1)
				(type default)
			)
			(layer "F.SilkS")
		)
		(fp_line
			(start 20.069302 -6.382004)
			(end 19.810222 -6.133338)
			(stroke
				(width 0.1)
				(type default)
			)
			(layer "F.SilkS")
		)
		(fp_line
			(start 20.069302 -6.382004)
			(end 19.810222 -6.133338)
			(stroke
				(width 0.1)
				(type default)
			)
			(layer "F.SilkS")
		)
		(fp_line
			(start 20.069302 -6.382004)
			(end 19.95424 -6.329172)
			(stroke
				(width 0.1)
				(type default)
			)
			(layer "F.SilkS")
		)
		(fp_line
			(start 20.069302 -6.382004)
			(end 19.95424 -6.329172)
			(stroke
				(width 0.1)
				(type default)
			)
			(layer "F.SilkS")
		)
		(fp_line
			(start 20.084542 -0.798576)
			(end 21.194268 -1.862836)
			(stroke
				(width 0.1)
				(type default)
			)
			(layer "F.SilkS")
		)
		(fp_line
			(start 20.084542 -0.798576)
			(end 21.194268 -1.862836)
			(stroke
				(width 0.1)
				(type default)
			)
			(layer "F.SilkS")
		)
		(fp_line
			(start 20.14982 -0.803402)
			(end 21.167852 -1.779778)
			(stroke
				(width 0.1)
				(type default)
			)
			(layer "F.SilkS")
		)
		(fp_line
			(start 20.14982 -0.803402)
			(end 21.167852 -1.779778)
			(stroke
				(width 0.1)
				(type default)
			)
			(layer "F.SilkS")
		)
		(fp_line
			(start 20.185126 -6.43509)
			(end 19.798284 -6.063996)
			(stroke
				(width 0.1)
				(type default)
			)
			(layer "F.SilkS")
		)
		(fp_line
			(start 20.185126 -6.43509)
			(end 19.798284 -6.063996)
			(stroke
				(width 0.1)
				(type default)
			)
			(layer "F.SilkS")
		)
		(fp_line
			(start 20.185126 -6.43509)
			(end 20.069302 -6.382004)
			(stroke
				(width 0.1)
				(type default)
			)
			(layer "F.SilkS")
		)
		(fp_line
			(start 20.185126 -6.43509)
			(end 20.069302 -6.382004)
			(stroke
				(width 0.1)
				(type default)
			)
			(layer "F.SilkS")
		)
		(fp_line
			(start 20.215352 -0.808228)
			(end 21.141436 -1.69672)
			(stroke
				(width 0.1)
				(type default)
			)
			(layer "F.SilkS")
		)
		(fp_line
			(start 20.215352 -0.808228)
			(end 21.141436 -1.69672)
			(stroke
				(width 0.1)
				(type default)
			)
			(layer "F.SilkS")
		)
		(fp_line
			(start 20.280884 -0.813562)
			(end 21.115274 -1.613916)
			(stroke
				(width 0.1)
				(type default)
			)
			(layer "F.SilkS")
		)
		(fp_line
			(start 20.280884 -0.813562)
			(end 21.115274 -1.613916)
			(stroke
				(width 0.1)
				(type default)
			)
			(layer "F.SilkS")
		)
		(fp_line
			(start 20.30095 -6.488176)
			(end 19.785838 -5.9944)
			(stroke
				(width 0.1)
				(type default)
			)
			(layer "F.SilkS")
		)
		(fp_line
			(start 20.30095 -6.488176)
			(end 19.785838 -5.9944)
			(stroke
				(width 0.1)
				(type default)
			)
			(layer "F.SilkS")
		)
		(fp_line
			(start 20.30095 -6.488176)
			(end 20.185126 -6.43509)
			(stroke
				(width 0.1)
				(type default)
			)
			(layer "F.SilkS")
		)
		(fp_line
			(start 20.30095 -6.488176)
			(end 20.185126 -6.43509)
			(stroke
				(width 0.1)
				(type default)
			)
			(layer "F.SilkS")
		)
		(fp_line
			(start 20.301966 -2.507234)
			(end 20.28952 -2.437892)
			(stroke
				(width 0.1)
				(type default)
			)
			(layer "F.SilkS")
		)
		(fp_line
			(start 20.301966 -2.507234)
			(end 20.28952 -2.437892)
			(stroke
				(width 0.1)
				(type default)
			)
			(layer "F.SilkS")
		)
		(fp_line
			(start 20.313904 -2.576576)
			(end 20.301966 -2.507234)
			(stroke
				(width 0.1)
				(type default)
			)
			(layer "F.SilkS")
		)
		(fp_line
			(start 20.313904 -2.576576)
			(end 20.301966 -2.507234)
			(stroke
				(width 0.1)
				(type default)
			)
			(layer "F.SilkS")
		)
		(fp_line
			(start 20.32635 -2.646172)
			(end 20.313904 -2.576576)
			(stroke
				(width 0.1)
				(type default)
			)
			(layer "F.SilkS")
		)
		(fp_line
			(start 20.32635 -2.646172)
			(end 20.313904 -2.576576)
			(stroke
				(width 0.1)
				(type default)
			)
			(layer "F.SilkS")
		)
		(fp_line
			(start 20.32635 -2.646172)
			(end 20.338288 -2.715768)
			(stroke
				(width 0.1)
				(type default)
			)
			(layer "F.SilkS")
		)
		(fp_line
			(start 20.32635 -2.646172)
			(end 20.338288 -2.715768)
			(stroke
				(width 0.1)
				(type default)
			)
			(layer "F.SilkS")
		)
		(fp_line
			(start 20.338288 -2.715768)
			(end 20.35048 -2.784856)
			(stroke
				(width 0.1)
				(type default)
			)
			(layer "F.SilkS")
		)
		(fp_line
			(start 20.338288 -2.715768)
			(end 20.35048 -2.784856)
			(stroke
				(width 0.1)
				(type default)
			)
			(layer "F.SilkS")
		)
		(fp_line
			(start 20.35048 -2.784856)
			(end 20.362926 -2.854198)
			(stroke
				(width 0.1)
				(type default)
			)
			(layer "F.SilkS")
		)
		(fp_line
			(start 20.35048 -2.784856)
			(end 20.362926 -2.854198)
			(stroke
				(width 0.1)
				(type default)
			)
			(layer "F.SilkS")
		)
		(fp_line
			(start 20.359116 -0.830834)
			(end 21.088858 -1.530604)
			(stroke
				(width 0.1)
				(type default)
			)
			(layer "F.SilkS")
		)
		(fp_line
			(start 20.359116 -0.830834)
			(end 21.088858 -1.530604)
			(stroke
				(width 0.1)
				(type default)
			)
			(layer "F.SilkS")
		)
		(fp_line
			(start 20.362926 -2.854198)
			(end 20.374864 -2.923794)
			(stroke
				(width 0.1)
				(type default)
			)
			(layer "F.SilkS")
		)
		(fp_line
			(start 20.362926 -2.854198)
			(end 20.374864 -2.923794)
			(stroke
				(width 0.1)
				(type default)
			)
			(layer "F.SilkS")
		)
		(fp_line
			(start 20.374864 -2.923794)
			(end 20.38731 -2.99339)
			(stroke
				(width 0.1)
				(type default)
			)
			(layer "F.SilkS")
		)
		(fp_line
			(start 20.374864 -2.923794)
			(end 20.38731 -2.99339)
			(stroke
				(width 0.1)
				(type default)
			)
			(layer "F.SilkS")
		)
		(fp_line
			(start 20.38731 -2.99339)
			(end 20.399248 -3.062478)
			(stroke
				(width 0.1)
				(type default)
			)
			(layer "F.SilkS")
		)
		(fp_line
			(start 20.38731 -2.99339)
			(end 20.399248 -3.062478)
			(stroke
				(width 0.1)
				(type default)
			)
			(layer "F.SilkS")
		)
		(fp_line
			(start 20.399248 -3.062478)
			(end 20.41144 -3.13182)
			(stroke
				(width 0.1)
				(type default)
			)
			(layer "F.SilkS")
		)
		(fp_line
			(start 20.399248 -3.062478)
			(end 20.41144 -3.13182)
			(stroke
				(width 0.1)
				(type default)
			)
			(layer "F.SilkS")
		)
		(fp_line
			(start 20.41144 -3.13182)
			(end 20.423886 -3.201416)
			(stroke
				(width 0.1)
				(type default)
			)
			(layer "F.SilkS")
		)
		(fp_line
			(start 20.41144 -3.13182)
			(end 20.423886 -3.201416)
			(stroke
				(width 0.1)
				(type default)
			)
			(layer "F.SilkS")
		)
		(fp_line
			(start 20.416012 -6.541262)
			(end 19.773646 -5.925058)
			(stroke
				(width 0.1)
				(type default)
			)
			(layer "F.SilkS")
		)
		(fp_line
			(start 20.416012 -6.541262)
			(end 19.773646 -5.925058)
			(stroke
				(width 0.1)
				(type default)
			)
			(layer "F.SilkS")
		)
		(fp_line
			(start 20.416012 -6.541262)
			(end 20.30095 -6.488176)
			(stroke
				(width 0.1)
				(type default)
			)
			(layer "F.SilkS")
		)
		(fp_line
			(start 20.416012 -6.541262)
			(end 20.30095 -6.488176)
			(stroke
				(width 0.1)
				(type default)
			)
			(layer "F.SilkS")
		)
		(fp_line
			(start 20.423886 -3.201416)
			(end 20.435824 -3.270758)
			(stroke
				(width 0.1)
				(type default)
			)
			(layer "F.SilkS")
		)
		(fp_line
			(start 20.423886 -3.201416)
			(end 20.435824 -3.270758)
			(stroke
				(width 0.1)
				(type default)
			)
			(layer "F.SilkS")
		)
		(fp_line
			(start 20.435824 -3.270758)
			(end 20.44827 -3.340354)
			(stroke
				(width 0.1)
				(type default)
			)
			(layer "F.SilkS")
		)
		(fp_line
			(start 20.435824 -3.270758)
			(end 20.44827 -3.340354)
			(stroke
				(width 0.1)
				(type default)
			)
			(layer "F.SilkS")
		)
		(fp_line
			(start 20.437602 -0.848106)
			(end 21.062188 -1.447546)
			(stroke
				(width 0.1)
				(type default)
			)
			(layer "F.SilkS")
		)
		(fp_line
			(start 20.437602 -0.848106)
			(end 21.062188 -1.447546)
			(stroke
				(width 0.1)
				(type default)
			)
			(layer "F.SilkS")
		)
		(fp_line
			(start 20.44827 -3.340354)
			(end 20.460462 -3.409442)
			(stroke
				(width 0.1)
				(type default)
			)
			(layer "F.SilkS")
		)
		(fp_line
			(start 20.44827 -3.340354)
			(end 20.460462 -3.409442)
			(stroke
				(width 0.1)
				(type default)
			)
			(layer "F.SilkS")
		)
		(fp_line
			(start 20.460462 -3.409442)
			(end 20.4724 -3.479038)
			(stroke
				(width 0.1)
				(type default)
			)
			(layer "F.SilkS")
		)
		(fp_line
			(start 20.460462 -3.409442)
			(end 20.4724 -3.479038)
			(stroke
				(width 0.1)
				(type default)
			)
			(layer "F.SilkS")
		)
		(fp_line
			(start 20.484846 -3.548634)
			(end 20.4724 -3.479038)
			(stroke
				(width 0.1)
				(type default)
			)
			(layer "F.SilkS")
		)
		(fp_line
			(start 20.484846 -3.548634)
			(end 20.4724 -3.479038)
			(stroke
				(width 0.1)
				(type default)
			)
			(layer "F.SilkS")
		)
		(fp_line
			(start 20.496784 -3.617976)
			(end 19.141186 -2.317242)
			(stroke
				(width 0.1)
				(type default)
			)
			(layer "F.SilkS")
		)
		(fp_line
			(start 20.496784 -3.617976)
			(end 19.141186 -2.317242)
			(stroke
				(width 0.1)
				(type default)
			)
			(layer "F.SilkS")
		)
		(fp_line
			(start 20.496784 -3.617976)
			(end 20.484846 -3.548634)
			(stroke
				(width 0.1)
				(type default)
			)
			(layer "F.SilkS")
		)
		(fp_line
			(start 20.496784 -3.617976)
			(end 20.484846 -3.548634)
			(stroke
				(width 0.1)
				(type default)
			)
			(layer "F.SilkS")
		)
		(fp_line
			(start 20.496784 -3.617976)
			(end 20.50923 -3.687064)
			(stroke
				(width 0.1)
				(type default)
			)
			(layer "F.SilkS")
		)
		(fp_line
			(start 20.496784 -3.617976)
			(end 20.50923 -3.687064)
			(stroke
				(width 0.1)
				(type default)
			)
			(layer "F.SilkS")
		)
		(fp_line
			(start 20.50923 -3.687064)
			(end 20.521422 -3.75666)
			(stroke
				(width 0.1)
				(type default)
			)
			(layer "F.SilkS")
		)
		(fp_line
			(start 20.50923 -3.687064)
			(end 20.521422 -3.75666)
			(stroke
				(width 0.1)
				(type default)
			)
			(layer "F.SilkS")
		)
		(fp_line
			(start 20.515834 -0.865632)
			(end 21.035772 -1.364742)
			(stroke
				(width 0.1)
				(type default)
			)
			(layer "F.SilkS")
		)
		(fp_line
			(start 20.515834 -0.865632)
			(end 21.035772 -1.364742)
			(stroke
				(width 0.1)
				(type default)
			)
			(layer "F.SilkS")
		)
		(fp_line
			(start 20.521422 -3.75666)
			(end 20.533614 -3.826256)
			(stroke
				(width 0.1)
				(type default)
			)
			(layer "F.SilkS")
		)
		(fp_line
			(start 20.521422 -3.75666)
			(end 20.533614 -3.826256)
			(stroke
				(width 0.1)
				(type default)
			)
			(layer "F.SilkS")
		)
		(fp_line
			(start 20.531328 -6.594348)
			(end 19.761708 -5.85597)
			(stroke
				(width 0.1)
				(type default)
			)
			(layer "F.SilkS")
		)
		(fp_line
			(start 20.531328 -6.594348)
			(end 19.761708 -5.85597)
			(stroke
				(width 0.1)
				(type default)
			)
			(layer "F.SilkS")
		)
		(fp_line
			(start 20.531328 -6.594348)
			(end 20.416012 -6.541262)
			(stroke
				(width 0.1)
				(type default)
			)
			(layer "F.SilkS")
		)
		(fp_line
			(start 20.531328 -6.594348)
			(end 20.416012 -6.541262)
			(stroke
				(width 0.1)
				(type default)
			)
			(layer "F.SilkS")
		)
		(fp_line
			(start 20.533614 -3.826256)
			(end 20.545806 -3.895344)
			(stroke
				(width 0.1)
				(type default)
			)
			(layer "F.SilkS")
		)
		(fp_line
			(start 20.533614 -3.826256)
			(end 20.545806 -3.895344)
			(stroke
				(width 0.1)
				(type default)
			)
			(layer "F.SilkS")
		)
		(fp_line
			(start 20.545806 -3.895344)
			(end 20.557744 -3.96494)
			(stroke
				(width 0.1)
				(type default)
			)
			(layer "F.SilkS")
		)
		(fp_line
			(start 20.545806 -3.895344)
			(end 20.557744 -3.96494)
			(stroke
				(width 0.1)
				(type default)
			)
			(layer "F.SilkS")
		)
		(fp_line
			(start 20.557744 -3.96494)
			(end 20.57019 -4.034282)
			(stroke
				(width 0.1)
				(type default)
			)
			(layer "F.SilkS")
		)
		(fp_line
			(start 20.557744 -3.96494)
			(end 20.57019 -4.034282)
			(stroke
				(width 0.1)
				(type default)
			)
			(layer "F.SilkS")
		)
		(fp_line
			(start 20.57019 -4.034282)
			(end 20.582382 -4.103878)
			(stroke
				(width 0.1)
				(type default)
			)
			(layer "F.SilkS")
		)
		(fp_line
			(start 20.57019 -4.034282)
			(end 20.582382 -4.103878)
			(stroke
				(width 0.1)
				(type default)
			)
			(layer "F.SilkS")
		)
		(fp_line
			(start 20.582382 -4.103878)
			(end 20.583398 -4.109466)
			(stroke
				(width 0.1)
				(type default)
			)
			(layer "F.SilkS")
		)
		(fp_line
			(start 20.582382 -4.103878)
			(end 20.583398 -4.109466)
			(stroke
				(width 0.1)
				(type default)
			)
			(layer "F.SilkS")
		)
		(fp_line
			(start 20.582382 -4.103878)
			(end 20.588224 -4.109466)
			(stroke
				(width 0.1)
				(type default)
			)
			(layer "F.SilkS")
		)
		(fp_line
			(start 20.582382 -4.103878)
			(end 20.588224 -4.109466)
			(stroke
				(width 0.1)
				(type default)
			)
			(layer "F.SilkS")
		)
		(fp_line
			(start 20.583398 -4.109466)
			(end 20.588224 -4.109466)
			(stroke
				(width 0.1)
				(type default)
			)
			(layer "F.SilkS")
		)
		(fp_line
			(start 20.583398 -4.109466)
			(end 20.588224 -4.109466)
			(stroke
				(width 0.1)
				(type default)
			)
			(layer "F.SilkS")
		)
		(fp_line
			(start 20.610322 -0.898652)
			(end 21.00961 -1.281684)
			(stroke
				(width 0.1)
				(type default)
			)
			(layer "F.SilkS")
		)
		(fp_line
			(start 20.610322 -0.898652)
			(end 21.00961 -1.281684)
			(stroke
				(width 0.1)
				(type default)
			)
			(layer "F.SilkS")
		)
		(fp_line
			(start 20.647152 -6.647434)
			(end 19.749262 -5.786374)
			(stroke
				(width 0.1)
				(type default)
			)
			(layer "F.SilkS")
		)
		(fp_line
			(start 20.647152 -6.647434)
			(end 19.749262 -5.786374)
			(stroke
				(width 0.1)
				(type default)
			)
			(layer "F.SilkS")
		)
		(fp_line
			(start 20.647152 -6.647434)
			(end 20.531328 -6.594348)
			(stroke
				(width 0.1)
				(type default)
			)
			(layer "F.SilkS")
		)
		(fp_line
			(start 20.647152 -6.647434)
			(end 20.531328 -6.594348)
			(stroke
				(width 0.1)
				(type default)
			)
			(layer "F.SilkS")
		)
		(fp_line
			(start 20.648422 -4.109466)
			(end 20.588224 -4.109466)
			(stroke
				(width 0.1)
				(type default)
			)
			(layer "F.SilkS")
		)
		(fp_line
			(start 20.648422 -4.109466)
			(end 20.588224 -4.109466)
			(stroke
				(width 0.1)
				(type default)
			)
			(layer "F.SilkS")
		)
		(fp_line
			(start 20.708366 -0.934974)
			(end 20.98294 -1.198626)
			(stroke
				(width 0.1)
				(type default)
			)
			(layer "F.SilkS")
		)
		(fp_line
			(start 20.708366 -0.934974)
			(end 20.98294 -1.198626)
			(stroke
				(width 0.1)
				(type default)
			)
			(layer "F.SilkS")
		)
		(fp_line
			(start 20.70862 -4.109466)
			(end 20.648422 -4.109466)
			(stroke
				(width 0.1)
				(type default)
			)
			(layer "F.SilkS")
		)
		(fp_line
			(start 20.70862 -4.109466)
			(end 20.648422 -4.109466)
			(stroke
				(width 0.1)
				(type default)
			)
			(layer "F.SilkS")
		)
		(fp_line
			(start 20.762722 -6.70052)
			(end 19.737324 -5.716778)
			(stroke
				(width 0.1)
				(type default)
			)
			(layer "F.SilkS")
		)
		(fp_line
			(start 20.762722 -6.70052)
			(end 19.737324 -5.716778)
			(stroke
				(width 0.1)
				(type default)
			)
			(layer "F.SilkS")
		)
		(fp_line
			(start 20.762722 -6.70052)
			(end 20.647152 -6.647434)
			(stroke
				(width 0.1)
				(type default)
			)
			(layer "F.SilkS")
		)
		(fp_line
			(start 20.762722 -6.70052)
			(end 20.647152 -6.647434)
			(stroke
				(width 0.1)
				(type default)
			)
			(layer "F.SilkS")
		)
		(fp_line
			(start 20.768564 -4.109466)
			(end 20.70862 -4.109466)
			(stroke
				(width 0.1)
				(type default)
			)
			(layer "F.SilkS")
		)
		(fp_line
			(start 20.768564 -4.109466)
			(end 20.70862 -4.109466)
			(stroke
				(width 0.1)
				(type default)
			)
			(layer "F.SilkS")
		)
		(fp_line
			(start 20.769072 -5.171694)
			(end 20.793202 -5.171694)
			(stroke
				(width 0.1)
				(type default)
			)
			(layer "F.SilkS")
		)
		(fp_line
			(start 20.769072 -5.171694)
			(end 20.793202 -5.171694)
			(stroke
				(width 0.1)
				(type default)
			)
			(layer "F.SilkS")
		)
		(fp_line
			(start 20.776184 -5.21335)
			(end 20.769072 -5.171694)
			(stroke
				(width 0.1)
				(type default)
			)
			(layer "F.SilkS")
		)
		(fp_line
			(start 20.776184 -5.21335)
			(end 20.769072 -5.171694)
			(stroke
				(width 0.1)
				(type default)
			)
			(layer "F.SilkS")
		)
		(fp_line
			(start 20.776184 -5.21335)
			(end 20.78863 -5.282692)
			(stroke
				(width 0.1)
				(type default)
			)
			(layer "F.SilkS")
		)
		(fp_line
			(start 20.776184 -5.21335)
			(end 20.78863 -5.282692)
			(stroke
				(width 0.1)
				(type default)
			)
			(layer "F.SilkS")
		)
		(fp_line
			(start 20.78863 -5.282692)
			(end 19.433032 -3.982466)
			(stroke
				(width 0.1)
				(type default)
			)
			(layer "F.SilkS")
		)
		(fp_line
			(start 20.78863 -5.282692)
			(end 19.433032 -3.982466)
			(stroke
				(width 0.1)
				(type default)
			)
			(layer "F.SilkS")
		)
		(fp_line
			(start 20.78863 -5.282692)
			(end 20.800822 -5.352034)
			(stroke
				(width 0.1)
				(type default)
			)
			(layer "F.SilkS")
		)
		(fp_line
			(start 20.78863 -5.282692)
			(end 20.800822 -5.352034)
			(stroke
				(width 0.1)
				(type default)
			)
			(layer "F.SilkS")
		)
		(fp_line
			(start 20.793202 -5.171694)
			(end 19.408902 -3.843528)
			(stroke
				(width 0.1)
				(type default)
			)
			(layer "F.SilkS")
		)
		(fp_line
			(start 20.793202 -5.171694)
			(end 19.408902 -3.843528)
			(stroke
				(width 0.1)
				(type default)
			)
			(layer "F.SilkS")
		)
		(fp_line
			(start 20.800822 -5.352034)
			(end 19.445478 -4.051554)
			(stroke
				(width 0.1)
				(type default)
			)
			(layer "F.SilkS")
		)
		(fp_line
			(start 20.800822 -5.352034)
			(end 19.445478 -4.051554)
			(stroke
				(width 0.1)
				(type default)
			)
			(layer "F.SilkS")
		)
		(fp_line
			(start 20.800822 -5.352034)
			(end 20.81276 -5.421376)
			(stroke
				(width 0.1)
				(type default)
			)
			(layer "F.SilkS")
		)
		(fp_line
			(start 20.800822 -5.352034)
			(end 20.81276 -5.421376)
			(stroke
				(width 0.1)
				(type default)
			)
			(layer "F.SilkS")
		)
		(fp_line
			(start 20.81276 -5.421376)
			(end 20.825206 -5.490972)
			(stroke
				(width 0.1)
				(type default)
			)
			(layer "F.SilkS")
		)
		(fp_line
			(start 20.81276 -5.421376)
			(end 20.825206 -5.490972)
			(stroke
				(width 0.1)
				(type default)
			)
			(layer "F.SilkS")
		)
		(fp_line
			(start 20.825206 -5.490972)
			(end 20.837144 -5.560314)
			(stroke
				(width 0.1)
				(type default)
			)
			(layer "F.SilkS")
		)
		(fp_line
			(start 20.825206 -5.490972)
			(end 20.837144 -5.560314)
			(stroke
				(width 0.1)
				(type default)
			)
			(layer "F.SilkS")
		)
		(fp_line
			(start 20.829016 -4.109466)
			(end 20.768564 -4.109466)
			(stroke
				(width 0.1)
				(type default)
			)
			(layer "F.SilkS")
		)
		(fp_line
			(start 20.829016 -4.109466)
			(end 20.768564 -4.109466)
			(stroke
				(width 0.1)
				(type default)
			)
			(layer "F.SilkS")
		)
		(fp_line
			(start 20.831302 -0.995426)
			(end 20.956524 -1.115314)
			(stroke
				(width 0.1)
				(type default)
			)
			(layer "F.SilkS")
		)
		(fp_line
			(start 20.831302 -0.995426)
			(end 20.956524 -1.115314)
			(stroke
				(width 0.1)
				(type default)
			)
			(layer "F.SilkS")
		)
		(fp_line
			(start 20.837144 -5.560314)
			(end 20.84959 -5.629656)
			(stroke
				(width 0.1)
				(type default)
			)
			(layer "F.SilkS")
		)
		(fp_line
			(start 20.837144 -5.560314)
			(end 20.84959 -5.629656)
			(stroke
				(width 0.1)
				(type default)
			)
			(layer "F.SilkS")
		)
		(fp_line
			(start 20.84959 -5.629656)
			(end 20.861782 -5.699252)
			(stroke
				(width 0.1)
				(type default)
			)
			(layer "F.SilkS")
		)
		(fp_line
			(start 20.84959 -5.629656)
			(end 20.861782 -5.699252)
			(stroke
				(width 0.1)
				(type default)
			)
			(layer "F.SilkS")
		)
		(fp_line
			(start 20.8534 -5.171694)
			(end 19.396456 -3.774186)
			(stroke
				(width 0.1)
				(type default)
			)
			(layer "F.SilkS")
		)
		(fp_line
			(start 20.8534 -5.171694)
			(end 19.396456 -3.774186)
			(stroke
				(width 0.1)
				(type default)
			)
			(layer "F.SilkS")
		)
		(fp_line
			(start 20.8534 -5.171694)
			(end 20.793202 -5.171694)
			(stroke
				(width 0.1)
				(type default)
			)
			(layer "F.SilkS")
		)
		(fp_line
			(start 20.8534 -5.171694)
			(end 20.793202 -5.171694)
			(stroke
				(width 0.1)
				(type default)
			)
			(layer "F.SilkS")
		)
		(fp_line
			(start 20.861782 -5.699252)
			(end 20.874228 -5.768594)
			(stroke
				(width 0.1)
				(type default)
			)
			(layer "F.SilkS")
		)
		(fp_line
			(start 20.861782 -5.699252)
			(end 20.874228 -5.768594)
			(stroke
				(width 0.1)
				(type default)
			)
			(layer "F.SilkS")
		)
		(fp_line
			(start 20.874228 -5.768594)
			(end 20.886166 -5.837936)
			(stroke
				(width 0.1)
				(type default)
			)
			(layer "F.SilkS")
		)
		(fp_line
			(start 20.874228 -5.768594)
			(end 20.886166 -5.837936)
			(stroke
				(width 0.1)
				(type default)
			)
			(layer "F.SilkS")
		)
		(fp_line
			(start 20.877784 -6.753606)
			(end 19.725132 -5.647436)
			(stroke
				(width 0.1)
				(type default)
			)
			(layer "F.SilkS")
		)
		(fp_line
			(start 20.877784 -6.753606)
			(end 19.725132 -5.647436)
			(stroke
				(width 0.1)
				(type default)
			)
			(layer "F.SilkS")
		)
		(fp_line
			(start 20.877784 -6.753606)
			(end 20.762722 -6.70052)
			(stroke
				(width 0.1)
				(type default)
			)
			(layer "F.SilkS")
		)
		(fp_line
			(start 20.877784 -6.753606)
			(end 20.762722 -6.70052)
			(stroke
				(width 0.1)
				(type default)
			)
			(layer "F.SilkS")
		)
		(fp_line
			(start 20.886166 -5.837936)
			(end 20.898104 -5.907278)
			(stroke
				(width 0.1)
				(type default)
			)
			(layer "F.SilkS")
		)
		(fp_line
			(start 20.886166 -5.837936)
			(end 20.898104 -5.907278)
			(stroke
				(width 0.1)
				(type default)
			)
			(layer "F.SilkS")
		)
		(fp_line
			(start 20.889214 -4.109466)
			(end 20.829016 -4.109466)
			(stroke
				(width 0.1)
				(type default)
			)
			(layer "F.SilkS")
		)
		(fp_line
			(start 20.889214 -4.109466)
			(end 20.829016 -4.109466)
			(stroke
				(width 0.1)
				(type default)
			)
			(layer "F.SilkS")
		)
		(fp_line
			(start 20.898104 -5.907278)
			(end 20.91055 -5.976874)
			(stroke
				(width 0.1)
				(type default)
			)
			(layer "F.SilkS")
		)
		(fp_line
			(start 20.898104 -5.907278)
			(end 20.91055 -5.976874)
			(stroke
				(width 0.1)
				(type default)
			)
			(layer "F.SilkS")
		)
		(fp_line
			(start 20.91055 -5.976874)
			(end 20.922742 -6.04647)
			(stroke
				(width 0.1)
				(type default)
			)
			(layer "F.SilkS")
		)
		(fp_line
			(start 20.91055 -5.976874)
			(end 20.922742 -6.04647)
			(stroke
				(width 0.1)
				(type default)
			)
			(layer "F.SilkS")
		)
		(fp_line
			(start 20.913344 -5.171694)
			(end 19.384518 -3.704844)
			(stroke
				(width 0.1)
				(type default)
			)
			(layer "F.SilkS")
		)
		(fp_line
			(start 20.913344 -5.171694)
			(end 19.384518 -3.704844)
			(stroke
				(width 0.1)
				(type default)
			)
			(layer "F.SilkS")
		)
		(fp_line
			(start 20.913344 -5.171694)
			(end 20.8534 -5.171694)
			(stroke
				(width 0.1)
				(type default)
			)
			(layer "F.SilkS")
		)
		(fp_line
			(start 20.913344 -5.171694)
			(end 20.8534 -5.171694)
			(stroke
				(width 0.1)
				(type default)
			)
			(layer "F.SilkS")
		)
		(fp_line
			(start 20.922742 -6.04647)
			(end 20.93468 -6.115558)
			(stroke
				(width 0.1)
				(type default)
			)
			(layer "F.SilkS")
		)
		(fp_line
			(start 20.922742 -6.04647)
			(end 20.93468 -6.115558)
			(stroke
				(width 0.1)
				(type default)
			)
			(layer "F.SilkS")
		)
		(fp_line
			(start 20.93468 -6.115558)
			(end 20.947126 -6.1849)
			(stroke
				(width 0.1)
				(type default)
			)
			(layer "F.SilkS")
		)
		(fp_line
			(start 20.93468 -6.115558)
			(end 20.947126 -6.1849)
			(stroke
				(width 0.1)
				(type default)
			)
			(layer "F.SilkS")
		)
		(fp_line
			(start 20.947126 -6.1849)
			(end 20.959318 -6.254496)
			(stroke
				(width 0.1)
				(type default)
			)
			(layer "F.SilkS")
		)
		(fp_line
			(start 20.947126 -6.1849)
			(end 20.959318 -6.254496)
			(stroke
				(width 0.1)
				(type default)
			)
			(layer "F.SilkS")
		)
		(fp_line
			(start 20.949666 -4.109466)
			(end 20.889214 -4.109466)
			(stroke
				(width 0.1)
				(type default)
			)
			(layer "F.SilkS")
		)
		(fp_line
			(start 20.949666 -4.109466)
			(end 20.889214 -4.109466)
			(stroke
				(width 0.1)
				(type default)
			)
			(layer "F.SilkS")
		)
		(fp_line
			(start 20.959318 -6.254496)
			(end 20.97151 -6.324092)
			(stroke
				(width 0.1)
				(type default)
			)
			(layer "F.SilkS")
		)
		(fp_line
			(start 20.959318 -6.254496)
			(end 20.97151 -6.324092)
			(stroke
				(width 0.1)
				(type default)
			)
			(layer "F.SilkS")
		)
		(fp_line
			(start 20.97151 -6.324092)
			(end 18.75155 -4.194556)
			(stroke
				(width 0.1)
				(type default)
			)
			(layer "F.SilkS")
		)
		(fp_line
			(start 20.97151 -6.324092)
			(end 18.75155 -4.194556)
			(stroke
				(width 0.1)
				(type default)
			)
			(layer "F.SilkS")
		)
		(fp_line
			(start 20.97151 -6.324092)
			(end 20.983702 -6.393434)
			(stroke
				(width 0.1)
				(type default)
			)
			(layer "F.SilkS")
		)
		(fp_line
			(start 20.97151 -6.324092)
			(end 20.983702 -6.393434)
			(stroke
				(width 0.1)
				(type default)
			)
			(layer "F.SilkS")
		)
		(fp_line
			(start 20.973542 -5.171694)
			(end 19.372326 -3.635502)
			(stroke
				(width 0.1)
				(type default)
			)
			(layer "F.SilkS")
		)
		(fp_line
			(start 20.973542 -5.171694)
			(end 19.372326 -3.635502)
			(stroke
				(width 0.1)
				(type default)
			)
			(layer "F.SilkS")
		)
		(fp_line
			(start 20.973542 -5.171694)
			(end 20.913344 -5.171694)
			(stroke
				(width 0.1)
				(type default)
			)
			(layer "F.SilkS")
		)
		(fp_line
			(start 20.973542 -5.171694)
			(end 20.913344 -5.171694)
			(stroke
				(width 0.1)
				(type default)
			)
			(layer "F.SilkS")
		)
		(fp_line
			(start 20.98294 -1.198626)
			(end 20.956524 -1.115314)
			(stroke
				(width 0.1)
				(type default)
			)
			(layer "F.SilkS")
		)
		(fp_line
			(start 20.98294 -1.198626)
			(end 20.956524 -1.115314)
			(stroke
				(width 0.1)
				(type default)
			)
			(layer "F.SilkS")
		)
		(fp_line
			(start 20.983702 -6.393434)
			(end 18.763996 -4.263898)
			(stroke
				(width 0.1)
				(type default)
			)
			(layer "F.SilkS")
		)
		(fp_line
			(start 20.983702 -6.393434)
			(end 18.763996 -4.263898)
			(stroke
				(width 0.1)
				(type default)
			)
			(layer "F.SilkS")
		)
		(fp_line
			(start 20.983702 -6.393434)
			(end 20.996148 -6.462522)
			(stroke
				(width 0.1)
				(type default)
			)
			(layer "F.SilkS")
		)
		(fp_line
			(start 20.983702 -6.393434)
			(end 20.996148 -6.462522)
			(stroke
				(width 0.1)
				(type default)
			)
			(layer "F.SilkS")
		)
		(fp_line
			(start 20.993354 -6.806438)
			(end 19.712686 -5.578094)
			(stroke
				(width 0.1)
				(type default)
			)
			(layer "F.SilkS")
		)
		(fp_line
			(start 20.993354 -6.806438)
			(end 19.712686 -5.578094)
			(stroke
				(width 0.1)
				(type default)
			)
			(layer "F.SilkS")
		)
		(fp_line
			(start 20.993354 -6.806438)
			(end 20.877784 -6.753606)
			(stroke
				(width 0.1)
				(type default)
			)
			(layer "F.SilkS")
		)
		(fp_line
			(start 20.993354 -6.806438)
			(end 20.877784 -6.753606)
			(stroke
				(width 0.1)
				(type default)
			)
			(layer "F.SilkS")
		)
		(fp_line
			(start 20.996148 -6.462522)
			(end 18.775934 -4.33324)
			(stroke
				(width 0.1)
				(type default)
			)
			(layer "F.SilkS")
		)
		(fp_line
			(start 20.996148 -6.462522)
			(end 18.775934 -4.33324)
			(stroke
				(width 0.1)
				(type default)
			)
			(layer "F.SilkS")
		)
		(fp_line
			(start 20.996148 -6.462522)
			(end 21.008086 -6.532118)
			(stroke
				(width 0.1)
				(type default)
			)
			(layer "F.SilkS")
		)
		(fp_line
			(start 20.996148 -6.462522)
			(end 21.008086 -6.532118)
			(stroke
				(width 0.1)
				(type default)
			)
			(layer "F.SilkS")
		)
		(fp_line
			(start 21.008086 -6.532118)
			(end 19.651726 -5.23113)
			(stroke
				(width 0.1)
				(type default)
			)
			(layer "F.SilkS")
		)
		(fp_line
			(start 21.008086 -6.532118)
			(end 19.651726 -5.23113)
			(stroke
				(width 0.1)
				(type default)
			)
			(layer "F.SilkS")
		)
		(fp_line
			(start 21.008086 -6.532118)
			(end 21.020278 -6.60146)
			(stroke
				(width 0.1)
				(type default)
			)
			(layer "F.SilkS")
		)
		(fp_line
			(start 21.008086 -6.532118)
			(end 21.020278 -6.60146)
			(stroke
				(width 0.1)
				(type default)
			)
			(layer "F.SilkS")
		)
		(fp_line
			(start 21.00961 -4.109466)
			(end 20.949666 -4.109466)
			(stroke
				(width 0.1)
				(type default)
			)
			(layer "F.SilkS")
		)
		(fp_line
			(start 21.00961 -4.109466)
			(end 20.949666 -4.109466)
			(stroke
				(width 0.1)
				(type default)
			)
			(layer "F.SilkS")
		)
		(fp_line
			(start 21.00961 -4.109466)
			(end 21.069554 -4.109466)
			(stroke
				(width 0.1)
				(type default)
			)
			(layer "F.SilkS")
		)
		(fp_line
			(start 21.00961 -4.109466)
			(end 21.069554 -4.109466)
			(stroke
				(width 0.1)
				(type default)
			)
			(layer "F.SilkS")
		)
		(fp_line
			(start 21.00961 -1.281684)
			(end 20.98294 -1.198626)
			(stroke
				(width 0.1)
				(type default)
			)
			(layer "F.SilkS")
		)
		(fp_line
			(start 21.00961 -1.281684)
			(end 20.98294 -1.198626)
			(stroke
				(width 0.1)
				(type default)
			)
			(layer "F.SilkS")
		)
		(fp_line
			(start 21.020278 -6.60146)
			(end 19.664172 -5.300472)
			(stroke
				(width 0.1)
				(type default)
			)
			(layer "F.SilkS")
		)
		(fp_line
			(start 21.020278 -6.60146)
			(end 19.664172 -5.300472)
			(stroke
				(width 0.1)
				(type default)
			)
			(layer "F.SilkS")
		)
		(fp_line
			(start 21.020278 -6.60146)
			(end 21.03247 -6.671056)
			(stroke
				(width 0.1)
				(type default)
			)
			(layer "F.SilkS")
		)
		(fp_line
			(start 21.020278 -6.60146)
			(end 21.03247 -6.671056)
			(stroke
				(width 0.1)
				(type default)
			)
			(layer "F.SilkS")
		)
		(fp_line
			(start 21.03247 -6.671056)
			(end 19.676364 -5.370068)
			(stroke
				(width 0.1)
				(type default)
			)
			(layer "F.SilkS")
		)
		(fp_line
			(start 21.03247 -6.671056)
			(end 19.676364 -5.370068)
			(stroke
				(width 0.1)
				(type default)
			)
			(layer "F.SilkS")
		)
		(fp_line
			(start 21.03247 -6.671056)
			(end 21.044662 -6.740144)
			(stroke
				(width 0.1)
				(type default)
			)
			(layer "F.SilkS")
		)
		(fp_line
			(start 21.03247 -6.671056)
			(end 21.044662 -6.740144)
			(stroke
				(width 0.1)
				(type default)
			)
			(layer "F.SilkS")
		)
		(fp_line
			(start 21.033994 -5.171694)
			(end 19.35988 -3.56616)
			(stroke
				(width 0.1)
				(type default)
			)
			(layer "F.SilkS")
		)
		(fp_line
			(start 21.033994 -5.171694)
			(end 19.35988 -3.56616)
			(stroke
				(width 0.1)
				(type default)
			)
			(layer "F.SilkS")
		)
		(fp_line
			(start 21.033994 -5.171694)
			(end 20.973542 -5.171694)
			(stroke
				(width 0.1)
				(type default)
			)
			(layer "F.SilkS")
		)
		(fp_line
			(start 21.033994 -5.171694)
			(end 20.973542 -5.171694)
			(stroke
				(width 0.1)
				(type default)
			)
			(layer "F.SilkS")
		)
		(fp_line
			(start 21.035772 -1.364742)
			(end 21.00961 -1.281684)
			(stroke
				(width 0.1)
				(type default)
			)
			(layer "F.SilkS")
		)
		(fp_line
			(start 21.035772 -1.364742)
			(end 21.00961 -1.281684)
			(stroke
				(width 0.1)
				(type default)
			)
			(layer "F.SilkS")
		)
		(fp_line
			(start 21.044662 -6.740144)
			(end 19.688302 -5.439156)
			(stroke
				(width 0.1)
				(type default)
			)
			(layer "F.SilkS")
		)
		(fp_line
			(start 21.044662 -6.740144)
			(end 19.688302 -5.439156)
			(stroke
				(width 0.1)
				(type default)
			)
			(layer "F.SilkS")
		)
		(fp_line
			(start 21.044662 -6.740144)
			(end 21.057108 -6.80974)
			(stroke
				(width 0.1)
				(type default)
			)
			(layer "F.SilkS")
		)
		(fp_line
			(start 21.044662 -6.740144)
			(end 21.057108 -6.80974)
			(stroke
				(width 0.1)
				(type default)
			)
			(layer "F.SilkS")
		)
		(fp_line
			(start 21.057108 -6.80974)
			(end 19.700748 -5.508752)
			(stroke
				(width 0.1)
				(type default)
			)
			(layer "F.SilkS")
		)
		(fp_line
			(start 21.057108 -6.80974)
			(end 19.700748 -5.508752)
			(stroke
				(width 0.1)
				(type default)
			)
			(layer "F.SilkS")
		)
		(fp_line
			(start 21.057108 -6.80974)
			(end 21.061934 -6.838188)
			(stroke
				(width 0.1)
				(type default)
			)
			(layer "F.SilkS")
		)
		(fp_line
			(start 21.057108 -6.80974)
			(end 21.061934 -6.838188)
			(stroke
				(width 0.1)
				(type default)
			)
			(layer "F.SilkS")
		)
		(fp_line
			(start 21.061934 -6.838188)
			(end 20.993354 -6.806438)
			(stroke
				(width 0.1)
				(type default)
			)
			(layer "F.SilkS")
		)
		(fp_line
			(start 21.061934 -6.838188)
			(end 20.993354 -6.806438)
			(stroke
				(width 0.1)
				(type default)
			)
			(layer "F.SilkS")
		)
		(fp_line
			(start 21.062188 -1.447546)
			(end 21.035772 -1.364742)
			(stroke
				(width 0.1)
				(type default)
			)
			(layer "F.SilkS")
		)
		(fp_line
			(start 21.062188 -1.447546)
			(end 21.035772 -1.364742)
			(stroke
				(width 0.1)
				(type default)
			)
			(layer "F.SilkS")
		)
		(fp_line
			(start 21.069554 -4.109466)
			(end 21.129752 -4.109466)
			(stroke
				(width 0.1)
				(type default)
			)
			(layer "F.SilkS")
		)
		(fp_line
			(start 21.069554 -4.109466)
			(end 21.129752 -4.109466)
			(stroke
				(width 0.1)
				(type default)
			)
			(layer "F.SilkS")
		)
		(fp_line
			(start 21.088858 -1.530604)
			(end 21.062188 -1.447546)
			(stroke
				(width 0.1)
				(type default)
			)
			(layer "F.SilkS")
		)
		(fp_line
			(start 21.088858 -1.530604)
			(end 21.062188 -1.447546)
			(stroke
				(width 0.1)
				(type default)
			)
			(layer "F.SilkS")
		)
		(fp_line
			(start 21.093938 -5.171694)
			(end 19.347942 -3.496564)
			(stroke
				(width 0.1)
				(type default)
			)
			(layer "F.SilkS")
		)
		(fp_line
			(start 21.093938 -5.171694)
			(end 19.347942 -3.496564)
			(stroke
				(width 0.1)
				(type default)
			)
			(layer "F.SilkS")
		)
		(fp_line
			(start 21.093938 -5.171694)
			(end 21.033994 -5.171694)
			(stroke
				(width 0.1)
				(type default)
			)
			(layer "F.SilkS")
		)
		(fp_line
			(start 21.093938 -5.171694)
			(end 21.033994 -5.171694)
			(stroke
				(width 0.1)
				(type default)
			)
			(layer "F.SilkS")
		)
		(fp_line
			(start 21.115274 -1.613916)
			(end 21.088858 -1.530604)
			(stroke
				(width 0.1)
				(type default)
			)
			(layer "F.SilkS")
		)
		(fp_line
			(start 21.115274 -1.613916)
			(end 21.088858 -1.530604)
			(stroke
				(width 0.1)
				(type default)
			)
			(layer "F.SilkS")
		)
		(fp_line
			(start 21.129752 -4.109466)
			(end 21.18995 -4.109466)
			(stroke
				(width 0.1)
				(type default)
			)
			(layer "F.SilkS")
		)
		(fp_line
			(start 21.129752 -4.109466)
			(end 21.18995 -4.109466)
			(stroke
				(width 0.1)
				(type default)
			)
			(layer "F.SilkS")
		)
		(fp_line
			(start 21.141436 -1.69672)
			(end 21.115274 -1.613916)
			(stroke
				(width 0.1)
				(type default)
			)
			(layer "F.SilkS")
		)
		(fp_line
			(start 21.141436 -1.69672)
			(end 21.115274 -1.613916)
			(stroke
				(width 0.1)
				(type default)
			)
			(layer "F.SilkS")
		)
		(fp_line
			(start 21.154136 -5.171694)
			(end 19.33575 -3.427476)
			(stroke
				(width 0.1)
				(type default)
			)
			(layer "F.SilkS")
		)
		(fp_line
			(start 21.154136 -5.171694)
			(end 19.33575 -3.427476)
			(stroke
				(width 0.1)
				(type default)
			)
			(layer "F.SilkS")
		)
		(fp_line
			(start 21.154136 -5.171694)
			(end 21.093938 -5.171694)
			(stroke
				(width 0.1)
				(type default)
			)
			(layer "F.SilkS")
		)
		(fp_line
			(start 21.154136 -5.171694)
			(end 21.093938 -5.171694)
			(stroke
				(width 0.1)
				(type default)
			)
			(layer "F.SilkS")
		)
		(fp_line
			(start 21.167852 -1.779778)
			(end 21.141436 -1.69672)
			(stroke
				(width 0.1)
				(type default)
			)
			(layer "F.SilkS")
		)
		(fp_line
			(start 21.167852 -1.779778)
			(end 21.141436 -1.69672)
			(stroke
				(width 0.1)
				(type default)
			)
			(layer "F.SilkS")
		)
		(fp_line
			(start 21.18995 -4.109466)
			(end 21.250402 -4.109466)
			(stroke
				(width 0.1)
				(type default)
			)
			(layer "F.SilkS")
		)
		(fp_line
			(start 21.18995 -4.109466)
			(end 21.250402 -4.109466)
			(stroke
				(width 0.1)
				(type default)
			)
			(layer "F.SilkS")
		)
		(fp_line
			(start 21.194268 -1.862836)
			(end 21.167852 -1.779778)
			(stroke
				(width 0.1)
				(type default)
			)
			(layer "F.SilkS")
		)
		(fp_line
			(start 21.194268 -1.862836)
			(end 21.167852 -1.779778)
			(stroke
				(width 0.1)
				(type default)
			)
			(layer "F.SilkS")
		)
		(fp_line
			(start 21.21408 -5.171694)
			(end 19.323558 -3.358134)
			(stroke
				(width 0.1)
				(type default)
			)
			(layer "F.SilkS")
		)
		(fp_line
			(start 21.21408 -5.171694)
			(end 19.323558 -3.358134)
			(stroke
				(width 0.1)
				(type default)
			)
			(layer "F.SilkS")
		)
		(fp_line
			(start 21.21408 -5.171694)
			(end 21.154136 -5.171694)
			(stroke
				(width 0.1)
				(type default)
			)
			(layer "F.SilkS")
		)
		(fp_line
			(start 21.21408 -5.171694)
			(end 21.154136 -5.171694)
			(stroke
				(width 0.1)
				(type default)
			)
			(layer "F.SilkS")
		)
		(fp_line
			(start 21.220684 -1.946148)
			(end 21.194268 -1.862836)
			(stroke
				(width 0.1)
				(type default)
			)
			(layer "F.SilkS")
		)
		(fp_line
			(start 21.220684 -1.946148)
			(end 21.194268 -1.862836)
			(stroke
				(width 0.1)
				(type default)
			)
			(layer "F.SilkS")
		)
		(fp_line
			(start 21.2471 -2.028952)
			(end 21.220684 -1.946148)
			(stroke
				(width 0.1)
				(type default)
			)
			(layer "F.SilkS")
		)
		(fp_line
			(start 21.2471 -2.028952)
			(end 21.220684 -1.946148)
			(stroke
				(width 0.1)
				(type default)
			)
			(layer "F.SilkS")
		)
		(fp_line
			(start 21.250402 -4.109466)
			(end 21.310346 -4.109466)
			(stroke
				(width 0.1)
				(type default)
			)
			(layer "F.SilkS")
		)
		(fp_line
			(start 21.250402 -4.109466)
			(end 21.310346 -4.109466)
			(stroke
				(width 0.1)
				(type default)
			)
			(layer "F.SilkS")
		)
		(fp_line
			(start 21.273516 -2.11201)
			(end 21.2471 -2.028952)
			(stroke
				(width 0.1)
				(type default)
			)
			(layer "F.SilkS")
		)
		(fp_line
			(start 21.273516 -2.11201)
			(end 21.2471 -2.028952)
			(stroke
				(width 0.1)
				(type default)
			)
			(layer "F.SilkS")
		)
		(fp_line
			(start 21.274532 -5.171694)
			(end 19.311366 -3.288538)
			(stroke
				(width 0.1)
				(type default)
			)
			(layer "F.SilkS")
		)
		(fp_line
			(start 21.274532 -5.171694)
			(end 19.311366 -3.288538)
			(stroke
				(width 0.1)
				(type default)
			)
			(layer "F.SilkS")
		)
		(fp_line
			(start 21.274532 -5.171694)
			(end 21.21408 -5.171694)
			(stroke
				(width 0.1)
				(type default)
			)
			(layer "F.SilkS")
		)
		(fp_line
			(start 21.274532 -5.171694)
			(end 21.21408 -5.171694)
			(stroke
				(width 0.1)
				(type default)
			)
			(layer "F.SilkS")
		)
		(fp_line
			(start 21.299932 -2.195068)
			(end 21.273516 -2.11201)
			(stroke
				(width 0.1)
				(type default)
			)
			(layer "F.SilkS")
		)
		(fp_line
			(start 21.299932 -2.195068)
			(end 21.273516 -2.11201)
			(stroke
				(width 0.1)
				(type default)
			)
			(layer "F.SilkS")
		)
		(fp_line
			(start 21.310346 -4.109466)
			(end 21.370544 -4.109466)
			(stroke
				(width 0.1)
				(type default)
			)
			(layer "F.SilkS")
		)
		(fp_line
			(start 21.310346 -4.109466)
			(end 21.370544 -4.109466)
			(stroke
				(width 0.1)
				(type default)
			)
			(layer "F.SilkS")
		)
		(fp_line
			(start 21.33473 -5.171694)
			(end 19.299428 -3.218942)
			(stroke
				(width 0.1)
				(type default)
			)
			(layer "F.SilkS")
		)
		(fp_line
			(start 21.33473 -5.171694)
			(end 19.299428 -3.218942)
			(stroke
				(width 0.1)
				(type default)
			)
			(layer "F.SilkS")
		)
		(fp_line
			(start 21.33473 -5.171694)
			(end 21.274532 -5.171694)
			(stroke
				(width 0.1)
				(type default)
			)
			(layer "F.SilkS")
		)
		(fp_line
			(start 21.33473 -5.171694)
			(end 21.274532 -5.171694)
			(stroke
				(width 0.1)
				(type default)
			)
			(layer "F.SilkS")
		)
		(fp_line
			(start 21.370544 -4.109466)
			(end 21.430742 -4.109466)
			(stroke
				(width 0.1)
				(type default)
			)
			(layer "F.SilkS")
		)
		(fp_line
			(start 21.370544 -4.109466)
			(end 21.430742 -4.109466)
			(stroke
				(width 0.1)
				(type default)
			)
			(layer "F.SilkS")
		)
		(fp_line
			(start 21.394674 -5.171694)
			(end 19.286982 -3.149854)
			(stroke
				(width 0.1)
				(type default)
			)
			(layer "F.SilkS")
		)
		(fp_line
			(start 21.394674 -5.171694)
			(end 19.286982 -3.149854)
			(stroke
				(width 0.1)
				(type default)
			)
			(layer "F.SilkS")
		)
		(fp_line
			(start 21.394674 -5.171694)
			(end 21.33473 -5.171694)
			(stroke
				(width 0.1)
				(type default)
			)
			(layer "F.SilkS")
		)
		(fp_line
			(start 21.394674 -5.171694)
			(end 21.33473 -5.171694)
			(stroke
				(width 0.1)
				(type default)
			)
			(layer "F.SilkS")
		)
		(fp_line
			(start 21.430742 -4.109466)
			(end 21.490686 -4.109466)
			(stroke
				(width 0.1)
				(type default)
			)
			(layer "F.SilkS")
		)
		(fp_line
			(start 21.430742 -4.109466)
			(end 21.490686 -4.109466)
			(stroke
				(width 0.1)
				(type default)
			)
			(layer "F.SilkS")
		)
		(fp_line
			(start 21.454872 -5.171694)
			(end 19.27479 -3.080512)
			(stroke
				(width 0.1)
				(type default)
			)
			(layer "F.SilkS")
		)
		(fp_line
			(start 21.454872 -5.171694)
			(end 19.27479 -3.080512)
			(stroke
				(width 0.1)
				(type default)
			)
			(layer "F.SilkS")
		)
		(fp_line
			(start 21.454872 -5.171694)
			(end 21.394674 -5.171694)
			(stroke
				(width 0.1)
				(type default)
			)
			(layer "F.SilkS")
		)
		(fp_line
			(start 21.454872 -5.171694)
			(end 21.394674 -5.171694)
			(stroke
				(width 0.1)
				(type default)
			)
			(layer "F.SilkS")
		)
		(fp_line
			(start 21.490686 -4.109466)
			(end 21.55063 -4.109466)
			(stroke
				(width 0.1)
				(type default)
			)
			(layer "F.SilkS")
		)
		(fp_line
			(start 21.490686 -4.109466)
			(end 21.55063 -4.109466)
			(stroke
				(width 0.1)
				(type default)
			)
			(layer "F.SilkS")
		)
		(fp_line
			(start 21.515324 -5.171694)
			(end 19.262852 -3.01117)
			(stroke
				(width 0.1)
				(type default)
			)
			(layer "F.SilkS")
		)
		(fp_line
			(start 21.515324 -5.171694)
			(end 19.262852 -3.01117)
			(stroke
				(width 0.1)
				(type default)
			)
			(layer "F.SilkS")
		)
		(fp_line
			(start 21.515324 -5.171694)
			(end 21.454872 -5.171694)
			(stroke
				(width 0.1)
				(type default)
			)
			(layer "F.SilkS")
		)
		(fp_line
			(start 21.515324 -5.171694)
			(end 21.454872 -5.171694)
			(stroke
				(width 0.1)
				(type default)
			)
			(layer "F.SilkS")
		)
		(fp_line
			(start 21.55063 -4.109466)
			(end 21.611082 -4.109466)
			(stroke
				(width 0.1)
				(type default)
			)
			(layer "F.SilkS")
		)
		(fp_line
			(start 21.55063 -4.109466)
			(end 21.611082 -4.109466)
			(stroke
				(width 0.1)
				(type default)
			)
			(layer "F.SilkS")
		)
		(fp_line
			(start 21.575522 -5.171694)
			(end 19.250406 -2.941574)
			(stroke
				(width 0.1)
				(type default)
			)
			(layer "F.SilkS")
		)
		(fp_line
			(start 21.575522 -5.171694)
			(end 19.250406 -2.941574)
			(stroke
				(width 0.1)
				(type default)
			)
			(layer "F.SilkS")
		)
		(fp_line
			(start 21.575522 -5.171694)
			(end 21.515324 -5.171694)
			(stroke
				(width 0.1)
				(type default)
			)
			(layer "F.SilkS")
		)
		(fp_line
			(start 21.575522 -5.171694)
			(end 21.515324 -5.171694)
			(stroke
				(width 0.1)
				(type default)
			)
			(layer "F.SilkS")
		)
		(fp_line
			(start 21.612352 -4.109466)
			(end 21.611082 -4.109466)
			(stroke
				(width 0.1)
				(type default)
			)
			(layer "F.SilkS")
		)
		(fp_line
			(start 21.612352 -4.109466)
			(end 21.611082 -4.109466)
			(stroke
				(width 0.1)
				(type default)
			)
			(layer "F.SilkS")
		)
		(fp_line
			(start 21.61286 -4.11099)
			(end 21.611082 -4.109466)
			(stroke
				(width 0.1)
				(type default)
			)
			(layer "F.SilkS")
		)
		(fp_line
			(start 21.61286 -4.11099)
			(end 21.611082 -4.109466)
			(stroke
				(width 0.1)
				(type default)
			)
			(layer "F.SilkS")
		)
		(fp_line
			(start 21.61286 -4.11099)
			(end 21.612352 -4.109466)
			(stroke
				(width 0.1)
				(type default)
			)
			(layer "F.SilkS")
		)
		(fp_line
			(start 21.61286 -4.11099)
			(end 21.612352 -4.109466)
			(stroke
				(width 0.1)
				(type default)
			)
			(layer "F.SilkS")
		)
		(fp_line
			(start 21.61286 -4.11099)
			(end 21.624798 -4.180586)
			(stroke
				(width 0.1)
				(type default)
			)
			(layer "F.SilkS")
		)
		(fp_line
			(start 21.61286 -4.11099)
			(end 21.624798 -4.180586)
			(stroke
				(width 0.1)
				(type default)
			)
			(layer "F.SilkS")
		)
		(fp_line
			(start 21.624798 -4.180586)
			(end 21.55063 -4.109466)
			(stroke
				(width 0.1)
				(type default)
			)
			(layer "F.SilkS")
		)
		(fp_line
			(start 21.624798 -4.180586)
			(end 21.55063 -4.109466)
			(stroke
				(width 0.1)
				(type default)
			)
			(layer "F.SilkS")
		)
		(fp_line
			(start 21.624798 -4.180586)
			(end 21.636736 -4.249674)
			(stroke
				(width 0.1)
				(type default)
			)
			(layer "F.SilkS")
		)
		(fp_line
			(start 21.624798 -4.180586)
			(end 21.636736 -4.249674)
			(stroke
				(width 0.1)
				(type default)
			)
			(layer "F.SilkS")
		)
		(fp_line
			(start 21.635466 -5.171694)
			(end 21.575522 -5.171694)
			(stroke
				(width 0.1)
				(type default)
			)
			(layer "F.SilkS")
		)
		(fp_line
			(start 21.635466 -5.171694)
			(end 21.575522 -5.171694)
			(stroke
				(width 0.1)
				(type default)
			)
			(layer "F.SilkS")
		)
		(fp_line
			(start 21.636736 -4.249674)
			(end 21.490686 -4.109466)
			(stroke
				(width 0.1)
				(type default)
			)
			(layer "F.SilkS")
		)
		(fp_line
			(start 21.636736 -4.249674)
			(end 21.490686 -4.109466)
			(stroke
				(width 0.1)
				(type default)
			)
			(layer "F.SilkS")
		)
		(fp_line
			(start 21.636736 -4.249674)
			(end 21.649182 -4.319016)
			(stroke
				(width 0.1)
				(type default)
			)
			(layer "F.SilkS")
		)
		(fp_line
			(start 21.636736 -4.249674)
			(end 21.649182 -4.319016)
			(stroke
				(width 0.1)
				(type default)
			)
			(layer "F.SilkS")
		)
		(fp_line
			(start 21.649182 -4.319016)
			(end 21.430742 -4.109466)
			(stroke
				(width 0.1)
				(type default)
			)
			(layer "F.SilkS")
		)
		(fp_line
			(start 21.649182 -4.319016)
			(end 21.430742 -4.109466)
			(stroke
				(width 0.1)
				(type default)
			)
			(layer "F.SilkS")
		)
		(fp_line
			(start 21.649182 -4.319016)
			(end 21.661374 -4.388358)
			(stroke
				(width 0.1)
				(type default)
			)
			(layer "F.SilkS")
		)
		(fp_line
			(start 21.649182 -4.319016)
			(end 21.661374 -4.388358)
			(stroke
				(width 0.1)
				(type default)
			)
			(layer "F.SilkS")
		)
		(fp_line
			(start 21.661374 -4.388358)
			(end 21.370544 -4.109466)
			(stroke
				(width 0.1)
				(type default)
			)
			(layer "F.SilkS")
		)
		(fp_line
			(start 21.661374 -4.388358)
			(end 21.370544 -4.109466)
			(stroke
				(width 0.1)
				(type default)
			)
			(layer "F.SilkS")
		)
		(fp_line
			(start 21.661374 -4.388358)
			(end 21.673312 -4.457954)
			(stroke
				(width 0.1)
				(type default)
			)
			(layer "F.SilkS")
		)
		(fp_line
			(start 21.661374 -4.388358)
			(end 21.673312 -4.457954)
			(stroke
				(width 0.1)
				(type default)
			)
			(layer "F.SilkS")
		)
		(fp_line
			(start 21.673312 -4.457954)
			(end 21.310346 -4.109466)
			(stroke
				(width 0.1)
				(type default)
			)
			(layer "F.SilkS")
		)
		(fp_line
			(start 21.673312 -4.457954)
			(end 21.310346 -4.109466)
			(stroke
				(width 0.1)
				(type default)
			)
			(layer "F.SilkS")
		)
		(fp_line
			(start 21.673312 -4.457954)
			(end 21.685504 -4.527296)
			(stroke
				(width 0.1)
				(type default)
			)
			(layer "F.SilkS")
		)
		(fp_line
			(start 21.673312 -4.457954)
			(end 21.685504 -4.527296)
			(stroke
				(width 0.1)
				(type default)
			)
			(layer "F.SilkS")
		)
		(fp_line
			(start 21.685504 -4.527296)
			(end 21.250402 -4.109466)
			(stroke
				(width 0.1)
				(type default)
			)
			(layer "F.SilkS")
		)
		(fp_line
			(start 21.685504 -4.527296)
			(end 21.250402 -4.109466)
			(stroke
				(width 0.1)
				(type default)
			)
			(layer "F.SilkS")
		)
		(fp_line
			(start 21.685504 -4.527296)
			(end 21.69795 -4.596638)
			(stroke
				(width 0.1)
				(type default)
			)
			(layer "F.SilkS")
		)
		(fp_line
			(start 21.685504 -4.527296)
			(end 21.69795 -4.596638)
			(stroke
				(width 0.1)
				(type default)
			)
			(layer "F.SilkS")
		)
		(fp_line
			(start 21.69541 -5.171694)
			(end 20.588224 -4.109466)
			(stroke
				(width 0.1)
				(type default)
			)
			(layer "F.SilkS")
		)
		(fp_line
			(start 21.69541 -5.171694)
			(end 20.588224 -4.109466)
			(stroke
				(width 0.1)
				(type default)
			)
			(layer "F.SilkS")
		)
		(fp_line
			(start 21.69541 -5.171694)
			(end 21.635466 -5.171694)
			(stroke
				(width 0.1)
				(type default)
			)
			(layer "F.SilkS")
		)
		(fp_line
			(start 21.69541 -5.171694)
			(end 21.635466 -5.171694)
			(stroke
				(width 0.1)
				(type default)
			)
			(layer "F.SilkS")
		)
		(fp_line
			(start 21.69795 -4.596638)
			(end 21.18995 -4.109466)
			(stroke
				(width 0.1)
				(type default)
			)
			(layer "F.SilkS")
		)
		(fp_line
			(start 21.69795 -4.596638)
			(end 21.18995 -4.109466)
			(stroke
				(width 0.1)
				(type default)
			)
			(layer "F.SilkS")
		)
		(fp_line
			(start 21.69795 -4.596638)
			(end 21.709888 -4.66598)
			(stroke
				(width 0.1)
				(type default)
			)
			(layer "F.SilkS")
		)
		(fp_line
			(start 21.69795 -4.596638)
			(end 21.709888 -4.66598)
			(stroke
				(width 0.1)
				(type default)
			)
			(layer "F.SilkS")
		)
		(fp_line
			(start 21.709888 -4.66598)
			(end 21.129752 -4.109466)
			(stroke
				(width 0.1)
				(type default)
			)
			(layer "F.SilkS")
		)
		(fp_line
			(start 21.709888 -4.66598)
			(end 21.129752 -4.109466)
			(stroke
				(width 0.1)
				(type default)
			)
			(layer "F.SilkS")
		)
		(fp_line
			(start 21.709888 -4.66598)
			(end 21.721826 -4.735576)
			(stroke
				(width 0.1)
				(type default)
			)
			(layer "F.SilkS")
		)
		(fp_line
			(start 21.709888 -4.66598)
			(end 21.721826 -4.735576)
			(stroke
				(width 0.1)
				(type default)
			)
			(layer "F.SilkS")
		)
		(fp_line
			(start 21.721826 -4.735576)
			(end 21.069554 -4.109466)
			(stroke
				(width 0.1)
				(type default)
			)
			(layer "F.SilkS")
		)
		(fp_line
			(start 21.721826 -4.735576)
			(end 21.069554 -4.109466)
			(stroke
				(width 0.1)
				(type default)
			)
			(layer "F.SilkS")
		)
		(fp_line
			(start 21.721826 -4.735576)
			(end 21.734018 -4.804664)
			(stroke
				(width 0.1)
				(type default)
			)
			(layer "F.SilkS")
		)
		(fp_line
			(start 21.721826 -4.735576)
			(end 21.734018 -4.804664)
			(stroke
				(width 0.1)
				(type default)
			)
			(layer "F.SilkS")
		)
		(fp_line
			(start 21.734018 -4.804664)
			(end 21.00961 -4.109466)
			(stroke
				(width 0.1)
				(type default)
			)
			(layer "F.SilkS")
		)
		(fp_line
			(start 21.734018 -4.804664)
			(end 21.00961 -4.109466)
			(stroke
				(width 0.1)
				(type default)
			)
			(layer "F.SilkS")
		)
		(fp_line
			(start 21.734018 -4.804664)
			(end 21.746464 -4.874006)
			(stroke
				(width 0.1)
				(type default)
			)
			(layer "F.SilkS")
		)
		(fp_line
			(start 21.734018 -4.804664)
			(end 21.746464 -4.874006)
			(stroke
				(width 0.1)
				(type default)
			)
			(layer "F.SilkS")
		)
		(fp_line
			(start 21.746464 -4.874006)
			(end 20.949666 -4.109466)
			(stroke
				(width 0.1)
				(type default)
			)
			(layer "F.SilkS")
		)
		(fp_line
			(start 21.746464 -4.874006)
			(end 20.949666 -4.109466)
			(stroke
				(width 0.1)
				(type default)
			)
			(layer "F.SilkS")
		)
		(fp_line
			(start 21.746464 -4.874006)
			(end 21.758402 -4.943348)
			(stroke
				(width 0.1)
				(type default)
			)
			(layer "F.SilkS")
		)
		(fp_line
			(start 21.746464 -4.874006)
			(end 21.758402 -4.943348)
			(stroke
				(width 0.1)
				(type default)
			)
			(layer "F.SilkS")
		)
		(fp_line
			(start 21.755608 -5.171694)
			(end 20.648422 -4.109466)
			(stroke
				(width 0.1)
				(type default)
			)
			(layer "F.SilkS")
		)
		(fp_line
			(start 21.755608 -5.171694)
			(end 20.648422 -4.109466)
			(stroke
				(width 0.1)
				(type default)
			)
			(layer "F.SilkS")
		)
		(fp_line
			(start 21.755608 -5.171694)
			(end 21.69541 -5.171694)
			(stroke
				(width 0.1)
				(type default)
			)
			(layer "F.SilkS")
		)
		(fp_line
			(start 21.755608 -5.171694)
			(end 21.69541 -5.171694)
			(stroke
				(width 0.1)
				(type default)
			)
			(layer "F.SilkS")
		)
		(fp_line
			(start 21.758402 -4.943348)
			(end 20.889214 -4.109466)
			(stroke
				(width 0.1)
				(type default)
			)
			(layer "F.SilkS")
		)
		(fp_line
			(start 21.758402 -4.943348)
			(end 20.889214 -4.109466)
			(stroke
				(width 0.1)
				(type default)
			)
			(layer "F.SilkS")
		)
		(fp_line
			(start 21.758402 -4.943348)
			(end 21.770594 -5.012944)
			(stroke
				(width 0.1)
				(type default)
			)
			(layer "F.SilkS")
		)
		(fp_line
			(start 21.758402 -4.943348)
			(end 21.770594 -5.012944)
			(stroke
				(width 0.1)
				(type default)
			)
			(layer "F.SilkS")
		)
		(fp_line
			(start 21.770594 -5.012944)
			(end 20.829016 -4.109466)
			(stroke
				(width 0.1)
				(type default)
			)
			(layer "F.SilkS")
		)
		(fp_line
			(start 21.770594 -5.012944)
			(end 20.829016 -4.109466)
			(stroke
				(width 0.1)
				(type default)
			)
			(layer "F.SilkS")
		)
		(fp_line
			(start 21.770594 -5.012944)
			(end 21.78304 -5.082032)
			(stroke
				(width 0.1)
				(type default)
			)
			(layer "F.SilkS")
		)
		(fp_line
			(start 21.770594 -5.012944)
			(end 21.78304 -5.082032)
			(stroke
				(width 0.1)
				(type default)
			)
			(layer "F.SilkS")
		)
		(fp_line
			(start 21.78304 -5.082032)
			(end 20.768564 -4.109466)
			(stroke
				(width 0.1)
				(type default)
			)
			(layer "F.SilkS")
		)
		(fp_line
			(start 21.78304 -5.082032)
			(end 20.768564 -4.109466)
			(stroke
				(width 0.1)
				(type default)
			)
			(layer "F.SilkS")
		)
		(fp_line
			(start 21.78304 -5.082032)
			(end 21.794978 -5.151374)
			(stroke
				(width 0.1)
				(type default)
			)
			(layer "F.SilkS")
		)
		(fp_line
			(start 21.78304 -5.082032)
			(end 21.794978 -5.151374)
			(stroke
				(width 0.1)
				(type default)
			)
			(layer "F.SilkS")
		)
		(fp_line
			(start 21.794978 -5.151374)
			(end 20.70862 -4.109466)
			(stroke
				(width 0.1)
				(type default)
			)
			(layer "F.SilkS")
		)
		(fp_line
			(start 21.794978 -5.151374)
			(end 20.70862 -4.109466)
			(stroke
				(width 0.1)
				(type default)
			)
			(layer "F.SilkS")
		)
		(fp_line
			(start 21.794978 -5.151374)
			(end 21.798534 -5.171694)
			(stroke
				(width 0.1)
				(type default)
			)
			(layer "F.SilkS")
		)
		(fp_line
			(start 21.794978 -5.151374)
			(end 21.798534 -5.171694)
			(stroke
				(width 0.1)
				(type default)
			)
			(layer "F.SilkS")
		)
		(fp_line
			(start 21.798534 -5.171694)
			(end 21.755608 -5.171694)
			(stroke
				(width 0.1)
				(type default)
			)
			(layer "F.SilkS")
		)
		(fp_line
			(start 21.798534 -5.171694)
			(end 21.755608 -5.171694)
			(stroke
				(width 0.1)
				(type default)
			)
			(layer "F.SilkS")
		)
		(fp_line
			(start 21.838158 -2.018792)
			(end 23.619206 -3.727196)
			(stroke
				(width 0.1)
				(type default)
			)
			(layer "F.SilkS")
		)
		(fp_line
			(start 21.838158 -2.018792)
			(end 23.619206 -3.727196)
			(stroke
				(width 0.1)
				(type default)
			)
			(layer "F.SilkS")
		)
		(fp_line
			(start 21.839428 -2.07772)
			(end 23.55469 -3.723386)
			(stroke
				(width 0.1)
				(type default)
			)
			(layer "F.SilkS")
		)
		(fp_line
			(start 21.839428 -2.07772)
			(end 23.55469 -3.723386)
			(stroke
				(width 0.1)
				(type default)
			)
			(layer "F.SilkS")
		)
		(fp_line
			(start 21.841206 -2.137156)
			(end 23.489666 -3.71856)
			(stroke
				(width 0.1)
				(type default)
			)
			(layer "F.SilkS")
		)
		(fp_line
			(start 21.841206 -2.137156)
			(end 23.489666 -3.71856)
			(stroke
				(width 0.1)
				(type default)
			)
			(layer "F.SilkS")
		)
		(fp_line
			(start 21.841206 -1.90627)
			(end 23.747984 -3.735324)
			(stroke
				(width 0.1)
				(type default)
			)
			(layer "F.SilkS")
		)
		(fp_line
			(start 21.841206 -1.90627)
			(end 23.747984 -3.735324)
			(stroke
				(width 0.1)
				(type default)
			)
			(layer "F.SilkS")
		)
		(fp_line
			(start 21.846032 -1.853184)
			(end 23.811992 -3.739388)
			(stroke
				(width 0.1)
				(type default)
			)
			(layer "F.SilkS")
		)
		(fp_line
			(start 21.846032 -1.853184)
			(end 23.811992 -3.739388)
			(stroke
				(width 0.1)
				(type default)
			)
			(layer "F.SilkS")
		)
		(fp_line
			(start 21.849334 -2.202942)
			(end 23.414228 -3.703828)
			(stroke
				(width 0.1)
				(type default)
			)
			(layer "F.SilkS")
		)
		(fp_line
			(start 21.849334 -2.202942)
			(end 23.414228 -3.703828)
			(stroke
				(width 0.1)
				(type default)
			)
			(layer "F.SilkS")
		)
		(fp_line
			(start 21.850858 -1.799844)
			(end 23.874222 -3.740912)
			(stroke
				(width 0.1)
				(type default)
			)
			(layer "F.SilkS")
		)
		(fp_line
			(start 21.850858 -1.799844)
			(end 23.874222 -3.740912)
			(stroke
				(width 0.1)
				(type default)
			)
			(layer "F.SilkS")
		)
		(fp_line
			(start 21.85797 -2.268728)
			(end 23.338282 -3.688842)
			(stroke
				(width 0.1)
				(type default)
			)
			(layer "F.SilkS")
		)
		(fp_line
			(start 21.85797 -2.268728)
			(end 23.338282 -3.688842)
			(stroke
				(width 0.1)
				(type default)
			)
			(layer "F.SilkS")
		)
		(fp_line
			(start 21.86051 -1.75133)
			(end 23.930864 -3.737864)
			(stroke
				(width 0.1)
				(type default)
			)
			(layer "F.SilkS")
		)
		(fp_line
			(start 21.86051 -1.75133)
			(end 23.930864 -3.737864)
			(stroke
				(width 0.1)
				(type default)
			)
			(layer "F.SilkS")
		)
		(fp_line
			(start 21.869146 -2.337308)
			(end 23.26259 -3.673856)
			(stroke
				(width 0.1)
				(type default)
			)
			(layer "F.SilkS")
		)
		(fp_line
			(start 21.869146 -2.337308)
			(end 23.26259 -3.673856)
			(stroke
				(width 0.1)
				(type default)
			)
			(layer "F.SilkS")
		)
		(fp_line
			(start 21.870416 -1.703578)
			(end 23.98776 -3.734816)
			(stroke
				(width 0.1)
				(type default)
			)
			(layer "F.SilkS")
		)
		(fp_line
			(start 21.870416 -1.703578)
			(end 23.98776 -3.734816)
			(stroke
				(width 0.1)
				(type default)
			)
			(layer "F.SilkS")
		)
		(fp_line
			(start 21.88083 -1.655826)
			(end 24.04491 -3.731768)
			(stroke
				(width 0.1)
				(type default)
			)
			(layer "F.SilkS")
		)
		(fp_line
			(start 21.88083 -1.655826)
			(end 24.04491 -3.731768)
			(stroke
				(width 0.1)
				(type default)
			)
			(layer "F.SilkS")
		)
		(fp_line
			(start 21.89099 -2.416048)
			(end 23.187152 -3.659124)
			(stroke
				(width 0.1)
				(type default)
			)
			(layer "F.SilkS")
		)
		(fp_line
			(start 21.89099 -2.416048)
			(end 23.187152 -3.659124)
			(stroke
				(width 0.1)
				(type default)
			)
			(layer "F.SilkS")
		)
		(fp_line
			(start 21.894546 -1.611376)
			(end 24.101806 -3.728974)
			(stroke
				(width 0.1)
				(type default)
			)
			(layer "F.SilkS")
		)
		(fp_line
			(start 21.894546 -1.611376)
			(end 24.101806 -3.728974)
			(stroke
				(width 0.1)
				(type default)
			)
			(layer "F.SilkS")
		)
		(fp_line
			(start 21.909786 -1.568196)
			(end 24.154892 -3.721862)
			(stroke
				(width 0.1)
				(type default)
			)
			(layer "F.SilkS")
		)
		(fp_line
			(start 21.909786 -1.568196)
			(end 24.154892 -3.721862)
			(stroke
				(width 0.1)
				(type default)
			)
			(layer "F.SilkS")
		)
		(fp_line
			(start 21.913088 -2.494788)
			(end 23.10003 -3.63347)
			(stroke
				(width 0.1)
				(type default)
			)
			(layer "F.SilkS")
		)
		(fp_line
			(start 21.913088 -2.494788)
			(end 23.10003 -3.63347)
			(stroke
				(width 0.1)
				(type default)
			)
			(layer "F.SilkS")
		)
		(fp_line
			(start 21.924772 -1.525016)
			(end 24.205946 -3.712972)
			(stroke
				(width 0.1)
				(type default)
			)
			(layer "F.SilkS")
		)
		(fp_line
			(start 21.924772 -1.525016)
			(end 24.205946 -3.712972)
			(stroke
				(width 0.1)
				(type default)
			)
			(layer "F.SilkS")
		)
		(fp_line
			(start 21.93544 -2.573782)
			(end 23.00478 -3.599942)
			(stroke
				(width 0.1)
				(type default)
			)
			(layer "F.SilkS")
		)
		(fp_line
			(start 21.93544 -2.573782)
			(end 23.00478 -3.599942)
			(stroke
				(width 0.1)
				(type default)
			)
			(layer "F.SilkS")
		)
		(fp_line
			(start 21.942806 -1.484376)
			(end 23.220934 -2.710688)
			(stroke
				(width 0.1)
				(type default)
			)
			(layer "F.SilkS")
		)
		(fp_line
			(start 21.942806 -1.484376)
			(end 23.220934 -2.710688)
			(stroke
				(width 0.1)
				(type default)
			)
			(layer "F.SilkS")
		)
		(fp_line
			(start 21.957538 -2.652776)
			(end 22.909784 -3.56616)
			(stroke
				(width 0.1)
				(type default)
			)
			(layer "F.SilkS")
		)
		(fp_line
			(start 21.957538 -2.652776)
			(end 22.909784 -3.56616)
			(stroke
				(width 0.1)
				(type default)
			)
			(layer "F.SilkS")
		)
		(fp_line
			(start 21.962364 -1.445514)
			(end 23.052786 -2.491486)
			(stroke
				(width 0.1)
				(type default)
			)
			(layer "F.SilkS")
		)
		(fp_line
			(start 21.962364 -1.445514)
			(end 23.052786 -2.491486)
			(stroke
				(width 0.1)
				(type default)
			)
			(layer "F.SilkS")
		)
		(fp_line
			(start 21.981922 -1.406652)
			(end 23.020782 -2.403094)
			(stroke
				(width 0.1)
				(type default)
			)
			(layer "F.SilkS")
		)
		(fp_line
			(start 21.981922 -1.406652)
			(end 23.020782 -2.403094)
			(stroke
				(width 0.1)
				(type default)
			)
			(layer "F.SilkS")
		)
		(fp_line
			(start 22.003004 -1.36906)
			(end 22.99081 -2.31648)
			(stroke
				(width 0.1)
				(type default)
			)
			(layer "F.SilkS")
		)
		(fp_line
			(start 22.003004 -1.36906)
			(end 22.99081 -2.31648)
			(stroke
				(width 0.1)
				(type default)
			)
			(layer "F.SilkS")
		)
		(fp_line
			(start 22.017228 -2.767838)
			(end 22.802342 -3.521202)
			(stroke
				(width 0.1)
				(type default)
			)
			(layer "F.SilkS")
		)
		(fp_line
			(start 22.017228 -2.767838)
			(end 22.802342 -3.521202)
			(stroke
				(width 0.1)
				(type default)
			)
			(layer "F.SilkS")
		)
		(fp_line
			(start 22.02688 -1.334262)
			(end 22.984206 -2.252726)
			(stroke
				(width 0.1)
				(type default)
			)
			(layer "F.SilkS")
		)
		(fp_line
			(start 22.02688 -1.334262)
			(end 22.984206 -2.252726)
			(stroke
				(width 0.1)
				(type default)
			)
			(layer "F.SilkS")
		)
		(fp_line
			(start 22.05101 -1.299464)
			(end 22.981158 -2.19202)
			(stroke
				(width 0.1)
				(type default)
			)
			(layer "F.SilkS")
		)
		(fp_line
			(start 22.05101 -1.299464)
			(end 22.981158 -2.19202)
			(stroke
				(width 0.1)
				(type default)
			)
			(layer "F.SilkS")
		)
		(fp_line
			(start 22.07514 -1.265174)
			(end 22.985222 -2.137918)
			(stroke
				(width 0.1)
				(type default)
			)
			(layer "F.SilkS")
		)
		(fp_line
			(start 22.07514 -1.265174)
			(end 22.985222 -2.137918)
			(stroke
				(width 0.1)
				(type default)
			)
			(layer "F.SilkS")
		)
		(fp_line
			(start 22.077934 -2.883408)
			(end 22.662896 -3.444748)
			(stroke
				(width 0.1)
				(type default)
			)
			(layer "F.SilkS")
		)
		(fp_line
			(start 22.077934 -2.883408)
			(end 22.662896 -3.444748)
			(stroke
				(width 0.1)
				(type default)
			)
			(layer "F.SilkS")
		)
		(fp_line
			(start 22.10308 -1.233932)
			(end 22.992588 -2.087372)
			(stroke
				(width 0.1)
				(type default)
			)
			(layer "F.SilkS")
		)
		(fp_line
			(start 22.10308 -1.233932)
			(end 22.992588 -2.087372)
			(stroke
				(width 0.1)
				(type default)
			)
			(layer "F.SilkS")
		)
		(fp_line
			(start 22.130512 -1.202944)
			(end 23.005542 -2.042414)
			(stroke
				(width 0.1)
				(type default)
			)
			(layer "F.SilkS")
		)
		(fp_line
			(start 22.130512 -1.202944)
			(end 23.005542 -2.042414)
			(stroke
				(width 0.1)
				(type default)
			)
			(layer "F.SilkS")
		)
		(fp_line
			(start 22.158452 -1.171956)
			(end 23.020782 -1.99898)
			(stroke
				(width 0.1)
				(type default)
			)
			(layer "F.SilkS")
		)
		(fp_line
			(start 22.158452 -1.171956)
			(end 23.020782 -1.99898)
			(stroke
				(width 0.1)
				(type default)
			)
			(layer "F.SilkS")
		)
		(fp_line
			(start 22.18944 -1.143762)
			(end 23.042372 -1.96215)
			(stroke
				(width 0.1)
				(type default)
			)
			(layer "F.SilkS")
		)
		(fp_line
			(start 22.18944 -1.143762)
			(end 23.042372 -1.96215)
			(stroke
				(width 0.1)
				(type default)
			)
			(layer "F.SilkS")
		)
		(fp_line
			(start 22.22119 -1.11633)
			(end 23.06447 -1.925828)
			(stroke
				(width 0.1)
				(type default)
			)
			(layer "F.SilkS")
		)
		(fp_line
			(start 22.22119 -1.11633)
			(end 23.06447 -1.925828)
			(stroke
				(width 0.1)
				(type default)
			)
			(layer "F.SilkS")
		)
		(fp_line
			(start 22.252432 -1.089152)
			(end 23.094188 -1.896364)
			(stroke
				(width 0.1)
				(type default)
			)
			(layer "F.SilkS")
		)
		(fp_line
			(start 22.252432 -1.089152)
			(end 23.094188 -1.896364)
			(stroke
				(width 0.1)
				(type default)
			)
			(layer "F.SilkS")
		)
		(fp_line
			(start 22.286214 -1.063752)
			(end 23.124414 -1.867916)
			(stroke
				(width 0.1)
				(type default)
			)
			(layer "F.SilkS")
		)
		(fp_line
			(start 22.286214 -1.063752)
			(end 23.124414 -1.867916)
			(stroke
				(width 0.1)
				(type default)
			)
			(layer "F.SilkS")
		)
		(fp_line
			(start 22.321774 -1.039622)
			(end 23.158196 -1.842262)
			(stroke
				(width 0.1)
				(type default)
			)
			(layer "F.SilkS")
		)
		(fp_line
			(start 22.321774 -1.039622)
			(end 23.158196 -1.842262)
			(stroke
				(width 0.1)
				(type default)
			)
			(layer "F.SilkS")
		)
		(fp_line
			(start 22.356572 -1.015746)
			(end 23.197058 -1.821942)
			(stroke
				(width 0.1)
				(type default)
			)
			(layer "F.SilkS")
		)
		(fp_line
			(start 22.356572 -1.015746)
			(end 23.197058 -1.821942)
			(stroke
				(width 0.1)
				(type default)
			)
			(layer "F.SilkS")
		)
		(fp_line
			(start 22.393402 -0.993394)
			(end 23.235666 -1.801622)
			(stroke
				(width 0.1)
				(type default)
			)
			(layer "F.SilkS")
		)
		(fp_line
			(start 22.393402 -0.993394)
			(end 23.235666 -1.801622)
			(stroke
				(width 0.1)
				(type default)
			)
			(layer "F.SilkS")
		)
		(fp_line
			(start 22.43201 -0.97282)
			(end 23.280878 -1.786636)
			(stroke
				(width 0.1)
				(type default)
			)
			(layer "F.SilkS")
		)
		(fp_line
			(start 22.43201 -0.97282)
			(end 23.280878 -1.786636)
			(stroke
				(width 0.1)
				(type default)
			)
			(layer "F.SilkS")
		)
		(fp_line
			(start 22.470872 -0.952246)
			(end 23.328122 -1.774444)
			(stroke
				(width 0.1)
				(type default)
			)
			(layer "F.SilkS")
		)
		(fp_line
			(start 22.470872 -0.952246)
			(end 23.328122 -1.774444)
			(stroke
				(width 0.1)
				(type default)
			)
			(layer "F.SilkS")
		)
		(fp_line
			(start 22.510496 -0.932688)
			(end 23.375366 -1.761998)
			(stroke
				(width 0.1)
				(type default)
			)
			(layer "F.SilkS")
		)
		(fp_line
			(start 22.510496 -0.932688)
			(end 23.375366 -1.761998)
			(stroke
				(width 0.1)
				(type default)
			)
			(layer "F.SilkS")
		)
		(fp_line
			(start 22.552914 -0.91567)
			(end 23.430484 -1.757172)
			(stroke
				(width 0.1)
				(type default)
			)
			(layer "F.SilkS")
		)
		(fp_line
			(start 22.552914 -0.91567)
			(end 23.430484 -1.757172)
			(stroke
				(width 0.1)
				(type default)
			)
			(layer "F.SilkS")
		)
		(fp_line
			(start 22.595332 -0.898398)
			(end 23.48611 -1.752854)
			(stroke
				(width 0.1)
				(type default)
			)
			(layer "F.SilkS")
		)
		(fp_line
			(start 22.595332 -0.898398)
			(end 23.48611 -1.752854)
			(stroke
				(width 0.1)
				(type default)
			)
			(layer "F.SilkS")
		)
		(fp_line
			(start 22.638258 -0.881888)
			(end 23.54199 -1.74879)
			(stroke
				(width 0.1)
				(type default)
			)
			(layer "F.SilkS")
		)
		(fp_line
			(start 22.638258 -0.881888)
			(end 23.54199 -1.74879)
			(stroke
				(width 0.1)
				(type default)
			)
			(layer "F.SilkS")
		)
		(fp_line
			(start 22.651212 -4.81838)
			(end 22.66696 -4.776216)
			(stroke
				(width 0.1)
				(type default)
			)
			(layer "F.SilkS")
		)
		(fp_line
			(start 22.651212 -4.81838)
			(end 22.66696 -4.776216)
			(stroke
				(width 0.1)
				(type default)
			)
			(layer "F.SilkS")
		)
		(fp_line
			(start 22.651212 -4.81838)
			(end 22.676358 -4.842764)
			(stroke
				(width 0.1)
				(type default)
			)
			(layer "F.SilkS")
		)
		(fp_line
			(start 22.651212 -4.81838)
			(end 22.676358 -4.842764)
			(stroke
				(width 0.1)
				(type default)
			)
			(layer "F.SilkS")
		)
		(fp_line
			(start 22.66696 -4.776216)
			(end 22.682708 -4.733798)
			(stroke
				(width 0.1)
				(type default)
			)
			(layer "F.SilkS")
		)
		(fp_line
			(start 22.66696 -4.776216)
			(end 22.682708 -4.733798)
			(stroke
				(width 0.1)
				(type default)
			)
			(layer "F.SilkS")
		)
		(fp_line
			(start 22.66696 -4.776216)
			(end 22.802088 -4.905756)
			(stroke
				(width 0.1)
				(type default)
			)
			(layer "F.SilkS")
		)
		(fp_line
			(start 22.66696 -4.776216)
			(end 22.802088 -4.905756)
			(stroke
				(width 0.1)
				(type default)
			)
			(layer "F.SilkS")
		)
		(fp_line
			(start 22.682708 -4.733798)
			(end 22.698964 -4.69138)
			(stroke
				(width 0.1)
				(type default)
			)
			(layer "F.SilkS")
		)
		(fp_line
			(start 22.682708 -4.733798)
			(end 22.698964 -4.69138)
			(stroke
				(width 0.1)
				(type default)
			)
			(layer "F.SilkS")
		)
		(fp_line
			(start 22.682708 -4.733798)
			(end 22.919436 -4.960874)
			(stroke
				(width 0.1)
				(type default)
			)
			(layer "F.SilkS")
		)
		(fp_line
			(start 22.682708 -4.733798)
			(end 22.919436 -4.960874)
			(stroke
				(width 0.1)
				(type default)
			)
			(layer "F.SilkS")
		)
		(fp_line
			(start 22.684232 -0.868172)
			(end 23.610316 -1.756664)
			(stroke
				(width 0.1)
				(type default)
			)
			(layer "F.SilkS")
		)
		(fp_line
			(start 22.684232 -0.868172)
			(end 23.610316 -1.756664)
			(stroke
				(width 0.1)
				(type default)
			)
			(layer "F.SilkS")
		)
		(fp_line
			(start 22.698964 -4.69138)
			(end 22.714712 -4.648962)
			(stroke
				(width 0.1)
				(type default)
			)
			(layer "F.SilkS")
		)
		(fp_line
			(start 22.698964 -4.69138)
			(end 22.714712 -4.648962)
			(stroke
				(width 0.1)
				(type default)
			)
			(layer "F.SilkS")
		)
		(fp_line
			(start 22.698964 -4.69138)
			(end 23.03272 -5.01142)
			(stroke
				(width 0.1)
				(type default)
			)
			(layer "F.SilkS")
		)
		(fp_line
			(start 22.698964 -4.69138)
			(end 23.03272 -5.01142)
			(stroke
				(width 0.1)
				(type default)
			)
			(layer "F.SilkS")
		)
		(fp_line
			(start 22.714712 -4.648962)
			(end 22.730714 -4.606544)
			(stroke
				(width 0.1)
				(type default)
			)
			(layer "F.SilkS")
		)
		(fp_line
			(start 22.714712 -4.648962)
			(end 22.730714 -4.606544)
			(stroke
				(width 0.1)
				(type default)
			)
			(layer "F.SilkS")
		)
		(fp_line
			(start 22.714712 -4.648962)
			(end 23.13432 -5.051298)
			(stroke
				(width 0.1)
				(type default)
			)
			(layer "F.SilkS")
		)
		(fp_line
			(start 22.714712 -4.648962)
			(end 23.13432 -5.051298)
			(stroke
				(width 0.1)
				(type default)
			)
			(layer "F.SilkS")
		)
		(fp_line
			(start 22.729952 -0.85471)
			(end 23.67915 -1.765046)
			(stroke
				(width 0.1)
				(type default)
			)
			(layer "F.SilkS")
		)
		(fp_line
			(start 22.729952 -0.85471)
			(end 23.67915 -1.765046)
			(stroke
				(width 0.1)
				(type default)
			)
			(layer "F.SilkS")
		)
		(fp_line
			(start 22.730714 -4.606544)
			(end 22.74697 -4.564126)
			(stroke
				(width 0.1)
				(type default)
			)
			(layer "F.SilkS")
		)
		(fp_line
			(start 22.730714 -4.606544)
			(end 22.74697 -4.564126)
			(stroke
				(width 0.1)
				(type default)
			)
			(layer "F.SilkS")
		)
		(fp_line
			(start 22.730714 -4.606544)
			(end 23.234396 -5.089652)
			(stroke
				(width 0.1)
				(type default)
			)
			(layer "F.SilkS")
		)
		(fp_line
			(start 22.730714 -4.606544)
			(end 23.234396 -5.089652)
			(stroke
				(width 0.1)
				(type default)
			)
			(layer "F.SilkS")
		)
		(fp_line
			(start 22.74697 -4.564126)
			(end 22.762718 -4.521708)
			(stroke
				(width 0.1)
				(type default)
			)
			(layer "F.SilkS")
		)
		(fp_line
			(start 22.74697 -4.564126)
			(end 22.762718 -4.521708)
			(stroke
				(width 0.1)
				(type default)
			)
			(layer "F.SilkS")
		)
		(fp_line
			(start 22.74697 -4.564126)
			(end 23.32355 -5.117592)
			(stroke
				(width 0.1)
				(type default)
			)
			(layer "F.SilkS")
		)
		(fp_line
			(start 22.74697 -4.564126)
			(end 23.32355 -5.117592)
			(stroke
				(width 0.1)
				(type default)
			)
			(layer "F.SilkS")
		)
		(fp_line
			(start 22.762718 -4.521708)
			(end 22.778466 -4.47929)
			(stroke
				(width 0.1)
				(type default)
			)
			(layer "F.SilkS")
		)
		(fp_line
			(start 22.762718 -4.521708)
			(end 22.778466 -4.47929)
			(stroke
				(width 0.1)
				(type default)
			)
			(layer "F.SilkS")
		)
		(fp_line
			(start 22.762718 -4.521708)
			(end 23.412704 -5.145278)
			(stroke
				(width 0.1)
				(type default)
			)
			(layer "F.SilkS")
		)
		(fp_line
			(start 22.762718 -4.521708)
			(end 23.412704 -5.145278)
			(stroke
				(width 0.1)
				(type default)
			)
			(layer "F.SilkS")
		)
		(fp_line
			(start 22.777196 -0.841756)
			(end 23.748238 -1.773682)
			(stroke
				(width 0.1)
				(type default)
			)
			(layer "F.SilkS")
		)
		(fp_line
			(start 22.777196 -0.841756)
			(end 23.748238 -1.773682)
			(stroke
				(width 0.1)
				(type default)
			)
			(layer "F.SilkS")
		)
		(fp_line
			(start 22.778466 -4.47929)
			(end 22.794722 -4.436872)
			(stroke
				(width 0.1)
				(type default)
			)
			(layer "F.SilkS")
		)
		(fp_line
			(start 22.778466 -4.47929)
			(end 22.794722 -4.436872)
			(stroke
				(width 0.1)
				(type default)
			)
			(layer "F.SilkS")
		)
		(fp_line
			(start 22.778466 -4.47929)
			(end 23.494746 -5.166106)
			(stroke
				(width 0.1)
				(type default)
			)
			(layer "F.SilkS")
		)
		(fp_line
			(start 22.778466 -4.47929)
			(end 23.494746 -5.166106)
			(stroke
				(width 0.1)
				(type default)
			)
			(layer "F.SilkS")
		)
		(fp_line
			(start 22.794722 -4.436872)
			(end 22.81047 -4.394708)
			(stroke
				(width 0.1)
				(type default)
			)
			(layer "F.SilkS")
		)
		(fp_line
			(start 22.794722 -4.436872)
			(end 22.81047 -4.394708)
			(stroke
				(width 0.1)
				(type default)
			)
			(layer "F.SilkS")
		)
		(fp_line
			(start 22.794722 -4.436872)
			(end 23.573994 -5.184648)
			(stroke
				(width 0.1)
				(type default)
			)
			(layer "F.SilkS")
		)
		(fp_line
			(start 22.794722 -4.436872)
			(end 23.573994 -5.184648)
			(stroke
				(width 0.1)
				(type default)
			)
			(layer "F.SilkS")
		)
		(fp_line
			(start 22.81047 -4.394708)
			(end 22.826472 -4.352036)
			(stroke
				(width 0.1)
				(type default)
			)
			(layer "F.SilkS")
		)
		(fp_line
			(start 22.81047 -4.394708)
			(end 22.826472 -4.352036)
			(stroke
				(width 0.1)
				(type default)
			)
			(layer "F.SilkS")
		)
		(fp_line
			(start 22.81047 -4.394708)
			(end 23.652226 -5.20192)
			(stroke
				(width 0.1)
				(type default)
			)
			(layer "F.SilkS")
		)
		(fp_line
			(start 22.81047 -4.394708)
			(end 23.652226 -5.20192)
			(stroke
				(width 0.1)
				(type default)
			)
			(layer "F.SilkS")
		)
		(fp_line
			(start 22.826472 -4.352036)
			(end 22.842728 -4.309618)
			(stroke
				(width 0.1)
				(type default)
			)
			(layer "F.SilkS")
		)
		(fp_line
			(start 22.826472 -4.352036)
			(end 22.842728 -4.309618)
			(stroke
				(width 0.1)
				(type default)
			)
			(layer "F.SilkS")
		)
		(fp_line
			(start 22.826472 -4.352036)
			(end 23.724616 -5.21335)
			(stroke
				(width 0.1)
				(type default)
			)
			(layer "F.SilkS")
		)
		(fp_line
			(start 22.826472 -4.352036)
			(end 23.724616 -5.21335)
			(stroke
				(width 0.1)
				(type default)
			)
			(layer "F.SilkS")
		)
		(fp_line
			(start 22.826726 -0.831596)
			(end 23.82012 -1.78435)
			(stroke
				(width 0.1)
				(type default)
			)
			(layer "F.SilkS")
		)
		(fp_line
			(start 22.826726 -0.831596)
			(end 23.82012 -1.78435)
			(stroke
				(width 0.1)
				(type default)
			)
			(layer "F.SilkS")
		)
		(fp_line
			(start 22.842728 -4.309618)
			(end 22.858476 -4.267454)
			(stroke
				(width 0.1)
				(type default)
			)
			(layer "F.SilkS")
		)
		(fp_line
			(start 22.842728 -4.309618)
			(end 22.858476 -4.267454)
			(stroke
				(width 0.1)
				(type default)
			)
			(layer "F.SilkS")
		)
		(fp_line
			(start 22.842728 -4.309618)
			(end 23.796498 -5.22478)
			(stroke
				(width 0.1)
				(type default)
			)
			(layer "F.SilkS")
		)
		(fp_line
			(start 22.842728 -4.309618)
			(end 23.796498 -5.22478)
			(stroke
				(width 0.1)
				(type default)
			)
			(layer "F.SilkS")
		)
		(fp_line
			(start 22.858476 -4.267454)
			(end 22.874224 -4.225036)
			(stroke
				(width 0.1)
				(type default)
			)
			(layer "F.SilkS")
		)
		(fp_line
			(start 22.858476 -4.267454)
			(end 22.874224 -4.225036)
			(stroke
				(width 0.1)
				(type default)
			)
			(layer "F.SilkS")
		)
		(fp_line
			(start 22.858476 -4.267454)
			(end 23.86711 -5.235194)
			(stroke
				(width 0.1)
				(type default)
			)
			(layer "F.SilkS")
		)
		(fp_line
			(start 22.858476 -4.267454)
			(end 23.86711 -5.235194)
			(stroke
				(width 0.1)
				(type default)
			)
			(layer "F.SilkS")
		)
		(fp_line
			(start 22.874224 -4.225036)
			(end 22.89048 -4.182618)
			(stroke
				(width 0.1)
				(type default)
			)
			(layer "F.SilkS")
		)
		(fp_line
			(start 22.874224 -4.225036)
			(end 22.89048 -4.182618)
			(stroke
				(width 0.1)
				(type default)
			)
			(layer "F.SilkS")
		)
		(fp_line
			(start 22.874224 -4.225036)
			(end 23.933658 -5.241036)
			(stroke
				(width 0.1)
				(type default)
			)
			(layer "F.SilkS")
		)
		(fp_line
			(start 22.874224 -4.225036)
			(end 23.933658 -5.241036)
			(stroke
				(width 0.1)
				(type default)
			)
			(layer "F.SilkS")
		)
		(fp_line
			(start 22.87651 -0.821436)
			(end 23.916894 -1.819656)
			(stroke
				(width 0.1)
				(type default)
			)
			(layer "F.SilkS")
		)
		(fp_line
			(start 22.87651 -0.821436)
			(end 23.916894 -1.819656)
			(stroke
				(width 0.1)
				(type default)
			)
			(layer "F.SilkS")
		)
		(fp_line
			(start 22.89048 -4.182618)
			(end 22.906482 -4.139946)
			(stroke
				(width 0.1)
				(type default)
			)
			(layer "F.SilkS")
		)
		(fp_line
			(start 22.89048 -4.182618)
			(end 22.906482 -4.139946)
			(stroke
				(width 0.1)
				(type default)
			)
			(layer "F.SilkS")
		)
		(fp_line
			(start 22.89048 -4.182618)
			(end 24.000206 -5.246878)
			(stroke
				(width 0.1)
				(type default)
			)
			(layer "F.SilkS")
		)
		(fp_line
			(start 22.89048 -4.182618)
			(end 24.000206 -5.246878)
			(stroke
				(width 0.1)
				(type default)
			)
			(layer "F.SilkS")
		)
		(fp_line
			(start 22.906482 -4.139946)
			(end 22.92223 -4.097782)
			(stroke
				(width 0.1)
				(type default)
			)
			(layer "F.SilkS")
		)
		(fp_line
			(start 22.906482 -4.139946)
			(end 22.92223 -4.097782)
			(stroke
				(width 0.1)
				(type default)
			)
			(layer "F.SilkS")
		)
		(fp_line
			(start 22.906482 -4.139946)
			(end 24.066246 -5.252974)
			(stroke
				(width 0.1)
				(type default)
			)
			(layer "F.SilkS")
		)
		(fp_line
			(start 22.906482 -4.139946)
			(end 24.066246 -5.252974)
			(stroke
				(width 0.1)
				(type default)
			)
			(layer "F.SilkS")
		)
		(fp_line
			(start 22.92223 -4.097782)
			(end 22.938486 -4.055364)
			(stroke
				(width 0.1)
				(type default)
			)
			(layer "F.SilkS")
		)
		(fp_line
			(start 22.92223 -4.097782)
			(end 22.938486 -4.055364)
			(stroke
				(width 0.1)
				(type default)
			)
			(layer "F.SilkS")
		)
		(fp_line
			(start 22.92223 -4.097782)
			(end 24.129492 -5.255768)
			(stroke
				(width 0.1)
				(type default)
			)
			(layer "F.SilkS")
		)
		(fp_line
			(start 22.92223 -4.097782)
			(end 24.129492 -5.255768)
			(stroke
				(width 0.1)
				(type default)
			)
			(layer "F.SilkS")
		)
		(fp_line
			(start 22.927818 -0.813308)
			(end 24.013668 -1.854962)
			(stroke
				(width 0.1)
				(type default)
			)
			(layer "F.SilkS")
		)
		(fp_line
			(start 22.927818 -0.813308)
			(end 24.013668 -1.854962)
			(stroke
				(width 0.1)
				(type default)
			)
			(layer "F.SilkS")
		)
		(fp_line
			(start 22.938486 -4.055364)
			(end 24.191468 -5.257546)
			(stroke
				(width 0.1)
				(type default)
			)
			(layer "F.SilkS")
		)
		(fp_line
			(start 22.938486 -4.055364)
			(end 24.191468 -5.257546)
			(stroke
				(width 0.1)
				(type default)
			)
			(layer "F.SilkS")
		)
		(fp_line
			(start 22.981158 -0.806704)
			(end 24.158956 -1.93675)
			(stroke
				(width 0.1)
				(type default)
			)
			(layer "F.SilkS")
		)
		(fp_line
			(start 22.981158 -0.806704)
			(end 24.158956 -1.93675)
			(stroke
				(width 0.1)
				(type default)
			)
			(layer "F.SilkS")
		)
		(fp_line
			(start 23.029672 -4.085336)
			(end 24.253444 -5.25907)
			(stroke
				(width 0.1)
				(type default)
			)
			(layer "F.SilkS")
		)
		(fp_line
			(start 23.029672 -4.085336)
			(end 24.253444 -5.25907)
			(stroke
				(width 0.1)
				(type default)
			)
			(layer "F.SilkS")
		)
		(fp_line
			(start 23.091394 -0.797052)
			(end 25.733502 -3.331464)
			(stroke
				(width 0.1)
				(type default)
			)
			(layer "F.SilkS")
		)
		(fp_line
			(start 23.091394 -0.797052)
			(end 25.733502 -3.331464)
			(stroke
				(width 0.1)
				(type default)
			)
			(layer "F.SilkS")
		)
		(fp_line
			(start 23.143718 -4.136898)
			(end 24.31542 -5.260848)
			(stroke
				(width 0.1)
				(type default)
			)
			(layer "F.SilkS")
		)
		(fp_line
			(start 23.143718 -4.136898)
			(end 24.31542 -5.260848)
			(stroke
				(width 0.1)
				(type default)
			)
			(layer "F.SilkS")
		)
		(fp_line
			(start 23.149306 -0.79502)
			(end 25.721056 -3.262122)
			(stroke
				(width 0.1)
				(type default)
			)
			(layer "F.SilkS")
		)
		(fp_line
			(start 23.149306 -0.79502)
			(end 25.721056 -3.262122)
			(stroke
				(width 0.1)
				(type default)
			)
			(layer "F.SilkS")
		)
		(fp_line
			(start 23.208488 -0.794258)
			(end 25.708864 -3.19278)
			(stroke
				(width 0.1)
				(type default)
			)
			(layer "F.SilkS")
		)
		(fp_line
			(start 23.208488 -0.794258)
			(end 25.708864 -3.19278)
			(stroke
				(width 0.1)
				(type default)
			)
			(layer "F.SilkS")
		)
		(fp_line
			(start 23.23084 -2.720086)
			(end 24.256492 -3.704082)
			(stroke
				(width 0.1)
				(type default)
			)
			(layer "F.SilkS")
		)
		(fp_line
			(start 23.23084 -2.720086)
			(end 24.256492 -3.704082)
			(stroke
				(width 0.1)
				(type default)
			)
			(layer "F.SilkS")
		)
		(fp_line
			(start 23.249382 -4.180586)
			(end 24.372824 -5.258562)
			(stroke
				(width 0.1)
				(type default)
			)
			(layer "F.SilkS")
		)
		(fp_line
			(start 23.249382 -4.180586)
			(end 24.372824 -5.258562)
			(stroke
				(width 0.1)
				(type default)
			)
			(layer "F.SilkS")
		)
		(fp_line
			(start 23.275798 -0.800608)
			(end 25.696926 -3.123184)
			(stroke
				(width 0.1)
				(type default)
			)
			(layer "F.SilkS")
		)
		(fp_line
			(start 23.275798 -0.800608)
			(end 25.696926 -3.123184)
			(stroke
				(width 0.1)
				(type default)
			)
			(layer "F.SilkS")
		)
		(fp_line
			(start 23.3426 -0.807466)
			(end 25.68448 -3.054096)
			(stroke
				(width 0.1)
				(type default)
			)
			(layer "F.SilkS")
		)
		(fp_line
			(start 23.3426 -0.807466)
			(end 25.68448 -3.054096)
			(stroke
				(width 0.1)
				(type default)
			)
			(layer "F.SilkS")
		)
		(fp_line
			(start 23.344632 -4.214114)
			(end 24.429212 -5.254752)
			(stroke
				(width 0.1)
				(type default)
			)
			(layer "F.SilkS")
		)
		(fp_line
			(start 23.344632 -4.214114)
			(end 24.429212 -5.254752)
			(stroke
				(width 0.1)
				(type default)
			)
			(layer "F.SilkS")
		)
		(fp_line
			(start 23.34895 -2.775712)
			(end 24.307546 -3.695192)
			(stroke
				(width 0.1)
				(type default)
			)
			(layer "F.SilkS")
		)
		(fp_line
			(start 23.34895 -2.775712)
			(end 24.307546 -3.695192)
			(stroke
				(width 0.1)
				(type default)
			)
			(layer "F.SilkS")
		)
		(fp_line
			(start 23.409402 -0.813562)
			(end 25.672542 -2.984754)
			(stroke
				(width 0.1)
				(type default)
			)
			(layer "F.SilkS")
		)
		(fp_line
			(start 23.409402 -0.813562)
			(end 25.672542 -2.984754)
			(stroke
				(width 0.1)
				(type default)
			)
			(layer "F.SilkS")
		)
		(fp_line
			(start 23.46071 -2.825242)
			(end 24.35606 -3.684016)
			(stroke
				(width 0.1)
				(type default)
			)
			(layer "F.SilkS")
		)
		(fp_line
			(start 23.46071 -2.825242)
			(end 24.35606 -3.684016)
			(stroke
				(width 0.1)
				(type default)
			)
			(layer "F.SilkS")
		)
		(fp_line
			(start 23.476458 -0.82042)
			(end 25.66035 -2.915412)
			(stroke
				(width 0.1)
				(type default)
			)
			(layer "F.SilkS")
		)
		(fp_line
			(start 23.476458 -0.82042)
			(end 25.66035 -2.915412)
			(stroke
				(width 0.1)
				(type default)
			)
			(layer "F.SilkS")
		)
		(fp_line
			(start 23.530052 -2.833878)
			(end 24.401272 -3.669538)
			(stroke
				(width 0.1)
				(type default)
			)
			(layer "F.SilkS")
		)
		(fp_line
			(start 23.530052 -2.833878)
			(end 24.401272 -3.669538)
			(stroke
				(width 0.1)
				(type default)
			)
			(layer "F.SilkS")
		)
		(fp_line
			(start 23.557484 -0.840232)
			(end 25.648412 -2.845816)
			(stroke
				(width 0.1)
				(type default)
			)
			(layer "F.SilkS")
		)
		(fp_line
			(start 23.557484 -0.840232)
			(end 25.648412 -2.845816)
			(stroke
				(width 0.1)
				(type default)
			)
			(layer "F.SilkS")
		)
		(fp_line
			(start 23.642828 -0.864616)
			(end 25.635966 -2.776474)
			(stroke
				(width 0.1)
				(type default)
			)
			(layer "F.SilkS")
		)
		(fp_line
			(start 23.642828 -0.864616)
			(end 25.635966 -2.776474)
			(stroke
				(width 0.1)
				(type default)
			)
			(layer "F.SilkS")
		)
		(fp_line
			(start 23.683468 -3.731514)
			(end 21.836634 -1.95961)
			(stroke
				(width 0.1)
				(type default)
			)
			(layer "F.SilkS")
		)
		(fp_line
			(start 23.683468 -3.731514)
			(end 21.836634 -1.95961)
			(stroke
				(width 0.1)
				(type default)
			)
			(layer "F.SilkS")
		)
		(fp_line
			(start 23.728426 -0.888746)
			(end 25.623774 -2.707132)
			(stroke
				(width 0.1)
				(type default)
			)
			(layer "F.SilkS")
		)
		(fp_line
			(start 23.728426 -0.888746)
			(end 25.623774 -2.707132)
			(stroke
				(width 0.1)
				(type default)
			)
			(layer "F.SilkS")
		)
		(fp_line
			(start 23.831296 -0.929894)
			(end 25.611836 -2.63779)
			(stroke
				(width 0.1)
				(type default)
			)
			(layer "F.SilkS")
		)
		(fp_line
			(start 23.831296 -0.929894)
			(end 25.611836 -2.63779)
			(stroke
				(width 0.1)
				(type default)
			)
			(layer "F.SilkS")
		)
		(fp_line
			(start 23.951692 -0.987552)
			(end 25.59939 -2.568194)
			(stroke
				(width 0.1)
				(type default)
			)
			(layer "F.SilkS")
		)
		(fp_line
			(start 23.951692 -0.987552)
			(end 25.59939 -2.568194)
			(stroke
				(width 0.1)
				(type default)
			)
			(layer "F.SilkS")
		)
		(fp_line
			(start 24.122888 -1.094232)
			(end 25.587452 -2.498852)
			(stroke
				(width 0.1)
				(type default)
			)
			(layer "F.SilkS")
		)
		(fp_line
			(start 24.122888 -1.094232)
			(end 25.587452 -2.498852)
			(stroke
				(width 0.1)
				(type default)
			)
			(layer "F.SilkS")
		)
		(fp_line
			(start 24.17699 -0.882904)
			(end 24.203406 -0.882904)
			(stroke
				(width 0.1)
				(type default)
			)
			(layer "F.SilkS")
		)
		(fp_line
			(start 24.17699 -0.882904)
			(end 24.203406 -0.882904)
			(stroke
				(width 0.1)
				(type default)
			)
			(layer "F.SilkS")
		)
		(fp_line
			(start 24.183848 -0.921512)
			(end 24.17699 -0.882904)
			(stroke
				(width 0.1)
				(type default)
			)
			(layer "F.SilkS")
		)
		(fp_line
			(start 24.183848 -0.921512)
			(end 24.17699 -0.882904)
			(stroke
				(width 0.1)
				(type default)
			)
			(layer "F.SilkS")
		)
		(fp_line
			(start 24.183848 -0.921512)
			(end 25.538684 -2.221484)
			(stroke
				(width 0.1)
				(type default)
			)
			(layer "F.SilkS")
		)
		(fp_line
			(start 24.183848 -0.921512)
			(end 25.538684 -2.221484)
			(stroke
				(width 0.1)
				(type default)
			)
			(layer "F.SilkS")
		)
		(fp_line
			(start 24.195786 -0.991108)
			(end 24.183848 -0.921512)
			(stroke
				(width 0.1)
				(type default)
			)
			(layer "F.SilkS")
		)
		(fp_line
			(start 24.195786 -0.991108)
			(end 24.183848 -0.921512)
			(stroke
				(width 0.1)
				(type default)
			)
			(layer "F.SilkS")
		)
		(fp_line
			(start 24.195786 -0.991108)
			(end 25.550876 -2.290826)
			(stroke
				(width 0.1)
				(type default)
			)
			(layer "F.SilkS")
		)
		(fp_line
			(start 24.195786 -0.991108)
			(end 25.550876 -2.290826)
			(stroke
				(width 0.1)
				(type default)
			)
			(layer "F.SilkS")
		)
		(fp_line
			(start 24.203406 -0.882904)
			(end 24.263858 -0.882904)
			(stroke
				(width 0.1)
				(type default)
			)
			(layer "F.SilkS")
		)
		(fp_line
			(start 24.203406 -0.882904)
			(end 24.263858 -0.882904)
			(stroke
				(width 0.1)
				(type default)
			)
			(layer "F.SilkS")
		)
		(fp_line
			(start 24.203406 -0.882904)
			(end 25.526746 -2.152142)
			(stroke
				(width 0.1)
				(type default)
			)
			(layer "F.SilkS")
		)
		(fp_line
			(start 24.203406 -0.882904)
			(end 25.526746 -2.152142)
			(stroke
				(width 0.1)
				(type default)
			)
			(layer "F.SilkS")
		)
		(fp_line
			(start 24.208232 -1.06045)
			(end 24.195786 -0.991108)
			(stroke
				(width 0.1)
				(type default)
			)
			(layer "F.SilkS")
		)
		(fp_line
			(start 24.208232 -1.06045)
			(end 24.195786 -0.991108)
			(stroke
				(width 0.1)
				(type default)
			)
			(layer "F.SilkS")
		)
		(fp_line
			(start 24.208232 -1.06045)
			(end 25.563322 -2.360422)
			(stroke
				(width 0.1)
				(type default)
			)
			(layer "F.SilkS")
		)
		(fp_line
			(start 24.208232 -1.06045)
			(end 25.563322 -2.360422)
			(stroke
				(width 0.1)
				(type default)
			)
			(layer "F.SilkS")
		)
		(fp_line
			(start 24.220424 -1.130046)
			(end 24.208232 -1.06045)
			(stroke
				(width 0.1)
				(type default)
			)
			(layer "F.SilkS")
		)
		(fp_line
			(start 24.220424 -1.130046)
			(end 24.208232 -1.06045)
			(stroke
				(width 0.1)
				(type default)
			)
			(layer "F.SilkS")
		)
		(fp_line
			(start 24.263858 -0.882904)
			(end 24.324056 -0.882904)
			(stroke
				(width 0.1)
				(type default)
			)
			(layer "F.SilkS")
		)
		(fp_line
			(start 24.263858 -0.882904)
			(end 24.324056 -0.882904)
			(stroke
				(width 0.1)
				(type default)
			)
			(layer "F.SilkS")
		)
		(fp_line
			(start 24.263858 -0.882904)
			(end 25.5143 -2.0828)
			(stroke
				(width 0.1)
				(type default)
			)
			(layer "F.SilkS")
		)
		(fp_line
			(start 24.263858 -0.882904)
			(end 25.5143 -2.0828)
			(stroke
				(width 0.1)
				(type default)
			)
			(layer "F.SilkS")
		)
		(fp_line
			(start 24.324056 -0.882904)
			(end 24.384 -0.882904)
			(stroke
				(width 0.1)
				(type default)
			)
			(layer "F.SilkS")
		)
		(fp_line
			(start 24.324056 -0.882904)
			(end 24.384 -0.882904)
			(stroke
				(width 0.1)
				(type default)
			)
			(layer "F.SilkS")
		)
		(fp_line
			(start 24.324056 -0.882904)
			(end 25.502362 -2.013204)
			(stroke
				(width 0.1)
				(type default)
			)
			(layer "F.SilkS")
		)
		(fp_line
			(start 24.324056 -0.882904)
			(end 25.502362 -2.013204)
			(stroke
				(width 0.1)
				(type default)
			)
			(layer "F.SilkS")
		)
		(fp_line
			(start 24.384 -0.882904)
			(end 24.443944 -0.882904)
			(stroke
				(width 0.1)
				(type default)
			)
			(layer "F.SilkS")
		)
		(fp_line
			(start 24.384 -0.882904)
			(end 24.443944 -0.882904)
			(stroke
				(width 0.1)
				(type default)
			)
			(layer "F.SilkS")
		)
		(fp_line
			(start 24.384 -0.882904)
			(end 25.49017 -1.943862)
			(stroke
				(width 0.1)
				(type default)
			)
			(layer "F.SilkS")
		)
		(fp_line
			(start 24.384 -0.882904)
			(end 25.49017 -1.943862)
			(stroke
				(width 0.1)
				(type default)
			)
			(layer "F.SilkS")
		)
		(fp_line
			(start 24.414988 -2.24028)
			(end 24.402796 -2.170938)
			(stroke
				(width 0.1)
				(type default)
			)
			(layer "F.SilkS")
		)
		(fp_line
			(start 24.414988 -2.24028)
			(end 24.402796 -2.170938)
			(stroke
				(width 0.1)
				(type default)
			)
			(layer "F.SilkS")
		)
		(fp_line
			(start 24.427434 -2.309368)
			(end 24.414988 -2.24028)
			(stroke
				(width 0.1)
				(type default)
			)
			(layer "F.SilkS")
		)
		(fp_line
			(start 24.427434 -2.309368)
			(end 24.414988 -2.24028)
			(stroke
				(width 0.1)
				(type default)
			)
			(layer "F.SilkS")
		)
		(fp_line
			(start 24.439372 -2.37871)
			(end 24.427434 -2.309368)
			(stroke
				(width 0.1)
				(type default)
			)
			(layer "F.SilkS")
		)
		(fp_line
			(start 24.439372 -2.37871)
			(end 24.427434 -2.309368)
			(stroke
				(width 0.1)
				(type default)
			)
			(layer "F.SilkS")
		)
		(fp_line
			(start 24.443944 -0.882904)
			(end 24.504142 -0.882904)
			(stroke
				(width 0.1)
				(type default)
			)
			(layer "F.SilkS")
		)
		(fp_line
			(start 24.443944 -0.882904)
			(end 24.504142 -0.882904)
			(stroke
				(width 0.1)
				(type default)
			)
			(layer "F.SilkS")
		)
		(fp_line
			(start 24.443944 -0.882904)
			(end 25.478232 -1.874774)
			(stroke
				(width 0.1)
				(type default)
			)
			(layer "F.SilkS")
		)
		(fp_line
			(start 24.443944 -0.882904)
			(end 25.478232 -1.874774)
			(stroke
				(width 0.1)
				(type default)
			)
			(layer "F.SilkS")
		)
		(fp_line
			(start 24.44623 -3.655568)
			(end 23.598886 -2.842514)
			(stroke
				(width 0.1)
				(type default)
			)
			(layer "F.SilkS")
		)
		(fp_line
			(start 24.44623 -3.655568)
			(end 23.598886 -2.842514)
			(stroke
				(width 0.1)
				(type default)
			)
			(layer "F.SilkS")
		)
		(fp_line
			(start 24.451564 -2.448306)
			(end 24.439372 -2.37871)
			(stroke
				(width 0.1)
				(type default)
			)
			(layer "F.SilkS")
		)
		(fp_line
			(start 24.451564 -2.448306)
			(end 24.439372 -2.37871)
			(stroke
				(width 0.1)
				(type default)
			)
			(layer "F.SilkS")
		)
		(fp_line
			(start 24.46401 -2.517648)
			(end 24.451564 -2.448306)
			(stroke
				(width 0.1)
				(type default)
			)
			(layer "F.SilkS")
		)
		(fp_line
			(start 24.46401 -2.517648)
			(end 24.451564 -2.448306)
			(stroke
				(width 0.1)
				(type default)
			)
			(layer "F.SilkS")
		)
		(fp_line
			(start 24.475948 -2.58699)
			(end 24.46401 -2.517648)
			(stroke
				(width 0.1)
				(type default)
			)
			(layer "F.SilkS")
		)
		(fp_line
			(start 24.475948 -2.58699)
			(end 24.46401 -2.517648)
			(stroke
				(width 0.1)
				(type default)
			)
			(layer "F.SilkS")
		)
		(fp_line
			(start 24.485346 -5.250942)
			(end 23.433532 -4.2418)
			(stroke
				(width 0.1)
				(type default)
			)
			(layer "F.SilkS")
		)
		(fp_line
			(start 24.485346 -5.250942)
			(end 23.433532 -4.2418)
			(stroke
				(width 0.1)
				(type default)
			)
			(layer "F.SilkS")
		)
		(fp_line
			(start 24.487886 -2.656332)
			(end 24.475948 -2.58699)
			(stroke
				(width 0.1)
				(type default)
			)
			(layer "F.SilkS")
		)
		(fp_line
			(start 24.487886 -2.656332)
			(end 24.475948 -2.58699)
			(stroke
				(width 0.1)
				(type default)
			)
			(layer "F.SilkS")
		)
		(fp_line
			(start 24.491696 -3.64109)
			(end 23.668482 -2.85115)
			(stroke
				(width 0.1)
				(type default)
			)
			(layer "F.SilkS")
		)
		(fp_line
			(start 24.491696 -3.64109)
			(end 23.668482 -2.85115)
			(stroke
				(width 0.1)
				(type default)
			)
			(layer "F.SilkS")
		)
		(fp_line
			(start 24.504142 -0.882904)
			(end 24.564594 -0.882904)
			(stroke
				(width 0.1)
				(type default)
			)
			(layer "F.SilkS")
		)
		(fp_line
			(start 24.504142 -0.882904)
			(end 24.564594 -0.882904)
			(stroke
				(width 0.1)
				(type default)
			)
			(layer "F.SilkS")
		)
		(fp_line
			(start 24.504142 -0.882904)
			(end 25.465786 -1.805178)
			(stroke
				(width 0.1)
				(type default)
			)
			(layer "F.SilkS")
		)
		(fp_line
			(start 24.504142 -0.882904)
			(end 25.465786 -1.805178)
			(stroke
				(width 0.1)
				(type default)
			)
			(layer "F.SilkS")
		)
		(fp_line
			(start 24.534114 -3.624072)
			(end 23.73757 -2.859786)
			(stroke
				(width 0.1)
				(type default)
			)
			(layer "F.SilkS")
		)
		(fp_line
			(start 24.534114 -3.624072)
			(end 23.73757 -2.859786)
			(stroke
				(width 0.1)
				(type default)
			)
			(layer "F.SilkS")
		)
		(fp_line
			(start 24.541734 -5.246878)
			(end 23.518114 -4.265168)
			(stroke
				(width 0.1)
				(type default)
			)
			(layer "F.SilkS")
		)
		(fp_line
			(start 24.541734 -5.246878)
			(end 23.518114 -4.265168)
			(stroke
				(width 0.1)
				(type default)
			)
			(layer "F.SilkS")
		)
		(fp_line
			(start 24.564594 -0.882904)
			(end 24.624538 -0.882904)
			(stroke
				(width 0.1)
				(type default)
			)
			(layer "F.SilkS")
		)
		(fp_line
			(start 24.564594 -0.882904)
			(end 24.624538 -0.882904)
			(stroke
				(width 0.1)
				(type default)
			)
			(layer "F.SilkS")
		)
		(fp_line
			(start 24.564594 -0.882904)
			(end 25.453594 -1.735836)
			(stroke
				(width 0.1)
				(type default)
			)
			(layer "F.SilkS")
		)
		(fp_line
			(start 24.564594 -0.882904)
			(end 25.453594 -1.735836)
			(stroke
				(width 0.1)
				(type default)
			)
			(layer "F.SilkS")
		)
		(fp_line
			(start 24.5745 -3.605276)
			(end 23.797006 -2.859024)
			(stroke
				(width 0.1)
				(type default)
			)
			(layer "F.SilkS")
		)
		(fp_line
			(start 24.5745 -3.605276)
			(end 23.797006 -2.859024)
			(stroke
				(width 0.1)
				(type default)
			)
			(layer "F.SilkS")
		)
		(fp_line
			(start 24.597614 -5.243068)
			(end 23.594822 -4.280916)
			(stroke
				(width 0.1)
				(type default)
			)
			(layer "F.SilkS")
		)
		(fp_line
			(start 24.597614 -5.243068)
			(end 23.594822 -4.280916)
			(stroke
				(width 0.1)
				(type default)
			)
			(layer "F.SilkS")
		)
		(fp_line
			(start 24.614886 -3.586226)
			(end 23.855426 -2.857754)
			(stroke
				(width 0.1)
				(type default)
			)
			(layer "F.SilkS")
		)
		(fp_line
			(start 24.614886 -3.586226)
			(end 23.855426 -2.857754)
			(stroke
				(width 0.1)
				(type default)
			)
			(layer "F.SilkS")
		)
		(fp_line
			(start 24.624538 -0.882904)
			(end 24.684736 -0.882904)
			(stroke
				(width 0.1)
				(type default)
			)
			(layer "F.SilkS")
		)
		(fp_line
			(start 24.624538 -0.882904)
			(end 24.684736 -0.882904)
			(stroke
				(width 0.1)
				(type default)
			)
			(layer "F.SilkS")
		)
		(fp_line
			(start 24.624538 -0.882904)
			(end 25.441656 -1.666494)
			(stroke
				(width 0.1)
				(type default)
			)
			(layer "F.SilkS")
		)
		(fp_line
			(start 24.624538 -0.882904)
			(end 25.441656 -1.666494)
			(stroke
				(width 0.1)
				(type default)
			)
			(layer "F.SilkS")
		)
		(fp_line
			(start 24.653748 -5.239258)
			(end 23.67026 -4.295902)
			(stroke
				(width 0.1)
				(type default)
			)
			(layer "F.SilkS")
		)
		(fp_line
			(start 24.653748 -5.239258)
			(end 23.67026 -4.295902)
			(stroke
				(width 0.1)
				(type default)
			)
			(layer "F.SilkS")
		)
		(fp_line
			(start 24.67102 -3.697478)
			(end 24.658574 -3.627882)
			(stroke
				(width 0.1)
				(type default)
			)
			(layer "F.SilkS")
		)
		(fp_line
			(start 24.67102 -3.697478)
			(end 24.658574 -3.627882)
			(stroke
				(width 0.1)
				(type default)
			)
			(layer "F.SilkS")
		)
		(fp_line
			(start 24.682958 -3.76682)
			(end 24.67102 -3.697478)
			(stroke
				(width 0.1)
				(type default)
			)
			(layer "F.SilkS")
		)
		(fp_line
			(start 24.682958 -3.76682)
			(end 24.67102 -3.697478)
			(stroke
				(width 0.1)
				(type default)
			)
			(layer "F.SilkS")
		)
		(fp_line
			(start 24.684736 -0.882904)
			(end 24.744934 -0.882904)
			(stroke
				(width 0.1)
				(type default)
			)
			(layer "F.SilkS")
		)
		(fp_line
			(start 24.684736 -0.882904)
			(end 24.744934 -0.882904)
			(stroke
				(width 0.1)
				(type default)
			)
			(layer "F.SilkS")
		)
		(fp_line
			(start 24.684736 -0.882904)
			(end 25.42921 -1.597406)
			(stroke
				(width 0.1)
				(type default)
			)
			(layer "F.SilkS")
		)
		(fp_line
			(start 24.684736 -0.882904)
			(end 25.42921 -1.597406)
			(stroke
				(width 0.1)
				(type default)
			)
			(layer "F.SilkS")
		)
		(fp_line
			(start 24.708866 -5.234432)
			(end 23.739856 -4.304792)
			(stroke
				(width 0.1)
				(type default)
			)
			(layer "F.SilkS")
		)
		(fp_line
			(start 24.708866 -5.234432)
			(end 23.739856 -4.304792)
			(stroke
				(width 0.1)
				(type default)
			)
			(layer "F.SilkS")
		)
		(fp_line
			(start 24.744934 -0.882904)
			(end 24.805386 -0.882904)
			(stroke
				(width 0.1)
				(type default)
			)
			(layer "F.SilkS")
		)
		(fp_line
			(start 24.744934 -0.882904)
			(end 24.805386 -0.882904)
			(stroke
				(width 0.1)
				(type default)
			)
			(layer "F.SilkS")
		)
		(fp_line
			(start 24.744934 -0.882904)
			(end 25.417272 -1.52781)
			(stroke
				(width 0.1)
				(type default)
			)
			(layer "F.SilkS")
		)
		(fp_line
			(start 24.744934 -0.882904)
			(end 25.417272 -1.52781)
			(stroke
				(width 0.1)
				(type default)
			)
			(layer "F.SilkS")
		)
		(fp_line
			(start 24.75738 -5.223256)
			(end 23.809452 -4.313936)
			(stroke
				(width 0.1)
				(type default)
			)
			(layer "F.SilkS")
		)
		(fp_line
			(start 24.75738 -5.223256)
			(end 23.809452 -4.313936)
			(stroke
				(width 0.1)
				(type default)
			)
			(layer "F.SilkS")
		)
		(fp_line
			(start 24.805386 -0.882904)
			(end 24.86533 -0.882904)
			(stroke
				(width 0.1)
				(type default)
			)
			(layer "F.SilkS")
		)
		(fp_line
			(start 24.805386 -0.882904)
			(end 24.86533 -0.882904)
			(stroke
				(width 0.1)
				(type default)
			)
			(layer "F.SilkS")
		)
		(fp_line
			(start 24.805386 -0.882904)
			(end 25.40508 -1.458214)
			(stroke
				(width 0.1)
				(type default)
			)
			(layer "F.SilkS")
		)
		(fp_line
			(start 24.805386 -0.882904)
			(end 25.40508 -1.458214)
			(stroke
				(width 0.1)
				(type default)
			)
			(layer "F.SilkS")
		)
		(fp_line
			(start 24.805894 -5.21208)
			(end 23.87473 -4.318762)
			(stroke
				(width 0.1)
				(type default)
			)
			(layer "F.SilkS")
		)
		(fp_line
			(start 24.805894 -5.21208)
			(end 23.87473 -4.318762)
			(stroke
				(width 0.1)
				(type default)
			)
			(layer "F.SilkS")
		)
		(fp_line
			(start 24.854154 -5.200904)
			(end 23.9395 -4.323334)
			(stroke
				(width 0.1)
				(type default)
			)
			(layer "F.SilkS")
		)
		(fp_line
			(start 24.854154 -5.200904)
			(end 23.9395 -4.323334)
			(stroke
				(width 0.1)
				(type default)
			)
			(layer "F.SilkS")
		)
		(fp_line
			(start 24.86533 -0.882904)
			(end 24.925274 -0.882904)
			(stroke
				(width 0.1)
				(type default)
			)
			(layer "F.SilkS")
		)
		(fp_line
			(start 24.86533 -0.882904)
			(end 24.925274 -0.882904)
			(stroke
				(width 0.1)
				(type default)
			)
			(layer "F.SilkS")
		)
		(fp_line
			(start 24.86533 -0.882904)
			(end 25.392634 -1.388872)
			(stroke
				(width 0.1)
				(type default)
			)
			(layer "F.SilkS")
		)
		(fp_line
			(start 24.86533 -0.882904)
			(end 25.392634 -1.388872)
			(stroke
				(width 0.1)
				(type default)
			)
			(layer "F.SilkS")
		)
		(fp_line
			(start 24.903176 -5.189728)
			(end 24.003254 -4.32689)
			(stroke
				(width 0.1)
				(type default)
			)
			(layer "F.SilkS")
		)
		(fp_line
			(start 24.903176 -5.189728)
			(end 24.003254 -4.32689)
			(stroke
				(width 0.1)
				(type default)
			)
			(layer "F.SilkS")
		)
		(fp_line
			(start 24.925274 -0.882904)
			(end 24.985472 -0.882904)
			(stroke
				(width 0.1)
				(type default)
			)
			(layer "F.SilkS")
		)
		(fp_line
			(start 24.925274 -0.882904)
			(end 24.985472 -0.882904)
			(stroke
				(width 0.1)
				(type default)
			)
			(layer "F.SilkS")
		)
		(fp_line
			(start 24.925274 -0.882904)
			(end 25.380696 -1.319784)
			(stroke
				(width 0.1)
				(type default)
			)
			(layer "F.SilkS")
		)
		(fp_line
			(start 24.925274 -0.882904)
			(end 25.380696 -1.319784)
			(stroke
				(width 0.1)
				(type default)
			)
			(layer "F.SilkS")
		)
		(fp_line
			(start 24.95169 -5.178552)
			(end 24.064976 -4.327906)
			(stroke
				(width 0.1)
				(type default)
			)
			(layer "F.SilkS")
		)
		(fp_line
			(start 24.95169 -5.178552)
			(end 24.064976 -4.327906)
			(stroke
				(width 0.1)
				(type default)
			)
			(layer "F.SilkS")
		)
		(fp_line
			(start 24.985472 -0.882904)
			(end 25.04567 -0.882904)
			(stroke
				(width 0.1)
				(type default)
			)
			(layer "F.SilkS")
		)
		(fp_line
			(start 24.985472 -0.882904)
			(end 25.04567 -0.882904)
			(stroke
				(width 0.1)
				(type default)
			)
			(layer "F.SilkS")
		)
		(fp_line
			(start 24.985472 -0.882904)
			(end 25.368504 -1.250188)
			(stroke
				(width 0.1)
				(type default)
			)
			(layer "F.SilkS")
		)
		(fp_line
			(start 24.985472 -0.882904)
			(end 25.368504 -1.250188)
			(stroke
				(width 0.1)
				(type default)
			)
			(layer "F.SilkS")
		)
		(fp_line
			(start 24.99995 -5.16763)
			(end 24.12619 -4.329176)
			(stroke
				(width 0.1)
				(type default)
			)
			(layer "F.SilkS")
		)
		(fp_line
			(start 24.99995 -5.16763)
			(end 24.12619 -4.329176)
			(stroke
				(width 0.1)
				(type default)
			)
			(layer "F.SilkS")
		)
		(fp_line
			(start 25.045162 -5.152898)
			(end 24.18588 -4.328922)
			(stroke
				(width 0.1)
				(type default)
			)
			(layer "F.SilkS")
		)
		(fp_line
			(start 25.045162 -5.152898)
			(end 24.18588 -4.328922)
			(stroke
				(width 0.1)
				(type default)
			)
			(layer "F.SilkS")
		)
		(fp_line
			(start 25.04567 -0.882904)
			(end 25.106122 -0.882904)
			(stroke
				(width 0.1)
				(type default)
			)
			(layer "F.SilkS")
		)
		(fp_line
			(start 25.04567 -0.882904)
			(end 25.106122 -0.882904)
			(stroke
				(width 0.1)
				(type default)
			)
			(layer "F.SilkS")
		)
		(fp_line
			(start 25.04567 -0.882904)
			(end 25.356058 -1.180592)
			(stroke
				(width 0.1)
				(type default)
			)
			(layer "F.SilkS")
		)
		(fp_line
			(start 25.04567 -0.882904)
			(end 25.356058 -1.180592)
			(stroke
				(width 0.1)
				(type default)
			)
			(layer "F.SilkS")
		)
		(fp_line
			(start 25.086056 -5.13461)
			(end 24.241252 -4.32435)
			(stroke
				(width 0.1)
				(type default)
			)
			(layer "F.SilkS")
		)
		(fp_line
			(start 25.086056 -5.13461)
			(end 24.241252 -4.32435)
			(stroke
				(width 0.1)
				(type default)
			)
			(layer "F.SilkS")
		)
		(fp_line
			(start 25.106122 -0.882904)
			(end 25.166066 -0.882904)
			(stroke
				(width 0.1)
				(type default)
			)
			(layer "F.SilkS")
		)
		(fp_line
			(start 25.106122 -0.882904)
			(end 25.166066 -0.882904)
			(stroke
				(width 0.1)
				(type default)
			)
			(layer "F.SilkS")
		)
		(fp_line
			(start 25.106122 -0.882904)
			(end 25.34412 -1.111504)
			(stroke
				(width 0.1)
				(type default)
			)
			(layer "F.SilkS")
		)
		(fp_line
			(start 25.106122 -0.882904)
			(end 25.34412 -1.111504)
			(stroke
				(width 0.1)
				(type default)
			)
			(layer "F.SilkS")
		)
		(fp_line
			(start 25.127458 -5.116322)
			(end 24.297132 -4.320032)
			(stroke
				(width 0.1)
				(type default)
			)
			(layer "F.SilkS")
		)
		(fp_line
			(start 25.127458 -5.116322)
			(end 24.297132 -4.320032)
			(stroke
				(width 0.1)
				(type default)
			)
			(layer "F.SilkS")
		)
		(fp_line
			(start 25.166066 -0.882904)
			(end 25.226264 -0.882904)
			(stroke
				(width 0.1)
				(type default)
			)
			(layer "F.SilkS")
		)
		(fp_line
			(start 25.166066 -0.882904)
			(end 25.226264 -0.882904)
			(stroke
				(width 0.1)
				(type default)
			)
			(layer "F.SilkS")
		)
		(fp_line
			(start 25.166066 -0.882904)
			(end 25.332182 -1.042416)
			(stroke
				(width 0.1)
				(type default)
			)
			(layer "F.SilkS")
		)
		(fp_line
			(start 25.166066 -0.882904)
			(end 25.332182 -1.042416)
			(stroke
				(width 0.1)
				(type default)
			)
			(layer "F.SilkS")
		)
		(fp_line
			(start 25.168352 -5.098034)
			(end 24.346408 -4.309618)
			(stroke
				(width 0.1)
				(type default)
			)
			(layer "F.SilkS")
		)
		(fp_line
			(start 25.168352 -5.098034)
			(end 24.346408 -4.309618)
			(stroke
				(width 0.1)
				(type default)
			)
			(layer "F.SilkS")
		)
		(fp_line
			(start 25.2095 -5.08)
			(end 24.393398 -4.296918)
			(stroke
				(width 0.1)
				(type default)
			)
			(layer "F.SilkS")
		)
		(fp_line
			(start 25.2095 -5.08)
			(end 24.393398 -4.296918)
			(stroke
				(width 0.1)
				(type default)
			)
			(layer "F.SilkS")
		)
		(fp_line
			(start 25.226264 -0.882904)
			(end 25.286462 -0.882904)
			(stroke
				(width 0.1)
				(type default)
			)
			(layer "F.SilkS")
		)
		(fp_line
			(start 25.226264 -0.882904)
			(end 25.286462 -0.882904)
			(stroke
				(width 0.1)
				(type default)
			)
			(layer "F.SilkS")
		)
		(fp_line
			(start 25.226264 -0.882904)
			(end 25.31999 -0.97282)
			(stroke
				(width 0.1)
				(type default)
			)
			(layer "F.SilkS")
		)
		(fp_line
			(start 25.226264 -0.882904)
			(end 25.31999 -0.97282)
			(stroke
				(width 0.1)
				(type default)
			)
			(layer "F.SilkS")
		)
		(fp_line
			(start 25.250648 -5.061712)
			(end 24.438356 -4.28244)
			(stroke
				(width 0.1)
				(type default)
			)
			(layer "F.SilkS")
		)
		(fp_line
			(start 25.250648 -5.061712)
			(end 24.438356 -4.28244)
			(stroke
				(width 0.1)
				(type default)
			)
			(layer "F.SilkS")
		)
		(fp_line
			(start 25.286462 -0.882904)
			(end 25.304242 -0.882904)
			(stroke
				(width 0.1)
				(type default)
			)
			(layer "F.SilkS")
		)
		(fp_line
			(start 25.286462 -0.882904)
			(end 25.304242 -0.882904)
			(stroke
				(width 0.1)
				(type default)
			)
			(layer "F.SilkS")
		)
		(fp_line
			(start 25.286462 -0.882904)
			(end 25.307544 -0.903224)
			(stroke
				(width 0.1)
				(type default)
			)
			(layer "F.SilkS")
		)
		(fp_line
			(start 25.286462 -0.882904)
			(end 25.307544 -0.903224)
			(stroke
				(width 0.1)
				(type default)
			)
			(layer "F.SilkS")
		)
		(fp_line
			(start 25.29205 -5.043424)
			(end 24.477726 -4.26212)
			(stroke
				(width 0.1)
				(type default)
			)
			(layer "F.SilkS")
		)
		(fp_line
			(start 25.29205 -5.043424)
			(end 24.477726 -4.26212)
			(stroke
				(width 0.1)
				(type default)
			)
			(layer "F.SilkS")
		)
		(fp_line
			(start 25.304242 -0.882904)
			(end 25.307544 -0.903224)
			(stroke
				(width 0.1)
				(type default)
			)
			(layer "F.SilkS")
		)
		(fp_line
			(start 25.304242 -0.882904)
			(end 25.307544 -0.903224)
			(stroke
				(width 0.1)
				(type default)
			)
			(layer "F.SilkS")
		)
		(fp_line
			(start 25.307544 -0.903224)
			(end 25.31999 -0.97282)
			(stroke
				(width 0.1)
				(type default)
			)
			(layer "F.SilkS")
		)
		(fp_line
			(start 25.307544 -0.903224)
			(end 25.31999 -0.97282)
			(stroke
				(width 0.1)
				(type default)
			)
			(layer "F.SilkS")
		)
		(fp_line
			(start 25.31999 -0.97282)
			(end 25.332182 -1.042416)
			(stroke
				(width 0.1)
				(type default)
			)
			(layer "F.SilkS")
		)
		(fp_line
			(start 25.31999 -0.97282)
			(end 25.332182 -1.042416)
			(stroke
				(width 0.1)
				(type default)
			)
			(layer "F.SilkS")
		)
		(fp_line
			(start 25.327356 -5.019294)
			(end 24.516334 -4.2418)
			(stroke
				(width 0.1)
				(type default)
			)
			(layer "F.SilkS")
		)
		(fp_line
			(start 25.327356 -5.019294)
			(end 24.516334 -4.2418)
			(stroke
				(width 0.1)
				(type default)
			)
			(layer "F.SilkS")
		)
		(fp_line
			(start 25.332182 -1.042416)
			(end 25.34412 -1.111504)
			(stroke
				(width 0.1)
				(type default)
			)
			(layer "F.SilkS")
		)
		(fp_line
			(start 25.332182 -1.042416)
			(end 25.34412 -1.111504)
			(stroke
				(width 0.1)
				(type default)
			)
			(layer "F.SilkS")
		)
		(fp_line
			(start 25.34412 -1.111504)
			(end 25.356058 -1.180592)
			(stroke
				(width 0.1)
				(type default)
			)
			(layer "F.SilkS")
		)
		(fp_line
			(start 25.34412 -1.111504)
			(end 25.356058 -1.180592)
			(stroke
				(width 0.1)
				(type default)
			)
			(layer "F.SilkS")
		)
		(fp_line
			(start 25.356058 -1.180592)
			(end 25.368504 -1.250188)
			(stroke
				(width 0.1)
				(type default)
			)
			(layer "F.SilkS")
		)
		(fp_line
			(start 25.356058 -1.180592)
			(end 25.368504 -1.250188)
			(stroke
				(width 0.1)
				(type default)
			)
			(layer "F.SilkS")
		)
		(fp_line
			(start 25.36063 -4.994148)
			(end 24.549354 -4.215892)
			(stroke
				(width 0.1)
				(type default)
			)
			(layer "F.SilkS")
		)
		(fp_line
			(start 25.36063 -4.994148)
			(end 24.549354 -4.215892)
			(stroke
				(width 0.1)
				(type default)
			)
			(layer "F.SilkS")
		)
		(fp_line
			(start 25.368504 -1.250188)
			(end 25.380696 -1.319784)
			(stroke
				(width 0.1)
				(type default)
			)
			(layer "F.SilkS")
		)
		(fp_line
			(start 25.368504 -1.250188)
			(end 25.380696 -1.319784)
			(stroke
				(width 0.1)
				(type default)
			)
			(layer "F.SilkS")
		)
		(fp_line
			(start 25.380696 -1.319784)
			(end 25.392634 -1.388872)
			(stroke
				(width 0.1)
				(type default)
			)
			(layer "F.SilkS")
		)
		(fp_line
			(start 25.380696 -1.319784)
			(end 25.392634 -1.388872)
			(stroke
				(width 0.1)
				(type default)
			)
			(layer "F.SilkS")
		)
		(fp_line
			(start 25.392634 -1.388872)
			(end 25.40508 -1.458214)
			(stroke
				(width 0.1)
				(type default)
			)
			(layer "F.SilkS")
		)
		(fp_line
			(start 25.392634 -1.388872)
			(end 25.40508 -1.458214)
			(stroke
				(width 0.1)
				(type default)
			)
			(layer "F.SilkS")
		)
		(fp_line
			(start 25.394412 -4.968494)
			(end 24.580596 -4.187952)
			(stroke
				(width 0.1)
				(type default)
			)
			(layer "F.SilkS")
		)
		(fp_line
			(start 25.394412 -4.968494)
			(end 24.580596 -4.187952)
			(stroke
				(width 0.1)
				(type default)
			)
			(layer "F.SilkS")
		)
		(fp_line
			(start 25.40508 -1.458214)
			(end 25.417272 -1.52781)
			(stroke
				(width 0.1)
				(type default)
			)
			(layer "F.SilkS")
		)
		(fp_line
			(start 25.40508 -1.458214)
			(end 25.417272 -1.52781)
			(stroke
				(width 0.1)
				(type default)
			)
			(layer "F.SilkS")
		)
		(fp_line
			(start 25.417272 -1.52781)
			(end 25.42921 -1.597406)
			(stroke
				(width 0.1)
				(type default)
			)
			(layer "F.SilkS")
		)
		(fp_line
			(start 25.417272 -1.52781)
			(end 25.42921 -1.597406)
			(stroke
				(width 0.1)
				(type default)
			)
			(layer "F.SilkS")
		)
		(fp_line
			(start 25.428194 -4.943094)
			(end 24.609044 -4.157218)
			(stroke
				(width 0.1)
				(type default)
			)
			(layer "F.SilkS")
		)
		(fp_line
			(start 25.428194 -4.943094)
			(end 24.609044 -4.157218)
			(stroke
				(width 0.1)
				(type default)
			)
			(layer "F.SilkS")
		)
		(fp_line
			(start 25.42921 -1.597406)
			(end 25.441656 -1.666494)
			(stroke
				(width 0.1)
				(type default)
			)
			(layer "F.SilkS")
		)
		(fp_line
			(start 25.42921 -1.597406)
			(end 25.441656 -1.666494)
			(stroke
				(width 0.1)
				(type default)
			)
			(layer "F.SilkS")
		)
		(fp_line
			(start 25.441656 -1.666494)
			(end 25.453594 -1.735836)
			(stroke
				(width 0.1)
				(type default)
			)
			(layer "F.SilkS")
		)
		(fp_line
			(start 25.441656 -1.666494)
			(end 25.453594 -1.735836)
			(stroke
				(width 0.1)
				(type default)
			)
			(layer "F.SilkS")
		)
		(fp_line
			(start 25.453594 -1.735836)
			(end 25.465786 -1.805178)
			(stroke
				(width 0.1)
				(type default)
			)
			(layer "F.SilkS")
		)
		(fp_line
			(start 25.453594 -1.735836)
			(end 25.465786 -1.805178)
			(stroke
				(width 0.1)
				(type default)
			)
			(layer "F.SilkS")
		)
		(fp_line
			(start 25.461722 -4.917694)
			(end 24.631904 -4.121912)
			(stroke
				(width 0.1)
				(type default)
			)
			(layer "F.SilkS")
		)
		(fp_line
			(start 25.461722 -4.917694)
			(end 24.631904 -4.121912)
			(stroke
				(width 0.1)
				(type default)
			)
			(layer "F.SilkS")
		)
		(fp_line
			(start 25.465786 -1.805178)
			(end 25.478232 -1.874774)
			(stroke
				(width 0.1)
				(type default)
			)
			(layer "F.SilkS")
		)
		(fp_line
			(start 25.465786 -1.805178)
			(end 25.478232 -1.874774)
			(stroke
				(width 0.1)
				(type default)
			)
			(layer "F.SilkS")
		)
		(fp_line
			(start 25.478232 -1.874774)
			(end 25.49017 -1.943862)
			(stroke
				(width 0.1)
				(type default)
			)
			(layer "F.SilkS")
		)
		(fp_line
			(start 25.478232 -1.874774)
			(end 25.49017 -1.943862)
			(stroke
				(width 0.1)
				(type default)
			)
			(layer "F.SilkS")
		)
		(fp_line
			(start 25.49017 -1.943862)
			(end 25.502362 -2.013204)
			(stroke
				(width 0.1)
				(type default)
			)
			(layer "F.SilkS")
		)
		(fp_line
			(start 25.49017 -1.943862)
			(end 25.502362 -2.013204)
			(stroke
				(width 0.1)
				(type default)
			)
			(layer "F.SilkS")
		)
		(fp_line
			(start 25.49525 -4.892294)
			(end 24.65451 -4.085844)
			(stroke
				(width 0.1)
				(type default)
			)
			(layer "F.SilkS")
		)
		(fp_line
			(start 25.49525 -4.892294)
			(end 24.65451 -4.085844)
			(stroke
				(width 0.1)
				(type default)
			)
			(layer "F.SilkS")
		)
		(fp_line
			(start 25.502362 -2.013204)
			(end 25.5143 -2.0828)
			(stroke
				(width 0.1)
				(type default)
			)
			(layer "F.SilkS")
		)
		(fp_line
			(start 25.502362 -2.013204)
			(end 25.5143 -2.0828)
			(stroke
				(width 0.1)
				(type default)
			)
			(layer "F.SilkS")
		)
		(fp_line
			(start 25.5143 -2.0828)
			(end 25.526746 -2.152142)
			(stroke
				(width 0.1)
				(type default)
			)
			(layer "F.SilkS")
		)
		(fp_line
			(start 25.5143 -2.0828)
			(end 25.526746 -2.152142)
			(stroke
				(width 0.1)
				(type default)
			)
			(layer "F.SilkS")
		)
		(fp_line
			(start 25.526746 -2.152142)
			(end 25.538684 -2.221484)
			(stroke
				(width 0.1)
				(type default)
			)
			(layer "F.SilkS")
		)
		(fp_line
			(start 25.526746 -2.152142)
			(end 25.538684 -2.221484)
			(stroke
				(width 0.1)
				(type default)
			)
			(layer "F.SilkS")
		)
		(fp_line
			(start 25.527508 -4.865624)
			(end 24.669242 -4.042156)
			(stroke
				(width 0.1)
				(type default)
			)
			(layer "F.SilkS")
		)
		(fp_line
			(start 25.527508 -4.865624)
			(end 24.669242 -4.042156)
			(stroke
				(width 0.1)
				(type default)
			)
			(layer "F.SilkS")
		)
		(fp_line
			(start 25.538684 -2.221484)
			(end 25.550876 -2.290826)
			(stroke
				(width 0.1)
				(type default)
			)
			(layer "F.SilkS")
		)
		(fp_line
			(start 25.538684 -2.221484)
			(end 25.550876 -2.290826)
			(stroke
				(width 0.1)
				(type default)
			)
			(layer "F.SilkS")
		)
		(fp_line
			(start 25.550876 -2.290826)
			(end 25.563322 -2.360422)
			(stroke
				(width 0.1)
				(type default)
			)
			(layer "F.SilkS")
		)
		(fp_line
			(start 25.550876 -2.290826)
			(end 25.563322 -2.360422)
			(stroke
				(width 0.1)
				(type default)
			)
			(layer "F.SilkS")
		)
		(fp_line
			(start 25.553162 -4.83235)
			(end 24.683974 -3.998722)
			(stroke
				(width 0.1)
				(type default)
			)
			(layer "F.SilkS")
		)
		(fp_line
			(start 25.553162 -4.83235)
			(end 24.683974 -3.998722)
			(stroke
				(width 0.1)
				(type default)
			)
			(layer "F.SilkS")
		)
		(fp_line
			(start 25.563322 -2.360422)
			(end 25.57526 -2.429764)
			(stroke
				(width 0.1)
				(type default)
			)
			(layer "F.SilkS")
		)
		(fp_line
			(start 25.563322 -2.360422)
			(end 25.57526 -2.429764)
			(stroke
				(width 0.1)
				(type default)
			)
			(layer "F.SilkS")
		)
		(fp_line
			(start 25.57526 -2.429764)
			(end 24.220424 -1.130046)
			(stroke
				(width 0.1)
				(type default)
			)
			(layer "F.SilkS")
		)
		(fp_line
			(start 25.57526 -2.429764)
			(end 24.220424 -1.130046)
			(stroke
				(width 0.1)
				(type default)
			)
			(layer "F.SilkS")
		)
		(fp_line
			(start 25.57526 -2.429764)
			(end 25.587452 -2.498852)
			(stroke
				(width 0.1)
				(type default)
			)
			(layer "F.SilkS")
		)
		(fp_line
			(start 25.57526 -2.429764)
			(end 25.587452 -2.498852)
			(stroke
				(width 0.1)
				(type default)
			)
			(layer "F.SilkS")
		)
		(fp_line
			(start 25.57907 -4.79933)
			(end 24.690324 -3.946652)
			(stroke
				(width 0.1)
				(type default)
			)
			(layer "F.SilkS")
		)
		(fp_line
			(start 25.57907 -4.79933)
			(end 24.690324 -3.946652)
			(stroke
				(width 0.1)
				(type default)
			)
			(layer "F.SilkS")
		)
		(fp_line
			(start 25.587452 -2.498852)
			(end 25.59939 -2.568194)
			(stroke
				(width 0.1)
				(type default)
			)
			(layer "F.SilkS")
		)
		(fp_line
			(start 25.587452 -2.498852)
			(end 25.59939 -2.568194)
			(stroke
				(width 0.1)
				(type default)
			)
			(layer "F.SilkS")
		)
		(fp_line
			(start 25.59939 -2.568194)
			(end 25.611836 -2.63779)
			(stroke
				(width 0.1)
				(type default)
			)
			(layer "F.SilkS")
		)
		(fp_line
			(start 25.59939 -2.568194)
			(end 25.611836 -2.63779)
			(stroke
				(width 0.1)
				(type default)
			)
			(layer "F.SilkS")
		)
		(fp_line
			(start 25.60447 -4.766564)
			(end 24.695658 -3.894328)
			(stroke
				(width 0.1)
				(type default)
			)
			(layer "F.SilkS")
		)
		(fp_line
			(start 25.60447 -4.766564)
			(end 24.695658 -3.894328)
			(stroke
				(width 0.1)
				(type default)
			)
			(layer "F.SilkS")
		)
		(fp_line
			(start 25.611836 -2.63779)
			(end 25.623774 -2.707132)
			(stroke
				(width 0.1)
				(type default)
			)
			(layer "F.SilkS")
		)
		(fp_line
			(start 25.611836 -2.63779)
			(end 25.623774 -2.707132)
			(stroke
				(width 0.1)
				(type default)
			)
			(layer "F.SilkS")
		)
		(fp_line
			(start 25.623774 -2.707132)
			(end 25.635966 -2.776474)
			(stroke
				(width 0.1)
				(type default)
			)
			(layer "F.SilkS")
		)
		(fp_line
			(start 25.623774 -2.707132)
			(end 25.635966 -2.776474)
			(stroke
				(width 0.1)
				(type default)
			)
			(layer "F.SilkS")
		)
		(fp_line
			(start 25.630378 -4.73329)
			(end 24.690324 -3.83159)
			(stroke
				(width 0.1)
				(type default)
			)
			(layer "F.SilkS")
		)
		(fp_line
			(start 25.630378 -4.73329)
			(end 24.690324 -3.83159)
			(stroke
				(width 0.1)
				(type default)
			)
			(layer "F.SilkS")
		)
		(fp_line
			(start 25.635966 -2.776474)
			(end 25.648412 -2.845816)
			(stroke
				(width 0.1)
				(type default)
			)
			(layer "F.SilkS")
		)
		(fp_line
			(start 25.635966 -2.776474)
			(end 25.648412 -2.845816)
			(stroke
				(width 0.1)
				(type default)
			)
			(layer "F.SilkS")
		)
		(fp_line
			(start 25.648412 -2.845816)
			(end 25.66035 -2.915412)
			(stroke
				(width 0.1)
				(type default)
			)
			(layer "F.SilkS")
		)
		(fp_line
			(start 25.648412 -2.845816)
			(end 25.66035 -2.915412)
			(stroke
				(width 0.1)
				(type default)
			)
			(layer "F.SilkS")
		)
		(fp_line
			(start 25.656286 -4.70027)
			(end 24.682958 -3.76682)
			(stroke
				(width 0.1)
				(type default)
			)
			(layer "F.SilkS")
		)
		(fp_line
			(start 25.656286 -4.70027)
			(end 24.682958 -3.76682)
			(stroke
				(width 0.1)
				(type default)
			)
			(layer "F.SilkS")
		)
		(fp_line
			(start 25.66035 -2.915412)
			(end 25.672542 -2.984754)
			(stroke
				(width 0.1)
				(type default)
			)
			(layer "F.SilkS")
		)
		(fp_line
			(start 25.66035 -2.915412)
			(end 25.672542 -2.984754)
			(stroke
				(width 0.1)
				(type default)
			)
			(layer "F.SilkS")
		)
		(fp_line
			(start 25.672542 -2.984754)
			(end 25.68448 -3.054096)
			(stroke
				(width 0.1)
				(type default)
			)
			(layer "F.SilkS")
		)
		(fp_line
			(start 25.672542 -2.984754)
			(end 25.68448 -3.054096)
			(stroke
				(width 0.1)
				(type default)
			)
			(layer "F.SilkS")
		)
		(fp_line
			(start 25.681686 -4.66725)
			(end 24.67102 -3.697478)
			(stroke
				(width 0.1)
				(type default)
			)
			(layer "F.SilkS")
		)
		(fp_line
			(start 25.681686 -4.66725)
			(end 24.67102 -3.697478)
			(stroke
				(width 0.1)
				(type default)
			)
			(layer "F.SilkS")
		)
		(fp_line
			(start 25.68448 -3.054096)
			(end 25.696926 -3.123184)
			(stroke
				(width 0.1)
				(type default)
			)
			(layer "F.SilkS")
		)
		(fp_line
			(start 25.68448 -3.054096)
			(end 25.696926 -3.123184)
			(stroke
				(width 0.1)
				(type default)
			)
			(layer "F.SilkS")
		)
		(fp_line
			(start 25.696926 -3.123184)
			(end 25.708864 -3.19278)
			(stroke
				(width 0.1)
				(type default)
			)
			(layer "F.SilkS")
		)
		(fp_line
			(start 25.696926 -3.123184)
			(end 25.708864 -3.19278)
			(stroke
				(width 0.1)
				(type default)
			)
			(layer "F.SilkS")
		)
		(fp_line
			(start 25.701498 -4.628388)
			(end 24.658574 -3.627882)
			(stroke
				(width 0.1)
				(type default)
			)
			(layer "F.SilkS")
		)
		(fp_line
			(start 25.701498 -4.628388)
			(end 24.658574 -3.627882)
			(stroke
				(width 0.1)
				(type default)
			)
			(layer "F.SilkS")
		)
		(fp_line
			(start 25.708864 -3.19278)
			(end 25.721056 -3.262122)
			(stroke
				(width 0.1)
				(type default)
			)
			(layer "F.SilkS")
		)
		(fp_line
			(start 25.708864 -3.19278)
			(end 25.721056 -3.262122)
			(stroke
				(width 0.1)
				(type default)
			)
			(layer "F.SilkS")
		)
		(fp_line
			(start 25.718516 -4.586986)
			(end 23.913084 -2.85496)
			(stroke
				(width 0.1)
				(type default)
			)
			(layer "F.SilkS")
		)
		(fp_line
			(start 25.718516 -4.586986)
			(end 23.913084 -2.85496)
			(stroke
				(width 0.1)
				(type default)
			)
			(layer "F.SilkS")
		)
		(fp_line
			(start 25.721056 -3.262122)
			(end 25.733502 -3.331464)
			(stroke
				(width 0.1)
				(type default)
			)
			(layer "F.SilkS")
		)
		(fp_line
			(start 25.721056 -3.262122)
			(end 25.733502 -3.331464)
			(stroke
				(width 0.1)
				(type default)
			)
			(layer "F.SilkS")
		)
		(fp_line
			(start 25.733502 -3.331464)
			(end 25.74544 -3.400806)
			(stroke
				(width 0.1)
				(type default)
			)
			(layer "F.SilkS")
		)
		(fp_line
			(start 25.733502 -3.331464)
			(end 25.74544 -3.400806)
			(stroke
				(width 0.1)
				(type default)
			)
			(layer "F.SilkS")
		)
		(fp_line
			(start 25.735534 -4.54533)
			(end 23.969472 -2.85115)
			(stroke
				(width 0.1)
				(type default)
			)
			(layer "F.SilkS")
		)
		(fp_line
			(start 25.735534 -4.54533)
			(end 23.969472 -2.85115)
			(stroke
				(width 0.1)
				(type default)
			)
			(layer "F.SilkS")
		)
		(fp_line
			(start 25.74544 -3.400806)
			(end 23.034752 -0.800608)
			(stroke
				(width 0.1)
				(type default)
			)
			(layer "F.SilkS")
		)
		(fp_line
			(start 25.74544 -3.400806)
			(end 23.034752 -0.800608)
			(stroke
				(width 0.1)
				(type default)
			)
			(layer "F.SilkS")
		)
		(fp_line
			(start 25.74544 -3.400806)
			(end 25.757632 -3.470402)
			(stroke
				(width 0.1)
				(type default)
			)
			(layer "F.SilkS")
		)
		(fp_line
			(start 25.74544 -3.400806)
			(end 25.757632 -3.470402)
			(stroke
				(width 0.1)
				(type default)
			)
			(layer "F.SilkS")
		)
		(fp_line
			(start 25.752298 -4.503928)
			(end 24.024336 -2.846324)
			(stroke
				(width 0.1)
				(type default)
			)
			(layer "F.SilkS")
		)
		(fp_line
			(start 25.752298 -4.503928)
			(end 24.024336 -2.846324)
			(stroke
				(width 0.1)
				(type default)
			)
			(layer "F.SilkS")
		)
		(fp_line
			(start 25.757632 -3.470402)
			(end 24.402796 -2.170938)
			(stroke
				(width 0.1)
				(type default)
			)
			(layer "F.SilkS")
		)
		(fp_line
			(start 25.757632 -3.470402)
			(end 24.402796 -2.170938)
			(stroke
				(width 0.1)
				(type default)
			)
			(layer "F.SilkS")
		)
		(fp_line
			(start 25.757632 -3.470402)
			(end 25.769824 -3.539744)
			(stroke
				(width 0.1)
				(type default)
			)
			(layer "F.SilkS")
		)
		(fp_line
			(start 25.757632 -3.470402)
			(end 25.769824 -3.539744)
			(stroke
				(width 0.1)
				(type default)
			)
			(layer "F.SilkS")
		)
		(fp_line
			(start 25.769316 -4.46278)
			(end 24.076914 -2.839466)
			(stroke
				(width 0.1)
				(type default)
			)
			(layer "F.SilkS")
		)
		(fp_line
			(start 25.769316 -4.46278)
			(end 24.076914 -2.839466)
			(stroke
				(width 0.1)
				(type default)
			)
			(layer "F.SilkS")
		)
		(fp_line
			(start 25.769824 -3.539744)
			(end 24.414988 -2.24028)
			(stroke
				(width 0.1)
				(type default)
			)
			(layer "F.SilkS")
		)
		(fp_line
			(start 25.769824 -3.539744)
			(end 24.414988 -2.24028)
			(stroke
				(width 0.1)
				(type default)
			)
			(layer "F.SilkS")
		)
		(fp_line
			(start 25.769824 -3.539744)
			(end 25.782016 -3.609086)
			(stroke
				(width 0.1)
				(type default)
			)
			(layer "F.SilkS")
		)
		(fp_line
			(start 25.769824 -3.539744)
			(end 25.782016 -3.609086)
			(stroke
				(width 0.1)
				(type default)
			)
			(layer "F.SilkS")
		)
		(fp_line
			(start 25.782016 -3.609086)
			(end 24.427434 -2.309368)
			(stroke
				(width 0.1)
				(type default)
			)
			(layer "F.SilkS")
		)
		(fp_line
			(start 25.782016 -3.609086)
			(end 24.427434 -2.309368)
			(stroke
				(width 0.1)
				(type default)
			)
			(layer "F.SilkS")
		)
		(fp_line
			(start 25.782016 -3.609086)
			(end 25.793954 -3.678174)
			(stroke
				(width 0.1)
				(type default)
			)
			(layer "F.SilkS")
		)
		(fp_line
			(start 25.782016 -3.609086)
			(end 25.793954 -3.678174)
			(stroke
				(width 0.1)
				(type default)
			)
			(layer "F.SilkS")
		)
		(fp_line
			(start 25.786588 -4.421378)
			(end 24.12873 -2.831084)
			(stroke
				(width 0.1)
				(type default)
			)
			(layer "F.SilkS")
		)
		(fp_line
			(start 25.786588 -4.421378)
			(end 24.12873 -2.831084)
			(stroke
				(width 0.1)
				(type default)
			)
			(layer "F.SilkS")
		)
		(fp_line
			(start 25.793954 -3.678174)
			(end 24.439372 -2.37871)
			(stroke
				(width 0.1)
				(type default)
			)
			(layer "F.SilkS")
		)
		(fp_line
			(start 25.793954 -3.678174)
			(end 24.439372 -2.37871)
			(stroke
				(width 0.1)
				(type default)
			)
			(layer "F.SilkS")
		)
		(fp_line
			(start 25.793954 -3.678174)
			(end 25.806146 -3.74777)
			(stroke
				(width 0.1)
				(type default)
			)
			(layer "F.SilkS")
		)
		(fp_line
			(start 25.793954 -3.678174)
			(end 25.806146 -3.74777)
			(stroke
				(width 0.1)
				(type default)
			)
			(layer "F.SilkS")
		)
		(fp_line
			(start 25.798526 -4.37515)
			(end 24.17826 -2.82067)
			(stroke
				(width 0.1)
				(type default)
			)
			(layer "F.SilkS")
		)
		(fp_line
			(start 25.798526 -4.37515)
			(end 24.17826 -2.82067)
			(stroke
				(width 0.1)
				(type default)
			)
			(layer "F.SilkS")
		)
		(fp_line
			(start 25.805384 -4.324096)
			(end 24.225504 -2.808478)
			(stroke
				(width 0.1)
				(type default)
			)
			(layer "F.SilkS")
		)
		(fp_line
			(start 25.805384 -4.324096)
			(end 24.225504 -2.808478)
			(stroke
				(width 0.1)
				(type default)
			)
			(layer "F.SilkS")
		)
		(fp_line
			(start 25.806146 -3.74777)
			(end 24.451564 -2.448306)
			(stroke
				(width 0.1)
				(type default)
			)
			(layer "F.SilkS")
		)
		(fp_line
			(start 25.806146 -3.74777)
			(end 24.451564 -2.448306)
			(stroke
				(width 0.1)
				(type default)
			)
			(layer "F.SilkS")
		)
		(fp_line
			(start 25.812242 -4.273296)
			(end 24.27097 -2.794508)
			(stroke
				(width 0.1)
				(type default)
			)
			(layer "F.SilkS")
		)
		(fp_line
			(start 25.812242 -4.273296)
			(end 24.27097 -2.794508)
			(stroke
				(width 0.1)
				(type default)
			)
			(layer "F.SilkS")
		)
		(fp_line
			(start 25.81275 -3.811524)
			(end 24.46401 -2.517648)
			(stroke
				(width 0.1)
				(type default)
			)
			(layer "F.SilkS")
		)
		(fp_line
			(start 25.81275 -3.811524)
			(end 24.46401 -2.517648)
			(stroke
				(width 0.1)
				(type default)
			)
			(layer "F.SilkS")
		)
		(fp_line
			(start 25.817576 -3.874008)
			(end 24.475948 -2.58699)
			(stroke
				(width 0.1)
				(type default)
			)
			(layer "F.SilkS")
		)
		(fp_line
			(start 25.817576 -3.874008)
			(end 24.475948 -2.58699)
			(stroke
				(width 0.1)
				(type default)
			)
			(layer "F.SilkS")
		)
		(fp_line
			(start 25.819608 -4.222242)
			(end 24.31415 -2.777998)
			(stroke
				(width 0.1)
				(type default)
			)
			(layer "F.SilkS")
		)
		(fp_line
			(start 25.819608 -4.222242)
			(end 24.31415 -2.777998)
			(stroke
				(width 0.1)
				(type default)
			)
			(layer "F.SilkS")
		)
		(fp_line
			(start 25.822656 -3.936492)
			(end 24.487886 -2.656332)
			(stroke
				(width 0.1)
				(type default)
			)
			(layer "F.SilkS")
		)
		(fp_line
			(start 25.822656 -3.936492)
			(end 24.487886 -2.656332)
			(stroke
				(width 0.1)
				(type default)
			)
			(layer "F.SilkS")
		)
		(fp_line
			(start 25.826466 -4.170934)
			(end 24.35606 -2.760472)
			(stroke
				(width 0.1)
				(type default)
			)
			(layer "F.SilkS")
		)
		(fp_line
			(start 25.826466 -4.170934)
			(end 24.35606 -2.760472)
			(stroke
				(width 0.1)
				(type default)
			)
			(layer "F.SilkS")
		)
		(fp_line
			(start 25.827736 -3.99923)
			(end 24.468836 -2.695448)
			(stroke
				(width 0.1)
				(type default)
			)
			(layer "F.SilkS")
		)
		(fp_line
			(start 25.827736 -3.99923)
			(end 24.468836 -2.695448)
			(stroke
				(width 0.1)
				(type default)
			)
			(layer "F.SilkS")
		)
		(fp_line
			(start 25.83307 -4.062222)
			(end 24.432514 -2.718816)
			(stroke
				(width 0.1)
				(type default)
			)
			(layer "F.SilkS")
		)
		(fp_line
			(start 25.83307 -4.062222)
			(end 24.432514 -2.718816)
			(stroke
				(width 0.1)
				(type default)
			)
			(layer "F.SilkS")
		)
		(fp_line
			(start 25.833324 -4.120134)
			(end 24.394668 -2.739898)
			(stroke
				(width 0.1)
				(type default)
			)
			(layer "F.SilkS")
		)
		(fp_line
			(start 25.833324 -4.120134)
			(end 24.394668 -2.739898)
			(stroke
				(width 0.1)
				(type default)
			)
			(layer "F.SilkS")
		)
	)
	(footprint ""
		(layer "F.Cu")
		(at 62.261242 -343.952322 90)
		(property "Reference" "C130"
			(at 0 0 90)
			(layer "F.SilkS")
			(hide yes)
			(effects
				(font
					(size 1.27 1.27)
				)
			)
		)
		(property "Value" ""
			(at 0 0 90)
			(layer "F.Fab")
			(effects
				(font
					(size 1.27 1.27)
				)
			)
		)
		(duplicate_pad_numbers_are_jumpers no)
		(fp_line
			(start 0.299974 -0.150114)
			(end 0.299974 0.150114)
			(stroke
				(width 0.1)
				(type default)
			)
			(layer "F.Fab")
		)
		(fp_line
			(start -0.299974 -0.150114)
			(end 0.299974 -0.150114)
			(stroke
				(width 0.1)
				(type default)
			)
			(layer "F.Fab")
		)
		(fp_line
			(start 0.299974 0.150114)
			(end -0.299974 0.150114)
			(stroke
				(width 0.1)
				(type default)
			)
			(layer "F.Fab")
		)
		(fp_line
			(start -0.299974 0.150114)
			(end -0.299974 -0.150114)
			(stroke
				(width 0.1)
				(type default)
			)
			(layer "F.Fab")
		)
		(pad "1" smd rect
			(at -0.2667 0 90)
			(size 0.3048 0.381)
			(layers "F.Cu" "F.Mask" "F.Paste")
			(net "P5E_PEX0_STN6_TX_DN<111>")
		)
		(pad "2" smd rect
			(at 0.2667 0 90)
			(size 0.3048 0.381)
			(layers "F.Cu" "F.Mask" "F.Paste")
			(net "P5E_PEX0_STN6_TX_C_DN<111>")
		)
	)
	(footprint ""
		(layer "F.Cu")
		(at 333.762604 -100.406708 -90)
		(property "Reference" "PC319"
			(at 0 0 270)
			(layer "F.SilkS")
			(hide yes)
			(effects
				(font
					(size 1.27 1.27)
				)
			)
		)
		(property "Value" ""
			(at 0 0 270)
			(layer "F.Fab")
			(effects
				(font
					(size 1.27 1.27)
				)
			)
		)
		(duplicate_pad_numbers_are_jumpers no)
		(fp_line
			(start -1.524 0.762)
			(end -1.524 -0.762)
			(stroke
				(width 0.1524)
				(type default)
			)
			(layer "F.SilkS")
		)
		(fp_line
			(start 1.524 0.762)
			(end -1.524 0.762)
			(stroke
				(width 0.1524)
				(type default)
			)
			(layer "F.SilkS")
		)
		(fp_line
			(start -1.524 -0.762)
			(end 1.524 -0.762)
			(stroke
				(width 0.1524)
				(type default)
			)
			(layer "F.SilkS")
		)
		(fp_line
			(start 1.524 -0.762)
			(end 1.524 0.762)
			(stroke
				(width 0.1524)
				(type default)
			)
			(layer "F.SilkS")
		)
		(fp_line
			(start -1.1049 0.724916)
			(end 1.1049 0.724916)
			(stroke
				(width 0.1)
				(type default)
			)
			(layer "F.Fab")
		)
		(fp_line
			(start 1.1049 0.724916)
			(end 1.1049 -0.724916)
			(stroke
				(width 0.1)
				(type default)
			)
			(layer "F.Fab")
		)
		(fp_line
			(start -1.1049 -0.724916)
			(end -1.1049 0.724916)
			(stroke
				(width 0.1)
				(type default)
			)
			(layer "F.Fab")
		)
		(fp_line
			(start 1.1049 -0.724916)
			(end -1.1049 -0.724916)
			(stroke
				(width 0.1)
				(type default)
			)
			(layer "F.Fab")
		)
		(pad "1" smd rect
			(at -0.889 0 90)
			(size 1.016 1.27)
			(layers "F.Cu" "F.Mask" "F.Paste")
			(net "GND")
		)
		(pad "2" smd rect
			(at 0.889 0 90)
			(size 1.016 1.27)
			(layers "F.Cu" "F.Mask" "F.Paste")
			(net "P12V_AUX")
		)
	)
	(footprint ""
		(layer "F.Cu")
		(at 280.307542 -350.098614 90)
		(property "Reference" "C601"
			(at 0 0 90)
			(layer "F.SilkS")
			(hide yes)
			(effects
				(font
					(size 1.27 1.27)
				)
			)
		)
		(property "Value" ""
			(at 0 0 90)
			(layer "F.Fab")
			(effects
				(font
					(size 1.27 1.27)
				)
			)
		)
		(duplicate_pad_numbers_are_jumpers no)
		(fp_line
			(start 0.299974 -0.150114)
			(end 0.299974 0.150114)
			(stroke
				(width 0.1)
				(type default)
			)
			(layer "F.Fab")
		)
		(fp_line
			(start -0.299974 -0.150114)
			(end 0.299974 -0.150114)
			(stroke
				(width 0.1)
				(type default)
			)
			(layer "F.Fab")
		)
		(fp_line
			(start 0.299974 0.150114)
			(end -0.299974 0.150114)
			(stroke
				(width 0.1)
				(type default)
			)
			(layer "F.Fab")
		)
		(fp_line
			(start -0.299974 0.150114)
			(end -0.299974 -0.150114)
			(stroke
				(width 0.1)
				(type default)
			)
			(layer "F.Fab")
		)
		(pad "1" smd rect
			(at -0.2667 0 90)
			(size 0.3048 0.381)
			(layers "F.Cu" "F.Mask" "F.Paste")
			(net "P5E_PEX2_STN7_TX_DP<118>")
		)
		(pad "2" smd rect
			(at 0.2667 0 90)
			(size 0.3048 0.381)
			(layers "F.Cu" "F.Mask" "F.Paste")
			(net "P5E_PEX2_STN7_TX_C_DP<118>")
		)
	)
	(footprint ""
		(layer "F.Cu")
		(at 31.698692 -309.570628 45)
		(property "Reference" "R1169"
			(at 0 0 45)
			(layer "F.SilkS")
			(hide yes)
			(effects
				(font
					(size 1.27 1.27)
				)
			)
		)
		(property "Value" ""
			(at 0 0 45)
			(layer "F.Fab")
			(effects
				(font
					(size 1.27 1.27)
				)
			)
		)
		(duplicate_pad_numbers_are_jumpers no)
		(fp_line
			(start -0.787389 -0.406267)
			(end 0.787389 -0.406267)
			(stroke
				(width 0.1524)
				(type default)
			)
			(layer "F.SilkS")
		)
		(fp_line
			(start -0.787389 0.406267)
			(end -0.787389 -0.406267)
			(stroke
				(width 0.1524)
				(type default)
			)
			(layer "F.SilkS")
		)
		(fp_line
			(start 0.787389 -0.406267)
			(end 0.787389 0.406267)
			(stroke
				(width 0.1524)
				(type default)
			)
			(layer "F.SilkS")
		)
		(fp_line
			(start 0.787389 0.406267)
			(end -0.787389 0.406267)
			(stroke
				(width 0.1524)
				(type default)
			)
			(layer "F.SilkS")
		)
		(fp_line
			(start -0.679446 -0.305149)
			(end -0.120695 -0.304969)
			(stroke
				(width 0.1)
				(type default)
			)
			(layer "F.Fab")
		)
		(fp_line
			(start -0.120695 -0.304969)
			(end -0.120695 -0.279466)
			(stroke
				(width 0.1)
				(type default)
			)
			(layer "F.Fab")
		)
		(fp_line
			(start -0.120695 -0.279466)
			(end 0.120695 -0.279466)
			(stroke
				(width 0.1)
				(type default)
			)
			(layer "F.Fab")
		)
		(fp_line
			(start -0.679446 0.30479)
			(end -0.679446 -0.305149)
			(stroke
				(width 0.1)
				(type default)
			)
			(layer "F.Fab")
		)
		(fp_line
			(start 0.120515 -0.30479)
			(end 0.679446 -0.30479)
			(stroke
				(width 0.1)
				(type default)
			)
			(layer "F.Fab")
		)
		(fp_line
			(start 0.120695 -0.279466)
			(end 0.120515 -0.30479)
			(stroke
				(width 0.1)
				(type default)
			)
			(layer "F.Fab")
		)
		(fp_line
			(start -0.120695 0.279466)
			(end -0.120515 0.30479)
			(stroke
				(width 0.1)
				(type default)
			)
			(layer "F.Fab")
		)
		(fp_line
			(start -0.120515 0.30479)
			(end -0.679446 0.30479)
			(stroke
				(width 0.1)
				(type default)
			)
			(layer "F.Fab")
		)
		(fp_line
			(start 0.679446 -0.30479)
			(end 0.679446 0.30479)
			(stroke
				(width 0.1)
				(type default)
			)
			(layer "F.Fab")
		)
		(fp_line
			(start 0.120335 0.279466)
			(end -0.120695 0.279466)
			(stroke
				(width 0.1)
				(type default)
			)
			(layer "F.Fab")
		)
		(fp_line
			(start 0.120515 0.30479)
			(end 0.120335 0.279466)
			(stroke
				(width 0.1)
				(type default)
			)
			(layer "F.Fab")
		)
		(fp_line
			(start 0.679446 0.30479)
			(end 0.120515 0.30479)
			(stroke
				(width 0.1)
				(type default)
			)
			(layer "F.Fab")
		)
		(pad "1" smd circle
			(at -0.40005 0 45)
			(size 0 0)
			(layers "F.Cu" "F.Mask" "F.Paste")
			(net "GND")
		)
		(pad "2" smd circle
			(at 0.40005 0 45)
			(size 0 0)
			(layers "F.Cu" "F.Mask" "F.Paste")
			(net "PEX0_DBG_MODE0")
		)
	)
	(footprint ""
		(layer "F.Cu")
		(at 38.608 -155.3464 180)
		(property "Reference" "R14"
			(at 0 0 180)
			(layer "F.SilkS")
			(hide yes)
			(effects
				(font
					(size 1.27 1.27)
				)
			)
		)
		(property "Value" ""
			(at 0 0 180)
			(layer "F.Fab")
			(effects
				(font
					(size 1.27 1.27)
				)
			)
		)
		(duplicate_pad_numbers_are_jumpers no)
		(fp_line
			(start 0.7874 0.4064)
			(end -0.7874 0.4064)
			(stroke
				(width 0.1524)
				(type default)
			)
			(layer "F.SilkS")
		)
		(fp_line
			(start 0.7874 -0.4064)
			(end 0.7874 0.4064)
			(stroke
				(width 0.1524)
				(type default)
			)
			(layer "F.SilkS")
		)
		(fp_line
			(start -0.7874 0.4064)
			(end -0.7874 -0.4064)
			(stroke
				(width 0.1524)
				(type default)
			)
			(layer "F.SilkS")
		)
		(fp_line
			(start -0.7874 -0.4064)
			(end 0.7874 -0.4064)
			(stroke
				(width 0.1524)
				(type default)
			)
			(layer "F.SilkS")
		)
		(fp_line
			(start 0.67945 0.3048)
			(end 0.120396 0.3048)
			(stroke
				(width 0.1)
				(type default)
			)
			(layer "F.Fab")
		)
		(fp_line
			(start 0.67945 -0.3048)
			(end 0.67945 0.3048)
			(stroke
				(width 0.1)
				(type default)
			)
			(layer "F.Fab")
		)
		(fp_line
			(start 0.12065 -0.2794)
			(end 0.12065 -0.3048)
			(stroke
				(width 0.1)
				(type default)
			)
			(layer "F.Fab")
		)
		(fp_line
			(start 0.12065 -0.3048)
			(end 0.67945 -0.3048)
			(stroke
				(width 0.1)
				(type default)
			)
			(layer "F.Fab")
		)
		(fp_line
			(start 0.120396 0.3048)
			(end 0.120396 0.2794)
			(stroke
				(width 0.1)
				(type default)
			)
			(layer "F.Fab")
		)
		(fp_line
			(start 0.120396 0.2794)
			(end -0.12065 0.2794)
			(stroke
				(width 0.1)
				(type default)
			)
			(layer "F.Fab")
		)
		(fp_line
			(start -0.12065 0.3048)
			(end -0.67945 0.3048)
			(stroke
				(width 0.1)
				(type default)
			)
			(layer "F.Fab")
		)
		(fp_line
			(start -0.12065 0.2794)
			(end -0.12065 0.3048)
			(stroke
				(width 0.1)
				(type default)
			)
			(layer "F.Fab")
		)
		(fp_line
			(start -0.12065 -0.2794)
			(end 0.12065 -0.2794)
			(stroke
				(width 0.1)
				(type default)
			)
			(layer "F.Fab")
		)
		(fp_line
			(start -0.12065 -0.305054)
			(end -0.12065 -0.2794)
			(stroke
				(width 0.1)
				(type default)
			)
			(layer "F.Fab")
		)
		(fp_line
			(start -0.67945 0.3048)
			(end -0.67945 -0.305054)
			(stroke
				(width 0.1)
				(type default)
			)
			(layer "F.Fab")
		)
		(fp_line
			(start -0.67945 -0.305054)
			(end -0.12065 -0.305054)
			(stroke
				(width 0.1)
				(type default)
			)
			(layer "F.Fab")
		)
		(pad "1" smd circle
			(at -0.40005 0 180)
			(size 0 0)
			(layers "F.Cu" "F.Mask" "F.Paste")
			(net "NIC0_CLK")
		)
		(pad "2" smd circle
			(at 0.40005 0 180)
			(size 0 0)
			(layers "F.Cu" "F.Mask" "F.Paste")
			(net "GND")
		)
	)
	(footprint ""
		(layer "F.Cu")
		(at 245.421658 -129.799334 180)
		(property "Reference" "PD92"
			(at 5.036058 2.584196 0)
			(unlocked yes)
			(layer "F.SilkS")
			(effects
				(font
					(size 0.7874 0.5842)
					(thickness 0.1524)
				)
				(justify left)
			)
		)
		(property "Value" ""
			(at 0 0 180)
			(layer "F.Fab")
			(effects
				(font
					(size 1.27 1.27)
				)
			)
		)
		(duplicate_pad_numbers_are_jumpers no)
		(fp_line
			(start 4.240784 1.970024)
			(end 4.240784 -1.970024)
			(stroke
				(width 0.1524)
				(type default)
			)
			(layer "F.SilkS")
		)
		(fp_line
			(start 4.240784 -1.970024)
			(end -3.656584 -1.970024)
			(stroke
				(width 0.1524)
				(type default)
			)
			(layer "F.SilkS")
		)
		(fp_line
			(start -3.656584 1.970024)
			(end 4.240784 1.970024)
			(stroke
				(width 0.1524)
				(type default)
			)
			(layer "F.SilkS")
		)
		(fp_line
			(start -3.656584 -1.970024)
			(end -3.656584 1.970024)
			(stroke
				(width 0.1524)
				(type default)
			)
			(layer "F.SilkS")
		)
		(fp_poly
			(pts
				(xy 3.580384 1.970024) (xy 3.580384 -1.970024) (xy 4.240784 -1.970024) (xy 4.240784 1.970024)
			)
			(stroke
				(width 0)
				(type default)
			)
			(fill yes)
			(layer "F.SilkS")
		)
		(fp_line
			(start 2.3749 1.970024)
			(end 2.3749 -1.970024)
			(stroke
				(width 0.1)
				(type default)
			)
			(layer "F.Fab")
		)
		(fp_line
			(start 2.3749 -1.970024)
			(end -2.3749 -1.970024)
			(stroke
				(width 0.1)
				(type default)
			)
			(layer "F.Fab")
		)
		(fp_line
			(start -2.3749 1.970024)
			(end 2.3749 1.970024)
			(stroke
				(width 0.1)
				(type default)
			)
			(layer "F.Fab")
		)
		(fp_line
			(start -2.3749 -1.970024)
			(end -2.3749 1.970024)
			(stroke
				(width 0.1)
				(type default)
			)
			(layer "F.Fab")
		)
		(fp_text user "-"
			(at 4.1656 -0.23495 180)
			(unlocked yes)
			(layer "F.Fab")
			(effects
				(font
					(size 1.905 1.4224)
					(thickness 0.1524)
				)
				(justify left)
			)
		)
		(fp_text user "+"
			(at -4.9784 -0.23495 180)
			(unlocked yes)
			(layer "F.Fab")
			(effects
				(font
					(size 1.905 1.4224)
					(thickness 0.1524)
				)
				(justify left)
			)
		)
		(pad "A" smd rect
			(at -2.450084 0 180)
			(size 2.159 2.2606)
			(layers "F.Cu" "F.Mask" "F.Paste")
			(net "GND")
		)
		(pad "C" smd rect
			(at 2.450084 0 180)
			(size 2.159 2.2606)
			(layers "F.Cu" "F.Mask" "F.Paste")
			(net "P12V_AUX")
		)
	)
	(footprint ""
		(layer "F.Cu")
		(at 365.506 -195.707 180)
		(property "Reference" "R4691"
			(at 0 0 180)
			(layer "F.SilkS")
			(hide yes)
			(effects
				(font
					(size 1.27 1.27)
				)
			)
		)
		(property "Value" ""
			(at 0 0 180)
			(layer "F.Fab")
			(effects
				(font
					(size 1.27 1.27)
				)
			)
		)
		(duplicate_pad_numbers_are_jumpers no)
		(fp_line
			(start 0.7874 0.4064)
			(end -0.7874 0.4064)
			(stroke
				(width 0.1524)
				(type default)
			)
			(layer "F.SilkS")
		)
		(fp_line
			(start 0.7874 -0.4064)
			(end 0.7874 0.4064)
			(stroke
				(width 0.1524)
				(type default)
			)
			(layer "F.SilkS")
		)
		(fp_line
			(start -0.7874 0.4064)
			(end -0.7874 -0.4064)
			(stroke
				(width 0.1524)
				(type default)
			)
			(layer "F.SilkS")
		)
		(fp_line
			(start -0.7874 -0.4064)
			(end 0.7874 -0.4064)
			(stroke
				(width 0.1524)
				(type default)
			)
			(layer "F.SilkS")
		)
		(fp_line
			(start 0.67945 0.3048)
			(end 0.120396 0.3048)
			(stroke
				(width 0.1)
				(type default)
			)
			(layer "F.Fab")
		)
		(fp_line
			(start 0.67945 -0.3048)
			(end 0.67945 0.3048)
			(stroke
				(width 0.1)
				(type default)
			)
			(layer "F.Fab")
		)
		(fp_line
			(start 0.12065 -0.2794)
			(end 0.12065 -0.3048)
			(stroke
				(width 0.1)
				(type default)
			)
			(layer "F.Fab")
		)
		(fp_line
			(start 0.12065 -0.3048)
			(end 0.67945 -0.3048)
			(stroke
				(width 0.1)
				(type default)
			)
			(layer "F.Fab")
		)
		(fp_line
			(start 0.120396 0.3048)
			(end 0.120396 0.2794)
			(stroke
				(width 0.1)
				(type default)
			)
			(layer "F.Fab")
		)
		(fp_line
			(start 0.120396 0.2794)
			(end -0.12065 0.2794)
			(stroke
				(width 0.1)
				(type default)
			)
			(layer "F.Fab")
		)
		(fp_line
			(start -0.12065 0.3048)
			(end -0.67945 0.3048)
			(stroke
				(width 0.1)
				(type default)
			)
			(layer "F.Fab")
		)
		(fp_line
			(start -0.12065 0.2794)
			(end -0.12065 0.3048)
			(stroke
				(width 0.1)
				(type default)
			)
			(layer "F.Fab")
		)
		(fp_line
			(start -0.12065 -0.2794)
			(end 0.12065 -0.2794)
			(stroke
				(width 0.1)
				(type default)
			)
			(layer "F.Fab")
		)
		(fp_line
			(start -0.12065 -0.305054)
			(end -0.12065 -0.2794)
			(stroke
				(width 0.1)
				(type default)
			)
			(layer "F.Fab")
		)
		(fp_line
			(start -0.67945 0.3048)
			(end -0.67945 -0.305054)
			(stroke
				(width 0.1)
				(type default)
			)
			(layer "F.Fab")
		)
		(fp_line
			(start -0.67945 -0.305054)
			(end -0.12065 -0.305054)
			(stroke
				(width 0.1)
				(type default)
			)
			(layer "F.Fab")
		)
		(pad "1" smd circle
			(at -0.40005 0 180)
			(size 0 0)
			(layers "F.Cu" "F.Mask" "F.Paste")
			(net "SSD5_PEX_PWR_EN")
		)
		(pad "2" smd circle
			(at 0.40005 0 180)
			(size 0 0)
			(layers "F.Cu" "F.Mask" "F.Paste")
			(net "SSD5_PEX_PWR_EN_R")
		)
	)
	(footprint ""
		(layer "F.Cu")
		(at 296.766742 -350.098614 90)
		(property "Reference" "C2368"
			(at 0 0 90)
			(layer "F.SilkS")
			(hide yes)
			(effects
				(font
					(size 1.27 1.27)
				)
			)
		)
		(property "Value" ""
			(at 0 0 90)
			(layer "F.Fab")
			(effects
				(font
					(size 1.27 1.27)
				)
			)
		)
		(duplicate_pad_numbers_are_jumpers no)
		(fp_line
			(start 0.299974 -0.150114)
			(end 0.299974 0.150114)
			(stroke
				(width 0.1)
				(type default)
			)
			(layer "F.Fab")
		)
		(fp_line
			(start -0.299974 -0.150114)
			(end 0.299974 -0.150114)
			(stroke
				(width 0.1)
				(type default)
			)
			(layer "F.Fab")
		)
		(fp_line
			(start 0.299974 0.150114)
			(end -0.299974 0.150114)
			(stroke
				(width 0.1)
				(type default)
			)
			(layer "F.Fab")
		)
		(fp_line
			(start -0.299974 0.150114)
			(end -0.299974 -0.150114)
			(stroke
				(width 0.1)
				(type default)
			)
			(layer "F.Fab")
		)
		(pad "1" smd rect
			(at -0.2667 0 90)
			(size 0.3048 0.381)
			(layers "F.Cu" "F.Mask" "F.Paste")
			(net "P5E_PEX2_STN4_TX_DN<66>")
		)
		(pad "2" smd rect
			(at 0.2667 0 90)
			(size 0.3048 0.381)
			(layers "F.Cu" "F.Mask" "F.Paste")
			(net "P5E_PEX2_STN4_TX_C_DN<66>")
		)
	)
	(footprint ""
		(layer "F.Cu")
		(at 324.913244 -343.952322 90)
		(property "Reference" "C561"
			(at 0 0 90)
			(layer "F.SilkS")
			(hide yes)
			(effects
				(font
					(size 1.27 1.27)
				)
			)
		)
		(property "Value" ""
			(at 0 0 90)
			(layer "F.Fab")
			(effects
				(font
					(size 1.27 1.27)
				)
			)
		)
		(duplicate_pad_numbers_are_jumpers no)
		(fp_line
			(start 0.299974 -0.150114)
			(end 0.299974 0.150114)
			(stroke
				(width 0.1)
				(type default)
			)
			(layer "F.Fab")
		)
		(fp_line
			(start -0.299974 -0.150114)
			(end 0.299974 -0.150114)
			(stroke
				(width 0.1)
				(type default)
			)
			(layer "F.Fab")
		)
		(fp_line
			(start 0.299974 0.150114)
			(end -0.299974 0.150114)
			(stroke
				(width 0.1)
				(type default)
			)
			(layer "F.Fab")
		)
		(fp_line
			(start -0.299974 0.150114)
			(end -0.299974 -0.150114)
			(stroke
				(width 0.1)
				(type default)
			)
			(layer "F.Fab")
		)
		(pad "1" smd rect
			(at -0.2667 0 90)
			(size 0.3048 0.381)
			(layers "F.Cu" "F.Mask" "F.Paste")
			(net "P5E_PEX2_STN6_TX_DP<106>")
		)
		(pad "2" smd rect
			(at 0.2667 0 90)
			(size 0.3048 0.381)
			(layers "F.Cu" "F.Mask" "F.Paste")
			(net "P5E_PEX2_STN6_TX_C_DP<106>")
		)
	)
	(footprint ""
		(layer "F.Cu")
		(at 235.476288 -97.258378 90)
		(property "Reference" "C2624"
			(at 0 0 90)
			(layer "F.SilkS")
			(hide yes)
			(effects
				(font
					(size 1.27 1.27)
				)
			)
		)
		(property "Value" ""
			(at 0 0 90)
			(layer "F.Fab")
			(effects
				(font
					(size 1.27 1.27)
				)
			)
		)
		(duplicate_pad_numbers_are_jumpers no)
		(fp_line
			(start 0.7874 -0.4064)
			(end 0.7874 0.4064)
			(stroke
				(width 0.1524)
				(type default)
			)
			(layer "F.SilkS")
		)
		(fp_line
			(start -0.7874 -0.4064)
			(end 0.7874 -0.4064)
			(stroke
				(width 0.1524)
				(type default)
			)
			(layer "F.SilkS")
		)
		(fp_line
			(start 0.7874 0.4064)
			(end -0.7874 0.4064)
			(stroke
				(width 0.1524)
				(type default)
			)
			(layer "F.SilkS")
		)
		(fp_line
			(start -0.7874 0.4064)
			(end -0.7874 -0.4064)
			(stroke
				(width 0.1524)
				(type default)
			)
			(layer "F.SilkS")
		)
		(fp_line
			(start -0.12065 -0.305054)
			(end -0.12065 -0.2794)
			(stroke
				(width 0.1)
				(type default)
			)
			(layer "F.Fab")
		)
		(fp_line
			(start -0.67945 -0.305054)
			(end -0.12065 -0.305054)
			(stroke
				(width 0.1)
				(type default)
			)
			(layer "F.Fab")
		)
		(fp_line
			(start 0.67945 -0.3048)
			(end 0.67945 0.3048)
			(stroke
				(width 0.1)
				(type default)
			)
			(layer "F.Fab")
		)
		(fp_line
			(start 0.12065 -0.3048)
			(end 0.67945 -0.3048)
			(stroke
				(width 0.1)
				(type default)
			)
			(layer "F.Fab")
		)
		(fp_line
			(start 0.12065 -0.2794)
			(end 0.12065 -0.3048)
			(stroke
				(width 0.1)
				(type default)
			)
			(layer "F.Fab")
		)
		(fp_line
			(start -0.12065 -0.2794)
			(end 0.12065 -0.2794)
			(stroke
				(width 0.1)
				(type default)
			)
			(layer "F.Fab")
		)
		(fp_line
			(start 0.120396 0.2794)
			(end -0.12065 0.2794)
			(stroke
				(width 0.1)
				(type default)
			)
			(layer "F.Fab")
		)
		(fp_line
			(start -0.12065 0.2794)
			(end -0.12065 0.3048)
			(stroke
				(width 0.1)
				(type default)
			)
			(layer "F.Fab")
		)
		(fp_line
			(start 0.67945 0.3048)
			(end 0.120396 0.3048)
			(stroke
				(width 0.1)
				(type default)
			)
			(layer "F.Fab")
		)
		(fp_line
			(start 0.120396 0.3048)
			(end 0.120396 0.2794)
			(stroke
				(width 0.1)
				(type default)
			)
			(layer "F.Fab")
		)
		(fp_line
			(start -0.12065 0.3048)
			(end -0.67945 0.3048)
			(stroke
				(width 0.1)
				(type default)
			)
			(layer "F.Fab")
		)
		(fp_line
			(start -0.67945 0.3048)
			(end -0.67945 -0.305054)
			(stroke
				(width 0.1)
				(type default)
			)
			(layer "F.Fab")
		)
		(pad "1" smd circle
			(at -0.40005 0 90)
			(size 0 0)
			(layers "F.Cu" "F.Mask" "F.Paste")
			(net "RST_PEX_USB_HUB_R_N")
		)
		(pad "2" smd circle
			(at 0.40005 0 90)
			(size 0 0)
			(layers "F.Cu" "F.Mask" "F.Paste")
			(net "GND")
		)
	)
	(footprint ""
		(layer "F.Cu")
		(at 168.378632 -350.098614 90)
		(property "Reference" "C2518"
			(at 0 0 90)
			(layer "F.SilkS")
			(hide yes)
			(effects
				(font
					(size 1.27 1.27)
				)
			)
		)
		(property "Value" ""
			(at 0 0 90)
			(layer "F.Fab")
			(effects
				(font
					(size 1.27 1.27)
				)
			)
		)
		(duplicate_pad_numbers_are_jumpers no)
		(fp_line
			(start 0.299974 -0.150114)
			(end 0.299974 0.150114)
			(stroke
				(width 0.1)
				(type default)
			)
			(layer "F.Fab")
		)
		(fp_line
			(start -0.299974 -0.150114)
			(end 0.299974 -0.150114)
			(stroke
				(width 0.1)
				(type default)
			)
			(layer "F.Fab")
		)
		(fp_line
			(start 0.299974 0.150114)
			(end -0.299974 0.150114)
			(stroke
				(width 0.1)
				(type default)
			)
			(layer "F.Fab")
		)
		(fp_line
			(start -0.299974 0.150114)
			(end -0.299974 -0.150114)
			(stroke
				(width 0.1)
				(type default)
			)
			(layer "F.Fab")
		)
		(pad "1" smd rect
			(at -0.2667 0 90)
			(size 0.3048 0.381)
			(layers "F.Cu" "F.Mask" "F.Paste")
			(net "P5E_PEX1_STN4_TX_DP<76>")
		)
		(pad "2" smd rect
			(at 0.2667 0 90)
			(size 0.3048 0.381)
			(layers "F.Cu" "F.Mask" "F.Paste")
			(net "P5E_PEX1_STN4_TX_C_DP<76>")
		)
	)
	(footprint ""
		(layer "F.Cu")
		(at 76.48194 -37.025072)
		(property "Reference" "R5657"
			(at 0 0 0)
			(layer "F.SilkS")
			(hide yes)
			(effects
				(font
					(size 1.27 1.27)
				)
			)
		)
		(property "Value" ""
			(at 0 0 0)
			(layer "F.Fab")
			(effects
				(font
					(size 1.27 1.27)
				)
			)
		)
		(duplicate_pad_numbers_are_jumpers no)
		(fp_line
			(start -0.7874 -0.4064)
			(end 0.7874 -0.4064)
			(stroke
				(width 0.1524)
				(type default)
			)
			(layer "F.SilkS")
		)
		(fp_line
			(start -0.7874 0.4064)
			(end -0.7874 -0.4064)
			(stroke
				(width 0.1524)
				(type default)
			)
			(layer "F.SilkS")
		)
		(fp_line
			(start 0.7874 -0.4064)
			(end 0.7874 0.4064)
			(stroke
				(width 0.1524)
				(type default)
			)
			(layer "F.SilkS")
		)
		(fp_line
			(start 0.7874 0.4064)
			(end -0.7874 0.4064)
			(stroke
				(width 0.1524)
				(type default)
			)
			(layer "F.SilkS")
		)
		(fp_line
			(start -0.67945 -0.305054)
			(end -0.12065 -0.305054)
			(stroke
				(width 0.1)
				(type default)
			)
			(layer "F.Fab")
		)
		(fp_line
			(start -0.67945 0.3048)
			(end -0.67945 -0.305054)
			(stroke
				(width 0.1)
				(type default)
			)
			(layer "F.Fab")
		)
		(fp_line
			(start -0.12065 -0.305054)
			(end -0.12065 -0.2794)
			(stroke
				(width 0.1)
				(type default)
			)
			(layer "F.Fab")
		)
		(fp_line
			(start -0.12065 -0.2794)
			(end 0.12065 -0.2794)
			(stroke
				(width 0.1)
				(type default)
			)
			(layer "F.Fab")
		)
		(fp_line
			(start -0.12065 0.2794)
			(end -0.12065 0.3048)
			(stroke
				(width 0.1)
				(type default)
			)
			(layer "F.Fab")
		)
		(fp_line
			(start -0.12065 0.3048)
			(end -0.67945 0.3048)
			(stroke
				(width 0.1)
				(type default)
			)
			(layer "F.Fab")
		)
		(fp_line
			(start 0.120396 0.2794)
			(end -0.12065 0.2794)
			(stroke
				(width 0.1)
				(type default)
			)
			(layer "F.Fab")
		)
		(fp_line
			(start 0.120396 0.3048)
			(end 0.120396 0.2794)
			(stroke
				(width 0.1)
				(type default)
			)
			(layer "F.Fab")
		)
		(fp_line
			(start 0.12065 -0.3048)
			(end 0.67945 -0.3048)
			(stroke
				(width 0.1)
				(type default)
			)
			(layer "F.Fab")
		)
		(fp_line
			(start 0.12065 -0.2794)
			(end 0.12065 -0.3048)
			(stroke
				(width 0.1)
				(type default)
			)
			(layer "F.Fab")
		)
		(fp_line
			(start 0.67945 -0.3048)
			(end 0.67945 0.3048)
			(stroke
				(width 0.1)
				(type default)
			)
			(layer "F.Fab")
		)
		(fp_line
			(start 0.67945 0.3048)
			(end 0.120396 0.3048)
			(stroke
				(width 0.1)
				(type default)
			)
			(layer "F.Fab")
		)
		(pad "1" smd circle
			(at -0.40005 0)
			(size 0 0)
			(layers "F.Cu" "F.Mask" "F.Paste")
			(net "RST_SMB_SSD_R_N")
		)
		(pad "2" smd circle
			(at 0.40005 0)
			(size 0 0)
			(layers "F.Cu" "F.Mask" "F.Paste")
			(net "RST_SMB_SSD3_N")
		)
	)
	(footprint ""
		(layer "F.Cu")
		(at 314.915042 -59.546236 90)
		(property "Reference" "C2900"
			(at 0 0 90)
			(layer "F.SilkS")
			(hide yes)
			(effects
				(font
					(size 1.27 1.27)
				)
			)
		)
		(property "Value" ""
			(at 0 0 90)
			(layer "F.Fab")
			(effects
				(font
					(size 1.27 1.27)
				)
			)
		)
		(duplicate_pad_numbers_are_jumpers no)
		(fp_line
			(start 0.7874 -0.4064)
			(end 0.7874 0.4064)
			(stroke
				(width 0.1524)
				(type default)
			)
			(layer "F.SilkS")
		)
		(fp_line
			(start -0.7874 -0.4064)
			(end 0.7874 -0.4064)
			(stroke
				(width 0.1524)
				(type default)
			)
			(layer "F.SilkS")
		)
		(fp_line
			(start 0.7874 0.4064)
			(end -0.7874 0.4064)
			(stroke
				(width 0.1524)
				(type default)
			)
			(layer "F.SilkS")
		)
		(fp_line
			(start -0.7874 0.4064)
			(end -0.7874 -0.4064)
			(stroke
				(width 0.1524)
				(type default)
			)
			(layer "F.SilkS")
		)
		(fp_line
			(start -0.12065 -0.305054)
			(end -0.12065 -0.2794)
			(stroke
				(width 0.1)
				(type default)
			)
			(layer "F.Fab")
		)
		(fp_line
			(start -0.67945 -0.305054)
			(end -0.12065 -0.305054)
			(stroke
				(width 0.1)
				(type default)
			)
			(layer "F.Fab")
		)
		(fp_line
			(start 0.67945 -0.3048)
			(end 0.67945 0.3048)
			(stroke
				(width 0.1)
				(type default)
			)
			(layer "F.Fab")
		)
		(fp_line
			(start 0.12065 -0.3048)
			(end 0.67945 -0.3048)
			(stroke
				(width 0.1)
				(type default)
			)
			(layer "F.Fab")
		)
		(fp_line
			(start 0.12065 -0.2794)
			(end 0.12065 -0.3048)
			(stroke
				(width 0.1)
				(type default)
			)
			(layer "F.Fab")
		)
		(fp_line
			(start -0.12065 -0.2794)
			(end 0.12065 -0.2794)
			(stroke
				(width 0.1)
				(type default)
			)
			(layer "F.Fab")
		)
		(fp_line
			(start 0.120396 0.2794)
			(end -0.12065 0.2794)
			(stroke
				(width 0.1)
				(type default)
			)
			(layer "F.Fab")
		)
		(fp_line
			(start -0.12065 0.2794)
			(end -0.12065 0.3048)
			(stroke
				(width 0.1)
				(type default)
			)
			(layer "F.Fab")
		)
		(fp_line
			(start 0.67945 0.3048)
			(end 0.120396 0.3048)
			(stroke
				(width 0.1)
				(type default)
			)
			(layer "F.Fab")
		)
		(fp_line
			(start 0.120396 0.3048)
			(end 0.120396 0.2794)
			(stroke
				(width 0.1)
				(type default)
			)
			(layer "F.Fab")
		)
		(fp_line
			(start -0.12065 0.3048)
			(end -0.67945 0.3048)
			(stroke
				(width 0.1)
				(type default)
			)
			(layer "F.Fab")
		)
		(fp_line
			(start -0.67945 0.3048)
			(end -0.67945 -0.305054)
			(stroke
				(width 0.1)
				(type default)
			)
			(layer "F.Fab")
		)
		(pad "1" smd circle
			(at -0.40005 0 90)
			(size 0 0)
			(layers "F.Cu" "F.Mask" "F.Paste")
			(net "SSD11_AUX_P3V3_EN_R")
		)
		(pad "2" smd circle
			(at 0.40005 0 90)
			(size 0 0)
			(layers "F.Cu" "F.Mask" "F.Paste")
			(net "GND")
		)
	)
	(footprint ""
		(layer "F.Cu")
		(at 32.411416 -299.645832 -90)
		(property "Reference" "R4559"
			(at 0 0 270)
			(layer "F.SilkS")
			(hide yes)
			(effects
				(font
					(size 1.27 1.27)
				)
			)
		)
		(property "Value" ""
			(at 0 0 270)
			(layer "F.Fab")
			(effects
				(font
					(size 1.27 1.27)
				)
			)
		)
		(duplicate_pad_numbers_are_jumpers no)
		(fp_line
			(start -0.7874 0.4064)
			(end -0.7874 -0.4064)
			(stroke
				(width 0.1524)
				(type default)
			)
			(layer "F.SilkS")
		)
		(fp_line
			(start 0.7874 0.4064)
			(end -0.7874 0.4064)
			(stroke
				(width 0.1524)
				(type default)
			)
			(layer "F.SilkS")
		)
		(fp_line
			(start -0.7874 -0.4064)
			(end 0.7874 -0.4064)
			(stroke
				(width 0.1524)
				(type default)
			)
			(layer "F.SilkS")
		)
		(fp_line
			(start 0.7874 -0.4064)
			(end 0.7874 0.4064)
			(stroke
				(width 0.1524)
				(type default)
			)
			(layer "F.SilkS")
		)
		(fp_line
			(start -0.67945 0.3048)
			(end -0.67945 -0.305054)
			(stroke
				(width 0.1)
				(type default)
			)
			(layer "F.Fab")
		)
		(fp_line
			(start -0.12065 0.3048)
			(end -0.67945 0.3048)
			(stroke
				(width 0.1)
				(type default)
			)
			(layer "F.Fab")
		)
		(fp_line
			(start 0.120396 0.3048)
			(end 0.120396 0.2794)
			(stroke
				(width 0.1)
				(type default)
			)
			(layer "F.Fab")
		)
		(fp_line
			(start 0.67945 0.3048)
			(end 0.120396 0.3048)
			(stroke
				(width 0.1)
				(type default)
			)
			(layer "F.Fab")
		)
		(fp_line
			(start -0.12065 0.2794)
			(end -0.12065 0.3048)
			(stroke
				(width 0.1)
				(type default)
			)
			(layer "F.Fab")
		)
		(fp_line
			(start 0.120396 0.2794)
			(end -0.12065 0.2794)
			(stroke
				(width 0.1)
				(type default)
			)
			(layer "F.Fab")
		)
		(fp_line
			(start -0.12065 -0.2794)
			(end 0.12065 -0.2794)
			(stroke
				(width 0.1)
				(type default)
			)
			(layer "F.Fab")
		)
		(fp_line
			(start 0.12065 -0.2794)
			(end 0.12065 -0.3048)
			(stroke
				(width 0.1)
				(type default)
			)
			(layer "F.Fab")
		)
		(fp_line
			(start 0.12065 -0.3048)
			(end 0.67945 -0.3048)
			(stroke
				(width 0.1)
				(type default)
			)
			(layer "F.Fab")
		)
		(fp_line
			(start 0.67945 -0.3048)
			(end 0.67945 0.3048)
			(stroke
				(width 0.1)
				(type default)
			)
			(layer "F.Fab")
		)
		(fp_line
			(start -0.67945 -0.305054)
			(end -0.12065 -0.305054)
			(stroke
				(width 0.1)
				(type default)
			)
			(layer "F.Fab")
		)
		(fp_line
			(start -0.12065 -0.305054)
			(end -0.12065 -0.2794)
			(stroke
				(width 0.1)
				(type default)
			)
			(layer "F.Fab")
		)
		(pad "1" smd circle
			(at -0.40005 0 270)
			(size 0 0)
			(layers "F.Cu" "F.Mask" "F.Paste")
			(net "PCEPLL1_VDDA18_PEX0")
		)
		(pad "2" smd circle
			(at 0.40005 0 270)
			(size 0 0)
			(layers "F.Cu" "F.Mask" "F.Paste")
			(net "PCEPLL1_VDDA18_PEX0_R")
		)
	)
	(footprint ""
		(layer "F.Cu")
		(at 223.889316 -257.975862 -90)
		(property "Reference" "R6493"
			(at 0 0 270)
			(layer "F.SilkS")
			(hide yes)
			(effects
				(font
					(size 1.27 1.27)
				)
			)
		)
		(property "Value" ""
			(at 0 0 270)
			(layer "F.Fab")
			(effects
				(font
					(size 1.27 1.27)
				)
			)
		)
		(duplicate_pad_numbers_are_jumpers no)
		(fp_line
			(start -0.7874 0.4064)
			(end -0.7874 -0.4064)
			(stroke
				(width 0.1524)
				(type default)
			)
			(layer "F.SilkS")
		)
		(fp_line
			(start 0.7874 0.4064)
			(end -0.7874 0.4064)
			(stroke
				(width 0.1524)
				(type default)
			)
			(layer "F.SilkS")
		)
		(fp_line
			(start -0.7874 -0.4064)
			(end 0.7874 -0.4064)
			(stroke
				(width 0.1524)
				(type default)
			)
			(layer "F.SilkS")
		)
		(fp_line
			(start 0.7874 -0.4064)
			(end 0.7874 0.4064)
			(stroke
				(width 0.1524)
				(type default)
			)
			(layer "F.SilkS")
		)
		(fp_line
			(start -0.67945 0.3048)
			(end -0.67945 -0.305054)
			(stroke
				(width 0.1)
				(type default)
			)
			(layer "F.Fab")
		)
		(fp_line
			(start -0.12065 0.3048)
			(end -0.67945 0.3048)
			(stroke
				(width 0.1)
				(type default)
			)
			(layer "F.Fab")
		)
		(fp_line
			(start 0.120396 0.3048)
			(end 0.120396 0.2794)
			(stroke
				(width 0.1)
				(type default)
			)
			(layer "F.Fab")
		)
		(fp_line
			(start 0.67945 0.3048)
			(end 0.120396 0.3048)
			(stroke
				(width 0.1)
				(type default)
			)
			(layer "F.Fab")
		)
		(fp_line
			(start -0.12065 0.2794)
			(end -0.12065 0.3048)
			(stroke
				(width 0.1)
				(type default)
			)
			(layer "F.Fab")
		)
		(fp_line
			(start 0.120396 0.2794)
			(end -0.12065 0.2794)
			(stroke
				(width 0.1)
				(type default)
			)
			(layer "F.Fab")
		)
		(fp_line
			(start -0.12065 -0.2794)
			(end 0.12065 -0.2794)
			(stroke
				(width 0.1)
				(type default)
			)
			(layer "F.Fab")
		)
		(fp_line
			(start 0.12065 -0.2794)
			(end 0.12065 -0.3048)
			(stroke
				(width 0.1)
				(type default)
			)
			(layer "F.Fab")
		)
		(fp_line
			(start 0.12065 -0.3048)
			(end 0.67945 -0.3048)
			(stroke
				(width 0.1)
				(type default)
			)
			(layer "F.Fab")
		)
		(fp_line
			(start 0.67945 -0.3048)
			(end 0.67945 0.3048)
			(stroke
				(width 0.1)
				(type default)
			)
			(layer "F.Fab")
		)
		(fp_line
			(start -0.67945 -0.305054)
			(end -0.12065 -0.305054)
			(stroke
				(width 0.1)
				(type default)
			)
			(layer "F.Fab")
		)
		(fp_line
			(start -0.12065 -0.305054)
			(end -0.12065 -0.2794)
			(stroke
				(width 0.1)
				(type default)
			)
			(layer "F.Fab")
		)
		(pad "1" smd circle
			(at -0.40005 0 270)
			(size 0 0)
			(layers "F.Cu" "F.Mask" "F.Paste")
			(net "P1V25_SERDES_VDDPLL_PEX1")
		)
		(pad "2" smd circle
			(at 0.40005 0 270)
			(size 0 0)
			(layers "F.Cu" "F.Mask" "F.Paste")
			(net "P1V25_SERDES_VDDPLL_PEX1_C2")
		)
	)
	(footprint ""
		(layer "F.Cu")
		(at 262.461756 -311.007252 -135)
		(property "Reference" "R1393"
			(at 0 0 225)
			(layer "F.SilkS")
			(hide yes)
			(effects
				(font
					(size 1.27 1.27)
				)
			)
		)
		(property "Value" ""
			(at 0 0 225)
			(layer "F.Fab")
			(effects
				(font
					(size 1.27 1.27)
				)
			)
		)
		(duplicate_pad_numbers_are_jumpers no)
		(fp_line
			(start 0.787389 0.406267)
			(end -0.787389 0.406267)
			(stroke
				(width 0.1524)
				(type default)
			)
			(layer "F.SilkS")
		)
		(fp_line
			(start 0.787389 -0.406267)
			(end 0.787389 0.406267)
			(stroke
				(width 0.1524)
				(type default)
			)
			(layer "F.SilkS")
		)
		(fp_line
			(start -0.787389 0.406267)
			(end -0.787389 -0.406267)
			(stroke
				(width 0.1524)
				(type default)
			)
			(layer "F.SilkS")
		)
		(fp_line
			(start -0.787389 -0.406267)
			(end 0.787389 -0.406267)
			(stroke
				(width 0.1524)
				(type default)
			)
			(layer "F.SilkS")
		)
		(fp_line
			(start 0.679446 0.30479)
			(end 0.120515 0.30479)
			(stroke
				(width 0.1)
				(type default)
			)
			(layer "F.Fab")
		)
		(fp_line
			(start 0.120515 0.30479)
			(end 0.120335 0.279466)
			(stroke
				(width 0.1)
				(type default)
			)
			(layer "F.Fab")
		)
		(fp_line
			(start 0.120335 0.279466)
			(end -0.120695 0.279466)
			(stroke
				(width 0.1)
				(type default)
			)
			(layer "F.Fab")
		)
		(fp_line
			(start 0.679446 -0.30479)
			(end 0.679446 0.30479)
			(stroke
				(width 0.1)
				(type default)
			)
			(layer "F.Fab")
		)
		(fp_line
			(start -0.120515 0.30479)
			(end -0.679446 0.30479)
			(stroke
				(width 0.1)
				(type default)
			)
			(layer "F.Fab")
		)
		(fp_line
			(start -0.120695 0.279466)
			(end -0.120515 0.30479)
			(stroke
				(width 0.1)
				(type default)
			)
			(layer "F.Fab")
		)
		(fp_line
			(start 0.120695 -0.279466)
			(end 0.120515 -0.30479)
			(stroke
				(width 0.1)
				(type default)
			)
			(layer "F.Fab")
		)
		(fp_line
			(start 0.120515 -0.30479)
			(end 0.679446 -0.30479)
			(stroke
				(width 0.1)
				(type default)
			)
			(layer "F.Fab")
		)
		(fp_line
			(start -0.679446 0.30479)
			(end -0.679446 -0.305149)
			(stroke
				(width 0.1)
				(type default)
			)
			(layer "F.Fab")
		)
		(fp_line
			(start -0.120695 -0.279466)
			(end 0.120695 -0.279466)
			(stroke
				(width 0.1)
				(type default)
			)
			(layer "F.Fab")
		)
		(fp_line
			(start -0.120695 -0.304969)
			(end -0.120695 -0.279466)
			(stroke
				(width 0.1)
				(type default)
			)
			(layer "F.Fab")
		)
		(fp_line
			(start -0.679446 -0.305149)
			(end -0.120695 -0.304969)
			(stroke
				(width 0.1)
				(type default)
			)
			(layer "F.Fab")
		)
		(pad "1" smd circle
			(at -0.40005 0 225)
			(size 0 0)
			(layers "F.Cu" "F.Mask" "F.Paste")
			(net "PU_PEX2_PAD_TRI_L")
		)
		(pad "2" smd circle
			(at 0.40005 0 225)
			(size 0 0)
			(layers "F.Cu" "F.Mask" "F.Paste")
			(net "P1V8_PEX")
		)
	)
	(footprint ""
		(layer "F.Cu")
		(at 52.243736 -43.85691)
		(property "Reference" "R521"
			(at 0 0 0)
			(layer "F.SilkS")
			(hide yes)
			(effects
				(font
					(size 1.27 1.27)
				)
			)
		)
		(property "Value" ""
			(at 0 0 0)
			(layer "F.Fab")
			(effects
				(font
					(size 1.27 1.27)
				)
			)
		)
		(duplicate_pad_numbers_are_jumpers no)
		(fp_line
			(start -0.7874 -0.4064)
			(end 0.7874 -0.4064)
			(stroke
				(width 0.1524)
				(type default)
			)
			(layer "F.SilkS")
		)
		(fp_line
			(start -0.7874 0.4064)
			(end -0.7874 -0.4064)
			(stroke
				(width 0.1524)
				(type default)
			)
			(layer "F.SilkS")
		)
		(fp_line
			(start 0.7874 -0.4064)
			(end 0.7874 0.4064)
			(stroke
				(width 0.1524)
				(type default)
			)
			(layer "F.SilkS")
		)
		(fp_line
			(start 0.7874 0.4064)
			(end -0.7874 0.4064)
			(stroke
				(width 0.1524)
				(type default)
			)
			(layer "F.SilkS")
		)
		(fp_line
			(start -0.67945 -0.305054)
			(end -0.12065 -0.305054)
			(stroke
				(width 0.1)
				(type default)
			)
			(layer "F.Fab")
		)
		(fp_line
			(start -0.67945 0.3048)
			(end -0.67945 -0.305054)
			(stroke
				(width 0.1)
				(type default)
			)
			(layer "F.Fab")
		)
		(fp_line
			(start -0.12065 -0.305054)
			(end -0.12065 -0.2794)
			(stroke
				(width 0.1)
				(type default)
			)
			(layer "F.Fab")
		)
		(fp_line
			(start -0.12065 -0.2794)
			(end 0.12065 -0.2794)
			(stroke
				(width 0.1)
				(type default)
			)
			(layer "F.Fab")
		)
		(fp_line
			(start -0.12065 0.2794)
			(end -0.12065 0.3048)
			(stroke
				(width 0.1)
				(type default)
			)
			(layer "F.Fab")
		)
		(fp_line
			(start -0.12065 0.3048)
			(end -0.67945 0.3048)
			(stroke
				(width 0.1)
				(type default)
			)
			(layer "F.Fab")
		)
		(fp_line
			(start 0.120396 0.2794)
			(end -0.12065 0.2794)
			(stroke
				(width 0.1)
				(type default)
			)
			(layer "F.Fab")
		)
		(fp_line
			(start 0.120396 0.3048)
			(end 0.120396 0.2794)
			(stroke
				(width 0.1)
				(type default)
			)
			(layer "F.Fab")
		)
		(fp_line
			(start 0.12065 -0.3048)
			(end 0.67945 -0.3048)
			(stroke
				(width 0.1)
				(type default)
			)
			(layer "F.Fab")
		)
		(fp_line
			(start 0.12065 -0.2794)
			(end 0.12065 -0.3048)
			(stroke
				(width 0.1)
				(type default)
			)
			(layer "F.Fab")
		)
		(fp_line
			(start 0.67945 -0.3048)
			(end 0.67945 0.3048)
			(stroke
				(width 0.1)
				(type default)
			)
			(layer "F.Fab")
		)
		(fp_line
			(start 0.67945 0.3048)
			(end 0.120396 0.3048)
			(stroke
				(width 0.1)
				(type default)
			)
			(layer "F.Fab")
		)
		(pad "1" smd circle
			(at -0.40005 0)
			(size 0 0)
			(layers "F.Cu" "F.Mask" "F.Paste")
			(net "SSD1_ADC_A1")
		)
		(pad "2" smd circle
			(at 0.40005 0)
			(size 0 0)
			(layers "F.Cu" "F.Mask" "F.Paste")
			(net "GND")
		)
	)
	(footprint ""
		(layer "F.Cu")
		(at 442.553344 18.028412 180)
		(property "Reference" "DE05F_1"
			(at 2.828544 3.218942 0)
			(unlocked yes)
			(layer "F.SilkS")
			(effects
				(font
					(size 0.7874 0.5842)
					(thickness 0.1524)
				)
				(justify left)
			)
		)
		(property "Value" ""
			(at 0 0 180)
			(layer "F.Fab")
			(effects
				(font
					(size 1.27 1.27)
				)
			)
		)
		(duplicate_pad_numbers_are_jumpers no)
		(fp_line
			(start 1.2192 2.1082)
			(end -1.2192 2.1082)
			(stroke
				(width 0.1524)
				(type default)
			)
			(layer "F.SilkS")
		)
		(fp_line
			(start 1.2192 -2.1082)
			(end 1.2192 2.1082)
			(stroke
				(width 0.1524)
				(type default)
			)
			(layer "F.SilkS")
		)
		(fp_line
			(start -1.2192 2.1082)
			(end -1.2192 -2.1082)
			(stroke
				(width 0.1524)
				(type default)
			)
			(layer "F.SilkS")
		)
		(fp_line
			(start -1.2192 -2.1082)
			(end 1.2192 -2.1082)
			(stroke
				(width 0.1524)
				(type default)
			)
			(layer "F.SilkS")
		)
		(pad "" np_thru_hole circle
			(at -2.8829 -1.27 90)
			(size 1.0414 1.0414)
			(drill 1.0414)
			(layers "*.Cu" "*.Mask")
			(clearance 0.381)
			(thermal_gap 0.381)
		)
		(pad "" np_thru_hole circle
			(at -2.8829 1.27 90)
			(size 1.0414 1.0414)
			(drill 1.0414)
			(layers "*.Cu" "*.Mask")
			(clearance 0.381)
			(thermal_gap 0.381)
		)
		(pad "" np_thru_hole circle
			(at 3.4671 -1.27 90)
			(size 1.0414 1.0414)
			(drill 1.0414)
			(layers "*.Cu" "*.Mask")
			(clearance 0.381)
			(thermal_gap 0.381)
		)
		(pad "" np_thru_hole circle
			(at 3.4671 1.27 90)
			(size 1.0414 1.0414)
			(drill 1.0414)
			(layers "*.Cu" "*.Mask")
			(clearance 0.381)
			(thermal_gap 0.381)
		)
		(pad "1" smd rect
			(at 0.8255 -0.249936 90)
			(size 0.3048 0.508)
			(layers "F.Cu" "F.Mask" "F.Paste")
			(net "85_5INCH_IN3_DP")
		)
		(pad "2" smd rect
			(at 0.8255 0.249936 90)
			(size 0.3048 0.508)
			(layers "F.Cu" "F.Mask" "F.Paste")
			(net "85_5INCH_IN3_DN")
		)
		(pad "3" smd circle
			(at 0 0 180)
			(size 0 0)
			(layers "F.Cu" "F.Mask" "F.Paste")
			(net "COUPON_GND2")
		)
		(zone
			(layer "F.Cu")
			(hatch none 0.5)
			(connect_pads
				(clearance 0)
			)
			(min_thickness 0.25)
			(keepout
				(tracks not_allowed)
				(vias allowed)
				(pads allowed)
				(copperpour not_allowed)
				(footprints allowed)
			)
			(placement
				(enabled no)
				(sheetname "")
			)
			(fill
				(thermal_gap 0.5)
				(thermal_bridge_width 0.5)
				(island_removal_mode 0)
			)
			(polygon
				(pts
					(xy 441.435744 18.577052) (xy 441.435744 18.481548) (xy 442.032644 18.481548) (xy 442.032644 18.075148)
					(xy 441.435744 18.075148) (xy 441.435744 17.981676) (xy 442.032644 17.981676) (xy 442.032644 17.575276)
					(xy 441.435744 17.575276) (xy 441.435744 17.479772) (xy 442.134244 17.479772) (xy 442.134244 18.577052)
				)
			)
		)
		(zone
			(layers "F.Cu" "B.Cu" "In1.Cu" "In2.Cu" "In3.Cu" "In4.Cu" "In5.Cu" "In6.Cu"
				"In7.Cu" "In8.Cu" "In9.Cu" "In10.Cu" "In11.Cu" "In12.Cu" "In13.Cu" "In14.Cu"
				"In15.Cu" "In16.Cu"
			)
			(hatch none 0.5)
			(connect_pads
				(clearance 0)
			)
			(min_thickness 0.25)
			(keepout
				(tracks not_allowed)
				(vias allowed)
				(pads allowed)
				(copperpour not_allowed)
				(footprints allowed)
			)
			(placement
				(enabled no)
				(sheetname "")
			)
			(fill
				(thermal_gap 0.5)
				(thermal_bridge_width 0.5)
				(island_removal_mode 0)
			)
			(polygon
				(pts
					(arc
						(start 440.013344 16.758412)
						(mid 438.159144 16.758412)
						(end 440.013344 16.758412)
					)
				)
			)
		)
		(zone
			(layers "F.Cu" "B.Cu" "In1.Cu" "In2.Cu" "In3.Cu" "In4.Cu" "In5.Cu" "In6.Cu"
				"In7.Cu" "In8.Cu" "In9.Cu" "In10.Cu" "In11.Cu" "In12.Cu" "In13.Cu" "In14.Cu"
				"In15.Cu" "In16.Cu"
			)
			(hatch none 0.5)
			(connect_pads
				(clearance 0)
			)
			(min_thickness 0.25)
			(keepout
				(tracks not_allowed)
				(vias allowed)
				(pads allowed)
				(copperpour not_allowed)
				(footprints allowed)
			)
			(placement
				(enabled no)
				(sheetname "")
			)
			(fill
				(thermal_gap 0.5)
				(thermal_bridge_width 0.5)
				(island_removal_mode 0)
			)
			(polygon
				(pts
					(arc
						(start 440.013344 19.298412)
						(mid 438.159144 19.298412)
						(end 440.013344 19.298412)
					)
				)
			)
		)
		(zone
			(layers "F.Cu" "B.Cu" "In1.Cu" "In2.Cu" "In3.Cu" "In4.Cu" "In5.Cu" "In6.Cu"
				"In7.Cu" "In8.Cu" "In9.Cu" "In10.Cu" "In11.Cu" "In12.Cu" "In13.Cu" "In14.Cu"
				"In15.Cu" "In16.Cu"
			)
			(hatch none 0.5)
			(connect_pads
				(clearance 0)
			)
			(min_thickness 0.25)
			(keepout
				(tracks not_allowed)
				(vias allowed)
				(pads allowed)
				(copperpour not_allowed)
				(footprints allowed)
			)
			(placement
				(enabled no)
				(sheetname "")
			)
			(fill
				(thermal_gap 0.5)
				(thermal_bridge_width 0.5)
				(island_removal_mode 0)
			)
			(polygon
				(pts
					(arc
						(start 446.363344 16.758412)
						(mid 444.509144 16.758412)
						(end 446.363344 16.758412)
					)
				)
			)
		)
		(zone
			(layers "F.Cu" "B.Cu" "In1.Cu" "In2.Cu" "In3.Cu" "In4.Cu" "In5.Cu" "In6.Cu"
				"In7.Cu" "In8.Cu" "In9.Cu" "In10.Cu" "In11.Cu" "In12.Cu" "In13.Cu" "In14.Cu"
				"In15.Cu" "In16.Cu"
			)
			(hatch none 0.5)
			(connect_pads
				(clearance 0)
			)
			(min_thickness 0.25)
			(keepout
				(tracks not_allowed)
				(vias allowed)
				(pads allowed)
				(copperpour not_allowed)
				(footprints allowed)
			)
			(placement
				(enabled no)
				(sheetname "")
			)
			(fill
				(thermal_gap 0.5)
				(thermal_bridge_width 0.5)
				(island_removal_mode 0)
			)
			(polygon
				(pts
					(arc
						(start 446.363344 19.298412)
						(mid 444.509144 19.298412)
						(end 446.363344 19.298412)
					)
				)
			)
		)
	)
	(footprint ""
		(layer "F.Cu")
		(at 259.399786 -334.015588 90)
		(property "Reference" "C4485"
			(at 0 0 90)
			(layer "F.SilkS")
			(hide yes)
			(effects
				(font
					(size 1.27 1.27)
				)
			)
		)
		(property "Value" ""
			(at 0 0 90)
			(layer "F.Fab")
			(effects
				(font
					(size 1.27 1.27)
				)
			)
		)
		(duplicate_pad_numbers_are_jumpers no)
		(fp_line
			(start 0.7874 -0.4064)
			(end 0.7874 0.4064)
			(stroke
				(width 0.1524)
				(type default)
			)
			(layer "F.SilkS")
		)
		(fp_line
			(start -0.7874 -0.4064)
			(end 0.7874 -0.4064)
			(stroke
				(width 0.1524)
				(type default)
			)
			(layer "F.SilkS")
		)
		(fp_line
			(start 0.7874 0.4064)
			(end -0.7874 0.4064)
			(stroke
				(width 0.1524)
				(type default)
			)
			(layer "F.SilkS")
		)
		(fp_line
			(start -0.7874 0.4064)
			(end -0.7874 -0.4064)
			(stroke
				(width 0.1524)
				(type default)
			)
			(layer "F.SilkS")
		)
		(fp_line
			(start -0.12065 -0.305054)
			(end -0.12065 -0.2794)
			(stroke
				(width 0.1)
				(type default)
			)
			(layer "F.Fab")
		)
		(fp_line
			(start -0.67945 -0.305054)
			(end -0.12065 -0.305054)
			(stroke
				(width 0.1)
				(type default)
			)
			(layer "F.Fab")
		)
		(fp_line
			(start 0.67945 -0.3048)
			(end 0.67945 0.3048)
			(stroke
				(width 0.1)
				(type default)
			)
			(layer "F.Fab")
		)
		(fp_line
			(start 0.12065 -0.3048)
			(end 0.67945 -0.3048)
			(stroke
				(width 0.1)
				(type default)
			)
			(layer "F.Fab")
		)
		(fp_line
			(start 0.12065 -0.2794)
			(end 0.12065 -0.3048)
			(stroke
				(width 0.1)
				(type default)
			)
			(layer "F.Fab")
		)
		(fp_line
			(start -0.12065 -0.2794)
			(end 0.12065 -0.2794)
			(stroke
				(width 0.1)
				(type default)
			)
			(layer "F.Fab")
		)
		(fp_line
			(start 0.120396 0.2794)
			(end -0.12065 0.2794)
			(stroke
				(width 0.1)
				(type default)
			)
			(layer "F.Fab")
		)
		(fp_line
			(start -0.12065 0.2794)
			(end -0.12065 0.3048)
			(stroke
				(width 0.1)
				(type default)
			)
			(layer "F.Fab")
		)
		(fp_line
			(start 0.67945 0.3048)
			(end 0.120396 0.3048)
			(stroke
				(width 0.1)
				(type default)
			)
			(layer "F.Fab")
		)
		(fp_line
			(start 0.120396 0.3048)
			(end 0.120396 0.2794)
			(stroke
				(width 0.1)
				(type default)
			)
			(layer "F.Fab")
		)
		(fp_line
			(start -0.12065 0.3048)
			(end -0.67945 0.3048)
			(stroke
				(width 0.1)
				(type default)
			)
			(layer "F.Fab")
		)
		(fp_line
			(start -0.67945 0.3048)
			(end -0.67945 -0.305054)
			(stroke
				(width 0.1)
				(type default)
			)
			(layer "F.Fab")
		)
		(pad "1" smd circle
			(at -0.40005 0 90)
			(size 0 0)
			(layers "F.Cu" "F.Mask" "F.Paste")
			(net "HSC_OC_VOL")
		)
		(pad "2" smd circle
			(at 0.40005 0 90)
			(size 0 0)
			(layers "F.Cu" "F.Mask" "F.Paste")
			(net "GND")
		)
	)
	(footprint ""
		(layer "F.Cu")
		(at 267.569442 -260.088634 -90)
		(property "Reference" "R4581"
			(at 0 0 270)
			(layer "F.SilkS")
			(hide yes)
			(effects
				(font
					(size 1.27 1.27)
				)
			)
		)
		(property "Value" ""
			(at 0 0 270)
			(layer "F.Fab")
			(effects
				(font
					(size 1.27 1.27)
				)
			)
		)
		(duplicate_pad_numbers_are_jumpers no)
		(fp_line
			(start -0.7874 0.4064)
			(end -0.7874 -0.4064)
			(stroke
				(width 0.1524)
				(type default)
			)
			(layer "F.SilkS")
		)
		(fp_line
			(start 0.7874 0.4064)
			(end -0.7874 0.4064)
			(stroke
				(width 0.1524)
				(type default)
			)
			(layer "F.SilkS")
		)
		(fp_line
			(start -0.7874 -0.4064)
			(end 0.7874 -0.4064)
			(stroke
				(width 0.1524)
				(type default)
			)
			(layer "F.SilkS")
		)
		(fp_line
			(start 0.7874 -0.4064)
			(end 0.7874 0.4064)
			(stroke
				(width 0.1524)
				(type default)
			)
			(layer "F.SilkS")
		)
		(fp_line
			(start -0.67945 0.3048)
			(end -0.67945 -0.305054)
			(stroke
				(width 0.1)
				(type default)
			)
			(layer "F.Fab")
		)
		(fp_line
			(start -0.12065 0.3048)
			(end -0.67945 0.3048)
			(stroke
				(width 0.1)
				(type default)
			)
			(layer "F.Fab")
		)
		(fp_line
			(start 0.120396 0.3048)
			(end 0.120396 0.2794)
			(stroke
				(width 0.1)
				(type default)
			)
			(layer "F.Fab")
		)
		(fp_line
			(start 0.67945 0.3048)
			(end 0.120396 0.3048)
			(stroke
				(width 0.1)
				(type default)
			)
			(layer "F.Fab")
		)
		(fp_line
			(start -0.12065 0.2794)
			(end -0.12065 0.3048)
			(stroke
				(width 0.1)
				(type default)
			)
			(layer "F.Fab")
		)
		(fp_line
			(start 0.120396 0.2794)
			(end -0.12065 0.2794)
			(stroke
				(width 0.1)
				(type default)
			)
			(layer "F.Fab")
		)
		(fp_line
			(start -0.12065 -0.2794)
			(end 0.12065 -0.2794)
			(stroke
				(width 0.1)
				(type default)
			)
			(layer "F.Fab")
		)
		(fp_line
			(start 0.12065 -0.2794)
			(end 0.12065 -0.3048)
			(stroke
				(width 0.1)
				(type default)
			)
			(layer "F.Fab")
		)
		(fp_line
			(start 0.12065 -0.3048)
			(end 0.67945 -0.3048)
			(stroke
				(width 0.1)
				(type default)
			)
			(layer "F.Fab")
		)
		(fp_line
			(start 0.67945 -0.3048)
			(end 0.67945 0.3048)
			(stroke
				(width 0.1)
				(type default)
			)
			(layer "F.Fab")
		)
		(fp_line
			(start -0.67945 -0.305054)
			(end -0.12065 -0.305054)
			(stroke
				(width 0.1)
				(type default)
			)
			(layer "F.Fab")
		)
		(fp_line
			(start -0.12065 -0.305054)
			(end -0.12065 -0.2794)
			(stroke
				(width 0.1)
				(type default)
			)
			(layer "F.Fab")
		)
		(pad "1" smd circle
			(at -0.40005 0 270)
			(size 0 0)
			(layers "F.Cu" "F.Mask" "F.Paste")
			(net "PCEPLL3_VDDA18_PEX2")
		)
		(pad "2" smd circle
			(at 0.40005 0 270)
			(size 0 0)
			(layers "F.Cu" "F.Mask" "F.Paste")
			(net "PCEPLL3_VDDA18_PEX2_R")
		)
	)
	(footprint ""
		(layer "F.Cu")
		(at 338.263484 -350.098614 90)
		(property "Reference" "C526"
			(at 0 0 90)
			(layer "F.SilkS")
			(hide yes)
			(effects
				(font
					(size 1.27 1.27)
				)
			)
		)
		(property "Value" ""
			(at 0 0 90)
			(layer "F.Fab")
			(effects
				(font
					(size 1.27 1.27)
				)
			)
		)
		(duplicate_pad_numbers_are_jumpers no)
		(fp_line
			(start 0.299974 -0.150114)
			(end 0.299974 0.150114)
			(stroke
				(width 0.1)
				(type default)
			)
			(layer "F.Fab")
		)
		(fp_line
			(start -0.299974 -0.150114)
			(end 0.299974 -0.150114)
			(stroke
				(width 0.1)
				(type default)
			)
			(layer "F.Fab")
		)
		(fp_line
			(start 0.299974 0.150114)
			(end -0.299974 0.150114)
			(stroke
				(width 0.1)
				(type default)
			)
			(layer "F.Fab")
		)
		(fp_line
			(start -0.299974 0.150114)
			(end -0.299974 -0.150114)
			(stroke
				(width 0.1)
				(type default)
			)
			(layer "F.Fab")
		)
		(pad "1" smd rect
			(at -0.2667 0 90)
			(size 0.3048 0.381)
			(layers "F.Cu" "F.Mask" "F.Paste")
			(net "P5E_PEX2_STN5_TX_DN<92>")
		)
		(pad "2" smd rect
			(at 0.2667 0 90)
			(size 0.3048 0.381)
			(layers "F.Cu" "F.Mask" "F.Paste")
			(net "P5E_PEX2_STN5_TX_C_DN<92>")
		)
	)
	(footprint ""
		(layer "F.Cu")
		(at 74.820526 -70.307454 90)
		(property "Reference" "PC648"
			(at 0 0 90)
			(layer "F.SilkS")
			(hide yes)
			(effects
				(font
					(size 1.27 1.27)
				)
			)
		)
		(property "Value" ""
			(at 0 0 90)
			(layer "F.Fab")
			(effects
				(font
					(size 1.27 1.27)
				)
			)
		)
		(duplicate_pad_numbers_are_jumpers no)
		(fp_line
			(start 0.7874 -0.4064)
			(end 0.7874 0.4064)
			(stroke
				(width 0.1524)
				(type default)
			)
			(layer "F.SilkS")
		)
		(fp_line
			(start -0.7874 -0.4064)
			(end 0.7874 -0.4064)
			(stroke
				(width 0.1524)
				(type default)
			)
			(layer "F.SilkS")
		)
		(fp_line
			(start 0.7874 0.4064)
			(end -0.7874 0.4064)
			(stroke
				(width 0.1524)
				(type default)
			)
			(layer "F.SilkS")
		)
		(fp_line
			(start -0.7874 0.4064)
			(end -0.7874 -0.4064)
			(stroke
				(width 0.1524)
				(type default)
			)
			(layer "F.SilkS")
		)
		(fp_line
			(start -0.12065 -0.305054)
			(end -0.12065 -0.2794)
			(stroke
				(width 0.1)
				(type default)
			)
			(layer "F.Fab")
		)
		(fp_line
			(start -0.67945 -0.305054)
			(end -0.12065 -0.305054)
			(stroke
				(width 0.1)
				(type default)
			)
			(layer "F.Fab")
		)
		(fp_line
			(start 0.67945 -0.3048)
			(end 0.67945 0.3048)
			(stroke
				(width 0.1)
				(type default)
			)
			(layer "F.Fab")
		)
		(fp_line
			(start 0.12065 -0.3048)
			(end 0.67945 -0.3048)
			(stroke
				(width 0.1)
				(type default)
			)
			(layer "F.Fab")
		)
		(fp_line
			(start 0.12065 -0.2794)
			(end 0.12065 -0.3048)
			(stroke
				(width 0.1)
				(type default)
			)
			(layer "F.Fab")
		)
		(fp_line
			(start -0.12065 -0.2794)
			(end 0.12065 -0.2794)
			(stroke
				(width 0.1)
				(type default)
			)
			(layer "F.Fab")
		)
		(fp_line
			(start 0.120396 0.2794)
			(end -0.12065 0.2794)
			(stroke
				(width 0.1)
				(type default)
			)
			(layer "F.Fab")
		)
		(fp_line
			(start -0.12065 0.2794)
			(end -0.12065 0.3048)
			(stroke
				(width 0.1)
				(type default)
			)
			(layer "F.Fab")
		)
		(fp_line
			(start 0.67945 0.3048)
			(end 0.120396 0.3048)
			(stroke
				(width 0.1)
				(type default)
			)
			(layer "F.Fab")
		)
		(fp_line
			(start 0.120396 0.3048)
			(end 0.120396 0.2794)
			(stroke
				(width 0.1)
				(type default)
			)
			(layer "F.Fab")
		)
		(fp_line
			(start -0.12065 0.3048)
			(end -0.67945 0.3048)
			(stroke
				(width 0.1)
				(type default)
			)
			(layer "F.Fab")
		)
		(fp_line
			(start -0.67945 0.3048)
			(end -0.67945 -0.305054)
			(stroke
				(width 0.1)
				(type default)
			)
			(layer "F.Fab")
		)
		(pad "1" smd circle
			(at -0.40005 0 90)
			(size 0 0)
			(layers "F.Cu" "F.Mask" "F.Paste")
			(net "P12V_AUX")
		)
		(pad "2" smd circle
			(at 0.40005 0 90)
			(size 0 0)
			(layers "F.Cu" "F.Mask" "F.Paste")
			(net "GND")
		)
	)
	(footprint ""
		(layer "F.Cu")
		(at 394.474954 -48.753014 180)
		(property "Reference" "C406"
			(at 0 0 180)
			(layer "F.SilkS")
			(hide yes)
			(effects
				(font
					(size 1.27 1.27)
				)
			)
		)
		(property "Value" ""
			(at 0 0 180)
			(layer "F.Fab")
			(effects
				(font
					(size 1.27 1.27)
				)
			)
		)
		(duplicate_pad_numbers_are_jumpers no)
		(fp_line
			(start 0.7874 0.4064)
			(end -0.7874 0.4064)
			(stroke
				(width 0.1524)
				(type default)
			)
			(layer "F.SilkS")
		)
		(fp_line
			(start 0.7874 -0.4064)
			(end 0.7874 0.4064)
			(stroke
				(width 0.1524)
				(type default)
			)
			(layer "F.SilkS")
		)
		(fp_line
			(start -0.7874 0.4064)
			(end -0.7874 -0.4064)
			(stroke
				(width 0.1524)
				(type default)
			)
			(layer "F.SilkS")
		)
		(fp_line
			(start -0.7874 -0.4064)
			(end 0.7874 -0.4064)
			(stroke
				(width 0.1524)
				(type default)
			)
			(layer "F.SilkS")
		)
		(fp_line
			(start 0.67945 0.3048)
			(end 0.120396 0.3048)
			(stroke
				(width 0.1)
				(type default)
			)
			(layer "F.Fab")
		)
		(fp_line
			(start 0.67945 -0.3048)
			(end 0.67945 0.3048)
			(stroke
				(width 0.1)
				(type default)
			)
			(layer "F.Fab")
		)
		(fp_line
			(start 0.12065 -0.2794)
			(end 0.12065 -0.3048)
			(stroke
				(width 0.1)
				(type default)
			)
			(layer "F.Fab")
		)
		(fp_line
			(start 0.12065 -0.3048)
			(end 0.67945 -0.3048)
			(stroke
				(width 0.1)
				(type default)
			)
			(layer "F.Fab")
		)
		(fp_line
			(start 0.120396 0.3048)
			(end 0.120396 0.2794)
			(stroke
				(width 0.1)
				(type default)
			)
			(layer "F.Fab")
		)
		(fp_line
			(start 0.120396 0.2794)
			(end -0.12065 0.2794)
			(stroke
				(width 0.1)
				(type default)
			)
			(layer "F.Fab")
		)
		(fp_line
			(start -0.12065 0.3048)
			(end -0.67945 0.3048)
			(stroke
				(width 0.1)
				(type default)
			)
			(layer "F.Fab")
		)
		(fp_line
			(start -0.12065 0.2794)
			(end -0.12065 0.3048)
			(stroke
				(width 0.1)
				(type default)
			)
			(layer "F.Fab")
		)
		(fp_line
			(start -0.12065 -0.2794)
			(end 0.12065 -0.2794)
			(stroke
				(width 0.1)
				(type default)
			)
			(layer "F.Fab")
		)
		(fp_line
			(start -0.12065 -0.305054)
			(end -0.12065 -0.2794)
			(stroke
				(width 0.1)
				(type default)
			)
			(layer "F.Fab")
		)
		(fp_line
			(start -0.67945 0.3048)
			(end -0.67945 -0.305054)
			(stroke
				(width 0.1)
				(type default)
			)
			(layer "F.Fab")
		)
		(fp_line
			(start -0.67945 -0.305054)
			(end -0.12065 -0.305054)
			(stroke
				(width 0.1)
				(type default)
			)
			(layer "F.Fab")
		)
		(pad "1" smd circle
			(at -0.40005 0 180)
			(size 0 0)
			(layers "F.Cu" "F.Mask" "F.Paste")
			(net "P3V3_AUX")
		)
		(pad "2" smd circle
			(at 0.40005 0 180)
			(size 0 0)
			(layers "F.Cu" "F.Mask" "F.Paste")
			(net "GND")
		)
	)
	(footprint ""
		(layer "F.Cu")
		(at 396.209266 -83.785202 180)
		(property "Reference" "R1757"
			(at 0 0 180)
			(layer "F.SilkS")
			(hide yes)
			(effects
				(font
					(size 1.27 1.27)
				)
			)
		)
		(property "Value" ""
			(at 0 0 180)
			(layer "F.Fab")
			(effects
				(font
					(size 1.27 1.27)
				)
			)
		)
		(duplicate_pad_numbers_are_jumpers no)
		(fp_line
			(start 0.7874 0.4064)
			(end -0.7874 0.4064)
			(stroke
				(width 0.1524)
				(type default)
			)
			(layer "F.SilkS")
		)
		(fp_line
			(start 0.7874 -0.4064)
			(end 0.7874 0.4064)
			(stroke
				(width 0.1524)
				(type default)
			)
			(layer "F.SilkS")
		)
		(fp_line
			(start -0.7874 0.4064)
			(end -0.7874 -0.4064)
			(stroke
				(width 0.1524)
				(type default)
			)
			(layer "F.SilkS")
		)
		(fp_line
			(start -0.7874 -0.4064)
			(end 0.7874 -0.4064)
			(stroke
				(width 0.1524)
				(type default)
			)
			(layer "F.SilkS")
		)
		(fp_line
			(start 0.67945 0.3048)
			(end 0.120396 0.3048)
			(stroke
				(width 0.1)
				(type default)
			)
			(layer "F.Fab")
		)
		(fp_line
			(start 0.67945 -0.3048)
			(end 0.67945 0.3048)
			(stroke
				(width 0.1)
				(type default)
			)
			(layer "F.Fab")
		)
		(fp_line
			(start 0.12065 -0.2794)
			(end 0.12065 -0.3048)
			(stroke
				(width 0.1)
				(type default)
			)
			(layer "F.Fab")
		)
		(fp_line
			(start 0.12065 -0.3048)
			(end 0.67945 -0.3048)
			(stroke
				(width 0.1)
				(type default)
			)
			(layer "F.Fab")
		)
		(fp_line
			(start 0.120396 0.3048)
			(end 0.120396 0.2794)
			(stroke
				(width 0.1)
				(type default)
			)
			(layer "F.Fab")
		)
		(fp_line
			(start 0.120396 0.2794)
			(end -0.12065 0.2794)
			(stroke
				(width 0.1)
				(type default)
			)
			(layer "F.Fab")
		)
		(fp_line
			(start -0.12065 0.3048)
			(end -0.67945 0.3048)
			(stroke
				(width 0.1)
				(type default)
			)
			(layer "F.Fab")
		)
		(fp_line
			(start -0.12065 0.2794)
			(end -0.12065 0.3048)
			(stroke
				(width 0.1)
				(type default)
			)
			(layer "F.Fab")
		)
		(fp_line
			(start -0.12065 -0.2794)
			(end 0.12065 -0.2794)
			(stroke
				(width 0.1)
				(type default)
			)
			(layer "F.Fab")
		)
		(fp_line
			(start -0.12065 -0.305054)
			(end -0.12065 -0.2794)
			(stroke
				(width 0.1)
				(type default)
			)
			(layer "F.Fab")
		)
		(fp_line
			(start -0.67945 0.3048)
			(end -0.67945 -0.305054)
			(stroke
				(width 0.1)
				(type default)
			)
			(layer "F.Fab")
		)
		(fp_line
			(start -0.67945 -0.305054)
			(end -0.12065 -0.305054)
			(stroke
				(width 0.1)
				(type default)
			)
			(layer "F.Fab")
		)
		(pad "1" smd circle
			(at -0.40005 0 180)
			(size 0 0)
			(layers "F.Cu" "F.Mask" "F.Paste")
			(net "P3V3_AUX")
		)
		(pad "2" smd circle
			(at 0.40005 0 180)
			(size 0 0)
			(layers "F.Cu" "F.Mask" "F.Paste")
			(net "SMB_BIC_I2C6_MUX_CLK_R_SCL")
		)
	)
	(footprint ""
		(layer "F.Cu")
		(at 246.82704 -258.039616 -90)
		(property "Reference" "R6529"
			(at 0 0 270)
			(layer "F.SilkS")
			(hide yes)
			(effects
				(font
					(size 1.27 1.27)
				)
			)
		)
		(property "Value" ""
			(at 0 0 270)
			(layer "F.Fab")
			(effects
				(font
					(size 1.27 1.27)
				)
			)
		)
		(duplicate_pad_numbers_are_jumpers no)
		(fp_line
			(start -0.7874 0.4064)
			(end -0.7874 -0.4064)
			(stroke
				(width 0.1524)
				(type default)
			)
			(layer "F.SilkS")
		)
		(fp_line
			(start 0.7874 0.4064)
			(end -0.7874 0.4064)
			(stroke
				(width 0.1524)
				(type default)
			)
			(layer "F.SilkS")
		)
		(fp_line
			(start -0.7874 -0.4064)
			(end 0.7874 -0.4064)
			(stroke
				(width 0.1524)
				(type default)
			)
			(layer "F.SilkS")
		)
		(fp_line
			(start 0.7874 -0.4064)
			(end 0.7874 0.4064)
			(stroke
				(width 0.1524)
				(type default)
			)
			(layer "F.SilkS")
		)
		(fp_line
			(start -0.67945 0.3048)
			(end -0.67945 -0.305054)
			(stroke
				(width 0.1)
				(type default)
			)
			(layer "F.Fab")
		)
		(fp_line
			(start -0.12065 0.3048)
			(end -0.67945 0.3048)
			(stroke
				(width 0.1)
				(type default)
			)
			(layer "F.Fab")
		)
		(fp_line
			(start 0.120396 0.3048)
			(end 0.120396 0.2794)
			(stroke
				(width 0.1)
				(type default)
			)
			(layer "F.Fab")
		)
		(fp_line
			(start 0.67945 0.3048)
			(end 0.120396 0.3048)
			(stroke
				(width 0.1)
				(type default)
			)
			(layer "F.Fab")
		)
		(fp_line
			(start -0.12065 0.2794)
			(end -0.12065 0.3048)
			(stroke
				(width 0.1)
				(type default)
			)
			(layer "F.Fab")
		)
		(fp_line
			(start 0.120396 0.2794)
			(end -0.12065 0.2794)
			(stroke
				(width 0.1)
				(type default)
			)
			(layer "F.Fab")
		)
		(fp_line
			(start -0.12065 -0.2794)
			(end 0.12065 -0.2794)
			(stroke
				(width 0.1)
				(type default)
			)
			(layer "F.Fab")
		)
		(fp_line
			(start 0.12065 -0.2794)
			(end 0.12065 -0.3048)
			(stroke
				(width 0.1)
				(type default)
			)
			(layer "F.Fab")
		)
		(fp_line
			(start 0.12065 -0.3048)
			(end 0.67945 -0.3048)
			(stroke
				(width 0.1)
				(type default)
			)
			(layer "F.Fab")
		)
		(fp_line
			(start 0.67945 -0.3048)
			(end 0.67945 0.3048)
			(stroke
				(width 0.1)
				(type default)
			)
			(layer "F.Fab")
		)
		(fp_line
			(start -0.67945 -0.305054)
			(end -0.12065 -0.305054)
			(stroke
				(width 0.1)
				(type default)
			)
			(layer "F.Fab")
		)
		(fp_line
			(start -0.12065 -0.305054)
			(end -0.12065 -0.2794)
			(stroke
				(width 0.1)
				(type default)
			)
			(layer "F.Fab")
		)
		(pad "1" smd circle
			(at -0.40005 0 270)
			(size 0 0)
			(layers "F.Cu" "F.Mask" "F.Paste")
			(net "P1V25_SERDES_VDDPLL_PEX2")
		)
		(pad "2" smd circle
			(at 0.40005 0 270)
			(size 0 0)
			(layers "F.Cu" "F.Mask" "F.Paste")
			(net "P1V25_SERDES_VDDPLL_PEX2_C6")
		)
	)
	(footprint ""
		(layer "F.Cu")
		(at 58.995056 -103.814372 180)
		(property "Reference" "R69"
			(at 0 0 180)
			(layer "F.SilkS")
			(hide yes)
			(effects
				(font
					(size 1.27 1.27)
				)
			)
		)
		(property "Value" ""
			(at 0 0 180)
			(layer "F.Fab")
			(effects
				(font
					(size 1.27 1.27)
				)
			)
		)
		(duplicate_pad_numbers_are_jumpers no)
		(fp_line
			(start 0.7874 0.4064)
			(end -0.7874 0.4064)
			(stroke
				(width 0.1524)
				(type default)
			)
			(layer "F.SilkS")
		)
		(fp_line
			(start 0.7874 -0.4064)
			(end 0.7874 0.4064)
			(stroke
				(width 0.1524)
				(type default)
			)
			(layer "F.SilkS")
		)
		(fp_line
			(start -0.7874 0.4064)
			(end -0.7874 -0.4064)
			(stroke
				(width 0.1524)
				(type default)
			)
			(layer "F.SilkS")
		)
		(fp_line
			(start -0.7874 -0.4064)
			(end 0.7874 -0.4064)
			(stroke
				(width 0.1524)
				(type default)
			)
			(layer "F.SilkS")
		)
		(fp_line
			(start 0.67945 0.3048)
			(end 0.120396 0.3048)
			(stroke
				(width 0.1)
				(type default)
			)
			(layer "F.Fab")
		)
		(fp_line
			(start 0.67945 -0.3048)
			(end 0.67945 0.3048)
			(stroke
				(width 0.1)
				(type default)
			)
			(layer "F.Fab")
		)
		(fp_line
			(start 0.12065 -0.2794)
			(end 0.12065 -0.3048)
			(stroke
				(width 0.1)
				(type default)
			)
			(layer "F.Fab")
		)
		(fp_line
			(start 0.12065 -0.3048)
			(end 0.67945 -0.3048)
			(stroke
				(width 0.1)
				(type default)
			)
			(layer "F.Fab")
		)
		(fp_line
			(start 0.120396 0.3048)
			(end 0.120396 0.2794)
			(stroke
				(width 0.1)
				(type default)
			)
			(layer "F.Fab")
		)
		(fp_line
			(start 0.120396 0.2794)
			(end -0.12065 0.2794)
			(stroke
				(width 0.1)
				(type default)
			)
			(layer "F.Fab")
		)
		(fp_line
			(start -0.12065 0.3048)
			(end -0.67945 0.3048)
			(stroke
				(width 0.1)
				(type default)
			)
			(layer "F.Fab")
		)
		(fp_line
			(start -0.12065 0.2794)
			(end -0.12065 0.3048)
			(stroke
				(width 0.1)
				(type default)
			)
			(layer "F.Fab")
		)
		(fp_line
			(start -0.12065 -0.2794)
			(end 0.12065 -0.2794)
			(stroke
				(width 0.1)
				(type default)
			)
			(layer "F.Fab")
		)
		(fp_line
			(start -0.12065 -0.305054)
			(end -0.12065 -0.2794)
			(stroke
				(width 0.1)
				(type default)
			)
			(layer "F.Fab")
		)
		(fp_line
			(start -0.67945 0.3048)
			(end -0.67945 -0.305054)
			(stroke
				(width 0.1)
				(type default)
			)
			(layer "F.Fab")
		)
		(fp_line
			(start -0.67945 -0.305054)
			(end -0.12065 -0.305054)
			(stroke
				(width 0.1)
				(type default)
			)
			(layer "F.Fab")
		)
		(pad "1" smd circle
			(at -0.40005 0 180)
			(size 0 0)
			(layers "F.Cu" "F.Mask" "F.Paste")
			(net "NCSI_NIC1_TXD0")
		)
		(pad "2" smd circle
			(at 0.40005 0 180)
			(size 0 0)
			(layers "F.Cu" "F.Mask" "F.Paste")
			(net "GND")
		)
	)
	(footprint ""
		(layer "F.Cu")
		(at 128.674876 -251.26569 180)
		(property "Reference" "PR69"
			(at 0 0 180)
			(layer "F.SilkS")
			(hide yes)
			(effects
				(font
					(size 1.27 1.27)
				)
			)
		)
		(property "Value" ""
			(at 0 0 180)
			(layer "F.Fab")
			(effects
				(font
					(size 1.27 1.27)
				)
			)
		)
		(duplicate_pad_numbers_are_jumpers no)
		(fp_line
			(start 0.7874 0.4064)
			(end -0.7874 0.4064)
			(stroke
				(width 0.1524)
				(type default)
			)
			(layer "F.SilkS")
		)
		(fp_line
			(start 0.7874 -0.4064)
			(end 0.7874 0.4064)
			(stroke
				(width 0.1524)
				(type default)
			)
			(layer "F.SilkS")
		)
		(fp_line
			(start -0.7874 0.4064)
			(end -0.7874 -0.4064)
			(stroke
				(width 0.1524)
				(type default)
			)
			(layer "F.SilkS")
		)
		(fp_line
			(start -0.7874 -0.4064)
			(end 0.7874 -0.4064)
			(stroke
				(width 0.1524)
				(type default)
			)
			(layer "F.SilkS")
		)
		(fp_line
			(start 0.67945 0.3048)
			(end 0.120396 0.3048)
			(stroke
				(width 0.1)
				(type default)
			)
			(layer "F.Fab")
		)
		(fp_line
			(start 0.67945 -0.3048)
			(end 0.67945 0.3048)
			(stroke
				(width 0.1)
				(type default)
			)
			(layer "F.Fab")
		)
		(fp_line
			(start 0.12065 -0.2794)
			(end 0.12065 -0.3048)
			(stroke
				(width 0.1)
				(type default)
			)
			(layer "F.Fab")
		)
		(fp_line
			(start 0.12065 -0.3048)
			(end 0.67945 -0.3048)
			(stroke
				(width 0.1)
				(type default)
			)
			(layer "F.Fab")
		)
		(fp_line
			(start 0.120396 0.3048)
			(end 0.120396 0.2794)
			(stroke
				(width 0.1)
				(type default)
			)
			(layer "F.Fab")
		)
		(fp_line
			(start 0.120396 0.2794)
			(end -0.12065 0.2794)
			(stroke
				(width 0.1)
				(type default)
			)
			(layer "F.Fab")
		)
		(fp_line
			(start -0.12065 0.3048)
			(end -0.67945 0.3048)
			(stroke
				(width 0.1)
				(type default)
			)
			(layer "F.Fab")
		)
		(fp_line
			(start -0.12065 0.2794)
			(end -0.12065 0.3048)
			(stroke
				(width 0.1)
				(type default)
			)
			(layer "F.Fab")
		)
		(fp_line
			(start -0.12065 -0.2794)
			(end 0.12065 -0.2794)
			(stroke
				(width 0.1)
				(type default)
			)
			(layer "F.Fab")
		)
		(fp_line
			(start -0.12065 -0.305054)
			(end -0.12065 -0.2794)
			(stroke
				(width 0.1)
				(type default)
			)
			(layer "F.Fab")
		)
		(fp_line
			(start -0.67945 0.3048)
			(end -0.67945 -0.305054)
			(stroke
				(width 0.1)
				(type default)
			)
			(layer "F.Fab")
		)
		(fp_line
			(start -0.67945 -0.305054)
			(end -0.12065 -0.305054)
			(stroke
				(width 0.1)
				(type default)
			)
			(layer "F.Fab")
		)
		(pad "1" smd circle
			(at -0.40005 0 180)
			(size 0 0)
			(layers "F.Cu" "F.Mask" "F.Paste")
			(net "SMB_PJP1_SCL")
		)
		(pad "2" smd circle
			(at 0.40005 0 180)
			(size 0 0)
			(layers "F.Cu" "F.Mask" "F.Paste")
			(net "SMB_BIC_I2C6_MUX_VR_R_SCL")
		)
	)
	(footprint ""
		(layer "F.Cu")
		(at 231.412288 -97.258378 -90)
		(property "Reference" "R1016"
			(at 0 0 270)
			(layer "F.SilkS")
			(hide yes)
			(effects
				(font
					(size 1.27 1.27)
				)
			)
		)
		(property "Value" ""
			(at 0 0 270)
			(layer "F.Fab")
			(effects
				(font
					(size 1.27 1.27)
				)
			)
		)
		(duplicate_pad_numbers_are_jumpers no)
		(fp_line
			(start -0.7874 0.4064)
			(end -0.7874 -0.4064)
			(stroke
				(width 0.1524)
				(type default)
			)
			(layer "F.SilkS")
		)
		(fp_line
			(start 0.7874 0.4064)
			(end -0.7874 0.4064)
			(stroke
				(width 0.1524)
				(type default)
			)
			(layer "F.SilkS")
		)
		(fp_line
			(start -0.7874 -0.4064)
			(end 0.7874 -0.4064)
			(stroke
				(width 0.1524)
				(type default)
			)
			(layer "F.SilkS")
		)
		(fp_line
			(start 0.7874 -0.4064)
			(end 0.7874 0.4064)
			(stroke
				(width 0.1524)
				(type default)
			)
			(layer "F.SilkS")
		)
		(fp_line
			(start -0.67945 0.3048)
			(end -0.67945 -0.305054)
			(stroke
				(width 0.1)
				(type default)
			)
			(layer "F.Fab")
		)
		(fp_line
			(start -0.12065 0.3048)
			(end -0.67945 0.3048)
			(stroke
				(width 0.1)
				(type default)
			)
			(layer "F.Fab")
		)
		(fp_line
			(start 0.120396 0.3048)
			(end 0.120396 0.2794)
			(stroke
				(width 0.1)
				(type default)
			)
			(layer "F.Fab")
		)
		(fp_line
			(start 0.67945 0.3048)
			(end 0.120396 0.3048)
			(stroke
				(width 0.1)
				(type default)
			)
			(layer "F.Fab")
		)
		(fp_line
			(start -0.12065 0.2794)
			(end -0.12065 0.3048)
			(stroke
				(width 0.1)
				(type default)
			)
			(layer "F.Fab")
		)
		(fp_line
			(start 0.120396 0.2794)
			(end -0.12065 0.2794)
			(stroke
				(width 0.1)
				(type default)
			)
			(layer "F.Fab")
		)
		(fp_line
			(start -0.12065 -0.2794)
			(end 0.12065 -0.2794)
			(stroke
				(width 0.1)
				(type default)
			)
			(layer "F.Fab")
		)
		(fp_line
			(start 0.12065 -0.2794)
			(end 0.12065 -0.3048)
			(stroke
				(width 0.1)
				(type default)
			)
			(layer "F.Fab")
		)
		(fp_line
			(start 0.12065 -0.3048)
			(end 0.67945 -0.3048)
			(stroke
				(width 0.1)
				(type default)
			)
			(layer "F.Fab")
		)
		(fp_line
			(start 0.67945 -0.3048)
			(end 0.67945 0.3048)
			(stroke
				(width 0.1)
				(type default)
			)
			(layer "F.Fab")
		)
		(fp_line
			(start -0.67945 -0.305054)
			(end -0.12065 -0.305054)
			(stroke
				(width 0.1)
				(type default)
			)
			(layer "F.Fab")
		)
		(fp_line
			(start -0.12065 -0.305054)
			(end -0.12065 -0.2794)
			(stroke
				(width 0.1)
				(type default)
			)
			(layer "F.Fab")
		)
		(pad "1" smd circle
			(at -0.40005 0 270)
			(size 0 0)
			(layers "F.Cu" "F.Mask" "F.Paste")
			(net "P3V3_AUX")
		)
		(pad "2" smd circle
			(at 0.40005 0 270)
			(size 0 0)
			(layers "F.Cu" "F.Mask" "F.Paste")
			(net "PEX_USB_HUB_OVCUR3")
		)
	)
	(footprint ""
		(layer "F.Cu")
		(at 375.291096 -255.359662)
		(property "Reference" "C3587"
			(at 0 0 0)
			(layer "F.SilkS")
			(hide yes)
			(effects
				(font
					(size 1.27 1.27)
				)
			)
		)
		(property "Value" ""
			(at 0 0 0)
			(layer "F.Fab")
			(effects
				(font
					(size 1.27 1.27)
				)
			)
		)
		(duplicate_pad_numbers_are_jumpers no)
		(fp_line
			(start -1.2954 -0.5842)
			(end 1.2954 -0.5842)
			(stroke
				(width 0.1524)
				(type default)
			)
			(layer "F.SilkS")
		)
		(fp_line
			(start -1.2954 0.5842)
			(end -1.2954 -0.5842)
			(stroke
				(width 0.1524)
				(type default)
			)
			(layer "F.SilkS")
		)
		(fp_line
			(start 1.2954 -0.5842)
			(end 1.2954 0.5842)
			(stroke
				(width 0.1524)
				(type default)
			)
			(layer "F.SilkS")
		)
		(fp_line
			(start 1.2954 0.5842)
			(end -1.2954 0.5842)
			(stroke
				(width 0.1524)
				(type default)
			)
			(layer "F.SilkS")
		)
		(fp_line
			(start -1.1938 -0.4064)
			(end -0.8636 -0.4064)
			(stroke
				(width 0.1)
				(type default)
			)
			(layer "F.Fab")
		)
		(fp_line
			(start -1.1938 0.4064)
			(end -1.1938 -0.4064)
			(stroke
				(width 0.1)
				(type default)
			)
			(layer "F.Fab")
		)
		(fp_line
			(start -0.8636 -0.4572)
			(end 0.8636 -0.4572)
			(stroke
				(width 0.1)
				(type default)
			)
			(layer "F.Fab")
		)
		(fp_line
			(start -0.8636 -0.4064)
			(end -0.8636 -0.4572)
			(stroke
				(width 0.1)
				(type default)
			)
			(layer "F.Fab")
		)
		(fp_line
			(start -0.8636 0.4064)
			(end -1.1938 0.4064)
			(stroke
				(width 0.1)
				(type default)
			)
			(layer "F.Fab")
		)
		(fp_line
			(start -0.8636 0.4572)
			(end -0.8636 0.4064)
			(stroke
				(width 0.1)
				(type default)
			)
			(layer "F.Fab")
		)
		(fp_line
			(start 0.8636 -0.4572)
			(end 0.8636 -0.4064)
			(stroke
				(width 0.1)
				(type default)
			)
			(layer "F.Fab")
		)
		(fp_line
			(start 0.8636 -0.4064)
			(end 1.1938 -0.4064)
			(stroke
				(width 0.1)
				(type default)
			)
			(layer "F.Fab")
		)
		(fp_line
			(start 0.8636 0.4064)
			(end 0.8636 0.4572)
			(stroke
				(width 0.1)
				(type default)
			)
			(layer "F.Fab")
		)
		(fp_line
			(start 0.8636 0.4572)
			(end -0.8636 0.4572)
			(stroke
				(width 0.1)
				(type default)
			)
			(layer "F.Fab")
		)
		(fp_line
			(start 1.1938 -0.4064)
			(end 1.1938 0.4064)
			(stroke
				(width 0.1)
				(type default)
			)
			(layer "F.Fab")
		)
		(fp_line
			(start 1.1938 0.4064)
			(end 0.8636 0.4064)
			(stroke
				(width 0.1)
				(type default)
			)
			(layer "F.Fab")
		)
		(pad "1" smd rect
			(at -0.7366 0 270)
			(size 0.7112 0.8128)
			(layers "F.Cu" "F.Mask" "F.Paste")
			(net "P1V8_PLL0_PEX3")
		)
		(pad "2" smd rect
			(at 0.7366 0 270)
			(size 0.7112 0.8128)
			(layers "F.Cu" "F.Mask" "F.Paste")
			(net "GND")
		)
	)
	(footprint ""
		(layer "F.Cu")
		(at 34.851848 -350.098614 90)
		(property "Reference" "C2166"
			(at 0 0 90)
			(layer "F.SilkS")
			(hide yes)
			(effects
				(font
					(size 1.27 1.27)
				)
			)
		)
		(property "Value" ""
			(at 0 0 90)
			(layer "F.Fab")
			(effects
				(font
					(size 1.27 1.27)
				)
			)
		)
		(duplicate_pad_numbers_are_jumpers no)
		(fp_line
			(start 0.299974 -0.150114)
			(end 0.299974 0.150114)
			(stroke
				(width 0.1)
				(type default)
			)
			(layer "F.Fab")
		)
		(fp_line
			(start -0.299974 -0.150114)
			(end 0.299974 -0.150114)
			(stroke
				(width 0.1)
				(type default)
			)
			(layer "F.Fab")
		)
		(fp_line
			(start 0.299974 0.150114)
			(end -0.299974 0.150114)
			(stroke
				(width 0.1)
				(type default)
			)
			(layer "F.Fab")
		)
		(fp_line
			(start -0.299974 0.150114)
			(end -0.299974 -0.150114)
			(stroke
				(width 0.1)
				(type default)
			)
			(layer "F.Fab")
		)
		(pad "1" smd rect
			(at -0.2667 0 90)
			(size 0.3048 0.381)
			(layers "F.Cu" "F.Mask" "F.Paste")
			(net "P5E_PEX0_STN4_TX_DP<72>")
		)
		(pad "2" smd rect
			(at 0.2667 0 90)
			(size 0.3048 0.381)
			(layers "F.Cu" "F.Mask" "F.Paste")
			(net "P5E_PEX0_STN4_TX_C_DP<72>")
		)
	)
	(footprint ""
		(layer "F.Cu")
		(at 78.267814 -55.083456)
		(property "Reference" "PC397"
			(at 0 0 0)
			(layer "F.SilkS")
			(hide yes)
			(effects
				(font
					(size 1.27 1.27)
				)
			)
		)
		(property "Value" ""
			(at 0 0 0)
			(layer "F.Fab")
			(effects
				(font
					(size 1.27 1.27)
				)
			)
		)
		(duplicate_pad_numbers_are_jumpers no)
		(fp_line
			(start -0.7874 -0.4064)
			(end 0.7874 -0.4064)
			(stroke
				(width 0.1524)
				(type default)
			)
			(layer "F.SilkS")
		)
		(fp_line
			(start -0.7874 0.4064)
			(end -0.7874 -0.4064)
			(stroke
				(width 0.1524)
				(type default)
			)
			(layer "F.SilkS")
		)
		(fp_line
			(start 0.7874 -0.4064)
			(end 0.7874 0.4064)
			(stroke
				(width 0.1524)
				(type default)
			)
			(layer "F.SilkS")
		)
		(fp_line
			(start 0.7874 0.4064)
			(end -0.7874 0.4064)
			(stroke
				(width 0.1524)
				(type default)
			)
			(layer "F.SilkS")
		)
		(fp_line
			(start -0.67945 -0.305054)
			(end -0.12065 -0.305054)
			(stroke
				(width 0.1)
				(type default)
			)
			(layer "F.Fab")
		)
		(fp_line
			(start -0.67945 0.3048)
			(end -0.67945 -0.305054)
			(stroke
				(width 0.1)
				(type default)
			)
			(layer "F.Fab")
		)
		(fp_line
			(start -0.12065 -0.305054)
			(end -0.12065 -0.2794)
			(stroke
				(width 0.1)
				(type default)
			)
			(layer "F.Fab")
		)
		(fp_line
			(start -0.12065 -0.2794)
			(end 0.12065 -0.2794)
			(stroke
				(width 0.1)
				(type default)
			)
			(layer "F.Fab")
		)
		(fp_line
			(start -0.12065 0.2794)
			(end -0.12065 0.3048)
			(stroke
				(width 0.1)
				(type default)
			)
			(layer "F.Fab")
		)
		(fp_line
			(start -0.12065 0.3048)
			(end -0.67945 0.3048)
			(stroke
				(width 0.1)
				(type default)
			)
			(layer "F.Fab")
		)
		(fp_line
			(start 0.120396 0.2794)
			(end -0.12065 0.2794)
			(stroke
				(width 0.1)
				(type default)
			)
			(layer "F.Fab")
		)
		(fp_line
			(start 0.120396 0.3048)
			(end 0.120396 0.2794)
			(stroke
				(width 0.1)
				(type default)
			)
			(layer "F.Fab")
		)
		(fp_line
			(start 0.12065 -0.3048)
			(end 0.67945 -0.3048)
			(stroke
				(width 0.1)
				(type default)
			)
			(layer "F.Fab")
		)
		(fp_line
			(start 0.12065 -0.2794)
			(end 0.12065 -0.3048)
			(stroke
				(width 0.1)
				(type default)
			)
			(layer "F.Fab")
		)
		(fp_line
			(start 0.67945 -0.3048)
			(end 0.67945 0.3048)
			(stroke
				(width 0.1)
				(type default)
			)
			(layer "F.Fab")
		)
		(fp_line
			(start 0.67945 0.3048)
			(end 0.120396 0.3048)
			(stroke
				(width 0.1)
				(type default)
			)
			(layer "F.Fab")
		)
		(pad "1" smd circle
			(at -0.40005 0)
			(size 0 0)
			(layers "F.Cu" "F.Mask" "F.Paste")
			(net "P5V_AUX")
		)
		(pad "2" smd circle
			(at 0.40005 0)
			(size 0 0)
			(layers "F.Cu" "F.Mask" "F.Paste")
			(net "GND")
		)
	)
	(footprint ""
		(layer "F.Cu")
		(at 162.355276 -35.876738)
		(property "Reference" "R6068"
			(at 0 0 0)
			(layer "F.SilkS")
			(hide yes)
			(effects
				(font
					(size 1.27 1.27)
				)
			)
		)
		(property "Value" ""
			(at 0 0 0)
			(layer "F.Fab")
			(effects
				(font
					(size 1.27 1.27)
				)
			)
		)
		(duplicate_pad_numbers_are_jumpers no)
		(fp_line
			(start -0.7874 -0.4064)
			(end 0.7874 -0.4064)
			(stroke
				(width 0.1524)
				(type default)
			)
			(layer "F.SilkS")
		)
		(fp_line
			(start -0.7874 0.4064)
			(end -0.7874 -0.4064)
			(stroke
				(width 0.1524)
				(type default)
			)
			(layer "F.SilkS")
		)
		(fp_line
			(start 0.7874 -0.4064)
			(end 0.7874 0.4064)
			(stroke
				(width 0.1524)
				(type default)
			)
			(layer "F.SilkS")
		)
		(fp_line
			(start 0.7874 0.4064)
			(end -0.7874 0.4064)
			(stroke
				(width 0.1524)
				(type default)
			)
			(layer "F.SilkS")
		)
		(fp_line
			(start -0.67945 -0.305054)
			(end -0.12065 -0.305054)
			(stroke
				(width 0.1)
				(type default)
			)
			(layer "F.Fab")
		)
		(fp_line
			(start -0.67945 0.3048)
			(end -0.67945 -0.305054)
			(stroke
				(width 0.1)
				(type default)
			)
			(layer "F.Fab")
		)
		(fp_line
			(start -0.12065 -0.305054)
			(end -0.12065 -0.2794)
			(stroke
				(width 0.1)
				(type default)
			)
			(layer "F.Fab")
		)
		(fp_line
			(start -0.12065 -0.2794)
			(end 0.12065 -0.2794)
			(stroke
				(width 0.1)
				(type default)
			)
			(layer "F.Fab")
		)
		(fp_line
			(start -0.12065 0.2794)
			(end -0.12065 0.3048)
			(stroke
				(width 0.1)
				(type default)
			)
			(layer "F.Fab")
		)
		(fp_line
			(start -0.12065 0.3048)
			(end -0.67945 0.3048)
			(stroke
				(width 0.1)
				(type default)
			)
			(layer "F.Fab")
		)
		(fp_line
			(start 0.120396 0.2794)
			(end -0.12065 0.2794)
			(stroke
				(width 0.1)
				(type default)
			)
			(layer "F.Fab")
		)
		(fp_line
			(start 0.120396 0.3048)
			(end 0.120396 0.2794)
			(stroke
				(width 0.1)
				(type default)
			)
			(layer "F.Fab")
		)
		(fp_line
			(start 0.12065 -0.3048)
			(end 0.67945 -0.3048)
			(stroke
				(width 0.1)
				(type default)
			)
			(layer "F.Fab")
		)
		(fp_line
			(start 0.12065 -0.2794)
			(end 0.12065 -0.3048)
			(stroke
				(width 0.1)
				(type default)
			)
			(layer "F.Fab")
		)
		(fp_line
			(start 0.67945 -0.3048)
			(end 0.67945 0.3048)
			(stroke
				(width 0.1)
				(type default)
			)
			(layer "F.Fab")
		)
		(fp_line
			(start 0.67945 0.3048)
			(end 0.120396 0.3048)
			(stroke
				(width 0.1)
				(type default)
			)
			(layer "F.Fab")
		)
		(pad "1" smd circle
			(at -0.40005 0)
			(size 0 0)
			(layers "F.Cu" "F.Mask" "F.Paste")
			(net "P3V3_AUX")
		)
		(pad "2" smd circle
			(at 0.40005 0)
			(size 0 0)
			(layers "F.Cu" "F.Mask" "F.Paste")
			(net "PWRGD_P3V3_SSD6_D")
		)
	)
	(footprint ""
		(layer "F.Cu")
		(at 314.861448 -131.686808 180)
		(property "Reference" "C444"
			(at 0 0 180)
			(layer "F.SilkS")
			(hide yes)
			(effects
				(font
					(size 1.27 1.27)
				)
			)
		)
		(property "Value" ""
			(at 0 0 180)
			(layer "F.Fab")
			(effects
				(font
					(size 1.27 1.27)
				)
			)
		)
		(duplicate_pad_numbers_are_jumpers no)
		(fp_line
			(start 0.299974 0.150114)
			(end -0.299974 0.150114)
			(stroke
				(width 0.1)
				(type default)
			)
			(layer "F.Fab")
		)
		(fp_line
			(start 0.299974 -0.150114)
			(end 0.299974 0.150114)
			(stroke
				(width 0.1)
				(type default)
			)
			(layer "F.Fab")
		)
		(fp_line
			(start -0.299974 0.150114)
			(end -0.299974 -0.150114)
			(stroke
				(width 0.1)
				(type default)
			)
			(layer "F.Fab")
		)
		(fp_line
			(start -0.299974 -0.150114)
			(end 0.299974 -0.150114)
			(stroke
				(width 0.1)
				(type default)
			)
			(layer "F.Fab")
		)
		(pad "1" smd rect
			(at -0.2667 0 180)
			(size 0.3048 0.381)
			(layers "F.Cu" "F.Mask" "F.Paste")
			(net "P5E_PEX2_STN0_TX_DN<5>")
		)
		(pad "2" smd rect
			(at 0.2667 0 180)
			(size 0.3048 0.381)
			(layers "F.Cu" "F.Mask" "F.Paste")
			(net "P5E_PEX2_STN0_TX_C_DN<5>")
		)
	)
	(footprint ""
		(layer "F.Cu")
		(at 188.675518 -69.47916 180)
		(property "Reference" "PU109"
			(at -1.978152 4.13004 90)
			(unlocked yes)
			(layer "F.SilkS")
			(effects
				(font
					(size 0.7874 0.5842)
					(thickness 0.1524)
				)
			)
		)
		(property "Value" ""
			(at 0 0 180)
			(layer "F.Fab")
			(effects
				(font
					(size 1.27 1.27)
				)
			)
		)
		(duplicate_pad_numbers_are_jumpers no)
		(fp_line
			(start 1.239774 1.495298)
			(end -1.239774 1.495298)
			(stroke
				(width 0.1524)
				(type default)
			)
			(layer "F.SilkS")
		)
		(fp_line
			(start 1.239774 -1.495298)
			(end 1.239774 1.495298)
			(stroke
				(width 0.1524)
				(type default)
			)
			(layer "F.SilkS")
		)
		(fp_line
			(start -1.239774 1.495298)
			(end -1.239774 -1.495298)
			(stroke
				(width 0.1524)
				(type default)
			)
			(layer "F.SilkS")
		)
		(fp_line
			(start -1.239774 -1.495298)
			(end 1.239774 -1.495298)
			(stroke
				(width 0.1524)
				(type default)
			)
			(layer "F.SilkS")
		)
		(fp_poly
			(pts
				(xy -1.742186 -1.195832) (xy -2.460752 -0.47752) (xy -1.38303 -0.118364)
			)
			(stroke
				(width 0)
				(type default)
			)
			(fill yes)
			(layer "F.SilkS")
		)
		(fp_line
			(start 0.8001 1.050036)
			(end -0.8001 1.050036)
			(stroke
				(width 0.1)
				(type default)
			)
			(layer "F.Fab")
		)
		(fp_line
			(start 0.8001 -1.050036)
			(end 0.8001 1.050036)
			(stroke
				(width 0.1)
				(type default)
			)
			(layer "F.Fab")
		)
		(fp_line
			(start -0.8001 1.050036)
			(end -0.8001 -1.050036)
			(stroke
				(width 0.1)
				(type default)
			)
			(layer "F.Fab")
		)
		(fp_line
			(start -0.8001 -1.050036)
			(end 0.8001 -1.050036)
			(stroke
				(width 0.1)
				(type default)
			)
			(layer "F.Fab")
		)
		(fp_poly
			(pts
				(xy -2.458974 -0.508) (xy -2.458974 0.508) (xy -1.442974 0)
			)
			(stroke
				(width 0)
				(type default)
			)
			(fill yes)
			(layer "F.Fab")
		)
		(pad "1_2" smd circle
			(at -0.374904 0 270)
			(size 0 0)
			(layers "F.Cu" "F.Mask" "F.Paste")
			(net "P12V_AUX")
		)
		(pad "3" smd rect
			(at -0.499872 0.999998 180)
			(size 0.254 0.7112)
			(layers "F.Cu" "F.Mask" "F.Paste")
			(net "GND")
		)
		(pad "4" smd rect
			(at 0 0.999998 180)
			(size 0.254 0.7112)
			(layers "F.Cu" "F.Mask" "F.Paste")
			(net "P12V_SSD6_CO_ILIMIT")
		)
		(pad "5" smd rect
			(at 0.499872 0.999998 180)
			(size 0.254 0.7112)
			(layers "F.Cu" "F.Mask" "F.Paste")
			(net "P12V_SSD6_CO_MODE")
		)
		(pad "6_7" smd circle
			(at 0.374904 0 90)
			(size 0 0)
			(layers "F.Cu" "F.Mask" "F.Paste")
			(net "P12V_SSD6_R")
		)
		(pad "8" smd rect
			(at 0.499872 -0.999998 180)
			(size 0.254 0.7112)
			(layers "F.Cu" "F.Mask" "F.Paste")
			(net "P12V_SSD6_CO_GATE")
		)
		(pad "9" smd rect
			(at 0 -0.999998 180)
			(size 0.254 0.7112)
			(layers "F.Cu" "F.Mask" "F.Paste")
			(net "P12V_SSD6_CO_EN")
		)
		(pad "10" smd rect
			(at -0.499872 -0.999998 180)
			(size 0.254 0.7112)
			(layers "F.Cu" "F.Mask" "F.Paste")
			(net "P12V_SSD6_CO_DV_DT")
		)
	)
	(footprint ""
		(layer "F.Cu")
		(at 318.32042 -26.666444 -90)
		(property "Reference" "R4075"
			(at 0 0 270)
			(layer "F.SilkS")
			(hide yes)
			(effects
				(font
					(size 1.27 1.27)
				)
			)
		)
		(property "Value" ""
			(at 0 0 270)
			(layer "F.Fab")
			(effects
				(font
					(size 1.27 1.27)
				)
			)
		)
		(duplicate_pad_numbers_are_jumpers no)
		(fp_line
			(start -0.7874 0.4064)
			(end -0.7874 -0.4064)
			(stroke
				(width 0.1524)
				(type default)
			)
			(layer "F.SilkS")
		)
		(fp_line
			(start 0.7874 0.4064)
			(end -0.7874 0.4064)
			(stroke
				(width 0.1524)
				(type default)
			)
			(layer "F.SilkS")
		)
		(fp_line
			(start -0.7874 -0.4064)
			(end 0.7874 -0.4064)
			(stroke
				(width 0.1524)
				(type default)
			)
			(layer "F.SilkS")
		)
		(fp_line
			(start 0.7874 -0.4064)
			(end 0.7874 0.4064)
			(stroke
				(width 0.1524)
				(type default)
			)
			(layer "F.SilkS")
		)
		(fp_line
			(start -0.67945 0.3048)
			(end -0.67945 -0.305054)
			(stroke
				(width 0.1)
				(type default)
			)
			(layer "F.Fab")
		)
		(fp_line
			(start -0.12065 0.3048)
			(end -0.67945 0.3048)
			(stroke
				(width 0.1)
				(type default)
			)
			(layer "F.Fab")
		)
		(fp_line
			(start 0.120396 0.3048)
			(end 0.120396 0.2794)
			(stroke
				(width 0.1)
				(type default)
			)
			(layer "F.Fab")
		)
		(fp_line
			(start 0.67945 0.3048)
			(end 0.120396 0.3048)
			(stroke
				(width 0.1)
				(type default)
			)
			(layer "F.Fab")
		)
		(fp_line
			(start -0.12065 0.2794)
			(end -0.12065 0.3048)
			(stroke
				(width 0.1)
				(type default)
			)
			(layer "F.Fab")
		)
		(fp_line
			(start 0.120396 0.2794)
			(end -0.12065 0.2794)
			(stroke
				(width 0.1)
				(type default)
			)
			(layer "F.Fab")
		)
		(fp_line
			(start -0.12065 -0.2794)
			(end 0.12065 -0.2794)
			(stroke
				(width 0.1)
				(type default)
			)
			(layer "F.Fab")
		)
		(fp_line
			(start 0.12065 -0.2794)
			(end 0.12065 -0.3048)
			(stroke
				(width 0.1)
				(type default)
			)
			(layer "F.Fab")
		)
		(fp_line
			(start 0.12065 -0.3048)
			(end 0.67945 -0.3048)
			(stroke
				(width 0.1)
				(type default)
			)
			(layer "F.Fab")
		)
		(fp_line
			(start 0.67945 -0.3048)
			(end 0.67945 0.3048)
			(stroke
				(width 0.1)
				(type default)
			)
			(layer "F.Fab")
		)
		(fp_line
			(start -0.67945 -0.305054)
			(end -0.12065 -0.305054)
			(stroke
				(width 0.1)
				(type default)
			)
			(layer "F.Fab")
		)
		(fp_line
			(start -0.12065 -0.305054)
			(end -0.12065 -0.2794)
			(stroke
				(width 0.1)
				(type default)
			)
			(layer "F.Fab")
		)
		(pad "1" smd circle
			(at -0.40005 0 270)
			(size 0 0)
			(layers "F.Cu" "F.Mask" "F.Paste")
			(net "PRSNT_SSD11_R_N")
		)
		(pad "2" smd circle
			(at 0.40005 0 270)
			(size 0 0)
			(layers "F.Cu" "F.Mask" "F.Paste")
			(net "PRSNT_SSD11_N")
		)
	)
	(footprint ""
		(layer "F.Cu")
		(at 369.830604 -66.32194 -90)
		(property "Reference" "PC884"
			(at 0 0 270)
			(layer "F.SilkS")
			(hide yes)
			(effects
				(font
					(size 1.27 1.27)
				)
			)
		)
		(property "Value" ""
			(at 0 0 270)
			(layer "F.Fab")
			(effects
				(font
					(size 1.27 1.27)
				)
			)
		)
		(duplicate_pad_numbers_are_jumpers no)
		(fp_line
			(start -0.7874 0.4064)
			(end -0.7874 -0.4064)
			(stroke
				(width 0.1524)
				(type default)
			)
			(layer "F.SilkS")
		)
		(fp_line
			(start 0.7874 0.4064)
			(end -0.7874 0.4064)
			(stroke
				(width 0.1524)
				(type default)
			)
			(layer "F.SilkS")
		)
		(fp_line
			(start -0.7874 -0.4064)
			(end 0.7874 -0.4064)
			(stroke
				(width 0.1524)
				(type default)
			)
			(layer "F.SilkS")
		)
		(fp_line
			(start 0.7874 -0.4064)
			(end 0.7874 0.4064)
			(stroke
				(width 0.1524)
				(type default)
			)
			(layer "F.SilkS")
		)
		(fp_line
			(start -0.67945 0.3048)
			(end -0.67945 -0.305054)
			(stroke
				(width 0.1)
				(type default)
			)
			(layer "F.Fab")
		)
		(fp_line
			(start -0.12065 0.3048)
			(end -0.67945 0.3048)
			(stroke
				(width 0.1)
				(type default)
			)
			(layer "F.Fab")
		)
		(fp_line
			(start 0.120396 0.3048)
			(end 0.120396 0.2794)
			(stroke
				(width 0.1)
				(type default)
			)
			(layer "F.Fab")
		)
		(fp_line
			(start 0.67945 0.3048)
			(end 0.120396 0.3048)
			(stroke
				(width 0.1)
				(type default)
			)
			(layer "F.Fab")
		)
		(fp_line
			(start -0.12065 0.2794)
			(end -0.12065 0.3048)
			(stroke
				(width 0.1)
				(type default)
			)
			(layer "F.Fab")
		)
		(fp_line
			(start 0.120396 0.2794)
			(end -0.12065 0.2794)
			(stroke
				(width 0.1)
				(type default)
			)
			(layer "F.Fab")
		)
		(fp_line
			(start -0.12065 -0.2794)
			(end 0.12065 -0.2794)
			(stroke
				(width 0.1)
				(type default)
			)
			(layer "F.Fab")
		)
		(fp_line
			(start 0.12065 -0.2794)
			(end 0.12065 -0.3048)
			(stroke
				(width 0.1)
				(type default)
			)
			(layer "F.Fab")
		)
		(fp_line
			(start 0.12065 -0.3048)
			(end 0.67945 -0.3048)
			(stroke
				(width 0.1)
				(type default)
			)
			(layer "F.Fab")
		)
		(fp_line
			(start 0.67945 -0.3048)
			(end 0.67945 0.3048)
			(stroke
				(width 0.1)
				(type default)
			)
			(layer "F.Fab")
		)
		(fp_line
			(start -0.67945 -0.305054)
			(end -0.12065 -0.305054)
			(stroke
				(width 0.1)
				(type default)
			)
			(layer "F.Fab")
		)
		(fp_line
			(start -0.12065 -0.305054)
			(end -0.12065 -0.2794)
			(stroke
				(width 0.1)
				(type default)
			)
			(layer "F.Fab")
		)
		(pad "1" smd circle
			(at -0.40005 0 270)
			(size 0 0)
			(layers "F.Cu" "F.Mask" "F.Paste")
			(net "P12V_SSD12_CO_DV_DT")
		)
		(pad "2" smd circle
			(at 0.40005 0 270)
			(size 0 0)
			(layers "F.Cu" "F.Mask" "F.Paste")
			(net "GND")
		)
	)
	(footprint ""
		(layer "F.Cu")
		(at 277.726648 -55.418228 90)
		(property "Reference" "PC416"
			(at 0 0 90)
			(layer "F.SilkS")
			(hide yes)
			(effects
				(font
					(size 1.27 1.27)
				)
			)
		)
		(property "Value" ""
			(at 0 0 90)
			(layer "F.Fab")
			(effects
				(font
					(size 1.27 1.27)
				)
			)
		)
		(duplicate_pad_numbers_are_jumpers no)
		(fp_line
			(start 0.7874 -0.4064)
			(end 0.7874 0.4064)
			(stroke
				(width 0.1524)
				(type default)
			)
			(layer "F.SilkS")
		)
		(fp_line
			(start -0.7874 -0.4064)
			(end 0.7874 -0.4064)
			(stroke
				(width 0.1524)
				(type default)
			)
			(layer "F.SilkS")
		)
		(fp_line
			(start 0.7874 0.4064)
			(end -0.7874 0.4064)
			(stroke
				(width 0.1524)
				(type default)
			)
			(layer "F.SilkS")
		)
		(fp_line
			(start -0.7874 0.4064)
			(end -0.7874 -0.4064)
			(stroke
				(width 0.1524)
				(type default)
			)
			(layer "F.SilkS")
		)
		(fp_line
			(start -0.12065 -0.305054)
			(end -0.12065 -0.2794)
			(stroke
				(width 0.1)
				(type default)
			)
			(layer "F.Fab")
		)
		(fp_line
			(start -0.67945 -0.305054)
			(end -0.12065 -0.305054)
			(stroke
				(width 0.1)
				(type default)
			)
			(layer "F.Fab")
		)
		(fp_line
			(start 0.67945 -0.3048)
			(end 0.67945 0.3048)
			(stroke
				(width 0.1)
				(type default)
			)
			(layer "F.Fab")
		)
		(fp_line
			(start 0.12065 -0.3048)
			(end 0.67945 -0.3048)
			(stroke
				(width 0.1)
				(type default)
			)
			(layer "F.Fab")
		)
		(fp_line
			(start 0.12065 -0.2794)
			(end 0.12065 -0.3048)
			(stroke
				(width 0.1)
				(type default)
			)
			(layer "F.Fab")
		)
		(fp_line
			(start -0.12065 -0.2794)
			(end 0.12065 -0.2794)
			(stroke
				(width 0.1)
				(type default)
			)
			(layer "F.Fab")
		)
		(fp_line
			(start 0.120396 0.2794)
			(end -0.12065 0.2794)
			(stroke
				(width 0.1)
				(type default)
			)
			(layer "F.Fab")
		)
		(fp_line
			(start -0.12065 0.2794)
			(end -0.12065 0.3048)
			(stroke
				(width 0.1)
				(type default)
			)
			(layer "F.Fab")
		)
		(fp_line
			(start 0.67945 0.3048)
			(end 0.120396 0.3048)
			(stroke
				(width 0.1)
				(type default)
			)
			(layer "F.Fab")
		)
		(fp_line
			(start 0.120396 0.3048)
			(end 0.120396 0.2794)
			(stroke
				(width 0.1)
				(type default)
			)
			(layer "F.Fab")
		)
		(fp_line
			(start -0.12065 0.3048)
			(end -0.67945 0.3048)
			(stroke
				(width 0.1)
				(type default)
			)
			(layer "F.Fab")
		)
		(fp_line
			(start -0.67945 0.3048)
			(end -0.67945 -0.305054)
			(stroke
				(width 0.1)
				(type default)
			)
			(layer "F.Fab")
		)
		(pad "1" smd circle
			(at -0.40005 0 90)
			(size 0 0)
			(layers "F.Cu" "F.Mask" "F.Paste")
			(net "P12V_SSD9_R")
		)
		(pad "2" smd circle
			(at 0.40005 0 90)
			(size 0 0)
			(layers "F.Cu" "F.Mask" "F.Paste")
			(net "GND")
		)
	)
	(footprint ""
		(layer "F.Cu")
		(at 323.233542 -304.036476 90)
		(property "Reference" "R1386"
			(at 0 0 90)
			(layer "F.SilkS")
			(hide yes)
			(effects
				(font
					(size 1.27 1.27)
				)
			)
		)
		(property "Value" ""
			(at 0 0 90)
			(layer "F.Fab")
			(effects
				(font
					(size 1.27 1.27)
				)
			)
		)
		(duplicate_pad_numbers_are_jumpers no)
		(fp_line
			(start 0.7874 -0.4064)
			(end 0.7874 0.4064)
			(stroke
				(width 0.1524)
				(type default)
			)
			(layer "F.SilkS")
		)
		(fp_line
			(start -0.7874 -0.4064)
			(end 0.7874 -0.4064)
			(stroke
				(width 0.1524)
				(type default)
			)
			(layer "F.SilkS")
		)
		(fp_line
			(start 0.7874 0.4064)
			(end -0.7874 0.4064)
			(stroke
				(width 0.1524)
				(type default)
			)
			(layer "F.SilkS")
		)
		(fp_line
			(start -0.7874 0.4064)
			(end -0.7874 -0.4064)
			(stroke
				(width 0.1524)
				(type default)
			)
			(layer "F.SilkS")
		)
		(fp_line
			(start -0.12065 -0.305054)
			(end -0.12065 -0.2794)
			(stroke
				(width 0.1)
				(type default)
			)
			(layer "F.Fab")
		)
		(fp_line
			(start -0.67945 -0.305054)
			(end -0.12065 -0.305054)
			(stroke
				(width 0.1)
				(type default)
			)
			(layer "F.Fab")
		)
		(fp_line
			(start 0.67945 -0.3048)
			(end 0.67945 0.3048)
			(stroke
				(width 0.1)
				(type default)
			)
			(layer "F.Fab")
		)
		(fp_line
			(start 0.12065 -0.3048)
			(end 0.67945 -0.3048)
			(stroke
				(width 0.1)
				(type default)
			)
			(layer "F.Fab")
		)
		(fp_line
			(start 0.12065 -0.2794)
			(end 0.12065 -0.3048)
			(stroke
				(width 0.1)
				(type default)
			)
			(layer "F.Fab")
		)
		(fp_line
			(start -0.12065 -0.2794)
			(end 0.12065 -0.2794)
			(stroke
				(width 0.1)
				(type default)
			)
			(layer "F.Fab")
		)
		(fp_line
			(start 0.120396 0.2794)
			(end -0.12065 0.2794)
			(stroke
				(width 0.1)
				(type default)
			)
			(layer "F.Fab")
		)
		(fp_line
			(start -0.12065 0.2794)
			(end -0.12065 0.3048)
			(stroke
				(width 0.1)
				(type default)
			)
			(layer "F.Fab")
		)
		(fp_line
			(start 0.67945 0.3048)
			(end 0.120396 0.3048)
			(stroke
				(width 0.1)
				(type default)
			)
			(layer "F.Fab")
		)
		(fp_line
			(start 0.120396 0.3048)
			(end 0.120396 0.2794)
			(stroke
				(width 0.1)
				(type default)
			)
			(layer "F.Fab")
		)
		(fp_line
			(start -0.12065 0.3048)
			(end -0.67945 0.3048)
			(stroke
				(width 0.1)
				(type default)
			)
			(layer "F.Fab")
		)
		(fp_line
			(start -0.67945 0.3048)
			(end -0.67945 -0.305054)
			(stroke
				(width 0.1)
				(type default)
			)
			(layer "F.Fab")
		)
		(pad "1" smd circle
			(at -0.40005 0 90)
			(size 0 0)
			(layers "F.Cu" "F.Mask" "F.Paste")
			(net "GND")
		)
		(pad "2" smd circle
			(at 0.40005 0 90)
			(size 0 0)
			(layers "F.Cu" "F.Mask" "F.Paste")
			(net "PEX2_SPARE1")
		)
	)
	(footprint ""
		(layer "F.Cu")
		(at 220.34373 -42.84091)
		(property "Reference" "R582"
			(at 0 0 0)
			(layer "F.SilkS")
			(hide yes)
			(effects
				(font
					(size 1.27 1.27)
				)
			)
		)
		(property "Value" ""
			(at 0 0 0)
			(layer "F.Fab")
			(effects
				(font
					(size 1.27 1.27)
				)
			)
		)
		(duplicate_pad_numbers_are_jumpers no)
		(fp_line
			(start -0.7874 -0.4064)
			(end 0.7874 -0.4064)
			(stroke
				(width 0.1524)
				(type default)
			)
			(layer "F.SilkS")
		)
		(fp_line
			(start -0.7874 0.4064)
			(end -0.7874 -0.4064)
			(stroke
				(width 0.1524)
				(type default)
			)
			(layer "F.SilkS")
		)
		(fp_line
			(start 0.7874 -0.4064)
			(end 0.7874 0.4064)
			(stroke
				(width 0.1524)
				(type default)
			)
			(layer "F.SilkS")
		)
		(fp_line
			(start 0.7874 0.4064)
			(end -0.7874 0.4064)
			(stroke
				(width 0.1524)
				(type default)
			)
			(layer "F.SilkS")
		)
		(fp_line
			(start -0.67945 -0.305054)
			(end -0.12065 -0.305054)
			(stroke
				(width 0.1)
				(type default)
			)
			(layer "F.Fab")
		)
		(fp_line
			(start -0.67945 0.3048)
			(end -0.67945 -0.305054)
			(stroke
				(width 0.1)
				(type default)
			)
			(layer "F.Fab")
		)
		(fp_line
			(start -0.12065 -0.305054)
			(end -0.12065 -0.2794)
			(stroke
				(width 0.1)
				(type default)
			)
			(layer "F.Fab")
		)
		(fp_line
			(start -0.12065 -0.2794)
			(end 0.12065 -0.2794)
			(stroke
				(width 0.1)
				(type default)
			)
			(layer "F.Fab")
		)
		(fp_line
			(start -0.12065 0.2794)
			(end -0.12065 0.3048)
			(stroke
				(width 0.1)
				(type default)
			)
			(layer "F.Fab")
		)
		(fp_line
			(start -0.12065 0.3048)
			(end -0.67945 0.3048)
			(stroke
				(width 0.1)
				(type default)
			)
			(layer "F.Fab")
		)
		(fp_line
			(start 0.120396 0.2794)
			(end -0.12065 0.2794)
			(stroke
				(width 0.1)
				(type default)
			)
			(layer "F.Fab")
		)
		(fp_line
			(start 0.120396 0.3048)
			(end 0.120396 0.2794)
			(stroke
				(width 0.1)
				(type default)
			)
			(layer "F.Fab")
		)
		(fp_line
			(start 0.12065 -0.3048)
			(end 0.67945 -0.3048)
			(stroke
				(width 0.1)
				(type default)
			)
			(layer "F.Fab")
		)
		(fp_line
			(start 0.12065 -0.2794)
			(end 0.12065 -0.3048)
			(stroke
				(width 0.1)
				(type default)
			)
			(layer "F.Fab")
		)
		(fp_line
			(start 0.67945 -0.3048)
			(end 0.67945 0.3048)
			(stroke
				(width 0.1)
				(type default)
			)
			(layer "F.Fab")
		)
		(fp_line
			(start 0.67945 0.3048)
			(end 0.120396 0.3048)
			(stroke
				(width 0.1)
				(type default)
			)
			(layer "F.Fab")
		)
		(pad "1" smd circle
			(at -0.40005 0)
			(size 0 0)
			(layers "F.Cu" "F.Mask" "F.Paste")
			(net "SSD7_ADC_A1")
		)
		(pad "2" smd circle
			(at 0.40005 0)
			(size 0 0)
			(layers "F.Cu" "F.Mask" "F.Paste")
			(net "P3V3_AUX")
		)
	)
	(footprint ""
		(layer "F.Cu")
		(at 26.243788 -45.88891)
		(property "Reference" "R508"
			(at 0 0 0)
			(layer "F.SilkS")
			(hide yes)
			(effects
				(font
					(size 1.27 1.27)
				)
			)
		)
		(property "Value" ""
			(at 0 0 0)
			(layer "F.Fab")
			(effects
				(font
					(size 1.27 1.27)
				)
			)
		)
		(duplicate_pad_numbers_are_jumpers no)
		(fp_line
			(start -0.7874 -0.4064)
			(end 0.7874 -0.4064)
			(stroke
				(width 0.1524)
				(type default)
			)
			(layer "F.SilkS")
		)
		(fp_line
			(start -0.7874 0.4064)
			(end -0.7874 -0.4064)
			(stroke
				(width 0.1524)
				(type default)
			)
			(layer "F.SilkS")
		)
		(fp_line
			(start 0.7874 -0.4064)
			(end 0.7874 0.4064)
			(stroke
				(width 0.1524)
				(type default)
			)
			(layer "F.SilkS")
		)
		(fp_line
			(start 0.7874 0.4064)
			(end -0.7874 0.4064)
			(stroke
				(width 0.1524)
				(type default)
			)
			(layer "F.SilkS")
		)
		(fp_line
			(start -0.67945 -0.305054)
			(end -0.12065 -0.305054)
			(stroke
				(width 0.1)
				(type default)
			)
			(layer "F.Fab")
		)
		(fp_line
			(start -0.67945 0.3048)
			(end -0.67945 -0.305054)
			(stroke
				(width 0.1)
				(type default)
			)
			(layer "F.Fab")
		)
		(fp_line
			(start -0.12065 -0.305054)
			(end -0.12065 -0.2794)
			(stroke
				(width 0.1)
				(type default)
			)
			(layer "F.Fab")
		)
		(fp_line
			(start -0.12065 -0.2794)
			(end 0.12065 -0.2794)
			(stroke
				(width 0.1)
				(type default)
			)
			(layer "F.Fab")
		)
		(fp_line
			(start -0.12065 0.2794)
			(end -0.12065 0.3048)
			(stroke
				(width 0.1)
				(type default)
			)
			(layer "F.Fab")
		)
		(fp_line
			(start -0.12065 0.3048)
			(end -0.67945 0.3048)
			(stroke
				(width 0.1)
				(type default)
			)
			(layer "F.Fab")
		)
		(fp_line
			(start 0.120396 0.2794)
			(end -0.12065 0.2794)
			(stroke
				(width 0.1)
				(type default)
			)
			(layer "F.Fab")
		)
		(fp_line
			(start 0.120396 0.3048)
			(end 0.120396 0.2794)
			(stroke
				(width 0.1)
				(type default)
			)
			(layer "F.Fab")
		)
		(fp_line
			(start 0.12065 -0.3048)
			(end 0.67945 -0.3048)
			(stroke
				(width 0.1)
				(type default)
			)
			(layer "F.Fab")
		)
		(fp_line
			(start 0.12065 -0.2794)
			(end 0.12065 -0.3048)
			(stroke
				(width 0.1)
				(type default)
			)
			(layer "F.Fab")
		)
		(fp_line
			(start 0.67945 -0.3048)
			(end 0.67945 0.3048)
			(stroke
				(width 0.1)
				(type default)
			)
			(layer "F.Fab")
		)
		(fp_line
			(start 0.67945 0.3048)
			(end 0.120396 0.3048)
			(stroke
				(width 0.1)
				(type default)
			)
			(layer "F.Fab")
		)
		(pad "1" smd circle
			(at -0.40005 0)
			(size 0 0)
			(layers "F.Cu" "F.Mask" "F.Paste")
			(net "SSD0_ADC_A0")
		)
		(pad "2" smd circle
			(at 0.40005 0)
			(size 0 0)
			(layers "F.Cu" "F.Mask" "F.Paste")
			(net "GND")
		)
	)
	(footprint ""
		(layer "F.Cu")
		(at 210.59394 -115.902486)
		(property "Reference" "PC795"
			(at 0 0 0)
			(layer "F.SilkS")
			(hide yes)
			(effects
				(font
					(size 1.27 1.27)
				)
			)
		)
		(property "Value" ""
			(at 0 0 0)
			(layer "F.Fab")
			(effects
				(font
					(size 1.27 1.27)
				)
			)
		)
		(duplicate_pad_numbers_are_jumpers no)
		(fp_line
			(start -0.7874 -0.4064)
			(end 0.7874 -0.4064)
			(stroke
				(width 0.1524)
				(type default)
			)
			(layer "F.SilkS")
		)
		(fp_line
			(start -0.7874 0.4064)
			(end -0.7874 -0.4064)
			(stroke
				(width 0.1524)
				(type default)
			)
			(layer "F.SilkS")
		)
		(fp_line
			(start 0.7874 -0.4064)
			(end 0.7874 0.4064)
			(stroke
				(width 0.1524)
				(type default)
			)
			(layer "F.SilkS")
		)
		(fp_line
			(start 0.7874 0.4064)
			(end -0.7874 0.4064)
			(stroke
				(width 0.1524)
				(type default)
			)
			(layer "F.SilkS")
		)
		(fp_line
			(start -0.67945 -0.305054)
			(end -0.12065 -0.305054)
			(stroke
				(width 0.1)
				(type default)
			)
			(layer "F.Fab")
		)
		(fp_line
			(start -0.67945 0.3048)
			(end -0.67945 -0.305054)
			(stroke
				(width 0.1)
				(type default)
			)
			(layer "F.Fab")
		)
		(fp_line
			(start -0.12065 -0.305054)
			(end -0.12065 -0.2794)
			(stroke
				(width 0.1)
				(type default)
			)
			(layer "F.Fab")
		)
		(fp_line
			(start -0.12065 -0.2794)
			(end 0.12065 -0.2794)
			(stroke
				(width 0.1)
				(type default)
			)
			(layer "F.Fab")
		)
		(fp_line
			(start -0.12065 0.2794)
			(end -0.12065 0.3048)
			(stroke
				(width 0.1)
				(type default)
			)
			(layer "F.Fab")
		)
		(fp_line
			(start -0.12065 0.3048)
			(end -0.67945 0.3048)
			(stroke
				(width 0.1)
				(type default)
			)
			(layer "F.Fab")
		)
		(fp_line
			(start 0.120396 0.2794)
			(end -0.12065 0.2794)
			(stroke
				(width 0.1)
				(type default)
			)
			(layer "F.Fab")
		)
		(fp_line
			(start 0.120396 0.3048)
			(end 0.120396 0.2794)
			(stroke
				(width 0.1)
				(type default)
			)
			(layer "F.Fab")
		)
		(fp_line
			(start 0.12065 -0.3048)
			(end 0.67945 -0.3048)
			(stroke
				(width 0.1)
				(type default)
			)
			(layer "F.Fab")
		)
		(fp_line
			(start 0.12065 -0.2794)
			(end 0.12065 -0.3048)
			(stroke
				(width 0.1)
				(type default)
			)
			(layer "F.Fab")
		)
		(fp_line
			(start 0.67945 -0.3048)
			(end 0.67945 0.3048)
			(stroke
				(width 0.1)
				(type default)
			)
			(layer "F.Fab")
		)
		(fp_line
			(start 0.67945 0.3048)
			(end 0.120396 0.3048)
			(stroke
				(width 0.1)
				(type default)
			)
			(layer "F.Fab")
		)
		(pad "1" smd circle
			(at -0.40005 0)
			(size 0 0)
			(layers "F.Cu" "F.Mask" "F.Paste")
			(net "P3V3_NIC3_CO_MODE")
		)
		(pad "2" smd circle
			(at 0.40005 0)
			(size 0 0)
			(layers "F.Cu" "F.Mask" "F.Paste")
			(net "GND")
		)
	)
	(footprint ""
		(layer "F.Cu")
		(at 232.9815 -140.49248 90)
		(property "Reference" "R4185"
			(at 0 0 90)
			(layer "F.SilkS")
			(hide yes)
			(effects
				(font
					(size 1.27 1.27)
				)
			)
		)
		(property "Value" ""
			(at 0 0 90)
			(layer "F.Fab")
			(effects
				(font
					(size 1.27 1.27)
				)
			)
		)
		(duplicate_pad_numbers_are_jumpers no)
		(fp_line
			(start 0.7874 -0.4064)
			(end 0.7874 0.4064)
			(stroke
				(width 0.1524)
				(type default)
			)
			(layer "F.SilkS")
		)
		(fp_line
			(start -0.7874 -0.4064)
			(end 0.7874 -0.4064)
			(stroke
				(width 0.1524)
				(type default)
			)
			(layer "F.SilkS")
		)
		(fp_line
			(start 0.7874 0.4064)
			(end -0.7874 0.4064)
			(stroke
				(width 0.1524)
				(type default)
			)
			(layer "F.SilkS")
		)
		(fp_line
			(start -0.7874 0.4064)
			(end -0.7874 -0.4064)
			(stroke
				(width 0.1524)
				(type default)
			)
			(layer "F.SilkS")
		)
		(fp_line
			(start -0.12065 -0.305054)
			(end -0.12065 -0.2794)
			(stroke
				(width 0.1)
				(type default)
			)
			(layer "F.Fab")
		)
		(fp_line
			(start -0.67945 -0.305054)
			(end -0.12065 -0.305054)
			(stroke
				(width 0.1)
				(type default)
			)
			(layer "F.Fab")
		)
		(fp_line
			(start 0.67945 -0.3048)
			(end 0.67945 0.3048)
			(stroke
				(width 0.1)
				(type default)
			)
			(layer "F.Fab")
		)
		(fp_line
			(start 0.12065 -0.3048)
			(end 0.67945 -0.3048)
			(stroke
				(width 0.1)
				(type default)
			)
			(layer "F.Fab")
		)
		(fp_line
			(start 0.12065 -0.2794)
			(end 0.12065 -0.3048)
			(stroke
				(width 0.1)
				(type default)
			)
			(layer "F.Fab")
		)
		(fp_line
			(start -0.12065 -0.2794)
			(end 0.12065 -0.2794)
			(stroke
				(width 0.1)
				(type default)
			)
			(layer "F.Fab")
		)
		(fp_line
			(start 0.120396 0.2794)
			(end -0.12065 0.2794)
			(stroke
				(width 0.1)
				(type default)
			)
			(layer "F.Fab")
		)
		(fp_line
			(start -0.12065 0.2794)
			(end -0.12065 0.3048)
			(stroke
				(width 0.1)
				(type default)
			)
			(layer "F.Fab")
		)
		(fp_line
			(start 0.67945 0.3048)
			(end 0.120396 0.3048)
			(stroke
				(width 0.1)
				(type default)
			)
			(layer "F.Fab")
		)
		(fp_line
			(start 0.120396 0.3048)
			(end 0.120396 0.2794)
			(stroke
				(width 0.1)
				(type default)
			)
			(layer "F.Fab")
		)
		(fp_line
			(start -0.12065 0.3048)
			(end -0.67945 0.3048)
			(stroke
				(width 0.1)
				(type default)
			)
			(layer "F.Fab")
		)
		(fp_line
			(start -0.67945 0.3048)
			(end -0.67945 -0.305054)
			(stroke
				(width 0.1)
				(type default)
			)
			(layer "F.Fab")
		)
		(pad "1" smd circle
			(at -0.40005 0 90)
			(size 0 0)
			(layers "F.Cu" "F.Mask" "F.Paste")
			(net "XTAL_CK440_PEX_25M_R_XIN")
		)
		(pad "2" smd circle
			(at 0.40005 0 90)
			(size 0 0)
			(layers "F.Cu" "F.Mask" "F.Paste")
			(net "XTAL_CK440_PEX_25M_XIN")
		)
	)
	(footprint ""
		(layer "F.Cu")
		(at 149.140164 -259.834634 180)
		(property "Reference" "C3222"
			(at 0 0 180)
			(layer "F.SilkS")
			(hide yes)
			(effects
				(font
					(size 1.27 1.27)
				)
			)
		)
		(property "Value" ""
			(at 0 0 180)
			(layer "F.Fab")
			(effects
				(font
					(size 1.27 1.27)
				)
			)
		)
		(duplicate_pad_numbers_are_jumpers no)
		(fp_line
			(start 1.2954 0.5842)
			(end -1.2954 0.5842)
			(stroke
				(width 0.1524)
				(type default)
			)
			(layer "F.SilkS")
		)
		(fp_line
			(start 1.2954 -0.5842)
			(end 1.2954 0.5842)
			(stroke
				(width 0.1524)
				(type default)
			)
			(layer "F.SilkS")
		)
		(fp_line
			(start -1.2954 0.5842)
			(end -1.2954 -0.5842)
			(stroke
				(width 0.1524)
				(type default)
			)
			(layer "F.SilkS")
		)
		(fp_line
			(start -1.2954 -0.5842)
			(end 1.2954 -0.5842)
			(stroke
				(width 0.1524)
				(type default)
			)
			(layer "F.SilkS")
		)
		(fp_line
			(start 1.1938 0.4064)
			(end 0.8636 0.4064)
			(stroke
				(width 0.1)
				(type default)
			)
			(layer "F.Fab")
		)
		(fp_line
			(start 1.1938 -0.4064)
			(end 1.1938 0.4064)
			(stroke
				(width 0.1)
				(type default)
			)
			(layer "F.Fab")
		)
		(fp_line
			(start 0.8636 0.4572)
			(end -0.8636 0.4572)
			(stroke
				(width 0.1)
				(type default)
			)
			(layer "F.Fab")
		)
		(fp_line
			(start 0.8636 0.4064)
			(end 0.8636 0.4572)
			(stroke
				(width 0.1)
				(type default)
			)
			(layer "F.Fab")
		)
		(fp_line
			(start 0.8636 -0.4064)
			(end 1.1938 -0.4064)
			(stroke
				(width 0.1)
				(type default)
			)
			(layer "F.Fab")
		)
		(fp_line
			(start 0.8636 -0.4572)
			(end 0.8636 -0.4064)
			(stroke
				(width 0.1)
				(type default)
			)
			(layer "F.Fab")
		)
		(fp_line
			(start -0.8636 0.4572)
			(end -0.8636 0.4064)
			(stroke
				(width 0.1)
				(type default)
			)
			(layer "F.Fab")
		)
		(fp_line
			(start -0.8636 0.4064)
			(end -1.1938 0.4064)
			(stroke
				(width 0.1)
				(type default)
			)
			(layer "F.Fab")
		)
		(fp_line
			(start -0.8636 -0.4064)
			(end -0.8636 -0.4572)
			(stroke
				(width 0.1)
				(type default)
			)
			(layer "F.Fab")
		)
		(fp_line
			(start -0.8636 -0.4572)
			(end 0.8636 -0.4572)
			(stroke
				(width 0.1)
				(type default)
			)
			(layer "F.Fab")
		)
		(fp_line
			(start -1.1938 0.4064)
			(end -1.1938 -0.4064)
			(stroke
				(width 0.1)
				(type default)
			)
			(layer "F.Fab")
		)
		(fp_line
			(start -1.1938 -0.4064)
			(end -0.8636 -0.4064)
			(stroke
				(width 0.1)
				(type default)
			)
			(layer "F.Fab")
		)
		(pad "1" smd rect
			(at -0.7366 0 90)
			(size 0.7112 0.8128)
			(layers "F.Cu" "F.Mask" "F.Paste")
			(net "PCEPLL3_VDDA18_PEX1_R")
		)
		(pad "2" smd rect
			(at 0.7366 0 90)
			(size 0.7112 0.8128)
			(layers "F.Cu" "F.Mask" "F.Paste")
			(net "GND")
		)
	)
	(footprint ""
		(layer "F.Cu")
		(at 153.153872 -147.969224 90)
		(property "Reference" "C876"
			(at 0 0 90)
			(layer "F.SilkS")
			(hide yes)
			(effects
				(font
					(size 1.27 1.27)
				)
			)
		)
		(property "Value" ""
			(at 0 0 90)
			(layer "F.Fab")
			(effects
				(font
					(size 1.27 1.27)
				)
			)
		)
		(duplicate_pad_numbers_are_jumpers no)
		(fp_line
			(start 1.524 -0.762)
			(end 1.524 0.762)
			(stroke
				(width 0.1524)
				(type default)
			)
			(layer "F.SilkS")
		)
		(fp_line
			(start -1.524 -0.762)
			(end 1.524 -0.762)
			(stroke
				(width 0.1524)
				(type default)
			)
			(layer "F.SilkS")
		)
		(fp_line
			(start 1.524 0.762)
			(end -1.524 0.762)
			(stroke
				(width 0.1524)
				(type default)
			)
			(layer "F.SilkS")
		)
		(fp_line
			(start -1.524 0.762)
			(end -1.524 -0.762)
			(stroke
				(width 0.1524)
				(type default)
			)
			(layer "F.SilkS")
		)
		(fp_line
			(start 1.1049 -0.724916)
			(end -1.1049 -0.724916)
			(stroke
				(width 0.1)
				(type default)
			)
			(layer "F.Fab")
		)
		(fp_line
			(start -1.1049 -0.724916)
			(end -1.1049 0.724916)
			(stroke
				(width 0.1)
				(type default)
			)
			(layer "F.Fab")
		)
		(fp_line
			(start 1.1049 0.724916)
			(end 1.1049 -0.724916)
			(stroke
				(width 0.1)
				(type default)
			)
			(layer "F.Fab")
		)
		(fp_line
			(start -1.1049 0.724916)
			(end 1.1049 0.724916)
			(stroke
				(width 0.1)
				(type default)
			)
			(layer "F.Fab")
		)
		(pad "1" smd rect
			(at -0.889 0 270)
			(size 1.016 1.27)
			(layers "F.Cu" "F.Mask" "F.Paste")
			(net "P12V_NIC2")
		)
		(pad "2" smd rect
			(at 0.889 0 270)
			(size 1.016 1.27)
			(layers "F.Cu" "F.Mask" "F.Paste")
			(net "GND")
		)
	)
	(footprint ""
		(layer "F.Cu")
		(at 10.14984 -148.872702)
		(property "Reference" "PD78"
			(at -3.4544 -2.225548 0)
			(unlocked yes)
			(layer "F.SilkS")
			(effects
				(font
					(size 0.7874 0.5842)
					(thickness 0.1524)
				)
				(justify left)
			)
		)
		(property "Value" ""
			(at 0 0 0)
			(layer "F.Fab")
			(effects
				(font
					(size 1.27 1.27)
				)
			)
		)
		(duplicate_pad_numbers_are_jumpers no)
		(fp_line
			(start -3.400044 -1.459992)
			(end 4.107942 -1.459992)
			(stroke
				(width 0.1524)
				(type default)
			)
			(layer "F.SilkS")
		)
		(fp_line
			(start -3.400044 1.459992)
			(end -3.400044 -1.459992)
			(stroke
				(width 0.1524)
				(type default)
			)
			(layer "F.SilkS")
		)
		(fp_line
			(start 4.107942 -1.459992)
			(end 4.107942 1.459992)
			(stroke
				(width 0.1524)
				(type default)
			)
			(layer "F.SilkS")
		)
		(fp_line
			(start 4.107942 1.459992)
			(end -3.400044 1.459992)
			(stroke
				(width 0.1524)
				(type default)
			)
			(layer "F.SilkS")
		)
		(fp_poly
			(pts
				(xy 4.107942 -1.459992) (xy 4.107942 1.459992) (xy 3.308096 1.459992) (xy 3.308096 -1.459992)
			)
			(stroke
				(width 0)
				(type default)
			)
			(fill yes)
			(layer "F.SilkS")
		)
		(fp_line
			(start -2.29997 -1.459992)
			(end 2.29997 -1.459992)
			(stroke
				(width 0.1)
				(type default)
			)
			(layer "F.Fab")
		)
		(fp_line
			(start -2.29997 1.459992)
			(end -2.29997 -1.459992)
			(stroke
				(width 0.1)
				(type default)
			)
			(layer "F.Fab")
		)
		(fp_line
			(start 2.29997 -1.459992)
			(end 2.29997 1.459992)
			(stroke
				(width 0.1)
				(type default)
			)
			(layer "F.Fab")
		)
		(fp_line
			(start 2.29997 1.459992)
			(end -2.29997 1.459992)
			(stroke
				(width 0.1)
				(type default)
			)
			(layer "F.Fab")
		)
		(fp_text user "+"
			(at -4.7752 -0.12065 0)
			(unlocked yes)
			(layer "F.SilkS")
			(effects
				(font
					(size 1.905 1.4224)
					(thickness 0.1524)
				)
				(justify left)
			)
		)
		(fp_text user "-"
			(at 5.4102 0.29845 180)
			(unlocked yes)
			(layer "F.SilkS")
			(effects
				(font
					(size 1.905 1.4224)
					(thickness 0.1524)
				)
				(justify left)
			)
		)
		(fp_text user "+"
			(at -4.7752 -0.12065 0)
			(unlocked yes)
			(layer "F.Fab")
			(effects
				(font
					(size 1.905 1.4224)
					(thickness 0.1524)
				)
				(justify left)
			)
		)
		(fp_text user "-"
			(at 5.4102 0.29845 180)
			(unlocked yes)
			(layer "F.Fab")
			(effects
				(font
					(size 1.905 1.4224)
					(thickness 0.1524)
				)
				(justify left)
			)
		)
		(pad "A" smd rect
			(at -1.999996 0 90)
			(size 1.7018 2.5146)
			(layers "F.Cu" "F.Mask" "F.Paste")
			(net "GND")
		)
		(pad "C" smd rect
			(at 1.999996 0 90)
			(size 1.7018 2.5146)
			(layers "F.Cu" "F.Mask" "F.Paste")
			(net "P12V_NIC0_R")
		)
	)
	(footprint ""
		(layer "F.Cu")
		(at 439.355484 -96.811592 -90)
		(property "Reference" "R761"
			(at 0 0 270)
			(layer "F.SilkS")
			(hide yes)
			(effects
				(font
					(size 1.27 1.27)
				)
			)
		)
		(property "Value" ""
			(at 0 0 270)
			(layer "F.Fab")
			(effects
				(font
					(size 1.27 1.27)
				)
			)
		)
		(duplicate_pad_numbers_are_jumpers no)
		(fp_line
			(start -0.7874 0.4064)
			(end -0.7874 -0.4064)
			(stroke
				(width 0.1524)
				(type default)
			)
			(layer "F.SilkS")
		)
		(fp_line
			(start 0.7874 0.4064)
			(end -0.7874 0.4064)
			(stroke
				(width 0.1524)
				(type default)
			)
			(layer "F.SilkS")
		)
		(fp_line
			(start -0.7874 -0.4064)
			(end 0.7874 -0.4064)
			(stroke
				(width 0.1524)
				(type default)
			)
			(layer "F.SilkS")
		)
		(fp_line
			(start 0.7874 -0.4064)
			(end 0.7874 0.4064)
			(stroke
				(width 0.1524)
				(type default)
			)
			(layer "F.SilkS")
		)
		(fp_line
			(start -0.67945 0.3048)
			(end -0.67945 -0.305054)
			(stroke
				(width 0.1)
				(type default)
			)
			(layer "F.Fab")
		)
		(fp_line
			(start -0.12065 0.3048)
			(end -0.67945 0.3048)
			(stroke
				(width 0.1)
				(type default)
			)
			(layer "F.Fab")
		)
		(fp_line
			(start 0.120396 0.3048)
			(end 0.120396 0.2794)
			(stroke
				(width 0.1)
				(type default)
			)
			(layer "F.Fab")
		)
		(fp_line
			(start 0.67945 0.3048)
			(end 0.120396 0.3048)
			(stroke
				(width 0.1)
				(type default)
			)
			(layer "F.Fab")
		)
		(fp_line
			(start -0.12065 0.2794)
			(end -0.12065 0.3048)
			(stroke
				(width 0.1)
				(type default)
			)
			(layer "F.Fab")
		)
		(fp_line
			(start 0.120396 0.2794)
			(end -0.12065 0.2794)
			(stroke
				(width 0.1)
				(type default)
			)
			(layer "F.Fab")
		)
		(fp_line
			(start -0.12065 -0.2794)
			(end 0.12065 -0.2794)
			(stroke
				(width 0.1)
				(type default)
			)
			(layer "F.Fab")
		)
		(fp_line
			(start 0.12065 -0.2794)
			(end 0.12065 -0.3048)
			(stroke
				(width 0.1)
				(type default)
			)
			(layer "F.Fab")
		)
		(fp_line
			(start 0.12065 -0.3048)
			(end 0.67945 -0.3048)
			(stroke
				(width 0.1)
				(type default)
			)
			(layer "F.Fab")
		)
		(fp_line
			(start 0.67945 -0.3048)
			(end 0.67945 0.3048)
			(stroke
				(width 0.1)
				(type default)
			)
			(layer "F.Fab")
		)
		(fp_line
			(start -0.67945 -0.305054)
			(end -0.12065 -0.305054)
			(stroke
				(width 0.1)
				(type default)
			)
			(layer "F.Fab")
		)
		(fp_line
			(start -0.12065 -0.305054)
			(end -0.12065 -0.2794)
			(stroke
				(width 0.1)
				(type default)
			)
			(layer "F.Fab")
		)
		(pad "1" smd circle
			(at -0.40005 0 270)
			(size 0 0)
			(layers "F.Cu" "F.Mask" "F.Paste")
			(net "NIC7_ADC_ALERT_N")
		)
		(pad "2" smd circle
			(at 0.40005 0 270)
			(size 0 0)
			(layers "F.Cu" "F.Mask" "F.Paste")
			(net "NIC_ADC_ALERT_N")
		)
	)
	(footprint ""
		(layer "F.Cu")
		(at 338.074 -154.686 180)
		(property "Reference" "R4817"
			(at 0 0 180)
			(layer "F.SilkS")
			(hide yes)
			(effects
				(font
					(size 1.27 1.27)
				)
			)
		)
		(property "Value" ""
			(at 0 0 180)
			(layer "F.Fab")
			(effects
				(font
					(size 1.27 1.27)
				)
			)
		)
		(duplicate_pad_numbers_are_jumpers no)
		(fp_line
			(start 0.7874 0.4064)
			(end -0.7874 0.4064)
			(stroke
				(width 0.1524)
				(type default)
			)
			(layer "F.SilkS")
		)
		(fp_line
			(start 0.7874 -0.4064)
			(end 0.7874 0.4064)
			(stroke
				(width 0.1524)
				(type default)
			)
			(layer "F.SilkS")
		)
		(fp_line
			(start -0.7874 0.4064)
			(end -0.7874 -0.4064)
			(stroke
				(width 0.1524)
				(type default)
			)
			(layer "F.SilkS")
		)
		(fp_line
			(start -0.7874 -0.4064)
			(end 0.7874 -0.4064)
			(stroke
				(width 0.1524)
				(type default)
			)
			(layer "F.SilkS")
		)
		(fp_line
			(start 0.67945 0.3048)
			(end 0.120396 0.3048)
			(stroke
				(width 0.1)
				(type default)
			)
			(layer "F.Fab")
		)
		(fp_line
			(start 0.67945 -0.3048)
			(end 0.67945 0.3048)
			(stroke
				(width 0.1)
				(type default)
			)
			(layer "F.Fab")
		)
		(fp_line
			(start 0.12065 -0.2794)
			(end 0.12065 -0.3048)
			(stroke
				(width 0.1)
				(type default)
			)
			(layer "F.Fab")
		)
		(fp_line
			(start 0.12065 -0.3048)
			(end 0.67945 -0.3048)
			(stroke
				(width 0.1)
				(type default)
			)
			(layer "F.Fab")
		)
		(fp_line
			(start 0.120396 0.3048)
			(end 0.120396 0.2794)
			(stroke
				(width 0.1)
				(type default)
			)
			(layer "F.Fab")
		)
		(fp_line
			(start 0.120396 0.2794)
			(end -0.12065 0.2794)
			(stroke
				(width 0.1)
				(type default)
			)
			(layer "F.Fab")
		)
		(fp_line
			(start -0.12065 0.3048)
			(end -0.67945 0.3048)
			(stroke
				(width 0.1)
				(type default)
			)
			(layer "F.Fab")
		)
		(fp_line
			(start -0.12065 0.2794)
			(end -0.12065 0.3048)
			(stroke
				(width 0.1)
				(type default)
			)
			(layer "F.Fab")
		)
		(fp_line
			(start -0.12065 -0.2794)
			(end 0.12065 -0.2794)
			(stroke
				(width 0.1)
				(type default)
			)
			(layer "F.Fab")
		)
		(fp_line
			(start -0.12065 -0.305054)
			(end -0.12065 -0.2794)
			(stroke
				(width 0.1)
				(type default)
			)
			(layer "F.Fab")
		)
		(fp_line
			(start -0.67945 0.3048)
			(end -0.67945 -0.305054)
			(stroke
				(width 0.1)
				(type default)
			)
			(layer "F.Fab")
		)
		(fp_line
			(start -0.67945 -0.305054)
			(end -0.12065 -0.305054)
			(stroke
				(width 0.1)
				(type default)
			)
			(layer "F.Fab")
		)
		(pad "1" smd circle
			(at -0.40005 0 180)
			(size 0 0)
			(layers "F.Cu" "F.Mask" "F.Paste")
			(net "SSD13_PEX_PWR_EN")
		)
		(pad "2" smd circle
			(at 0.40005 0 180)
			(size 0 0)
			(layers "F.Cu" "F.Mask" "F.Paste")
			(net "SSD13_PEX_PWR_EN_R")
		)
	)
	(footprint ""
		(layer "F.Cu")
		(at 386.90804 -162.044126 180)
		(property "Reference" "R328"
			(at 0 0 180)
			(layer "F.SilkS")
			(hide yes)
			(effects
				(font
					(size 1.27 1.27)
				)
			)
		)
		(property "Value" ""
			(at 0 0 180)
			(layer "F.Fab")
			(effects
				(font
					(size 1.27 1.27)
				)
			)
		)
		(duplicate_pad_numbers_are_jumpers no)
		(fp_line
			(start 0.7874 0.4064)
			(end -0.7874 0.4064)
			(stroke
				(width 0.1524)
				(type default)
			)
			(layer "F.SilkS")
		)
		(fp_line
			(start 0.7874 -0.4064)
			(end 0.7874 0.4064)
			(stroke
				(width 0.1524)
				(type default)
			)
			(layer "F.SilkS")
		)
		(fp_line
			(start -0.7874 0.4064)
			(end -0.7874 -0.4064)
			(stroke
				(width 0.1524)
				(type default)
			)
			(layer "F.SilkS")
		)
		(fp_line
			(start -0.7874 -0.4064)
			(end 0.7874 -0.4064)
			(stroke
				(width 0.1524)
				(type default)
			)
			(layer "F.SilkS")
		)
		(fp_line
			(start 0.67945 0.3048)
			(end 0.120396 0.3048)
			(stroke
				(width 0.1)
				(type default)
			)
			(layer "F.Fab")
		)
		(fp_line
			(start 0.67945 -0.3048)
			(end 0.67945 0.3048)
			(stroke
				(width 0.1)
				(type default)
			)
			(layer "F.Fab")
		)
		(fp_line
			(start 0.12065 -0.2794)
			(end 0.12065 -0.3048)
			(stroke
				(width 0.1)
				(type default)
			)
			(layer "F.Fab")
		)
		(fp_line
			(start 0.12065 -0.3048)
			(end 0.67945 -0.3048)
			(stroke
				(width 0.1)
				(type default)
			)
			(layer "F.Fab")
		)
		(fp_line
			(start 0.120396 0.3048)
			(end 0.120396 0.2794)
			(stroke
				(width 0.1)
				(type default)
			)
			(layer "F.Fab")
		)
		(fp_line
			(start 0.120396 0.2794)
			(end -0.12065 0.2794)
			(stroke
				(width 0.1)
				(type default)
			)
			(layer "F.Fab")
		)
		(fp_line
			(start -0.12065 0.3048)
			(end -0.67945 0.3048)
			(stroke
				(width 0.1)
				(type default)
			)
			(layer "F.Fab")
		)
		(fp_line
			(start -0.12065 0.2794)
			(end -0.12065 0.3048)
			(stroke
				(width 0.1)
				(type default)
			)
			(layer "F.Fab")
		)
		(fp_line
			(start -0.12065 -0.2794)
			(end 0.12065 -0.2794)
			(stroke
				(width 0.1)
				(type default)
			)
			(layer "F.Fab")
		)
		(fp_line
			(start -0.12065 -0.305054)
			(end -0.12065 -0.2794)
			(stroke
				(width 0.1)
				(type default)
			)
			(layer "F.Fab")
		)
		(fp_line
			(start -0.67945 0.3048)
			(end -0.67945 -0.305054)
			(stroke
				(width 0.1)
				(type default)
			)
			(layer "F.Fab")
		)
		(fp_line
			(start -0.67945 -0.305054)
			(end -0.12065 -0.305054)
			(stroke
				(width 0.1)
				(type default)
			)
			(layer "F.Fab")
		)
		(pad "1" smd circle
			(at -0.40005 0 180)
			(size 0 0)
			(layers "F.Cu" "F.Mask" "F.Paste")
			(net "PWRGD_NIC6_PWR_GOOD")
		)
		(pad "2" smd circle
			(at 0.40005 0 180)
			(size 0 0)
			(layers "F.Cu" "F.Mask" "F.Paste")
			(net "GND")
		)
	)
	(footprint ""
		(layer "F.Cu")
		(at 249.94743 -92.096336 90)
		(property "Reference" "C2652"
			(at 0 0 90)
			(layer "F.SilkS")
			(hide yes)
			(effects
				(font
					(size 1.27 1.27)
				)
			)
		)
		(property "Value" ""
			(at 0 0 90)
			(layer "F.Fab")
			(effects
				(font
					(size 1.27 1.27)
				)
			)
		)
		(duplicate_pad_numbers_are_jumpers no)
		(fp_line
			(start 0.7874 -0.4064)
			(end 0.7874 0.4064)
			(stroke
				(width 0.1524)
				(type default)
			)
			(layer "F.SilkS")
		)
		(fp_line
			(start -0.7874 -0.4064)
			(end 0.7874 -0.4064)
			(stroke
				(width 0.1524)
				(type default)
			)
			(layer "F.SilkS")
		)
		(fp_line
			(start 0.7874 0.4064)
			(end -0.7874 0.4064)
			(stroke
				(width 0.1524)
				(type default)
			)
			(layer "F.SilkS")
		)
		(fp_line
			(start -0.7874 0.4064)
			(end -0.7874 -0.4064)
			(stroke
				(width 0.1524)
				(type default)
			)
			(layer "F.SilkS")
		)
		(fp_line
			(start -0.12065 -0.305054)
			(end -0.12065 -0.2794)
			(stroke
				(width 0.1)
				(type default)
			)
			(layer "F.Fab")
		)
		(fp_line
			(start -0.67945 -0.305054)
			(end -0.12065 -0.305054)
			(stroke
				(width 0.1)
				(type default)
			)
			(layer "F.Fab")
		)
		(fp_line
			(start 0.67945 -0.3048)
			(end 0.67945 0.3048)
			(stroke
				(width 0.1)
				(type default)
			)
			(layer "F.Fab")
		)
		(fp_line
			(start 0.12065 -0.3048)
			(end 0.67945 -0.3048)
			(stroke
				(width 0.1)
				(type default)
			)
			(layer "F.Fab")
		)
		(fp_line
			(start 0.12065 -0.2794)
			(end 0.12065 -0.3048)
			(stroke
				(width 0.1)
				(type default)
			)
			(layer "F.Fab")
		)
		(fp_line
			(start -0.12065 -0.2794)
			(end 0.12065 -0.2794)
			(stroke
				(width 0.1)
				(type default)
			)
			(layer "F.Fab")
		)
		(fp_line
			(start 0.120396 0.2794)
			(end -0.12065 0.2794)
			(stroke
				(width 0.1)
				(type default)
			)
			(layer "F.Fab")
		)
		(fp_line
			(start -0.12065 0.2794)
			(end -0.12065 0.3048)
			(stroke
				(width 0.1)
				(type default)
			)
			(layer "F.Fab")
		)
		(fp_line
			(start 0.67945 0.3048)
			(end 0.120396 0.3048)
			(stroke
				(width 0.1)
				(type default)
			)
			(layer "F.Fab")
		)
		(fp_line
			(start 0.120396 0.3048)
			(end 0.120396 0.2794)
			(stroke
				(width 0.1)
				(type default)
			)
			(layer "F.Fab")
		)
		(fp_line
			(start -0.12065 0.3048)
			(end -0.67945 0.3048)
			(stroke
				(width 0.1)
				(type default)
			)
			(layer "F.Fab")
		)
		(fp_line
			(start -0.67945 0.3048)
			(end -0.67945 -0.305054)
			(stroke
				(width 0.1)
				(type default)
			)
			(layer "F.Fab")
		)
		(pad "1" smd circle
			(at -0.40005 0 90)
			(size 0 0)
			(layers "F.Cu" "F.Mask" "F.Paste")
			(net "FM_CK440Q_DEV_25M_EN")
		)
		(pad "2" smd circle
			(at 0.40005 0 90)
			(size 0 0)
			(layers "F.Cu" "F.Mask" "F.Paste")
			(net "GND")
		)
	)
	(footprint ""
		(layer "F.Cu")
		(at 73.782682 -356.244906 90)
		(property "Reference" "C141"
			(at 0 0 90)
			(layer "F.SilkS")
			(hide yes)
			(effects
				(font
					(size 1.27 1.27)
				)
			)
		)
		(property "Value" ""
			(at 0 0 90)
			(layer "F.Fab")
			(effects
				(font
					(size 1.27 1.27)
				)
			)
		)
		(duplicate_pad_numbers_are_jumpers no)
		(fp_line
			(start 0.299974 -0.150114)
			(end 0.299974 0.150114)
			(stroke
				(width 0.1)
				(type default)
			)
			(layer "F.Fab")
		)
		(fp_line
			(start -0.299974 -0.150114)
			(end 0.299974 -0.150114)
			(stroke
				(width 0.1)
				(type default)
			)
			(layer "F.Fab")
		)
		(fp_line
			(start 0.299974 0.150114)
			(end -0.299974 0.150114)
			(stroke
				(width 0.1)
				(type default)
			)
			(layer "F.Fab")
		)
		(fp_line
			(start -0.299974 0.150114)
			(end -0.299974 -0.150114)
			(stroke
				(width 0.1)
				(type default)
			)
			(layer "F.Fab")
		)
		(pad "1" smd rect
			(at -0.2667 0 90)
			(size 0.3048 0.381)
			(layers "F.Cu" "F.Mask" "F.Paste")
			(net "P5E_PEX0_STN6_TX_DP<105>")
		)
		(pad "2" smd rect
			(at 0.2667 0 90)
			(size 0.3048 0.381)
			(layers "F.Cu" "F.Mask" "F.Paste")
			(net "P5E_PEX0_STN6_TX_C_DP<105>")
		)
	)
	(footprint ""
		(layer "F.Cu")
		(at 92.436442 -356.244906 90)
		(property "Reference" "C159"
			(at 0 0 90)
			(layer "F.SilkS")
			(hide yes)
			(effects
				(font
					(size 1.27 1.27)
				)
			)
		)
		(property "Value" ""
			(at 0 0 90)
			(layer "F.Fab")
			(effects
				(font
					(size 1.27 1.27)
				)
			)
		)
		(duplicate_pad_numbers_are_jumpers no)
		(fp_line
			(start 0.299974 -0.150114)
			(end 0.299974 0.150114)
			(stroke
				(width 0.1)
				(type default)
			)
			(layer "F.Fab")
		)
		(fp_line
			(start -0.299974 -0.150114)
			(end 0.299974 -0.150114)
			(stroke
				(width 0.1)
				(type default)
			)
			(layer "F.Fab")
		)
		(fp_line
			(start 0.299974 0.150114)
			(end -0.299974 0.150114)
			(stroke
				(width 0.1)
				(type default)
			)
			(layer "F.Fab")
		)
		(fp_line
			(start -0.299974 0.150114)
			(end -0.299974 -0.150114)
			(stroke
				(width 0.1)
				(type default)
			)
			(layer "F.Fab")
		)
		(pad "1" smd rect
			(at -0.2667 0 90)
			(size 0.3048 0.381)
			(layers "F.Cu" "F.Mask" "F.Paste")
			(net "P5E_PEX0_STN6_TX_DP<96>")
		)
		(pad "2" smd rect
			(at 0.2667 0 90)
			(size 0.3048 0.381)
			(layers "F.Cu" "F.Mask" "F.Paste")
			(net "P5E_PEX0_STN6_TX_C_DP<96>")
		)
	)
	(footprint ""
		(layer "F.Cu")
		(at 365.072422 -391.66546 90)
		(property "Reference" "R6699"
			(at 0 0 90)
			(layer "F.SilkS")
			(hide yes)
			(effects
				(font
					(size 1.27 1.27)
				)
			)
		)
		(property "Value" ""
			(at 0 0 90)
			(layer "F.Fab")
			(effects
				(font
					(size 1.27 1.27)
				)
			)
		)
		(duplicate_pad_numbers_are_jumpers no)
		(fp_line
			(start 0.7874 -0.4064)
			(end 0.7874 0.4064)
			(stroke
				(width 0.1524)
				(type default)
			)
			(layer "F.SilkS")
		)
		(fp_line
			(start -0.7874 -0.4064)
			(end 0.7874 -0.4064)
			(stroke
				(width 0.1524)
				(type default)
			)
			(layer "F.SilkS")
		)
		(fp_line
			(start 0.7874 0.4064)
			(end -0.7874 0.4064)
			(stroke
				(width 0.1524)
				(type default)
			)
			(layer "F.SilkS")
		)
		(fp_line
			(start -0.7874 0.4064)
			(end -0.7874 -0.4064)
			(stroke
				(width 0.1524)
				(type default)
			)
			(layer "F.SilkS")
		)
		(fp_line
			(start -0.12065 -0.305054)
			(end -0.12065 -0.2794)
			(stroke
				(width 0.1)
				(type default)
			)
			(layer "F.Fab")
		)
		(fp_line
			(start -0.67945 -0.305054)
			(end -0.12065 -0.305054)
			(stroke
				(width 0.1)
				(type default)
			)
			(layer "F.Fab")
		)
		(fp_line
			(start 0.67945 -0.3048)
			(end 0.67945 0.3048)
			(stroke
				(width 0.1)
				(type default)
			)
			(layer "F.Fab")
		)
		(fp_line
			(start 0.12065 -0.3048)
			(end 0.67945 -0.3048)
			(stroke
				(width 0.1)
				(type default)
			)
			(layer "F.Fab")
		)
		(fp_line
			(start 0.12065 -0.2794)
			(end 0.12065 -0.3048)
			(stroke
				(width 0.1)
				(type default)
			)
			(layer "F.Fab")
		)
		(fp_line
			(start -0.12065 -0.2794)
			(end 0.12065 -0.2794)
			(stroke
				(width 0.1)
				(type default)
			)
			(layer "F.Fab")
		)
		(fp_line
			(start 0.120396 0.2794)
			(end -0.12065 0.2794)
			(stroke
				(width 0.1)
				(type default)
			)
			(layer "F.Fab")
		)
		(fp_line
			(start -0.12065 0.2794)
			(end -0.12065 0.3048)
			(stroke
				(width 0.1)
				(type default)
			)
			(layer "F.Fab")
		)
		(fp_line
			(start 0.67945 0.3048)
			(end 0.120396 0.3048)
			(stroke
				(width 0.1)
				(type default)
			)
			(layer "F.Fab")
		)
		(fp_line
			(start 0.120396 0.3048)
			(end 0.120396 0.2794)
			(stroke
				(width 0.1)
				(type default)
			)
			(layer "F.Fab")
		)
		(fp_line
			(start -0.12065 0.3048)
			(end -0.67945 0.3048)
			(stroke
				(width 0.1)
				(type default)
			)
			(layer "F.Fab")
		)
		(fp_line
			(start -0.67945 0.3048)
			(end -0.67945 -0.305054)
			(stroke
				(width 0.1)
				(type default)
			)
			(layer "F.Fab")
		)
		(pad "1" smd circle
			(at -0.40005 0 90)
			(size 0 0)
			(layers "F.Cu" "F.Mask" "F.Paste")
			(net "MB_3V3IO_RSVD1")
		)
		(pad "2" smd circle
			(at 0.40005 0 90)
			(size 0 0)
			(layers "F.Cu" "F.Mask" "F.Paste")
			(net "GND")
		)
	)
	(footprint ""
		(layer "F.Cu")
		(at 434.478938 -59.577986 -90)
		(property "Reference" "R900"
			(at 0 0 270)
			(layer "F.SilkS")
			(hide yes)
			(effects
				(font
					(size 1.27 1.27)
				)
			)
		)
		(property "Value" ""
			(at 0 0 270)
			(layer "F.Fab")
			(effects
				(font
					(size 1.27 1.27)
				)
			)
		)
		(duplicate_pad_numbers_are_jumpers no)
		(fp_line
			(start -0.7874 0.4064)
			(end -0.7874 -0.4064)
			(stroke
				(width 0.1524)
				(type default)
			)
			(layer "F.SilkS")
		)
		(fp_line
			(start 0.7874 0.4064)
			(end -0.7874 0.4064)
			(stroke
				(width 0.1524)
				(type default)
			)
			(layer "F.SilkS")
		)
		(fp_line
			(start -0.7874 -0.4064)
			(end 0.7874 -0.4064)
			(stroke
				(width 0.1524)
				(type default)
			)
			(layer "F.SilkS")
		)
		(fp_line
			(start 0.7874 -0.4064)
			(end 0.7874 0.4064)
			(stroke
				(width 0.1524)
				(type default)
			)
			(layer "F.SilkS")
		)
		(fp_line
			(start -0.67945 0.3048)
			(end -0.67945 -0.305054)
			(stroke
				(width 0.1)
				(type default)
			)
			(layer "F.Fab")
		)
		(fp_line
			(start -0.12065 0.3048)
			(end -0.67945 0.3048)
			(stroke
				(width 0.1)
				(type default)
			)
			(layer "F.Fab")
		)
		(fp_line
			(start 0.120396 0.3048)
			(end 0.120396 0.2794)
			(stroke
				(width 0.1)
				(type default)
			)
			(layer "F.Fab")
		)
		(fp_line
			(start 0.67945 0.3048)
			(end 0.120396 0.3048)
			(stroke
				(width 0.1)
				(type default)
			)
			(layer "F.Fab")
		)
		(fp_line
			(start -0.12065 0.2794)
			(end -0.12065 0.3048)
			(stroke
				(width 0.1)
				(type default)
			)
			(layer "F.Fab")
		)
		(fp_line
			(start 0.120396 0.2794)
			(end -0.12065 0.2794)
			(stroke
				(width 0.1)
				(type default)
			)
			(layer "F.Fab")
		)
		(fp_line
			(start -0.12065 -0.2794)
			(end 0.12065 -0.2794)
			(stroke
				(width 0.1)
				(type default)
			)
			(layer "F.Fab")
		)
		(fp_line
			(start 0.12065 -0.2794)
			(end 0.12065 -0.3048)
			(stroke
				(width 0.1)
				(type default)
			)
			(layer "F.Fab")
		)
		(fp_line
			(start 0.12065 -0.3048)
			(end 0.67945 -0.3048)
			(stroke
				(width 0.1)
				(type default)
			)
			(layer "F.Fab")
		)
		(fp_line
			(start 0.67945 -0.3048)
			(end 0.67945 0.3048)
			(stroke
				(width 0.1)
				(type default)
			)
			(layer "F.Fab")
		)
		(fp_line
			(start -0.67945 -0.305054)
			(end -0.12065 -0.305054)
			(stroke
				(width 0.1)
				(type default)
			)
			(layer "F.Fab")
		)
		(fp_line
			(start -0.12065 -0.305054)
			(end -0.12065 -0.2794)
			(stroke
				(width 0.1)
				(type default)
			)
			(layer "F.Fab")
		)
		(pad "1" smd circle
			(at -0.40005 0 270)
			(size 0 0)
			(layers "F.Cu" "F.Mask" "F.Paste")
			(net "P3V3_SSD15")
		)
		(pad "2" smd circle
			(at 0.40005 0 270)
			(size 0 0)
			(layers "F.Cu" "F.Mask" "F.Paste")
			(net "PWRGD_P3V3_SSD15")
		)
	)
	(footprint ""
		(layer "F.Cu")
		(at 64.455802 -356.244906 90)
		(property "Reference" "C123"
			(at 0 0 90)
			(layer "F.SilkS")
			(hide yes)
			(effects
				(font
					(size 1.27 1.27)
				)
			)
		)
		(property "Value" ""
			(at 0 0 90)
			(layer "F.Fab")
			(effects
				(font
					(size 1.27 1.27)
				)
			)
		)
		(duplicate_pad_numbers_are_jumpers no)
		(fp_line
			(start 0.299974 -0.150114)
			(end 0.299974 0.150114)
			(stroke
				(width 0.1)
				(type default)
			)
			(layer "F.Fab")
		)
		(fp_line
			(start -0.299974 -0.150114)
			(end 0.299974 -0.150114)
			(stroke
				(width 0.1)
				(type default)
			)
			(layer "F.Fab")
		)
		(fp_line
			(start 0.299974 0.150114)
			(end -0.299974 0.150114)
			(stroke
				(width 0.1)
				(type default)
			)
			(layer "F.Fab")
		)
		(fp_line
			(start -0.299974 0.150114)
			(end -0.299974 -0.150114)
			(stroke
				(width 0.1)
				(type default)
			)
			(layer "F.Fab")
		)
		(pad "1" smd rect
			(at -0.2667 0 90)
			(size 0.3048 0.381)
			(layers "F.Cu" "F.Mask" "F.Paste")
			(net "P5E_PEX0_STN5_TX_DP<82>")
		)
		(pad "2" smd rect
			(at 0.2667 0 90)
			(size 0.3048 0.381)
			(layers "F.Cu" "F.Mask" "F.Paste")
			(net "P5E_PEX0_STN5_TX_C_DP<82>")
		)
	)
	(footprint ""
		(layer "F.Cu")
		(at 204.115416 -306.06365 90)
		(property "Reference" "R3929"
			(at 0 0 90)
			(layer "F.SilkS")
			(hide yes)
			(effects
				(font
					(size 1.27 1.27)
				)
			)
		)
		(property "Value" ""
			(at 0 0 90)
			(layer "F.Fab")
			(effects
				(font
					(size 1.27 1.27)
				)
			)
		)
		(duplicate_pad_numbers_are_jumpers no)
		(fp_line
			(start 0.7874 -0.4064)
			(end 0.7874 0.4064)
			(stroke
				(width 0.1524)
				(type default)
			)
			(layer "F.SilkS")
		)
		(fp_line
			(start -0.7874 -0.4064)
			(end 0.7874 -0.4064)
			(stroke
				(width 0.1524)
				(type default)
			)
			(layer "F.SilkS")
		)
		(fp_line
			(start 0.7874 0.4064)
			(end -0.7874 0.4064)
			(stroke
				(width 0.1524)
				(type default)
			)
			(layer "F.SilkS")
		)
		(fp_line
			(start -0.7874 0.4064)
			(end -0.7874 -0.4064)
			(stroke
				(width 0.1524)
				(type default)
			)
			(layer "F.SilkS")
		)
		(fp_line
			(start -0.12065 -0.305054)
			(end -0.12065 -0.2794)
			(stroke
				(width 0.1)
				(type default)
			)
			(layer "F.Fab")
		)
		(fp_line
			(start -0.67945 -0.305054)
			(end -0.12065 -0.305054)
			(stroke
				(width 0.1)
				(type default)
			)
			(layer "F.Fab")
		)
		(fp_line
			(start 0.67945 -0.3048)
			(end 0.67945 0.3048)
			(stroke
				(width 0.1)
				(type default)
			)
			(layer "F.Fab")
		)
		(fp_line
			(start 0.12065 -0.3048)
			(end 0.67945 -0.3048)
			(stroke
				(width 0.1)
				(type default)
			)
			(layer "F.Fab")
		)
		(fp_line
			(start 0.12065 -0.2794)
			(end 0.12065 -0.3048)
			(stroke
				(width 0.1)
				(type default)
			)
			(layer "F.Fab")
		)
		(fp_line
			(start -0.12065 -0.2794)
			(end 0.12065 -0.2794)
			(stroke
				(width 0.1)
				(type default)
			)
			(layer "F.Fab")
		)
		(fp_line
			(start 0.120396 0.2794)
			(end -0.12065 0.2794)
			(stroke
				(width 0.1)
				(type default)
			)
			(layer "F.Fab")
		)
		(fp_line
			(start -0.12065 0.2794)
			(end -0.12065 0.3048)
			(stroke
				(width 0.1)
				(type default)
			)
			(layer "F.Fab")
		)
		(fp_line
			(start 0.67945 0.3048)
			(end 0.120396 0.3048)
			(stroke
				(width 0.1)
				(type default)
			)
			(layer "F.Fab")
		)
		(fp_line
			(start 0.120396 0.3048)
			(end 0.120396 0.2794)
			(stroke
				(width 0.1)
				(type default)
			)
			(layer "F.Fab")
		)
		(fp_line
			(start -0.12065 0.3048)
			(end -0.67945 0.3048)
			(stroke
				(width 0.1)
				(type default)
			)
			(layer "F.Fab")
		)
		(fp_line
			(start -0.67945 0.3048)
			(end -0.67945 -0.305054)
			(stroke
				(width 0.1)
				(type default)
			)
			(layer "F.Fab")
		)
		(pad "1" smd circle
			(at -0.40005 0 90)
			(size 0 0)
			(layers "F.Cu" "F.Mask" "F.Paste")
			(net "SMB_PEX1_SLAVE_SDA")
		)
		(pad "2" smd circle
			(at 0.40005 0 90)
			(size 0 0)
			(layers "F.Cu" "F.Mask" "F.Paste")
			(net "SMB_PEX1_R_SDA")
		)
	)
	(footprint ""
		(layer "F.Cu")
		(at 295.72585 -165.670484 -90)
		(property "Reference" "R3309"
			(at 0 0 270)
			(layer "F.SilkS")
			(hide yes)
			(effects
				(font
					(size 1.27 1.27)
				)
			)
		)
		(property "Value" ""
			(at 0 0 270)
			(layer "F.Fab")
			(effects
				(font
					(size 1.27 1.27)
				)
			)
		)
		(duplicate_pad_numbers_are_jumpers no)
		(fp_line
			(start -0.7874 0.4064)
			(end -0.7874 -0.4064)
			(stroke
				(width 0.1524)
				(type default)
			)
			(layer "F.SilkS")
		)
		(fp_line
			(start 0.7874 0.4064)
			(end -0.7874 0.4064)
			(stroke
				(width 0.1524)
				(type default)
			)
			(layer "F.SilkS")
		)
		(fp_line
			(start -0.7874 -0.4064)
			(end 0.7874 -0.4064)
			(stroke
				(width 0.1524)
				(type default)
			)
			(layer "F.SilkS")
		)
		(fp_line
			(start 0.7874 -0.4064)
			(end 0.7874 0.4064)
			(stroke
				(width 0.1524)
				(type default)
			)
			(layer "F.SilkS")
		)
		(fp_line
			(start -0.67945 0.3048)
			(end -0.67945 -0.305054)
			(stroke
				(width 0.1)
				(type default)
			)
			(layer "F.Fab")
		)
		(fp_line
			(start -0.12065 0.3048)
			(end -0.67945 0.3048)
			(stroke
				(width 0.1)
				(type default)
			)
			(layer "F.Fab")
		)
		(fp_line
			(start 0.120396 0.3048)
			(end 0.120396 0.2794)
			(stroke
				(width 0.1)
				(type default)
			)
			(layer "F.Fab")
		)
		(fp_line
			(start 0.67945 0.3048)
			(end 0.120396 0.3048)
			(stroke
				(width 0.1)
				(type default)
			)
			(layer "F.Fab")
		)
		(fp_line
			(start -0.12065 0.2794)
			(end -0.12065 0.3048)
			(stroke
				(width 0.1)
				(type default)
			)
			(layer "F.Fab")
		)
		(fp_line
			(start 0.120396 0.2794)
			(end -0.12065 0.2794)
			(stroke
				(width 0.1)
				(type default)
			)
			(layer "F.Fab")
		)
		(fp_line
			(start -0.12065 -0.2794)
			(end 0.12065 -0.2794)
			(stroke
				(width 0.1)
				(type default)
			)
			(layer "F.Fab")
		)
		(fp_line
			(start 0.12065 -0.2794)
			(end 0.12065 -0.3048)
			(stroke
				(width 0.1)
				(type default)
			)
			(layer "F.Fab")
		)
		(fp_line
			(start 0.12065 -0.3048)
			(end 0.67945 -0.3048)
			(stroke
				(width 0.1)
				(type default)
			)
			(layer "F.Fab")
		)
		(fp_line
			(start 0.67945 -0.3048)
			(end 0.67945 0.3048)
			(stroke
				(width 0.1)
				(type default)
			)
			(layer "F.Fab")
		)
		(fp_line
			(start -0.67945 -0.305054)
			(end -0.12065 -0.305054)
			(stroke
				(width 0.1)
				(type default)
			)
			(layer "F.Fab")
		)
		(fp_line
			(start -0.12065 -0.305054)
			(end -0.12065 -0.2794)
			(stroke
				(width 0.1)
				(type default)
			)
			(layer "F.Fab")
		)
		(pad "1" smd circle
			(at -0.40005 0 270)
			(size 0 0)
			(layers "F.Cu" "F.Mask" "F.Paste")
			(net "FM_SYS_THROTTLE_R")
		)
		(pad "2" smd circle
			(at 0.40005 0 270)
			(size 0 0)
			(layers "F.Cu" "F.Mask" "F.Paste")
			(net "FM_SYS_THROTTLE_NIC5")
		)
	)
	(footprint ""
		(layer "F.Cu")
		(at 110.496096 -92.333572 -90)
		(property "Reference" "R1150"
			(at 0 0 270)
			(layer "F.SilkS")
			(hide yes)
			(effects
				(font
					(size 1.27 1.27)
				)
			)
		)
		(property "Value" ""
			(at 0 0 270)
			(layer "F.Fab")
			(effects
				(font
					(size 1.27 1.27)
				)
			)
		)
		(duplicate_pad_numbers_are_jumpers no)
		(fp_line
			(start -0.7874 -0.4064)
			(end 0.7874 -0.4064)
			(stroke
				(width 0.1524)
				(type default)
			)
			(layer "F.SilkS")
		)
		(fp_line
			(start -0.67945 0.3048)
			(end -0.67945 -0.305054)
			(stroke
				(width 0.1)
				(type default)
			)
			(layer "F.Fab")
		)
		(fp_line
			(start -0.12065 0.3048)
			(end -0.67945 0.3048)
			(stroke
				(width 0.1)
				(type default)
			)
			(layer "F.Fab")
		)
		(fp_line
			(start 0.120396 0.3048)
			(end 0.120396 0.2794)
			(stroke
				(width 0.1)
				(type default)
			)
			(layer "F.Fab")
		)
		(fp_line
			(start 0.67945 0.3048)
			(end 0.120396 0.3048)
			(stroke
				(width 0.1)
				(type default)
			)
			(layer "F.Fab")
		)
		(fp_line
			(start -0.12065 0.2794)
			(end -0.12065 0.3048)
			(stroke
				(width 0.1)
				(type default)
			)
			(layer "F.Fab")
		)
		(fp_line
			(start 0.120396 0.2794)
			(end -0.12065 0.2794)
			(stroke
				(width 0.1)
				(type default)
			)
			(layer "F.Fab")
		)
		(fp_line
			(start -0.12065 -0.2794)
			(end 0.12065 -0.2794)
			(stroke
				(width 0.1)
				(type default)
			)
			(layer "F.Fab")
		)
		(fp_line
			(start 0.12065 -0.2794)
			(end 0.12065 -0.3048)
			(stroke
				(width 0.1)
				(type default)
			)
			(layer "F.Fab")
		)
		(fp_line
			(start 0.12065 -0.3048)
			(end 0.67945 -0.3048)
			(stroke
				(width 0.1)
				(type default)
			)
			(layer "F.Fab")
		)
		(fp_line
			(start 0.67945 -0.3048)
			(end 0.67945 0.3048)
			(stroke
				(width 0.1)
				(type default)
			)
			(layer "F.Fab")
		)
		(fp_line
			(start -0.67945 -0.305054)
			(end -0.12065 -0.305054)
			(stroke
				(width 0.1)
				(type default)
			)
			(layer "F.Fab")
		)
		(fp_line
			(start -0.12065 -0.305054)
			(end -0.12065 -0.2794)
			(stroke
				(width 0.1)
				(type default)
			)
			(layer "F.Fab")
		)
		(pad "1" smd circle
			(at -0.40005 0 270)
			(size 0 0)
			(layers "F.Cu" "F.Mask" "F.Paste")
			(net "CLK_100M_DB800ZL_SSD7_R_DP")
		)
		(pad "2" smd circle
			(at 0.40005 0 270)
			(size 0 0)
			(layers "F.Cu" "F.Mask" "F.Paste")
			(net "CLK_100M_DB800ZL_SSD7_DP")
		)
	)
	(footprint ""
		(layer "F.Cu")
		(at 168.367964 -56.353456)
		(property "Reference" "C2864"
			(at 0 0 0)
			(layer "F.SilkS")
			(hide yes)
			(effects
				(font
					(size 1.27 1.27)
				)
			)
		)
		(property "Value" ""
			(at 0 0 0)
			(layer "F.Fab")
			(effects
				(font
					(size 1.27 1.27)
				)
			)
		)
		(duplicate_pad_numbers_are_jumpers no)
		(fp_line
			(start -0.7874 -0.4064)
			(end 0.7874 -0.4064)
			(stroke
				(width 0.1524)
				(type default)
			)
			(layer "F.SilkS")
		)
		(fp_line
			(start -0.7874 0.4064)
			(end -0.7874 -0.4064)
			(stroke
				(width 0.1524)
				(type default)
			)
			(layer "F.SilkS")
		)
		(fp_line
			(start 0.7874 -0.4064)
			(end 0.7874 0.4064)
			(stroke
				(width 0.1524)
				(type default)
			)
			(layer "F.SilkS")
		)
		(fp_line
			(start 0.7874 0.4064)
			(end -0.7874 0.4064)
			(stroke
				(width 0.1524)
				(type default)
			)
			(layer "F.SilkS")
		)
		(fp_line
			(start -0.67945 -0.305054)
			(end -0.12065 -0.305054)
			(stroke
				(width 0.1)
				(type default)
			)
			(layer "F.Fab")
		)
		(fp_line
			(start -0.67945 0.3048)
			(end -0.67945 -0.305054)
			(stroke
				(width 0.1)
				(type default)
			)
			(layer "F.Fab")
		)
		(fp_line
			(start -0.12065 -0.305054)
			(end -0.12065 -0.2794)
			(stroke
				(width 0.1)
				(type default)
			)
			(layer "F.Fab")
		)
		(fp_line
			(start -0.12065 -0.2794)
			(end 0.12065 -0.2794)
			(stroke
				(width 0.1)
				(type default)
			)
			(layer "F.Fab")
		)
		(fp_line
			(start -0.12065 0.2794)
			(end -0.12065 0.3048)
			(stroke
				(width 0.1)
				(type default)
			)
			(layer "F.Fab")
		)
		(fp_line
			(start -0.12065 0.3048)
			(end -0.67945 0.3048)
			(stroke
				(width 0.1)
				(type default)
			)
			(layer "F.Fab")
		)
		(fp_line
			(start 0.120396 0.2794)
			(end -0.12065 0.2794)
			(stroke
				(width 0.1)
				(type default)
			)
			(layer "F.Fab")
		)
		(fp_line
			(start 0.120396 0.3048)
			(end 0.120396 0.2794)
			(stroke
				(width 0.1)
				(type default)
			)
			(layer "F.Fab")
		)
		(fp_line
			(start 0.12065 -0.3048)
			(end 0.67945 -0.3048)
			(stroke
				(width 0.1)
				(type default)
			)
			(layer "F.Fab")
		)
		(fp_line
			(start 0.12065 -0.2794)
			(end 0.12065 -0.3048)
			(stroke
				(width 0.1)
				(type default)
			)
			(layer "F.Fab")
		)
		(fp_line
			(start 0.67945 -0.3048)
			(end 0.67945 0.3048)
			(stroke
				(width 0.1)
				(type default)
			)
			(layer "F.Fab")
		)
		(fp_line
			(start 0.67945 0.3048)
			(end 0.120396 0.3048)
			(stroke
				(width 0.1)
				(type default)
			)
			(layer "F.Fab")
		)
		(pad "1" smd circle
			(at -0.40005 0)
			(size 0 0)
			(layers "F.Cu" "F.Mask" "F.Paste")
			(net "SSD5_PWR_EN_R")
		)
		(pad "2" smd circle
			(at 0.40005 0)
			(size 0 0)
			(layers "F.Cu" "F.Mask" "F.Paste")
			(net "GND")
		)
	)
	(footprint ""
		(layer "F.Cu")
		(at 448.309746 -254.5969 -90)
		(property "Reference" "C4409"
			(at 0 0 270)
			(layer "F.SilkS")
			(hide yes)
			(effects
				(font
					(size 1.27 1.27)
				)
			)
		)
		(property "Value" ""
			(at 0 0 270)
			(layer "F.Fab")
			(effects
				(font
					(size 1.27 1.27)
				)
			)
		)
		(duplicate_pad_numbers_are_jumpers no)
		(fp_line
			(start -1.2954 0.5842)
			(end -1.2954 -0.5842)
			(stroke
				(width 0.1524)
				(type default)
			)
			(layer "F.SilkS")
		)
		(fp_line
			(start 1.2954 0.5842)
			(end -1.2954 0.5842)
			(stroke
				(width 0.1524)
				(type default)
			)
			(layer "F.SilkS")
		)
		(fp_line
			(start -1.2954 -0.5842)
			(end 1.2954 -0.5842)
			(stroke
				(width 0.1524)
				(type default)
			)
			(layer "F.SilkS")
		)
		(fp_line
			(start 1.2954 -0.5842)
			(end 1.2954 0.5842)
			(stroke
				(width 0.1524)
				(type default)
			)
			(layer "F.SilkS")
		)
		(fp_line
			(start -0.8636 0.4572)
			(end -0.8636 0.4064)
			(stroke
				(width 0.1)
				(type default)
			)
			(layer "F.Fab")
		)
		(fp_line
			(start 0.8636 0.4572)
			(end -0.8636 0.4572)
			(stroke
				(width 0.1)
				(type default)
			)
			(layer "F.Fab")
		)
		(fp_line
			(start -1.1938 0.4064)
			(end -1.1938 -0.4064)
			(stroke
				(width 0.1)
				(type default)
			)
			(layer "F.Fab")
		)
		(fp_line
			(start -0.8636 0.4064)
			(end -1.1938 0.4064)
			(stroke
				(width 0.1)
				(type default)
			)
			(layer "F.Fab")
		)
		(fp_line
			(start 0.8636 0.4064)
			(end 0.8636 0.4572)
			(stroke
				(width 0.1)
				(type default)
			)
			(layer "F.Fab")
		)
		(fp_line
			(start 1.1938 0.4064)
			(end 0.8636 0.4064)
			(stroke
				(width 0.1)
				(type default)
			)
			(layer "F.Fab")
		)
		(fp_line
			(start -1.1938 -0.4064)
			(end -0.8636 -0.4064)
			(stroke
				(width 0.1)
				(type default)
			)
			(layer "F.Fab")
		)
		(fp_line
			(start -0.8636 -0.4064)
			(end -0.8636 -0.4572)
			(stroke
				(width 0.1)
				(type default)
			)
			(layer "F.Fab")
		)
		(fp_line
			(start 0.8636 -0.4064)
			(end 1.1938 -0.4064)
			(stroke
				(width 0.1)
				(type default)
			)
			(layer "F.Fab")
		)
		(fp_line
			(start 1.1938 -0.4064)
			(end 1.1938 0.4064)
			(stroke
				(width 0.1)
				(type default)
			)
			(layer "F.Fab")
		)
		(fp_line
			(start -0.8636 -0.4572)
			(end 0.8636 -0.4572)
			(stroke
				(width 0.1)
				(type default)
			)
			(layer "F.Fab")
		)
		(fp_line
			(start 0.8636 -0.4572)
			(end 0.8636 -0.4064)
			(stroke
				(width 0.1)
				(type default)
			)
			(layer "F.Fab")
		)
		(pad "1" smd rect
			(at -0.7366 0 180)
			(size 0.7112 0.8128)
			(layers "F.Cu" "F.Mask" "F.Paste")
			(net "P1V25_SERDES_VDDPLL_PEX3_C7")
		)
		(pad "2" smd rect
			(at 0.7366 0 180)
			(size 0.7112 0.8128)
			(layers "F.Cu" "F.Mask" "F.Paste")
			(net "GND")
		)
	)
	(footprint ""
		(layer "F.Cu")
		(at 392.919966 -15.649956 180)
		(property "Reference" "H125"
			(at -1.811782 2.60604 0)
			(unlocked yes)
			(layer "B.SilkS")
			(effects
				(font
					(size 0.7874 0.5842)
					(thickness 0.1524)
				)
				(justify left mirror)
			)
		)
		(property "Value" ""
			(at 0 0 180)
			(layer "F.Fab")
			(effects
				(font
					(size 1.27 1.27)
				)
			)
		)
		(duplicate_pad_numbers_are_jumpers no)
		(pad "1" thru_hole rect
			(at 0 0 180)
			(size 4.2164 5.0038)
			(drill 2.0066
				(offset 0.099822 0)
			)
			(layers "*.Cu" "*.Mask")
			(remove_unused_layers no)
			(net "Net_8538")
			(clearance -0.8509)
			(padstack
				(mode front_inner_back)
				(layer "Inner"
					(shape circle)
					(size 4.0132 4.0132)
					(clearance -0.7493)
				)
				(layer "B.Cu"
					(shape circle)
					(size 4.0132 4.0132)
					(clearance -0.7493)
				)
			)
		)
	)
	(footprint ""
		(layer "F.Cu")
		(at 105.287826 -319.545462 90)
		(property "Reference" "L50"
			(at 3.108198 1.49479 0)
			(unlocked yes)
			(layer "F.SilkS")
			(effects
				(font
					(size 0.7874 0.5842)
					(thickness 0.1524)
				)
				(justify left)
			)
		)
		(property "Value" ""
			(at 0 0 90)
			(layer "F.Fab")
			(effects
				(font
					(size 1.27 1.27)
				)
			)
		)
		(duplicate_pad_numbers_are_jumpers no)
		(fp_line
			(start 2.248154 -4.9911)
			(end -2.248154 -4.9911)
			(stroke
				(width 0.1524)
				(type default)
			)
			(layer "F.SilkS")
		)
		(fp_line
			(start -2.248154 -4.9911)
			(end -2.248154 -1.528318)
			(stroke
				(width 0.1524)
				(type default)
			)
			(layer "F.SilkS")
		)
		(fp_line
			(start 2.248154 -1.583436)
			(end 2.248154 -4.9911)
			(stroke
				(width 0.1524)
				(type default)
			)
			(layer "F.SilkS")
		)
		(fp_line
			(start -2.248154 1.59004)
			(end -2.248154 4.9911)
			(stroke
				(width 0.1524)
				(type default)
			)
			(layer "F.SilkS")
		)
		(fp_line
			(start 2.248154 4.9911)
			(end 2.248154 1.480058)
			(stroke
				(width 0.1524)
				(type default)
			)
			(layer "F.SilkS")
		)
		(fp_line
			(start -2.248154 4.9911)
			(end 2.248154 4.9911)
			(stroke
				(width 0.1524)
				(type default)
			)
			(layer "F.SilkS")
		)
		(fp_line
			(start 1.700022 -0.899922)
			(end -1.700022 -0.899922)
			(stroke
				(width 0.1)
				(type default)
			)
			(layer "F.Fab")
		)
		(fp_line
			(start -1.700022 -0.899922)
			(end -1.700022 0.899922)
			(stroke
				(width 0.1)
				(type default)
			)
			(layer "F.Fab")
		)
		(fp_line
			(start 1.700022 0.899922)
			(end 1.700022 -0.899922)
			(stroke
				(width 0.1)
				(type default)
			)
			(layer "F.Fab")
		)
		(fp_line
			(start -1.700022 0.899922)
			(end 1.700022 0.899922)
			(stroke
				(width 0.1)
				(type default)
			)
			(layer "F.Fab")
		)
		(pad "1" smd rect
			(at -1.575054 0 90)
			(size 1.1684 9.8044)
			(layers "F.Cu" "F.Mask" "F.Paste")
			(net "P0V8_PEX0")
		)
		(pad "2" smd rect
			(at 1.575054 0 90)
			(size 1.1684 9.8044)
			(layers "F.Cu" "F.Mask" "F.Paste")
			(net "P0V8_SERDES_VDDA_PEX0")
		)
	)
	(footprint ""
		(layer "F.Cu")
		(at 75.66787 -19.453098)
		(property "Reference" "R1653"
			(at 0 0 0)
			(layer "F.SilkS")
			(hide yes)
			(effects
				(font
					(size 1.27 1.27)
				)
			)
		)
		(property "Value" ""
			(at 0 0 0)
			(layer "F.Fab")
			(effects
				(font
					(size 1.27 1.27)
				)
			)
		)
		(duplicate_pad_numbers_are_jumpers no)
		(fp_line
			(start -0.7874 -0.4064)
			(end 0.7874 -0.4064)
			(stroke
				(width 0.1524)
				(type default)
			)
			(layer "F.SilkS")
		)
		(fp_line
			(start -0.7874 0.4064)
			(end -0.7874 -0.4064)
			(stroke
				(width 0.1524)
				(type default)
			)
			(layer "F.SilkS")
		)
		(fp_line
			(start 0.7874 -0.4064)
			(end 0.7874 0.4064)
			(stroke
				(width 0.1524)
				(type default)
			)
			(layer "F.SilkS")
		)
		(fp_line
			(start 0.7874 0.4064)
			(end -0.7874 0.4064)
			(stroke
				(width 0.1524)
				(type default)
			)
			(layer "F.SilkS")
		)
		(fp_line
			(start -0.67945 -0.305054)
			(end -0.12065 -0.305054)
			(stroke
				(width 0.1)
				(type default)
			)
			(layer "F.Fab")
		)
		(fp_line
			(start -0.67945 0.3048)
			(end -0.67945 -0.305054)
			(stroke
				(width 0.1)
				(type default)
			)
			(layer "F.Fab")
		)
		(fp_line
			(start -0.12065 -0.305054)
			(end -0.12065 -0.2794)
			(stroke
				(width 0.1)
				(type default)
			)
			(layer "F.Fab")
		)
		(fp_line
			(start -0.12065 -0.2794)
			(end 0.12065 -0.2794)
			(stroke
				(width 0.1)
				(type default)
			)
			(layer "F.Fab")
		)
		(fp_line
			(start -0.12065 0.2794)
			(end -0.12065 0.3048)
			(stroke
				(width 0.1)
				(type default)
			)
			(layer "F.Fab")
		)
		(fp_line
			(start -0.12065 0.3048)
			(end -0.67945 0.3048)
			(stroke
				(width 0.1)
				(type default)
			)
			(layer "F.Fab")
		)
		(fp_line
			(start 0.120396 0.2794)
			(end -0.12065 0.2794)
			(stroke
				(width 0.1)
				(type default)
			)
			(layer "F.Fab")
		)
		(fp_line
			(start 0.120396 0.3048)
			(end 0.120396 0.2794)
			(stroke
				(width 0.1)
				(type default)
			)
			(layer "F.Fab")
		)
		(fp_line
			(start 0.12065 -0.3048)
			(end 0.67945 -0.3048)
			(stroke
				(width 0.1)
				(type default)
			)
			(layer "F.Fab")
		)
		(fp_line
			(start 0.12065 -0.2794)
			(end 0.12065 -0.3048)
			(stroke
				(width 0.1)
				(type default)
			)
			(layer "F.Fab")
		)
		(fp_line
			(start 0.67945 -0.3048)
			(end 0.67945 0.3048)
			(stroke
				(width 0.1)
				(type default)
			)
			(layer "F.Fab")
		)
		(fp_line
			(start 0.67945 0.3048)
			(end 0.120396 0.3048)
			(stroke
				(width 0.1)
				(type default)
			)
			(layer "F.Fab")
		)
		(pad "1" smd circle
			(at -0.40005 0)
			(size 0 0)
			(layers "F.Cu" "F.Mask" "F.Paste")
			(net "SMB_ISO_SSD2_R_SDA")
		)
		(pad "2" smd circle
			(at 0.40005 0)
			(size 0 0)
			(layers "F.Cu" "F.Mask" "F.Paste")
			(net "SMB_ISO_SSD2_SDA")
		)
	)
	(footprint ""
		(layer "F.Cu")
		(at 266.702286 -252.356874 -90)
		(property "Reference" "R1367"
			(at 0 0 270)
			(layer "F.SilkS")
			(hide yes)
			(effects
				(font
					(size 1.27 1.27)
				)
			)
		)
		(property "Value" ""
			(at 0 0 270)
			(layer "F.Fab")
			(effects
				(font
					(size 1.27 1.27)
				)
			)
		)
		(duplicate_pad_numbers_are_jumpers no)
		(fp_line
			(start -0.7874 0.4064)
			(end -0.7874 -0.4064)
			(stroke
				(width 0.1524)
				(type default)
			)
			(layer "F.SilkS")
		)
		(fp_line
			(start 0.7874 0.4064)
			(end -0.7874 0.4064)
			(stroke
				(width 0.1524)
				(type default)
			)
			(layer "F.SilkS")
		)
		(fp_line
			(start -0.7874 -0.4064)
			(end 0.7874 -0.4064)
			(stroke
				(width 0.1524)
				(type default)
			)
			(layer "F.SilkS")
		)
		(fp_line
			(start 0.7874 -0.4064)
			(end 0.7874 0.4064)
			(stroke
				(width 0.1524)
				(type default)
			)
			(layer "F.SilkS")
		)
		(fp_line
			(start -0.67945 0.3048)
			(end -0.67945 -0.305054)
			(stroke
				(width 0.1)
				(type default)
			)
			(layer "F.Fab")
		)
		(fp_line
			(start -0.12065 0.3048)
			(end -0.67945 0.3048)
			(stroke
				(width 0.1)
				(type default)
			)
			(layer "F.Fab")
		)
		(fp_line
			(start 0.120396 0.3048)
			(end 0.120396 0.2794)
			(stroke
				(width 0.1)
				(type default)
			)
			(layer "F.Fab")
		)
		(fp_line
			(start 0.67945 0.3048)
			(end 0.120396 0.3048)
			(stroke
				(width 0.1)
				(type default)
			)
			(layer "F.Fab")
		)
		(fp_line
			(start -0.12065 0.2794)
			(end -0.12065 0.3048)
			(stroke
				(width 0.1)
				(type default)
			)
			(layer "F.Fab")
		)
		(fp_line
			(start 0.120396 0.2794)
			(end -0.12065 0.2794)
			(stroke
				(width 0.1)
				(type default)
			)
			(layer "F.Fab")
		)
		(fp_line
			(start -0.12065 -0.2794)
			(end 0.12065 -0.2794)
			(stroke
				(width 0.1)
				(type default)
			)
			(layer "F.Fab")
		)
		(fp_line
			(start 0.12065 -0.2794)
			(end 0.12065 -0.3048)
			(stroke
				(width 0.1)
				(type default)
			)
			(layer "F.Fab")
		)
		(fp_line
			(start 0.12065 -0.3048)
			(end 0.67945 -0.3048)
			(stroke
				(width 0.1)
				(type default)
			)
			(layer "F.Fab")
		)
		(fp_line
			(start 0.67945 -0.3048)
			(end 0.67945 0.3048)
			(stroke
				(width 0.1)
				(type default)
			)
			(layer "F.Fab")
		)
		(fp_line
			(start -0.67945 -0.305054)
			(end -0.12065 -0.305054)
			(stroke
				(width 0.1)
				(type default)
			)
			(layer "F.Fab")
		)
		(fp_line
			(start -0.12065 -0.305054)
			(end -0.12065 -0.2794)
			(stroke
				(width 0.1)
				(type default)
			)
			(layer "F.Fab")
		)
		(pad "1" smd circle
			(at -0.40005 0 270)
			(size 0 0)
			(layers "F.Cu" "F.Mask" "F.Paste")
			(net "GND")
		)
		(pad "2" smd circle
			(at 0.40005 0 270)
			(size 0 0)
			(layers "F.Cu" "F.Mask" "F.Paste")
			(net "PEX2_MODE_SEL11")
		)
	)
	(footprint ""
		(layer "F.Cu")
		(at 71.796148 -47.20082 90)
		(property "Reference" "C208"
			(at 0 0 90)
			(layer "F.SilkS")
			(hide yes)
			(effects
				(font
					(size 1.27 1.27)
				)
			)
		)
		(property "Value" ""
			(at 0 0 90)
			(layer "F.Fab")
			(effects
				(font
					(size 1.27 1.27)
				)
			)
		)
		(duplicate_pad_numbers_are_jumpers no)
		(fp_line
			(start 0.7874 -0.4064)
			(end 0.7874 0.4064)
			(stroke
				(width 0.1524)
				(type default)
			)
			(layer "F.SilkS")
		)
		(fp_line
			(start -0.7874 -0.4064)
			(end 0.7874 -0.4064)
			(stroke
				(width 0.1524)
				(type default)
			)
			(layer "F.SilkS")
		)
		(fp_line
			(start 0.7874 0.4064)
			(end -0.7874 0.4064)
			(stroke
				(width 0.1524)
				(type default)
			)
			(layer "F.SilkS")
		)
		(fp_line
			(start -0.7874 0.4064)
			(end -0.7874 -0.4064)
			(stroke
				(width 0.1524)
				(type default)
			)
			(layer "F.SilkS")
		)
		(fp_line
			(start -0.12065 -0.305054)
			(end -0.12065 -0.2794)
			(stroke
				(width 0.1)
				(type default)
			)
			(layer "F.Fab")
		)
		(fp_line
			(start -0.67945 -0.305054)
			(end -0.12065 -0.305054)
			(stroke
				(width 0.1)
				(type default)
			)
			(layer "F.Fab")
		)
		(fp_line
			(start 0.67945 -0.3048)
			(end 0.67945 0.3048)
			(stroke
				(width 0.1)
				(type default)
			)
			(layer "F.Fab")
		)
		(fp_line
			(start 0.12065 -0.3048)
			(end 0.67945 -0.3048)
			(stroke
				(width 0.1)
				(type default)
			)
			(layer "F.Fab")
		)
		(fp_line
			(start 0.12065 -0.2794)
			(end 0.12065 -0.3048)
			(stroke
				(width 0.1)
				(type default)
			)
			(layer "F.Fab")
		)
		(fp_line
			(start -0.12065 -0.2794)
			(end 0.12065 -0.2794)
			(stroke
				(width 0.1)
				(type default)
			)
			(layer "F.Fab")
		)
		(fp_line
			(start 0.120396 0.2794)
			(end -0.12065 0.2794)
			(stroke
				(width 0.1)
				(type default)
			)
			(layer "F.Fab")
		)
		(fp_line
			(start -0.12065 0.2794)
			(end -0.12065 0.3048)
			(stroke
				(width 0.1)
				(type default)
			)
			(layer "F.Fab")
		)
		(fp_line
			(start 0.67945 0.3048)
			(end 0.120396 0.3048)
			(stroke
				(width 0.1)
				(type default)
			)
			(layer "F.Fab")
		)
		(fp_line
			(start 0.120396 0.3048)
			(end 0.120396 0.2794)
			(stroke
				(width 0.1)
				(type default)
			)
			(layer "F.Fab")
		)
		(fp_line
			(start -0.12065 0.3048)
			(end -0.67945 0.3048)
			(stroke
				(width 0.1)
				(type default)
			)
			(layer "F.Fab")
		)
		(fp_line
			(start -0.67945 0.3048)
			(end -0.67945 -0.305054)
			(stroke
				(width 0.1)
				(type default)
			)
			(layer "F.Fab")
		)
		(pad "1" smd circle
			(at -0.40005 0 90)
			(size 0 0)
			(layers "F.Cu" "F.Mask" "F.Paste")
			(net "P12V_SSD2_R")
		)
		(pad "2" smd circle
			(at 0.40005 0 90)
			(size 0 0)
			(layers "F.Cu" "F.Mask" "F.Paste")
			(net "GND")
		)
	)
	(footprint ""
		(layer "F.Cu")
		(at 16.785336 -272.200624)
		(property "Reference" "R773"
			(at 0 0 0)
			(layer "F.SilkS")
			(hide yes)
			(effects
				(font
					(size 1.27 1.27)
				)
			)
		)
		(property "Value" ""
			(at 0 0 0)
			(layer "F.Fab")
			(effects
				(font
					(size 1.27 1.27)
				)
			)
		)
		(duplicate_pad_numbers_are_jumpers no)
		(fp_line
			(start -0.7874 -0.4064)
			(end 0.7874 -0.4064)
			(stroke
				(width 0.1524)
				(type default)
			)
			(layer "F.SilkS")
		)
		(fp_line
			(start -0.7874 0.4064)
			(end -0.7874 -0.4064)
			(stroke
				(width 0.1524)
				(type default)
			)
			(layer "F.SilkS")
		)
		(fp_line
			(start 0.7874 -0.4064)
			(end 0.7874 0.4064)
			(stroke
				(width 0.1524)
				(type default)
			)
			(layer "F.SilkS")
		)
		(fp_line
			(start 0.7874 0.4064)
			(end -0.7874 0.4064)
			(stroke
				(width 0.1524)
				(type default)
			)
			(layer "F.SilkS")
		)
		(fp_line
			(start -0.67945 -0.305054)
			(end -0.12065 -0.305054)
			(stroke
				(width 0.1)
				(type default)
			)
			(layer "F.Fab")
		)
		(fp_line
			(start -0.67945 0.3048)
			(end -0.67945 -0.305054)
			(stroke
				(width 0.1)
				(type default)
			)
			(layer "F.Fab")
		)
		(fp_line
			(start -0.12065 -0.305054)
			(end -0.12065 -0.2794)
			(stroke
				(width 0.1)
				(type default)
			)
			(layer "F.Fab")
		)
		(fp_line
			(start -0.12065 -0.2794)
			(end 0.12065 -0.2794)
			(stroke
				(width 0.1)
				(type default)
			)
			(layer "F.Fab")
		)
		(fp_line
			(start -0.12065 0.2794)
			(end -0.12065 0.3048)
			(stroke
				(width 0.1)
				(type default)
			)
			(layer "F.Fab")
		)
		(fp_line
			(start -0.12065 0.3048)
			(end -0.67945 0.3048)
			(stroke
				(width 0.1)
				(type default)
			)
			(layer "F.Fab")
		)
		(fp_line
			(start 0.120396 0.2794)
			(end -0.12065 0.2794)
			(stroke
				(width 0.1)
				(type default)
			)
			(layer "F.Fab")
		)
		(fp_line
			(start 0.120396 0.3048)
			(end 0.120396 0.2794)
			(stroke
				(width 0.1)
				(type default)
			)
			(layer "F.Fab")
		)
		(fp_line
			(start 0.12065 -0.3048)
			(end 0.67945 -0.3048)
			(stroke
				(width 0.1)
				(type default)
			)
			(layer "F.Fab")
		)
		(fp_line
			(start 0.12065 -0.2794)
			(end 0.12065 -0.3048)
			(stroke
				(width 0.1)
				(type default)
			)
			(layer "F.Fab")
		)
		(fp_line
			(start 0.67945 -0.3048)
			(end 0.67945 0.3048)
			(stroke
				(width 0.1)
				(type default)
			)
			(layer "F.Fab")
		)
		(fp_line
			(start 0.67945 0.3048)
			(end 0.120396 0.3048)
			(stroke
				(width 0.1)
				(type default)
			)
			(layer "F.Fab")
		)
		(pad "1" smd circle
			(at -0.40005 0)
			(size 0 0)
			(layers "F.Cu" "F.Mask" "F.Paste")
			(net "PEX0_P1V25_ADC_A1")
		)
		(pad "2" smd circle
			(at 0.40005 0)
			(size 0 0)
			(layers "F.Cu" "F.Mask" "F.Paste")
			(net "GND")
		)
	)
	(footprint ""
		(layer "F.Cu")
		(at 186.047126 -55.63489 90)
		(property "Reference" "PC383"
			(at 0 0 90)
			(layer "F.SilkS")
			(hide yes)
			(effects
				(font
					(size 1.27 1.27)
				)
			)
		)
		(property "Value" ""
			(at 0 0 90)
			(layer "F.Fab")
			(effects
				(font
					(size 1.27 1.27)
				)
			)
		)
		(duplicate_pad_numbers_are_jumpers no)
		(fp_line
			(start 1.524 -0.762)
			(end 1.524 0.762)
			(stroke
				(width 0.1524)
				(type default)
			)
			(layer "F.SilkS")
		)
		(fp_line
			(start -1.524 -0.762)
			(end 1.524 -0.762)
			(stroke
				(width 0.1524)
				(type default)
			)
			(layer "F.SilkS")
		)
		(fp_line
			(start 1.524 0.762)
			(end -1.524 0.762)
			(stroke
				(width 0.1524)
				(type default)
			)
			(layer "F.SilkS")
		)
		(fp_line
			(start -1.524 0.762)
			(end -1.524 -0.762)
			(stroke
				(width 0.1524)
				(type default)
			)
			(layer "F.SilkS")
		)
		(fp_line
			(start 1.1049 -0.724916)
			(end -1.1049 -0.724916)
			(stroke
				(width 0.1)
				(type default)
			)
			(layer "F.Fab")
		)
		(fp_line
			(start -1.1049 -0.724916)
			(end -1.1049 0.724916)
			(stroke
				(width 0.1)
				(type default)
			)
			(layer "F.Fab")
		)
		(fp_line
			(start 1.1049 0.724916)
			(end 1.1049 -0.724916)
			(stroke
				(width 0.1)
				(type default)
			)
			(layer "F.Fab")
		)
		(fp_line
			(start -1.1049 0.724916)
			(end 1.1049 0.724916)
			(stroke
				(width 0.1)
				(type default)
			)
			(layer "F.Fab")
		)
		(pad "1" smd rect
			(at -0.889 0 270)
			(size 1.016 1.27)
			(layers "F.Cu" "F.Mask" "F.Paste")
			(net "P12V_SSD6_R")
		)
		(pad "2" smd rect
			(at 0.889 0 270)
			(size 1.016 1.27)
			(layers "F.Cu" "F.Mask" "F.Paste")
			(net "GND")
		)
	)
	(footprint ""
		(layer "F.Cu")
		(at 248.094754 -275.503386)
		(property "Reference" "R791"
			(at 0 0 0)
			(layer "F.SilkS")
			(hide yes)
			(effects
				(font
					(size 1.27 1.27)
				)
			)
		)
		(property "Value" ""
			(at 0 0 0)
			(layer "F.Fab")
			(effects
				(font
					(size 1.27 1.27)
				)
			)
		)
		(duplicate_pad_numbers_are_jumpers no)
		(fp_line
			(start -0.7874 -0.4064)
			(end 0.7874 -0.4064)
			(stroke
				(width 0.1524)
				(type default)
			)
			(layer "F.SilkS")
		)
		(fp_line
			(start -0.7874 0.4064)
			(end -0.7874 -0.4064)
			(stroke
				(width 0.1524)
				(type default)
			)
			(layer "F.SilkS")
		)
		(fp_line
			(start 0.7874 -0.4064)
			(end 0.7874 0.4064)
			(stroke
				(width 0.1524)
				(type default)
			)
			(layer "F.SilkS")
		)
		(fp_line
			(start 0.7874 0.4064)
			(end -0.7874 0.4064)
			(stroke
				(width 0.1524)
				(type default)
			)
			(layer "F.SilkS")
		)
		(fp_line
			(start -0.67945 -0.305054)
			(end -0.12065 -0.305054)
			(stroke
				(width 0.1)
				(type default)
			)
			(layer "F.Fab")
		)
		(fp_line
			(start -0.67945 0.3048)
			(end -0.67945 -0.305054)
			(stroke
				(width 0.1)
				(type default)
			)
			(layer "F.Fab")
		)
		(fp_line
			(start -0.12065 -0.305054)
			(end -0.12065 -0.2794)
			(stroke
				(width 0.1)
				(type default)
			)
			(layer "F.Fab")
		)
		(fp_line
			(start -0.12065 -0.2794)
			(end 0.12065 -0.2794)
			(stroke
				(width 0.1)
				(type default)
			)
			(layer "F.Fab")
		)
		(fp_line
			(start -0.12065 0.2794)
			(end -0.12065 0.3048)
			(stroke
				(width 0.1)
				(type default)
			)
			(layer "F.Fab")
		)
		(fp_line
			(start -0.12065 0.3048)
			(end -0.67945 0.3048)
			(stroke
				(width 0.1)
				(type default)
			)
			(layer "F.Fab")
		)
		(fp_line
			(start 0.120396 0.2794)
			(end -0.12065 0.2794)
			(stroke
				(width 0.1)
				(type default)
			)
			(layer "F.Fab")
		)
		(fp_line
			(start 0.120396 0.3048)
			(end 0.120396 0.2794)
			(stroke
				(width 0.1)
				(type default)
			)
			(layer "F.Fab")
		)
		(fp_line
			(start 0.12065 -0.3048)
			(end 0.67945 -0.3048)
			(stroke
				(width 0.1)
				(type default)
			)
			(layer "F.Fab")
		)
		(fp_line
			(start 0.12065 -0.2794)
			(end 0.12065 -0.3048)
			(stroke
				(width 0.1)
				(type default)
			)
			(layer "F.Fab")
		)
		(fp_line
			(start 0.67945 -0.3048)
			(end 0.67945 0.3048)
			(stroke
				(width 0.1)
				(type default)
			)
			(layer "F.Fab")
		)
		(fp_line
			(start 0.67945 0.3048)
			(end 0.120396 0.3048)
			(stroke
				(width 0.1)
				(type default)
			)
			(layer "F.Fab")
		)
		(pad "1" smd circle
			(at -0.40005 0)
			(size 0 0)
			(layers "F.Cu" "F.Mask" "F.Paste")
			(net "PEX2_P1V25_ADC_A0")
		)
		(pad "2" smd circle
			(at 0.40005 0)
			(size 0 0)
			(layers "F.Cu" "F.Mask" "F.Paste")
			(net "P3V3_AUX")
		)
	)
	(footprint ""
		(layer "F.Cu")
		(at 480.069906 -524.787368 180)
		(property "Reference" "J35_OTH"
			(at -3.2385 -1.402334 0)
			(unlocked yes)
			(layer "B.SilkS")
			(effects
				(font
					(size 0.7874 0.5842)
					(thickness 0.1524)
				)
				(justify mirror)
			)
		)
		(property "Value" ""
			(at 0 0 180)
			(layer "F.Fab")
			(effects
				(font
					(size 1.27 1.27)
				)
			)
		)
		(duplicate_pad_numbers_are_jumpers no)
		(pad "1" thru_hole circle
			(at 0 0 180)
			(size 0.4572 0.4572)
			(drill 0.2032)
			(layers "*.Cu" "*.Mask")
			(remove_unused_layers no)
			(net "Net_9101")
			(clearance 0.127)
			(thermal_gap 0.127)
			(padstack
				(mode front_inner_back)
				(layer "Inner"
					(shape circle)
					(size 0.4572 0.4572)
					(clearance 0.127)
				)
				(layer "B.Cu"
					(shape circle)
					(size 0.508 0.508)
					(clearance 0.1016)
				)
			)
		)
	)
	(footprint ""
		(layer "F.Cu")
		(at 384.938524 -122.79884)
		(property "Reference" "C676"
			(at 0 0 0)
			(layer "F.SilkS")
			(hide yes)
			(effects
				(font
					(size 1.27 1.27)
				)
			)
		)
		(property "Value" ""
			(at 0 0 0)
			(layer "F.Fab")
			(effects
				(font
					(size 1.27 1.27)
				)
			)
		)
		(duplicate_pad_numbers_are_jumpers no)
		(fp_line
			(start -0.299974 -0.150114)
			(end 0.299974 -0.150114)
			(stroke
				(width 0.1)
				(type default)
			)
			(layer "F.Fab")
		)
		(fp_line
			(start -0.299974 0.150114)
			(end -0.299974 -0.150114)
			(stroke
				(width 0.1)
				(type default)
			)
			(layer "F.Fab")
		)
		(fp_line
			(start 0.299974 -0.150114)
			(end 0.299974 0.150114)
			(stroke
				(width 0.1)
				(type default)
			)
			(layer "F.Fab")
		)
		(fp_line
			(start 0.299974 0.150114)
			(end -0.299974 0.150114)
			(stroke
				(width 0.1)
				(type default)
			)
			(layer "F.Fab")
		)
		(pad "1" smd rect
			(at -0.2667 0)
			(size 0.3048 0.381)
			(layers "F.Cu" "F.Mask" "F.Paste")
			(net "P5E_PEX3_STN1_TX_DP<26>")
		)
		(pad "2" smd rect
			(at 0.2667 0)
			(size 0.3048 0.381)
			(layers "F.Cu" "F.Mask" "F.Paste")
			(net "P5E_PEX3_STN1_TX_C_DP<26>")
		)
	)
	(footprint ""
		(layer "F.Cu")
		(at 210.087972 -45.704252 90)
		(property "Reference" "R583"
			(at 0 0 90)
			(layer "F.SilkS")
			(hide yes)
			(effects
				(font
					(size 1.27 1.27)
				)
			)
		)
		(property "Value" ""
			(at 0 0 90)
			(layer "F.Fab")
			(effects
				(font
					(size 1.27 1.27)
				)
			)
		)
		(duplicate_pad_numbers_are_jumpers no)
		(fp_line
			(start 3.937508 -1.8796)
			(end -3.937508 -1.8796)
			(stroke
				(width 0.1524)
				(type default)
			)
			(layer "F.SilkS")
		)
		(fp_line
			(start -3.937508 -1.8796)
			(end -3.937508 1.8796)
			(stroke
				(width 0.1524)
				(type default)
			)
			(layer "F.SilkS")
		)
		(fp_line
			(start 3.937508 1.8796)
			(end 3.937508 -1.8796)
			(stroke
				(width 0.1524)
				(type default)
			)
			(layer "F.SilkS")
		)
		(fp_line
			(start -3.937508 1.8796)
			(end 3.937508 1.8796)
			(stroke
				(width 0.1524)
				(type default)
			)
			(layer "F.SilkS")
		)
		(fp_line
			(start 3.275076 -1.674876)
			(end -3.275076 -1.674876)
			(stroke
				(width 0.1)
				(type default)
			)
			(layer "F.Fab")
		)
		(fp_line
			(start -3.275076 -1.674876)
			(end -3.275076 1.674876)
			(stroke
				(width 0.1)
				(type default)
			)
			(layer "F.Fab")
		)
		(fp_line
			(start 3.275076 1.674876)
			(end 3.275076 -1.674876)
			(stroke
				(width 0.1)
				(type default)
			)
			(layer "F.Fab")
		)
		(fp_line
			(start -3.275076 1.674876)
			(end 3.275076 1.674876)
			(stroke
				(width 0.1)
				(type default)
			)
			(layer "F.Fab")
		)
		(pad "1" smd rect
			(at -2.350008 0 90)
			(size 2.921 3.5052)
			(layers "F.Cu" "F.Mask" "F.Paste")
			(net "P12V_SSD7")
		)
		(pad "2" smd rect
			(at 2.350008 0 90)
			(size 2.921 3.5052)
			(layers "F.Cu" "F.Mask" "F.Paste")
			(net "P12V_SSD7_R")
		)
	)
	(footprint ""
		(layer "F.Cu")
		(at 13.625322 -119.105426 90)
		(property "Reference" "R5864"
			(at 0 0 90)
			(layer "F.SilkS")
			(hide yes)
			(effects
				(font
					(size 1.27 1.27)
				)
			)
		)
		(property "Value" ""
			(at 0 0 90)
			(layer "F.Fab")
			(effects
				(font
					(size 1.27 1.27)
				)
			)
		)
		(duplicate_pad_numbers_are_jumpers no)
		(fp_line
			(start 0.7874 -0.4064)
			(end 0.7874 0.4064)
			(stroke
				(width 0.1524)
				(type default)
			)
			(layer "F.SilkS")
		)
		(fp_line
			(start -0.7874 -0.4064)
			(end 0.7874 -0.4064)
			(stroke
				(width 0.1524)
				(type default)
			)
			(layer "F.SilkS")
		)
		(fp_line
			(start 0.7874 0.4064)
			(end -0.7874 0.4064)
			(stroke
				(width 0.1524)
				(type default)
			)
			(layer "F.SilkS")
		)
		(fp_line
			(start -0.7874 0.4064)
			(end -0.7874 -0.4064)
			(stroke
				(width 0.1524)
				(type default)
			)
			(layer "F.SilkS")
		)
		(fp_line
			(start -0.12065 -0.305054)
			(end -0.12065 -0.2794)
			(stroke
				(width 0.1)
				(type default)
			)
			(layer "F.Fab")
		)
		(fp_line
			(start -0.67945 -0.305054)
			(end -0.12065 -0.305054)
			(stroke
				(width 0.1)
				(type default)
			)
			(layer "F.Fab")
		)
		(fp_line
			(start 0.67945 -0.3048)
			(end 0.67945 0.3048)
			(stroke
				(width 0.1)
				(type default)
			)
			(layer "F.Fab")
		)
		(fp_line
			(start 0.12065 -0.3048)
			(end 0.67945 -0.3048)
			(stroke
				(width 0.1)
				(type default)
			)
			(layer "F.Fab")
		)
		(fp_line
			(start 0.12065 -0.2794)
			(end 0.12065 -0.3048)
			(stroke
				(width 0.1)
				(type default)
			)
			(layer "F.Fab")
		)
		(fp_line
			(start -0.12065 -0.2794)
			(end 0.12065 -0.2794)
			(stroke
				(width 0.1)
				(type default)
			)
			(layer "F.Fab")
		)
		(fp_line
			(start 0.120396 0.2794)
			(end -0.12065 0.2794)
			(stroke
				(width 0.1)
				(type default)
			)
			(layer "F.Fab")
		)
		(fp_line
			(start -0.12065 0.2794)
			(end -0.12065 0.3048)
			(stroke
				(width 0.1)
				(type default)
			)
			(layer "F.Fab")
		)
		(fp_line
			(start 0.67945 0.3048)
			(end 0.120396 0.3048)
			(stroke
				(width 0.1)
				(type default)
			)
			(layer "F.Fab")
		)
		(fp_line
			(start 0.120396 0.3048)
			(end 0.120396 0.2794)
			(stroke
				(width 0.1)
				(type default)
			)
			(layer "F.Fab")
		)
		(fp_line
			(start -0.12065 0.3048)
			(end -0.67945 0.3048)
			(stroke
				(width 0.1)
				(type default)
			)
			(layer "F.Fab")
		)
		(fp_line
			(start -0.67945 0.3048)
			(end -0.67945 -0.305054)
			(stroke
				(width 0.1)
				(type default)
			)
			(layer "F.Fab")
		)
		(pad "1" smd circle
			(at -0.40005 0 90)
			(size 0 0)
			(layers "F.Cu" "F.Mask" "F.Paste")
			(net "P3V3_NIC0_PG_G1")
		)
		(pad "2" smd circle
			(at 0.40005 0 90)
			(size 0 0)
			(layers "F.Cu" "F.Mask" "F.Paste")
			(net "GND")
		)
	)
	(footprint ""
		(layer "F.Cu")
		(at 358.830626 -142.035276 180)
		(property "Reference" "PC335"
			(at 0 0 180)
			(layer "F.SilkS")
			(hide yes)
			(effects
				(font
					(size 1.27 1.27)
				)
			)
		)
		(property "Value" ""
			(at 0 0 180)
			(layer "F.Fab")
			(effects
				(font
					(size 1.27 1.27)
				)
			)
		)
		(duplicate_pad_numbers_are_jumpers no)
		(fp_line
			(start 1.524 0.762)
			(end -1.524 0.762)
			(stroke
				(width 0.1524)
				(type default)
			)
			(layer "F.SilkS")
		)
		(fp_line
			(start 1.524 -0.762)
			(end 1.524 0.762)
			(stroke
				(width 0.1524)
				(type default)
			)
			(layer "F.SilkS")
		)
		(fp_line
			(start -1.524 0.762)
			(end -1.524 -0.762)
			(stroke
				(width 0.1524)
				(type default)
			)
			(layer "F.SilkS")
		)
		(fp_line
			(start -1.524 -0.762)
			(end 1.524 -0.762)
			(stroke
				(width 0.1524)
				(type default)
			)
			(layer "F.SilkS")
		)
		(fp_line
			(start 1.1049 0.724916)
			(end 1.1049 -0.724916)
			(stroke
				(width 0.1)
				(type default)
			)
			(layer "F.Fab")
		)
		(fp_line
			(start 1.1049 -0.724916)
			(end -1.1049 -0.724916)
			(stroke
				(width 0.1)
				(type default)
			)
			(layer "F.Fab")
		)
		(fp_line
			(start -1.1049 0.724916)
			(end 1.1049 0.724916)
			(stroke
				(width 0.1)
				(type default)
			)
			(layer "F.Fab")
		)
		(fp_line
			(start -1.1049 -0.724916)
			(end -1.1049 0.724916)
			(stroke
				(width 0.1)
				(type default)
			)
			(layer "F.Fab")
		)
		(pad "1" smd rect
			(at -0.889 0)
			(size 1.016 1.27)
			(layers "F.Cu" "F.Mask" "F.Paste")
			(net "P12V_NIC6_R")
		)
		(pad "2" smd rect
			(at 0.889 0)
			(size 1.016 1.27)
			(layers "F.Cu" "F.Mask" "F.Paste")
			(net "GND")
		)
	)
	(footprint ""
		(layer "F.Cu")
		(at 486.553764 -528.154392 180)
		(property "Reference" "PEX1_HS"
			(at 0.127 -0.593598 0)
			(unlocked yes)
			(layer "F.SilkS")
			(effects
				(font
					(size 0.254 0.127)
					(thickness 0.000001)
				)
			)
		)
		(property "Value" ""
			(at 0 0 180)
			(layer "F.Fab")
			(effects
				(font
					(size 1.27 1.27)
				)
			)
		)
		(duplicate_pad_numbers_are_jumpers no)
		(pad "1" smd circle
			(at 0 0 180)
			(size 0.762 0.762)
			(layers "F.Cu" "F.Mask" "F.Paste")
			(net "Net_9123")
		)
	)
	(footprint ""
		(layer "F.Cu")
		(at 263.207246 -257.439414 -90)
		(property "Reference" "C3368"
			(at 0 0 270)
			(layer "F.SilkS")
			(hide yes)
			(effects
				(font
					(size 1.27 1.27)
				)
			)
		)
		(property "Value" ""
			(at 0 0 270)
			(layer "F.Fab")
			(effects
				(font
					(size 1.27 1.27)
				)
			)
		)
		(duplicate_pad_numbers_are_jumpers no)
		(fp_line
			(start -0.299974 0.150114)
			(end -0.299974 -0.150114)
			(stroke
				(width 0.1)
				(type default)
			)
			(layer "F.Fab")
		)
		(fp_line
			(start 0.299974 0.150114)
			(end -0.299974 0.150114)
			(stroke
				(width 0.1)
				(type default)
			)
			(layer "F.Fab")
		)
		(fp_line
			(start -0.299974 -0.150114)
			(end 0.299974 -0.150114)
			(stroke
				(width 0.1)
				(type default)
			)
			(layer "F.Fab")
		)
		(fp_line
			(start 0.299974 -0.150114)
			(end 0.299974 0.150114)
			(stroke
				(width 0.1)
				(type default)
			)
			(layer "F.Fab")
		)
		(pad "1" smd rect
			(at -0.2667 0 270)
			(size 0.3048 0.381)
			(layers "F.Cu" "F.Mask" "F.Paste")
			(net "P1V8_PLL0_PEX2")
		)
		(pad "2" smd rect
			(at 0.2667 0 270)
			(size 0.3048 0.381)
			(layers "F.Cu" "F.Mask" "F.Paste")
			(net "GND")
		)
	)
	(footprint ""
		(layer "F.Cu")
		(at 121.13514 -91.462606)
		(property "Reference" "R1556"
			(at 0 0 0)
			(layer "F.SilkS")
			(hide yes)
			(effects
				(font
					(size 1.27 1.27)
				)
			)
		)
		(property "Value" ""
			(at 0 0 0)
			(layer "F.Fab")
			(effects
				(font
					(size 1.27 1.27)
				)
			)
		)
		(duplicate_pad_numbers_are_jumpers no)
		(fp_line
			(start -0.7874 -0.4064)
			(end 0.7874 -0.4064)
			(stroke
				(width 0.1524)
				(type default)
			)
			(layer "F.SilkS")
		)
		(fp_line
			(start -0.7874 0.4064)
			(end -0.7874 -0.4064)
			(stroke
				(width 0.1524)
				(type default)
			)
			(layer "F.SilkS")
		)
		(fp_line
			(start 0.7874 -0.4064)
			(end 0.7874 0.4064)
			(stroke
				(width 0.1524)
				(type default)
			)
			(layer "F.SilkS")
		)
		(fp_line
			(start 0.7874 0.4064)
			(end -0.7874 0.4064)
			(stroke
				(width 0.1524)
				(type default)
			)
			(layer "F.SilkS")
		)
		(fp_line
			(start -0.67945 -0.305054)
			(end -0.12065 -0.305054)
			(stroke
				(width 0.1)
				(type default)
			)
			(layer "F.Fab")
		)
		(fp_line
			(start -0.67945 0.3048)
			(end -0.67945 -0.305054)
			(stroke
				(width 0.1)
				(type default)
			)
			(layer "F.Fab")
		)
		(fp_line
			(start -0.12065 -0.305054)
			(end -0.12065 -0.2794)
			(stroke
				(width 0.1)
				(type default)
			)
			(layer "F.Fab")
		)
		(fp_line
			(start -0.12065 -0.2794)
			(end 0.12065 -0.2794)
			(stroke
				(width 0.1)
				(type default)
			)
			(layer "F.Fab")
		)
		(fp_line
			(start -0.12065 0.2794)
			(end -0.12065 0.3048)
			(stroke
				(width 0.1)
				(type default)
			)
			(layer "F.Fab")
		)
		(fp_line
			(start -0.12065 0.3048)
			(end -0.67945 0.3048)
			(stroke
				(width 0.1)
				(type default)
			)
			(layer "F.Fab")
		)
		(fp_line
			(start 0.120396 0.2794)
			(end -0.12065 0.2794)
			(stroke
				(width 0.1)
				(type default)
			)
			(layer "F.Fab")
		)
		(fp_line
			(start 0.120396 0.3048)
			(end 0.120396 0.2794)
			(stroke
				(width 0.1)
				(type default)
			)
			(layer "F.Fab")
		)
		(fp_line
			(start 0.12065 -0.3048)
			(end 0.67945 -0.3048)
			(stroke
				(width 0.1)
				(type default)
			)
			(layer "F.Fab")
		)
		(fp_line
			(start 0.12065 -0.2794)
			(end 0.12065 -0.3048)
			(stroke
				(width 0.1)
				(type default)
			)
			(layer "F.Fab")
		)
		(fp_line
			(start 0.67945 -0.3048)
			(end 0.67945 0.3048)
			(stroke
				(width 0.1)
				(type default)
			)
			(layer "F.Fab")
		)
		(fp_line
			(start 0.67945 0.3048)
			(end 0.120396 0.3048)
			(stroke
				(width 0.1)
				(type default)
			)
			(layer "F.Fab")
		)
		(pad "1" smd circle
			(at -0.40005 0)
			(size 0 0)
			(layers "F.Cu" "F.Mask" "F.Paste")
			(net "P3V3_AUX")
		)
		(pad "2" smd circle
			(at 0.40005 0)
			(size 0 0)
			(layers "F.Cu" "F.Mask" "F.Paste")
			(net "SMB_BIC_I2C9_MUX0_SSD2_R_SCL")
		)
	)
	(footprint ""
		(layer "F.Cu")
		(at 33.287716 -294.819832)
		(property "Reference" "C3027"
			(at 0 0 0)
			(layer "F.SilkS")
			(hide yes)
			(effects
				(font
					(size 1.27 1.27)
				)
			)
		)
		(property "Value" ""
			(at 0 0 0)
			(layer "F.Fab")
			(effects
				(font
					(size 1.27 1.27)
				)
			)
		)
		(duplicate_pad_numbers_are_jumpers no)
		(fp_line
			(start -1.2954 -0.5842)
			(end 1.2954 -0.5842)
			(stroke
				(width 0.1524)
				(type default)
			)
			(layer "F.SilkS")
		)
		(fp_line
			(start -1.2954 0.5842)
			(end -1.2954 -0.5842)
			(stroke
				(width 0.1524)
				(type default)
			)
			(layer "F.SilkS")
		)
		(fp_line
			(start 1.2954 -0.5842)
			(end 1.2954 0.5842)
			(stroke
				(width 0.1524)
				(type default)
			)
			(layer "F.SilkS")
		)
		(fp_line
			(start 1.2954 0.5842)
			(end -1.2954 0.5842)
			(stroke
				(width 0.1524)
				(type default)
			)
			(layer "F.SilkS")
		)
		(fp_line
			(start -1.1938 -0.4064)
			(end -0.8636 -0.4064)
			(stroke
				(width 0.1)
				(type default)
			)
			(layer "F.Fab")
		)
		(fp_line
			(start -1.1938 0.4064)
			(end -1.1938 -0.4064)
			(stroke
				(width 0.1)
				(type default)
			)
			(layer "F.Fab")
		)
		(fp_line
			(start -0.8636 -0.4572)
			(end 0.8636 -0.4572)
			(stroke
				(width 0.1)
				(type default)
			)
			(layer "F.Fab")
		)
		(fp_line
			(start -0.8636 -0.4064)
			(end -0.8636 -0.4572)
			(stroke
				(width 0.1)
				(type default)
			)
			(layer "F.Fab")
		)
		(fp_line
			(start -0.8636 0.4064)
			(end -1.1938 0.4064)
			(stroke
				(width 0.1)
				(type default)
			)
			(layer "F.Fab")
		)
		(fp_line
			(start -0.8636 0.4572)
			(end -0.8636 0.4064)
			(stroke
				(width 0.1)
				(type default)
			)
			(layer "F.Fab")
		)
		(fp_line
			(start 0.8636 -0.4572)
			(end 0.8636 -0.4064)
			(stroke
				(width 0.1)
				(type default)
			)
			(layer "F.Fab")
		)
		(fp_line
			(start 0.8636 -0.4064)
			(end 1.1938 -0.4064)
			(stroke
				(width 0.1)
				(type default)
			)
			(layer "F.Fab")
		)
		(fp_line
			(start 0.8636 0.4064)
			(end 0.8636 0.4572)
			(stroke
				(width 0.1)
				(type default)
			)
			(layer "F.Fab")
		)
		(fp_line
			(start 0.8636 0.4572)
			(end -0.8636 0.4572)
			(stroke
				(width 0.1)
				(type default)
			)
			(layer "F.Fab")
		)
		(fp_line
			(start 1.1938 -0.4064)
			(end 1.1938 0.4064)
			(stroke
				(width 0.1)
				(type default)
			)
			(layer "F.Fab")
		)
		(fp_line
			(start 1.1938 0.4064)
			(end 0.8636 0.4064)
			(stroke
				(width 0.1)
				(type default)
			)
			(layer "F.Fab")
		)
		(pad "1" smd rect
			(at -0.7366 0 270)
			(size 0.7112 0.8128)
			(layers "F.Cu" "F.Mask" "F.Paste")
			(net "PCEPLL2_VDDA18_PEX0")
		)
		(pad "2" smd rect
			(at 0.7366 0 270)
			(size 0.7112 0.8128)
			(layers "F.Cu" "F.Mask" "F.Paste")
			(net "GND")
		)
	)
	(footprint ""
		(layer "F.Cu")
		(at 104.267 -57.332626)
		(property "Reference" "R6838"
			(at 0 0 0)
			(layer "F.SilkS")
			(hide yes)
			(effects
				(font
					(size 1.27 1.27)
				)
			)
		)
		(property "Value" ""
			(at 0 0 0)
			(layer "F.Fab")
			(effects
				(font
					(size 1.27 1.27)
				)
			)
		)
		(duplicate_pad_numbers_are_jumpers no)
		(fp_line
			(start -0.7874 -0.4064)
			(end 0.7874 -0.4064)
			(stroke
				(width 0.1524)
				(type default)
			)
			(layer "F.SilkS")
		)
		(fp_line
			(start -0.7874 0.4064)
			(end -0.7874 -0.4064)
			(stroke
				(width 0.1524)
				(type default)
			)
			(layer "F.SilkS")
		)
		(fp_line
			(start 0.7874 -0.4064)
			(end 0.7874 0.4064)
			(stroke
				(width 0.1524)
				(type default)
			)
			(layer "F.SilkS")
		)
		(fp_line
			(start 0.7874 0.4064)
			(end -0.7874 0.4064)
			(stroke
				(width 0.1524)
				(type default)
			)
			(layer "F.SilkS")
		)
		(fp_line
			(start -0.67945 -0.305054)
			(end -0.12065 -0.305054)
			(stroke
				(width 0.1)
				(type default)
			)
			(layer "F.Fab")
		)
		(fp_line
			(start -0.67945 0.3048)
			(end -0.67945 -0.305054)
			(stroke
				(width 0.1)
				(type default)
			)
			(layer "F.Fab")
		)
		(fp_line
			(start -0.12065 -0.305054)
			(end -0.12065 -0.2794)
			(stroke
				(width 0.1)
				(type default)
			)
			(layer "F.Fab")
		)
		(fp_line
			(start -0.12065 -0.2794)
			(end 0.12065 -0.2794)
			(stroke
				(width 0.1)
				(type default)
			)
			(layer "F.Fab")
		)
		(fp_line
			(start -0.12065 0.2794)
			(end -0.12065 0.3048)
			(stroke
				(width 0.1)
				(type default)
			)
			(layer "F.Fab")
		)
		(fp_line
			(start -0.12065 0.3048)
			(end -0.67945 0.3048)
			(stroke
				(width 0.1)
				(type default)
			)
			(layer "F.Fab")
		)
		(fp_line
			(start 0.120396 0.2794)
			(end -0.12065 0.2794)
			(stroke
				(width 0.1)
				(type default)
			)
			(layer "F.Fab")
		)
		(fp_line
			(start 0.120396 0.3048)
			(end 0.120396 0.2794)
			(stroke
				(width 0.1)
				(type default)
			)
			(layer "F.Fab")
		)
		(fp_line
			(start 0.12065 -0.3048)
			(end 0.67945 -0.3048)
			(stroke
				(width 0.1)
				(type default)
			)
			(layer "F.Fab")
		)
		(fp_line
			(start 0.12065 -0.2794)
			(end 0.12065 -0.3048)
			(stroke
				(width 0.1)
				(type default)
			)
			(layer "F.Fab")
		)
		(fp_line
			(start 0.67945 -0.3048)
			(end 0.67945 0.3048)
			(stroke
				(width 0.1)
				(type default)
			)
			(layer "F.Fab")
		)
		(fp_line
			(start 0.67945 0.3048)
			(end 0.120396 0.3048)
			(stroke
				(width 0.1)
				(type default)
			)
			(layer "F.Fab")
		)
		(pad "1" smd circle
			(at -0.40005 0)
			(size 0 0)
			(layers "F.Cu" "F.Mask" "F.Paste")
			(net "SSD3_PWR_EN_R")
		)
		(pad "2" smd circle
			(at 0.40005 0)
			(size 0 0)
			(layers "F.Cu" "F.Mask" "F.Paste")
			(net "GND")
		)
	)
	(footprint ""
		(layer "F.Cu")
		(at 420.975028 -56.977534 180)
		(property "Reference" "PC426"
			(at 0 0 180)
			(layer "F.SilkS")
			(hide yes)
			(effects
				(font
					(size 1.27 1.27)
				)
			)
		)
		(property "Value" ""
			(at 0 0 180)
			(layer "F.Fab")
			(effects
				(font
					(size 1.27 1.27)
				)
			)
		)
		(duplicate_pad_numbers_are_jumpers no)
		(fp_line
			(start 0.7874 0.4064)
			(end -0.7874 0.4064)
			(stroke
				(width 0.1524)
				(type default)
			)
			(layer "F.SilkS")
		)
		(fp_line
			(start 0.7874 -0.4064)
			(end 0.7874 0.4064)
			(stroke
				(width 0.1524)
				(type default)
			)
			(layer "F.SilkS")
		)
		(fp_line
			(start -0.7874 0.4064)
			(end -0.7874 -0.4064)
			(stroke
				(width 0.1524)
				(type default)
			)
			(layer "F.SilkS")
		)
		(fp_line
			(start -0.7874 -0.4064)
			(end 0.7874 -0.4064)
			(stroke
				(width 0.1524)
				(type default)
			)
			(layer "F.SilkS")
		)
		(fp_line
			(start 0.67945 0.3048)
			(end 0.120396 0.3048)
			(stroke
				(width 0.1)
				(type default)
			)
			(layer "F.Fab")
		)
		(fp_line
			(start 0.67945 -0.3048)
			(end 0.67945 0.3048)
			(stroke
				(width 0.1)
				(type default)
			)
			(layer "F.Fab")
		)
		(fp_line
			(start 0.12065 -0.2794)
			(end 0.12065 -0.3048)
			(stroke
				(width 0.1)
				(type default)
			)
			(layer "F.Fab")
		)
		(fp_line
			(start 0.12065 -0.3048)
			(end 0.67945 -0.3048)
			(stroke
				(width 0.1)
				(type default)
			)
			(layer "F.Fab")
		)
		(fp_line
			(start 0.120396 0.3048)
			(end 0.120396 0.2794)
			(stroke
				(width 0.1)
				(type default)
			)
			(layer "F.Fab")
		)
		(fp_line
			(start 0.120396 0.2794)
			(end -0.12065 0.2794)
			(stroke
				(width 0.1)
				(type default)
			)
			(layer "F.Fab")
		)
		(fp_line
			(start -0.12065 0.3048)
			(end -0.67945 0.3048)
			(stroke
				(width 0.1)
				(type default)
			)
			(layer "F.Fab")
		)
		(fp_line
			(start -0.12065 0.2794)
			(end -0.12065 0.3048)
			(stroke
				(width 0.1)
				(type default)
			)
			(layer "F.Fab")
		)
		(fp_line
			(start -0.12065 -0.2794)
			(end 0.12065 -0.2794)
			(stroke
				(width 0.1)
				(type default)
			)
			(layer "F.Fab")
		)
		(fp_line
			(start -0.12065 -0.305054)
			(end -0.12065 -0.2794)
			(stroke
				(width 0.1)
				(type default)
			)
			(layer "F.Fab")
		)
		(fp_line
			(start -0.67945 0.3048)
			(end -0.67945 -0.305054)
			(stroke
				(width 0.1)
				(type default)
			)
			(layer "F.Fab")
		)
		(fp_line
			(start -0.67945 -0.305054)
			(end -0.12065 -0.305054)
			(stroke
				(width 0.1)
				(type default)
			)
			(layer "F.Fab")
		)
		(pad "1" smd circle
			(at -0.40005 0 180)
			(size 0 0)
			(layers "F.Cu" "F.Mask" "F.Paste")
			(net "P12V_AUX")
		)
		(pad "2" smd circle
			(at 0.40005 0 180)
			(size 0 0)
			(layers "F.Cu" "F.Mask" "F.Paste")
			(net "GND")
		)
	)
	(footprint ""
		(layer "F.Cu")
		(at 217.235786 -223.382586 180)
		(property "Reference" "R1485"
			(at 0 0 180)
			(layer "F.SilkS")
			(hide yes)
			(effects
				(font
					(size 1.27 1.27)
				)
			)
		)
		(property "Value" ""
			(at 0 0 180)
			(layer "F.Fab")
			(effects
				(font
					(size 1.27 1.27)
				)
			)
		)
		(duplicate_pad_numbers_are_jumpers no)
		(fp_line
			(start 0.7874 0.4064)
			(end -0.7874 0.4064)
			(stroke
				(width 0.1524)
				(type default)
			)
			(layer "F.SilkS")
		)
		(fp_line
			(start 0.7874 -0.4064)
			(end 0.7874 0.4064)
			(stroke
				(width 0.1524)
				(type default)
			)
			(layer "F.SilkS")
		)
		(fp_line
			(start -0.7874 0.4064)
			(end -0.7874 -0.4064)
			(stroke
				(width 0.1524)
				(type default)
			)
			(layer "F.SilkS")
		)
		(fp_line
			(start -0.7874 -0.4064)
			(end 0.7874 -0.4064)
			(stroke
				(width 0.1524)
				(type default)
			)
			(layer "F.SilkS")
		)
		(fp_line
			(start 0.67945 0.3048)
			(end 0.120396 0.3048)
			(stroke
				(width 0.1)
				(type default)
			)
			(layer "F.Fab")
		)
		(fp_line
			(start 0.67945 -0.3048)
			(end 0.67945 0.3048)
			(stroke
				(width 0.1)
				(type default)
			)
			(layer "F.Fab")
		)
		(fp_line
			(start 0.12065 -0.2794)
			(end 0.12065 -0.3048)
			(stroke
				(width 0.1)
				(type default)
			)
			(layer "F.Fab")
		)
		(fp_line
			(start 0.12065 -0.3048)
			(end 0.67945 -0.3048)
			(stroke
				(width 0.1)
				(type default)
			)
			(layer "F.Fab")
		)
		(fp_line
			(start 0.120396 0.3048)
			(end 0.120396 0.2794)
			(stroke
				(width 0.1)
				(type default)
			)
			(layer "F.Fab")
		)
		(fp_line
			(start 0.120396 0.2794)
			(end -0.12065 0.2794)
			(stroke
				(width 0.1)
				(type default)
			)
			(layer "F.Fab")
		)
		(fp_line
			(start -0.12065 0.3048)
			(end -0.67945 0.3048)
			(stroke
				(width 0.1)
				(type default)
			)
			(layer "F.Fab")
		)
		(fp_line
			(start -0.12065 0.2794)
			(end -0.12065 0.3048)
			(stroke
				(width 0.1)
				(type default)
			)
			(layer "F.Fab")
		)
		(fp_line
			(start -0.12065 -0.2794)
			(end 0.12065 -0.2794)
			(stroke
				(width 0.1)
				(type default)
			)
			(layer "F.Fab")
		)
		(fp_line
			(start -0.12065 -0.305054)
			(end -0.12065 -0.2794)
			(stroke
				(width 0.1)
				(type default)
			)
			(layer "F.Fab")
		)
		(fp_line
			(start -0.67945 0.3048)
			(end -0.67945 -0.305054)
			(stroke
				(width 0.1)
				(type default)
			)
			(layer "F.Fab")
		)
		(fp_line
			(start -0.67945 -0.305054)
			(end -0.12065 -0.305054)
			(stroke
				(width 0.1)
				(type default)
			)
			(layer "F.Fab")
		)
		(pad "1" smd circle
			(at -0.40005 0 180)
			(size 0 0)
			(layers "F.Cu" "F.Mask" "F.Paste")
			(net "I3C_MB_SDA")
		)
		(pad "2" smd circle
			(at 0.40005 0 180)
			(size 0 0)
			(layers "F.Cu" "F.Mask" "F.Paste")
			(net "SMB_MB_I3C_ISO_SDA")
		)
	)
	(footprint ""
		(layer "F.Cu")
		(at 205.112366 -300.64202 -90)
		(property "Reference" "R3931"
			(at 0 0 270)
			(layer "F.SilkS")
			(hide yes)
			(effects
				(font
					(size 1.27 1.27)
				)
			)
		)
		(property "Value" ""
			(at 0 0 270)
			(layer "F.Fab")
			(effects
				(font
					(size 1.27 1.27)
				)
			)
		)
		(duplicate_pad_numbers_are_jumpers no)
		(fp_line
			(start -0.7874 0.4064)
			(end -0.7874 -0.4064)
			(stroke
				(width 0.1524)
				(type default)
			)
			(layer "F.SilkS")
		)
		(fp_line
			(start 0.7874 0.4064)
			(end -0.7874 0.4064)
			(stroke
				(width 0.1524)
				(type default)
			)
			(layer "F.SilkS")
		)
		(fp_line
			(start -0.7874 -0.4064)
			(end 0.7874 -0.4064)
			(stroke
				(width 0.1524)
				(type default)
			)
			(layer "F.SilkS")
		)
		(fp_line
			(start 0.7874 -0.4064)
			(end 0.7874 0.4064)
			(stroke
				(width 0.1524)
				(type default)
			)
			(layer "F.SilkS")
		)
		(fp_line
			(start -0.67945 0.3048)
			(end -0.67945 -0.305054)
			(stroke
				(width 0.1)
				(type default)
			)
			(layer "F.Fab")
		)
		(fp_line
			(start -0.12065 0.3048)
			(end -0.67945 0.3048)
			(stroke
				(width 0.1)
				(type default)
			)
			(layer "F.Fab")
		)
		(fp_line
			(start 0.120396 0.3048)
			(end 0.120396 0.2794)
			(stroke
				(width 0.1)
				(type default)
			)
			(layer "F.Fab")
		)
		(fp_line
			(start 0.67945 0.3048)
			(end 0.120396 0.3048)
			(stroke
				(width 0.1)
				(type default)
			)
			(layer "F.Fab")
		)
		(fp_line
			(start -0.12065 0.2794)
			(end -0.12065 0.3048)
			(stroke
				(width 0.1)
				(type default)
			)
			(layer "F.Fab")
		)
		(fp_line
			(start 0.120396 0.2794)
			(end -0.12065 0.2794)
			(stroke
				(width 0.1)
				(type default)
			)
			(layer "F.Fab")
		)
		(fp_line
			(start -0.12065 -0.2794)
			(end 0.12065 -0.2794)
			(stroke
				(width 0.1)
				(type default)
			)
			(layer "F.Fab")
		)
		(fp_line
			(start 0.12065 -0.2794)
			(end 0.12065 -0.3048)
			(stroke
				(width 0.1)
				(type default)
			)
			(layer "F.Fab")
		)
		(fp_line
			(start 0.12065 -0.3048)
			(end 0.67945 -0.3048)
			(stroke
				(width 0.1)
				(type default)
			)
			(layer "F.Fab")
		)
		(fp_line
			(start 0.67945 -0.3048)
			(end 0.67945 0.3048)
			(stroke
				(width 0.1)
				(type default)
			)
			(layer "F.Fab")
		)
		(fp_line
			(start -0.67945 -0.305054)
			(end -0.12065 -0.305054)
			(stroke
				(width 0.1)
				(type default)
			)
			(layer "F.Fab")
		)
		(fp_line
			(start -0.12065 -0.305054)
			(end -0.12065 -0.2794)
			(stroke
				(width 0.1)
				(type default)
			)
			(layer "F.Fab")
		)
		(pad "1" smd circle
			(at -0.40005 0 270)
			(size 0 0)
			(layers "F.Cu" "F.Mask" "F.Paste")
			(net "I2C0_PEX1_SHPC_SDA")
		)
		(pad "2" smd circle
			(at 0.40005 0 270)
			(size 0 0)
			(layers "F.Cu" "F.Mask" "F.Paste")
			(net "I2C_PEX1_HOST_SDA")
		)
	)
	(footprint ""
		(layer "F.Cu")
		(at 224.851976 -366.994186)
		(property "Reference" "PR29"
			(at 0 0 0)
			(layer "F.SilkS")
			(hide yes)
			(effects
				(font
					(size 1.27 1.27)
				)
			)
		)
		(property "Value" ""
			(at 0 0 0)
			(layer "F.Fab")
			(effects
				(font
					(size 1.27 1.27)
				)
			)
		)
		(duplicate_pad_numbers_are_jumpers no)
		(fp_line
			(start -0.7874 -0.4064)
			(end 0.7874 -0.4064)
			(stroke
				(width 0.1524)
				(type default)
			)
			(layer "F.SilkS")
		)
		(fp_line
			(start -0.7874 0.4064)
			(end -0.7874 -0.4064)
			(stroke
				(width 0.1524)
				(type default)
			)
			(layer "F.SilkS")
		)
		(fp_line
			(start 0.7874 -0.4064)
			(end 0.7874 0.4064)
			(stroke
				(width 0.1524)
				(type default)
			)
			(layer "F.SilkS")
		)
		(fp_line
			(start 0.7874 0.4064)
			(end -0.7874 0.4064)
			(stroke
				(width 0.1524)
				(type default)
			)
			(layer "F.SilkS")
		)
		(fp_line
			(start -0.67945 -0.305054)
			(end -0.12065 -0.305054)
			(stroke
				(width 0.1)
				(type default)
			)
			(layer "F.Fab")
		)
		(fp_line
			(start -0.67945 0.3048)
			(end -0.67945 -0.305054)
			(stroke
				(width 0.1)
				(type default)
			)
			(layer "F.Fab")
		)
		(fp_line
			(start -0.12065 -0.305054)
			(end -0.12065 -0.2794)
			(stroke
				(width 0.1)
				(type default)
			)
			(layer "F.Fab")
		)
		(fp_line
			(start -0.12065 -0.2794)
			(end 0.12065 -0.2794)
			(stroke
				(width 0.1)
				(type default)
			)
			(layer "F.Fab")
		)
		(fp_line
			(start -0.12065 0.2794)
			(end -0.12065 0.3048)
			(stroke
				(width 0.1)
				(type default)
			)
			(layer "F.Fab")
		)
		(fp_line
			(start -0.12065 0.3048)
			(end -0.67945 0.3048)
			(stroke
				(width 0.1)
				(type default)
			)
			(layer "F.Fab")
		)
		(fp_line
			(start 0.120396 0.2794)
			(end -0.12065 0.2794)
			(stroke
				(width 0.1)
				(type default)
			)
			(layer "F.Fab")
		)
		(fp_line
			(start 0.120396 0.3048)
			(end 0.120396 0.2794)
			(stroke
				(width 0.1)
				(type default)
			)
			(layer "F.Fab")
		)
		(fp_line
			(start 0.12065 -0.3048)
			(end 0.67945 -0.3048)
			(stroke
				(width 0.1)
				(type default)
			)
			(layer "F.Fab")
		)
		(fp_line
			(start 0.12065 -0.2794)
			(end 0.12065 -0.3048)
			(stroke
				(width 0.1)
				(type default)
			)
			(layer "F.Fab")
		)
		(fp_line
			(start 0.67945 -0.3048)
			(end 0.67945 0.3048)
			(stroke
				(width 0.1)
				(type default)
			)
			(layer "F.Fab")
		)
		(fp_line
			(start 0.67945 0.3048)
			(end 0.120396 0.3048)
			(stroke
				(width 0.1)
				(type default)
			)
			(layer "F.Fab")
		)
		(pad "1" smd circle
			(at -0.40005 0)
			(size 0 0)
			(layers "F.Cu" "F.Mask" "F.Paste")
			(net "HSC_D_OC_1")
		)
		(pad "2" smd circle
			(at 0.40005 0)
			(size 0 0)
			(layers "F.Cu" "F.Mask" "F.Paste")
			(net "HSC_D_OC")
		)
	)
	(footprint ""
		(layer "F.Cu")
		(at 397.956532 -20.467574 180)
		(property "Reference" "R1720"
			(at 0 0 180)
			(layer "F.SilkS")
			(hide yes)
			(effects
				(font
					(size 1.27 1.27)
				)
			)
		)
		(property "Value" ""
			(at 0 0 180)
			(layer "F.Fab")
			(effects
				(font
					(size 1.27 1.27)
				)
			)
		)
		(duplicate_pad_numbers_are_jumpers no)
		(fp_line
			(start 0.7874 0.4064)
			(end -0.7874 0.4064)
			(stroke
				(width 0.1524)
				(type default)
			)
			(layer "F.SilkS")
		)
		(fp_line
			(start 0.7874 -0.4064)
			(end 0.7874 0.4064)
			(stroke
				(width 0.1524)
				(type default)
			)
			(layer "F.SilkS")
		)
		(fp_line
			(start -0.7874 0.4064)
			(end -0.7874 -0.4064)
			(stroke
				(width 0.1524)
				(type default)
			)
			(layer "F.SilkS")
		)
		(fp_line
			(start -0.7874 -0.4064)
			(end 0.7874 -0.4064)
			(stroke
				(width 0.1524)
				(type default)
			)
			(layer "F.SilkS")
		)
		(fp_line
			(start 0.67945 0.3048)
			(end 0.120396 0.3048)
			(stroke
				(width 0.1)
				(type default)
			)
			(layer "F.Fab")
		)
		(fp_line
			(start 0.67945 -0.3048)
			(end 0.67945 0.3048)
			(stroke
				(width 0.1)
				(type default)
			)
			(layer "F.Fab")
		)
		(fp_line
			(start 0.12065 -0.2794)
			(end 0.12065 -0.3048)
			(stroke
				(width 0.1)
				(type default)
			)
			(layer "F.Fab")
		)
		(fp_line
			(start 0.12065 -0.3048)
			(end 0.67945 -0.3048)
			(stroke
				(width 0.1)
				(type default)
			)
			(layer "F.Fab")
		)
		(fp_line
			(start 0.120396 0.3048)
			(end 0.120396 0.2794)
			(stroke
				(width 0.1)
				(type default)
			)
			(layer "F.Fab")
		)
		(fp_line
			(start 0.120396 0.2794)
			(end -0.12065 0.2794)
			(stroke
				(width 0.1)
				(type default)
			)
			(layer "F.Fab")
		)
		(fp_line
			(start -0.12065 0.3048)
			(end -0.67945 0.3048)
			(stroke
				(width 0.1)
				(type default)
			)
			(layer "F.Fab")
		)
		(fp_line
			(start -0.12065 0.2794)
			(end -0.12065 0.3048)
			(stroke
				(width 0.1)
				(type default)
			)
			(layer "F.Fab")
		)
		(fp_line
			(start -0.12065 -0.2794)
			(end 0.12065 -0.2794)
			(stroke
				(width 0.1)
				(type default)
			)
			(layer "F.Fab")
		)
		(fp_line
			(start -0.12065 -0.305054)
			(end -0.12065 -0.2794)
			(stroke
				(width 0.1)
				(type default)
			)
			(layer "F.Fab")
		)
		(fp_line
			(start -0.67945 0.3048)
			(end -0.67945 -0.305054)
			(stroke
				(width 0.1)
				(type default)
			)
			(layer "F.Fab")
		)
		(fp_line
			(start -0.67945 -0.305054)
			(end -0.12065 -0.305054)
			(stroke
				(width 0.1)
				(type default)
			)
			(layer "F.Fab")
		)
		(pad "1" smd circle
			(at -0.40005 0 180)
			(size 0 0)
			(layers "F.Cu" "F.Mask" "F.Paste")
			(net "P3V3_SSD13")
		)
		(pad "2" smd circle
			(at 0.40005 0 180)
			(size 0 0)
			(layers "F.Cu" "F.Mask" "F.Paste")
			(net "SMB_ISO_SSD13_SDA")
		)
	)
	(footprint ""
		(layer "F.Cu")
		(at 234.13466 -207.02016 -90)
		(property "Reference" "R5712"
			(at 0 0 270)
			(layer "F.SilkS")
			(hide yes)
			(effects
				(font
					(size 1.27 1.27)
				)
			)
		)
		(property "Value" ""
			(at 0 0 270)
			(layer "F.Fab")
			(effects
				(font
					(size 1.27 1.27)
				)
			)
		)
		(duplicate_pad_numbers_are_jumpers no)
		(fp_line
			(start -0.7874 0.4064)
			(end -0.7874 -0.4064)
			(stroke
				(width 0.1524)
				(type default)
			)
			(layer "F.SilkS")
		)
		(fp_line
			(start 0.7874 0.4064)
			(end -0.7874 0.4064)
			(stroke
				(width 0.1524)
				(type default)
			)
			(layer "F.SilkS")
		)
		(fp_line
			(start -0.7874 -0.4064)
			(end 0.7874 -0.4064)
			(stroke
				(width 0.1524)
				(type default)
			)
			(layer "F.SilkS")
		)
		(fp_line
			(start 0.7874 -0.4064)
			(end 0.7874 0.4064)
			(stroke
				(width 0.1524)
				(type default)
			)
			(layer "F.SilkS")
		)
		(fp_line
			(start -0.67945 0.3048)
			(end -0.67945 -0.305054)
			(stroke
				(width 0.1)
				(type default)
			)
			(layer "F.Fab")
		)
		(fp_line
			(start -0.12065 0.3048)
			(end -0.67945 0.3048)
			(stroke
				(width 0.1)
				(type default)
			)
			(layer "F.Fab")
		)
		(fp_line
			(start 0.120396 0.3048)
			(end 0.120396 0.2794)
			(stroke
				(width 0.1)
				(type default)
			)
			(layer "F.Fab")
		)
		(fp_line
			(start 0.67945 0.3048)
			(end 0.120396 0.3048)
			(stroke
				(width 0.1)
				(type default)
			)
			(layer "F.Fab")
		)
		(fp_line
			(start -0.12065 0.2794)
			(end -0.12065 0.3048)
			(stroke
				(width 0.1)
				(type default)
			)
			(layer "F.Fab")
		)
		(fp_line
			(start 0.120396 0.2794)
			(end -0.12065 0.2794)
			(stroke
				(width 0.1)
				(type default)
			)
			(layer "F.Fab")
		)
		(fp_line
			(start -0.12065 -0.2794)
			(end 0.12065 -0.2794)
			(stroke
				(width 0.1)
				(type default)
			)
			(layer "F.Fab")
		)
		(fp_line
			(start 0.12065 -0.2794)
			(end 0.12065 -0.3048)
			(stroke
				(width 0.1)
				(type default)
			)
			(layer "F.Fab")
		)
		(fp_line
			(start 0.12065 -0.3048)
			(end 0.67945 -0.3048)
			(stroke
				(width 0.1)
				(type default)
			)
			(layer "F.Fab")
		)
		(fp_line
			(start 0.67945 -0.3048)
			(end 0.67945 0.3048)
			(stroke
				(width 0.1)
				(type default)
			)
			(layer "F.Fab")
		)
		(fp_line
			(start -0.67945 -0.305054)
			(end -0.12065 -0.305054)
			(stroke
				(width 0.1)
				(type default)
			)
			(layer "F.Fab")
		)
		(fp_line
			(start -0.12065 -0.305054)
			(end -0.12065 -0.2794)
			(stroke
				(width 0.1)
				(type default)
			)
			(layer "F.Fab")
		)
		(pad "1" smd circle
			(at -0.40005 0 270)
			(size 0 0)
			(layers "F.Cu" "F.Mask" "F.Paste")
			(net "PD_BIC_ENTEST")
		)
		(pad "2" smd circle
			(at 0.40005 0 270)
			(size 0 0)
			(layers "F.Cu" "F.Mask" "F.Paste")
			(net "GND")
		)
	)
	(footprint ""
		(layer "F.Cu")
		(at 461.924908 -308.692296)
		(property "Reference" "PJ15"
			(at 0 0 0)
			(layer "F.SilkS")
			(hide yes)
			(effects
				(font
					(size 1.27 1.27)
				)
			)
		)
		(property "Value" ""
			(at 0 0 0)
			(layer "F.Fab")
			(effects
				(font
					(size 1.27 1.27)
				)
			)
		)
		(duplicate_pad_numbers_are_jumpers no)
		(pad "1" smd circle
			(at -0.40005 0 90)
			(size 0 0)
			(layers "F.Cu" "F.Mask" "F.Paste")
			(net "SH_P1V25_PEX3_FB_P")
		)
		(pad "2" smd rect
			(at 0.40005 0 180)
			(size 0.4572 0.508)
			(layers "F.Cu" "F.Mask" "F.Paste")
			(net "P1V25_PEX3")
		)
		(zone
			(layer "F.Cu")
			(hatch none 0.5)
			(connect_pads
				(clearance 0)
			)
			(min_thickness 0.25)
			(keepout
				(tracks allowed)
				(vias not_allowed)
				(pads allowed)
				(copperpour not_allowed)
				(footprints allowed)
			)
			(placement
				(enabled no)
				(sheetname "")
			)
			(fill
				(thermal_gap 0.5)
				(thermal_bridge_width 0.5)
				(island_removal_mode 0)
			)
			(polygon
				(pts
					(xy 461.239108 -308.387496) (xy 462.610708 -308.387496) (xy 462.610708 -308.997096) (xy 461.239108 -308.997096)
				)
			)
		)
	)
	(footprint ""
		(layer "F.Cu")
		(at 257.170682 -348.674436 180)
		(property "Reference" "R6650"
			(at 0 0 180)
			(layer "F.SilkS")
			(hide yes)
			(effects
				(font
					(size 1.27 1.27)
				)
			)
		)
		(property "Value" ""
			(at 0 0 180)
			(layer "F.Fab")
			(effects
				(font
					(size 1.27 1.27)
				)
			)
		)
		(duplicate_pad_numbers_are_jumpers no)
		(fp_line
			(start 0.7874 0.4064)
			(end -0.7874 0.4064)
			(stroke
				(width 0.1524)
				(type default)
			)
			(layer "F.SilkS")
		)
		(fp_line
			(start 0.7874 -0.4064)
			(end 0.7874 0.4064)
			(stroke
				(width 0.1524)
				(type default)
			)
			(layer "F.SilkS")
		)
		(fp_line
			(start -0.7874 0.4064)
			(end -0.7874 -0.4064)
			(stroke
				(width 0.1524)
				(type default)
			)
			(layer "F.SilkS")
		)
		(fp_line
			(start -0.7874 -0.4064)
			(end 0.7874 -0.4064)
			(stroke
				(width 0.1524)
				(type default)
			)
			(layer "F.SilkS")
		)
		(fp_line
			(start 0.67945 0.3048)
			(end 0.120396 0.3048)
			(stroke
				(width 0.1)
				(type default)
			)
			(layer "F.Fab")
		)
		(fp_line
			(start 0.67945 -0.3048)
			(end 0.67945 0.3048)
			(stroke
				(width 0.1)
				(type default)
			)
			(layer "F.Fab")
		)
		(fp_line
			(start 0.12065 -0.2794)
			(end 0.12065 -0.3048)
			(stroke
				(width 0.1)
				(type default)
			)
			(layer "F.Fab")
		)
		(fp_line
			(start 0.12065 -0.3048)
			(end 0.67945 -0.3048)
			(stroke
				(width 0.1)
				(type default)
			)
			(layer "F.Fab")
		)
		(fp_line
			(start 0.120396 0.3048)
			(end 0.120396 0.2794)
			(stroke
				(width 0.1)
				(type default)
			)
			(layer "F.Fab")
		)
		(fp_line
			(start 0.120396 0.2794)
			(end -0.12065 0.2794)
			(stroke
				(width 0.1)
				(type default)
			)
			(layer "F.Fab")
		)
		(fp_line
			(start -0.12065 0.3048)
			(end -0.67945 0.3048)
			(stroke
				(width 0.1)
				(type default)
			)
			(layer "F.Fab")
		)
		(fp_line
			(start -0.12065 0.2794)
			(end -0.12065 0.3048)
			(stroke
				(width 0.1)
				(type default)
			)
			(layer "F.Fab")
		)
		(fp_line
			(start -0.12065 -0.2794)
			(end 0.12065 -0.2794)
			(stroke
				(width 0.1)
				(type default)
			)
			(layer "F.Fab")
		)
		(fp_line
			(start -0.12065 -0.305054)
			(end -0.12065 -0.2794)
			(stroke
				(width 0.1)
				(type default)
			)
			(layer "F.Fab")
		)
		(fp_line
			(start -0.67945 0.3048)
			(end -0.67945 -0.305054)
			(stroke
				(width 0.1)
				(type default)
			)
			(layer "F.Fab")
		)
		(fp_line
			(start -0.67945 -0.305054)
			(end -0.12065 -0.305054)
			(stroke
				(width 0.1)
				(type default)
			)
			(layer "F.Fab")
		)
		(pad "1" smd circle
			(at -0.40005 0 180)
			(size 0 0)
			(layers "F.Cu" "F.Mask" "F.Paste")
			(net "A_HSC_LOW")
		)
		(pad "2" smd circle
			(at 0.40005 0 180)
			(size 0 0)
			(layers "F.Cu" "F.Mask" "F.Paste")
			(net "GND")
		)
	)
	(footprint ""
		(layer "F.Cu")
		(at 290.908994 -26.03373)
		(property "Reference" "R4072"
			(at 0 0 0)
			(layer "F.SilkS")
			(hide yes)
			(effects
				(font
					(size 1.27 1.27)
				)
			)
		)
		(property "Value" ""
			(at 0 0 0)
			(layer "F.Fab")
			(effects
				(font
					(size 1.27 1.27)
				)
			)
		)
		(duplicate_pad_numbers_are_jumpers no)
		(fp_line
			(start -0.7874 -0.4064)
			(end 0.7874 -0.4064)
			(stroke
				(width 0.1524)
				(type default)
			)
			(layer "F.SilkS")
		)
		(fp_line
			(start -0.7874 0.4064)
			(end -0.7874 -0.4064)
			(stroke
				(width 0.1524)
				(type default)
			)
			(layer "F.SilkS")
		)
		(fp_line
			(start 0.7874 -0.4064)
			(end 0.7874 0.4064)
			(stroke
				(width 0.1524)
				(type default)
			)
			(layer "F.SilkS")
		)
		(fp_line
			(start 0.7874 0.4064)
			(end -0.7874 0.4064)
			(stroke
				(width 0.1524)
				(type default)
			)
			(layer "F.SilkS")
		)
		(fp_line
			(start -0.67945 -0.305054)
			(end -0.12065 -0.305054)
			(stroke
				(width 0.1)
				(type default)
			)
			(layer "F.Fab")
		)
		(fp_line
			(start -0.67945 0.3048)
			(end -0.67945 -0.305054)
			(stroke
				(width 0.1)
				(type default)
			)
			(layer "F.Fab")
		)
		(fp_line
			(start -0.12065 -0.305054)
			(end -0.12065 -0.2794)
			(stroke
				(width 0.1)
				(type default)
			)
			(layer "F.Fab")
		)
		(fp_line
			(start -0.12065 -0.2794)
			(end 0.12065 -0.2794)
			(stroke
				(width 0.1)
				(type default)
			)
			(layer "F.Fab")
		)
		(fp_line
			(start -0.12065 0.2794)
			(end -0.12065 0.3048)
			(stroke
				(width 0.1)
				(type default)
			)
			(layer "F.Fab")
		)
		(fp_line
			(start -0.12065 0.3048)
			(end -0.67945 0.3048)
			(stroke
				(width 0.1)
				(type default)
			)
			(layer "F.Fab")
		)
		(fp_line
			(start 0.120396 0.2794)
			(end -0.12065 0.2794)
			(stroke
				(width 0.1)
				(type default)
			)
			(layer "F.Fab")
		)
		(fp_line
			(start 0.120396 0.3048)
			(end 0.120396 0.2794)
			(stroke
				(width 0.1)
				(type default)
			)
			(layer "F.Fab")
		)
		(fp_line
			(start 0.12065 -0.3048)
			(end 0.67945 -0.3048)
			(stroke
				(width 0.1)
				(type default)
			)
			(layer "F.Fab")
		)
		(fp_line
			(start 0.12065 -0.2794)
			(end 0.12065 -0.3048)
			(stroke
				(width 0.1)
				(type default)
			)
			(layer "F.Fab")
		)
		(fp_line
			(start 0.67945 -0.3048)
			(end 0.67945 0.3048)
			(stroke
				(width 0.1)
				(type default)
			)
			(layer "F.Fab")
		)
		(fp_line
			(start 0.67945 0.3048)
			(end 0.120396 0.3048)
			(stroke
				(width 0.1)
				(type default)
			)
			(layer "F.Fab")
		)
		(pad "1" smd circle
			(at -0.40005 0)
			(size 0 0)
			(layers "F.Cu" "F.Mask" "F.Paste")
			(net "P3V3_AUX")
		)
		(pad "2" smd circle
			(at 0.40005 0)
			(size 0 0)
			(layers "F.Cu" "F.Mask" "F.Paste")
			(net "PRSNT_SSD10_R_N")
		)
	)
	(footprint ""
		(layer "F.Cu")
		(at 95.105728 -244.808248 180)
		(property "Reference" "R814"
			(at 0 0 180)
			(layer "F.SilkS")
			(hide yes)
			(effects
				(font
					(size 1.27 1.27)
				)
			)
		)
		(property "Value" ""
			(at 0 0 180)
			(layer "F.Fab")
			(effects
				(font
					(size 1.27 1.27)
				)
			)
		)
		(duplicate_pad_numbers_are_jumpers no)
		(fp_line
			(start 0.7874 0.4064)
			(end -0.7874 0.4064)
			(stroke
				(width 0.1524)
				(type default)
			)
			(layer "F.SilkS")
		)
		(fp_line
			(start 0.7874 -0.4064)
			(end 0.7874 0.4064)
			(stroke
				(width 0.1524)
				(type default)
			)
			(layer "F.SilkS")
		)
		(fp_line
			(start -0.7874 0.4064)
			(end -0.7874 -0.4064)
			(stroke
				(width 0.1524)
				(type default)
			)
			(layer "F.SilkS")
		)
		(fp_line
			(start -0.7874 -0.4064)
			(end 0.7874 -0.4064)
			(stroke
				(width 0.1524)
				(type default)
			)
			(layer "F.SilkS")
		)
		(fp_line
			(start 0.67945 0.3048)
			(end 0.120396 0.3048)
			(stroke
				(width 0.1)
				(type default)
			)
			(layer "F.Fab")
		)
		(fp_line
			(start 0.67945 -0.3048)
			(end 0.67945 0.3048)
			(stroke
				(width 0.1)
				(type default)
			)
			(layer "F.Fab")
		)
		(fp_line
			(start 0.12065 -0.2794)
			(end 0.12065 -0.3048)
			(stroke
				(width 0.1)
				(type default)
			)
			(layer "F.Fab")
		)
		(fp_line
			(start 0.12065 -0.3048)
			(end 0.67945 -0.3048)
			(stroke
				(width 0.1)
				(type default)
			)
			(layer "F.Fab")
		)
		(fp_line
			(start 0.120396 0.3048)
			(end 0.120396 0.2794)
			(stroke
				(width 0.1)
				(type default)
			)
			(layer "F.Fab")
		)
		(fp_line
			(start 0.120396 0.2794)
			(end -0.12065 0.2794)
			(stroke
				(width 0.1)
				(type default)
			)
			(layer "F.Fab")
		)
		(fp_line
			(start -0.12065 0.3048)
			(end -0.67945 0.3048)
			(stroke
				(width 0.1)
				(type default)
			)
			(layer "F.Fab")
		)
		(fp_line
			(start -0.12065 0.2794)
			(end -0.12065 0.3048)
			(stroke
				(width 0.1)
				(type default)
			)
			(layer "F.Fab")
		)
		(fp_line
			(start -0.12065 -0.2794)
			(end 0.12065 -0.2794)
			(stroke
				(width 0.1)
				(type default)
			)
			(layer "F.Fab")
		)
		(fp_line
			(start -0.12065 -0.305054)
			(end -0.12065 -0.2794)
			(stroke
				(width 0.1)
				(type default)
			)
			(layer "F.Fab")
		)
		(fp_line
			(start -0.67945 0.3048)
			(end -0.67945 -0.305054)
			(stroke
				(width 0.1)
				(type default)
			)
			(layer "F.Fab")
		)
		(fp_line
			(start -0.67945 -0.305054)
			(end -0.12065 -0.305054)
			(stroke
				(width 0.1)
				(type default)
			)
			(layer "F.Fab")
		)
		(pad "1" smd circle
			(at -0.40005 0 180)
			(size 0 0)
			(layers "F.Cu" "F.Mask" "F.Paste")
			(net "PEX_P1V8_ADC_A0")
		)
		(pad "2" smd circle
			(at 0.40005 0 180)
			(size 0 0)
			(layers "F.Cu" "F.Mask" "F.Paste")
			(net "P3V3_AUX")
		)
	)
	(footprint ""
		(layer "F.Cu")
		(at 269.385542 -115.2652 90)
		(property "Reference" "R248"
			(at 0 0 90)
			(layer "F.SilkS")
			(hide yes)
			(effects
				(font
					(size 1.27 1.27)
				)
			)
		)
		(property "Value" ""
			(at 0 0 90)
			(layer "F.Fab")
			(effects
				(font
					(size 1.27 1.27)
				)
			)
		)
		(duplicate_pad_numbers_are_jumpers no)
		(fp_line
			(start 0.7874 -0.4064)
			(end 0.7874 0.4064)
			(stroke
				(width 0.1524)
				(type default)
			)
			(layer "F.SilkS")
		)
		(fp_line
			(start -0.7874 -0.4064)
			(end 0.7874 -0.4064)
			(stroke
				(width 0.1524)
				(type default)
			)
			(layer "F.SilkS")
		)
		(fp_line
			(start 0.7874 0.4064)
			(end -0.7874 0.4064)
			(stroke
				(width 0.1524)
				(type default)
			)
			(layer "F.SilkS")
		)
		(fp_line
			(start -0.7874 0.4064)
			(end -0.7874 -0.4064)
			(stroke
				(width 0.1524)
				(type default)
			)
			(layer "F.SilkS")
		)
		(fp_line
			(start -0.12065 -0.305054)
			(end -0.12065 -0.2794)
			(stroke
				(width 0.1)
				(type default)
			)
			(layer "F.Fab")
		)
		(fp_line
			(start -0.67945 -0.305054)
			(end -0.12065 -0.305054)
			(stroke
				(width 0.1)
				(type default)
			)
			(layer "F.Fab")
		)
		(fp_line
			(start 0.67945 -0.3048)
			(end 0.67945 0.3048)
			(stroke
				(width 0.1)
				(type default)
			)
			(layer "F.Fab")
		)
		(fp_line
			(start 0.12065 -0.3048)
			(end 0.67945 -0.3048)
			(stroke
				(width 0.1)
				(type default)
			)
			(layer "F.Fab")
		)
		(fp_line
			(start 0.12065 -0.2794)
			(end 0.12065 -0.3048)
			(stroke
				(width 0.1)
				(type default)
			)
			(layer "F.Fab")
		)
		(fp_line
			(start -0.12065 -0.2794)
			(end 0.12065 -0.2794)
			(stroke
				(width 0.1)
				(type default)
			)
			(layer "F.Fab")
		)
		(fp_line
			(start 0.120396 0.2794)
			(end -0.12065 0.2794)
			(stroke
				(width 0.1)
				(type default)
			)
			(layer "F.Fab")
		)
		(fp_line
			(start -0.12065 0.2794)
			(end -0.12065 0.3048)
			(stroke
				(width 0.1)
				(type default)
			)
			(layer "F.Fab")
		)
		(fp_line
			(start 0.67945 0.3048)
			(end 0.120396 0.3048)
			(stroke
				(width 0.1)
				(type default)
			)
			(layer "F.Fab")
		)
		(fp_line
			(start 0.120396 0.3048)
			(end 0.120396 0.2794)
			(stroke
				(width 0.1)
				(type default)
			)
			(layer "F.Fab")
		)
		(fp_line
			(start -0.12065 0.3048)
			(end -0.67945 0.3048)
			(stroke
				(width 0.1)
				(type default)
			)
			(layer "F.Fab")
		)
		(fp_line
			(start -0.67945 0.3048)
			(end -0.67945 -0.305054)
			(stroke
				(width 0.1)
				(type default)
			)
			(layer "F.Fab")
		)
		(pad "1" smd circle
			(at -0.40005 0 90)
			(size 0 0)
			(layers "F.Cu" "F.Mask" "F.Paste")
			(net "P3V3_AUX")
		)
		(pad "2" smd circle
			(at 0.40005 0 90)
			(size 0 0)
			(layers "F.Cu" "F.Mask" "F.Paste")
			(net "HP_NIC4_EN")
		)
	)
	(footprint ""
		(layer "F.Cu")
		(at 138.985244 -94.671642 180)
		(property "Reference" "R1571"
			(at 0 0 180)
			(layer "F.SilkS")
			(hide yes)
			(effects
				(font
					(size 1.27 1.27)
				)
			)
		)
		(property "Value" ""
			(at 0 0 180)
			(layer "F.Fab")
			(effects
				(font
					(size 1.27 1.27)
				)
			)
		)
		(duplicate_pad_numbers_are_jumpers no)
		(fp_line
			(start 0.7874 0.4064)
			(end -0.7874 0.4064)
			(stroke
				(width 0.1524)
				(type default)
			)
			(layer "F.SilkS")
		)
		(fp_line
			(start 0.7874 -0.4064)
			(end 0.7874 0.4064)
			(stroke
				(width 0.1524)
				(type default)
			)
			(layer "F.SilkS")
		)
		(fp_line
			(start -0.7874 0.4064)
			(end -0.7874 -0.4064)
			(stroke
				(width 0.1524)
				(type default)
			)
			(layer "F.SilkS")
		)
		(fp_line
			(start -0.7874 -0.4064)
			(end 0.7874 -0.4064)
			(stroke
				(width 0.1524)
				(type default)
			)
			(layer "F.SilkS")
		)
		(fp_line
			(start 0.67945 0.3048)
			(end 0.120396 0.3048)
			(stroke
				(width 0.1)
				(type default)
			)
			(layer "F.Fab")
		)
		(fp_line
			(start 0.67945 -0.3048)
			(end 0.67945 0.3048)
			(stroke
				(width 0.1)
				(type default)
			)
			(layer "F.Fab")
		)
		(fp_line
			(start 0.12065 -0.2794)
			(end 0.12065 -0.3048)
			(stroke
				(width 0.1)
				(type default)
			)
			(layer "F.Fab")
		)
		(fp_line
			(start 0.12065 -0.3048)
			(end 0.67945 -0.3048)
			(stroke
				(width 0.1)
				(type default)
			)
			(layer "F.Fab")
		)
		(fp_line
			(start 0.120396 0.3048)
			(end 0.120396 0.2794)
			(stroke
				(width 0.1)
				(type default)
			)
			(layer "F.Fab")
		)
		(fp_line
			(start 0.120396 0.2794)
			(end -0.12065 0.2794)
			(stroke
				(width 0.1)
				(type default)
			)
			(layer "F.Fab")
		)
		(fp_line
			(start -0.12065 0.3048)
			(end -0.67945 0.3048)
			(stroke
				(width 0.1)
				(type default)
			)
			(layer "F.Fab")
		)
		(fp_line
			(start -0.12065 0.2794)
			(end -0.12065 0.3048)
			(stroke
				(width 0.1)
				(type default)
			)
			(layer "F.Fab")
		)
		(fp_line
			(start -0.12065 -0.2794)
			(end 0.12065 -0.2794)
			(stroke
				(width 0.1)
				(type default)
			)
			(layer "F.Fab")
		)
		(fp_line
			(start -0.12065 -0.305054)
			(end -0.12065 -0.2794)
			(stroke
				(width 0.1)
				(type default)
			)
			(layer "F.Fab")
		)
		(fp_line
			(start -0.67945 0.3048)
			(end -0.67945 -0.305054)
			(stroke
				(width 0.1)
				(type default)
			)
			(layer "F.Fab")
		)
		(fp_line
			(start -0.67945 -0.305054)
			(end -0.12065 -0.305054)
			(stroke
				(width 0.1)
				(type default)
			)
			(layer "F.Fab")
		)
		(pad "1" smd circle
			(at -0.40005 0 180)
			(size 0 0)
			(layers "F.Cu" "F.Mask" "F.Paste")
			(net "P3V3_AUX")
		)
		(pad "2" smd circle
			(at 0.40005 0 180)
			(size 0 0)
			(layers "F.Cu" "F.Mask" "F.Paste")
			(net "SMB_BIC_I2C9_MUX0_SSD7_R_SDA")
		)
	)
	(footprint ""
		(layer "F.Cu")
		(at 31.742888 -343.952322 90)
		(property "Reference" "C2162"
			(at 0 0 90)
			(layer "F.SilkS")
			(hide yes)
			(effects
				(font
					(size 1.27 1.27)
				)
			)
		)
		(property "Value" ""
			(at 0 0 90)
			(layer "F.Fab")
			(effects
				(font
					(size 1.27 1.27)
				)
			)
		)
		(duplicate_pad_numbers_are_jumpers no)
		(fp_line
			(start 0.299974 -0.150114)
			(end 0.299974 0.150114)
			(stroke
				(width 0.1)
				(type default)
			)
			(layer "F.Fab")
		)
		(fp_line
			(start -0.299974 -0.150114)
			(end 0.299974 -0.150114)
			(stroke
				(width 0.1)
				(type default)
			)
			(layer "F.Fab")
		)
		(fp_line
			(start 0.299974 0.150114)
			(end -0.299974 0.150114)
			(stroke
				(width 0.1)
				(type default)
			)
			(layer "F.Fab")
		)
		(fp_line
			(start -0.299974 0.150114)
			(end -0.299974 -0.150114)
			(stroke
				(width 0.1)
				(type default)
			)
			(layer "F.Fab")
		)
		(pad "1" smd rect
			(at -0.2667 0 90)
			(size 0.3048 0.381)
			(layers "F.Cu" "F.Mask" "F.Paste")
			(net "P5E_PEX0_STN4_TX_DP<74>")
		)
		(pad "2" smd rect
			(at 0.2667 0 90)
			(size 0.3048 0.381)
			(layers "F.Cu" "F.Mask" "F.Paste")
			(net "P5E_PEX0_STN4_TX_C_DP<74>")
		)
	)
	(footprint ""
		(layer "F.Cu")
		(at 78.320392 -458.963014)
		(property "Reference" "X8"
			(at -0.1778 -1.92913 0)
			(unlocked yes)
			(layer "F.SilkS")
			(effects
				(font
					(size 0.7874 0.5842)
					(thickness 0.1524)
				)
				(justify left)
			)
		)
		(property "Value" ""
			(at 0 0 0)
			(layer "F.Fab")
			(effects
				(font
					(size 1.27 1.27)
				)
			)
		)
		(property "Device Type" "TP_TDR_4P_FTS_MPKT4_H025P0200_IO_TP15_TP_TDR_4P_DIP"
			(at 1.30175 1.27 90)
			(unlocked yes)
			(layer "F.Fab")
			(hide yes)
			(effects
				(font
					(size 0.635 0.4064)
					(thickness 0.1524)
				)
			)
		)
		(property "User Part Number" "TP15"
			(at 1.30175 1.27 90)
			(unlocked yes)
			(layer "Cmts.User")
			(hide yes)
			(effects
				(font
					(size 0.635 0.4064)
					(thickness 0.1524)
				)
			)
		)
		(duplicate_pad_numbers_are_jumpers no)
		(fp_line
			(start 0 -1.27)
			(end 0 -0.635)
			(stroke
				(width 0.1524)
				(type default)
			)
			(layer "F.SilkS")
		)
		(fp_line
			(start 0 0.635)
			(end 0 1.905)
			(stroke
				(width 0.1524)
				(type default)
			)
			(layer "F.SilkS")
		)
		(fp_line
			(start 0 3.175)
			(end 0 3.81)
			(stroke
				(width 0.1524)
				(type default)
			)
			(layer "F.SilkS")
		)
		(fp_line
			(start 0 3.81)
			(end 2.54 3.81)
			(stroke
				(width 0.1524)
				(type default)
			)
			(layer "F.SilkS")
		)
		(fp_line
			(start 2.54 -1.27)
			(end 0 -1.27)
			(stroke
				(width 0.1524)
				(type default)
			)
			(layer "F.SilkS")
		)
		(fp_line
			(start 2.54 -1.1303)
			(end 2.54 -1.27)
			(stroke
				(width 0.1524)
				(type default)
			)
			(layer "F.SilkS")
		)
		(fp_line
			(start 2.54 1.4097)
			(end 2.54 1.1303)
			(stroke
				(width 0.1524)
				(type default)
			)
			(layer "F.SilkS")
		)
		(fp_line
			(start 2.54 3.81)
			(end 2.54 3.6703)
			(stroke
				(width 0.1524)
				(type default)
			)
			(layer "F.SilkS")
		)
		(fp_poly
			(pts
				(xy -0.761746 0) (xy -2.285746 -0.762) (xy -2.285746 0.762)
			)
			(stroke
				(width 0)
				(type default)
			)
			(fill yes)
			(layer "F.SilkS")
		)
		(fp_line
			(start 0 -1.27)
			(end 0 3.81)
			(stroke
				(width 0.1)
				(type default)
			)
			(layer "F.Fab")
		)
		(fp_line
			(start 0 3.81)
			(end 2.54 3.81)
			(stroke
				(width 0.1)
				(type default)
			)
			(layer "F.Fab")
		)
		(fp_line
			(start 2.54 -1.27)
			(end 0 -1.27)
			(stroke
				(width 0.1)
				(type default)
			)
			(layer "F.Fab")
		)
		(fp_line
			(start 2.54 3.81)
			(end 2.54 -1.27)
			(stroke
				(width 0.1)
				(type default)
			)
			(layer "F.Fab")
		)
		(fp_poly
			(pts
				(xy -0.761746 0) (xy -2.285746 -0.762) (xy -2.285746 0.762)
			)
			(stroke
				(width 0)
				(type default)
			)
			(fill yes)
			(layer "F.Fab")
		)
		(pad "1" thru_hole circle
			(at 0 0)
			(size 1.0033 1.0033)
			(drill 0.249936)
			(layers "*.Cu" "*.Mask")
			(remove_unused_layers no)
			(net "TDR_DIFF_85_IN1_DIP")
			(clearance 0.10795)
			(thermal_gap 0.10795)
			(padstack
				(mode front_inner_back)
				(layer "Inner"
					(shape circle)
					(size 0.8001 0.8001)
					(clearance 0.1524)
				)
				(layer "B.Cu"
					(shape circle)
					(size 1.0033 1.0033)
					(clearance 0.10795)
				)
			)
		)
		(pad "2" thru_hole circle
			(at 2.54 0)
			(size 1.9939 1.9939)
			(drill 0.249936)
			(layers "*.Cu" "*.Mask")
			(remove_unused_layers no)
			(net "COUPON_GND1")
			(clearance 0.10795)
			(thermal_gap 0.10795)
			(padstack
				(mode front_inner_back)
				(layer "Inner"
					(shape circle)
					(size 0.8001 0.8001)
					(clearance 0.1524)
				)
				(layer "B.Cu"
					(shape circle)
					(size 1.9939 1.9939)
					(clearance 0.10795)
				)
			)
		)
		(pad "3" thru_hole circle
			(at 2.54 2.54)
			(size 1.9939 1.9939)
			(drill 0.249936)
			(layers "*.Cu" "*.Mask")
			(remove_unused_layers no)
			(net "COUPON_GND1")
			(clearance 0.10795)
			(thermal_gap 0.10795)
			(padstack
				(mode front_inner_back)
				(layer "Inner"
					(shape circle)
					(size 0.8001 0.8001)
					(clearance 0.1524)
				)
				(layer "B.Cu"
					(shape circle)
					(size 1.9939 1.9939)
					(clearance 0.10795)
				)
			)
		)
		(pad "4" thru_hole circle
			(at 0 2.54)
			(size 1.0033 1.0033)
			(drill 0.249936)
			(layers "*.Cu" "*.Mask")
			(remove_unused_layers no)
			(net "TDR_DIFF_85_IN1_DIN")
			(clearance 0.10795)
			(thermal_gap 0.10795)
			(padstack
				(mode front_inner_back)
				(layer "Inner"
					(shape circle)
					(size 0.8001 0.8001)
					(clearance 0.1524)
				)
				(layer "B.Cu"
					(shape circle)
					(size 1.0033 1.0033)
					(clearance 0.10795)
				)
			)
		)
	)
	(footprint ""
		(layer "F.Cu")
		(at 121.13514 -99.463606)
		(property "Reference" "R1557"
			(at 0 0 0)
			(layer "F.SilkS")
			(hide yes)
			(effects
				(font
					(size 1.27 1.27)
				)
			)
		)
		(property "Value" ""
			(at 0 0 0)
			(layer "F.Fab")
			(effects
				(font
					(size 1.27 1.27)
				)
			)
		)
		(duplicate_pad_numbers_are_jumpers no)
		(fp_line
			(start -0.7874 -0.4064)
			(end 0.7874 -0.4064)
			(stroke
				(width 0.1524)
				(type default)
			)
			(layer "F.SilkS")
		)
		(fp_line
			(start -0.7874 0.4064)
			(end -0.7874 -0.4064)
			(stroke
				(width 0.1524)
				(type default)
			)
			(layer "F.SilkS")
		)
		(fp_line
			(start 0.7874 -0.4064)
			(end 0.7874 0.4064)
			(stroke
				(width 0.1524)
				(type default)
			)
			(layer "F.SilkS")
		)
		(fp_line
			(start 0.7874 0.4064)
			(end -0.7874 0.4064)
			(stroke
				(width 0.1524)
				(type default)
			)
			(layer "F.SilkS")
		)
		(fp_line
			(start -0.67945 -0.305054)
			(end -0.12065 -0.305054)
			(stroke
				(width 0.1)
				(type default)
			)
			(layer "F.Fab")
		)
		(fp_line
			(start -0.67945 0.3048)
			(end -0.67945 -0.305054)
			(stroke
				(width 0.1)
				(type default)
			)
			(layer "F.Fab")
		)
		(fp_line
			(start -0.12065 -0.305054)
			(end -0.12065 -0.2794)
			(stroke
				(width 0.1)
				(type default)
			)
			(layer "F.Fab")
		)
		(fp_line
			(start -0.12065 -0.2794)
			(end 0.12065 -0.2794)
			(stroke
				(width 0.1)
				(type default)
			)
			(layer "F.Fab")
		)
		(fp_line
			(start -0.12065 0.2794)
			(end -0.12065 0.3048)
			(stroke
				(width 0.1)
				(type default)
			)
			(layer "F.Fab")
		)
		(fp_line
			(start -0.12065 0.3048)
			(end -0.67945 0.3048)
			(stroke
				(width 0.1)
				(type default)
			)
			(layer "F.Fab")
		)
		(fp_line
			(start 0.120396 0.2794)
			(end -0.12065 0.2794)
			(stroke
				(width 0.1)
				(type default)
			)
			(layer "F.Fab")
		)
		(fp_line
			(start 0.120396 0.3048)
			(end 0.120396 0.2794)
			(stroke
				(width 0.1)
				(type default)
			)
			(layer "F.Fab")
		)
		(fp_line
			(start 0.12065 -0.3048)
			(end 0.67945 -0.3048)
			(stroke
				(width 0.1)
				(type default)
			)
			(layer "F.Fab")
		)
		(fp_line
			(start 0.12065 -0.2794)
			(end 0.12065 -0.3048)
			(stroke
				(width 0.1)
				(type default)
			)
			(layer "F.Fab")
		)
		(fp_line
			(start 0.67945 -0.3048)
			(end 0.67945 0.3048)
			(stroke
				(width 0.1)
				(type default)
			)
			(layer "F.Fab")
		)
		(fp_line
			(start 0.67945 0.3048)
			(end 0.120396 0.3048)
			(stroke
				(width 0.1)
				(type default)
			)
			(layer "F.Fab")
		)
		(pad "1" smd circle
			(at -0.40005 0)
			(size 0 0)
			(layers "F.Cu" "F.Mask" "F.Paste")
			(net "P3V3_AUX")
		)
		(pad "2" smd circle
			(at 0.40005 0)
			(size 0 0)
			(layers "F.Cu" "F.Mask" "F.Paste")
			(net "BIC_I2C9_SSD_MUX0_A0")
		)
	)
	(footprint ""
		(layer "F.Cu")
		(at 366.638586 -263.121394 -90)
		(property "Reference" "R3067"
			(at 0 0 270)
			(layer "F.SilkS")
			(hide yes)
			(effects
				(font
					(size 1.27 1.27)
				)
			)
		)
		(property "Value" ""
			(at 0 0 270)
			(layer "F.Fab")
			(effects
				(font
					(size 1.27 1.27)
				)
			)
		)
		(duplicate_pad_numbers_are_jumpers no)
		(fp_line
			(start -0.7874 0.4064)
			(end -0.7874 -0.4064)
			(stroke
				(width 0.1524)
				(type default)
			)
			(layer "F.SilkS")
		)
		(fp_line
			(start 0.7874 0.4064)
			(end -0.7874 0.4064)
			(stroke
				(width 0.1524)
				(type default)
			)
			(layer "F.SilkS")
		)
		(fp_line
			(start -0.7874 -0.4064)
			(end 0.7874 -0.4064)
			(stroke
				(width 0.1524)
				(type default)
			)
			(layer "F.SilkS")
		)
		(fp_line
			(start 0.7874 -0.4064)
			(end 0.7874 0.4064)
			(stroke
				(width 0.1524)
				(type default)
			)
			(layer "F.SilkS")
		)
		(fp_line
			(start -0.67945 0.3048)
			(end -0.67945 -0.305054)
			(stroke
				(width 0.1)
				(type default)
			)
			(layer "F.Fab")
		)
		(fp_line
			(start -0.12065 0.3048)
			(end -0.67945 0.3048)
			(stroke
				(width 0.1)
				(type default)
			)
			(layer "F.Fab")
		)
		(fp_line
			(start 0.120396 0.3048)
			(end 0.120396 0.2794)
			(stroke
				(width 0.1)
				(type default)
			)
			(layer "F.Fab")
		)
		(fp_line
			(start 0.67945 0.3048)
			(end 0.120396 0.3048)
			(stroke
				(width 0.1)
				(type default)
			)
			(layer "F.Fab")
		)
		(fp_line
			(start -0.12065 0.2794)
			(end -0.12065 0.3048)
			(stroke
				(width 0.1)
				(type default)
			)
			(layer "F.Fab")
		)
		(fp_line
			(start 0.120396 0.2794)
			(end -0.12065 0.2794)
			(stroke
				(width 0.1)
				(type default)
			)
			(layer "F.Fab")
		)
		(fp_line
			(start -0.12065 -0.2794)
			(end 0.12065 -0.2794)
			(stroke
				(width 0.1)
				(type default)
			)
			(layer "F.Fab")
		)
		(fp_line
			(start 0.12065 -0.2794)
			(end 0.12065 -0.3048)
			(stroke
				(width 0.1)
				(type default)
			)
			(layer "F.Fab")
		)
		(fp_line
			(start 0.12065 -0.3048)
			(end 0.67945 -0.3048)
			(stroke
				(width 0.1)
				(type default)
			)
			(layer "F.Fab")
		)
		(fp_line
			(start 0.67945 -0.3048)
			(end 0.67945 0.3048)
			(stroke
				(width 0.1)
				(type default)
			)
			(layer "F.Fab")
		)
		(fp_line
			(start -0.67945 -0.305054)
			(end -0.12065 -0.305054)
			(stroke
				(width 0.1)
				(type default)
			)
			(layer "F.Fab")
		)
		(fp_line
			(start -0.12065 -0.305054)
			(end -0.12065 -0.2794)
			(stroke
				(width 0.1)
				(type default)
			)
			(layer "F.Fab")
		)
		(pad "1" smd circle
			(at -0.40005 0 270)
			(size 0 0)
			(layers "F.Cu" "F.Mask" "F.Paste")
			(net "PWR_EN_PEX_R")
		)
		(pad "2" smd circle
			(at 0.40005 0 270)
			(size 0 0)
			(layers "F.Cu" "F.Mask" "F.Paste")
			(net "PWR_EN_PEX_BUF")
		)
	)
	(footprint ""
		(layer "F.Cu")
		(at 238.418878 -93.017594 90)
		(property "Reference" "R6843"
			(at 0 0 90)
			(layer "F.SilkS")
			(hide yes)
			(effects
				(font
					(size 1.27 1.27)
				)
			)
		)
		(property "Value" ""
			(at 0 0 90)
			(layer "F.Fab")
			(effects
				(font
					(size 1.27 1.27)
				)
			)
		)
		(duplicate_pad_numbers_are_jumpers no)
		(fp_line
			(start 0.7874 -0.4064)
			(end 0.7874 0.4064)
			(stroke
				(width 0.1524)
				(type default)
			)
			(layer "F.SilkS")
		)
		(fp_line
			(start -0.7874 -0.4064)
			(end 0.7874 -0.4064)
			(stroke
				(width 0.1524)
				(type default)
			)
			(layer "F.SilkS")
		)
		(fp_line
			(start 0.7874 0.4064)
			(end -0.7874 0.4064)
			(stroke
				(width 0.1524)
				(type default)
			)
			(layer "F.SilkS")
		)
		(fp_line
			(start -0.7874 0.4064)
			(end -0.7874 -0.4064)
			(stroke
				(width 0.1524)
				(type default)
			)
			(layer "F.SilkS")
		)
		(fp_line
			(start -0.12065 -0.305054)
			(end -0.12065 -0.2794)
			(stroke
				(width 0.1)
				(type default)
			)
			(layer "F.Fab")
		)
		(fp_line
			(start -0.67945 -0.305054)
			(end -0.12065 -0.305054)
			(stroke
				(width 0.1)
				(type default)
			)
			(layer "F.Fab")
		)
		(fp_line
			(start 0.67945 -0.3048)
			(end 0.67945 0.3048)
			(stroke
				(width 0.1)
				(type default)
			)
			(layer "F.Fab")
		)
		(fp_line
			(start 0.12065 -0.3048)
			(end 0.67945 -0.3048)
			(stroke
				(width 0.1)
				(type default)
			)
			(layer "F.Fab")
		)
		(fp_line
			(start 0.12065 -0.2794)
			(end 0.12065 -0.3048)
			(stroke
				(width 0.1)
				(type default)
			)
			(layer "F.Fab")
		)
		(fp_line
			(start -0.12065 -0.2794)
			(end 0.12065 -0.2794)
			(stroke
				(width 0.1)
				(type default)
			)
			(layer "F.Fab")
		)
		(fp_line
			(start 0.120396 0.2794)
			(end -0.12065 0.2794)
			(stroke
				(width 0.1)
				(type default)
			)
			(layer "F.Fab")
		)
		(fp_line
			(start -0.12065 0.2794)
			(end -0.12065 0.3048)
			(stroke
				(width 0.1)
				(type default)
			)
			(layer "F.Fab")
		)
		(fp_line
			(start 0.67945 0.3048)
			(end 0.120396 0.3048)
			(stroke
				(width 0.1)
				(type default)
			)
			(layer "F.Fab")
		)
		(fp_line
			(start 0.120396 0.3048)
			(end 0.120396 0.2794)
			(stroke
				(width 0.1)
				(type default)
			)
			(layer "F.Fab")
		)
		(fp_line
			(start -0.12065 0.3048)
			(end -0.67945 0.3048)
			(stroke
				(width 0.1)
				(type default)
			)
			(layer "F.Fab")
		)
		(fp_line
			(start -0.67945 0.3048)
			(end -0.67945 -0.305054)
			(stroke
				(width 0.1)
				(type default)
			)
			(layer "F.Fab")
		)
		(pad "1" smd circle
			(at -0.40005 0 90)
			(size 0 0)
			(layers "F.Cu" "F.Mask" "F.Paste")
			(net "PEX_USB_HUB_XOUT")
		)
		(pad "2" smd circle
			(at 0.40005 0 90)
			(size 0 0)
			(layers "F.Cu" "F.Mask" "F.Paste")
			(net "PEX_USB_HUB_XOUT_R")
		)
	)
	(footprint ""
		(layer "F.Cu")
		(at 310.467756 -55.083456)
		(property "Reference" "PC361"
			(at 0 0 0)
			(layer "F.SilkS")
			(hide yes)
			(effects
				(font
					(size 1.27 1.27)
				)
			)
		)
		(property "Value" ""
			(at 0 0 0)
			(layer "F.Fab")
			(effects
				(font
					(size 1.27 1.27)
				)
			)
		)
		(duplicate_pad_numbers_are_jumpers no)
		(fp_line
			(start -0.7874 -0.4064)
			(end 0.7874 -0.4064)
			(stroke
				(width 0.1524)
				(type default)
			)
			(layer "F.SilkS")
		)
		(fp_line
			(start -0.7874 0.4064)
			(end -0.7874 -0.4064)
			(stroke
				(width 0.1524)
				(type default)
			)
			(layer "F.SilkS")
		)
		(fp_line
			(start 0.7874 -0.4064)
			(end 0.7874 0.4064)
			(stroke
				(width 0.1524)
				(type default)
			)
			(layer "F.SilkS")
		)
		(fp_line
			(start 0.7874 0.4064)
			(end -0.7874 0.4064)
			(stroke
				(width 0.1524)
				(type default)
			)
			(layer "F.SilkS")
		)
		(fp_line
			(start -0.67945 -0.305054)
			(end -0.12065 -0.305054)
			(stroke
				(width 0.1)
				(type default)
			)
			(layer "F.Fab")
		)
		(fp_line
			(start -0.67945 0.3048)
			(end -0.67945 -0.305054)
			(stroke
				(width 0.1)
				(type default)
			)
			(layer "F.Fab")
		)
		(fp_line
			(start -0.12065 -0.305054)
			(end -0.12065 -0.2794)
			(stroke
				(width 0.1)
				(type default)
			)
			(layer "F.Fab")
		)
		(fp_line
			(start -0.12065 -0.2794)
			(end 0.12065 -0.2794)
			(stroke
				(width 0.1)
				(type default)
			)
			(layer "F.Fab")
		)
		(fp_line
			(start -0.12065 0.2794)
			(end -0.12065 0.3048)
			(stroke
				(width 0.1)
				(type default)
			)
			(layer "F.Fab")
		)
		(fp_line
			(start -0.12065 0.3048)
			(end -0.67945 0.3048)
			(stroke
				(width 0.1)
				(type default)
			)
			(layer "F.Fab")
		)
		(fp_line
			(start 0.120396 0.2794)
			(end -0.12065 0.2794)
			(stroke
				(width 0.1)
				(type default)
			)
			(layer "F.Fab")
		)
		(fp_line
			(start 0.120396 0.3048)
			(end 0.120396 0.2794)
			(stroke
				(width 0.1)
				(type default)
			)
			(layer "F.Fab")
		)
		(fp_line
			(start 0.12065 -0.3048)
			(end 0.67945 -0.3048)
			(stroke
				(width 0.1)
				(type default)
			)
			(layer "F.Fab")
		)
		(fp_line
			(start 0.12065 -0.2794)
			(end 0.12065 -0.3048)
			(stroke
				(width 0.1)
				(type default)
			)
			(layer "F.Fab")
		)
		(fp_line
			(start 0.67945 -0.3048)
			(end 0.67945 0.3048)
			(stroke
				(width 0.1)
				(type default)
			)
			(layer "F.Fab")
		)
		(fp_line
			(start 0.67945 0.3048)
			(end 0.120396 0.3048)
			(stroke
				(width 0.1)
				(type default)
			)
			(layer "F.Fab")
		)
		(pad "1" smd circle
			(at -0.40005 0)
			(size 0 0)
			(layers "F.Cu" "F.Mask" "F.Paste")
			(net "P5V_AUX")
		)
		(pad "2" smd circle
			(at 0.40005 0)
			(size 0 0)
			(layers "F.Cu" "F.Mask" "F.Paste")
			(net "GND")
		)
	)
	(footprint ""
		(layer "F.Cu")
		(at 219.202 -204.216 180)
		(property "Reference" "C2625"
			(at 0 0 180)
			(layer "F.SilkS")
			(hide yes)
			(effects
				(font
					(size 1.27 1.27)
				)
			)
		)
		(property "Value" ""
			(at 0 0 180)
			(layer "F.Fab")
			(effects
				(font
					(size 1.27 1.27)
				)
			)
		)
		(duplicate_pad_numbers_are_jumpers no)
		(fp_line
			(start 0.7874 0.4064)
			(end -0.7874 0.4064)
			(stroke
				(width 0.1524)
				(type default)
			)
			(layer "F.SilkS")
		)
		(fp_line
			(start 0.7874 -0.4064)
			(end 0.7874 0.4064)
			(stroke
				(width 0.1524)
				(type default)
			)
			(layer "F.SilkS")
		)
		(fp_line
			(start -0.7874 0.4064)
			(end -0.7874 -0.4064)
			(stroke
				(width 0.1524)
				(type default)
			)
			(layer "F.SilkS")
		)
		(fp_line
			(start -0.7874 -0.4064)
			(end 0.7874 -0.4064)
			(stroke
				(width 0.1524)
				(type default)
			)
			(layer "F.SilkS")
		)
		(fp_line
			(start 0.67945 0.3048)
			(end 0.120396 0.3048)
			(stroke
				(width 0.1)
				(type default)
			)
			(layer "F.Fab")
		)
		(fp_line
			(start 0.67945 -0.3048)
			(end 0.67945 0.3048)
			(stroke
				(width 0.1)
				(type default)
			)
			(layer "F.Fab")
		)
		(fp_line
			(start 0.12065 -0.2794)
			(end 0.12065 -0.3048)
			(stroke
				(width 0.1)
				(type default)
			)
			(layer "F.Fab")
		)
		(fp_line
			(start 0.12065 -0.3048)
			(end 0.67945 -0.3048)
			(stroke
				(width 0.1)
				(type default)
			)
			(layer "F.Fab")
		)
		(fp_line
			(start 0.120396 0.3048)
			(end 0.120396 0.2794)
			(stroke
				(width 0.1)
				(type default)
			)
			(layer "F.Fab")
		)
		(fp_line
			(start 0.120396 0.2794)
			(end -0.12065 0.2794)
			(stroke
				(width 0.1)
				(type default)
			)
			(layer "F.Fab")
		)
		(fp_line
			(start -0.12065 0.3048)
			(end -0.67945 0.3048)
			(stroke
				(width 0.1)
				(type default)
			)
			(layer "F.Fab")
		)
		(fp_line
			(start -0.12065 0.2794)
			(end -0.12065 0.3048)
			(stroke
				(width 0.1)
				(type default)
			)
			(layer "F.Fab")
		)
		(fp_line
			(start -0.12065 -0.2794)
			(end 0.12065 -0.2794)
			(stroke
				(width 0.1)
				(type default)
			)
			(layer "F.Fab")
		)
		(fp_line
			(start -0.12065 -0.305054)
			(end -0.12065 -0.2794)
			(stroke
				(width 0.1)
				(type default)
			)
			(layer "F.Fab")
		)
		(fp_line
			(start -0.67945 0.3048)
			(end -0.67945 -0.305054)
			(stroke
				(width 0.1)
				(type default)
			)
			(layer "F.Fab")
		)
		(fp_line
			(start -0.67945 -0.305054)
			(end -0.12065 -0.305054)
			(stroke
				(width 0.1)
				(type default)
			)
			(layer "F.Fab")
		)
		(pad "1" smd circle
			(at -0.40005 0 180)
			(size 0 0)
			(layers "F.Cu" "F.Mask" "F.Paste")
			(net "GND")
		)
		(pad "2" smd circle
			(at 0.40005 0 180)
			(size 0 0)
			(layers "F.Cu" "F.Mask" "F.Paste")
			(net "P3V3_NIC5")
		)
	)
	(footprint ""
		(layer "F.Cu")
		(at 208.185766 -227.10902 90)
		(property "Reference" "R5474"
			(at 0 0 90)
			(layer "F.SilkS")
			(hide yes)
			(effects
				(font
					(size 1.27 1.27)
				)
			)
		)
		(property "Value" ""
			(at 0 0 90)
			(layer "F.Fab")
			(effects
				(font
					(size 1.27 1.27)
				)
			)
		)
		(duplicate_pad_numbers_are_jumpers no)
		(fp_line
			(start 0.7874 -0.4064)
			(end 0.7874 0.4064)
			(stroke
				(width 0.1524)
				(type default)
			)
			(layer "F.SilkS")
		)
		(fp_line
			(start -0.7874 -0.4064)
			(end 0.7874 -0.4064)
			(stroke
				(width 0.1524)
				(type default)
			)
			(layer "F.SilkS")
		)
		(fp_line
			(start 0.7874 0.4064)
			(end -0.7874 0.4064)
			(stroke
				(width 0.1524)
				(type default)
			)
			(layer "F.SilkS")
		)
		(fp_line
			(start -0.7874 0.4064)
			(end -0.7874 -0.4064)
			(stroke
				(width 0.1524)
				(type default)
			)
			(layer "F.SilkS")
		)
		(fp_line
			(start -0.12065 -0.305054)
			(end -0.12065 -0.2794)
			(stroke
				(width 0.1)
				(type default)
			)
			(layer "F.Fab")
		)
		(fp_line
			(start -0.67945 -0.305054)
			(end -0.12065 -0.305054)
			(stroke
				(width 0.1)
				(type default)
			)
			(layer "F.Fab")
		)
		(fp_line
			(start 0.67945 -0.3048)
			(end 0.67945 0.3048)
			(stroke
				(width 0.1)
				(type default)
			)
			(layer "F.Fab")
		)
		(fp_line
			(start 0.12065 -0.3048)
			(end 0.67945 -0.3048)
			(stroke
				(width 0.1)
				(type default)
			)
			(layer "F.Fab")
		)
		(fp_line
			(start 0.12065 -0.2794)
			(end 0.12065 -0.3048)
			(stroke
				(width 0.1)
				(type default)
			)
			(layer "F.Fab")
		)
		(fp_line
			(start -0.12065 -0.2794)
			(end 0.12065 -0.2794)
			(stroke
				(width 0.1)
				(type default)
			)
			(layer "F.Fab")
		)
		(fp_line
			(start 0.120396 0.2794)
			(end -0.12065 0.2794)
			(stroke
				(width 0.1)
				(type default)
			)
			(layer "F.Fab")
		)
		(fp_line
			(start -0.12065 0.2794)
			(end -0.12065 0.3048)
			(stroke
				(width 0.1)
				(type default)
			)
			(layer "F.Fab")
		)
		(fp_line
			(start 0.67945 0.3048)
			(end 0.120396 0.3048)
			(stroke
				(width 0.1)
				(type default)
			)
			(layer "F.Fab")
		)
		(fp_line
			(start 0.120396 0.3048)
			(end 0.120396 0.2794)
			(stroke
				(width 0.1)
				(type default)
			)
			(layer "F.Fab")
		)
		(fp_line
			(start -0.12065 0.3048)
			(end -0.67945 0.3048)
			(stroke
				(width 0.1)
				(type default)
			)
			(layer "F.Fab")
		)
		(fp_line
			(start -0.67945 0.3048)
			(end -0.67945 -0.305054)
			(stroke
				(width 0.1)
				(type default)
			)
			(layer "F.Fab")
		)
		(pad "1" smd circle
			(at -0.40005 0 90)
			(size 0 0)
			(layers "F.Cu" "F.Mask" "F.Paste")
			(net "BUF_UART_MB_BIC_RX_EN")
		)
		(pad "2" smd circle
			(at 0.40005 0 90)
			(size 0 0)
			(layers "F.Cu" "F.Mask" "F.Paste")
			(net "P3V3_AUX")
		)
	)
	(footprint ""
		(layer "F.Cu")
		(at 107.051094 -397.512286 -90)
		(property "Reference" "R6181"
			(at 0 0 270)
			(layer "F.SilkS")
			(hide yes)
			(effects
				(font
					(size 1.27 1.27)
				)
			)
		)
		(property "Value" ""
			(at 0 0 270)
			(layer "F.Fab")
			(effects
				(font
					(size 1.27 1.27)
				)
			)
		)
		(duplicate_pad_numbers_are_jumpers no)
		(fp_line
			(start -0.7874 0.4064)
			(end -0.7874 -0.4064)
			(stroke
				(width 0.1524)
				(type default)
			)
			(layer "F.SilkS")
		)
		(fp_line
			(start 0.7874 0.4064)
			(end -0.7874 0.4064)
			(stroke
				(width 0.1524)
				(type default)
			)
			(layer "F.SilkS")
		)
		(fp_line
			(start -0.7874 -0.4064)
			(end 0.7874 -0.4064)
			(stroke
				(width 0.1524)
				(type default)
			)
			(layer "F.SilkS")
		)
		(fp_line
			(start 0.7874 -0.4064)
			(end 0.7874 0.4064)
			(stroke
				(width 0.1524)
				(type default)
			)
			(layer "F.SilkS")
		)
		(fp_line
			(start -0.67945 0.3048)
			(end -0.67945 -0.305054)
			(stroke
				(width 0.1)
				(type default)
			)
			(layer "F.Fab")
		)
		(fp_line
			(start -0.12065 0.3048)
			(end -0.67945 0.3048)
			(stroke
				(width 0.1)
				(type default)
			)
			(layer "F.Fab")
		)
		(fp_line
			(start 0.120396 0.3048)
			(end 0.120396 0.2794)
			(stroke
				(width 0.1)
				(type default)
			)
			(layer "F.Fab")
		)
		(fp_line
			(start 0.67945 0.3048)
			(end 0.120396 0.3048)
			(stroke
				(width 0.1)
				(type default)
			)
			(layer "F.Fab")
		)
		(fp_line
			(start -0.12065 0.2794)
			(end -0.12065 0.3048)
			(stroke
				(width 0.1)
				(type default)
			)
			(layer "F.Fab")
		)
		(fp_line
			(start 0.120396 0.2794)
			(end -0.12065 0.2794)
			(stroke
				(width 0.1)
				(type default)
			)
			(layer "F.Fab")
		)
		(fp_line
			(start -0.12065 -0.2794)
			(end 0.12065 -0.2794)
			(stroke
				(width 0.1)
				(type default)
			)
			(layer "F.Fab")
		)
		(fp_line
			(start 0.12065 -0.2794)
			(end 0.12065 -0.3048)
			(stroke
				(width 0.1)
				(type default)
			)
			(layer "F.Fab")
		)
		(fp_line
			(start 0.12065 -0.3048)
			(end 0.67945 -0.3048)
			(stroke
				(width 0.1)
				(type default)
			)
			(layer "F.Fab")
		)
		(fp_line
			(start 0.67945 -0.3048)
			(end 0.67945 0.3048)
			(stroke
				(width 0.1)
				(type default)
			)
			(layer "F.Fab")
		)
		(fp_line
			(start -0.67945 -0.305054)
			(end -0.12065 -0.305054)
			(stroke
				(width 0.1)
				(type default)
			)
			(layer "F.Fab")
		)
		(fp_line
			(start -0.12065 -0.305054)
			(end -0.12065 -0.2794)
			(stroke
				(width 0.1)
				(type default)
			)
			(layer "F.Fab")
		)
		(pad "1" smd circle
			(at -0.40005 0 270)
			(size 0 0)
			(layers "F.Cu" "F.Mask" "F.Paste")
			(net "RST_BIC_USB_HUB_R_N")
		)
		(pad "2" smd circle
			(at 0.40005 0 270)
			(size 0 0)
			(layers "F.Cu" "F.Mask" "F.Paste")
			(net "RST_BIC_USB_HUB_R1_N")
		)
	)
	(footprint ""
		(layer "F.Cu")
		(at 381.254 -198.374)
		(property "Reference" "R4696"
			(at 0 0 0)
			(layer "F.SilkS")
			(hide yes)
			(effects
				(font
					(size 1.27 1.27)
				)
			)
		)
		(property "Value" ""
			(at 0 0 0)
			(layer "F.Fab")
			(effects
				(font
					(size 1.27 1.27)
				)
			)
		)
		(duplicate_pad_numbers_are_jumpers no)
		(fp_line
			(start -0.7874 -0.4064)
			(end 0.7874 -0.4064)
			(stroke
				(width 0.1524)
				(type default)
			)
			(layer "F.SilkS")
		)
		(fp_line
			(start -0.7874 0.4064)
			(end -0.7874 -0.4064)
			(stroke
				(width 0.1524)
				(type default)
			)
			(layer "F.SilkS")
		)
		(fp_line
			(start 0.7874 -0.4064)
			(end 0.7874 0.4064)
			(stroke
				(width 0.1524)
				(type default)
			)
			(layer "F.SilkS")
		)
		(fp_line
			(start 0.7874 0.4064)
			(end -0.7874 0.4064)
			(stroke
				(width 0.1524)
				(type default)
			)
			(layer "F.SilkS")
		)
		(fp_line
			(start -0.67945 -0.305054)
			(end -0.12065 -0.305054)
			(stroke
				(width 0.1)
				(type default)
			)
			(layer "F.Fab")
		)
		(fp_line
			(start -0.67945 0.3048)
			(end -0.67945 -0.305054)
			(stroke
				(width 0.1)
				(type default)
			)
			(layer "F.Fab")
		)
		(fp_line
			(start -0.12065 -0.305054)
			(end -0.12065 -0.2794)
			(stroke
				(width 0.1)
				(type default)
			)
			(layer "F.Fab")
		)
		(fp_line
			(start -0.12065 -0.2794)
			(end 0.12065 -0.2794)
			(stroke
				(width 0.1)
				(type default)
			)
			(layer "F.Fab")
		)
		(fp_line
			(start -0.12065 0.2794)
			(end -0.12065 0.3048)
			(stroke
				(width 0.1)
				(type default)
			)
			(layer "F.Fab")
		)
		(fp_line
			(start -0.12065 0.3048)
			(end -0.67945 0.3048)
			(stroke
				(width 0.1)
				(type default)
			)
			(layer "F.Fab")
		)
		(fp_line
			(start 0.120396 0.2794)
			(end -0.12065 0.2794)
			(stroke
				(width 0.1)
				(type default)
			)
			(layer "F.Fab")
		)
		(fp_line
			(start 0.120396 0.3048)
			(end 0.120396 0.2794)
			(stroke
				(width 0.1)
				(type default)
			)
			(layer "F.Fab")
		)
		(fp_line
			(start 0.12065 -0.3048)
			(end 0.67945 -0.3048)
			(stroke
				(width 0.1)
				(type default)
			)
			(layer "F.Fab")
		)
		(fp_line
			(start 0.12065 -0.2794)
			(end 0.12065 -0.3048)
			(stroke
				(width 0.1)
				(type default)
			)
			(layer "F.Fab")
		)
		(fp_line
			(start 0.67945 -0.3048)
			(end 0.67945 0.3048)
			(stroke
				(width 0.1)
				(type default)
			)
			(layer "F.Fab")
		)
		(fp_line
			(start 0.67945 0.3048)
			(end 0.120396 0.3048)
			(stroke
				(width 0.1)
				(type default)
			)
			(layer "F.Fab")
		)
		(pad "1" smd circle
			(at -0.40005 0)
			(size 0 0)
			(layers "F.Cu" "F.Mask" "F.Paste")
			(net "RST_PEX_NIC2_PERST_N")
		)
		(pad "2" smd circle
			(at 0.40005 0)
			(size 0 0)
			(layers "F.Cu" "F.Mask" "F.Paste")
			(net "RST_PEX_NIC2_PERST_R_N")
		)
	)
	(footprint ""
		(layer "F.Cu")
		(at 96.131888 -201.109326 90)
		(property "Reference" "R6622"
			(at 0 0 90)
			(layer "F.SilkS")
			(hide yes)
			(effects
				(font
					(size 1.27 1.27)
				)
			)
		)
		(property "Value" ""
			(at 0 0 90)
			(layer "F.Fab")
			(effects
				(font
					(size 1.27 1.27)
				)
			)
		)
		(duplicate_pad_numbers_are_jumpers no)
		(fp_line
			(start 0.7874 -0.4064)
			(end 0.7874 0.4064)
			(stroke
				(width 0.1524)
				(type default)
			)
			(layer "F.SilkS")
		)
		(fp_line
			(start -0.7874 -0.4064)
			(end 0.7874 -0.4064)
			(stroke
				(width 0.1524)
				(type default)
			)
			(layer "F.SilkS")
		)
		(fp_line
			(start 0.7874 0.4064)
			(end -0.7874 0.4064)
			(stroke
				(width 0.1524)
				(type default)
			)
			(layer "F.SilkS")
		)
		(fp_line
			(start -0.7874 0.4064)
			(end -0.7874 -0.4064)
			(stroke
				(width 0.1524)
				(type default)
			)
			(layer "F.SilkS")
		)
		(fp_line
			(start -0.12065 -0.305054)
			(end -0.12065 -0.2794)
			(stroke
				(width 0.1)
				(type default)
			)
			(layer "F.Fab")
		)
		(fp_line
			(start -0.67945 -0.305054)
			(end -0.12065 -0.305054)
			(stroke
				(width 0.1)
				(type default)
			)
			(layer "F.Fab")
		)
		(fp_line
			(start 0.67945 -0.3048)
			(end 0.67945 0.3048)
			(stroke
				(width 0.1)
				(type default)
			)
			(layer "F.Fab")
		)
		(fp_line
			(start 0.12065 -0.3048)
			(end 0.67945 -0.3048)
			(stroke
				(width 0.1)
				(type default)
			)
			(layer "F.Fab")
		)
		(fp_line
			(start 0.12065 -0.2794)
			(end 0.12065 -0.3048)
			(stroke
				(width 0.1)
				(type default)
			)
			(layer "F.Fab")
		)
		(fp_line
			(start -0.12065 -0.2794)
			(end 0.12065 -0.2794)
			(stroke
				(width 0.1)
				(type default)
			)
			(layer "F.Fab")
		)
		(fp_line
			(start 0.120396 0.2794)
			(end -0.12065 0.2794)
			(stroke
				(width 0.1)
				(type default)
			)
			(layer "F.Fab")
		)
		(fp_line
			(start -0.12065 0.2794)
			(end -0.12065 0.3048)
			(stroke
				(width 0.1)
				(type default)
			)
			(layer "F.Fab")
		)
		(fp_line
			(start 0.67945 0.3048)
			(end 0.120396 0.3048)
			(stroke
				(width 0.1)
				(type default)
			)
			(layer "F.Fab")
		)
		(fp_line
			(start 0.120396 0.3048)
			(end 0.120396 0.2794)
			(stroke
				(width 0.1)
				(type default)
			)
			(layer "F.Fab")
		)
		(fp_line
			(start -0.12065 0.3048)
			(end -0.67945 0.3048)
			(stroke
				(width 0.1)
				(type default)
			)
			(layer "F.Fab")
		)
		(fp_line
			(start -0.67945 0.3048)
			(end -0.67945 -0.305054)
			(stroke
				(width 0.1)
				(type default)
			)
			(layer "F.Fab")
		)
		(pad "1" smd circle
			(at -0.40005 0 90)
			(size 0 0)
			(layers "F.Cu" "F.Mask" "F.Paste")
			(net "RST_CP2108_CLI_R_N")
		)
		(pad "2" smd circle
			(at 0.40005 0 90)
			(size 0 0)
			(layers "F.Cu" "F.Mask" "F.Paste")
			(net "RST_FT4232_R_N")
		)
	)
	(footprint ""
		(layer "F.Cu")
		(at 265.51509 -20.72513)
		(property "Reference" "H112"
			(at 1.628394 -2.603754 0)
			(unlocked yes)
			(layer "B.SilkS")
			(effects
				(font
					(size 0.7874 0.5842)
					(thickness 0.1524)
				)
				(justify left mirror)
			)
		)
		(property "Value" ""
			(at 0 0 0)
			(layer "F.Fab")
			(effects
				(font
					(size 1.27 1.27)
				)
			)
		)
		(duplicate_pad_numbers_are_jumpers no)
		(pad "1" thru_hole rect
			(at 0 0)
			(size 4.2164 5.0038)
			(drill 2.0066
				(offset 0.099822 0)
			)
			(layers "*.Cu" "*.Mask")
			(remove_unused_layers no)
			(net "Net_8551")
			(clearance -0.8509)
			(padstack
				(mode front_inner_back)
				(layer "Inner"
					(shape circle)
					(size 4.0132 4.0132)
					(clearance -0.7493)
				)
				(layer "B.Cu"
					(shape circle)
					(size 4.0132 4.0132)
					(clearance -0.7493)
				)
			)
		)
	)
	(footprint ""
		(layer "F.Cu")
		(at 227.678234 -273.05762 90)
		(property "Reference" "C4280"
			(at 0 0 90)
			(layer "F.SilkS")
			(hide yes)
			(effects
				(font
					(size 1.27 1.27)
				)
			)
		)
		(property "Value" ""
			(at 0 0 90)
			(layer "F.Fab")
			(effects
				(font
					(size 1.27 1.27)
				)
			)
		)
		(duplicate_pad_numbers_are_jumpers no)
		(fp_line
			(start 0.299974 -0.150114)
			(end 0.299974 0.150114)
			(stroke
				(width 0.1)
				(type default)
			)
			(layer "F.Fab")
		)
		(fp_line
			(start -0.299974 -0.150114)
			(end 0.299974 -0.150114)
			(stroke
				(width 0.1)
				(type default)
			)
			(layer "F.Fab")
		)
		(fp_line
			(start 0.299974 0.150114)
			(end -0.299974 0.150114)
			(stroke
				(width 0.1)
				(type default)
			)
			(layer "F.Fab")
		)
		(fp_line
			(start -0.299974 0.150114)
			(end -0.299974 -0.150114)
			(stroke
				(width 0.1)
				(type default)
			)
			(layer "F.Fab")
		)
		(pad "1" smd rect
			(at -0.2667 0 90)
			(size 0.3048 0.381)
			(layers "F.Cu" "F.Mask" "F.Paste")
			(net "P1V25_SERDES_VDDPLL_PEX1")
		)
		(pad "2" smd rect
			(at 0.2667 0 90)
			(size 0.3048 0.381)
			(layers "F.Cu" "F.Mask" "F.Paste")
			(net "GND")
		)
	)
	(footprint ""
		(layer "F.Cu")
		(at 93.087444 -96.811592 90)
		(property "Reference" "R699"
			(at 0 0 90)
			(layer "F.SilkS")
			(hide yes)
			(effects
				(font
					(size 1.27 1.27)
				)
			)
		)
		(property "Value" ""
			(at 0 0 90)
			(layer "F.Fab")
			(effects
				(font
					(size 1.27 1.27)
				)
			)
		)
		(duplicate_pad_numbers_are_jumpers no)
		(fp_line
			(start 0.7874 -0.4064)
			(end 0.7874 0.4064)
			(stroke
				(width 0.1524)
				(type default)
			)
			(layer "F.SilkS")
		)
		(fp_line
			(start -0.7874 -0.4064)
			(end 0.7874 -0.4064)
			(stroke
				(width 0.1524)
				(type default)
			)
			(layer "F.SilkS")
		)
		(fp_line
			(start 0.7874 0.4064)
			(end -0.7874 0.4064)
			(stroke
				(width 0.1524)
				(type default)
			)
			(layer "F.SilkS")
		)
		(fp_line
			(start -0.7874 0.4064)
			(end -0.7874 -0.4064)
			(stroke
				(width 0.1524)
				(type default)
			)
			(layer "F.SilkS")
		)
		(fp_line
			(start -0.12065 -0.305054)
			(end -0.12065 -0.2794)
			(stroke
				(width 0.1)
				(type default)
			)
			(layer "F.Fab")
		)
		(fp_line
			(start -0.67945 -0.305054)
			(end -0.12065 -0.305054)
			(stroke
				(width 0.1)
				(type default)
			)
			(layer "F.Fab")
		)
		(fp_line
			(start 0.67945 -0.3048)
			(end 0.67945 0.3048)
			(stroke
				(width 0.1)
				(type default)
			)
			(layer "F.Fab")
		)
		(fp_line
			(start 0.12065 -0.3048)
			(end 0.67945 -0.3048)
			(stroke
				(width 0.1)
				(type default)
			)
			(layer "F.Fab")
		)
		(fp_line
			(start 0.12065 -0.2794)
			(end 0.12065 -0.3048)
			(stroke
				(width 0.1)
				(type default)
			)
			(layer "F.Fab")
		)
		(fp_line
			(start -0.12065 -0.2794)
			(end 0.12065 -0.2794)
			(stroke
				(width 0.1)
				(type default)
			)
			(layer "F.Fab")
		)
		(fp_line
			(start 0.120396 0.2794)
			(end -0.12065 0.2794)
			(stroke
				(width 0.1)
				(type default)
			)
			(layer "F.Fab")
		)
		(fp_line
			(start -0.12065 0.2794)
			(end -0.12065 0.3048)
			(stroke
				(width 0.1)
				(type default)
			)
			(layer "F.Fab")
		)
		(fp_line
			(start 0.67945 0.3048)
			(end 0.120396 0.3048)
			(stroke
				(width 0.1)
				(type default)
			)
			(layer "F.Fab")
		)
		(fp_line
			(start 0.120396 0.3048)
			(end 0.120396 0.2794)
			(stroke
				(width 0.1)
				(type default)
			)
			(layer "F.Fab")
		)
		(fp_line
			(start -0.12065 0.3048)
			(end -0.67945 0.3048)
			(stroke
				(width 0.1)
				(type default)
			)
			(layer "F.Fab")
		)
		(fp_line
			(start -0.67945 0.3048)
			(end -0.67945 -0.305054)
			(stroke
				(width 0.1)
				(type default)
			)
			(layer "F.Fab")
		)
		(pad "1" smd circle
			(at -0.40005 0 90)
			(size 0 0)
			(layers "F.Cu" "F.Mask" "F.Paste")
			(net "SMB_BIC_I2C6_MUX_NIC_ADC_R_SDA")
		)
		(pad "2" smd circle
			(at 0.40005 0 90)
			(size 0 0)
			(layers "F.Cu" "F.Mask" "F.Paste")
			(net "SMB_NIC1_ADC_SDA")
		)
	)
	(footprint ""
		(layer "F.Cu")
		(at 269.204694 -141.87297 180)
		(property "Reference" "R235"
			(at 0 0 180)
			(layer "F.SilkS")
			(hide yes)
			(effects
				(font
					(size 1.27 1.27)
				)
			)
		)
		(property "Value" ""
			(at 0 0 180)
			(layer "F.Fab")
			(effects
				(font
					(size 1.27 1.27)
				)
			)
		)
		(duplicate_pad_numbers_are_jumpers no)
		(fp_line
			(start 0.7874 0.4064)
			(end -0.7874 0.4064)
			(stroke
				(width 0.1524)
				(type default)
			)
			(layer "F.SilkS")
		)
		(fp_line
			(start 0.7874 -0.4064)
			(end 0.7874 0.4064)
			(stroke
				(width 0.1524)
				(type default)
			)
			(layer "F.SilkS")
		)
		(fp_line
			(start -0.7874 0.4064)
			(end -0.7874 -0.4064)
			(stroke
				(width 0.1524)
				(type default)
			)
			(layer "F.SilkS")
		)
		(fp_line
			(start -0.7874 -0.4064)
			(end 0.7874 -0.4064)
			(stroke
				(width 0.1524)
				(type default)
			)
			(layer "F.SilkS")
		)
		(fp_line
			(start 0.67945 0.3048)
			(end 0.120396 0.3048)
			(stroke
				(width 0.1)
				(type default)
			)
			(layer "F.Fab")
		)
		(fp_line
			(start 0.67945 -0.3048)
			(end 0.67945 0.3048)
			(stroke
				(width 0.1)
				(type default)
			)
			(layer "F.Fab")
		)
		(fp_line
			(start 0.12065 -0.2794)
			(end 0.12065 -0.3048)
			(stroke
				(width 0.1)
				(type default)
			)
			(layer "F.Fab")
		)
		(fp_line
			(start 0.12065 -0.3048)
			(end 0.67945 -0.3048)
			(stroke
				(width 0.1)
				(type default)
			)
			(layer "F.Fab")
		)
		(fp_line
			(start 0.120396 0.3048)
			(end 0.120396 0.2794)
			(stroke
				(width 0.1)
				(type default)
			)
			(layer "F.Fab")
		)
		(fp_line
			(start 0.120396 0.2794)
			(end -0.12065 0.2794)
			(stroke
				(width 0.1)
				(type default)
			)
			(layer "F.Fab")
		)
		(fp_line
			(start -0.12065 0.3048)
			(end -0.67945 0.3048)
			(stroke
				(width 0.1)
				(type default)
			)
			(layer "F.Fab")
		)
		(fp_line
			(start -0.12065 0.2794)
			(end -0.12065 0.3048)
			(stroke
				(width 0.1)
				(type default)
			)
			(layer "F.Fab")
		)
		(fp_line
			(start -0.12065 -0.2794)
			(end 0.12065 -0.2794)
			(stroke
				(width 0.1)
				(type default)
			)
			(layer "F.Fab")
		)
		(fp_line
			(start -0.12065 -0.305054)
			(end -0.12065 -0.2794)
			(stroke
				(width 0.1)
				(type default)
			)
			(layer "F.Fab")
		)
		(fp_line
			(start -0.67945 0.3048)
			(end -0.67945 -0.305054)
			(stroke
				(width 0.1)
				(type default)
			)
			(layer "F.Fab")
		)
		(fp_line
			(start -0.67945 -0.305054)
			(end -0.12065 -0.305054)
			(stroke
				(width 0.1)
				(type default)
			)
			(layer "F.Fab")
		)
		(pad "1" smd circle
			(at -0.40005 0 180)
			(size 0 0)
			(layers "F.Cu" "F.Mask" "F.Paste")
			(net "NIC4_BIF1_N")
		)
		(pad "2" smd circle
			(at 0.40005 0 180)
			(size 0 0)
			(layers "F.Cu" "F.Mask" "F.Paste")
			(net "P3V3_AUX")
		)
	)
	(footprint ""
		(layer "F.Cu")
		(at 133.594856 -170.599862 90)
		(property "Reference" "R1094"
			(at 0 0 90)
			(layer "F.SilkS")
			(hide yes)
			(effects
				(font
					(size 1.27 1.27)
				)
			)
		)
		(property "Value" ""
			(at 0 0 90)
			(layer "F.Fab")
			(effects
				(font
					(size 1.27 1.27)
				)
			)
		)
		(duplicate_pad_numbers_are_jumpers no)
		(fp_line
			(start -0.7874 -0.4064)
			(end 0.7874 -0.4064)
			(stroke
				(width 0.1524)
				(type default)
			)
			(layer "F.SilkS")
		)
		(fp_line
			(start -0.12065 -0.305054)
			(end -0.12065 -0.2794)
			(stroke
				(width 0.1)
				(type default)
			)
			(layer "F.Fab")
		)
		(fp_line
			(start -0.67945 -0.305054)
			(end -0.12065 -0.305054)
			(stroke
				(width 0.1)
				(type default)
			)
			(layer "F.Fab")
		)
		(fp_line
			(start 0.67945 -0.3048)
			(end 0.67945 0.3048)
			(stroke
				(width 0.1)
				(type default)
			)
			(layer "F.Fab")
		)
		(fp_line
			(start 0.12065 -0.3048)
			(end 0.67945 -0.3048)
			(stroke
				(width 0.1)
				(type default)
			)
			(layer "F.Fab")
		)
		(fp_line
			(start 0.12065 -0.2794)
			(end 0.12065 -0.3048)
			(stroke
				(width 0.1)
				(type default)
			)
			(layer "F.Fab")
		)
		(fp_line
			(start -0.12065 -0.2794)
			(end 0.12065 -0.2794)
			(stroke
				(width 0.1)
				(type default)
			)
			(layer "F.Fab")
		)
		(fp_line
			(start 0.120396 0.2794)
			(end -0.12065 0.2794)
			(stroke
				(width 0.1)
				(type default)
			)
			(layer "F.Fab")
		)
		(fp_line
			(start -0.12065 0.2794)
			(end -0.12065 0.3048)
			(stroke
				(width 0.1)
				(type default)
			)
			(layer "F.Fab")
		)
		(fp_line
			(start 0.67945 0.3048)
			(end 0.120396 0.3048)
			(stroke
				(width 0.1)
				(type default)
			)
			(layer "F.Fab")
		)
		(fp_line
			(start 0.120396 0.3048)
			(end 0.120396 0.2794)
			(stroke
				(width 0.1)
				(type default)
			)
			(layer "F.Fab")
		)
		(fp_line
			(start -0.12065 0.3048)
			(end -0.67945 0.3048)
			(stroke
				(width 0.1)
				(type default)
			)
			(layer "F.Fab")
		)
		(fp_line
			(start -0.67945 0.3048)
			(end -0.67945 -0.305054)
			(stroke
				(width 0.1)
				(type default)
			)
			(layer "F.Fab")
		)
		(pad "1" smd circle
			(at -0.40005 0 90)
			(size 0 0)
			(layers "F.Cu" "F.Mask" "F.Paste")
			(net "CLK_100M_DB2000QL_NIC0_R_DP")
		)
		(pad "2" smd circle
			(at 0.40005 0 90)
			(size 0 0)
			(layers "F.Cu" "F.Mask" "F.Paste")
			(net "CLK_100M_DB2000QL_NIC0_DP")
		)
	)
	(footprint ""
		(layer "F.Cu")
		(at 22.416008 -343.952322 90)
		(property "Reference" "C189"
			(at 0 0 90)
			(layer "F.SilkS")
			(hide yes)
			(effects
				(font
					(size 1.27 1.27)
				)
			)
		)
		(property "Value" ""
			(at 0 0 90)
			(layer "F.Fab")
			(effects
				(font
					(size 1.27 1.27)
				)
			)
		)
		(duplicate_pad_numbers_are_jumpers no)
		(fp_line
			(start 0.299974 -0.150114)
			(end 0.299974 0.150114)
			(stroke
				(width 0.1)
				(type default)
			)
			(layer "F.Fab")
		)
		(fp_line
			(start -0.299974 -0.150114)
			(end 0.299974 -0.150114)
			(stroke
				(width 0.1)
				(type default)
			)
			(layer "F.Fab")
		)
		(fp_line
			(start 0.299974 0.150114)
			(end -0.299974 0.150114)
			(stroke
				(width 0.1)
				(type default)
			)
			(layer "F.Fab")
		)
		(fp_line
			(start -0.299974 0.150114)
			(end -0.299974 -0.150114)
			(stroke
				(width 0.1)
				(type default)
			)
			(layer "F.Fab")
		)
		(pad "1" smd rect
			(at -0.2667 0 90)
			(size 0.3048 0.381)
			(layers "F.Cu" "F.Mask" "F.Paste")
			(net "P5E_PEX0_STN7_TX_DP<113>")
		)
		(pad "2" smd rect
			(at 0.2667 0 90)
			(size 0.3048 0.381)
			(layers "F.Cu" "F.Mask" "F.Paste")
			(net "P5E_PEX0_STN7_TX_C_DP<113>")
		)
	)
	(footprint ""
		(layer "F.Cu")
		(at 198.250302 -80.581246 90)
		(property "Reference" "U27"
			(at -0.063246 2.410968 90)
			(unlocked yes)
			(layer "F.SilkS")
			(effects
				(font
					(size 0.7874 0.5842)
					(thickness 0.1524)
				)
			)
		)
		(property "Value" ""
			(at 0 0 90)
			(layer "F.Fab")
			(effects
				(font
					(size 1.27 1.27)
				)
			)
		)
		(duplicate_pad_numbers_are_jumpers no)
		(fp_line
			(start 1.905 -1.651)
			(end 1.905 1.651)
			(stroke
				(width 0.1524)
				(type default)
			)
			(layer "F.SilkS")
		)
		(fp_line
			(start -1.905 -1.651)
			(end 1.905 -1.651)
			(stroke
				(width 0.1524)
				(type default)
			)
			(layer "F.SilkS")
		)
		(fp_line
			(start 1.905 1.651)
			(end -1.905 1.651)
			(stroke
				(width 0.1524)
				(type default)
			)
			(layer "F.SilkS")
		)
		(fp_line
			(start -1.905 1.651)
			(end -1.905 -1.651)
			(stroke
				(width 0.1524)
				(type default)
			)
			(layer "F.SilkS")
		)
		(fp_line
			(start 0.6985 -1.524)
			(end 0.6985 -0.219964)
			(stroke
				(width 0.1)
				(type default)
			)
			(layer "F.Fab")
		)
		(fp_line
			(start -0.649986 -1.524)
			(end 0.6985 -1.524)
			(stroke
				(width 0.1)
				(type default)
			)
			(layer "F.Fab")
		)
		(fp_line
			(start -0.649986 -1.169924)
			(end -0.649986 -1.524)
			(stroke
				(width 0.1)
				(type default)
			)
			(layer "F.Fab")
		)
		(fp_line
			(start -1.249934 -1.169924)
			(end -0.649986 -1.169924)
			(stroke
				(width 0.1)
				(type default)
			)
			(layer "F.Fab")
		)
		(fp_line
			(start -0.6985 -0.729996)
			(end -1.249934 -0.729996)
			(stroke
				(width 0.1)
				(type default)
			)
			(layer "F.Fab")
		)
		(fp_line
			(start -1.249934 -0.729996)
			(end -1.249934 -1.169924)
			(stroke
				(width 0.1)
				(type default)
			)
			(layer "F.Fab")
		)
		(fp_line
			(start 1.249934 -0.219964)
			(end 1.249934 0.219964)
			(stroke
				(width 0.1)
				(type default)
			)
			(layer "F.Fab")
		)
		(fp_line
			(start 0.6985 -0.219964)
			(end 1.249934 -0.219964)
			(stroke
				(width 0.1)
				(type default)
			)
			(layer "F.Fab")
		)
		(fp_line
			(start 1.249934 0.219964)
			(end 0.6985 0.219964)
			(stroke
				(width 0.1)
				(type default)
			)
			(layer "F.Fab")
		)
		(fp_line
			(start 0.6985 0.219964)
			(end 0.6985 1.524)
			(stroke
				(width 0.1)
				(type default)
			)
			(layer "F.Fab")
		)
		(fp_line
			(start -0.6985 0.729996)
			(end -0.6985 -0.729996)
			(stroke
				(width 0.1)
				(type default)
			)
			(layer "F.Fab")
		)
		(fp_line
			(start -1.249934 0.729996)
			(end -0.6985 0.729996)
			(stroke
				(width 0.1)
				(type default)
			)
			(layer "F.Fab")
		)
		(fp_line
			(start -0.649986 1.169924)
			(end -1.249934 1.169924)
			(stroke
				(width 0.1)
				(type default)
			)
			(layer "F.Fab")
		)
		(fp_line
			(start -1.249934 1.169924)
			(end -1.249934 0.729996)
			(stroke
				(width 0.1)
				(type default)
			)
			(layer "F.Fab")
		)
		(fp_line
			(start 0.6985 1.524)
			(end -0.649986 1.524)
			(stroke
				(width 0.1)
				(type default)
			)
			(layer "F.Fab")
		)
		(fp_line
			(start -0.649986 1.524)
			(end -0.649986 1.169924)
			(stroke
				(width 0.1)
				(type default)
			)
			(layer "F.Fab")
		)
		(pad "1" smd rect
			(at -1.1176 -1.016)
			(size 1.016 1.27)
			(layers "F.Cu" "F.Mask" "F.Paste")
			(net "HP_NIC3_PWRGD")
		)
		(pad "2" smd rect
			(at -1.1176 1.016)
			(size 1.016 1.27)
			(layers "F.Cu" "F.Mask" "F.Paste")
			(net "P3V3_NIC3")
		)
		(pad "3" smd rect
			(at 1.1176 0)
			(size 1.016 1.27)
			(layers "F.Cu" "F.Mask" "F.Paste")
			(net "GND")
		)
	)
	(footprint ""
		(layer "F.Cu")
		(at 277.938484 -44.341542 90)
		(property "Reference" "C326"
			(at 0 0 90)
			(layer "F.SilkS")
			(hide yes)
			(effects
				(font
					(size 1.27 1.27)
				)
			)
		)
		(property "Value" ""
			(at 0 0 90)
			(layer "F.Fab")
			(effects
				(font
					(size 1.27 1.27)
				)
			)
		)
		(duplicate_pad_numbers_are_jumpers no)
		(fp_line
			(start 0.7874 -0.4064)
			(end 0.7874 0.4064)
			(stroke
				(width 0.1524)
				(type default)
			)
			(layer "F.SilkS")
		)
		(fp_line
			(start -0.7874 -0.4064)
			(end 0.7874 -0.4064)
			(stroke
				(width 0.1524)
				(type default)
			)
			(layer "F.SilkS")
		)
		(fp_line
			(start 0.7874 0.4064)
			(end -0.7874 0.4064)
			(stroke
				(width 0.1524)
				(type default)
			)
			(layer "F.SilkS")
		)
		(fp_line
			(start -0.7874 0.4064)
			(end -0.7874 -0.4064)
			(stroke
				(width 0.1524)
				(type default)
			)
			(layer "F.SilkS")
		)
		(fp_line
			(start -0.12065 -0.305054)
			(end -0.12065 -0.2794)
			(stroke
				(width 0.1)
				(type default)
			)
			(layer "F.Fab")
		)
		(fp_line
			(start -0.67945 -0.305054)
			(end -0.12065 -0.305054)
			(stroke
				(width 0.1)
				(type default)
			)
			(layer "F.Fab")
		)
		(fp_line
			(start 0.67945 -0.3048)
			(end 0.67945 0.3048)
			(stroke
				(width 0.1)
				(type default)
			)
			(layer "F.Fab")
		)
		(fp_line
			(start 0.12065 -0.3048)
			(end 0.67945 -0.3048)
			(stroke
				(width 0.1)
				(type default)
			)
			(layer "F.Fab")
		)
		(fp_line
			(start 0.12065 -0.2794)
			(end 0.12065 -0.3048)
			(stroke
				(width 0.1)
				(type default)
			)
			(layer "F.Fab")
		)
		(fp_line
			(start -0.12065 -0.2794)
			(end 0.12065 -0.2794)
			(stroke
				(width 0.1)
				(type default)
			)
			(layer "F.Fab")
		)
		(fp_line
			(start 0.120396 0.2794)
			(end -0.12065 0.2794)
			(stroke
				(width 0.1)
				(type default)
			)
			(layer "F.Fab")
		)
		(fp_line
			(start -0.12065 0.2794)
			(end -0.12065 0.3048)
			(stroke
				(width 0.1)
				(type default)
			)
			(layer "F.Fab")
		)
		(fp_line
			(start 0.67945 0.3048)
			(end 0.120396 0.3048)
			(stroke
				(width 0.1)
				(type default)
			)
			(layer "F.Fab")
		)
		(fp_line
			(start 0.120396 0.3048)
			(end 0.120396 0.2794)
			(stroke
				(width 0.1)
				(type default)
			)
			(layer "F.Fab")
		)
		(fp_line
			(start -0.12065 0.3048)
			(end -0.67945 0.3048)
			(stroke
				(width 0.1)
				(type default)
			)
			(layer "F.Fab")
		)
		(fp_line
			(start -0.67945 0.3048)
			(end -0.67945 -0.305054)
			(stroke
				(width 0.1)
				(type default)
			)
			(layer "F.Fab")
		)
		(pad "1" smd circle
			(at -0.40005 0 90)
			(size 0 0)
			(layers "F.Cu" "F.Mask" "F.Paste")
			(net "P12V_SSD9_VIN_P")
		)
		(pad "2" smd circle
			(at 0.40005 0 90)
			(size 0 0)
			(layers "F.Cu" "F.Mask" "F.Paste")
			(net "P12V_SSD9_VIN_N")
		)
	)
	(footprint ""
		(layer "F.Cu")
		(at 40.598344 -250.070874 -90)
		(property "Reference" "R1153"
			(at 0 0 270)
			(layer "F.SilkS")
			(hide yes)
			(effects
				(font
					(size 1.27 1.27)
				)
			)
		)
		(property "Value" ""
			(at 0 0 270)
			(layer "F.Fab")
			(effects
				(font
					(size 1.27 1.27)
				)
			)
		)
		(duplicate_pad_numbers_are_jumpers no)
		(fp_line
			(start -0.7874 0.4064)
			(end -0.7874 -0.4064)
			(stroke
				(width 0.1524)
				(type default)
			)
			(layer "F.SilkS")
		)
		(fp_line
			(start 0.7874 0.4064)
			(end -0.7874 0.4064)
			(stroke
				(width 0.1524)
				(type default)
			)
			(layer "F.SilkS")
		)
		(fp_line
			(start -0.7874 -0.4064)
			(end 0.7874 -0.4064)
			(stroke
				(width 0.1524)
				(type default)
			)
			(layer "F.SilkS")
		)
		(fp_line
			(start 0.7874 -0.4064)
			(end 0.7874 0.4064)
			(stroke
				(width 0.1524)
				(type default)
			)
			(layer "F.SilkS")
		)
		(fp_line
			(start -0.67945 0.3048)
			(end -0.67945 -0.305054)
			(stroke
				(width 0.1)
				(type default)
			)
			(layer "F.Fab")
		)
		(fp_line
			(start -0.12065 0.3048)
			(end -0.67945 0.3048)
			(stroke
				(width 0.1)
				(type default)
			)
			(layer "F.Fab")
		)
		(fp_line
			(start 0.120396 0.3048)
			(end 0.120396 0.2794)
			(stroke
				(width 0.1)
				(type default)
			)
			(layer "F.Fab")
		)
		(fp_line
			(start 0.67945 0.3048)
			(end 0.120396 0.3048)
			(stroke
				(width 0.1)
				(type default)
			)
			(layer "F.Fab")
		)
		(fp_line
			(start -0.12065 0.2794)
			(end -0.12065 0.3048)
			(stroke
				(width 0.1)
				(type default)
			)
			(layer "F.Fab")
		)
		(fp_line
			(start 0.120396 0.2794)
			(end -0.12065 0.2794)
			(stroke
				(width 0.1)
				(type default)
			)
			(layer "F.Fab")
		)
		(fp_line
			(start -0.12065 -0.2794)
			(end 0.12065 -0.2794)
			(stroke
				(width 0.1)
				(type default)
			)
			(layer "F.Fab")
		)
		(fp_line
			(start 0.12065 -0.2794)
			(end 0.12065 -0.3048)
			(stroke
				(width 0.1)
				(type default)
			)
			(layer "F.Fab")
		)
		(fp_line
			(start 0.12065 -0.3048)
			(end 0.67945 -0.3048)
			(stroke
				(width 0.1)
				(type default)
			)
			(layer "F.Fab")
		)
		(fp_line
			(start 0.67945 -0.3048)
			(end 0.67945 0.3048)
			(stroke
				(width 0.1)
				(type default)
			)
			(layer "F.Fab")
		)
		(fp_line
			(start -0.67945 -0.305054)
			(end -0.12065 -0.305054)
			(stroke
				(width 0.1)
				(type default)
			)
			(layer "F.Fab")
		)
		(fp_line
			(start -0.12065 -0.305054)
			(end -0.12065 -0.2794)
			(stroke
				(width 0.1)
				(type default)
			)
			(layer "F.Fab")
		)
		(pad "1" smd circle
			(at -0.40005 0 270)
			(size 0 0)
			(layers "F.Cu" "F.Mask" "F.Paste")
			(net "PEX0_MODE_SEL1")
		)
		(pad "2" smd circle
			(at 0.40005 0 270)
			(size 0 0)
			(layers "F.Cu" "F.Mask" "F.Paste")
			(net "P1V8_PEX")
		)
	)
	(footprint ""
		(layer "F.Cu")
		(at 8.110474 -63.652146 180)
		(property "Reference" "R5840"
			(at 0 0 180)
			(layer "F.SilkS")
			(hide yes)
			(effects
				(font
					(size 1.27 1.27)
				)
			)
		)
		(property "Value" ""
			(at 0 0 180)
			(layer "F.Fab")
			(effects
				(font
					(size 1.27 1.27)
				)
			)
		)
		(duplicate_pad_numbers_are_jumpers no)
		(fp_line
			(start 0.7874 0.4064)
			(end -0.7874 0.4064)
			(stroke
				(width 0.1524)
				(type default)
			)
			(layer "F.SilkS")
		)
		(fp_line
			(start 0.7874 -0.4064)
			(end 0.7874 0.4064)
			(stroke
				(width 0.1524)
				(type default)
			)
			(layer "F.SilkS")
		)
		(fp_line
			(start -0.7874 0.4064)
			(end -0.7874 -0.4064)
			(stroke
				(width 0.1524)
				(type default)
			)
			(layer "F.SilkS")
		)
		(fp_line
			(start -0.7874 -0.4064)
			(end 0.7874 -0.4064)
			(stroke
				(width 0.1524)
				(type default)
			)
			(layer "F.SilkS")
		)
		(fp_line
			(start 0.67945 0.3048)
			(end 0.120396 0.3048)
			(stroke
				(width 0.1)
				(type default)
			)
			(layer "F.Fab")
		)
		(fp_line
			(start 0.67945 -0.3048)
			(end 0.67945 0.3048)
			(stroke
				(width 0.1)
				(type default)
			)
			(layer "F.Fab")
		)
		(fp_line
			(start 0.12065 -0.2794)
			(end 0.12065 -0.3048)
			(stroke
				(width 0.1)
				(type default)
			)
			(layer "F.Fab")
		)
		(fp_line
			(start 0.12065 -0.3048)
			(end 0.67945 -0.3048)
			(stroke
				(width 0.1)
				(type default)
			)
			(layer "F.Fab")
		)
		(fp_line
			(start 0.120396 0.3048)
			(end 0.120396 0.2794)
			(stroke
				(width 0.1)
				(type default)
			)
			(layer "F.Fab")
		)
		(fp_line
			(start 0.120396 0.2794)
			(end -0.12065 0.2794)
			(stroke
				(width 0.1)
				(type default)
			)
			(layer "F.Fab")
		)
		(fp_line
			(start -0.12065 0.3048)
			(end -0.67945 0.3048)
			(stroke
				(width 0.1)
				(type default)
			)
			(layer "F.Fab")
		)
		(fp_line
			(start -0.12065 0.2794)
			(end -0.12065 0.3048)
			(stroke
				(width 0.1)
				(type default)
			)
			(layer "F.Fab")
		)
		(fp_line
			(start -0.12065 -0.2794)
			(end 0.12065 -0.2794)
			(stroke
				(width 0.1)
				(type default)
			)
			(layer "F.Fab")
		)
		(fp_line
			(start -0.12065 -0.305054)
			(end -0.12065 -0.2794)
			(stroke
				(width 0.1)
				(type default)
			)
			(layer "F.Fab")
		)
		(fp_line
			(start -0.67945 0.3048)
			(end -0.67945 -0.305054)
			(stroke
				(width 0.1)
				(type default)
			)
			(layer "F.Fab")
		)
		(fp_line
			(start -0.67945 -0.305054)
			(end -0.12065 -0.305054)
			(stroke
				(width 0.1)
				(type default)
			)
			(layer "F.Fab")
		)
		(pad "1" smd circle
			(at -0.40005 0 180)
			(size 0 0)
			(layers "F.Cu" "F.Mask" "F.Paste")
			(net "P5V_AUX")
		)
		(pad "2" smd circle
			(at 0.40005 0 180)
			(size 0 0)
			(layers "F.Cu" "F.Mask" "F.Paste")
			(net "P12V_SSD0_PG_G2")
		)
	)
	(footprint ""
		(layer "F.Cu")
		(at 462.465674 -273.59483)
		(property "Reference" "R802"
			(at 0 0 0)
			(layer "F.SilkS")
			(hide yes)
			(effects
				(font
					(size 1.27 1.27)
				)
			)
		)
		(property "Value" ""
			(at 0 0 0)
			(layer "F.Fab")
			(effects
				(font
					(size 1.27 1.27)
				)
			)
		)
		(duplicate_pad_numbers_are_jumpers no)
		(fp_line
			(start -0.7874 -0.4064)
			(end 0.7874 -0.4064)
			(stroke
				(width 0.1524)
				(type default)
			)
			(layer "F.SilkS")
		)
		(fp_line
			(start -0.7874 0.4064)
			(end -0.7874 -0.4064)
			(stroke
				(width 0.1524)
				(type default)
			)
			(layer "F.SilkS")
		)
		(fp_line
			(start 0.7874 -0.4064)
			(end 0.7874 0.4064)
			(stroke
				(width 0.1524)
				(type default)
			)
			(layer "F.SilkS")
		)
		(fp_line
			(start 0.7874 0.4064)
			(end -0.7874 0.4064)
			(stroke
				(width 0.1524)
				(type default)
			)
			(layer "F.SilkS")
		)
		(fp_line
			(start -0.67945 -0.305054)
			(end -0.12065 -0.305054)
			(stroke
				(width 0.1)
				(type default)
			)
			(layer "F.Fab")
		)
		(fp_line
			(start -0.67945 0.3048)
			(end -0.67945 -0.305054)
			(stroke
				(width 0.1)
				(type default)
			)
			(layer "F.Fab")
		)
		(fp_line
			(start -0.12065 -0.305054)
			(end -0.12065 -0.2794)
			(stroke
				(width 0.1)
				(type default)
			)
			(layer "F.Fab")
		)
		(fp_line
			(start -0.12065 -0.2794)
			(end 0.12065 -0.2794)
			(stroke
				(width 0.1)
				(type default)
			)
			(layer "F.Fab")
		)
		(fp_line
			(start -0.12065 0.2794)
			(end -0.12065 0.3048)
			(stroke
				(width 0.1)
				(type default)
			)
			(layer "F.Fab")
		)
		(fp_line
			(start -0.12065 0.3048)
			(end -0.67945 0.3048)
			(stroke
				(width 0.1)
				(type default)
			)
			(layer "F.Fab")
		)
		(fp_line
			(start 0.120396 0.2794)
			(end -0.12065 0.2794)
			(stroke
				(width 0.1)
				(type default)
			)
			(layer "F.Fab")
		)
		(fp_line
			(start 0.120396 0.3048)
			(end 0.120396 0.2794)
			(stroke
				(width 0.1)
				(type default)
			)
			(layer "F.Fab")
		)
		(fp_line
			(start 0.12065 -0.3048)
			(end 0.67945 -0.3048)
			(stroke
				(width 0.1)
				(type default)
			)
			(layer "F.Fab")
		)
		(fp_line
			(start 0.12065 -0.2794)
			(end 0.12065 -0.3048)
			(stroke
				(width 0.1)
				(type default)
			)
			(layer "F.Fab")
		)
		(fp_line
			(start 0.67945 -0.3048)
			(end 0.67945 0.3048)
			(stroke
				(width 0.1)
				(type default)
			)
			(layer "F.Fab")
		)
		(fp_line
			(start 0.67945 0.3048)
			(end 0.120396 0.3048)
			(stroke
				(width 0.1)
				(type default)
			)
			(layer "F.Fab")
		)
		(pad "1" smd circle
			(at -0.40005 0)
			(size 0 0)
			(layers "F.Cu" "F.Mask" "F.Paste")
			(net "PEX3_P1V25_ADC_A1")
		)
		(pad "2" smd circle
			(at 0.40005 0)
			(size 0 0)
			(layers "F.Cu" "F.Mask" "F.Paste")
			(net "P3V3_AUX")
		)
	)
	(footprint ""
		(layer "F.Cu")
		(at 98.866198 -95.263716 -90)
		(property "Reference" "PC456"
			(at 0 0 270)
			(layer "F.SilkS")
			(hide yes)
			(effects
				(font
					(size 1.27 1.27)
				)
			)
		)
		(property "Value" ""
			(at 0 0 270)
			(layer "F.Fab")
			(effects
				(font
					(size 1.27 1.27)
				)
			)
		)
		(duplicate_pad_numbers_are_jumpers no)
		(fp_line
			(start -0.7874 0.4064)
			(end -0.7874 -0.4064)
			(stroke
				(width 0.1524)
				(type default)
			)
			(layer "F.SilkS")
		)
		(fp_line
			(start 0.7874 0.4064)
			(end -0.7874 0.4064)
			(stroke
				(width 0.1524)
				(type default)
			)
			(layer "F.SilkS")
		)
		(fp_line
			(start -0.7874 -0.4064)
			(end 0.7874 -0.4064)
			(stroke
				(width 0.1524)
				(type default)
			)
			(layer "F.SilkS")
		)
		(fp_line
			(start 0.7874 -0.4064)
			(end 0.7874 0.4064)
			(stroke
				(width 0.1524)
				(type default)
			)
			(layer "F.SilkS")
		)
		(fp_line
			(start -0.67945 0.3048)
			(end -0.67945 -0.305054)
			(stroke
				(width 0.1)
				(type default)
			)
			(layer "F.Fab")
		)
		(fp_line
			(start -0.12065 0.3048)
			(end -0.67945 0.3048)
			(stroke
				(width 0.1)
				(type default)
			)
			(layer "F.Fab")
		)
		(fp_line
			(start 0.120396 0.3048)
			(end 0.120396 0.2794)
			(stroke
				(width 0.1)
				(type default)
			)
			(layer "F.Fab")
		)
		(fp_line
			(start 0.67945 0.3048)
			(end 0.120396 0.3048)
			(stroke
				(width 0.1)
				(type default)
			)
			(layer "F.Fab")
		)
		(fp_line
			(start -0.12065 0.2794)
			(end -0.12065 0.3048)
			(stroke
				(width 0.1)
				(type default)
			)
			(layer "F.Fab")
		)
		(fp_line
			(start 0.120396 0.2794)
			(end -0.12065 0.2794)
			(stroke
				(width 0.1)
				(type default)
			)
			(layer "F.Fab")
		)
		(fp_line
			(start -0.12065 -0.2794)
			(end 0.12065 -0.2794)
			(stroke
				(width 0.1)
				(type default)
			)
			(layer "F.Fab")
		)
		(fp_line
			(start 0.12065 -0.2794)
			(end 0.12065 -0.3048)
			(stroke
				(width 0.1)
				(type default)
			)
			(layer "F.Fab")
		)
		(fp_line
			(start 0.12065 -0.3048)
			(end 0.67945 -0.3048)
			(stroke
				(width 0.1)
				(type default)
			)
			(layer "F.Fab")
		)
		(fp_line
			(start 0.67945 -0.3048)
			(end 0.67945 0.3048)
			(stroke
				(width 0.1)
				(type default)
			)
			(layer "F.Fab")
		)
		(fp_line
			(start -0.67945 -0.305054)
			(end -0.12065 -0.305054)
			(stroke
				(width 0.1)
				(type default)
			)
			(layer "F.Fab")
		)
		(fp_line
			(start -0.12065 -0.305054)
			(end -0.12065 -0.2794)
			(stroke
				(width 0.1)
				(type default)
			)
			(layer "F.Fab")
		)
		(pad "1" smd circle
			(at -0.40005 0 270)
			(size 0 0)
			(layers "F.Cu" "F.Mask" "F.Paste")
			(net "P5V_AUX")
		)
		(pad "2" smd circle
			(at 0.40005 0 270)
			(size 0 0)
			(layers "F.Cu" "F.Mask" "F.Paste")
			(net "GND")
		)
	)
	(footprint ""
		(layer "F.Cu")
		(at 225.530664 -204.44206 90)
		(property "Reference" "R5280"
			(at 0 0 90)
			(layer "F.SilkS")
			(hide yes)
			(effects
				(font
					(size 1.27 1.27)
				)
			)
		)
		(property "Value" ""
			(at 0 0 90)
			(layer "F.Fab")
			(effects
				(font
					(size 1.27 1.27)
				)
			)
		)
		(duplicate_pad_numbers_are_jumpers no)
		(fp_line
			(start 0.7874 -0.4064)
			(end 0.7874 0.4064)
			(stroke
				(width 0.1524)
				(type default)
			)
			(layer "F.SilkS")
		)
		(fp_line
			(start -0.7874 -0.4064)
			(end 0.7874 -0.4064)
			(stroke
				(width 0.1524)
				(type default)
			)
			(layer "F.SilkS")
		)
		(fp_line
			(start 0.7874 0.4064)
			(end -0.7874 0.4064)
			(stroke
				(width 0.1524)
				(type default)
			)
			(layer "F.SilkS")
		)
		(fp_line
			(start -0.7874 0.4064)
			(end -0.7874 -0.4064)
			(stroke
				(width 0.1524)
				(type default)
			)
			(layer "F.SilkS")
		)
		(fp_line
			(start -0.12065 -0.305054)
			(end -0.12065 -0.2794)
			(stroke
				(width 0.1)
				(type default)
			)
			(layer "F.Fab")
		)
		(fp_line
			(start -0.67945 -0.305054)
			(end -0.12065 -0.305054)
			(stroke
				(width 0.1)
				(type default)
			)
			(layer "F.Fab")
		)
		(fp_line
			(start 0.67945 -0.3048)
			(end 0.67945 0.3048)
			(stroke
				(width 0.1)
				(type default)
			)
			(layer "F.Fab")
		)
		(fp_line
			(start 0.12065 -0.3048)
			(end 0.67945 -0.3048)
			(stroke
				(width 0.1)
				(type default)
			)
			(layer "F.Fab")
		)
		(fp_line
			(start 0.12065 -0.2794)
			(end 0.12065 -0.3048)
			(stroke
				(width 0.1)
				(type default)
			)
			(layer "F.Fab")
		)
		(fp_line
			(start -0.12065 -0.2794)
			(end 0.12065 -0.2794)
			(stroke
				(width 0.1)
				(type default)
			)
			(layer "F.Fab")
		)
		(fp_line
			(start 0.120396 0.2794)
			(end -0.12065 0.2794)
			(stroke
				(width 0.1)
				(type default)
			)
			(layer "F.Fab")
		)
		(fp_line
			(start -0.12065 0.2794)
			(end -0.12065 0.3048)
			(stroke
				(width 0.1)
				(type default)
			)
			(layer "F.Fab")
		)
		(fp_line
			(start 0.67945 0.3048)
			(end 0.120396 0.3048)
			(stroke
				(width 0.1)
				(type default)
			)
			(layer "F.Fab")
		)
		(fp_line
			(start 0.120396 0.3048)
			(end 0.120396 0.2794)
			(stroke
				(width 0.1)
				(type default)
			)
			(layer "F.Fab")
		)
		(fp_line
			(start -0.12065 0.3048)
			(end -0.67945 0.3048)
			(stroke
				(width 0.1)
				(type default)
			)
			(layer "F.Fab")
		)
		(fp_line
			(start -0.67945 0.3048)
			(end -0.67945 -0.305054)
			(stroke
				(width 0.1)
				(type default)
			)
			(layer "F.Fab")
		)
		(pad "1" smd circle
			(at -0.40005 0 90)
			(size 0 0)
			(layers "F.Cu" "F.Mask" "F.Paste")
			(net "P3V3_AUX")
		)
		(pad "2" smd circle
			(at 0.40005 0 90)
			(size 0 0)
			(layers "F.Cu" "F.Mask" "F.Paste")
			(net "JTAG_BIC_NTRST_R_N")
		)
	)
	(footprint ""
		(layer "F.Cu")
		(at 391.085832 -89.421462)
		(property "Reference" "C2743"
			(at 0 0 0)
			(layer "F.SilkS")
			(hide yes)
			(effects
				(font
					(size 1.27 1.27)
				)
			)
		)
		(property "Value" ""
			(at 0 0 0)
			(layer "F.Fab")
			(effects
				(font
					(size 1.27 1.27)
				)
			)
		)
		(duplicate_pad_numbers_are_jumpers no)
		(fp_line
			(start -0.7874 -0.4064)
			(end 0.7874 -0.4064)
			(stroke
				(width 0.1524)
				(type default)
			)
			(layer "F.SilkS")
		)
		(fp_line
			(start -0.7874 0.4064)
			(end -0.7874 -0.4064)
			(stroke
				(width 0.1524)
				(type default)
			)
			(layer "F.SilkS")
		)
		(fp_line
			(start 0.7874 -0.4064)
			(end 0.7874 0.4064)
			(stroke
				(width 0.1524)
				(type default)
			)
			(layer "F.SilkS")
		)
		(fp_line
			(start 0.7874 0.4064)
			(end -0.7874 0.4064)
			(stroke
				(width 0.1524)
				(type default)
			)
			(layer "F.SilkS")
		)
		(fp_line
			(start -0.67945 -0.305054)
			(end -0.12065 -0.305054)
			(stroke
				(width 0.1)
				(type default)
			)
			(layer "F.Fab")
		)
		(fp_line
			(start -0.67945 0.3048)
			(end -0.67945 -0.305054)
			(stroke
				(width 0.1)
				(type default)
			)
			(layer "F.Fab")
		)
		(fp_line
			(start -0.12065 -0.305054)
			(end -0.12065 -0.2794)
			(stroke
				(width 0.1)
				(type default)
			)
			(layer "F.Fab")
		)
		(fp_line
			(start -0.12065 -0.2794)
			(end 0.12065 -0.2794)
			(stroke
				(width 0.1)
				(type default)
			)
			(layer "F.Fab")
		)
		(fp_line
			(start -0.12065 0.2794)
			(end -0.12065 0.3048)
			(stroke
				(width 0.1)
				(type default)
			)
			(layer "F.Fab")
		)
		(fp_line
			(start -0.12065 0.3048)
			(end -0.67945 0.3048)
			(stroke
				(width 0.1)
				(type default)
			)
			(layer "F.Fab")
		)
		(fp_line
			(start 0.120396 0.2794)
			(end -0.12065 0.2794)
			(stroke
				(width 0.1)
				(type default)
			)
			(layer "F.Fab")
		)
		(fp_line
			(start 0.120396 0.3048)
			(end 0.120396 0.2794)
			(stroke
				(width 0.1)
				(type default)
			)
			(layer "F.Fab")
		)
		(fp_line
			(start 0.12065 -0.3048)
			(end 0.67945 -0.3048)
			(stroke
				(width 0.1)
				(type default)
			)
			(layer "F.Fab")
		)
		(fp_line
			(start 0.12065 -0.2794)
			(end 0.12065 -0.3048)
			(stroke
				(width 0.1)
				(type default)
			)
			(layer "F.Fab")
		)
		(fp_line
			(start 0.67945 -0.3048)
			(end 0.67945 0.3048)
			(stroke
				(width 0.1)
				(type default)
			)
			(layer "F.Fab")
		)
		(fp_line
			(start 0.67945 0.3048)
			(end 0.120396 0.3048)
			(stroke
				(width 0.1)
				(type default)
			)
			(layer "F.Fab")
		)
		(pad "1" smd circle
			(at -0.40005 0)
			(size 0 0)
			(layers "F.Cu" "F.Mask" "F.Paste")
			(net "P3V3_AUX")
		)
		(pad "2" smd circle
			(at 0.40005 0)
			(size 0 0)
			(layers "F.Cu" "F.Mask" "F.Paste")
			(net "GND")
		)
	)
	(footprint ""
		(layer "F.Cu")
		(at 132.034026 -135.77697 -90)
		(property "Reference" "PC333"
			(at 0 0 270)
			(layer "F.SilkS")
			(hide yes)
			(effects
				(font
					(size 1.27 1.27)
				)
			)
		)
		(property "Value" ""
			(at 0 0 270)
			(layer "F.Fab")
			(effects
				(font
					(size 1.27 1.27)
				)
			)
		)
		(duplicate_pad_numbers_are_jumpers no)
		(fp_line
			(start -1.524 0.762)
			(end -1.524 -0.762)
			(stroke
				(width 0.1524)
				(type default)
			)
			(layer "F.SilkS")
		)
		(fp_line
			(start 1.524 0.762)
			(end -1.524 0.762)
			(stroke
				(width 0.1524)
				(type default)
			)
			(layer "F.SilkS")
		)
		(fp_line
			(start -1.524 -0.762)
			(end 1.524 -0.762)
			(stroke
				(width 0.1524)
				(type default)
			)
			(layer "F.SilkS")
		)
		(fp_line
			(start 1.524 -0.762)
			(end 1.524 0.762)
			(stroke
				(width 0.1524)
				(type default)
			)
			(layer "F.SilkS")
		)
		(fp_line
			(start -1.1049 0.724916)
			(end 1.1049 0.724916)
			(stroke
				(width 0.1)
				(type default)
			)
			(layer "F.Fab")
		)
		(fp_line
			(start 1.1049 0.724916)
			(end 1.1049 -0.724916)
			(stroke
				(width 0.1)
				(type default)
			)
			(layer "F.Fab")
		)
		(fp_line
			(start -1.1049 -0.724916)
			(end -1.1049 0.724916)
			(stroke
				(width 0.1)
				(type default)
			)
			(layer "F.Fab")
		)
		(fp_line
			(start 1.1049 -0.724916)
			(end -1.1049 -0.724916)
			(stroke
				(width 0.1)
				(type default)
			)
			(layer "F.Fab")
		)
		(pad "1" smd rect
			(at -0.889 0 90)
			(size 1.016 1.27)
			(layers "F.Cu" "F.Mask" "F.Paste")
			(net "P12V_NIC2_R")
		)
		(pad "2" smd rect
			(at 0.889 0 90)
			(size 1.016 1.27)
			(layers "F.Cu" "F.Mask" "F.Paste")
			(net "GND")
		)
	)
	(footprint ""
		(layer "F.Cu")
		(at 39.280592 -124.605542)
		(property "Reference" "C41"
			(at 0 0 0)
			(layer "F.SilkS")
			(hide yes)
			(effects
				(font
					(size 1.27 1.27)
				)
			)
		)
		(property "Value" ""
			(at 0 0 0)
			(layer "F.Fab")
			(effects
				(font
					(size 1.27 1.27)
				)
			)
		)
		(duplicate_pad_numbers_are_jumpers no)
		(fp_line
			(start -0.299974 -0.150114)
			(end 0.299974 -0.150114)
			(stroke
				(width 0.1)
				(type default)
			)
			(layer "F.Fab")
		)
		(fp_line
			(start -0.299974 0.150114)
			(end -0.299974 -0.150114)
			(stroke
				(width 0.1)
				(type default)
			)
			(layer "F.Fab")
		)
		(fp_line
			(start 0.299974 -0.150114)
			(end 0.299974 0.150114)
			(stroke
				(width 0.1)
				(type default)
			)
			(layer "F.Fab")
		)
		(fp_line
			(start 0.299974 0.150114)
			(end -0.299974 0.150114)
			(stroke
				(width 0.1)
				(type default)
			)
			(layer "F.Fab")
		)
		(pad "1" smd rect
			(at -0.2667 0)
			(size 0.3048 0.381)
			(layers "F.Cu" "F.Mask" "F.Paste")
			(net "P5E_PEX0_STN1_TX_DN<27>")
		)
		(pad "2" smd rect
			(at 0.2667 0)
			(size 0.3048 0.381)
			(layers "F.Cu" "F.Mask" "F.Paste")
			(net "P5E_PEX0_STN1_TX_C_DN<27>")
		)
	)
	(footprint ""
		(layer "F.Cu")
		(at 121.108978 -89.53373)
		(property "Reference" "R1560"
			(at 0 0 0)
			(layer "F.SilkS")
			(hide yes)
			(effects
				(font
					(size 1.27 1.27)
				)
			)
		)
		(property "Value" ""
			(at 0 0 0)
			(layer "F.Fab")
			(effects
				(font
					(size 1.27 1.27)
				)
			)
		)
		(duplicate_pad_numbers_are_jumpers no)
		(fp_line
			(start -0.7874 -0.4064)
			(end 0.7874 -0.4064)
			(stroke
				(width 0.1524)
				(type default)
			)
			(layer "F.SilkS")
		)
		(fp_line
			(start -0.7874 0.4064)
			(end -0.7874 -0.4064)
			(stroke
				(width 0.1524)
				(type default)
			)
			(layer "F.SilkS")
		)
		(fp_line
			(start 0.7874 -0.4064)
			(end 0.7874 0.4064)
			(stroke
				(width 0.1524)
				(type default)
			)
			(layer "F.SilkS")
		)
		(fp_line
			(start 0.7874 0.4064)
			(end -0.7874 0.4064)
			(stroke
				(width 0.1524)
				(type default)
			)
			(layer "F.SilkS")
		)
		(fp_line
			(start -0.67945 -0.305054)
			(end -0.12065 -0.305054)
			(stroke
				(width 0.1)
				(type default)
			)
			(layer "F.Fab")
		)
		(fp_line
			(start -0.67945 0.3048)
			(end -0.67945 -0.305054)
			(stroke
				(width 0.1)
				(type default)
			)
			(layer "F.Fab")
		)
		(fp_line
			(start -0.12065 -0.305054)
			(end -0.12065 -0.2794)
			(stroke
				(width 0.1)
				(type default)
			)
			(layer "F.Fab")
		)
		(fp_line
			(start -0.12065 -0.2794)
			(end 0.12065 -0.2794)
			(stroke
				(width 0.1)
				(type default)
			)
			(layer "F.Fab")
		)
		(fp_line
			(start -0.12065 0.2794)
			(end -0.12065 0.3048)
			(stroke
				(width 0.1)
				(type default)
			)
			(layer "F.Fab")
		)
		(fp_line
			(start -0.12065 0.3048)
			(end -0.67945 0.3048)
			(stroke
				(width 0.1)
				(type default)
			)
			(layer "F.Fab")
		)
		(fp_line
			(start 0.120396 0.2794)
			(end -0.12065 0.2794)
			(stroke
				(width 0.1)
				(type default)
			)
			(layer "F.Fab")
		)
		(fp_line
			(start 0.120396 0.3048)
			(end 0.120396 0.2794)
			(stroke
				(width 0.1)
				(type default)
			)
			(layer "F.Fab")
		)
		(fp_line
			(start 0.12065 -0.3048)
			(end 0.67945 -0.3048)
			(stroke
				(width 0.1)
				(type default)
			)
			(layer "F.Fab")
		)
		(fp_line
			(start 0.12065 -0.2794)
			(end 0.12065 -0.3048)
			(stroke
				(width 0.1)
				(type default)
			)
			(layer "F.Fab")
		)
		(fp_line
			(start 0.67945 -0.3048)
			(end 0.67945 0.3048)
			(stroke
				(width 0.1)
				(type default)
			)
			(layer "F.Fab")
		)
		(fp_line
			(start 0.67945 0.3048)
			(end 0.120396 0.3048)
			(stroke
				(width 0.1)
				(type default)
			)
			(layer "F.Fab")
		)
		(pad "1" smd circle
			(at -0.40005 0)
			(size 0 0)
			(layers "F.Cu" "F.Mask" "F.Paste")
			(net "P3V3_AUX")
		)
		(pad "2" smd circle
			(at 0.40005 0)
			(size 0 0)
			(layers "F.Cu" "F.Mask" "F.Paste")
			(net "SMB_BIC_I2C9_MUX0_SSD3_R_SDA")
		)
	)
	(footprint ""
		(layer "F.Cu")
		(at 220.676978 -266.873228 180)
		(property "Reference" "L99"
			(at 0 0 180)
			(layer "F.SilkS")
			(hide yes)
			(effects
				(font
					(size 1.27 1.27)
				)
			)
		)
		(property "Value" ""
			(at 0 0 180)
			(layer "F.Fab")
			(effects
				(font
					(size 1.27 1.27)
				)
			)
		)
		(duplicate_pad_numbers_are_jumpers no)
		(fp_line
			(start 2.248154 4.9911)
			(end 2.248154 1.606296)
			(stroke
				(width 0.1524)
				(type default)
			)
			(layer "F.SilkS")
		)
		(fp_line
			(start 2.248154 -1.580642)
			(end 2.248154 -4.9911)
			(stroke
				(width 0.1524)
				(type default)
			)
			(layer "F.SilkS")
		)
		(fp_line
			(start 2.248154 -4.9911)
			(end -2.248154 -4.9911)
			(stroke
				(width 0.1524)
				(type default)
			)
			(layer "F.SilkS")
		)
		(fp_line
			(start -2.248154 4.9911)
			(end 2.248154 4.9911)
			(stroke
				(width 0.1524)
				(type default)
			)
			(layer "F.SilkS")
		)
		(fp_line
			(start -2.248154 1.617218)
			(end -2.248154 4.9911)
			(stroke
				(width 0.1524)
				(type default)
			)
			(layer "F.SilkS")
		)
		(fp_line
			(start -2.248154 -4.9911)
			(end -2.248154 -1.62179)
			(stroke
				(width 0.1524)
				(type default)
			)
			(layer "F.SilkS")
		)
		(fp_line
			(start 1.700022 0.899922)
			(end 1.700022 -0.899922)
			(stroke
				(width 0.1)
				(type default)
			)
			(layer "F.Fab")
		)
		(fp_line
			(start 1.700022 -0.899922)
			(end -1.700022 -0.899922)
			(stroke
				(width 0.1)
				(type default)
			)
			(layer "F.Fab")
		)
		(fp_line
			(start -1.700022 0.899922)
			(end 1.700022 0.899922)
			(stroke
				(width 0.1)
				(type default)
			)
			(layer "F.Fab")
		)
		(fp_line
			(start -1.700022 -0.899922)
			(end -1.700022 0.899922)
			(stroke
				(width 0.1)
				(type default)
			)
			(layer "F.Fab")
		)
		(pad "1" smd rect
			(at -1.575054 0 180)
			(size 1.1684 9.8044)
			(layers "F.Cu" "F.Mask" "F.Paste")
			(net "P1V25_PEX1")
		)
		(pad "2" smd rect
			(at 1.575054 0 180)
			(size 1.1684 9.8044)
			(layers "F.Cu" "F.Mask" "F.Paste")
			(net "P1V25_SERDES_VDDPLL_PEX1")
		)
	)
	(footprint ""
		(layer "F.Cu")
		(at 151.618442 -250.070874 -90)
		(property "Reference" "R1281"
			(at 0 0 270)
			(layer "F.SilkS")
			(hide yes)
			(effects
				(font
					(size 1.27 1.27)
				)
			)
		)
		(property "Value" ""
			(at 0 0 270)
			(layer "F.Fab")
			(effects
				(font
					(size 1.27 1.27)
				)
			)
		)
		(duplicate_pad_numbers_are_jumpers no)
		(fp_line
			(start -0.7874 0.4064)
			(end -0.7874 -0.4064)
			(stroke
				(width 0.1524)
				(type default)
			)
			(layer "F.SilkS")
		)
		(fp_line
			(start 0.7874 0.4064)
			(end -0.7874 0.4064)
			(stroke
				(width 0.1524)
				(type default)
			)
			(layer "F.SilkS")
		)
		(fp_line
			(start -0.7874 -0.4064)
			(end 0.7874 -0.4064)
			(stroke
				(width 0.1524)
				(type default)
			)
			(layer "F.SilkS")
		)
		(fp_line
			(start 0.7874 -0.4064)
			(end 0.7874 0.4064)
			(stroke
				(width 0.1524)
				(type default)
			)
			(layer "F.SilkS")
		)
		(fp_line
			(start -0.67945 0.3048)
			(end -0.67945 -0.305054)
			(stroke
				(width 0.1)
				(type default)
			)
			(layer "F.Fab")
		)
		(fp_line
			(start -0.12065 0.3048)
			(end -0.67945 0.3048)
			(stroke
				(width 0.1)
				(type default)
			)
			(layer "F.Fab")
		)
		(fp_line
			(start 0.120396 0.3048)
			(end 0.120396 0.2794)
			(stroke
				(width 0.1)
				(type default)
			)
			(layer "F.Fab")
		)
		(fp_line
			(start 0.67945 0.3048)
			(end 0.120396 0.3048)
			(stroke
				(width 0.1)
				(type default)
			)
			(layer "F.Fab")
		)
		(fp_line
			(start -0.12065 0.2794)
			(end -0.12065 0.3048)
			(stroke
				(width 0.1)
				(type default)
			)
			(layer "F.Fab")
		)
		(fp_line
			(start 0.120396 0.2794)
			(end -0.12065 0.2794)
			(stroke
				(width 0.1)
				(type default)
			)
			(layer "F.Fab")
		)
		(fp_line
			(start -0.12065 -0.2794)
			(end 0.12065 -0.2794)
			(stroke
				(width 0.1)
				(type default)
			)
			(layer "F.Fab")
		)
		(fp_line
			(start 0.12065 -0.2794)
			(end 0.12065 -0.3048)
			(stroke
				(width 0.1)
				(type default)
			)
			(layer "F.Fab")
		)
		(fp_line
			(start 0.12065 -0.3048)
			(end 0.67945 -0.3048)
			(stroke
				(width 0.1)
				(type default)
			)
			(layer "F.Fab")
		)
		(fp_line
			(start 0.67945 -0.3048)
			(end 0.67945 0.3048)
			(stroke
				(width 0.1)
				(type default)
			)
			(layer "F.Fab")
		)
		(fp_line
			(start -0.67945 -0.305054)
			(end -0.12065 -0.305054)
			(stroke
				(width 0.1)
				(type default)
			)
			(layer "F.Fab")
		)
		(fp_line
			(start -0.12065 -0.305054)
			(end -0.12065 -0.2794)
			(stroke
				(width 0.1)
				(type default)
			)
			(layer "F.Fab")
		)
		(pad "1" smd circle
			(at -0.40005 0 270)
			(size 0 0)
			(layers "F.Cu" "F.Mask" "F.Paste")
			(net "PEX1_MODE_SEL12")
		)
		(pad "2" smd circle
			(at 0.40005 0 270)
			(size 0 0)
			(layers "F.Cu" "F.Mask" "F.Paste")
			(net "P1V8_PEX")
		)
	)
	(footprint ""
		(layer "F.Cu")
		(at 46.947328 -20.35556)
		(property "Reference" "C3883"
			(at 0 0 0)
			(layer "F.SilkS")
			(hide yes)
			(effects
				(font
					(size 1.27 1.27)
				)
			)
		)
		(property "Value" ""
			(at 0 0 0)
			(layer "F.Fab")
			(effects
				(font
					(size 1.27 1.27)
				)
			)
		)
		(duplicate_pad_numbers_are_jumpers no)
		(fp_line
			(start -0.7874 -0.4064)
			(end 0.7874 -0.4064)
			(stroke
				(width 0.1524)
				(type default)
			)
			(layer "F.SilkS")
		)
		(fp_line
			(start -0.7874 0.4064)
			(end -0.7874 -0.4064)
			(stroke
				(width 0.1524)
				(type default)
			)
			(layer "F.SilkS")
		)
		(fp_line
			(start 0.7874 -0.4064)
			(end 0.7874 0.4064)
			(stroke
				(width 0.1524)
				(type default)
			)
			(layer "F.SilkS")
		)
		(fp_line
			(start 0.7874 0.4064)
			(end -0.7874 0.4064)
			(stroke
				(width 0.1524)
				(type default)
			)
			(layer "F.SilkS")
		)
		(fp_line
			(start -0.67945 -0.305054)
			(end -0.12065 -0.305054)
			(stroke
				(width 0.1)
				(type default)
			)
			(layer "F.Fab")
		)
		(fp_line
			(start -0.67945 0.3048)
			(end -0.67945 -0.305054)
			(stroke
				(width 0.1)
				(type default)
			)
			(layer "F.Fab")
		)
		(fp_line
			(start -0.12065 -0.305054)
			(end -0.12065 -0.2794)
			(stroke
				(width 0.1)
				(type default)
			)
			(layer "F.Fab")
		)
		(fp_line
			(start -0.12065 -0.2794)
			(end 0.12065 -0.2794)
			(stroke
				(width 0.1)
				(type default)
			)
			(layer "F.Fab")
		)
		(fp_line
			(start -0.12065 0.2794)
			(end -0.12065 0.3048)
			(stroke
				(width 0.1)
				(type default)
			)
			(layer "F.Fab")
		)
		(fp_line
			(start -0.12065 0.3048)
			(end -0.67945 0.3048)
			(stroke
				(width 0.1)
				(type default)
			)
			(layer "F.Fab")
		)
		(fp_line
			(start 0.120396 0.2794)
			(end -0.12065 0.2794)
			(stroke
				(width 0.1)
				(type default)
			)
			(layer "F.Fab")
		)
		(fp_line
			(start 0.120396 0.3048)
			(end 0.120396 0.2794)
			(stroke
				(width 0.1)
				(type default)
			)
			(layer "F.Fab")
		)
		(fp_line
			(start 0.12065 -0.3048)
			(end 0.67945 -0.3048)
			(stroke
				(width 0.1)
				(type default)
			)
			(layer "F.Fab")
		)
		(fp_line
			(start 0.12065 -0.2794)
			(end 0.12065 -0.3048)
			(stroke
				(width 0.1)
				(type default)
			)
			(layer "F.Fab")
		)
		(fp_line
			(start 0.67945 -0.3048)
			(end 0.67945 0.3048)
			(stroke
				(width 0.1)
				(type default)
			)
			(layer "F.Fab")
		)
		(fp_line
			(start 0.67945 0.3048)
			(end 0.120396 0.3048)
			(stroke
				(width 0.1)
				(type default)
			)
			(layer "F.Fab")
		)
		(pad "1" smd circle
			(at -0.40005 0)
			(size 0 0)
			(layers "F.Cu" "F.Mask" "F.Paste")
			(net "P12V_SSD1")
		)
		(pad "2" smd circle
			(at 0.40005 0)
			(size 0 0)
			(layers "F.Cu" "F.Mask" "F.Paste")
			(net "GND")
		)
	)
	(footprint ""
		(layer "F.Cu")
		(at 334.151478 -7.591552)
		(property "Reference" "U137"
			(at -1.360678 2.462022 0)
			(unlocked yes)
			(layer "F.SilkS")
			(effects
				(font
					(size 0.7874 0.5842)
					(thickness 0.1524)
				)
				(justify left)
			)
		)
		(property "Value" ""
			(at 0 0 0)
			(layer "F.Fab")
			(effects
				(font
					(size 1.27 1.27)
				)
			)
		)
		(duplicate_pad_numbers_are_jumpers no)
		(fp_line
			(start -1.463548 -1.549908)
			(end -0.787908 -1.549908)
			(stroke
				(width 0.1524)
				(type default)
			)
			(layer "F.SilkS")
		)
		(fp_line
			(start -1.463548 1.549908)
			(end -1.463548 -1.549908)
			(stroke
				(width 0.1524)
				(type default)
			)
			(layer "F.SilkS")
		)
		(fp_line
			(start -0.787908 -1.549908)
			(end 0 -0.762)
			(stroke
				(width 0.1524)
				(type default)
			)
			(layer "F.SilkS")
		)
		(fp_line
			(start 0 -0.762)
			(end 0.762 -1.549908)
			(stroke
				(width 0.1524)
				(type default)
			)
			(layer "F.SilkS")
		)
		(fp_line
			(start 0.762 -1.549908)
			(end 1.463548 -1.549908)
			(stroke
				(width 0.1524)
				(type default)
			)
			(layer "F.SilkS")
		)
		(fp_line
			(start 1.463548 -1.549908)
			(end 1.463548 1.549908)
			(stroke
				(width 0.1524)
				(type default)
			)
			(layer "F.SilkS")
		)
		(fp_line
			(start 1.463548 1.549908)
			(end -1.463548 1.549908)
			(stroke
				(width 0.1524)
				(type default)
			)
			(layer "F.SilkS")
		)
		(fp_poly
			(pts
				(xy -3.4798 -1.359916) (xy -2.86004 -1.050036) (xy -3.4798 -0.740156)
			)
			(stroke
				(width 0)
				(type default)
			)
			(fill yes)
			(layer "F.SilkS")
		)
		(fp_line
			(start -1.549908 -1.549908)
			(end 1.549908 -1.549908)
			(stroke
				(width 0.1)
				(type default)
			)
			(layer "F.Fab")
		)
		(fp_line
			(start -1.549908 1.549908)
			(end -1.549908 -1.549908)
			(stroke
				(width 0.1)
				(type default)
			)
			(layer "F.Fab")
		)
		(fp_line
			(start 1.549908 -1.549908)
			(end 1.549908 1.549908)
			(stroke
				(width 0.1)
				(type default)
			)
			(layer "F.Fab")
		)
		(fp_line
			(start 1.549908 1.549908)
			(end -1.549908 1.549908)
			(stroke
				(width 0.1)
				(type default)
			)
			(layer "F.Fab")
		)
		(fp_poly
			(pts
				(xy -3.4798 -1.359916) (xy -2.86004 -1.050036) (xy -3.4798 -0.740156)
			)
			(stroke
				(width 0)
				(type default)
			)
			(fill yes)
			(layer "F.Fab")
		)
		(pad "1" smd rect
			(at -2.175002 -1.050036 90)
			(size 0.6096 1.1684)
			(layers "F.Cu" "F.Mask" "F.Paste")
			(net "P3V3_SSD11")
		)
		(pad "2" smd rect
			(at -2.175002 -0.32512 90)
			(size 0.4318 1.1684)
			(layers "F.Cu" "F.Mask" "F.Paste")
			(net "SMB_ISO_SSD11_SCL")
		)
		(pad "3" smd rect
			(at -2.175002 0.32512 90)
			(size 0.4318 1.1684)
			(layers "F.Cu" "F.Mask" "F.Paste")
			(net "SMB_ISO_SSD11_SDA")
		)
		(pad "4" smd rect
			(at -2.175002 1.050036 90)
			(size 0.6096 1.1684)
			(layers "F.Cu" "F.Mask" "F.Paste")
			(net "GND")
		)
		(pad "5" smd rect
			(at 2.175002 1.050036 90)
			(size 0.6096 1.1684)
			(layers "F.Cu" "F.Mask" "F.Paste")
			(net "SMB_SSD11_ISO_EN")
		)
		(pad "6" smd rect
			(at 2.175002 0.32512 90)
			(size 0.4318 1.1684)
			(layers "F.Cu" "F.Mask" "F.Paste")
			(net "SMB_BIC_I2C9_MUX1_SSD11_R_SDA")
		)
		(pad "7" smd rect
			(at 2.175002 -0.32512 90)
			(size 0.4318 1.1684)
			(layers "F.Cu" "F.Mask" "F.Paste")
			(net "SMB_BIC_I2C9_MUX1_SSD11_R_SCL")
		)
		(pad "8" smd rect
			(at 2.175002 -1.050036 90)
			(size 0.6096 1.1684)
			(layers "F.Cu" "F.Mask" "F.Paste")
			(net "P3V3_AUX")
		)
	)
	(footprint ""
		(layer "F.Cu")
		(at 386.90804 -159.4104 180)
		(property "Reference" "R308"
			(at 0 0 180)
			(layer "F.SilkS")
			(hide yes)
			(effects
				(font
					(size 1.27 1.27)
				)
			)
		)
		(property "Value" ""
			(at 0 0 180)
			(layer "F.Fab")
			(effects
				(font
					(size 1.27 1.27)
				)
			)
		)
		(duplicate_pad_numbers_are_jumpers no)
		(fp_line
			(start 0.7874 0.4064)
			(end -0.7874 0.4064)
			(stroke
				(width 0.1524)
				(type default)
			)
			(layer "F.SilkS")
		)
		(fp_line
			(start 0.7874 -0.4064)
			(end 0.7874 0.4064)
			(stroke
				(width 0.1524)
				(type default)
			)
			(layer "F.SilkS")
		)
		(fp_line
			(start -0.7874 0.4064)
			(end -0.7874 -0.4064)
			(stroke
				(width 0.1524)
				(type default)
			)
			(layer "F.SilkS")
		)
		(fp_line
			(start -0.7874 -0.4064)
			(end 0.7874 -0.4064)
			(stroke
				(width 0.1524)
				(type default)
			)
			(layer "F.SilkS")
		)
		(fp_line
			(start 0.67945 0.3048)
			(end 0.120396 0.3048)
			(stroke
				(width 0.1)
				(type default)
			)
			(layer "F.Fab")
		)
		(fp_line
			(start 0.67945 -0.3048)
			(end 0.67945 0.3048)
			(stroke
				(width 0.1)
				(type default)
			)
			(layer "F.Fab")
		)
		(fp_line
			(start 0.12065 -0.2794)
			(end 0.12065 -0.3048)
			(stroke
				(width 0.1)
				(type default)
			)
			(layer "F.Fab")
		)
		(fp_line
			(start 0.12065 -0.3048)
			(end 0.67945 -0.3048)
			(stroke
				(width 0.1)
				(type default)
			)
			(layer "F.Fab")
		)
		(fp_line
			(start 0.120396 0.3048)
			(end 0.120396 0.2794)
			(stroke
				(width 0.1)
				(type default)
			)
			(layer "F.Fab")
		)
		(fp_line
			(start 0.120396 0.2794)
			(end -0.12065 0.2794)
			(stroke
				(width 0.1)
				(type default)
			)
			(layer "F.Fab")
		)
		(fp_line
			(start -0.12065 0.3048)
			(end -0.67945 0.3048)
			(stroke
				(width 0.1)
				(type default)
			)
			(layer "F.Fab")
		)
		(fp_line
			(start -0.12065 0.2794)
			(end -0.12065 0.3048)
			(stroke
				(width 0.1)
				(type default)
			)
			(layer "F.Fab")
		)
		(fp_line
			(start -0.12065 -0.2794)
			(end 0.12065 -0.2794)
			(stroke
				(width 0.1)
				(type default)
			)
			(layer "F.Fab")
		)
		(fp_line
			(start -0.12065 -0.305054)
			(end -0.12065 -0.2794)
			(stroke
				(width 0.1)
				(type default)
			)
			(layer "F.Fab")
		)
		(fp_line
			(start -0.67945 0.3048)
			(end -0.67945 -0.305054)
			(stroke
				(width 0.1)
				(type default)
			)
			(layer "F.Fab")
		)
		(fp_line
			(start -0.67945 -0.305054)
			(end -0.12065 -0.305054)
			(stroke
				(width 0.1)
				(type default)
			)
			(layer "F.Fab")
		)
		(pad "1" smd circle
			(at -0.40005 0 180)
			(size 0 0)
			(layers "F.Cu" "F.Mask" "F.Paste")
			(net "NIC6_MAIN_PWR_EN_R")
		)
		(pad "2" smd circle
			(at 0.40005 0 180)
			(size 0 0)
			(layers "F.Cu" "F.Mask" "F.Paste")
			(net "NIC6_MAIN_PWR_EN")
		)
	)
	(footprint ""
		(layer "F.Cu")
		(at 454.66889 -258.331208 -90)
		(property "Reference" "R6553"
			(at 0 0 270)
			(layer "F.SilkS")
			(hide yes)
			(effects
				(font
					(size 1.27 1.27)
				)
			)
		)
		(property "Value" ""
			(at 0 0 270)
			(layer "F.Fab")
			(effects
				(font
					(size 1.27 1.27)
				)
			)
		)
		(duplicate_pad_numbers_are_jumpers no)
		(fp_line
			(start -0.7874 0.4064)
			(end -0.7874 -0.4064)
			(stroke
				(width 0.1524)
				(type default)
			)
			(layer "F.SilkS")
		)
		(fp_line
			(start 0.7874 0.4064)
			(end -0.7874 0.4064)
			(stroke
				(width 0.1524)
				(type default)
			)
			(layer "F.SilkS")
		)
		(fp_line
			(start -0.7874 -0.4064)
			(end 0.7874 -0.4064)
			(stroke
				(width 0.1524)
				(type default)
			)
			(layer "F.SilkS")
		)
		(fp_line
			(start 0.7874 -0.4064)
			(end 0.7874 0.4064)
			(stroke
				(width 0.1524)
				(type default)
			)
			(layer "F.SilkS")
		)
		(fp_line
			(start -0.67945 0.3048)
			(end -0.67945 -0.305054)
			(stroke
				(width 0.1)
				(type default)
			)
			(layer "F.Fab")
		)
		(fp_line
			(start -0.12065 0.3048)
			(end -0.67945 0.3048)
			(stroke
				(width 0.1)
				(type default)
			)
			(layer "F.Fab")
		)
		(fp_line
			(start 0.120396 0.3048)
			(end 0.120396 0.2794)
			(stroke
				(width 0.1)
				(type default)
			)
			(layer "F.Fab")
		)
		(fp_line
			(start 0.67945 0.3048)
			(end 0.120396 0.3048)
			(stroke
				(width 0.1)
				(type default)
			)
			(layer "F.Fab")
		)
		(fp_line
			(start -0.12065 0.2794)
			(end -0.12065 0.3048)
			(stroke
				(width 0.1)
				(type default)
			)
			(layer "F.Fab")
		)
		(fp_line
			(start 0.120396 0.2794)
			(end -0.12065 0.2794)
			(stroke
				(width 0.1)
				(type default)
			)
			(layer "F.Fab")
		)
		(fp_line
			(start -0.12065 -0.2794)
			(end 0.12065 -0.2794)
			(stroke
				(width 0.1)
				(type default)
			)
			(layer "F.Fab")
		)
		(fp_line
			(start 0.12065 -0.2794)
			(end 0.12065 -0.3048)
			(stroke
				(width 0.1)
				(type default)
			)
			(layer "F.Fab")
		)
		(fp_line
			(start 0.12065 -0.3048)
			(end 0.67945 -0.3048)
			(stroke
				(width 0.1)
				(type default)
			)
			(layer "F.Fab")
		)
		(fp_line
			(start 0.67945 -0.3048)
			(end 0.67945 0.3048)
			(stroke
				(width 0.1)
				(type default)
			)
			(layer "F.Fab")
		)
		(fp_line
			(start -0.67945 -0.305054)
			(end -0.12065 -0.305054)
			(stroke
				(width 0.1)
				(type default)
			)
			(layer "F.Fab")
		)
		(fp_line
			(start -0.12065 -0.305054)
			(end -0.12065 -0.2794)
			(stroke
				(width 0.1)
				(type default)
			)
			(layer "F.Fab")
		)
		(pad "1" smd circle
			(at -0.40005 0 270)
			(size 0 0)
			(layers "F.Cu" "F.Mask" "F.Paste")
			(net "P1V25_SERDES_VDDPLL_PEX3")
		)
		(pad "2" smd circle
			(at 0.40005 0 270)
			(size 0 0)
			(layers "F.Cu" "F.Mask" "F.Paste")
			(net "P1V25_SERDES_VDDPLL_PEX3_C2")
		)
	)
	(footprint ""
		(layer "F.Cu")
		(at 226.115118 -5.999988)
		(property "Reference" "H63"
			(at -4.574794 -5.022342 0)
			(unlocked yes)
			(layer "F.SilkS")
			(effects
				(font
					(size 0.7874 0.5842)
					(thickness 0.1524)
				)
				(justify left)
			)
		)
		(property "Value" ""
			(at 0 0 0)
			(layer "F.Fab")
			(effects
				(font
					(size 1.27 1.27)
				)
			)
		)
		(duplicate_pad_numbers_are_jumpers no)
		(pad "1" thru_hole circle
			(at 0 0)
			(size 10.0076 10.0076)
			(drill 5.6134)
			(layers "*.Cu" "*.Mask")
			(remove_unused_layers no)
			(net "GND")
			(clearance -1.9431)
		)
	)
	(footprint ""
		(layer "F.Cu")
		(at 98.659442 -61.612526)
		(property "Reference" "PD33"
			(at -3.7084 -2.733548 0)
			(unlocked yes)
			(layer "F.SilkS")
			(effects
				(font
					(size 0.7874 0.5842)
					(thickness 0.1524)
				)
				(justify left)
			)
		)
		(property "Value" ""
			(at 0 0 0)
			(layer "F.Fab")
			(effects
				(font
					(size 1.27 1.27)
				)
			)
		)
		(duplicate_pad_numbers_are_jumpers no)
		(fp_line
			(start -3.656584 -1.970024)
			(end -3.656584 1.970024)
			(stroke
				(width 0.1524)
				(type default)
			)
			(layer "F.SilkS")
		)
		(fp_line
			(start -3.656584 1.970024)
			(end 4.240784 1.970024)
			(stroke
				(width 0.1524)
				(type default)
			)
			(layer "F.SilkS")
		)
		(fp_line
			(start 4.240784 -1.970024)
			(end -3.656584 -1.970024)
			(stroke
				(width 0.1524)
				(type default)
			)
			(layer "F.SilkS")
		)
		(fp_line
			(start 4.240784 1.970024)
			(end 4.240784 -1.970024)
			(stroke
				(width 0.1524)
				(type default)
			)
			(layer "F.SilkS")
		)
		(fp_poly
			(pts
				(xy 3.580384 1.970024) (xy 3.580384 -1.970024) (xy 4.240784 -1.970024) (xy 4.240784 1.970024)
			)
			(stroke
				(width 0)
				(type default)
			)
			(fill yes)
			(layer "F.SilkS")
		)
		(fp_line
			(start -2.3749 -1.970024)
			(end -2.3749 1.970024)
			(stroke
				(width 0.1)
				(type default)
			)
			(layer "F.Fab")
		)
		(fp_line
			(start -2.3749 1.970024)
			(end 2.3749 1.970024)
			(stroke
				(width 0.1)
				(type default)
			)
			(layer "F.Fab")
		)
		(fp_line
			(start 2.3749 -1.970024)
			(end -2.3749 -1.970024)
			(stroke
				(width 0.1)
				(type default)
			)
			(layer "F.Fab")
		)
		(fp_line
			(start 2.3749 1.970024)
			(end 2.3749 -1.970024)
			(stroke
				(width 0.1)
				(type default)
			)
			(layer "F.Fab")
		)
		(fp_text user "+"
			(at -4.9784 -0.23495 0)
			(unlocked yes)
			(layer "F.Fab")
			(effects
				(font
					(size 1.905 1.4224)
					(thickness 0.1524)
				)
				(justify left)
			)
		)
		(fp_text user "-"
			(at 4.1656 -0.23495 0)
			(unlocked yes)
			(layer "F.Fab")
			(effects
				(font
					(size 1.905 1.4224)
					(thickness 0.1524)
				)
				(justify left)
			)
		)
		(pad "A" smd rect
			(at -2.450084 0)
			(size 2.159 2.2606)
			(layers "F.Cu" "F.Mask" "F.Paste")
			(net "GND")
		)
		(pad "C" smd rect
			(at 2.450084 0)
			(size 2.159 2.2606)
			(layers "F.Cu" "F.Mask" "F.Paste")
			(net "P12V_AUX")
		)
	)
	(footprint ""
		(layer "F.Cu")
		(at 163.390072 -72.766682 90)
		(property "Reference" "PR7066"
			(at 0 0 90)
			(layer "F.SilkS")
			(hide yes)
			(effects
				(font
					(size 1.27 1.27)
				)
			)
		)
		(property "Value" ""
			(at 0 0 90)
			(layer "F.Fab")
			(effects
				(font
					(size 1.27 1.27)
				)
			)
		)
		(duplicate_pad_numbers_are_jumpers no)
		(fp_line
			(start 0.7874 -0.4064)
			(end 0.7874 0.4064)
			(stroke
				(width 0.1524)
				(type default)
			)
			(layer "F.SilkS")
		)
		(fp_line
			(start -0.7874 -0.4064)
			(end 0.7874 -0.4064)
			(stroke
				(width 0.1524)
				(type default)
			)
			(layer "F.SilkS")
		)
		(fp_line
			(start 0.7874 0.4064)
			(end -0.7874 0.4064)
			(stroke
				(width 0.1524)
				(type default)
			)
			(layer "F.SilkS")
		)
		(fp_line
			(start -0.7874 0.4064)
			(end -0.7874 -0.4064)
			(stroke
				(width 0.1524)
				(type default)
			)
			(layer "F.SilkS")
		)
		(fp_line
			(start -0.12065 -0.305054)
			(end -0.12065 -0.2794)
			(stroke
				(width 0.1)
				(type default)
			)
			(layer "F.Fab")
		)
		(fp_line
			(start -0.67945 -0.305054)
			(end -0.12065 -0.305054)
			(stroke
				(width 0.1)
				(type default)
			)
			(layer "F.Fab")
		)
		(fp_line
			(start 0.67945 -0.3048)
			(end 0.67945 0.3048)
			(stroke
				(width 0.1)
				(type default)
			)
			(layer "F.Fab")
		)
		(fp_line
			(start 0.12065 -0.3048)
			(end 0.67945 -0.3048)
			(stroke
				(width 0.1)
				(type default)
			)
			(layer "F.Fab")
		)
		(fp_line
			(start 0.12065 -0.2794)
			(end 0.12065 -0.3048)
			(stroke
				(width 0.1)
				(type default)
			)
			(layer "F.Fab")
		)
		(fp_line
			(start -0.12065 -0.2794)
			(end 0.12065 -0.2794)
			(stroke
				(width 0.1)
				(type default)
			)
			(layer "F.Fab")
		)
		(fp_line
			(start 0.120396 0.2794)
			(end -0.12065 0.2794)
			(stroke
				(width 0.1)
				(type default)
			)
			(layer "F.Fab")
		)
		(fp_line
			(start -0.12065 0.2794)
			(end -0.12065 0.3048)
			(stroke
				(width 0.1)
				(type default)
			)
			(layer "F.Fab")
		)
		(fp_line
			(start 0.67945 0.3048)
			(end 0.120396 0.3048)
			(stroke
				(width 0.1)
				(type default)
			)
			(layer "F.Fab")
		)
		(fp_line
			(start 0.120396 0.3048)
			(end 0.120396 0.2794)
			(stroke
				(width 0.1)
				(type default)
			)
			(layer "F.Fab")
		)
		(fp_line
			(start -0.12065 0.3048)
			(end -0.67945 0.3048)
			(stroke
				(width 0.1)
				(type default)
			)
			(layer "F.Fab")
		)
		(fp_line
			(start -0.67945 0.3048)
			(end -0.67945 -0.305054)
			(stroke
				(width 0.1)
				(type default)
			)
			(layer "F.Fab")
		)
		(pad "1" smd circle
			(at -0.40005 0 90)
			(size 0 0)
			(layers "F.Cu" "F.Mask" "F.Paste")
			(net "P12V_SSD5_CO_ILIMIT")
		)
		(pad "2" smd circle
			(at 0.40005 0 90)
			(size 0 0)
			(layers "F.Cu" "F.Mask" "F.Paste")
			(net "GND")
		)
	)
	(footprint ""
		(layer "F.Cu")
		(at 403.082506 -29.875734)
		(property "Reference" "PU133"
			(at -3.015996 -2.166366 90)
			(unlocked yes)
			(layer "F.SilkS")
			(effects
				(font
					(size 0.7874 0.5842)
					(thickness 0.1524)
				)
			)
		)
		(property "Value" ""
			(at 0 0 0)
			(layer "F.Fab")
			(effects
				(font
					(size 1.27 1.27)
				)
			)
		)
		(duplicate_pad_numbers_are_jumpers no)
		(fp_line
			(start -1.239774 -1.495298)
			(end 1.239774 -1.495298)
			(stroke
				(width 0.1524)
				(type default)
			)
			(layer "F.SilkS")
		)
		(fp_line
			(start -1.239774 1.495298)
			(end -1.239774 -1.495298)
			(stroke
				(width 0.1524)
				(type default)
			)
			(layer "F.SilkS")
		)
		(fp_line
			(start 1.239774 -1.495298)
			(end 1.239774 1.495298)
			(stroke
				(width 0.1524)
				(type default)
			)
			(layer "F.SilkS")
		)
		(fp_line
			(start 1.239774 1.495298)
			(end -1.239774 1.495298)
			(stroke
				(width 0.1524)
				(type default)
			)
			(layer "F.SilkS")
		)
		(fp_poly
			(pts
				(xy -1.965706 -1.257046) (xy -2.684018 -0.538734) (xy -1.60655 -0.179578)
			)
			(stroke
				(width 0)
				(type default)
			)
			(fill yes)
			(layer "F.SilkS")
		)
		(fp_line
			(start -0.8001 -1.050036)
			(end 0.8001 -1.050036)
			(stroke
				(width 0.1)
				(type default)
			)
			(layer "F.Fab")
		)
		(fp_line
			(start -0.8001 1.050036)
			(end -0.8001 -1.050036)
			(stroke
				(width 0.1)
				(type default)
			)
			(layer "F.Fab")
		)
		(fp_line
			(start 0.8001 -1.050036)
			(end 0.8001 1.050036)
			(stroke
				(width 0.1)
				(type default)
			)
			(layer "F.Fab")
		)
		(fp_line
			(start 0.8001 1.050036)
			(end -0.8001 1.050036)
			(stroke
				(width 0.1)
				(type default)
			)
			(layer "F.Fab")
		)
		(fp_poly
			(pts
				(xy -2.458974 -0.508) (xy -2.458974 0.508) (xy -1.442974 0)
			)
			(stroke
				(width 0)
				(type default)
			)
			(fill yes)
			(layer "F.Fab")
		)
		(pad "1_2" smd circle
			(at -0.374904 0 90)
			(size 0 0)
			(layers "F.Cu" "F.Mask" "F.Paste")
			(net "P3V3_AUX")
		)
		(pad "3" smd rect
			(at -0.499872 0.999998)
			(size 0.254 0.7112)
			(layers "F.Cu" "F.Mask" "F.Paste")
			(net "GND")
		)
		(pad "4" smd rect
			(at 0 0.999998)
			(size 0.254 0.7112)
			(layers "F.Cu" "F.Mask" "F.Paste")
			(net "P3V3_SSD14_CO_ILIMIT")
		)
		(pad "5" smd rect
			(at 0.499872 0.999998)
			(size 0.254 0.7112)
			(layers "F.Cu" "F.Mask" "F.Paste")
			(net "P3V3_SSD14_CO_MODE")
		)
		(pad "6_7" smd circle
			(at 0.374904 0 270)
			(size 0 0)
			(layers "F.Cu" "F.Mask" "F.Paste")
			(net "P3V3_SSD14")
		)
		(pad "8" smd rect
			(at 0.499872 -0.999998)
			(size 0.254 0.7112)
			(layers "F.Cu" "F.Mask" "F.Paste")
			(net "P3V3_SSD14_CO_GATE")
		)
		(pad "9" smd rect
			(at 0 -0.999998)
			(size 0.254 0.7112)
			(layers "F.Cu" "F.Mask" "F.Paste")
			(net "P3V3_SSD14_CO_EN")
		)
		(pad "10" smd rect
			(at -0.499872 -0.999998)
			(size 0.254 0.7112)
			(layers "F.Cu" "F.Mask" "F.Paste")
			(net "P3V3_SSD14_CO_DV_DT")
		)
	)
	(footprint ""
		(layer "F.Cu")
		(at 407.295096 -100.766372 180)
		(property "Reference" "R384"
			(at 0 0 180)
			(layer "F.SilkS")
			(hide yes)
			(effects
				(font
					(size 1.27 1.27)
				)
			)
		)
		(property "Value" ""
			(at 0 0 180)
			(layer "F.Fab")
			(effects
				(font
					(size 1.27 1.27)
				)
			)
		)
		(duplicate_pad_numbers_are_jumpers no)
		(fp_line
			(start 0.7874 0.4064)
			(end -0.7874 0.4064)
			(stroke
				(width 0.1524)
				(type default)
			)
			(layer "F.SilkS")
		)
		(fp_line
			(start 0.7874 -0.4064)
			(end 0.7874 0.4064)
			(stroke
				(width 0.1524)
				(type default)
			)
			(layer "F.SilkS")
		)
		(fp_line
			(start -0.7874 0.4064)
			(end -0.7874 -0.4064)
			(stroke
				(width 0.1524)
				(type default)
			)
			(layer "F.SilkS")
		)
		(fp_line
			(start -0.7874 -0.4064)
			(end 0.7874 -0.4064)
			(stroke
				(width 0.1524)
				(type default)
			)
			(layer "F.SilkS")
		)
		(fp_line
			(start 0.67945 0.3048)
			(end 0.120396 0.3048)
			(stroke
				(width 0.1)
				(type default)
			)
			(layer "F.Fab")
		)
		(fp_line
			(start 0.67945 -0.3048)
			(end 0.67945 0.3048)
			(stroke
				(width 0.1)
				(type default)
			)
			(layer "F.Fab")
		)
		(fp_line
			(start 0.12065 -0.2794)
			(end 0.12065 -0.3048)
			(stroke
				(width 0.1)
				(type default)
			)
			(layer "F.Fab")
		)
		(fp_line
			(start 0.12065 -0.3048)
			(end 0.67945 -0.3048)
			(stroke
				(width 0.1)
				(type default)
			)
			(layer "F.Fab")
		)
		(fp_line
			(start 0.120396 0.3048)
			(end 0.120396 0.2794)
			(stroke
				(width 0.1)
				(type default)
			)
			(layer "F.Fab")
		)
		(fp_line
			(start 0.120396 0.2794)
			(end -0.12065 0.2794)
			(stroke
				(width 0.1)
				(type default)
			)
			(layer "F.Fab")
		)
		(fp_line
			(start -0.12065 0.3048)
			(end -0.67945 0.3048)
			(stroke
				(width 0.1)
				(type default)
			)
			(layer "F.Fab")
		)
		(fp_line
			(start -0.12065 0.2794)
			(end -0.12065 0.3048)
			(stroke
				(width 0.1)
				(type default)
			)
			(layer "F.Fab")
		)
		(fp_line
			(start -0.12065 -0.2794)
			(end 0.12065 -0.2794)
			(stroke
				(width 0.1)
				(type default)
			)
			(layer "F.Fab")
		)
		(fp_line
			(start -0.12065 -0.305054)
			(end -0.12065 -0.2794)
			(stroke
				(width 0.1)
				(type default)
			)
			(layer "F.Fab")
		)
		(fp_line
			(start -0.67945 0.3048)
			(end -0.67945 -0.305054)
			(stroke
				(width 0.1)
				(type default)
			)
			(layer "F.Fab")
		)
		(fp_line
			(start -0.67945 -0.305054)
			(end -0.12065 -0.305054)
			(stroke
				(width 0.1)
				(type default)
			)
			(layer "F.Fab")
		)
		(pad "1" smd circle
			(at -0.40005 0 180)
			(size 0 0)
			(layers "F.Cu" "F.Mask" "F.Paste")
			(net "NIC7_SLOT_ID1")
		)
		(pad "2" smd circle
			(at 0.40005 0 180)
			(size 0 0)
			(layers "F.Cu" "F.Mask" "F.Paste")
			(net "P3V3_NIC7")
		)
	)
	(footprint ""
		(layer "F.Cu")
		(at 24.342344 -252.356874 -90)
		(property "Reference" "R1215"
			(at 0 0 270)
			(layer "F.SilkS")
			(hide yes)
			(effects
				(font
					(size 1.27 1.27)
				)
			)
		)
		(property "Value" ""
			(at 0 0 270)
			(layer "F.Fab")
			(effects
				(font
					(size 1.27 1.27)
				)
			)
		)
		(duplicate_pad_numbers_are_jumpers no)
		(fp_line
			(start -0.7874 0.4064)
			(end -0.7874 -0.4064)
			(stroke
				(width 0.1524)
				(type default)
			)
			(layer "F.SilkS")
		)
		(fp_line
			(start 0.7874 0.4064)
			(end -0.7874 0.4064)
			(stroke
				(width 0.1524)
				(type default)
			)
			(layer "F.SilkS")
		)
		(fp_line
			(start -0.7874 -0.4064)
			(end 0.7874 -0.4064)
			(stroke
				(width 0.1524)
				(type default)
			)
			(layer "F.SilkS")
		)
		(fp_line
			(start 0.7874 -0.4064)
			(end 0.7874 0.4064)
			(stroke
				(width 0.1524)
				(type default)
			)
			(layer "F.SilkS")
		)
		(fp_line
			(start -0.67945 0.3048)
			(end -0.67945 -0.305054)
			(stroke
				(width 0.1)
				(type default)
			)
			(layer "F.Fab")
		)
		(fp_line
			(start -0.12065 0.3048)
			(end -0.67945 0.3048)
			(stroke
				(width 0.1)
				(type default)
			)
			(layer "F.Fab")
		)
		(fp_line
			(start 0.120396 0.3048)
			(end 0.120396 0.2794)
			(stroke
				(width 0.1)
				(type default)
			)
			(layer "F.Fab")
		)
		(fp_line
			(start 0.67945 0.3048)
			(end 0.120396 0.3048)
			(stroke
				(width 0.1)
				(type default)
			)
			(layer "F.Fab")
		)
		(fp_line
			(start -0.12065 0.2794)
			(end -0.12065 0.3048)
			(stroke
				(width 0.1)
				(type default)
			)
			(layer "F.Fab")
		)
		(fp_line
			(start 0.120396 0.2794)
			(end -0.12065 0.2794)
			(stroke
				(width 0.1)
				(type default)
			)
			(layer "F.Fab")
		)
		(fp_line
			(start -0.12065 -0.2794)
			(end 0.12065 -0.2794)
			(stroke
				(width 0.1)
				(type default)
			)
			(layer "F.Fab")
		)
		(fp_line
			(start 0.12065 -0.2794)
			(end 0.12065 -0.3048)
			(stroke
				(width 0.1)
				(type default)
			)
			(layer "F.Fab")
		)
		(fp_line
			(start 0.12065 -0.3048)
			(end 0.67945 -0.3048)
			(stroke
				(width 0.1)
				(type default)
			)
			(layer "F.Fab")
		)
		(fp_line
			(start 0.67945 -0.3048)
			(end 0.67945 0.3048)
			(stroke
				(width 0.1)
				(type default)
			)
			(layer "F.Fab")
		)
		(fp_line
			(start -0.67945 -0.305054)
			(end -0.12065 -0.305054)
			(stroke
				(width 0.1)
				(type default)
			)
			(layer "F.Fab")
		)
		(fp_line
			(start -0.12065 -0.305054)
			(end -0.12065 -0.2794)
			(stroke
				(width 0.1)
				(type default)
			)
			(layer "F.Fab")
		)
		(pad "1" smd circle
			(at -0.40005 0 270)
			(size 0 0)
			(layers "F.Cu" "F.Mask" "F.Paste")
			(net "GND")
		)
		(pad "2" smd circle
			(at 0.40005 0 270)
			(size 0 0)
			(layers "F.Cu" "F.Mask" "F.Paste")
			(net "PEX0_MODE_SEL9")
		)
	)
	(footprint ""
		(layer "F.Cu")
		(at 402.25218 -350.098614 90)
		(property "Reference" "C746"
			(at 0 0 90)
			(layer "F.SilkS")
			(hide yes)
			(effects
				(font
					(size 1.27 1.27)
				)
			)
		)
		(property "Value" ""
			(at 0 0 90)
			(layer "F.Fab")
			(effects
				(font
					(size 1.27 1.27)
				)
			)
		)
		(duplicate_pad_numbers_are_jumpers no)
		(fp_line
			(start 0.299974 -0.150114)
			(end 0.299974 0.150114)
			(stroke
				(width 0.1)
				(type default)
			)
			(layer "F.Fab")
		)
		(fp_line
			(start -0.299974 -0.150114)
			(end 0.299974 -0.150114)
			(stroke
				(width 0.1)
				(type default)
			)
			(layer "F.Fab")
		)
		(fp_line
			(start 0.299974 0.150114)
			(end -0.299974 0.150114)
			(stroke
				(width 0.1)
				(type default)
			)
			(layer "F.Fab")
		)
		(fp_line
			(start -0.299974 0.150114)
			(end -0.299974 -0.150114)
			(stroke
				(width 0.1)
				(type default)
			)
			(layer "F.Fab")
		)
		(pad "1" smd rect
			(at -0.2667 0 90)
			(size 0.3048 0.381)
			(layers "F.Cu" "F.Mask" "F.Paste")
			(net "P5E_PEX3_STN5_TX_DP<87>")
		)
		(pad "2" smd rect
			(at 0.2667 0 90)
			(size 0.3048 0.381)
			(layers "F.Cu" "F.Mask" "F.Paste")
			(net "P5E_PEX3_STN5_TX_C_DP<87>")
		)
	)
	(footprint ""
		(layer "F.Cu")
		(at 304.634392 -30.03169 180)
		(property "Reference" "C508"
			(at 0 0 180)
			(layer "F.SilkS")
			(hide yes)
			(effects
				(font
					(size 1.27 1.27)
				)
			)
		)
		(property "Value" ""
			(at 0 0 180)
			(layer "F.Fab")
			(effects
				(font
					(size 1.27 1.27)
				)
			)
		)
		(duplicate_pad_numbers_are_jumpers no)
		(fp_line
			(start 0.299974 0.150114)
			(end -0.299974 0.150114)
			(stroke
				(width 0.1)
				(type default)
			)
			(layer "F.Fab")
		)
		(fp_line
			(start 0.299974 -0.150114)
			(end 0.299974 0.150114)
			(stroke
				(width 0.1)
				(type default)
			)
			(layer "F.Fab")
		)
		(fp_line
			(start -0.299974 0.150114)
			(end -0.299974 -0.150114)
			(stroke
				(width 0.1)
				(type default)
			)
			(layer "F.Fab")
		)
		(fp_line
			(start -0.299974 -0.150114)
			(end 0.299974 -0.150114)
			(stroke
				(width 0.1)
				(type default)
			)
			(layer "F.Fab")
		)
		(pad "1" smd rect
			(at -0.2667 0 180)
			(size 0.3048 0.381)
			(layers "F.Cu" "F.Mask" "F.Paste")
			(net "P5E_PEX2_STN2_TX_DN<37>")
		)
		(pad "2" smd rect
			(at 0.2667 0 180)
			(size 0.3048 0.381)
			(layers "F.Cu" "F.Mask" "F.Paste")
			(net "P5E_PEX2_STN2_TX_C_DN<37>")
		)
	)
	(footprint ""
		(layer "F.Cu")
		(at 304.634392 -30.94609 180)
		(property "Reference" "C507"
			(at 0 0 180)
			(layer "F.SilkS")
			(hide yes)
			(effects
				(font
					(size 1.27 1.27)
				)
			)
		)
		(property "Value" ""
			(at 0 0 180)
			(layer "F.Fab")
			(effects
				(font
					(size 1.27 1.27)
				)
			)
		)
		(duplicate_pad_numbers_are_jumpers no)
		(fp_line
			(start 0.299974 0.150114)
			(end -0.299974 0.150114)
			(stroke
				(width 0.1)
				(type default)
			)
			(layer "F.Fab")
		)
		(fp_line
			(start 0.299974 -0.150114)
			(end 0.299974 0.150114)
			(stroke
				(width 0.1)
				(type default)
			)
			(layer "F.Fab")
		)
		(fp_line
			(start -0.299974 0.150114)
			(end -0.299974 -0.150114)
			(stroke
				(width 0.1)
				(type default)
			)
			(layer "F.Fab")
		)
		(fp_line
			(start -0.299974 -0.150114)
			(end 0.299974 -0.150114)
			(stroke
				(width 0.1)
				(type default)
			)
			(layer "F.Fab")
		)
		(pad "1" smd rect
			(at -0.2667 0 180)
			(size 0.3048 0.381)
			(layers "F.Cu" "F.Mask" "F.Paste")
			(net "P5E_PEX2_STN2_TX_DP<37>")
		)
		(pad "2" smd rect
			(at 0.2667 0 180)
			(size 0.3048 0.381)
			(layers "F.Cu" "F.Mask" "F.Paste")
			(net "P5E_PEX2_STN2_TX_C_DP<37>")
		)
	)
	(footprint ""
		(layer "F.Cu")
		(at 271.03197 -147.969224 90)
		(property "Reference" "C906"
			(at 0 0 90)
			(layer "F.SilkS")
			(hide yes)
			(effects
				(font
					(size 1.27 1.27)
				)
			)
		)
		(property "Value" ""
			(at 0 0 90)
			(layer "F.Fab")
			(effects
				(font
					(size 1.27 1.27)
				)
			)
		)
		(duplicate_pad_numbers_are_jumpers no)
		(fp_line
			(start 1.524 -0.762)
			(end 1.524 0.762)
			(stroke
				(width 0.1524)
				(type default)
			)
			(layer "F.SilkS")
		)
		(fp_line
			(start -1.524 -0.762)
			(end 1.524 -0.762)
			(stroke
				(width 0.1524)
				(type default)
			)
			(layer "F.SilkS")
		)
		(fp_line
			(start 1.524 0.762)
			(end -1.524 0.762)
			(stroke
				(width 0.1524)
				(type default)
			)
			(layer "F.SilkS")
		)
		(fp_line
			(start -1.524 0.762)
			(end -1.524 -0.762)
			(stroke
				(width 0.1524)
				(type default)
			)
			(layer "F.SilkS")
		)
		(fp_line
			(start 1.1049 -0.724916)
			(end -1.1049 -0.724916)
			(stroke
				(width 0.1)
				(type default)
			)
			(layer "F.Fab")
		)
		(fp_line
			(start -1.1049 -0.724916)
			(end -1.1049 0.724916)
			(stroke
				(width 0.1)
				(type default)
			)
			(layer "F.Fab")
		)
		(fp_line
			(start 1.1049 0.724916)
			(end 1.1049 -0.724916)
			(stroke
				(width 0.1)
				(type default)
			)
			(layer "F.Fab")
		)
		(fp_line
			(start -1.1049 0.724916)
			(end 1.1049 0.724916)
			(stroke
				(width 0.1)
				(type default)
			)
			(layer "F.Fab")
		)
		(pad "1" smd rect
			(at -0.889 0 270)
			(size 1.016 1.27)
			(layers "F.Cu" "F.Mask" "F.Paste")
			(net "P12V_NIC4")
		)
		(pad "2" smd rect
			(at 0.889 0 270)
			(size 1.016 1.27)
			(layers "F.Cu" "F.Mask" "F.Paste")
			(net "GND")
		)
	)
	(footprint ""
		(layer "F.Cu")
		(at 115.279424 -170.951652)
		(property "Reference" "PC25"
			(at 0 0 0)
			(layer "F.SilkS")
			(hide yes)
			(effects
				(font
					(size 1.27 1.27)
				)
			)
		)
		(property "Value" ""
			(at 0 0 0)
			(layer "F.Fab")
			(effects
				(font
					(size 1.27 1.27)
				)
			)
		)
		(duplicate_pad_numbers_are_jumpers no)
		(fp_line
			(start -3.400044 -2.146046)
			(end -3.400044 -0.9398)
			(stroke
				(width 0.1524)
				(type default)
			)
			(layer "F.SilkS")
		)
		(fp_line
			(start -3.400044 2.146046)
			(end -3.400044 0.9398)
			(stroke
				(width 0.1524)
				(type default)
			)
			(layer "F.SilkS")
		)
		(fp_line
			(start -2.146046 -3.400044)
			(end -3.400044 -2.146046)
			(stroke
				(width 0.1524)
				(type default)
			)
			(layer "F.SilkS")
		)
		(fp_line
			(start -2.146046 3.400044)
			(end -3.400044 2.146046)
			(stroke
				(width 0.1524)
				(type default)
			)
			(layer "F.SilkS")
		)
		(fp_line
			(start 3.400044 -3.400044)
			(end -2.146046 -3.400044)
			(stroke
				(width 0.1524)
				(type default)
			)
			(layer "F.SilkS")
		)
		(fp_line
			(start 3.400044 -0.9398)
			(end 3.400044 -3.400044)
			(stroke
				(width 0.1524)
				(type default)
			)
			(layer "F.SilkS")
		)
		(fp_line
			(start 3.400044 0.9398)
			(end 3.400044 3.400044)
			(stroke
				(width 0.1524)
				(type default)
			)
			(layer "F.SilkS")
		)
		(fp_line
			(start 3.400044 3.400044)
			(end -2.146046 3.400044)
			(stroke
				(width 0.1524)
				(type default)
			)
			(layer "F.SilkS")
		)
		(fp_line
			(start -3.400044 -3.400044)
			(end -3.400044 3.400044)
			(stroke
				(width 0.1)
				(type default)
			)
			(layer "F.Fab")
		)
		(fp_line
			(start -3.400044 3.400044)
			(end 3.400044 3.400044)
			(stroke
				(width 0.1)
				(type default)
			)
			(layer "F.Fab")
		)
		(fp_line
			(start 3.400044 -3.400044)
			(end -3.400044 -3.400044)
			(stroke
				(width 0.1)
				(type default)
			)
			(layer "F.Fab")
		)
		(fp_line
			(start 3.400044 3.400044)
			(end 3.400044 -3.400044)
			(stroke
				(width 0.1)
				(type default)
			)
			(layer "F.Fab")
		)
		(pad "1" smd rect
			(at -2.70002 0 270)
			(size 1.6002 3.5052)
			(layers "F.Cu" "F.Mask" "F.Paste")
			(net "SW_P12V_P3V3_AUX_FLT")
		)
		(pad "2" smd rect
			(at 2.70002 0 270)
			(size 1.6002 3.5052)
			(layers "F.Cu" "F.Mask" "F.Paste")
			(net "GND")
		)
	)
	(footprint ""
		(layer "F.Cu")
		(at 270.799814 -150.263352 180)
		(property "Reference" "R219"
			(at 0 0 180)
			(layer "F.SilkS")
			(hide yes)
			(effects
				(font
					(size 1.27 1.27)
				)
			)
		)
		(property "Value" ""
			(at 0 0 180)
			(layer "F.Fab")
			(effects
				(font
					(size 1.27 1.27)
				)
			)
		)
		(duplicate_pad_numbers_are_jumpers no)
		(fp_line
			(start 0.7874 0.4064)
			(end -0.7874 0.4064)
			(stroke
				(width 0.1524)
				(type default)
			)
			(layer "F.SilkS")
		)
		(fp_line
			(start 0.7874 -0.4064)
			(end 0.7874 0.4064)
			(stroke
				(width 0.1524)
				(type default)
			)
			(layer "F.SilkS")
		)
		(fp_line
			(start -0.7874 0.4064)
			(end -0.7874 -0.4064)
			(stroke
				(width 0.1524)
				(type default)
			)
			(layer "F.SilkS")
		)
		(fp_line
			(start -0.7874 -0.4064)
			(end 0.7874 -0.4064)
			(stroke
				(width 0.1524)
				(type default)
			)
			(layer "F.SilkS")
		)
		(fp_line
			(start 0.67945 0.3048)
			(end 0.120396 0.3048)
			(stroke
				(width 0.1)
				(type default)
			)
			(layer "F.Fab")
		)
		(fp_line
			(start 0.67945 -0.3048)
			(end 0.67945 0.3048)
			(stroke
				(width 0.1)
				(type default)
			)
			(layer "F.Fab")
		)
		(fp_line
			(start 0.12065 -0.2794)
			(end 0.12065 -0.3048)
			(stroke
				(width 0.1)
				(type default)
			)
			(layer "F.Fab")
		)
		(fp_line
			(start 0.12065 -0.3048)
			(end 0.67945 -0.3048)
			(stroke
				(width 0.1)
				(type default)
			)
			(layer "F.Fab")
		)
		(fp_line
			(start 0.120396 0.3048)
			(end 0.120396 0.2794)
			(stroke
				(width 0.1)
				(type default)
			)
			(layer "F.Fab")
		)
		(fp_line
			(start 0.120396 0.2794)
			(end -0.12065 0.2794)
			(stroke
				(width 0.1)
				(type default)
			)
			(layer "F.Fab")
		)
		(fp_line
			(start -0.12065 0.3048)
			(end -0.67945 0.3048)
			(stroke
				(width 0.1)
				(type default)
			)
			(layer "F.Fab")
		)
		(fp_line
			(start -0.12065 0.2794)
			(end -0.12065 0.3048)
			(stroke
				(width 0.1)
				(type default)
			)
			(layer "F.Fab")
		)
		(fp_line
			(start -0.12065 -0.2794)
			(end 0.12065 -0.2794)
			(stroke
				(width 0.1)
				(type default)
			)
			(layer "F.Fab")
		)
		(fp_line
			(start -0.12065 -0.305054)
			(end -0.12065 -0.2794)
			(stroke
				(width 0.1)
				(type default)
			)
			(layer "F.Fab")
		)
		(fp_line
			(start -0.67945 0.3048)
			(end -0.67945 -0.305054)
			(stroke
				(width 0.1)
				(type default)
			)
			(layer "F.Fab")
		)
		(fp_line
			(start -0.67945 -0.305054)
			(end -0.12065 -0.305054)
			(stroke
				(width 0.1)
				(type default)
			)
			(layer "F.Fab")
		)
		(pad "1" smd circle
			(at -0.40005 0 180)
			(size 0 0)
			(layers "F.Cu" "F.Mask" "F.Paste")
			(net "NCSI_NIC4_CRS_DV")
		)
		(pad "2" smd circle
			(at 0.40005 0 180)
			(size 0 0)
			(layers "F.Cu" "F.Mask" "F.Paste")
			(net "GND")
		)
	)
	(footprint ""
		(layer "F.Cu")
		(at 271.480534 -110.088934)
		(property "Reference" "C473"
			(at 0 0 0)
			(layer "F.SilkS")
			(hide yes)
			(effects
				(font
					(size 1.27 1.27)
				)
			)
		)
		(property "Value" ""
			(at 0 0 0)
			(layer "F.Fab")
			(effects
				(font
					(size 1.27 1.27)
				)
			)
		)
		(duplicate_pad_numbers_are_jumpers no)
		(fp_line
			(start -0.299974 -0.150114)
			(end 0.299974 -0.150114)
			(stroke
				(width 0.1)
				(type default)
			)
			(layer "F.Fab")
		)
		(fp_line
			(start -0.299974 0.150114)
			(end -0.299974 -0.150114)
			(stroke
				(width 0.1)
				(type default)
			)
			(layer "F.Fab")
		)
		(fp_line
			(start 0.299974 -0.150114)
			(end 0.299974 0.150114)
			(stroke
				(width 0.1)
				(type default)
			)
			(layer "F.Fab")
		)
		(fp_line
			(start 0.299974 0.150114)
			(end -0.299974 0.150114)
			(stroke
				(width 0.1)
				(type default)
			)
			(layer "F.Fab")
		)
		(pad "1" smd rect
			(at -0.2667 0)
			(size 0.3048 0.381)
			(layers "F.Cu" "F.Mask" "F.Paste")
			(net "P5E_PEX2_STN1_TX_DP<22>")
		)
		(pad "2" smd rect
			(at 0.2667 0)
			(size 0.3048 0.381)
			(layers "F.Cu" "F.Mask" "F.Paste")
			(net "P5E_PEX2_STN1_TX_C_DP<22>")
		)
	)
	(footprint ""
		(layer "F.Cu")
		(at 383.598674 -137.259314 -90)
		(property "Reference" "C944"
			(at 0 0 270)
			(layer "F.SilkS")
			(hide yes)
			(effects
				(font
					(size 1.27 1.27)
				)
			)
		)
		(property "Value" ""
			(at 0 0 270)
			(layer "F.Fab")
			(effects
				(font
					(size 1.27 1.27)
				)
			)
		)
		(duplicate_pad_numbers_are_jumpers no)
		(fp_line
			(start -0.7874 0.4064)
			(end -0.7874 -0.4064)
			(stroke
				(width 0.1524)
				(type default)
			)
			(layer "F.SilkS")
		)
		(fp_line
			(start 0.7874 0.4064)
			(end -0.7874 0.4064)
			(stroke
				(width 0.1524)
				(type default)
			)
			(layer "F.SilkS")
		)
		(fp_line
			(start -0.7874 -0.4064)
			(end 0.7874 -0.4064)
			(stroke
				(width 0.1524)
				(type default)
			)
			(layer "F.SilkS")
		)
		(fp_line
			(start 0.7874 -0.4064)
			(end 0.7874 0.4064)
			(stroke
				(width 0.1524)
				(type default)
			)
			(layer "F.SilkS")
		)
		(fp_line
			(start -0.67945 0.3048)
			(end -0.67945 -0.305054)
			(stroke
				(width 0.1)
				(type default)
			)
			(layer "F.Fab")
		)
		(fp_line
			(start -0.12065 0.3048)
			(end -0.67945 0.3048)
			(stroke
				(width 0.1)
				(type default)
			)
			(layer "F.Fab")
		)
		(fp_line
			(start 0.120396 0.3048)
			(end 0.120396 0.2794)
			(stroke
				(width 0.1)
				(type default)
			)
			(layer "F.Fab")
		)
		(fp_line
			(start 0.67945 0.3048)
			(end 0.120396 0.3048)
			(stroke
				(width 0.1)
				(type default)
			)
			(layer "F.Fab")
		)
		(fp_line
			(start -0.12065 0.2794)
			(end -0.12065 0.3048)
			(stroke
				(width 0.1)
				(type default)
			)
			(layer "F.Fab")
		)
		(fp_line
			(start 0.120396 0.2794)
			(end -0.12065 0.2794)
			(stroke
				(width 0.1)
				(type default)
			)
			(layer "F.Fab")
		)
		(fp_line
			(start -0.12065 -0.2794)
			(end 0.12065 -0.2794)
			(stroke
				(width 0.1)
				(type default)
			)
			(layer "F.Fab")
		)
		(fp_line
			(start 0.12065 -0.2794)
			(end 0.12065 -0.3048)
			(stroke
				(width 0.1)
				(type default)
			)
			(layer "F.Fab")
		)
		(fp_line
			(start 0.12065 -0.3048)
			(end 0.67945 -0.3048)
			(stroke
				(width 0.1)
				(type default)
			)
			(layer "F.Fab")
		)
		(fp_line
			(start 0.67945 -0.3048)
			(end 0.67945 0.3048)
			(stroke
				(width 0.1)
				(type default)
			)
			(layer "F.Fab")
		)
		(fp_line
			(start -0.67945 -0.305054)
			(end -0.12065 -0.305054)
			(stroke
				(width 0.1)
				(type default)
			)
			(layer "F.Fab")
		)
		(fp_line
			(start -0.12065 -0.305054)
			(end -0.12065 -0.2794)
			(stroke
				(width 0.1)
				(type default)
			)
			(layer "F.Fab")
		)
		(pad "1" smd circle
			(at -0.40005 0 270)
			(size 0 0)
			(layers "F.Cu" "F.Mask" "F.Paste")
			(net "P3V3_NIC6")
		)
		(pad "2" smd circle
			(at 0.40005 0 270)
			(size 0 0)
			(layers "F.Cu" "F.Mask" "F.Paste")
			(net "GND")
		)
	)
	(footprint ""
		(layer "F.Cu")
		(at 242.730528 -146.099276 180)
		(property "Reference" "PC802"
			(at 0 0 180)
			(layer "F.SilkS")
			(hide yes)
			(effects
				(font
					(size 1.27 1.27)
				)
			)
		)
		(property "Value" ""
			(at 0 0 180)
			(layer "F.Fab")
			(effects
				(font
					(size 1.27 1.27)
				)
			)
		)
		(duplicate_pad_numbers_are_jumpers no)
		(fp_line
			(start 1.524 0.762)
			(end -1.524 0.762)
			(stroke
				(width 0.1524)
				(type default)
			)
			(layer "F.SilkS")
		)
		(fp_line
			(start 1.524 -0.762)
			(end 1.524 0.762)
			(stroke
				(width 0.1524)
				(type default)
			)
			(layer "F.SilkS")
		)
		(fp_line
			(start -1.524 0.762)
			(end -1.524 -0.762)
			(stroke
				(width 0.1524)
				(type default)
			)
			(layer "F.SilkS")
		)
		(fp_line
			(start -1.524 -0.762)
			(end 1.524 -0.762)
			(stroke
				(width 0.1524)
				(type default)
			)
			(layer "F.SilkS")
		)
		(fp_line
			(start 1.1049 0.724916)
			(end 1.1049 -0.724916)
			(stroke
				(width 0.1)
				(type default)
			)
			(layer "F.Fab")
		)
		(fp_line
			(start 1.1049 -0.724916)
			(end -1.1049 -0.724916)
			(stroke
				(width 0.1)
				(type default)
			)
			(layer "F.Fab")
		)
		(fp_line
			(start -1.1049 0.724916)
			(end 1.1049 0.724916)
			(stroke
				(width 0.1)
				(type default)
			)
			(layer "F.Fab")
		)
		(fp_line
			(start -1.1049 -0.724916)
			(end -1.1049 0.724916)
			(stroke
				(width 0.1)
				(type default)
			)
			(layer "F.Fab")
		)
		(pad "1" smd rect
			(at -0.889 0)
			(size 1.016 1.27)
			(layers "F.Cu" "F.Mask" "F.Paste")
			(net "P12V_NIC4_R")
		)
		(pad "2" smd rect
			(at 0.889 0)
			(size 1.016 1.27)
			(layers "F.Cu" "F.Mask" "F.Paste")
			(net "GND")
		)
	)
	(footprint ""
		(layer "F.Cu")
		(at 261.07517 -63.086234)
		(property "Reference" "R5999"
			(at 0 0 0)
			(layer "F.SilkS")
			(hide yes)
			(effects
				(font
					(size 1.27 1.27)
				)
			)
		)
		(property "Value" ""
			(at 0 0 0)
			(layer "F.Fab")
			(effects
				(font
					(size 1.27 1.27)
				)
			)
		)
		(duplicate_pad_numbers_are_jumpers no)
		(fp_line
			(start -0.7874 -0.4064)
			(end 0.7874 -0.4064)
			(stroke
				(width 0.1524)
				(type default)
			)
			(layer "F.SilkS")
		)
		(fp_line
			(start -0.7874 0.4064)
			(end -0.7874 -0.4064)
			(stroke
				(width 0.1524)
				(type default)
			)
			(layer "F.SilkS")
		)
		(fp_line
			(start 0.7874 -0.4064)
			(end 0.7874 0.4064)
			(stroke
				(width 0.1524)
				(type default)
			)
			(layer "F.SilkS")
		)
		(fp_line
			(start 0.7874 0.4064)
			(end -0.7874 0.4064)
			(stroke
				(width 0.1524)
				(type default)
			)
			(layer "F.SilkS")
		)
		(fp_line
			(start -0.67945 -0.305054)
			(end -0.12065 -0.305054)
			(stroke
				(width 0.1)
				(type default)
			)
			(layer "F.Fab")
		)
		(fp_line
			(start -0.67945 0.3048)
			(end -0.67945 -0.305054)
			(stroke
				(width 0.1)
				(type default)
			)
			(layer "F.Fab")
		)
		(fp_line
			(start -0.12065 -0.305054)
			(end -0.12065 -0.2794)
			(stroke
				(width 0.1)
				(type default)
			)
			(layer "F.Fab")
		)
		(fp_line
			(start -0.12065 -0.2794)
			(end 0.12065 -0.2794)
			(stroke
				(width 0.1)
				(type default)
			)
			(layer "F.Fab")
		)
		(fp_line
			(start -0.12065 0.2794)
			(end -0.12065 0.3048)
			(stroke
				(width 0.1)
				(type default)
			)
			(layer "F.Fab")
		)
		(fp_line
			(start -0.12065 0.3048)
			(end -0.67945 0.3048)
			(stroke
				(width 0.1)
				(type default)
			)
			(layer "F.Fab")
		)
		(fp_line
			(start 0.120396 0.2794)
			(end -0.12065 0.2794)
			(stroke
				(width 0.1)
				(type default)
			)
			(layer "F.Fab")
		)
		(fp_line
			(start 0.120396 0.3048)
			(end 0.120396 0.2794)
			(stroke
				(width 0.1)
				(type default)
			)
			(layer "F.Fab")
		)
		(fp_line
			(start 0.12065 -0.3048)
			(end 0.67945 -0.3048)
			(stroke
				(width 0.1)
				(type default)
			)
			(layer "F.Fab")
		)
		(fp_line
			(start 0.12065 -0.2794)
			(end 0.12065 -0.3048)
			(stroke
				(width 0.1)
				(type default)
			)
			(layer "F.Fab")
		)
		(fp_line
			(start 0.67945 -0.3048)
			(end 0.67945 0.3048)
			(stroke
				(width 0.1)
				(type default)
			)
			(layer "F.Fab")
		)
		(fp_line
			(start 0.67945 0.3048)
			(end 0.120396 0.3048)
			(stroke
				(width 0.1)
				(type default)
			)
			(layer "F.Fab")
		)
		(pad "1" smd circle
			(at -0.40005 0)
			(size 0 0)
			(layers "F.Cu" "F.Mask" "F.Paste")
			(net "P12V_SSD9_R")
		)
		(pad "2" smd circle
			(at 0.40005 0)
			(size 0 0)
			(layers "F.Cu" "F.Mask" "F.Paste")
			(net "P12V_SSD9_PG_G1")
		)
	)
	(footprint ""
		(layer "F.Cu")
		(at 478.67189 -547.47541 180)
		(property "Reference" "SCREW_SSD15_2"
			(at -5.6007 -1.402334 0)
			(unlocked yes)
			(layer "B.SilkS")
			(effects
				(font
					(size 0.7874 0.5842)
					(thickness 0.1524)
				)
				(justify mirror)
			)
		)
		(property "Value" ""
			(at 0 0 180)
			(layer "F.Fab")
			(effects
				(font
					(size 1.27 1.27)
				)
			)
		)
		(duplicate_pad_numbers_are_jumpers no)
		(pad "1" thru_hole circle
			(at 0 0 180)
			(size 0.4572 0.4572)
			(drill 0.2032)
			(layers "*.Cu" "*.Mask")
			(remove_unused_layers no)
			(net "Net_9143")
			(clearance 0.127)
			(thermal_gap 0.127)
			(padstack
				(mode front_inner_back)
				(layer "Inner"
					(shape circle)
					(size 0.4572 0.4572)
					(clearance 0.127)
				)
				(layer "B.Cu"
					(shape circle)
					(size 0.508 0.508)
					(clearance 0.1016)
				)
			)
		)
	)
	(footprint ""
		(layer "F.Cu")
		(at 322.718684 -350.098614 90)
		(property "Reference" "C560"
			(at 0 0 90)
			(layer "F.SilkS")
			(hide yes)
			(effects
				(font
					(size 1.27 1.27)
				)
			)
		)
		(property "Value" ""
			(at 0 0 90)
			(layer "F.Fab")
			(effects
				(font
					(size 1.27 1.27)
				)
			)
		)
		(duplicate_pad_numbers_are_jumpers no)
		(fp_line
			(start 0.299974 -0.150114)
			(end 0.299974 0.150114)
			(stroke
				(width 0.1)
				(type default)
			)
			(layer "F.Fab")
		)
		(fp_line
			(start -0.299974 -0.150114)
			(end 0.299974 -0.150114)
			(stroke
				(width 0.1)
				(type default)
			)
			(layer "F.Fab")
		)
		(fp_line
			(start 0.299974 0.150114)
			(end -0.299974 0.150114)
			(stroke
				(width 0.1)
				(type default)
			)
			(layer "F.Fab")
		)
		(fp_line
			(start -0.299974 0.150114)
			(end -0.299974 -0.150114)
			(stroke
				(width 0.1)
				(type default)
			)
			(layer "F.Fab")
		)
		(pad "1" smd rect
			(at -0.2667 0 90)
			(size 0.3048 0.381)
			(layers "F.Cu" "F.Mask" "F.Paste")
			(net "P5E_PEX2_STN6_TX_DN<107>")
		)
		(pad "2" smd rect
			(at 0.2667 0 90)
			(size 0.3048 0.381)
			(layers "F.Cu" "F.Mask" "F.Paste")
			(net "P5E_PEX2_STN6_TX_C_DN<107>")
		)
	)
	(footprint ""
		(layer "F.Cu")
		(at 88.65235 -115.400836)
		(property "Reference" "R5854"
			(at 0 0 0)
			(layer "F.SilkS")
			(hide yes)
			(effects
				(font
					(size 1.27 1.27)
				)
			)
		)
		(property "Value" ""
			(at 0 0 0)
			(layer "F.Fab")
			(effects
				(font
					(size 1.27 1.27)
				)
			)
		)
		(duplicate_pad_numbers_are_jumpers no)
		(fp_line
			(start -0.7874 -0.4064)
			(end 0.7874 -0.4064)
			(stroke
				(width 0.1524)
				(type default)
			)
			(layer "F.SilkS")
		)
		(fp_line
			(start -0.7874 0.4064)
			(end -0.7874 -0.4064)
			(stroke
				(width 0.1524)
				(type default)
			)
			(layer "F.SilkS")
		)
		(fp_line
			(start 0.7874 -0.4064)
			(end 0.7874 0.4064)
			(stroke
				(width 0.1524)
				(type default)
			)
			(layer "F.SilkS")
		)
		(fp_line
			(start 0.7874 0.4064)
			(end -0.7874 0.4064)
			(stroke
				(width 0.1524)
				(type default)
			)
			(layer "F.SilkS")
		)
		(fp_line
			(start -0.67945 -0.305054)
			(end -0.12065 -0.305054)
			(stroke
				(width 0.1)
				(type default)
			)
			(layer "F.Fab")
		)
		(fp_line
			(start -0.67945 0.3048)
			(end -0.67945 -0.305054)
			(stroke
				(width 0.1)
				(type default)
			)
			(layer "F.Fab")
		)
		(fp_line
			(start -0.12065 -0.305054)
			(end -0.12065 -0.2794)
			(stroke
				(width 0.1)
				(type default)
			)
			(layer "F.Fab")
		)
		(fp_line
			(start -0.12065 -0.2794)
			(end 0.12065 -0.2794)
			(stroke
				(width 0.1)
				(type default)
			)
			(layer "F.Fab")
		)
		(fp_line
			(start -0.12065 0.2794)
			(end -0.12065 0.3048)
			(stroke
				(width 0.1)
				(type default)
			)
			(layer "F.Fab")
		)
		(fp_line
			(start -0.12065 0.3048)
			(end -0.67945 0.3048)
			(stroke
				(width 0.1)
				(type default)
			)
			(layer "F.Fab")
		)
		(fp_line
			(start 0.120396 0.2794)
			(end -0.12065 0.2794)
			(stroke
				(width 0.1)
				(type default)
			)
			(layer "F.Fab")
		)
		(fp_line
			(start 0.120396 0.3048)
			(end 0.120396 0.2794)
			(stroke
				(width 0.1)
				(type default)
			)
			(layer "F.Fab")
		)
		(fp_line
			(start 0.12065 -0.3048)
			(end 0.67945 -0.3048)
			(stroke
				(width 0.1)
				(type default)
			)
			(layer "F.Fab")
		)
		(fp_line
			(start 0.12065 -0.2794)
			(end 0.12065 -0.3048)
			(stroke
				(width 0.1)
				(type default)
			)
			(layer "F.Fab")
		)
		(fp_line
			(start 0.67945 -0.3048)
			(end 0.67945 0.3048)
			(stroke
				(width 0.1)
				(type default)
			)
			(layer "F.Fab")
		)
		(fp_line
			(start 0.67945 0.3048)
			(end 0.120396 0.3048)
			(stroke
				(width 0.1)
				(type default)
			)
			(layer "F.Fab")
		)
		(pad "1" smd circle
			(at -0.40005 0)
			(size 0 0)
			(layers "F.Cu" "F.Mask" "F.Paste")
			(net "HP_NIC1_EN")
		)
		(pad "2" smd circle
			(at 0.40005 0)
			(size 0 0)
			(layers "F.Cu" "F.Mask" "F.Paste")
			(net "P3V3_NIC1_CO_EN")
		)
	)
	(footprint ""
		(layer "F.Cu")
		(at 143.840708 -343.952322 90)
		(property "Reference" "C2246"
			(at 0 0 90)
			(layer "F.SilkS")
			(hide yes)
			(effects
				(font
					(size 1.27 1.27)
				)
			)
		)
		(property "Value" ""
			(at 0 0 90)
			(layer "F.Fab")
			(effects
				(font
					(size 1.27 1.27)
				)
			)
		)
		(duplicate_pad_numbers_are_jumpers no)
		(fp_line
			(start 0.299974 -0.150114)
			(end 0.299974 0.150114)
			(stroke
				(width 0.1)
				(type default)
			)
			(layer "F.Fab")
		)
		(fp_line
			(start -0.299974 -0.150114)
			(end 0.299974 -0.150114)
			(stroke
				(width 0.1)
				(type default)
			)
			(layer "F.Fab")
		)
		(fp_line
			(start 0.299974 0.150114)
			(end -0.299974 0.150114)
			(stroke
				(width 0.1)
				(type default)
			)
			(layer "F.Fab")
		)
		(fp_line
			(start -0.299974 0.150114)
			(end -0.299974 -0.150114)
			(stroke
				(width 0.1)
				(type default)
			)
			(layer "F.Fab")
		)
		(pad "1" smd rect
			(at -0.2667 0 90)
			(size 0.3048 0.381)
			(layers "F.Cu" "F.Mask" "F.Paste")
			(net "P5E_PEX1_STN5_TX_DN<94>")
		)
		(pad "2" smd rect
			(at 0.2667 0 90)
			(size 0.3048 0.381)
			(layers "F.Cu" "F.Mask" "F.Paste")
			(net "P5E_PEX1_STN5_TX_C_DN<94>")
		)
	)
	(footprint ""
		(layer "F.Cu")
		(at 20.221448 -343.952322 90)
		(property "Reference" "C2153"
			(at 0 0 90)
			(layer "F.SilkS")
			(hide yes)
			(effects
				(font
					(size 1.27 1.27)
				)
			)
		)
		(property "Value" ""
			(at 0 0 90)
			(layer "F.Fab")
			(effects
				(font
					(size 1.27 1.27)
				)
			)
		)
		(duplicate_pad_numbers_are_jumpers no)
		(fp_line
			(start 0.299974 -0.150114)
			(end 0.299974 0.150114)
			(stroke
				(width 0.1)
				(type default)
			)
			(layer "F.Fab")
		)
		(fp_line
			(start -0.299974 -0.150114)
			(end 0.299974 -0.150114)
			(stroke
				(width 0.1)
				(type default)
			)
			(layer "F.Fab")
		)
		(fp_line
			(start 0.299974 0.150114)
			(end -0.299974 0.150114)
			(stroke
				(width 0.1)
				(type default)
			)
			(layer "F.Fab")
		)
		(fp_line
			(start -0.299974 0.150114)
			(end -0.299974 -0.150114)
			(stroke
				(width 0.1)
				(type default)
			)
			(layer "F.Fab")
		)
		(pad "1" smd rect
			(at -0.2667 0 90)
			(size 0.3048 0.381)
			(layers "F.Cu" "F.Mask" "F.Paste")
			(net "P5E_PEX0_STN4_TX_DN<79>")
		)
		(pad "2" smd rect
			(at 0.2667 0 90)
			(size 0.3048 0.381)
			(layers "F.Cu" "F.Mask" "F.Paste")
			(net "P5E_PEX0_STN4_TX_C_DN<79>")
		)
	)
	(footprint ""
		(layer "F.Cu")
		(at 352.920554 -89.502234)
		(property "Reference" "R1615"
			(at 0 0 0)
			(layer "F.SilkS")
			(hide yes)
			(effects
				(font
					(size 1.27 1.27)
				)
			)
		)
		(property "Value" ""
			(at 0 0 0)
			(layer "F.Fab")
			(effects
				(font
					(size 1.27 1.27)
				)
			)
		)
		(duplicate_pad_numbers_are_jumpers no)
		(fp_line
			(start -0.7874 -0.4064)
			(end 0.7874 -0.4064)
			(stroke
				(width 0.1524)
				(type default)
			)
			(layer "F.SilkS")
		)
		(fp_line
			(start -0.7874 0.4064)
			(end -0.7874 -0.4064)
			(stroke
				(width 0.1524)
				(type default)
			)
			(layer "F.SilkS")
		)
		(fp_line
			(start 0.7874 -0.4064)
			(end 0.7874 0.4064)
			(stroke
				(width 0.1524)
				(type default)
			)
			(layer "F.SilkS")
		)
		(fp_line
			(start 0.7874 0.4064)
			(end -0.7874 0.4064)
			(stroke
				(width 0.1524)
				(type default)
			)
			(layer "F.SilkS")
		)
		(fp_line
			(start -0.67945 -0.305054)
			(end -0.12065 -0.305054)
			(stroke
				(width 0.1)
				(type default)
			)
			(layer "F.Fab")
		)
		(fp_line
			(start -0.67945 0.3048)
			(end -0.67945 -0.305054)
			(stroke
				(width 0.1)
				(type default)
			)
			(layer "F.Fab")
		)
		(fp_line
			(start -0.12065 -0.305054)
			(end -0.12065 -0.2794)
			(stroke
				(width 0.1)
				(type default)
			)
			(layer "F.Fab")
		)
		(fp_line
			(start -0.12065 -0.2794)
			(end 0.12065 -0.2794)
			(stroke
				(width 0.1)
				(type default)
			)
			(layer "F.Fab")
		)
		(fp_line
			(start -0.12065 0.2794)
			(end -0.12065 0.3048)
			(stroke
				(width 0.1)
				(type default)
			)
			(layer "F.Fab")
		)
		(fp_line
			(start -0.12065 0.3048)
			(end -0.67945 0.3048)
			(stroke
				(width 0.1)
				(type default)
			)
			(layer "F.Fab")
		)
		(fp_line
			(start 0.120396 0.2794)
			(end -0.12065 0.2794)
			(stroke
				(width 0.1)
				(type default)
			)
			(layer "F.Fab")
		)
		(fp_line
			(start 0.120396 0.3048)
			(end 0.120396 0.2794)
			(stroke
				(width 0.1)
				(type default)
			)
			(layer "F.Fab")
		)
		(fp_line
			(start 0.12065 -0.3048)
			(end 0.67945 -0.3048)
			(stroke
				(width 0.1)
				(type default)
			)
			(layer "F.Fab")
		)
		(fp_line
			(start 0.12065 -0.2794)
			(end 0.12065 -0.3048)
			(stroke
				(width 0.1)
				(type default)
			)
			(layer "F.Fab")
		)
		(fp_line
			(start 0.67945 -0.3048)
			(end 0.67945 0.3048)
			(stroke
				(width 0.1)
				(type default)
			)
			(layer "F.Fab")
		)
		(fp_line
			(start 0.67945 0.3048)
			(end 0.120396 0.3048)
			(stroke
				(width 0.1)
				(type default)
			)
			(layer "F.Fab")
		)
		(pad "1" smd circle
			(at -0.40005 0)
			(size 0 0)
			(layers "F.Cu" "F.Mask" "F.Paste")
			(net "SMB_BIC_I2C9_MUX1_SSD8_R_SDA")
		)
		(pad "2" smd circle
			(at 0.40005 0)
			(size 0 0)
			(layers "F.Cu" "F.Mask" "F.Paste")
			(net "SMB_BIC_I2C9_MUX1_SSD8_SDA")
		)
	)
	(footprint ""
		(layer "F.Cu")
		(at 213.833456 -217.27033)
		(property "Reference" "R4876"
			(at 0 0 0)
			(layer "F.SilkS")
			(hide yes)
			(effects
				(font
					(size 1.27 1.27)
				)
			)
		)
		(property "Value" ""
			(at 0 0 0)
			(layer "F.Fab")
			(effects
				(font
					(size 1.27 1.27)
				)
			)
		)
		(duplicate_pad_numbers_are_jumpers no)
		(fp_line
			(start -0.7874 -0.4064)
			(end 0.7874 -0.4064)
			(stroke
				(width 0.1524)
				(type default)
			)
			(layer "F.SilkS")
		)
		(fp_line
			(start -0.7874 0.4064)
			(end -0.7874 -0.4064)
			(stroke
				(width 0.1524)
				(type default)
			)
			(layer "F.SilkS")
		)
		(fp_line
			(start 0.7874 -0.4064)
			(end 0.7874 0.4064)
			(stroke
				(width 0.1524)
				(type default)
			)
			(layer "F.SilkS")
		)
		(fp_line
			(start 0.7874 0.4064)
			(end -0.7874 0.4064)
			(stroke
				(width 0.1524)
				(type default)
			)
			(layer "F.SilkS")
		)
		(fp_line
			(start -0.67945 -0.305054)
			(end -0.12065 -0.305054)
			(stroke
				(width 0.1)
				(type default)
			)
			(layer "F.Fab")
		)
		(fp_line
			(start -0.67945 0.3048)
			(end -0.67945 -0.305054)
			(stroke
				(width 0.1)
				(type default)
			)
			(layer "F.Fab")
		)
		(fp_line
			(start -0.12065 -0.305054)
			(end -0.12065 -0.2794)
			(stroke
				(width 0.1)
				(type default)
			)
			(layer "F.Fab")
		)
		(fp_line
			(start -0.12065 -0.2794)
			(end 0.12065 -0.2794)
			(stroke
				(width 0.1)
				(type default)
			)
			(layer "F.Fab")
		)
		(fp_line
			(start -0.12065 0.2794)
			(end -0.12065 0.3048)
			(stroke
				(width 0.1)
				(type default)
			)
			(layer "F.Fab")
		)
		(fp_line
			(start -0.12065 0.3048)
			(end -0.67945 0.3048)
			(stroke
				(width 0.1)
				(type default)
			)
			(layer "F.Fab")
		)
		(fp_line
			(start 0.120396 0.2794)
			(end -0.12065 0.2794)
			(stroke
				(width 0.1)
				(type default)
			)
			(layer "F.Fab")
		)
		(fp_line
			(start 0.120396 0.3048)
			(end 0.120396 0.2794)
			(stroke
				(width 0.1)
				(type default)
			)
			(layer "F.Fab")
		)
		(fp_line
			(start 0.12065 -0.3048)
			(end 0.67945 -0.3048)
			(stroke
				(width 0.1)
				(type default)
			)
			(layer "F.Fab")
		)
		(fp_line
			(start 0.12065 -0.2794)
			(end 0.12065 -0.3048)
			(stroke
				(width 0.1)
				(type default)
			)
			(layer "F.Fab")
		)
		(fp_line
			(start 0.67945 -0.3048)
			(end 0.67945 0.3048)
			(stroke
				(width 0.1)
				(type default)
			)
			(layer "F.Fab")
		)
		(fp_line
			(start 0.67945 0.3048)
			(end 0.120396 0.3048)
			(stroke
				(width 0.1)
				(type default)
			)
			(layer "F.Fab")
		)
		(pad "1" smd circle
			(at -0.40005 0)
			(size 0 0)
			(layers "F.Cu" "F.Mask" "F.Paste")
			(net "P1V2_AUX")
		)
		(pad "2" smd circle
			(at 0.40005 0)
			(size 0 0)
			(layers "F.Cu" "F.Mask" "F.Paste")
			(net "SMB_NIC5_SDA")
		)
	)
	(footprint ""
		(layer "F.Cu")
		(at 435.285134 -306.041044 -90)
		(property "Reference" "R6811"
			(at 0 0 270)
			(layer "F.SilkS")
			(hide yes)
			(effects
				(font
					(size 1.27 1.27)
				)
			)
		)
		(property "Value" ""
			(at 0 0 270)
			(layer "F.Fab")
			(effects
				(font
					(size 1.27 1.27)
				)
			)
		)
		(duplicate_pad_numbers_are_jumpers no)
		(fp_line
			(start -0.7874 0.4064)
			(end -0.7874 -0.4064)
			(stroke
				(width 0.1524)
				(type default)
			)
			(layer "F.SilkS")
		)
		(fp_line
			(start 0.7874 0.4064)
			(end -0.7874 0.4064)
			(stroke
				(width 0.1524)
				(type default)
			)
			(layer "F.SilkS")
		)
		(fp_line
			(start -0.7874 -0.4064)
			(end 0.7874 -0.4064)
			(stroke
				(width 0.1524)
				(type default)
			)
			(layer "F.SilkS")
		)
		(fp_line
			(start 0.7874 -0.4064)
			(end 0.7874 0.4064)
			(stroke
				(width 0.1524)
				(type default)
			)
			(layer "F.SilkS")
		)
		(fp_line
			(start -0.67945 0.3048)
			(end -0.67945 -0.305054)
			(stroke
				(width 0.1)
				(type default)
			)
			(layer "F.Fab")
		)
		(fp_line
			(start -0.12065 0.3048)
			(end -0.67945 0.3048)
			(stroke
				(width 0.1)
				(type default)
			)
			(layer "F.Fab")
		)
		(fp_line
			(start 0.120396 0.3048)
			(end 0.120396 0.2794)
			(stroke
				(width 0.1)
				(type default)
			)
			(layer "F.Fab")
		)
		(fp_line
			(start 0.67945 0.3048)
			(end 0.120396 0.3048)
			(stroke
				(width 0.1)
				(type default)
			)
			(layer "F.Fab")
		)
		(fp_line
			(start -0.12065 0.2794)
			(end -0.12065 0.3048)
			(stroke
				(width 0.1)
				(type default)
			)
			(layer "F.Fab")
		)
		(fp_line
			(start 0.120396 0.2794)
			(end -0.12065 0.2794)
			(stroke
				(width 0.1)
				(type default)
			)
			(layer "F.Fab")
		)
		(fp_line
			(start -0.12065 -0.2794)
			(end 0.12065 -0.2794)
			(stroke
				(width 0.1)
				(type default)
			)
			(layer "F.Fab")
		)
		(fp_line
			(start 0.12065 -0.2794)
			(end 0.12065 -0.3048)
			(stroke
				(width 0.1)
				(type default)
			)
			(layer "F.Fab")
		)
		(fp_line
			(start 0.12065 -0.3048)
			(end 0.67945 -0.3048)
			(stroke
				(width 0.1)
				(type default)
			)
			(layer "F.Fab")
		)
		(fp_line
			(start 0.67945 -0.3048)
			(end 0.67945 0.3048)
			(stroke
				(width 0.1)
				(type default)
			)
			(layer "F.Fab")
		)
		(fp_line
			(start -0.67945 -0.305054)
			(end -0.12065 -0.305054)
			(stroke
				(width 0.1)
				(type default)
			)
			(layer "F.Fab")
		)
		(fp_line
			(start -0.12065 -0.305054)
			(end -0.12065 -0.2794)
			(stroke
				(width 0.1)
				(type default)
			)
			(layer "F.Fab")
		)
		(pad "1" smd circle
			(at -0.40005 0 270)
			(size 0 0)
			(layers "F.Cu" "F.Mask" "F.Paste")
			(net "SMB_PEX3_R_SDA")
		)
		(pad "2" smd circle
			(at 0.40005 0 270)
			(size 0 0)
			(layers "F.Cu" "F.Mask" "F.Paste")
			(net "SMB_PEX3_SDA")
		)
	)
	(footprint ""
		(layer "F.Cu")
		(at 198.76135 -151.596852 180)
		(property "Reference" "C217"
			(at 0 0 180)
			(layer "F.SilkS")
			(hide yes)
			(effects
				(font
					(size 1.27 1.27)
				)
			)
		)
		(property "Value" ""
			(at 0 0 180)
			(layer "F.Fab")
			(effects
				(font
					(size 1.27 1.27)
				)
			)
		)
		(duplicate_pad_numbers_are_jumpers no)
		(fp_line
			(start 0.299974 0.150114)
			(end -0.299974 0.150114)
			(stroke
				(width 0.1)
				(type default)
			)
			(layer "F.Fab")
		)
		(fp_line
			(start 0.299974 -0.150114)
			(end 0.299974 0.150114)
			(stroke
				(width 0.1)
				(type default)
			)
			(layer "F.Fab")
		)
		(fp_line
			(start -0.299974 0.150114)
			(end -0.299974 -0.150114)
			(stroke
				(width 0.1)
				(type default)
			)
			(layer "F.Fab")
		)
		(fp_line
			(start -0.299974 -0.150114)
			(end 0.299974 -0.150114)
			(stroke
				(width 0.1)
				(type default)
			)
			(layer "F.Fab")
		)
		(pad "1" smd rect
			(at -0.2667 0 180)
			(size 0.3048 0.381)
			(layers "F.Cu" "F.Mask" "F.Paste")
			(net "P5E_PEX1_STN0_TX_DN<13>")
		)
		(pad "2" smd rect
			(at 0.2667 0 180)
			(size 0.3048 0.381)
			(layers "F.Cu" "F.Mask" "F.Paste")
			(net "P5E_PEX1_STN0_TX_C_DN<13>")
		)
	)
	(footprint ""
		(layer "F.Cu")
		(at 168.367964 -54.067456)
		(property "Reference" "PR214"
			(at 0 0 0)
			(layer "F.SilkS")
			(hide yes)
			(effects
				(font
					(size 1.27 1.27)
				)
			)
		)
		(property "Value" ""
			(at 0 0 0)
			(layer "F.Fab")
			(effects
				(font
					(size 1.27 1.27)
				)
			)
		)
		(duplicate_pad_numbers_are_jumpers no)
		(fp_line
			(start -0.7874 -0.4064)
			(end 0.7874 -0.4064)
			(stroke
				(width 0.1524)
				(type default)
			)
			(layer "F.SilkS")
		)
		(fp_line
			(start -0.7874 0.4064)
			(end -0.7874 -0.4064)
			(stroke
				(width 0.1524)
				(type default)
			)
			(layer "F.SilkS")
		)
		(fp_line
			(start 0.7874 -0.4064)
			(end 0.7874 0.4064)
			(stroke
				(width 0.1524)
				(type default)
			)
			(layer "F.SilkS")
		)
		(fp_line
			(start 0.7874 0.4064)
			(end -0.7874 0.4064)
			(stroke
				(width 0.1524)
				(type default)
			)
			(layer "F.SilkS")
		)
		(fp_line
			(start -0.67945 -0.305054)
			(end -0.12065 -0.305054)
			(stroke
				(width 0.1)
				(type default)
			)
			(layer "F.Fab")
		)
		(fp_line
			(start -0.67945 0.3048)
			(end -0.67945 -0.305054)
			(stroke
				(width 0.1)
				(type default)
			)
			(layer "F.Fab")
		)
		(fp_line
			(start -0.12065 -0.305054)
			(end -0.12065 -0.2794)
			(stroke
				(width 0.1)
				(type default)
			)
			(layer "F.Fab")
		)
		(fp_line
			(start -0.12065 -0.2794)
			(end 0.12065 -0.2794)
			(stroke
				(width 0.1)
				(type default)
			)
			(layer "F.Fab")
		)
		(fp_line
			(start -0.12065 0.2794)
			(end -0.12065 0.3048)
			(stroke
				(width 0.1)
				(type default)
			)
			(layer "F.Fab")
		)
		(fp_line
			(start -0.12065 0.3048)
			(end -0.67945 0.3048)
			(stroke
				(width 0.1)
				(type default)
			)
			(layer "F.Fab")
		)
		(fp_line
			(start 0.120396 0.2794)
			(end -0.12065 0.2794)
			(stroke
				(width 0.1)
				(type default)
			)
			(layer "F.Fab")
		)
		(fp_line
			(start 0.120396 0.3048)
			(end 0.120396 0.2794)
			(stroke
				(width 0.1)
				(type default)
			)
			(layer "F.Fab")
		)
		(fp_line
			(start 0.12065 -0.3048)
			(end 0.67945 -0.3048)
			(stroke
				(width 0.1)
				(type default)
			)
			(layer "F.Fab")
		)
		(fp_line
			(start 0.12065 -0.2794)
			(end 0.12065 -0.3048)
			(stroke
				(width 0.1)
				(type default)
			)
			(layer "F.Fab")
		)
		(fp_line
			(start 0.67945 -0.3048)
			(end 0.67945 0.3048)
			(stroke
				(width 0.1)
				(type default)
			)
			(layer "F.Fab")
		)
		(fp_line
			(start 0.67945 0.3048)
			(end 0.120396 0.3048)
			(stroke
				(width 0.1)
				(type default)
			)
			(layer "F.Fab")
		)
		(pad "1" smd circle
			(at -0.40005 0)
			(size 0 0)
			(layers "F.Cu" "F.Mask" "F.Paste")
			(net "P12V_SSD5_OCP")
		)
		(pad "2" smd circle
			(at 0.40005 0)
			(size 0 0)
			(layers "F.Cu" "F.Mask" "F.Paste")
			(net "GND")
		)
	)
	(footprint ""
		(layer "F.Cu")
		(at 438.318148 -306.074572 90)
		(property "Reference" "R1440"
			(at 0 0 90)
			(layer "F.SilkS")
			(hide yes)
			(effects
				(font
					(size 1.27 1.27)
				)
			)
		)
		(property "Value" ""
			(at 0 0 90)
			(layer "F.Fab")
			(effects
				(font
					(size 1.27 1.27)
				)
			)
		)
		(duplicate_pad_numbers_are_jumpers no)
		(fp_line
			(start 0.7874 -0.4064)
			(end 0.7874 0.4064)
			(stroke
				(width 0.1524)
				(type default)
			)
			(layer "F.SilkS")
		)
		(fp_line
			(start -0.7874 -0.4064)
			(end 0.7874 -0.4064)
			(stroke
				(width 0.1524)
				(type default)
			)
			(layer "F.SilkS")
		)
		(fp_line
			(start 0.7874 0.4064)
			(end -0.7874 0.4064)
			(stroke
				(width 0.1524)
				(type default)
			)
			(layer "F.SilkS")
		)
		(fp_line
			(start -0.7874 0.4064)
			(end -0.7874 -0.4064)
			(stroke
				(width 0.1524)
				(type default)
			)
			(layer "F.SilkS")
		)
		(fp_line
			(start -0.12065 -0.305054)
			(end -0.12065 -0.2794)
			(stroke
				(width 0.1)
				(type default)
			)
			(layer "F.Fab")
		)
		(fp_line
			(start -0.67945 -0.305054)
			(end -0.12065 -0.305054)
			(stroke
				(width 0.1)
				(type default)
			)
			(layer "F.Fab")
		)
		(fp_line
			(start 0.67945 -0.3048)
			(end 0.67945 0.3048)
			(stroke
				(width 0.1)
				(type default)
			)
			(layer "F.Fab")
		)
		(fp_line
			(start 0.12065 -0.3048)
			(end 0.67945 -0.3048)
			(stroke
				(width 0.1)
				(type default)
			)
			(layer "F.Fab")
		)
		(fp_line
			(start 0.12065 -0.2794)
			(end 0.12065 -0.3048)
			(stroke
				(width 0.1)
				(type default)
			)
			(layer "F.Fab")
		)
		(fp_line
			(start -0.12065 -0.2794)
			(end 0.12065 -0.2794)
			(stroke
				(width 0.1)
				(type default)
			)
			(layer "F.Fab")
		)
		(fp_line
			(start 0.120396 0.2794)
			(end -0.12065 0.2794)
			(stroke
				(width 0.1)
				(type default)
			)
			(layer "F.Fab")
		)
		(fp_line
			(start -0.12065 0.2794)
			(end -0.12065 0.3048)
			(stroke
				(width 0.1)
				(type default)
			)
			(layer "F.Fab")
		)
		(fp_line
			(start 0.67945 0.3048)
			(end 0.120396 0.3048)
			(stroke
				(width 0.1)
				(type default)
			)
			(layer "F.Fab")
		)
		(fp_line
			(start 0.120396 0.3048)
			(end 0.120396 0.2794)
			(stroke
				(width 0.1)
				(type default)
			)
			(layer "F.Fab")
		)
		(fp_line
			(start -0.12065 0.3048)
			(end -0.67945 0.3048)
			(stroke
				(width 0.1)
				(type default)
			)
			(layer "F.Fab")
		)
		(fp_line
			(start -0.67945 0.3048)
			(end -0.67945 -0.305054)
			(stroke
				(width 0.1)
				(type default)
			)
			(layer "F.Fab")
		)
		(pad "1" smd circle
			(at -0.40005 0 90)
			(size 0 0)
			(layers "F.Cu" "F.Mask" "F.Paste")
			(net "PEX3_SPARE3")
		)
		(pad "2" smd circle
			(at 0.40005 0 90)
			(size 0 0)
			(layers "F.Cu" "F.Mask" "F.Paste")
			(net "P1V8_PEX")
		)
	)
	(footprint ""
		(layer "F.Cu")
		(at 212.422994 -222.399352 90)
		(property "Reference" "R4885"
			(at 0 0 90)
			(layer "F.SilkS")
			(hide yes)
			(effects
				(font
					(size 1.27 1.27)
				)
			)
		)
		(property "Value" ""
			(at 0 0 90)
			(layer "F.Fab")
			(effects
				(font
					(size 1.27 1.27)
				)
			)
		)
		(duplicate_pad_numbers_are_jumpers no)
		(fp_line
			(start 0.7874 -0.4064)
			(end 0.7874 0.4064)
			(stroke
				(width 0.1524)
				(type default)
			)
			(layer "F.SilkS")
		)
		(fp_line
			(start -0.7874 -0.4064)
			(end 0.7874 -0.4064)
			(stroke
				(width 0.1524)
				(type default)
			)
			(layer "F.SilkS")
		)
		(fp_line
			(start 0.7874 0.4064)
			(end -0.7874 0.4064)
			(stroke
				(width 0.1524)
				(type default)
			)
			(layer "F.SilkS")
		)
		(fp_line
			(start -0.7874 0.4064)
			(end -0.7874 -0.4064)
			(stroke
				(width 0.1524)
				(type default)
			)
			(layer "F.SilkS")
		)
		(fp_line
			(start -0.12065 -0.305054)
			(end -0.12065 -0.2794)
			(stroke
				(width 0.1)
				(type default)
			)
			(layer "F.Fab")
		)
		(fp_line
			(start -0.67945 -0.305054)
			(end -0.12065 -0.305054)
			(stroke
				(width 0.1)
				(type default)
			)
			(layer "F.Fab")
		)
		(fp_line
			(start 0.67945 -0.3048)
			(end 0.67945 0.3048)
			(stroke
				(width 0.1)
				(type default)
			)
			(layer "F.Fab")
		)
		(fp_line
			(start 0.12065 -0.3048)
			(end 0.67945 -0.3048)
			(stroke
				(width 0.1)
				(type default)
			)
			(layer "F.Fab")
		)
		(fp_line
			(start 0.12065 -0.2794)
			(end 0.12065 -0.3048)
			(stroke
				(width 0.1)
				(type default)
			)
			(layer "F.Fab")
		)
		(fp_line
			(start -0.12065 -0.2794)
			(end 0.12065 -0.2794)
			(stroke
				(width 0.1)
				(type default)
			)
			(layer "F.Fab")
		)
		(fp_line
			(start 0.120396 0.2794)
			(end -0.12065 0.2794)
			(stroke
				(width 0.1)
				(type default)
			)
			(layer "F.Fab")
		)
		(fp_line
			(start -0.12065 0.2794)
			(end -0.12065 0.3048)
			(stroke
				(width 0.1)
				(type default)
			)
			(layer "F.Fab")
		)
		(fp_line
			(start 0.67945 0.3048)
			(end 0.120396 0.3048)
			(stroke
				(width 0.1)
				(type default)
			)
			(layer "F.Fab")
		)
		(fp_line
			(start 0.120396 0.3048)
			(end 0.120396 0.2794)
			(stroke
				(width 0.1)
				(type default)
			)
			(layer "F.Fab")
		)
		(fp_line
			(start -0.12065 0.3048)
			(end -0.67945 0.3048)
			(stroke
				(width 0.1)
				(type default)
			)
			(layer "F.Fab")
		)
		(fp_line
			(start -0.67945 0.3048)
			(end -0.67945 -0.305054)
			(stroke
				(width 0.1)
				(type default)
			)
			(layer "F.Fab")
		)
		(pad "1" smd circle
			(at -0.40005 0 90)
			(size 0 0)
			(layers "F.Cu" "F.Mask" "F.Paste")
			(net "SMB_BIC_I2C9_SSD_MUX_R_SCL")
		)
		(pad "2" smd circle
			(at 0.40005 0 90)
			(size 0 0)
			(layers "F.Cu" "F.Mask" "F.Paste")
			(net "P3V3_AUX")
		)
	)
	(footprint ""
		(layer "F.Cu")
		(at 210.439 -199.263)
		(property "Reference" "C2626"
			(at 0 0 0)
			(layer "F.SilkS")
			(hide yes)
			(effects
				(font
					(size 1.27 1.27)
				)
			)
		)
		(property "Value" ""
			(at 0 0 0)
			(layer "F.Fab")
			(effects
				(font
					(size 1.27 1.27)
				)
			)
		)
		(duplicate_pad_numbers_are_jumpers no)
		(fp_line
			(start -0.7874 -0.4064)
			(end 0.7874 -0.4064)
			(stroke
				(width 0.1524)
				(type default)
			)
			(layer "F.SilkS")
		)
		(fp_line
			(start -0.7874 0.4064)
			(end -0.7874 -0.4064)
			(stroke
				(width 0.1524)
				(type default)
			)
			(layer "F.SilkS")
		)
		(fp_line
			(start 0.7874 -0.4064)
			(end 0.7874 0.4064)
			(stroke
				(width 0.1524)
				(type default)
			)
			(layer "F.SilkS")
		)
		(fp_line
			(start 0.7874 0.4064)
			(end -0.7874 0.4064)
			(stroke
				(width 0.1524)
				(type default)
			)
			(layer "F.SilkS")
		)
		(fp_line
			(start -0.67945 -0.305054)
			(end -0.12065 -0.305054)
			(stroke
				(width 0.1)
				(type default)
			)
			(layer "F.Fab")
		)
		(fp_line
			(start -0.67945 0.3048)
			(end -0.67945 -0.305054)
			(stroke
				(width 0.1)
				(type default)
			)
			(layer "F.Fab")
		)
		(fp_line
			(start -0.12065 -0.305054)
			(end -0.12065 -0.2794)
			(stroke
				(width 0.1)
				(type default)
			)
			(layer "F.Fab")
		)
		(fp_line
			(start -0.12065 -0.2794)
			(end 0.12065 -0.2794)
			(stroke
				(width 0.1)
				(type default)
			)
			(layer "F.Fab")
		)
		(fp_line
			(start -0.12065 0.2794)
			(end -0.12065 0.3048)
			(stroke
				(width 0.1)
				(type default)
			)
			(layer "F.Fab")
		)
		(fp_line
			(start -0.12065 0.3048)
			(end -0.67945 0.3048)
			(stroke
				(width 0.1)
				(type default)
			)
			(layer "F.Fab")
		)
		(fp_line
			(start 0.120396 0.2794)
			(end -0.12065 0.2794)
			(stroke
				(width 0.1)
				(type default)
			)
			(layer "F.Fab")
		)
		(fp_line
			(start 0.120396 0.3048)
			(end 0.120396 0.2794)
			(stroke
				(width 0.1)
				(type default)
			)
			(layer "F.Fab")
		)
		(fp_line
			(start 0.12065 -0.3048)
			(end 0.67945 -0.3048)
			(stroke
				(width 0.1)
				(type default)
			)
			(layer "F.Fab")
		)
		(fp_line
			(start 0.12065 -0.2794)
			(end 0.12065 -0.3048)
			(stroke
				(width 0.1)
				(type default)
			)
			(layer "F.Fab")
		)
		(fp_line
			(start 0.67945 -0.3048)
			(end 0.67945 0.3048)
			(stroke
				(width 0.1)
				(type default)
			)
			(layer "F.Fab")
		)
		(fp_line
			(start 0.67945 0.3048)
			(end 0.120396 0.3048)
			(stroke
				(width 0.1)
				(type default)
			)
			(layer "F.Fab")
		)
		(pad "1" smd circle
			(at -0.40005 0)
			(size 0 0)
			(layers "F.Cu" "F.Mask" "F.Paste")
			(net "GND")
		)
		(pad "2" smd circle
			(at 0.40005 0)
			(size 0 0)
			(layers "F.Cu" "F.Mask" "F.Paste")
			(net "P1V2_AUX")
		)
	)
	(footprint ""
		(layer "F.Cu")
		(at 384.938524 -104.695498)
		(property "Reference" "C690"
			(at 0 0 0)
			(layer "F.SilkS")
			(hide yes)
			(effects
				(font
					(size 1.27 1.27)
				)
			)
		)
		(property "Value" ""
			(at 0 0 0)
			(layer "F.Fab")
			(effects
				(font
					(size 1.27 1.27)
				)
			)
		)
		(duplicate_pad_numbers_are_jumpers no)
		(fp_line
			(start -0.299974 -0.150114)
			(end 0.299974 -0.150114)
			(stroke
				(width 0.1)
				(type default)
			)
			(layer "F.Fab")
		)
		(fp_line
			(start -0.299974 0.150114)
			(end -0.299974 -0.150114)
			(stroke
				(width 0.1)
				(type default)
			)
			(layer "F.Fab")
		)
		(fp_line
			(start 0.299974 -0.150114)
			(end 0.299974 0.150114)
			(stroke
				(width 0.1)
				(type default)
			)
			(layer "F.Fab")
		)
		(fp_line
			(start 0.299974 0.150114)
			(end -0.299974 0.150114)
			(stroke
				(width 0.1)
				(type default)
			)
			(layer "F.Fab")
		)
		(pad "1" smd rect
			(at -0.2667 0)
			(size 0.3048 0.381)
			(layers "F.Cu" "F.Mask" "F.Paste")
			(net "P5E_PEX3_STN1_TX_DN<19>")
		)
		(pad "2" smd rect
			(at 0.2667 0)
			(size 0.3048 0.381)
			(layers "F.Cu" "F.Mask" "F.Paste")
			(net "P5E_PEX3_STN1_TX_C_DN<19>")
		)
	)
	(footprint ""
		(layer "F.Cu")
		(at 206.711296 -226.928426 180)
		(property "Reference" "R5916"
			(at 0 0 180)
			(layer "F.SilkS")
			(hide yes)
			(effects
				(font
					(size 1.27 1.27)
				)
			)
		)
		(property "Value" ""
			(at 0 0 180)
			(layer "F.Fab")
			(effects
				(font
					(size 1.27 1.27)
				)
			)
		)
		(duplicate_pad_numbers_are_jumpers no)
		(fp_line
			(start 0.7874 0.4064)
			(end -0.7874 0.4064)
			(stroke
				(width 0.1524)
				(type default)
			)
			(layer "F.SilkS")
		)
		(fp_line
			(start 0.7874 -0.4064)
			(end 0.7874 0.4064)
			(stroke
				(width 0.1524)
				(type default)
			)
			(layer "F.SilkS")
		)
		(fp_line
			(start -0.7874 0.4064)
			(end -0.7874 -0.4064)
			(stroke
				(width 0.1524)
				(type default)
			)
			(layer "F.SilkS")
		)
		(fp_line
			(start -0.7874 -0.4064)
			(end 0.7874 -0.4064)
			(stroke
				(width 0.1524)
				(type default)
			)
			(layer "F.SilkS")
		)
		(fp_line
			(start 0.67945 0.3048)
			(end 0.120396 0.3048)
			(stroke
				(width 0.1)
				(type default)
			)
			(layer "F.Fab")
		)
		(fp_line
			(start 0.67945 -0.3048)
			(end 0.67945 0.3048)
			(stroke
				(width 0.1)
				(type default)
			)
			(layer "F.Fab")
		)
		(fp_line
			(start 0.12065 -0.2794)
			(end 0.12065 -0.3048)
			(stroke
				(width 0.1)
				(type default)
			)
			(layer "F.Fab")
		)
		(fp_line
			(start 0.12065 -0.3048)
			(end 0.67945 -0.3048)
			(stroke
				(width 0.1)
				(type default)
			)
			(layer "F.Fab")
		)
		(fp_line
			(start 0.120396 0.3048)
			(end 0.120396 0.2794)
			(stroke
				(width 0.1)
				(type default)
			)
			(layer "F.Fab")
		)
		(fp_line
			(start 0.120396 0.2794)
			(end -0.12065 0.2794)
			(stroke
				(width 0.1)
				(type default)
			)
			(layer "F.Fab")
		)
		(fp_line
			(start -0.12065 0.3048)
			(end -0.67945 0.3048)
			(stroke
				(width 0.1)
				(type default)
			)
			(layer "F.Fab")
		)
		(fp_line
			(start -0.12065 0.2794)
			(end -0.12065 0.3048)
			(stroke
				(width 0.1)
				(type default)
			)
			(layer "F.Fab")
		)
		(fp_line
			(start -0.12065 -0.2794)
			(end 0.12065 -0.2794)
			(stroke
				(width 0.1)
				(type default)
			)
			(layer "F.Fab")
		)
		(fp_line
			(start -0.12065 -0.305054)
			(end -0.12065 -0.2794)
			(stroke
				(width 0.1)
				(type default)
			)
			(layer "F.Fab")
		)
		(fp_line
			(start -0.67945 0.3048)
			(end -0.67945 -0.305054)
			(stroke
				(width 0.1)
				(type default)
			)
			(layer "F.Fab")
		)
		(fp_line
			(start -0.67945 -0.305054)
			(end -0.12065 -0.305054)
			(stroke
				(width 0.1)
				(type default)
			)
			(layer "F.Fab")
		)
		(pad "1" smd circle
			(at -0.40005 0 180)
			(size 0 0)
			(layers "F.Cu" "F.Mask" "F.Paste")
			(net "P3V3_AUX")
		)
		(pad "2" smd circle
			(at 0.40005 0 180)
			(size 0 0)
			(layers "F.Cu" "F.Mask" "F.Paste")
			(net "PU_BIC_UART_SEL")
		)
	)
	(footprint ""
		(layer "F.Cu")
		(at 415.487612 -350.098614 90)
		(property "Reference" "C2445"
			(at 0 0 90)
			(layer "F.SilkS")
			(hide yes)
			(effects
				(font
					(size 1.27 1.27)
				)
			)
		)
		(property "Value" ""
			(at 0 0 90)
			(layer "F.Fab")
			(effects
				(font
					(size 1.27 1.27)
				)
			)
		)
		(duplicate_pad_numbers_are_jumpers no)
		(fp_line
			(start 0.299974 -0.150114)
			(end 0.299974 0.150114)
			(stroke
				(width 0.1)
				(type default)
			)
			(layer "F.Fab")
		)
		(fp_line
			(start -0.299974 -0.150114)
			(end 0.299974 -0.150114)
			(stroke
				(width 0.1)
				(type default)
			)
			(layer "F.Fab")
		)
		(fp_line
			(start 0.299974 0.150114)
			(end -0.299974 0.150114)
			(stroke
				(width 0.1)
				(type default)
			)
			(layer "F.Fab")
		)
		(fp_line
			(start -0.299974 0.150114)
			(end -0.299974 -0.150114)
			(stroke
				(width 0.1)
				(type default)
			)
			(layer "F.Fab")
		)
		(pad "1" smd rect
			(at -0.2667 0 90)
			(size 0.3048 0.381)
			(layers "F.Cu" "F.Mask" "F.Paste")
			(net "P5E_PEX3_STN4_TX_DP<76>")
		)
		(pad "2" smd rect
			(at 0.2667 0 90)
			(size 0.3048 0.381)
			(layers "F.Cu" "F.Mask" "F.Paste")
			(net "P5E_PEX3_STN4_TX_C_DP<76>")
		)
	)
	(footprint ""
		(layer "F.Cu")
		(at 396.03426 -350.098614 90)
		(property "Reference" "C752"
			(at 0 0 90)
			(layer "F.SilkS")
			(hide yes)
			(effects
				(font
					(size 1.27 1.27)
				)
			)
		)
		(property "Value" ""
			(at 0 0 90)
			(layer "F.Fab")
			(effects
				(font
					(size 1.27 1.27)
				)
			)
		)
		(duplicate_pad_numbers_are_jumpers no)
		(fp_line
			(start 0.299974 -0.150114)
			(end 0.299974 0.150114)
			(stroke
				(width 0.1)
				(type default)
			)
			(layer "F.Fab")
		)
		(fp_line
			(start -0.299974 -0.150114)
			(end 0.299974 -0.150114)
			(stroke
				(width 0.1)
				(type default)
			)
			(layer "F.Fab")
		)
		(fp_line
			(start 0.299974 0.150114)
			(end -0.299974 0.150114)
			(stroke
				(width 0.1)
				(type default)
			)
			(layer "F.Fab")
		)
		(fp_line
			(start -0.299974 0.150114)
			(end -0.299974 -0.150114)
			(stroke
				(width 0.1)
				(type default)
			)
			(layer "F.Fab")
		)
		(pad "1" smd rect
			(at -0.2667 0 90)
			(size 0.3048 0.381)
			(layers "F.Cu" "F.Mask" "F.Paste")
			(net "P5E_PEX3_STN5_TX_DP<84>")
		)
		(pad "2" smd rect
			(at 0.2667 0 90)
			(size 0.3048 0.381)
			(layers "F.Cu" "F.Mask" "F.Paste")
			(net "P5E_PEX3_STN5_TX_C_DP<84>")
		)
	)
	(footprint ""
		(layer "F.Cu")
		(at 336.042 -154.686)
		(property "Reference" "R4788"
			(at 0 0 0)
			(layer "F.SilkS")
			(hide yes)
			(effects
				(font
					(size 1.27 1.27)
				)
			)
		)
		(property "Value" ""
			(at 0 0 0)
			(layer "F.Fab")
			(effects
				(font
					(size 1.27 1.27)
				)
			)
		)
		(duplicate_pad_numbers_are_jumpers no)
		(fp_line
			(start -0.7874 -0.4064)
			(end 0.7874 -0.4064)
			(stroke
				(width 0.1524)
				(type default)
			)
			(layer "F.SilkS")
		)
		(fp_line
			(start -0.7874 0.4064)
			(end -0.7874 -0.4064)
			(stroke
				(width 0.1524)
				(type default)
			)
			(layer "F.SilkS")
		)
		(fp_line
			(start 0.7874 -0.4064)
			(end 0.7874 0.4064)
			(stroke
				(width 0.1524)
				(type default)
			)
			(layer "F.SilkS")
		)
		(fp_line
			(start 0.7874 0.4064)
			(end -0.7874 0.4064)
			(stroke
				(width 0.1524)
				(type default)
			)
			(layer "F.SilkS")
		)
		(fp_line
			(start -0.67945 -0.305054)
			(end -0.12065 -0.305054)
			(stroke
				(width 0.1)
				(type default)
			)
			(layer "F.Fab")
		)
		(fp_line
			(start -0.67945 0.3048)
			(end -0.67945 -0.305054)
			(stroke
				(width 0.1)
				(type default)
			)
			(layer "F.Fab")
		)
		(fp_line
			(start -0.12065 -0.305054)
			(end -0.12065 -0.2794)
			(stroke
				(width 0.1)
				(type default)
			)
			(layer "F.Fab")
		)
		(fp_line
			(start -0.12065 -0.2794)
			(end 0.12065 -0.2794)
			(stroke
				(width 0.1)
				(type default)
			)
			(layer "F.Fab")
		)
		(fp_line
			(start -0.12065 0.2794)
			(end -0.12065 0.3048)
			(stroke
				(width 0.1)
				(type default)
			)
			(layer "F.Fab")
		)
		(fp_line
			(start -0.12065 0.3048)
			(end -0.67945 0.3048)
			(stroke
				(width 0.1)
				(type default)
			)
			(layer "F.Fab")
		)
		(fp_line
			(start 0.120396 0.2794)
			(end -0.12065 0.2794)
			(stroke
				(width 0.1)
				(type default)
			)
			(layer "F.Fab")
		)
		(fp_line
			(start 0.120396 0.3048)
			(end 0.120396 0.2794)
			(stroke
				(width 0.1)
				(type default)
			)
			(layer "F.Fab")
		)
		(fp_line
			(start 0.12065 -0.3048)
			(end 0.67945 -0.3048)
			(stroke
				(width 0.1)
				(type default)
			)
			(layer "F.Fab")
		)
		(fp_line
			(start 0.12065 -0.2794)
			(end 0.12065 -0.3048)
			(stroke
				(width 0.1)
				(type default)
			)
			(layer "F.Fab")
		)
		(fp_line
			(start 0.67945 -0.3048)
			(end 0.67945 0.3048)
			(stroke
				(width 0.1)
				(type default)
			)
			(layer "F.Fab")
		)
		(fp_line
			(start 0.67945 0.3048)
			(end 0.120396 0.3048)
			(stroke
				(width 0.1)
				(type default)
			)
			(layer "F.Fab")
		)
		(pad "1" smd circle
			(at -0.40005 0)
			(size 0 0)
			(layers "F.Cu" "F.Mask" "F.Paste")
			(net "P3V3_AUX")
		)
		(pad "2" smd circle
			(at 0.40005 0)
			(size 0 0)
			(layers "F.Cu" "F.Mask" "F.Paste")
			(net "SSD13_PEX_PWR_EN_R")
		)
	)
	(footprint ""
		(layer "F.Cu")
		(at 493.02416 -525.811496)
		(property "Reference" "SCREW_9"
			(at -0.5842 -1.31953 0)
			(unlocked yes)
			(layer "B.SilkS")
			(effects
				(font
					(size 0.7874 0.5842)
					(thickness 0.1524)
				)
				(justify left mirror)
			)
		)
		(property "Value" ""
			(at 0 0 0)
			(layer "F.Fab")
			(effects
				(font
					(size 1.27 1.27)
				)
			)
		)
		(duplicate_pad_numbers_are_jumpers no)
		(pad "1" thru_hole circle
			(at 0 0)
			(size 0.4572 0.4572)
			(drill 0.2032)
			(layers "*.Cu" "*.Mask")
			(remove_unused_layers no)
			(net "Net_9328")
			(clearance 0.127)
			(thermal_gap 0.127)
			(padstack
				(mode front_inner_back)
				(layer "Inner"
					(shape circle)
					(size 0.4572 0.4572)
					(clearance 0.127)
				)
				(layer "B.Cu"
					(shape circle)
					(size 0.508 0.508)
					(clearance 0.1016)
				)
			)
		)
	)
	(footprint ""
		(layer "F.Cu")
		(at 301.138336 -82.332068 180)
		(property "Reference" "R488"
			(at 0 0 180)
			(layer "F.SilkS")
			(hide yes)
			(effects
				(font
					(size 1.27 1.27)
				)
			)
		)
		(property "Value" ""
			(at 0 0 180)
			(layer "F.Fab")
			(effects
				(font
					(size 1.27 1.27)
				)
			)
		)
		(duplicate_pad_numbers_are_jumpers no)
		(fp_line
			(start 0.7874 0.4064)
			(end -0.7874 0.4064)
			(stroke
				(width 0.1524)
				(type default)
			)
			(layer "F.SilkS")
		)
		(fp_line
			(start 0.7874 -0.4064)
			(end 0.7874 0.4064)
			(stroke
				(width 0.1524)
				(type default)
			)
			(layer "F.SilkS")
		)
		(fp_line
			(start -0.7874 0.4064)
			(end -0.7874 -0.4064)
			(stroke
				(width 0.1524)
				(type default)
			)
			(layer "F.SilkS")
		)
		(fp_line
			(start -0.7874 -0.4064)
			(end 0.7874 -0.4064)
			(stroke
				(width 0.1524)
				(type default)
			)
			(layer "F.SilkS")
		)
		(fp_line
			(start 0.67945 0.3048)
			(end 0.120396 0.3048)
			(stroke
				(width 0.1)
				(type default)
			)
			(layer "F.Fab")
		)
		(fp_line
			(start 0.67945 -0.3048)
			(end 0.67945 0.3048)
			(stroke
				(width 0.1)
				(type default)
			)
			(layer "F.Fab")
		)
		(fp_line
			(start 0.12065 -0.2794)
			(end 0.12065 -0.3048)
			(stroke
				(width 0.1)
				(type default)
			)
			(layer "F.Fab")
		)
		(fp_line
			(start 0.12065 -0.3048)
			(end 0.67945 -0.3048)
			(stroke
				(width 0.1)
				(type default)
			)
			(layer "F.Fab")
		)
		(fp_line
			(start 0.120396 0.3048)
			(end 0.120396 0.2794)
			(stroke
				(width 0.1)
				(type default)
			)
			(layer "F.Fab")
		)
		(fp_line
			(start 0.120396 0.2794)
			(end -0.12065 0.2794)
			(stroke
				(width 0.1)
				(type default)
			)
			(layer "F.Fab")
		)
		(fp_line
			(start -0.12065 0.3048)
			(end -0.67945 0.3048)
			(stroke
				(width 0.1)
				(type default)
			)
			(layer "F.Fab")
		)
		(fp_line
			(start -0.12065 0.2794)
			(end -0.12065 0.3048)
			(stroke
				(width 0.1)
				(type default)
			)
			(layer "F.Fab")
		)
		(fp_line
			(start -0.12065 -0.2794)
			(end 0.12065 -0.2794)
			(stroke
				(width 0.1)
				(type default)
			)
			(layer "F.Fab")
		)
		(fp_line
			(start -0.12065 -0.305054)
			(end -0.12065 -0.2794)
			(stroke
				(width 0.1)
				(type default)
			)
			(layer "F.Fab")
		)
		(fp_line
			(start -0.67945 0.3048)
			(end -0.67945 -0.305054)
			(stroke
				(width 0.1)
				(type default)
			)
			(layer "F.Fab")
		)
		(fp_line
			(start -0.67945 -0.305054)
			(end -0.12065 -0.305054)
			(stroke
				(width 0.1)
				(type default)
			)
			(layer "F.Fab")
		)
		(pad "1" smd circle
			(at -0.40005 0 180)
			(size 0 0)
			(layers "F.Cu" "F.Mask" "F.Paste")
			(net "SMB_BIC_I2C6_MUX_FRU_R_SDA")
		)
		(pad "2" smd circle
			(at 0.40005 0 180)
			(size 0 0)
			(layers "F.Cu" "F.Mask" "F.Paste")
			(net "SMB_BMC_FRU_SDA")
		)
	)
	(footprint ""
		(layer "F.Cu")
		(at 438.497218 -309.0418 135)
		(property "Reference" "R1452"
			(at 0 0 135)
			(layer "F.SilkS")
			(hide yes)
			(effects
				(font
					(size 1.27 1.27)
				)
			)
		)
		(property "Value" ""
			(at 0 0 135)
			(layer "F.Fab")
			(effects
				(font
					(size 1.27 1.27)
				)
			)
		)
		(duplicate_pad_numbers_are_jumpers no)
		(fp_line
			(start 0.787389 -0.406267)
			(end 0.787389 0.406267)
			(stroke
				(width 0.1524)
				(type default)
			)
			(layer "F.SilkS")
		)
		(fp_line
			(start 0.787389 0.406267)
			(end -0.787389 0.406267)
			(stroke
				(width 0.1524)
				(type default)
			)
			(layer "F.SilkS")
		)
		(fp_line
			(start -0.787389 -0.406267)
			(end 0.787389 -0.406267)
			(stroke
				(width 0.1524)
				(type default)
			)
			(layer "F.SilkS")
		)
		(fp_line
			(start -0.787389 0.406267)
			(end -0.787389 -0.406267)
			(stroke
				(width 0.1524)
				(type default)
			)
			(layer "F.SilkS")
		)
		(fp_line
			(start 0.679446 -0.30479)
			(end 0.679446 0.30479)
			(stroke
				(width 0.1)
				(type default)
			)
			(layer "F.Fab")
		)
		(fp_line
			(start 0.120515 -0.30479)
			(end 0.679446 -0.30479)
			(stroke
				(width 0.1)
				(type default)
			)
			(layer "F.Fab")
		)
		(fp_line
			(start 0.120695 -0.279466)
			(end 0.120515 -0.30479)
			(stroke
				(width 0.1)
				(type default)
			)
			(layer "F.Fab")
		)
		(fp_line
			(start 0.679446 0.30479)
			(end 0.120515 0.30479)
			(stroke
				(width 0.1)
				(type default)
			)
			(layer "F.Fab")
		)
		(fp_line
			(start -0.120695 -0.304969)
			(end -0.120695 -0.279466)
			(stroke
				(width 0.1)
				(type default)
			)
			(layer "F.Fab")
		)
		(fp_line
			(start -0.120695 -0.279466)
			(end 0.120695 -0.279466)
			(stroke
				(width 0.1)
				(type default)
			)
			(layer "F.Fab")
		)
		(fp_line
			(start 0.120335 0.279466)
			(end -0.120695 0.279466)
			(stroke
				(width 0.1)
				(type default)
			)
			(layer "F.Fab")
		)
		(fp_line
			(start 0.120515 0.30479)
			(end 0.120335 0.279466)
			(stroke
				(width 0.1)
				(type default)
			)
			(layer "F.Fab")
		)
		(fp_line
			(start -0.679446 -0.305149)
			(end -0.120695 -0.304969)
			(stroke
				(width 0.1)
				(type default)
			)
			(layer "F.Fab")
		)
		(fp_line
			(start -0.120695 0.279466)
			(end -0.120515 0.30479)
			(stroke
				(width 0.1)
				(type default)
			)
			(layer "F.Fab")
		)
		(fp_line
			(start -0.120515 0.30479)
			(end -0.679446 0.30479)
			(stroke
				(width 0.1)
				(type default)
			)
			(layer "F.Fab")
		)
		(fp_line
			(start -0.679446 0.30479)
			(end -0.679446 -0.305149)
			(stroke
				(width 0.1)
				(type default)
			)
			(layer "F.Fab")
		)
		(pad "1" smd circle
			(at -0.40005 0 135)
			(size 0 0)
			(layers "F.Cu" "F.Mask" "F.Paste")
			(net "GND")
		)
		(pad "2" smd circle
			(at 0.40005 0 135)
			(size 0 0)
			(layers "F.Cu" "F.Mask" "F.Paste")
			(net "PEX3_SPARE2")
		)
	)
	(footprint ""
		(layer "F.Cu")
		(at 243.355114 -305.118262)
		(property "Reference" "PC251"
			(at 0 0 0)
			(layer "F.SilkS")
			(hide yes)
			(effects
				(font
					(size 1.27 1.27)
				)
			)
		)
		(property "Value" ""
			(at 0 0 0)
			(layer "F.Fab")
			(effects
				(font
					(size 1.27 1.27)
				)
			)
		)
		(duplicate_pad_numbers_are_jumpers no)
		(fp_line
			(start -0.7874 -0.4064)
			(end 0.7874 -0.4064)
			(stroke
				(width 0.1524)
				(type default)
			)
			(layer "F.SilkS")
		)
		(fp_line
			(start -0.7874 0.4064)
			(end -0.7874 -0.4064)
			(stroke
				(width 0.1524)
				(type default)
			)
			(layer "F.SilkS")
		)
		(fp_line
			(start 0.7874 -0.4064)
			(end 0.7874 0.4064)
			(stroke
				(width 0.1524)
				(type default)
			)
			(layer "F.SilkS")
		)
		(fp_line
			(start 0.7874 0.4064)
			(end -0.7874 0.4064)
			(stroke
				(width 0.1524)
				(type default)
			)
			(layer "F.SilkS")
		)
		(fp_line
			(start -0.67945 -0.305054)
			(end -0.12065 -0.305054)
			(stroke
				(width 0.1)
				(type default)
			)
			(layer "F.Fab")
		)
		(fp_line
			(start -0.67945 0.3048)
			(end -0.67945 -0.305054)
			(stroke
				(width 0.1)
				(type default)
			)
			(layer "F.Fab")
		)
		(fp_line
			(start -0.12065 -0.305054)
			(end -0.12065 -0.2794)
			(stroke
				(width 0.1)
				(type default)
			)
			(layer "F.Fab")
		)
		(fp_line
			(start -0.12065 -0.2794)
			(end 0.12065 -0.2794)
			(stroke
				(width 0.1)
				(type default)
			)
			(layer "F.Fab")
		)
		(fp_line
			(start -0.12065 0.2794)
			(end -0.12065 0.3048)
			(stroke
				(width 0.1)
				(type default)
			)
			(layer "F.Fab")
		)
		(fp_line
			(start -0.12065 0.3048)
			(end -0.67945 0.3048)
			(stroke
				(width 0.1)
				(type default)
			)
			(layer "F.Fab")
		)
		(fp_line
			(start 0.120396 0.2794)
			(end -0.12065 0.2794)
			(stroke
				(width 0.1)
				(type default)
			)
			(layer "F.Fab")
		)
		(fp_line
			(start 0.120396 0.3048)
			(end 0.120396 0.2794)
			(stroke
				(width 0.1)
				(type default)
			)
			(layer "F.Fab")
		)
		(fp_line
			(start 0.12065 -0.3048)
			(end 0.67945 -0.3048)
			(stroke
				(width 0.1)
				(type default)
			)
			(layer "F.Fab")
		)
		(fp_line
			(start 0.12065 -0.2794)
			(end 0.12065 -0.3048)
			(stroke
				(width 0.1)
				(type default)
			)
			(layer "F.Fab")
		)
		(fp_line
			(start 0.67945 -0.3048)
			(end 0.67945 0.3048)
			(stroke
				(width 0.1)
				(type default)
			)
			(layer "F.Fab")
		)
		(fp_line
			(start 0.67945 0.3048)
			(end 0.120396 0.3048)
			(stroke
				(width 0.1)
				(type default)
			)
			(layer "F.Fab")
		)
		(pad "1" smd circle
			(at -0.40005 0)
			(size 0 0)
			(layers "F.Cu" "F.Mask" "F.Paste")
			(net "SW_P1V25_PEX2_BT")
		)
		(pad "2" smd circle
			(at 0.40005 0)
			(size 0 0)
			(layers "F.Cu" "F.Mask" "F.Paste")
			(net "SW_P1V25_PEX2_PH")
		)
	)
	(footprint ""
		(layer "F.Cu")
		(at 214.773002 -22.867366 90)
		(property "Reference" "C3921"
			(at 0 0 90)
			(layer "F.SilkS")
			(hide yes)
			(effects
				(font
					(size 1.27 1.27)
				)
			)
		)
		(property "Value" ""
			(at 0 0 90)
			(layer "F.Fab")
			(effects
				(font
					(size 1.27 1.27)
				)
			)
		)
		(duplicate_pad_numbers_are_jumpers no)
		(fp_line
			(start 0.7874 -0.4064)
			(end 0.7874 0.4064)
			(stroke
				(width 0.1524)
				(type default)
			)
			(layer "F.SilkS")
		)
		(fp_line
			(start -0.7874 -0.4064)
			(end 0.7874 -0.4064)
			(stroke
				(width 0.1524)
				(type default)
			)
			(layer "F.SilkS")
		)
		(fp_line
			(start 0.7874 0.4064)
			(end -0.7874 0.4064)
			(stroke
				(width 0.1524)
				(type default)
			)
			(layer "F.SilkS")
		)
		(fp_line
			(start -0.7874 0.4064)
			(end -0.7874 -0.4064)
			(stroke
				(width 0.1524)
				(type default)
			)
			(layer "F.SilkS")
		)
		(fp_line
			(start -0.12065 -0.305054)
			(end -0.12065 -0.2794)
			(stroke
				(width 0.1)
				(type default)
			)
			(layer "F.Fab")
		)
		(fp_line
			(start -0.67945 -0.305054)
			(end -0.12065 -0.305054)
			(stroke
				(width 0.1)
				(type default)
			)
			(layer "F.Fab")
		)
		(fp_line
			(start 0.67945 -0.3048)
			(end 0.67945 0.3048)
			(stroke
				(width 0.1)
				(type default)
			)
			(layer "F.Fab")
		)
		(fp_line
			(start 0.12065 -0.3048)
			(end 0.67945 -0.3048)
			(stroke
				(width 0.1)
				(type default)
			)
			(layer "F.Fab")
		)
		(fp_line
			(start 0.12065 -0.2794)
			(end 0.12065 -0.3048)
			(stroke
				(width 0.1)
				(type default)
			)
			(layer "F.Fab")
		)
		(fp_line
			(start -0.12065 -0.2794)
			(end 0.12065 -0.2794)
			(stroke
				(width 0.1)
				(type default)
			)
			(layer "F.Fab")
		)
		(fp_line
			(start 0.120396 0.2794)
			(end -0.12065 0.2794)
			(stroke
				(width 0.1)
				(type default)
			)
			(layer "F.Fab")
		)
		(fp_line
			(start -0.12065 0.2794)
			(end -0.12065 0.3048)
			(stroke
				(width 0.1)
				(type default)
			)
			(layer "F.Fab")
		)
		(fp_line
			(start 0.67945 0.3048)
			(end 0.120396 0.3048)
			(stroke
				(width 0.1)
				(type default)
			)
			(layer "F.Fab")
		)
		(fp_line
			(start 0.120396 0.3048)
			(end 0.120396 0.2794)
			(stroke
				(width 0.1)
				(type default)
			)
			(layer "F.Fab")
		)
		(fp_line
			(start -0.12065 0.3048)
			(end -0.67945 0.3048)
			(stroke
				(width 0.1)
				(type default)
			)
			(layer "F.Fab")
		)
		(fp_line
			(start -0.67945 0.3048)
			(end -0.67945 -0.305054)
			(stroke
				(width 0.1)
				(type default)
			)
			(layer "F.Fab")
		)
		(pad "1" smd circle
			(at -0.40005 0 90)
			(size 0 0)
			(layers "F.Cu" "F.Mask" "F.Paste")
			(net "P12V_SSD7")
		)
		(pad "2" smd circle
			(at 0.40005 0 90)
			(size 0 0)
			(layers "F.Cu" "F.Mask" "F.Paste")
			(net "GND")
		)
	)
	(footprint ""
		(layer "F.Cu")
		(at 167.164512 -29.079952 180)
		(property "Reference" "R6203"
			(at 0 0 180)
			(layer "F.SilkS")
			(hide yes)
			(effects
				(font
					(size 1.27 1.27)
				)
			)
		)
		(property "Value" ""
			(at 0 0 180)
			(layer "F.Fab")
			(effects
				(font
					(size 1.27 1.27)
				)
			)
		)
		(duplicate_pad_numbers_are_jumpers no)
		(fp_line
			(start 0.7874 0.4064)
			(end -0.7874 0.4064)
			(stroke
				(width 0.1524)
				(type default)
			)
			(layer "F.SilkS")
		)
		(fp_line
			(start 0.7874 -0.4064)
			(end 0.7874 0.4064)
			(stroke
				(width 0.1524)
				(type default)
			)
			(layer "F.SilkS")
		)
		(fp_line
			(start -0.7874 0.4064)
			(end -0.7874 -0.4064)
			(stroke
				(width 0.1524)
				(type default)
			)
			(layer "F.SilkS")
		)
		(fp_line
			(start -0.7874 -0.4064)
			(end 0.7874 -0.4064)
			(stroke
				(width 0.1524)
				(type default)
			)
			(layer "F.SilkS")
		)
		(fp_line
			(start 0.67945 0.3048)
			(end 0.120396 0.3048)
			(stroke
				(width 0.1)
				(type default)
			)
			(layer "F.Fab")
		)
		(fp_line
			(start 0.67945 -0.3048)
			(end 0.67945 0.3048)
			(stroke
				(width 0.1)
				(type default)
			)
			(layer "F.Fab")
		)
		(fp_line
			(start 0.12065 -0.2794)
			(end 0.12065 -0.3048)
			(stroke
				(width 0.1)
				(type default)
			)
			(layer "F.Fab")
		)
		(fp_line
			(start 0.12065 -0.3048)
			(end 0.67945 -0.3048)
			(stroke
				(width 0.1)
				(type default)
			)
			(layer "F.Fab")
		)
		(fp_line
			(start 0.120396 0.3048)
			(end 0.120396 0.2794)
			(stroke
				(width 0.1)
				(type default)
			)
			(layer "F.Fab")
		)
		(fp_line
			(start 0.120396 0.2794)
			(end -0.12065 0.2794)
			(stroke
				(width 0.1)
				(type default)
			)
			(layer "F.Fab")
		)
		(fp_line
			(start -0.12065 0.3048)
			(end -0.67945 0.3048)
			(stroke
				(width 0.1)
				(type default)
			)
			(layer "F.Fab")
		)
		(fp_line
			(start -0.12065 0.2794)
			(end -0.12065 0.3048)
			(stroke
				(width 0.1)
				(type default)
			)
			(layer "F.Fab")
		)
		(fp_line
			(start -0.12065 -0.2794)
			(end 0.12065 -0.2794)
			(stroke
				(width 0.1)
				(type default)
			)
			(layer "F.Fab")
		)
		(fp_line
			(start -0.12065 -0.305054)
			(end -0.12065 -0.2794)
			(stroke
				(width 0.1)
				(type default)
			)
			(layer "F.Fab")
		)
		(fp_line
			(start -0.67945 0.3048)
			(end -0.67945 -0.305054)
			(stroke
				(width 0.1)
				(type default)
			)
			(layer "F.Fab")
		)
		(fp_line
			(start -0.67945 -0.305054)
			(end -0.12065 -0.305054)
			(stroke
				(width 0.1)
				(type default)
			)
			(layer "F.Fab")
		)
		(pad "1" smd circle
			(at -0.40005 0 180)
			(size 0 0)
			(layers "F.Cu" "F.Mask" "F.Paste")
			(net "GND")
		)
		(pad "2" smd circle
			(at 0.40005 0 180)
			(size 0 0)
			(layers "F.Cu" "F.Mask" "F.Paste")
			(net "SSD5_PWRDIS_R")
		)
	)
	(footprint ""
		(layer "F.Cu")
		(at 430.961546 -156.111194 180)
		(property "Reference" "C634"
			(at 0 0 180)
			(layer "F.SilkS")
			(hide yes)
			(effects
				(font
					(size 1.27 1.27)
				)
			)
		)
		(property "Value" ""
			(at 0 0 180)
			(layer "F.Fab")
			(effects
				(font
					(size 1.27 1.27)
				)
			)
		)
		(duplicate_pad_numbers_are_jumpers no)
		(fp_line
			(start 0.299974 0.150114)
			(end -0.299974 0.150114)
			(stroke
				(width 0.1)
				(type default)
			)
			(layer "F.Fab")
		)
		(fp_line
			(start 0.299974 -0.150114)
			(end 0.299974 0.150114)
			(stroke
				(width 0.1)
				(type default)
			)
			(layer "F.Fab")
		)
		(fp_line
			(start -0.299974 0.150114)
			(end -0.299974 -0.150114)
			(stroke
				(width 0.1)
				(type default)
			)
			(layer "F.Fab")
		)
		(fp_line
			(start -0.299974 -0.150114)
			(end 0.299974 -0.150114)
			(stroke
				(width 0.1)
				(type default)
			)
			(layer "F.Fab")
		)
		(pad "1" smd rect
			(at -0.2667 0 180)
			(size 0.3048 0.381)
			(layers "F.Cu" "F.Mask" "F.Paste")
			(net "P5E_PEX3_STN0_TX_DP<15>")
		)
		(pad "2" smd rect
			(at 0.2667 0 180)
			(size 0.3048 0.381)
			(layers "F.Cu" "F.Mask" "F.Paste")
			(net "P5E_PEX3_STN0_TX_C_DP<15>")
		)
	)
	(footprint ""
		(layer "F.Cu")
		(at 355.300788 -293.5351 90)
		(property "Reference" "PL15"
			(at -4.976876 14.56182 90)
			(unlocked yes)
			(layer "F.SilkS")
			(effects
				(font
					(size 0.7874 0.5842)
					(thickness 0.1524)
				)
				(justify left)
			)
		)
		(property "Value" ""
			(at 0 0 90)
			(layer "F.Fab")
			(effects
				(font
					(size 1.27 1.27)
				)
			)
		)
		(duplicate_pad_numbers_are_jumpers no)
		(fp_line
			(start 4.800092 -3.199892)
			(end 4.800092 -1.6764)
			(stroke
				(width 0.1524)
				(type default)
			)
			(layer "F.SilkS")
		)
		(fp_line
			(start -4.800092 -3.199892)
			(end 4.800092 -3.199892)
			(stroke
				(width 0.1524)
				(type default)
			)
			(layer "F.SilkS")
		)
		(fp_line
			(start -4.800092 -1.6764)
			(end -4.800092 -3.199892)
			(stroke
				(width 0.1524)
				(type default)
			)
			(layer "F.SilkS")
		)
		(fp_line
			(start 4.800092 1.6764)
			(end 4.800092 3.199892)
			(stroke
				(width 0.1524)
				(type default)
			)
			(layer "F.SilkS")
		)
		(fp_line
			(start 4.800092 3.199892)
			(end -4.800092 3.199892)
			(stroke
				(width 0.1524)
				(type default)
			)
			(layer "F.SilkS")
		)
		(fp_line
			(start -4.800092 3.199892)
			(end -4.800092 1.6764)
			(stroke
				(width 0.1524)
				(type default)
			)
			(layer "F.SilkS")
		)
		(fp_line
			(start 4.800092 -3.199892)
			(end 4.800092 3.199892)
			(stroke
				(width 0.1)
				(type default)
			)
			(layer "F.Fab")
		)
		(fp_line
			(start -4.800092 -3.199892)
			(end 4.800092 -3.199892)
			(stroke
				(width 0.1)
				(type default)
			)
			(layer "F.Fab")
		)
		(fp_line
			(start 4.800092 3.199892)
			(end -4.800092 3.199892)
			(stroke
				(width 0.1)
				(type default)
			)
			(layer "F.Fab")
		)
		(fp_line
			(start -4.800092 3.199892)
			(end -4.800092 -3.199892)
			(stroke
				(width 0.1)
				(type default)
			)
			(layer "F.Fab")
		)
		(pad "1" smd rect
			(at -3.074924 0 180)
			(size 3.0988 3.3528)
			(layers "F.Cu" "F.Mask" "F.Paste")
			(net "SW_P0V8_PEX3_PH1")
		)
		(pad "2" smd rect
			(at 3.074924 0 180)
			(size 3.0988 3.3528)
			(layers "F.Cu" "F.Mask" "F.Paste")
			(net "P0V8_PEX3")
		)
	)
	(footprint ""
		(layer "F.Cu")
		(at 319.191386 -96.811592 -90)
		(property "Reference" "R736"
			(at 0 0 270)
			(layer "F.SilkS")
			(hide yes)
			(effects
				(font
					(size 1.27 1.27)
				)
			)
		)
		(property "Value" ""
			(at 0 0 270)
			(layer "F.Fab")
			(effects
				(font
					(size 1.27 1.27)
				)
			)
		)
		(duplicate_pad_numbers_are_jumpers no)
		(fp_line
			(start -0.7874 0.4064)
			(end -0.7874 -0.4064)
			(stroke
				(width 0.1524)
				(type default)
			)
			(layer "F.SilkS")
		)
		(fp_line
			(start 0.7874 0.4064)
			(end -0.7874 0.4064)
			(stroke
				(width 0.1524)
				(type default)
			)
			(layer "F.SilkS")
		)
		(fp_line
			(start -0.7874 -0.4064)
			(end 0.7874 -0.4064)
			(stroke
				(width 0.1524)
				(type default)
			)
			(layer "F.SilkS")
		)
		(fp_line
			(start 0.7874 -0.4064)
			(end 0.7874 0.4064)
			(stroke
				(width 0.1524)
				(type default)
			)
			(layer "F.SilkS")
		)
		(fp_line
			(start -0.67945 0.3048)
			(end -0.67945 -0.305054)
			(stroke
				(width 0.1)
				(type default)
			)
			(layer "F.Fab")
		)
		(fp_line
			(start -0.12065 0.3048)
			(end -0.67945 0.3048)
			(stroke
				(width 0.1)
				(type default)
			)
			(layer "F.Fab")
		)
		(fp_line
			(start 0.120396 0.3048)
			(end 0.120396 0.2794)
			(stroke
				(width 0.1)
				(type default)
			)
			(layer "F.Fab")
		)
		(fp_line
			(start 0.67945 0.3048)
			(end 0.120396 0.3048)
			(stroke
				(width 0.1)
				(type default)
			)
			(layer "F.Fab")
		)
		(fp_line
			(start -0.12065 0.2794)
			(end -0.12065 0.3048)
			(stroke
				(width 0.1)
				(type default)
			)
			(layer "F.Fab")
		)
		(fp_line
			(start 0.120396 0.2794)
			(end -0.12065 0.2794)
			(stroke
				(width 0.1)
				(type default)
			)
			(layer "F.Fab")
		)
		(fp_line
			(start -0.12065 -0.2794)
			(end 0.12065 -0.2794)
			(stroke
				(width 0.1)
				(type default)
			)
			(layer "F.Fab")
		)
		(fp_line
			(start 0.12065 -0.2794)
			(end 0.12065 -0.3048)
			(stroke
				(width 0.1)
				(type default)
			)
			(layer "F.Fab")
		)
		(fp_line
			(start 0.12065 -0.3048)
			(end 0.67945 -0.3048)
			(stroke
				(width 0.1)
				(type default)
			)
			(layer "F.Fab")
		)
		(fp_line
			(start 0.67945 -0.3048)
			(end 0.67945 0.3048)
			(stroke
				(width 0.1)
				(type default)
			)
			(layer "F.Fab")
		)
		(fp_line
			(start -0.67945 -0.305054)
			(end -0.12065 -0.305054)
			(stroke
				(width 0.1)
				(type default)
			)
			(layer "F.Fab")
		)
		(fp_line
			(start -0.12065 -0.305054)
			(end -0.12065 -0.2794)
			(stroke
				(width 0.1)
				(type default)
			)
			(layer "F.Fab")
		)
		(pad "1" smd circle
			(at -0.40005 0 270)
			(size 0 0)
			(layers "F.Cu" "F.Mask" "F.Paste")
			(net "NIC5_ADC_A1")
		)
		(pad "2" smd circle
			(at 0.40005 0 270)
			(size 0 0)
			(layers "F.Cu" "F.Mask" "F.Paste")
			(net "P3V3_AUX")
		)
	)
	(footprint ""
		(layer "F.Cu")
		(at 118.595394 -35.48253)
		(property "Reference" "U387"
			(at -2.566924 1.70053 90)
			(unlocked yes)
			(layer "F.SilkS")
			(effects
				(font
					(size 0.7874 0.5842)
					(thickness 0.1524)
				)
				(justify left)
			)
		)
		(property "Value" ""
			(at 0 0 0)
			(layer "F.Fab")
			(effects
				(font
					(size 1.27 1.27)
				)
			)
		)
		(duplicate_pad_numbers_are_jumpers no)
		(fp_line
			(start -1.3462 -1.1938)
			(end -1.3462 1.1684)
			(stroke
				(width 0.1524)
				(type default)
			)
			(layer "F.SilkS")
		)
		(fp_line
			(start -1.3462 1.1938)
			(end 1.3462 1.1938)
			(stroke
				(width 0.1524)
				(type default)
			)
			(layer "F.SilkS")
		)
		(fp_line
			(start 1.3462 -1.1938)
			(end -1.3462 -1.1938)
			(stroke
				(width 0.1524)
				(type default)
			)
			(layer "F.SilkS")
		)
		(fp_line
			(start 1.3462 1.1938)
			(end 1.3462 -1.1938)
			(stroke
				(width 0.1524)
				(type default)
			)
			(layer "F.SilkS")
		)
		(fp_poly
			(pts
				(xy -1.447038 -0.760476) (xy -2.052066 -0.457962) (xy -2.052066 -1.06299)
			)
			(stroke
				(width 0)
				(type default)
			)
			(fill yes)
			(layer "F.SilkS")
		)
		(fp_line
			(start -0.674878 -1.124966)
			(end -0.674878 1.124966)
			(stroke
				(width 0.1)
				(type default)
			)
			(layer "F.Fab")
		)
		(fp_line
			(start -0.674878 1.124966)
			(end 0.674878 1.124966)
			(stroke
				(width 0.1)
				(type default)
			)
			(layer "F.Fab")
		)
		(fp_line
			(start 0.674878 -1.124966)
			(end -0.674878 -1.124966)
			(stroke
				(width 0.1)
				(type default)
			)
			(layer "F.Fab")
		)
		(fp_line
			(start 0.674878 1.124966)
			(end 0.674878 -1.124966)
			(stroke
				(width 0.1)
				(type default)
			)
			(layer "F.Fab")
		)
		(fp_poly
			(pts
				(xy -1.447038 -0.760476) (xy -2.052066 -0.457962) (xy -2.052066 -1.06299)
			)
			(stroke
				(width 0)
				(type default)
			)
			(fill yes)
			(layer "F.Fab")
		)
		(pad "1" smd rect
			(at -0.899922 -0.750062)
			(size 0.6096 0.6096)
			(layers "F.Cu" "F.Mask" "F.Paste")
			(net "PWRGD_P3V3_SSD4_R")
		)
		(pad "2" smd rect
			(at -0.899922 0 90)
			(size 0.4064 0.6096)
			(layers "F.Cu" "F.Mask" "F.Paste")
			(net "RST_SMB_SSD4_N")
		)
		(pad "3" smd rect
			(at -0.899922 0.750062)
			(size 0.6096 0.6096)
			(layers "F.Cu" "F.Mask" "F.Paste")
			(net "GND")
		)
		(pad "4" smd rect
			(at 0.899922 0.750062)
			(size 0.6096 0.6096)
			(layers "F.Cu" "F.Mask" "F.Paste")
			(net "RST_SMB_SSD4_ISO_N")
		)
		(pad "5" smd rect
			(at 0.899922 -0.750062)
			(size 0.6096 0.6096)
			(layers "F.Cu" "F.Mask" "F.Paste")
			(net "P3V3_AUX")
		)
	)
	(footprint ""
		(layer "F.Cu")
		(at 320.207386 -96.811592 -90)
		(property "Reference" "R741"
			(at 0 0 270)
			(layer "F.SilkS")
			(hide yes)
			(effects
				(font
					(size 1.27 1.27)
				)
			)
		)
		(property "Value" ""
			(at 0 0 270)
			(layer "F.Fab")
			(effects
				(font
					(size 1.27 1.27)
				)
			)
		)
		(duplicate_pad_numbers_are_jumpers no)
		(fp_line
			(start -0.7874 0.4064)
			(end -0.7874 -0.4064)
			(stroke
				(width 0.1524)
				(type default)
			)
			(layer "F.SilkS")
		)
		(fp_line
			(start 0.7874 0.4064)
			(end -0.7874 0.4064)
			(stroke
				(width 0.1524)
				(type default)
			)
			(layer "F.SilkS")
		)
		(fp_line
			(start -0.7874 -0.4064)
			(end 0.7874 -0.4064)
			(stroke
				(width 0.1524)
				(type default)
			)
			(layer "F.SilkS")
		)
		(fp_line
			(start 0.7874 -0.4064)
			(end 0.7874 0.4064)
			(stroke
				(width 0.1524)
				(type default)
			)
			(layer "F.SilkS")
		)
		(fp_line
			(start -0.67945 0.3048)
			(end -0.67945 -0.305054)
			(stroke
				(width 0.1)
				(type default)
			)
			(layer "F.Fab")
		)
		(fp_line
			(start -0.12065 0.3048)
			(end -0.67945 0.3048)
			(stroke
				(width 0.1)
				(type default)
			)
			(layer "F.Fab")
		)
		(fp_line
			(start 0.120396 0.3048)
			(end 0.120396 0.2794)
			(stroke
				(width 0.1)
				(type default)
			)
			(layer "F.Fab")
		)
		(fp_line
			(start 0.67945 0.3048)
			(end 0.120396 0.3048)
			(stroke
				(width 0.1)
				(type default)
			)
			(layer "F.Fab")
		)
		(fp_line
			(start -0.12065 0.2794)
			(end -0.12065 0.3048)
			(stroke
				(width 0.1)
				(type default)
			)
			(layer "F.Fab")
		)
		(fp_line
			(start 0.120396 0.2794)
			(end -0.12065 0.2794)
			(stroke
				(width 0.1)
				(type default)
			)
			(layer "F.Fab")
		)
		(fp_line
			(start -0.12065 -0.2794)
			(end 0.12065 -0.2794)
			(stroke
				(width 0.1)
				(type default)
			)
			(layer "F.Fab")
		)
		(fp_line
			(start 0.12065 -0.2794)
			(end 0.12065 -0.3048)
			(stroke
				(width 0.1)
				(type default)
			)
			(layer "F.Fab")
		)
		(fp_line
			(start 0.12065 -0.3048)
			(end 0.67945 -0.3048)
			(stroke
				(width 0.1)
				(type default)
			)
			(layer "F.Fab")
		)
		(fp_line
			(start 0.67945 -0.3048)
			(end 0.67945 0.3048)
			(stroke
				(width 0.1)
				(type default)
			)
			(layer "F.Fab")
		)
		(fp_line
			(start -0.67945 -0.305054)
			(end -0.12065 -0.305054)
			(stroke
				(width 0.1)
				(type default)
			)
			(layer "F.Fab")
		)
		(fp_line
			(start -0.12065 -0.305054)
			(end -0.12065 -0.2794)
			(stroke
				(width 0.1)
				(type default)
			)
			(layer "F.Fab")
		)
		(pad "1" smd circle
			(at -0.40005 0 270)
			(size 0 0)
			(layers "F.Cu" "F.Mask" "F.Paste")
			(net "NIC5_ADC_A1")
		)
		(pad "2" smd circle
			(at 0.40005 0 270)
			(size 0 0)
			(layers "F.Cu" "F.Mask" "F.Paste")
			(net "GND")
		)
	)
	(footprint ""
		(layer "F.Cu")
		(at 376.936 -183.769)
		(property "Reference" "R4650"
			(at 0 0 0)
			(layer "F.SilkS")
			(hide yes)
			(effects
				(font
					(size 1.27 1.27)
				)
			)
		)
		(property "Value" ""
			(at 0 0 0)
			(layer "F.Fab")
			(effects
				(font
					(size 1.27 1.27)
				)
			)
		)
		(duplicate_pad_numbers_are_jumpers no)
		(fp_line
			(start -0.7874 -0.4064)
			(end 0.7874 -0.4064)
			(stroke
				(width 0.1524)
				(type default)
			)
			(layer "F.SilkS")
		)
		(fp_line
			(start -0.7874 0.4064)
			(end -0.7874 -0.4064)
			(stroke
				(width 0.1524)
				(type default)
			)
			(layer "F.SilkS")
		)
		(fp_line
			(start 0.7874 -0.4064)
			(end 0.7874 0.4064)
			(stroke
				(width 0.1524)
				(type default)
			)
			(layer "F.SilkS")
		)
		(fp_line
			(start 0.7874 0.4064)
			(end -0.7874 0.4064)
			(stroke
				(width 0.1524)
				(type default)
			)
			(layer "F.SilkS")
		)
		(fp_line
			(start -0.67945 -0.305054)
			(end -0.12065 -0.305054)
			(stroke
				(width 0.1)
				(type default)
			)
			(layer "F.Fab")
		)
		(fp_line
			(start -0.67945 0.3048)
			(end -0.67945 -0.305054)
			(stroke
				(width 0.1)
				(type default)
			)
			(layer "F.Fab")
		)
		(fp_line
			(start -0.12065 -0.305054)
			(end -0.12065 -0.2794)
			(stroke
				(width 0.1)
				(type default)
			)
			(layer "F.Fab")
		)
		(fp_line
			(start -0.12065 -0.2794)
			(end 0.12065 -0.2794)
			(stroke
				(width 0.1)
				(type default)
			)
			(layer "F.Fab")
		)
		(fp_line
			(start -0.12065 0.2794)
			(end -0.12065 0.3048)
			(stroke
				(width 0.1)
				(type default)
			)
			(layer "F.Fab")
		)
		(fp_line
			(start -0.12065 0.3048)
			(end -0.67945 0.3048)
			(stroke
				(width 0.1)
				(type default)
			)
			(layer "F.Fab")
		)
		(fp_line
			(start 0.120396 0.2794)
			(end -0.12065 0.2794)
			(stroke
				(width 0.1)
				(type default)
			)
			(layer "F.Fab")
		)
		(fp_line
			(start 0.120396 0.3048)
			(end 0.120396 0.2794)
			(stroke
				(width 0.1)
				(type default)
			)
			(layer "F.Fab")
		)
		(fp_line
			(start 0.12065 -0.3048)
			(end 0.67945 -0.3048)
			(stroke
				(width 0.1)
				(type default)
			)
			(layer "F.Fab")
		)
		(fp_line
			(start 0.12065 -0.2794)
			(end 0.12065 -0.3048)
			(stroke
				(width 0.1)
				(type default)
			)
			(layer "F.Fab")
		)
		(fp_line
			(start 0.67945 -0.3048)
			(end 0.67945 0.3048)
			(stroke
				(width 0.1)
				(type default)
			)
			(layer "F.Fab")
		)
		(fp_line
			(start 0.67945 0.3048)
			(end 0.120396 0.3048)
			(stroke
				(width 0.1)
				(type default)
			)
			(layer "F.Fab")
		)
		(pad "1" smd circle
			(at -0.40005 0)
			(size 0 0)
			(layers "F.Cu" "F.Mask" "F.Paste")
			(net "PRSNT_NIC1_FPGA_PCA9555_N")
		)
		(pad "2" smd circle
			(at 0.40005 0)
			(size 0 0)
			(layers "F.Cu" "F.Mask" "F.Paste")
			(net "PRSNT_NIC1_FPGA_R_N")
		)
	)
	(footprint ""
		(layer "F.Cu")
		(at 10.577322 -119.105426 90)
		(property "Reference" "R5858"
			(at 0 0 90)
			(layer "F.SilkS")
			(hide yes)
			(effects
				(font
					(size 1.27 1.27)
				)
			)
		)
		(property "Value" ""
			(at 0 0 90)
			(layer "F.Fab")
			(effects
				(font
					(size 1.27 1.27)
				)
			)
		)
		(duplicate_pad_numbers_are_jumpers no)
		(fp_line
			(start 0.7874 -0.4064)
			(end 0.7874 0.4064)
			(stroke
				(width 0.1524)
				(type default)
			)
			(layer "F.SilkS")
		)
		(fp_line
			(start -0.7874 -0.4064)
			(end 0.7874 -0.4064)
			(stroke
				(width 0.1524)
				(type default)
			)
			(layer "F.SilkS")
		)
		(fp_line
			(start 0.7874 0.4064)
			(end -0.7874 0.4064)
			(stroke
				(width 0.1524)
				(type default)
			)
			(layer "F.SilkS")
		)
		(fp_line
			(start -0.7874 0.4064)
			(end -0.7874 -0.4064)
			(stroke
				(width 0.1524)
				(type default)
			)
			(layer "F.SilkS")
		)
		(fp_line
			(start -0.12065 -0.305054)
			(end -0.12065 -0.2794)
			(stroke
				(width 0.1)
				(type default)
			)
			(layer "F.Fab")
		)
		(fp_line
			(start -0.67945 -0.305054)
			(end -0.12065 -0.305054)
			(stroke
				(width 0.1)
				(type default)
			)
			(layer "F.Fab")
		)
		(fp_line
			(start 0.67945 -0.3048)
			(end 0.67945 0.3048)
			(stroke
				(width 0.1)
				(type default)
			)
			(layer "F.Fab")
		)
		(fp_line
			(start 0.12065 -0.3048)
			(end 0.67945 -0.3048)
			(stroke
				(width 0.1)
				(type default)
			)
			(layer "F.Fab")
		)
		(fp_line
			(start 0.12065 -0.2794)
			(end 0.12065 -0.3048)
			(stroke
				(width 0.1)
				(type default)
			)
			(layer "F.Fab")
		)
		(fp_line
			(start -0.12065 -0.2794)
			(end 0.12065 -0.2794)
			(stroke
				(width 0.1)
				(type default)
			)
			(layer "F.Fab")
		)
		(fp_line
			(start 0.120396 0.2794)
			(end -0.12065 0.2794)
			(stroke
				(width 0.1)
				(type default)
			)
			(layer "F.Fab")
		)
		(fp_line
			(start -0.12065 0.2794)
			(end -0.12065 0.3048)
			(stroke
				(width 0.1)
				(type default)
			)
			(layer "F.Fab")
		)
		(fp_line
			(start 0.67945 0.3048)
			(end 0.120396 0.3048)
			(stroke
				(width 0.1)
				(type default)
			)
			(layer "F.Fab")
		)
		(fp_line
			(start 0.120396 0.3048)
			(end 0.120396 0.2794)
			(stroke
				(width 0.1)
				(type default)
			)
			(layer "F.Fab")
		)
		(fp_line
			(start -0.12065 0.3048)
			(end -0.67945 0.3048)
			(stroke
				(width 0.1)
				(type default)
			)
			(layer "F.Fab")
		)
		(fp_line
			(start -0.67945 0.3048)
			(end -0.67945 -0.305054)
			(stroke
				(width 0.1)
				(type default)
			)
			(layer "F.Fab")
		)
		(pad "1" smd circle
			(at -0.40005 0 90)
			(size 0 0)
			(layers "F.Cu" "F.Mask" "F.Paste")
			(net "PWRGD_P3V3_NIC0_D")
		)
		(pad "2" smd circle
			(at 0.40005 0 90)
			(size 0 0)
			(layers "F.Cu" "F.Mask" "F.Paste")
			(net "PWRGD_P3V3_NIC0_R")
		)
	)
	(footprint ""
		(layer "F.Cu")
		(at 189.210696 -409.795472 90)
		(property "Reference" "R4415"
			(at 0 0 90)
			(layer "F.SilkS")
			(hide yes)
			(effects
				(font
					(size 1.27 1.27)
				)
			)
		)
		(property "Value" ""
			(at 0 0 90)
			(layer "F.Fab")
			(effects
				(font
					(size 1.27 1.27)
				)
			)
		)
		(duplicate_pad_numbers_are_jumpers no)
		(fp_line
			(start 0.7874 -0.4064)
			(end 0.7874 0.4064)
			(stroke
				(width 0.1524)
				(type default)
			)
			(layer "F.SilkS")
		)
		(fp_line
			(start -0.7874 -0.4064)
			(end 0.7874 -0.4064)
			(stroke
				(width 0.1524)
				(type default)
			)
			(layer "F.SilkS")
		)
		(fp_line
			(start 0.7874 0.4064)
			(end -0.7874 0.4064)
			(stroke
				(width 0.1524)
				(type default)
			)
			(layer "F.SilkS")
		)
		(fp_line
			(start -0.7874 0.4064)
			(end -0.7874 -0.4064)
			(stroke
				(width 0.1524)
				(type default)
			)
			(layer "F.SilkS")
		)
		(fp_line
			(start -0.12065 -0.305054)
			(end -0.12065 -0.2794)
			(stroke
				(width 0.1)
				(type default)
			)
			(layer "F.Fab")
		)
		(fp_line
			(start -0.67945 -0.305054)
			(end -0.12065 -0.305054)
			(stroke
				(width 0.1)
				(type default)
			)
			(layer "F.Fab")
		)
		(fp_line
			(start 0.67945 -0.3048)
			(end 0.67945 0.3048)
			(stroke
				(width 0.1)
				(type default)
			)
			(layer "F.Fab")
		)
		(fp_line
			(start 0.12065 -0.3048)
			(end 0.67945 -0.3048)
			(stroke
				(width 0.1)
				(type default)
			)
			(layer "F.Fab")
		)
		(fp_line
			(start 0.12065 -0.2794)
			(end 0.12065 -0.3048)
			(stroke
				(width 0.1)
				(type default)
			)
			(layer "F.Fab")
		)
		(fp_line
			(start -0.12065 -0.2794)
			(end 0.12065 -0.2794)
			(stroke
				(width 0.1)
				(type default)
			)
			(layer "F.Fab")
		)
		(fp_line
			(start 0.120396 0.2794)
			(end -0.12065 0.2794)
			(stroke
				(width 0.1)
				(type default)
			)
			(layer "F.Fab")
		)
		(fp_line
			(start -0.12065 0.2794)
			(end -0.12065 0.3048)
			(stroke
				(width 0.1)
				(type default)
			)
			(layer "F.Fab")
		)
		(fp_line
			(start 0.67945 0.3048)
			(end 0.120396 0.3048)
			(stroke
				(width 0.1)
				(type default)
			)
			(layer "F.Fab")
		)
		(fp_line
			(start 0.120396 0.3048)
			(end 0.120396 0.2794)
			(stroke
				(width 0.1)
				(type default)
			)
			(layer "F.Fab")
		)
		(fp_line
			(start -0.12065 0.3048)
			(end -0.67945 0.3048)
			(stroke
				(width 0.1)
				(type default)
			)
			(layer "F.Fab")
		)
		(fp_line
			(start -0.67945 0.3048)
			(end -0.67945 -0.305054)
			(stroke
				(width 0.1)
				(type default)
			)
			(layer "F.Fab")
		)
		(pad "1" smd circle
			(at -0.40005 0 90)
			(size 0 0)
			(layers "F.Cu" "F.Mask" "F.Paste")
			(net "A_P12V_AUX_FP_TRIGGER")
		)
		(pad "2" smd circle
			(at 0.40005 0 90)
			(size 0 0)
			(layers "F.Cu" "F.Mask" "F.Paste")
			(net "P12V_AUX")
		)
	)
	(footprint ""
		(layer "F.Cu")
		(at 61.346842 -343.952322 90)
		(property "Reference" "C129"
			(at 0 0 90)
			(layer "F.SilkS")
			(hide yes)
			(effects
				(font
					(size 1.27 1.27)
				)
			)
		)
		(property "Value" ""
			(at 0 0 90)
			(layer "F.Fab")
			(effects
				(font
					(size 1.27 1.27)
				)
			)
		)
		(duplicate_pad_numbers_are_jumpers no)
		(fp_line
			(start 0.299974 -0.150114)
			(end 0.299974 0.150114)
			(stroke
				(width 0.1)
				(type default)
			)
			(layer "F.Fab")
		)
		(fp_line
			(start -0.299974 -0.150114)
			(end 0.299974 -0.150114)
			(stroke
				(width 0.1)
				(type default)
			)
			(layer "F.Fab")
		)
		(fp_line
			(start 0.299974 0.150114)
			(end -0.299974 0.150114)
			(stroke
				(width 0.1)
				(type default)
			)
			(layer "F.Fab")
		)
		(fp_line
			(start -0.299974 0.150114)
			(end -0.299974 -0.150114)
			(stroke
				(width 0.1)
				(type default)
			)
			(layer "F.Fab")
		)
		(pad "1" smd rect
			(at -0.2667 0 90)
			(size 0.3048 0.381)
			(layers "F.Cu" "F.Mask" "F.Paste")
			(net "P5E_PEX0_STN6_TX_DP<111>")
		)
		(pad "2" smd rect
			(at 0.2667 0 90)
			(size 0.3048 0.381)
			(layers "F.Cu" "F.Mask" "F.Paste")
			(net "P5E_PEX0_STN6_TX_C_DP<111>")
		)
	)
	(footprint ""
		(layer "F.Cu")
		(at 314.861448 -124.076714 180)
		(property "Reference" "C448"
			(at 0 0 180)
			(layer "F.SilkS")
			(hide yes)
			(effects
				(font
					(size 1.27 1.27)
				)
			)
		)
		(property "Value" ""
			(at 0 0 180)
			(layer "F.Fab")
			(effects
				(font
					(size 1.27 1.27)
				)
			)
		)
		(duplicate_pad_numbers_are_jumpers no)
		(fp_line
			(start 0.299974 0.150114)
			(end -0.299974 0.150114)
			(stroke
				(width 0.1)
				(type default)
			)
			(layer "F.Fab")
		)
		(fp_line
			(start 0.299974 -0.150114)
			(end 0.299974 0.150114)
			(stroke
				(width 0.1)
				(type default)
			)
			(layer "F.Fab")
		)
		(fp_line
			(start -0.299974 0.150114)
			(end -0.299974 -0.150114)
			(stroke
				(width 0.1)
				(type default)
			)
			(layer "F.Fab")
		)
		(fp_line
			(start -0.299974 -0.150114)
			(end 0.299974 -0.150114)
			(stroke
				(width 0.1)
				(type default)
			)
			(layer "F.Fab")
		)
		(pad "1" smd rect
			(at -0.2667 0 180)
			(size 0.3048 0.381)
			(layers "F.Cu" "F.Mask" "F.Paste")
			(net "P5E_PEX2_STN0_TX_DN<3>")
		)
		(pad "2" smd rect
			(at 0.2667 0 180)
			(size 0.3048 0.381)
			(layers "F.Cu" "F.Mask" "F.Paste")
			(net "P5E_PEX2_STN0_TX_C_DN<3>")
		)
	)
	(footprint ""
		(layer "F.Cu")
		(at 263.495282 -345.766898)
		(property "Reference" "R6656"
			(at 0 0 0)
			(layer "F.SilkS")
			(hide yes)
			(effects
				(font
					(size 1.27 1.27)
				)
			)
		)
		(property "Value" ""
			(at 0 0 0)
			(layer "F.Fab")
			(effects
				(font
					(size 1.27 1.27)
				)
			)
		)
		(duplicate_pad_numbers_are_jumpers no)
		(fp_line
			(start -0.7874 -0.4064)
			(end 0.7874 -0.4064)
			(stroke
				(width 0.1524)
				(type default)
			)
			(layer "F.SilkS")
		)
		(fp_line
			(start -0.7874 0.4064)
			(end -0.7874 -0.4064)
			(stroke
				(width 0.1524)
				(type default)
			)
			(layer "F.SilkS")
		)
		(fp_line
			(start 0.7874 -0.4064)
			(end 0.7874 0.4064)
			(stroke
				(width 0.1524)
				(type default)
			)
			(layer "F.SilkS")
		)
		(fp_line
			(start 0.7874 0.4064)
			(end -0.7874 0.4064)
			(stroke
				(width 0.1524)
				(type default)
			)
			(layer "F.SilkS")
		)
		(fp_line
			(start -0.67945 -0.305054)
			(end -0.12065 -0.305054)
			(stroke
				(width 0.1)
				(type default)
			)
			(layer "F.Fab")
		)
		(fp_line
			(start -0.67945 0.3048)
			(end -0.67945 -0.305054)
			(stroke
				(width 0.1)
				(type default)
			)
			(layer "F.Fab")
		)
		(fp_line
			(start -0.12065 -0.305054)
			(end -0.12065 -0.2794)
			(stroke
				(width 0.1)
				(type default)
			)
			(layer "F.Fab")
		)
		(fp_line
			(start -0.12065 -0.2794)
			(end 0.12065 -0.2794)
			(stroke
				(width 0.1)
				(type default)
			)
			(layer "F.Fab")
		)
		(fp_line
			(start -0.12065 0.2794)
			(end -0.12065 0.3048)
			(stroke
				(width 0.1)
				(type default)
			)
			(layer "F.Fab")
		)
		(fp_line
			(start -0.12065 0.3048)
			(end -0.67945 0.3048)
			(stroke
				(width 0.1)
				(type default)
			)
			(layer "F.Fab")
		)
		(fp_line
			(start 0.120396 0.2794)
			(end -0.12065 0.2794)
			(stroke
				(width 0.1)
				(type default)
			)
			(layer "F.Fab")
		)
		(fp_line
			(start 0.120396 0.3048)
			(end 0.120396 0.2794)
			(stroke
				(width 0.1)
				(type default)
			)
			(layer "F.Fab")
		)
		(fp_line
			(start 0.12065 -0.3048)
			(end 0.67945 -0.3048)
			(stroke
				(width 0.1)
				(type default)
			)
			(layer "F.Fab")
		)
		(fp_line
			(start 0.12065 -0.2794)
			(end 0.12065 -0.3048)
			(stroke
				(width 0.1)
				(type default)
			)
			(layer "F.Fab")
		)
		(fp_line
			(start 0.67945 -0.3048)
			(end 0.67945 0.3048)
			(stroke
				(width 0.1)
				(type default)
			)
			(layer "F.Fab")
		)
		(fp_line
			(start 0.67945 0.3048)
			(end 0.120396 0.3048)
			(stroke
				(width 0.1)
				(type default)
			)
			(layer "F.Fab")
		)
		(pad "1" smd circle
			(at -0.40005 0)
			(size 0 0)
			(layers "F.Cu" "F.Mask" "F.Paste")
			(net "HSC_CSOUT")
		)
		(pad "2" smd circle
			(at 0.40005 0)
			(size 0 0)
			(layers "F.Cu" "F.Mask" "F.Paste")
			(net "HSC_D_OC_R")
		)
	)
	(footprint ""
		(layer "F.Cu")
		(at 447.247264 -19.33956)
		(property "Reference" "C3982"
			(at 0 0 0)
			(layer "F.SilkS")
			(hide yes)
			(effects
				(font
					(size 1.27 1.27)
				)
			)
		)
		(property "Value" ""
			(at 0 0 0)
			(layer "F.Fab")
			(effects
				(font
					(size 1.27 1.27)
				)
			)
		)
		(duplicate_pad_numbers_are_jumpers no)
		(fp_line
			(start -0.7874 -0.4064)
			(end 0.7874 -0.4064)
			(stroke
				(width 0.1524)
				(type default)
			)
			(layer "F.SilkS")
		)
		(fp_line
			(start -0.7874 0.4064)
			(end -0.7874 -0.4064)
			(stroke
				(width 0.1524)
				(type default)
			)
			(layer "F.SilkS")
		)
		(fp_line
			(start 0.7874 -0.4064)
			(end 0.7874 0.4064)
			(stroke
				(width 0.1524)
				(type default)
			)
			(layer "F.SilkS")
		)
		(fp_line
			(start 0.7874 0.4064)
			(end -0.7874 0.4064)
			(stroke
				(width 0.1524)
				(type default)
			)
			(layer "F.SilkS")
		)
		(fp_line
			(start -0.67945 -0.305054)
			(end -0.12065 -0.305054)
			(stroke
				(width 0.1)
				(type default)
			)
			(layer "F.Fab")
		)
		(fp_line
			(start -0.67945 0.3048)
			(end -0.67945 -0.305054)
			(stroke
				(width 0.1)
				(type default)
			)
			(layer "F.Fab")
		)
		(fp_line
			(start -0.12065 -0.305054)
			(end -0.12065 -0.2794)
			(stroke
				(width 0.1)
				(type default)
			)
			(layer "F.Fab")
		)
		(fp_line
			(start -0.12065 -0.2794)
			(end 0.12065 -0.2794)
			(stroke
				(width 0.1)
				(type default)
			)
			(layer "F.Fab")
		)
		(fp_line
			(start -0.12065 0.2794)
			(end -0.12065 0.3048)
			(stroke
				(width 0.1)
				(type default)
			)
			(layer "F.Fab")
		)
		(fp_line
			(start -0.12065 0.3048)
			(end -0.67945 0.3048)
			(stroke
				(width 0.1)
				(type default)
			)
			(layer "F.Fab")
		)
		(fp_line
			(start 0.120396 0.2794)
			(end -0.12065 0.2794)
			(stroke
				(width 0.1)
				(type default)
			)
			(layer "F.Fab")
		)
		(fp_line
			(start 0.120396 0.3048)
			(end 0.120396 0.2794)
			(stroke
				(width 0.1)
				(type default)
			)
			(layer "F.Fab")
		)
		(fp_line
			(start 0.12065 -0.3048)
			(end 0.67945 -0.3048)
			(stroke
				(width 0.1)
				(type default)
			)
			(layer "F.Fab")
		)
		(fp_line
			(start 0.12065 -0.2794)
			(end 0.12065 -0.3048)
			(stroke
				(width 0.1)
				(type default)
			)
			(layer "F.Fab")
		)
		(fp_line
			(start 0.67945 -0.3048)
			(end 0.67945 0.3048)
			(stroke
				(width 0.1)
				(type default)
			)
			(layer "F.Fab")
		)
		(fp_line
			(start 0.67945 0.3048)
			(end 0.120396 0.3048)
			(stroke
				(width 0.1)
				(type default)
			)
			(layer "F.Fab")
		)
		(pad "1" smd circle
			(at -0.40005 0)
			(size 0 0)
			(layers "F.Cu" "F.Mask" "F.Paste")
			(net "P12V_SSD15")
		)
		(pad "2" smd circle
			(at 0.40005 0)
			(size 0 0)
			(layers "F.Cu" "F.Mask" "F.Paste")
			(net "GND")
		)
	)
	(footprint ""
		(layer "F.Cu")
		(at 162.5346 -30.03169 180)
		(property "Reference" "C289"
			(at 0 0 180)
			(layer "F.SilkS")
			(hide yes)
			(effects
				(font
					(size 1.27 1.27)
				)
			)
		)
		(property "Value" ""
			(at 0 0 180)
			(layer "F.Fab")
			(effects
				(font
					(size 1.27 1.27)
				)
			)
		)
		(duplicate_pad_numbers_are_jumpers no)
		(fp_line
			(start 0.299974 0.150114)
			(end -0.299974 0.150114)
			(stroke
				(width 0.1)
				(type default)
			)
			(layer "F.Fab")
		)
		(fp_line
			(start 0.299974 -0.150114)
			(end 0.299974 0.150114)
			(stroke
				(width 0.1)
				(type default)
			)
			(layer "F.Fab")
		)
		(fp_line
			(start -0.299974 0.150114)
			(end -0.299974 -0.150114)
			(stroke
				(width 0.1)
				(type default)
			)
			(layer "F.Fab")
		)
		(fp_line
			(start -0.299974 -0.150114)
			(end 0.299974 -0.150114)
			(stroke
				(width 0.1)
				(type default)
			)
			(layer "F.Fab")
		)
		(pad "1" smd rect
			(at -0.2667 0 180)
			(size 0.3048 0.381)
			(layers "F.Cu" "F.Mask" "F.Paste")
			(net "P5E_PEX1_STN2_TX_DN<41>")
		)
		(pad "2" smd rect
			(at 0.2667 0 180)
			(size 0.3048 0.381)
			(layers "F.Cu" "F.Mask" "F.Paste")
			(net "P5E_PEX1_STN2_TX_C_DN<41>")
		)
	)
	(footprint ""
		(layer "F.Cu")
		(at 379.633988 -7.884922)
		(property "Reference" "R5815"
			(at 0 0 0)
			(layer "F.SilkS")
			(hide yes)
			(effects
				(font
					(size 1.27 1.27)
				)
			)
		)
		(property "Value" ""
			(at 0 0 0)
			(layer "F.Fab")
			(effects
				(font
					(size 1.27 1.27)
				)
			)
		)
		(duplicate_pad_numbers_are_jumpers no)
		(fp_line
			(start -0.7874 -0.4064)
			(end 0.7874 -0.4064)
			(stroke
				(width 0.1524)
				(type default)
			)
			(layer "F.SilkS")
		)
		(fp_line
			(start -0.7874 0.4064)
			(end -0.7874 -0.4064)
			(stroke
				(width 0.1524)
				(type default)
			)
			(layer "F.SilkS")
		)
		(fp_line
			(start 0.7874 -0.4064)
			(end 0.7874 0.4064)
			(stroke
				(width 0.1524)
				(type default)
			)
			(layer "F.SilkS")
		)
		(fp_line
			(start 0.7874 0.4064)
			(end -0.7874 0.4064)
			(stroke
				(width 0.1524)
				(type default)
			)
			(layer "F.SilkS")
		)
		(fp_line
			(start -0.67945 -0.305054)
			(end -0.12065 -0.305054)
			(stroke
				(width 0.1)
				(type default)
			)
			(layer "F.Fab")
		)
		(fp_line
			(start -0.67945 0.3048)
			(end -0.67945 -0.305054)
			(stroke
				(width 0.1)
				(type default)
			)
			(layer "F.Fab")
		)
		(fp_line
			(start -0.12065 -0.305054)
			(end -0.12065 -0.2794)
			(stroke
				(width 0.1)
				(type default)
			)
			(layer "F.Fab")
		)
		(fp_line
			(start -0.12065 -0.2794)
			(end 0.12065 -0.2794)
			(stroke
				(width 0.1)
				(type default)
			)
			(layer "F.Fab")
		)
		(fp_line
			(start -0.12065 0.2794)
			(end -0.12065 0.3048)
			(stroke
				(width 0.1)
				(type default)
			)
			(layer "F.Fab")
		)
		(fp_line
			(start -0.12065 0.3048)
			(end -0.67945 0.3048)
			(stroke
				(width 0.1)
				(type default)
			)
			(layer "F.Fab")
		)
		(fp_line
			(start 0.120396 0.2794)
			(end -0.12065 0.2794)
			(stroke
				(width 0.1)
				(type default)
			)
			(layer "F.Fab")
		)
		(fp_line
			(start 0.120396 0.3048)
			(end 0.120396 0.2794)
			(stroke
				(width 0.1)
				(type default)
			)
			(layer "F.Fab")
		)
		(fp_line
			(start 0.12065 -0.3048)
			(end 0.67945 -0.3048)
			(stroke
				(width 0.1)
				(type default)
			)
			(layer "F.Fab")
		)
		(fp_line
			(start 0.12065 -0.2794)
			(end 0.12065 -0.3048)
			(stroke
				(width 0.1)
				(type default)
			)
			(layer "F.Fab")
		)
		(fp_line
			(start 0.67945 -0.3048)
			(end 0.67945 0.3048)
			(stroke
				(width 0.1)
				(type default)
			)
			(layer "F.Fab")
		)
		(fp_line
			(start 0.67945 0.3048)
			(end 0.120396 0.3048)
			(stroke
				(width 0.1)
				(type default)
			)
			(layer "F.Fab")
		)
		(pad "1" smd circle
			(at -0.40005 0)
			(size 0 0)
			(layers "F.Cu" "F.Mask" "F.Paste")
			(net "LM75_3_A0")
		)
		(pad "2" smd circle
			(at 0.40005 0)
			(size 0 0)
			(layers "F.Cu" "F.Mask" "F.Paste")
			(net "P3V3_AUX")
		)
	)
	(footprint ""
		(layer "F.Cu")
		(at 215.30056 -210.232244)
		(property "Reference" "R5524"
			(at 0 0 0)
			(layer "F.SilkS")
			(hide yes)
			(effects
				(font
					(size 1.27 1.27)
				)
			)
		)
		(property "Value" ""
			(at 0 0 0)
			(layer "F.Fab")
			(effects
				(font
					(size 1.27 1.27)
				)
			)
		)
		(duplicate_pad_numbers_are_jumpers no)
		(fp_line
			(start -0.7874 -0.4064)
			(end 0.7874 -0.4064)
			(stroke
				(width 0.1524)
				(type default)
			)
			(layer "F.SilkS")
		)
		(fp_line
			(start -0.7874 0.4064)
			(end -0.7874 -0.4064)
			(stroke
				(width 0.1524)
				(type default)
			)
			(layer "F.SilkS")
		)
		(fp_line
			(start 0.7874 -0.4064)
			(end 0.7874 0.4064)
			(stroke
				(width 0.1524)
				(type default)
			)
			(layer "F.SilkS")
		)
		(fp_line
			(start 0.7874 0.4064)
			(end -0.7874 0.4064)
			(stroke
				(width 0.1524)
				(type default)
			)
			(layer "F.SilkS")
		)
		(fp_line
			(start -0.67945 -0.305054)
			(end -0.12065 -0.305054)
			(stroke
				(width 0.1)
				(type default)
			)
			(layer "F.Fab")
		)
		(fp_line
			(start -0.67945 0.3048)
			(end -0.67945 -0.305054)
			(stroke
				(width 0.1)
				(type default)
			)
			(layer "F.Fab")
		)
		(fp_line
			(start -0.12065 -0.305054)
			(end -0.12065 -0.2794)
			(stroke
				(width 0.1)
				(type default)
			)
			(layer "F.Fab")
		)
		(fp_line
			(start -0.12065 -0.2794)
			(end 0.12065 -0.2794)
			(stroke
				(width 0.1)
				(type default)
			)
			(layer "F.Fab")
		)
		(fp_line
			(start -0.12065 0.2794)
			(end -0.12065 0.3048)
			(stroke
				(width 0.1)
				(type default)
			)
			(layer "F.Fab")
		)
		(fp_line
			(start -0.12065 0.3048)
			(end -0.67945 0.3048)
			(stroke
				(width 0.1)
				(type default)
			)
			(layer "F.Fab")
		)
		(fp_line
			(start 0.120396 0.2794)
			(end -0.12065 0.2794)
			(stroke
				(width 0.1)
				(type default)
			)
			(layer "F.Fab")
		)
		(fp_line
			(start 0.120396 0.3048)
			(end 0.120396 0.2794)
			(stroke
				(width 0.1)
				(type default)
			)
			(layer "F.Fab")
		)
		(fp_line
			(start 0.12065 -0.3048)
			(end 0.67945 -0.3048)
			(stroke
				(width 0.1)
				(type default)
			)
			(layer "F.Fab")
		)
		(fp_line
			(start 0.12065 -0.2794)
			(end 0.12065 -0.3048)
			(stroke
				(width 0.1)
				(type default)
			)
			(layer "F.Fab")
		)
		(fp_line
			(start 0.67945 -0.3048)
			(end 0.67945 0.3048)
			(stroke
				(width 0.1)
				(type default)
			)
			(layer "F.Fab")
		)
		(fp_line
			(start 0.67945 0.3048)
			(end 0.120396 0.3048)
			(stroke
				(width 0.1)
				(type default)
			)
			(layer "F.Fab")
		)
		(pad "1" smd circle
			(at -0.40005 0)
			(size 0 0)
			(layers "F.Cu" "F.Mask" "F.Paste")
			(net "GND")
		)
		(pad "2" smd circle
			(at 0.40005 0)
			(size 0 0)
			(layers "F.Cu" "F.Mask" "F.Paste")
			(net "RST_SSD_LED_IOEXP_R_N")
		)
	)
	(footprint ""
		(layer "F.Cu")
		(at 363.596936 -118.378986 -90)
		(property "Reference" "R6042"
			(at 0 0 270)
			(layer "F.SilkS")
			(hide yes)
			(effects
				(font
					(size 1.27 1.27)
				)
			)
		)
		(property "Value" ""
			(at 0 0 270)
			(layer "F.Fab")
			(effects
				(font
					(size 1.27 1.27)
				)
			)
		)
		(duplicate_pad_numbers_are_jumpers no)
		(fp_line
			(start -0.7874 0.4064)
			(end -0.7874 -0.4064)
			(stroke
				(width 0.1524)
				(type default)
			)
			(layer "F.SilkS")
		)
		(fp_line
			(start 0.7874 0.4064)
			(end -0.7874 0.4064)
			(stroke
				(width 0.1524)
				(type default)
			)
			(layer "F.SilkS")
		)
		(fp_line
			(start -0.7874 -0.4064)
			(end 0.7874 -0.4064)
			(stroke
				(width 0.1524)
				(type default)
			)
			(layer "F.SilkS")
		)
		(fp_line
			(start 0.7874 -0.4064)
			(end 0.7874 0.4064)
			(stroke
				(width 0.1524)
				(type default)
			)
			(layer "F.SilkS")
		)
		(fp_line
			(start -0.67945 0.3048)
			(end -0.67945 -0.305054)
			(stroke
				(width 0.1)
				(type default)
			)
			(layer "F.Fab")
		)
		(fp_line
			(start -0.12065 0.3048)
			(end -0.67945 0.3048)
			(stroke
				(width 0.1)
				(type default)
			)
			(layer "F.Fab")
		)
		(fp_line
			(start 0.120396 0.3048)
			(end 0.120396 0.2794)
			(stroke
				(width 0.1)
				(type default)
			)
			(layer "F.Fab")
		)
		(fp_line
			(start 0.67945 0.3048)
			(end 0.120396 0.3048)
			(stroke
				(width 0.1)
				(type default)
			)
			(layer "F.Fab")
		)
		(fp_line
			(start -0.12065 0.2794)
			(end -0.12065 0.3048)
			(stroke
				(width 0.1)
				(type default)
			)
			(layer "F.Fab")
		)
		(fp_line
			(start 0.120396 0.2794)
			(end -0.12065 0.2794)
			(stroke
				(width 0.1)
				(type default)
			)
			(layer "F.Fab")
		)
		(fp_line
			(start -0.12065 -0.2794)
			(end 0.12065 -0.2794)
			(stroke
				(width 0.1)
				(type default)
			)
			(layer "F.Fab")
		)
		(fp_line
			(start 0.12065 -0.2794)
			(end 0.12065 -0.3048)
			(stroke
				(width 0.1)
				(type default)
			)
			(layer "F.Fab")
		)
		(fp_line
			(start 0.12065 -0.3048)
			(end 0.67945 -0.3048)
			(stroke
				(width 0.1)
				(type default)
			)
			(layer "F.Fab")
		)
		(fp_line
			(start 0.67945 -0.3048)
			(end 0.67945 0.3048)
			(stroke
				(width 0.1)
				(type default)
			)
			(layer "F.Fab")
		)
		(fp_line
			(start -0.67945 -0.305054)
			(end -0.12065 -0.305054)
			(stroke
				(width 0.1)
				(type default)
			)
			(layer "F.Fab")
		)
		(fp_line
			(start -0.12065 -0.305054)
			(end -0.12065 -0.2794)
			(stroke
				(width 0.1)
				(type default)
			)
			(layer "F.Fab")
		)
		(pad "1" smd circle
			(at -0.40005 0 270)
			(size 0 0)
			(layers "F.Cu" "F.Mask" "F.Paste")
			(net "HP_NIC6_EN")
		)
		(pad "2" smd circle
			(at 0.40005 0 270)
			(size 0 0)
			(layers "F.Cu" "F.Mask" "F.Paste")
			(net "P3V3_NIC6_CO_EN")
		)
	)
	(footprint ""
		(layer "F.Cu")
		(at 121.163588 -350.098614 90)
		(property "Reference" "C348"
			(at 0 0 90)
			(layer "F.SilkS")
			(hide yes)
			(effects
				(font
					(size 1.27 1.27)
				)
			)
		)
		(property "Value" ""
			(at 0 0 90)
			(layer "F.Fab")
			(effects
				(font
					(size 1.27 1.27)
				)
			)
		)
		(duplicate_pad_numbers_are_jumpers no)
		(fp_line
			(start 0.299974 -0.150114)
			(end 0.299974 0.150114)
			(stroke
				(width 0.1)
				(type default)
			)
			(layer "F.Fab")
		)
		(fp_line
			(start -0.299974 -0.150114)
			(end 0.299974 -0.150114)
			(stroke
				(width 0.1)
				(type default)
			)
			(layer "F.Fab")
		)
		(fp_line
			(start 0.299974 0.150114)
			(end -0.299974 0.150114)
			(stroke
				(width 0.1)
				(type default)
			)
			(layer "F.Fab")
		)
		(fp_line
			(start -0.299974 0.150114)
			(end -0.299974 -0.150114)
			(stroke
				(width 0.1)
				(type default)
			)
			(layer "F.Fab")
		)
		(pad "1" smd rect
			(at -0.2667 0 90)
			(size 0.3048 0.381)
			(layers "F.Cu" "F.Mask" "F.Paste")
			(net "P5E_PEX1_STN6_TX_DP<107>")
		)
		(pad "2" smd rect
			(at 0.2667 0 90)
			(size 0.3048 0.381)
			(layers "F.Cu" "F.Mask" "F.Paste")
			(net "P5E_PEX1_STN6_TX_C_DP<107>")
		)
	)
	(footprint ""
		(layer "F.Cu")
		(at 386.70738 -343.952322 90)
		(property "Reference" "C792"
			(at 0 0 90)
			(layer "F.SilkS")
			(hide yes)
			(effects
				(font
					(size 1.27 1.27)
				)
			)
		)
		(property "Value" ""
			(at 0 0 90)
			(layer "F.Fab")
			(effects
				(font
					(size 1.27 1.27)
				)
			)
		)
		(duplicate_pad_numbers_are_jumpers no)
		(fp_line
			(start 0.299974 -0.150114)
			(end 0.299974 0.150114)
			(stroke
				(width 0.1)
				(type default)
			)
			(layer "F.Fab")
		)
		(fp_line
			(start -0.299974 -0.150114)
			(end 0.299974 -0.150114)
			(stroke
				(width 0.1)
				(type default)
			)
			(layer "F.Fab")
		)
		(fp_line
			(start 0.299974 0.150114)
			(end -0.299974 0.150114)
			(stroke
				(width 0.1)
				(type default)
			)
			(layer "F.Fab")
		)
		(fp_line
			(start -0.299974 0.150114)
			(end -0.299974 -0.150114)
			(stroke
				(width 0.1)
				(type default)
			)
			(layer "F.Fab")
		)
		(pad "1" smd rect
			(at -0.2667 0 90)
			(size 0.3048 0.381)
			(layers "F.Cu" "F.Mask" "F.Paste")
			(net "P5E_PEX3_STN6_TX_DP<96>")
		)
		(pad "2" smd rect
			(at 0.2667 0 90)
			(size 0.3048 0.381)
			(layers "F.Cu" "F.Mask" "F.Paste")
			(net "P5E_PEX3_STN6_TX_C_DP<96>")
		)
	)
	(footprint ""
		(layer "F.Cu")
		(at 361.188 -177.038 180)
		(property "Reference" "R4707"
			(at 0 0 180)
			(layer "F.SilkS")
			(hide yes)
			(effects
				(font
					(size 1.27 1.27)
				)
			)
		)
		(property "Value" ""
			(at 0 0 180)
			(layer "F.Fab")
			(effects
				(font
					(size 1.27 1.27)
				)
			)
		)
		(duplicate_pad_numbers_are_jumpers no)
		(fp_line
			(start 0.7874 0.4064)
			(end -0.7874 0.4064)
			(stroke
				(width 0.1524)
				(type default)
			)
			(layer "F.SilkS")
		)
		(fp_line
			(start 0.7874 -0.4064)
			(end 0.7874 0.4064)
			(stroke
				(width 0.1524)
				(type default)
			)
			(layer "F.SilkS")
		)
		(fp_line
			(start -0.7874 0.4064)
			(end -0.7874 -0.4064)
			(stroke
				(width 0.1524)
				(type default)
			)
			(layer "F.SilkS")
		)
		(fp_line
			(start -0.7874 -0.4064)
			(end 0.7874 -0.4064)
			(stroke
				(width 0.1524)
				(type default)
			)
			(layer "F.SilkS")
		)
		(fp_line
			(start 0.67945 0.3048)
			(end 0.120396 0.3048)
			(stroke
				(width 0.1)
				(type default)
			)
			(layer "F.Fab")
		)
		(fp_line
			(start 0.67945 -0.3048)
			(end 0.67945 0.3048)
			(stroke
				(width 0.1)
				(type default)
			)
			(layer "F.Fab")
		)
		(fp_line
			(start 0.12065 -0.2794)
			(end 0.12065 -0.3048)
			(stroke
				(width 0.1)
				(type default)
			)
			(layer "F.Fab")
		)
		(fp_line
			(start 0.12065 -0.3048)
			(end 0.67945 -0.3048)
			(stroke
				(width 0.1)
				(type default)
			)
			(layer "F.Fab")
		)
		(fp_line
			(start 0.120396 0.3048)
			(end 0.120396 0.2794)
			(stroke
				(width 0.1)
				(type default)
			)
			(layer "F.Fab")
		)
		(fp_line
			(start 0.120396 0.2794)
			(end -0.12065 0.2794)
			(stroke
				(width 0.1)
				(type default)
			)
			(layer "F.Fab")
		)
		(fp_line
			(start -0.12065 0.3048)
			(end -0.67945 0.3048)
			(stroke
				(width 0.1)
				(type default)
			)
			(layer "F.Fab")
		)
		(fp_line
			(start -0.12065 0.2794)
			(end -0.12065 0.3048)
			(stroke
				(width 0.1)
				(type default)
			)
			(layer "F.Fab")
		)
		(fp_line
			(start -0.12065 -0.2794)
			(end 0.12065 -0.2794)
			(stroke
				(width 0.1)
				(type default)
			)
			(layer "F.Fab")
		)
		(fp_line
			(start -0.12065 -0.305054)
			(end -0.12065 -0.2794)
			(stroke
				(width 0.1)
				(type default)
			)
			(layer "F.Fab")
		)
		(fp_line
			(start -0.67945 0.3048)
			(end -0.67945 -0.305054)
			(stroke
				(width 0.1)
				(type default)
			)
			(layer "F.Fab")
		)
		(fp_line
			(start -0.67945 -0.305054)
			(end -0.12065 -0.305054)
			(stroke
				(width 0.1)
				(type default)
			)
			(layer "F.Fab")
		)
		(pad "1" smd circle
			(at -0.40005 0 180)
			(size 0 0)
			(layers "F.Cu" "F.Mask" "F.Paste")
			(net "RST_PEX_SSD6_PERST_N")
		)
		(pad "2" smd circle
			(at 0.40005 0 180)
			(size 0 0)
			(layers "F.Cu" "F.Mask" "F.Paste")
			(net "RST_PEX_SSD6_PERST_R_N")
		)
	)
	(footprint ""
		(layer "F.Cu")
		(at 239.86871 -156.288994 -90)
		(property "Reference" "PR7024"
			(at 0 0 270)
			(layer "F.SilkS")
			(hide yes)
			(effects
				(font
					(size 1.27 1.27)
				)
			)
		)
		(property "Value" ""
			(at 0 0 270)
			(layer "F.Fab")
			(effects
				(font
					(size 1.27 1.27)
				)
			)
		)
		(duplicate_pad_numbers_are_jumpers no)
		(fp_line
			(start -0.7874 0.4064)
			(end -0.7874 -0.4064)
			(stroke
				(width 0.1524)
				(type default)
			)
			(layer "F.SilkS")
		)
		(fp_line
			(start 0.7874 0.4064)
			(end -0.7874 0.4064)
			(stroke
				(width 0.1524)
				(type default)
			)
			(layer "F.SilkS")
		)
		(fp_line
			(start -0.7874 -0.4064)
			(end 0.7874 -0.4064)
			(stroke
				(width 0.1524)
				(type default)
			)
			(layer "F.SilkS")
		)
		(fp_line
			(start 0.7874 -0.4064)
			(end 0.7874 0.4064)
			(stroke
				(width 0.1524)
				(type default)
			)
			(layer "F.SilkS")
		)
		(fp_line
			(start -0.67945 0.3048)
			(end -0.67945 -0.305054)
			(stroke
				(width 0.1)
				(type default)
			)
			(layer "F.Fab")
		)
		(fp_line
			(start -0.12065 0.3048)
			(end -0.67945 0.3048)
			(stroke
				(width 0.1)
				(type default)
			)
			(layer "F.Fab")
		)
		(fp_line
			(start 0.120396 0.3048)
			(end 0.120396 0.2794)
			(stroke
				(width 0.1)
				(type default)
			)
			(layer "F.Fab")
		)
		(fp_line
			(start 0.67945 0.3048)
			(end 0.120396 0.3048)
			(stroke
				(width 0.1)
				(type default)
			)
			(layer "F.Fab")
		)
		(fp_line
			(start -0.12065 0.2794)
			(end -0.12065 0.3048)
			(stroke
				(width 0.1)
				(type default)
			)
			(layer "F.Fab")
		)
		(fp_line
			(start 0.120396 0.2794)
			(end -0.12065 0.2794)
			(stroke
				(width 0.1)
				(type default)
			)
			(layer "F.Fab")
		)
		(fp_line
			(start -0.12065 -0.2794)
			(end 0.12065 -0.2794)
			(stroke
				(width 0.1)
				(type default)
			)
			(layer "F.Fab")
		)
		(fp_line
			(start 0.12065 -0.2794)
			(end 0.12065 -0.3048)
			(stroke
				(width 0.1)
				(type default)
			)
			(layer "F.Fab")
		)
		(fp_line
			(start 0.12065 -0.3048)
			(end 0.67945 -0.3048)
			(stroke
				(width 0.1)
				(type default)
			)
			(layer "F.Fab")
		)
		(fp_line
			(start 0.67945 -0.3048)
			(end 0.67945 0.3048)
			(stroke
				(width 0.1)
				(type default)
			)
			(layer "F.Fab")
		)
		(fp_line
			(start -0.67945 -0.305054)
			(end -0.12065 -0.305054)
			(stroke
				(width 0.1)
				(type default)
			)
			(layer "F.Fab")
		)
		(fp_line
			(start -0.12065 -0.305054)
			(end -0.12065 -0.2794)
			(stroke
				(width 0.1)
				(type default)
			)
			(layer "F.Fab")
		)
		(pad "1" smd circle
			(at -0.40005 0 270)
			(size 0 0)
			(layers "F.Cu" "F.Mask" "F.Paste")
			(net "P12V_NIC4_CO_OV_FB")
		)
		(pad "2" smd circle
			(at 0.40005 0 270)
			(size 0 0)
			(layers "F.Cu" "F.Mask" "F.Paste")
			(net "P12V_AUX")
		)
	)
	(footprint ""
		(layer "F.Cu")
		(at 336.467704 -53.051456)
		(property "Reference" "R4472"
			(at 0 0 0)
			(layer "F.SilkS")
			(hide yes)
			(effects
				(font
					(size 1.27 1.27)
				)
			)
		)
		(property "Value" ""
			(at 0 0 0)
			(layer "F.Fab")
			(effects
				(font
					(size 1.27 1.27)
				)
			)
		)
		(duplicate_pad_numbers_are_jumpers no)
		(fp_line
			(start -0.7874 -0.4064)
			(end 0.7874 -0.4064)
			(stroke
				(width 0.1524)
				(type default)
			)
			(layer "F.SilkS")
		)
		(fp_line
			(start -0.7874 0.4064)
			(end -0.7874 -0.4064)
			(stroke
				(width 0.1524)
				(type default)
			)
			(layer "F.SilkS")
		)
		(fp_line
			(start 0.7874 -0.4064)
			(end 0.7874 0.4064)
			(stroke
				(width 0.1524)
				(type default)
			)
			(layer "F.SilkS")
		)
		(fp_line
			(start 0.7874 0.4064)
			(end -0.7874 0.4064)
			(stroke
				(width 0.1524)
				(type default)
			)
			(layer "F.SilkS")
		)
		(fp_line
			(start -0.67945 -0.305054)
			(end -0.12065 -0.305054)
			(stroke
				(width 0.1)
				(type default)
			)
			(layer "F.Fab")
		)
		(fp_line
			(start -0.67945 0.3048)
			(end -0.67945 -0.305054)
			(stroke
				(width 0.1)
				(type default)
			)
			(layer "F.Fab")
		)
		(fp_line
			(start -0.12065 -0.305054)
			(end -0.12065 -0.2794)
			(stroke
				(width 0.1)
				(type default)
			)
			(layer "F.Fab")
		)
		(fp_line
			(start -0.12065 -0.2794)
			(end 0.12065 -0.2794)
			(stroke
				(width 0.1)
				(type default)
			)
			(layer "F.Fab")
		)
		(fp_line
			(start -0.12065 0.2794)
			(end -0.12065 0.3048)
			(stroke
				(width 0.1)
				(type default)
			)
			(layer "F.Fab")
		)
		(fp_line
			(start -0.12065 0.3048)
			(end -0.67945 0.3048)
			(stroke
				(width 0.1)
				(type default)
			)
			(layer "F.Fab")
		)
		(fp_line
			(start 0.120396 0.2794)
			(end -0.12065 0.2794)
			(stroke
				(width 0.1)
				(type default)
			)
			(layer "F.Fab")
		)
		(fp_line
			(start 0.120396 0.3048)
			(end 0.120396 0.2794)
			(stroke
				(width 0.1)
				(type default)
			)
			(layer "F.Fab")
		)
		(fp_line
			(start 0.12065 -0.3048)
			(end 0.67945 -0.3048)
			(stroke
				(width 0.1)
				(type default)
			)
			(layer "F.Fab")
		)
		(fp_line
			(start 0.12065 -0.2794)
			(end 0.12065 -0.3048)
			(stroke
				(width 0.1)
				(type default)
			)
			(layer "F.Fab")
		)
		(fp_line
			(start 0.67945 -0.3048)
			(end 0.67945 0.3048)
			(stroke
				(width 0.1)
				(type default)
			)
			(layer "F.Fab")
		)
		(fp_line
			(start 0.67945 0.3048)
			(end 0.120396 0.3048)
			(stroke
				(width 0.1)
				(type default)
			)
			(layer "F.Fab")
		)
		(pad "1" smd circle
			(at -0.40005 0)
			(size 0 0)
			(layers "F.Cu" "F.Mask" "F.Paste")
			(net "PWRGD_P12V_SSD11")
		)
		(pad "2" smd circle
			(at 0.40005 0)
			(size 0 0)
			(layers "F.Cu" "F.Mask" "F.Paste")
			(net "PWRGD_P12V_SSD11_R")
		)
	)
	(footprint ""
		(layer "F.Cu")
		(at 245.29796 -352.400108 180)
		(property "Reference" "J69"
			(at -0.43815 -8.612886 0)
			(unlocked yes)
			(layer "F.SilkS")
			(effects
				(font
					(size 0.7874 0.5842)
					(thickness 0.1524)
				)
				(justify left)
			)
		)
		(property "Value" ""
			(at 0 0 180)
			(layer "F.Fab")
			(effects
				(font
					(size 1.27 1.27)
				)
			)
		)
		(duplicate_pad_numbers_are_jumpers no)
		(fp_line
			(start 2.500122 7.649972)
			(end -2.500122 7.649972)
			(stroke
				(width 0.1524)
				(type default)
			)
			(layer "F.SilkS")
		)
		(fp_line
			(start 2.500122 7.559802)
			(end 2.500122 7.649972)
			(stroke
				(width 0.1524)
				(type default)
			)
			(layer "F.SilkS")
		)
		(fp_line
			(start 2.500122 5.44449)
			(end 2.500122 5.880354)
			(stroke
				(width 0.1524)
				(type default)
			)
			(layer "F.SilkS")
		)
		(fp_line
			(start 2.500122 -5.880354)
			(end 2.500122 -5.44449)
			(stroke
				(width 0.1524)
				(type default)
			)
			(layer "F.SilkS")
		)
		(fp_line
			(start 2.500122 -7.649972)
			(end 2.500122 -7.559802)
			(stroke
				(width 0.1524)
				(type default)
			)
			(layer "F.SilkS")
		)
		(fp_line
			(start -2.500122 7.649972)
			(end -2.500122 7.559802)
			(stroke
				(width 0.1524)
				(type default)
			)
			(layer "F.SilkS")
		)
		(fp_line
			(start -2.500122 5.880354)
			(end -2.500122 4.944618)
			(stroke
				(width 0.1524)
				(type default)
			)
			(layer "F.SilkS")
		)
		(fp_line
			(start -2.500122 -4.944618)
			(end -2.500122 -5.880354)
			(stroke
				(width 0.1524)
				(type default)
			)
			(layer "F.SilkS")
		)
		(fp_line
			(start -2.500122 -7.559802)
			(end -2.500122 -7.649972)
			(stroke
				(width 0.1524)
				(type default)
			)
			(layer "F.SilkS")
		)
		(fp_line
			(start -2.500122 -7.649972)
			(end 2.500122 -7.649972)
			(stroke
				(width 0.1524)
				(type default)
			)
			(layer "F.SilkS")
		)
		(fp_poly
			(pts
				(xy 4.133088 -4.49199) (xy 4.133088 -5.50799) (xy 3.117088 -4.99999)
			)
			(stroke
				(width 0)
				(type default)
			)
			(fill yes)
			(layer "F.SilkS")
		)
		(fp_line
			(start 2.500122 7.649972)
			(end -2.500122 7.649972)
			(stroke
				(width 0.1)
				(type default)
			)
			(layer "F.Fab")
		)
		(fp_line
			(start 2.500122 -7.649972)
			(end 2.500122 7.649972)
			(stroke
				(width 0.1)
				(type default)
			)
			(layer "F.Fab")
		)
		(fp_line
			(start -2.500122 7.649972)
			(end -2.500122 -7.649972)
			(stroke
				(width 0.1)
				(type default)
			)
			(layer "F.Fab")
		)
		(fp_line
			(start -2.500122 -7.649972)
			(end 2.500122 -7.649972)
			(stroke
				(width 0.1)
				(type default)
			)
			(layer "F.Fab")
		)
		(fp_poly
			(pts
				(xy 4.133088 -4.49199) (xy 4.133088 -5.50799) (xy 3.117088 -4.99999)
			)
			(stroke
				(width 0)
				(type default)
			)
			(fill yes)
			(layer "F.Fab")
		)
		(pad "" np_thru_hole circle
			(at -1.100074 -5.5245 90)
			(size 0.762 0.762)
			(drill 0.762)
			(layers "*.Cu" "*.Mask")
			(clearance 0.381)
			(thermal_gap 0.381)
		)
		(pad "" np_thru_hole circle
			(at -1.100074 5.5245 90)
			(size 0.762 0.762)
			(drill 0.762)
			(layers "*.Cu" "*.Mask")
			(clearance 0.381)
			(thermal_gap 0.381)
		)
		(pad "1" smd rect
			(at 1.720088 -4.99999 90)
			(size 0.6096 2.413)
			(layers "F.Cu" "F.Mask" "F.Paste")
			(net "GND")
		)
		(pad "2" smd rect
			(at 1.720088 -3.999992 90)
			(size 0.6096 2.413)
			(layers "F.Cu" "F.Mask" "F.Paste")
			(net "P12V_AUX")
		)
		(pad "3" smd rect
			(at 1.720088 -2.999994 90)
			(size 0.6096 2.413)
			(layers "F.Cu" "F.Mask" "F.Paste")
			(net "P12V_HSC_GATE2")
		)
		(pad "4" smd rect
			(at 1.720088 -1.999996 90)
			(size 0.6096 2.413)
			(layers "F.Cu" "F.Mask" "F.Paste")
			(net "P12V_HSC_GATE1")
		)
		(pad "5" smd rect
			(at 1.720088 -0.999998 90)
			(size 0.6096 2.413)
			(layers "F.Cu" "F.Mask" "F.Paste")
			(net "P12V_HSC_ADC_P")
		)
		(pad "6" smd rect
			(at 1.720088 0 90)
			(size 0.6096 2.413)
			(layers "F.Cu" "F.Mask" "F.Paste")
			(net "P12V_HSC_ADC_N")
		)
		(pad "7" smd rect
			(at 1.720088 0.999998 90)
			(size 0.6096 2.413)
			(layers "F.Cu" "F.Mask" "F.Paste")
			(net "P12V_HSC_SENSE2_N")
		)
		(pad "8" smd rect
			(at 1.720088 1.999996 90)
			(size 0.6096 2.413)
			(layers "F.Cu" "F.Mask" "F.Paste")
			(net "P12V_HSC_SENSE2_P")
		)
		(pad "9" smd rect
			(at 1.720088 2.999994 90)
			(size 0.6096 2.413)
			(layers "F.Cu" "F.Mask" "F.Paste")
			(net "P12V_HSC_SENSE1_N")
		)
		(pad "10" smd rect
			(at 1.720088 3.999992 90)
			(size 0.6096 2.413)
			(layers "F.Cu" "F.Mask" "F.Paste")
			(net "P12V_HSC_SENSE1_P")
		)
		(pad "11" smd rect
			(at 1.720088 4.99999 90)
			(size 0.6096 2.413)
			(layers "F.Cu" "F.Mask" "F.Paste")
			(net "P12V_STBY")
		)
		(pad "12" smd rect
			(at -1.720088 -4.500118 270)
			(size 0.6096 2.413)
			(layers "F.Cu" "F.Mask" "F.Paste")
			(net "GND")
		)
		(pad "13" smd rect
			(at -1.720088 -3.50012 270)
			(size 0.6096 2.413)
			(layers "F.Cu" "F.Mask" "F.Paste")
			(net "IRQ_SML1_PMBUS_ALERT_N")
		)
		(pad "14" smd rect
			(at -1.720088 -2.500122 270)
			(size 0.6096 2.413)
			(layers "F.Cu" "F.Mask" "F.Paste")
			(net "SMB_SML1_PMBUS_HSC_SDA")
		)
		(pad "15" smd rect
			(at -1.720088 -1.500124 270)
			(size 0.6096 2.413)
			(layers "F.Cu" "F.Mask" "F.Paste")
			(net "SMB_SML1_PMBUS_HSC_SCL")
		)
		(pad "16" smd rect
			(at -1.720088 -0.499872 270)
			(size 0.6096 2.413)
			(layers "F.Cu" "F.Mask" "F.Paste")
			(net "HSC_TYPE_ADC")
		)
		(pad "17" smd rect
			(at -1.720088 0.499872 270)
			(size 0.6096 2.413)
			(layers "F.Cu" "F.Mask" "F.Paste")
			(net "HSC_CSOUT")
		)
		(pad "18" smd rect
			(at -1.720088 1.500124 270)
			(size 0.6096 2.413)
			(layers "F.Cu" "F.Mask" "F.Paste")
			(net "MB0_P12V_STBY_PWRGD")
		)
		(pad "19" smd rect
			(at -1.720088 2.500122 270)
			(size 0.6096 2.413)
			(layers "F.Cu" "F.Mask" "F.Paste")
			(net "P12V_HSC_EN")
		)
		(pad "20" smd rect
			(at -1.720088 3.50012 270)
			(size 0.6096 2.413)
			(layers "F.Cu" "F.Mask" "F.Paste")
			(net "IRQ_HSC_FAULT_R_N")
		)
		(pad "21" smd rect
			(at -1.720088 4.500118 270)
			(size 0.6096 2.413)
			(layers "F.Cu" "F.Mask" "F.Paste")
			(net "P3V3_AUX")
		)
		(pad "G1" smd circle
			(at 0 -6.720078 270)
			(size 0 0)
			(layers "F.Cu" "F.Mask" "F.Paste")
			(net "GND")
		)
		(pad "G2" smd circle
			(at 0 6.720078 270)
			(size 0 0)
			(layers "F.Cu" "F.Mask" "F.Paste")
			(net "GND")
		)
		(zone
			(layer "F.Cu")
			(hatch none 0.5)
			(connect_pads
				(clearance 0)
			)
			(min_thickness 0.25)
			(keepout
				(tracks not_allowed)
				(vias allowed)
				(pads allowed)
				(copperpour not_allowed)
				(footprints allowed)
			)
			(placement
				(enabled no)
				(sheetname "")
			)
			(fill
				(thermal_gap 0.5)
				(thermal_bridge_width 0.5)
				(island_removal_mode 0)
			)
			(polygon
				(pts
					(xy 244.835172 -357.704898) (xy 244.835172 -347.095318) (xy 245.760748 -347.095318) (xy 245.760748 -357.704898)
				)
			)
		)
		(zone
			(layers "F.Cu" "B.Cu" "In1.Cu" "In2.Cu" "In3.Cu" "In4.Cu" "In5.Cu" "In6.Cu"
				"In7.Cu" "In8.Cu" "In9.Cu" "In10.Cu" "In11.Cu" "In12.Cu" "In13.Cu" "In14.Cu"
				"In15.Cu" "In16.Cu"
			)
			(hatch none 0.5)
			(connect_pads
				(clearance 0)
			)
			(min_thickness 0.25)
			(keepout
				(tracks not_allowed)
				(vias allowed)
				(pads allowed)
				(copperpour not_allowed)
				(footprints allowed)
			)
			(placement
				(enabled no)
				(sheetname "")
			)
			(fill
				(thermal_gap 0.5)
				(thermal_bridge_width 0.5)
				(island_removal_mode 0)
			)
			(polygon
				(pts
					(arc
						(start 247.28678 -357.924608)
						(mid 245.509288 -357.924608)
						(end 247.28678 -357.924608)
					)
				)
			)
		)
		(zone
			(layers "F.Cu" "B.Cu" "In1.Cu" "In2.Cu" "In3.Cu" "In4.Cu" "In5.Cu" "In6.Cu"
				"In7.Cu" "In8.Cu" "In9.Cu" "In10.Cu" "In11.Cu" "In12.Cu" "In13.Cu" "In14.Cu"
				"In15.Cu" "In16.Cu"
			)
			(hatch none 0.5)
			(connect_pads
				(clearance 0)
			)
			(min_thickness 0.25)
			(keepout
				(tracks not_allowed)
				(vias allowed)
				(pads allowed)
				(copperpour not_allowed)
				(footprints allowed)
			)
			(placement
				(enabled no)
				(sheetname "")
			)
			(fill
				(thermal_gap 0.5)
				(thermal_bridge_width 0.5)
				(island_removal_mode 0)
			)
			(polygon
				(pts
					(arc
						(start 247.28678 -346.875608)
						(mid 245.509288 -346.875608)
						(end 247.28678 -346.875608)
					)
				)
			)
		)
	)
	(footprint ""
		(layer "F.Cu")
		(at 363.207808 -154.510994)
		(property "Reference" "PC820"
			(at 0 0 0)
			(layer "F.SilkS")
			(hide yes)
			(effects
				(font
					(size 1.27 1.27)
				)
			)
		)
		(property "Value" ""
			(at 0 0 0)
			(layer "F.Fab")
			(effects
				(font
					(size 1.27 1.27)
				)
			)
		)
		(duplicate_pad_numbers_are_jumpers no)
		(fp_line
			(start -0.7874 -0.4064)
			(end 0.7874 -0.4064)
			(stroke
				(width 0.1524)
				(type default)
			)
			(layer "F.SilkS")
		)
		(fp_line
			(start -0.7874 0.4064)
			(end -0.7874 -0.4064)
			(stroke
				(width 0.1524)
				(type default)
			)
			(layer "F.SilkS")
		)
		(fp_line
			(start 0.7874 -0.4064)
			(end 0.7874 0.4064)
			(stroke
				(width 0.1524)
				(type default)
			)
			(layer "F.SilkS")
		)
		(fp_line
			(start 0.7874 0.4064)
			(end -0.7874 0.4064)
			(stroke
				(width 0.1524)
				(type default)
			)
			(layer "F.SilkS")
		)
		(fp_line
			(start -0.67945 -0.305054)
			(end -0.12065 -0.305054)
			(stroke
				(width 0.1)
				(type default)
			)
			(layer "F.Fab")
		)
		(fp_line
			(start -0.67945 0.3048)
			(end -0.67945 -0.305054)
			(stroke
				(width 0.1)
				(type default)
			)
			(layer "F.Fab")
		)
		(fp_line
			(start -0.12065 -0.305054)
			(end -0.12065 -0.2794)
			(stroke
				(width 0.1)
				(type default)
			)
			(layer "F.Fab")
		)
		(fp_line
			(start -0.12065 -0.2794)
			(end 0.12065 -0.2794)
			(stroke
				(width 0.1)
				(type default)
			)
			(layer "F.Fab")
		)
		(fp_line
			(start -0.12065 0.2794)
			(end -0.12065 0.3048)
			(stroke
				(width 0.1)
				(type default)
			)
			(layer "F.Fab")
		)
		(fp_line
			(start -0.12065 0.3048)
			(end -0.67945 0.3048)
			(stroke
				(width 0.1)
				(type default)
			)
			(layer "F.Fab")
		)
		(fp_line
			(start 0.120396 0.2794)
			(end -0.12065 0.2794)
			(stroke
				(width 0.1)
				(type default)
			)
			(layer "F.Fab")
		)
		(fp_line
			(start 0.120396 0.3048)
			(end 0.120396 0.2794)
			(stroke
				(width 0.1)
				(type default)
			)
			(layer "F.Fab")
		)
		(fp_line
			(start 0.12065 -0.3048)
			(end 0.67945 -0.3048)
			(stroke
				(width 0.1)
				(type default)
			)
			(layer "F.Fab")
		)
		(fp_line
			(start 0.12065 -0.2794)
			(end 0.12065 -0.3048)
			(stroke
				(width 0.1)
				(type default)
			)
			(layer "F.Fab")
		)
		(fp_line
			(start 0.67945 -0.3048)
			(end 0.67945 0.3048)
			(stroke
				(width 0.1)
				(type default)
			)
			(layer "F.Fab")
		)
		(fp_line
			(start 0.67945 0.3048)
			(end 0.120396 0.3048)
			(stroke
				(width 0.1)
				(type default)
			)
			(layer "F.Fab")
		)
		(pad "1" smd circle
			(at -0.40005 0)
			(size 0 0)
			(layers "F.Cu" "F.Mask" "F.Paste")
			(net "P12V_NIC6_R")
		)
		(pad "2" smd circle
			(at 0.40005 0)
			(size 0 0)
			(layers "F.Cu" "F.Mask" "F.Paste")
			(net "GND")
		)
	)
	(footprint ""
		(layer "F.Cu")
		(at 102.900734 -237.306612 90)
		(property "Reference" "PC291"
			(at 0 0 90)
			(layer "F.SilkS")
			(hide yes)
			(effects
				(font
					(size 1.27 1.27)
				)
			)
		)
		(property "Value" ""
			(at 0 0 90)
			(layer "F.Fab")
			(effects
				(font
					(size 1.27 1.27)
				)
			)
		)
		(duplicate_pad_numbers_are_jumpers no)
		(fp_line
			(start 1.524 -0.762)
			(end 1.524 0.762)
			(stroke
				(width 0.1524)
				(type default)
			)
			(layer "F.SilkS")
		)
		(fp_line
			(start -1.524 -0.762)
			(end 1.524 -0.762)
			(stroke
				(width 0.1524)
				(type default)
			)
			(layer "F.SilkS")
		)
		(fp_line
			(start 1.524 0.762)
			(end -1.524 0.762)
			(stroke
				(width 0.1524)
				(type default)
			)
			(layer "F.SilkS")
		)
		(fp_line
			(start -1.524 0.762)
			(end -1.524 -0.762)
			(stroke
				(width 0.1524)
				(type default)
			)
			(layer "F.SilkS")
		)
		(fp_line
			(start 1.1049 -0.724916)
			(end -1.1049 -0.724916)
			(stroke
				(width 0.1)
				(type default)
			)
			(layer "F.Fab")
		)
		(fp_line
			(start -1.1049 -0.724916)
			(end -1.1049 0.724916)
			(stroke
				(width 0.1)
				(type default)
			)
			(layer "F.Fab")
		)
		(fp_line
			(start 1.1049 0.724916)
			(end 1.1049 -0.724916)
			(stroke
				(width 0.1)
				(type default)
			)
			(layer "F.Fab")
		)
		(fp_line
			(start -1.1049 0.724916)
			(end 1.1049 0.724916)
			(stroke
				(width 0.1)
				(type default)
			)
			(layer "F.Fab")
		)
		(pad "1" smd rect
			(at -0.889 0 270)
			(size 1.016 1.27)
			(layers "F.Cu" "F.Mask" "F.Paste")
			(net "P1V8_PEX_R")
		)
		(pad "2" smd rect
			(at 0.889 0 270)
			(size 1.016 1.27)
			(layers "F.Cu" "F.Mask" "F.Paste")
			(net "GND")
		)
	)
	(footprint ""
		(layer "F.Cu")
		(at 295.52519 -213.523068 -90)
		(property "Reference" "R3396"
			(at 0 0 270)
			(layer "F.SilkS")
			(hide yes)
			(effects
				(font
					(size 1.27 1.27)
				)
			)
		)
		(property "Value" ""
			(at 0 0 270)
			(layer "F.Fab")
			(effects
				(font
					(size 1.27 1.27)
				)
			)
		)
		(duplicate_pad_numbers_are_jumpers no)
		(fp_line
			(start -0.7874 0.4064)
			(end -0.7874 -0.4064)
			(stroke
				(width 0.1524)
				(type default)
			)
			(layer "F.SilkS")
		)
		(fp_line
			(start 0.7874 0.4064)
			(end -0.7874 0.4064)
			(stroke
				(width 0.1524)
				(type default)
			)
			(layer "F.SilkS")
		)
		(fp_line
			(start -0.7874 -0.4064)
			(end 0.7874 -0.4064)
			(stroke
				(width 0.1524)
				(type default)
			)
			(layer "F.SilkS")
		)
		(fp_line
			(start 0.7874 -0.4064)
			(end 0.7874 0.4064)
			(stroke
				(width 0.1524)
				(type default)
			)
			(layer "F.SilkS")
		)
		(fp_line
			(start -0.67945 0.3048)
			(end -0.67945 -0.305054)
			(stroke
				(width 0.1)
				(type default)
			)
			(layer "F.Fab")
		)
		(fp_line
			(start -0.12065 0.3048)
			(end -0.67945 0.3048)
			(stroke
				(width 0.1)
				(type default)
			)
			(layer "F.Fab")
		)
		(fp_line
			(start 0.120396 0.3048)
			(end 0.120396 0.2794)
			(stroke
				(width 0.1)
				(type default)
			)
			(layer "F.Fab")
		)
		(fp_line
			(start 0.67945 0.3048)
			(end 0.120396 0.3048)
			(stroke
				(width 0.1)
				(type default)
			)
			(layer "F.Fab")
		)
		(fp_line
			(start -0.12065 0.2794)
			(end -0.12065 0.3048)
			(stroke
				(width 0.1)
				(type default)
			)
			(layer "F.Fab")
		)
		(fp_line
			(start 0.120396 0.2794)
			(end -0.12065 0.2794)
			(stroke
				(width 0.1)
				(type default)
			)
			(layer "F.Fab")
		)
		(fp_line
			(start -0.12065 -0.2794)
			(end 0.12065 -0.2794)
			(stroke
				(width 0.1)
				(type default)
			)
			(layer "F.Fab")
		)
		(fp_line
			(start 0.12065 -0.2794)
			(end 0.12065 -0.3048)
			(stroke
				(width 0.1)
				(type default)
			)
			(layer "F.Fab")
		)
		(fp_line
			(start 0.12065 -0.3048)
			(end 0.67945 -0.3048)
			(stroke
				(width 0.1)
				(type default)
			)
			(layer "F.Fab")
		)
		(fp_line
			(start 0.67945 -0.3048)
			(end 0.67945 0.3048)
			(stroke
				(width 0.1)
				(type default)
			)
			(layer "F.Fab")
		)
		(fp_line
			(start -0.67945 -0.305054)
			(end -0.12065 -0.305054)
			(stroke
				(width 0.1)
				(type default)
			)
			(layer "F.Fab")
		)
		(fp_line
			(start -0.12065 -0.305054)
			(end -0.12065 -0.2794)
			(stroke
				(width 0.1)
				(type default)
			)
			(layer "F.Fab")
		)
		(pad "1" smd circle
			(at -0.40005 0 270)
			(size 0 0)
			(layers "F.Cu" "F.Mask" "F.Paste")
			(net "SPI_BIC1_MOSI_LS23_R1")
		)
		(pad "2" smd circle
			(at 0.40005 0 270)
			(size 0 0)
			(layers "F.Cu" "F.Mask" "F.Paste")
			(net "SPI_BIC1_MOSI_LS23_R")
		)
	)
	(footprint ""
		(layer "F.Cu")
		(at 127.658114 -261.814564 180)
		(property "Reference" "C832"
			(at 0 0 180)
			(layer "F.SilkS")
			(hide yes)
			(effects
				(font
					(size 1.27 1.27)
				)
			)
		)
		(property "Value" ""
			(at 0 0 180)
			(layer "F.Fab")
			(effects
				(font
					(size 1.27 1.27)
				)
			)
		)
		(duplicate_pad_numbers_are_jumpers no)
		(fp_line
			(start 0.7874 0.4064)
			(end -0.7874 0.4064)
			(stroke
				(width 0.1524)
				(type default)
			)
			(layer "F.SilkS")
		)
		(fp_line
			(start 0.7874 -0.4064)
			(end 0.7874 0.4064)
			(stroke
				(width 0.1524)
				(type default)
			)
			(layer "F.SilkS")
		)
		(fp_line
			(start -0.7874 0.4064)
			(end -0.7874 -0.4064)
			(stroke
				(width 0.1524)
				(type default)
			)
			(layer "F.SilkS")
		)
		(fp_line
			(start -0.7874 -0.4064)
			(end 0.7874 -0.4064)
			(stroke
				(width 0.1524)
				(type default)
			)
			(layer "F.SilkS")
		)
		(fp_line
			(start 0.67945 0.3048)
			(end 0.120396 0.3048)
			(stroke
				(width 0.1)
				(type default)
			)
			(layer "F.Fab")
		)
		(fp_line
			(start 0.67945 -0.3048)
			(end 0.67945 0.3048)
			(stroke
				(width 0.1)
				(type default)
			)
			(layer "F.Fab")
		)
		(fp_line
			(start 0.12065 -0.2794)
			(end 0.12065 -0.3048)
			(stroke
				(width 0.1)
				(type default)
			)
			(layer "F.Fab")
		)
		(fp_line
			(start 0.12065 -0.3048)
			(end 0.67945 -0.3048)
			(stroke
				(width 0.1)
				(type default)
			)
			(layer "F.Fab")
		)
		(fp_line
			(start 0.120396 0.3048)
			(end 0.120396 0.2794)
			(stroke
				(width 0.1)
				(type default)
			)
			(layer "F.Fab")
		)
		(fp_line
			(start 0.120396 0.2794)
			(end -0.12065 0.2794)
			(stroke
				(width 0.1)
				(type default)
			)
			(layer "F.Fab")
		)
		(fp_line
			(start -0.12065 0.3048)
			(end -0.67945 0.3048)
			(stroke
				(width 0.1)
				(type default)
			)
			(layer "F.Fab")
		)
		(fp_line
			(start -0.12065 0.2794)
			(end -0.12065 0.3048)
			(stroke
				(width 0.1)
				(type default)
			)
			(layer "F.Fab")
		)
		(fp_line
			(start -0.12065 -0.2794)
			(end 0.12065 -0.2794)
			(stroke
				(width 0.1)
				(type default)
			)
			(layer "F.Fab")
		)
		(fp_line
			(start -0.12065 -0.305054)
			(end -0.12065 -0.2794)
			(stroke
				(width 0.1)
				(type default)
			)
			(layer "F.Fab")
		)
		(fp_line
			(start -0.67945 0.3048)
			(end -0.67945 -0.305054)
			(stroke
				(width 0.1)
				(type default)
			)
			(layer "F.Fab")
		)
		(fp_line
			(start -0.67945 -0.305054)
			(end -0.12065 -0.305054)
			(stroke
				(width 0.1)
				(type default)
			)
			(layer "F.Fab")
		)
		(pad "1" smd circle
			(at -0.40005 0 180)
			(size 0 0)
			(layers "F.Cu" "F.Mask" "F.Paste")
			(net "GND")
		)
		(pad "2" smd circle
			(at 0.40005 0 180)
			(size 0 0)
			(layers "F.Cu" "F.Mask" "F.Paste")
			(net "FM_P0V8_PEX1_EN_R")
		)
	)
	(footprint ""
		(layer "F.Cu")
		(at 300.60519 -213.523068 -90)
		(property "Reference" "R3394"
			(at 0 0 270)
			(layer "F.SilkS")
			(hide yes)
			(effects
				(font
					(size 1.27 1.27)
				)
			)
		)
		(property "Value" ""
			(at 0 0 270)
			(layer "F.Fab")
			(effects
				(font
					(size 1.27 1.27)
				)
			)
		)
		(duplicate_pad_numbers_are_jumpers no)
		(fp_line
			(start -0.7874 0.4064)
			(end -0.7874 -0.4064)
			(stroke
				(width 0.1524)
				(type default)
			)
			(layer "F.SilkS")
		)
		(fp_line
			(start 0.7874 0.4064)
			(end -0.7874 0.4064)
			(stroke
				(width 0.1524)
				(type default)
			)
			(layer "F.SilkS")
		)
		(fp_line
			(start -0.7874 -0.4064)
			(end 0.7874 -0.4064)
			(stroke
				(width 0.1524)
				(type default)
			)
			(layer "F.SilkS")
		)
		(fp_line
			(start 0.7874 -0.4064)
			(end 0.7874 0.4064)
			(stroke
				(width 0.1524)
				(type default)
			)
			(layer "F.SilkS")
		)
		(fp_line
			(start -0.67945 0.3048)
			(end -0.67945 -0.305054)
			(stroke
				(width 0.1)
				(type default)
			)
			(layer "F.Fab")
		)
		(fp_line
			(start -0.12065 0.3048)
			(end -0.67945 0.3048)
			(stroke
				(width 0.1)
				(type default)
			)
			(layer "F.Fab")
		)
		(fp_line
			(start 0.120396 0.3048)
			(end 0.120396 0.2794)
			(stroke
				(width 0.1)
				(type default)
			)
			(layer "F.Fab")
		)
		(fp_line
			(start 0.67945 0.3048)
			(end 0.120396 0.3048)
			(stroke
				(width 0.1)
				(type default)
			)
			(layer "F.Fab")
		)
		(fp_line
			(start -0.12065 0.2794)
			(end -0.12065 0.3048)
			(stroke
				(width 0.1)
				(type default)
			)
			(layer "F.Fab")
		)
		(fp_line
			(start 0.120396 0.2794)
			(end -0.12065 0.2794)
			(stroke
				(width 0.1)
				(type default)
			)
			(layer "F.Fab")
		)
		(fp_line
			(start -0.12065 -0.2794)
			(end 0.12065 -0.2794)
			(stroke
				(width 0.1)
				(type default)
			)
			(layer "F.Fab")
		)
		(fp_line
			(start 0.12065 -0.2794)
			(end 0.12065 -0.3048)
			(stroke
				(width 0.1)
				(type default)
			)
			(layer "F.Fab")
		)
		(fp_line
			(start 0.12065 -0.3048)
			(end 0.67945 -0.3048)
			(stroke
				(width 0.1)
				(type default)
			)
			(layer "F.Fab")
		)
		(fp_line
			(start 0.67945 -0.3048)
			(end 0.67945 0.3048)
			(stroke
				(width 0.1)
				(type default)
			)
			(layer "F.Fab")
		)
		(fp_line
			(start -0.67945 -0.305054)
			(end -0.12065 -0.305054)
			(stroke
				(width 0.1)
				(type default)
			)
			(layer "F.Fab")
		)
		(fp_line
			(start -0.12065 -0.305054)
			(end -0.12065 -0.2794)
			(stroke
				(width 0.1)
				(type default)
			)
			(layer "F.Fab")
		)
		(pad "1" smd circle
			(at -0.40005 0 270)
			(size 0 0)
			(layers "F.Cu" "F.Mask" "F.Paste")
			(net "SPI_BIC1_CS0_LS23_R1_N")
		)
		(pad "2" smd circle
			(at 0.40005 0 270)
			(size 0 0)
			(layers "F.Cu" "F.Mask" "F.Paste")
			(net "SPI_BIC1_CS0_LS23_R_N")
		)
	)
	(footprint ""
		(layer "F.Cu")
		(at 258.362196 -262.645652 90)
		(property "Reference" "C3420"
			(at 0 0 90)
			(layer "F.SilkS")
			(hide yes)
			(effects
				(font
					(size 1.27 1.27)
				)
			)
		)
		(property "Value" ""
			(at 0 0 90)
			(layer "F.Fab")
			(effects
				(font
					(size 1.27 1.27)
				)
			)
		)
		(duplicate_pad_numbers_are_jumpers no)
		(fp_line
			(start 0.299974 -0.150114)
			(end 0.299974 0.150114)
			(stroke
				(width 0.1)
				(type default)
			)
			(layer "F.Fab")
		)
		(fp_line
			(start -0.299974 -0.150114)
			(end 0.299974 -0.150114)
			(stroke
				(width 0.1)
				(type default)
			)
			(layer "F.Fab")
		)
		(fp_line
			(start 0.299974 0.150114)
			(end -0.299974 0.150114)
			(stroke
				(width 0.1)
				(type default)
			)
			(layer "F.Fab")
		)
		(fp_line
			(start -0.299974 0.150114)
			(end -0.299974 -0.150114)
			(stroke
				(width 0.1)
				(type default)
			)
			(layer "F.Fab")
		)
		(pad "1" smd rect
			(at -0.2667 0 90)
			(size 0.3048 0.381)
			(layers "F.Cu" "F.Mask" "F.Paste")
			(net "P1V8_VDDA_PEX2")
		)
		(pad "2" smd rect
			(at 0.2667 0 90)
			(size 0.3048 0.381)
			(layers "F.Cu" "F.Mask" "F.Paste")
			(net "GND")
		)
	)
	(footprint ""
		(layer "F.Cu")
		(at 214.616284 -231.150922 90)
		(property "Reference" "R6361"
			(at 0 0 90)
			(layer "F.SilkS")
			(hide yes)
			(effects
				(font
					(size 1.27 1.27)
				)
			)
		)
		(property "Value" ""
			(at 0 0 90)
			(layer "F.Fab")
			(effects
				(font
					(size 1.27 1.27)
				)
			)
		)
		(duplicate_pad_numbers_are_jumpers no)
		(fp_line
			(start 0.7874 -0.4064)
			(end 0.7874 0.4064)
			(stroke
				(width 0.1524)
				(type default)
			)
			(layer "F.SilkS")
		)
		(fp_line
			(start -0.7874 -0.4064)
			(end 0.7874 -0.4064)
			(stroke
				(width 0.1524)
				(type default)
			)
			(layer "F.SilkS")
		)
		(fp_line
			(start 0.7874 0.4064)
			(end -0.7874 0.4064)
			(stroke
				(width 0.1524)
				(type default)
			)
			(layer "F.SilkS")
		)
		(fp_line
			(start -0.7874 0.4064)
			(end -0.7874 -0.4064)
			(stroke
				(width 0.1524)
				(type default)
			)
			(layer "F.SilkS")
		)
		(fp_line
			(start -0.12065 -0.305054)
			(end -0.12065 -0.2794)
			(stroke
				(width 0.1)
				(type default)
			)
			(layer "F.Fab")
		)
		(fp_line
			(start -0.67945 -0.305054)
			(end -0.12065 -0.305054)
			(stroke
				(width 0.1)
				(type default)
			)
			(layer "F.Fab")
		)
		(fp_line
			(start 0.67945 -0.3048)
			(end 0.67945 0.3048)
			(stroke
				(width 0.1)
				(type default)
			)
			(layer "F.Fab")
		)
		(fp_line
			(start 0.12065 -0.3048)
			(end 0.67945 -0.3048)
			(stroke
				(width 0.1)
				(type default)
			)
			(layer "F.Fab")
		)
		(fp_line
			(start 0.12065 -0.2794)
			(end 0.12065 -0.3048)
			(stroke
				(width 0.1)
				(type default)
			)
			(layer "F.Fab")
		)
		(fp_line
			(start -0.12065 -0.2794)
			(end 0.12065 -0.2794)
			(stroke
				(width 0.1)
				(type default)
			)
			(layer "F.Fab")
		)
		(fp_line
			(start 0.120396 0.2794)
			(end -0.12065 0.2794)
			(stroke
				(width 0.1)
				(type default)
			)
			(layer "F.Fab")
		)
		(fp_line
			(start -0.12065 0.2794)
			(end -0.12065 0.3048)
			(stroke
				(width 0.1)
				(type default)
			)
			(layer "F.Fab")
		)
		(fp_line
			(start 0.67945 0.3048)
			(end 0.120396 0.3048)
			(stroke
				(width 0.1)
				(type default)
			)
			(layer "F.Fab")
		)
		(fp_line
			(start 0.120396 0.3048)
			(end 0.120396 0.2794)
			(stroke
				(width 0.1)
				(type default)
			)
			(layer "F.Fab")
		)
		(fp_line
			(start -0.12065 0.3048)
			(end -0.67945 0.3048)
			(stroke
				(width 0.1)
				(type default)
			)
			(layer "F.Fab")
		)
		(fp_line
			(start -0.67945 0.3048)
			(end -0.67945 -0.305054)
			(stroke
				(width 0.1)
				(type default)
			)
			(layer "F.Fab")
		)
		(pad "1" smd circle
			(at -0.40005 0 90)
			(size 0 0)
			(layers "F.Cu" "F.Mask" "F.Paste")
			(net "RST_PEX_MUX_N")
		)
		(pad "2" smd circle
			(at 0.40005 0 90)
			(size 0 0)
			(layers "F.Cu" "F.Mask" "F.Paste")
			(net "RST_PEX_MUX_R_N")
		)
	)
	(footprint ""
		(layer "F.Cu")
		(at 76.891642 -343.952322 90)
		(property "Reference" "C113"
			(at 0 0 90)
			(layer "F.SilkS")
			(hide yes)
			(effects
				(font
					(size 1.27 1.27)
				)
			)
		)
		(property "Value" ""
			(at 0 0 90)
			(layer "F.Fab")
			(effects
				(font
					(size 1.27 1.27)
				)
			)
		)
		(duplicate_pad_numbers_are_jumpers no)
		(fp_line
			(start 0.299974 -0.150114)
			(end 0.299974 0.150114)
			(stroke
				(width 0.1)
				(type default)
			)
			(layer "F.Fab")
		)
		(fp_line
			(start -0.299974 -0.150114)
			(end 0.299974 -0.150114)
			(stroke
				(width 0.1)
				(type default)
			)
			(layer "F.Fab")
		)
		(fp_line
			(start 0.299974 0.150114)
			(end -0.299974 0.150114)
			(stroke
				(width 0.1)
				(type default)
			)
			(layer "F.Fab")
		)
		(fp_line
			(start -0.299974 0.150114)
			(end -0.299974 -0.150114)
			(stroke
				(width 0.1)
				(type default)
			)
			(layer "F.Fab")
		)
		(pad "1" smd rect
			(at -0.2667 0 90)
			(size 0.3048 0.381)
			(layers "F.Cu" "F.Mask" "F.Paste")
			(net "P5E_PEX0_STN5_TX_DP<87>")
		)
		(pad "2" smd rect
			(at 0.2667 0 90)
			(size 0.3048 0.381)
			(layers "F.Cu" "F.Mask" "F.Paste")
			(net "P5E_PEX0_STN5_TX_C_DP<87>")
		)
	)
	(footprint ""
		(layer "F.Cu")
		(at 151.53259 -381.370332 180)
		(property "Reference" "C4100"
			(at 0 0 180)
			(layer "F.SilkS")
			(hide yes)
			(effects
				(font
					(size 1.27 1.27)
				)
			)
		)
		(property "Value" ""
			(at 0 0 180)
			(layer "F.Fab")
			(effects
				(font
					(size 1.27 1.27)
				)
			)
		)
		(duplicate_pad_numbers_are_jumpers no)
		(fp_line
			(start 0.7874 0.4064)
			(end -0.7874 0.4064)
			(stroke
				(width 0.1524)
				(type default)
			)
			(layer "F.SilkS")
		)
		(fp_line
			(start 0.7874 -0.4064)
			(end 0.7874 0.4064)
			(stroke
				(width 0.1524)
				(type default)
			)
			(layer "F.SilkS")
		)
		(fp_line
			(start -0.7874 0.4064)
			(end -0.7874 -0.4064)
			(stroke
				(width 0.1524)
				(type default)
			)
			(layer "F.SilkS")
		)
		(fp_line
			(start -0.7874 -0.4064)
			(end 0.7874 -0.4064)
			(stroke
				(width 0.1524)
				(type default)
			)
			(layer "F.SilkS")
		)
		(fp_line
			(start 0.67945 0.3048)
			(end 0.120396 0.3048)
			(stroke
				(width 0.1)
				(type default)
			)
			(layer "F.Fab")
		)
		(fp_line
			(start 0.67945 -0.3048)
			(end 0.67945 0.3048)
			(stroke
				(width 0.1)
				(type default)
			)
			(layer "F.Fab")
		)
		(fp_line
			(start 0.12065 -0.2794)
			(end 0.12065 -0.3048)
			(stroke
				(width 0.1)
				(type default)
			)
			(layer "F.Fab")
		)
		(fp_line
			(start 0.12065 -0.3048)
			(end 0.67945 -0.3048)
			(stroke
				(width 0.1)
				(type default)
			)
			(layer "F.Fab")
		)
		(fp_line
			(start 0.120396 0.3048)
			(end 0.120396 0.2794)
			(stroke
				(width 0.1)
				(type default)
			)
			(layer "F.Fab")
		)
		(fp_line
			(start 0.120396 0.2794)
			(end -0.12065 0.2794)
			(stroke
				(width 0.1)
				(type default)
			)
			(layer "F.Fab")
		)
		(fp_line
			(start -0.12065 0.3048)
			(end -0.67945 0.3048)
			(stroke
				(width 0.1)
				(type default)
			)
			(layer "F.Fab")
		)
		(fp_line
			(start -0.12065 0.2794)
			(end -0.12065 0.3048)
			(stroke
				(width 0.1)
				(type default)
			)
			(layer "F.Fab")
		)
		(fp_line
			(start -0.12065 -0.2794)
			(end 0.12065 -0.2794)
			(stroke
				(width 0.1)
				(type default)
			)
			(layer "F.Fab")
		)
		(fp_line
			(start -0.12065 -0.305054)
			(end -0.12065 -0.2794)
			(stroke
				(width 0.1)
				(type default)
			)
			(layer "F.Fab")
		)
		(fp_line
			(start -0.67945 0.3048)
			(end -0.67945 -0.305054)
			(stroke
				(width 0.1)
				(type default)
			)
			(layer "F.Fab")
		)
		(fp_line
			(start -0.67945 -0.305054)
			(end -0.12065 -0.305054)
			(stroke
				(width 0.1)
				(type default)
			)
			(layer "F.Fab")
		)
		(pad "1" smd circle
			(at -0.40005 0 180)
			(size 0 0)
			(layers "F.Cu" "F.Mask" "F.Paste")
			(net "GND")
		)
		(pad "2" smd circle
			(at 0.40005 0 180)
			(size 0 0)
			(layers "F.Cu" "F.Mask" "F.Paste")
			(net "GPU_3V3IO_RSVD1_FFU")
		)
	)
	(footprint ""
		(layer "F.Cu")
		(at 104.31526 -279.101804)
		(property "Reference" "PC58"
			(at 0 0 0)
			(layer "F.SilkS")
			(hide yes)
			(effects
				(font
					(size 1.27 1.27)
				)
			)
		)
		(property "Value" ""
			(at 0 0 0)
			(layer "F.Fab")
			(effects
				(font
					(size 1.27 1.27)
				)
			)
		)
		(duplicate_pad_numbers_are_jumpers no)
		(fp_line
			(start -0.7874 -0.4064)
			(end 0.7874 -0.4064)
			(stroke
				(width 0.1524)
				(type default)
			)
			(layer "F.SilkS")
		)
		(fp_line
			(start -0.7874 0.4064)
			(end -0.7874 -0.4064)
			(stroke
				(width 0.1524)
				(type default)
			)
			(layer "F.SilkS")
		)
		(fp_line
			(start 0.7874 -0.4064)
			(end 0.7874 0.4064)
			(stroke
				(width 0.1524)
				(type default)
			)
			(layer "F.SilkS")
		)
		(fp_line
			(start 0.7874 0.4064)
			(end -0.7874 0.4064)
			(stroke
				(width 0.1524)
				(type default)
			)
			(layer "F.SilkS")
		)
		(fp_line
			(start -0.67945 -0.305054)
			(end -0.12065 -0.305054)
			(stroke
				(width 0.1)
				(type default)
			)
			(layer "F.Fab")
		)
		(fp_line
			(start -0.67945 0.3048)
			(end -0.67945 -0.305054)
			(stroke
				(width 0.1)
				(type default)
			)
			(layer "F.Fab")
		)
		(fp_line
			(start -0.12065 -0.305054)
			(end -0.12065 -0.2794)
			(stroke
				(width 0.1)
				(type default)
			)
			(layer "F.Fab")
		)
		(fp_line
			(start -0.12065 -0.2794)
			(end 0.12065 -0.2794)
			(stroke
				(width 0.1)
				(type default)
			)
			(layer "F.Fab")
		)
		(fp_line
			(start -0.12065 0.2794)
			(end -0.12065 0.3048)
			(stroke
				(width 0.1)
				(type default)
			)
			(layer "F.Fab")
		)
		(fp_line
			(start -0.12065 0.3048)
			(end -0.67945 0.3048)
			(stroke
				(width 0.1)
				(type default)
			)
			(layer "F.Fab")
		)
		(fp_line
			(start 0.120396 0.2794)
			(end -0.12065 0.2794)
			(stroke
				(width 0.1)
				(type default)
			)
			(layer "F.Fab")
		)
		(fp_line
			(start 0.120396 0.3048)
			(end 0.120396 0.2794)
			(stroke
				(width 0.1)
				(type default)
			)
			(layer "F.Fab")
		)
		(fp_line
			(start 0.12065 -0.3048)
			(end 0.67945 -0.3048)
			(stroke
				(width 0.1)
				(type default)
			)
			(layer "F.Fab")
		)
		(fp_line
			(start 0.12065 -0.2794)
			(end 0.12065 -0.3048)
			(stroke
				(width 0.1)
				(type default)
			)
			(layer "F.Fab")
		)
		(fp_line
			(start 0.67945 -0.3048)
			(end 0.67945 0.3048)
			(stroke
				(width 0.1)
				(type default)
			)
			(layer "F.Fab")
		)
		(fp_line
			(start 0.67945 0.3048)
			(end 0.120396 0.3048)
			(stroke
				(width 0.1)
				(type default)
			)
			(layer "F.Fab")
		)
		(pad "1" smd circle
			(at -0.40005 0)
			(size 0 0)
			(layers "F.Cu" "F.Mask" "F.Paste")
			(net "SW_P12V_P0V8_PEX0_FLT")
		)
		(pad "2" smd circle
			(at 0.40005 0)
			(size 0 0)
			(layers "F.Cu" "F.Mask" "F.Paste")
			(net "GND")
		)
	)
	(footprint ""
		(layer "F.Cu")
		(at 54.341776 -27.006296 -90)
		(property "Reference" "PR6924"
			(at 0 0 270)
			(layer "F.SilkS")
			(hide yes)
			(effects
				(font
					(size 1.27 1.27)
				)
			)
		)
		(property "Value" ""
			(at 0 0 270)
			(layer "F.Fab")
			(effects
				(font
					(size 1.27 1.27)
				)
			)
		)
		(duplicate_pad_numbers_are_jumpers no)
		(fp_line
			(start -0.7874 0.4064)
			(end -0.7874 -0.4064)
			(stroke
				(width 0.1524)
				(type default)
			)
			(layer "F.SilkS")
		)
		(fp_line
			(start 0.7874 0.4064)
			(end -0.7874 0.4064)
			(stroke
				(width 0.1524)
				(type default)
			)
			(layer "F.SilkS")
		)
		(fp_line
			(start -0.7874 -0.4064)
			(end 0.7874 -0.4064)
			(stroke
				(width 0.1524)
				(type default)
			)
			(layer "F.SilkS")
		)
		(fp_line
			(start 0.7874 -0.4064)
			(end 0.7874 0.4064)
			(stroke
				(width 0.1524)
				(type default)
			)
			(layer "F.SilkS")
		)
		(fp_line
			(start -0.67945 0.3048)
			(end -0.67945 -0.305054)
			(stroke
				(width 0.1)
				(type default)
			)
			(layer "F.Fab")
		)
		(fp_line
			(start -0.12065 0.3048)
			(end -0.67945 0.3048)
			(stroke
				(width 0.1)
				(type default)
			)
			(layer "F.Fab")
		)
		(fp_line
			(start 0.120396 0.3048)
			(end 0.120396 0.2794)
			(stroke
				(width 0.1)
				(type default)
			)
			(layer "F.Fab")
		)
		(fp_line
			(start 0.67945 0.3048)
			(end 0.120396 0.3048)
			(stroke
				(width 0.1)
				(type default)
			)
			(layer "F.Fab")
		)
		(fp_line
			(start -0.12065 0.2794)
			(end -0.12065 0.3048)
			(stroke
				(width 0.1)
				(type default)
			)
			(layer "F.Fab")
		)
		(fp_line
			(start 0.120396 0.2794)
			(end -0.12065 0.2794)
			(stroke
				(width 0.1)
				(type default)
			)
			(layer "F.Fab")
		)
		(fp_line
			(start -0.12065 -0.2794)
			(end 0.12065 -0.2794)
			(stroke
				(width 0.1)
				(type default)
			)
			(layer "F.Fab")
		)
		(fp_line
			(start 0.12065 -0.2794)
			(end 0.12065 -0.3048)
			(stroke
				(width 0.1)
				(type default)
			)
			(layer "F.Fab")
		)
		(fp_line
			(start 0.12065 -0.3048)
			(end 0.67945 -0.3048)
			(stroke
				(width 0.1)
				(type default)
			)
			(layer "F.Fab")
		)
		(fp_line
			(start 0.67945 -0.3048)
			(end 0.67945 0.3048)
			(stroke
				(width 0.1)
				(type default)
			)
			(layer "F.Fab")
		)
		(fp_line
			(start -0.67945 -0.305054)
			(end -0.12065 -0.305054)
			(stroke
				(width 0.1)
				(type default)
			)
			(layer "F.Fab")
		)
		(fp_line
			(start -0.12065 -0.305054)
			(end -0.12065 -0.2794)
			(stroke
				(width 0.1)
				(type default)
			)
			(layer "F.Fab")
		)
		(pad "1" smd circle
			(at -0.40005 0 270)
			(size 0 0)
			(layers "F.Cu" "F.Mask" "F.Paste")
			(net "P3V3_SSD2_CO_ILIMIT")
		)
		(pad "2" smd circle
			(at 0.40005 0 270)
			(size 0 0)
			(layers "F.Cu" "F.Mask" "F.Paste")
			(net "GND")
		)
	)
	(footprint ""
		(layer "F.Cu")
		(at 263.497314 -346.712286)
		(property "Reference" "R6801"
			(at 0 0 0)
			(layer "F.SilkS")
			(hide yes)
			(effects
				(font
					(size 1.27 1.27)
				)
			)
		)
		(property "Value" ""
			(at 0 0 0)
			(layer "F.Fab")
			(effects
				(font
					(size 1.27 1.27)
				)
			)
		)
		(duplicate_pad_numbers_are_jumpers no)
		(fp_line
			(start -0.7874 -0.4064)
			(end 0.7874 -0.4064)
			(stroke
				(width 0.1524)
				(type default)
			)
			(layer "F.SilkS")
		)
		(fp_line
			(start -0.7874 0.4064)
			(end -0.7874 -0.4064)
			(stroke
				(width 0.1524)
				(type default)
			)
			(layer "F.SilkS")
		)
		(fp_line
			(start 0.7874 -0.4064)
			(end 0.7874 0.4064)
			(stroke
				(width 0.1524)
				(type default)
			)
			(layer "F.SilkS")
		)
		(fp_line
			(start 0.7874 0.4064)
			(end -0.7874 0.4064)
			(stroke
				(width 0.1524)
				(type default)
			)
			(layer "F.SilkS")
		)
		(fp_line
			(start -0.67945 -0.305054)
			(end -0.12065 -0.305054)
			(stroke
				(width 0.1)
				(type default)
			)
			(layer "F.Fab")
		)
		(fp_line
			(start -0.67945 0.3048)
			(end -0.67945 -0.305054)
			(stroke
				(width 0.1)
				(type default)
			)
			(layer "F.Fab")
		)
		(fp_line
			(start -0.12065 -0.305054)
			(end -0.12065 -0.2794)
			(stroke
				(width 0.1)
				(type default)
			)
			(layer "F.Fab")
		)
		(fp_line
			(start -0.12065 -0.2794)
			(end 0.12065 -0.2794)
			(stroke
				(width 0.1)
				(type default)
			)
			(layer "F.Fab")
		)
		(fp_line
			(start -0.12065 0.2794)
			(end -0.12065 0.3048)
			(stroke
				(width 0.1)
				(type default)
			)
			(layer "F.Fab")
		)
		(fp_line
			(start -0.12065 0.3048)
			(end -0.67945 0.3048)
			(stroke
				(width 0.1)
				(type default)
			)
			(layer "F.Fab")
		)
		(fp_line
			(start 0.120396 0.2794)
			(end -0.12065 0.2794)
			(stroke
				(width 0.1)
				(type default)
			)
			(layer "F.Fab")
		)
		(fp_line
			(start 0.120396 0.3048)
			(end 0.120396 0.2794)
			(stroke
				(width 0.1)
				(type default)
			)
			(layer "F.Fab")
		)
		(fp_line
			(start 0.12065 -0.3048)
			(end 0.67945 -0.3048)
			(stroke
				(width 0.1)
				(type default)
			)
			(layer "F.Fab")
		)
		(fp_line
			(start 0.12065 -0.2794)
			(end 0.12065 -0.3048)
			(stroke
				(width 0.1)
				(type default)
			)
			(layer "F.Fab")
		)
		(fp_line
			(start 0.67945 -0.3048)
			(end 0.67945 0.3048)
			(stroke
				(width 0.1)
				(type default)
			)
			(layer "F.Fab")
		)
		(fp_line
			(start 0.67945 0.3048)
			(end 0.120396 0.3048)
			(stroke
				(width 0.1)
				(type default)
			)
			(layer "F.Fab")
		)
		(pad "1" smd circle
			(at -0.40005 0)
			(size 0 0)
			(layers "F.Cu" "F.Mask" "F.Paste")
			(net "HSC_CSOUT")
		)
		(pad "2" smd circle
			(at 0.40005 0)
			(size 0 0)
			(layers "F.Cu" "F.Mask" "F.Paste")
			(net "HSC_D_OC_R")
		)
	)
	(footprint ""
		(layer "F.Cu")
		(at 374.325134 -14.735302 180)
		(property "Reference" "C2736"
			(at 0 0 180)
			(layer "F.SilkS")
			(hide yes)
			(effects
				(font
					(size 1.27 1.27)
				)
			)
		)
		(property "Value" ""
			(at 0 0 180)
			(layer "F.Fab")
			(effects
				(font
					(size 1.27 1.27)
				)
			)
		)
		(duplicate_pad_numbers_are_jumpers no)
		(fp_line
			(start 0.7874 0.4064)
			(end -0.7874 0.4064)
			(stroke
				(width 0.1524)
				(type default)
			)
			(layer "F.SilkS")
		)
		(fp_line
			(start 0.7874 -0.4064)
			(end 0.7874 0.4064)
			(stroke
				(width 0.1524)
				(type default)
			)
			(layer "F.SilkS")
		)
		(fp_line
			(start -0.7874 0.4064)
			(end -0.7874 -0.4064)
			(stroke
				(width 0.1524)
				(type default)
			)
			(layer "F.SilkS")
		)
		(fp_line
			(start -0.7874 -0.4064)
			(end 0.7874 -0.4064)
			(stroke
				(width 0.1524)
				(type default)
			)
			(layer "F.SilkS")
		)
		(fp_line
			(start 0.67945 0.3048)
			(end 0.120396 0.3048)
			(stroke
				(width 0.1)
				(type default)
			)
			(layer "F.Fab")
		)
		(fp_line
			(start 0.67945 -0.3048)
			(end 0.67945 0.3048)
			(stroke
				(width 0.1)
				(type default)
			)
			(layer "F.Fab")
		)
		(fp_line
			(start 0.12065 -0.2794)
			(end 0.12065 -0.3048)
			(stroke
				(width 0.1)
				(type default)
			)
			(layer "F.Fab")
		)
		(fp_line
			(start 0.12065 -0.3048)
			(end 0.67945 -0.3048)
			(stroke
				(width 0.1)
				(type default)
			)
			(layer "F.Fab")
		)
		(fp_line
			(start 0.120396 0.3048)
			(end 0.120396 0.2794)
			(stroke
				(width 0.1)
				(type default)
			)
			(layer "F.Fab")
		)
		(fp_line
			(start 0.120396 0.2794)
			(end -0.12065 0.2794)
			(stroke
				(width 0.1)
				(type default)
			)
			(layer "F.Fab")
		)
		(fp_line
			(start -0.12065 0.3048)
			(end -0.67945 0.3048)
			(stroke
				(width 0.1)
				(type default)
			)
			(layer "F.Fab")
		)
		(fp_line
			(start -0.12065 0.2794)
			(end -0.12065 0.3048)
			(stroke
				(width 0.1)
				(type default)
			)
			(layer "F.Fab")
		)
		(fp_line
			(start -0.12065 -0.2794)
			(end 0.12065 -0.2794)
			(stroke
				(width 0.1)
				(type default)
			)
			(layer "F.Fab")
		)
		(fp_line
			(start -0.12065 -0.305054)
			(end -0.12065 -0.2794)
			(stroke
				(width 0.1)
				(type default)
			)
			(layer "F.Fab")
		)
		(fp_line
			(start -0.67945 0.3048)
			(end -0.67945 -0.305054)
			(stroke
				(width 0.1)
				(type default)
			)
			(layer "F.Fab")
		)
		(fp_line
			(start -0.67945 -0.305054)
			(end -0.12065 -0.305054)
			(stroke
				(width 0.1)
				(type default)
			)
			(layer "F.Fab")
		)
		(pad "1" smd circle
			(at -0.40005 0 180)
			(size 0 0)
			(layers "F.Cu" "F.Mask" "F.Paste")
			(net "GND")
		)
		(pad "2" smd circle
			(at 0.40005 0 180)
			(size 0 0)
			(layers "F.Cu" "F.Mask" "F.Paste")
			(net "P3V3_SSD12")
		)
	)
	(footprint ""
		(layer "F.Cu")
		(at 362.03128 -125.144784 180)
		(property "Reference" "PU51"
			(at 2.769362 -4.61264 0)
			(unlocked yes)
			(layer "F.SilkS")
			(effects
				(font
					(size 0.7874 0.5842)
					(thickness 0.1524)
				)
				(justify left)
			)
		)
		(property "Value" ""
			(at 0 0 180)
			(layer "F.Fab")
			(effects
				(font
					(size 1.27 1.27)
				)
			)
		)
		(duplicate_pad_numbers_are_jumpers no)
		(fp_line
			(start 1.943608 1.549908)
			(end -1.943608 1.549908)
			(stroke
				(width 0.1524)
				(type default)
			)
			(layer "F.SilkS")
		)
		(fp_line
			(start 1.943608 -1.549908)
			(end 1.943608 1.549908)
			(stroke
				(width 0.1524)
				(type default)
			)
			(layer "F.SilkS")
		)
		(fp_line
			(start -1.943608 1.549908)
			(end -1.943608 -1.549908)
			(stroke
				(width 0.1524)
				(type default)
			)
			(layer "F.SilkS")
		)
		(fp_line
			(start -1.943608 -1.549908)
			(end 1.943608 -1.549908)
			(stroke
				(width 0.1524)
				(type default)
			)
			(layer "F.SilkS")
		)
		(fp_poly
			(pts
				(xy -2.019808 -1.549908) (xy -1.257808 -1.549908) (xy -1.257808 -1.880108) (xy -2.019808 -1.880108)
			)
			(stroke
				(width 0)
				(type default)
			)
			(fill yes)
			(layer "F.SilkS")
		)
		(fp_line
			(start 1.549908 1.549908)
			(end -1.549908 1.549908)
			(stroke
				(width 0.1)
				(type default)
			)
			(layer "F.Fab")
		)
		(fp_line
			(start 1.549908 -1.549908)
			(end 1.549908 1.549908)
			(stroke
				(width 0.1)
				(type default)
			)
			(layer "F.Fab")
		)
		(fp_line
			(start -1.549908 1.549908)
			(end -1.549908 -1.549908)
			(stroke
				(width 0.1)
				(type default)
			)
			(layer "F.Fab")
		)
		(fp_line
			(start -1.549908 -1.549908)
			(end 1.549908 -1.549908)
			(stroke
				(width 0.1)
				(type default)
			)
			(layer "F.Fab")
		)
		(fp_poly
			(pts
				(xy -2.019808 -1.549908) (xy -1.257808 -1.549908) (xy -1.257808 -1.880108) (xy -2.019808 -1.880108)
			)
			(stroke
				(width 0)
				(type default)
			)
			(fill yes)
			(layer "F.Fab")
		)
		(pad "1" smd rect
			(at -1.500124 -1.249934 90)
			(size 0.2794 0.6096)
			(layers "F.Cu" "F.Mask" "F.Paste")
			(net "P3V3_NIC6")
		)
		(pad "2" smd rect
			(at -1.500124 -0.750062 90)
			(size 0.2794 0.6096)
			(layers "F.Cu" "F.Mask" "F.Paste")
			(net "P3V3_NIC6")
		)
		(pad "3" smd rect
			(at -1.500124 -0.249936 90)
			(size 0.2794 0.6096)
			(layers "F.Cu" "F.Mask" "F.Paste")
			(net "P3V3_NIC6")
		)
		(pad "4" smd rect
			(at -1.500124 0.249936 90)
			(size 0.2794 0.6096)
			(layers "F.Cu" "F.Mask" "F.Paste")
			(net "P3V3_NIC6")
		)
		(pad "5" smd rect
			(at -1.500124 0.750062 90)
			(size 0.2794 0.6096)
			(layers "F.Cu" "F.Mask" "F.Paste")
			(net "P3V3_NIC6")
		)
		(pad "6" smd rect
			(at -1.500124 1.249934 90)
			(size 0.2794 0.6096)
			(layers "F.Cu" "F.Mask" "F.Paste")
			(net "GND")
		)
		(pad "7" smd rect
			(at 1.500124 1.249934 90)
			(size 0.2794 0.6096)
			(layers "F.Cu" "F.Mask" "F.Paste")
			(net "P3V3_NIC6_SS")
		)
		(pad "8" smd rect
			(at 1.500124 0.750062 90)
			(size 0.2794 0.6096)
			(layers "F.Cu" "F.Mask" "F.Paste")
			(net "PWRGD_P3V3_NIC6")
		)
		(pad "9" smd rect
			(at 1.500124 0.249936 90)
			(size 0.2794 0.6096)
			(layers "F.Cu" "F.Mask" "F.Paste")
			(net "P3V3_NIC6_OCP")
		)
		(pad "10" smd rect
			(at 1.500124 -0.249936 90)
			(size 0.2794 0.6096)
			(layers "F.Cu" "F.Mask" "F.Paste")
			(net "P5V_AUX")
		)
		(pad "11" smd rect
			(at 1.500124 -0.750062 90)
			(size 0.2794 0.6096)
			(layers "F.Cu" "F.Mask" "F.Paste")
			(net "HP_NIC6_EN")
		)
		(pad "12" smd rect
			(at 1.500124 -1.249934 90)
			(size 0.2794 0.6096)
			(layers "F.Cu" "F.Mask" "F.Paste")
			(net "P3V3_AUX")
		)
		(pad "13" smd rect
			(at 0 0 180)
			(size 1.9812 2.7178)
			(layers "F.Cu" "F.Mask" "F.Paste")
			(net "P3V3_AUX")
		)
		(zone
			(layer "F.Cu")
			(hatch none 0.5)
			(connect_pads
				(clearance 0)
			)
			(min_thickness 0.25)
			(keepout
				(tracks not_allowed)
				(vias allowed)
				(pads allowed)
				(copperpour not_allowed)
				(footprints allowed)
			)
			(placement
				(enabled no)
				(sheetname "")
			)
			(fill
				(thermal_gap 0.5)
				(thermal_bridge_width 0.5)
				(island_removal_mode 0)
			)
			(polygon
				(pts
					(xy 360.88828 -123.595384) (xy 360.88828 -123.722384) (xy 360.88828 -126.694184) (xy 360.88828 -126.694692)
					(xy 363.17428 -126.694692) (xy 363.17428 -126.694184) (xy 363.17428 -126.567184) (xy 363.17428 -125.144784)
					(xy 363.07268 -125.144784) (xy 363.07268 -126.567184) (xy 360.98988 -126.567184) (xy 360.98988 -123.722384)
					(xy 363.07268 -123.722384) (xy 363.07268 -125.119384) (xy 363.17428 -125.119384) (xy 363.17428 -123.722384)
					(xy 363.17428 -123.595384) (xy 363.17428 -123.594876) (xy 360.88828 -123.594876)
				)
			)
		)
	)
	(footprint ""
		(layer "F.Cu")
		(at 480.851972 -521.86459 180)
		(property "Reference" "J30_OTH"
			(at -3.2385 -1.402334 0)
			(unlocked yes)
			(layer "B.SilkS")
			(effects
				(font
					(size 0.7874 0.5842)
					(thickness 0.1524)
				)
				(justify mirror)
			)
		)
		(property "Value" ""
			(at 0 0 180)
			(layer "F.Fab")
			(effects
				(font
					(size 1.27 1.27)
				)
			)
		)
		(duplicate_pad_numbers_are_jumpers no)
		(pad "1" thru_hole circle
			(at 0 0 180)
			(size 0.4572 0.4572)
			(drill 0.2032)
			(layers "*.Cu" "*.Mask")
			(remove_unused_layers no)
			(net "Net_9106")
			(clearance 0.127)
			(thermal_gap 0.127)
			(padstack
				(mode front_inner_back)
				(layer "Inner"
					(shape circle)
					(size 0.4572 0.4572)
					(clearance 0.127)
				)
				(layer "B.Cu"
					(shape circle)
					(size 0.508 0.508)
					(clearance 0.1016)
				)
			)
		)
	)
	(footprint ""
		(layer "F.Cu")
		(at 10.11047 -122.931428 180)
		(property "Reference" "PC481"
			(at 0 0 180)
			(layer "F.SilkS")
			(hide yes)
			(effects
				(font
					(size 1.27 1.27)
				)
			)
		)
		(property "Value" ""
			(at 0 0 180)
			(layer "F.Fab")
			(effects
				(font
					(size 1.27 1.27)
				)
			)
		)
		(duplicate_pad_numbers_are_jumpers no)
		(fp_line
			(start 0.7874 0.4064)
			(end -0.7874 0.4064)
			(stroke
				(width 0.1524)
				(type default)
			)
			(layer "F.SilkS")
		)
		(fp_line
			(start 0.7874 -0.4064)
			(end 0.7874 0.4064)
			(stroke
				(width 0.1524)
				(type default)
			)
			(layer "F.SilkS")
		)
		(fp_line
			(start -0.7874 0.4064)
			(end -0.7874 -0.4064)
			(stroke
				(width 0.1524)
				(type default)
			)
			(layer "F.SilkS")
		)
		(fp_line
			(start -0.7874 -0.4064)
			(end 0.7874 -0.4064)
			(stroke
				(width 0.1524)
				(type default)
			)
			(layer "F.SilkS")
		)
		(fp_line
			(start 0.67945 0.3048)
			(end 0.120396 0.3048)
			(stroke
				(width 0.1)
				(type default)
			)
			(layer "F.Fab")
		)
		(fp_line
			(start 0.67945 -0.3048)
			(end 0.67945 0.3048)
			(stroke
				(width 0.1)
				(type default)
			)
			(layer "F.Fab")
		)
		(fp_line
			(start 0.12065 -0.2794)
			(end 0.12065 -0.3048)
			(stroke
				(width 0.1)
				(type default)
			)
			(layer "F.Fab")
		)
		(fp_line
			(start 0.12065 -0.3048)
			(end 0.67945 -0.3048)
			(stroke
				(width 0.1)
				(type default)
			)
			(layer "F.Fab")
		)
		(fp_line
			(start 0.120396 0.3048)
			(end 0.120396 0.2794)
			(stroke
				(width 0.1)
				(type default)
			)
			(layer "F.Fab")
		)
		(fp_line
			(start 0.120396 0.2794)
			(end -0.12065 0.2794)
			(stroke
				(width 0.1)
				(type default)
			)
			(layer "F.Fab")
		)
		(fp_line
			(start -0.12065 0.3048)
			(end -0.67945 0.3048)
			(stroke
				(width 0.1)
				(type default)
			)
			(layer "F.Fab")
		)
		(fp_line
			(start -0.12065 0.2794)
			(end -0.12065 0.3048)
			(stroke
				(width 0.1)
				(type default)
			)
			(layer "F.Fab")
		)
		(fp_line
			(start -0.12065 -0.2794)
			(end 0.12065 -0.2794)
			(stroke
				(width 0.1)
				(type default)
			)
			(layer "F.Fab")
		)
		(fp_line
			(start -0.12065 -0.305054)
			(end -0.12065 -0.2794)
			(stroke
				(width 0.1)
				(type default)
			)
			(layer "F.Fab")
		)
		(fp_line
			(start -0.67945 0.3048)
			(end -0.67945 -0.305054)
			(stroke
				(width 0.1)
				(type default)
			)
			(layer "F.Fab")
		)
		(fp_line
			(start -0.67945 -0.305054)
			(end -0.12065 -0.305054)
			(stroke
				(width 0.1)
				(type default)
			)
			(layer "F.Fab")
		)
		(pad "1" smd circle
			(at -0.40005 0 180)
			(size 0 0)
			(layers "F.Cu" "F.Mask" "F.Paste")
			(net "P5V_AUX")
		)
		(pad "2" smd circle
			(at 0.40005 0 180)
			(size 0 0)
			(layers "F.Cu" "F.Mask" "F.Paste")
			(net "GND")
		)
	)
	(footprint ""
		(layer "F.Cu")
		(at 120.96877 -280.44902 -90)
		(property "Reference" "PC99"
			(at 0 0 270)
			(layer "F.SilkS")
			(hide yes)
			(effects
				(font
					(size 1.27 1.27)
				)
			)
		)
		(property "Value" ""
			(at 0 0 270)
			(layer "F.Fab")
			(effects
				(font
					(size 1.27 1.27)
				)
			)
		)
		(duplicate_pad_numbers_are_jumpers no)
		(fp_line
			(start -0.7874 0.4064)
			(end -0.7874 -0.4064)
			(stroke
				(width 0.1524)
				(type default)
			)
			(layer "F.SilkS")
		)
		(fp_line
			(start 0.7874 0.4064)
			(end -0.7874 0.4064)
			(stroke
				(width 0.1524)
				(type default)
			)
			(layer "F.SilkS")
		)
		(fp_line
			(start -0.7874 -0.4064)
			(end 0.7874 -0.4064)
			(stroke
				(width 0.1524)
				(type default)
			)
			(layer "F.SilkS")
		)
		(fp_line
			(start 0.7874 -0.4064)
			(end 0.7874 0.4064)
			(stroke
				(width 0.1524)
				(type default)
			)
			(layer "F.SilkS")
		)
		(fp_line
			(start -0.67945 0.3048)
			(end -0.67945 -0.305054)
			(stroke
				(width 0.1)
				(type default)
			)
			(layer "F.Fab")
		)
		(fp_line
			(start -0.12065 0.3048)
			(end -0.67945 0.3048)
			(stroke
				(width 0.1)
				(type default)
			)
			(layer "F.Fab")
		)
		(fp_line
			(start 0.120396 0.3048)
			(end 0.120396 0.2794)
			(stroke
				(width 0.1)
				(type default)
			)
			(layer "F.Fab")
		)
		(fp_line
			(start 0.67945 0.3048)
			(end 0.120396 0.3048)
			(stroke
				(width 0.1)
				(type default)
			)
			(layer "F.Fab")
		)
		(fp_line
			(start -0.12065 0.2794)
			(end -0.12065 0.3048)
			(stroke
				(width 0.1)
				(type default)
			)
			(layer "F.Fab")
		)
		(fp_line
			(start 0.120396 0.2794)
			(end -0.12065 0.2794)
			(stroke
				(width 0.1)
				(type default)
			)
			(layer "F.Fab")
		)
		(fp_line
			(start -0.12065 -0.2794)
			(end 0.12065 -0.2794)
			(stroke
				(width 0.1)
				(type default)
			)
			(layer "F.Fab")
		)
		(fp_line
			(start 0.12065 -0.2794)
			(end 0.12065 -0.3048)
			(stroke
				(width 0.1)
				(type default)
			)
			(layer "F.Fab")
		)
		(fp_line
			(start 0.12065 -0.3048)
			(end 0.67945 -0.3048)
			(stroke
				(width 0.1)
				(type default)
			)
			(layer "F.Fab")
		)
		(fp_line
			(start 0.67945 -0.3048)
			(end 0.67945 0.3048)
			(stroke
				(width 0.1)
				(type default)
			)
			(layer "F.Fab")
		)
		(fp_line
			(start -0.67945 -0.305054)
			(end -0.12065 -0.305054)
			(stroke
				(width 0.1)
				(type default)
			)
			(layer "F.Fab")
		)
		(fp_line
			(start -0.12065 -0.305054)
			(end -0.12065 -0.2794)
			(stroke
				(width 0.1)
				(type default)
			)
			(layer "F.Fab")
		)
		(pad "1" smd circle
			(at -0.40005 0 270)
			(size 0 0)
			(layers "F.Cu" "F.Mask" "F.Paste")
			(net "SW_P0V8_PEX1_PHASE1")
		)
		(pad "2" smd circle
			(at 0.40005 0 270)
			(size 0 0)
			(layers "F.Cu" "F.Mask" "F.Paste")
			(net "SW_P0V8_PEX1_BOOT1_R")
		)
	)
	(footprint ""
		(layer "F.Cu")
		(at 284.467808 -54.067456)
		(property "Reference" "PR229"
			(at 0 0 0)
			(layer "F.SilkS")
			(hide yes)
			(effects
				(font
					(size 1.27 1.27)
				)
			)
		)
		(property "Value" ""
			(at 0 0 0)
			(layer "F.Fab")
			(effects
				(font
					(size 1.27 1.27)
				)
			)
		)
		(duplicate_pad_numbers_are_jumpers no)
		(fp_line
			(start -0.7874 -0.4064)
			(end 0.7874 -0.4064)
			(stroke
				(width 0.1524)
				(type default)
			)
			(layer "F.SilkS")
		)
		(fp_line
			(start -0.7874 0.4064)
			(end -0.7874 -0.4064)
			(stroke
				(width 0.1524)
				(type default)
			)
			(layer "F.SilkS")
		)
		(fp_line
			(start 0.7874 -0.4064)
			(end 0.7874 0.4064)
			(stroke
				(width 0.1524)
				(type default)
			)
			(layer "F.SilkS")
		)
		(fp_line
			(start 0.7874 0.4064)
			(end -0.7874 0.4064)
			(stroke
				(width 0.1524)
				(type default)
			)
			(layer "F.SilkS")
		)
		(fp_line
			(start -0.67945 -0.305054)
			(end -0.12065 -0.305054)
			(stroke
				(width 0.1)
				(type default)
			)
			(layer "F.Fab")
		)
		(fp_line
			(start -0.67945 0.3048)
			(end -0.67945 -0.305054)
			(stroke
				(width 0.1)
				(type default)
			)
			(layer "F.Fab")
		)
		(fp_line
			(start -0.12065 -0.305054)
			(end -0.12065 -0.2794)
			(stroke
				(width 0.1)
				(type default)
			)
			(layer "F.Fab")
		)
		(fp_line
			(start -0.12065 -0.2794)
			(end 0.12065 -0.2794)
			(stroke
				(width 0.1)
				(type default)
			)
			(layer "F.Fab")
		)
		(fp_line
			(start -0.12065 0.2794)
			(end -0.12065 0.3048)
			(stroke
				(width 0.1)
				(type default)
			)
			(layer "F.Fab")
		)
		(fp_line
			(start -0.12065 0.3048)
			(end -0.67945 0.3048)
			(stroke
				(width 0.1)
				(type default)
			)
			(layer "F.Fab")
		)
		(fp_line
			(start 0.120396 0.2794)
			(end -0.12065 0.2794)
			(stroke
				(width 0.1)
				(type default)
			)
			(layer "F.Fab")
		)
		(fp_line
			(start 0.120396 0.3048)
			(end 0.120396 0.2794)
			(stroke
				(width 0.1)
				(type default)
			)
			(layer "F.Fab")
		)
		(fp_line
			(start 0.12065 -0.3048)
			(end 0.67945 -0.3048)
			(stroke
				(width 0.1)
				(type default)
			)
			(layer "F.Fab")
		)
		(fp_line
			(start 0.12065 -0.2794)
			(end 0.12065 -0.3048)
			(stroke
				(width 0.1)
				(type default)
			)
			(layer "F.Fab")
		)
		(fp_line
			(start 0.67945 -0.3048)
			(end 0.67945 0.3048)
			(stroke
				(width 0.1)
				(type default)
			)
			(layer "F.Fab")
		)
		(fp_line
			(start 0.67945 0.3048)
			(end 0.120396 0.3048)
			(stroke
				(width 0.1)
				(type default)
			)
			(layer "F.Fab")
		)
		(pad "1" smd circle
			(at -0.40005 0)
			(size 0 0)
			(layers "F.Cu" "F.Mask" "F.Paste")
			(net "P12V_SSD9_OCP")
		)
		(pad "2" smd circle
			(at 0.40005 0)
			(size 0 0)
			(layers "F.Cu" "F.Mask" "F.Paste")
			(net "GND")
		)
	)
	(footprint ""
		(layer "F.Cu")
		(at 241.550698 -257.975862 -90)
		(property "Reference" "R6526"
			(at 0 0 270)
			(layer "F.SilkS")
			(hide yes)
			(effects
				(font
					(size 1.27 1.27)
				)
			)
		)
		(property "Value" ""
			(at 0 0 270)
			(layer "F.Fab")
			(effects
				(font
					(size 1.27 1.27)
				)
			)
		)
		(duplicate_pad_numbers_are_jumpers no)
		(fp_line
			(start -0.7874 0.4064)
			(end -0.7874 -0.4064)
			(stroke
				(width 0.1524)
				(type default)
			)
			(layer "F.SilkS")
		)
		(fp_line
			(start 0.7874 0.4064)
			(end -0.7874 0.4064)
			(stroke
				(width 0.1524)
				(type default)
			)
			(layer "F.SilkS")
		)
		(fp_line
			(start -0.7874 -0.4064)
			(end 0.7874 -0.4064)
			(stroke
				(width 0.1524)
				(type default)
			)
			(layer "F.SilkS")
		)
		(fp_line
			(start 0.7874 -0.4064)
			(end 0.7874 0.4064)
			(stroke
				(width 0.1524)
				(type default)
			)
			(layer "F.SilkS")
		)
		(fp_line
			(start -0.67945 0.3048)
			(end -0.67945 -0.305054)
			(stroke
				(width 0.1)
				(type default)
			)
			(layer "F.Fab")
		)
		(fp_line
			(start -0.12065 0.3048)
			(end -0.67945 0.3048)
			(stroke
				(width 0.1)
				(type default)
			)
			(layer "F.Fab")
		)
		(fp_line
			(start 0.120396 0.3048)
			(end 0.120396 0.2794)
			(stroke
				(width 0.1)
				(type default)
			)
			(layer "F.Fab")
		)
		(fp_line
			(start 0.67945 0.3048)
			(end 0.120396 0.3048)
			(stroke
				(width 0.1)
				(type default)
			)
			(layer "F.Fab")
		)
		(fp_line
			(start -0.12065 0.2794)
			(end -0.12065 0.3048)
			(stroke
				(width 0.1)
				(type default)
			)
			(layer "F.Fab")
		)
		(fp_line
			(start 0.120396 0.2794)
			(end -0.12065 0.2794)
			(stroke
				(width 0.1)
				(type default)
			)
			(layer "F.Fab")
		)
		(fp_line
			(start -0.12065 -0.2794)
			(end 0.12065 -0.2794)
			(stroke
				(width 0.1)
				(type default)
			)
			(layer "F.Fab")
		)
		(fp_line
			(start 0.12065 -0.2794)
			(end 0.12065 -0.3048)
			(stroke
				(width 0.1)
				(type default)
			)
			(layer "F.Fab")
		)
		(fp_line
			(start 0.12065 -0.3048)
			(end 0.67945 -0.3048)
			(stroke
				(width 0.1)
				(type default)
			)
			(layer "F.Fab")
		)
		(fp_line
			(start 0.67945 -0.3048)
			(end 0.67945 0.3048)
			(stroke
				(width 0.1)
				(type default)
			)
			(layer "F.Fab")
		)
		(fp_line
			(start -0.67945 -0.305054)
			(end -0.12065 -0.305054)
			(stroke
				(width 0.1)
				(type default)
			)
			(layer "F.Fab")
		)
		(fp_line
			(start -0.12065 -0.305054)
			(end -0.12065 -0.2794)
			(stroke
				(width 0.1)
				(type default)
			)
			(layer "F.Fab")
		)
		(pad "1" smd circle
			(at -0.40005 0 270)
			(size 0 0)
			(layers "F.Cu" "F.Mask" "F.Paste")
			(net "P1V25_SERDES_VDDPLL_PEX2")
		)
		(pad "2" smd circle
			(at 0.40005 0 270)
			(size 0 0)
			(layers "F.Cu" "F.Mask" "F.Paste")
			(net "P1V25_SERDES_VDDPLL_PEX2_C5")
		)
	)
	(footprint ""
		(layer "F.Cu")
		(at 219.99829 -251.163836 -90)
		(property "Reference" "C4301"
			(at 0 0 270)
			(layer "F.SilkS")
			(hide yes)
			(effects
				(font
					(size 1.27 1.27)
				)
			)
		)
		(property "Value" ""
			(at 0 0 270)
			(layer "F.Fab")
			(effects
				(font
					(size 1.27 1.27)
				)
			)
		)
		(duplicate_pad_numbers_are_jumpers no)
		(fp_line
			(start -1.524 0.762)
			(end -1.524 -0.762)
			(stroke
				(width 0.1524)
				(type default)
			)
			(layer "F.SilkS")
		)
		(fp_line
			(start 1.524 0.762)
			(end -1.524 0.762)
			(stroke
				(width 0.1524)
				(type default)
			)
			(layer "F.SilkS")
		)
		(fp_line
			(start -1.524 -0.762)
			(end 1.524 -0.762)
			(stroke
				(width 0.1524)
				(type default)
			)
			(layer "F.SilkS")
		)
		(fp_line
			(start 1.524 -0.762)
			(end 1.524 0.762)
			(stroke
				(width 0.1524)
				(type default)
			)
			(layer "F.SilkS")
		)
		(fp_line
			(start -1.1049 0.724916)
			(end 1.1049 0.724916)
			(stroke
				(width 0.1)
				(type default)
			)
			(layer "F.Fab")
		)
		(fp_line
			(start 1.1049 0.724916)
			(end 1.1049 -0.724916)
			(stroke
				(width 0.1)
				(type default)
			)
			(layer "F.Fab")
		)
		(fp_line
			(start -1.1049 -0.724916)
			(end -1.1049 0.724916)
			(stroke
				(width 0.1)
				(type default)
			)
			(layer "F.Fab")
		)
		(fp_line
			(start 1.1049 -0.724916)
			(end -1.1049 -0.724916)
			(stroke
				(width 0.1)
				(type default)
			)
			(layer "F.Fab")
		)
		(pad "1" smd rect
			(at -0.889 0 90)
			(size 1.016 1.27)
			(layers "F.Cu" "F.Mask" "F.Paste")
			(net "P1V25_SERDES_VDDPLL_PEX1_C11")
		)
		(pad "2" smd rect
			(at 0.889 0 90)
			(size 1.016 1.27)
			(layers "F.Cu" "F.Mask" "F.Paste")
			(net "GND")
		)
		(zone
			(layer "F.Cu")
			(hatch none 0.5)
			(connect_pads
				(clearance 0)
			)
			(min_thickness 0.25)
			(keepout
				(tracks not_allowed)
				(vias allowed)
				(pads allowed)
				(copperpour not_allowed)
				(footprints allowed)
			)
			(placement
				(enabled no)
				(sheetname "")
			)
			(fill
				(thermal_gap 0.5)
				(thermal_bridge_width 0.5)
				(island_removal_mode 0)
			)
			(polygon
				(pts
					(xy 220.723206 -251.494036) (xy 219.273374 -251.494036) (xy 219.273374 -250.833636) (xy 220.723206 -250.833636)
				)
			)
		)
	)
	(footprint ""
		(layer "F.Cu")
		(at 441.921138 -102.880414 90)
		(property "Reference" "C616"
			(at 0 0 90)
			(layer "F.SilkS")
			(hide yes)
			(effects
				(font
					(size 1.27 1.27)
				)
			)
		)
		(property "Value" ""
			(at 0 0 90)
			(layer "F.Fab")
			(effects
				(font
					(size 1.27 1.27)
				)
			)
		)
		(duplicate_pad_numbers_are_jumpers no)
		(fp_line
			(start 0.7874 -0.4064)
			(end 0.7874 0.4064)
			(stroke
				(width 0.1524)
				(type default)
			)
			(layer "F.SilkS")
		)
		(fp_line
			(start -0.7874 -0.4064)
			(end 0.7874 -0.4064)
			(stroke
				(width 0.1524)
				(type default)
			)
			(layer "F.SilkS")
		)
		(fp_line
			(start 0.7874 0.4064)
			(end -0.7874 0.4064)
			(stroke
				(width 0.1524)
				(type default)
			)
			(layer "F.SilkS")
		)
		(fp_line
			(start -0.7874 0.4064)
			(end -0.7874 -0.4064)
			(stroke
				(width 0.1524)
				(type default)
			)
			(layer "F.SilkS")
		)
		(fp_line
			(start -0.12065 -0.305054)
			(end -0.12065 -0.2794)
			(stroke
				(width 0.1)
				(type default)
			)
			(layer "F.Fab")
		)
		(fp_line
			(start -0.67945 -0.305054)
			(end -0.12065 -0.305054)
			(stroke
				(width 0.1)
				(type default)
			)
			(layer "F.Fab")
		)
		(fp_line
			(start 0.67945 -0.3048)
			(end 0.67945 0.3048)
			(stroke
				(width 0.1)
				(type default)
			)
			(layer "F.Fab")
		)
		(fp_line
			(start 0.12065 -0.3048)
			(end 0.67945 -0.3048)
			(stroke
				(width 0.1)
				(type default)
			)
			(layer "F.Fab")
		)
		(fp_line
			(start 0.12065 -0.2794)
			(end 0.12065 -0.3048)
			(stroke
				(width 0.1)
				(type default)
			)
			(layer "F.Fab")
		)
		(fp_line
			(start -0.12065 -0.2794)
			(end 0.12065 -0.2794)
			(stroke
				(width 0.1)
				(type default)
			)
			(layer "F.Fab")
		)
		(fp_line
			(start 0.120396 0.2794)
			(end -0.12065 0.2794)
			(stroke
				(width 0.1)
				(type default)
			)
			(layer "F.Fab")
		)
		(fp_line
			(start -0.12065 0.2794)
			(end -0.12065 0.3048)
			(stroke
				(width 0.1)
				(type default)
			)
			(layer "F.Fab")
		)
		(fp_line
			(start 0.67945 0.3048)
			(end 0.120396 0.3048)
			(stroke
				(width 0.1)
				(type default)
			)
			(layer "F.Fab")
		)
		(fp_line
			(start 0.120396 0.3048)
			(end 0.120396 0.2794)
			(stroke
				(width 0.1)
				(type default)
			)
			(layer "F.Fab")
		)
		(fp_line
			(start -0.12065 0.3048)
			(end -0.67945 0.3048)
			(stroke
				(width 0.1)
				(type default)
			)
			(layer "F.Fab")
		)
		(fp_line
			(start -0.67945 0.3048)
			(end -0.67945 -0.305054)
			(stroke
				(width 0.1)
				(type default)
			)
			(layer "F.Fab")
		)
		(pad "1" smd circle
			(at -0.40005 0 90)
			(size 0 0)
			(layers "F.Cu" "F.Mask" "F.Paste")
			(net "P3V3_AUX")
		)
		(pad "2" smd circle
			(at 0.40005 0 90)
			(size 0 0)
			(layers "F.Cu" "F.Mask" "F.Paste")
			(net "GND")
		)
	)
	(footprint ""
		(layer "F.Cu")
		(at 14.354556 -135.993632 -90)
		(property "Reference" "PC308"
			(at 0 0 270)
			(layer "F.SilkS")
			(hide yes)
			(effects
				(font
					(size 1.27 1.27)
				)
			)
		)
		(property "Value" ""
			(at 0 0 270)
			(layer "F.Fab")
			(effects
				(font
					(size 1.27 1.27)
				)
			)
		)
		(duplicate_pad_numbers_are_jumpers no)
		(fp_line
			(start -0.7874 0.4064)
			(end -0.7874 -0.4064)
			(stroke
				(width 0.1524)
				(type default)
			)
			(layer "F.SilkS")
		)
		(fp_line
			(start 0.7874 0.4064)
			(end -0.7874 0.4064)
			(stroke
				(width 0.1524)
				(type default)
			)
			(layer "F.SilkS")
		)
		(fp_line
			(start -0.7874 -0.4064)
			(end 0.7874 -0.4064)
			(stroke
				(width 0.1524)
				(type default)
			)
			(layer "F.SilkS")
		)
		(fp_line
			(start 0.7874 -0.4064)
			(end 0.7874 0.4064)
			(stroke
				(width 0.1524)
				(type default)
			)
			(layer "F.SilkS")
		)
		(fp_line
			(start -0.67945 0.3048)
			(end -0.67945 -0.305054)
			(stroke
				(width 0.1)
				(type default)
			)
			(layer "F.Fab")
		)
		(fp_line
			(start -0.12065 0.3048)
			(end -0.67945 0.3048)
			(stroke
				(width 0.1)
				(type default)
			)
			(layer "F.Fab")
		)
		(fp_line
			(start 0.120396 0.3048)
			(end 0.120396 0.2794)
			(stroke
				(width 0.1)
				(type default)
			)
			(layer "F.Fab")
		)
		(fp_line
			(start 0.67945 0.3048)
			(end 0.120396 0.3048)
			(stroke
				(width 0.1)
				(type default)
			)
			(layer "F.Fab")
		)
		(fp_line
			(start -0.12065 0.2794)
			(end -0.12065 0.3048)
			(stroke
				(width 0.1)
				(type default)
			)
			(layer "F.Fab")
		)
		(fp_line
			(start 0.120396 0.2794)
			(end -0.12065 0.2794)
			(stroke
				(width 0.1)
				(type default)
			)
			(layer "F.Fab")
		)
		(fp_line
			(start -0.12065 -0.2794)
			(end 0.12065 -0.2794)
			(stroke
				(width 0.1)
				(type default)
			)
			(layer "F.Fab")
		)
		(fp_line
			(start 0.12065 -0.2794)
			(end 0.12065 -0.3048)
			(stroke
				(width 0.1)
				(type default)
			)
			(layer "F.Fab")
		)
		(fp_line
			(start 0.12065 -0.3048)
			(end 0.67945 -0.3048)
			(stroke
				(width 0.1)
				(type default)
			)
			(layer "F.Fab")
		)
		(fp_line
			(start 0.67945 -0.3048)
			(end 0.67945 0.3048)
			(stroke
				(width 0.1)
				(type default)
			)
			(layer "F.Fab")
		)
		(fp_line
			(start -0.67945 -0.305054)
			(end -0.12065 -0.305054)
			(stroke
				(width 0.1)
				(type default)
			)
			(layer "F.Fab")
		)
		(fp_line
			(start -0.12065 -0.305054)
			(end -0.12065 -0.2794)
			(stroke
				(width 0.1)
				(type default)
			)
			(layer "F.Fab")
		)
		(pad "1" smd circle
			(at -0.40005 0 270)
			(size 0 0)
			(layers "F.Cu" "F.Mask" "F.Paste")
			(net "P12V_NIC0_R")
		)
		(pad "2" smd circle
			(at 0.40005 0 270)
			(size 0 0)
			(layers "F.Cu" "F.Mask" "F.Paste")
			(net "GND")
		)
	)
	(footprint ""
		(layer "F.Cu")
		(at 37.054028 -147.969224 90)
		(property "Reference" "C845"
			(at 0 0 90)
			(layer "F.SilkS")
			(hide yes)
			(effects
				(font
					(size 1.27 1.27)
				)
			)
		)
		(property "Value" ""
			(at 0 0 90)
			(layer "F.Fab")
			(effects
				(font
					(size 1.27 1.27)
				)
			)
		)
		(duplicate_pad_numbers_are_jumpers no)
		(fp_line
			(start 1.524 -0.762)
			(end 1.524 0.762)
			(stroke
				(width 0.1524)
				(type default)
			)
			(layer "F.SilkS")
		)
		(fp_line
			(start -1.524 -0.762)
			(end 1.524 -0.762)
			(stroke
				(width 0.1524)
				(type default)
			)
			(layer "F.SilkS")
		)
		(fp_line
			(start 1.524 0.762)
			(end -1.524 0.762)
			(stroke
				(width 0.1524)
				(type default)
			)
			(layer "F.SilkS")
		)
		(fp_line
			(start -1.524 0.762)
			(end -1.524 -0.762)
			(stroke
				(width 0.1524)
				(type default)
			)
			(layer "F.SilkS")
		)
		(fp_line
			(start 1.1049 -0.724916)
			(end -1.1049 -0.724916)
			(stroke
				(width 0.1)
				(type default)
			)
			(layer "F.Fab")
		)
		(fp_line
			(start -1.1049 -0.724916)
			(end -1.1049 0.724916)
			(stroke
				(width 0.1)
				(type default)
			)
			(layer "F.Fab")
		)
		(fp_line
			(start 1.1049 0.724916)
			(end 1.1049 -0.724916)
			(stroke
				(width 0.1)
				(type default)
			)
			(layer "F.Fab")
		)
		(fp_line
			(start -1.1049 0.724916)
			(end 1.1049 0.724916)
			(stroke
				(width 0.1)
				(type default)
			)
			(layer "F.Fab")
		)
		(pad "1" smd rect
			(at -0.889 0 270)
			(size 1.016 1.27)
			(layers "F.Cu" "F.Mask" "F.Paste")
			(net "P12V_NIC0")
		)
		(pad "2" smd rect
			(at 0.889 0 270)
			(size 1.016 1.27)
			(layers "F.Cu" "F.Mask" "F.Paste")
			(net "GND")
		)
	)
	(footprint ""
		(layer "F.Cu")
		(at 331.778102 -90.666316)
		(property "Reference" "R1162"
			(at 0 0 0)
			(layer "F.SilkS")
			(hide yes)
			(effects
				(font
					(size 1.27 1.27)
				)
			)
		)
		(property "Value" ""
			(at 0 0 0)
			(layer "F.Fab")
			(effects
				(font
					(size 1.27 1.27)
				)
			)
		)
		(duplicate_pad_numbers_are_jumpers no)
		(fp_line
			(start -1.2954 -0.5842)
			(end 1.2954 -0.5842)
			(stroke
				(width 0.1524)
				(type default)
			)
			(layer "F.SilkS")
		)
		(fp_line
			(start -1.2954 0.5842)
			(end -1.2954 -0.5842)
			(stroke
				(width 0.1524)
				(type default)
			)
			(layer "F.SilkS")
		)
		(fp_line
			(start 1.2954 -0.5842)
			(end 1.2954 0.5842)
			(stroke
				(width 0.1524)
				(type default)
			)
			(layer "F.SilkS")
		)
		(fp_line
			(start 1.2954 0.5842)
			(end -1.2954 0.5842)
			(stroke
				(width 0.1524)
				(type default)
			)
			(layer "F.SilkS")
		)
		(fp_line
			(start -1.1938 -0.406654)
			(end -0.8636 -0.406654)
			(stroke
				(width 0.1)
				(type default)
			)
			(layer "F.Fab")
		)
		(fp_line
			(start -1.1938 0.4064)
			(end -1.1938 -0.406654)
			(stroke
				(width 0.1)
				(type default)
			)
			(layer "F.Fab")
		)
		(fp_line
			(start -0.8636 -0.4572)
			(end 0.8636 -0.4572)
			(stroke
				(width 0.1)
				(type default)
			)
			(layer "F.Fab")
		)
		(fp_line
			(start -0.8636 -0.406654)
			(end -0.8636 -0.4572)
			(stroke
				(width 0.1)
				(type default)
			)
			(layer "F.Fab")
		)
		(fp_line
			(start -0.8636 0.4064)
			(end -1.1938 0.4064)
			(stroke
				(width 0.1)
				(type default)
			)
			(layer "F.Fab")
		)
		(fp_line
			(start -0.8636 0.4318)
			(end -0.8636 0.4064)
			(stroke
				(width 0.1)
				(type default)
			)
			(layer "F.Fab")
		)
		(fp_line
			(start -0.8636 0.4572)
			(end -0.8636 0.4318)
			(stroke
				(width 0.1)
				(type default)
			)
			(layer "F.Fab")
		)
		(fp_line
			(start 0.8636 -0.4572)
			(end 0.8636 -0.406654)
			(stroke
				(width 0.1)
				(type default)
			)
			(layer "F.Fab")
		)
		(fp_line
			(start 0.8636 -0.406654)
			(end 1.1938 -0.406654)
			(stroke
				(width 0.1)
				(type default)
			)
			(layer "F.Fab")
		)
		(fp_line
			(start 0.8636 0.4064)
			(end 0.8636 0.4572)
			(stroke
				(width 0.1)
				(type default)
			)
			(layer "F.Fab")
		)
		(fp_line
			(start 0.8636 0.4572)
			(end -0.8636 0.4572)
			(stroke
				(width 0.1)
				(type default)
			)
			(layer "F.Fab")
		)
		(fp_line
			(start 1.1938 -0.406654)
			(end 1.1938 0.4064)
			(stroke
				(width 0.1)
				(type default)
			)
			(layer "F.Fab")
		)
		(fp_line
			(start 1.1938 0.4064)
			(end 0.8636 0.4064)
			(stroke
				(width 0.1)
				(type default)
			)
			(layer "F.Fab")
		)
		(pad "1" smd rect
			(at -0.7366 0 270)
			(size 0.7112 0.8128)
			(layers "F.Cu" "F.Mask" "F.Paste")
			(net "P3V3_VDD_9ZXL0851_8_15")
		)
		(pad "2" smd rect
			(at 0.7366 0 270)
			(size 0.7112 0.8128)
			(layers "F.Cu" "F.Mask" "F.Paste")
			(net "P3V3_VDDAR_9ZXL0851_8_15")
		)
	)
	(footprint ""
		(layer "F.Cu")
		(at 14.670786 -112.139476 -90)
		(property "Reference" "PR6916"
			(at 0 0 270)
			(layer "F.SilkS")
			(hide yes)
			(effects
				(font
					(size 1.27 1.27)
				)
			)
		)
		(property "Value" ""
			(at 0 0 270)
			(layer "F.Fab")
			(effects
				(font
					(size 1.27 1.27)
				)
			)
		)
		(duplicate_pad_numbers_are_jumpers no)
		(fp_line
			(start -0.7874 0.4064)
			(end -0.7874 -0.4064)
			(stroke
				(width 0.1524)
				(type default)
			)
			(layer "F.SilkS")
		)
		(fp_line
			(start 0.7874 0.4064)
			(end -0.7874 0.4064)
			(stroke
				(width 0.1524)
				(type default)
			)
			(layer "F.SilkS")
		)
		(fp_line
			(start -0.7874 -0.4064)
			(end 0.7874 -0.4064)
			(stroke
				(width 0.1524)
				(type default)
			)
			(layer "F.SilkS")
		)
		(fp_line
			(start 0.7874 -0.4064)
			(end 0.7874 0.4064)
			(stroke
				(width 0.1524)
				(type default)
			)
			(layer "F.SilkS")
		)
		(fp_line
			(start -0.67945 0.3048)
			(end -0.67945 -0.305054)
			(stroke
				(width 0.1)
				(type default)
			)
			(layer "F.Fab")
		)
		(fp_line
			(start -0.12065 0.3048)
			(end -0.67945 0.3048)
			(stroke
				(width 0.1)
				(type default)
			)
			(layer "F.Fab")
		)
		(fp_line
			(start 0.120396 0.3048)
			(end 0.120396 0.2794)
			(stroke
				(width 0.1)
				(type default)
			)
			(layer "F.Fab")
		)
		(fp_line
			(start 0.67945 0.3048)
			(end 0.120396 0.3048)
			(stroke
				(width 0.1)
				(type default)
			)
			(layer "F.Fab")
		)
		(fp_line
			(start -0.12065 0.2794)
			(end -0.12065 0.3048)
			(stroke
				(width 0.1)
				(type default)
			)
			(layer "F.Fab")
		)
		(fp_line
			(start 0.120396 0.2794)
			(end -0.12065 0.2794)
			(stroke
				(width 0.1)
				(type default)
			)
			(layer "F.Fab")
		)
		(fp_line
			(start -0.12065 -0.2794)
			(end 0.12065 -0.2794)
			(stroke
				(width 0.1)
				(type default)
			)
			(layer "F.Fab")
		)
		(fp_line
			(start 0.12065 -0.2794)
			(end 0.12065 -0.3048)
			(stroke
				(width 0.1)
				(type default)
			)
			(layer "F.Fab")
		)
		(fp_line
			(start 0.12065 -0.3048)
			(end 0.67945 -0.3048)
			(stroke
				(width 0.1)
				(type default)
			)
			(layer "F.Fab")
		)
		(fp_line
			(start 0.67945 -0.3048)
			(end 0.67945 0.3048)
			(stroke
				(width 0.1)
				(type default)
			)
			(layer "F.Fab")
		)
		(fp_line
			(start -0.67945 -0.305054)
			(end -0.12065 -0.305054)
			(stroke
				(width 0.1)
				(type default)
			)
			(layer "F.Fab")
		)
		(fp_line
			(start -0.12065 -0.305054)
			(end -0.12065 -0.2794)
			(stroke
				(width 0.1)
				(type default)
			)
			(layer "F.Fab")
		)
		(pad "1" smd circle
			(at -0.40005 0 270)
			(size 0 0)
			(layers "F.Cu" "F.Mask" "F.Paste")
			(net "P3V3_NIC0_CO_ILIMIT")
		)
		(pad "2" smd circle
			(at 0.40005 0 270)
			(size 0 0)
			(layers "F.Cu" "F.Mask" "F.Paste")
			(net "GND")
		)
	)
	(footprint ""
		(layer "F.Cu")
		(at 2.718054 -255.046734 -90)
		(property "Reference" "R6470"
			(at 0 0 270)
			(layer "F.SilkS")
			(hide yes)
			(effects
				(font
					(size 1.27 1.27)
				)
			)
		)
		(property "Value" ""
			(at 0 0 270)
			(layer "F.Fab")
			(effects
				(font
					(size 1.27 1.27)
				)
			)
		)
		(duplicate_pad_numbers_are_jumpers no)
		(fp_line
			(start -0.7874 0.4064)
			(end -0.7874 -0.4064)
			(stroke
				(width 0.1524)
				(type default)
			)
			(layer "F.SilkS")
		)
		(fp_line
			(start 0.7874 0.4064)
			(end -0.7874 0.4064)
			(stroke
				(width 0.1524)
				(type default)
			)
			(layer "F.SilkS")
		)
		(fp_line
			(start -0.7874 -0.4064)
			(end 0.7874 -0.4064)
			(stroke
				(width 0.1524)
				(type default)
			)
			(layer "F.SilkS")
		)
		(fp_line
			(start 0.7874 -0.4064)
			(end 0.7874 0.4064)
			(stroke
				(width 0.1524)
				(type default)
			)
			(layer "F.SilkS")
		)
		(fp_line
			(start -0.67945 0.3048)
			(end -0.67945 -0.305054)
			(stroke
				(width 0.1)
				(type default)
			)
			(layer "F.Fab")
		)
		(fp_line
			(start -0.12065 0.3048)
			(end -0.67945 0.3048)
			(stroke
				(width 0.1)
				(type default)
			)
			(layer "F.Fab")
		)
		(fp_line
			(start 0.120396 0.3048)
			(end 0.120396 0.2794)
			(stroke
				(width 0.1)
				(type default)
			)
			(layer "F.Fab")
		)
		(fp_line
			(start 0.67945 0.3048)
			(end 0.120396 0.3048)
			(stroke
				(width 0.1)
				(type default)
			)
			(layer "F.Fab")
		)
		(fp_line
			(start -0.12065 0.2794)
			(end -0.12065 0.3048)
			(stroke
				(width 0.1)
				(type default)
			)
			(layer "F.Fab")
		)
		(fp_line
			(start 0.120396 0.2794)
			(end -0.12065 0.2794)
			(stroke
				(width 0.1)
				(type default)
			)
			(layer "F.Fab")
		)
		(fp_line
			(start -0.12065 -0.2794)
			(end 0.12065 -0.2794)
			(stroke
				(width 0.1)
				(type default)
			)
			(layer "F.Fab")
		)
		(fp_line
			(start 0.12065 -0.2794)
			(end 0.12065 -0.3048)
			(stroke
				(width 0.1)
				(type default)
			)
			(layer "F.Fab")
		)
		(fp_line
			(start 0.12065 -0.3048)
			(end 0.67945 -0.3048)
			(stroke
				(width 0.1)
				(type default)
			)
			(layer "F.Fab")
		)
		(fp_line
			(start 0.67945 -0.3048)
			(end 0.67945 0.3048)
			(stroke
				(width 0.1)
				(type default)
			)
			(layer "F.Fab")
		)
		(fp_line
			(start -0.67945 -0.305054)
			(end -0.12065 -0.305054)
			(stroke
				(width 0.1)
				(type default)
			)
			(layer "F.Fab")
		)
		(fp_line
			(start -0.12065 -0.305054)
			(end -0.12065 -0.2794)
			(stroke
				(width 0.1)
				(type default)
			)
			(layer "F.Fab")
		)
		(pad "1" smd circle
			(at -0.40005 0 270)
			(size 0 0)
			(layers "F.Cu" "F.Mask" "F.Paste")
			(net "P1V25_SERDES_VDDPLL_PEX0")
		)
		(pad "2" smd circle
			(at 0.40005 0 270)
			(size 0 0)
			(layers "F.Cu" "F.Mask" "F.Paste")
			(net "P1V25_SERDES_VDDPLL_PEX0_C7")
		)
	)
	(footprint ""
		(layer "F.Cu")
		(at 369.495578 -88.356694 180)
		(property "Reference" "R1611"
			(at 0 0 180)
			(layer "F.SilkS")
			(hide yes)
			(effects
				(font
					(size 1.27 1.27)
				)
			)
		)
		(property "Value" ""
			(at 0 0 180)
			(layer "F.Fab")
			(effects
				(font
					(size 1.27 1.27)
				)
			)
		)
		(duplicate_pad_numbers_are_jumpers no)
		(fp_line
			(start 0.7874 0.4064)
			(end -0.7874 0.4064)
			(stroke
				(width 0.1524)
				(type default)
			)
			(layer "F.SilkS")
		)
		(fp_line
			(start 0.7874 -0.4064)
			(end 0.7874 0.4064)
			(stroke
				(width 0.1524)
				(type default)
			)
			(layer "F.SilkS")
		)
		(fp_line
			(start -0.7874 0.4064)
			(end -0.7874 -0.4064)
			(stroke
				(width 0.1524)
				(type default)
			)
			(layer "F.SilkS")
		)
		(fp_line
			(start -0.7874 -0.4064)
			(end 0.7874 -0.4064)
			(stroke
				(width 0.1524)
				(type default)
			)
			(layer "F.SilkS")
		)
		(fp_line
			(start 0.67945 0.3048)
			(end 0.120396 0.3048)
			(stroke
				(width 0.1)
				(type default)
			)
			(layer "F.Fab")
		)
		(fp_line
			(start 0.67945 -0.3048)
			(end 0.67945 0.3048)
			(stroke
				(width 0.1)
				(type default)
			)
			(layer "F.Fab")
		)
		(fp_line
			(start 0.12065 -0.2794)
			(end 0.12065 -0.3048)
			(stroke
				(width 0.1)
				(type default)
			)
			(layer "F.Fab")
		)
		(fp_line
			(start 0.12065 -0.3048)
			(end 0.67945 -0.3048)
			(stroke
				(width 0.1)
				(type default)
			)
			(layer "F.Fab")
		)
		(fp_line
			(start 0.120396 0.3048)
			(end 0.120396 0.2794)
			(stroke
				(width 0.1)
				(type default)
			)
			(layer "F.Fab")
		)
		(fp_line
			(start 0.120396 0.2794)
			(end -0.12065 0.2794)
			(stroke
				(width 0.1)
				(type default)
			)
			(layer "F.Fab")
		)
		(fp_line
			(start -0.12065 0.3048)
			(end -0.67945 0.3048)
			(stroke
				(width 0.1)
				(type default)
			)
			(layer "F.Fab")
		)
		(fp_line
			(start -0.12065 0.2794)
			(end -0.12065 0.3048)
			(stroke
				(width 0.1)
				(type default)
			)
			(layer "F.Fab")
		)
		(fp_line
			(start -0.12065 -0.2794)
			(end 0.12065 -0.2794)
			(stroke
				(width 0.1)
				(type default)
			)
			(layer "F.Fab")
		)
		(fp_line
			(start -0.12065 -0.305054)
			(end -0.12065 -0.2794)
			(stroke
				(width 0.1)
				(type default)
			)
			(layer "F.Fab")
		)
		(fp_line
			(start -0.67945 0.3048)
			(end -0.67945 -0.305054)
			(stroke
				(width 0.1)
				(type default)
			)
			(layer "F.Fab")
		)
		(fp_line
			(start -0.67945 -0.305054)
			(end -0.12065 -0.305054)
			(stroke
				(width 0.1)
				(type default)
			)
			(layer "F.Fab")
		)
		(pad "1" smd circle
			(at -0.40005 0 180)
			(size 0 0)
			(layers "F.Cu" "F.Mask" "F.Paste")
			(net "P3V3_AUX")
		)
		(pad "2" smd circle
			(at 0.40005 0 180)
			(size 0 0)
			(layers "F.Cu" "F.Mask" "F.Paste")
			(net "SMB_BIC_I2C9_MUX1_SSD15_R_SDA")
		)
	)
	(footprint ""
		(layer "F.Cu")
		(at 330.646278 -58.323734)
		(property "Reference" "PC425"
			(at 0 0 0)
			(layer "F.SilkS")
			(hide yes)
			(effects
				(font
					(size 1.27 1.27)
				)
			)
		)
		(property "Value" ""
			(at 0 0 0)
			(layer "F.Fab")
			(effects
				(font
					(size 1.27 1.27)
				)
			)
		)
		(duplicate_pad_numbers_are_jumpers no)
		(fp_line
			(start -1.524 -0.762)
			(end 1.524 -0.762)
			(stroke
				(width 0.1524)
				(type default)
			)
			(layer "F.SilkS")
		)
		(fp_line
			(start -1.524 0.762)
			(end -1.524 -0.762)
			(stroke
				(width 0.1524)
				(type default)
			)
			(layer "F.SilkS")
		)
		(fp_line
			(start 1.524 -0.762)
			(end 1.524 0.762)
			(stroke
				(width 0.1524)
				(type default)
			)
			(layer "F.SilkS")
		)
		(fp_line
			(start 1.524 0.762)
			(end -1.524 0.762)
			(stroke
				(width 0.1524)
				(type default)
			)
			(layer "F.SilkS")
		)
		(fp_line
			(start -1.1049 -0.724916)
			(end -1.1049 0.724916)
			(stroke
				(width 0.1)
				(type default)
			)
			(layer "F.Fab")
		)
		(fp_line
			(start -1.1049 0.724916)
			(end 1.1049 0.724916)
			(stroke
				(width 0.1)
				(type default)
			)
			(layer "F.Fab")
		)
		(fp_line
			(start 1.1049 -0.724916)
			(end -1.1049 -0.724916)
			(stroke
				(width 0.1)
				(type default)
			)
			(layer "F.Fab")
		)
		(fp_line
			(start 1.1049 0.724916)
			(end 1.1049 -0.724916)
			(stroke
				(width 0.1)
				(type default)
			)
			(layer "F.Fab")
		)
		(pad "1" smd rect
			(at -0.889 0 180)
			(size 1.016 1.27)
			(layers "F.Cu" "F.Mask" "F.Paste")
			(net "GND")
		)
		(pad "2" smd rect
			(at 0.889 0 180)
			(size 1.016 1.27)
			(layers "F.Cu" "F.Mask" "F.Paste")
			(net "P12V_AUX")
		)
	)
	(footprint ""
		(layer "F.Cu")
		(at 319.39484 -59.577986 90)
		(property "Reference" "PC591"
			(at 0 0 90)
			(layer "F.SilkS")
			(hide yes)
			(effects
				(font
					(size 1.27 1.27)
				)
			)
		)
		(property "Value" ""
			(at 0 0 90)
			(layer "F.Fab")
			(effects
				(font
					(size 1.27 1.27)
				)
			)
		)
		(duplicate_pad_numbers_are_jumpers no)
		(fp_line
			(start 0.7874 -0.4064)
			(end 0.7874 0.4064)
			(stroke
				(width 0.1524)
				(type default)
			)
			(layer "F.SilkS")
		)
		(fp_line
			(start -0.7874 -0.4064)
			(end 0.7874 -0.4064)
			(stroke
				(width 0.1524)
				(type default)
			)
			(layer "F.SilkS")
		)
		(fp_line
			(start 0.7874 0.4064)
			(end -0.7874 0.4064)
			(stroke
				(width 0.1524)
				(type default)
			)
			(layer "F.SilkS")
		)
		(fp_line
			(start -0.7874 0.4064)
			(end -0.7874 -0.4064)
			(stroke
				(width 0.1524)
				(type default)
			)
			(layer "F.SilkS")
		)
		(fp_line
			(start -0.12065 -0.305054)
			(end -0.12065 -0.2794)
			(stroke
				(width 0.1)
				(type default)
			)
			(layer "F.Fab")
		)
		(fp_line
			(start -0.67945 -0.305054)
			(end -0.12065 -0.305054)
			(stroke
				(width 0.1)
				(type default)
			)
			(layer "F.Fab")
		)
		(fp_line
			(start 0.67945 -0.3048)
			(end 0.67945 0.3048)
			(stroke
				(width 0.1)
				(type default)
			)
			(layer "F.Fab")
		)
		(fp_line
			(start 0.12065 -0.3048)
			(end 0.67945 -0.3048)
			(stroke
				(width 0.1)
				(type default)
			)
			(layer "F.Fab")
		)
		(fp_line
			(start 0.12065 -0.2794)
			(end 0.12065 -0.3048)
			(stroke
				(width 0.1)
				(type default)
			)
			(layer "F.Fab")
		)
		(fp_line
			(start -0.12065 -0.2794)
			(end 0.12065 -0.2794)
			(stroke
				(width 0.1)
				(type default)
			)
			(layer "F.Fab")
		)
		(fp_line
			(start 0.120396 0.2794)
			(end -0.12065 0.2794)
			(stroke
				(width 0.1)
				(type default)
			)
			(layer "F.Fab")
		)
		(fp_line
			(start -0.12065 0.2794)
			(end -0.12065 0.3048)
			(stroke
				(width 0.1)
				(type default)
			)
			(layer "F.Fab")
		)
		(fp_line
			(start 0.67945 0.3048)
			(end 0.120396 0.3048)
			(stroke
				(width 0.1)
				(type default)
			)
			(layer "F.Fab")
		)
		(fp_line
			(start 0.120396 0.3048)
			(end 0.120396 0.2794)
			(stroke
				(width 0.1)
				(type default)
			)
			(layer "F.Fab")
		)
		(fp_line
			(start -0.12065 0.3048)
			(end -0.67945 0.3048)
			(stroke
				(width 0.1)
				(type default)
			)
			(layer "F.Fab")
		)
		(fp_line
			(start -0.67945 0.3048)
			(end -0.67945 -0.305054)
			(stroke
				(width 0.1)
				(type default)
			)
			(layer "F.Fab")
		)
		(pad "1" smd circle
			(at -0.40005 0 90)
			(size 0 0)
			(layers "F.Cu" "F.Mask" "F.Paste")
			(net "P3V3_SSD11_SS")
		)
		(pad "2" smd circle
			(at 0.40005 0 90)
			(size 0 0)
			(layers "F.Cu" "F.Mask" "F.Paste")
			(net "GND")
		)
	)
	(footprint ""
		(layer "F.Cu")
		(at 258.574286 -250.070874 -90)
		(property "Reference" "R1338"
			(at 0 0 270)
			(layer "F.SilkS")
			(hide yes)
			(effects
				(font
					(size 1.27 1.27)
				)
			)
		)
		(property "Value" ""
			(at 0 0 270)
			(layer "F.Fab")
			(effects
				(font
					(size 1.27 1.27)
				)
			)
		)
		(duplicate_pad_numbers_are_jumpers no)
		(fp_line
			(start -0.7874 0.4064)
			(end -0.7874 -0.4064)
			(stroke
				(width 0.1524)
				(type default)
			)
			(layer "F.SilkS")
		)
		(fp_line
			(start 0.7874 0.4064)
			(end -0.7874 0.4064)
			(stroke
				(width 0.1524)
				(type default)
			)
			(layer "F.SilkS")
		)
		(fp_line
			(start -0.7874 -0.4064)
			(end 0.7874 -0.4064)
			(stroke
				(width 0.1524)
				(type default)
			)
			(layer "F.SilkS")
		)
		(fp_line
			(start 0.7874 -0.4064)
			(end 0.7874 0.4064)
			(stroke
				(width 0.1524)
				(type default)
			)
			(layer "F.SilkS")
		)
		(fp_line
			(start -0.67945 0.3048)
			(end -0.67945 -0.305054)
			(stroke
				(width 0.1)
				(type default)
			)
			(layer "F.Fab")
		)
		(fp_line
			(start -0.12065 0.3048)
			(end -0.67945 0.3048)
			(stroke
				(width 0.1)
				(type default)
			)
			(layer "F.Fab")
		)
		(fp_line
			(start 0.120396 0.3048)
			(end 0.120396 0.2794)
			(stroke
				(width 0.1)
				(type default)
			)
			(layer "F.Fab")
		)
		(fp_line
			(start 0.67945 0.3048)
			(end 0.120396 0.3048)
			(stroke
				(width 0.1)
				(type default)
			)
			(layer "F.Fab")
		)
		(fp_line
			(start -0.12065 0.2794)
			(end -0.12065 0.3048)
			(stroke
				(width 0.1)
				(type default)
			)
			(layer "F.Fab")
		)
		(fp_line
			(start 0.120396 0.2794)
			(end -0.12065 0.2794)
			(stroke
				(width 0.1)
				(type default)
			)
			(layer "F.Fab")
		)
		(fp_line
			(start -0.12065 -0.2794)
			(end 0.12065 -0.2794)
			(stroke
				(width 0.1)
				(type default)
			)
			(layer "F.Fab")
		)
		(fp_line
			(start 0.12065 -0.2794)
			(end 0.12065 -0.3048)
			(stroke
				(width 0.1)
				(type default)
			)
			(layer "F.Fab")
		)
		(fp_line
			(start 0.12065 -0.3048)
			(end 0.67945 -0.3048)
			(stroke
				(width 0.1)
				(type default)
			)
			(layer "F.Fab")
		)
		(fp_line
			(start 0.67945 -0.3048)
			(end 0.67945 0.3048)
			(stroke
				(width 0.1)
				(type default)
			)
			(layer "F.Fab")
		)
		(fp_line
			(start -0.67945 -0.305054)
			(end -0.12065 -0.305054)
			(stroke
				(width 0.1)
				(type default)
			)
			(layer "F.Fab")
		)
		(fp_line
			(start -0.12065 -0.305054)
			(end -0.12065 -0.2794)
			(stroke
				(width 0.1)
				(type default)
			)
			(layer "F.Fab")
		)
		(pad "1" smd circle
			(at -0.40005 0 270)
			(size 0 0)
			(layers "F.Cu" "F.Mask" "F.Paste")
			(net "PEX2_MODE_SEL2")
		)
		(pad "2" smd circle
			(at 0.40005 0 270)
			(size 0 0)
			(layers "F.Cu" "F.Mask" "F.Paste")
			(net "P1V8_PEX")
		)
	)
	(footprint ""
		(layer "F.Cu")
		(at 353.822 -167.64)
		(property "Reference" "R4778"
			(at 0 0 0)
			(layer "F.SilkS")
			(hide yes)
			(effects
				(font
					(size 1.27 1.27)
				)
			)
		)
		(property "Value" ""
			(at 0 0 0)
			(layer "F.Fab")
			(effects
				(font
					(size 1.27 1.27)
				)
			)
		)
		(duplicate_pad_numbers_are_jumpers no)
		(fp_line
			(start -0.7874 -0.4064)
			(end 0.7874 -0.4064)
			(stroke
				(width 0.1524)
				(type default)
			)
			(layer "F.SilkS")
		)
		(fp_line
			(start -0.7874 0.4064)
			(end -0.7874 -0.4064)
			(stroke
				(width 0.1524)
				(type default)
			)
			(layer "F.SilkS")
		)
		(fp_line
			(start 0.7874 -0.4064)
			(end 0.7874 0.4064)
			(stroke
				(width 0.1524)
				(type default)
			)
			(layer "F.SilkS")
		)
		(fp_line
			(start 0.7874 0.4064)
			(end -0.7874 0.4064)
			(stroke
				(width 0.1524)
				(type default)
			)
			(layer "F.SilkS")
		)
		(fp_line
			(start -0.67945 -0.305054)
			(end -0.12065 -0.305054)
			(stroke
				(width 0.1)
				(type default)
			)
			(layer "F.Fab")
		)
		(fp_line
			(start -0.67945 0.3048)
			(end -0.67945 -0.305054)
			(stroke
				(width 0.1)
				(type default)
			)
			(layer "F.Fab")
		)
		(fp_line
			(start -0.12065 -0.305054)
			(end -0.12065 -0.2794)
			(stroke
				(width 0.1)
				(type default)
			)
			(layer "F.Fab")
		)
		(fp_line
			(start -0.12065 -0.2794)
			(end 0.12065 -0.2794)
			(stroke
				(width 0.1)
				(type default)
			)
			(layer "F.Fab")
		)
		(fp_line
			(start -0.12065 0.2794)
			(end -0.12065 0.3048)
			(stroke
				(width 0.1)
				(type default)
			)
			(layer "F.Fab")
		)
		(fp_line
			(start -0.12065 0.3048)
			(end -0.67945 0.3048)
			(stroke
				(width 0.1)
				(type default)
			)
			(layer "F.Fab")
		)
		(fp_line
			(start 0.120396 0.2794)
			(end -0.12065 0.2794)
			(stroke
				(width 0.1)
				(type default)
			)
			(layer "F.Fab")
		)
		(fp_line
			(start 0.120396 0.3048)
			(end 0.120396 0.2794)
			(stroke
				(width 0.1)
				(type default)
			)
			(layer "F.Fab")
		)
		(fp_line
			(start 0.12065 -0.3048)
			(end 0.67945 -0.3048)
			(stroke
				(width 0.1)
				(type default)
			)
			(layer "F.Fab")
		)
		(fp_line
			(start 0.12065 -0.2794)
			(end 0.12065 -0.3048)
			(stroke
				(width 0.1)
				(type default)
			)
			(layer "F.Fab")
		)
		(fp_line
			(start 0.67945 -0.3048)
			(end 0.67945 0.3048)
			(stroke
				(width 0.1)
				(type default)
			)
			(layer "F.Fab")
		)
		(fp_line
			(start 0.67945 0.3048)
			(end 0.120396 0.3048)
			(stroke
				(width 0.1)
				(type default)
			)
			(layer "F.Fab")
		)
		(pad "1" smd circle
			(at -0.40005 0)
			(size 0 0)
			(layers "F.Cu" "F.Mask" "F.Paste")
			(net "RST_PEX_NIC5_PERST_N")
		)
		(pad "2" smd circle
			(at 0.40005 0)
			(size 0 0)
			(layers "F.Cu" "F.Mask" "F.Paste")
			(net "RST_PEX_NIC5_PERST_R_N")
		)
	)
	(footprint ""
		(layer "F.Cu")
		(at 103.011224 -84.223606 180)
		(property "Reference" "R1470"
			(at 0 0 180)
			(layer "F.SilkS")
			(hide yes)
			(effects
				(font
					(size 1.27 1.27)
				)
			)
		)
		(property "Value" ""
			(at 0 0 180)
			(layer "F.Fab")
			(effects
				(font
					(size 1.27 1.27)
				)
			)
		)
		(duplicate_pad_numbers_are_jumpers no)
		(fp_line
			(start 0.7874 0.4064)
			(end -0.7874 0.4064)
			(stroke
				(width 0.1524)
				(type default)
			)
			(layer "F.SilkS")
		)
		(fp_line
			(start 0.7874 -0.4064)
			(end 0.7874 0.4064)
			(stroke
				(width 0.1524)
				(type default)
			)
			(layer "F.SilkS")
		)
		(fp_line
			(start -0.7874 0.4064)
			(end -0.7874 -0.4064)
			(stroke
				(width 0.1524)
				(type default)
			)
			(layer "F.SilkS")
		)
		(fp_line
			(start -0.7874 -0.4064)
			(end 0.7874 -0.4064)
			(stroke
				(width 0.1524)
				(type default)
			)
			(layer "F.SilkS")
		)
		(fp_line
			(start 0.67945 0.3048)
			(end 0.120396 0.3048)
			(stroke
				(width 0.1)
				(type default)
			)
			(layer "F.Fab")
		)
		(fp_line
			(start 0.67945 -0.3048)
			(end 0.67945 0.3048)
			(stroke
				(width 0.1)
				(type default)
			)
			(layer "F.Fab")
		)
		(fp_line
			(start 0.12065 -0.2794)
			(end 0.12065 -0.3048)
			(stroke
				(width 0.1)
				(type default)
			)
			(layer "F.Fab")
		)
		(fp_line
			(start 0.12065 -0.3048)
			(end 0.67945 -0.3048)
			(stroke
				(width 0.1)
				(type default)
			)
			(layer "F.Fab")
		)
		(fp_line
			(start 0.120396 0.3048)
			(end 0.120396 0.2794)
			(stroke
				(width 0.1)
				(type default)
			)
			(layer "F.Fab")
		)
		(fp_line
			(start 0.120396 0.2794)
			(end -0.12065 0.2794)
			(stroke
				(width 0.1)
				(type default)
			)
			(layer "F.Fab")
		)
		(fp_line
			(start -0.12065 0.3048)
			(end -0.67945 0.3048)
			(stroke
				(width 0.1)
				(type default)
			)
			(layer "F.Fab")
		)
		(fp_line
			(start -0.12065 0.2794)
			(end -0.12065 0.3048)
			(stroke
				(width 0.1)
				(type default)
			)
			(layer "F.Fab")
		)
		(fp_line
			(start -0.12065 -0.2794)
			(end 0.12065 -0.2794)
			(stroke
				(width 0.1)
				(type default)
			)
			(layer "F.Fab")
		)
		(fp_line
			(start -0.12065 -0.305054)
			(end -0.12065 -0.2794)
			(stroke
				(width 0.1)
				(type default)
			)
			(layer "F.Fab")
		)
		(fp_line
			(start -0.67945 0.3048)
			(end -0.67945 -0.305054)
			(stroke
				(width 0.1)
				(type default)
			)
			(layer "F.Fab")
		)
		(fp_line
			(start -0.67945 -0.305054)
			(end -0.12065 -0.305054)
			(stroke
				(width 0.1)
				(type default)
			)
			(layer "F.Fab")
		)
		(pad "1" smd circle
			(at -0.40005 0 180)
			(size 0 0)
			(layers "F.Cu" "F.Mask" "F.Paste")
			(net "SMB_BMC_9ZXL0851_0_7_SCL")
		)
		(pad "2" smd circle
			(at 0.40005 0 180)
			(size 0 0)
			(layers "F.Cu" "F.Mask" "F.Paste")
			(net "SMB_CLK_ISO_R_SCL")
		)
	)
	(footprint ""
		(layer "F.Cu")
		(at 447.275712 -118.467886)
		(property "Reference" "PC495"
			(at 0 0 0)
			(layer "F.SilkS")
			(hide yes)
			(effects
				(font
					(size 1.27 1.27)
				)
			)
		)
		(property "Value" ""
			(at 0 0 0)
			(layer "F.Fab")
			(effects
				(font
					(size 1.27 1.27)
				)
			)
		)
		(duplicate_pad_numbers_are_jumpers no)
		(fp_line
			(start -0.7874 -0.4064)
			(end 0.7874 -0.4064)
			(stroke
				(width 0.1524)
				(type default)
			)
			(layer "F.SilkS")
		)
		(fp_line
			(start -0.7874 0.4064)
			(end -0.7874 -0.4064)
			(stroke
				(width 0.1524)
				(type default)
			)
			(layer "F.SilkS")
		)
		(fp_line
			(start 0.7874 -0.4064)
			(end 0.7874 0.4064)
			(stroke
				(width 0.1524)
				(type default)
			)
			(layer "F.SilkS")
		)
		(fp_line
			(start 0.7874 0.4064)
			(end -0.7874 0.4064)
			(stroke
				(width 0.1524)
				(type default)
			)
			(layer "F.SilkS")
		)
		(fp_line
			(start -0.67945 -0.305054)
			(end -0.12065 -0.305054)
			(stroke
				(width 0.1)
				(type default)
			)
			(layer "F.Fab")
		)
		(fp_line
			(start -0.67945 0.3048)
			(end -0.67945 -0.305054)
			(stroke
				(width 0.1)
				(type default)
			)
			(layer "F.Fab")
		)
		(fp_line
			(start -0.12065 -0.305054)
			(end -0.12065 -0.2794)
			(stroke
				(width 0.1)
				(type default)
			)
			(layer "F.Fab")
		)
		(fp_line
			(start -0.12065 -0.2794)
			(end 0.12065 -0.2794)
			(stroke
				(width 0.1)
				(type default)
			)
			(layer "F.Fab")
		)
		(fp_line
			(start -0.12065 0.2794)
			(end -0.12065 0.3048)
			(stroke
				(width 0.1)
				(type default)
			)
			(layer "F.Fab")
		)
		(fp_line
			(start -0.12065 0.3048)
			(end -0.67945 0.3048)
			(stroke
				(width 0.1)
				(type default)
			)
			(layer "F.Fab")
		)
		(fp_line
			(start 0.120396 0.2794)
			(end -0.12065 0.2794)
			(stroke
				(width 0.1)
				(type default)
			)
			(layer "F.Fab")
		)
		(fp_line
			(start 0.120396 0.3048)
			(end 0.120396 0.2794)
			(stroke
				(width 0.1)
				(type default)
			)
			(layer "F.Fab")
		)
		(fp_line
			(start 0.12065 -0.3048)
			(end 0.67945 -0.3048)
			(stroke
				(width 0.1)
				(type default)
			)
			(layer "F.Fab")
		)
		(fp_line
			(start 0.12065 -0.2794)
			(end 0.12065 -0.3048)
			(stroke
				(width 0.1)
				(type default)
			)
			(layer "F.Fab")
		)
		(fp_line
			(start 0.67945 -0.3048)
			(end 0.67945 0.3048)
			(stroke
				(width 0.1)
				(type default)
			)
			(layer "F.Fab")
		)
		(fp_line
			(start 0.67945 0.3048)
			(end 0.120396 0.3048)
			(stroke
				(width 0.1)
				(type default)
			)
			(layer "F.Fab")
		)
		(pad "1" smd circle
			(at -0.40005 0)
			(size 0 0)
			(layers "F.Cu" "F.Mask" "F.Paste")
			(net "P3V3_NIC7_SS")
		)
		(pad "2" smd circle
			(at 0.40005 0)
			(size 0 0)
			(layers "F.Cu" "F.Mask" "F.Paste")
			(net "GND")
		)
	)
	(footprint ""
		(layer "F.Cu")
		(at 138.946128 -46.4439 180)
		(property "Reference" "U59"
			(at -0.042672 -2.40157 0)
			(unlocked yes)
			(layer "F.SilkS")
			(effects
				(font
					(size 0.7874 0.5842)
					(thickness 0.1524)
				)
			)
		)
		(property "Value" ""
			(at 0 0 180)
			(layer "F.Fab")
			(effects
				(font
					(size 1.27 1.27)
				)
			)
		)
		(duplicate_pad_numbers_are_jumpers no)
		(fp_line
			(start 1.500124 1.500124)
			(end 1.004062 1.500124)
			(stroke
				(width 0.1524)
				(type default)
			)
			(layer "F.SilkS")
		)
		(fp_line
			(start 1.500124 1.004062)
			(end 1.500124 1.500124)
			(stroke
				(width 0.1524)
				(type default)
			)
			(layer "F.SilkS")
		)
		(fp_line
			(start 1.500124 -1.500124)
			(end 1.500124 -1.004062)
			(stroke
				(width 0.1524)
				(type default)
			)
			(layer "F.SilkS")
		)
		(fp_line
			(start 1.004062 -1.500124)
			(end 1.500124 -1.500124)
			(stroke
				(width 0.1524)
				(type default)
			)
			(layer "F.SilkS")
		)
		(fp_line
			(start -1.004062 1.500124)
			(end -1.500124 1.500124)
			(stroke
				(width 0.1524)
				(type default)
			)
			(layer "F.SilkS")
		)
		(fp_line
			(start -1.500124 1.500124)
			(end -1.500124 1.004062)
			(stroke
				(width 0.1524)
				(type default)
			)
			(layer "F.SilkS")
		)
		(fp_line
			(start -1.500124 -1.004062)
			(end -1.500124 -1.500124)
			(stroke
				(width 0.1524)
				(type default)
			)
			(layer "F.SilkS")
		)
		(fp_line
			(start -1.500124 -1.500124)
			(end -1.004062 -1.500124)
			(stroke
				(width 0.1524)
				(type default)
			)
			(layer "F.SilkS")
		)
		(fp_poly
			(pts
				(xy -1.957832 -1.995678) (xy -2.676144 -1.277366) (xy -1.598422 -0.917956)
			)
			(stroke
				(width 0)
				(type default)
			)
			(fill yes)
			(layer "F.SilkS")
		)
		(fp_line
			(start 1.500124 1.500124)
			(end -1.500124 1.500124)
			(stroke
				(width 0.1)
				(type default)
			)
			(layer "F.Fab")
		)
		(fp_line
			(start 1.500124 -1.500124)
			(end 1.500124 1.500124)
			(stroke
				(width 0.1)
				(type default)
			)
			(layer "F.Fab")
		)
		(fp_line
			(start -1.500124 1.500124)
			(end -1.500124 -1.500124)
			(stroke
				(width 0.1)
				(type default)
			)
			(layer "F.Fab")
		)
		(fp_line
			(start -1.500124 -1.500124)
			(end 1.500124 -1.500124)
			(stroke
				(width 0.1)
				(type default)
			)
			(layer "F.Fab")
		)
		(fp_poly
			(pts
				(xy -2.847848 -1.258062) (xy -2.847848 -0.242062) (xy -1.831848 -0.750062)
			)
			(stroke
				(width 0)
				(type default)
			)
			(fill yes)
			(layer "F.Fab")
		)
		(pad "1" smd rect
			(at -1.400048 -0.750062 90)
			(size 0.2286 0.6096)
			(layers "F.Cu" "F.Mask" "F.Paste")
			(net "SSD4_ADC_A1")
		)
		(pad "2" smd rect
			(at -1.400048 -0.249936 90)
			(size 0.2286 0.6096)
			(layers "F.Cu" "F.Mask" "F.Paste")
			(net "SSD4_ADC_A0")
		)
		(pad "3" smd rect
			(at -1.400048 0.249936 90)
			(size 0.2286 0.6096)
			(layers "F.Cu" "F.Mask" "F.Paste")
			(net "SSD4_ADC_ALERT_N")
		)
		(pad "4" smd rect
			(at -1.400048 0.750062 90)
			(size 0.2286 0.6096)
			(layers "F.Cu" "F.Mask" "F.Paste")
			(net "SMB_SSD4_ADC_SDA")
		)
		(pad "5" smd rect
			(at -0.750062 1.400048 180)
			(size 0.2286 0.6096)
			(layers "F.Cu" "F.Mask" "F.Paste")
			(net "SMB_SSD4_ADC_SCL")
		)
		(pad "6" smd rect
			(at -0.249936 1.400048 180)
			(size 0.2286 0.6096)
			(layers "F.Cu" "F.Mask" "F.Paste")
			(net "Net_8738")
		)
		(pad "7" smd rect
			(at 0.249936 1.400048 180)
			(size 0.2286 0.6096)
			(layers "F.Cu" "F.Mask" "F.Paste")
			(net "Net_8737")
		)
		(pad "8" smd rect
			(at 0.750062 1.400048 180)
			(size 0.2286 0.6096)
			(layers "F.Cu" "F.Mask" "F.Paste")
			(net "Net_8736")
		)
		(pad "9" smd rect
			(at 1.400048 0.750062 90)
			(size 0.2286 0.6096)
			(layers "F.Cu" "F.Mask" "F.Paste")
			(net "P3V3_AUX")
		)
		(pad "10" smd rect
			(at 1.400048 0.249936 90)
			(size 0.2286 0.6096)
			(layers "F.Cu" "F.Mask" "F.Paste")
			(net "GND")
		)
		(pad "11" smd rect
			(at 1.400048 -0.249936 90)
			(size 0.2286 0.6096)
			(layers "F.Cu" "F.Mask" "F.Paste")
			(net "P12V_SSD4_R")
		)
		(pad "12" smd rect
			(at 1.400048 -0.750062 90)
			(size 0.2286 0.6096)
			(layers "F.Cu" "F.Mask" "F.Paste")
			(net "P12V_SSD4_VIN_N")
		)
		(pad "13" smd rect
			(at 0.750062 -1.400048 180)
			(size 0.2286 0.6096)
			(layers "F.Cu" "F.Mask" "F.Paste")
			(net "P12V_SSD4_VIN_P")
		)
		(pad "14" smd rect
			(at 0.249936 -1.400048 180)
			(size 0.2286 0.6096)
			(layers "F.Cu" "F.Mask" "F.Paste")
			(net "Net_8735")
		)
		(pad "15" smd rect
			(at -0.249936 -1.400048 180)
			(size 0.2286 0.6096)
			(layers "F.Cu" "F.Mask" "F.Paste")
			(net "Net_8734")
		)
		(pad "16" smd rect
			(at -0.750062 -1.400048 180)
			(size 0.2286 0.6096)
			(layers "F.Cu" "F.Mask" "F.Paste")
			(net "Net_8733")
		)
		(pad "TH" smd rect
			(at 0 0 180)
			(size 1.7018 1.7018)
			(layers "F.Cu" "F.Mask" "F.Paste")
			(net "GND")
		)
		(zone
			(layer "F.Cu")
			(hatch none 0.5)
			(connect_pads
				(clearance 0)
			)
			(min_thickness 0.25)
			(keepout
				(tracks not_allowed)
				(vias allowed)
				(pads allowed)
				(copperpour not_allowed)
				(footprints allowed)
			)
			(placement
				(enabled no)
				(sheetname "")
			)
			(fill
				(thermal_gap 0.5)
				(thermal_bridge_width 0.5)
				(island_removal_mode 0)
			)
			(polygon
				(pts
					(xy 139.990576 -46.4185) (xy 139.990576 -45.399452) (xy 137.90168 -45.399452) (xy 137.90168 -47.488348)
					(xy 139.990576 -47.488348) (xy 139.990576 -46.4439) (xy 139.847828 -46.4439) (xy 139.847828 -47.3456)
					(xy 138.044428 -47.3456) (xy 138.044428 -45.5422) (xy 139.847828 -45.5422) (xy 139.847828 -46.4185)
				)
			)
		)
	)
	(footprint ""
		(layer "F.Cu")
		(at 464.381088 -279.535128 -90)
		(property "Reference" "R1771"
			(at 0 0 270)
			(layer "F.SilkS")
			(hide yes)
			(effects
				(font
					(size 1.27 1.27)
				)
			)
		)
		(property "Value" ""
			(at 0 0 270)
			(layer "F.Fab")
			(effects
				(font
					(size 1.27 1.27)
				)
			)
		)
		(duplicate_pad_numbers_are_jumpers no)
		(fp_line
			(start -0.7874 0.4064)
			(end -0.7874 -0.4064)
			(stroke
				(width 0.1524)
				(type default)
			)
			(layer "F.SilkS")
		)
		(fp_line
			(start 0.7874 0.4064)
			(end -0.7874 0.4064)
			(stroke
				(width 0.1524)
				(type default)
			)
			(layer "F.SilkS")
		)
		(fp_line
			(start -0.7874 -0.4064)
			(end 0.7874 -0.4064)
			(stroke
				(width 0.1524)
				(type default)
			)
			(layer "F.SilkS")
		)
		(fp_line
			(start 0.7874 -0.4064)
			(end 0.7874 0.4064)
			(stroke
				(width 0.1524)
				(type default)
			)
			(layer "F.SilkS")
		)
		(fp_line
			(start -0.67945 0.3048)
			(end -0.67945 -0.305054)
			(stroke
				(width 0.1)
				(type default)
			)
			(layer "F.Fab")
		)
		(fp_line
			(start -0.12065 0.3048)
			(end -0.67945 0.3048)
			(stroke
				(width 0.1)
				(type default)
			)
			(layer "F.Fab")
		)
		(fp_line
			(start 0.120396 0.3048)
			(end 0.120396 0.2794)
			(stroke
				(width 0.1)
				(type default)
			)
			(layer "F.Fab")
		)
		(fp_line
			(start 0.67945 0.3048)
			(end 0.120396 0.3048)
			(stroke
				(width 0.1)
				(type default)
			)
			(layer "F.Fab")
		)
		(fp_line
			(start -0.12065 0.2794)
			(end -0.12065 0.3048)
			(stroke
				(width 0.1)
				(type default)
			)
			(layer "F.Fab")
		)
		(fp_line
			(start 0.120396 0.2794)
			(end -0.12065 0.2794)
			(stroke
				(width 0.1)
				(type default)
			)
			(layer "F.Fab")
		)
		(fp_line
			(start -0.12065 -0.2794)
			(end 0.12065 -0.2794)
			(stroke
				(width 0.1)
				(type default)
			)
			(layer "F.Fab")
		)
		(fp_line
			(start 0.12065 -0.2794)
			(end 0.12065 -0.3048)
			(stroke
				(width 0.1)
				(type default)
			)
			(layer "F.Fab")
		)
		(fp_line
			(start 0.12065 -0.3048)
			(end 0.67945 -0.3048)
			(stroke
				(width 0.1)
				(type default)
			)
			(layer "F.Fab")
		)
		(fp_line
			(start 0.67945 -0.3048)
			(end 0.67945 0.3048)
			(stroke
				(width 0.1)
				(type default)
			)
			(layer "F.Fab")
		)
		(fp_line
			(start -0.67945 -0.305054)
			(end -0.12065 -0.305054)
			(stroke
				(width 0.1)
				(type default)
			)
			(layer "F.Fab")
		)
		(fp_line
			(start -0.12065 -0.305054)
			(end -0.12065 -0.2794)
			(stroke
				(width 0.1)
				(type default)
			)
			(layer "F.Fab")
		)
		(pad "1" smd circle
			(at -0.40005 0 270)
			(size 0 0)
			(layers "F.Cu" "F.Mask" "F.Paste")
			(net "SMB_BIC_I2C6_MUX_PEX_ADC_R_SCL")
		)
		(pad "2" smd circle
			(at 0.40005 0 270)
			(size 0 0)
			(layers "F.Cu" "F.Mask" "F.Paste")
			(net "SMB_BIC_I2C6_MUX_PEX_ADC_SCL")
		)
	)
	(footprint ""
		(layer "F.Cu")
		(at 14.788896 -119.140986 90)
		(property "Reference" "PC665"
			(at 0 0 90)
			(layer "F.SilkS")
			(hide yes)
			(effects
				(font
					(size 1.27 1.27)
				)
			)
		)
		(property "Value" ""
			(at 0 0 90)
			(layer "F.Fab")
			(effects
				(font
					(size 1.27 1.27)
				)
			)
		)
		(duplicate_pad_numbers_are_jumpers no)
		(fp_line
			(start 0.7874 -0.4064)
			(end 0.7874 0.4064)
			(stroke
				(width 0.1524)
				(type default)
			)
			(layer "F.SilkS")
		)
		(fp_line
			(start -0.7874 -0.4064)
			(end 0.7874 -0.4064)
			(stroke
				(width 0.1524)
				(type default)
			)
			(layer "F.SilkS")
		)
		(fp_line
			(start 0.7874 0.4064)
			(end -0.7874 0.4064)
			(stroke
				(width 0.1524)
				(type default)
			)
			(layer "F.SilkS")
		)
		(fp_line
			(start -0.7874 0.4064)
			(end -0.7874 -0.4064)
			(stroke
				(width 0.1524)
				(type default)
			)
			(layer "F.SilkS")
		)
		(fp_line
			(start -0.12065 -0.305054)
			(end -0.12065 -0.2794)
			(stroke
				(width 0.1)
				(type default)
			)
			(layer "F.Fab")
		)
		(fp_line
			(start -0.67945 -0.305054)
			(end -0.12065 -0.305054)
			(stroke
				(width 0.1)
				(type default)
			)
			(layer "F.Fab")
		)
		(fp_line
			(start 0.67945 -0.3048)
			(end 0.67945 0.3048)
			(stroke
				(width 0.1)
				(type default)
			)
			(layer "F.Fab")
		)
		(fp_line
			(start 0.12065 -0.3048)
			(end 0.67945 -0.3048)
			(stroke
				(width 0.1)
				(type default)
			)
			(layer "F.Fab")
		)
		(fp_line
			(start 0.12065 -0.2794)
			(end 0.12065 -0.3048)
			(stroke
				(width 0.1)
				(type default)
			)
			(layer "F.Fab")
		)
		(fp_line
			(start -0.12065 -0.2794)
			(end 0.12065 -0.2794)
			(stroke
				(width 0.1)
				(type default)
			)
			(layer "F.Fab")
		)
		(fp_line
			(start 0.120396 0.2794)
			(end -0.12065 0.2794)
			(stroke
				(width 0.1)
				(type default)
			)
			(layer "F.Fab")
		)
		(fp_line
			(start -0.12065 0.2794)
			(end -0.12065 0.3048)
			(stroke
				(width 0.1)
				(type default)
			)
			(layer "F.Fab")
		)
		(fp_line
			(start 0.67945 0.3048)
			(end 0.120396 0.3048)
			(stroke
				(width 0.1)
				(type default)
			)
			(layer "F.Fab")
		)
		(fp_line
			(start 0.120396 0.3048)
			(end 0.120396 0.2794)
			(stroke
				(width 0.1)
				(type default)
			)
			(layer "F.Fab")
		)
		(fp_line
			(start -0.12065 0.3048)
			(end -0.67945 0.3048)
			(stroke
				(width 0.1)
				(type default)
			)
			(layer "F.Fab")
		)
		(fp_line
			(start -0.67945 0.3048)
			(end -0.67945 -0.305054)
			(stroke
				(width 0.1)
				(type default)
			)
			(layer "F.Fab")
		)
		(pad "1" smd circle
			(at -0.40005 0 90)
			(size 0 0)
			(layers "F.Cu" "F.Mask" "F.Paste")
			(net "P3V3_NIC0_CO_DV_DT")
		)
		(pad "2" smd circle
			(at 0.40005 0 90)
			(size 0 0)
			(layers "F.Cu" "F.Mask" "F.Paste")
			(net "GND")
		)
	)
	(footprint ""
		(layer "F.Cu")
		(at 450.085968 -258.331208 -90)
		(property "Reference" "R6561"
			(at 0 0 270)
			(layer "F.SilkS")
			(hide yes)
			(effects
				(font
					(size 1.27 1.27)
				)
			)
		)
		(property "Value" ""
			(at 0 0 270)
			(layer "F.Fab")
			(effects
				(font
					(size 1.27 1.27)
				)
			)
		)
		(duplicate_pad_numbers_are_jumpers no)
		(fp_line
			(start -0.7874 0.4064)
			(end -0.7874 -0.4064)
			(stroke
				(width 0.1524)
				(type default)
			)
			(layer "F.SilkS")
		)
		(fp_line
			(start 0.7874 0.4064)
			(end -0.7874 0.4064)
			(stroke
				(width 0.1524)
				(type default)
			)
			(layer "F.SilkS")
		)
		(fp_line
			(start -0.7874 -0.4064)
			(end 0.7874 -0.4064)
			(stroke
				(width 0.1524)
				(type default)
			)
			(layer "F.SilkS")
		)
		(fp_line
			(start 0.7874 -0.4064)
			(end 0.7874 0.4064)
			(stroke
				(width 0.1524)
				(type default)
			)
			(layer "F.SilkS")
		)
		(fp_line
			(start -0.67945 0.3048)
			(end -0.67945 -0.305054)
			(stroke
				(width 0.1)
				(type default)
			)
			(layer "F.Fab")
		)
		(fp_line
			(start -0.12065 0.3048)
			(end -0.67945 0.3048)
			(stroke
				(width 0.1)
				(type default)
			)
			(layer "F.Fab")
		)
		(fp_line
			(start 0.120396 0.3048)
			(end 0.120396 0.2794)
			(stroke
				(width 0.1)
				(type default)
			)
			(layer "F.Fab")
		)
		(fp_line
			(start 0.67945 0.3048)
			(end 0.120396 0.3048)
			(stroke
				(width 0.1)
				(type default)
			)
			(layer "F.Fab")
		)
		(fp_line
			(start -0.12065 0.2794)
			(end -0.12065 0.3048)
			(stroke
				(width 0.1)
				(type default)
			)
			(layer "F.Fab")
		)
		(fp_line
			(start 0.120396 0.2794)
			(end -0.12065 0.2794)
			(stroke
				(width 0.1)
				(type default)
			)
			(layer "F.Fab")
		)
		(fp_line
			(start -0.12065 -0.2794)
			(end 0.12065 -0.2794)
			(stroke
				(width 0.1)
				(type default)
			)
			(layer "F.Fab")
		)
		(fp_line
			(start 0.12065 -0.2794)
			(end 0.12065 -0.3048)
			(stroke
				(width 0.1)
				(type default)
			)
			(layer "F.Fab")
		)
		(fp_line
			(start 0.12065 -0.3048)
			(end 0.67945 -0.3048)
			(stroke
				(width 0.1)
				(type default)
			)
			(layer "F.Fab")
		)
		(fp_line
			(start 0.67945 -0.3048)
			(end 0.67945 0.3048)
			(stroke
				(width 0.1)
				(type default)
			)
			(layer "F.Fab")
		)
		(fp_line
			(start -0.67945 -0.305054)
			(end -0.12065 -0.305054)
			(stroke
				(width 0.1)
				(type default)
			)
			(layer "F.Fab")
		)
		(fp_line
			(start -0.12065 -0.305054)
			(end -0.12065 -0.2794)
			(stroke
				(width 0.1)
				(type default)
			)
			(layer "F.Fab")
		)
		(pad "1" smd circle
			(at -0.40005 0 270)
			(size 0 0)
			(layers "F.Cu" "F.Mask" "F.Paste")
			(net "P1V25_SERDES_VDDPLL_PEX3")
		)
		(pad "2" smd circle
			(at 0.40005 0 270)
			(size 0 0)
			(layers "F.Cu" "F.Mask" "F.Paste")
			(net "P1V25_SERDES_VDDPLL_PEX3_C8")
		)
	)
	(footprint ""
		(layer "F.Cu")
		(at 239.813338 -140.392404 180)
		(property "Reference" "PC315"
			(at 0 0 180)
			(layer "F.SilkS")
			(hide yes)
			(effects
				(font
					(size 1.27 1.27)
				)
			)
		)
		(property "Value" ""
			(at 0 0 180)
			(layer "F.Fab")
			(effects
				(font
					(size 1.27 1.27)
				)
			)
		)
		(duplicate_pad_numbers_are_jumpers no)
		(fp_line
			(start 0.7874 0.4064)
			(end -0.7874 0.4064)
			(stroke
				(width 0.1524)
				(type default)
			)
			(layer "F.SilkS")
		)
		(fp_line
			(start 0.7874 -0.4064)
			(end 0.7874 0.4064)
			(stroke
				(width 0.1524)
				(type default)
			)
			(layer "F.SilkS")
		)
		(fp_line
			(start -0.7874 0.4064)
			(end -0.7874 -0.4064)
			(stroke
				(width 0.1524)
				(type default)
			)
			(layer "F.SilkS")
		)
		(fp_line
			(start -0.7874 -0.4064)
			(end 0.7874 -0.4064)
			(stroke
				(width 0.1524)
				(type default)
			)
			(layer "F.SilkS")
		)
		(fp_line
			(start 0.6858 0.3048)
			(end 0.1016 0.3048)
			(stroke
				(width 0.1)
				(type default)
			)
			(layer "F.Fab")
		)
		(fp_line
			(start 0.6858 -0.3048)
			(end 0.6858 0.3048)
			(stroke
				(width 0.1)
				(type default)
			)
			(layer "F.Fab")
		)
		(fp_line
			(start 0.1016 0.3048)
			(end 0.1016 0.2794)
			(stroke
				(width 0.1)
				(type default)
			)
			(layer "F.Fab")
		)
		(fp_line
			(start 0.1016 0.2794)
			(end -0.1016 0.2794)
			(stroke
				(width 0.1)
				(type default)
			)
			(layer "F.Fab")
		)
		(fp_line
			(start 0.1016 -0.2794)
			(end 0.1016 -0.3048)
			(stroke
				(width 0.1)
				(type default)
			)
			(layer "F.Fab")
		)
		(fp_line
			(start 0.1016 -0.3048)
			(end 0.6858 -0.3048)
			(stroke
				(width 0.1)
				(type default)
			)
			(layer "F.Fab")
		)
		(fp_line
			(start -0.1016 0.3048)
			(end -0.6858 0.3048)
			(stroke
				(width 0.1)
				(type default)
			)
			(layer "F.Fab")
		)
		(fp_line
			(start -0.1016 0.2794)
			(end -0.1016 0.3048)
			(stroke
				(width 0.1)
				(type default)
			)
			(layer "F.Fab")
		)
		(fp_line
			(start -0.1016 -0.2794)
			(end 0.1016 -0.2794)
			(stroke
				(width 0.1)
				(type default)
			)
			(layer "F.Fab")
		)
		(fp_line
			(start -0.1016 -0.3048)
			(end -0.1016 -0.2794)
			(stroke
				(width 0.1)
				(type default)
			)
			(layer "F.Fab")
		)
		(fp_line
			(start -0.6858 0.3048)
			(end -0.6858 -0.3048)
			(stroke
				(width 0.1)
				(type default)
			)
			(layer "F.Fab")
		)
		(fp_line
			(start -0.6858 -0.3048)
			(end -0.1016 -0.3048)
			(stroke
				(width 0.1)
				(type default)
			)
			(layer "F.Fab")
		)
		(pad "1" smd rect
			(at -0.40005 0)
			(size 0.4572 0.508)
			(layers "F.Cu" "F.Mask" "F.Paste")
			(net "P12V_NIC4_SS")
		)
		(pad "2" smd rect
			(at 0.40005 0)
			(size 0.4572 0.508)
			(layers "F.Cu" "F.Mask" "F.Paste")
			(net "GND")
		)
	)
	(footprint ""
		(layer "F.Cu")
		(at 426.543724 -43.85691)
		(property "Reference" "R663"
			(at 0 0 0)
			(layer "F.SilkS")
			(hide yes)
			(effects
				(font
					(size 1.27 1.27)
				)
			)
		)
		(property "Value" ""
			(at 0 0 0)
			(layer "F.Fab")
			(effects
				(font
					(size 1.27 1.27)
				)
			)
		)
		(duplicate_pad_numbers_are_jumpers no)
		(fp_line
			(start -0.7874 -0.4064)
			(end 0.7874 -0.4064)
			(stroke
				(width 0.1524)
				(type default)
			)
			(layer "F.SilkS")
		)
		(fp_line
			(start -0.7874 0.4064)
			(end -0.7874 -0.4064)
			(stroke
				(width 0.1524)
				(type default)
			)
			(layer "F.SilkS")
		)
		(fp_line
			(start 0.7874 -0.4064)
			(end 0.7874 0.4064)
			(stroke
				(width 0.1524)
				(type default)
			)
			(layer "F.SilkS")
		)
		(fp_line
			(start 0.7874 0.4064)
			(end -0.7874 0.4064)
			(stroke
				(width 0.1524)
				(type default)
			)
			(layer "F.SilkS")
		)
		(fp_line
			(start -0.67945 -0.305054)
			(end -0.12065 -0.305054)
			(stroke
				(width 0.1)
				(type default)
			)
			(layer "F.Fab")
		)
		(fp_line
			(start -0.67945 0.3048)
			(end -0.67945 -0.305054)
			(stroke
				(width 0.1)
				(type default)
			)
			(layer "F.Fab")
		)
		(fp_line
			(start -0.12065 -0.305054)
			(end -0.12065 -0.2794)
			(stroke
				(width 0.1)
				(type default)
			)
			(layer "F.Fab")
		)
		(fp_line
			(start -0.12065 -0.2794)
			(end 0.12065 -0.2794)
			(stroke
				(width 0.1)
				(type default)
			)
			(layer "F.Fab")
		)
		(fp_line
			(start -0.12065 0.2794)
			(end -0.12065 0.3048)
			(stroke
				(width 0.1)
				(type default)
			)
			(layer "F.Fab")
		)
		(fp_line
			(start -0.12065 0.3048)
			(end -0.67945 0.3048)
			(stroke
				(width 0.1)
				(type default)
			)
			(layer "F.Fab")
		)
		(fp_line
			(start 0.120396 0.2794)
			(end -0.12065 0.2794)
			(stroke
				(width 0.1)
				(type default)
			)
			(layer "F.Fab")
		)
		(fp_line
			(start 0.120396 0.3048)
			(end 0.120396 0.2794)
			(stroke
				(width 0.1)
				(type default)
			)
			(layer "F.Fab")
		)
		(fp_line
			(start 0.12065 -0.3048)
			(end 0.67945 -0.3048)
			(stroke
				(width 0.1)
				(type default)
			)
			(layer "F.Fab")
		)
		(fp_line
			(start 0.12065 -0.2794)
			(end 0.12065 -0.3048)
			(stroke
				(width 0.1)
				(type default)
			)
			(layer "F.Fab")
		)
		(fp_line
			(start 0.67945 -0.3048)
			(end 0.67945 0.3048)
			(stroke
				(width 0.1)
				(type default)
			)
			(layer "F.Fab")
		)
		(fp_line
			(start 0.67945 0.3048)
			(end 0.120396 0.3048)
			(stroke
				(width 0.1)
				(type default)
			)
			(layer "F.Fab")
		)
		(pad "1" smd circle
			(at -0.40005 0)
			(size 0 0)
			(layers "F.Cu" "F.Mask" "F.Paste")
			(net "SSD14_ADC_A1")
		)
		(pad "2" smd circle
			(at 0.40005 0)
			(size 0 0)
			(layers "F.Cu" "F.Mask" "F.Paste")
			(net "GND")
		)
	)
	(footprint ""
		(layer "F.Cu")
		(at 363.833156 -114.933476)
		(property "Reference" "PU121"
			(at 3.502152 -2.790444 90)
			(unlocked yes)
			(layer "F.SilkS")
			(effects
				(font
					(size 0.7874 0.5842)
					(thickness 0.1524)
				)
			)
		)
		(property "Value" ""
			(at 0 0 0)
			(layer "F.Fab")
			(effects
				(font
					(size 1.27 1.27)
				)
			)
		)
		(duplicate_pad_numbers_are_jumpers no)
		(fp_line
			(start -1.239774 -1.495298)
			(end 1.239774 -1.495298)
			(stroke
				(width 0.1524)
				(type default)
			)
			(layer "F.SilkS")
		)
		(fp_line
			(start -1.239774 1.495298)
			(end -1.239774 -1.495298)
			(stroke
				(width 0.1524)
				(type default)
			)
			(layer "F.SilkS")
		)
		(fp_line
			(start 1.239774 -1.495298)
			(end 1.239774 1.495298)
			(stroke
				(width 0.1524)
				(type default)
			)
			(layer "F.SilkS")
		)
		(fp_line
			(start 1.239774 1.495298)
			(end -1.239774 1.495298)
			(stroke
				(width 0.1524)
				(type default)
			)
			(layer "F.SilkS")
		)
		(fp_poly
			(pts
				(xy -1.814576 -1.456944) (xy -2.533142 -0.738632) (xy -1.45542 -0.379476)
			)
			(stroke
				(width 0)
				(type default)
			)
			(fill yes)
			(layer "F.SilkS")
		)
		(fp_line
			(start -0.8001 -1.050036)
			(end 0.8001 -1.050036)
			(stroke
				(width 0.1)
				(type default)
			)
			(layer "F.Fab")
		)
		(fp_line
			(start -0.8001 1.050036)
			(end -0.8001 -1.050036)
			(stroke
				(width 0.1)
				(type default)
			)
			(layer "F.Fab")
		)
		(fp_line
			(start 0.8001 -1.050036)
			(end 0.8001 1.050036)
			(stroke
				(width 0.1)
				(type default)
			)
			(layer "F.Fab")
		)
		(fp_line
			(start 0.8001 1.050036)
			(end -0.8001 1.050036)
			(stroke
				(width 0.1)
				(type default)
			)
			(layer "F.Fab")
		)
		(fp_poly
			(pts
				(xy -2.458974 -0.508) (xy -2.458974 0.508) (xy -1.442974 0)
			)
			(stroke
				(width 0)
				(type default)
			)
			(fill yes)
			(layer "F.Fab")
		)
		(pad "1_2" smd circle
			(at -0.374904 0 90)
			(size 0 0)
			(layers "F.Cu" "F.Mask" "F.Paste")
			(net "P3V3_AUX")
		)
		(pad "3" smd rect
			(at -0.499872 0.999998)
			(size 0.254 0.7112)
			(layers "F.Cu" "F.Mask" "F.Paste")
			(net "GND")
		)
		(pad "4" smd rect
			(at 0 0.999998)
			(size 0.254 0.7112)
			(layers "F.Cu" "F.Mask" "F.Paste")
			(net "P3V3_NIC6_CO_ILIMIT")
		)
		(pad "5" smd rect
			(at 0.499872 0.999998)
			(size 0.254 0.7112)
			(layers "F.Cu" "F.Mask" "F.Paste")
			(net "P3V3_NIC6_CO_MODE")
		)
		(pad "6_7" smd circle
			(at 0.374904 0 270)
			(size 0 0)
			(layers "F.Cu" "F.Mask" "F.Paste")
			(net "P3V3_NIC6")
		)
		(pad "8" smd rect
			(at 0.499872 -0.999998)
			(size 0.254 0.7112)
			(layers "F.Cu" "F.Mask" "F.Paste")
			(net "P3V3_NIC6_CO_GATE")
		)
		(pad "9" smd rect
			(at 0 -0.999998)
			(size 0.254 0.7112)
			(layers "F.Cu" "F.Mask" "F.Paste")
			(net "P3V3_NIC6_CO_EN")
		)
		(pad "10" smd rect
			(at -0.499872 -0.999998)
			(size 0.254 0.7112)
			(layers "F.Cu" "F.Mask" "F.Paste")
			(net "P3V3_NIC6_CO_DV_DT")
		)
	)
	(footprint ""
		(layer "F.Cu")
		(at 443.802262 -435.658006 90)
		(property "Reference" "J46"
			(at -3.5052 -5.552948 90)
			(unlocked yes)
			(layer "F.SilkS")
			(effects
				(font
					(size 0.7874 0.5842)
					(thickness 0.1524)
				)
				(justify left)
			)
		)
		(property "Value" ""
			(at 0 0 90)
			(layer "F.Fab")
			(effects
				(font
					(size 1.27 1.27)
				)
			)
		)
		(duplicate_pad_numbers_are_jumpers no)
		(fp_line
			(start 3.330702 -4.771136)
			(end 0 4.011168)
			(stroke
				(width 0.1524)
				(type default)
			)
			(layer "F.SilkS")
		)
		(fp_line
			(start -3.330702 -4.771136)
			(end 3.330702 -4.771136)
			(stroke
				(width 0.1524)
				(type default)
			)
			(layer "F.SilkS")
		)
		(fp_line
			(start 0 4.011168)
			(end -3.330702 -4.771136)
			(stroke
				(width 0.1524)
				(type default)
			)
			(layer "F.SilkS")
		)
		(fp_line
			(start 3.330702 -4.771136)
			(end 0 4.011168)
			(stroke
				(width 0.1)
				(type default)
			)
			(layer "F.Fab")
		)
		(fp_line
			(start -3.330702 -4.771136)
			(end 3.330702 -4.771136)
			(stroke
				(width 0.1)
				(type default)
			)
			(layer "F.Fab")
		)
		(fp_line
			(start 0 4.011168)
			(end -3.330702 -4.771136)
			(stroke
				(width 0.1)
				(type default)
			)
			(layer "F.Fab")
		)
		(pad "1" thru_hole circle
			(at 0 0 90)
			(size 2.159 2.159)
			(drill 1.7018)
			(layers "*.Cu" "*.Mask")
			(remove_unused_layers no)
			(net "COUPON_GND1")
			(clearance 0.0254)
			(thermal_gap 0.0254)
		)
		(pad "2" thru_hole circle
			(at -1.27 -3.348736 90)
			(size 2.159 2.159)
			(drill 1.7018)
			(layers "*.Cu" "*.Mask")
			(remove_unused_layers no)
			(net "TDR_SE_50_OHM_TOP")
			(clearance 0.0254)
			(thermal_gap 0.0254)
		)
		(pad "3" thru_hole circle
			(at 1.27 -3.348736 90)
			(size 2.159 2.159)
			(drill 1.7018)
			(layers "*.Cu" "*.Mask")
			(remove_unused_layers no)
			(net "TDR_SE_50_OHM_TOP")
			(clearance 0.0254)
			(thermal_gap 0.0254)
		)
	)
	(footprint ""
		(layer "F.Cu")
		(at 359.156 -181.102 180)
		(property "Reference" "R4704"
			(at 0 0 180)
			(layer "F.SilkS")
			(hide yes)
			(effects
				(font
					(size 1.27 1.27)
				)
			)
		)
		(property "Value" ""
			(at 0 0 180)
			(layer "F.Fab")
			(effects
				(font
					(size 1.27 1.27)
				)
			)
		)
		(duplicate_pad_numbers_are_jumpers no)
		(fp_line
			(start 0.7874 0.4064)
			(end -0.7874 0.4064)
			(stroke
				(width 0.1524)
				(type default)
			)
			(layer "F.SilkS")
		)
		(fp_line
			(start 0.7874 -0.4064)
			(end 0.7874 0.4064)
			(stroke
				(width 0.1524)
				(type default)
			)
			(layer "F.SilkS")
		)
		(fp_line
			(start -0.7874 0.4064)
			(end -0.7874 -0.4064)
			(stroke
				(width 0.1524)
				(type default)
			)
			(layer "F.SilkS")
		)
		(fp_line
			(start -0.7874 -0.4064)
			(end 0.7874 -0.4064)
			(stroke
				(width 0.1524)
				(type default)
			)
			(layer "F.SilkS")
		)
		(fp_line
			(start 0.67945 0.3048)
			(end 0.120396 0.3048)
			(stroke
				(width 0.1)
				(type default)
			)
			(layer "F.Fab")
		)
		(fp_line
			(start 0.67945 -0.3048)
			(end 0.67945 0.3048)
			(stroke
				(width 0.1)
				(type default)
			)
			(layer "F.Fab")
		)
		(fp_line
			(start 0.12065 -0.2794)
			(end 0.12065 -0.3048)
			(stroke
				(width 0.1)
				(type default)
			)
			(layer "F.Fab")
		)
		(fp_line
			(start 0.12065 -0.3048)
			(end 0.67945 -0.3048)
			(stroke
				(width 0.1)
				(type default)
			)
			(layer "F.Fab")
		)
		(fp_line
			(start 0.120396 0.3048)
			(end 0.120396 0.2794)
			(stroke
				(width 0.1)
				(type default)
			)
			(layer "F.Fab")
		)
		(fp_line
			(start 0.120396 0.2794)
			(end -0.12065 0.2794)
			(stroke
				(width 0.1)
				(type default)
			)
			(layer "F.Fab")
		)
		(fp_line
			(start -0.12065 0.3048)
			(end -0.67945 0.3048)
			(stroke
				(width 0.1)
				(type default)
			)
			(layer "F.Fab")
		)
		(fp_line
			(start -0.12065 0.2794)
			(end -0.12065 0.3048)
			(stroke
				(width 0.1)
				(type default)
			)
			(layer "F.Fab")
		)
		(fp_line
			(start -0.12065 -0.2794)
			(end 0.12065 -0.2794)
			(stroke
				(width 0.1)
				(type default)
			)
			(layer "F.Fab")
		)
		(fp_line
			(start -0.12065 -0.305054)
			(end -0.12065 -0.2794)
			(stroke
				(width 0.1)
				(type default)
			)
			(layer "F.Fab")
		)
		(fp_line
			(start -0.67945 0.3048)
			(end -0.67945 -0.305054)
			(stroke
				(width 0.1)
				(type default)
			)
			(layer "F.Fab")
		)
		(fp_line
			(start -0.67945 -0.305054)
			(end -0.12065 -0.305054)
			(stroke
				(width 0.1)
				(type default)
			)
			(layer "F.Fab")
		)
		(pad "1" smd circle
			(at -0.40005 0 180)
			(size 0 0)
			(layers "F.Cu" "F.Mask" "F.Paste")
			(net "PCA9555_1_PEX1_A1")
		)
		(pad "2" smd circle
			(at 0.40005 0 180)
			(size 0 0)
			(layers "F.Cu" "F.Mask" "F.Paste")
			(net "P3V3_AUX")
		)
	)
	(footprint ""
		(layer "F.Cu")
		(at 245.813072 -369.875562 90)
		(property "Reference" "PQ6602"
			(at -8.218932 -2.080514 0)
			(unlocked yes)
			(layer "F.SilkS")
			(effects
				(font
					(size 0.7874 0.5842)
					(thickness 0.1524)
				)
				(justify left)
			)
		)
		(property "Value" ""
			(at 0 0 90)
			(layer "F.Fab")
			(effects
				(font
					(size 1.27 1.27)
				)
			)
		)
		(duplicate_pad_numbers_are_jumpers no)
		(fp_line
			(start 2.350008 -2.649982)
			(end 2.350008 -2.4892)
			(stroke
				(width 0.1524)
				(type default)
			)
			(layer "F.SilkS")
		)
		(fp_line
			(start -2.350008 -2.649982)
			(end 2.350008 -2.649982)
			(stroke
				(width 0.1524)
				(type default)
			)
			(layer "F.SilkS")
		)
		(fp_line
			(start -2.350008 -2.4384)
			(end -2.350008 -2.649982)
			(stroke
				(width 0.1524)
				(type default)
			)
			(layer "F.SilkS")
		)
		(fp_line
			(start 2.350008 2.4892)
			(end 2.350008 2.649982)
			(stroke
				(width 0.1524)
				(type default)
			)
			(layer "F.SilkS")
		)
		(fp_line
			(start 2.350008 2.649982)
			(end -2.350008 2.649982)
			(stroke
				(width 0.1524)
				(type default)
			)
			(layer "F.SilkS")
		)
		(fp_line
			(start -2.350008 2.649982)
			(end -2.350008 2.413)
			(stroke
				(width 0.1524)
				(type default)
			)
			(layer "F.SilkS")
		)
		(fp_poly
			(pts
				(xy -4.710684 -1.905) (xy -5.752084 -2.3241) (xy -5.752084 -1.524)
			)
			(stroke
				(width 0)
				(type default)
			)
			(fill yes)
			(layer "F.SilkS")
		)
		(fp_line
			(start 2.350008 -2.649982)
			(end 2.350008 2.649982)
			(stroke
				(width 0.1)
				(type default)
			)
			(layer "F.Fab")
		)
		(fp_line
			(start -2.350008 -2.649982)
			(end 2.350008 -2.649982)
			(stroke
				(width 0.1)
				(type default)
			)
			(layer "F.Fab")
		)
		(fp_line
			(start 2.350008 2.649982)
			(end -2.350008 2.649982)
			(stroke
				(width 0.1)
				(type default)
			)
			(layer "F.Fab")
		)
		(fp_line
			(start -2.350008 2.649982)
			(end -2.350008 -2.649982)
			(stroke
				(width 0.1)
				(type default)
			)
			(layer "F.Fab")
		)
		(fp_poly
			(pts
				(xy -3.717544 -1.905) (xy -4.758944 -2.3241) (xy -4.758944 -1.524)
			)
			(stroke
				(width 0)
				(type default)
			)
			(fill yes)
			(layer "F.Fab")
		)
		(pad "1" smd rect
			(at -2.999994 -1.905)
			(size 0.7112 1.1684)
			(layers "F.Cu" "F.Mask" "F.Paste")
			(net "P12V_AUX")
		)
		(pad "2" smd rect
			(at -2.999994 -0.635)
			(size 0.7112 1.1684)
			(layers "F.Cu" "F.Mask" "F.Paste")
			(net "P12V_AUX")
		)
		(pad "3" smd rect
			(at -2.999994 0.635)
			(size 0.7112 1.1684)
			(layers "F.Cu" "F.Mask" "F.Paste")
			(net "P12V_AUX")
		)
		(pad "4" smd rect
			(at -2.999994 1.905)
			(size 0.7112 1.1684)
			(layers "F.Cu" "F.Mask" "F.Paste")
			(net "HS_GATE2_R_1")
		)
		(pad "5" smd circle
			(at 0.925068 0)
			(size 0 0)
			(layers "F.Cu" "F.Mask" "F.Paste")
			(net "P12V_STBY_R2")
		)
		(zone
			(layer "F.Cu")
			(hatch none 0.5)
			(connect_pads
				(clearance 0)
			)
			(min_thickness 0.25)
			(keepout
				(tracks not_allowed)
				(vias allowed)
				(pads allowed)
				(copperpour not_allowed)
				(footprints allowed)
			)
			(placement
				(enabled no)
				(sheetname "")
			)
			(fill
				(thermal_gap 0.5)
				(thermal_bridge_width 0.5)
				(island_removal_mode 0)
			)
			(polygon
				(pts
					(xy 243.654072 -368.427762) (xy 247.972072 -368.427762) (xy 248.454672 -368.427762) (xy 248.454672 -367.526062)
					(xy 243.171472 -367.526062) (xy 243.171472 -368.427762)
				)
			)
		)
	)
	(footprint ""
		(layer "F.Cu")
		(at 117.700044 -194.360038)
		(property "Reference" "H55"
			(at -4.12242 -5.192014 0)
			(unlocked yes)
			(layer "F.SilkS")
			(effects
				(font
					(size 0.7874 0.5842)
					(thickness 0.1524)
				)
				(justify left)
			)
		)
		(property "Value" ""
			(at 0 0 0)
			(layer "F.Fab")
			(effects
				(font
					(size 1.27 1.27)
				)
			)
		)
		(duplicate_pad_numbers_are_jumpers no)
		(pad "1" thru_hole circle
			(at 0 0)
			(size 10.0076 10.0076)
			(drill 5.6134)
			(layers "*.Cu" "*.Mask")
			(remove_unused_layers no)
			(net "GND")
			(clearance -1.9431)
		)
	)
	(footprint ""
		(layer "F.Cu")
		(at 440.371484 -96.811592 -90)
		(property "Reference" "R746"
			(at 0 0 270)
			(layer "F.SilkS")
			(hide yes)
			(effects
				(font
					(size 1.27 1.27)
				)
			)
		)
		(property "Value" ""
			(at 0 0 270)
			(layer "F.Fab")
			(effects
				(font
					(size 1.27 1.27)
				)
			)
		)
		(duplicate_pad_numbers_are_jumpers no)
		(fp_line
			(start -0.7874 0.4064)
			(end -0.7874 -0.4064)
			(stroke
				(width 0.1524)
				(type default)
			)
			(layer "F.SilkS")
		)
		(fp_line
			(start 0.7874 0.4064)
			(end -0.7874 0.4064)
			(stroke
				(width 0.1524)
				(type default)
			)
			(layer "F.SilkS")
		)
		(fp_line
			(start -0.7874 -0.4064)
			(end 0.7874 -0.4064)
			(stroke
				(width 0.1524)
				(type default)
			)
			(layer "F.SilkS")
		)
		(fp_line
			(start 0.7874 -0.4064)
			(end 0.7874 0.4064)
			(stroke
				(width 0.1524)
				(type default)
			)
			(layer "F.SilkS")
		)
		(fp_line
			(start -0.67945 0.3048)
			(end -0.67945 -0.305054)
			(stroke
				(width 0.1)
				(type default)
			)
			(layer "F.Fab")
		)
		(fp_line
			(start -0.12065 0.3048)
			(end -0.67945 0.3048)
			(stroke
				(width 0.1)
				(type default)
			)
			(layer "F.Fab")
		)
		(fp_line
			(start 0.120396 0.3048)
			(end 0.120396 0.2794)
			(stroke
				(width 0.1)
				(type default)
			)
			(layer "F.Fab")
		)
		(fp_line
			(start 0.67945 0.3048)
			(end 0.120396 0.3048)
			(stroke
				(width 0.1)
				(type default)
			)
			(layer "F.Fab")
		)
		(fp_line
			(start -0.12065 0.2794)
			(end -0.12065 0.3048)
			(stroke
				(width 0.1)
				(type default)
			)
			(layer "F.Fab")
		)
		(fp_line
			(start 0.120396 0.2794)
			(end -0.12065 0.2794)
			(stroke
				(width 0.1)
				(type default)
			)
			(layer "F.Fab")
		)
		(fp_line
			(start -0.12065 -0.2794)
			(end 0.12065 -0.2794)
			(stroke
				(width 0.1)
				(type default)
			)
			(layer "F.Fab")
		)
		(fp_line
			(start 0.12065 -0.2794)
			(end 0.12065 -0.3048)
			(stroke
				(width 0.1)
				(type default)
			)
			(layer "F.Fab")
		)
		(fp_line
			(start 0.12065 -0.3048)
			(end 0.67945 -0.3048)
			(stroke
				(width 0.1)
				(type default)
			)
			(layer "F.Fab")
		)
		(fp_line
			(start 0.67945 -0.3048)
			(end 0.67945 0.3048)
			(stroke
				(width 0.1)
				(type default)
			)
			(layer "F.Fab")
		)
		(fp_line
			(start -0.67945 -0.305054)
			(end -0.12065 -0.305054)
			(stroke
				(width 0.1)
				(type default)
			)
			(layer "F.Fab")
		)
		(fp_line
			(start -0.12065 -0.305054)
			(end -0.12065 -0.2794)
			(stroke
				(width 0.1)
				(type default)
			)
			(layer "F.Fab")
		)
		(pad "1" smd circle
			(at -0.40005 0 270)
			(size 0 0)
			(layers "F.Cu" "F.Mask" "F.Paste")
			(net "P3V3_AUX")
		)
		(pad "2" smd circle
			(at 0.40005 0 270)
			(size 0 0)
			(layers "F.Cu" "F.Mask" "F.Paste")
			(net "NIC_ADC_ALERT_N")
		)
	)
	(footprint ""
		(layer "F.Cu")
		(at 249.862848 -182.394606 -90)
		(property "Reference" "R5522"
			(at 0 0 270)
			(layer "F.SilkS")
			(hide yes)
			(effects
				(font
					(size 1.27 1.27)
				)
			)
		)
		(property "Value" ""
			(at 0 0 270)
			(layer "F.Fab")
			(effects
				(font
					(size 1.27 1.27)
				)
			)
		)
		(duplicate_pad_numbers_are_jumpers no)
		(fp_line
			(start -0.7874 0.4064)
			(end -0.7874 -0.4064)
			(stroke
				(width 0.1524)
				(type default)
			)
			(layer "F.SilkS")
		)
		(fp_line
			(start 0.7874 0.4064)
			(end -0.7874 0.4064)
			(stroke
				(width 0.1524)
				(type default)
			)
			(layer "F.SilkS")
		)
		(fp_line
			(start -0.7874 -0.4064)
			(end 0.7874 -0.4064)
			(stroke
				(width 0.1524)
				(type default)
			)
			(layer "F.SilkS")
		)
		(fp_line
			(start 0.7874 -0.4064)
			(end 0.7874 0.4064)
			(stroke
				(width 0.1524)
				(type default)
			)
			(layer "F.SilkS")
		)
		(fp_line
			(start -0.67945 0.3048)
			(end -0.67945 -0.305054)
			(stroke
				(width 0.1)
				(type default)
			)
			(layer "F.Fab")
		)
		(fp_line
			(start -0.12065 0.3048)
			(end -0.67945 0.3048)
			(stroke
				(width 0.1)
				(type default)
			)
			(layer "F.Fab")
		)
		(fp_line
			(start 0.120396 0.3048)
			(end 0.120396 0.2794)
			(stroke
				(width 0.1)
				(type default)
			)
			(layer "F.Fab")
		)
		(fp_line
			(start 0.67945 0.3048)
			(end 0.120396 0.3048)
			(stroke
				(width 0.1)
				(type default)
			)
			(layer "F.Fab")
		)
		(fp_line
			(start -0.12065 0.2794)
			(end -0.12065 0.3048)
			(stroke
				(width 0.1)
				(type default)
			)
			(layer "F.Fab")
		)
		(fp_line
			(start 0.120396 0.2794)
			(end -0.12065 0.2794)
			(stroke
				(width 0.1)
				(type default)
			)
			(layer "F.Fab")
		)
		(fp_line
			(start -0.12065 -0.2794)
			(end 0.12065 -0.2794)
			(stroke
				(width 0.1)
				(type default)
			)
			(layer "F.Fab")
		)
		(fp_line
			(start 0.12065 -0.2794)
			(end 0.12065 -0.3048)
			(stroke
				(width 0.1)
				(type default)
			)
			(layer "F.Fab")
		)
		(fp_line
			(start 0.12065 -0.3048)
			(end 0.67945 -0.3048)
			(stroke
				(width 0.1)
				(type default)
			)
			(layer "F.Fab")
		)
		(fp_line
			(start 0.67945 -0.3048)
			(end 0.67945 0.3048)
			(stroke
				(width 0.1)
				(type default)
			)
			(layer "F.Fab")
		)
		(fp_line
			(start -0.67945 -0.305054)
			(end -0.12065 -0.305054)
			(stroke
				(width 0.1)
				(type default)
			)
			(layer "F.Fab")
		)
		(fp_line
			(start -0.12065 -0.305054)
			(end -0.12065 -0.2794)
			(stroke
				(width 0.1)
				(type default)
			)
			(layer "F.Fab")
		)
		(pad "1" smd circle
			(at -0.40005 0 270)
			(size 0 0)
			(layers "F.Cu" "F.Mask" "F.Paste")
			(net "GND")
		)
		(pad "2" smd circle
			(at 0.40005 0 270)
			(size 0 0)
			(layers "F.Cu" "F.Mask" "F.Paste")
			(net "BIC_FWSPICK")
		)
	)
	(footprint ""
		(layer "F.Cu")
		(at 72.659494 -61.612526)
		(property "Reference" "PD29"
			(at -4.849368 -2.685288 0)
			(unlocked yes)
			(layer "F.SilkS")
			(effects
				(font
					(size 0.7874 0.5842)
					(thickness 0.1524)
				)
				(justify left)
			)
		)
		(property "Value" ""
			(at 0 0 0)
			(layer "F.Fab")
			(effects
				(font
					(size 1.27 1.27)
				)
			)
		)
		(duplicate_pad_numbers_are_jumpers no)
		(fp_line
			(start -3.656584 -1.970024)
			(end -3.656584 1.970024)
			(stroke
				(width 0.1524)
				(type default)
			)
			(layer "F.SilkS")
		)
		(fp_line
			(start -3.656584 1.970024)
			(end 4.240784 1.970024)
			(stroke
				(width 0.1524)
				(type default)
			)
			(layer "F.SilkS")
		)
		(fp_line
			(start 4.240784 -1.970024)
			(end -3.656584 -1.970024)
			(stroke
				(width 0.1524)
				(type default)
			)
			(layer "F.SilkS")
		)
		(fp_line
			(start 4.240784 1.970024)
			(end 4.240784 -1.970024)
			(stroke
				(width 0.1524)
				(type default)
			)
			(layer "F.SilkS")
		)
		(fp_poly
			(pts
				(xy 3.580384 1.970024) (xy 3.580384 -1.970024) (xy 4.240784 -1.970024) (xy 4.240784 1.970024)
			)
			(stroke
				(width 0)
				(type default)
			)
			(fill yes)
			(layer "F.SilkS")
		)
		(fp_line
			(start -2.3749 -1.970024)
			(end -2.3749 1.970024)
			(stroke
				(width 0.1)
				(type default)
			)
			(layer "F.Fab")
		)
		(fp_line
			(start -2.3749 1.970024)
			(end 2.3749 1.970024)
			(stroke
				(width 0.1)
				(type default)
			)
			(layer "F.Fab")
		)
		(fp_line
			(start 2.3749 -1.970024)
			(end -2.3749 -1.970024)
			(stroke
				(width 0.1)
				(type default)
			)
			(layer "F.Fab")
		)
		(fp_line
			(start 2.3749 1.970024)
			(end 2.3749 -1.970024)
			(stroke
				(width 0.1)
				(type default)
			)
			(layer "F.Fab")
		)
		(fp_text user "+"
			(at -4.9784 -0.23495 0)
			(unlocked yes)
			(layer "F.Fab")
			(effects
				(font
					(size 1.905 1.4224)
					(thickness 0.1524)
				)
				(justify left)
			)
		)
		(fp_text user "-"
			(at 4.1656 -0.23495 0)
			(unlocked yes)
			(layer "F.Fab")
			(effects
				(font
					(size 1.905 1.4224)
					(thickness 0.1524)
				)
				(justify left)
			)
		)
		(pad "A" smd rect
			(at -2.450084 0)
			(size 2.159 2.2606)
			(layers "F.Cu" "F.Mask" "F.Paste")
			(net "GND")
		)
		(pad "C" smd rect
			(at 2.450084 0)
			(size 2.159 2.2606)
			(layers "F.Cu" "F.Mask" "F.Paste")
			(net "P12V_AUX")
		)
	)
	(footprint ""
		(layer "F.Cu")
		(at 416.560508 -184.941718 180)
		(property "Reference" "R6445"
			(at 0 0 180)
			(layer "F.SilkS")
			(hide yes)
			(effects
				(font
					(size 1.27 1.27)
				)
			)
		)
		(property "Value" ""
			(at 0 0 180)
			(layer "F.Fab")
			(effects
				(font
					(size 1.27 1.27)
				)
			)
		)
		(duplicate_pad_numbers_are_jumpers no)
		(fp_line
			(start 0.7874 0.4064)
			(end -0.7874 0.4064)
			(stroke
				(width 0.1524)
				(type default)
			)
			(layer "F.SilkS")
		)
		(fp_line
			(start 0.7874 -0.4064)
			(end 0.7874 0.4064)
			(stroke
				(width 0.1524)
				(type default)
			)
			(layer "F.SilkS")
		)
		(fp_line
			(start -0.7874 0.4064)
			(end -0.7874 -0.4064)
			(stroke
				(width 0.1524)
				(type default)
			)
			(layer "F.SilkS")
		)
		(fp_line
			(start -0.7874 -0.4064)
			(end 0.7874 -0.4064)
			(stroke
				(width 0.1524)
				(type default)
			)
			(layer "F.SilkS")
		)
		(fp_line
			(start 0.67945 0.3048)
			(end 0.120396 0.3048)
			(stroke
				(width 0.1)
				(type default)
			)
			(layer "F.Fab")
		)
		(fp_line
			(start 0.67945 -0.3048)
			(end 0.67945 0.3048)
			(stroke
				(width 0.1)
				(type default)
			)
			(layer "F.Fab")
		)
		(fp_line
			(start 0.12065 -0.2794)
			(end 0.12065 -0.3048)
			(stroke
				(width 0.1)
				(type default)
			)
			(layer "F.Fab")
		)
		(fp_line
			(start 0.12065 -0.3048)
			(end 0.67945 -0.3048)
			(stroke
				(width 0.1)
				(type default)
			)
			(layer "F.Fab")
		)
		(fp_line
			(start 0.120396 0.3048)
			(end 0.120396 0.2794)
			(stroke
				(width 0.1)
				(type default)
			)
			(layer "F.Fab")
		)
		(fp_line
			(start 0.120396 0.2794)
			(end -0.12065 0.2794)
			(stroke
				(width 0.1)
				(type default)
			)
			(layer "F.Fab")
		)
		(fp_line
			(start -0.12065 0.3048)
			(end -0.67945 0.3048)
			(stroke
				(width 0.1)
				(type default)
			)
			(layer "F.Fab")
		)
		(fp_line
			(start -0.12065 0.2794)
			(end -0.12065 0.3048)
			(stroke
				(width 0.1)
				(type default)
			)
			(layer "F.Fab")
		)
		(fp_line
			(start -0.12065 -0.2794)
			(end 0.12065 -0.2794)
			(stroke
				(width 0.1)
				(type default)
			)
			(layer "F.Fab")
		)
		(fp_line
			(start -0.12065 -0.305054)
			(end -0.12065 -0.2794)
			(stroke
				(width 0.1)
				(type default)
			)
			(layer "F.Fab")
		)
		(fp_line
			(start -0.67945 0.3048)
			(end -0.67945 -0.305054)
			(stroke
				(width 0.1)
				(type default)
			)
			(layer "F.Fab")
		)
		(fp_line
			(start -0.67945 -0.305054)
			(end -0.12065 -0.305054)
			(stroke
				(width 0.1)
				(type default)
			)
			(layer "F.Fab")
		)
		(pad "1" smd circle
			(at -0.40005 0 180)
			(size 0 0)
			(layers "F.Cu" "F.Mask" "F.Paste")
			(net "FPGA_PEX3_MODE_SEL2_D_N")
		)
		(pad "2" smd circle
			(at 0.40005 0 180)
			(size 0 0)
			(layers "F.Cu" "F.Mask" "F.Paste")
			(net "P3V3_AUX")
		)
	)
	(footprint ""
		(layer "F.Cu")
		(at 283.248354 -166.302944 90)
		(property "Reference" "R249"
			(at 0 0 90)
			(layer "F.SilkS")
			(hide yes)
			(effects
				(font
					(size 1.27 1.27)
				)
			)
		)
		(property "Value" ""
			(at 0 0 90)
			(layer "F.Fab")
			(effects
				(font
					(size 1.27 1.27)
				)
			)
		)
		(duplicate_pad_numbers_are_jumpers no)
		(fp_line
			(start 0.7874 -0.4064)
			(end 0.7874 0.4064)
			(stroke
				(width 0.1524)
				(type default)
			)
			(layer "F.SilkS")
		)
		(fp_line
			(start -0.7874 -0.4064)
			(end 0.7874 -0.4064)
			(stroke
				(width 0.1524)
				(type default)
			)
			(layer "F.SilkS")
		)
		(fp_line
			(start 0.7874 0.4064)
			(end -0.7874 0.4064)
			(stroke
				(width 0.1524)
				(type default)
			)
			(layer "F.SilkS")
		)
		(fp_line
			(start -0.7874 0.4064)
			(end -0.7874 -0.4064)
			(stroke
				(width 0.1524)
				(type default)
			)
			(layer "F.SilkS")
		)
		(fp_line
			(start -0.12065 -0.305054)
			(end -0.12065 -0.2794)
			(stroke
				(width 0.1)
				(type default)
			)
			(layer "F.Fab")
		)
		(fp_line
			(start -0.67945 -0.305054)
			(end -0.12065 -0.305054)
			(stroke
				(width 0.1)
				(type default)
			)
			(layer "F.Fab")
		)
		(fp_line
			(start 0.67945 -0.3048)
			(end 0.67945 0.3048)
			(stroke
				(width 0.1)
				(type default)
			)
			(layer "F.Fab")
		)
		(fp_line
			(start 0.12065 -0.3048)
			(end 0.67945 -0.3048)
			(stroke
				(width 0.1)
				(type default)
			)
			(layer "F.Fab")
		)
		(fp_line
			(start 0.12065 -0.2794)
			(end 0.12065 -0.3048)
			(stroke
				(width 0.1)
				(type default)
			)
			(layer "F.Fab")
		)
		(fp_line
			(start -0.12065 -0.2794)
			(end 0.12065 -0.2794)
			(stroke
				(width 0.1)
				(type default)
			)
			(layer "F.Fab")
		)
		(fp_line
			(start 0.120396 0.2794)
			(end -0.12065 0.2794)
			(stroke
				(width 0.1)
				(type default)
			)
			(layer "F.Fab")
		)
		(fp_line
			(start -0.12065 0.2794)
			(end -0.12065 0.3048)
			(stroke
				(width 0.1)
				(type default)
			)
			(layer "F.Fab")
		)
		(fp_line
			(start 0.67945 0.3048)
			(end 0.120396 0.3048)
			(stroke
				(width 0.1)
				(type default)
			)
			(layer "F.Fab")
		)
		(fp_line
			(start 0.120396 0.3048)
			(end 0.120396 0.2794)
			(stroke
				(width 0.1)
				(type default)
			)
			(layer "F.Fab")
		)
		(fp_line
			(start -0.12065 0.3048)
			(end -0.67945 0.3048)
			(stroke
				(width 0.1)
				(type default)
			)
			(layer "F.Fab")
		)
		(fp_line
			(start -0.67945 0.3048)
			(end -0.67945 -0.305054)
			(stroke
				(width 0.1)
				(type default)
			)
			(layer "F.Fab")
		)
		(pad "1" smd circle
			(at -0.40005 0 90)
			(size 0 0)
			(layers "F.Cu" "F.Mask" "F.Paste")
			(net "RST_NIC4_PERST0_R_N")
		)
		(pad "2" smd circle
			(at 0.40005 0 90)
			(size 0 0)
			(layers "F.Cu" "F.Mask" "F.Paste")
			(net "RST_HP_NIC4_BUF_N")
		)
	)
	(footprint ""
		(layer "F.Cu")
		(at 136.870948 -145.189956 180)
		(property "Reference" "R712"
			(at 0 0 180)
			(layer "F.SilkS")
			(hide yes)
			(effects
				(font
					(size 1.27 1.27)
				)
			)
		)
		(property "Value" ""
			(at 0 0 180)
			(layer "F.Fab")
			(effects
				(font
					(size 1.27 1.27)
				)
			)
		)
		(duplicate_pad_numbers_are_jumpers no)
		(fp_line
			(start 0.7874 0.4064)
			(end -0.7874 0.4064)
			(stroke
				(width 0.1524)
				(type default)
			)
			(layer "F.SilkS")
		)
		(fp_line
			(start 0.7874 -0.4064)
			(end 0.7874 0.4064)
			(stroke
				(width 0.1524)
				(type default)
			)
			(layer "F.SilkS")
		)
		(fp_line
			(start -0.7874 0.4064)
			(end -0.7874 -0.4064)
			(stroke
				(width 0.1524)
				(type default)
			)
			(layer "F.SilkS")
		)
		(fp_line
			(start -0.7874 -0.4064)
			(end 0.7874 -0.4064)
			(stroke
				(width 0.1524)
				(type default)
			)
			(layer "F.SilkS")
		)
		(fp_line
			(start 0.67945 0.3048)
			(end 0.120396 0.3048)
			(stroke
				(width 0.1)
				(type default)
			)
			(layer "F.Fab")
		)
		(fp_line
			(start 0.67945 -0.3048)
			(end 0.67945 0.3048)
			(stroke
				(width 0.1)
				(type default)
			)
			(layer "F.Fab")
		)
		(fp_line
			(start 0.12065 -0.2794)
			(end 0.12065 -0.3048)
			(stroke
				(width 0.1)
				(type default)
			)
			(layer "F.Fab")
		)
		(fp_line
			(start 0.12065 -0.3048)
			(end 0.67945 -0.3048)
			(stroke
				(width 0.1)
				(type default)
			)
			(layer "F.Fab")
		)
		(fp_line
			(start 0.120396 0.3048)
			(end 0.120396 0.2794)
			(stroke
				(width 0.1)
				(type default)
			)
			(layer "F.Fab")
		)
		(fp_line
			(start 0.120396 0.2794)
			(end -0.12065 0.2794)
			(stroke
				(width 0.1)
				(type default)
			)
			(layer "F.Fab")
		)
		(fp_line
			(start -0.12065 0.3048)
			(end -0.67945 0.3048)
			(stroke
				(width 0.1)
				(type default)
			)
			(layer "F.Fab")
		)
		(fp_line
			(start -0.12065 0.2794)
			(end -0.12065 0.3048)
			(stroke
				(width 0.1)
				(type default)
			)
			(layer "F.Fab")
		)
		(fp_line
			(start -0.12065 -0.2794)
			(end 0.12065 -0.2794)
			(stroke
				(width 0.1)
				(type default)
			)
			(layer "F.Fab")
		)
		(fp_line
			(start -0.12065 -0.305054)
			(end -0.12065 -0.2794)
			(stroke
				(width 0.1)
				(type default)
			)
			(layer "F.Fab")
		)
		(fp_line
			(start -0.67945 0.3048)
			(end -0.67945 -0.305054)
			(stroke
				(width 0.1)
				(type default)
			)
			(layer "F.Fab")
		)
		(fp_line
			(start -0.67945 -0.305054)
			(end -0.12065 -0.305054)
			(stroke
				(width 0.1)
				(type default)
			)
			(layer "F.Fab")
		)
		(pad "1" smd circle
			(at -0.40005 0 180)
			(size 0 0)
			(layers "F.Cu" "F.Mask" "F.Paste")
			(net "P12V_NIC2")
		)
		(pad "2" smd circle
			(at 0.40005 0 180)
			(size 0 0)
			(layers "F.Cu" "F.Mask" "F.Paste")
			(net "P12V_NIC2_VIN_N")
		)
	)
	(footprint ""
		(layer "F.Cu")
		(at 290.908994 -27.04973 180)
		(property "Reference" "C2773"
			(at 0 0 180)
			(layer "F.SilkS")
			(hide yes)
			(effects
				(font
					(size 1.27 1.27)
				)
			)
		)
		(property "Value" ""
			(at 0 0 180)
			(layer "F.Fab")
			(effects
				(font
					(size 1.27 1.27)
				)
			)
		)
		(duplicate_pad_numbers_are_jumpers no)
		(fp_line
			(start 0.7874 0.4064)
			(end -0.7874 0.4064)
			(stroke
				(width 0.1524)
				(type default)
			)
			(layer "F.SilkS")
		)
		(fp_line
			(start 0.7874 -0.4064)
			(end 0.7874 0.4064)
			(stroke
				(width 0.1524)
				(type default)
			)
			(layer "F.SilkS")
		)
		(fp_line
			(start -0.7874 0.4064)
			(end -0.7874 -0.4064)
			(stroke
				(width 0.1524)
				(type default)
			)
			(layer "F.SilkS")
		)
		(fp_line
			(start -0.7874 -0.4064)
			(end 0.7874 -0.4064)
			(stroke
				(width 0.1524)
				(type default)
			)
			(layer "F.SilkS")
		)
		(fp_line
			(start 0.67945 0.3048)
			(end 0.120396 0.3048)
			(stroke
				(width 0.1)
				(type default)
			)
			(layer "F.Fab")
		)
		(fp_line
			(start 0.67945 -0.3048)
			(end 0.67945 0.3048)
			(stroke
				(width 0.1)
				(type default)
			)
			(layer "F.Fab")
		)
		(fp_line
			(start 0.12065 -0.2794)
			(end 0.12065 -0.3048)
			(stroke
				(width 0.1)
				(type default)
			)
			(layer "F.Fab")
		)
		(fp_line
			(start 0.12065 -0.3048)
			(end 0.67945 -0.3048)
			(stroke
				(width 0.1)
				(type default)
			)
			(layer "F.Fab")
		)
		(fp_line
			(start 0.120396 0.3048)
			(end 0.120396 0.2794)
			(stroke
				(width 0.1)
				(type default)
			)
			(layer "F.Fab")
		)
		(fp_line
			(start 0.120396 0.2794)
			(end -0.12065 0.2794)
			(stroke
				(width 0.1)
				(type default)
			)
			(layer "F.Fab")
		)
		(fp_line
			(start -0.12065 0.3048)
			(end -0.67945 0.3048)
			(stroke
				(width 0.1)
				(type default)
			)
			(layer "F.Fab")
		)
		(fp_line
			(start -0.12065 0.2794)
			(end -0.12065 0.3048)
			(stroke
				(width 0.1)
				(type default)
			)
			(layer "F.Fab")
		)
		(fp_line
			(start -0.12065 -0.2794)
			(end 0.12065 -0.2794)
			(stroke
				(width 0.1)
				(type default)
			)
			(layer "F.Fab")
		)
		(fp_line
			(start -0.12065 -0.305054)
			(end -0.12065 -0.2794)
			(stroke
				(width 0.1)
				(type default)
			)
			(layer "F.Fab")
		)
		(fp_line
			(start -0.67945 0.3048)
			(end -0.67945 -0.305054)
			(stroke
				(width 0.1)
				(type default)
			)
			(layer "F.Fab")
		)
		(fp_line
			(start -0.67945 -0.305054)
			(end -0.12065 -0.305054)
			(stroke
				(width 0.1)
				(type default)
			)
			(layer "F.Fab")
		)
		(pad "1" smd circle
			(at -0.40005 0 180)
			(size 0 0)
			(layers "F.Cu" "F.Mask" "F.Paste")
			(net "PRSNT_SSD10_R_N")
		)
		(pad "2" smd circle
			(at 0.40005 0 180)
			(size 0 0)
			(layers "F.Cu" "F.Mask" "F.Paste")
			(net "GND")
		)
	)
	(footprint ""
		(layer "F.Cu")
		(at 286.525462 -356.244906 90)
		(property "Reference" "C2359"
			(at 0 0 90)
			(layer "F.SilkS")
			(hide yes)
			(effects
				(font
					(size 1.27 1.27)
				)
			)
		)
		(property "Value" ""
			(at 0 0 90)
			(layer "F.Fab")
			(effects
				(font
					(size 1.27 1.27)
				)
			)
		)
		(duplicate_pad_numbers_are_jumpers no)
		(fp_line
			(start 0.299974 -0.150114)
			(end 0.299974 0.150114)
			(stroke
				(width 0.1)
				(type default)
			)
			(layer "F.Fab")
		)
		(fp_line
			(start -0.299974 -0.150114)
			(end 0.299974 -0.150114)
			(stroke
				(width 0.1)
				(type default)
			)
			(layer "F.Fab")
		)
		(fp_line
			(start 0.299974 0.150114)
			(end -0.299974 0.150114)
			(stroke
				(width 0.1)
				(type default)
			)
			(layer "F.Fab")
		)
		(fp_line
			(start -0.299974 0.150114)
			(end -0.299974 -0.150114)
			(stroke
				(width 0.1)
				(type default)
			)
			(layer "F.Fab")
		)
		(pad "1" smd rect
			(at -0.2667 0 90)
			(size 0.3048 0.381)
			(layers "F.Cu" "F.Mask" "F.Paste")
			(net "P5E_PEX2_STN4_TX_DP<70>")
		)
		(pad "2" smd rect
			(at 0.2667 0 90)
			(size 0.3048 0.381)
			(layers "F.Cu" "F.Mask" "F.Paste")
			(net "P5E_PEX2_STN4_TX_C_DP<70>")
		)
	)
	(footprint ""
		(layer "F.Cu")
		(at 9.64057 -294.47744 -90)
		(property "Reference" "PL18"
			(at -1.673352 -7.272274 90)
			(unlocked yes)
			(layer "F.SilkS")
			(effects
				(font
					(size 0.7874 0.5842)
					(thickness 0.1524)
				)
				(justify left)
			)
		)
		(property "Value" ""
			(at 0 0 270)
			(layer "F.Fab")
			(effects
				(font
					(size 1.27 1.27)
				)
			)
		)
		(duplicate_pad_numbers_are_jumpers no)
		(fp_line
			(start -6.849872 6.450076)
			(end -6.849872 1.9812)
			(stroke
				(width 0.1524)
				(type default)
			)
			(layer "F.SilkS")
		)
		(fp_line
			(start 6.849872 6.450076)
			(end -6.849872 6.450076)
			(stroke
				(width 0.1524)
				(type default)
			)
			(layer "F.SilkS")
		)
		(fp_line
			(start 6.849872 1.9812)
			(end 6.849872 6.450076)
			(stroke
				(width 0.1524)
				(type default)
			)
			(layer "F.SilkS")
		)
		(fp_line
			(start -6.849872 -1.9812)
			(end -6.849872 -6.450076)
			(stroke
				(width 0.1524)
				(type default)
			)
			(layer "F.SilkS")
		)
		(fp_line
			(start -6.849872 -6.450076)
			(end 6.849872 -6.450076)
			(stroke
				(width 0.1524)
				(type default)
			)
			(layer "F.SilkS")
		)
		(fp_line
			(start 6.849872 -6.450076)
			(end 6.849872 -1.9812)
			(stroke
				(width 0.1524)
				(type default)
			)
			(layer "F.SilkS")
		)
		(fp_line
			(start -6.849872 6.450076)
			(end -6.849872 -6.450076)
			(stroke
				(width 0.1)
				(type default)
			)
			(layer "F.Fab")
		)
		(fp_line
			(start 6.849872 6.450076)
			(end -6.849872 6.450076)
			(stroke
				(width 0.1)
				(type default)
			)
			(layer "F.Fab")
		)
		(fp_line
			(start -6.849872 -6.450076)
			(end 6.849872 -6.450076)
			(stroke
				(width 0.1)
				(type default)
			)
			(layer "F.Fab")
		)
		(fp_line
			(start 6.849872 -6.450076)
			(end 6.849872 6.450076)
			(stroke
				(width 0.1)
				(type default)
			)
			(layer "F.Fab")
		)
		(pad "1" smd rect
			(at -5.407406 0 270)
			(size 2.9464 3.7084)
			(layers "F.Cu" "F.Mask" "F.Paste")
			(net "SW_P1V25_PEX0_PH")
		)
		(pad "2" smd rect
			(at 5.407406 0 270)
			(size 2.9464 3.7084)
			(layers "F.Cu" "F.Mask" "F.Paste")
			(net "P1V25_PEX0_R")
		)
	)
	(footprint ""
		(layer "F.Cu")
		(at 196.975222 -63.086234)
		(property "Reference" "R5989"
			(at 0 0 0)
			(layer "F.SilkS")
			(hide yes)
			(effects
				(font
					(size 1.27 1.27)
				)
			)
		)
		(property "Value" ""
			(at 0 0 0)
			(layer "F.Fab")
			(effects
				(font
					(size 1.27 1.27)
				)
			)
		)
		(duplicate_pad_numbers_are_jumpers no)
		(fp_line
			(start -0.7874 -0.4064)
			(end 0.7874 -0.4064)
			(stroke
				(width 0.1524)
				(type default)
			)
			(layer "F.SilkS")
		)
		(fp_line
			(start -0.7874 0.4064)
			(end -0.7874 -0.4064)
			(stroke
				(width 0.1524)
				(type default)
			)
			(layer "F.SilkS")
		)
		(fp_line
			(start 0.7874 -0.4064)
			(end 0.7874 0.4064)
			(stroke
				(width 0.1524)
				(type default)
			)
			(layer "F.SilkS")
		)
		(fp_line
			(start 0.7874 0.4064)
			(end -0.7874 0.4064)
			(stroke
				(width 0.1524)
				(type default)
			)
			(layer "F.SilkS")
		)
		(fp_line
			(start -0.67945 -0.305054)
			(end -0.12065 -0.305054)
			(stroke
				(width 0.1)
				(type default)
			)
			(layer "F.Fab")
		)
		(fp_line
			(start -0.67945 0.3048)
			(end -0.67945 -0.305054)
			(stroke
				(width 0.1)
				(type default)
			)
			(layer "F.Fab")
		)
		(fp_line
			(start -0.12065 -0.305054)
			(end -0.12065 -0.2794)
			(stroke
				(width 0.1)
				(type default)
			)
			(layer "F.Fab")
		)
		(fp_line
			(start -0.12065 -0.2794)
			(end 0.12065 -0.2794)
			(stroke
				(width 0.1)
				(type default)
			)
			(layer "F.Fab")
		)
		(fp_line
			(start -0.12065 0.2794)
			(end -0.12065 0.3048)
			(stroke
				(width 0.1)
				(type default)
			)
			(layer "F.Fab")
		)
		(fp_line
			(start -0.12065 0.3048)
			(end -0.67945 0.3048)
			(stroke
				(width 0.1)
				(type default)
			)
			(layer "F.Fab")
		)
		(fp_line
			(start 0.120396 0.2794)
			(end -0.12065 0.2794)
			(stroke
				(width 0.1)
				(type default)
			)
			(layer "F.Fab")
		)
		(fp_line
			(start 0.120396 0.3048)
			(end 0.120396 0.2794)
			(stroke
				(width 0.1)
				(type default)
			)
			(layer "F.Fab")
		)
		(fp_line
			(start 0.12065 -0.3048)
			(end 0.67945 -0.3048)
			(stroke
				(width 0.1)
				(type default)
			)
			(layer "F.Fab")
		)
		(fp_line
			(start 0.12065 -0.2794)
			(end 0.12065 -0.3048)
			(stroke
				(width 0.1)
				(type default)
			)
			(layer "F.Fab")
		)
		(fp_line
			(start 0.67945 -0.3048)
			(end 0.67945 0.3048)
			(stroke
				(width 0.1)
				(type default)
			)
			(layer "F.Fab")
		)
		(fp_line
			(start 0.67945 0.3048)
			(end 0.120396 0.3048)
			(stroke
				(width 0.1)
				(type default)
			)
			(layer "F.Fab")
		)
		(pad "1" smd circle
			(at -0.40005 0)
			(size 0 0)
			(layers "F.Cu" "F.Mask" "F.Paste")
			(net "P12V_SSD7_R")
		)
		(pad "2" smd circle
			(at 0.40005 0)
			(size 0 0)
			(layers "F.Cu" "F.Mask" "F.Paste")
			(net "P12V_SSD7_PG_G1")
		)
	)
	(footprint ""
		(layer "F.Cu")
		(at 419.826694 -55.418228 90)
		(property "Reference" "PC430"
			(at 0 0 90)
			(layer "F.SilkS")
			(hide yes)
			(effects
				(font
					(size 1.27 1.27)
				)
			)
		)
		(property "Value" ""
			(at 0 0 90)
			(layer "F.Fab")
			(effects
				(font
					(size 1.27 1.27)
				)
			)
		)
		(duplicate_pad_numbers_are_jumpers no)
		(fp_line
			(start 0.7874 -0.4064)
			(end 0.7874 0.4064)
			(stroke
				(width 0.1524)
				(type default)
			)
			(layer "F.SilkS")
		)
		(fp_line
			(start -0.7874 -0.4064)
			(end 0.7874 -0.4064)
			(stroke
				(width 0.1524)
				(type default)
			)
			(layer "F.SilkS")
		)
		(fp_line
			(start 0.7874 0.4064)
			(end -0.7874 0.4064)
			(stroke
				(width 0.1524)
				(type default)
			)
			(layer "F.SilkS")
		)
		(fp_line
			(start -0.7874 0.4064)
			(end -0.7874 -0.4064)
			(stroke
				(width 0.1524)
				(type default)
			)
			(layer "F.SilkS")
		)
		(fp_line
			(start -0.12065 -0.305054)
			(end -0.12065 -0.2794)
			(stroke
				(width 0.1)
				(type default)
			)
			(layer "F.Fab")
		)
		(fp_line
			(start -0.67945 -0.305054)
			(end -0.12065 -0.305054)
			(stroke
				(width 0.1)
				(type default)
			)
			(layer "F.Fab")
		)
		(fp_line
			(start 0.67945 -0.3048)
			(end 0.67945 0.3048)
			(stroke
				(width 0.1)
				(type default)
			)
			(layer "F.Fab")
		)
		(fp_line
			(start 0.12065 -0.3048)
			(end 0.67945 -0.3048)
			(stroke
				(width 0.1)
				(type default)
			)
			(layer "F.Fab")
		)
		(fp_line
			(start 0.12065 -0.2794)
			(end 0.12065 -0.3048)
			(stroke
				(width 0.1)
				(type default)
			)
			(layer "F.Fab")
		)
		(fp_line
			(start -0.12065 -0.2794)
			(end 0.12065 -0.2794)
			(stroke
				(width 0.1)
				(type default)
			)
			(layer "F.Fab")
		)
		(fp_line
			(start 0.120396 0.2794)
			(end -0.12065 0.2794)
			(stroke
				(width 0.1)
				(type default)
			)
			(layer "F.Fab")
		)
		(fp_line
			(start -0.12065 0.2794)
			(end -0.12065 0.3048)
			(stroke
				(width 0.1)
				(type default)
			)
			(layer "F.Fab")
		)
		(fp_line
			(start 0.67945 0.3048)
			(end 0.120396 0.3048)
			(stroke
				(width 0.1)
				(type default)
			)
			(layer "F.Fab")
		)
		(fp_line
			(start 0.120396 0.3048)
			(end 0.120396 0.2794)
			(stroke
				(width 0.1)
				(type default)
			)
			(layer "F.Fab")
		)
		(fp_line
			(start -0.12065 0.3048)
			(end -0.67945 0.3048)
			(stroke
				(width 0.1)
				(type default)
			)
			(layer "F.Fab")
		)
		(fp_line
			(start -0.67945 0.3048)
			(end -0.67945 -0.305054)
			(stroke
				(width 0.1)
				(type default)
			)
			(layer "F.Fab")
		)
		(pad "1" smd circle
			(at -0.40005 0 90)
			(size 0 0)
			(layers "F.Cu" "F.Mask" "F.Paste")
			(net "P12V_SSD14_R")
		)
		(pad "2" smd circle
			(at 0.40005 0 90)
			(size 0 0)
			(layers "F.Cu" "F.Mask" "F.Paste")
			(net "GND")
		)
	)
	(footprint ""
		(layer "F.Cu")
		(at 29.422344 -252.356874 -90)
		(property "Reference" "R1193"
			(at 0 0 270)
			(layer "F.SilkS")
			(hide yes)
			(effects
				(font
					(size 1.27 1.27)
				)
			)
		)
		(property "Value" ""
			(at 0 0 270)
			(layer "F.Fab")
			(effects
				(font
					(size 1.27 1.27)
				)
			)
		)
		(duplicate_pad_numbers_are_jumpers no)
		(fp_line
			(start -0.7874 0.4064)
			(end -0.7874 -0.4064)
			(stroke
				(width 0.1524)
				(type default)
			)
			(layer "F.SilkS")
		)
		(fp_line
			(start 0.7874 0.4064)
			(end -0.7874 0.4064)
			(stroke
				(width 0.1524)
				(type default)
			)
			(layer "F.SilkS")
		)
		(fp_line
			(start -0.7874 -0.4064)
			(end 0.7874 -0.4064)
			(stroke
				(width 0.1524)
				(type default)
			)
			(layer "F.SilkS")
		)
		(fp_line
			(start 0.7874 -0.4064)
			(end 0.7874 0.4064)
			(stroke
				(width 0.1524)
				(type default)
			)
			(layer "F.SilkS")
		)
		(fp_line
			(start -0.67945 0.3048)
			(end -0.67945 -0.305054)
			(stroke
				(width 0.1)
				(type default)
			)
			(layer "F.Fab")
		)
		(fp_line
			(start -0.12065 0.3048)
			(end -0.67945 0.3048)
			(stroke
				(width 0.1)
				(type default)
			)
			(layer "F.Fab")
		)
		(fp_line
			(start 0.120396 0.3048)
			(end 0.120396 0.2794)
			(stroke
				(width 0.1)
				(type default)
			)
			(layer "F.Fab")
		)
		(fp_line
			(start 0.67945 0.3048)
			(end 0.120396 0.3048)
			(stroke
				(width 0.1)
				(type default)
			)
			(layer "F.Fab")
		)
		(fp_line
			(start -0.12065 0.2794)
			(end -0.12065 0.3048)
			(stroke
				(width 0.1)
				(type default)
			)
			(layer "F.Fab")
		)
		(fp_line
			(start 0.120396 0.2794)
			(end -0.12065 0.2794)
			(stroke
				(width 0.1)
				(type default)
			)
			(layer "F.Fab")
		)
		(fp_line
			(start -0.12065 -0.2794)
			(end 0.12065 -0.2794)
			(stroke
				(width 0.1)
				(type default)
			)
			(layer "F.Fab")
		)
		(fp_line
			(start 0.12065 -0.2794)
			(end 0.12065 -0.3048)
			(stroke
				(width 0.1)
				(type default)
			)
			(layer "F.Fab")
		)
		(fp_line
			(start 0.12065 -0.3048)
			(end 0.67945 -0.3048)
			(stroke
				(width 0.1)
				(type default)
			)
			(layer "F.Fab")
		)
		(fp_line
			(start 0.67945 -0.3048)
			(end 0.67945 0.3048)
			(stroke
				(width 0.1)
				(type default)
			)
			(layer "F.Fab")
		)
		(fp_line
			(start -0.67945 -0.305054)
			(end -0.12065 -0.305054)
			(stroke
				(width 0.1)
				(type default)
			)
			(layer "F.Fab")
		)
		(fp_line
			(start -0.12065 -0.305054)
			(end -0.12065 -0.2794)
			(stroke
				(width 0.1)
				(type default)
			)
			(layer "F.Fab")
		)
		(pad "1" smd circle
			(at -0.40005 0 270)
			(size 0 0)
			(layers "F.Cu" "F.Mask" "F.Paste")
			(net "GND")
		)
		(pad "2" smd circle
			(at 0.40005 0 270)
			(size 0 0)
			(layers "F.Cu" "F.Mask" "F.Paste")
			(net "PEX0_MODE_SEL3")
		)
	)
	(footprint ""
		(layer "F.Cu")
		(at 346.075 -169.291)
		(property "Reference" "U348"
			(at -1.4478 -4.613148 0)
			(unlocked yes)
			(layer "F.SilkS")
			(effects
				(font
					(size 0.7874 0.5842)
					(thickness 0.1524)
				)
				(justify left)
			)
		)
		(property "Value" ""
			(at 0 0 0)
			(layer "F.Fab")
			(effects
				(font
					(size 1.27 1.27)
				)
			)
		)
		(duplicate_pad_numbers_are_jumpers no)
		(fp_line
			(start -2.097532 -3.949954)
			(end -2.097532 3.949954)
			(stroke
				(width 0.1524)
				(type default)
			)
			(layer "F.SilkS")
		)
		(fp_line
			(start -2.097532 3.949954)
			(end 2.097532 3.949954)
			(stroke
				(width 0.1524)
				(type default)
			)
			(layer "F.SilkS")
		)
		(fp_line
			(start -1.409954 -3.949954)
			(end -2.097532 -3.949954)
			(stroke
				(width 0.1524)
				(type default)
			)
			(layer "F.SilkS")
		)
		(fp_line
			(start 0 -2.54)
			(end -1.409954 -3.949954)
			(stroke
				(width 0.1524)
				(type default)
			)
			(layer "F.SilkS")
		)
		(fp_line
			(start 1.409954 -3.949954)
			(end 0 -2.54)
			(stroke
				(width 0.1524)
				(type default)
			)
			(layer "F.SilkS")
		)
		(fp_line
			(start 2.097532 -3.949954)
			(end 1.409954 -3.949954)
			(stroke
				(width 0.1524)
				(type default)
			)
			(layer "F.SilkS")
		)
		(fp_line
			(start 2.097532 3.949954)
			(end 2.097532 -3.949954)
			(stroke
				(width 0.1524)
				(type default)
			)
			(layer "F.SilkS")
		)
		(fp_poly
			(pts
				(xy -4.7498 -4.182872) (xy -4.7498 -3.166872) (xy -3.7338 -3.674872)
			)
			(stroke
				(width 0)
				(type default)
			)
			(fill yes)
			(layer "F.SilkS")
		)
		(fp_line
			(start -2.249932 -3.949954)
			(end -2.249932 3.949954)
			(stroke
				(width 0.1)
				(type default)
			)
			(layer "F.Fab")
		)
		(fp_line
			(start -2.249932 3.949954)
			(end 2.249932 3.949954)
			(stroke
				(width 0.1)
				(type default)
			)
			(layer "F.Fab")
		)
		(fp_line
			(start 2.249932 -3.949954)
			(end -2.249932 -3.949954)
			(stroke
				(width 0.1)
				(type default)
			)
			(layer "F.Fab")
		)
		(fp_line
			(start 2.249932 3.949954)
			(end 2.249932 -3.949954)
			(stroke
				(width 0.1)
				(type default)
			)
			(layer "F.Fab")
		)
		(fp_poly
			(pts
				(xy -4.7498 -4.182872) (xy -4.7498 -3.166872) (xy -3.7338 -3.674872)
			)
			(stroke
				(width 0)
				(type default)
			)
			(fill yes)
			(layer "F.Fab")
		)
		(pad "1" smd rect
			(at -2.925064 -3.674872 270)
			(size 0.6096 1.3716)
			(layers "F.Cu" "F.Mask" "F.Paste")
			(net "PEX2_PCA9555_1_INT_N")
		)
		(pad "2" smd rect
			(at -2.925064 -2.925064 270)
			(size 0.4064 1.3716)
			(layers "F.Cu" "F.Mask" "F.Paste")
			(net "PCA9555_1_PEX2_A1")
		)
		(pad "3" smd rect
			(at -2.925064 -2.275078 270)
			(size 0.4064 1.3716)
			(layers "F.Cu" "F.Mask" "F.Paste")
			(net "PCA9555_1_PEX2_A2")
		)
		(pad "4" smd rect
			(at -2.925064 -1.625092 270)
			(size 0.4064 1.3716)
			(layers "F.Cu" "F.Mask" "F.Paste")
			(net "PRSNT_SSD10_FPGA_PCA9555_N")
		)
		(pad "5" smd rect
			(at -2.925064 -0.975106 270)
			(size 0.4064 1.3716)
			(layers "F.Cu" "F.Mask" "F.Paste")
			(net "SSD10_PEX_PWR_EN")
		)
		(pad "6" smd rect
			(at -2.925064 -0.32512 270)
			(size 0.4064 1.3716)
			(layers "F.Cu" "F.Mask" "F.Paste")
			(net "RST_PEX_SSD10_PERST_N")
		)
		(pad "7" smd rect
			(at -2.925064 0.32512 270)
			(size 0.4064 1.3716)
			(layers "F.Cu" "F.Mask" "F.Paste")
			(net "Net_1178")
		)
		(pad "8" smd rect
			(at -2.925064 0.975106 270)
			(size 0.4064 1.3716)
			(layers "F.Cu" "F.Mask" "F.Paste")
			(net "PRSNT_SSD11_FPGA_PCA9555_N")
		)
		(pad "9" smd rect
			(at -2.925064 1.625092 270)
			(size 0.4064 1.3716)
			(layers "F.Cu" "F.Mask" "F.Paste")
			(net "SSD11_PEX_PWR_EN")
		)
		(pad "10" smd rect
			(at -2.925064 2.275078 270)
			(size 0.4064 1.3716)
			(layers "F.Cu" "F.Mask" "F.Paste")
			(net "RST_PEX_SSD11_PERST_N")
		)
		(pad "11" smd rect
			(at -2.925064 2.925064 270)
			(size 0.4064 1.3716)
			(layers "F.Cu" "F.Mask" "F.Paste")
			(net "Net_1179")
		)
		(pad "12" smd rect
			(at -2.925064 3.674872 270)
			(size 0.6096 1.3716)
			(layers "F.Cu" "F.Mask" "F.Paste")
			(net "GND")
		)
		(pad "13" smd rect
			(at 2.925064 3.674872 270)
			(size 0.6096 1.3716)
			(layers "F.Cu" "F.Mask" "F.Paste")
			(net "PRSNT_NIC5_FPGA_PCA9555_N")
		)
		(pad "14" smd rect
			(at 2.925064 2.925064 270)
			(size 0.4064 1.3716)
			(layers "F.Cu" "F.Mask" "F.Paste")
			(net "NIC5_PEX_PWR_EN")
		)
		(pad "15" smd rect
			(at 2.925064 2.275078 270)
			(size 0.4064 1.3716)
			(layers "F.Cu" "F.Mask" "F.Paste")
			(net "RST_PEX_NIC5_PERST_N")
		)
		(pad "16" smd rect
			(at 2.925064 1.625092 270)
			(size 0.4064 1.3716)
			(layers "F.Cu" "F.Mask" "F.Paste")
			(net "Net_1181")
		)
		(pad "17" smd rect
			(at 2.925064 0.975106 270)
			(size 0.4064 1.3716)
			(layers "F.Cu" "F.Mask" "F.Paste")
			(net "Net_8972")
		)
		(pad "18" smd rect
			(at 2.925064 0.32512 270)
			(size 0.4064 1.3716)
			(layers "F.Cu" "F.Mask" "F.Paste")
			(net "Net_8971")
		)
		(pad "19" smd rect
			(at 2.925064 -0.32512 270)
			(size 0.4064 1.3716)
			(layers "F.Cu" "F.Mask" "F.Paste")
			(net "Net_8970")
		)
		(pad "20" smd rect
			(at 2.925064 -0.975106 270)
			(size 0.4064 1.3716)
			(layers "F.Cu" "F.Mask" "F.Paste")
			(net "Net_8969")
		)
		(pad "21" smd rect
			(at 2.925064 -1.625092 270)
			(size 0.4064 1.3716)
			(layers "F.Cu" "F.Mask" "F.Paste")
			(net "PCA9555_1_PEX2_A0")
		)
		(pad "22" smd rect
			(at 2.925064 -2.275078 270)
			(size 0.4064 1.3716)
			(layers "F.Cu" "F.Mask" "F.Paste")
			(net "SMB_PEX2_PCA9555_SCL")
		)
		(pad "23" smd rect
			(at 2.925064 -2.925064 270)
			(size 0.4064 1.3716)
			(layers "F.Cu" "F.Mask" "F.Paste")
			(net "SMB_PEX2_PCA9555_SDA")
		)
		(pad "24" smd rect
			(at 2.925064 -3.674872 270)
			(size 0.6096 1.3716)
			(layers "F.Cu" "F.Mask" "F.Paste")
			(net "P3V3_AUX")
		)
	)
	(footprint ""
		(layer "F.Cu")
		(at 454.313036 -363.462824 180)
		(property "Reference" "R6694"
			(at 0 0 180)
			(layer "F.SilkS")
			(hide yes)
			(effects
				(font
					(size 1.27 1.27)
				)
			)
		)
		(property "Value" ""
			(at 0 0 180)
			(layer "F.Fab")
			(effects
				(font
					(size 1.27 1.27)
				)
			)
		)
		(duplicate_pad_numbers_are_jumpers no)
		(fp_line
			(start 0.7874 0.4064)
			(end -0.7874 0.4064)
			(stroke
				(width 0.1524)
				(type default)
			)
			(layer "F.SilkS")
		)
		(fp_line
			(start 0.7874 -0.4064)
			(end 0.7874 0.4064)
			(stroke
				(width 0.1524)
				(type default)
			)
			(layer "F.SilkS")
		)
		(fp_line
			(start -0.7874 0.4064)
			(end -0.7874 -0.4064)
			(stroke
				(width 0.1524)
				(type default)
			)
			(layer "F.SilkS")
		)
		(fp_line
			(start -0.7874 -0.4064)
			(end 0.7874 -0.4064)
			(stroke
				(width 0.1524)
				(type default)
			)
			(layer "F.SilkS")
		)
		(fp_line
			(start 0.67945 0.3048)
			(end 0.120396 0.3048)
			(stroke
				(width 0.1)
				(type default)
			)
			(layer "F.Fab")
		)
		(fp_line
			(start 0.67945 -0.3048)
			(end 0.67945 0.3048)
			(stroke
				(width 0.1)
				(type default)
			)
			(layer "F.Fab")
		)
		(fp_line
			(start 0.12065 -0.2794)
			(end 0.12065 -0.3048)
			(stroke
				(width 0.1)
				(type default)
			)
			(layer "F.Fab")
		)
		(fp_line
			(start 0.12065 -0.3048)
			(end 0.67945 -0.3048)
			(stroke
				(width 0.1)
				(type default)
			)
			(layer "F.Fab")
		)
		(fp_line
			(start 0.120396 0.3048)
			(end 0.120396 0.2794)
			(stroke
				(width 0.1)
				(type default)
			)
			(layer "F.Fab")
		)
		(fp_line
			(start 0.120396 0.2794)
			(end -0.12065 0.2794)
			(stroke
				(width 0.1)
				(type default)
			)
			(layer "F.Fab")
		)
		(fp_line
			(start -0.12065 0.3048)
			(end -0.67945 0.3048)
			(stroke
				(width 0.1)
				(type default)
			)
			(layer "F.Fab")
		)
		(fp_line
			(start -0.12065 0.2794)
			(end -0.12065 0.3048)
			(stroke
				(width 0.1)
				(type default)
			)
			(layer "F.Fab")
		)
		(fp_line
			(start -0.12065 -0.2794)
			(end 0.12065 -0.2794)
			(stroke
				(width 0.1)
				(type default)
			)
			(layer "F.Fab")
		)
		(fp_line
			(start -0.12065 -0.305054)
			(end -0.12065 -0.2794)
			(stroke
				(width 0.1)
				(type default)
			)
			(layer "F.Fab")
		)
		(fp_line
			(start -0.67945 0.3048)
			(end -0.67945 -0.305054)
			(stroke
				(width 0.1)
				(type default)
			)
			(layer "F.Fab")
		)
		(fp_line
			(start -0.67945 -0.305054)
			(end -0.12065 -0.305054)
			(stroke
				(width 0.1)
				(type default)
			)
			(layer "F.Fab")
		)
		(pad "1" smd circle
			(at -0.40005 0 180)
			(size 0 0)
			(layers "F.Cu" "F.Mask" "F.Paste")
			(net "GPU_3V3IO_RSVD4_ISO")
		)
		(pad "2" smd circle
			(at 0.40005 0 180)
			(size 0 0)
			(layers "F.Cu" "F.Mask" "F.Paste")
			(net "GPU_3V3IO_RSVD4")
		)
	)
	(footprint ""
		(layer "F.Cu")
		(at 92.436442 -350.098614 90)
		(property "Reference" "C97"
			(at 0 0 90)
			(layer "F.SilkS")
			(hide yes)
			(effects
				(font
					(size 1.27 1.27)
				)
			)
		)
		(property "Value" ""
			(at 0 0 90)
			(layer "F.Fab")
			(effects
				(font
					(size 1.27 1.27)
				)
			)
		)
		(duplicate_pad_numbers_are_jumpers no)
		(fp_line
			(start 0.299974 -0.150114)
			(end 0.299974 0.150114)
			(stroke
				(width 0.1)
				(type default)
			)
			(layer "F.Fab")
		)
		(fp_line
			(start -0.299974 -0.150114)
			(end 0.299974 -0.150114)
			(stroke
				(width 0.1)
				(type default)
			)
			(layer "F.Fab")
		)
		(fp_line
			(start 0.299974 0.150114)
			(end -0.299974 0.150114)
			(stroke
				(width 0.1)
				(type default)
			)
			(layer "F.Fab")
		)
		(fp_line
			(start -0.299974 0.150114)
			(end -0.299974 -0.150114)
			(stroke
				(width 0.1)
				(type default)
			)
			(layer "F.Fab")
		)
		(pad "1" smd rect
			(at -0.2667 0 90)
			(size 0.3048 0.381)
			(layers "F.Cu" "F.Mask" "F.Paste")
			(net "P5E_PEX0_STN5_TX_DP<95>")
		)
		(pad "2" smd rect
			(at 0.2667 0 90)
			(size 0.3048 0.381)
			(layers "F.Cu" "F.Mask" "F.Paste")
			(net "P5E_PEX0_STN5_TX_C_DP<95>")
		)
	)
	(footprint ""
		(layer "F.Cu")
		(at 366.139984 -70.52437 90)
		(property "Reference" "PC883"
			(at 0 0 90)
			(layer "F.SilkS")
			(hide yes)
			(effects
				(font
					(size 1.27 1.27)
				)
			)
		)
		(property "Value" ""
			(at 0 0 90)
			(layer "F.Fab")
			(effects
				(font
					(size 1.27 1.27)
				)
			)
		)
		(duplicate_pad_numbers_are_jumpers no)
		(fp_line
			(start 1.524 -0.762)
			(end 1.524 0.762)
			(stroke
				(width 0.1524)
				(type default)
			)
			(layer "F.SilkS")
		)
		(fp_line
			(start -1.524 -0.762)
			(end 1.524 -0.762)
			(stroke
				(width 0.1524)
				(type default)
			)
			(layer "F.SilkS")
		)
		(fp_line
			(start 1.524 0.762)
			(end -1.524 0.762)
			(stroke
				(width 0.1524)
				(type default)
			)
			(layer "F.SilkS")
		)
		(fp_line
			(start -1.524 0.762)
			(end -1.524 -0.762)
			(stroke
				(width 0.1524)
				(type default)
			)
			(layer "F.SilkS")
		)
		(fp_line
			(start 1.1049 -0.724916)
			(end -1.1049 -0.724916)
			(stroke
				(width 0.1)
				(type default)
			)
			(layer "F.Fab")
		)
		(fp_line
			(start -1.1049 -0.724916)
			(end -1.1049 0.724916)
			(stroke
				(width 0.1)
				(type default)
			)
			(layer "F.Fab")
		)
		(fp_line
			(start 1.1049 0.724916)
			(end 1.1049 -0.724916)
			(stroke
				(width 0.1)
				(type default)
			)
			(layer "F.Fab")
		)
		(fp_line
			(start -1.1049 0.724916)
			(end 1.1049 0.724916)
			(stroke
				(width 0.1)
				(type default)
			)
			(layer "F.Fab")
		)
		(pad "1" smd rect
			(at -0.889 0 270)
			(size 1.016 1.27)
			(layers "F.Cu" "F.Mask" "F.Paste")
			(net "P12V_SSD12_R")
		)
		(pad "2" smd rect
			(at 0.889 0 270)
			(size 1.016 1.27)
			(layers "F.Cu" "F.Mask" "F.Paste")
			(net "GND")
		)
	)
	(footprint ""
		(layer "F.Cu")
		(at 123.768612 -156.288994 -90)
		(property "Reference" "PR6890"
			(at 0 0 270)
			(layer "F.SilkS")
			(hide yes)
			(effects
				(font
					(size 1.27 1.27)
				)
			)
		)
		(property "Value" ""
			(at 0 0 270)
			(layer "F.Fab")
			(effects
				(font
					(size 1.27 1.27)
				)
			)
		)
		(duplicate_pad_numbers_are_jumpers no)
		(fp_line
			(start -0.7874 0.4064)
			(end -0.7874 -0.4064)
			(stroke
				(width 0.1524)
				(type default)
			)
			(layer "F.SilkS")
		)
		(fp_line
			(start 0.7874 0.4064)
			(end -0.7874 0.4064)
			(stroke
				(width 0.1524)
				(type default)
			)
			(layer "F.SilkS")
		)
		(fp_line
			(start -0.7874 -0.4064)
			(end 0.7874 -0.4064)
			(stroke
				(width 0.1524)
				(type default)
			)
			(layer "F.SilkS")
		)
		(fp_line
			(start 0.7874 -0.4064)
			(end 0.7874 0.4064)
			(stroke
				(width 0.1524)
				(type default)
			)
			(layer "F.SilkS")
		)
		(fp_line
			(start -0.67945 0.3048)
			(end -0.67945 -0.305054)
			(stroke
				(width 0.1)
				(type default)
			)
			(layer "F.Fab")
		)
		(fp_line
			(start -0.12065 0.3048)
			(end -0.67945 0.3048)
			(stroke
				(width 0.1)
				(type default)
			)
			(layer "F.Fab")
		)
		(fp_line
			(start 0.120396 0.3048)
			(end 0.120396 0.2794)
			(stroke
				(width 0.1)
				(type default)
			)
			(layer "F.Fab")
		)
		(fp_line
			(start 0.67945 0.3048)
			(end 0.120396 0.3048)
			(stroke
				(width 0.1)
				(type default)
			)
			(layer "F.Fab")
		)
		(fp_line
			(start -0.12065 0.2794)
			(end -0.12065 0.3048)
			(stroke
				(width 0.1)
				(type default)
			)
			(layer "F.Fab")
		)
		(fp_line
			(start 0.120396 0.2794)
			(end -0.12065 0.2794)
			(stroke
				(width 0.1)
				(type default)
			)
			(layer "F.Fab")
		)
		(fp_line
			(start -0.12065 -0.2794)
			(end 0.12065 -0.2794)
			(stroke
				(width 0.1)
				(type default)
			)
			(layer "F.Fab")
		)
		(fp_line
			(start 0.12065 -0.2794)
			(end 0.12065 -0.3048)
			(stroke
				(width 0.1)
				(type default)
			)
			(layer "F.Fab")
		)
		(fp_line
			(start 0.12065 -0.3048)
			(end 0.67945 -0.3048)
			(stroke
				(width 0.1)
				(type default)
			)
			(layer "F.Fab")
		)
		(fp_line
			(start 0.67945 -0.3048)
			(end 0.67945 0.3048)
			(stroke
				(width 0.1)
				(type default)
			)
			(layer "F.Fab")
		)
		(fp_line
			(start -0.67945 -0.305054)
			(end -0.12065 -0.305054)
			(stroke
				(width 0.1)
				(type default)
			)
			(layer "F.Fab")
		)
		(fp_line
			(start -0.12065 -0.305054)
			(end -0.12065 -0.2794)
			(stroke
				(width 0.1)
				(type default)
			)
			(layer "F.Fab")
		)
		(pad "1" smd circle
			(at -0.40005 0 270)
			(size 0 0)
			(layers "F.Cu" "F.Mask" "F.Paste")
			(net "P12V_NIC2_CO_OV_FB")
		)
		(pad "2" smd circle
			(at 0.40005 0 270)
			(size 0 0)
			(layers "F.Cu" "F.Mask" "F.Paste")
			(net "P12V_AUX")
		)
	)
	(footprint ""
		(layer "F.Cu")
		(at 374.567958 -55.083456)
		(property "Reference" "PC409"
			(at 0 0 0)
			(layer "F.SilkS")
			(hide yes)
			(effects
				(font
					(size 1.27 1.27)
				)
			)
		)
		(property "Value" ""
			(at 0 0 0)
			(layer "F.Fab")
			(effects
				(font
					(size 1.27 1.27)
				)
			)
		)
		(duplicate_pad_numbers_are_jumpers no)
		(fp_line
			(start -0.7874 -0.4064)
			(end 0.7874 -0.4064)
			(stroke
				(width 0.1524)
				(type default)
			)
			(layer "F.SilkS")
		)
		(fp_line
			(start -0.7874 0.4064)
			(end -0.7874 -0.4064)
			(stroke
				(width 0.1524)
				(type default)
			)
			(layer "F.SilkS")
		)
		(fp_line
			(start 0.7874 -0.4064)
			(end 0.7874 0.4064)
			(stroke
				(width 0.1524)
				(type default)
			)
			(layer "F.SilkS")
		)
		(fp_line
			(start 0.7874 0.4064)
			(end -0.7874 0.4064)
			(stroke
				(width 0.1524)
				(type default)
			)
			(layer "F.SilkS")
		)
		(fp_line
			(start -0.67945 -0.305054)
			(end -0.12065 -0.305054)
			(stroke
				(width 0.1)
				(type default)
			)
			(layer "F.Fab")
		)
		(fp_line
			(start -0.67945 0.3048)
			(end -0.67945 -0.305054)
			(stroke
				(width 0.1)
				(type default)
			)
			(layer "F.Fab")
		)
		(fp_line
			(start -0.12065 -0.305054)
			(end -0.12065 -0.2794)
			(stroke
				(width 0.1)
				(type default)
			)
			(layer "F.Fab")
		)
		(fp_line
			(start -0.12065 -0.2794)
			(end 0.12065 -0.2794)
			(stroke
				(width 0.1)
				(type default)
			)
			(layer "F.Fab")
		)
		(fp_line
			(start -0.12065 0.2794)
			(end -0.12065 0.3048)
			(stroke
				(width 0.1)
				(type default)
			)
			(layer "F.Fab")
		)
		(fp_line
			(start -0.12065 0.3048)
			(end -0.67945 0.3048)
			(stroke
				(width 0.1)
				(type default)
			)
			(layer "F.Fab")
		)
		(fp_line
			(start 0.120396 0.2794)
			(end -0.12065 0.2794)
			(stroke
				(width 0.1)
				(type default)
			)
			(layer "F.Fab")
		)
		(fp_line
			(start 0.120396 0.3048)
			(end 0.120396 0.2794)
			(stroke
				(width 0.1)
				(type default)
			)
			(layer "F.Fab")
		)
		(fp_line
			(start 0.12065 -0.3048)
			(end 0.67945 -0.3048)
			(stroke
				(width 0.1)
				(type default)
			)
			(layer "F.Fab")
		)
		(fp_line
			(start 0.12065 -0.2794)
			(end 0.12065 -0.3048)
			(stroke
				(width 0.1)
				(type default)
			)
			(layer "F.Fab")
		)
		(fp_line
			(start 0.67945 -0.3048)
			(end 0.67945 0.3048)
			(stroke
				(width 0.1)
				(type default)
			)
			(layer "F.Fab")
		)
		(fp_line
			(start 0.67945 0.3048)
			(end 0.120396 0.3048)
			(stroke
				(width 0.1)
				(type default)
			)
			(layer "F.Fab")
		)
		(pad "1" smd circle
			(at -0.40005 0)
			(size 0 0)
			(layers "F.Cu" "F.Mask" "F.Paste")
			(net "P5V_AUX")
		)
		(pad "2" smd circle
			(at 0.40005 0)
			(size 0 0)
			(layers "F.Cu" "F.Mask" "F.Paste")
			(net "GND")
		)
	)
	(footprint ""
		(layer "F.Cu")
		(at 35.766248 -350.098614 90)
		(property "Reference" "C2167"
			(at 0 0 90)
			(layer "F.SilkS")
			(hide yes)
			(effects
				(font
					(size 1.27 1.27)
				)
			)
		)
		(property "Value" ""
			(at 0 0 90)
			(layer "F.Fab")
			(effects
				(font
					(size 1.27 1.27)
				)
			)
		)
		(duplicate_pad_numbers_are_jumpers no)
		(fp_line
			(start 0.299974 -0.150114)
			(end 0.299974 0.150114)
			(stroke
				(width 0.1)
				(type default)
			)
			(layer "F.Fab")
		)
		(fp_line
			(start -0.299974 -0.150114)
			(end 0.299974 -0.150114)
			(stroke
				(width 0.1)
				(type default)
			)
			(layer "F.Fab")
		)
		(fp_line
			(start 0.299974 0.150114)
			(end -0.299974 0.150114)
			(stroke
				(width 0.1)
				(type default)
			)
			(layer "F.Fab")
		)
		(fp_line
			(start -0.299974 0.150114)
			(end -0.299974 -0.150114)
			(stroke
				(width 0.1)
				(type default)
			)
			(layer "F.Fab")
		)
		(pad "1" smd rect
			(at -0.2667 0 90)
			(size 0.3048 0.381)
			(layers "F.Cu" "F.Mask" "F.Paste")
			(net "P5E_PEX0_STN4_TX_DN<72>")
		)
		(pad "2" smd rect
			(at 0.2667 0 90)
			(size 0.3048 0.381)
			(layers "F.Cu" "F.Mask" "F.Paste")
			(net "P5E_PEX0_STN4_TX_C_DN<72>")
		)
	)
	(footprint ""
		(layer "F.Cu")
		(at 319.003934 -289.230816 90)
		(property "Reference" "R3984"
			(at 0 0 90)
			(layer "F.SilkS")
			(hide yes)
			(effects
				(font
					(size 1.27 1.27)
				)
			)
		)
		(property "Value" ""
			(at 0 0 90)
			(layer "F.Fab")
			(effects
				(font
					(size 1.27 1.27)
				)
			)
		)
		(duplicate_pad_numbers_are_jumpers no)
		(fp_line
			(start 0.7874 -0.4064)
			(end 0.7874 0.4064)
			(stroke
				(width 0.1524)
				(type default)
			)
			(layer "F.SilkS")
		)
		(fp_line
			(start -0.7874 -0.4064)
			(end 0.7874 -0.4064)
			(stroke
				(width 0.1524)
				(type default)
			)
			(layer "F.SilkS")
		)
		(fp_line
			(start 0.7874 0.4064)
			(end -0.7874 0.4064)
			(stroke
				(width 0.1524)
				(type default)
			)
			(layer "F.SilkS")
		)
		(fp_line
			(start -0.7874 0.4064)
			(end -0.7874 -0.4064)
			(stroke
				(width 0.1524)
				(type default)
			)
			(layer "F.SilkS")
		)
		(fp_line
			(start -0.12065 -0.305054)
			(end -0.12065 -0.2794)
			(stroke
				(width 0.1)
				(type default)
			)
			(layer "F.Fab")
		)
		(fp_line
			(start -0.67945 -0.305054)
			(end -0.12065 -0.305054)
			(stroke
				(width 0.1)
				(type default)
			)
			(layer "F.Fab")
		)
		(fp_line
			(start 0.67945 -0.3048)
			(end 0.67945 0.3048)
			(stroke
				(width 0.1)
				(type default)
			)
			(layer "F.Fab")
		)
		(fp_line
			(start 0.12065 -0.3048)
			(end 0.67945 -0.3048)
			(stroke
				(width 0.1)
				(type default)
			)
			(layer "F.Fab")
		)
		(fp_line
			(start 0.12065 -0.2794)
			(end 0.12065 -0.3048)
			(stroke
				(width 0.1)
				(type default)
			)
			(layer "F.Fab")
		)
		(fp_line
			(start -0.12065 -0.2794)
			(end 0.12065 -0.2794)
			(stroke
				(width 0.1)
				(type default)
			)
			(layer "F.Fab")
		)
		(fp_line
			(start 0.120396 0.2794)
			(end -0.12065 0.2794)
			(stroke
				(width 0.1)
				(type default)
			)
			(layer "F.Fab")
		)
		(fp_line
			(start -0.12065 0.2794)
			(end -0.12065 0.3048)
			(stroke
				(width 0.1)
				(type default)
			)
			(layer "F.Fab")
		)
		(fp_line
			(start 0.67945 0.3048)
			(end 0.120396 0.3048)
			(stroke
				(width 0.1)
				(type default)
			)
			(layer "F.Fab")
		)
		(fp_line
			(start 0.120396 0.3048)
			(end 0.120396 0.2794)
			(stroke
				(width 0.1)
				(type default)
			)
			(layer "F.Fab")
		)
		(fp_line
			(start -0.12065 0.3048)
			(end -0.67945 0.3048)
			(stroke
				(width 0.1)
				(type default)
			)
			(layer "F.Fab")
		)
		(fp_line
			(start -0.67945 0.3048)
			(end -0.67945 -0.305054)
			(stroke
				(width 0.1)
				(type default)
			)
			(layer "F.Fab")
		)
		(pad "1" smd circle
			(at -0.40005 0 90)
			(size 0 0)
			(layers "F.Cu" "F.Mask" "F.Paste")
			(net "PWRGD_P1V8_PEX_R")
		)
		(pad "2" smd circle
			(at 0.40005 0 90)
			(size 0 0)
			(layers "F.Cu" "F.Mask" "F.Paste")
			(net "PWRGD_P1V8_PEX2_R")
		)
	)
	(footprint ""
		(layer "F.Cu")
		(at 270.960342 -116.7384)
		(property "Reference" "R243"
			(at 0 0 0)
			(layer "F.SilkS")
			(hide yes)
			(effects
				(font
					(size 1.27 1.27)
				)
			)
		)
		(property "Value" ""
			(at 0 0 0)
			(layer "F.Fab")
			(effects
				(font
					(size 1.27 1.27)
				)
			)
		)
		(duplicate_pad_numbers_are_jumpers no)
		(fp_line
			(start -0.7874 -0.4064)
			(end 0.7874 -0.4064)
			(stroke
				(width 0.1524)
				(type default)
			)
			(layer "F.SilkS")
		)
		(fp_line
			(start -0.7874 0.4064)
			(end -0.7874 -0.4064)
			(stroke
				(width 0.1524)
				(type default)
			)
			(layer "F.SilkS")
		)
		(fp_line
			(start 0.7874 -0.4064)
			(end 0.7874 0.4064)
			(stroke
				(width 0.1524)
				(type default)
			)
			(layer "F.SilkS")
		)
		(fp_line
			(start 0.7874 0.4064)
			(end -0.7874 0.4064)
			(stroke
				(width 0.1524)
				(type default)
			)
			(layer "F.SilkS")
		)
		(fp_line
			(start -0.67945 -0.305054)
			(end -0.12065 -0.305054)
			(stroke
				(width 0.1)
				(type default)
			)
			(layer "F.Fab")
		)
		(fp_line
			(start -0.67945 0.3048)
			(end -0.67945 -0.305054)
			(stroke
				(width 0.1)
				(type default)
			)
			(layer "F.Fab")
		)
		(fp_line
			(start -0.12065 -0.305054)
			(end -0.12065 -0.2794)
			(stroke
				(width 0.1)
				(type default)
			)
			(layer "F.Fab")
		)
		(fp_line
			(start -0.12065 -0.2794)
			(end 0.12065 -0.2794)
			(stroke
				(width 0.1)
				(type default)
			)
			(layer "F.Fab")
		)
		(fp_line
			(start -0.12065 0.2794)
			(end -0.12065 0.3048)
			(stroke
				(width 0.1)
				(type default)
			)
			(layer "F.Fab")
		)
		(fp_line
			(start -0.12065 0.3048)
			(end -0.67945 0.3048)
			(stroke
				(width 0.1)
				(type default)
			)
			(layer "F.Fab")
		)
		(fp_line
			(start 0.120396 0.2794)
			(end -0.12065 0.2794)
			(stroke
				(width 0.1)
				(type default)
			)
			(layer "F.Fab")
		)
		(fp_line
			(start 0.120396 0.3048)
			(end 0.120396 0.2794)
			(stroke
				(width 0.1)
				(type default)
			)
			(layer "F.Fab")
		)
		(fp_line
			(start 0.12065 -0.3048)
			(end 0.67945 -0.3048)
			(stroke
				(width 0.1)
				(type default)
			)
			(layer "F.Fab")
		)
		(fp_line
			(start 0.12065 -0.2794)
			(end 0.12065 -0.3048)
			(stroke
				(width 0.1)
				(type default)
			)
			(layer "F.Fab")
		)
		(fp_line
			(start 0.67945 -0.3048)
			(end 0.67945 0.3048)
			(stroke
				(width 0.1)
				(type default)
			)
			(layer "F.Fab")
		)
		(fp_line
			(start 0.67945 0.3048)
			(end 0.120396 0.3048)
			(stroke
				(width 0.1)
				(type default)
			)
			(layer "F.Fab")
		)
		(pad "1" smd circle
			(at -0.40005 0)
			(size 0 0)
			(layers "F.Cu" "F.Mask" "F.Paste")
			(net "PRSNT_NIC4_N")
		)
		(pad "2" smd circle
			(at 0.40005 0)
			(size 0 0)
			(layers "F.Cu" "F.Mask" "F.Paste")
			(net "PRSNTB0_NIC4_N")
		)
	)
	(footprint ""
		(layer "F.Cu")
		(at 381.587756 -301.220632)
		(property "Reference" "C3546"
			(at 0 0 0)
			(layer "F.SilkS")
			(hide yes)
			(effects
				(font
					(size 1.27 1.27)
				)
			)
		)
		(property "Value" ""
			(at 0 0 0)
			(layer "F.Fab")
			(effects
				(font
					(size 1.27 1.27)
				)
			)
		)
		(duplicate_pad_numbers_are_jumpers no)
		(fp_line
			(start -1.2954 -0.5842)
			(end 1.2954 -0.5842)
			(stroke
				(width 0.1524)
				(type default)
			)
			(layer "F.SilkS")
		)
		(fp_line
			(start -1.2954 0.5842)
			(end -1.2954 -0.5842)
			(stroke
				(width 0.1524)
				(type default)
			)
			(layer "F.SilkS")
		)
		(fp_line
			(start 1.2954 -0.5842)
			(end 1.2954 0.5842)
			(stroke
				(width 0.1524)
				(type default)
			)
			(layer "F.SilkS")
		)
		(fp_line
			(start 1.2954 0.5842)
			(end -1.2954 0.5842)
			(stroke
				(width 0.1524)
				(type default)
			)
			(layer "F.SilkS")
		)
		(fp_line
			(start -1.1938 -0.4064)
			(end -0.8636 -0.4064)
			(stroke
				(width 0.1)
				(type default)
			)
			(layer "F.Fab")
		)
		(fp_line
			(start -1.1938 0.4064)
			(end -1.1938 -0.4064)
			(stroke
				(width 0.1)
				(type default)
			)
			(layer "F.Fab")
		)
		(fp_line
			(start -0.8636 -0.4572)
			(end 0.8636 -0.4572)
			(stroke
				(width 0.1)
				(type default)
			)
			(layer "F.Fab")
		)
		(fp_line
			(start -0.8636 -0.4064)
			(end -0.8636 -0.4572)
			(stroke
				(width 0.1)
				(type default)
			)
			(layer "F.Fab")
		)
		(fp_line
			(start -0.8636 0.4064)
			(end -1.1938 0.4064)
			(stroke
				(width 0.1)
				(type default)
			)
			(layer "F.Fab")
		)
		(fp_line
			(start -0.8636 0.4572)
			(end -0.8636 0.4064)
			(stroke
				(width 0.1)
				(type default)
			)
			(layer "F.Fab")
		)
		(fp_line
			(start 0.8636 -0.4572)
			(end 0.8636 -0.4064)
			(stroke
				(width 0.1)
				(type default)
			)
			(layer "F.Fab")
		)
		(fp_line
			(start 0.8636 -0.4064)
			(end 1.1938 -0.4064)
			(stroke
				(width 0.1)
				(type default)
			)
			(layer "F.Fab")
		)
		(fp_line
			(start 0.8636 0.4064)
			(end 0.8636 0.4572)
			(stroke
				(width 0.1)
				(type default)
			)
			(layer "F.Fab")
		)
		(fp_line
			(start 0.8636 0.4572)
			(end -0.8636 0.4572)
			(stroke
				(width 0.1)
				(type default)
			)
			(layer "F.Fab")
		)
		(fp_line
			(start 1.1938 -0.4064)
			(end 1.1938 0.4064)
			(stroke
				(width 0.1)
				(type default)
			)
			(layer "F.Fab")
		)
		(fp_line
			(start 1.1938 0.4064)
			(end 0.8636 0.4064)
			(stroke
				(width 0.1)
				(type default)
			)
			(layer "F.Fab")
		)
		(pad "1" smd rect
			(at -0.7366 0 270)
			(size 0.7112 0.8128)
			(layers "F.Cu" "F.Mask" "F.Paste")
			(net "PCEPLL1_VDDA18_PEX3")
		)
		(pad "2" smd rect
			(at 0.7366 0 270)
			(size 0.7112 0.8128)
			(layers "F.Cu" "F.Mask" "F.Paste")
			(net "GND")
		)
	)
	(footprint ""
		(layer "F.Cu")
		(at 152.345898 -258.463034)
		(property "Reference" "C3219"
			(at 0 0 0)
			(layer "F.SilkS")
			(hide yes)
			(effects
				(font
					(size 1.27 1.27)
				)
			)
		)
		(property "Value" ""
			(at 0 0 0)
			(layer "F.Fab")
			(effects
				(font
					(size 1.27 1.27)
				)
			)
		)
		(duplicate_pad_numbers_are_jumpers no)
		(fp_line
			(start -1.2954 -0.5842)
			(end 1.2954 -0.5842)
			(stroke
				(width 0.1524)
				(type default)
			)
			(layer "F.SilkS")
		)
		(fp_line
			(start -1.2954 0.5842)
			(end -1.2954 -0.5842)
			(stroke
				(width 0.1524)
				(type default)
			)
			(layer "F.SilkS")
		)
		(fp_line
			(start 1.2954 -0.5842)
			(end 1.2954 0.5842)
			(stroke
				(width 0.1524)
				(type default)
			)
			(layer "F.SilkS")
		)
		(fp_line
			(start 1.2954 0.5842)
			(end -1.2954 0.5842)
			(stroke
				(width 0.1524)
				(type default)
			)
			(layer "F.SilkS")
		)
		(fp_line
			(start -1.1938 -0.4064)
			(end -0.8636 -0.4064)
			(stroke
				(width 0.1)
				(type default)
			)
			(layer "F.Fab")
		)
		(fp_line
			(start -1.1938 0.4064)
			(end -1.1938 -0.4064)
			(stroke
				(width 0.1)
				(type default)
			)
			(layer "F.Fab")
		)
		(fp_line
			(start -0.8636 -0.4572)
			(end 0.8636 -0.4572)
			(stroke
				(width 0.1)
				(type default)
			)
			(layer "F.Fab")
		)
		(fp_line
			(start -0.8636 -0.4064)
			(end -0.8636 -0.4572)
			(stroke
				(width 0.1)
				(type default)
			)
			(layer "F.Fab")
		)
		(fp_line
			(start -0.8636 0.4064)
			(end -1.1938 0.4064)
			(stroke
				(width 0.1)
				(type default)
			)
			(layer "F.Fab")
		)
		(fp_line
			(start -0.8636 0.4572)
			(end -0.8636 0.4064)
			(stroke
				(width 0.1)
				(type default)
			)
			(layer "F.Fab")
		)
		(fp_line
			(start 0.8636 -0.4572)
			(end 0.8636 -0.4064)
			(stroke
				(width 0.1)
				(type default)
			)
			(layer "F.Fab")
		)
		(fp_line
			(start 0.8636 -0.4064)
			(end 1.1938 -0.4064)
			(stroke
				(width 0.1)
				(type default)
			)
			(layer "F.Fab")
		)
		(fp_line
			(start 0.8636 0.4064)
			(end 0.8636 0.4572)
			(stroke
				(width 0.1)
				(type default)
			)
			(layer "F.Fab")
		)
		(fp_line
			(start 0.8636 0.4572)
			(end -0.8636 0.4572)
			(stroke
				(width 0.1)
				(type default)
			)
			(layer "F.Fab")
		)
		(fp_line
			(start 1.1938 -0.4064)
			(end 1.1938 0.4064)
			(stroke
				(width 0.1)
				(type default)
			)
			(layer "F.Fab")
		)
		(fp_line
			(start 1.1938 0.4064)
			(end 0.8636 0.4064)
			(stroke
				(width 0.1)
				(type default)
			)
			(layer "F.Fab")
		)
		(pad "1" smd rect
			(at -0.7366 0 270)
			(size 0.7112 0.8128)
			(layers "F.Cu" "F.Mask" "F.Paste")
			(net "PCEPLL5_VDDA18_PEX1")
		)
		(pad "2" smd rect
			(at 0.7366 0 270)
			(size 0.7112 0.8128)
			(layers "F.Cu" "F.Mask" "F.Paste")
			(net "GND")
		)
	)
	(footprint ""
		(layer "F.Cu")
		(at 120.815354 -59.546236 90)
		(property "Reference" "C2886"
			(at 0 0 90)
			(layer "F.SilkS")
			(hide yes)
			(effects
				(font
					(size 1.27 1.27)
				)
			)
		)
		(property "Value" ""
			(at 0 0 90)
			(layer "F.Fab")
			(effects
				(font
					(size 1.27 1.27)
				)
			)
		)
		(duplicate_pad_numbers_are_jumpers no)
		(fp_line
			(start 0.7874 -0.4064)
			(end 0.7874 0.4064)
			(stroke
				(width 0.1524)
				(type default)
			)
			(layer "F.SilkS")
		)
		(fp_line
			(start -0.7874 -0.4064)
			(end 0.7874 -0.4064)
			(stroke
				(width 0.1524)
				(type default)
			)
			(layer "F.SilkS")
		)
		(fp_line
			(start 0.7874 0.4064)
			(end -0.7874 0.4064)
			(stroke
				(width 0.1524)
				(type default)
			)
			(layer "F.SilkS")
		)
		(fp_line
			(start -0.7874 0.4064)
			(end -0.7874 -0.4064)
			(stroke
				(width 0.1524)
				(type default)
			)
			(layer "F.SilkS")
		)
		(fp_line
			(start -0.12065 -0.305054)
			(end -0.12065 -0.2794)
			(stroke
				(width 0.1)
				(type default)
			)
			(layer "F.Fab")
		)
		(fp_line
			(start -0.67945 -0.305054)
			(end -0.12065 -0.305054)
			(stroke
				(width 0.1)
				(type default)
			)
			(layer "F.Fab")
		)
		(fp_line
			(start 0.67945 -0.3048)
			(end 0.67945 0.3048)
			(stroke
				(width 0.1)
				(type default)
			)
			(layer "F.Fab")
		)
		(fp_line
			(start 0.12065 -0.3048)
			(end 0.67945 -0.3048)
			(stroke
				(width 0.1)
				(type default)
			)
			(layer "F.Fab")
		)
		(fp_line
			(start 0.12065 -0.2794)
			(end 0.12065 -0.3048)
			(stroke
				(width 0.1)
				(type default)
			)
			(layer "F.Fab")
		)
		(fp_line
			(start -0.12065 -0.2794)
			(end 0.12065 -0.2794)
			(stroke
				(width 0.1)
				(type default)
			)
			(layer "F.Fab")
		)
		(fp_line
			(start 0.120396 0.2794)
			(end -0.12065 0.2794)
			(stroke
				(width 0.1)
				(type default)
			)
			(layer "F.Fab")
		)
		(fp_line
			(start -0.12065 0.2794)
			(end -0.12065 0.3048)
			(stroke
				(width 0.1)
				(type default)
			)
			(layer "F.Fab")
		)
		(fp_line
			(start 0.67945 0.3048)
			(end 0.120396 0.3048)
			(stroke
				(width 0.1)
				(type default)
			)
			(layer "F.Fab")
		)
		(fp_line
			(start 0.120396 0.3048)
			(end 0.120396 0.2794)
			(stroke
				(width 0.1)
				(type default)
			)
			(layer "F.Fab")
		)
		(fp_line
			(start -0.12065 0.3048)
			(end -0.67945 0.3048)
			(stroke
				(width 0.1)
				(type default)
			)
			(layer "F.Fab")
		)
		(fp_line
			(start -0.67945 0.3048)
			(end -0.67945 -0.305054)
			(stroke
				(width 0.1)
				(type default)
			)
			(layer "F.Fab")
		)
		(pad "1" smd circle
			(at -0.40005 0 90)
			(size 0 0)
			(layers "F.Cu" "F.Mask" "F.Paste")
			(net "SSD4_AUX_P3V3_EN_R")
		)
		(pad "2" smd circle
			(at 0.40005 0 90)
			(size 0 0)
			(layers "F.Cu" "F.Mask" "F.Paste")
			(net "GND")
		)
	)
	(footprint ""
		(layer "F.Cu")
		(at 205.777592 -350.312482 90)
		(property "Reference" "R496"
			(at 0 0 90)
			(layer "F.SilkS")
			(hide yes)
			(effects
				(font
					(size 1.27 1.27)
				)
			)
		)
		(property "Value" ""
			(at 0 0 90)
			(layer "F.Fab")
			(effects
				(font
					(size 1.27 1.27)
				)
			)
		)
		(duplicate_pad_numbers_are_jumpers no)
		(fp_line
			(start 0.7874 -0.4064)
			(end 0.7874 0.4064)
			(stroke
				(width 0.1524)
				(type default)
			)
			(layer "F.SilkS")
		)
		(fp_line
			(start -0.7874 -0.4064)
			(end 0.7874 -0.4064)
			(stroke
				(width 0.1524)
				(type default)
			)
			(layer "F.SilkS")
		)
		(fp_line
			(start 0.7874 0.4064)
			(end -0.7874 0.4064)
			(stroke
				(width 0.1524)
				(type default)
			)
			(layer "F.SilkS")
		)
		(fp_line
			(start -0.7874 0.4064)
			(end -0.7874 -0.4064)
			(stroke
				(width 0.1524)
				(type default)
			)
			(layer "F.SilkS")
		)
		(fp_line
			(start -0.12065 -0.305054)
			(end -0.12065 -0.2794)
			(stroke
				(width 0.1)
				(type default)
			)
			(layer "F.Fab")
		)
		(fp_line
			(start -0.67945 -0.305054)
			(end -0.12065 -0.305054)
			(stroke
				(width 0.1)
				(type default)
			)
			(layer "F.Fab")
		)
		(fp_line
			(start 0.67945 -0.3048)
			(end 0.67945 0.3048)
			(stroke
				(width 0.1)
				(type default)
			)
			(layer "F.Fab")
		)
		(fp_line
			(start 0.12065 -0.3048)
			(end 0.67945 -0.3048)
			(stroke
				(width 0.1)
				(type default)
			)
			(layer "F.Fab")
		)
		(fp_line
			(start 0.12065 -0.2794)
			(end 0.12065 -0.3048)
			(stroke
				(width 0.1)
				(type default)
			)
			(layer "F.Fab")
		)
		(fp_line
			(start -0.12065 -0.2794)
			(end 0.12065 -0.2794)
			(stroke
				(width 0.1)
				(type default)
			)
			(layer "F.Fab")
		)
		(fp_line
			(start 0.120396 0.2794)
			(end -0.12065 0.2794)
			(stroke
				(width 0.1)
				(type default)
			)
			(layer "F.Fab")
		)
		(fp_line
			(start -0.12065 0.2794)
			(end -0.12065 0.3048)
			(stroke
				(width 0.1)
				(type default)
			)
			(layer "F.Fab")
		)
		(fp_line
			(start 0.67945 0.3048)
			(end 0.120396 0.3048)
			(stroke
				(width 0.1)
				(type default)
			)
			(layer "F.Fab")
		)
		(fp_line
			(start 0.120396 0.3048)
			(end 0.120396 0.2794)
			(stroke
				(width 0.1)
				(type default)
			)
			(layer "F.Fab")
		)
		(fp_line
			(start -0.12065 0.3048)
			(end -0.67945 0.3048)
			(stroke
				(width 0.1)
				(type default)
			)
			(layer "F.Fab")
		)
		(fp_line
			(start -0.67945 0.3048)
			(end -0.67945 -0.305054)
			(stroke
				(width 0.1)
				(type default)
			)
			(layer "F.Fab")
		)
		(pad "1" smd circle
			(at -0.40005 0 90)
			(size 0 0)
			(layers "F.Cu" "F.Mask" "F.Paste")
			(net "P3V3_AUX")
		)
		(pad "2" smd circle
			(at 0.40005 0 90)
			(size 0 0)
			(layers "F.Cu" "F.Mask" "F.Paste")
			(net "HSC_D_OC_BUF_N")
		)
	)
	(footprint ""
		(layer "F.Cu")
		(at 134.026656 -25.432004 -90)
		(property "Reference" "C969"
			(at 0 0 270)
			(layer "F.SilkS")
			(hide yes)
			(effects
				(font
					(size 1.27 1.27)
				)
			)
		)
		(property "Value" ""
			(at 0 0 270)
			(layer "F.Fab")
			(effects
				(font
					(size 1.27 1.27)
				)
			)
		)
		(duplicate_pad_numbers_are_jumpers no)
		(fp_line
			(start -0.7874 0.4064)
			(end -0.7874 -0.4064)
			(stroke
				(width 0.1524)
				(type default)
			)
			(layer "F.SilkS")
		)
		(fp_line
			(start 0.7874 0.4064)
			(end -0.7874 0.4064)
			(stroke
				(width 0.1524)
				(type default)
			)
			(layer "F.SilkS")
		)
		(fp_line
			(start -0.7874 -0.4064)
			(end 0.7874 -0.4064)
			(stroke
				(width 0.1524)
				(type default)
			)
			(layer "F.SilkS")
		)
		(fp_line
			(start 0.7874 -0.4064)
			(end 0.7874 0.4064)
			(stroke
				(width 0.1524)
				(type default)
			)
			(layer "F.SilkS")
		)
		(fp_line
			(start -0.67945 0.3048)
			(end -0.67945 -0.305054)
			(stroke
				(width 0.1)
				(type default)
			)
			(layer "F.Fab")
		)
		(fp_line
			(start -0.12065 0.3048)
			(end -0.67945 0.3048)
			(stroke
				(width 0.1)
				(type default)
			)
			(layer "F.Fab")
		)
		(fp_line
			(start 0.120396 0.3048)
			(end 0.120396 0.2794)
			(stroke
				(width 0.1)
				(type default)
			)
			(layer "F.Fab")
		)
		(fp_line
			(start 0.67945 0.3048)
			(end 0.120396 0.3048)
			(stroke
				(width 0.1)
				(type default)
			)
			(layer "F.Fab")
		)
		(fp_line
			(start -0.12065 0.2794)
			(end -0.12065 0.3048)
			(stroke
				(width 0.1)
				(type default)
			)
			(layer "F.Fab")
		)
		(fp_line
			(start 0.120396 0.2794)
			(end -0.12065 0.2794)
			(stroke
				(width 0.1)
				(type default)
			)
			(layer "F.Fab")
		)
		(fp_line
			(start -0.12065 -0.2794)
			(end 0.12065 -0.2794)
			(stroke
				(width 0.1)
				(type default)
			)
			(layer "F.Fab")
		)
		(fp_line
			(start 0.12065 -0.2794)
			(end 0.12065 -0.3048)
			(stroke
				(width 0.1)
				(type default)
			)
			(layer "F.Fab")
		)
		(fp_line
			(start 0.12065 -0.3048)
			(end 0.67945 -0.3048)
			(stroke
				(width 0.1)
				(type default)
			)
			(layer "F.Fab")
		)
		(fp_line
			(start 0.67945 -0.3048)
			(end 0.67945 0.3048)
			(stroke
				(width 0.1)
				(type default)
			)
			(layer "F.Fab")
		)
		(fp_line
			(start -0.67945 -0.305054)
			(end -0.12065 -0.305054)
			(stroke
				(width 0.1)
				(type default)
			)
			(layer "F.Fab")
		)
		(fp_line
			(start -0.12065 -0.305054)
			(end -0.12065 -0.2794)
			(stroke
				(width 0.1)
				(type default)
			)
			(layer "F.Fab")
		)
		(pad "1" smd circle
			(at -0.40005 0 270)
			(size 0 0)
			(layers "F.Cu" "F.Mask" "F.Paste")
			(net "GND")
		)
		(pad "2" smd circle
			(at 0.40005 0 270)
			(size 0 0)
			(layers "F.Cu" "F.Mask" "F.Paste")
			(net "P3V3_SSD4")
		)
	)
	(footprint ""
		(layer "F.Cu")
		(at 220.36786 -56.353456)
		(property "Reference" "C2868"
			(at 0 0 0)
			(layer "F.SilkS")
			(hide yes)
			(effects
				(font
					(size 1.27 1.27)
				)
			)
		)
		(property "Value" ""
			(at 0 0 0)
			(layer "F.Fab")
			(effects
				(font
					(size 1.27 1.27)
				)
			)
		)
		(duplicate_pad_numbers_are_jumpers no)
		(fp_line
			(start -0.7874 -0.4064)
			(end 0.7874 -0.4064)
			(stroke
				(width 0.1524)
				(type default)
			)
			(layer "F.SilkS")
		)
		(fp_line
			(start -0.7874 0.4064)
			(end -0.7874 -0.4064)
			(stroke
				(width 0.1524)
				(type default)
			)
			(layer "F.SilkS")
		)
		(fp_line
			(start 0.7874 -0.4064)
			(end 0.7874 0.4064)
			(stroke
				(width 0.1524)
				(type default)
			)
			(layer "F.SilkS")
		)
		(fp_line
			(start 0.7874 0.4064)
			(end -0.7874 0.4064)
			(stroke
				(width 0.1524)
				(type default)
			)
			(layer "F.SilkS")
		)
		(fp_line
			(start -0.67945 -0.305054)
			(end -0.12065 -0.305054)
			(stroke
				(width 0.1)
				(type default)
			)
			(layer "F.Fab")
		)
		(fp_line
			(start -0.67945 0.3048)
			(end -0.67945 -0.305054)
			(stroke
				(width 0.1)
				(type default)
			)
			(layer "F.Fab")
		)
		(fp_line
			(start -0.12065 -0.305054)
			(end -0.12065 -0.2794)
			(stroke
				(width 0.1)
				(type default)
			)
			(layer "F.Fab")
		)
		(fp_line
			(start -0.12065 -0.2794)
			(end 0.12065 -0.2794)
			(stroke
				(width 0.1)
				(type default)
			)
			(layer "F.Fab")
		)
		(fp_line
			(start -0.12065 0.2794)
			(end -0.12065 0.3048)
			(stroke
				(width 0.1)
				(type default)
			)
			(layer "F.Fab")
		)
		(fp_line
			(start -0.12065 0.3048)
			(end -0.67945 0.3048)
			(stroke
				(width 0.1)
				(type default)
			)
			(layer "F.Fab")
		)
		(fp_line
			(start 0.120396 0.2794)
			(end -0.12065 0.2794)
			(stroke
				(width 0.1)
				(type default)
			)
			(layer "F.Fab")
		)
		(fp_line
			(start 0.120396 0.3048)
			(end 0.120396 0.2794)
			(stroke
				(width 0.1)
				(type default)
			)
			(layer "F.Fab")
		)
		(fp_line
			(start 0.12065 -0.3048)
			(end 0.67945 -0.3048)
			(stroke
				(width 0.1)
				(type default)
			)
			(layer "F.Fab")
		)
		(fp_line
			(start 0.12065 -0.2794)
			(end 0.12065 -0.3048)
			(stroke
				(width 0.1)
				(type default)
			)
			(layer "F.Fab")
		)
		(fp_line
			(start 0.67945 -0.3048)
			(end 0.67945 0.3048)
			(stroke
				(width 0.1)
				(type default)
			)
			(layer "F.Fab")
		)
		(fp_line
			(start 0.67945 0.3048)
			(end 0.120396 0.3048)
			(stroke
				(width 0.1)
				(type default)
			)
			(layer "F.Fab")
		)
		(pad "1" smd circle
			(at -0.40005 0)
			(size 0 0)
			(layers "F.Cu" "F.Mask" "F.Paste")
			(net "SSD7_PWR_EN_R")
		)
		(pad "2" smd circle
			(at 0.40005 0)
			(size 0 0)
			(layers "F.Cu" "F.Mask" "F.Paste")
			(net "GND")
		)
	)
	(footprint ""
		(layer "F.Cu")
		(at 134.76859 -149.313392 -90)
		(property "Reference" "U81"
			(at 0.012192 -2.44348 90)
			(unlocked yes)
			(layer "F.SilkS")
			(effects
				(font
					(size 0.7874 0.5842)
					(thickness 0.1524)
				)
			)
		)
		(property "Value" ""
			(at 0 0 270)
			(layer "F.Fab")
			(effects
				(font
					(size 1.27 1.27)
				)
			)
		)
		(duplicate_pad_numbers_are_jumpers no)
		(fp_line
			(start -1.500124 1.500124)
			(end -1.500124 1.004062)
			(stroke
				(width 0.1524)
				(type default)
			)
			(layer "F.SilkS")
		)
		(fp_line
			(start -1.004062 1.500124)
			(end -1.500124 1.500124)
			(stroke
				(width 0.1524)
				(type default)
			)
			(layer "F.SilkS")
		)
		(fp_line
			(start 1.500124 1.500124)
			(end 1.004062 1.500124)
			(stroke
				(width 0.1524)
				(type default)
			)
			(layer "F.SilkS")
		)
		(fp_line
			(start 1.500124 1.004062)
			(end 1.500124 1.500124)
			(stroke
				(width 0.1524)
				(type default)
			)
			(layer "F.SilkS")
		)
		(fp_line
			(start -1.500124 -1.004062)
			(end -1.500124 -1.500124)
			(stroke
				(width 0.1524)
				(type default)
			)
			(layer "F.SilkS")
		)
		(fp_line
			(start -1.500124 -1.500124)
			(end -1.004062 -1.500124)
			(stroke
				(width 0.1524)
				(type default)
			)
			(layer "F.SilkS")
		)
		(fp_line
			(start 1.004062 -1.500124)
			(end 1.500124 -1.500124)
			(stroke
				(width 0.1524)
				(type default)
			)
			(layer "F.SilkS")
		)
		(fp_line
			(start 1.500124 -1.500124)
			(end 1.500124 -1.004062)
			(stroke
				(width 0.1524)
				(type default)
			)
			(layer "F.SilkS")
		)
		(fp_poly
			(pts
				(xy -1.963166 -2.07772) (xy -2.681732 -1.359408) (xy -1.60401 -1.000252)
			)
			(stroke
				(width 0)
				(type default)
			)
			(fill yes)
			(layer "F.SilkS")
		)
		(fp_line
			(start -1.500124 1.500124)
			(end -1.500124 -1.500124)
			(stroke
				(width 0.1)
				(type default)
			)
			(layer "F.Fab")
		)
		(fp_line
			(start 1.500124 1.500124)
			(end -1.500124 1.500124)
			(stroke
				(width 0.1)
				(type default)
			)
			(layer "F.Fab")
		)
		(fp_line
			(start -1.500124 -1.500124)
			(end 1.500124 -1.500124)
			(stroke
				(width 0.1)
				(type default)
			)
			(layer "F.Fab")
		)
		(fp_line
			(start 1.500124 -1.500124)
			(end 1.500124 1.500124)
			(stroke
				(width 0.1)
				(type default)
			)
			(layer "F.Fab")
		)
		(fp_poly
			(pts
				(xy -2.847848 -1.258062) (xy -2.847848 -0.242062) (xy -1.831848 -0.750062)
			)
			(stroke
				(width 0)
				(type default)
			)
			(fill yes)
			(layer "F.Fab")
		)
		(pad "1" smd rect
			(at -1.400048 -0.750062 180)
			(size 0.2286 0.6096)
			(layers "F.Cu" "F.Mask" "F.Paste")
			(net "NIC2_ADC_A1")
		)
		(pad "2" smd rect
			(at -1.400048 -0.249936 180)
			(size 0.2286 0.6096)
			(layers "F.Cu" "F.Mask" "F.Paste")
			(net "NIC2_ADC_A0")
		)
		(pad "3" smd rect
			(at -1.400048 0.249936 180)
			(size 0.2286 0.6096)
			(layers "F.Cu" "F.Mask" "F.Paste")
			(net "NIC2_ADC_ALERT_N")
		)
		(pad "4" smd rect
			(at -1.400048 0.750062 180)
			(size 0.2286 0.6096)
			(layers "F.Cu" "F.Mask" "F.Paste")
			(net "SMB_NIC2_ADC_SDA")
		)
		(pad "5" smd rect
			(at -0.750062 1.400048 270)
			(size 0.2286 0.6096)
			(layers "F.Cu" "F.Mask" "F.Paste")
			(net "SMB_NIC2_ADC_SCL")
		)
		(pad "6" smd rect
			(at -0.249936 1.400048 270)
			(size 0.2286 0.6096)
			(layers "F.Cu" "F.Mask" "F.Paste")
			(net "Net_8654")
		)
		(pad "7" smd rect
			(at 0.249936 1.400048 270)
			(size 0.2286 0.6096)
			(layers "F.Cu" "F.Mask" "F.Paste")
			(net "Net_8653")
		)
		(pad "8" smd rect
			(at 0.750062 1.400048 270)
			(size 0.2286 0.6096)
			(layers "F.Cu" "F.Mask" "F.Paste")
			(net "Net_8652")
		)
		(pad "9" smd rect
			(at 1.400048 0.750062 180)
			(size 0.2286 0.6096)
			(layers "F.Cu" "F.Mask" "F.Paste")
			(net "P3V3_AUX")
		)
		(pad "10" smd rect
			(at 1.400048 0.249936 180)
			(size 0.2286 0.6096)
			(layers "F.Cu" "F.Mask" "F.Paste")
			(net "GND")
		)
		(pad "11" smd rect
			(at 1.400048 -0.249936 180)
			(size 0.2286 0.6096)
			(layers "F.Cu" "F.Mask" "F.Paste")
			(net "P12V_NIC2_R")
		)
		(pad "12" smd rect
			(at 1.400048 -0.750062 180)
			(size 0.2286 0.6096)
			(layers "F.Cu" "F.Mask" "F.Paste")
			(net "P12V_NIC2_VIN_N")
		)
		(pad "13" smd rect
			(at 0.750062 -1.400048 270)
			(size 0.2286 0.6096)
			(layers "F.Cu" "F.Mask" "F.Paste")
			(net "P12V_NIC2_VIN_P")
		)
		(pad "14" smd rect
			(at 0.249936 -1.400048 270)
			(size 0.2286 0.6096)
			(layers "F.Cu" "F.Mask" "F.Paste")
			(net "Net_8651")
		)
		(pad "15" smd rect
			(at -0.249936 -1.400048 270)
			(size 0.2286 0.6096)
			(layers "F.Cu" "F.Mask" "F.Paste")
			(net "Net_8650")
		)
		(pad "16" smd rect
			(at -0.750062 -1.400048 270)
			(size 0.2286 0.6096)
			(layers "F.Cu" "F.Mask" "F.Paste")
			(net "Net_8649")
		)
		(pad "TH" smd rect
			(at 0 0 270)
			(size 1.7018 1.7018)
			(layers "F.Cu" "F.Mask" "F.Paste")
			(net "GND")
		)
		(zone
			(layer "F.Cu")
			(hatch none 0.5)
			(connect_pads
				(clearance 0)
			)
			(min_thickness 0.25)
			(keepout
				(tracks not_allowed)
				(vias allowed)
				(pads allowed)
				(copperpour not_allowed)
				(footprints allowed)
			)
			(placement
				(enabled no)
				(sheetname "")
			)
			(fill
				(thermal_gap 0.5)
				(thermal_bridge_width 0.5)
				(island_removal_mode 0)
			)
			(polygon
				(pts
					(xy 134.79399 -150.35784) (xy 135.813038 -150.35784) (xy 135.813038 -148.268944) (xy 133.724142 -148.268944)
					(xy 133.724142 -150.35784) (xy 134.76859 -150.35784) (xy 134.76859 -150.215092) (xy 133.86689 -150.215092)
					(xy 133.86689 -148.411692) (xy 135.67029 -148.411692) (xy 135.67029 -150.215092) (xy 134.79399 -150.215092)
				)
			)
		)
	)
	(footprint ""
		(layer "F.Cu")
		(at 399.14322 -350.098614 90)
		(property "Reference" "C734"
			(at 0 0 90)
			(layer "F.SilkS")
			(hide yes)
			(effects
				(font
					(size 1.27 1.27)
				)
			)
		)
		(property "Value" ""
			(at 0 0 90)
			(layer "F.Fab")
			(effects
				(font
					(size 1.27 1.27)
				)
			)
		)
		(duplicate_pad_numbers_are_jumpers no)
		(fp_line
			(start 0.299974 -0.150114)
			(end 0.299974 0.150114)
			(stroke
				(width 0.1)
				(type default)
			)
			(layer "F.Fab")
		)
		(fp_line
			(start -0.299974 -0.150114)
			(end 0.299974 -0.150114)
			(stroke
				(width 0.1)
				(type default)
			)
			(layer "F.Fab")
		)
		(fp_line
			(start 0.299974 0.150114)
			(end -0.299974 0.150114)
			(stroke
				(width 0.1)
				(type default)
			)
			(layer "F.Fab")
		)
		(fp_line
			(start -0.299974 0.150114)
			(end -0.299974 -0.150114)
			(stroke
				(width 0.1)
				(type default)
			)
			(layer "F.Fab")
		)
		(pad "1" smd rect
			(at -0.2667 0 90)
			(size 0.3048 0.381)
			(layers "F.Cu" "F.Mask" "F.Paste")
			(net "P5E_PEX3_STN5_TX_DP<93>")
		)
		(pad "2" smd rect
			(at 0.2667 0 90)
			(size 0.3048 0.381)
			(layers "F.Cu" "F.Mask" "F.Paste")
			(net "P5E_PEX3_STN5_TX_C_DP<93>")
		)
	)
	(footprint ""
		(layer "F.Cu")
		(at 149.080728 -379.396498)
		(property "Reference" "R1838"
			(at 0 0 0)
			(layer "F.SilkS")
			(hide yes)
			(effects
				(font
					(size 1.27 1.27)
				)
			)
		)
		(property "Value" ""
			(at 0 0 0)
			(layer "F.Fab")
			(effects
				(font
					(size 1.27 1.27)
				)
			)
		)
		(duplicate_pad_numbers_are_jumpers no)
		(fp_line
			(start -0.7874 -0.4064)
			(end 0.7874 -0.4064)
			(stroke
				(width 0.1524)
				(type default)
			)
			(layer "F.SilkS")
		)
		(fp_line
			(start -0.7874 0.4064)
			(end -0.7874 -0.4064)
			(stroke
				(width 0.1524)
				(type default)
			)
			(layer "F.SilkS")
		)
		(fp_line
			(start 0.7874 -0.4064)
			(end 0.7874 0.4064)
			(stroke
				(width 0.1524)
				(type default)
			)
			(layer "F.SilkS")
		)
		(fp_line
			(start 0.7874 0.4064)
			(end -0.7874 0.4064)
			(stroke
				(width 0.1524)
				(type default)
			)
			(layer "F.SilkS")
		)
		(fp_line
			(start -0.67945 -0.305054)
			(end -0.12065 -0.305054)
			(stroke
				(width 0.1)
				(type default)
			)
			(layer "F.Fab")
		)
		(fp_line
			(start -0.67945 0.3048)
			(end -0.67945 -0.305054)
			(stroke
				(width 0.1)
				(type default)
			)
			(layer "F.Fab")
		)
		(fp_line
			(start -0.12065 -0.305054)
			(end -0.12065 -0.2794)
			(stroke
				(width 0.1)
				(type default)
			)
			(layer "F.Fab")
		)
		(fp_line
			(start -0.12065 -0.2794)
			(end 0.12065 -0.2794)
			(stroke
				(width 0.1)
				(type default)
			)
			(layer "F.Fab")
		)
		(fp_line
			(start -0.12065 0.2794)
			(end -0.12065 0.3048)
			(stroke
				(width 0.1)
				(type default)
			)
			(layer "F.Fab")
		)
		(fp_line
			(start -0.12065 0.3048)
			(end -0.67945 0.3048)
			(stroke
				(width 0.1)
				(type default)
			)
			(layer "F.Fab")
		)
		(fp_line
			(start 0.120396 0.2794)
			(end -0.12065 0.2794)
			(stroke
				(width 0.1)
				(type default)
			)
			(layer "F.Fab")
		)
		(fp_line
			(start 0.120396 0.3048)
			(end 0.120396 0.2794)
			(stroke
				(width 0.1)
				(type default)
			)
			(layer "F.Fab")
		)
		(fp_line
			(start 0.12065 -0.3048)
			(end 0.67945 -0.3048)
			(stroke
				(width 0.1)
				(type default)
			)
			(layer "F.Fab")
		)
		(fp_line
			(start 0.12065 -0.2794)
			(end 0.12065 -0.3048)
			(stroke
				(width 0.1)
				(type default)
			)
			(layer "F.Fab")
		)
		(fp_line
			(start 0.67945 -0.3048)
			(end 0.67945 0.3048)
			(stroke
				(width 0.1)
				(type default)
			)
			(layer "F.Fab")
		)
		(fp_line
			(start 0.67945 0.3048)
			(end 0.120396 0.3048)
			(stroke
				(width 0.1)
				(type default)
			)
			(layer "F.Fab")
		)
		(pad "1" smd circle
			(at -0.40005 0)
			(size 0 0)
			(layers "F.Cu" "F.Mask" "F.Paste")
			(net "GPU_FPGA_EROT_FATALERR_R_N")
		)
		(pad "2" smd circle
			(at 0.40005 0)
			(size 0 0)
			(layers "F.Cu" "F.Mask" "F.Paste")
			(net "GPU_FPGA_EROT_FATALERR_N")
		)
	)
	(footprint ""
		(layer "F.Cu")
		(at 339.75294 -80.607662 90)
		(property "Reference" "R1175"
			(at 0 0 90)
			(layer "F.SilkS")
			(hide yes)
			(effects
				(font
					(size 1.27 1.27)
				)
			)
		)
		(property "Value" ""
			(at 0 0 90)
			(layer "F.Fab")
			(effects
				(font
					(size 1.27 1.27)
				)
			)
		)
		(duplicate_pad_numbers_are_jumpers no)
		(fp_line
			(start 0.7874 0.4064)
			(end -0.7874 0.4064)
			(stroke
				(width 0.1524)
				(type default)
			)
			(layer "F.SilkS")
		)
		(fp_line
			(start -0.12065 -0.305054)
			(end -0.12065 -0.2794)
			(stroke
				(width 0.1)
				(type default)
			)
			(layer "F.Fab")
		)
		(fp_line
			(start -0.67945 -0.305054)
			(end -0.12065 -0.305054)
			(stroke
				(width 0.1)
				(type default)
			)
			(layer "F.Fab")
		)
		(fp_line
			(start 0.67945 -0.3048)
			(end 0.67945 0.3048)
			(stroke
				(width 0.1)
				(type default)
			)
			(layer "F.Fab")
		)
		(fp_line
			(start 0.12065 -0.3048)
			(end 0.67945 -0.3048)
			(stroke
				(width 0.1)
				(type default)
			)
			(layer "F.Fab")
		)
		(fp_line
			(start 0.12065 -0.2794)
			(end 0.12065 -0.3048)
			(stroke
				(width 0.1)
				(type default)
			)
			(layer "F.Fab")
		)
		(fp_line
			(start -0.12065 -0.2794)
			(end 0.12065 -0.2794)
			(stroke
				(width 0.1)
				(type default)
			)
			(layer "F.Fab")
		)
		(fp_line
			(start 0.120396 0.2794)
			(end -0.12065 0.2794)
			(stroke
				(width 0.1)
				(type default)
			)
			(layer "F.Fab")
		)
		(fp_line
			(start -0.12065 0.2794)
			(end -0.12065 0.3048)
			(stroke
				(width 0.1)
				(type default)
			)
			(layer "F.Fab")
		)
		(fp_line
			(start 0.67945 0.3048)
			(end 0.120396 0.3048)
			(stroke
				(width 0.1)
				(type default)
			)
			(layer "F.Fab")
		)
		(fp_line
			(start 0.120396 0.3048)
			(end 0.120396 0.2794)
			(stroke
				(width 0.1)
				(type default)
			)
			(layer "F.Fab")
		)
		(fp_line
			(start -0.12065 0.3048)
			(end -0.67945 0.3048)
			(stroke
				(width 0.1)
				(type default)
			)
			(layer "F.Fab")
		)
		(fp_line
			(start -0.67945 0.3048)
			(end -0.67945 -0.305054)
			(stroke
				(width 0.1)
				(type default)
			)
			(layer "F.Fab")
		)
		(pad "1" smd circle
			(at -0.40005 0 90)
			(size 0 0)
			(layers "F.Cu" "F.Mask" "F.Paste")
			(net "CLK_100M_DB800ZL_SSD10_R_DN")
		)
		(pad "2" smd circle
			(at 0.40005 0 90)
			(size 0 0)
			(layers "F.Cu" "F.Mask" "F.Paste")
			(net "CLK_100M_DB800ZL_SSD10_DN")
		)
	)
	(footprint ""
		(layer "F.Cu")
		(at 312.541666 -27.006296 -90)
		(property "Reference" "PR7122"
			(at 0 0 270)
			(layer "F.SilkS")
			(hide yes)
			(effects
				(font
					(size 1.27 1.27)
				)
			)
		)
		(property "Value" ""
			(at 0 0 270)
			(layer "F.Fab")
			(effects
				(font
					(size 1.27 1.27)
				)
			)
		)
		(duplicate_pad_numbers_are_jumpers no)
		(fp_line
			(start -0.7874 0.4064)
			(end -0.7874 -0.4064)
			(stroke
				(width 0.1524)
				(type default)
			)
			(layer "F.SilkS")
		)
		(fp_line
			(start 0.7874 0.4064)
			(end -0.7874 0.4064)
			(stroke
				(width 0.1524)
				(type default)
			)
			(layer "F.SilkS")
		)
		(fp_line
			(start -0.7874 -0.4064)
			(end 0.7874 -0.4064)
			(stroke
				(width 0.1524)
				(type default)
			)
			(layer "F.SilkS")
		)
		(fp_line
			(start 0.7874 -0.4064)
			(end 0.7874 0.4064)
			(stroke
				(width 0.1524)
				(type default)
			)
			(layer "F.SilkS")
		)
		(fp_line
			(start -0.67945 0.3048)
			(end -0.67945 -0.305054)
			(stroke
				(width 0.1)
				(type default)
			)
			(layer "F.Fab")
		)
		(fp_line
			(start -0.12065 0.3048)
			(end -0.67945 0.3048)
			(stroke
				(width 0.1)
				(type default)
			)
			(layer "F.Fab")
		)
		(fp_line
			(start 0.120396 0.3048)
			(end 0.120396 0.2794)
			(stroke
				(width 0.1)
				(type default)
			)
			(layer "F.Fab")
		)
		(fp_line
			(start 0.67945 0.3048)
			(end 0.120396 0.3048)
			(stroke
				(width 0.1)
				(type default)
			)
			(layer "F.Fab")
		)
		(fp_line
			(start -0.12065 0.2794)
			(end -0.12065 0.3048)
			(stroke
				(width 0.1)
				(type default)
			)
			(layer "F.Fab")
		)
		(fp_line
			(start 0.120396 0.2794)
			(end -0.12065 0.2794)
			(stroke
				(width 0.1)
				(type default)
			)
			(layer "F.Fab")
		)
		(fp_line
			(start -0.12065 -0.2794)
			(end 0.12065 -0.2794)
			(stroke
				(width 0.1)
				(type default)
			)
			(layer "F.Fab")
		)
		(fp_line
			(start 0.12065 -0.2794)
			(end 0.12065 -0.3048)
			(stroke
				(width 0.1)
				(type default)
			)
			(layer "F.Fab")
		)
		(fp_line
			(start 0.12065 -0.3048)
			(end 0.67945 -0.3048)
			(stroke
				(width 0.1)
				(type default)
			)
			(layer "F.Fab")
		)
		(fp_line
			(start 0.67945 -0.3048)
			(end 0.67945 0.3048)
			(stroke
				(width 0.1)
				(type default)
			)
			(layer "F.Fab")
		)
		(fp_line
			(start -0.67945 -0.305054)
			(end -0.12065 -0.305054)
			(stroke
				(width 0.1)
				(type default)
			)
			(layer "F.Fab")
		)
		(fp_line
			(start -0.12065 -0.305054)
			(end -0.12065 -0.2794)
			(stroke
				(width 0.1)
				(type default)
			)
			(layer "F.Fab")
		)
		(pad "1" smd circle
			(at -0.40005 0 270)
			(size 0 0)
			(layers "F.Cu" "F.Mask" "F.Paste")
			(net "P3V3_SSD11_CO_ILIMIT")
		)
		(pad "2" smd circle
			(at 0.40005 0 270)
			(size 0 0)
			(layers "F.Cu" "F.Mask" "F.Paste")
			(net "GND")
		)
	)
	(footprint ""
		(layer "F.Cu")
		(at 106.614214 -219.111576)
		(property "Reference" "PC287"
			(at 0 0 0)
			(layer "F.SilkS")
			(hide yes)
			(effects
				(font
					(size 1.27 1.27)
				)
			)
		)
		(property "Value" ""
			(at 0 0 0)
			(layer "F.Fab")
			(effects
				(font
					(size 1.27 1.27)
				)
			)
		)
		(duplicate_pad_numbers_are_jumpers no)
		(fp_line
			(start -1.524 -0.762)
			(end 1.524 -0.762)
			(stroke
				(width 0.1524)
				(type default)
			)
			(layer "F.SilkS")
		)
		(fp_line
			(start -1.524 0.762)
			(end -1.524 -0.762)
			(stroke
				(width 0.1524)
				(type default)
			)
			(layer "F.SilkS")
		)
		(fp_line
			(start 1.524 -0.762)
			(end 1.524 0.762)
			(stroke
				(width 0.1524)
				(type default)
			)
			(layer "F.SilkS")
		)
		(fp_line
			(start 1.524 0.762)
			(end -1.524 0.762)
			(stroke
				(width 0.1524)
				(type default)
			)
			(layer "F.SilkS")
		)
		(fp_line
			(start -1.1049 -0.724916)
			(end -1.1049 0.724916)
			(stroke
				(width 0.1)
				(type default)
			)
			(layer "F.Fab")
		)
		(fp_line
			(start -1.1049 0.724916)
			(end 1.1049 0.724916)
			(stroke
				(width 0.1)
				(type default)
			)
			(layer "F.Fab")
		)
		(fp_line
			(start 1.1049 -0.724916)
			(end -1.1049 -0.724916)
			(stroke
				(width 0.1)
				(type default)
			)
			(layer "F.Fab")
		)
		(fp_line
			(start 1.1049 0.724916)
			(end 1.1049 -0.724916)
			(stroke
				(width 0.1)
				(type default)
			)
			(layer "F.Fab")
		)
		(pad "1" smd rect
			(at -0.889 0 180)
			(size 1.016 1.27)
			(layers "F.Cu" "F.Mask" "F.Paste")
			(net "SW_P12V_P1V8_PEX_FLT")
		)
		(pad "2" smd rect
			(at 0.889 0 180)
			(size 1.016 1.27)
			(layers "F.Cu" "F.Mask" "F.Paste")
			(net "GND")
		)
	)
	(footprint ""
		(layer "F.Cu")
		(at 235.707936 -257.975862 -90)
		(property "Reference" "R6521"
			(at 0 0 270)
			(layer "F.SilkS")
			(hide yes)
			(effects
				(font
					(size 1.27 1.27)
				)
			)
		)
		(property "Value" ""
			(at 0 0 270)
			(layer "F.Fab")
			(effects
				(font
					(size 1.27 1.27)
				)
			)
		)
		(duplicate_pad_numbers_are_jumpers no)
		(fp_line
			(start -0.7874 0.4064)
			(end -0.7874 -0.4064)
			(stroke
				(width 0.1524)
				(type default)
			)
			(layer "F.SilkS")
		)
		(fp_line
			(start 0.7874 0.4064)
			(end -0.7874 0.4064)
			(stroke
				(width 0.1524)
				(type default)
			)
			(layer "F.SilkS")
		)
		(fp_line
			(start -0.7874 -0.4064)
			(end 0.7874 -0.4064)
			(stroke
				(width 0.1524)
				(type default)
			)
			(layer "F.SilkS")
		)
		(fp_line
			(start 0.7874 -0.4064)
			(end 0.7874 0.4064)
			(stroke
				(width 0.1524)
				(type default)
			)
			(layer "F.SilkS")
		)
		(fp_line
			(start -0.67945 0.3048)
			(end -0.67945 -0.305054)
			(stroke
				(width 0.1)
				(type default)
			)
			(layer "F.Fab")
		)
		(fp_line
			(start -0.12065 0.3048)
			(end -0.67945 0.3048)
			(stroke
				(width 0.1)
				(type default)
			)
			(layer "F.Fab")
		)
		(fp_line
			(start 0.120396 0.3048)
			(end 0.120396 0.2794)
			(stroke
				(width 0.1)
				(type default)
			)
			(layer "F.Fab")
		)
		(fp_line
			(start 0.67945 0.3048)
			(end 0.120396 0.3048)
			(stroke
				(width 0.1)
				(type default)
			)
			(layer "F.Fab")
		)
		(fp_line
			(start -0.12065 0.2794)
			(end -0.12065 0.3048)
			(stroke
				(width 0.1)
				(type default)
			)
			(layer "F.Fab")
		)
		(fp_line
			(start 0.120396 0.2794)
			(end -0.12065 0.2794)
			(stroke
				(width 0.1)
				(type default)
			)
			(layer "F.Fab")
		)
		(fp_line
			(start -0.12065 -0.2794)
			(end 0.12065 -0.2794)
			(stroke
				(width 0.1)
				(type default)
			)
			(layer "F.Fab")
		)
		(fp_line
			(start 0.12065 -0.2794)
			(end 0.12065 -0.3048)
			(stroke
				(width 0.1)
				(type default)
			)
			(layer "F.Fab")
		)
		(fp_line
			(start 0.12065 -0.3048)
			(end 0.67945 -0.3048)
			(stroke
				(width 0.1)
				(type default)
			)
			(layer "F.Fab")
		)
		(fp_line
			(start 0.67945 -0.3048)
			(end 0.67945 0.3048)
			(stroke
				(width 0.1)
				(type default)
			)
			(layer "F.Fab")
		)
		(fp_line
			(start -0.67945 -0.305054)
			(end -0.12065 -0.305054)
			(stroke
				(width 0.1)
				(type default)
			)
			(layer "F.Fab")
		)
		(fp_line
			(start -0.12065 -0.305054)
			(end -0.12065 -0.2794)
			(stroke
				(width 0.1)
				(type default)
			)
			(layer "F.Fab")
		)
		(pad "1" smd circle
			(at -0.40005 0 270)
			(size 0 0)
			(layers "F.Cu" "F.Mask" "F.Paste")
			(net "P1V25_SERDES_VDDPLL_PEX2")
		)
		(pad "2" smd circle
			(at 0.40005 0 270)
			(size 0 0)
			(layers "F.Cu" "F.Mask" "F.Paste")
			(net "P1V25_SERDES_VDDPLL_PEX2_C0")
		)
	)
	(footprint ""
		(layer "F.Cu")
		(at 268.838426 -104.695498)
		(property "Reference" "C479"
			(at 0 0 0)
			(layer "F.SilkS")
			(hide yes)
			(effects
				(font
					(size 1.27 1.27)
				)
			)
		)
		(property "Value" ""
			(at 0 0 0)
			(layer "F.Fab")
			(effects
				(font
					(size 1.27 1.27)
				)
			)
		)
		(duplicate_pad_numbers_are_jumpers no)
		(fp_line
			(start -0.299974 -0.150114)
			(end 0.299974 -0.150114)
			(stroke
				(width 0.1)
				(type default)
			)
			(layer "F.Fab")
		)
		(fp_line
			(start -0.299974 0.150114)
			(end -0.299974 -0.150114)
			(stroke
				(width 0.1)
				(type default)
			)
			(layer "F.Fab")
		)
		(fp_line
			(start 0.299974 -0.150114)
			(end 0.299974 0.150114)
			(stroke
				(width 0.1)
				(type default)
			)
			(layer "F.Fab")
		)
		(fp_line
			(start 0.299974 0.150114)
			(end -0.299974 0.150114)
			(stroke
				(width 0.1)
				(type default)
			)
			(layer "F.Fab")
		)
		(pad "1" smd rect
			(at -0.2667 0)
			(size 0.3048 0.381)
			(layers "F.Cu" "F.Mask" "F.Paste")
			(net "P5E_PEX2_STN1_TX_DN<19>")
		)
		(pad "2" smd rect
			(at 0.2667 0)
			(size 0.3048 0.381)
			(layers "F.Cu" "F.Mask" "F.Paste")
			(net "P5E_PEX2_STN1_TX_C_DN<19>")
		)
	)
	(footprint ""
		(layer "F.Cu")
		(at 32.657288 -356.244906 90)
		(property "Reference" "C2165"
			(at 0 0 90)
			(layer "F.SilkS")
			(hide yes)
			(effects
				(font
					(size 1.27 1.27)
				)
			)
		)
		(property "Value" ""
			(at 0 0 90)
			(layer "F.Fab")
			(effects
				(font
					(size 1.27 1.27)
				)
			)
		)
		(duplicate_pad_numbers_are_jumpers no)
		(fp_line
			(start 0.299974 -0.150114)
			(end 0.299974 0.150114)
			(stroke
				(width 0.1)
				(type default)
			)
			(layer "F.Fab")
		)
		(fp_line
			(start -0.299974 -0.150114)
			(end 0.299974 -0.150114)
			(stroke
				(width 0.1)
				(type default)
			)
			(layer "F.Fab")
		)
		(fp_line
			(start 0.299974 0.150114)
			(end -0.299974 0.150114)
			(stroke
				(width 0.1)
				(type default)
			)
			(layer "F.Fab")
		)
		(fp_line
			(start -0.299974 0.150114)
			(end -0.299974 -0.150114)
			(stroke
				(width 0.1)
				(type default)
			)
			(layer "F.Fab")
		)
		(pad "1" smd rect
			(at -0.2667 0 90)
			(size 0.3048 0.381)
			(layers "F.Cu" "F.Mask" "F.Paste")
			(net "P5E_PEX0_STN4_TX_DN<73>")
		)
		(pad "2" smd rect
			(at 0.2667 0 90)
			(size 0.3048 0.381)
			(layers "F.Cu" "F.Mask" "F.Paste")
			(net "P5E_PEX0_STN4_TX_C_DN<73>")
		)
	)
	(footprint ""
		(layer "F.Cu")
		(at 18.207736 -152.71115 90)
		(property "Reference" "R684"
			(at 0 0 90)
			(layer "F.SilkS")
			(hide yes)
			(effects
				(font
					(size 1.27 1.27)
				)
			)
		)
		(property "Value" ""
			(at 0 0 90)
			(layer "F.Fab")
			(effects
				(font
					(size 1.27 1.27)
				)
			)
		)
		(duplicate_pad_numbers_are_jumpers no)
		(fp_line
			(start 0.7874 -0.4064)
			(end 0.7874 0.4064)
			(stroke
				(width 0.1524)
				(type default)
			)
			(layer "F.SilkS")
		)
		(fp_line
			(start -0.7874 -0.4064)
			(end 0.7874 -0.4064)
			(stroke
				(width 0.1524)
				(type default)
			)
			(layer "F.SilkS")
		)
		(fp_line
			(start 0.7874 0.4064)
			(end -0.7874 0.4064)
			(stroke
				(width 0.1524)
				(type default)
			)
			(layer "F.SilkS")
		)
		(fp_line
			(start -0.7874 0.4064)
			(end -0.7874 -0.4064)
			(stroke
				(width 0.1524)
				(type default)
			)
			(layer "F.SilkS")
		)
		(fp_line
			(start -0.12065 -0.305054)
			(end -0.12065 -0.2794)
			(stroke
				(width 0.1)
				(type default)
			)
			(layer "F.Fab")
		)
		(fp_line
			(start -0.67945 -0.305054)
			(end -0.12065 -0.305054)
			(stroke
				(width 0.1)
				(type default)
			)
			(layer "F.Fab")
		)
		(fp_line
			(start 0.67945 -0.3048)
			(end 0.67945 0.3048)
			(stroke
				(width 0.1)
				(type default)
			)
			(layer "F.Fab")
		)
		(fp_line
			(start 0.12065 -0.3048)
			(end 0.67945 -0.3048)
			(stroke
				(width 0.1)
				(type default)
			)
			(layer "F.Fab")
		)
		(fp_line
			(start 0.12065 -0.2794)
			(end 0.12065 -0.3048)
			(stroke
				(width 0.1)
				(type default)
			)
			(layer "F.Fab")
		)
		(fp_line
			(start -0.12065 -0.2794)
			(end 0.12065 -0.2794)
			(stroke
				(width 0.1)
				(type default)
			)
			(layer "F.Fab")
		)
		(fp_line
			(start 0.120396 0.2794)
			(end -0.12065 0.2794)
			(stroke
				(width 0.1)
				(type default)
			)
			(layer "F.Fab")
		)
		(fp_line
			(start -0.12065 0.2794)
			(end -0.12065 0.3048)
			(stroke
				(width 0.1)
				(type default)
			)
			(layer "F.Fab")
		)
		(fp_line
			(start 0.67945 0.3048)
			(end 0.120396 0.3048)
			(stroke
				(width 0.1)
				(type default)
			)
			(layer "F.Fab")
		)
		(fp_line
			(start 0.120396 0.3048)
			(end 0.120396 0.2794)
			(stroke
				(width 0.1)
				(type default)
			)
			(layer "F.Fab")
		)
		(fp_line
			(start -0.12065 0.3048)
			(end -0.67945 0.3048)
			(stroke
				(width 0.1)
				(type default)
			)
			(layer "F.Fab")
		)
		(fp_line
			(start -0.67945 0.3048)
			(end -0.67945 -0.305054)
			(stroke
				(width 0.1)
				(type default)
			)
			(layer "F.Fab")
		)
		(pad "1" smd circle
			(at -0.40005 0 90)
			(size 0 0)
			(layers "F.Cu" "F.Mask" "F.Paste")
			(net "NIC0_ADC_ALERT_N")
		)
		(pad "2" smd circle
			(at 0.40005 0 90)
			(size 0 0)
			(layers "F.Cu" "F.Mask" "F.Paste")
			(net "NIC_ADC_ALERT_N")
		)
	)
	(footprint ""
		(layer "F.Cu")
		(at 131.007612 -154.510994)
		(property "Reference" "PC620"
			(at 0 0 0)
			(layer "F.SilkS")
			(hide yes)
			(effects
				(font
					(size 1.27 1.27)
				)
			)
		)
		(property "Value" ""
			(at 0 0 0)
			(layer "F.Fab")
			(effects
				(font
					(size 1.27 1.27)
				)
			)
		)
		(duplicate_pad_numbers_are_jumpers no)
		(fp_line
			(start -0.7874 -0.4064)
			(end 0.7874 -0.4064)
			(stroke
				(width 0.1524)
				(type default)
			)
			(layer "F.SilkS")
		)
		(fp_line
			(start -0.7874 0.4064)
			(end -0.7874 -0.4064)
			(stroke
				(width 0.1524)
				(type default)
			)
			(layer "F.SilkS")
		)
		(fp_line
			(start 0.7874 -0.4064)
			(end 0.7874 0.4064)
			(stroke
				(width 0.1524)
				(type default)
			)
			(layer "F.SilkS")
		)
		(fp_line
			(start 0.7874 0.4064)
			(end -0.7874 0.4064)
			(stroke
				(width 0.1524)
				(type default)
			)
			(layer "F.SilkS")
		)
		(fp_line
			(start -0.67945 -0.305054)
			(end -0.12065 -0.305054)
			(stroke
				(width 0.1)
				(type default)
			)
			(layer "F.Fab")
		)
		(fp_line
			(start -0.67945 0.3048)
			(end -0.67945 -0.305054)
			(stroke
				(width 0.1)
				(type default)
			)
			(layer "F.Fab")
		)
		(fp_line
			(start -0.12065 -0.305054)
			(end -0.12065 -0.2794)
			(stroke
				(width 0.1)
				(type default)
			)
			(layer "F.Fab")
		)
		(fp_line
			(start -0.12065 -0.2794)
			(end 0.12065 -0.2794)
			(stroke
				(width 0.1)
				(type default)
			)
			(layer "F.Fab")
		)
		(fp_line
			(start -0.12065 0.2794)
			(end -0.12065 0.3048)
			(stroke
				(width 0.1)
				(type default)
			)
			(layer "F.Fab")
		)
		(fp_line
			(start -0.12065 0.3048)
			(end -0.67945 0.3048)
			(stroke
				(width 0.1)
				(type default)
			)
			(layer "F.Fab")
		)
		(fp_line
			(start 0.120396 0.2794)
			(end -0.12065 0.2794)
			(stroke
				(width 0.1)
				(type default)
			)
			(layer "F.Fab")
		)
		(fp_line
			(start 0.120396 0.3048)
			(end 0.120396 0.2794)
			(stroke
				(width 0.1)
				(type default)
			)
			(layer "F.Fab")
		)
		(fp_line
			(start 0.12065 -0.3048)
			(end 0.67945 -0.3048)
			(stroke
				(width 0.1)
				(type default)
			)
			(layer "F.Fab")
		)
		(fp_line
			(start 0.12065 -0.2794)
			(end 0.12065 -0.3048)
			(stroke
				(width 0.1)
				(type default)
			)
			(layer "F.Fab")
		)
		(fp_line
			(start 0.67945 -0.3048)
			(end 0.67945 0.3048)
			(stroke
				(width 0.1)
				(type default)
			)
			(layer "F.Fab")
		)
		(fp_line
			(start 0.67945 0.3048)
			(end 0.120396 0.3048)
			(stroke
				(width 0.1)
				(type default)
			)
			(layer "F.Fab")
		)
		(pad "1" smd circle
			(at -0.40005 0)
			(size 0 0)
			(layers "F.Cu" "F.Mask" "F.Paste")
			(net "P12V_NIC2_R")
		)
		(pad "2" smd circle
			(at 0.40005 0)
			(size 0 0)
			(layers "F.Cu" "F.Mask" "F.Paste")
			(net "GND")
		)
	)
	(footprint ""
		(layer "F.Cu")
		(at 62.509908 -165.670484 -90)
		(property "Reference" "R2464"
			(at 0 0 270)
			(layer "F.SilkS")
			(hide yes)
			(effects
				(font
					(size 1.27 1.27)
				)
			)
		)
		(property "Value" ""
			(at 0 0 270)
			(layer "F.Fab")
			(effects
				(font
					(size 1.27 1.27)
				)
			)
		)
		(duplicate_pad_numbers_are_jumpers no)
		(fp_line
			(start -0.7874 0.4064)
			(end -0.7874 -0.4064)
			(stroke
				(width 0.1524)
				(type default)
			)
			(layer "F.SilkS")
		)
		(fp_line
			(start 0.7874 0.4064)
			(end -0.7874 0.4064)
			(stroke
				(width 0.1524)
				(type default)
			)
			(layer "F.SilkS")
		)
		(fp_line
			(start -0.7874 -0.4064)
			(end 0.7874 -0.4064)
			(stroke
				(width 0.1524)
				(type default)
			)
			(layer "F.SilkS")
		)
		(fp_line
			(start 0.7874 -0.4064)
			(end 0.7874 0.4064)
			(stroke
				(width 0.1524)
				(type default)
			)
			(layer "F.SilkS")
		)
		(fp_line
			(start -0.67945 0.3048)
			(end -0.67945 -0.305054)
			(stroke
				(width 0.1)
				(type default)
			)
			(layer "F.Fab")
		)
		(fp_line
			(start -0.12065 0.3048)
			(end -0.67945 0.3048)
			(stroke
				(width 0.1)
				(type default)
			)
			(layer "F.Fab")
		)
		(fp_line
			(start 0.120396 0.3048)
			(end 0.120396 0.2794)
			(stroke
				(width 0.1)
				(type default)
			)
			(layer "F.Fab")
		)
		(fp_line
			(start 0.67945 0.3048)
			(end 0.120396 0.3048)
			(stroke
				(width 0.1)
				(type default)
			)
			(layer "F.Fab")
		)
		(fp_line
			(start -0.12065 0.2794)
			(end -0.12065 0.3048)
			(stroke
				(width 0.1)
				(type default)
			)
			(layer "F.Fab")
		)
		(fp_line
			(start 0.120396 0.2794)
			(end -0.12065 0.2794)
			(stroke
				(width 0.1)
				(type default)
			)
			(layer "F.Fab")
		)
		(fp_line
			(start -0.12065 -0.2794)
			(end 0.12065 -0.2794)
			(stroke
				(width 0.1)
				(type default)
			)
			(layer "F.Fab")
		)
		(fp_line
			(start 0.12065 -0.2794)
			(end 0.12065 -0.3048)
			(stroke
				(width 0.1)
				(type default)
			)
			(layer "F.Fab")
		)
		(fp_line
			(start 0.12065 -0.3048)
			(end 0.67945 -0.3048)
			(stroke
				(width 0.1)
				(type default)
			)
			(layer "F.Fab")
		)
		(fp_line
			(start 0.67945 -0.3048)
			(end 0.67945 0.3048)
			(stroke
				(width 0.1)
				(type default)
			)
			(layer "F.Fab")
		)
		(fp_line
			(start -0.67945 -0.305054)
			(end -0.12065 -0.305054)
			(stroke
				(width 0.1)
				(type default)
			)
			(layer "F.Fab")
		)
		(fp_line
			(start -0.12065 -0.305054)
			(end -0.12065 -0.2794)
			(stroke
				(width 0.1)
				(type default)
			)
			(layer "F.Fab")
		)
		(pad "1" smd circle
			(at -0.40005 0 270)
			(size 0 0)
			(layers "F.Cu" "F.Mask" "F.Paste")
			(net "NIC0_PWRBRK_R_N")
		)
		(pad "2" smd circle
			(at 0.40005 0 270)
			(size 0 0)
			(layers "F.Cu" "F.Mask" "F.Paste")
			(net "NIC0_PWRBRK_N")
		)
	)
	(footprint ""
		(layer "F.Cu")
		(at 354.212398 -205.150466 90)
		(property "Reference" "R5803"
			(at 0 0 90)
			(layer "F.SilkS")
			(hide yes)
			(effects
				(font
					(size 1.27 1.27)
				)
			)
		)
		(property "Value" ""
			(at 0 0 90)
			(layer "F.Fab")
			(effects
				(font
					(size 1.27 1.27)
				)
			)
		)
		(duplicate_pad_numbers_are_jumpers no)
		(fp_line
			(start 0.7874 -0.4064)
			(end 0.7874 0.4064)
			(stroke
				(width 0.1524)
				(type default)
			)
			(layer "F.SilkS")
		)
		(fp_line
			(start -0.7874 -0.4064)
			(end 0.7874 -0.4064)
			(stroke
				(width 0.1524)
				(type default)
			)
			(layer "F.SilkS")
		)
		(fp_line
			(start 0.7874 0.4064)
			(end -0.7874 0.4064)
			(stroke
				(width 0.1524)
				(type default)
			)
			(layer "F.SilkS")
		)
		(fp_line
			(start -0.7874 0.4064)
			(end -0.7874 -0.4064)
			(stroke
				(width 0.1524)
				(type default)
			)
			(layer "F.SilkS")
		)
		(fp_line
			(start -0.12065 -0.305054)
			(end -0.12065 -0.2794)
			(stroke
				(width 0.1)
				(type default)
			)
			(layer "F.Fab")
		)
		(fp_line
			(start -0.67945 -0.305054)
			(end -0.12065 -0.305054)
			(stroke
				(width 0.1)
				(type default)
			)
			(layer "F.Fab")
		)
		(fp_line
			(start 0.67945 -0.3048)
			(end 0.67945 0.3048)
			(stroke
				(width 0.1)
				(type default)
			)
			(layer "F.Fab")
		)
		(fp_line
			(start 0.12065 -0.3048)
			(end 0.67945 -0.3048)
			(stroke
				(width 0.1)
				(type default)
			)
			(layer "F.Fab")
		)
		(fp_line
			(start 0.12065 -0.2794)
			(end 0.12065 -0.3048)
			(stroke
				(width 0.1)
				(type default)
			)
			(layer "F.Fab")
		)
		(fp_line
			(start -0.12065 -0.2794)
			(end 0.12065 -0.2794)
			(stroke
				(width 0.1)
				(type default)
			)
			(layer "F.Fab")
		)
		(fp_line
			(start 0.120396 0.2794)
			(end -0.12065 0.2794)
			(stroke
				(width 0.1)
				(type default)
			)
			(layer "F.Fab")
		)
		(fp_line
			(start -0.12065 0.2794)
			(end -0.12065 0.3048)
			(stroke
				(width 0.1)
				(type default)
			)
			(layer "F.Fab")
		)
		(fp_line
			(start 0.67945 0.3048)
			(end 0.120396 0.3048)
			(stroke
				(width 0.1)
				(type default)
			)
			(layer "F.Fab")
		)
		(fp_line
			(start 0.120396 0.3048)
			(end 0.120396 0.2794)
			(stroke
				(width 0.1)
				(type default)
			)
			(layer "F.Fab")
		)
		(fp_line
			(start -0.12065 0.3048)
			(end -0.67945 0.3048)
			(stroke
				(width 0.1)
				(type default)
			)
			(layer "F.Fab")
		)
		(fp_line
			(start -0.67945 0.3048)
			(end -0.67945 -0.305054)
			(stroke
				(width 0.1)
				(type default)
			)
			(layer "F.Fab")
		)
		(pad "1" smd circle
			(at -0.40005 0 90)
			(size 0 0)
			(layers "F.Cu" "F.Mask" "F.Paste")
			(net "P3V3_FPGA_VCCIO2")
		)
		(pad "2" smd circle
			(at 0.40005 0 90)
			(size 0 0)
			(layers "F.Cu" "F.Mask" "F.Paste")
			(net "PU_FPGA_SN")
		)
	)
	(footprint ""
		(layer "F.Cu")
		(at 488.553252 -554.392338 180)
		(property "Reference" "SCREW_SSD6_2"
			(at -5.207 -1.402334 0)
			(unlocked yes)
			(layer "B.SilkS")
			(effects
				(font
					(size 0.7874 0.5842)
					(thickness 0.1524)
				)
				(justify mirror)
			)
		)
		(property "Value" ""
			(at 0 0 180)
			(layer "F.Fab")
			(effects
				(font
					(size 1.27 1.27)
				)
			)
		)
		(duplicate_pad_numbers_are_jumpers no)
		(pad "1" thru_hole circle
			(at 0 0 180)
			(size 0.4572 0.4572)
			(drill 0.2032)
			(layers "*.Cu" "*.Mask")
			(remove_unused_layers no)
			(net "Net_9131")
			(clearance 0.127)
			(thermal_gap 0.127)
			(padstack
				(mode front_inner_back)
				(layer "Inner"
					(shape circle)
					(size 0.4572 0.4572)
					(clearance 0.127)
				)
				(layer "B.Cu"
					(shape circle)
					(size 0.508 0.508)
					(clearance 0.1016)
				)
			)
		)
	)
	(footprint ""
		(layer "F.Cu")
		(at 428.319438 -118.670324 180)
		(property "Reference" "C665"
			(at 0 0 180)
			(layer "F.SilkS")
			(hide yes)
			(effects
				(font
					(size 1.27 1.27)
				)
			)
		)
		(property "Value" ""
			(at 0 0 180)
			(layer "F.Fab")
			(effects
				(font
					(size 1.27 1.27)
				)
			)
		)
		(duplicate_pad_numbers_are_jumpers no)
		(fp_line
			(start 0.299974 0.150114)
			(end -0.299974 0.150114)
			(stroke
				(width 0.1)
				(type default)
			)
			(layer "F.Fab")
		)
		(fp_line
			(start 0.299974 -0.150114)
			(end 0.299974 0.150114)
			(stroke
				(width 0.1)
				(type default)
			)
			(layer "F.Fab")
		)
		(fp_line
			(start -0.299974 0.150114)
			(end -0.299974 -0.150114)
			(stroke
				(width 0.1)
				(type default)
			)
			(layer "F.Fab")
		)
		(fp_line
			(start -0.299974 -0.150114)
			(end 0.299974 -0.150114)
			(stroke
				(width 0.1)
				(type default)
			)
			(layer "F.Fab")
		)
		(pad "1" smd rect
			(at -0.2667 0 180)
			(size 0.3048 0.381)
			(layers "F.Cu" "F.Mask" "F.Paste")
			(net "P5E_PEX3_STN0_TX_DN<0>")
		)
		(pad "2" smd rect
			(at 0.2667 0 180)
			(size 0.3048 0.381)
			(layers "F.Cu" "F.Mask" "F.Paste")
			(net "P5E_PEX3_STN0_TX_C_DN<0>")
		)
	)
	(footprint ""
		(layer "F.Cu")
		(at 210.59394 -113.870486)
		(property "Reference" "PR7014"
			(at 0 0 0)
			(layer "F.SilkS")
			(hide yes)
			(effects
				(font
					(size 1.27 1.27)
				)
			)
		)
		(property "Value" ""
			(at 0 0 0)
			(layer "F.Fab")
			(effects
				(font
					(size 1.27 1.27)
				)
			)
		)
		(duplicate_pad_numbers_are_jumpers no)
		(fp_line
			(start -0.7874 -0.4064)
			(end 0.7874 -0.4064)
			(stroke
				(width 0.1524)
				(type default)
			)
			(layer "F.SilkS")
		)
		(fp_line
			(start -0.7874 0.4064)
			(end -0.7874 -0.4064)
			(stroke
				(width 0.1524)
				(type default)
			)
			(layer "F.SilkS")
		)
		(fp_line
			(start 0.7874 -0.4064)
			(end 0.7874 0.4064)
			(stroke
				(width 0.1524)
				(type default)
			)
			(layer "F.SilkS")
		)
		(fp_line
			(start 0.7874 0.4064)
			(end -0.7874 0.4064)
			(stroke
				(width 0.1524)
				(type default)
			)
			(layer "F.SilkS")
		)
		(fp_line
			(start -0.67945 -0.305054)
			(end -0.12065 -0.305054)
			(stroke
				(width 0.1)
				(type default)
			)
			(layer "F.Fab")
		)
		(fp_line
			(start -0.67945 0.3048)
			(end -0.67945 -0.305054)
			(stroke
				(width 0.1)
				(type default)
			)
			(layer "F.Fab")
		)
		(fp_line
			(start -0.12065 -0.305054)
			(end -0.12065 -0.2794)
			(stroke
				(width 0.1)
				(type default)
			)
			(layer "F.Fab")
		)
		(fp_line
			(start -0.12065 -0.2794)
			(end 0.12065 -0.2794)
			(stroke
				(width 0.1)
				(type default)
			)
			(layer "F.Fab")
		)
		(fp_line
			(start -0.12065 0.2794)
			(end -0.12065 0.3048)
			(stroke
				(width 0.1)
				(type default)
			)
			(layer "F.Fab")
		)
		(fp_line
			(start -0.12065 0.3048)
			(end -0.67945 0.3048)
			(stroke
				(width 0.1)
				(type default)
			)
			(layer "F.Fab")
		)
		(fp_line
			(start 0.120396 0.2794)
			(end -0.12065 0.2794)
			(stroke
				(width 0.1)
				(type default)
			)
			(layer "F.Fab")
		)
		(fp_line
			(start 0.120396 0.3048)
			(end 0.120396 0.2794)
			(stroke
				(width 0.1)
				(type default)
			)
			(layer "F.Fab")
		)
		(fp_line
			(start 0.12065 -0.3048)
			(end 0.67945 -0.3048)
			(stroke
				(width 0.1)
				(type default)
			)
			(layer "F.Fab")
		)
		(fp_line
			(start 0.12065 -0.2794)
			(end 0.12065 -0.3048)
			(stroke
				(width 0.1)
				(type default)
			)
			(layer "F.Fab")
		)
		(fp_line
			(start 0.67945 -0.3048)
			(end 0.67945 0.3048)
			(stroke
				(width 0.1)
				(type default)
			)
			(layer "F.Fab")
		)
		(fp_line
			(start 0.67945 0.3048)
			(end 0.120396 0.3048)
			(stroke
				(width 0.1)
				(type default)
			)
			(layer "F.Fab")
		)
		(pad "1" smd circle
			(at -0.40005 0)
			(size 0 0)
			(layers "F.Cu" "F.Mask" "F.Paste")
			(net "P3V3_NIC3_CO_ILIMIT")
		)
		(pad "2" smd circle
			(at 0.40005 0)
			(size 0 0)
			(layers "F.Cu" "F.Mask" "F.Paste")
			(net "GND")
		)
	)
	(footprint ""
		(layer "F.Cu")
		(at 142.125192 -14.735302 180)
		(property "Reference" "C2720"
			(at 0 0 180)
			(layer "F.SilkS")
			(hide yes)
			(effects
				(font
					(size 1.27 1.27)
				)
			)
		)
		(property "Value" ""
			(at 0 0 180)
			(layer "F.Fab")
			(effects
				(font
					(size 1.27 1.27)
				)
			)
		)
		(duplicate_pad_numbers_are_jumpers no)
		(fp_line
			(start 0.7874 0.4064)
			(end -0.7874 0.4064)
			(stroke
				(width 0.1524)
				(type default)
			)
			(layer "F.SilkS")
		)
		(fp_line
			(start 0.7874 -0.4064)
			(end 0.7874 0.4064)
			(stroke
				(width 0.1524)
				(type default)
			)
			(layer "F.SilkS")
		)
		(fp_line
			(start -0.7874 0.4064)
			(end -0.7874 -0.4064)
			(stroke
				(width 0.1524)
				(type default)
			)
			(layer "F.SilkS")
		)
		(fp_line
			(start -0.7874 -0.4064)
			(end 0.7874 -0.4064)
			(stroke
				(width 0.1524)
				(type default)
			)
			(layer "F.SilkS")
		)
		(fp_line
			(start 0.67945 0.3048)
			(end 0.120396 0.3048)
			(stroke
				(width 0.1)
				(type default)
			)
			(layer "F.Fab")
		)
		(fp_line
			(start 0.67945 -0.3048)
			(end 0.67945 0.3048)
			(stroke
				(width 0.1)
				(type default)
			)
			(layer "F.Fab")
		)
		(fp_line
			(start 0.12065 -0.2794)
			(end 0.12065 -0.3048)
			(stroke
				(width 0.1)
				(type default)
			)
			(layer "F.Fab")
		)
		(fp_line
			(start 0.12065 -0.3048)
			(end 0.67945 -0.3048)
			(stroke
				(width 0.1)
				(type default)
			)
			(layer "F.Fab")
		)
		(fp_line
			(start 0.120396 0.3048)
			(end 0.120396 0.2794)
			(stroke
				(width 0.1)
				(type default)
			)
			(layer "F.Fab")
		)
		(fp_line
			(start 0.120396 0.2794)
			(end -0.12065 0.2794)
			(stroke
				(width 0.1)
				(type default)
			)
			(layer "F.Fab")
		)
		(fp_line
			(start -0.12065 0.3048)
			(end -0.67945 0.3048)
			(stroke
				(width 0.1)
				(type default)
			)
			(layer "F.Fab")
		)
		(fp_line
			(start -0.12065 0.2794)
			(end -0.12065 0.3048)
			(stroke
				(width 0.1)
				(type default)
			)
			(layer "F.Fab")
		)
		(fp_line
			(start -0.12065 -0.2794)
			(end 0.12065 -0.2794)
			(stroke
				(width 0.1)
				(type default)
			)
			(layer "F.Fab")
		)
		(fp_line
			(start -0.12065 -0.305054)
			(end -0.12065 -0.2794)
			(stroke
				(width 0.1)
				(type default)
			)
			(layer "F.Fab")
		)
		(fp_line
			(start -0.67945 0.3048)
			(end -0.67945 -0.305054)
			(stroke
				(width 0.1)
				(type default)
			)
			(layer "F.Fab")
		)
		(fp_line
			(start -0.67945 -0.305054)
			(end -0.12065 -0.305054)
			(stroke
				(width 0.1)
				(type default)
			)
			(layer "F.Fab")
		)
		(pad "1" smd circle
			(at -0.40005 0 180)
			(size 0 0)
			(layers "F.Cu" "F.Mask" "F.Paste")
			(net "GND")
		)
		(pad "2" smd circle
			(at 0.40005 0 180)
			(size 0 0)
			(layers "F.Cu" "F.Mask" "F.Paste")
			(net "P3V3_SSD4")
		)
	)
	(footprint ""
		(layer "F.Cu")
		(at 491.797848 -552.071032 180)
		(property "Reference" "J31_OTH"
			(at -3.2385 -1.402334 0)
			(unlocked yes)
			(layer "B.SilkS")
			(effects
				(font
					(size 0.7874 0.5842)
					(thickness 0.1524)
				)
				(justify mirror)
			)
		)
		(property "Value" ""
			(at 0 0 180)
			(layer "F.Fab")
			(effects
				(font
					(size 1.27 1.27)
				)
			)
		)
		(duplicate_pad_numbers_are_jumpers no)
		(pad "1" thru_hole circle
			(at 0 0 180)
			(size 0.4572 0.4572)
			(drill 0.2032)
			(layers "*.Cu" "*.Mask")
			(remove_unused_layers no)
			(net "Net_9105")
			(clearance 0.127)
			(thermal_gap 0.127)
			(padstack
				(mode front_inner_back)
				(layer "Inner"
					(shape circle)
					(size 0.4572 0.4572)
					(clearance 0.127)
				)
				(layer "B.Cu"
					(shape circle)
					(size 0.508 0.508)
					(clearance 0.1016)
				)
			)
		)
	)
	(footprint ""
		(layer "F.Cu")
		(at 119.972328 -32.848042 90)
		(property "Reference" "PC920"
			(at 0 0 90)
			(layer "F.SilkS")
			(hide yes)
			(effects
				(font
					(size 1.27 1.27)
				)
			)
		)
		(property "Value" ""
			(at 0 0 90)
			(layer "F.Fab")
			(effects
				(font
					(size 1.27 1.27)
				)
			)
		)
		(duplicate_pad_numbers_are_jumpers no)
		(fp_line
			(start 0.7874 -0.4064)
			(end 0.7874 0.4064)
			(stroke
				(width 0.1524)
				(type default)
			)
			(layer "F.SilkS")
		)
		(fp_line
			(start -0.7874 -0.4064)
			(end 0.7874 -0.4064)
			(stroke
				(width 0.1524)
				(type default)
			)
			(layer "F.SilkS")
		)
		(fp_line
			(start 0.7874 0.4064)
			(end -0.7874 0.4064)
			(stroke
				(width 0.1524)
				(type default)
			)
			(layer "F.SilkS")
		)
		(fp_line
			(start -0.7874 0.4064)
			(end -0.7874 -0.4064)
			(stroke
				(width 0.1524)
				(type default)
			)
			(layer "F.SilkS")
		)
		(fp_line
			(start -0.12065 -0.305054)
			(end -0.12065 -0.2794)
			(stroke
				(width 0.1)
				(type default)
			)
			(layer "F.Fab")
		)
		(fp_line
			(start -0.67945 -0.305054)
			(end -0.12065 -0.305054)
			(stroke
				(width 0.1)
				(type default)
			)
			(layer "F.Fab")
		)
		(fp_line
			(start 0.67945 -0.3048)
			(end 0.67945 0.3048)
			(stroke
				(width 0.1)
				(type default)
			)
			(layer "F.Fab")
		)
		(fp_line
			(start 0.12065 -0.3048)
			(end 0.67945 -0.3048)
			(stroke
				(width 0.1)
				(type default)
			)
			(layer "F.Fab")
		)
		(fp_line
			(start 0.12065 -0.2794)
			(end 0.12065 -0.3048)
			(stroke
				(width 0.1)
				(type default)
			)
			(layer "F.Fab")
		)
		(fp_line
			(start -0.12065 -0.2794)
			(end 0.12065 -0.2794)
			(stroke
				(width 0.1)
				(type default)
			)
			(layer "F.Fab")
		)
		(fp_line
			(start 0.120396 0.2794)
			(end -0.12065 0.2794)
			(stroke
				(width 0.1)
				(type default)
			)
			(layer "F.Fab")
		)
		(fp_line
			(start -0.12065 0.2794)
			(end -0.12065 0.3048)
			(stroke
				(width 0.1)
				(type default)
			)
			(layer "F.Fab")
		)
		(fp_line
			(start 0.67945 0.3048)
			(end 0.120396 0.3048)
			(stroke
				(width 0.1)
				(type default)
			)
			(layer "F.Fab")
		)
		(fp_line
			(start 0.120396 0.3048)
			(end 0.120396 0.2794)
			(stroke
				(width 0.1)
				(type default)
			)
			(layer "F.Fab")
		)
		(fp_line
			(start -0.12065 0.3048)
			(end -0.67945 0.3048)
			(stroke
				(width 0.1)
				(type default)
			)
			(layer "F.Fab")
		)
		(fp_line
			(start -0.67945 0.3048)
			(end -0.67945 -0.305054)
			(stroke
				(width 0.1)
				(type default)
			)
			(layer "F.Fab")
		)
		(pad "1" smd circle
			(at -0.40005 0 90)
			(size 0 0)
			(layers "F.Cu" "F.Mask" "F.Paste")
			(net "P3V3_SSD4_CO_GATE")
		)
		(pad "2" smd circle
			(at 0.40005 0 90)
			(size 0 0)
			(layers "F.Cu" "F.Mask" "F.Paste")
			(net "GND")
		)
	)
	(footprint ""
		(layer "F.Cu")
		(at 430.961546 -124.076714 180)
		(property "Reference" "C659"
			(at 0 0 180)
			(layer "F.SilkS")
			(hide yes)
			(effects
				(font
					(size 1.27 1.27)
				)
			)
		)
		(property "Value" ""
			(at 0 0 180)
			(layer "F.Fab")
			(effects
				(font
					(size 1.27 1.27)
				)
			)
		)
		(duplicate_pad_numbers_are_jumpers no)
		(fp_line
			(start 0.299974 0.150114)
			(end -0.299974 0.150114)
			(stroke
				(width 0.1)
				(type default)
			)
			(layer "F.Fab")
		)
		(fp_line
			(start 0.299974 -0.150114)
			(end 0.299974 0.150114)
			(stroke
				(width 0.1)
				(type default)
			)
			(layer "F.Fab")
		)
		(fp_line
			(start -0.299974 0.150114)
			(end -0.299974 -0.150114)
			(stroke
				(width 0.1)
				(type default)
			)
			(layer "F.Fab")
		)
		(fp_line
			(start -0.299974 -0.150114)
			(end 0.299974 -0.150114)
			(stroke
				(width 0.1)
				(type default)
			)
			(layer "F.Fab")
		)
		(pad "1" smd rect
			(at -0.2667 0 180)
			(size 0.3048 0.381)
			(layers "F.Cu" "F.Mask" "F.Paste")
			(net "P5E_PEX3_STN0_TX_DN<3>")
		)
		(pad "2" smd rect
			(at 0.2667 0 180)
			(size 0.3048 0.381)
			(layers "F.Cu" "F.Mask" "F.Paste")
			(net "P5E_PEX3_STN0_TX_C_DN<3>")
		)
	)
	(footprint ""
		(layer "F.Cu")
		(at 92.538804 -122.798332 90)
		(property "Reference" "PC464"
			(at 0 0 90)
			(layer "F.SilkS")
			(hide yes)
			(effects
				(font
					(size 1.27 1.27)
				)
			)
		)
		(property "Value" ""
			(at 0 0 90)
			(layer "F.Fab")
			(effects
				(font
					(size 1.27 1.27)
				)
			)
		)
		(duplicate_pad_numbers_are_jumpers no)
		(fp_line
			(start 0.7874 -0.4064)
			(end 0.7874 0.4064)
			(stroke
				(width 0.1524)
				(type default)
			)
			(layer "F.SilkS")
		)
		(fp_line
			(start -0.7874 -0.4064)
			(end 0.7874 -0.4064)
			(stroke
				(width 0.1524)
				(type default)
			)
			(layer "F.SilkS")
		)
		(fp_line
			(start 0.7874 0.4064)
			(end -0.7874 0.4064)
			(stroke
				(width 0.1524)
				(type default)
			)
			(layer "F.SilkS")
		)
		(fp_line
			(start -0.7874 0.4064)
			(end -0.7874 -0.4064)
			(stroke
				(width 0.1524)
				(type default)
			)
			(layer "F.SilkS")
		)
		(fp_line
			(start -0.12065 -0.305054)
			(end -0.12065 -0.2794)
			(stroke
				(width 0.1)
				(type default)
			)
			(layer "F.Fab")
		)
		(fp_line
			(start -0.67945 -0.305054)
			(end -0.12065 -0.305054)
			(stroke
				(width 0.1)
				(type default)
			)
			(layer "F.Fab")
		)
		(fp_line
			(start 0.67945 -0.3048)
			(end 0.67945 0.3048)
			(stroke
				(width 0.1)
				(type default)
			)
			(layer "F.Fab")
		)
		(fp_line
			(start 0.12065 -0.3048)
			(end 0.67945 -0.3048)
			(stroke
				(width 0.1)
				(type default)
			)
			(layer "F.Fab")
		)
		(fp_line
			(start 0.12065 -0.2794)
			(end 0.12065 -0.3048)
			(stroke
				(width 0.1)
				(type default)
			)
			(layer "F.Fab")
		)
		(fp_line
			(start -0.12065 -0.2794)
			(end 0.12065 -0.2794)
			(stroke
				(width 0.1)
				(type default)
			)
			(layer "F.Fab")
		)
		(fp_line
			(start 0.120396 0.2794)
			(end -0.12065 0.2794)
			(stroke
				(width 0.1)
				(type default)
			)
			(layer "F.Fab")
		)
		(fp_line
			(start -0.12065 0.2794)
			(end -0.12065 0.3048)
			(stroke
				(width 0.1)
				(type default)
			)
			(layer "F.Fab")
		)
		(fp_line
			(start 0.67945 0.3048)
			(end 0.120396 0.3048)
			(stroke
				(width 0.1)
				(type default)
			)
			(layer "F.Fab")
		)
		(fp_line
			(start 0.120396 0.3048)
			(end 0.120396 0.2794)
			(stroke
				(width 0.1)
				(type default)
			)
			(layer "F.Fab")
		)
		(fp_line
			(start -0.12065 0.3048)
			(end -0.67945 0.3048)
			(stroke
				(width 0.1)
				(type default)
			)
			(layer "F.Fab")
		)
		(fp_line
			(start -0.67945 0.3048)
			(end -0.67945 -0.305054)
			(stroke
				(width 0.1)
				(type default)
			)
			(layer "F.Fab")
		)
		(pad "1" smd circle
			(at -0.40005 0 90)
			(size 0 0)
			(layers "F.Cu" "F.Mask" "F.Paste")
			(net "P3V3_NIC1")
		)
		(pad "2" smd circle
			(at 0.40005 0 90)
			(size 0 0)
			(layers "F.Cu" "F.Mask" "F.Paste")
			(net "GND")
		)
	)
	(footprint ""
		(layer "F.Cu")
		(at 427.762416 -22.937216 90)
		(property "Reference" "R1739"
			(at 0 0 90)
			(layer "F.SilkS")
			(hide yes)
			(effects
				(font
					(size 1.27 1.27)
				)
			)
		)
		(property "Value" ""
			(at 0 0 90)
			(layer "F.Fab")
			(effects
				(font
					(size 1.27 1.27)
				)
			)
		)
		(duplicate_pad_numbers_are_jumpers no)
		(fp_line
			(start 0.7874 -0.4064)
			(end 0.7874 0.4064)
			(stroke
				(width 0.1524)
				(type default)
			)
			(layer "F.SilkS")
		)
		(fp_line
			(start -0.7874 -0.4064)
			(end 0.7874 -0.4064)
			(stroke
				(width 0.1524)
				(type default)
			)
			(layer "F.SilkS")
		)
		(fp_line
			(start 0.7874 0.4064)
			(end -0.7874 0.4064)
			(stroke
				(width 0.1524)
				(type default)
			)
			(layer "F.SilkS")
		)
		(fp_line
			(start -0.7874 0.4064)
			(end -0.7874 -0.4064)
			(stroke
				(width 0.1524)
				(type default)
			)
			(layer "F.SilkS")
		)
		(fp_line
			(start -0.12065 -0.305054)
			(end -0.12065 -0.2794)
			(stroke
				(width 0.1)
				(type default)
			)
			(layer "F.Fab")
		)
		(fp_line
			(start -0.67945 -0.305054)
			(end -0.12065 -0.305054)
			(stroke
				(width 0.1)
				(type default)
			)
			(layer "F.Fab")
		)
		(fp_line
			(start 0.67945 -0.3048)
			(end 0.67945 0.3048)
			(stroke
				(width 0.1)
				(type default)
			)
			(layer "F.Fab")
		)
		(fp_line
			(start 0.12065 -0.3048)
			(end 0.67945 -0.3048)
			(stroke
				(width 0.1)
				(type default)
			)
			(layer "F.Fab")
		)
		(fp_line
			(start 0.12065 -0.2794)
			(end 0.12065 -0.3048)
			(stroke
				(width 0.1)
				(type default)
			)
			(layer "F.Fab")
		)
		(fp_line
			(start -0.12065 -0.2794)
			(end 0.12065 -0.2794)
			(stroke
				(width 0.1)
				(type default)
			)
			(layer "F.Fab")
		)
		(fp_line
			(start 0.120396 0.2794)
			(end -0.12065 0.2794)
			(stroke
				(width 0.1)
				(type default)
			)
			(layer "F.Fab")
		)
		(fp_line
			(start -0.12065 0.2794)
			(end -0.12065 0.3048)
			(stroke
				(width 0.1)
				(type default)
			)
			(layer "F.Fab")
		)
		(fp_line
			(start 0.67945 0.3048)
			(end 0.120396 0.3048)
			(stroke
				(width 0.1)
				(type default)
			)
			(layer "F.Fab")
		)
		(fp_line
			(start 0.120396 0.3048)
			(end 0.120396 0.2794)
			(stroke
				(width 0.1)
				(type default)
			)
			(layer "F.Fab")
		)
		(fp_line
			(start -0.12065 0.3048)
			(end -0.67945 0.3048)
			(stroke
				(width 0.1)
				(type default)
			)
			(layer "F.Fab")
		)
		(fp_line
			(start -0.67945 0.3048)
			(end -0.67945 -0.305054)
			(stroke
				(width 0.1)
				(type default)
			)
			(layer "F.Fab")
		)
		(pad "1" smd circle
			(at -0.40005 0 90)
			(size 0 0)
			(layers "F.Cu" "F.Mask" "F.Paste")
			(net "SMB_BIC_I2C9_MUX1_SSD14_R_SDA")
		)
		(pad "2" smd circle
			(at 0.40005 0 90)
			(size 0 0)
			(layers "F.Cu" "F.Mask" "F.Paste")
			(net "SMB_ISO_SSD14_SDA")
		)
	)
	(footprint ""
		(layer "F.Cu")
		(at 192.582038 -38.041072 180)
		(property "Reference" "R6073"
			(at 0 0 180)
			(layer "F.SilkS")
			(hide yes)
			(effects
				(font
					(size 1.27 1.27)
				)
			)
		)
		(property "Value" ""
			(at 0 0 180)
			(layer "F.Fab")
			(effects
				(font
					(size 1.27 1.27)
				)
			)
		)
		(duplicate_pad_numbers_are_jumpers no)
		(fp_line
			(start 0.7874 0.4064)
			(end -0.7874 0.4064)
			(stroke
				(width 0.1524)
				(type default)
			)
			(layer "F.SilkS")
		)
		(fp_line
			(start 0.7874 -0.4064)
			(end 0.7874 0.4064)
			(stroke
				(width 0.1524)
				(type default)
			)
			(layer "F.SilkS")
		)
		(fp_line
			(start -0.7874 0.4064)
			(end -0.7874 -0.4064)
			(stroke
				(width 0.1524)
				(type default)
			)
			(layer "F.SilkS")
		)
		(fp_line
			(start -0.7874 -0.4064)
			(end 0.7874 -0.4064)
			(stroke
				(width 0.1524)
				(type default)
			)
			(layer "F.SilkS")
		)
		(fp_line
			(start 0.67945 0.3048)
			(end 0.120396 0.3048)
			(stroke
				(width 0.1)
				(type default)
			)
			(layer "F.Fab")
		)
		(fp_line
			(start 0.67945 -0.3048)
			(end 0.67945 0.3048)
			(stroke
				(width 0.1)
				(type default)
			)
			(layer "F.Fab")
		)
		(fp_line
			(start 0.12065 -0.2794)
			(end 0.12065 -0.3048)
			(stroke
				(width 0.1)
				(type default)
			)
			(layer "F.Fab")
		)
		(fp_line
			(start 0.12065 -0.3048)
			(end 0.67945 -0.3048)
			(stroke
				(width 0.1)
				(type default)
			)
			(layer "F.Fab")
		)
		(fp_line
			(start 0.120396 0.3048)
			(end 0.120396 0.2794)
			(stroke
				(width 0.1)
				(type default)
			)
			(layer "F.Fab")
		)
		(fp_line
			(start 0.120396 0.2794)
			(end -0.12065 0.2794)
			(stroke
				(width 0.1)
				(type default)
			)
			(layer "F.Fab")
		)
		(fp_line
			(start -0.12065 0.3048)
			(end -0.67945 0.3048)
			(stroke
				(width 0.1)
				(type default)
			)
			(layer "F.Fab")
		)
		(fp_line
			(start -0.12065 0.2794)
			(end -0.12065 0.3048)
			(stroke
				(width 0.1)
				(type default)
			)
			(layer "F.Fab")
		)
		(fp_line
			(start -0.12065 -0.2794)
			(end 0.12065 -0.2794)
			(stroke
				(width 0.1)
				(type default)
			)
			(layer "F.Fab")
		)
		(fp_line
			(start -0.12065 -0.305054)
			(end -0.12065 -0.2794)
			(stroke
				(width 0.1)
				(type default)
			)
			(layer "F.Fab")
		)
		(fp_line
			(start -0.67945 0.3048)
			(end -0.67945 -0.305054)
			(stroke
				(width 0.1)
				(type default)
			)
			(layer "F.Fab")
		)
		(fp_line
			(start -0.67945 -0.305054)
			(end -0.12065 -0.305054)
			(stroke
				(width 0.1)
				(type default)
			)
			(layer "F.Fab")
		)
		(pad "1" smd circle
			(at -0.40005 0 180)
			(size 0 0)
			(layers "F.Cu" "F.Mask" "F.Paste")
			(net "P5V_AUX")
		)
		(pad "2" smd circle
			(at 0.40005 0 180)
			(size 0 0)
			(layers "F.Cu" "F.Mask" "F.Paste")
			(net "P3V3_SSD7_PG_G2")
		)
	)
	(footprint ""
		(layer "F.Cu")
		(at 45.257974 -72.766682 90)
		(property "Reference" "PC644"
			(at 0 0 90)
			(layer "F.SilkS")
			(hide yes)
			(effects
				(font
					(size 1.27 1.27)
				)
			)
		)
		(property "Value" ""
			(at 0 0 90)
			(layer "F.Fab")
			(effects
				(font
					(size 1.27 1.27)
				)
			)
		)
		(duplicate_pad_numbers_are_jumpers no)
		(fp_line
			(start 0.7874 -0.4064)
			(end 0.7874 0.4064)
			(stroke
				(width 0.1524)
				(type default)
			)
			(layer "F.SilkS")
		)
		(fp_line
			(start -0.7874 -0.4064)
			(end 0.7874 -0.4064)
			(stroke
				(width 0.1524)
				(type default)
			)
			(layer "F.SilkS")
		)
		(fp_line
			(start 0.7874 0.4064)
			(end -0.7874 0.4064)
			(stroke
				(width 0.1524)
				(type default)
			)
			(layer "F.SilkS")
		)
		(fp_line
			(start -0.7874 0.4064)
			(end -0.7874 -0.4064)
			(stroke
				(width 0.1524)
				(type default)
			)
			(layer "F.SilkS")
		)
		(fp_line
			(start -0.12065 -0.305054)
			(end -0.12065 -0.2794)
			(stroke
				(width 0.1)
				(type default)
			)
			(layer "F.Fab")
		)
		(fp_line
			(start -0.67945 -0.305054)
			(end -0.12065 -0.305054)
			(stroke
				(width 0.1)
				(type default)
			)
			(layer "F.Fab")
		)
		(fp_line
			(start 0.67945 -0.3048)
			(end 0.67945 0.3048)
			(stroke
				(width 0.1)
				(type default)
			)
			(layer "F.Fab")
		)
		(fp_line
			(start 0.12065 -0.3048)
			(end 0.67945 -0.3048)
			(stroke
				(width 0.1)
				(type default)
			)
			(layer "F.Fab")
		)
		(fp_line
			(start 0.12065 -0.2794)
			(end 0.12065 -0.3048)
			(stroke
				(width 0.1)
				(type default)
			)
			(layer "F.Fab")
		)
		(fp_line
			(start -0.12065 -0.2794)
			(end 0.12065 -0.2794)
			(stroke
				(width 0.1)
				(type default)
			)
			(layer "F.Fab")
		)
		(fp_line
			(start 0.120396 0.2794)
			(end -0.12065 0.2794)
			(stroke
				(width 0.1)
				(type default)
			)
			(layer "F.Fab")
		)
		(fp_line
			(start -0.12065 0.2794)
			(end -0.12065 0.3048)
			(stroke
				(width 0.1)
				(type default)
			)
			(layer "F.Fab")
		)
		(fp_line
			(start 0.67945 0.3048)
			(end 0.120396 0.3048)
			(stroke
				(width 0.1)
				(type default)
			)
			(layer "F.Fab")
		)
		(fp_line
			(start 0.120396 0.3048)
			(end 0.120396 0.2794)
			(stroke
				(width 0.1)
				(type default)
			)
			(layer "F.Fab")
		)
		(fp_line
			(start -0.12065 0.3048)
			(end -0.67945 0.3048)
			(stroke
				(width 0.1)
				(type default)
			)
			(layer "F.Fab")
		)
		(fp_line
			(start -0.67945 0.3048)
			(end -0.67945 -0.305054)
			(stroke
				(width 0.1)
				(type default)
			)
			(layer "F.Fab")
		)
		(pad "1" smd circle
			(at -0.40005 0 90)
			(size 0 0)
			(layers "F.Cu" "F.Mask" "F.Paste")
			(net "P12V_SSD1_CO_MODE")
		)
		(pad "2" smd circle
			(at 0.40005 0 90)
			(size 0 0)
			(layers "F.Cu" "F.Mask" "F.Paste")
			(net "GND")
		)
	)
	(footprint ""
		(layer "F.Cu")
		(at 385.304792 -142.88897 180)
		(property "Reference" "R335"
			(at 0 0 180)
			(layer "F.SilkS")
			(hide yes)
			(effects
				(font
					(size 1.27 1.27)
				)
			)
		)
		(property "Value" ""
			(at 0 0 180)
			(layer "F.Fab")
			(effects
				(font
					(size 1.27 1.27)
				)
			)
		)
		(duplicate_pad_numbers_are_jumpers no)
		(fp_line
			(start 0.7874 0.4064)
			(end -0.7874 0.4064)
			(stroke
				(width 0.1524)
				(type default)
			)
			(layer "F.SilkS")
		)
		(fp_line
			(start 0.7874 -0.4064)
			(end 0.7874 0.4064)
			(stroke
				(width 0.1524)
				(type default)
			)
			(layer "F.SilkS")
		)
		(fp_line
			(start -0.7874 0.4064)
			(end -0.7874 -0.4064)
			(stroke
				(width 0.1524)
				(type default)
			)
			(layer "F.SilkS")
		)
		(fp_line
			(start -0.7874 -0.4064)
			(end 0.7874 -0.4064)
			(stroke
				(width 0.1524)
				(type default)
			)
			(layer "F.SilkS")
		)
		(fp_line
			(start 0.67945 0.3048)
			(end 0.120396 0.3048)
			(stroke
				(width 0.1)
				(type default)
			)
			(layer "F.Fab")
		)
		(fp_line
			(start 0.67945 -0.3048)
			(end 0.67945 0.3048)
			(stroke
				(width 0.1)
				(type default)
			)
			(layer "F.Fab")
		)
		(fp_line
			(start 0.12065 -0.2794)
			(end 0.12065 -0.3048)
			(stroke
				(width 0.1)
				(type default)
			)
			(layer "F.Fab")
		)
		(fp_line
			(start 0.12065 -0.3048)
			(end 0.67945 -0.3048)
			(stroke
				(width 0.1)
				(type default)
			)
			(layer "F.Fab")
		)
		(fp_line
			(start 0.120396 0.3048)
			(end 0.120396 0.2794)
			(stroke
				(width 0.1)
				(type default)
			)
			(layer "F.Fab")
		)
		(fp_line
			(start 0.120396 0.2794)
			(end -0.12065 0.2794)
			(stroke
				(width 0.1)
				(type default)
			)
			(layer "F.Fab")
		)
		(fp_line
			(start -0.12065 0.3048)
			(end -0.67945 0.3048)
			(stroke
				(width 0.1)
				(type default)
			)
			(layer "F.Fab")
		)
		(fp_line
			(start -0.12065 0.2794)
			(end -0.12065 0.3048)
			(stroke
				(width 0.1)
				(type default)
			)
			(layer "F.Fab")
		)
		(fp_line
			(start -0.12065 -0.2794)
			(end 0.12065 -0.2794)
			(stroke
				(width 0.1)
				(type default)
			)
			(layer "F.Fab")
		)
		(fp_line
			(start -0.12065 -0.305054)
			(end -0.12065 -0.2794)
			(stroke
				(width 0.1)
				(type default)
			)
			(layer "F.Fab")
		)
		(fp_line
			(start -0.67945 0.3048)
			(end -0.67945 -0.305054)
			(stroke
				(width 0.1)
				(type default)
			)
			(layer "F.Fab")
		)
		(fp_line
			(start -0.67945 -0.305054)
			(end -0.12065 -0.305054)
			(stroke
				(width 0.1)
				(type default)
			)
			(layer "F.Fab")
		)
		(pad "1" smd circle
			(at -0.40005 0 180)
			(size 0 0)
			(layers "F.Cu" "F.Mask" "F.Paste")
			(net "NIC6_BIF0_N")
		)
		(pad "2" smd circle
			(at 0.40005 0 180)
			(size 0 0)
			(layers "F.Cu" "F.Mask" "F.Paste")
			(net "P3V3_AUX")
		)
	)
	(footprint ""
		(layer "F.Cu")
		(at 348.107 -234.061 -90)
		(property "Reference" "R3570"
			(at 0 0 270)
			(layer "F.SilkS")
			(hide yes)
			(effects
				(font
					(size 1.27 1.27)
				)
			)
		)
		(property "Value" ""
			(at 0 0 270)
			(layer "F.Fab")
			(effects
				(font
					(size 1.27 1.27)
				)
			)
		)
		(duplicate_pad_numbers_are_jumpers no)
		(fp_line
			(start -0.7874 0.4064)
			(end -0.7874 -0.4064)
			(stroke
				(width 0.1524)
				(type default)
			)
			(layer "F.SilkS")
		)
		(fp_line
			(start 0.7874 0.4064)
			(end -0.7874 0.4064)
			(stroke
				(width 0.1524)
				(type default)
			)
			(layer "F.SilkS")
		)
		(fp_line
			(start -0.7874 -0.4064)
			(end 0.7874 -0.4064)
			(stroke
				(width 0.1524)
				(type default)
			)
			(layer "F.SilkS")
		)
		(fp_line
			(start 0.7874 -0.4064)
			(end 0.7874 0.4064)
			(stroke
				(width 0.1524)
				(type default)
			)
			(layer "F.SilkS")
		)
		(fp_line
			(start -0.67945 0.3048)
			(end -0.67945 -0.305054)
			(stroke
				(width 0.1)
				(type default)
			)
			(layer "F.Fab")
		)
		(fp_line
			(start -0.12065 0.3048)
			(end -0.67945 0.3048)
			(stroke
				(width 0.1)
				(type default)
			)
			(layer "F.Fab")
		)
		(fp_line
			(start 0.120396 0.3048)
			(end 0.120396 0.2794)
			(stroke
				(width 0.1)
				(type default)
			)
			(layer "F.Fab")
		)
		(fp_line
			(start 0.67945 0.3048)
			(end 0.120396 0.3048)
			(stroke
				(width 0.1)
				(type default)
			)
			(layer "F.Fab")
		)
		(fp_line
			(start -0.12065 0.2794)
			(end -0.12065 0.3048)
			(stroke
				(width 0.1)
				(type default)
			)
			(layer "F.Fab")
		)
		(fp_line
			(start 0.120396 0.2794)
			(end -0.12065 0.2794)
			(stroke
				(width 0.1)
				(type default)
			)
			(layer "F.Fab")
		)
		(fp_line
			(start -0.12065 -0.2794)
			(end 0.12065 -0.2794)
			(stroke
				(width 0.1)
				(type default)
			)
			(layer "F.Fab")
		)
		(fp_line
			(start 0.12065 -0.2794)
			(end 0.12065 -0.3048)
			(stroke
				(width 0.1)
				(type default)
			)
			(layer "F.Fab")
		)
		(fp_line
			(start 0.12065 -0.3048)
			(end 0.67945 -0.3048)
			(stroke
				(width 0.1)
				(type default)
			)
			(layer "F.Fab")
		)
		(fp_line
			(start 0.67945 -0.3048)
			(end 0.67945 0.3048)
			(stroke
				(width 0.1)
				(type default)
			)
			(layer "F.Fab")
		)
		(fp_line
			(start -0.67945 -0.305054)
			(end -0.12065 -0.305054)
			(stroke
				(width 0.1)
				(type default)
			)
			(layer "F.Fab")
		)
		(fp_line
			(start -0.12065 -0.305054)
			(end -0.12065 -0.2794)
			(stroke
				(width 0.1)
				(type default)
			)
			(layer "F.Fab")
		)
		(pad "1" smd circle
			(at -0.40005 0 270)
			(size 0 0)
			(layers "F.Cu" "F.Mask" "F.Paste")
			(net "SSD5_CLK_EN_R_N")
		)
		(pad "2" smd circle
			(at 0.40005 0 270)
			(size 0 0)
			(layers "F.Cu" "F.Mask" "F.Paste")
			(net "SSD5_CLK_EN_N")
		)
	)
	(footprint ""
		(layer "F.Cu")
		(at 365.491776 -152.71115 90)
		(property "Reference" "R757"
			(at 0 0 90)
			(layer "F.SilkS")
			(hide yes)
			(effects
				(font
					(size 1.27 1.27)
				)
			)
		)
		(property "Value" ""
			(at 0 0 90)
			(layer "F.Fab")
			(effects
				(font
					(size 1.27 1.27)
				)
			)
		)
		(duplicate_pad_numbers_are_jumpers no)
		(fp_line
			(start 0.7874 -0.4064)
			(end 0.7874 0.4064)
			(stroke
				(width 0.1524)
				(type default)
			)
			(layer "F.SilkS")
		)
		(fp_line
			(start -0.7874 -0.4064)
			(end 0.7874 -0.4064)
			(stroke
				(width 0.1524)
				(type default)
			)
			(layer "F.SilkS")
		)
		(fp_line
			(start 0.7874 0.4064)
			(end -0.7874 0.4064)
			(stroke
				(width 0.1524)
				(type default)
			)
			(layer "F.SilkS")
		)
		(fp_line
			(start -0.7874 0.4064)
			(end -0.7874 -0.4064)
			(stroke
				(width 0.1524)
				(type default)
			)
			(layer "F.SilkS")
		)
		(fp_line
			(start -0.12065 -0.305054)
			(end -0.12065 -0.2794)
			(stroke
				(width 0.1)
				(type default)
			)
			(layer "F.Fab")
		)
		(fp_line
			(start -0.67945 -0.305054)
			(end -0.12065 -0.305054)
			(stroke
				(width 0.1)
				(type default)
			)
			(layer "F.Fab")
		)
		(fp_line
			(start 0.67945 -0.3048)
			(end 0.67945 0.3048)
			(stroke
				(width 0.1)
				(type default)
			)
			(layer "F.Fab")
		)
		(fp_line
			(start 0.12065 -0.3048)
			(end 0.67945 -0.3048)
			(stroke
				(width 0.1)
				(type default)
			)
			(layer "F.Fab")
		)
		(fp_line
			(start 0.12065 -0.2794)
			(end 0.12065 -0.3048)
			(stroke
				(width 0.1)
				(type default)
			)
			(layer "F.Fab")
		)
		(fp_line
			(start -0.12065 -0.2794)
			(end 0.12065 -0.2794)
			(stroke
				(width 0.1)
				(type default)
			)
			(layer "F.Fab")
		)
		(fp_line
			(start 0.120396 0.2794)
			(end -0.12065 0.2794)
			(stroke
				(width 0.1)
				(type default)
			)
			(layer "F.Fab")
		)
		(fp_line
			(start -0.12065 0.2794)
			(end -0.12065 0.3048)
			(stroke
				(width 0.1)
				(type default)
			)
			(layer "F.Fab")
		)
		(fp_line
			(start 0.67945 0.3048)
			(end 0.120396 0.3048)
			(stroke
				(width 0.1)
				(type default)
			)
			(layer "F.Fab")
		)
		(fp_line
			(start 0.120396 0.3048)
			(end 0.120396 0.2794)
			(stroke
				(width 0.1)
				(type default)
			)
			(layer "F.Fab")
		)
		(fp_line
			(start -0.12065 0.3048)
			(end -0.67945 0.3048)
			(stroke
				(width 0.1)
				(type default)
			)
			(layer "F.Fab")
		)
		(fp_line
			(start -0.67945 0.3048)
			(end -0.67945 -0.305054)
			(stroke
				(width 0.1)
				(type default)
			)
			(layer "F.Fab")
		)
		(pad "1" smd circle
			(at -0.40005 0 90)
			(size 0 0)
			(layers "F.Cu" "F.Mask" "F.Paste")
			(net "P3V3_AUX")
		)
		(pad "2" smd circle
			(at 0.40005 0 90)
			(size 0 0)
			(layers "F.Cu" "F.Mask" "F.Paste")
			(net "NIC_ADC_ALERT_N")
		)
	)
	(footprint ""
		(layer "F.Cu")
		(at 477.990408 -557.9364 180)
		(property "Reference" "JPEX3_FW1"
			(at -4.0259 -1.402334 0)
			(unlocked yes)
			(layer "B.SilkS")
			(effects
				(font
					(size 0.7874 0.5842)
					(thickness 0.1524)
				)
				(justify mirror)
			)
		)
		(property "Value" ""
			(at 0 0 180)
			(layer "F.Fab")
			(effects
				(font
					(size 1.27 1.27)
				)
			)
		)
		(duplicate_pad_numbers_are_jumpers no)
		(pad "1" thru_hole circle
			(at 0 0 180)
			(size 0.4572 0.4572)
			(drill 0.2032)
			(layers "*.Cu" "*.Mask")
			(remove_unused_layers no)
			(net "Net_9087")
			(clearance 0.127)
			(thermal_gap 0.127)
			(padstack
				(mode front_inner_back)
				(layer "Inner"
					(shape circle)
					(size 0.4572 0.4572)
					(clearance 0.127)
				)
				(layer "B.Cu"
					(shape circle)
					(size 0.508 0.508)
					(clearance 0.1016)
				)
			)
		)
	)
	(footprint ""
		(layer "F.Cu")
		(at 376.809 -176.18202)
		(property "Reference" "R4672"
			(at 0 0 0)
			(layer "F.SilkS")
			(hide yes)
			(effects
				(font
					(size 1.27 1.27)
				)
			)
		)
		(property "Value" ""
			(at 0 0 0)
			(layer "F.Fab")
			(effects
				(font
					(size 1.27 1.27)
				)
			)
		)
		(duplicate_pad_numbers_are_jumpers no)
		(fp_line
			(start -0.7874 -0.4064)
			(end 0.7874 -0.4064)
			(stroke
				(width 0.1524)
				(type default)
			)
			(layer "F.SilkS")
		)
		(fp_line
			(start -0.7874 0.4064)
			(end -0.7874 -0.4064)
			(stroke
				(width 0.1524)
				(type default)
			)
			(layer "F.SilkS")
		)
		(fp_line
			(start 0.7874 -0.4064)
			(end 0.7874 0.4064)
			(stroke
				(width 0.1524)
				(type default)
			)
			(layer "F.SilkS")
		)
		(fp_line
			(start 0.7874 0.4064)
			(end -0.7874 0.4064)
			(stroke
				(width 0.1524)
				(type default)
			)
			(layer "F.SilkS")
		)
		(fp_line
			(start -0.67945 -0.305054)
			(end -0.12065 -0.305054)
			(stroke
				(width 0.1)
				(type default)
			)
			(layer "F.Fab")
		)
		(fp_line
			(start -0.67945 0.3048)
			(end -0.67945 -0.305054)
			(stroke
				(width 0.1)
				(type default)
			)
			(layer "F.Fab")
		)
		(fp_line
			(start -0.12065 -0.305054)
			(end -0.12065 -0.2794)
			(stroke
				(width 0.1)
				(type default)
			)
			(layer "F.Fab")
		)
		(fp_line
			(start -0.12065 -0.2794)
			(end 0.12065 -0.2794)
			(stroke
				(width 0.1)
				(type default)
			)
			(layer "F.Fab")
		)
		(fp_line
			(start -0.12065 0.2794)
			(end -0.12065 0.3048)
			(stroke
				(width 0.1)
				(type default)
			)
			(layer "F.Fab")
		)
		(fp_line
			(start -0.12065 0.3048)
			(end -0.67945 0.3048)
			(stroke
				(width 0.1)
				(type default)
			)
			(layer "F.Fab")
		)
		(fp_line
			(start 0.120396 0.2794)
			(end -0.12065 0.2794)
			(stroke
				(width 0.1)
				(type default)
			)
			(layer "F.Fab")
		)
		(fp_line
			(start 0.120396 0.3048)
			(end 0.120396 0.2794)
			(stroke
				(width 0.1)
				(type default)
			)
			(layer "F.Fab")
		)
		(fp_line
			(start 0.12065 -0.3048)
			(end 0.67945 -0.3048)
			(stroke
				(width 0.1)
				(type default)
			)
			(layer "F.Fab")
		)
		(fp_line
			(start 0.12065 -0.2794)
			(end 0.12065 -0.3048)
			(stroke
				(width 0.1)
				(type default)
			)
			(layer "F.Fab")
		)
		(fp_line
			(start 0.67945 -0.3048)
			(end 0.67945 0.3048)
			(stroke
				(width 0.1)
				(type default)
			)
			(layer "F.Fab")
		)
		(fp_line
			(start 0.67945 0.3048)
			(end 0.120396 0.3048)
			(stroke
				(width 0.1)
				(type default)
			)
			(layer "F.Fab")
		)
		(pad "1" smd circle
			(at -0.40005 0)
			(size 0 0)
			(layers "F.Cu" "F.Mask" "F.Paste")
			(net "P3V3_AUX")
		)
		(pad "2" smd circle
			(at 0.40005 0)
			(size 0 0)
			(layers "F.Cu" "F.Mask" "F.Paste")
			(net "RST_PEX_NIC3_PERST_R_N")
		)
	)
	(footprint ""
		(layer "F.Cu")
		(at 54.856126 -32.848042 -90)
		(property "Reference" "R5878"
			(at 0 0 270)
			(layer "F.SilkS")
			(hide yes)
			(effects
				(font
					(size 1.27 1.27)
				)
			)
		)
		(property "Value" ""
			(at 0 0 270)
			(layer "F.Fab")
			(effects
				(font
					(size 1.27 1.27)
				)
			)
		)
		(duplicate_pad_numbers_are_jumpers no)
		(fp_line
			(start -0.7874 0.4064)
			(end -0.7874 -0.4064)
			(stroke
				(width 0.1524)
				(type default)
			)
			(layer "F.SilkS")
		)
		(fp_line
			(start 0.7874 0.4064)
			(end -0.7874 0.4064)
			(stroke
				(width 0.1524)
				(type default)
			)
			(layer "F.SilkS")
		)
		(fp_line
			(start -0.7874 -0.4064)
			(end 0.7874 -0.4064)
			(stroke
				(width 0.1524)
				(type default)
			)
			(layer "F.SilkS")
		)
		(fp_line
			(start 0.7874 -0.4064)
			(end 0.7874 0.4064)
			(stroke
				(width 0.1524)
				(type default)
			)
			(layer "F.SilkS")
		)
		(fp_line
			(start -0.67945 0.3048)
			(end -0.67945 -0.305054)
			(stroke
				(width 0.1)
				(type default)
			)
			(layer "F.Fab")
		)
		(fp_line
			(start -0.12065 0.3048)
			(end -0.67945 0.3048)
			(stroke
				(width 0.1)
				(type default)
			)
			(layer "F.Fab")
		)
		(fp_line
			(start 0.120396 0.3048)
			(end 0.120396 0.2794)
			(stroke
				(width 0.1)
				(type default)
			)
			(layer "F.Fab")
		)
		(fp_line
			(start 0.67945 0.3048)
			(end 0.120396 0.3048)
			(stroke
				(width 0.1)
				(type default)
			)
			(layer "F.Fab")
		)
		(fp_line
			(start -0.12065 0.2794)
			(end -0.12065 0.3048)
			(stroke
				(width 0.1)
				(type default)
			)
			(layer "F.Fab")
		)
		(fp_line
			(start 0.120396 0.2794)
			(end -0.12065 0.2794)
			(stroke
				(width 0.1)
				(type default)
			)
			(layer "F.Fab")
		)
		(fp_line
			(start -0.12065 -0.2794)
			(end 0.12065 -0.2794)
			(stroke
				(width 0.1)
				(type default)
			)
			(layer "F.Fab")
		)
		(fp_line
			(start 0.12065 -0.2794)
			(end 0.12065 -0.3048)
			(stroke
				(width 0.1)
				(type default)
			)
			(layer "F.Fab")
		)
		(fp_line
			(start 0.12065 -0.3048)
			(end 0.67945 -0.3048)
			(stroke
				(width 0.1)
				(type default)
			)
			(layer "F.Fab")
		)
		(fp_line
			(start 0.67945 -0.3048)
			(end 0.67945 0.3048)
			(stroke
				(width 0.1)
				(type default)
			)
			(layer "F.Fab")
		)
		(fp_line
			(start -0.67945 -0.305054)
			(end -0.12065 -0.305054)
			(stroke
				(width 0.1)
				(type default)
			)
			(layer "F.Fab")
		)
		(fp_line
			(start -0.12065 -0.305054)
			(end -0.12065 -0.2794)
			(stroke
				(width 0.1)
				(type default)
			)
			(layer "F.Fab")
		)
		(pad "1" smd circle
			(at -0.40005 0 270)
			(size 0 0)
			(layers "F.Cu" "F.Mask" "F.Paste")
			(net "SSD2_AUX_P3V3_EN_R")
		)
		(pad "2" smd circle
			(at 0.40005 0 270)
			(size 0 0)
			(layers "F.Cu" "F.Mask" "F.Paste")
			(net "P3V3_SSD2_CO_EN")
		)
	)
	(footprint ""
		(layer "F.Cu")
		(at 386.90804 -160.380934)
		(property "Reference" "R329"
			(at 0 0 0)
			(layer "F.SilkS")
			(hide yes)
			(effects
				(font
					(size 1.27 1.27)
				)
			)
		)
		(property "Value" ""
			(at 0 0 0)
			(layer "F.Fab")
			(effects
				(font
					(size 1.27 1.27)
				)
			)
		)
		(duplicate_pad_numbers_are_jumpers no)
		(fp_line
			(start -0.7874 -0.4064)
			(end 0.7874 -0.4064)
			(stroke
				(width 0.1524)
				(type default)
			)
			(layer "F.SilkS")
		)
		(fp_line
			(start -0.7874 0.4064)
			(end -0.7874 -0.4064)
			(stroke
				(width 0.1524)
				(type default)
			)
			(layer "F.SilkS")
		)
		(fp_line
			(start 0.7874 -0.4064)
			(end 0.7874 0.4064)
			(stroke
				(width 0.1524)
				(type default)
			)
			(layer "F.SilkS")
		)
		(fp_line
			(start 0.7874 0.4064)
			(end -0.7874 0.4064)
			(stroke
				(width 0.1524)
				(type default)
			)
			(layer "F.SilkS")
		)
		(fp_line
			(start -0.67945 -0.305054)
			(end -0.12065 -0.305054)
			(stroke
				(width 0.1)
				(type default)
			)
			(layer "F.Fab")
		)
		(fp_line
			(start -0.67945 0.3048)
			(end -0.67945 -0.305054)
			(stroke
				(width 0.1)
				(type default)
			)
			(layer "F.Fab")
		)
		(fp_line
			(start -0.12065 -0.305054)
			(end -0.12065 -0.2794)
			(stroke
				(width 0.1)
				(type default)
			)
			(layer "F.Fab")
		)
		(fp_line
			(start -0.12065 -0.2794)
			(end 0.12065 -0.2794)
			(stroke
				(width 0.1)
				(type default)
			)
			(layer "F.Fab")
		)
		(fp_line
			(start -0.12065 0.2794)
			(end -0.12065 0.3048)
			(stroke
				(width 0.1)
				(type default)
			)
			(layer "F.Fab")
		)
		(fp_line
			(start -0.12065 0.3048)
			(end -0.67945 0.3048)
			(stroke
				(width 0.1)
				(type default)
			)
			(layer "F.Fab")
		)
		(fp_line
			(start 0.120396 0.2794)
			(end -0.12065 0.2794)
			(stroke
				(width 0.1)
				(type default)
			)
			(layer "F.Fab")
		)
		(fp_line
			(start 0.120396 0.3048)
			(end 0.120396 0.2794)
			(stroke
				(width 0.1)
				(type default)
			)
			(layer "F.Fab")
		)
		(fp_line
			(start 0.12065 -0.3048)
			(end 0.67945 -0.3048)
			(stroke
				(width 0.1)
				(type default)
			)
			(layer "F.Fab")
		)
		(fp_line
			(start 0.12065 -0.2794)
			(end 0.12065 -0.3048)
			(stroke
				(width 0.1)
				(type default)
			)
			(layer "F.Fab")
		)
		(fp_line
			(start 0.67945 -0.3048)
			(end 0.67945 0.3048)
			(stroke
				(width 0.1)
				(type default)
			)
			(layer "F.Fab")
		)
		(fp_line
			(start 0.67945 0.3048)
			(end 0.120396 0.3048)
			(stroke
				(width 0.1)
				(type default)
			)
			(layer "F.Fab")
		)
		(pad "1" smd circle
			(at -0.40005 0)
			(size 0 0)
			(layers "F.Cu" "F.Mask" "F.Paste")
			(net "NIC6_MAIN_PWR_EN")
		)
		(pad "2" smd circle
			(at 0.40005 0)
			(size 0 0)
			(layers "F.Cu" "F.Mask" "F.Paste")
			(net "GND")
		)
	)
	(footprint ""
		(layer "F.Cu")
		(at 214.757 -207.264)
		(property "Reference" "U119"
			(at -4.578604 2.039112 0)
			(unlocked yes)
			(layer "F.SilkS")
			(effects
				(font
					(size 0.7874 0.5842)
					(thickness 0.1524)
				)
				(justify left)
			)
		)
		(property "Value" ""
			(at 0 0 0)
			(layer "F.Fab")
			(effects
				(font
					(size 1.27 1.27)
				)
			)
		)
		(duplicate_pad_numbers_are_jumpers no)
		(fp_line
			(start -1.3208 -1.525016)
			(end -0.508 -1.525016)
			(stroke
				(width 0.1524)
				(type default)
			)
			(layer "F.SilkS")
		)
		(fp_line
			(start -1.3208 1.525016)
			(end -1.3208 -1.525016)
			(stroke
				(width 0.1524)
				(type default)
			)
			(layer "F.SilkS")
		)
		(fp_line
			(start -0.508 -1.525016)
			(end 0 -0.999998)
			(stroke
				(width 0.1524)
				(type default)
			)
			(layer "F.SilkS")
		)
		(fp_line
			(start 0 -0.999998)
			(end 0.508 -1.525016)
			(stroke
				(width 0.1524)
				(type default)
			)
			(layer "F.SilkS")
		)
		(fp_line
			(start 0.508 -1.525016)
			(end 1.3208 -1.525016)
			(stroke
				(width 0.1524)
				(type default)
			)
			(layer "F.SilkS")
		)
		(fp_line
			(start 1.3208 -1.525016)
			(end 1.3208 1.525016)
			(stroke
				(width 0.1524)
				(type default)
			)
			(layer "F.SilkS")
		)
		(fp_line
			(start 1.3208 1.525016)
			(end -1.3208 1.525016)
			(stroke
				(width 0.1524)
				(type default)
			)
			(layer "F.SilkS")
		)
		(fp_poly
			(pts
				(xy -2.86512 -1.320038) (xy -3.673348 -1.589532) (xy -3.13436 -2.128266)
			)
			(stroke
				(width 0)
				(type default)
			)
			(fill yes)
			(layer "F.SilkS")
		)
		(fp_line
			(start -3.037078 -1.20777)
			(end -1.524 -1.20777)
			(stroke
				(width 0.1)
				(type default)
			)
			(layer "F.Fab")
		)
		(fp_line
			(start -3.037078 1.203706)
			(end -3.037078 -1.20777)
			(stroke
				(width 0.1)
				(type default)
			)
			(layer "F.Fab")
		)
		(fp_line
			(start -1.5494 1.203706)
			(end -3.037078 1.203706)
			(stroke
				(width 0.1)
				(type default)
			)
			(layer "F.Fab")
		)
		(fp_line
			(start -1.5494 1.5494)
			(end -1.5494 1.203706)
			(stroke
				(width 0.1)
				(type default)
			)
			(layer "F.Fab")
		)
		(fp_line
			(start -1.524 -1.524)
			(end 1.524 -1.524)
			(stroke
				(width 0.1)
				(type default)
			)
			(layer "F.Fab")
		)
		(fp_line
			(start -1.524 -1.20777)
			(end -1.524 -1.524)
			(stroke
				(width 0.1)
				(type default)
			)
			(layer "F.Fab")
		)
		(fp_line
			(start 1.524 -1.524)
			(end 1.524 -1.20777)
			(stroke
				(width 0.1)
				(type default)
			)
			(layer "F.Fab")
		)
		(fp_line
			(start 1.524 -1.20777)
			(end 3.0353 -1.20777)
			(stroke
				(width 0.1)
				(type default)
			)
			(layer "F.Fab")
		)
		(fp_line
			(start 1.524 1.208786)
			(end 1.524 1.5494)
			(stroke
				(width 0.1)
				(type default)
			)
			(layer "F.Fab")
		)
		(fp_line
			(start 1.524 1.5494)
			(end -1.5494 1.5494)
			(stroke
				(width 0.1)
				(type default)
			)
			(layer "F.Fab")
		)
		(fp_line
			(start 3.0353 -1.20777)
			(end 3.0353 1.208786)
			(stroke
				(width 0.1)
				(type default)
			)
			(layer "F.Fab")
		)
		(fp_line
			(start 3.0353 1.208786)
			(end 1.524 1.208786)
			(stroke
				(width 0.1)
				(type default)
			)
			(layer "F.Fab")
		)
		(fp_poly
			(pts
				(xy -3.175 -1.016) (xy -3.937 -0.635) (xy -3.937 -1.397)
			)
			(stroke
				(width 0)
				(type default)
			)
			(fill yes)
			(layer "F.Fab")
		)
		(pad "1" smd rect
			(at -2.234946 -0.975106 270)
			(size 0.3556 1.4986)
			(layers "F.Cu" "F.Mask" "F.Paste")
			(net "P1V2_AUX")
		)
		(pad "2" smd rect
			(at -2.234946 -0.32512 270)
			(size 0.3556 1.4986)
			(layers "F.Cu" "F.Mask" "F.Paste")
			(net "SMB_NIC4_R_SDA")
		)
		(pad "3" smd rect
			(at -2.234946 0.32512 270)
			(size 0.3556 1.4986)
			(layers "F.Cu" "F.Mask" "F.Paste")
			(net "SMB_NIC4_R_SCL")
		)
		(pad "4" smd rect
			(at -2.234946 0.975106 270)
			(size 0.3556 1.4986)
			(layers "F.Cu" "F.Mask" "F.Paste")
			(net "GND")
		)
		(pad "5" smd rect
			(at 2.234946 0.975106 270)
			(size 0.3556 1.4986)
			(layers "F.Cu" "F.Mask" "F.Paste")
			(net "SMB_NIC4_LS_EN")
		)
		(pad "6" smd rect
			(at 2.234946 0.32512 270)
			(size 0.3556 1.4986)
			(layers "F.Cu" "F.Mask" "F.Paste")
			(net "SMB_NIC4_LS_R_SCL")
		)
		(pad "7" smd rect
			(at 2.234946 -0.32512 270)
			(size 0.3556 1.4986)
			(layers "F.Cu" "F.Mask" "F.Paste")
			(net "SMB_NIC4_LS_R_SDA")
		)
		(pad "8" smd rect
			(at 2.234946 -0.975106 270)
			(size 0.3556 1.4986)
			(layers "F.Cu" "F.Mask" "F.Paste")
			(net "P3V3_NIC4")
		)
	)
	(footprint ""
		(layer "F.Cu")
		(at 355.854 -234.061 -90)
		(property "Reference" "R3593"
			(at 0 0 270)
			(layer "F.SilkS")
			(hide yes)
			(effects
				(font
					(size 1.27 1.27)
				)
			)
		)
		(property "Value" ""
			(at 0 0 270)
			(layer "F.Fab")
			(effects
				(font
					(size 1.27 1.27)
				)
			)
		)
		(duplicate_pad_numbers_are_jumpers no)
		(fp_line
			(start -0.7874 0.4064)
			(end -0.7874 -0.4064)
			(stroke
				(width 0.1524)
				(type default)
			)
			(layer "F.SilkS")
		)
		(fp_line
			(start 0.7874 0.4064)
			(end -0.7874 0.4064)
			(stroke
				(width 0.1524)
				(type default)
			)
			(layer "F.SilkS")
		)
		(fp_line
			(start -0.7874 -0.4064)
			(end 0.7874 -0.4064)
			(stroke
				(width 0.1524)
				(type default)
			)
			(layer "F.SilkS")
		)
		(fp_line
			(start 0.7874 -0.4064)
			(end 0.7874 0.4064)
			(stroke
				(width 0.1524)
				(type default)
			)
			(layer "F.SilkS")
		)
		(fp_line
			(start -0.67945 0.3048)
			(end -0.67945 -0.305054)
			(stroke
				(width 0.1)
				(type default)
			)
			(layer "F.Fab")
		)
		(fp_line
			(start -0.12065 0.3048)
			(end -0.67945 0.3048)
			(stroke
				(width 0.1)
				(type default)
			)
			(layer "F.Fab")
		)
		(fp_line
			(start 0.120396 0.3048)
			(end 0.120396 0.2794)
			(stroke
				(width 0.1)
				(type default)
			)
			(layer "F.Fab")
		)
		(fp_line
			(start 0.67945 0.3048)
			(end 0.120396 0.3048)
			(stroke
				(width 0.1)
				(type default)
			)
			(layer "F.Fab")
		)
		(fp_line
			(start -0.12065 0.2794)
			(end -0.12065 0.3048)
			(stroke
				(width 0.1)
				(type default)
			)
			(layer "F.Fab")
		)
		(fp_line
			(start 0.120396 0.2794)
			(end -0.12065 0.2794)
			(stroke
				(width 0.1)
				(type default)
			)
			(layer "F.Fab")
		)
		(fp_line
			(start -0.12065 -0.2794)
			(end 0.12065 -0.2794)
			(stroke
				(width 0.1)
				(type default)
			)
			(layer "F.Fab")
		)
		(fp_line
			(start 0.12065 -0.2794)
			(end 0.12065 -0.3048)
			(stroke
				(width 0.1)
				(type default)
			)
			(layer "F.Fab")
		)
		(fp_line
			(start 0.12065 -0.3048)
			(end 0.67945 -0.3048)
			(stroke
				(width 0.1)
				(type default)
			)
			(layer "F.Fab")
		)
		(fp_line
			(start 0.67945 -0.3048)
			(end 0.67945 0.3048)
			(stroke
				(width 0.1)
				(type default)
			)
			(layer "F.Fab")
		)
		(fp_line
			(start -0.67945 -0.305054)
			(end -0.12065 -0.305054)
			(stroke
				(width 0.1)
				(type default)
			)
			(layer "F.Fab")
		)
		(fp_line
			(start -0.12065 -0.305054)
			(end -0.12065 -0.2794)
			(stroke
				(width 0.1)
				(type default)
			)
			(layer "F.Fab")
		)
		(pad "1" smd circle
			(at -0.40005 0 270)
			(size 0 0)
			(layers "F.Cu" "F.Mask" "F.Paste")
			(net "SSD7_PWRDIS_R")
		)
		(pad "2" smd circle
			(at 0.40005 0 270)
			(size 0 0)
			(layers "F.Cu" "F.Mask" "F.Paste")
			(net "SSD7_PWRDIS")
		)
	)
	(footprint ""
		(layer "F.Cu")
		(at 340.561422 -187.36945 180)
		(property "Reference" "R4237"
			(at 0 0 180)
			(layer "F.SilkS")
			(hide yes)
			(effects
				(font
					(size 1.27 1.27)
				)
			)
		)
		(property "Value" ""
			(at 0 0 180)
			(layer "F.Fab")
			(effects
				(font
					(size 1.27 1.27)
				)
			)
		)
		(duplicate_pad_numbers_are_jumpers no)
		(fp_line
			(start 0.7874 0.4064)
			(end -0.7874 0.4064)
			(stroke
				(width 0.1524)
				(type default)
			)
			(layer "F.SilkS")
		)
		(fp_line
			(start 0.7874 -0.4064)
			(end 0.7874 0.4064)
			(stroke
				(width 0.1524)
				(type default)
			)
			(layer "F.SilkS")
		)
		(fp_line
			(start -0.7874 0.4064)
			(end -0.7874 -0.4064)
			(stroke
				(width 0.1524)
				(type default)
			)
			(layer "F.SilkS")
		)
		(fp_line
			(start -0.7874 -0.4064)
			(end 0.7874 -0.4064)
			(stroke
				(width 0.1524)
				(type default)
			)
			(layer "F.SilkS")
		)
		(fp_line
			(start 0.67945 0.3048)
			(end 0.120396 0.3048)
			(stroke
				(width 0.1)
				(type default)
			)
			(layer "F.Fab")
		)
		(fp_line
			(start 0.67945 -0.3048)
			(end 0.67945 0.3048)
			(stroke
				(width 0.1)
				(type default)
			)
			(layer "F.Fab")
		)
		(fp_line
			(start 0.12065 -0.2794)
			(end 0.12065 -0.3048)
			(stroke
				(width 0.1)
				(type default)
			)
			(layer "F.Fab")
		)
		(fp_line
			(start 0.12065 -0.3048)
			(end 0.67945 -0.3048)
			(stroke
				(width 0.1)
				(type default)
			)
			(layer "F.Fab")
		)
		(fp_line
			(start 0.120396 0.3048)
			(end 0.120396 0.2794)
			(stroke
				(width 0.1)
				(type default)
			)
			(layer "F.Fab")
		)
		(fp_line
			(start 0.120396 0.2794)
			(end -0.12065 0.2794)
			(stroke
				(width 0.1)
				(type default)
			)
			(layer "F.Fab")
		)
		(fp_line
			(start -0.12065 0.3048)
			(end -0.67945 0.3048)
			(stroke
				(width 0.1)
				(type default)
			)
			(layer "F.Fab")
		)
		(fp_line
			(start -0.12065 0.2794)
			(end -0.12065 0.3048)
			(stroke
				(width 0.1)
				(type default)
			)
			(layer "F.Fab")
		)
		(fp_line
			(start -0.12065 -0.2794)
			(end 0.12065 -0.2794)
			(stroke
				(width 0.1)
				(type default)
			)
			(layer "F.Fab")
		)
		(fp_line
			(start -0.12065 -0.305054)
			(end -0.12065 -0.2794)
			(stroke
				(width 0.1)
				(type default)
			)
			(layer "F.Fab")
		)
		(fp_line
			(start -0.67945 0.3048)
			(end -0.67945 -0.305054)
			(stroke
				(width 0.1)
				(type default)
			)
			(layer "F.Fab")
		)
		(fp_line
			(start -0.67945 -0.305054)
			(end -0.12065 -0.305054)
			(stroke
				(width 0.1)
				(type default)
			)
			(layer "F.Fab")
		)
		(pad "1" smd circle
			(at -0.40005 0 180)
			(size 0 0)
			(layers "F.Cu" "F.Mask" "F.Paste")
			(net "P3V3_AUX")
		)
		(pad "2" smd circle
			(at 0.40005 0 180)
			(size 0 0)
			(layers "F.Cu" "F.Mask" "F.Paste")
			(net "USB_DEBUG_RST_BTN_N")
		)
	)
	(footprint ""
		(layer "F.Cu")
		(at 231.844596 -280.583386 180)
		(property "Reference" "R786"
			(at 0 0 180)
			(layer "F.SilkS")
			(hide yes)
			(effects
				(font
					(size 1.27 1.27)
				)
			)
		)
		(property "Value" ""
			(at 0 0 180)
			(layer "F.Fab")
			(effects
				(font
					(size 1.27 1.27)
				)
			)
		)
		(duplicate_pad_numbers_are_jumpers no)
		(fp_line
			(start 0.7874 0.4064)
			(end -0.7874 0.4064)
			(stroke
				(width 0.1524)
				(type default)
			)
			(layer "F.SilkS")
		)
		(fp_line
			(start 0.7874 -0.4064)
			(end 0.7874 0.4064)
			(stroke
				(width 0.1524)
				(type default)
			)
			(layer "F.SilkS")
		)
		(fp_line
			(start -0.7874 0.4064)
			(end -0.7874 -0.4064)
			(stroke
				(width 0.1524)
				(type default)
			)
			(layer "F.SilkS")
		)
		(fp_line
			(start -0.7874 -0.4064)
			(end 0.7874 -0.4064)
			(stroke
				(width 0.1524)
				(type default)
			)
			(layer "F.SilkS")
		)
		(fp_line
			(start 0.67945 0.3048)
			(end 0.120396 0.3048)
			(stroke
				(width 0.1)
				(type default)
			)
			(layer "F.Fab")
		)
		(fp_line
			(start 0.67945 -0.3048)
			(end 0.67945 0.3048)
			(stroke
				(width 0.1)
				(type default)
			)
			(layer "F.Fab")
		)
		(fp_line
			(start 0.12065 -0.2794)
			(end 0.12065 -0.3048)
			(stroke
				(width 0.1)
				(type default)
			)
			(layer "F.Fab")
		)
		(fp_line
			(start 0.12065 -0.3048)
			(end 0.67945 -0.3048)
			(stroke
				(width 0.1)
				(type default)
			)
			(layer "F.Fab")
		)
		(fp_line
			(start 0.120396 0.3048)
			(end 0.120396 0.2794)
			(stroke
				(width 0.1)
				(type default)
			)
			(layer "F.Fab")
		)
		(fp_line
			(start 0.120396 0.2794)
			(end -0.12065 0.2794)
			(stroke
				(width 0.1)
				(type default)
			)
			(layer "F.Fab")
		)
		(fp_line
			(start -0.12065 0.3048)
			(end -0.67945 0.3048)
			(stroke
				(width 0.1)
				(type default)
			)
			(layer "F.Fab")
		)
		(fp_line
			(start -0.12065 0.2794)
			(end -0.12065 0.3048)
			(stroke
				(width 0.1)
				(type default)
			)
			(layer "F.Fab")
		)
		(fp_line
			(start -0.12065 -0.2794)
			(end 0.12065 -0.2794)
			(stroke
				(width 0.1)
				(type default)
			)
			(layer "F.Fab")
		)
		(fp_line
			(start -0.12065 -0.305054)
			(end -0.12065 -0.2794)
			(stroke
				(width 0.1)
				(type default)
			)
			(layer "F.Fab")
		)
		(fp_line
			(start -0.67945 0.3048)
			(end -0.67945 -0.305054)
			(stroke
				(width 0.1)
				(type default)
			)
			(layer "F.Fab")
		)
		(fp_line
			(start -0.67945 -0.305054)
			(end -0.12065 -0.305054)
			(stroke
				(width 0.1)
				(type default)
			)
			(layer "F.Fab")
		)
		(pad "1" smd circle
			(at -0.40005 0 180)
			(size 0 0)
			(layers "F.Cu" "F.Mask" "F.Paste")
			(net "SMB_BIC_I2C6_MUX_PEX_ADC_R_SCL")
		)
		(pad "2" smd circle
			(at 0.40005 0 180)
			(size 0 0)
			(layers "F.Cu" "F.Mask" "F.Paste")
			(net "SMB_PEX1_P1V25_ADC_SCL")
		)
	)
	(footprint ""
		(layer "F.Cu")
		(at 385.79679 -246.059706 180)
		(property "Reference" "C2574"
			(at 0 0 180)
			(layer "F.SilkS")
			(hide yes)
			(effects
				(font
					(size 1.27 1.27)
				)
			)
		)
		(property "Value" ""
			(at 0 0 180)
			(layer "F.Fab")
			(effects
				(font
					(size 1.27 1.27)
				)
			)
		)
		(duplicate_pad_numbers_are_jumpers no)
		(fp_line
			(start 0.7874 0.4064)
			(end -0.7874 0.4064)
			(stroke
				(width 0.1524)
				(type default)
			)
			(layer "F.SilkS")
		)
		(fp_line
			(start 0.7874 -0.4064)
			(end 0.7874 0.4064)
			(stroke
				(width 0.1524)
				(type default)
			)
			(layer "F.SilkS")
		)
		(fp_line
			(start -0.7874 0.4064)
			(end -0.7874 -0.4064)
			(stroke
				(width 0.1524)
				(type default)
			)
			(layer "F.SilkS")
		)
		(fp_line
			(start -0.7874 -0.4064)
			(end 0.7874 -0.4064)
			(stroke
				(width 0.1524)
				(type default)
			)
			(layer "F.SilkS")
		)
		(fp_line
			(start 0.67945 0.3048)
			(end 0.120396 0.3048)
			(stroke
				(width 0.1)
				(type default)
			)
			(layer "F.Fab")
		)
		(fp_line
			(start 0.67945 -0.3048)
			(end 0.67945 0.3048)
			(stroke
				(width 0.1)
				(type default)
			)
			(layer "F.Fab")
		)
		(fp_line
			(start 0.12065 -0.2794)
			(end 0.12065 -0.3048)
			(stroke
				(width 0.1)
				(type default)
			)
			(layer "F.Fab")
		)
		(fp_line
			(start 0.12065 -0.3048)
			(end 0.67945 -0.3048)
			(stroke
				(width 0.1)
				(type default)
			)
			(layer "F.Fab")
		)
		(fp_line
			(start 0.120396 0.3048)
			(end 0.120396 0.2794)
			(stroke
				(width 0.1)
				(type default)
			)
			(layer "F.Fab")
		)
		(fp_line
			(start 0.120396 0.2794)
			(end -0.12065 0.2794)
			(stroke
				(width 0.1)
				(type default)
			)
			(layer "F.Fab")
		)
		(fp_line
			(start -0.12065 0.3048)
			(end -0.67945 0.3048)
			(stroke
				(width 0.1)
				(type default)
			)
			(layer "F.Fab")
		)
		(fp_line
			(start -0.12065 0.2794)
			(end -0.12065 0.3048)
			(stroke
				(width 0.1)
				(type default)
			)
			(layer "F.Fab")
		)
		(fp_line
			(start -0.12065 -0.2794)
			(end 0.12065 -0.2794)
			(stroke
				(width 0.1)
				(type default)
			)
			(layer "F.Fab")
		)
		(fp_line
			(start -0.12065 -0.305054)
			(end -0.12065 -0.2794)
			(stroke
				(width 0.1)
				(type default)
			)
			(layer "F.Fab")
		)
		(fp_line
			(start -0.67945 0.3048)
			(end -0.67945 -0.305054)
			(stroke
				(width 0.1)
				(type default)
			)
			(layer "F.Fab")
		)
		(fp_line
			(start -0.67945 -0.305054)
			(end -0.12065 -0.305054)
			(stroke
				(width 0.1)
				(type default)
			)
			(layer "F.Fab")
		)
		(pad "1" smd circle
			(at -0.40005 0 180)
			(size 0 0)
			(layers "F.Cu" "F.Mask" "F.Paste")
			(net "P1V8_SDB_VCORE")
		)
		(pad "2" smd circle
			(at 0.40005 0 180)
			(size 0 0)
			(layers "F.Cu" "F.Mask" "F.Paste")
			(net "GND")
		)
	)
	(footprint ""
		(layer "F.Cu")
		(at 371.12067 -70.307454 90)
		(property "Reference" "PC888"
			(at 0 0 90)
			(layer "F.SilkS")
			(hide yes)
			(effects
				(font
					(size 1.27 1.27)
				)
			)
		)
		(property "Value" ""
			(at 0 0 90)
			(layer "F.Fab")
			(effects
				(font
					(size 1.27 1.27)
				)
			)
		)
		(duplicate_pad_numbers_are_jumpers no)
		(fp_line
			(start 0.7874 -0.4064)
			(end 0.7874 0.4064)
			(stroke
				(width 0.1524)
				(type default)
			)
			(layer "F.SilkS")
		)
		(fp_line
			(start -0.7874 -0.4064)
			(end 0.7874 -0.4064)
			(stroke
				(width 0.1524)
				(type default)
			)
			(layer "F.SilkS")
		)
		(fp_line
			(start 0.7874 0.4064)
			(end -0.7874 0.4064)
			(stroke
				(width 0.1524)
				(type default)
			)
			(layer "F.SilkS")
		)
		(fp_line
			(start -0.7874 0.4064)
			(end -0.7874 -0.4064)
			(stroke
				(width 0.1524)
				(type default)
			)
			(layer "F.SilkS")
		)
		(fp_line
			(start -0.12065 -0.305054)
			(end -0.12065 -0.2794)
			(stroke
				(width 0.1)
				(type default)
			)
			(layer "F.Fab")
		)
		(fp_line
			(start -0.67945 -0.305054)
			(end -0.12065 -0.305054)
			(stroke
				(width 0.1)
				(type default)
			)
			(layer "F.Fab")
		)
		(fp_line
			(start 0.67945 -0.3048)
			(end 0.67945 0.3048)
			(stroke
				(width 0.1)
				(type default)
			)
			(layer "F.Fab")
		)
		(fp_line
			(start 0.12065 -0.3048)
			(end 0.67945 -0.3048)
			(stroke
				(width 0.1)
				(type default)
			)
			(layer "F.Fab")
		)
		(fp_line
			(start 0.12065 -0.2794)
			(end 0.12065 -0.3048)
			(stroke
				(width 0.1)
				(type default)
			)
			(layer "F.Fab")
		)
		(fp_line
			(start -0.12065 -0.2794)
			(end 0.12065 -0.2794)
			(stroke
				(width 0.1)
				(type default)
			)
			(layer "F.Fab")
		)
		(fp_line
			(start 0.120396 0.2794)
			(end -0.12065 0.2794)
			(stroke
				(width 0.1)
				(type default)
			)
			(layer "F.Fab")
		)
		(fp_line
			(start -0.12065 0.2794)
			(end -0.12065 0.3048)
			(stroke
				(width 0.1)
				(type default)
			)
			(layer "F.Fab")
		)
		(fp_line
			(start 0.67945 0.3048)
			(end 0.120396 0.3048)
			(stroke
				(width 0.1)
				(type default)
			)
			(layer "F.Fab")
		)
		(fp_line
			(start 0.120396 0.3048)
			(end 0.120396 0.2794)
			(stroke
				(width 0.1)
				(type default)
			)
			(layer "F.Fab")
		)
		(fp_line
			(start -0.12065 0.3048)
			(end -0.67945 0.3048)
			(stroke
				(width 0.1)
				(type default)
			)
			(layer "F.Fab")
		)
		(fp_line
			(start -0.67945 0.3048)
			(end -0.67945 -0.305054)
			(stroke
				(width 0.1)
				(type default)
			)
			(layer "F.Fab")
		)
		(pad "1" smd circle
			(at -0.40005 0 90)
			(size 0 0)
			(layers "F.Cu" "F.Mask" "F.Paste")
			(net "P12V_AUX")
		)
		(pad "2" smd circle
			(at 0.40005 0 90)
			(size 0 0)
			(layers "F.Cu" "F.Mask" "F.Paste")
			(net "GND")
		)
	)
	(footprint ""
		(layer "F.Cu")
		(at 155.380436 -107.403138)
		(property "Reference" "C267"
			(at 0 0 0)
			(layer "F.SilkS")
			(hide yes)
			(effects
				(font
					(size 1.27 1.27)
				)
			)
		)
		(property "Value" ""
			(at 0 0 0)
			(layer "F.Fab")
			(effects
				(font
					(size 1.27 1.27)
				)
			)
		)
		(duplicate_pad_numbers_are_jumpers no)
		(fp_line
			(start -0.299974 -0.150114)
			(end 0.299974 -0.150114)
			(stroke
				(width 0.1)
				(type default)
			)
			(layer "F.Fab")
		)
		(fp_line
			(start -0.299974 0.150114)
			(end -0.299974 -0.150114)
			(stroke
				(width 0.1)
				(type default)
			)
			(layer "F.Fab")
		)
		(fp_line
			(start 0.299974 -0.150114)
			(end 0.299974 0.150114)
			(stroke
				(width 0.1)
				(type default)
			)
			(layer "F.Fab")
		)
		(fp_line
			(start 0.299974 0.150114)
			(end -0.299974 0.150114)
			(stroke
				(width 0.1)
				(type default)
			)
			(layer "F.Fab")
		)
		(pad "1" smd rect
			(at -0.2667 0)
			(size 0.3048 0.381)
			(layers "F.Cu" "F.Mask" "F.Paste")
			(net "P5E_PEX1_STN1_TX_DN<20>")
		)
		(pad "2" smd rect
			(at 0.2667 0)
			(size 0.3048 0.381)
			(layers "F.Cu" "F.Mask" "F.Paste")
			(net "P5E_PEX1_STN1_TX_C_DN<20>")
		)
	)
	(footprint ""
		(layer "F.Cu")
		(at 413.293052 -350.098614 90)
		(property "Reference" "C823"
			(at 0 0 90)
			(layer "F.SilkS")
			(hide yes)
			(effects
				(font
					(size 1.27 1.27)
				)
			)
		)
		(property "Value" ""
			(at 0 0 90)
			(layer "F.Fab")
			(effects
				(font
					(size 1.27 1.27)
				)
			)
		)
		(duplicate_pad_numbers_are_jumpers no)
		(fp_line
			(start 0.299974 -0.150114)
			(end 0.299974 0.150114)
			(stroke
				(width 0.1)
				(type default)
			)
			(layer "F.Fab")
		)
		(fp_line
			(start -0.299974 -0.150114)
			(end 0.299974 -0.150114)
			(stroke
				(width 0.1)
				(type default)
			)
			(layer "F.Fab")
		)
		(fp_line
			(start 0.299974 0.150114)
			(end -0.299974 0.150114)
			(stroke
				(width 0.1)
				(type default)
			)
			(layer "F.Fab")
		)
		(fp_line
			(start -0.299974 0.150114)
			(end -0.299974 -0.150114)
			(stroke
				(width 0.1)
				(type default)
			)
			(layer "F.Fab")
		)
		(pad "1" smd rect
			(at -0.2667 0 90)
			(size 0.3048 0.381)
			(layers "F.Cu" "F.Mask" "F.Paste")
			(net "P5E_PEX3_STN7_TX_DN<113>")
		)
		(pad "2" smd rect
			(at 0.2667 0 90)
			(size 0.3048 0.381)
			(layers "F.Cu" "F.Mask" "F.Paste")
			(net "P5E_PEX3_STN7_TX_C_DN<113>")
		)
	)
	(footprint ""
		(layer "F.Cu")
		(at 439.168032 -289.230816 90)
		(property "Reference" "R4004"
			(at 0 0 90)
			(layer "F.SilkS")
			(hide yes)
			(effects
				(font
					(size 1.27 1.27)
				)
			)
		)
		(property "Value" ""
			(at 0 0 90)
			(layer "F.Fab")
			(effects
				(font
					(size 1.27 1.27)
				)
			)
		)
		(duplicate_pad_numbers_are_jumpers no)
		(fp_line
			(start 0.7874 -0.4064)
			(end 0.7874 0.4064)
			(stroke
				(width 0.1524)
				(type default)
			)
			(layer "F.SilkS")
		)
		(fp_line
			(start -0.7874 -0.4064)
			(end 0.7874 -0.4064)
			(stroke
				(width 0.1524)
				(type default)
			)
			(layer "F.SilkS")
		)
		(fp_line
			(start 0.7874 0.4064)
			(end -0.7874 0.4064)
			(stroke
				(width 0.1524)
				(type default)
			)
			(layer "F.SilkS")
		)
		(fp_line
			(start -0.7874 0.4064)
			(end -0.7874 -0.4064)
			(stroke
				(width 0.1524)
				(type default)
			)
			(layer "F.SilkS")
		)
		(fp_line
			(start -0.12065 -0.305054)
			(end -0.12065 -0.2794)
			(stroke
				(width 0.1)
				(type default)
			)
			(layer "F.Fab")
		)
		(fp_line
			(start -0.67945 -0.305054)
			(end -0.12065 -0.305054)
			(stroke
				(width 0.1)
				(type default)
			)
			(layer "F.Fab")
		)
		(fp_line
			(start 0.67945 -0.3048)
			(end 0.67945 0.3048)
			(stroke
				(width 0.1)
				(type default)
			)
			(layer "F.Fab")
		)
		(fp_line
			(start 0.12065 -0.3048)
			(end 0.67945 -0.3048)
			(stroke
				(width 0.1)
				(type default)
			)
			(layer "F.Fab")
		)
		(fp_line
			(start 0.12065 -0.2794)
			(end 0.12065 -0.3048)
			(stroke
				(width 0.1)
				(type default)
			)
			(layer "F.Fab")
		)
		(fp_line
			(start -0.12065 -0.2794)
			(end 0.12065 -0.2794)
			(stroke
				(width 0.1)
				(type default)
			)
			(layer "F.Fab")
		)
		(fp_line
			(start 0.120396 0.2794)
			(end -0.12065 0.2794)
			(stroke
				(width 0.1)
				(type default)
			)
			(layer "F.Fab")
		)
		(fp_line
			(start -0.12065 0.2794)
			(end -0.12065 0.3048)
			(stroke
				(width 0.1)
				(type default)
			)
			(layer "F.Fab")
		)
		(fp_line
			(start 0.67945 0.3048)
			(end 0.120396 0.3048)
			(stroke
				(width 0.1)
				(type default)
			)
			(layer "F.Fab")
		)
		(fp_line
			(start 0.120396 0.3048)
			(end 0.120396 0.2794)
			(stroke
				(width 0.1)
				(type default)
			)
			(layer "F.Fab")
		)
		(fp_line
			(start -0.12065 0.3048)
			(end -0.67945 0.3048)
			(stroke
				(width 0.1)
				(type default)
			)
			(layer "F.Fab")
		)
		(fp_line
			(start -0.67945 0.3048)
			(end -0.67945 -0.305054)
			(stroke
				(width 0.1)
				(type default)
			)
			(layer "F.Fab")
		)
		(pad "1" smd circle
			(at -0.40005 0 90)
			(size 0 0)
			(layers "F.Cu" "F.Mask" "F.Paste")
			(net "SMB_PEX3_FPGA_SCL")
		)
		(pad "2" smd circle
			(at 0.40005 0 90)
			(size 0 0)
			(layers "F.Cu" "F.Mask" "F.Paste")
			(net "SMB_PEX3_HOST_LS_SCL")
		)
	)
	(footprint ""
		(layer "F.Cu")
		(at 277.67153 -25.342342 -90)
		(property "Reference" "R436"
			(at 0 0 270)
			(layer "F.SilkS")
			(hide yes)
			(effects
				(font
					(size 1.27 1.27)
				)
			)
		)
		(property "Value" ""
			(at 0 0 270)
			(layer "F.Fab")
			(effects
				(font
					(size 1.27 1.27)
				)
			)
		)
		(duplicate_pad_numbers_are_jumpers no)
		(fp_line
			(start -0.7874 0.4064)
			(end -0.7874 -0.4064)
			(stroke
				(width 0.1524)
				(type default)
			)
			(layer "F.SilkS")
		)
		(fp_line
			(start 0.7874 0.4064)
			(end -0.7874 0.4064)
			(stroke
				(width 0.1524)
				(type default)
			)
			(layer "F.SilkS")
		)
		(fp_line
			(start -0.7874 -0.4064)
			(end 0.7874 -0.4064)
			(stroke
				(width 0.1524)
				(type default)
			)
			(layer "F.SilkS")
		)
		(fp_line
			(start 0.7874 -0.4064)
			(end 0.7874 0.4064)
			(stroke
				(width 0.1524)
				(type default)
			)
			(layer "F.SilkS")
		)
		(fp_line
			(start -0.67945 0.3048)
			(end -0.67945 -0.305054)
			(stroke
				(width 0.1)
				(type default)
			)
			(layer "F.Fab")
		)
		(fp_line
			(start -0.12065 0.3048)
			(end -0.67945 0.3048)
			(stroke
				(width 0.1)
				(type default)
			)
			(layer "F.Fab")
		)
		(fp_line
			(start 0.120396 0.3048)
			(end 0.120396 0.2794)
			(stroke
				(width 0.1)
				(type default)
			)
			(layer "F.Fab")
		)
		(fp_line
			(start 0.67945 0.3048)
			(end 0.120396 0.3048)
			(stroke
				(width 0.1)
				(type default)
			)
			(layer "F.Fab")
		)
		(fp_line
			(start -0.12065 0.2794)
			(end -0.12065 0.3048)
			(stroke
				(width 0.1)
				(type default)
			)
			(layer "F.Fab")
		)
		(fp_line
			(start 0.120396 0.2794)
			(end -0.12065 0.2794)
			(stroke
				(width 0.1)
				(type default)
			)
			(layer "F.Fab")
		)
		(fp_line
			(start -0.12065 -0.2794)
			(end 0.12065 -0.2794)
			(stroke
				(width 0.1)
				(type default)
			)
			(layer "F.Fab")
		)
		(fp_line
			(start 0.12065 -0.2794)
			(end 0.12065 -0.3048)
			(stroke
				(width 0.1)
				(type default)
			)
			(layer "F.Fab")
		)
		(fp_line
			(start 0.12065 -0.3048)
			(end 0.67945 -0.3048)
			(stroke
				(width 0.1)
				(type default)
			)
			(layer "F.Fab")
		)
		(fp_line
			(start 0.67945 -0.3048)
			(end 0.67945 0.3048)
			(stroke
				(width 0.1)
				(type default)
			)
			(layer "F.Fab")
		)
		(fp_line
			(start -0.67945 -0.305054)
			(end -0.12065 -0.305054)
			(stroke
				(width 0.1)
				(type default)
			)
			(layer "F.Fab")
		)
		(fp_line
			(start -0.12065 -0.305054)
			(end -0.12065 -0.2794)
			(stroke
				(width 0.1)
				(type default)
			)
			(layer "F.Fab")
		)
		(pad "1" smd circle
			(at -0.40005 0 270)
			(size 0 0)
			(layers "F.Cu" "F.Mask" "F.Paste")
			(net "P3V3_SSD9")
		)
		(pad "2" smd circle
			(at 0.40005 0 270)
			(size 0 0)
			(layers "F.Cu" "F.Mask" "F.Paste")
			(net "DUALPORT_N_SSD9")
		)
	)
	(footprint ""
		(layer "F.Cu")
		(at 467.68893 -524.540988 180)
		(property "Reference" "SCREW_SSD1_1"
			(at -5.207 -1.402334 0)
			(unlocked yes)
			(layer "B.SilkS")
			(effects
				(font
					(size 0.7874 0.5842)
					(thickness 0.1524)
				)
				(justify mirror)
			)
		)
		(property "Value" ""
			(at 0 0 180)
			(layer "F.Fab")
			(effects
				(font
					(size 1.27 1.27)
				)
			)
		)
		(duplicate_pad_numbers_are_jumpers no)
		(pad "1" thru_hole circle
			(at 0 0 180)
			(size 0.4572 0.4572)
			(drill 0.2032)
			(layers "*.Cu" "*.Mask")
			(remove_unused_layers no)
			(net "Net_9142")
			(clearance 0.127)
			(thermal_gap 0.127)
			(padstack
				(mode front_inner_back)
				(layer "Inner"
					(shape circle)
					(size 0.4572 0.4572)
					(clearance 0.127)
				)
				(layer "B.Cu"
					(shape circle)
					(size 0.508 0.508)
					(clearance 0.1016)
				)
			)
		)
	)
	(footprint ""
		(layer "F.Cu")
		(at 249.733562 -209.590386)
		(property "Reference" "R5538"
			(at 0 0 0)
			(layer "F.SilkS")
			(hide yes)
			(effects
				(font
					(size 1.27 1.27)
				)
			)
		)
		(property "Value" ""
			(at 0 0 0)
			(layer "F.Fab")
			(effects
				(font
					(size 1.27 1.27)
				)
			)
		)
		(duplicate_pad_numbers_are_jumpers no)
		(fp_line
			(start -0.7874 -0.4064)
			(end 0.7874 -0.4064)
			(stroke
				(width 0.1524)
				(type default)
			)
			(layer "F.SilkS")
		)
		(fp_line
			(start -0.7874 0.4064)
			(end -0.7874 -0.4064)
			(stroke
				(width 0.1524)
				(type default)
			)
			(layer "F.SilkS")
		)
		(fp_line
			(start 0.7874 -0.4064)
			(end 0.7874 0.4064)
			(stroke
				(width 0.1524)
				(type default)
			)
			(layer "F.SilkS")
		)
		(fp_line
			(start 0.7874 0.4064)
			(end -0.7874 0.4064)
			(stroke
				(width 0.1524)
				(type default)
			)
			(layer "F.SilkS")
		)
		(fp_line
			(start -0.67945 -0.305054)
			(end -0.12065 -0.305054)
			(stroke
				(width 0.1)
				(type default)
			)
			(layer "F.Fab")
		)
		(fp_line
			(start -0.67945 0.3048)
			(end -0.67945 -0.305054)
			(stroke
				(width 0.1)
				(type default)
			)
			(layer "F.Fab")
		)
		(fp_line
			(start -0.12065 -0.305054)
			(end -0.12065 -0.2794)
			(stroke
				(width 0.1)
				(type default)
			)
			(layer "F.Fab")
		)
		(fp_line
			(start -0.12065 -0.2794)
			(end 0.12065 -0.2794)
			(stroke
				(width 0.1)
				(type default)
			)
			(layer "F.Fab")
		)
		(fp_line
			(start -0.12065 0.2794)
			(end -0.12065 0.3048)
			(stroke
				(width 0.1)
				(type default)
			)
			(layer "F.Fab")
		)
		(fp_line
			(start -0.12065 0.3048)
			(end -0.67945 0.3048)
			(stroke
				(width 0.1)
				(type default)
			)
			(layer "F.Fab")
		)
		(fp_line
			(start 0.120396 0.2794)
			(end -0.12065 0.2794)
			(stroke
				(width 0.1)
				(type default)
			)
			(layer "F.Fab")
		)
		(fp_line
			(start 0.120396 0.3048)
			(end 0.120396 0.2794)
			(stroke
				(width 0.1)
				(type default)
			)
			(layer "F.Fab")
		)
		(fp_line
			(start 0.12065 -0.3048)
			(end 0.67945 -0.3048)
			(stroke
				(width 0.1)
				(type default)
			)
			(layer "F.Fab")
		)
		(fp_line
			(start 0.12065 -0.2794)
			(end 0.12065 -0.3048)
			(stroke
				(width 0.1)
				(type default)
			)
			(layer "F.Fab")
		)
		(fp_line
			(start 0.67945 -0.3048)
			(end 0.67945 0.3048)
			(stroke
				(width 0.1)
				(type default)
			)
			(layer "F.Fab")
		)
		(fp_line
			(start 0.67945 0.3048)
			(end 0.120396 0.3048)
			(stroke
				(width 0.1)
				(type default)
			)
			(layer "F.Fab")
		)
		(pad "1" smd circle
			(at -0.40005 0)
			(size 0 0)
			(layers "F.Cu" "F.Mask" "F.Paste")
			(net "PWRGD_P1V2_AUX_R")
		)
		(pad "2" smd circle
			(at 0.40005 0)
			(size 0 0)
			(layers "F.Cu" "F.Mask" "F.Paste")
			(net "PWRGD_P1V2_AUX")
		)
	)
	(footprint ""
		(layer "F.Cu")
		(at 58.995056 -97.718372 180)
		(property "Reference" "R99"
			(at 0 0 180)
			(layer "F.SilkS")
			(hide yes)
			(effects
				(font
					(size 1.27 1.27)
				)
			)
		)
		(property "Value" ""
			(at 0 0 180)
			(layer "F.Fab")
			(effects
				(font
					(size 1.27 1.27)
				)
			)
		)
		(duplicate_pad_numbers_are_jumpers no)
		(fp_line
			(start 0.7874 0.4064)
			(end -0.7874 0.4064)
			(stroke
				(width 0.1524)
				(type default)
			)
			(layer "F.SilkS")
		)
		(fp_line
			(start 0.7874 -0.4064)
			(end 0.7874 0.4064)
			(stroke
				(width 0.1524)
				(type default)
			)
			(layer "F.SilkS")
		)
		(fp_line
			(start -0.7874 0.4064)
			(end -0.7874 -0.4064)
			(stroke
				(width 0.1524)
				(type default)
			)
			(layer "F.SilkS")
		)
		(fp_line
			(start -0.7874 -0.4064)
			(end 0.7874 -0.4064)
			(stroke
				(width 0.1524)
				(type default)
			)
			(layer "F.SilkS")
		)
		(fp_line
			(start 0.67945 0.3048)
			(end 0.120396 0.3048)
			(stroke
				(width 0.1)
				(type default)
			)
			(layer "F.Fab")
		)
		(fp_line
			(start 0.67945 -0.3048)
			(end 0.67945 0.3048)
			(stroke
				(width 0.1)
				(type default)
			)
			(layer "F.Fab")
		)
		(fp_line
			(start 0.12065 -0.2794)
			(end 0.12065 -0.3048)
			(stroke
				(width 0.1)
				(type default)
			)
			(layer "F.Fab")
		)
		(fp_line
			(start 0.12065 -0.3048)
			(end 0.67945 -0.3048)
			(stroke
				(width 0.1)
				(type default)
			)
			(layer "F.Fab")
		)
		(fp_line
			(start 0.120396 0.3048)
			(end 0.120396 0.2794)
			(stroke
				(width 0.1)
				(type default)
			)
			(layer "F.Fab")
		)
		(fp_line
			(start 0.120396 0.2794)
			(end -0.12065 0.2794)
			(stroke
				(width 0.1)
				(type default)
			)
			(layer "F.Fab")
		)
		(fp_line
			(start -0.12065 0.3048)
			(end -0.67945 0.3048)
			(stroke
				(width 0.1)
				(type default)
			)
			(layer "F.Fab")
		)
		(fp_line
			(start -0.12065 0.2794)
			(end -0.12065 0.3048)
			(stroke
				(width 0.1)
				(type default)
			)
			(layer "F.Fab")
		)
		(fp_line
			(start -0.12065 -0.2794)
			(end 0.12065 -0.2794)
			(stroke
				(width 0.1)
				(type default)
			)
			(layer "F.Fab")
		)
		(fp_line
			(start -0.12065 -0.305054)
			(end -0.12065 -0.2794)
			(stroke
				(width 0.1)
				(type default)
			)
			(layer "F.Fab")
		)
		(fp_line
			(start -0.67945 0.3048)
			(end -0.67945 -0.305054)
			(stroke
				(width 0.1)
				(type default)
			)
			(layer "F.Fab")
		)
		(fp_line
			(start -0.67945 -0.305054)
			(end -0.12065 -0.305054)
			(stroke
				(width 0.1)
				(type default)
			)
			(layer "F.Fab")
		)
		(pad "1" smd circle
			(at -0.40005 0 180)
			(size 0 0)
			(layers "F.Cu" "F.Mask" "F.Paste")
			(net "RST_NIC1_PERST3_R_N")
		)
		(pad "2" smd circle
			(at 0.40005 0 180)
			(size 0 0)
			(layers "F.Cu" "F.Mask" "F.Paste")
			(net "RST_HP_NIC1_BUF_N")
		)
	)
	(footprint ""
		(layer "F.Cu")
		(at 340.320884 -116.230654 -90)
		(property "Reference" "R953"
			(at 0 0 270)
			(layer "F.SilkS")
			(hide yes)
			(effects
				(font
					(size 1.27 1.27)
				)
			)
		)
		(property "Value" ""
			(at 0 0 270)
			(layer "F.Fab")
			(effects
				(font
					(size 1.27 1.27)
				)
			)
		)
		(duplicate_pad_numbers_are_jumpers no)
		(fp_line
			(start -0.7874 0.4064)
			(end -0.7874 -0.4064)
			(stroke
				(width 0.1524)
				(type default)
			)
			(layer "F.SilkS")
		)
		(fp_line
			(start 0.7874 0.4064)
			(end -0.7874 0.4064)
			(stroke
				(width 0.1524)
				(type default)
			)
			(layer "F.SilkS")
		)
		(fp_line
			(start -0.7874 -0.4064)
			(end 0.7874 -0.4064)
			(stroke
				(width 0.1524)
				(type default)
			)
			(layer "F.SilkS")
		)
		(fp_line
			(start 0.7874 -0.4064)
			(end 0.7874 0.4064)
			(stroke
				(width 0.1524)
				(type default)
			)
			(layer "F.SilkS")
		)
		(fp_line
			(start -0.67945 0.3048)
			(end -0.67945 -0.305054)
			(stroke
				(width 0.1)
				(type default)
			)
			(layer "F.Fab")
		)
		(fp_line
			(start -0.12065 0.3048)
			(end -0.67945 0.3048)
			(stroke
				(width 0.1)
				(type default)
			)
			(layer "F.Fab")
		)
		(fp_line
			(start 0.120396 0.3048)
			(end 0.120396 0.2794)
			(stroke
				(width 0.1)
				(type default)
			)
			(layer "F.Fab")
		)
		(fp_line
			(start 0.67945 0.3048)
			(end 0.120396 0.3048)
			(stroke
				(width 0.1)
				(type default)
			)
			(layer "F.Fab")
		)
		(fp_line
			(start -0.12065 0.2794)
			(end -0.12065 0.3048)
			(stroke
				(width 0.1)
				(type default)
			)
			(layer "F.Fab")
		)
		(fp_line
			(start 0.120396 0.2794)
			(end -0.12065 0.2794)
			(stroke
				(width 0.1)
				(type default)
			)
			(layer "F.Fab")
		)
		(fp_line
			(start -0.12065 -0.2794)
			(end 0.12065 -0.2794)
			(stroke
				(width 0.1)
				(type default)
			)
			(layer "F.Fab")
		)
		(fp_line
			(start 0.12065 -0.2794)
			(end 0.12065 -0.3048)
			(stroke
				(width 0.1)
				(type default)
			)
			(layer "F.Fab")
		)
		(fp_line
			(start 0.12065 -0.3048)
			(end 0.67945 -0.3048)
			(stroke
				(width 0.1)
				(type default)
			)
			(layer "F.Fab")
		)
		(fp_line
			(start 0.67945 -0.3048)
			(end 0.67945 0.3048)
			(stroke
				(width 0.1)
				(type default)
			)
			(layer "F.Fab")
		)
		(fp_line
			(start -0.67945 -0.305054)
			(end -0.12065 -0.305054)
			(stroke
				(width 0.1)
				(type default)
			)
			(layer "F.Fab")
		)
		(fp_line
			(start -0.12065 -0.305054)
			(end -0.12065 -0.2794)
			(stroke
				(width 0.1)
				(type default)
			)
			(layer "F.Fab")
		)
		(pad "1" smd circle
			(at -0.40005 0 270)
			(size 0 0)
			(layers "F.Cu" "F.Mask" "F.Paste")
			(net "P3V3_AUX")
		)
		(pad "2" smd circle
			(at 0.40005 0 270)
			(size 0 0)
			(layers "F.Cu" "F.Mask" "F.Paste")
			(net "PWRGD_P12V_NIC5_CO")
		)
	)
	(footprint ""
		(layer "F.Cu")
		(at 238.124746 -114.666268)
		(property "Reference" "PC636"
			(at 0 0 0)
			(layer "F.SilkS")
			(hide yes)
			(effects
				(font
					(size 1.27 1.27)
				)
			)
		)
		(property "Value" ""
			(at 0 0 0)
			(layer "F.Fab")
			(effects
				(font
					(size 1.27 1.27)
				)
			)
		)
		(duplicate_pad_numbers_are_jumpers no)
		(fp_line
			(start -0.7874 -0.4064)
			(end 0.7874 -0.4064)
			(stroke
				(width 0.1524)
				(type default)
			)
			(layer "F.SilkS")
		)
		(fp_line
			(start -0.7874 0.4064)
			(end -0.7874 -0.4064)
			(stroke
				(width 0.1524)
				(type default)
			)
			(layer "F.SilkS")
		)
		(fp_line
			(start 0.7874 -0.4064)
			(end 0.7874 0.4064)
			(stroke
				(width 0.1524)
				(type default)
			)
			(layer "F.SilkS")
		)
		(fp_line
			(start 0.7874 0.4064)
			(end -0.7874 0.4064)
			(stroke
				(width 0.1524)
				(type default)
			)
			(layer "F.SilkS")
		)
		(fp_line
			(start -0.67945 -0.305054)
			(end -0.12065 -0.305054)
			(stroke
				(width 0.1)
				(type default)
			)
			(layer "F.Fab")
		)
		(fp_line
			(start -0.67945 0.3048)
			(end -0.67945 -0.305054)
			(stroke
				(width 0.1)
				(type default)
			)
			(layer "F.Fab")
		)
		(fp_line
			(start -0.12065 -0.305054)
			(end -0.12065 -0.2794)
			(stroke
				(width 0.1)
				(type default)
			)
			(layer "F.Fab")
		)
		(fp_line
			(start -0.12065 -0.2794)
			(end 0.12065 -0.2794)
			(stroke
				(width 0.1)
				(type default)
			)
			(layer "F.Fab")
		)
		(fp_line
			(start -0.12065 0.2794)
			(end -0.12065 0.3048)
			(stroke
				(width 0.1)
				(type default)
			)
			(layer "F.Fab")
		)
		(fp_line
			(start -0.12065 0.3048)
			(end -0.67945 0.3048)
			(stroke
				(width 0.1)
				(type default)
			)
			(layer "F.Fab")
		)
		(fp_line
			(start 0.120396 0.2794)
			(end -0.12065 0.2794)
			(stroke
				(width 0.1)
				(type default)
			)
			(layer "F.Fab")
		)
		(fp_line
			(start 0.120396 0.3048)
			(end 0.120396 0.2794)
			(stroke
				(width 0.1)
				(type default)
			)
			(layer "F.Fab")
		)
		(fp_line
			(start 0.12065 -0.3048)
			(end 0.67945 -0.3048)
			(stroke
				(width 0.1)
				(type default)
			)
			(layer "F.Fab")
		)
		(fp_line
			(start 0.12065 -0.2794)
			(end 0.12065 -0.3048)
			(stroke
				(width 0.1)
				(type default)
			)
			(layer "F.Fab")
		)
		(fp_line
			(start 0.67945 -0.3048)
			(end 0.67945 0.3048)
			(stroke
				(width 0.1)
				(type default)
			)
			(layer "F.Fab")
		)
		(fp_line
			(start 0.67945 0.3048)
			(end 0.120396 0.3048)
			(stroke
				(width 0.1)
				(type default)
			)
			(layer "F.Fab")
		)
		(pad "1" smd circle
			(at -0.40005 0)
			(size 0 0)
			(layers "F.Cu" "F.Mask" "F.Paste")
			(net "P12V_NIC3_CO_TIMER")
		)
		(pad "2" smd circle
			(at 0.40005 0)
			(size 0 0)
			(layers "F.Cu" "F.Mask" "F.Paste")
			(net "GND")
		)
	)
	(footprint ""
		(layer "F.Cu")
		(at 368.78768 -25.342342 -90)
		(property "Reference" "R447"
			(at 0 0 270)
			(layer "F.SilkS")
			(hide yes)
			(effects
				(font
					(size 1.27 1.27)
				)
			)
		)
		(property "Value" ""
			(at 0 0 270)
			(layer "F.Fab")
			(effects
				(font
					(size 1.27 1.27)
				)
			)
		)
		(duplicate_pad_numbers_are_jumpers no)
		(fp_line
			(start -0.7874 0.4064)
			(end -0.7874 -0.4064)
			(stroke
				(width 0.1524)
				(type default)
			)
			(layer "F.SilkS")
		)
		(fp_line
			(start 0.7874 0.4064)
			(end -0.7874 0.4064)
			(stroke
				(width 0.1524)
				(type default)
			)
			(layer "F.SilkS")
		)
		(fp_line
			(start -0.7874 -0.4064)
			(end 0.7874 -0.4064)
			(stroke
				(width 0.1524)
				(type default)
			)
			(layer "F.SilkS")
		)
		(fp_line
			(start 0.7874 -0.4064)
			(end 0.7874 0.4064)
			(stroke
				(width 0.1524)
				(type default)
			)
			(layer "F.SilkS")
		)
		(fp_line
			(start -0.67945 0.3048)
			(end -0.67945 -0.305054)
			(stroke
				(width 0.1)
				(type default)
			)
			(layer "F.Fab")
		)
		(fp_line
			(start -0.12065 0.3048)
			(end -0.67945 0.3048)
			(stroke
				(width 0.1)
				(type default)
			)
			(layer "F.Fab")
		)
		(fp_line
			(start 0.120396 0.3048)
			(end 0.120396 0.2794)
			(stroke
				(width 0.1)
				(type default)
			)
			(layer "F.Fab")
		)
		(fp_line
			(start 0.67945 0.3048)
			(end 0.120396 0.3048)
			(stroke
				(width 0.1)
				(type default)
			)
			(layer "F.Fab")
		)
		(fp_line
			(start -0.12065 0.2794)
			(end -0.12065 0.3048)
			(stroke
				(width 0.1)
				(type default)
			)
			(layer "F.Fab")
		)
		(fp_line
			(start 0.120396 0.2794)
			(end -0.12065 0.2794)
			(stroke
				(width 0.1)
				(type default)
			)
			(layer "F.Fab")
		)
		(fp_line
			(start -0.12065 -0.2794)
			(end 0.12065 -0.2794)
			(stroke
				(width 0.1)
				(type default)
			)
			(layer "F.Fab")
		)
		(fp_line
			(start 0.12065 -0.2794)
			(end 0.12065 -0.3048)
			(stroke
				(width 0.1)
				(type default)
			)
			(layer "F.Fab")
		)
		(fp_line
			(start 0.12065 -0.3048)
			(end 0.67945 -0.3048)
			(stroke
				(width 0.1)
				(type default)
			)
			(layer "F.Fab")
		)
		(fp_line
			(start 0.67945 -0.3048)
			(end 0.67945 0.3048)
			(stroke
				(width 0.1)
				(type default)
			)
			(layer "F.Fab")
		)
		(fp_line
			(start -0.67945 -0.305054)
			(end -0.12065 -0.305054)
			(stroke
				(width 0.1)
				(type default)
			)
			(layer "F.Fab")
		)
		(fp_line
			(start -0.12065 -0.305054)
			(end -0.12065 -0.2794)
			(stroke
				(width 0.1)
				(type default)
			)
			(layer "F.Fab")
		)
		(pad "1" smd circle
			(at -0.40005 0 270)
			(size 0 0)
			(layers "F.Cu" "F.Mask" "F.Paste")
			(net "GND")
		)
		(pad "2" smd circle
			(at 0.40005 0 270)
			(size 0 0)
			(layers "F.Cu" "F.Mask" "F.Paste")
			(net "DUALPORT_N_SSD12")
		)
	)
	(footprint ""
		(layer "F.Cu")
		(at 205.598522 -297.46448)
		(property "Reference" "R3941"
			(at 0 0 0)
			(layer "F.SilkS")
			(hide yes)
			(effects
				(font
					(size 1.27 1.27)
				)
			)
		)
		(property "Value" ""
			(at 0 0 0)
			(layer "F.Fab")
			(effects
				(font
					(size 1.27 1.27)
				)
			)
		)
		(duplicate_pad_numbers_are_jumpers no)
		(fp_line
			(start -0.7874 -0.4064)
			(end 0.7874 -0.4064)
			(stroke
				(width 0.1524)
				(type default)
			)
			(layer "F.SilkS")
		)
		(fp_line
			(start -0.7874 0.4064)
			(end -0.7874 -0.4064)
			(stroke
				(width 0.1524)
				(type default)
			)
			(layer "F.SilkS")
		)
		(fp_line
			(start 0.7874 -0.4064)
			(end 0.7874 0.4064)
			(stroke
				(width 0.1524)
				(type default)
			)
			(layer "F.SilkS")
		)
		(fp_line
			(start 0.7874 0.4064)
			(end -0.7874 0.4064)
			(stroke
				(width 0.1524)
				(type default)
			)
			(layer "F.SilkS")
		)
		(fp_line
			(start -0.67945 -0.305054)
			(end -0.12065 -0.305054)
			(stroke
				(width 0.1)
				(type default)
			)
			(layer "F.Fab")
		)
		(fp_line
			(start -0.67945 0.3048)
			(end -0.67945 -0.305054)
			(stroke
				(width 0.1)
				(type default)
			)
			(layer "F.Fab")
		)
		(fp_line
			(start -0.12065 -0.305054)
			(end -0.12065 -0.2794)
			(stroke
				(width 0.1)
				(type default)
			)
			(layer "F.Fab")
		)
		(fp_line
			(start -0.12065 -0.2794)
			(end 0.12065 -0.2794)
			(stroke
				(width 0.1)
				(type default)
			)
			(layer "F.Fab")
		)
		(fp_line
			(start -0.12065 0.2794)
			(end -0.12065 0.3048)
			(stroke
				(width 0.1)
				(type default)
			)
			(layer "F.Fab")
		)
		(fp_line
			(start -0.12065 0.3048)
			(end -0.67945 0.3048)
			(stroke
				(width 0.1)
				(type default)
			)
			(layer "F.Fab")
		)
		(fp_line
			(start 0.120396 0.2794)
			(end -0.12065 0.2794)
			(stroke
				(width 0.1)
				(type default)
			)
			(layer "F.Fab")
		)
		(fp_line
			(start 0.120396 0.3048)
			(end 0.120396 0.2794)
			(stroke
				(width 0.1)
				(type default)
			)
			(layer "F.Fab")
		)
		(fp_line
			(start 0.12065 -0.3048)
			(end 0.67945 -0.3048)
			(stroke
				(width 0.1)
				(type default)
			)
			(layer "F.Fab")
		)
		(fp_line
			(start 0.12065 -0.2794)
			(end 0.12065 -0.3048)
			(stroke
				(width 0.1)
				(type default)
			)
			(layer "F.Fab")
		)
		(fp_line
			(start 0.67945 -0.3048)
			(end 0.67945 0.3048)
			(stroke
				(width 0.1)
				(type default)
			)
			(layer "F.Fab")
		)
		(fp_line
			(start 0.67945 0.3048)
			(end 0.120396 0.3048)
			(stroke
				(width 0.1)
				(type default)
			)
			(layer "F.Fab")
		)
		(pad "1" smd circle
			(at -0.40005 0)
			(size 0 0)
			(layers "F.Cu" "F.Mask" "F.Paste")
			(net "SMB_PEX1_HOST_LS_SDA")
		)
		(pad "2" smd circle
			(at 0.40005 0)
			(size 0 0)
			(layers "F.Cu" "F.Mask" "F.Paste")
			(net "I2C_PEX1_HOST_R_SDA")
		)
	)
	(footprint ""
		(layer "F.Cu")
		(at 384.938524 -134.923276)
		(property "Reference" "C669"
			(at 0 0 0)
			(layer "F.SilkS")
			(hide yes)
			(effects
				(font
					(size 1.27 1.27)
				)
			)
		)
		(property "Value" ""
			(at 0 0 0)
			(layer "F.Fab")
			(effects
				(font
					(size 1.27 1.27)
				)
			)
		)
		(duplicate_pad_numbers_are_jumpers no)
		(fp_line
			(start -0.299974 -0.150114)
			(end 0.299974 -0.150114)
			(stroke
				(width 0.1)
				(type default)
			)
			(layer "F.Fab")
		)
		(fp_line
			(start -0.299974 0.150114)
			(end -0.299974 -0.150114)
			(stroke
				(width 0.1)
				(type default)
			)
			(layer "F.Fab")
		)
		(fp_line
			(start 0.299974 -0.150114)
			(end 0.299974 0.150114)
			(stroke
				(width 0.1)
				(type default)
			)
			(layer "F.Fab")
		)
		(fp_line
			(start 0.299974 0.150114)
			(end -0.299974 0.150114)
			(stroke
				(width 0.1)
				(type default)
			)
			(layer "F.Fab")
		)
		(pad "1" smd rect
			(at -0.2667 0)
			(size 0.3048 0.381)
			(layers "F.Cu" "F.Mask" "F.Paste")
			(net "P5E_PEX3_STN1_TX_DN<30>")
		)
		(pad "2" smd rect
			(at 0.2667 0)
			(size 0.3048 0.381)
			(layers "F.Cu" "F.Mask" "F.Paste")
			(net "P5E_PEX3_STN1_TX_C_DN<30>")
		)
	)
	(footprint ""
		(layer "F.Cu")
		(at 436.03799 -291.102034 180)
		(property "Reference" "R6399"
			(at 0 0 180)
			(layer "F.SilkS")
			(hide yes)
			(effects
				(font
					(size 1.27 1.27)
				)
			)
		)
		(property "Value" ""
			(at 0 0 180)
			(layer "F.Fab")
			(effects
				(font
					(size 1.27 1.27)
				)
			)
		)
		(duplicate_pad_numbers_are_jumpers no)
		(fp_line
			(start 0.7874 0.4064)
			(end -0.7874 0.4064)
			(stroke
				(width 0.1524)
				(type default)
			)
			(layer "F.SilkS")
		)
		(fp_line
			(start 0.7874 -0.4064)
			(end 0.7874 0.4064)
			(stroke
				(width 0.1524)
				(type default)
			)
			(layer "F.SilkS")
		)
		(fp_line
			(start -0.7874 0.4064)
			(end -0.7874 -0.4064)
			(stroke
				(width 0.1524)
				(type default)
			)
			(layer "F.SilkS")
		)
		(fp_line
			(start -0.7874 -0.4064)
			(end 0.7874 -0.4064)
			(stroke
				(width 0.1524)
				(type default)
			)
			(layer "F.SilkS")
		)
		(fp_line
			(start 0.67945 0.3048)
			(end 0.120396 0.3048)
			(stroke
				(width 0.1)
				(type default)
			)
			(layer "F.Fab")
		)
		(fp_line
			(start 0.67945 -0.3048)
			(end 0.67945 0.3048)
			(stroke
				(width 0.1)
				(type default)
			)
			(layer "F.Fab")
		)
		(fp_line
			(start 0.12065 -0.2794)
			(end 0.12065 -0.3048)
			(stroke
				(width 0.1)
				(type default)
			)
			(layer "F.Fab")
		)
		(fp_line
			(start 0.12065 -0.3048)
			(end 0.67945 -0.3048)
			(stroke
				(width 0.1)
				(type default)
			)
			(layer "F.Fab")
		)
		(fp_line
			(start 0.120396 0.3048)
			(end 0.120396 0.2794)
			(stroke
				(width 0.1)
				(type default)
			)
			(layer "F.Fab")
		)
		(fp_line
			(start 0.120396 0.2794)
			(end -0.12065 0.2794)
			(stroke
				(width 0.1)
				(type default)
			)
			(layer "F.Fab")
		)
		(fp_line
			(start -0.12065 0.3048)
			(end -0.67945 0.3048)
			(stroke
				(width 0.1)
				(type default)
			)
			(layer "F.Fab")
		)
		(fp_line
			(start -0.12065 0.2794)
			(end -0.12065 0.3048)
			(stroke
				(width 0.1)
				(type default)
			)
			(layer "F.Fab")
		)
		(fp_line
			(start -0.12065 -0.2794)
			(end 0.12065 -0.2794)
			(stroke
				(width 0.1)
				(type default)
			)
			(layer "F.Fab")
		)
		(fp_line
			(start -0.12065 -0.305054)
			(end -0.12065 -0.2794)
			(stroke
				(width 0.1)
				(type default)
			)
			(layer "F.Fab")
		)
		(fp_line
			(start -0.67945 0.3048)
			(end -0.67945 -0.305054)
			(stroke
				(width 0.1)
				(type default)
			)
			(layer "F.Fab")
		)
		(fp_line
			(start -0.67945 -0.305054)
			(end -0.12065 -0.305054)
			(stroke
				(width 0.1)
				(type default)
			)
			(layer "F.Fab")
		)
		(pad "1" smd circle
			(at -0.40005 0 180)
			(size 0 0)
			(layers "F.Cu" "F.Mask" "F.Paste")
			(net "GND")
		)
		(pad "2" smd circle
			(at 0.40005 0 180)
			(size 0 0)
			(layers "F.Cu" "F.Mask" "F.Paste")
			(net "RST_PEX3_PERST_R_N")
		)
	)
	(footprint ""
		(layer "F.Cu")
		(at 313.075066 -64.102234 180)
		(property "Reference" "PR7086"
			(at 0 0 180)
			(layer "F.SilkS")
			(hide yes)
			(effects
				(font
					(size 1.27 1.27)
				)
			)
		)
		(property "Value" ""
			(at 0 0 180)
			(layer "F.Fab")
			(effects
				(font
					(size 1.27 1.27)
				)
			)
		)
		(duplicate_pad_numbers_are_jumpers no)
		(fp_line
			(start 0.7874 0.4064)
			(end -0.7874 0.4064)
			(stroke
				(width 0.1524)
				(type default)
			)
			(layer "F.SilkS")
		)
		(fp_line
			(start 0.7874 -0.4064)
			(end 0.7874 0.4064)
			(stroke
				(width 0.1524)
				(type default)
			)
			(layer "F.SilkS")
		)
		(fp_line
			(start -0.7874 0.4064)
			(end -0.7874 -0.4064)
			(stroke
				(width 0.1524)
				(type default)
			)
			(layer "F.SilkS")
		)
		(fp_line
			(start -0.7874 -0.4064)
			(end 0.7874 -0.4064)
			(stroke
				(width 0.1524)
				(type default)
			)
			(layer "F.SilkS")
		)
		(fp_line
			(start 0.67945 0.3048)
			(end 0.120396 0.3048)
			(stroke
				(width 0.1)
				(type default)
			)
			(layer "F.Fab")
		)
		(fp_line
			(start 0.67945 -0.3048)
			(end 0.67945 0.3048)
			(stroke
				(width 0.1)
				(type default)
			)
			(layer "F.Fab")
		)
		(fp_line
			(start 0.12065 -0.2794)
			(end 0.12065 -0.3048)
			(stroke
				(width 0.1)
				(type default)
			)
			(layer "F.Fab")
		)
		(fp_line
			(start 0.12065 -0.3048)
			(end 0.67945 -0.3048)
			(stroke
				(width 0.1)
				(type default)
			)
			(layer "F.Fab")
		)
		(fp_line
			(start 0.120396 0.3048)
			(end 0.120396 0.2794)
			(stroke
				(width 0.1)
				(type default)
			)
			(layer "F.Fab")
		)
		(fp_line
			(start 0.120396 0.2794)
			(end -0.12065 0.2794)
			(stroke
				(width 0.1)
				(type default)
			)
			(layer "F.Fab")
		)
		(fp_line
			(start -0.12065 0.3048)
			(end -0.67945 0.3048)
			(stroke
				(width 0.1)
				(type default)
			)
			(layer "F.Fab")
		)
		(fp_line
			(start -0.12065 0.2794)
			(end -0.12065 0.3048)
			(stroke
				(width 0.1)
				(type default)
			)
			(layer "F.Fab")
		)
		(fp_line
			(start -0.12065 -0.2794)
			(end 0.12065 -0.2794)
			(stroke
				(width 0.1)
				(type default)
			)
			(layer "F.Fab")
		)
		(fp_line
			(start -0.12065 -0.305054)
			(end -0.12065 -0.2794)
			(stroke
				(width 0.1)
				(type default)
			)
			(layer "F.Fab")
		)
		(fp_line
			(start -0.67945 0.3048)
			(end -0.67945 -0.305054)
			(stroke
				(width 0.1)
				(type default)
			)
			(layer "F.Fab")
		)
		(fp_line
			(start -0.67945 -0.305054)
			(end -0.12065 -0.305054)
			(stroke
				(width 0.1)
				(type default)
			)
			(layer "F.Fab")
		)
		(pad "1" smd circle
			(at -0.40005 0 180)
			(size 0 0)
			(layers "F.Cu" "F.Mask" "F.Paste")
			(net "P12V_SSD11_PG_G1")
		)
		(pad "2" smd circle
			(at 0.40005 0 180)
			(size 0 0)
			(layers "F.Cu" "F.Mask" "F.Paste")
			(net "GND")
		)
	)
	(footprint ""
		(layer "F.Cu")
		(at 350.380554 -82.644234)
		(property "Reference" "R1600"
			(at 0 0 0)
			(layer "F.SilkS")
			(hide yes)
			(effects
				(font
					(size 1.27 1.27)
				)
			)
		)
		(property "Value" ""
			(at 0 0 0)
			(layer "F.Fab")
			(effects
				(font
					(size 1.27 1.27)
				)
			)
		)
		(duplicate_pad_numbers_are_jumpers no)
		(fp_line
			(start -0.7874 -0.4064)
			(end 0.7874 -0.4064)
			(stroke
				(width 0.1524)
				(type default)
			)
			(layer "F.SilkS")
		)
		(fp_line
			(start -0.7874 0.4064)
			(end -0.7874 -0.4064)
			(stroke
				(width 0.1524)
				(type default)
			)
			(layer "F.SilkS")
		)
		(fp_line
			(start 0.7874 -0.4064)
			(end 0.7874 0.4064)
			(stroke
				(width 0.1524)
				(type default)
			)
			(layer "F.SilkS")
		)
		(fp_line
			(start 0.7874 0.4064)
			(end -0.7874 0.4064)
			(stroke
				(width 0.1524)
				(type default)
			)
			(layer "F.SilkS")
		)
		(fp_line
			(start -0.67945 -0.305054)
			(end -0.12065 -0.305054)
			(stroke
				(width 0.1)
				(type default)
			)
			(layer "F.Fab")
		)
		(fp_line
			(start -0.67945 0.3048)
			(end -0.67945 -0.305054)
			(stroke
				(width 0.1)
				(type default)
			)
			(layer "F.Fab")
		)
		(fp_line
			(start -0.12065 -0.305054)
			(end -0.12065 -0.2794)
			(stroke
				(width 0.1)
				(type default)
			)
			(layer "F.Fab")
		)
		(fp_line
			(start -0.12065 -0.2794)
			(end 0.12065 -0.2794)
			(stroke
				(width 0.1)
				(type default)
			)
			(layer "F.Fab")
		)
		(fp_line
			(start -0.12065 0.2794)
			(end -0.12065 0.3048)
			(stroke
				(width 0.1)
				(type default)
			)
			(layer "F.Fab")
		)
		(fp_line
			(start -0.12065 0.3048)
			(end -0.67945 0.3048)
			(stroke
				(width 0.1)
				(type default)
			)
			(layer "F.Fab")
		)
		(fp_line
			(start 0.120396 0.2794)
			(end -0.12065 0.2794)
			(stroke
				(width 0.1)
				(type default)
			)
			(layer "F.Fab")
		)
		(fp_line
			(start 0.120396 0.3048)
			(end 0.120396 0.2794)
			(stroke
				(width 0.1)
				(type default)
			)
			(layer "F.Fab")
		)
		(fp_line
			(start 0.12065 -0.3048)
			(end 0.67945 -0.3048)
			(stroke
				(width 0.1)
				(type default)
			)
			(layer "F.Fab")
		)
		(fp_line
			(start 0.12065 -0.2794)
			(end 0.12065 -0.3048)
			(stroke
				(width 0.1)
				(type default)
			)
			(layer "F.Fab")
		)
		(fp_line
			(start 0.67945 -0.3048)
			(end 0.67945 0.3048)
			(stroke
				(width 0.1)
				(type default)
			)
			(layer "F.Fab")
		)
		(fp_line
			(start 0.67945 0.3048)
			(end 0.120396 0.3048)
			(stroke
				(width 0.1)
				(type default)
			)
			(layer "F.Fab")
		)
		(pad "1" smd circle
			(at -0.40005 0)
			(size 0 0)
			(layers "F.Cu" "F.Mask" "F.Paste")
			(net "P3V3_AUX")
		)
		(pad "2" smd circle
			(at 0.40005 0)
			(size 0 0)
			(layers "F.Cu" "F.Mask" "F.Paste")
			(net "SMB_BIC_I2C9_MUX1_SSD11_R_SDA")
		)
	)
	(footprint ""
		(layer "F.Cu")
		(at 80.53959 -137.645648)
		(property "Reference" "R56"
			(at 0 0 0)
			(layer "F.SilkS")
			(hide yes)
			(effects
				(font
					(size 1.27 1.27)
				)
			)
		)
		(property "Value" ""
			(at 0 0 0)
			(layer "F.Fab")
			(effects
				(font
					(size 1.27 1.27)
				)
			)
		)
		(duplicate_pad_numbers_are_jumpers no)
		(fp_line
			(start -0.7874 -0.4064)
			(end 0.7874 -0.4064)
			(stroke
				(width 0.1524)
				(type default)
			)
			(layer "F.SilkS")
		)
		(fp_line
			(start -0.7874 0.4064)
			(end -0.7874 -0.4064)
			(stroke
				(width 0.1524)
				(type default)
			)
			(layer "F.SilkS")
		)
		(fp_line
			(start 0.7874 -0.4064)
			(end 0.7874 0.4064)
			(stroke
				(width 0.1524)
				(type default)
			)
			(layer "F.SilkS")
		)
		(fp_line
			(start 0.7874 0.4064)
			(end -0.7874 0.4064)
			(stroke
				(width 0.1524)
				(type default)
			)
			(layer "F.SilkS")
		)
		(fp_line
			(start -0.67945 -0.305054)
			(end -0.12065 -0.305054)
			(stroke
				(width 0.1)
				(type default)
			)
			(layer "F.Fab")
		)
		(fp_line
			(start -0.67945 0.3048)
			(end -0.67945 -0.305054)
			(stroke
				(width 0.1)
				(type default)
			)
			(layer "F.Fab")
		)
		(fp_line
			(start -0.12065 -0.305054)
			(end -0.12065 -0.2794)
			(stroke
				(width 0.1)
				(type default)
			)
			(layer "F.Fab")
		)
		(fp_line
			(start -0.12065 -0.2794)
			(end 0.12065 -0.2794)
			(stroke
				(width 0.1)
				(type default)
			)
			(layer "F.Fab")
		)
		(fp_line
			(start -0.12065 0.2794)
			(end -0.12065 0.3048)
			(stroke
				(width 0.1)
				(type default)
			)
			(layer "F.Fab")
		)
		(fp_line
			(start -0.12065 0.3048)
			(end -0.67945 0.3048)
			(stroke
				(width 0.1)
				(type default)
			)
			(layer "F.Fab")
		)
		(fp_line
			(start 0.120396 0.2794)
			(end -0.12065 0.2794)
			(stroke
				(width 0.1)
				(type default)
			)
			(layer "F.Fab")
		)
		(fp_line
			(start 0.120396 0.3048)
			(end 0.120396 0.2794)
			(stroke
				(width 0.1)
				(type default)
			)
			(layer "F.Fab")
		)
		(fp_line
			(start 0.12065 -0.3048)
			(end 0.67945 -0.3048)
			(stroke
				(width 0.1)
				(type default)
			)
			(layer "F.Fab")
		)
		(fp_line
			(start 0.12065 -0.2794)
			(end 0.12065 -0.3048)
			(stroke
				(width 0.1)
				(type default)
			)
			(layer "F.Fab")
		)
		(fp_line
			(start 0.67945 -0.3048)
			(end 0.67945 0.3048)
			(stroke
				(width 0.1)
				(type default)
			)
			(layer "F.Fab")
		)
		(fp_line
			(start 0.67945 0.3048)
			(end 0.120396 0.3048)
			(stroke
				(width 0.1)
				(type default)
			)
			(layer "F.Fab")
		)
		(pad "1" smd circle
			(at -0.40005 0)
			(size 0 0)
			(layers "F.Cu" "F.Mask" "F.Paste")
			(net "PRSNTB0_NIC1_N")
		)
		(pad "2" smd circle
			(at 0.40005 0)
			(size 0 0)
			(layers "F.Cu" "F.Mask" "F.Paste")
			(net "P3V3_AUX")
		)
	)
	(footprint ""
		(layer "F.Cu")
		(at 221.251272 -141.910562 180)
		(property "Reference" "C2807"
			(at 0 0 180)
			(layer "F.SilkS")
			(hide yes)
			(effects
				(font
					(size 1.27 1.27)
				)
			)
		)
		(property "Value" ""
			(at 0 0 180)
			(layer "F.Fab")
			(effects
				(font
					(size 1.27 1.27)
				)
			)
		)
		(duplicate_pad_numbers_are_jumpers no)
		(fp_line
			(start 0.7874 0.4064)
			(end -0.7874 0.4064)
			(stroke
				(width 0.1524)
				(type default)
			)
			(layer "F.SilkS")
		)
		(fp_line
			(start 0.7874 -0.4064)
			(end 0.7874 0.4064)
			(stroke
				(width 0.1524)
				(type default)
			)
			(layer "F.SilkS")
		)
		(fp_line
			(start -0.7874 0.4064)
			(end -0.7874 -0.4064)
			(stroke
				(width 0.1524)
				(type default)
			)
			(layer "F.SilkS")
		)
		(fp_line
			(start -0.7874 -0.4064)
			(end 0.7874 -0.4064)
			(stroke
				(width 0.1524)
				(type default)
			)
			(layer "F.SilkS")
		)
		(fp_line
			(start 0.67945 0.3048)
			(end 0.120396 0.3048)
			(stroke
				(width 0.1)
				(type default)
			)
			(layer "F.Fab")
		)
		(fp_line
			(start 0.67945 -0.3048)
			(end 0.67945 0.3048)
			(stroke
				(width 0.1)
				(type default)
			)
			(layer "F.Fab")
		)
		(fp_line
			(start 0.12065 -0.2794)
			(end 0.12065 -0.3048)
			(stroke
				(width 0.1)
				(type default)
			)
			(layer "F.Fab")
		)
		(fp_line
			(start 0.12065 -0.3048)
			(end 0.67945 -0.3048)
			(stroke
				(width 0.1)
				(type default)
			)
			(layer "F.Fab")
		)
		(fp_line
			(start 0.120396 0.3048)
			(end 0.120396 0.2794)
			(stroke
				(width 0.1)
				(type default)
			)
			(layer "F.Fab")
		)
		(fp_line
			(start 0.120396 0.2794)
			(end -0.12065 0.2794)
			(stroke
				(width 0.1)
				(type default)
			)
			(layer "F.Fab")
		)
		(fp_line
			(start -0.12065 0.3048)
			(end -0.67945 0.3048)
			(stroke
				(width 0.1)
				(type default)
			)
			(layer "F.Fab")
		)
		(fp_line
			(start -0.12065 0.2794)
			(end -0.12065 0.3048)
			(stroke
				(width 0.1)
				(type default)
			)
			(layer "F.Fab")
		)
		(fp_line
			(start -0.12065 -0.2794)
			(end 0.12065 -0.2794)
			(stroke
				(width 0.1)
				(type default)
			)
			(layer "F.Fab")
		)
		(fp_line
			(start -0.12065 -0.305054)
			(end -0.12065 -0.2794)
			(stroke
				(width 0.1)
				(type default)
			)
			(layer "F.Fab")
		)
		(fp_line
			(start -0.67945 0.3048)
			(end -0.67945 -0.305054)
			(stroke
				(width 0.1)
				(type default)
			)
			(layer "F.Fab")
		)
		(fp_line
			(start -0.67945 -0.305054)
			(end -0.12065 -0.305054)
			(stroke
				(width 0.1)
				(type default)
			)
			(layer "F.Fab")
		)
		(pad "1" smd circle
			(at -0.40005 0 180)
			(size 0 0)
			(layers "F.Cu" "F.Mask" "F.Paste")
			(net "FM_CK440_PEX_DEV_25M_EN")
		)
		(pad "2" smd circle
			(at 0.40005 0 180)
			(size 0 0)
			(layers "F.Cu" "F.Mask" "F.Paste")
			(net "GND")
		)
	)
	(footprint ""
		(layer "F.Cu")
		(at 373.092726 -257.148838 -90)
		(property "Reference" "R1463"
			(at 0 0 270)
			(layer "F.SilkS")
			(hide yes)
			(effects
				(font
					(size 1.27 1.27)
				)
			)
		)
		(property "Value" ""
			(at 0 0 270)
			(layer "F.Fab")
			(effects
				(font
					(size 1.27 1.27)
				)
			)
		)
		(duplicate_pad_numbers_are_jumpers no)
		(fp_line
			(start -0.7874 0.4064)
			(end -0.7874 -0.4064)
			(stroke
				(width 0.1524)
				(type default)
			)
			(layer "F.SilkS")
		)
		(fp_line
			(start 0.7874 0.4064)
			(end -0.7874 0.4064)
			(stroke
				(width 0.1524)
				(type default)
			)
			(layer "F.SilkS")
		)
		(fp_line
			(start -0.7874 -0.4064)
			(end 0.7874 -0.4064)
			(stroke
				(width 0.1524)
				(type default)
			)
			(layer "F.SilkS")
		)
		(fp_line
			(start 0.7874 -0.4064)
			(end 0.7874 0.4064)
			(stroke
				(width 0.1524)
				(type default)
			)
			(layer "F.SilkS")
		)
		(fp_line
			(start -0.67945 0.3048)
			(end -0.67945 -0.305054)
			(stroke
				(width 0.1)
				(type default)
			)
			(layer "F.Fab")
		)
		(fp_line
			(start -0.12065 0.3048)
			(end -0.67945 0.3048)
			(stroke
				(width 0.1)
				(type default)
			)
			(layer "F.Fab")
		)
		(fp_line
			(start 0.120396 0.3048)
			(end 0.120396 0.2794)
			(stroke
				(width 0.1)
				(type default)
			)
			(layer "F.Fab")
		)
		(fp_line
			(start 0.67945 0.3048)
			(end 0.120396 0.3048)
			(stroke
				(width 0.1)
				(type default)
			)
			(layer "F.Fab")
		)
		(fp_line
			(start -0.12065 0.2794)
			(end -0.12065 0.3048)
			(stroke
				(width 0.1)
				(type default)
			)
			(layer "F.Fab")
		)
		(fp_line
			(start 0.120396 0.2794)
			(end -0.12065 0.2794)
			(stroke
				(width 0.1)
				(type default)
			)
			(layer "F.Fab")
		)
		(fp_line
			(start -0.12065 -0.2794)
			(end 0.12065 -0.2794)
			(stroke
				(width 0.1)
				(type default)
			)
			(layer "F.Fab")
		)
		(fp_line
			(start 0.12065 -0.2794)
			(end 0.12065 -0.3048)
			(stroke
				(width 0.1)
				(type default)
			)
			(layer "F.Fab")
		)
		(fp_line
			(start 0.12065 -0.3048)
			(end 0.67945 -0.3048)
			(stroke
				(width 0.1)
				(type default)
			)
			(layer "F.Fab")
		)
		(fp_line
			(start 0.67945 -0.3048)
			(end 0.67945 0.3048)
			(stroke
				(width 0.1)
				(type default)
			)
			(layer "F.Fab")
		)
		(fp_line
			(start -0.67945 -0.305054)
			(end -0.12065 -0.305054)
			(stroke
				(width 0.1)
				(type default)
			)
			(layer "F.Fab")
		)
		(fp_line
			(start -0.12065 -0.305054)
			(end -0.12065 -0.2794)
			(stroke
				(width 0.1)
				(type default)
			)
			(layer "F.Fab")
		)
		(pad "1" smd circle
			(at -0.40005 0 270)
			(size 0 0)
			(layers "F.Cu" "F.Mask" "F.Paste")
			(net "P3V3_LED")
		)
		(pad "2" smd circle
			(at 0.40005 0 270)
			(size 0 0)
			(layers "F.Cu" "F.Mask" "F.Paste")
			(net "LED_PEX3_SYS_ERR_N")
		)
	)
	(footprint ""
		(layer "F.Cu")
		(at 384.938524 -130.408934)
		(property "Reference" "C672"
			(at 0 0 0)
			(layer "F.SilkS")
			(hide yes)
			(effects
				(font
					(size 1.27 1.27)
				)
			)
		)
		(property "Value" ""
			(at 0 0 0)
			(layer "F.Fab")
			(effects
				(font
					(size 1.27 1.27)
				)
			)
		)
		(duplicate_pad_numbers_are_jumpers no)
		(fp_line
			(start -0.299974 -0.150114)
			(end 0.299974 -0.150114)
			(stroke
				(width 0.1)
				(type default)
			)
			(layer "F.Fab")
		)
		(fp_line
			(start -0.299974 0.150114)
			(end -0.299974 -0.150114)
			(stroke
				(width 0.1)
				(type default)
			)
			(layer "F.Fab")
		)
		(fp_line
			(start 0.299974 -0.150114)
			(end 0.299974 0.150114)
			(stroke
				(width 0.1)
				(type default)
			)
			(layer "F.Fab")
		)
		(fp_line
			(start 0.299974 0.150114)
			(end -0.299974 0.150114)
			(stroke
				(width 0.1)
				(type default)
			)
			(layer "F.Fab")
		)
		(pad "1" smd rect
			(at -0.2667 0)
			(size 0.3048 0.381)
			(layers "F.Cu" "F.Mask" "F.Paste")
			(net "P5E_PEX3_STN1_TX_DP<28>")
		)
		(pad "2" smd rect
			(at 0.2667 0)
			(size 0.3048 0.381)
			(layers "F.Cu" "F.Mask" "F.Paste")
			(net "P5E_PEX3_STN1_TX_C_DP<28>")
		)
	)
	(footprint ""
		(layer "F.Cu")
		(at 227.743512 -231.416606 -90)
		(property "Reference" "R4539"
			(at 0 0 270)
			(layer "F.SilkS")
			(hide yes)
			(effects
				(font
					(size 1.27 1.27)
				)
			)
		)
		(property "Value" ""
			(at 0 0 270)
			(layer "F.Fab")
			(effects
				(font
					(size 1.27 1.27)
				)
			)
		)
		(duplicate_pad_numbers_are_jumpers no)
		(fp_line
			(start -0.7874 0.4064)
			(end -0.7874 -0.4064)
			(stroke
				(width 0.1524)
				(type default)
			)
			(layer "F.SilkS")
		)
		(fp_line
			(start 0.7874 0.4064)
			(end -0.7874 0.4064)
			(stroke
				(width 0.1524)
				(type default)
			)
			(layer "F.SilkS")
		)
		(fp_line
			(start -0.7874 -0.4064)
			(end 0.7874 -0.4064)
			(stroke
				(width 0.1524)
				(type default)
			)
			(layer "F.SilkS")
		)
		(fp_line
			(start 0.7874 -0.4064)
			(end 0.7874 0.4064)
			(stroke
				(width 0.1524)
				(type default)
			)
			(layer "F.SilkS")
		)
		(fp_line
			(start -0.67945 0.3048)
			(end -0.67945 -0.305054)
			(stroke
				(width 0.1)
				(type default)
			)
			(layer "F.Fab")
		)
		(fp_line
			(start -0.12065 0.3048)
			(end -0.67945 0.3048)
			(stroke
				(width 0.1)
				(type default)
			)
			(layer "F.Fab")
		)
		(fp_line
			(start 0.120396 0.3048)
			(end 0.120396 0.2794)
			(stroke
				(width 0.1)
				(type default)
			)
			(layer "F.Fab")
		)
		(fp_line
			(start 0.67945 0.3048)
			(end 0.120396 0.3048)
			(stroke
				(width 0.1)
				(type default)
			)
			(layer "F.Fab")
		)
		(fp_line
			(start -0.12065 0.2794)
			(end -0.12065 0.3048)
			(stroke
				(width 0.1)
				(type default)
			)
			(layer "F.Fab")
		)
		(fp_line
			(start 0.120396 0.2794)
			(end -0.12065 0.2794)
			(stroke
				(width 0.1)
				(type default)
			)
			(layer "F.Fab")
		)
		(fp_line
			(start -0.12065 -0.2794)
			(end 0.12065 -0.2794)
			(stroke
				(width 0.1)
				(type default)
			)
			(layer "F.Fab")
		)
		(fp_line
			(start 0.12065 -0.2794)
			(end 0.12065 -0.3048)
			(stroke
				(width 0.1)
				(type default)
			)
			(layer "F.Fab")
		)
		(fp_line
			(start 0.12065 -0.3048)
			(end 0.67945 -0.3048)
			(stroke
				(width 0.1)
				(type default)
			)
			(layer "F.Fab")
		)
		(fp_line
			(start 0.67945 -0.3048)
			(end 0.67945 0.3048)
			(stroke
				(width 0.1)
				(type default)
			)
			(layer "F.Fab")
		)
		(fp_line
			(start -0.67945 -0.305054)
			(end -0.12065 -0.305054)
			(stroke
				(width 0.1)
				(type default)
			)
			(layer "F.Fab")
		)
		(fp_line
			(start -0.12065 -0.305054)
			(end -0.12065 -0.2794)
			(stroke
				(width 0.1)
				(type default)
			)
			(layer "F.Fab")
		)
		(pad "1" smd circle
			(at -0.40005 0 270)
			(size 0 0)
			(layers "F.Cu" "F.Mask" "F.Paste")
			(net "NIC3_MAIN_PWR_BIC_EN_R")
		)
		(pad "2" smd circle
			(at 0.40005 0 270)
			(size 0 0)
			(layers "F.Cu" "F.Mask" "F.Paste")
			(net "NIC3_MAIN_PWR_BIC_EN")
		)
	)
	(footprint ""
		(layer "F.Cu")
		(at 204.591158 -87.977472)
		(property "Reference" "R4261"
			(at 0 0 0)
			(layer "F.SilkS")
			(hide yes)
			(effects
				(font
					(size 1.27 1.27)
				)
			)
		)
		(property "Value" ""
			(at 0 0 0)
			(layer "F.Fab")
			(effects
				(font
					(size 1.27 1.27)
				)
			)
		)
		(duplicate_pad_numbers_are_jumpers no)
		(fp_line
			(start -0.7874 -0.4064)
			(end 0.7874 -0.4064)
			(stroke
				(width 0.1524)
				(type default)
			)
			(layer "F.SilkS")
		)
		(fp_line
			(start -0.7874 0.4064)
			(end -0.7874 -0.4064)
			(stroke
				(width 0.1524)
				(type default)
			)
			(layer "F.SilkS")
		)
		(fp_line
			(start 0.7874 -0.4064)
			(end 0.7874 0.4064)
			(stroke
				(width 0.1524)
				(type default)
			)
			(layer "F.SilkS")
		)
		(fp_line
			(start 0.7874 0.4064)
			(end -0.7874 0.4064)
			(stroke
				(width 0.1524)
				(type default)
			)
			(layer "F.SilkS")
		)
		(fp_line
			(start -0.67945 -0.305054)
			(end -0.12065 -0.305054)
			(stroke
				(width 0.1)
				(type default)
			)
			(layer "F.Fab")
		)
		(fp_line
			(start -0.67945 0.3048)
			(end -0.67945 -0.305054)
			(stroke
				(width 0.1)
				(type default)
			)
			(layer "F.Fab")
		)
		(fp_line
			(start -0.12065 -0.305054)
			(end -0.12065 -0.2794)
			(stroke
				(width 0.1)
				(type default)
			)
			(layer "F.Fab")
		)
		(fp_line
			(start -0.12065 -0.2794)
			(end 0.12065 -0.2794)
			(stroke
				(width 0.1)
				(type default)
			)
			(layer "F.Fab")
		)
		(fp_line
			(start -0.12065 0.2794)
			(end -0.12065 0.3048)
			(stroke
				(width 0.1)
				(type default)
			)
			(layer "F.Fab")
		)
		(fp_line
			(start -0.12065 0.3048)
			(end -0.67945 0.3048)
			(stroke
				(width 0.1)
				(type default)
			)
			(layer "F.Fab")
		)
		(fp_line
			(start 0.120396 0.2794)
			(end -0.12065 0.2794)
			(stroke
				(width 0.1)
				(type default)
			)
			(layer "F.Fab")
		)
		(fp_line
			(start 0.120396 0.3048)
			(end 0.120396 0.2794)
			(stroke
				(width 0.1)
				(type default)
			)
			(layer "F.Fab")
		)
		(fp_line
			(start 0.12065 -0.3048)
			(end 0.67945 -0.3048)
			(stroke
				(width 0.1)
				(type default)
			)
			(layer "F.Fab")
		)
		(fp_line
			(start 0.12065 -0.2794)
			(end 0.12065 -0.3048)
			(stroke
				(width 0.1)
				(type default)
			)
			(layer "F.Fab")
		)
		(fp_line
			(start 0.67945 -0.3048)
			(end 0.67945 0.3048)
			(stroke
				(width 0.1)
				(type default)
			)
			(layer "F.Fab")
		)
		(fp_line
			(start 0.67945 0.3048)
			(end 0.120396 0.3048)
			(stroke
				(width 0.1)
				(type default)
			)
			(layer "F.Fab")
		)
		(pad "1" smd circle
			(at -0.40005 0)
			(size 0 0)
			(layers "F.Cu" "F.Mask" "F.Paste")
			(net "P3V3_AUX")
		)
		(pad "2" smd circle
			(at 0.40005 0)
			(size 0 0)
			(layers "F.Cu" "F.Mask" "F.Paste")
			(net "SSD_LED_IOEXP_A1")
		)
	)
	(footprint ""
		(layer "F.Cu")
		(at 364.659672 -146.642328 -90)
		(property "Reference" "C946"
			(at 0 0 270)
			(layer "F.SilkS")
			(hide yes)
			(effects
				(font
					(size 1.27 1.27)
				)
			)
		)
		(property "Value" ""
			(at 0 0 270)
			(layer "F.Fab")
			(effects
				(font
					(size 1.27 1.27)
				)
			)
		)
		(duplicate_pad_numbers_are_jumpers no)
		(fp_line
			(start -0.7874 0.4064)
			(end -0.7874 -0.4064)
			(stroke
				(width 0.1524)
				(type default)
			)
			(layer "F.SilkS")
		)
		(fp_line
			(start 0.7874 0.4064)
			(end -0.7874 0.4064)
			(stroke
				(width 0.1524)
				(type default)
			)
			(layer "F.SilkS")
		)
		(fp_line
			(start -0.7874 -0.4064)
			(end 0.7874 -0.4064)
			(stroke
				(width 0.1524)
				(type default)
			)
			(layer "F.SilkS")
		)
		(fp_line
			(start 0.7874 -0.4064)
			(end 0.7874 0.4064)
			(stroke
				(width 0.1524)
				(type default)
			)
			(layer "F.SilkS")
		)
		(fp_line
			(start -0.67945 0.3048)
			(end -0.67945 -0.305054)
			(stroke
				(width 0.1)
				(type default)
			)
			(layer "F.Fab")
		)
		(fp_line
			(start -0.12065 0.3048)
			(end -0.67945 0.3048)
			(stroke
				(width 0.1)
				(type default)
			)
			(layer "F.Fab")
		)
		(fp_line
			(start 0.120396 0.3048)
			(end 0.120396 0.2794)
			(stroke
				(width 0.1)
				(type default)
			)
			(layer "F.Fab")
		)
		(fp_line
			(start 0.67945 0.3048)
			(end 0.120396 0.3048)
			(stroke
				(width 0.1)
				(type default)
			)
			(layer "F.Fab")
		)
		(fp_line
			(start -0.12065 0.2794)
			(end -0.12065 0.3048)
			(stroke
				(width 0.1)
				(type default)
			)
			(layer "F.Fab")
		)
		(fp_line
			(start 0.120396 0.2794)
			(end -0.12065 0.2794)
			(stroke
				(width 0.1)
				(type default)
			)
			(layer "F.Fab")
		)
		(fp_line
			(start -0.12065 -0.2794)
			(end 0.12065 -0.2794)
			(stroke
				(width 0.1)
				(type default)
			)
			(layer "F.Fab")
		)
		(fp_line
			(start 0.12065 -0.2794)
			(end 0.12065 -0.3048)
			(stroke
				(width 0.1)
				(type default)
			)
			(layer "F.Fab")
		)
		(fp_line
			(start 0.12065 -0.3048)
			(end 0.67945 -0.3048)
			(stroke
				(width 0.1)
				(type default)
			)
			(layer "F.Fab")
		)
		(fp_line
			(start 0.67945 -0.3048)
			(end 0.67945 0.3048)
			(stroke
				(width 0.1)
				(type default)
			)
			(layer "F.Fab")
		)
		(fp_line
			(start -0.67945 -0.305054)
			(end -0.12065 -0.305054)
			(stroke
				(width 0.1)
				(type default)
			)
			(layer "F.Fab")
		)
		(fp_line
			(start -0.12065 -0.305054)
			(end -0.12065 -0.2794)
			(stroke
				(width 0.1)
				(type default)
			)
			(layer "F.Fab")
		)
		(pad "1" smd circle
			(at -0.40005 0 270)
			(size 0 0)
			(layers "F.Cu" "F.Mask" "F.Paste")
			(net "P3V3_AUX")
		)
		(pad "2" smd circle
			(at 0.40005 0 270)
			(size 0 0)
			(layers "F.Cu" "F.Mask" "F.Paste")
			(net "GND")
		)
	)
	(footprint ""
		(layer "F.Cu")
		(at 10.3378 -276.389084 90)
		(property "Reference" "C626"
			(at 0 0 90)
			(layer "F.SilkS")
			(hide yes)
			(effects
				(font
					(size 1.27 1.27)
				)
			)
		)
		(property "Value" ""
			(at 0 0 90)
			(layer "F.Fab")
			(effects
				(font
					(size 1.27 1.27)
				)
			)
		)
		(duplicate_pad_numbers_are_jumpers no)
		(fp_line
			(start 0.7874 -0.4064)
			(end 0.7874 0.4064)
			(stroke
				(width 0.1524)
				(type default)
			)
			(layer "F.SilkS")
		)
		(fp_line
			(start -0.7874 -0.4064)
			(end 0.7874 -0.4064)
			(stroke
				(width 0.1524)
				(type default)
			)
			(layer "F.SilkS")
		)
		(fp_line
			(start 0.7874 0.4064)
			(end -0.7874 0.4064)
			(stroke
				(width 0.1524)
				(type default)
			)
			(layer "F.SilkS")
		)
		(fp_line
			(start -0.7874 0.4064)
			(end -0.7874 -0.4064)
			(stroke
				(width 0.1524)
				(type default)
			)
			(layer "F.SilkS")
		)
		(fp_line
			(start -0.12065 -0.305054)
			(end -0.12065 -0.2794)
			(stroke
				(width 0.1)
				(type default)
			)
			(layer "F.Fab")
		)
		(fp_line
			(start -0.67945 -0.305054)
			(end -0.12065 -0.305054)
			(stroke
				(width 0.1)
				(type default)
			)
			(layer "F.Fab")
		)
		(fp_line
			(start 0.67945 -0.3048)
			(end 0.67945 0.3048)
			(stroke
				(width 0.1)
				(type default)
			)
			(layer "F.Fab")
		)
		(fp_line
			(start 0.12065 -0.3048)
			(end 0.67945 -0.3048)
			(stroke
				(width 0.1)
				(type default)
			)
			(layer "F.Fab")
		)
		(fp_line
			(start 0.12065 -0.2794)
			(end 0.12065 -0.3048)
			(stroke
				(width 0.1)
				(type default)
			)
			(layer "F.Fab")
		)
		(fp_line
			(start -0.12065 -0.2794)
			(end 0.12065 -0.2794)
			(stroke
				(width 0.1)
				(type default)
			)
			(layer "F.Fab")
		)
		(fp_line
			(start 0.120396 0.2794)
			(end -0.12065 0.2794)
			(stroke
				(width 0.1)
				(type default)
			)
			(layer "F.Fab")
		)
		(fp_line
			(start -0.12065 0.2794)
			(end -0.12065 0.3048)
			(stroke
				(width 0.1)
				(type default)
			)
			(layer "F.Fab")
		)
		(fp_line
			(start 0.67945 0.3048)
			(end 0.120396 0.3048)
			(stroke
				(width 0.1)
				(type default)
			)
			(layer "F.Fab")
		)
		(fp_line
			(start 0.120396 0.3048)
			(end 0.120396 0.2794)
			(stroke
				(width 0.1)
				(type default)
			)
			(layer "F.Fab")
		)
		(fp_line
			(start -0.12065 0.3048)
			(end -0.67945 0.3048)
			(stroke
				(width 0.1)
				(type default)
			)
			(layer "F.Fab")
		)
		(fp_line
			(start -0.67945 0.3048)
			(end -0.67945 -0.305054)
			(stroke
				(width 0.1)
				(type default)
			)
			(layer "F.Fab")
		)
		(pad "1" smd circle
			(at -0.40005 0 90)
			(size 0 0)
			(layers "F.Cu" "F.Mask" "F.Paste")
			(net "P1V25_PEX0_R")
		)
		(pad "2" smd circle
			(at 0.40005 0 90)
			(size 0 0)
			(layers "F.Cu" "F.Mask" "F.Paste")
			(net "GND")
		)
	)
	(footprint ""
		(layer "F.Cu")
		(at 26.267156 -57.332626)
		(property "Reference" "R6841"
			(at 0 0 0)
			(layer "F.SilkS")
			(hide yes)
			(effects
				(font
					(size 1.27 1.27)
				)
			)
		)
		(property "Value" ""
			(at 0 0 0)
			(layer "F.Fab")
			(effects
				(font
					(size 1.27 1.27)
				)
			)
		)
		(duplicate_pad_numbers_are_jumpers no)
		(fp_line
			(start -0.7874 -0.4064)
			(end 0.7874 -0.4064)
			(stroke
				(width 0.1524)
				(type default)
			)
			(layer "F.SilkS")
		)
		(fp_line
			(start -0.7874 0.4064)
			(end -0.7874 -0.4064)
			(stroke
				(width 0.1524)
				(type default)
			)
			(layer "F.SilkS")
		)
		(fp_line
			(start 0.7874 -0.4064)
			(end 0.7874 0.4064)
			(stroke
				(width 0.1524)
				(type default)
			)
			(layer "F.SilkS")
		)
		(fp_line
			(start 0.7874 0.4064)
			(end -0.7874 0.4064)
			(stroke
				(width 0.1524)
				(type default)
			)
			(layer "F.SilkS")
		)
		(fp_line
			(start -0.67945 -0.305054)
			(end -0.12065 -0.305054)
			(stroke
				(width 0.1)
				(type default)
			)
			(layer "F.Fab")
		)
		(fp_line
			(start -0.67945 0.3048)
			(end -0.67945 -0.305054)
			(stroke
				(width 0.1)
				(type default)
			)
			(layer "F.Fab")
		)
		(fp_line
			(start -0.12065 -0.305054)
			(end -0.12065 -0.2794)
			(stroke
				(width 0.1)
				(type default)
			)
			(layer "F.Fab")
		)
		(fp_line
			(start -0.12065 -0.2794)
			(end 0.12065 -0.2794)
			(stroke
				(width 0.1)
				(type default)
			)
			(layer "F.Fab")
		)
		(fp_line
			(start -0.12065 0.2794)
			(end -0.12065 0.3048)
			(stroke
				(width 0.1)
				(type default)
			)
			(layer "F.Fab")
		)
		(fp_line
			(start -0.12065 0.3048)
			(end -0.67945 0.3048)
			(stroke
				(width 0.1)
				(type default)
			)
			(layer "F.Fab")
		)
		(fp_line
			(start 0.120396 0.2794)
			(end -0.12065 0.2794)
			(stroke
				(width 0.1)
				(type default)
			)
			(layer "F.Fab")
		)
		(fp_line
			(start 0.120396 0.3048)
			(end 0.120396 0.2794)
			(stroke
				(width 0.1)
				(type default)
			)
			(layer "F.Fab")
		)
		(fp_line
			(start 0.12065 -0.3048)
			(end 0.67945 -0.3048)
			(stroke
				(width 0.1)
				(type default)
			)
			(layer "F.Fab")
		)
		(fp_line
			(start 0.12065 -0.2794)
			(end 0.12065 -0.3048)
			(stroke
				(width 0.1)
				(type default)
			)
			(layer "F.Fab")
		)
		(fp_line
			(start 0.67945 -0.3048)
			(end 0.67945 0.3048)
			(stroke
				(width 0.1)
				(type default)
			)
			(layer "F.Fab")
		)
		(fp_line
			(start 0.67945 0.3048)
			(end 0.120396 0.3048)
			(stroke
				(width 0.1)
				(type default)
			)
			(layer "F.Fab")
		)
		(pad "1" smd circle
			(at -0.40005 0)
			(size 0 0)
			(layers "F.Cu" "F.Mask" "F.Paste")
			(net "SSD0_PWR_EN_R")
		)
		(pad "2" smd circle
			(at 0.40005 0)
			(size 0 0)
			(layers "F.Cu" "F.Mask" "F.Paste")
			(net "GND")
		)
	)
	(footprint ""
		(layer "F.Cu")
		(at 355.913436 -140.392404 180)
		(property "Reference" "PC339"
			(at 0 0 180)
			(layer "F.SilkS")
			(hide yes)
			(effects
				(font
					(size 1.27 1.27)
				)
			)
		)
		(property "Value" ""
			(at 0 0 180)
			(layer "F.Fab")
			(effects
				(font
					(size 1.27 1.27)
				)
			)
		)
		(duplicate_pad_numbers_are_jumpers no)
		(fp_line
			(start 0.7874 0.4064)
			(end -0.7874 0.4064)
			(stroke
				(width 0.1524)
				(type default)
			)
			(layer "F.SilkS")
		)
		(fp_line
			(start 0.7874 -0.4064)
			(end 0.7874 0.4064)
			(stroke
				(width 0.1524)
				(type default)
			)
			(layer "F.SilkS")
		)
		(fp_line
			(start -0.7874 0.4064)
			(end -0.7874 -0.4064)
			(stroke
				(width 0.1524)
				(type default)
			)
			(layer "F.SilkS")
		)
		(fp_line
			(start -0.7874 -0.4064)
			(end 0.7874 -0.4064)
			(stroke
				(width 0.1524)
				(type default)
			)
			(layer "F.SilkS")
		)
		(fp_line
			(start 0.6858 0.3048)
			(end 0.1016 0.3048)
			(stroke
				(width 0.1)
				(type default)
			)
			(layer "F.Fab")
		)
		(fp_line
			(start 0.6858 -0.3048)
			(end 0.6858 0.3048)
			(stroke
				(width 0.1)
				(type default)
			)
			(layer "F.Fab")
		)
		(fp_line
			(start 0.1016 0.3048)
			(end 0.1016 0.2794)
			(stroke
				(width 0.1)
				(type default)
			)
			(layer "F.Fab")
		)
		(fp_line
			(start 0.1016 0.2794)
			(end -0.1016 0.2794)
			(stroke
				(width 0.1)
				(type default)
			)
			(layer "F.Fab")
		)
		(fp_line
			(start 0.1016 -0.2794)
			(end 0.1016 -0.3048)
			(stroke
				(width 0.1)
				(type default)
			)
			(layer "F.Fab")
		)
		(fp_line
			(start 0.1016 -0.3048)
			(end 0.6858 -0.3048)
			(stroke
				(width 0.1)
				(type default)
			)
			(layer "F.Fab")
		)
		(fp_line
			(start -0.1016 0.3048)
			(end -0.6858 0.3048)
			(stroke
				(width 0.1)
				(type default)
			)
			(layer "F.Fab")
		)
		(fp_line
			(start -0.1016 0.2794)
			(end -0.1016 0.3048)
			(stroke
				(width 0.1)
				(type default)
			)
			(layer "F.Fab")
		)
		(fp_line
			(start -0.1016 -0.2794)
			(end 0.1016 -0.2794)
			(stroke
				(width 0.1)
				(type default)
			)
			(layer "F.Fab")
		)
		(fp_line
			(start -0.1016 -0.3048)
			(end -0.1016 -0.2794)
			(stroke
				(width 0.1)
				(type default)
			)
			(layer "F.Fab")
		)
		(fp_line
			(start -0.6858 0.3048)
			(end -0.6858 -0.3048)
			(stroke
				(width 0.1)
				(type default)
			)
			(layer "F.Fab")
		)
		(fp_line
			(start -0.6858 -0.3048)
			(end -0.1016 -0.3048)
			(stroke
				(width 0.1)
				(type default)
			)
			(layer "F.Fab")
		)
		(pad "1" smd rect
			(at -0.40005 0)
			(size 0.4572 0.508)
			(layers "F.Cu" "F.Mask" "F.Paste")
			(net "P12V_NIC6_SS")
		)
		(pad "2" smd rect
			(at 0.40005 0)
			(size 0.4572 0.508)
			(layers "F.Cu" "F.Mask" "F.Paste")
			(net "GND")
		)
	)
	(footprint ""
		(layer "F.Cu")
		(at 307.856382 -20.467574 180)
		(property "Reference" "R1703"
			(at 0 0 180)
			(layer "F.SilkS")
			(hide yes)
			(effects
				(font
					(size 1.27 1.27)
				)
			)
		)
		(property "Value" ""
			(at 0 0 180)
			(layer "F.Fab")
			(effects
				(font
					(size 1.27 1.27)
				)
			)
		)
		(duplicate_pad_numbers_are_jumpers no)
		(fp_line
			(start 0.7874 0.4064)
			(end -0.7874 0.4064)
			(stroke
				(width 0.1524)
				(type default)
			)
			(layer "F.SilkS")
		)
		(fp_line
			(start 0.7874 -0.4064)
			(end 0.7874 0.4064)
			(stroke
				(width 0.1524)
				(type default)
			)
			(layer "F.SilkS")
		)
		(fp_line
			(start -0.7874 0.4064)
			(end -0.7874 -0.4064)
			(stroke
				(width 0.1524)
				(type default)
			)
			(layer "F.SilkS")
		)
		(fp_line
			(start -0.7874 -0.4064)
			(end 0.7874 -0.4064)
			(stroke
				(width 0.1524)
				(type default)
			)
			(layer "F.SilkS")
		)
		(fp_line
			(start 0.67945 0.3048)
			(end 0.120396 0.3048)
			(stroke
				(width 0.1)
				(type default)
			)
			(layer "F.Fab")
		)
		(fp_line
			(start 0.67945 -0.3048)
			(end 0.67945 0.3048)
			(stroke
				(width 0.1)
				(type default)
			)
			(layer "F.Fab")
		)
		(fp_line
			(start 0.12065 -0.2794)
			(end 0.12065 -0.3048)
			(stroke
				(width 0.1)
				(type default)
			)
			(layer "F.Fab")
		)
		(fp_line
			(start 0.12065 -0.3048)
			(end 0.67945 -0.3048)
			(stroke
				(width 0.1)
				(type default)
			)
			(layer "F.Fab")
		)
		(fp_line
			(start 0.120396 0.3048)
			(end 0.120396 0.2794)
			(stroke
				(width 0.1)
				(type default)
			)
			(layer "F.Fab")
		)
		(fp_line
			(start 0.120396 0.2794)
			(end -0.12065 0.2794)
			(stroke
				(width 0.1)
				(type default)
			)
			(layer "F.Fab")
		)
		(fp_line
			(start -0.12065 0.3048)
			(end -0.67945 0.3048)
			(stroke
				(width 0.1)
				(type default)
			)
			(layer "F.Fab")
		)
		(fp_line
			(start -0.12065 0.2794)
			(end -0.12065 0.3048)
			(stroke
				(width 0.1)
				(type default)
			)
			(layer "F.Fab")
		)
		(fp_line
			(start -0.12065 -0.2794)
			(end 0.12065 -0.2794)
			(stroke
				(width 0.1)
				(type default)
			)
			(layer "F.Fab")
		)
		(fp_line
			(start -0.12065 -0.305054)
			(end -0.12065 -0.2794)
			(stroke
				(width 0.1)
				(type default)
			)
			(layer "F.Fab")
		)
		(fp_line
			(start -0.67945 0.3048)
			(end -0.67945 -0.305054)
			(stroke
				(width 0.1)
				(type default)
			)
			(layer "F.Fab")
		)
		(fp_line
			(start -0.67945 -0.305054)
			(end -0.12065 -0.305054)
			(stroke
				(width 0.1)
				(type default)
			)
			(layer "F.Fab")
		)
		(pad "1" smd circle
			(at -0.40005 0 180)
			(size 0 0)
			(layers "F.Cu" "F.Mask" "F.Paste")
			(net "P3V3_SSD10")
		)
		(pad "2" smd circle
			(at 0.40005 0 180)
			(size 0 0)
			(layers "F.Cu" "F.Mask" "F.Paste")
			(net "SMB_ISO_SSD10_SDA")
		)
	)
	(footprint ""
		(layer "F.Cu")
		(at 287.439862 -350.098614 90)
		(property "Reference" "C595"
			(at 0 0 90)
			(layer "F.SilkS")
			(hide yes)
			(effects
				(font
					(size 1.27 1.27)
				)
			)
		)
		(property "Value" ""
			(at 0 0 90)
			(layer "F.Fab")
			(effects
				(font
					(size 1.27 1.27)
				)
			)
		)
		(duplicate_pad_numbers_are_jumpers no)
		(fp_line
			(start 0.299974 -0.150114)
			(end 0.299974 0.150114)
			(stroke
				(width 0.1)
				(type default)
			)
			(layer "F.Fab")
		)
		(fp_line
			(start -0.299974 -0.150114)
			(end 0.299974 -0.150114)
			(stroke
				(width 0.1)
				(type default)
			)
			(layer "F.Fab")
		)
		(fp_line
			(start 0.299974 0.150114)
			(end -0.299974 0.150114)
			(stroke
				(width 0.1)
				(type default)
			)
			(layer "F.Fab")
		)
		(fp_line
			(start -0.299974 0.150114)
			(end -0.299974 -0.150114)
			(stroke
				(width 0.1)
				(type default)
			)
			(layer "F.Fab")
		)
		(pad "1" smd rect
			(at -0.2667 0 90)
			(size 0.3048 0.381)
			(layers "F.Cu" "F.Mask" "F.Paste")
			(net "P5E_PEX2_STN7_TX_DP<121>")
		)
		(pad "2" smd rect
			(at 0.2667 0 90)
			(size 0.3048 0.381)
			(layers "F.Cu" "F.Mask" "F.Paste")
			(net "P5E_PEX2_STN7_TX_C_DP<121>")
		)
	)
	(footprint ""
		(layer "F.Cu")
		(at 368.425476 -42.849038 180)
		(property "Reference" "R645"
			(at 0 0 180)
			(layer "F.SilkS")
			(hide yes)
			(effects
				(font
					(size 1.27 1.27)
				)
			)
		)
		(property "Value" ""
			(at 0 0 180)
			(layer "F.Fab")
			(effects
				(font
					(size 1.27 1.27)
				)
			)
		)
		(duplicate_pad_numbers_are_jumpers no)
		(fp_line
			(start 0.7874 0.4064)
			(end -0.7874 0.4064)
			(stroke
				(width 0.1524)
				(type default)
			)
			(layer "F.SilkS")
		)
		(fp_line
			(start 0.7874 -0.4064)
			(end 0.7874 0.4064)
			(stroke
				(width 0.1524)
				(type default)
			)
			(layer "F.SilkS")
		)
		(fp_line
			(start -0.7874 0.4064)
			(end -0.7874 -0.4064)
			(stroke
				(width 0.1524)
				(type default)
			)
			(layer "F.SilkS")
		)
		(fp_line
			(start -0.7874 -0.4064)
			(end 0.7874 -0.4064)
			(stroke
				(width 0.1524)
				(type default)
			)
			(layer "F.SilkS")
		)
		(fp_line
			(start 0.67945 0.3048)
			(end 0.120396 0.3048)
			(stroke
				(width 0.1)
				(type default)
			)
			(layer "F.Fab")
		)
		(fp_line
			(start 0.67945 -0.3048)
			(end 0.67945 0.3048)
			(stroke
				(width 0.1)
				(type default)
			)
			(layer "F.Fab")
		)
		(fp_line
			(start 0.12065 -0.2794)
			(end 0.12065 -0.3048)
			(stroke
				(width 0.1)
				(type default)
			)
			(layer "F.Fab")
		)
		(fp_line
			(start 0.12065 -0.3048)
			(end 0.67945 -0.3048)
			(stroke
				(width 0.1)
				(type default)
			)
			(layer "F.Fab")
		)
		(fp_line
			(start 0.120396 0.3048)
			(end 0.120396 0.2794)
			(stroke
				(width 0.1)
				(type default)
			)
			(layer "F.Fab")
		)
		(fp_line
			(start 0.120396 0.2794)
			(end -0.12065 0.2794)
			(stroke
				(width 0.1)
				(type default)
			)
			(layer "F.Fab")
		)
		(fp_line
			(start -0.12065 0.3048)
			(end -0.67945 0.3048)
			(stroke
				(width 0.1)
				(type default)
			)
			(layer "F.Fab")
		)
		(fp_line
			(start -0.12065 0.2794)
			(end -0.12065 0.3048)
			(stroke
				(width 0.1)
				(type default)
			)
			(layer "F.Fab")
		)
		(fp_line
			(start -0.12065 -0.2794)
			(end 0.12065 -0.2794)
			(stroke
				(width 0.1)
				(type default)
			)
			(layer "F.Fab")
		)
		(fp_line
			(start -0.12065 -0.305054)
			(end -0.12065 -0.2794)
			(stroke
				(width 0.1)
				(type default)
			)
			(layer "F.Fab")
		)
		(fp_line
			(start -0.67945 0.3048)
			(end -0.67945 -0.305054)
			(stroke
				(width 0.1)
				(type default)
			)
			(layer "F.Fab")
		)
		(fp_line
			(start -0.67945 -0.305054)
			(end -0.12065 -0.305054)
			(stroke
				(width 0.1)
				(type default)
			)
			(layer "F.Fab")
		)
		(pad "1" smd circle
			(at -0.40005 0 180)
			(size 0 0)
			(layers "F.Cu" "F.Mask" "F.Paste")
			(net "P12V_SSD12_R")
		)
		(pad "2" smd circle
			(at 0.40005 0 180)
			(size 0 0)
			(layers "F.Cu" "F.Mask" "F.Paste")
			(net "P12V_SSD12_VIN_P")
		)
	)
	(footprint ""
		(layer "F.Cu")
		(at 263.856216 -61.487812 180)
		(property "Reference" "R5993"
			(at 0 0 180)
			(layer "F.SilkS")
			(hide yes)
			(effects
				(font
					(size 1.27 1.27)
				)
			)
		)
		(property "Value" ""
			(at 0 0 180)
			(layer "F.Fab")
			(effects
				(font
					(size 1.27 1.27)
				)
			)
		)
		(duplicate_pad_numbers_are_jumpers no)
		(fp_line
			(start 0.7874 0.4064)
			(end -0.7874 0.4064)
			(stroke
				(width 0.1524)
				(type default)
			)
			(layer "F.SilkS")
		)
		(fp_line
			(start 0.7874 -0.4064)
			(end 0.7874 0.4064)
			(stroke
				(width 0.1524)
				(type default)
			)
			(layer "F.SilkS")
		)
		(fp_line
			(start -0.7874 0.4064)
			(end -0.7874 -0.4064)
			(stroke
				(width 0.1524)
				(type default)
			)
			(layer "F.SilkS")
		)
		(fp_line
			(start -0.7874 -0.4064)
			(end 0.7874 -0.4064)
			(stroke
				(width 0.1524)
				(type default)
			)
			(layer "F.SilkS")
		)
		(fp_line
			(start 0.67945 0.3048)
			(end 0.120396 0.3048)
			(stroke
				(width 0.1)
				(type default)
			)
			(layer "F.Fab")
		)
		(fp_line
			(start 0.67945 -0.3048)
			(end 0.67945 0.3048)
			(stroke
				(width 0.1)
				(type default)
			)
			(layer "F.Fab")
		)
		(fp_line
			(start 0.12065 -0.2794)
			(end 0.12065 -0.3048)
			(stroke
				(width 0.1)
				(type default)
			)
			(layer "F.Fab")
		)
		(fp_line
			(start 0.12065 -0.3048)
			(end 0.67945 -0.3048)
			(stroke
				(width 0.1)
				(type default)
			)
			(layer "F.Fab")
		)
		(fp_line
			(start 0.120396 0.3048)
			(end 0.120396 0.2794)
			(stroke
				(width 0.1)
				(type default)
			)
			(layer "F.Fab")
		)
		(fp_line
			(start 0.120396 0.2794)
			(end -0.12065 0.2794)
			(stroke
				(width 0.1)
				(type default)
			)
			(layer "F.Fab")
		)
		(fp_line
			(start -0.12065 0.3048)
			(end -0.67945 0.3048)
			(stroke
				(width 0.1)
				(type default)
			)
			(layer "F.Fab")
		)
		(fp_line
			(start -0.12065 0.2794)
			(end -0.12065 0.3048)
			(stroke
				(width 0.1)
				(type default)
			)
			(layer "F.Fab")
		)
		(fp_line
			(start -0.12065 -0.2794)
			(end 0.12065 -0.2794)
			(stroke
				(width 0.1)
				(type default)
			)
			(layer "F.Fab")
		)
		(fp_line
			(start -0.12065 -0.305054)
			(end -0.12065 -0.2794)
			(stroke
				(width 0.1)
				(type default)
			)
			(layer "F.Fab")
		)
		(fp_line
			(start -0.67945 0.3048)
			(end -0.67945 -0.305054)
			(stroke
				(width 0.1)
				(type default)
			)
			(layer "F.Fab")
		)
		(fp_line
			(start -0.67945 -0.305054)
			(end -0.12065 -0.305054)
			(stroke
				(width 0.1)
				(type default)
			)
			(layer "F.Fab")
		)
		(pad "1" smd circle
			(at -0.40005 0 180)
			(size 0 0)
			(layers "F.Cu" "F.Mask" "F.Paste")
			(net "P3V3_AUX")
		)
		(pad "2" smd circle
			(at 0.40005 0 180)
			(size 0 0)
			(layers "F.Cu" "F.Mask" "F.Paste")
			(net "PWRGD_P12V_SSD9_D")
		)
	)
	(footprint ""
		(layer "F.Cu")
		(at 54.404514 -362.580682 90)
		(property "Reference" "R6734"
			(at 0 0 90)
			(layer "F.SilkS")
			(hide yes)
			(effects
				(font
					(size 1.27 1.27)
				)
			)
		)
		(property "Value" ""
			(at 0 0 90)
			(layer "F.Fab")
			(effects
				(font
					(size 1.27 1.27)
				)
			)
		)
		(duplicate_pad_numbers_are_jumpers no)
		(fp_line
			(start 0.7874 -0.4064)
			(end 0.7874 0.4064)
			(stroke
				(width 0.1524)
				(type default)
			)
			(layer "F.SilkS")
		)
		(fp_line
			(start -0.7874 -0.4064)
			(end 0.7874 -0.4064)
			(stroke
				(width 0.1524)
				(type default)
			)
			(layer "F.SilkS")
		)
		(fp_line
			(start 0.04318 0.4064)
			(end -0.7874 0.4064)
			(stroke
				(width 0.1524)
				(type default)
			)
			(layer "F.SilkS")
		)
		(fp_line
			(start -0.12065 -0.305054)
			(end -0.12065 -0.2794)
			(stroke
				(width 0.1)
				(type default)
			)
			(layer "F.Fab")
		)
		(fp_line
			(start -0.67945 -0.305054)
			(end -0.12065 -0.305054)
			(stroke
				(width 0.1)
				(type default)
			)
			(layer "F.Fab")
		)
		(fp_line
			(start 0.67945 -0.3048)
			(end 0.67945 0.3048)
			(stroke
				(width 0.1)
				(type default)
			)
			(layer "F.Fab")
		)
		(fp_line
			(start 0.12065 -0.3048)
			(end 0.67945 -0.3048)
			(stroke
				(width 0.1)
				(type default)
			)
			(layer "F.Fab")
		)
		(fp_line
			(start 0.12065 -0.2794)
			(end 0.12065 -0.3048)
			(stroke
				(width 0.1)
				(type default)
			)
			(layer "F.Fab")
		)
		(fp_line
			(start -0.12065 -0.2794)
			(end 0.12065 -0.2794)
			(stroke
				(width 0.1)
				(type default)
			)
			(layer "F.Fab")
		)
		(fp_line
			(start 0.120396 0.2794)
			(end -0.12065 0.2794)
			(stroke
				(width 0.1)
				(type default)
			)
			(layer "F.Fab")
		)
		(fp_line
			(start -0.12065 0.2794)
			(end -0.12065 0.3048)
			(stroke
				(width 0.1)
				(type default)
			)
			(layer "F.Fab")
		)
		(fp_line
			(start 0.67945 0.3048)
			(end 0.120396 0.3048)
			(stroke
				(width 0.1)
				(type default)
			)
			(layer "F.Fab")
		)
		(fp_line
			(start 0.120396 0.3048)
			(end 0.120396 0.2794)
			(stroke
				(width 0.1)
				(type default)
			)
			(layer "F.Fab")
		)
		(fp_line
			(start -0.12065 0.3048)
			(end -0.67945 0.3048)
			(stroke
				(width 0.1)
				(type default)
			)
			(layer "F.Fab")
		)
		(fp_line
			(start -0.67945 0.3048)
			(end -0.67945 -0.305054)
			(stroke
				(width 0.1)
				(type default)
			)
			(layer "F.Fab")
		)
		(pad "1" smd rect
			(at -0.40005 0 270)
			(size 0.4572 0.508)
			(layers "F.Cu" "F.Mask" "F.Paste")
			(net "USB2_GPU_HMC_USB8042_DN")
		)
		(pad "2" smd rect
			(at 0.40005 0 270)
			(size 0.4572 0.508)
			(layers "F.Cu" "F.Mask" "F.Paste")
			(net "USB2_GPU_HMC_DN")
		)
	)
	(footprint ""
		(layer "F.Cu")
		(at 17.792446 -32.739584 180)
		(property "Reference" "C67"
			(at 0 0 180)
			(layer "F.SilkS")
			(hide yes)
			(effects
				(font
					(size 1.27 1.27)
				)
			)
		)
		(property "Value" ""
			(at 0 0 180)
			(layer "F.Fab")
			(effects
				(font
					(size 1.27 1.27)
				)
			)
		)
		(duplicate_pad_numbers_are_jumpers no)
		(fp_line
			(start 0.299974 0.150114)
			(end -0.299974 0.150114)
			(stroke
				(width 0.1)
				(type default)
			)
			(layer "F.Fab")
		)
		(fp_line
			(start 0.299974 -0.150114)
			(end 0.299974 0.150114)
			(stroke
				(width 0.1)
				(type default)
			)
			(layer "F.Fab")
		)
		(fp_line
			(start -0.299974 0.150114)
			(end -0.299974 -0.150114)
			(stroke
				(width 0.1)
				(type default)
			)
			(layer "F.Fab")
		)
		(fp_line
			(start -0.299974 -0.150114)
			(end 0.299974 -0.150114)
			(stroke
				(width 0.1)
				(type default)
			)
			(layer "F.Fab")
		)
		(pad "1" smd rect
			(at -0.2667 0 180)
			(size 0.3048 0.381)
			(layers "F.Cu" "F.Mask" "F.Paste")
			(net "P5E_PEX0_STN2_TX_DP<46>")
		)
		(pad "2" smd rect
			(at 0.2667 0 180)
			(size 0.3048 0.381)
			(layers "F.Cu" "F.Mask" "F.Paste")
			(net "P5E_PEX0_STN2_TX_C_DP<46>")
		)
	)
	(footprint ""
		(layer "F.Cu")
		(at 13.764768 -162.003994 90)
		(property "Reference" "PC614"
			(at 0 0 90)
			(layer "F.SilkS")
			(hide yes)
			(effects
				(font
					(size 1.27 1.27)
				)
			)
		)
		(property "Value" ""
			(at 0 0 90)
			(layer "F.Fab")
			(effects
				(font
					(size 1.27 1.27)
				)
			)
		)
		(duplicate_pad_numbers_are_jumpers no)
		(fp_line
			(start 0.7874 -0.4064)
			(end 0.7874 0.4064)
			(stroke
				(width 0.1524)
				(type default)
			)
			(layer "F.SilkS")
		)
		(fp_line
			(start -0.7874 -0.4064)
			(end 0.7874 -0.4064)
			(stroke
				(width 0.1524)
				(type default)
			)
			(layer "F.SilkS")
		)
		(fp_line
			(start 0.7874 0.4064)
			(end -0.7874 0.4064)
			(stroke
				(width 0.1524)
				(type default)
			)
			(layer "F.SilkS")
		)
		(fp_line
			(start -0.7874 0.4064)
			(end -0.7874 -0.4064)
			(stroke
				(width 0.1524)
				(type default)
			)
			(layer "F.SilkS")
		)
		(fp_line
			(start -0.12065 -0.305054)
			(end -0.12065 -0.2794)
			(stroke
				(width 0.1)
				(type default)
			)
			(layer "F.Fab")
		)
		(fp_line
			(start -0.67945 -0.305054)
			(end -0.12065 -0.305054)
			(stroke
				(width 0.1)
				(type default)
			)
			(layer "F.Fab")
		)
		(fp_line
			(start 0.67945 -0.3048)
			(end 0.67945 0.3048)
			(stroke
				(width 0.1)
				(type default)
			)
			(layer "F.Fab")
		)
		(fp_line
			(start 0.12065 -0.3048)
			(end 0.67945 -0.3048)
			(stroke
				(width 0.1)
				(type default)
			)
			(layer "F.Fab")
		)
		(fp_line
			(start 0.12065 -0.2794)
			(end 0.12065 -0.3048)
			(stroke
				(width 0.1)
				(type default)
			)
			(layer "F.Fab")
		)
		(fp_line
			(start -0.12065 -0.2794)
			(end 0.12065 -0.2794)
			(stroke
				(width 0.1)
				(type default)
			)
			(layer "F.Fab")
		)
		(fp_line
			(start 0.120396 0.2794)
			(end -0.12065 0.2794)
			(stroke
				(width 0.1)
				(type default)
			)
			(layer "F.Fab")
		)
		(fp_line
			(start -0.12065 0.2794)
			(end -0.12065 0.3048)
			(stroke
				(width 0.1)
				(type default)
			)
			(layer "F.Fab")
		)
		(fp_line
			(start 0.67945 0.3048)
			(end 0.120396 0.3048)
			(stroke
				(width 0.1)
				(type default)
			)
			(layer "F.Fab")
		)
		(fp_line
			(start 0.120396 0.3048)
			(end 0.120396 0.2794)
			(stroke
				(width 0.1)
				(type default)
			)
			(layer "F.Fab")
		)
		(fp_line
			(start -0.12065 0.3048)
			(end -0.67945 0.3048)
			(stroke
				(width 0.1)
				(type default)
			)
			(layer "F.Fab")
		)
		(fp_line
			(start -0.67945 0.3048)
			(end -0.67945 -0.305054)
			(stroke
				(width 0.1)
				(type default)
			)
			(layer "F.Fab")
		)
		(pad "1" smd circle
			(at -0.40005 0 90)
			(size 0 0)
			(layers "F.Cu" "F.Mask" "F.Paste")
			(net "P12V_NIC0_CO_TIMER")
		)
		(pad "2" smd circle
			(at 0.40005 0 90)
			(size 0 0)
			(layers "F.Cu" "F.Mask" "F.Paste")
			(net "GND")
		)
	)
	(footprint ""
		(layer "F.Cu")
		(at 258.996434 -342.010746 -90)
		(property "Reference" "C4447"
			(at 0 0 270)
			(layer "F.SilkS")
			(hide yes)
			(effects
				(font
					(size 1.27 1.27)
				)
			)
		)
		(property "Value" ""
			(at 0 0 270)
			(layer "F.Fab")
			(effects
				(font
					(size 1.27 1.27)
				)
			)
		)
		(duplicate_pad_numbers_are_jumpers no)
		(fp_line
			(start -0.7874 0.4064)
			(end -0.7874 -0.4064)
			(stroke
				(width 0.1524)
				(type default)
			)
			(layer "F.SilkS")
		)
		(fp_line
			(start 0.7874 0.4064)
			(end -0.7874 0.4064)
			(stroke
				(width 0.1524)
				(type default)
			)
			(layer "F.SilkS")
		)
		(fp_line
			(start -0.7874 -0.4064)
			(end 0.7874 -0.4064)
			(stroke
				(width 0.1524)
				(type default)
			)
			(layer "F.SilkS")
		)
		(fp_line
			(start 0.7874 -0.4064)
			(end 0.7874 0.4064)
			(stroke
				(width 0.1524)
				(type default)
			)
			(layer "F.SilkS")
		)
		(fp_line
			(start -0.67945 0.3048)
			(end -0.67945 -0.305054)
			(stroke
				(width 0.1)
				(type default)
			)
			(layer "F.Fab")
		)
		(fp_line
			(start -0.12065 0.3048)
			(end -0.67945 0.3048)
			(stroke
				(width 0.1)
				(type default)
			)
			(layer "F.Fab")
		)
		(fp_line
			(start 0.120396 0.3048)
			(end 0.120396 0.2794)
			(stroke
				(width 0.1)
				(type default)
			)
			(layer "F.Fab")
		)
		(fp_line
			(start 0.67945 0.3048)
			(end 0.120396 0.3048)
			(stroke
				(width 0.1)
				(type default)
			)
			(layer "F.Fab")
		)
		(fp_line
			(start -0.12065 0.2794)
			(end -0.12065 0.3048)
			(stroke
				(width 0.1)
				(type default)
			)
			(layer "F.Fab")
		)
		(fp_line
			(start 0.120396 0.2794)
			(end -0.12065 0.2794)
			(stroke
				(width 0.1)
				(type default)
			)
			(layer "F.Fab")
		)
		(fp_line
			(start -0.12065 -0.2794)
			(end 0.12065 -0.2794)
			(stroke
				(width 0.1)
				(type default)
			)
			(layer "F.Fab")
		)
		(fp_line
			(start 0.12065 -0.2794)
			(end 0.12065 -0.3048)
			(stroke
				(width 0.1)
				(type default)
			)
			(layer "F.Fab")
		)
		(fp_line
			(start 0.12065 -0.3048)
			(end 0.67945 -0.3048)
			(stroke
				(width 0.1)
				(type default)
			)
			(layer "F.Fab")
		)
		(fp_line
			(start 0.67945 -0.3048)
			(end 0.67945 0.3048)
			(stroke
				(width 0.1)
				(type default)
			)
			(layer "F.Fab")
		)
		(fp_line
			(start -0.67945 -0.305054)
			(end -0.12065 -0.305054)
			(stroke
				(width 0.1)
				(type default)
			)
			(layer "F.Fab")
		)
		(fp_line
			(start -0.12065 -0.305054)
			(end -0.12065 -0.2794)
			(stroke
				(width 0.1)
				(type default)
			)
			(layer "F.Fab")
		)
		(pad "1" smd circle
			(at -0.40005 0 270)
			(size 0 0)
			(layers "F.Cu" "F.Mask" "F.Paste")
			(net "HSC_OC_LT6700_VS")
		)
		(pad "2" smd circle
			(at 0.40005 0 270)
			(size 0 0)
			(layers "F.Cu" "F.Mask" "F.Paste")
			(net "GND")
		)
	)
	(footprint ""
		(layer "F.Cu")
		(at 447.830448 -66.32194 -90)
		(property "Reference" "PC897"
			(at 0 0 270)
			(layer "F.SilkS")
			(hide yes)
			(effects
				(font
					(size 1.27 1.27)
				)
			)
		)
		(property "Value" ""
			(at 0 0 270)
			(layer "F.Fab")
			(effects
				(font
					(size 1.27 1.27)
				)
			)
		)
		(duplicate_pad_numbers_are_jumpers no)
		(fp_line
			(start -0.7874 0.4064)
			(end -0.7874 -0.4064)
			(stroke
				(width 0.1524)
				(type default)
			)
			(layer "F.SilkS")
		)
		(fp_line
			(start 0.7874 0.4064)
			(end -0.7874 0.4064)
			(stroke
				(width 0.1524)
				(type default)
			)
			(layer "F.SilkS")
		)
		(fp_line
			(start -0.7874 -0.4064)
			(end 0.7874 -0.4064)
			(stroke
				(width 0.1524)
				(type default)
			)
			(layer "F.SilkS")
		)
		(fp_line
			(start 0.7874 -0.4064)
			(end 0.7874 0.4064)
			(stroke
				(width 0.1524)
				(type default)
			)
			(layer "F.SilkS")
		)
		(fp_line
			(start -0.67945 0.3048)
			(end -0.67945 -0.305054)
			(stroke
				(width 0.1)
				(type default)
			)
			(layer "F.Fab")
		)
		(fp_line
			(start -0.12065 0.3048)
			(end -0.67945 0.3048)
			(stroke
				(width 0.1)
				(type default)
			)
			(layer "F.Fab")
		)
		(fp_line
			(start 0.120396 0.3048)
			(end 0.120396 0.2794)
			(stroke
				(width 0.1)
				(type default)
			)
			(layer "F.Fab")
		)
		(fp_line
			(start 0.67945 0.3048)
			(end 0.120396 0.3048)
			(stroke
				(width 0.1)
				(type default)
			)
			(layer "F.Fab")
		)
		(fp_line
			(start -0.12065 0.2794)
			(end -0.12065 0.3048)
			(stroke
				(width 0.1)
				(type default)
			)
			(layer "F.Fab")
		)
		(fp_line
			(start 0.120396 0.2794)
			(end -0.12065 0.2794)
			(stroke
				(width 0.1)
				(type default)
			)
			(layer "F.Fab")
		)
		(fp_line
			(start -0.12065 -0.2794)
			(end 0.12065 -0.2794)
			(stroke
				(width 0.1)
				(type default)
			)
			(layer "F.Fab")
		)
		(fp_line
			(start 0.12065 -0.2794)
			(end 0.12065 -0.3048)
			(stroke
				(width 0.1)
				(type default)
			)
			(layer "F.Fab")
		)
		(fp_line
			(start 0.12065 -0.3048)
			(end 0.67945 -0.3048)
			(stroke
				(width 0.1)
				(type default)
			)
			(layer "F.Fab")
		)
		(fp_line
			(start 0.67945 -0.3048)
			(end 0.67945 0.3048)
			(stroke
				(width 0.1)
				(type default)
			)
			(layer "F.Fab")
		)
		(fp_line
			(start -0.67945 -0.305054)
			(end -0.12065 -0.305054)
			(stroke
				(width 0.1)
				(type default)
			)
			(layer "F.Fab")
		)
		(fp_line
			(start -0.12065 -0.305054)
			(end -0.12065 -0.2794)
			(stroke
				(width 0.1)
				(type default)
			)
			(layer "F.Fab")
		)
		(pad "1" smd circle
			(at -0.40005 0 270)
			(size 0 0)
			(layers "F.Cu" "F.Mask" "F.Paste")
			(net "P12V_SSD15_CO_DV_DT")
		)
		(pad "2" smd circle
			(at 0.40005 0 270)
			(size 0 0)
			(layers "F.Cu" "F.Mask" "F.Paste")
			(net "GND")
		)
	)
	(footprint ""
		(layer "F.Cu")
		(at 270.982694 -140.85697)
		(property "Reference" "R238"
			(at 0 0 0)
			(layer "F.SilkS")
			(hide yes)
			(effects
				(font
					(size 1.27 1.27)
				)
			)
		)
		(property "Value" ""
			(at 0 0 0)
			(layer "F.Fab")
			(effects
				(font
					(size 1.27 1.27)
				)
			)
		)
		(duplicate_pad_numbers_are_jumpers no)
		(fp_line
			(start -0.7874 -0.4064)
			(end 0.7874 -0.4064)
			(stroke
				(width 0.1524)
				(type default)
			)
			(layer "F.SilkS")
		)
		(fp_line
			(start -0.7874 0.4064)
			(end -0.7874 -0.4064)
			(stroke
				(width 0.1524)
				(type default)
			)
			(layer "F.SilkS")
		)
		(fp_line
			(start 0.7874 -0.4064)
			(end 0.7874 0.4064)
			(stroke
				(width 0.1524)
				(type default)
			)
			(layer "F.SilkS")
		)
		(fp_line
			(start 0.7874 0.4064)
			(end -0.7874 0.4064)
			(stroke
				(width 0.1524)
				(type default)
			)
			(layer "F.SilkS")
		)
		(fp_line
			(start -0.67945 -0.305054)
			(end -0.12065 -0.305054)
			(stroke
				(width 0.1)
				(type default)
			)
			(layer "F.Fab")
		)
		(fp_line
			(start -0.67945 0.3048)
			(end -0.67945 -0.305054)
			(stroke
				(width 0.1)
				(type default)
			)
			(layer "F.Fab")
		)
		(fp_line
			(start -0.12065 -0.305054)
			(end -0.12065 -0.2794)
			(stroke
				(width 0.1)
				(type default)
			)
			(layer "F.Fab")
		)
		(fp_line
			(start -0.12065 -0.2794)
			(end 0.12065 -0.2794)
			(stroke
				(width 0.1)
				(type default)
			)
			(layer "F.Fab")
		)
		(fp_line
			(start -0.12065 0.2794)
			(end -0.12065 0.3048)
			(stroke
				(width 0.1)
				(type default)
			)
			(layer "F.Fab")
		)
		(fp_line
			(start -0.12065 0.3048)
			(end -0.67945 0.3048)
			(stroke
				(width 0.1)
				(type default)
			)
			(layer "F.Fab")
		)
		(fp_line
			(start 0.120396 0.2794)
			(end -0.12065 0.2794)
			(stroke
				(width 0.1)
				(type default)
			)
			(layer "F.Fab")
		)
		(fp_line
			(start 0.120396 0.3048)
			(end 0.120396 0.2794)
			(stroke
				(width 0.1)
				(type default)
			)
			(layer "F.Fab")
		)
		(fp_line
			(start 0.12065 -0.3048)
			(end 0.67945 -0.3048)
			(stroke
				(width 0.1)
				(type default)
			)
			(layer "F.Fab")
		)
		(fp_line
			(start 0.12065 -0.2794)
			(end 0.12065 -0.3048)
			(stroke
				(width 0.1)
				(type default)
			)
			(layer "F.Fab")
		)
		(fp_line
			(start 0.67945 -0.3048)
			(end 0.67945 0.3048)
			(stroke
				(width 0.1)
				(type default)
			)
			(layer "F.Fab")
		)
		(fp_line
			(start 0.67945 0.3048)
			(end 0.120396 0.3048)
			(stroke
				(width 0.1)
				(type default)
			)
			(layer "F.Fab")
		)
		(pad "1" smd circle
			(at -0.40005 0)
			(size 0 0)
			(layers "F.Cu" "F.Mask" "F.Paste")
			(net "NIC4_BIF2_N")
		)
		(pad "2" smd circle
			(at 0.40005 0)
			(size 0 0)
			(layers "F.Cu" "F.Mask" "F.Paste")
			(net "GND")
		)
	)
	(footprint ""
		(layer "F.Cu")
		(at 142.262352 -262.645652 90)
		(property "Reference" "C3246"
			(at 0 0 90)
			(layer "F.SilkS")
			(hide yes)
			(effects
				(font
					(size 1.27 1.27)
				)
			)
		)
		(property "Value" ""
			(at 0 0 90)
			(layer "F.Fab")
			(effects
				(font
					(size 1.27 1.27)
				)
			)
		)
		(duplicate_pad_numbers_are_jumpers no)
		(fp_line
			(start 0.299974 -0.150114)
			(end 0.299974 0.150114)
			(stroke
				(width 0.1)
				(type default)
			)
			(layer "F.Fab")
		)
		(fp_line
			(start -0.299974 -0.150114)
			(end 0.299974 -0.150114)
			(stroke
				(width 0.1)
				(type default)
			)
			(layer "F.Fab")
		)
		(fp_line
			(start 0.299974 0.150114)
			(end -0.299974 0.150114)
			(stroke
				(width 0.1)
				(type default)
			)
			(layer "F.Fab")
		)
		(fp_line
			(start -0.299974 0.150114)
			(end -0.299974 -0.150114)
			(stroke
				(width 0.1)
				(type default)
			)
			(layer "F.Fab")
		)
		(pad "1" smd rect
			(at -0.2667 0 90)
			(size 0.3048 0.381)
			(layers "F.Cu" "F.Mask" "F.Paste")
			(net "P1V8_VDDA_PEX1")
		)
		(pad "2" smd rect
			(at 0.2667 0 90)
			(size 0.3048 0.381)
			(layers "F.Cu" "F.Mask" "F.Paste")
			(net "GND")
		)
	)
	(footprint ""
		(layer "F.Cu")
		(at 283.416502 -350.098614 90)
		(property "Reference" "C2355"
			(at 0 0 90)
			(layer "F.SilkS")
			(hide yes)
			(effects
				(font
					(size 1.27 1.27)
				)
			)
		)
		(property "Value" ""
			(at 0 0 90)
			(layer "F.Fab")
			(effects
				(font
					(size 1.27 1.27)
				)
			)
		)
		(duplicate_pad_numbers_are_jumpers no)
		(fp_line
			(start 0.299974 -0.150114)
			(end 0.299974 0.150114)
			(stroke
				(width 0.1)
				(type default)
			)
			(layer "F.Fab")
		)
		(fp_line
			(start -0.299974 -0.150114)
			(end 0.299974 -0.150114)
			(stroke
				(width 0.1)
				(type default)
			)
			(layer "F.Fab")
		)
		(fp_line
			(start 0.299974 0.150114)
			(end -0.299974 0.150114)
			(stroke
				(width 0.1)
				(type default)
			)
			(layer "F.Fab")
		)
		(fp_line
			(start -0.299974 0.150114)
			(end -0.299974 -0.150114)
			(stroke
				(width 0.1)
				(type default)
			)
			(layer "F.Fab")
		)
		(pad "1" smd rect
			(at -0.2667 0 90)
			(size 0.3048 0.381)
			(layers "F.Cu" "F.Mask" "F.Paste")
			(net "P5E_PEX2_STN4_TX_DP<72>")
		)
		(pad "2" smd rect
			(at 0.2667 0 90)
			(size 0.3048 0.381)
			(layers "F.Cu" "F.Mask" "F.Paste")
			(net "P5E_PEX2_STN4_TX_C_DP<72>")
		)
	)
	(footprint ""
		(layer "F.Cu")
		(at 242.447318 -266.794996)
		(property "Reference" "L114"
			(at 0 0 0)
			(layer "F.SilkS")
			(hide yes)
			(effects
				(font
					(size 1.27 1.27)
				)
			)
		)
		(property "Value" ""
			(at 0 0 0)
			(layer "F.Fab")
			(effects
				(font
					(size 1.27 1.27)
				)
			)
		)
		(duplicate_pad_numbers_are_jumpers no)
		(fp_line
			(start -2.248154 -4.9911)
			(end -2.248154 -1.772412)
			(stroke
				(width 0.1524)
				(type default)
			)
			(layer "F.SilkS")
		)
		(fp_line
			(start -2.248154 1.653286)
			(end -2.248154 4.9911)
			(stroke
				(width 0.1524)
				(type default)
			)
			(layer "F.SilkS")
		)
		(fp_line
			(start -2.248154 4.9911)
			(end 2.248154 4.9911)
			(stroke
				(width 0.1524)
				(type default)
			)
			(layer "F.SilkS")
		)
		(fp_line
			(start 2.248154 -4.9911)
			(end -2.248154 -4.9911)
			(stroke
				(width 0.1524)
				(type default)
			)
			(layer "F.SilkS")
		)
		(fp_line
			(start 2.248154 -1.860296)
			(end 2.248154 -4.9911)
			(stroke
				(width 0.1524)
				(type default)
			)
			(layer "F.SilkS")
		)
		(fp_line
			(start 2.248154 4.9911)
			(end 2.248154 1.675384)
			(stroke
				(width 0.1524)
				(type default)
			)
			(layer "F.SilkS")
		)
		(fp_line
			(start -1.700022 -0.899922)
			(end -1.700022 0.899922)
			(stroke
				(width 0.1)
				(type default)
			)
			(layer "F.Fab")
		)
		(fp_line
			(start -1.700022 0.899922)
			(end 1.700022 0.899922)
			(stroke
				(width 0.1)
				(type default)
			)
			(layer "F.Fab")
		)
		(fp_line
			(start 1.700022 -0.899922)
			(end -1.700022 -0.899922)
			(stroke
				(width 0.1)
				(type default)
			)
			(layer "F.Fab")
		)
		(fp_line
			(start 1.700022 0.899922)
			(end 1.700022 -0.899922)
			(stroke
				(width 0.1)
				(type default)
			)
			(layer "F.Fab")
		)
		(pad "1" smd rect
			(at -1.575054 0)
			(size 1.1684 9.8044)
			(layers "F.Cu" "F.Mask" "F.Paste")
			(net "P1V25_PEX2")
		)
		(pad "2" smd rect
			(at 1.575054 0)
			(size 1.1684 9.8044)
			(layers "F.Cu" "F.Mask" "F.Paste")
			(net "P1V25_SERDES_VDDPLL_PEX2")
		)
	)
	(footprint ""
		(layer "F.Cu")
		(at 78.02499 -14.735302 180)
		(property "Reference" "C2716"
			(at 0 0 180)
			(layer "F.SilkS")
			(hide yes)
			(effects
				(font
					(size 1.27 1.27)
				)
			)
		)
		(property "Value" ""
			(at 0 0 180)
			(layer "F.Fab")
			(effects
				(font
					(size 1.27 1.27)
				)
			)
		)
		(duplicate_pad_numbers_are_jumpers no)
		(fp_line
			(start 0.7874 0.4064)
			(end -0.7874 0.4064)
			(stroke
				(width 0.1524)
				(type default)
			)
			(layer "F.SilkS")
		)
		(fp_line
			(start 0.7874 -0.4064)
			(end 0.7874 0.4064)
			(stroke
				(width 0.1524)
				(type default)
			)
			(layer "F.SilkS")
		)
		(fp_line
			(start -0.7874 0.4064)
			(end -0.7874 -0.4064)
			(stroke
				(width 0.1524)
				(type default)
			)
			(layer "F.SilkS")
		)
		(fp_line
			(start -0.7874 -0.4064)
			(end 0.7874 -0.4064)
			(stroke
				(width 0.1524)
				(type default)
			)
			(layer "F.SilkS")
		)
		(fp_line
			(start 0.67945 0.3048)
			(end 0.120396 0.3048)
			(stroke
				(width 0.1)
				(type default)
			)
			(layer "F.Fab")
		)
		(fp_line
			(start 0.67945 -0.3048)
			(end 0.67945 0.3048)
			(stroke
				(width 0.1)
				(type default)
			)
			(layer "F.Fab")
		)
		(fp_line
			(start 0.12065 -0.2794)
			(end 0.12065 -0.3048)
			(stroke
				(width 0.1)
				(type default)
			)
			(layer "F.Fab")
		)
		(fp_line
			(start 0.12065 -0.3048)
			(end 0.67945 -0.3048)
			(stroke
				(width 0.1)
				(type default)
			)
			(layer "F.Fab")
		)
		(fp_line
			(start 0.120396 0.3048)
			(end 0.120396 0.2794)
			(stroke
				(width 0.1)
				(type default)
			)
			(layer "F.Fab")
		)
		(fp_line
			(start 0.120396 0.2794)
			(end -0.12065 0.2794)
			(stroke
				(width 0.1)
				(type default)
			)
			(layer "F.Fab")
		)
		(fp_line
			(start -0.12065 0.3048)
			(end -0.67945 0.3048)
			(stroke
				(width 0.1)
				(type default)
			)
			(layer "F.Fab")
		)
		(fp_line
			(start -0.12065 0.2794)
			(end -0.12065 0.3048)
			(stroke
				(width 0.1)
				(type default)
			)
			(layer "F.Fab")
		)
		(fp_line
			(start -0.12065 -0.2794)
			(end 0.12065 -0.2794)
			(stroke
				(width 0.1)
				(type default)
			)
			(layer "F.Fab")
		)
		(fp_line
			(start -0.12065 -0.305054)
			(end -0.12065 -0.2794)
			(stroke
				(width 0.1)
				(type default)
			)
			(layer "F.Fab")
		)
		(fp_line
			(start -0.67945 0.3048)
			(end -0.67945 -0.305054)
			(stroke
				(width 0.1)
				(type default)
			)
			(layer "F.Fab")
		)
		(fp_line
			(start -0.67945 -0.305054)
			(end -0.12065 -0.305054)
			(stroke
				(width 0.1)
				(type default)
			)
			(layer "F.Fab")
		)
		(pad "1" smd circle
			(at -0.40005 0 180)
			(size 0 0)
			(layers "F.Cu" "F.Mask" "F.Paste")
			(net "GND")
		)
		(pad "2" smd circle
			(at 0.40005 0 180)
			(size 0 0)
			(layers "F.Cu" "F.Mask" "F.Paste")
			(net "P3V3_SSD2")
		)
	)
	(footprint ""
		(layer "F.Cu")
		(at 14.668246 -215.320372 180)
		(property "Reference" "R6570"
			(at 0 0 180)
			(layer "F.SilkS")
			(hide yes)
			(effects
				(font
					(size 1.27 1.27)
				)
			)
		)
		(property "Value" ""
			(at 0 0 180)
			(layer "F.Fab")
			(effects
				(font
					(size 1.27 1.27)
				)
			)
		)
		(duplicate_pad_numbers_are_jumpers no)
		(fp_line
			(start 0.7874 0.4064)
			(end -0.7874 0.4064)
			(stroke
				(width 0.1524)
				(type default)
			)
			(layer "F.SilkS")
		)
		(fp_line
			(start 0.7874 -0.4064)
			(end 0.7874 0.4064)
			(stroke
				(width 0.1524)
				(type default)
			)
			(layer "F.SilkS")
		)
		(fp_line
			(start -0.7874 0.4064)
			(end -0.7874 -0.4064)
			(stroke
				(width 0.1524)
				(type default)
			)
			(layer "F.SilkS")
		)
		(fp_line
			(start -0.7874 -0.4064)
			(end 0.7874 -0.4064)
			(stroke
				(width 0.1524)
				(type default)
			)
			(layer "F.SilkS")
		)
		(fp_line
			(start 0.67945 0.3048)
			(end 0.120396 0.3048)
			(stroke
				(width 0.1)
				(type default)
			)
			(layer "F.Fab")
		)
		(fp_line
			(start 0.67945 -0.3048)
			(end 0.67945 0.3048)
			(stroke
				(width 0.1)
				(type default)
			)
			(layer "F.Fab")
		)
		(fp_line
			(start 0.12065 -0.2794)
			(end 0.12065 -0.3048)
			(stroke
				(width 0.1)
				(type default)
			)
			(layer "F.Fab")
		)
		(fp_line
			(start 0.12065 -0.3048)
			(end 0.67945 -0.3048)
			(stroke
				(width 0.1)
				(type default)
			)
			(layer "F.Fab")
		)
		(fp_line
			(start 0.120396 0.3048)
			(end 0.120396 0.2794)
			(stroke
				(width 0.1)
				(type default)
			)
			(layer "F.Fab")
		)
		(fp_line
			(start 0.120396 0.2794)
			(end -0.12065 0.2794)
			(stroke
				(width 0.1)
				(type default)
			)
			(layer "F.Fab")
		)
		(fp_line
			(start -0.12065 0.3048)
			(end -0.67945 0.3048)
			(stroke
				(width 0.1)
				(type default)
			)
			(layer "F.Fab")
		)
		(fp_line
			(start -0.12065 0.2794)
			(end -0.12065 0.3048)
			(stroke
				(width 0.1)
				(type default)
			)
			(layer "F.Fab")
		)
		(fp_line
			(start -0.12065 -0.2794)
			(end 0.12065 -0.2794)
			(stroke
				(width 0.1)
				(type default)
			)
			(layer "F.Fab")
		)
		(fp_line
			(start -0.12065 -0.305054)
			(end -0.12065 -0.2794)
			(stroke
				(width 0.1)
				(type default)
			)
			(layer "F.Fab")
		)
		(fp_line
			(start -0.67945 0.3048)
			(end -0.67945 -0.305054)
			(stroke
				(width 0.1)
				(type default)
			)
			(layer "F.Fab")
		)
		(fp_line
			(start -0.67945 -0.305054)
			(end -0.12065 -0.305054)
			(stroke
				(width 0.1)
				(type default)
			)
			(layer "F.Fab")
		)
		(pad "1" smd circle
			(at -0.40005 0 180)
			(size 0 0)
			(layers "F.Cu" "F.Mask" "F.Paste")
			(net "PWR_EN_PEX_R")
		)
		(pad "2" smd circle
			(at 0.40005 0 180)
			(size 0 0)
			(layers "F.Cu" "F.Mask" "F.Paste")
			(net "PEX0_P1V8_PLL_EN")
		)
	)
	(footprint ""
		(layer "F.Cu")
		(at 454.896982 -116.611654 180)
		(property "Reference" "PR7055"
			(at 0 0 180)
			(layer "F.SilkS")
			(hide yes)
			(effects
				(font
					(size 1.27 1.27)
				)
			)
		)
		(property "Value" ""
			(at 0 0 180)
			(layer "F.Fab")
			(effects
				(font
					(size 1.27 1.27)
				)
			)
		)
		(duplicate_pad_numbers_are_jumpers no)
		(fp_line
			(start 0.7874 0.4064)
			(end -0.7874 0.4064)
			(stroke
				(width 0.1524)
				(type default)
			)
			(layer "F.SilkS")
		)
		(fp_line
			(start 0.7874 -0.4064)
			(end 0.7874 0.4064)
			(stroke
				(width 0.1524)
				(type default)
			)
			(layer "F.SilkS")
		)
		(fp_line
			(start -0.7874 0.4064)
			(end -0.7874 -0.4064)
			(stroke
				(width 0.1524)
				(type default)
			)
			(layer "F.SilkS")
		)
		(fp_line
			(start -0.7874 -0.4064)
			(end 0.7874 -0.4064)
			(stroke
				(width 0.1524)
				(type default)
			)
			(layer "F.SilkS")
		)
		(fp_line
			(start 0.67945 0.3048)
			(end 0.120396 0.3048)
			(stroke
				(width 0.1)
				(type default)
			)
			(layer "F.Fab")
		)
		(fp_line
			(start 0.67945 -0.3048)
			(end 0.67945 0.3048)
			(stroke
				(width 0.1)
				(type default)
			)
			(layer "F.Fab")
		)
		(fp_line
			(start 0.12065 -0.2794)
			(end 0.12065 -0.3048)
			(stroke
				(width 0.1)
				(type default)
			)
			(layer "F.Fab")
		)
		(fp_line
			(start 0.12065 -0.3048)
			(end 0.67945 -0.3048)
			(stroke
				(width 0.1)
				(type default)
			)
			(layer "F.Fab")
		)
		(fp_line
			(start 0.120396 0.3048)
			(end 0.120396 0.2794)
			(stroke
				(width 0.1)
				(type default)
			)
			(layer "F.Fab")
		)
		(fp_line
			(start 0.120396 0.2794)
			(end -0.12065 0.2794)
			(stroke
				(width 0.1)
				(type default)
			)
			(layer "F.Fab")
		)
		(fp_line
			(start -0.12065 0.3048)
			(end -0.67945 0.3048)
			(stroke
				(width 0.1)
				(type default)
			)
			(layer "F.Fab")
		)
		(fp_line
			(start -0.12065 0.2794)
			(end -0.12065 0.3048)
			(stroke
				(width 0.1)
				(type default)
			)
			(layer "F.Fab")
		)
		(fp_line
			(start -0.12065 -0.2794)
			(end 0.12065 -0.2794)
			(stroke
				(width 0.1)
				(type default)
			)
			(layer "F.Fab")
		)
		(fp_line
			(start -0.12065 -0.305054)
			(end -0.12065 -0.2794)
			(stroke
				(width 0.1)
				(type default)
			)
			(layer "F.Fab")
		)
		(fp_line
			(start -0.67945 0.3048)
			(end -0.67945 -0.305054)
			(stroke
				(width 0.1)
				(type default)
			)
			(layer "F.Fab")
		)
		(fp_line
			(start -0.67945 -0.305054)
			(end -0.12065 -0.305054)
			(stroke
				(width 0.1)
				(type default)
			)
			(layer "F.Fab")
		)
		(pad "1" smd circle
			(at -0.40005 0 180)
			(size 0 0)
			(layers "F.Cu" "F.Mask" "F.Paste")
			(net "P12V_NIC7_CO_OV_FB")
		)
		(pad "2" smd circle
			(at 0.40005 0 180)
			(size 0 0)
			(layers "F.Cu" "F.Mask" "F.Paste")
			(net "P12V_AUX")
		)
	)
	(footprint ""
		(layer "F.Cu")
		(at 114.800888 -163.217352)
		(property "Reference" "R4430"
			(at 0 0 0)
			(layer "F.SilkS")
			(hide yes)
			(effects
				(font
					(size 1.27 1.27)
				)
			)
		)
		(property "Value" ""
			(at 0 0 0)
			(layer "F.Fab")
			(effects
				(font
					(size 1.27 1.27)
				)
			)
		)
		(duplicate_pad_numbers_are_jumpers no)
		(fp_line
			(start -0.7874 -0.4064)
			(end 0.7874 -0.4064)
			(stroke
				(width 0.1524)
				(type default)
			)
			(layer "F.SilkS")
		)
		(fp_line
			(start -0.7874 0.4064)
			(end -0.7874 -0.4064)
			(stroke
				(width 0.1524)
				(type default)
			)
			(layer "F.SilkS")
		)
		(fp_line
			(start 0.7874 -0.4064)
			(end 0.7874 0.4064)
			(stroke
				(width 0.1524)
				(type default)
			)
			(layer "F.SilkS")
		)
		(fp_line
			(start 0.7874 0.4064)
			(end -0.7874 0.4064)
			(stroke
				(width 0.1524)
				(type default)
			)
			(layer "F.SilkS")
		)
		(fp_line
			(start -0.67945 -0.305054)
			(end -0.12065 -0.305054)
			(stroke
				(width 0.1)
				(type default)
			)
			(layer "F.Fab")
		)
		(fp_line
			(start -0.67945 0.3048)
			(end -0.67945 -0.305054)
			(stroke
				(width 0.1)
				(type default)
			)
			(layer "F.Fab")
		)
		(fp_line
			(start -0.12065 -0.305054)
			(end -0.12065 -0.2794)
			(stroke
				(width 0.1)
				(type default)
			)
			(layer "F.Fab")
		)
		(fp_line
			(start -0.12065 -0.2794)
			(end 0.12065 -0.2794)
			(stroke
				(width 0.1)
				(type default)
			)
			(layer "F.Fab")
		)
		(fp_line
			(start -0.12065 0.2794)
			(end -0.12065 0.3048)
			(stroke
				(width 0.1)
				(type default)
			)
			(layer "F.Fab")
		)
		(fp_line
			(start -0.12065 0.3048)
			(end -0.67945 0.3048)
			(stroke
				(width 0.1)
				(type default)
			)
			(layer "F.Fab")
		)
		(fp_line
			(start 0.120396 0.2794)
			(end -0.12065 0.2794)
			(stroke
				(width 0.1)
				(type default)
			)
			(layer "F.Fab")
		)
		(fp_line
			(start 0.120396 0.3048)
			(end 0.120396 0.2794)
			(stroke
				(width 0.1)
				(type default)
			)
			(layer "F.Fab")
		)
		(fp_line
			(start 0.12065 -0.3048)
			(end 0.67945 -0.3048)
			(stroke
				(width 0.1)
				(type default)
			)
			(layer "F.Fab")
		)
		(fp_line
			(start 0.12065 -0.2794)
			(end 0.12065 -0.3048)
			(stroke
				(width 0.1)
				(type default)
			)
			(layer "F.Fab")
		)
		(fp_line
			(start 0.67945 -0.3048)
			(end 0.67945 0.3048)
			(stroke
				(width 0.1)
				(type default)
			)
			(layer "F.Fab")
		)
		(fp_line
			(start 0.67945 0.3048)
			(end 0.120396 0.3048)
			(stroke
				(width 0.1)
				(type default)
			)
			(layer "F.Fab")
		)
		(pad "1" smd circle
			(at -0.40005 0)
			(size 0 0)
			(layers "F.Cu" "F.Mask" "F.Paste")
			(net "PWRGD_P3V3_AUX")
		)
		(pad "2" smd circle
			(at 0.40005 0)
			(size 0 0)
			(layers "F.Cu" "F.Mask" "F.Paste")
			(net "PWRGD_P3V3_AUX_R")
		)
	)
	(footprint ""
		(layer "F.Cu")
		(at 175.871886 -24.807418)
		(property "Reference" "R429"
			(at 0 0 0)
			(layer "F.SilkS")
			(hide yes)
			(effects
				(font
					(size 1.27 1.27)
				)
			)
		)
		(property "Value" ""
			(at 0 0 0)
			(layer "F.Fab")
			(effects
				(font
					(size 1.27 1.27)
				)
			)
		)
		(duplicate_pad_numbers_are_jumpers no)
		(fp_line
			(start -0.7874 -0.4064)
			(end 0.7874 -0.4064)
			(stroke
				(width 0.1524)
				(type default)
			)
			(layer "F.SilkS")
		)
		(fp_line
			(start -0.7874 0.4064)
			(end -0.7874 -0.4064)
			(stroke
				(width 0.1524)
				(type default)
			)
			(layer "F.SilkS")
		)
		(fp_line
			(start 0.7874 -0.4064)
			(end 0.7874 0.4064)
			(stroke
				(width 0.1524)
				(type default)
			)
			(layer "F.SilkS")
		)
		(fp_line
			(start 0.7874 0.4064)
			(end -0.7874 0.4064)
			(stroke
				(width 0.1524)
				(type default)
			)
			(layer "F.SilkS")
		)
		(fp_line
			(start -0.67945 -0.305054)
			(end -0.12065 -0.305054)
			(stroke
				(width 0.1)
				(type default)
			)
			(layer "F.Fab")
		)
		(fp_line
			(start -0.67945 0.3048)
			(end -0.67945 -0.305054)
			(stroke
				(width 0.1)
				(type default)
			)
			(layer "F.Fab")
		)
		(fp_line
			(start -0.12065 -0.305054)
			(end -0.12065 -0.2794)
			(stroke
				(width 0.1)
				(type default)
			)
			(layer "F.Fab")
		)
		(fp_line
			(start -0.12065 -0.2794)
			(end 0.12065 -0.2794)
			(stroke
				(width 0.1)
				(type default)
			)
			(layer "F.Fab")
		)
		(fp_line
			(start -0.12065 0.2794)
			(end -0.12065 0.3048)
			(stroke
				(width 0.1)
				(type default)
			)
			(layer "F.Fab")
		)
		(fp_line
			(start -0.12065 0.3048)
			(end -0.67945 0.3048)
			(stroke
				(width 0.1)
				(type default)
			)
			(layer "F.Fab")
		)
		(fp_line
			(start 0.120396 0.2794)
			(end -0.12065 0.2794)
			(stroke
				(width 0.1)
				(type default)
			)
			(layer "F.Fab")
		)
		(fp_line
			(start 0.120396 0.3048)
			(end 0.120396 0.2794)
			(stroke
				(width 0.1)
				(type default)
			)
			(layer "F.Fab")
		)
		(fp_line
			(start 0.12065 -0.3048)
			(end 0.67945 -0.3048)
			(stroke
				(width 0.1)
				(type default)
			)
			(layer "F.Fab")
		)
		(fp_line
			(start 0.12065 -0.2794)
			(end 0.12065 -0.3048)
			(stroke
				(width 0.1)
				(type default)
			)
			(layer "F.Fab")
		)
		(fp_line
			(start 0.67945 -0.3048)
			(end 0.67945 0.3048)
			(stroke
				(width 0.1)
				(type default)
			)
			(layer "F.Fab")
		)
		(fp_line
			(start 0.67945 0.3048)
			(end 0.120396 0.3048)
			(stroke
				(width 0.1)
				(type default)
			)
			(layer "F.Fab")
		)
		(pad "1" smd circle
			(at -0.40005 0)
			(size 0 0)
			(layers "F.Cu" "F.Mask" "F.Paste")
			(net "P3V3_SSD6")
		)
		(pad "2" smd circle
			(at 0.40005 0)
			(size 0 0)
			(layers "F.Cu" "F.Mask" "F.Paste")
			(net "PU_CLKREQ6")
		)
	)
	(footprint ""
		(layer "F.Cu")
		(at 26.439368 -343.952322 90)
		(property "Reference" "C2157"
			(at 0 0 90)
			(layer "F.SilkS")
			(hide yes)
			(effects
				(font
					(size 1.27 1.27)
				)
			)
		)
		(property "Value" ""
			(at 0 0 90)
			(layer "F.Fab")
			(effects
				(font
					(size 1.27 1.27)
				)
			)
		)
		(duplicate_pad_numbers_are_jumpers no)
		(fp_line
			(start 0.299974 -0.150114)
			(end 0.299974 0.150114)
			(stroke
				(width 0.1)
				(type default)
			)
			(layer "F.Fab")
		)
		(fp_line
			(start -0.299974 -0.150114)
			(end 0.299974 -0.150114)
			(stroke
				(width 0.1)
				(type default)
			)
			(layer "F.Fab")
		)
		(fp_line
			(start 0.299974 0.150114)
			(end -0.299974 0.150114)
			(stroke
				(width 0.1)
				(type default)
			)
			(layer "F.Fab")
		)
		(fp_line
			(start -0.299974 0.150114)
			(end -0.299974 -0.150114)
			(stroke
				(width 0.1)
				(type default)
			)
			(layer "F.Fab")
		)
		(pad "1" smd rect
			(at -0.2667 0 90)
			(size 0.3048 0.381)
			(layers "F.Cu" "F.Mask" "F.Paste")
			(net "P5E_PEX0_STN4_TX_DN<77>")
		)
		(pad "2" smd rect
			(at 0.2667 0 90)
			(size 0.3048 0.381)
			(layers "F.Cu" "F.Mask" "F.Paste")
			(net "P5E_PEX0_STN4_TX_C_DN<77>")
		)
	)
	(footprint ""
		(layer "F.Cu")
		(at 385.354068 -147.969224 90)
		(property "Reference" "C936"
			(at 0 0 90)
			(layer "F.SilkS")
			(hide yes)
			(effects
				(font
					(size 1.27 1.27)
				)
			)
		)
		(property "Value" ""
			(at 0 0 90)
			(layer "F.Fab")
			(effects
				(font
					(size 1.27 1.27)
				)
			)
		)
		(duplicate_pad_numbers_are_jumpers no)
		(fp_line
			(start 1.524 -0.762)
			(end 1.524 0.762)
			(stroke
				(width 0.1524)
				(type default)
			)
			(layer "F.SilkS")
		)
		(fp_line
			(start -1.524 -0.762)
			(end 1.524 -0.762)
			(stroke
				(width 0.1524)
				(type default)
			)
			(layer "F.SilkS")
		)
		(fp_line
			(start 1.524 0.762)
			(end -1.524 0.762)
			(stroke
				(width 0.1524)
				(type default)
			)
			(layer "F.SilkS")
		)
		(fp_line
			(start -1.524 0.762)
			(end -1.524 -0.762)
			(stroke
				(width 0.1524)
				(type default)
			)
			(layer "F.SilkS")
		)
		(fp_line
			(start 1.1049 -0.724916)
			(end -1.1049 -0.724916)
			(stroke
				(width 0.1)
				(type default)
			)
			(layer "F.Fab")
		)
		(fp_line
			(start -1.1049 -0.724916)
			(end -1.1049 0.724916)
			(stroke
				(width 0.1)
				(type default)
			)
			(layer "F.Fab")
		)
		(fp_line
			(start 1.1049 0.724916)
			(end 1.1049 -0.724916)
			(stroke
				(width 0.1)
				(type default)
			)
			(layer "F.Fab")
		)
		(fp_line
			(start -1.1049 0.724916)
			(end 1.1049 0.724916)
			(stroke
				(width 0.1)
				(type default)
			)
			(layer "F.Fab")
		)
		(pad "1" smd rect
			(at -0.889 0 270)
			(size 1.016 1.27)
			(layers "F.Cu" "F.Mask" "F.Paste")
			(net "P12V_NIC6")
		)
		(pad "2" smd rect
			(at 0.889 0 270)
			(size 1.016 1.27)
			(layers "F.Cu" "F.Mask" "F.Paste")
			(net "GND")
		)
	)
	(footprint ""
		(layer "F.Cu")
		(at 325.265542 -304.036476 90)
		(property "Reference" "R4182"
			(at 0 0 90)
			(layer "F.SilkS")
			(hide yes)
			(effects
				(font
					(size 1.27 1.27)
				)
			)
		)
		(property "Value" ""
			(at 0 0 90)
			(layer "F.Fab")
			(effects
				(font
					(size 1.27 1.27)
				)
			)
		)
		(duplicate_pad_numbers_are_jumpers no)
		(fp_line
			(start 0.7874 -0.4064)
			(end 0.7874 0.4064)
			(stroke
				(width 0.1524)
				(type default)
			)
			(layer "F.SilkS")
		)
		(fp_line
			(start -0.7874 -0.4064)
			(end 0.7874 -0.4064)
			(stroke
				(width 0.1524)
				(type default)
			)
			(layer "F.SilkS")
		)
		(fp_line
			(start 0.7874 0.4064)
			(end -0.7874 0.4064)
			(stroke
				(width 0.1524)
				(type default)
			)
			(layer "F.SilkS")
		)
		(fp_line
			(start -0.7874 0.4064)
			(end -0.7874 -0.4064)
			(stroke
				(width 0.1524)
				(type default)
			)
			(layer "F.SilkS")
		)
		(fp_line
			(start -0.12065 -0.305054)
			(end -0.12065 -0.2794)
			(stroke
				(width 0.1)
				(type default)
			)
			(layer "F.Fab")
		)
		(fp_line
			(start -0.67945 -0.305054)
			(end -0.12065 -0.305054)
			(stroke
				(width 0.1)
				(type default)
			)
			(layer "F.Fab")
		)
		(fp_line
			(start 0.67945 -0.3048)
			(end 0.67945 0.3048)
			(stroke
				(width 0.1)
				(type default)
			)
			(layer "F.Fab")
		)
		(fp_line
			(start 0.12065 -0.3048)
			(end 0.67945 -0.3048)
			(stroke
				(width 0.1)
				(type default)
			)
			(layer "F.Fab")
		)
		(fp_line
			(start 0.12065 -0.2794)
			(end 0.12065 -0.3048)
			(stroke
				(width 0.1)
				(type default)
			)
			(layer "F.Fab")
		)
		(fp_line
			(start -0.12065 -0.2794)
			(end 0.12065 -0.2794)
			(stroke
				(width 0.1)
				(type default)
			)
			(layer "F.Fab")
		)
		(fp_line
			(start 0.120396 0.2794)
			(end -0.12065 0.2794)
			(stroke
				(width 0.1)
				(type default)
			)
			(layer "F.Fab")
		)
		(fp_line
			(start -0.12065 0.2794)
			(end -0.12065 0.3048)
			(stroke
				(width 0.1)
				(type default)
			)
			(layer "F.Fab")
		)
		(fp_line
			(start 0.67945 0.3048)
			(end 0.120396 0.3048)
			(stroke
				(width 0.1)
				(type default)
			)
			(layer "F.Fab")
		)
		(fp_line
			(start 0.120396 0.3048)
			(end 0.120396 0.2794)
			(stroke
				(width 0.1)
				(type default)
			)
			(layer "F.Fab")
		)
		(fp_line
			(start -0.12065 0.3048)
			(end -0.67945 0.3048)
			(stroke
				(width 0.1)
				(type default)
			)
			(layer "F.Fab")
		)
		(fp_line
			(start -0.67945 0.3048)
			(end -0.67945 -0.305054)
			(stroke
				(width 0.1)
				(type default)
			)
			(layer "F.Fab")
		)
		(pad "1" smd circle
			(at -0.40005 0 90)
			(size 0 0)
			(layers "F.Cu" "F.Mask" "F.Paste")
			(net "GND")
		)
		(pad "2" smd circle
			(at 0.40005 0 90)
			(size 0 0)
			(layers "F.Cu" "F.Mask" "F.Paste")
			(net "PEX2_EXT_GPIO_LATCH_N")
		)
	)
	(footprint ""
		(layer "F.Cu")
		(at 111.313976 -271.703546 -90)
		(property "Reference" "PC64"
			(at 0 0 270)
			(layer "F.SilkS")
			(hide yes)
			(effects
				(font
					(size 1.27 1.27)
				)
			)
		)
		(property "Value" ""
			(at 0 0 270)
			(layer "F.Fab")
			(effects
				(font
					(size 1.27 1.27)
				)
			)
		)
		(duplicate_pad_numbers_are_jumpers no)
		(fp_line
			(start -2.146046 3.400044)
			(end -3.400044 2.146046)
			(stroke
				(width 0.1524)
				(type default)
			)
			(layer "F.SilkS")
		)
		(fp_line
			(start 3.400044 3.400044)
			(end -2.146046 3.400044)
			(stroke
				(width 0.1524)
				(type default)
			)
			(layer "F.SilkS")
		)
		(fp_line
			(start -3.400044 2.146046)
			(end -3.400044 0.9398)
			(stroke
				(width 0.1524)
				(type default)
			)
			(layer "F.SilkS")
		)
		(fp_line
			(start 3.400044 0.9398)
			(end 3.400044 3.400044)
			(stroke
				(width 0.1524)
				(type default)
			)
			(layer "F.SilkS")
		)
		(fp_line
			(start 3.400044 -0.9398)
			(end 3.400044 -3.400044)
			(stroke
				(width 0.1524)
				(type default)
			)
			(layer "F.SilkS")
		)
		(fp_line
			(start -3.400044 -2.146046)
			(end -3.400044 -0.9398)
			(stroke
				(width 0.1524)
				(type default)
			)
			(layer "F.SilkS")
		)
		(fp_line
			(start -2.146046 -3.400044)
			(end -3.400044 -2.146046)
			(stroke
				(width 0.1524)
				(type default)
			)
			(layer "F.SilkS")
		)
		(fp_line
			(start 3.400044 -3.400044)
			(end -2.146046 -3.400044)
			(stroke
				(width 0.1524)
				(type default)
			)
			(layer "F.SilkS")
		)
		(fp_line
			(start -3.400044 3.400044)
			(end 3.400044 3.400044)
			(stroke
				(width 0.1)
				(type default)
			)
			(layer "F.Fab")
		)
		(fp_line
			(start 3.400044 3.400044)
			(end 3.400044 -3.400044)
			(stroke
				(width 0.1)
				(type default)
			)
			(layer "F.Fab")
		)
		(fp_line
			(start -3.400044 -3.400044)
			(end -3.400044 3.400044)
			(stroke
				(width 0.1)
				(type default)
			)
			(layer "F.Fab")
		)
		(fp_line
			(start 3.400044 -3.400044)
			(end -3.400044 -3.400044)
			(stroke
				(width 0.1)
				(type default)
			)
			(layer "F.Fab")
		)
		(pad "1" smd rect
			(at -2.70002 0 180)
			(size 1.6002 3.5052)
			(layers "F.Cu" "F.Mask" "F.Paste")
			(net "SW_P12V_P0V8_PEX0_FLT")
		)
		(pad "2" smd rect
			(at 2.70002 0 180)
			(size 1.6002 3.5052)
			(layers "F.Cu" "F.Mask" "F.Paste")
			(net "GND")
		)
	)
	(footprint ""
		(layer "F.Cu")
		(at 392.226546 -25.432004 -90)
		(property "Reference" "C978"
			(at 0 0 270)
			(layer "F.SilkS")
			(hide yes)
			(effects
				(font
					(size 1.27 1.27)
				)
			)
		)
		(property "Value" ""
			(at 0 0 270)
			(layer "F.Fab")
			(effects
				(font
					(size 1.27 1.27)
				)
			)
		)
		(duplicate_pad_numbers_are_jumpers no)
		(fp_line
			(start -0.7874 0.4064)
			(end -0.7874 -0.4064)
			(stroke
				(width 0.1524)
				(type default)
			)
			(layer "F.SilkS")
		)
		(fp_line
			(start 0.7874 0.4064)
			(end -0.7874 0.4064)
			(stroke
				(width 0.1524)
				(type default)
			)
			(layer "F.SilkS")
		)
		(fp_line
			(start -0.7874 -0.4064)
			(end 0.7874 -0.4064)
			(stroke
				(width 0.1524)
				(type default)
			)
			(layer "F.SilkS")
		)
		(fp_line
			(start 0.7874 -0.4064)
			(end 0.7874 0.4064)
			(stroke
				(width 0.1524)
				(type default)
			)
			(layer "F.SilkS")
		)
		(fp_line
			(start -0.67945 0.3048)
			(end -0.67945 -0.305054)
			(stroke
				(width 0.1)
				(type default)
			)
			(layer "F.Fab")
		)
		(fp_line
			(start -0.12065 0.3048)
			(end -0.67945 0.3048)
			(stroke
				(width 0.1)
				(type default)
			)
			(layer "F.Fab")
		)
		(fp_line
			(start 0.120396 0.3048)
			(end 0.120396 0.2794)
			(stroke
				(width 0.1)
				(type default)
			)
			(layer "F.Fab")
		)
		(fp_line
			(start 0.67945 0.3048)
			(end 0.120396 0.3048)
			(stroke
				(width 0.1)
				(type default)
			)
			(layer "F.Fab")
		)
		(fp_line
			(start -0.12065 0.2794)
			(end -0.12065 0.3048)
			(stroke
				(width 0.1)
				(type default)
			)
			(layer "F.Fab")
		)
		(fp_line
			(start 0.120396 0.2794)
			(end -0.12065 0.2794)
			(stroke
				(width 0.1)
				(type default)
			)
			(layer "F.Fab")
		)
		(fp_line
			(start -0.12065 -0.2794)
			(end 0.12065 -0.2794)
			(stroke
				(width 0.1)
				(type default)
			)
			(layer "F.Fab")
		)
		(fp_line
			(start 0.12065 -0.2794)
			(end 0.12065 -0.3048)
			(stroke
				(width 0.1)
				(type default)
			)
			(layer "F.Fab")
		)
		(fp_line
			(start 0.12065 -0.3048)
			(end 0.67945 -0.3048)
			(stroke
				(width 0.1)
				(type default)
			)
			(layer "F.Fab")
		)
		(fp_line
			(start 0.67945 -0.3048)
			(end 0.67945 0.3048)
			(stroke
				(width 0.1)
				(type default)
			)
			(layer "F.Fab")
		)
		(fp_line
			(start -0.67945 -0.305054)
			(end -0.12065 -0.305054)
			(stroke
				(width 0.1)
				(type default)
			)
			(layer "F.Fab")
		)
		(fp_line
			(start -0.12065 -0.305054)
			(end -0.12065 -0.2794)
			(stroke
				(width 0.1)
				(type default)
			)
			(layer "F.Fab")
		)
		(pad "1" smd circle
			(at -0.40005 0 270)
			(size 0 0)
			(layers "F.Cu" "F.Mask" "F.Paste")
			(net "GND")
		)
		(pad "2" smd circle
			(at 0.40005 0 270)
			(size 0 0)
			(layers "F.Cu" "F.Mask" "F.Paste")
			(net "P3V3_SSD13")
		)
	)
	(footprint ""
		(layer "F.Cu")
		(at 380.770384 -250.070874 -90)
		(property "Reference" "R1413"
			(at 0 0 270)
			(layer "F.SilkS")
			(hide yes)
			(effects
				(font
					(size 1.27 1.27)
				)
			)
		)
		(property "Value" ""
			(at 0 0 270)
			(layer "F.Fab")
			(effects
				(font
					(size 1.27 1.27)
				)
			)
		)
		(duplicate_pad_numbers_are_jumpers no)
		(fp_line
			(start -0.7874 0.4064)
			(end -0.7874 -0.4064)
			(stroke
				(width 0.1524)
				(type default)
			)
			(layer "F.SilkS")
		)
		(fp_line
			(start 0.7874 0.4064)
			(end -0.7874 0.4064)
			(stroke
				(width 0.1524)
				(type default)
			)
			(layer "F.SilkS")
		)
		(fp_line
			(start -0.7874 -0.4064)
			(end 0.7874 -0.4064)
			(stroke
				(width 0.1524)
				(type default)
			)
			(layer "F.SilkS")
		)
		(fp_line
			(start 0.7874 -0.4064)
			(end 0.7874 0.4064)
			(stroke
				(width 0.1524)
				(type default)
			)
			(layer "F.SilkS")
		)
		(fp_line
			(start -0.67945 0.3048)
			(end -0.67945 -0.305054)
			(stroke
				(width 0.1)
				(type default)
			)
			(layer "F.Fab")
		)
		(fp_line
			(start -0.12065 0.3048)
			(end -0.67945 0.3048)
			(stroke
				(width 0.1)
				(type default)
			)
			(layer "F.Fab")
		)
		(fp_line
			(start 0.120396 0.3048)
			(end 0.120396 0.2794)
			(stroke
				(width 0.1)
				(type default)
			)
			(layer "F.Fab")
		)
		(fp_line
			(start 0.67945 0.3048)
			(end 0.120396 0.3048)
			(stroke
				(width 0.1)
				(type default)
			)
			(layer "F.Fab")
		)
		(fp_line
			(start -0.12065 0.2794)
			(end -0.12065 0.3048)
			(stroke
				(width 0.1)
				(type default)
			)
			(layer "F.Fab")
		)
		(fp_line
			(start 0.120396 0.2794)
			(end -0.12065 0.2794)
			(stroke
				(width 0.1)
				(type default)
			)
			(layer "F.Fab")
		)
		(fp_line
			(start -0.12065 -0.2794)
			(end 0.12065 -0.2794)
			(stroke
				(width 0.1)
				(type default)
			)
			(layer "F.Fab")
		)
		(fp_line
			(start 0.12065 -0.2794)
			(end 0.12065 -0.3048)
			(stroke
				(width 0.1)
				(type default)
			)
			(layer "F.Fab")
		)
		(fp_line
			(start 0.12065 -0.3048)
			(end 0.67945 -0.3048)
			(stroke
				(width 0.1)
				(type default)
			)
			(layer "F.Fab")
		)
		(fp_line
			(start 0.67945 -0.3048)
			(end 0.67945 0.3048)
			(stroke
				(width 0.1)
				(type default)
			)
			(layer "F.Fab")
		)
		(fp_line
			(start -0.67945 -0.305054)
			(end -0.12065 -0.305054)
			(stroke
				(width 0.1)
				(type default)
			)
			(layer "F.Fab")
		)
		(fp_line
			(start -0.12065 -0.305054)
			(end -0.12065 -0.2794)
			(stroke
				(width 0.1)
				(type default)
			)
			(layer "F.Fab")
		)
		(pad "1" smd circle
			(at -0.40005 0 270)
			(size 0 0)
			(layers "F.Cu" "F.Mask" "F.Paste")
			(net "PEX3_MODE_SEL8")
		)
		(pad "2" smd circle
			(at 0.40005 0 270)
			(size 0 0)
			(layers "F.Cu" "F.Mask" "F.Paste")
			(net "P1V8_PEX")
		)
	)
	(footprint ""
		(layer "F.Cu")
		(at 375.512838 -9.713976 180)
		(property "Reference" "C3871"
			(at 0 0 180)
			(layer "F.SilkS")
			(hide yes)
			(effects
				(font
					(size 1.27 1.27)
				)
			)
		)
		(property "Value" ""
			(at 0 0 180)
			(layer "F.Fab")
			(effects
				(font
					(size 1.27 1.27)
				)
			)
		)
		(duplicate_pad_numbers_are_jumpers no)
		(fp_line
			(start 0.7874 0.4064)
			(end -0.7874 0.4064)
			(stroke
				(width 0.1524)
				(type default)
			)
			(layer "F.SilkS")
		)
		(fp_line
			(start 0.7874 -0.4064)
			(end 0.7874 0.4064)
			(stroke
				(width 0.1524)
				(type default)
			)
			(layer "F.SilkS")
		)
		(fp_line
			(start -0.7874 0.4064)
			(end -0.7874 -0.4064)
			(stroke
				(width 0.1524)
				(type default)
			)
			(layer "F.SilkS")
		)
		(fp_line
			(start -0.7874 -0.4064)
			(end 0.7874 -0.4064)
			(stroke
				(width 0.1524)
				(type default)
			)
			(layer "F.SilkS")
		)
		(fp_line
			(start 0.67945 0.3048)
			(end 0.120396 0.3048)
			(stroke
				(width 0.1)
				(type default)
			)
			(layer "F.Fab")
		)
		(fp_line
			(start 0.67945 -0.3048)
			(end 0.67945 0.3048)
			(stroke
				(width 0.1)
				(type default)
			)
			(layer "F.Fab")
		)
		(fp_line
			(start 0.12065 -0.2794)
			(end 0.12065 -0.3048)
			(stroke
				(width 0.1)
				(type default)
			)
			(layer "F.Fab")
		)
		(fp_line
			(start 0.12065 -0.3048)
			(end 0.67945 -0.3048)
			(stroke
				(width 0.1)
				(type default)
			)
			(layer "F.Fab")
		)
		(fp_line
			(start 0.120396 0.3048)
			(end 0.120396 0.2794)
			(stroke
				(width 0.1)
				(type default)
			)
			(layer "F.Fab")
		)
		(fp_line
			(start 0.120396 0.2794)
			(end -0.12065 0.2794)
			(stroke
				(width 0.1)
				(type default)
			)
			(layer "F.Fab")
		)
		(fp_line
			(start -0.12065 0.3048)
			(end -0.67945 0.3048)
			(stroke
				(width 0.1)
				(type default)
			)
			(layer "F.Fab")
		)
		(fp_line
			(start -0.12065 0.2794)
			(end -0.12065 0.3048)
			(stroke
				(width 0.1)
				(type default)
			)
			(layer "F.Fab")
		)
		(fp_line
			(start -0.12065 -0.2794)
			(end 0.12065 -0.2794)
			(stroke
				(width 0.1)
				(type default)
			)
			(layer "F.Fab")
		)
		(fp_line
			(start -0.12065 -0.305054)
			(end -0.12065 -0.2794)
			(stroke
				(width 0.1)
				(type default)
			)
			(layer "F.Fab")
		)
		(fp_line
			(start -0.67945 0.3048)
			(end -0.67945 -0.305054)
			(stroke
				(width 0.1)
				(type default)
			)
			(layer "F.Fab")
		)
		(fp_line
			(start -0.67945 -0.305054)
			(end -0.12065 -0.305054)
			(stroke
				(width 0.1)
				(type default)
			)
			(layer "F.Fab")
		)
		(pad "1" smd circle
			(at -0.40005 0 180)
			(size 0 0)
			(layers "F.Cu" "F.Mask" "F.Paste")
			(net "P3V3_AUX")
		)
		(pad "2" smd circle
			(at 0.40005 0 180)
			(size 0 0)
			(layers "F.Cu" "F.Mask" "F.Paste")
			(net "GND")
		)
	)
	(footprint ""
		(layer "F.Cu")
		(at 405.88946 -63.56223)
		(property "Reference" "Q210"
			(at 0.00254 -1.8669 0)
			(unlocked yes)
			(layer "F.SilkS")
			(effects
				(font
					(size 0.7874 0.5842)
					(thickness 0.1524)
				)
			)
		)
		(property "Value" ""
			(at 0 0 0)
			(layer "F.Fab")
			(effects
				(font
					(size 1.27 1.27)
				)
			)
		)
		(duplicate_pad_numbers_are_jumpers no)
		(fp_line
			(start -1.376172 -1.199896)
			(end -0.508 -1.199896)
			(stroke
				(width 0.1524)
				(type default)
			)
			(layer "F.SilkS")
		)
		(fp_line
			(start -1.376172 1.199896)
			(end -1.376172 -1.199896)
			(stroke
				(width 0.1524)
				(type default)
			)
			(layer "F.SilkS")
		)
		(fp_line
			(start -0.508 -1.199896)
			(end 0 -0.762)
			(stroke
				(width 0.1524)
				(type default)
			)
			(layer "F.SilkS")
		)
		(fp_line
			(start 0 -0.762)
			(end 0.508 -1.199896)
			(stroke
				(width 0.1524)
				(type default)
			)
			(layer "F.SilkS")
		)
		(fp_line
			(start 0.508 -1.199896)
			(end 1.376172 -1.199896)
			(stroke
				(width 0.1524)
				(type default)
			)
			(layer "F.SilkS")
		)
		(fp_line
			(start 1.376172 -1.199896)
			(end 1.376172 1.199896)
			(stroke
				(width 0.1524)
				(type default)
			)
			(layer "F.SilkS")
		)
		(fp_line
			(start 1.376172 1.199896)
			(end -1.376172 1.199896)
			(stroke
				(width 0.1524)
				(type default)
			)
			(layer "F.SilkS")
		)
		(fp_poly
			(pts
				(xy -1.478788 -0.890778) (xy -1.748028 -1.699006) (xy -2.287016 -1.160272)
			)
			(stroke
				(width 0)
				(type default)
			)
			(fill yes)
			(layer "F.SilkS")
		)
		(fp_line
			(start -0.674878 -1.100074)
			(end 0.674878 -1.100074)
			(stroke
				(width 0.1)
				(type default)
			)
			(layer "F.Fab")
		)
		(fp_line
			(start -0.674878 1.100074)
			(end -0.674878 -1.100074)
			(stroke
				(width 0.1)
				(type default)
			)
			(layer "F.Fab")
		)
		(fp_line
			(start 0.674878 -1.100074)
			(end 0.674878 1.100074)
			(stroke
				(width 0.1)
				(type default)
			)
			(layer "F.Fab")
		)
		(fp_line
			(start 0.674878 1.100074)
			(end -0.674878 1.100074)
			(stroke
				(width 0.1)
				(type default)
			)
			(layer "F.Fab")
		)
		(fp_poly
			(pts
				(xy -1.4605 -0.7493) (xy -2.2225 -1.1303) (xy -2.2225 -0.3683)
			)
			(stroke
				(width 0)
				(type default)
			)
			(fill yes)
			(layer "F.Fab")
		)
		(pad "1" smd rect
			(at -0.899922 -0.750062 270)
			(size 0.6096 0.6096)
			(layers "F.Cu" "F.Mask" "F.Paste")
			(net "GND")
		)
		(pad "2" smd rect
			(at -0.899922 0 270)
			(size 0.4064 0.6096)
			(layers "F.Cu" "F.Mask" "F.Paste")
			(net "P12V_SSD14_PG_G1")
		)
		(pad "3" smd rect
			(at -0.899922 0.750062 270)
			(size 0.6096 0.6096)
			(layers "F.Cu" "F.Mask" "F.Paste")
			(net "PWRGD_P12V_SSD14_D")
		)
		(pad "4" smd rect
			(at 0.899922 0.750062 270)
			(size 0.6096 0.6096)
			(layers "F.Cu" "F.Mask" "F.Paste")
			(net "GND")
		)
		(pad "5" smd rect
			(at 0.899922 0 270)
			(size 0.4064 0.6096)
			(layers "F.Cu" "F.Mask" "F.Paste")
			(net "P12V_SSD14_PG_G2")
		)
		(pad "6" smd rect
			(at 0.899922 -0.750062 270)
			(size 0.6096 0.6096)
			(layers "F.Cu" "F.Mask" "F.Paste")
			(net "P12V_SSD14_PG_G2")
		)
	)
	(footprint ""
		(layer "F.Cu")
		(at 404.673816 -27.006296 -90)
		(property "Reference" "PC970"
			(at 0 0 270)
			(layer "F.SilkS")
			(hide yes)
			(effects
				(font
					(size 1.27 1.27)
				)
			)
		)
		(property "Value" ""
			(at 0 0 270)
			(layer "F.Fab")
			(effects
				(font
					(size 1.27 1.27)
				)
			)
		)
		(duplicate_pad_numbers_are_jumpers no)
		(fp_line
			(start -0.7874 0.4064)
			(end -0.7874 -0.4064)
			(stroke
				(width 0.1524)
				(type default)
			)
			(layer "F.SilkS")
		)
		(fp_line
			(start 0.7874 0.4064)
			(end -0.7874 0.4064)
			(stroke
				(width 0.1524)
				(type default)
			)
			(layer "F.SilkS")
		)
		(fp_line
			(start -0.7874 -0.4064)
			(end 0.7874 -0.4064)
			(stroke
				(width 0.1524)
				(type default)
			)
			(layer "F.SilkS")
		)
		(fp_line
			(start 0.7874 -0.4064)
			(end 0.7874 0.4064)
			(stroke
				(width 0.1524)
				(type default)
			)
			(layer "F.SilkS")
		)
		(fp_line
			(start -0.67945 0.3048)
			(end -0.67945 -0.305054)
			(stroke
				(width 0.1)
				(type default)
			)
			(layer "F.Fab")
		)
		(fp_line
			(start -0.12065 0.3048)
			(end -0.67945 0.3048)
			(stroke
				(width 0.1)
				(type default)
			)
			(layer "F.Fab")
		)
		(fp_line
			(start 0.120396 0.3048)
			(end 0.120396 0.2794)
			(stroke
				(width 0.1)
				(type default)
			)
			(layer "F.Fab")
		)
		(fp_line
			(start 0.67945 0.3048)
			(end 0.120396 0.3048)
			(stroke
				(width 0.1)
				(type default)
			)
			(layer "F.Fab")
		)
		(fp_line
			(start -0.12065 0.2794)
			(end -0.12065 0.3048)
			(stroke
				(width 0.1)
				(type default)
			)
			(layer "F.Fab")
		)
		(fp_line
			(start 0.120396 0.2794)
			(end -0.12065 0.2794)
			(stroke
				(width 0.1)
				(type default)
			)
			(layer "F.Fab")
		)
		(fp_line
			(start -0.12065 -0.2794)
			(end 0.12065 -0.2794)
			(stroke
				(width 0.1)
				(type default)
			)
			(layer "F.Fab")
		)
		(fp_line
			(start 0.12065 -0.2794)
			(end 0.12065 -0.3048)
			(stroke
				(width 0.1)
				(type default)
			)
			(layer "F.Fab")
		)
		(fp_line
			(start 0.12065 -0.3048)
			(end 0.67945 -0.3048)
			(stroke
				(width 0.1)
				(type default)
			)
			(layer "F.Fab")
		)
		(fp_line
			(start 0.67945 -0.3048)
			(end 0.67945 0.3048)
			(stroke
				(width 0.1)
				(type default)
			)
			(layer "F.Fab")
		)
		(fp_line
			(start -0.67945 -0.305054)
			(end -0.12065 -0.305054)
			(stroke
				(width 0.1)
				(type default)
			)
			(layer "F.Fab")
		)
		(fp_line
			(start -0.12065 -0.305054)
			(end -0.12065 -0.2794)
			(stroke
				(width 0.1)
				(type default)
			)
			(layer "F.Fab")
		)
		(pad "1" smd circle
			(at -0.40005 0 270)
			(size 0 0)
			(layers "F.Cu" "F.Mask" "F.Paste")
			(net "P3V3_SSD14_CO_MODE")
		)
		(pad "2" smd circle
			(at 0.40005 0 270)
			(size 0 0)
			(layers "F.Cu" "F.Mask" "F.Paste")
			(net "GND")
		)
	)
	(footprint ""
		(layer "F.Cu")
		(at 151.618442 -252.356874 -90)
		(property "Reference" "R1301"
			(at 0 0 270)
			(layer "F.SilkS")
			(hide yes)
			(effects
				(font
					(size 1.27 1.27)
				)
			)
		)
		(property "Value" ""
			(at 0 0 270)
			(layer "F.Fab")
			(effects
				(font
					(size 1.27 1.27)
				)
			)
		)
		(duplicate_pad_numbers_are_jumpers no)
		(fp_line
			(start -0.7874 0.4064)
			(end -0.7874 -0.4064)
			(stroke
				(width 0.1524)
				(type default)
			)
			(layer "F.SilkS")
		)
		(fp_line
			(start 0.7874 0.4064)
			(end -0.7874 0.4064)
			(stroke
				(width 0.1524)
				(type default)
			)
			(layer "F.SilkS")
		)
		(fp_line
			(start -0.7874 -0.4064)
			(end 0.7874 -0.4064)
			(stroke
				(width 0.1524)
				(type default)
			)
			(layer "F.SilkS")
		)
		(fp_line
			(start 0.7874 -0.4064)
			(end 0.7874 0.4064)
			(stroke
				(width 0.1524)
				(type default)
			)
			(layer "F.SilkS")
		)
		(fp_line
			(start -0.67945 0.3048)
			(end -0.67945 -0.305054)
			(stroke
				(width 0.1)
				(type default)
			)
			(layer "F.Fab")
		)
		(fp_line
			(start -0.12065 0.3048)
			(end -0.67945 0.3048)
			(stroke
				(width 0.1)
				(type default)
			)
			(layer "F.Fab")
		)
		(fp_line
			(start 0.120396 0.3048)
			(end 0.120396 0.2794)
			(stroke
				(width 0.1)
				(type default)
			)
			(layer "F.Fab")
		)
		(fp_line
			(start 0.67945 0.3048)
			(end 0.120396 0.3048)
			(stroke
				(width 0.1)
				(type default)
			)
			(layer "F.Fab")
		)
		(fp_line
			(start -0.12065 0.2794)
			(end -0.12065 0.3048)
			(stroke
				(width 0.1)
				(type default)
			)
			(layer "F.Fab")
		)
		(fp_line
			(start 0.120396 0.2794)
			(end -0.12065 0.2794)
			(stroke
				(width 0.1)
				(type default)
			)
			(layer "F.Fab")
		)
		(fp_line
			(start -0.12065 -0.2794)
			(end 0.12065 -0.2794)
			(stroke
				(width 0.1)
				(type default)
			)
			(layer "F.Fab")
		)
		(fp_line
			(start 0.12065 -0.2794)
			(end 0.12065 -0.3048)
			(stroke
				(width 0.1)
				(type default)
			)
			(layer "F.Fab")
		)
		(fp_line
			(start 0.12065 -0.3048)
			(end 0.67945 -0.3048)
			(stroke
				(width 0.1)
				(type default)
			)
			(layer "F.Fab")
		)
		(fp_line
			(start 0.67945 -0.3048)
			(end 0.67945 0.3048)
			(stroke
				(width 0.1)
				(type default)
			)
			(layer "F.Fab")
		)
		(fp_line
			(start -0.67945 -0.305054)
			(end -0.12065 -0.305054)
			(stroke
				(width 0.1)
				(type default)
			)
			(layer "F.Fab")
		)
		(fp_line
			(start -0.12065 -0.305054)
			(end -0.12065 -0.2794)
			(stroke
				(width 0.1)
				(type default)
			)
			(layer "F.Fab")
		)
		(pad "1" smd circle
			(at -0.40005 0 270)
			(size 0 0)
			(layers "F.Cu" "F.Mask" "F.Paste")
			(net "GND")
		)
		(pad "2" smd circle
			(at 0.40005 0 270)
			(size 0 0)
			(layers "F.Cu" "F.Mask" "F.Paste")
			(net "PEX1_MODE_SEL12")
		)
	)
	(footprint ""
		(layer "F.Cu")
		(at 135.642096 -198.091806 180)
		(property "Reference" "C2597"
			(at 0 0 180)
			(layer "F.SilkS")
			(hide yes)
			(effects
				(font
					(size 1.27 1.27)
				)
			)
		)
		(property "Value" ""
			(at 0 0 180)
			(layer "F.Fab")
			(effects
				(font
					(size 1.27 1.27)
				)
			)
		)
		(duplicate_pad_numbers_are_jumpers no)
		(fp_line
			(start 0.7874 0.4064)
			(end -0.7874 0.4064)
			(stroke
				(width 0.1524)
				(type default)
			)
			(layer "F.SilkS")
		)
		(fp_line
			(start 0.7874 -0.4064)
			(end 0.7874 0.4064)
			(stroke
				(width 0.1524)
				(type default)
			)
			(layer "F.SilkS")
		)
		(fp_line
			(start -0.7874 0.4064)
			(end -0.7874 -0.4064)
			(stroke
				(width 0.1524)
				(type default)
			)
			(layer "F.SilkS")
		)
		(fp_line
			(start -0.7874 -0.4064)
			(end 0.7874 -0.4064)
			(stroke
				(width 0.1524)
				(type default)
			)
			(layer "F.SilkS")
		)
		(fp_line
			(start 0.67945 0.3048)
			(end 0.120396 0.3048)
			(stroke
				(width 0.1)
				(type default)
			)
			(layer "F.Fab")
		)
		(fp_line
			(start 0.67945 -0.3048)
			(end 0.67945 0.3048)
			(stroke
				(width 0.1)
				(type default)
			)
			(layer "F.Fab")
		)
		(fp_line
			(start 0.12065 -0.2794)
			(end 0.12065 -0.3048)
			(stroke
				(width 0.1)
				(type default)
			)
			(layer "F.Fab")
		)
		(fp_line
			(start 0.12065 -0.3048)
			(end 0.67945 -0.3048)
			(stroke
				(width 0.1)
				(type default)
			)
			(layer "F.Fab")
		)
		(fp_line
			(start 0.120396 0.3048)
			(end 0.120396 0.2794)
			(stroke
				(width 0.1)
				(type default)
			)
			(layer "F.Fab")
		)
		(fp_line
			(start 0.120396 0.2794)
			(end -0.12065 0.2794)
			(stroke
				(width 0.1)
				(type default)
			)
			(layer "F.Fab")
		)
		(fp_line
			(start -0.12065 0.3048)
			(end -0.67945 0.3048)
			(stroke
				(width 0.1)
				(type default)
			)
			(layer "F.Fab")
		)
		(fp_line
			(start -0.12065 0.2794)
			(end -0.12065 0.3048)
			(stroke
				(width 0.1)
				(type default)
			)
			(layer "F.Fab")
		)
		(fp_line
			(start -0.12065 -0.2794)
			(end 0.12065 -0.2794)
			(stroke
				(width 0.1)
				(type default)
			)
			(layer "F.Fab")
		)
		(fp_line
			(start -0.12065 -0.305054)
			(end -0.12065 -0.2794)
			(stroke
				(width 0.1)
				(type default)
			)
			(layer "F.Fab")
		)
		(fp_line
			(start -0.67945 0.3048)
			(end -0.67945 -0.305054)
			(stroke
				(width 0.1)
				(type default)
			)
			(layer "F.Fab")
		)
		(fp_line
			(start -0.67945 -0.305054)
			(end -0.12065 -0.305054)
			(stroke
				(width 0.1)
				(type default)
			)
			(layer "F.Fab")
		)
		(pad "1" smd circle
			(at -0.40005 0 180)
			(size 0 0)
			(layers "F.Cu" "F.Mask" "F.Paste")
			(net "OSC_CLI_IN")
		)
		(pad "2" smd circle
			(at 0.40005 0 180)
			(size 0 0)
			(layers "F.Cu" "F.Mask" "F.Paste")
			(net "GND")
		)
	)
	(footprint ""
		(layer "F.Cu")
		(at 363.314996 -380.25578 -90)
		(property "Reference" "R6708"
			(at 0 0 270)
			(layer "F.SilkS")
			(hide yes)
			(effects
				(font
					(size 1.27 1.27)
				)
			)
		)
		(property "Value" ""
			(at 0 0 270)
			(layer "F.Fab")
			(effects
				(font
					(size 1.27 1.27)
				)
			)
		)
		(duplicate_pad_numbers_are_jumpers no)
		(fp_line
			(start -0.7874 0.4064)
			(end -0.7874 -0.4064)
			(stroke
				(width 0.1524)
				(type default)
			)
			(layer "F.SilkS")
		)
		(fp_line
			(start 0.7874 0.4064)
			(end -0.7874 0.4064)
			(stroke
				(width 0.1524)
				(type default)
			)
			(layer "F.SilkS")
		)
		(fp_line
			(start -0.7874 -0.4064)
			(end 0.7874 -0.4064)
			(stroke
				(width 0.1524)
				(type default)
			)
			(layer "F.SilkS")
		)
		(fp_line
			(start 0.7874 -0.4064)
			(end 0.7874 0.4064)
			(stroke
				(width 0.1524)
				(type default)
			)
			(layer "F.SilkS")
		)
		(fp_line
			(start -0.67945 0.3048)
			(end -0.67945 -0.305054)
			(stroke
				(width 0.1)
				(type default)
			)
			(layer "F.Fab")
		)
		(fp_line
			(start -0.12065 0.3048)
			(end -0.67945 0.3048)
			(stroke
				(width 0.1)
				(type default)
			)
			(layer "F.Fab")
		)
		(fp_line
			(start 0.120396 0.3048)
			(end 0.120396 0.2794)
			(stroke
				(width 0.1)
				(type default)
			)
			(layer "F.Fab")
		)
		(fp_line
			(start 0.67945 0.3048)
			(end 0.120396 0.3048)
			(stroke
				(width 0.1)
				(type default)
			)
			(layer "F.Fab")
		)
		(fp_line
			(start -0.12065 0.2794)
			(end -0.12065 0.3048)
			(stroke
				(width 0.1)
				(type default)
			)
			(layer "F.Fab")
		)
		(fp_line
			(start 0.120396 0.2794)
			(end -0.12065 0.2794)
			(stroke
				(width 0.1)
				(type default)
			)
			(layer "F.Fab")
		)
		(fp_line
			(start -0.12065 -0.2794)
			(end 0.12065 -0.2794)
			(stroke
				(width 0.1)
				(type default)
			)
			(layer "F.Fab")
		)
		(fp_line
			(start 0.12065 -0.2794)
			(end 0.12065 -0.3048)
			(stroke
				(width 0.1)
				(type default)
			)
			(layer "F.Fab")
		)
		(fp_line
			(start 0.12065 -0.3048)
			(end 0.67945 -0.3048)
			(stroke
				(width 0.1)
				(type default)
			)
			(layer "F.Fab")
		)
		(fp_line
			(start 0.67945 -0.3048)
			(end 0.67945 0.3048)
			(stroke
				(width 0.1)
				(type default)
			)
			(layer "F.Fab")
		)
		(fp_line
			(start -0.67945 -0.305054)
			(end -0.12065 -0.305054)
			(stroke
				(width 0.1)
				(type default)
			)
			(layer "F.Fab")
		)
		(fp_line
			(start -0.12065 -0.305054)
			(end -0.12065 -0.2794)
			(stroke
				(width 0.1)
				(type default)
			)
			(layer "F.Fab")
		)
		(pad "1" smd circle
			(at -0.40005 0 270)
			(size 0 0)
			(layers "F.Cu" "F.Mask" "F.Paste")
			(net "MB_3V3IO_RSVD4_N")
		)
		(pad "2" smd circle
			(at 0.40005 0 270)
			(size 0 0)
			(layers "F.Cu" "F.Mask" "F.Paste")
			(net "P3V3_AUX")
		)
	)
	(footprint ""
		(layer "F.Cu")
		(at 437.136032 -289.230816 90)
		(property "Reference" "R4005"
			(at 0 0 90)
			(layer "F.SilkS")
			(hide yes)
			(effects
				(font
					(size 1.27 1.27)
				)
			)
		)
		(property "Value" ""
			(at 0 0 90)
			(layer "F.Fab")
			(effects
				(font
					(size 1.27 1.27)
				)
			)
		)
		(duplicate_pad_numbers_are_jumpers no)
		(fp_line
			(start 0.7874 -0.4064)
			(end 0.7874 0.4064)
			(stroke
				(width 0.1524)
				(type default)
			)
			(layer "F.SilkS")
		)
		(fp_line
			(start -0.7874 -0.4064)
			(end 0.7874 -0.4064)
			(stroke
				(width 0.1524)
				(type default)
			)
			(layer "F.SilkS")
		)
		(fp_line
			(start 0.7874 0.4064)
			(end -0.7874 0.4064)
			(stroke
				(width 0.1524)
				(type default)
			)
			(layer "F.SilkS")
		)
		(fp_line
			(start -0.7874 0.4064)
			(end -0.7874 -0.4064)
			(stroke
				(width 0.1524)
				(type default)
			)
			(layer "F.SilkS")
		)
		(fp_line
			(start -0.12065 -0.305054)
			(end -0.12065 -0.2794)
			(stroke
				(width 0.1)
				(type default)
			)
			(layer "F.Fab")
		)
		(fp_line
			(start -0.67945 -0.305054)
			(end -0.12065 -0.305054)
			(stroke
				(width 0.1)
				(type default)
			)
			(layer "F.Fab")
		)
		(fp_line
			(start 0.67945 -0.3048)
			(end 0.67945 0.3048)
			(stroke
				(width 0.1)
				(type default)
			)
			(layer "F.Fab")
		)
		(fp_line
			(start 0.12065 -0.3048)
			(end 0.67945 -0.3048)
			(stroke
				(width 0.1)
				(type default)
			)
			(layer "F.Fab")
		)
		(fp_line
			(start 0.12065 -0.2794)
			(end 0.12065 -0.3048)
			(stroke
				(width 0.1)
				(type default)
			)
			(layer "F.Fab")
		)
		(fp_line
			(start -0.12065 -0.2794)
			(end 0.12065 -0.2794)
			(stroke
				(width 0.1)
				(type default)
			)
			(layer "F.Fab")
		)
		(fp_line
			(start 0.120396 0.2794)
			(end -0.12065 0.2794)
			(stroke
				(width 0.1)
				(type default)
			)
			(layer "F.Fab")
		)
		(fp_line
			(start -0.12065 0.2794)
			(end -0.12065 0.3048)
			(stroke
				(width 0.1)
				(type default)
			)
			(layer "F.Fab")
		)
		(fp_line
			(start 0.67945 0.3048)
			(end 0.120396 0.3048)
			(stroke
				(width 0.1)
				(type default)
			)
			(layer "F.Fab")
		)
		(fp_line
			(start 0.120396 0.3048)
			(end 0.120396 0.2794)
			(stroke
				(width 0.1)
				(type default)
			)
			(layer "F.Fab")
		)
		(fp_line
			(start -0.12065 0.3048)
			(end -0.67945 0.3048)
			(stroke
				(width 0.1)
				(type default)
			)
			(layer "F.Fab")
		)
		(fp_line
			(start -0.67945 0.3048)
			(end -0.67945 -0.305054)
			(stroke
				(width 0.1)
				(type default)
			)
			(layer "F.Fab")
		)
		(pad "1" smd circle
			(at -0.40005 0 90)
			(size 0 0)
			(layers "F.Cu" "F.Mask" "F.Paste")
			(net "SMB_PEX3_FPGA_SDA")
		)
		(pad "2" smd circle
			(at 0.40005 0 90)
			(size 0 0)
			(layers "F.Cu" "F.Mask" "F.Paste")
			(net "SMB_PEX3_HOST_LS_SDA")
		)
	)
	(footprint ""
		(layer "F.Cu")
		(at 336.042 -170.053)
		(property "Reference" "R4726"
			(at 0 0 0)
			(layer "F.SilkS")
			(hide yes)
			(effects
				(font
					(size 1.27 1.27)
				)
			)
		)
		(property "Value" ""
			(at 0 0 0)
			(layer "F.Fab")
			(effects
				(font
					(size 1.27 1.27)
				)
			)
		)
		(duplicate_pad_numbers_are_jumpers no)
		(fp_line
			(start -0.7874 -0.4064)
			(end 0.7874 -0.4064)
			(stroke
				(width 0.1524)
				(type default)
			)
			(layer "F.SilkS")
		)
		(fp_line
			(start -0.7874 0.4064)
			(end -0.7874 -0.4064)
			(stroke
				(width 0.1524)
				(type default)
			)
			(layer "F.SilkS")
		)
		(fp_line
			(start 0.7874 -0.4064)
			(end 0.7874 0.4064)
			(stroke
				(width 0.1524)
				(type default)
			)
			(layer "F.SilkS")
		)
		(fp_line
			(start 0.7874 0.4064)
			(end -0.7874 0.4064)
			(stroke
				(width 0.1524)
				(type default)
			)
			(layer "F.SilkS")
		)
		(fp_line
			(start -0.67945 -0.305054)
			(end -0.12065 -0.305054)
			(stroke
				(width 0.1)
				(type default)
			)
			(layer "F.Fab")
		)
		(fp_line
			(start -0.67945 0.3048)
			(end -0.67945 -0.305054)
			(stroke
				(width 0.1)
				(type default)
			)
			(layer "F.Fab")
		)
		(fp_line
			(start -0.12065 -0.305054)
			(end -0.12065 -0.2794)
			(stroke
				(width 0.1)
				(type default)
			)
			(layer "F.Fab")
		)
		(fp_line
			(start -0.12065 -0.2794)
			(end 0.12065 -0.2794)
			(stroke
				(width 0.1)
				(type default)
			)
			(layer "F.Fab")
		)
		(fp_line
			(start -0.12065 0.2794)
			(end -0.12065 0.3048)
			(stroke
				(width 0.1)
				(type default)
			)
			(layer "F.Fab")
		)
		(fp_line
			(start -0.12065 0.3048)
			(end -0.67945 0.3048)
			(stroke
				(width 0.1)
				(type default)
			)
			(layer "F.Fab")
		)
		(fp_line
			(start 0.120396 0.2794)
			(end -0.12065 0.2794)
			(stroke
				(width 0.1)
				(type default)
			)
			(layer "F.Fab")
		)
		(fp_line
			(start 0.120396 0.3048)
			(end 0.120396 0.2794)
			(stroke
				(width 0.1)
				(type default)
			)
			(layer "F.Fab")
		)
		(fp_line
			(start 0.12065 -0.3048)
			(end 0.67945 -0.3048)
			(stroke
				(width 0.1)
				(type default)
			)
			(layer "F.Fab")
		)
		(fp_line
			(start 0.12065 -0.2794)
			(end 0.12065 -0.3048)
			(stroke
				(width 0.1)
				(type default)
			)
			(layer "F.Fab")
		)
		(fp_line
			(start 0.67945 -0.3048)
			(end 0.67945 0.3048)
			(stroke
				(width 0.1)
				(type default)
			)
			(layer "F.Fab")
		)
		(fp_line
			(start 0.67945 0.3048)
			(end 0.120396 0.3048)
			(stroke
				(width 0.1)
				(type default)
			)
			(layer "F.Fab")
		)
		(pad "1" smd circle
			(at -0.40005 0)
			(size 0 0)
			(layers "F.Cu" "F.Mask" "F.Paste")
			(net "P3V3_AUX")
		)
		(pad "2" smd circle
			(at 0.40005 0)
			(size 0 0)
			(layers "F.Cu" "F.Mask" "F.Paste")
			(net "SSD10_PEX_PWR_EN_R")
		)
	)
	(footprint ""
		(layer "F.Cu")
		(at 448.64528 -410.15666 90)
		(property "Reference" "U329"
			(at -1.245108 3.82016 90)
			(unlocked yes)
			(layer "F.SilkS")
			(effects
				(font
					(size 0.7874 0.5842)
					(thickness 0.1524)
				)
				(justify left)
			)
		)
		(property "Value" ""
			(at 0 0 90)
			(layer "F.Fab")
			(effects
				(font
					(size 1.27 1.27)
				)
			)
		)
		(duplicate_pad_numbers_are_jumpers no)
		(fp_line
			(start 3.447796 -2.500122)
			(end 1.484122 -2.500122)
			(stroke
				(width 0.1524)
				(type default)
			)
			(layer "F.SilkS")
		)
		(fp_line
			(start 1.484122 -2.500122)
			(end 0 -1.016)
			(stroke
				(width 0.1524)
				(type default)
			)
			(layer "F.SilkS")
		)
		(fp_line
			(start -1.484122 -2.500122)
			(end -3.447796 -2.500122)
			(stroke
				(width 0.1524)
				(type default)
			)
			(layer "F.SilkS")
		)
		(fp_line
			(start -3.447796 -2.500122)
			(end -3.447796 2.500122)
			(stroke
				(width 0.1524)
				(type default)
			)
			(layer "F.SilkS")
		)
		(fp_line
			(start 0 -1.016)
			(end -1.484122 -2.500122)
			(stroke
				(width 0.1524)
				(type default)
			)
			(layer "F.SilkS")
		)
		(fp_line
			(start 3.447796 2.500122)
			(end 3.447796 -2.500122)
			(stroke
				(width 0.1524)
				(type default)
			)
			(layer "F.SilkS")
		)
		(fp_line
			(start -3.447796 2.500122)
			(end 3.447796 2.500122)
			(stroke
				(width 0.1524)
				(type default)
			)
			(layer "F.SilkS")
		)
		(fp_poly
			(pts
				(xy -4.053332 -3.443732) (xy -4.771644 -2.72542) (xy -3.693922 -2.36601)
			)
			(stroke
				(width 0)
				(type default)
			)
			(fill yes)
			(layer "F.SilkS")
		)
		(fp_line
			(start 1.999996 -2.500122)
			(end -1.999996 -2.500122)
			(stroke
				(width 0.1)
				(type default)
			)
			(layer "F.Fab")
		)
		(fp_line
			(start -1.999996 -2.500122)
			(end -1.999996 2.500122)
			(stroke
				(width 0.1)
				(type default)
			)
			(layer "F.Fab")
		)
		(fp_line
			(start 1.999996 2.500122)
			(end 1.999996 -2.500122)
			(stroke
				(width 0.1)
				(type default)
			)
			(layer "F.Fab")
		)
		(fp_line
			(start -1.999996 2.500122)
			(end 1.999996 2.500122)
			(stroke
				(width 0.1)
				(type default)
			)
			(layer "F.Fab")
		)
		(fp_poly
			(pts
				(xy -4.5974 -2.413) (xy -4.5974 -1.397) (xy -3.5814 -1.905)
			)
			(stroke
				(width 0)
				(type default)
			)
			(fill yes)
			(layer "F.Fab")
		)
		(pad "1" smd rect
			(at -2.649982 -1.905)
			(size 0.6096 1.3208)
			(layers "F.Cu" "F.Mask" "F.Paste")
			(net "SMB_LM75_1_SDA")
		)
		(pad "2" smd rect
			(at -2.649982 -0.635)
			(size 0.6096 1.3208)
			(layers "F.Cu" "F.Mask" "F.Paste")
			(net "SMB_LM75_1_SCL")
		)
		(pad "3" smd rect
			(at -2.649982 0.635)
			(size 0.6096 1.3208)
			(layers "F.Cu" "F.Mask" "F.Paste")
			(net "Net_406")
		)
		(pad "4" smd rect
			(at -2.649982 1.905)
			(size 0.6096 1.3208)
			(layers "F.Cu" "F.Mask" "F.Paste")
			(net "GND")
		)
		(pad "5" smd rect
			(at 2.649982 1.905)
			(size 0.6096 1.3208)
			(layers "F.Cu" "F.Mask" "F.Paste")
			(net "LM75_1_A2")
		)
		(pad "6" smd rect
			(at 2.649982 0.635)
			(size 0.6096 1.3208)
			(layers "F.Cu" "F.Mask" "F.Paste")
			(net "LM75_1_A1")
		)
		(pad "7" smd rect
			(at 2.649982 -0.635)
			(size 0.6096 1.3208)
			(layers "F.Cu" "F.Mask" "F.Paste")
			(net "LM75_1_A0")
		)
		(pad "8" smd rect
			(at 2.649982 -1.905)
			(size 0.6096 1.3208)
			(layers "F.Cu" "F.Mask" "F.Paste")
			(net "P3V3_AUX")
		)
	)
	(footprint ""
		(layer "F.Cu")
		(at 320.354452 -218.309698 180)
		(property "Reference" "D19"
			(at 3.743452 -0.023368 0)
			(unlocked yes)
			(layer "F.SilkS")
			(effects
				(font
					(size 0.7874 0.5842)
					(thickness 0.1524)
				)
				(justify left)
			)
		)
		(property "Value" ""
			(at 0 0 180)
			(layer "F.Fab")
			(effects
				(font
					(size 1.27 1.27)
				)
			)
		)
		(duplicate_pad_numbers_are_jumpers no)
		(fp_line
			(start 1.16078 0.4826)
			(end -0.64008 0.4826)
			(stroke
				(width 0.1524)
				(type default)
			)
			(layer "F.SilkS")
		)
		(fp_line
			(start 1.16078 -0.4826)
			(end 1.16078 0.4826)
			(stroke
				(width 0.1524)
				(type default)
			)
			(layer "F.SilkS")
		)
		(fp_line
			(start 1.03378 0.4826)
			(end -0.79248 0.4826)
			(stroke
				(width 0.1524)
				(type default)
			)
			(layer "F.SilkS")
		)
		(fp_line
			(start 1.03378 -0.4826)
			(end 1.03378 0.4826)
			(stroke
				(width 0.1524)
				(type default)
			)
			(layer "F.SilkS")
		)
		(fp_line
			(start 0.90678 0.4826)
			(end -0.90678 0.4826)
			(stroke
				(width 0.1524)
				(type default)
			)
			(layer "F.SilkS")
		)
		(fp_line
			(start 0.90678 -0.4826)
			(end 0.90678 0.4826)
			(stroke
				(width 0.1524)
				(type default)
			)
			(layer "F.SilkS")
		)
		(fp_line
			(start -0.64008 -0.4826)
			(end 1.16078 -0.4826)
			(stroke
				(width 0.1524)
				(type default)
			)
			(layer "F.SilkS")
		)
		(fp_line
			(start -0.79248 -0.4826)
			(end 1.03378 -0.4826)
			(stroke
				(width 0.1524)
				(type default)
			)
			(layer "F.SilkS")
		)
		(fp_line
			(start -0.89408 -0.4826)
			(end 0.90678 -0.4826)
			(stroke
				(width 0.1524)
				(type default)
			)
			(layer "F.SilkS")
		)
		(fp_line
			(start -0.90678 0.4826)
			(end -0.90678 -0.4699)
			(stroke
				(width 0.1524)
				(type default)
			)
			(layer "F.SilkS")
		)
		(fp_line
			(start 0.499872 0.249936)
			(end -0.499872 0.249936)
			(stroke
				(width 0.1)
				(type default)
			)
			(layer "F.Fab")
		)
		(fp_line
			(start 0.499872 -0.249936)
			(end 0.499872 0.249936)
			(stroke
				(width 0.1)
				(type default)
			)
			(layer "F.Fab")
		)
		(fp_line
			(start -0.499872 0.249936)
			(end -0.499872 -0.249936)
			(stroke
				(width 0.1)
				(type default)
			)
			(layer "F.Fab")
		)
		(fp_line
			(start -0.499872 -0.249936)
			(end 0.499872 -0.249936)
			(stroke
				(width 0.1)
				(type default)
			)
			(layer "F.Fab")
		)
		(pad "A" smd rect
			(at -0.47498 0 180)
			(size 0.6096 0.7112)
			(layers "F.Cu" "F.Mask" "F.Paste")
			(net "LED_POSTCODE_R_6")
		)
		(pad "C" smd rect
			(at 0.47498 0 180)
			(size 0.6096 0.7112)
			(layers "F.Cu" "F.Mask" "F.Paste")
			(net "FPGA_DEBUG_LED_R_N")
		)
	)
	(footprint ""
		(layer "F.Cu")
		(at 370.889784 -235.756958)
		(property "Reference" "R6409"
			(at 0 0 0)
			(layer "F.SilkS")
			(hide yes)
			(effects
				(font
					(size 1.27 1.27)
				)
			)
		)
		(property "Value" ""
			(at 0 0 0)
			(layer "F.Fab")
			(effects
				(font
					(size 1.27 1.27)
				)
			)
		)
		(duplicate_pad_numbers_are_jumpers no)
		(fp_line
			(start -0.7874 -0.4064)
			(end 0.7874 -0.4064)
			(stroke
				(width 0.1524)
				(type default)
			)
			(layer "F.SilkS")
		)
		(fp_line
			(start -0.7874 0.4064)
			(end -0.7874 -0.4064)
			(stroke
				(width 0.1524)
				(type default)
			)
			(layer "F.SilkS")
		)
		(fp_line
			(start 0.7874 -0.4064)
			(end 0.7874 0.4064)
			(stroke
				(width 0.1524)
				(type default)
			)
			(layer "F.SilkS")
		)
		(fp_line
			(start 0.7874 0.4064)
			(end -0.7874 0.4064)
			(stroke
				(width 0.1524)
				(type default)
			)
			(layer "F.SilkS")
		)
		(fp_line
			(start -0.67945 -0.305054)
			(end -0.12065 -0.305054)
			(stroke
				(width 0.1)
				(type default)
			)
			(layer "F.Fab")
		)
		(fp_line
			(start -0.67945 0.3048)
			(end -0.67945 -0.305054)
			(stroke
				(width 0.1)
				(type default)
			)
			(layer "F.Fab")
		)
		(fp_line
			(start -0.12065 -0.305054)
			(end -0.12065 -0.2794)
			(stroke
				(width 0.1)
				(type default)
			)
			(layer "F.Fab")
		)
		(fp_line
			(start -0.12065 -0.2794)
			(end 0.12065 -0.2794)
			(stroke
				(width 0.1)
				(type default)
			)
			(layer "F.Fab")
		)
		(fp_line
			(start -0.12065 0.2794)
			(end -0.12065 0.3048)
			(stroke
				(width 0.1)
				(type default)
			)
			(layer "F.Fab")
		)
		(fp_line
			(start -0.12065 0.3048)
			(end -0.67945 0.3048)
			(stroke
				(width 0.1)
				(type default)
			)
			(layer "F.Fab")
		)
		(fp_line
			(start 0.120396 0.2794)
			(end -0.12065 0.2794)
			(stroke
				(width 0.1)
				(type default)
			)
			(layer "F.Fab")
		)
		(fp_line
			(start 0.120396 0.3048)
			(end 0.120396 0.2794)
			(stroke
				(width 0.1)
				(type default)
			)
			(layer "F.Fab")
		)
		(fp_line
			(start 0.12065 -0.3048)
			(end 0.67945 -0.3048)
			(stroke
				(width 0.1)
				(type default)
			)
			(layer "F.Fab")
		)
		(fp_line
			(start 0.12065 -0.2794)
			(end 0.12065 -0.3048)
			(stroke
				(width 0.1)
				(type default)
			)
			(layer "F.Fab")
		)
		(fp_line
			(start 0.67945 -0.3048)
			(end 0.67945 0.3048)
			(stroke
				(width 0.1)
				(type default)
			)
			(layer "F.Fab")
		)
		(fp_line
			(start 0.67945 0.3048)
			(end 0.120396 0.3048)
			(stroke
				(width 0.1)
				(type default)
			)
			(layer "F.Fab")
		)
		(pad "1" smd circle
			(at -0.40005 0)
			(size 0 0)
			(layers "F.Cu" "F.Mask" "F.Paste")
			(net "GND")
		)
		(pad "2" smd circle
			(at 0.40005 0)
			(size 0 0)
			(layers "F.Cu" "F.Mask" "F.Paste")
			(net "PWRGD_P5V_AUX_BUF")
		)
	)
	(footprint ""
		(layer "F.Cu")
		(at 221.251272 -146.990562)
		(property "Reference" "R4204"
			(at 0 0 0)
			(layer "F.SilkS")
			(hide yes)
			(effects
				(font
					(size 1.27 1.27)
				)
			)
		)
		(property "Value" ""
			(at 0 0 0)
			(layer "F.Fab")
			(effects
				(font
					(size 1.27 1.27)
				)
			)
		)
		(duplicate_pad_numbers_are_jumpers no)
		(fp_line
			(start -0.7874 -0.4064)
			(end 0.7874 -0.4064)
			(stroke
				(width 0.1524)
				(type default)
			)
			(layer "F.SilkS")
		)
		(fp_line
			(start -0.7874 0.4064)
			(end -0.7874 -0.4064)
			(stroke
				(width 0.1524)
				(type default)
			)
			(layer "F.SilkS")
		)
		(fp_line
			(start 0.7874 -0.4064)
			(end 0.7874 0.4064)
			(stroke
				(width 0.1524)
				(type default)
			)
			(layer "F.SilkS")
		)
		(fp_line
			(start 0.7874 0.4064)
			(end -0.7874 0.4064)
			(stroke
				(width 0.1524)
				(type default)
			)
			(layer "F.SilkS")
		)
		(fp_line
			(start -0.67945 -0.305054)
			(end -0.12065 -0.305054)
			(stroke
				(width 0.1)
				(type default)
			)
			(layer "F.Fab")
		)
		(fp_line
			(start -0.67945 0.3048)
			(end -0.67945 -0.305054)
			(stroke
				(width 0.1)
				(type default)
			)
			(layer "F.Fab")
		)
		(fp_line
			(start -0.12065 -0.305054)
			(end -0.12065 -0.2794)
			(stroke
				(width 0.1)
				(type default)
			)
			(layer "F.Fab")
		)
		(fp_line
			(start -0.12065 -0.2794)
			(end 0.12065 -0.2794)
			(stroke
				(width 0.1)
				(type default)
			)
			(layer "F.Fab")
		)
		(fp_line
			(start -0.12065 0.2794)
			(end -0.12065 0.3048)
			(stroke
				(width 0.1)
				(type default)
			)
			(layer "F.Fab")
		)
		(fp_line
			(start -0.12065 0.3048)
			(end -0.67945 0.3048)
			(stroke
				(width 0.1)
				(type default)
			)
			(layer "F.Fab")
		)
		(fp_line
			(start 0.120396 0.2794)
			(end -0.12065 0.2794)
			(stroke
				(width 0.1)
				(type default)
			)
			(layer "F.Fab")
		)
		(fp_line
			(start 0.120396 0.3048)
			(end 0.120396 0.2794)
			(stroke
				(width 0.1)
				(type default)
			)
			(layer "F.Fab")
		)
		(fp_line
			(start 0.12065 -0.3048)
			(end 0.67945 -0.3048)
			(stroke
				(width 0.1)
				(type default)
			)
			(layer "F.Fab")
		)
		(fp_line
			(start 0.12065 -0.2794)
			(end 0.12065 -0.3048)
			(stroke
				(width 0.1)
				(type default)
			)
			(layer "F.Fab")
		)
		(fp_line
			(start 0.67945 -0.3048)
			(end 0.67945 0.3048)
			(stroke
				(width 0.1)
				(type default)
			)
			(layer "F.Fab")
		)
		(fp_line
			(start 0.67945 0.3048)
			(end 0.120396 0.3048)
			(stroke
				(width 0.1)
				(type default)
			)
			(layer "F.Fab")
		)
		(pad "1" smd circle
			(at -0.40005 0)
			(size 0 0)
			(layers "F.Cu" "F.Mask" "F.Paste")
			(net "GND")
		)
		(pad "2" smd circle
			(at 0.40005 0)
			(size 0 0)
			(layers "F.Cu" "F.Mask" "F.Paste")
			(net "PU_CK440_PEX_SHFT_LD_N")
		)
	)
	(footprint ""
		(layer "F.Cu")
		(at 129.86639 -184.656984 -90)
		(property "Reference" "R1117"
			(at 0 0 270)
			(layer "F.SilkS")
			(hide yes)
			(effects
				(font
					(size 1.27 1.27)
				)
			)
		)
		(property "Value" ""
			(at 0 0 270)
			(layer "F.Fab")
			(effects
				(font
					(size 1.27 1.27)
				)
			)
		)
		(duplicate_pad_numbers_are_jumpers no)
		(fp_line
			(start 0.7874 0.4064)
			(end -0.7874 0.4064)
			(stroke
				(width 0.1524)
				(type default)
			)
			(layer "F.SilkS")
		)
		(fp_line
			(start -0.67945 0.3048)
			(end -0.67945 -0.305054)
			(stroke
				(width 0.1)
				(type default)
			)
			(layer "F.Fab")
		)
		(fp_line
			(start -0.12065 0.3048)
			(end -0.67945 0.3048)
			(stroke
				(width 0.1)
				(type default)
			)
			(layer "F.Fab")
		)
		(fp_line
			(start 0.120396 0.3048)
			(end 0.120396 0.2794)
			(stroke
				(width 0.1)
				(type default)
			)
			(layer "F.Fab")
		)
		(fp_line
			(start 0.67945 0.3048)
			(end 0.120396 0.3048)
			(stroke
				(width 0.1)
				(type default)
			)
			(layer "F.Fab")
		)
		(fp_line
			(start -0.12065 0.2794)
			(end -0.12065 0.3048)
			(stroke
				(width 0.1)
				(type default)
			)
			(layer "F.Fab")
		)
		(fp_line
			(start 0.120396 0.2794)
			(end -0.12065 0.2794)
			(stroke
				(width 0.1)
				(type default)
			)
			(layer "F.Fab")
		)
		(fp_line
			(start -0.12065 -0.2794)
			(end 0.12065 -0.2794)
			(stroke
				(width 0.1)
				(type default)
			)
			(layer "F.Fab")
		)
		(fp_line
			(start 0.12065 -0.2794)
			(end 0.12065 -0.3048)
			(stroke
				(width 0.1)
				(type default)
			)
			(layer "F.Fab")
		)
		(fp_line
			(start 0.12065 -0.3048)
			(end 0.67945 -0.3048)
			(stroke
				(width 0.1)
				(type default)
			)
			(layer "F.Fab")
		)
		(fp_line
			(start 0.67945 -0.3048)
			(end 0.67945 0.3048)
			(stroke
				(width 0.1)
				(type default)
			)
			(layer "F.Fab")
		)
		(fp_line
			(start -0.67945 -0.305054)
			(end -0.12065 -0.305054)
			(stroke
				(width 0.1)
				(type default)
			)
			(layer "F.Fab")
		)
		(fp_line
			(start -0.12065 -0.305054)
			(end -0.12065 -0.2794)
			(stroke
				(width 0.1)
				(type default)
			)
			(layer "F.Fab")
		)
		(pad "1" smd circle
			(at -0.40005 0 270)
			(size 0 0)
			(layers "F.Cu" "F.Mask" "F.Paste")
			(net "CLK_100M_DB2000QL_GPU_REF2_R_DN")
		)
		(pad "2" smd circle
			(at 0.40005 0 270)
			(size 0 0)
			(layers "F.Cu" "F.Mask" "F.Paste")
			(net "CLK_100M_DB2000QL_GPU_REF2_DN")
		)
	)
	(footprint ""
		(layer "F.Cu")
		(at 332.956662 -10.545572 90)
		(property "Reference" "R1705"
			(at 0 0 90)
			(layer "F.SilkS")
			(hide yes)
			(effects
				(font
					(size 1.27 1.27)
				)
			)
		)
		(property "Value" ""
			(at 0 0 90)
			(layer "F.Fab")
			(effects
				(font
					(size 1.27 1.27)
				)
			)
		)
		(duplicate_pad_numbers_are_jumpers no)
		(fp_line
			(start 0.7874 -0.4064)
			(end 0.7874 0.4064)
			(stroke
				(width 0.1524)
				(type default)
			)
			(layer "F.SilkS")
		)
		(fp_line
			(start -0.7874 -0.4064)
			(end 0.7874 -0.4064)
			(stroke
				(width 0.1524)
				(type default)
			)
			(layer "F.SilkS")
		)
		(fp_line
			(start 0.7874 0.4064)
			(end -0.7874 0.4064)
			(stroke
				(width 0.1524)
				(type default)
			)
			(layer "F.SilkS")
		)
		(fp_line
			(start -0.7874 0.4064)
			(end -0.7874 -0.4064)
			(stroke
				(width 0.1524)
				(type default)
			)
			(layer "F.SilkS")
		)
		(fp_line
			(start -0.12065 -0.305054)
			(end -0.12065 -0.2794)
			(stroke
				(width 0.1)
				(type default)
			)
			(layer "F.Fab")
		)
		(fp_line
			(start -0.67945 -0.305054)
			(end -0.12065 -0.305054)
			(stroke
				(width 0.1)
				(type default)
			)
			(layer "F.Fab")
		)
		(fp_line
			(start 0.67945 -0.3048)
			(end 0.67945 0.3048)
			(stroke
				(width 0.1)
				(type default)
			)
			(layer "F.Fab")
		)
		(fp_line
			(start 0.12065 -0.3048)
			(end 0.67945 -0.3048)
			(stroke
				(width 0.1)
				(type default)
			)
			(layer "F.Fab")
		)
		(fp_line
			(start 0.12065 -0.2794)
			(end 0.12065 -0.3048)
			(stroke
				(width 0.1)
				(type default)
			)
			(layer "F.Fab")
		)
		(fp_line
			(start -0.12065 -0.2794)
			(end 0.12065 -0.2794)
			(stroke
				(width 0.1)
				(type default)
			)
			(layer "F.Fab")
		)
		(fp_line
			(start 0.120396 0.2794)
			(end -0.12065 0.2794)
			(stroke
				(width 0.1)
				(type default)
			)
			(layer "F.Fab")
		)
		(fp_line
			(start -0.12065 0.2794)
			(end -0.12065 0.3048)
			(stroke
				(width 0.1)
				(type default)
			)
			(layer "F.Fab")
		)
		(fp_line
			(start 0.67945 0.3048)
			(end 0.120396 0.3048)
			(stroke
				(width 0.1)
				(type default)
			)
			(layer "F.Fab")
		)
		(fp_line
			(start 0.120396 0.3048)
			(end 0.120396 0.2794)
			(stroke
				(width 0.1)
				(type default)
			)
			(layer "F.Fab")
		)
		(fp_line
			(start -0.12065 0.3048)
			(end -0.67945 0.3048)
			(stroke
				(width 0.1)
				(type default)
			)
			(layer "F.Fab")
		)
		(fp_line
			(start -0.67945 0.3048)
			(end -0.67945 -0.305054)
			(stroke
				(width 0.1)
				(type default)
			)
			(layer "F.Fab")
		)
		(pad "1" smd circle
			(at -0.40005 0 90)
			(size 0 0)
			(layers "F.Cu" "F.Mask" "F.Paste")
			(net "P3V3_SSD11")
		)
		(pad "2" smd circle
			(at 0.40005 0 90)
			(size 0 0)
			(layers "F.Cu" "F.Mask" "F.Paste")
			(net "SMB_ISO_SSD11_SCL")
		)
	)
	(footprint ""
		(layer "F.Cu")
		(at 444.922148 -227.908866 180)
		(property "Reference" "R6609"
			(at 0 0 180)
			(layer "F.SilkS")
			(hide yes)
			(effects
				(font
					(size 1.27 1.27)
				)
			)
		)
		(property "Value" ""
			(at 0 0 180)
			(layer "F.Fab")
			(effects
				(font
					(size 1.27 1.27)
				)
			)
		)
		(duplicate_pad_numbers_are_jumpers no)
		(fp_line
			(start 0.7874 0.4064)
			(end -0.7874 0.4064)
			(stroke
				(width 0.1524)
				(type default)
			)
			(layer "F.SilkS")
		)
		(fp_line
			(start 0.7874 -0.4064)
			(end 0.7874 0.4064)
			(stroke
				(width 0.1524)
				(type default)
			)
			(layer "F.SilkS")
		)
		(fp_line
			(start -0.7874 0.4064)
			(end -0.7874 -0.4064)
			(stroke
				(width 0.1524)
				(type default)
			)
			(layer "F.SilkS")
		)
		(fp_line
			(start -0.7874 -0.4064)
			(end 0.7874 -0.4064)
			(stroke
				(width 0.1524)
				(type default)
			)
			(layer "F.SilkS")
		)
		(fp_line
			(start 0.67945 0.3048)
			(end 0.120396 0.3048)
			(stroke
				(width 0.1)
				(type default)
			)
			(layer "F.Fab")
		)
		(fp_line
			(start 0.67945 -0.3048)
			(end 0.67945 0.3048)
			(stroke
				(width 0.1)
				(type default)
			)
			(layer "F.Fab")
		)
		(fp_line
			(start 0.12065 -0.2794)
			(end 0.12065 -0.3048)
			(stroke
				(width 0.1)
				(type default)
			)
			(layer "F.Fab")
		)
		(fp_line
			(start 0.12065 -0.3048)
			(end 0.67945 -0.3048)
			(stroke
				(width 0.1)
				(type default)
			)
			(layer "F.Fab")
		)
		(fp_line
			(start 0.120396 0.3048)
			(end 0.120396 0.2794)
			(stroke
				(width 0.1)
				(type default)
			)
			(layer "F.Fab")
		)
		(fp_line
			(start 0.120396 0.2794)
			(end -0.12065 0.2794)
			(stroke
				(width 0.1)
				(type default)
			)
			(layer "F.Fab")
		)
		(fp_line
			(start -0.12065 0.3048)
			(end -0.67945 0.3048)
			(stroke
				(width 0.1)
				(type default)
			)
			(layer "F.Fab")
		)
		(fp_line
			(start -0.12065 0.2794)
			(end -0.12065 0.3048)
			(stroke
				(width 0.1)
				(type default)
			)
			(layer "F.Fab")
		)
		(fp_line
			(start -0.12065 -0.2794)
			(end 0.12065 -0.2794)
			(stroke
				(width 0.1)
				(type default)
			)
			(layer "F.Fab")
		)
		(fp_line
			(start -0.12065 -0.305054)
			(end -0.12065 -0.2794)
			(stroke
				(width 0.1)
				(type default)
			)
			(layer "F.Fab")
		)
		(fp_line
			(start -0.67945 0.3048)
			(end -0.67945 -0.305054)
			(stroke
				(width 0.1)
				(type default)
			)
			(layer "F.Fab")
		)
		(fp_line
			(start -0.67945 -0.305054)
			(end -0.12065 -0.305054)
			(stroke
				(width 0.1)
				(type default)
			)
			(layer "F.Fab")
		)
		(pad "1" smd circle
			(at -0.40005 0 180)
			(size 0 0)
			(layers "F.Cu" "F.Mask" "F.Paste")
			(net "UART_PEX3_SDB_CP2108_RX")
		)
		(pad "2" smd circle
			(at 0.40005 0 180)
			(size 0 0)
			(layers "F.Cu" "F.Mask" "F.Paste")
			(net "UART_PEX3_SDB_R_RX")
		)
	)
	(footprint ""
		(layer "F.Cu")
		(at 226.701858 -176.306226)
		(property "Reference" "U359"
			(at -1.8034 -1.793748 0)
			(unlocked yes)
			(layer "F.SilkS")
			(effects
				(font
					(size 0.7874 0.5842)
					(thickness 0.1524)
				)
				(justify left)
			)
		)
		(property "Value" ""
			(at 0 0 0)
			(layer "F.Fab")
			(effects
				(font
					(size 1.27 1.27)
				)
			)
		)
		(duplicate_pad_numbers_are_jumpers no)
		(fp_line
			(start -1.640078 -1.100074)
			(end -1.640078 1.100074)
			(stroke
				(width 0.1524)
				(type default)
			)
			(layer "F.SilkS")
		)
		(fp_line
			(start -1.640078 1.100074)
			(end 1.640078 1.100074)
			(stroke
				(width 0.1524)
				(type default)
			)
			(layer "F.SilkS")
		)
		(fp_line
			(start 1.640078 -1.100074)
			(end -1.640078 -1.100074)
			(stroke
				(width 0.1524)
				(type default)
			)
			(layer "F.SilkS")
		)
		(fp_line
			(start 1.640078 1.100074)
			(end 1.640078 -1.100074)
			(stroke
				(width 0.1524)
				(type default)
			)
			(layer "F.SilkS")
		)
		(fp_poly
			(pts
				(xy -1.82753 -1.354582) (xy -2.643886 -1.626616) (xy -2.099818 -2.170684)
			)
			(stroke
				(width 0)
				(type default)
			)
			(fill yes)
			(layer "F.SilkS")
		)
		(fp_line
			(start -0.674878 -1.100074)
			(end -0.674878 1.100074)
			(stroke
				(width 0.1)
				(type default)
			)
			(layer "F.Fab")
		)
		(fp_line
			(start -0.674878 1.100074)
			(end 0.674878 1.100074)
			(stroke
				(width 0.1)
				(type default)
			)
			(layer "F.Fab")
		)
		(fp_line
			(start 0.674878 -1.100074)
			(end -0.674878 -1.100074)
			(stroke
				(width 0.1)
				(type default)
			)
			(layer "F.Fab")
		)
		(fp_line
			(start 0.674878 1.100074)
			(end 0.674878 -1.100074)
			(stroke
				(width 0.1)
				(type default)
			)
			(layer "F.Fab")
		)
		(fp_poly
			(pts
				(xy -1.74879 -0.649986) (xy -2.51841 -0.265176) (xy -2.51841 -1.034796)
			)
			(stroke
				(width 0)
				(type default)
			)
			(fill yes)
			(layer "F.Fab")
		)
		(pad "1" smd rect
			(at -0.818896 -0.649986 270)
			(size 0.3556 1.4732)
			(layers "F.Cu" "F.Mask" "F.Paste")
			(net "ADM1085_CEXT")
		)
		(pad "2" smd rect
			(at -0.818896 0 270)
			(size 0.3556 1.4732)
			(layers "F.Cu" "F.Mask" "F.Paste")
			(net "GND")
		)
		(pad "3" smd rect
			(at -0.818896 0.649986 270)
			(size 0.3556 1.4732)
			(layers "F.Cu" "F.Mask" "F.Paste")
			(net "ADM1085_IN")
		)
		(pad "4" smd rect
			(at 0.818896 0.649986 270)
			(size 0.3556 1.4732)
			(layers "F.Cu" "F.Mask" "F.Paste")
			(net "ADM1085_ENOUT")
		)
		(pad "5" smd rect
			(at 0.818896 0 270)
			(size 0.3556 1.4732)
			(layers "F.Cu" "F.Mask" "F.Paste")
			(net "THRESHOLD")
		)
		(pad "6" smd rect
			(at 0.818896 -0.649986 270)
			(size 0.3556 1.4732)
			(layers "F.Cu" "F.Mask" "F.Paste")
			(net "P3V3_AUX")
		)
	)
	(footprint ""
		(layer "F.Cu")
		(at 20.575524 -69.47916 180)
		(property "Reference" "PU76"
			(at -1.921764 3.80238 90)
			(unlocked yes)
			(layer "F.SilkS")
			(effects
				(font
					(size 0.7874 0.5842)
					(thickness 0.1524)
				)
			)
		)
		(property "Value" ""
			(at 0 0 180)
			(layer "F.Fab")
			(effects
				(font
					(size 1.27 1.27)
				)
			)
		)
		(duplicate_pad_numbers_are_jumpers no)
		(fp_line
			(start 1.239774 1.495298)
			(end -1.239774 1.495298)
			(stroke
				(width 0.1524)
				(type default)
			)
			(layer "F.SilkS")
		)
		(fp_line
			(start 1.239774 -1.495298)
			(end 1.239774 1.495298)
			(stroke
				(width 0.1524)
				(type default)
			)
			(layer "F.SilkS")
		)
		(fp_line
			(start -1.239774 1.495298)
			(end -1.239774 -1.495298)
			(stroke
				(width 0.1524)
				(type default)
			)
			(layer "F.SilkS")
		)
		(fp_line
			(start -1.239774 -1.495298)
			(end 1.239774 -1.495298)
			(stroke
				(width 0.1524)
				(type default)
			)
			(layer "F.SilkS")
		)
		(fp_poly
			(pts
				(xy -1.825498 -1.322832) (xy -2.54381 -0.604266) (xy -1.466342 -0.24511)
			)
			(stroke
				(width 0)
				(type default)
			)
			(fill yes)
			(layer "F.SilkS")
		)
		(fp_line
			(start 0.8001 1.050036)
			(end -0.8001 1.050036)
			(stroke
				(width 0.1)
				(type default)
			)
			(layer "F.Fab")
		)
		(fp_line
			(start 0.8001 -1.050036)
			(end 0.8001 1.050036)
			(stroke
				(width 0.1)
				(type default)
			)
			(layer "F.Fab")
		)
		(fp_line
			(start -0.8001 1.050036)
			(end -0.8001 -1.050036)
			(stroke
				(width 0.1)
				(type default)
			)
			(layer "F.Fab")
		)
		(fp_line
			(start -0.8001 -1.050036)
			(end 0.8001 -1.050036)
			(stroke
				(width 0.1)
				(type default)
			)
			(layer "F.Fab")
		)
		(fp_poly
			(pts
				(xy -2.458974 -0.508) (xy -2.458974 0.508) (xy -1.442974 0)
			)
			(stroke
				(width 0)
				(type default)
			)
			(fill yes)
			(layer "F.Fab")
		)
		(pad "1_2" smd circle
			(at -0.374904 0 270)
			(size 0 0)
			(layers "F.Cu" "F.Mask" "F.Paste")
			(net "P12V_AUX")
		)
		(pad "3" smd rect
			(at -0.499872 0.999998 180)
			(size 0.254 0.7112)
			(layers "F.Cu" "F.Mask" "F.Paste")
			(net "GND")
		)
		(pad "4" smd rect
			(at 0 0.999998 180)
			(size 0.254 0.7112)
			(layers "F.Cu" "F.Mask" "F.Paste")
			(net "P12V_SSD0_CO_ILIMIT")
		)
		(pad "5" smd rect
			(at 0.499872 0.999998 180)
			(size 0.254 0.7112)
			(layers "F.Cu" "F.Mask" "F.Paste")
			(net "P12V_SSD0_CO_MODE")
		)
		(pad "6_7" smd circle
			(at 0.374904 0 90)
			(size 0 0)
			(layers "F.Cu" "F.Mask" "F.Paste")
			(net "P12V_SSD0_R")
		)
		(pad "8" smd rect
			(at 0.499872 -0.999998 180)
			(size 0.254 0.7112)
			(layers "F.Cu" "F.Mask" "F.Paste")
			(net "P12V_SSD0_CO_GATE")
		)
		(pad "9" smd rect
			(at 0 -0.999998 180)
			(size 0.254 0.7112)
			(layers "F.Cu" "F.Mask" "F.Paste")
			(net "P12V_SSD0_CO_EN")
		)
		(pad "10" smd rect
			(at -0.499872 -0.999998 180)
			(size 0.254 0.7112)
			(layers "F.Cu" "F.Mask" "F.Paste")
			(net "P12V_SSD0_CO_DV_DT")
		)
	)
	(footprint ""
		(layer "F.Cu")
		(at 302.14697 -55.63489 90)
		(property "Reference" "PC872"
			(at 0 0 90)
			(layer "F.SilkS")
			(hide yes)
			(effects
				(font
					(size 1.27 1.27)
				)
			)
		)
		(property "Value" ""
			(at 0 0 90)
			(layer "F.Fab")
			(effects
				(font
					(size 1.27 1.27)
				)
			)
		)
		(duplicate_pad_numbers_are_jumpers no)
		(fp_line
			(start 1.524 -0.762)
			(end 1.524 0.762)
			(stroke
				(width 0.1524)
				(type default)
			)
			(layer "F.SilkS")
		)
		(fp_line
			(start -1.524 -0.762)
			(end 1.524 -0.762)
			(stroke
				(width 0.1524)
				(type default)
			)
			(layer "F.SilkS")
		)
		(fp_line
			(start 1.524 0.762)
			(end -1.524 0.762)
			(stroke
				(width 0.1524)
				(type default)
			)
			(layer "F.SilkS")
		)
		(fp_line
			(start -1.524 0.762)
			(end -1.524 -0.762)
			(stroke
				(width 0.1524)
				(type default)
			)
			(layer "F.SilkS")
		)
		(fp_line
			(start 1.1049 -0.724916)
			(end -1.1049 -0.724916)
			(stroke
				(width 0.1)
				(type default)
			)
			(layer "F.Fab")
		)
		(fp_line
			(start -1.1049 -0.724916)
			(end -1.1049 0.724916)
			(stroke
				(width 0.1)
				(type default)
			)
			(layer "F.Fab")
		)
		(fp_line
			(start 1.1049 0.724916)
			(end 1.1049 -0.724916)
			(stroke
				(width 0.1)
				(type default)
			)
			(layer "F.Fab")
		)
		(fp_line
			(start -1.1049 0.724916)
			(end 1.1049 0.724916)
			(stroke
				(width 0.1)
				(type default)
			)
			(layer "F.Fab")
		)
		(pad "1" smd rect
			(at -0.889 0 270)
			(size 1.016 1.27)
			(layers "F.Cu" "F.Mask" "F.Paste")
			(net "P12V_SSD10_R")
		)
		(pad "2" smd rect
			(at 0.889 0 270)
			(size 1.016 1.27)
			(layers "F.Cu" "F.Mask" "F.Paste")
			(net "GND")
		)
	)
	(footprint ""
		(layer "F.Cu")
		(at 328.168 -227.711 90)
		(property "Reference" "R4169"
			(at 0 0 90)
			(layer "F.SilkS")
			(hide yes)
			(effects
				(font
					(size 1.27 1.27)
				)
			)
		)
		(property "Value" ""
			(at 0 0 90)
			(layer "F.Fab")
			(effects
				(font
					(size 1.27 1.27)
				)
			)
		)
		(duplicate_pad_numbers_are_jumpers no)
		(fp_line
			(start 0.7874 -0.4064)
			(end 0.7874 0.4064)
			(stroke
				(width 0.1524)
				(type default)
			)
			(layer "F.SilkS")
		)
		(fp_line
			(start -0.7874 -0.4064)
			(end 0.7874 -0.4064)
			(stroke
				(width 0.1524)
				(type default)
			)
			(layer "F.SilkS")
		)
		(fp_line
			(start 0.7874 0.4064)
			(end -0.7874 0.4064)
			(stroke
				(width 0.1524)
				(type default)
			)
			(layer "F.SilkS")
		)
		(fp_line
			(start -0.7874 0.4064)
			(end -0.7874 -0.4064)
			(stroke
				(width 0.1524)
				(type default)
			)
			(layer "F.SilkS")
		)
		(fp_line
			(start -0.12065 -0.305054)
			(end -0.12065 -0.2794)
			(stroke
				(width 0.1)
				(type default)
			)
			(layer "F.Fab")
		)
		(fp_line
			(start -0.67945 -0.305054)
			(end -0.12065 -0.305054)
			(stroke
				(width 0.1)
				(type default)
			)
			(layer "F.Fab")
		)
		(fp_line
			(start 0.67945 -0.3048)
			(end 0.67945 0.3048)
			(stroke
				(width 0.1)
				(type default)
			)
			(layer "F.Fab")
		)
		(fp_line
			(start 0.12065 -0.3048)
			(end 0.67945 -0.3048)
			(stroke
				(width 0.1)
				(type default)
			)
			(layer "F.Fab")
		)
		(fp_line
			(start 0.12065 -0.2794)
			(end 0.12065 -0.3048)
			(stroke
				(width 0.1)
				(type default)
			)
			(layer "F.Fab")
		)
		(fp_line
			(start -0.12065 -0.2794)
			(end 0.12065 -0.2794)
			(stroke
				(width 0.1)
				(type default)
			)
			(layer "F.Fab")
		)
		(fp_line
			(start 0.120396 0.2794)
			(end -0.12065 0.2794)
			(stroke
				(width 0.1)
				(type default)
			)
			(layer "F.Fab")
		)
		(fp_line
			(start -0.12065 0.2794)
			(end -0.12065 0.3048)
			(stroke
				(width 0.1)
				(type default)
			)
			(layer "F.Fab")
		)
		(fp_line
			(start 0.67945 0.3048)
			(end 0.120396 0.3048)
			(stroke
				(width 0.1)
				(type default)
			)
			(layer "F.Fab")
		)
		(fp_line
			(start 0.120396 0.3048)
			(end 0.120396 0.2794)
			(stroke
				(width 0.1)
				(type default)
			)
			(layer "F.Fab")
		)
		(fp_line
			(start -0.12065 0.3048)
			(end -0.67945 0.3048)
			(stroke
				(width 0.1)
				(type default)
			)
			(layer "F.Fab")
		)
		(fp_line
			(start -0.67945 0.3048)
			(end -0.67945 -0.305054)
			(stroke
				(width 0.1)
				(type default)
			)
			(layer "F.Fab")
		)
		(pad "1" smd circle
			(at -0.40005 0 90)
			(size 0 0)
			(layers "F.Cu" "F.Mask" "F.Paste")
			(net "RST_PEX_SYS_N")
		)
		(pad "2" smd circle
			(at 0.40005 0 90)
			(size 0 0)
			(layers "F.Cu" "F.Mask" "F.Paste")
			(net "RST_PEX_SYS_R_N")
		)
	)
	(footprint ""
		(layer "F.Cu")
		(at 41.069768 -356.244906 90)
		(property "Reference" "C169"
			(at 0 0 90)
			(layer "F.SilkS")
			(hide yes)
			(effects
				(font
					(size 1.27 1.27)
				)
			)
		)
		(property "Value" ""
			(at 0 0 90)
			(layer "F.Fab")
			(effects
				(font
					(size 1.27 1.27)
				)
			)
		)
		(duplicate_pad_numbers_are_jumpers no)
		(fp_line
			(start 0.299974 -0.150114)
			(end 0.299974 0.150114)
			(stroke
				(width 0.1)
				(type default)
			)
			(layer "F.Fab")
		)
		(fp_line
			(start -0.299974 -0.150114)
			(end 0.299974 -0.150114)
			(stroke
				(width 0.1)
				(type default)
			)
			(layer "F.Fab")
		)
		(fp_line
			(start 0.299974 0.150114)
			(end -0.299974 0.150114)
			(stroke
				(width 0.1)
				(type default)
			)
			(layer "F.Fab")
		)
		(fp_line
			(start -0.299974 0.150114)
			(end -0.299974 -0.150114)
			(stroke
				(width 0.1)
				(type default)
			)
			(layer "F.Fab")
		)
		(pad "1" smd rect
			(at -0.2667 0 90)
			(size 0.3048 0.381)
			(layers "F.Cu" "F.Mask" "F.Paste")
			(net "P5E_PEX0_STN7_TX_DP<123>")
		)
		(pad "2" smd rect
			(at 0.2667 0 90)
			(size 0.3048 0.381)
			(layers "F.Cu" "F.Mask" "F.Paste")
			(net "P5E_PEX0_STN7_TX_C_DP<123>")
		)
	)
	(footprint ""
		(layer "F.Cu")
		(at 37.960808 -343.952322 90)
		(property "Reference" "C2168"
			(at 0 0 90)
			(layer "F.SilkS")
			(hide yes)
			(effects
				(font
					(size 1.27 1.27)
				)
			)
		)
		(property "Value" ""
			(at 0 0 90)
			(layer "F.Fab")
			(effects
				(font
					(size 1.27 1.27)
				)
			)
		)
		(duplicate_pad_numbers_are_jumpers no)
		(fp_line
			(start 0.299974 -0.150114)
			(end 0.299974 0.150114)
			(stroke
				(width 0.1)
				(type default)
			)
			(layer "F.Fab")
		)
		(fp_line
			(start -0.299974 -0.150114)
			(end 0.299974 -0.150114)
			(stroke
				(width 0.1)
				(type default)
			)
			(layer "F.Fab")
		)
		(fp_line
			(start 0.299974 0.150114)
			(end -0.299974 0.150114)
			(stroke
				(width 0.1)
				(type default)
			)
			(layer "F.Fab")
		)
		(fp_line
			(start -0.299974 0.150114)
			(end -0.299974 -0.150114)
			(stroke
				(width 0.1)
				(type default)
			)
			(layer "F.Fab")
		)
		(pad "1" smd rect
			(at -0.2667 0 90)
			(size 0.3048 0.381)
			(layers "F.Cu" "F.Mask" "F.Paste")
			(net "P5E_PEX0_STN4_TX_DP<71>")
		)
		(pad "2" smd rect
			(at 0.2667 0 90)
			(size 0.3048 0.381)
			(layers "F.Cu" "F.Mask" "F.Paste")
			(net "P5E_PEX0_STN4_TX_C_DP<71>")
		)
	)
	(footprint ""
		(layer "F.Cu")
		(at 94.216474 -92.929456 -90)
		(property "Reference" "R687"
			(at 0 0 270)
			(layer "F.SilkS")
			(hide yes)
			(effects
				(font
					(size 1.27 1.27)
				)
			)
		)
		(property "Value" ""
			(at 0 0 270)
			(layer "F.Fab")
			(effects
				(font
					(size 1.27 1.27)
				)
			)
		)
		(duplicate_pad_numbers_are_jumpers no)
		(fp_line
			(start -0.7874 0.4064)
			(end -0.7874 -0.4064)
			(stroke
				(width 0.1524)
				(type default)
			)
			(layer "F.SilkS")
		)
		(fp_line
			(start 0.7874 0.4064)
			(end -0.7874 0.4064)
			(stroke
				(width 0.1524)
				(type default)
			)
			(layer "F.SilkS")
		)
		(fp_line
			(start -0.7874 -0.4064)
			(end 0.7874 -0.4064)
			(stroke
				(width 0.1524)
				(type default)
			)
			(layer "F.SilkS")
		)
		(fp_line
			(start 0.7874 -0.4064)
			(end 0.7874 0.4064)
			(stroke
				(width 0.1524)
				(type default)
			)
			(layer "F.SilkS")
		)
		(fp_line
			(start -0.67945 0.3048)
			(end -0.67945 -0.305054)
			(stroke
				(width 0.1)
				(type default)
			)
			(layer "F.Fab")
		)
		(fp_line
			(start -0.12065 0.3048)
			(end -0.67945 0.3048)
			(stroke
				(width 0.1)
				(type default)
			)
			(layer "F.Fab")
		)
		(fp_line
			(start 0.120396 0.3048)
			(end 0.120396 0.2794)
			(stroke
				(width 0.1)
				(type default)
			)
			(layer "F.Fab")
		)
		(fp_line
			(start 0.67945 0.3048)
			(end 0.120396 0.3048)
			(stroke
				(width 0.1)
				(type default)
			)
			(layer "F.Fab")
		)
		(fp_line
			(start -0.12065 0.2794)
			(end -0.12065 0.3048)
			(stroke
				(width 0.1)
				(type default)
			)
			(layer "F.Fab")
		)
		(fp_line
			(start 0.120396 0.2794)
			(end -0.12065 0.2794)
			(stroke
				(width 0.1)
				(type default)
			)
			(layer "F.Fab")
		)
		(fp_line
			(start -0.12065 -0.2794)
			(end 0.12065 -0.2794)
			(stroke
				(width 0.1)
				(type default)
			)
			(layer "F.Fab")
		)
		(fp_line
			(start 0.12065 -0.2794)
			(end 0.12065 -0.3048)
			(stroke
				(width 0.1)
				(type default)
			)
			(layer "F.Fab")
		)
		(fp_line
			(start 0.12065 -0.3048)
			(end 0.67945 -0.3048)
			(stroke
				(width 0.1)
				(type default)
			)
			(layer "F.Fab")
		)
		(fp_line
			(start 0.67945 -0.3048)
			(end 0.67945 0.3048)
			(stroke
				(width 0.1)
				(type default)
			)
			(layer "F.Fab")
		)
		(fp_line
			(start -0.67945 -0.305054)
			(end -0.12065 -0.305054)
			(stroke
				(width 0.1)
				(type default)
			)
			(layer "F.Fab")
		)
		(fp_line
			(start -0.12065 -0.305054)
			(end -0.12065 -0.2794)
			(stroke
				(width 0.1)
				(type default)
			)
			(layer "F.Fab")
		)
		(pad "1" smd circle
			(at -0.40005 0 270)
			(size 0 0)
			(layers "F.Cu" "F.Mask" "F.Paste")
			(net "SMB_BIC_I2C6_MUX_NIC_ADC_R_SCL")
		)
		(pad "2" smd circle
			(at 0.40005 0 270)
			(size 0 0)
			(layers "F.Cu" "F.Mask" "F.Paste")
			(net "SMB_NIC0_ADC_SCL")
		)
	)
	(footprint ""
		(layer "F.Cu")
		(at 87.132922 -356.244906 90)
		(property "Reference" "C154"
			(at 0 0 90)
			(layer "F.SilkS")
			(hide yes)
			(effects
				(font
					(size 1.27 1.27)
				)
			)
		)
		(property "Value" ""
			(at 0 0 90)
			(layer "F.Fab")
			(effects
				(font
					(size 1.27 1.27)
				)
			)
		)
		(duplicate_pad_numbers_are_jumpers no)
		(fp_line
			(start 0.299974 -0.150114)
			(end 0.299974 0.150114)
			(stroke
				(width 0.1)
				(type default)
			)
			(layer "F.Fab")
		)
		(fp_line
			(start -0.299974 -0.150114)
			(end 0.299974 -0.150114)
			(stroke
				(width 0.1)
				(type default)
			)
			(layer "F.Fab")
		)
		(fp_line
			(start 0.299974 0.150114)
			(end -0.299974 0.150114)
			(stroke
				(width 0.1)
				(type default)
			)
			(layer "F.Fab")
		)
		(fp_line
			(start -0.299974 0.150114)
			(end -0.299974 -0.150114)
			(stroke
				(width 0.1)
				(type default)
			)
			(layer "F.Fab")
		)
		(pad "1" smd rect
			(at -0.2667 0 90)
			(size 0.3048 0.381)
			(layers "F.Cu" "F.Mask" "F.Paste")
			(net "P5E_PEX0_STN6_TX_DN<99>")
		)
		(pad "2" smd rect
			(at 0.2667 0 90)
			(size 0.3048 0.381)
			(layers "F.Cu" "F.Mask" "F.Paste")
			(net "P5E_PEX0_STN6_TX_C_DN<99>")
		)
	)
	(footprint ""
		(layer "F.Cu")
		(at 430.172114 -32.848042 90)
		(property "Reference" "PC975"
			(at 0 0 90)
			(layer "F.SilkS")
			(hide yes)
			(effects
				(font
					(size 1.27 1.27)
				)
			)
		)
		(property "Value" ""
			(at 0 0 90)
			(layer "F.Fab")
			(effects
				(font
					(size 1.27 1.27)
				)
			)
		)
		(duplicate_pad_numbers_are_jumpers no)
		(fp_line
			(start 0.7874 -0.4064)
			(end 0.7874 0.4064)
			(stroke
				(width 0.1524)
				(type default)
			)
			(layer "F.SilkS")
		)
		(fp_line
			(start -0.7874 -0.4064)
			(end 0.7874 -0.4064)
			(stroke
				(width 0.1524)
				(type default)
			)
			(layer "F.SilkS")
		)
		(fp_line
			(start 0.7874 0.4064)
			(end -0.7874 0.4064)
			(stroke
				(width 0.1524)
				(type default)
			)
			(layer "F.SilkS")
		)
		(fp_line
			(start -0.7874 0.4064)
			(end -0.7874 -0.4064)
			(stroke
				(width 0.1524)
				(type default)
			)
			(layer "F.SilkS")
		)
		(fp_line
			(start -0.12065 -0.305054)
			(end -0.12065 -0.2794)
			(stroke
				(width 0.1)
				(type default)
			)
			(layer "F.Fab")
		)
		(fp_line
			(start -0.67945 -0.305054)
			(end -0.12065 -0.305054)
			(stroke
				(width 0.1)
				(type default)
			)
			(layer "F.Fab")
		)
		(fp_line
			(start 0.67945 -0.3048)
			(end 0.67945 0.3048)
			(stroke
				(width 0.1)
				(type default)
			)
			(layer "F.Fab")
		)
		(fp_line
			(start 0.12065 -0.3048)
			(end 0.67945 -0.3048)
			(stroke
				(width 0.1)
				(type default)
			)
			(layer "F.Fab")
		)
		(fp_line
			(start 0.12065 -0.2794)
			(end 0.12065 -0.3048)
			(stroke
				(width 0.1)
				(type default)
			)
			(layer "F.Fab")
		)
		(fp_line
			(start -0.12065 -0.2794)
			(end 0.12065 -0.2794)
			(stroke
				(width 0.1)
				(type default)
			)
			(layer "F.Fab")
		)
		(fp_line
			(start 0.120396 0.2794)
			(end -0.12065 0.2794)
			(stroke
				(width 0.1)
				(type default)
			)
			(layer "F.Fab")
		)
		(fp_line
			(start -0.12065 0.2794)
			(end -0.12065 0.3048)
			(stroke
				(width 0.1)
				(type default)
			)
			(layer "F.Fab")
		)
		(fp_line
			(start 0.67945 0.3048)
			(end 0.120396 0.3048)
			(stroke
				(width 0.1)
				(type default)
			)
			(layer "F.Fab")
		)
		(fp_line
			(start 0.120396 0.3048)
			(end 0.120396 0.2794)
			(stroke
				(width 0.1)
				(type default)
			)
			(layer "F.Fab")
		)
		(fp_line
			(start -0.12065 0.3048)
			(end -0.67945 0.3048)
			(stroke
				(width 0.1)
				(type default)
			)
			(layer "F.Fab")
		)
		(fp_line
			(start -0.67945 0.3048)
			(end -0.67945 -0.305054)
			(stroke
				(width 0.1)
				(type default)
			)
			(layer "F.Fab")
		)
		(pad "1" smd circle
			(at -0.40005 0 90)
			(size 0 0)
			(layers "F.Cu" "F.Mask" "F.Paste")
			(net "P3V3_SSD15_CO_GATE")
		)
		(pad "2" smd circle
			(at 0.40005 0 90)
			(size 0 0)
			(layers "F.Cu" "F.Mask" "F.Paste")
			(net "GND")
		)
	)
	(footprint ""
		(layer "F.Cu")
		(at 130.11658 -246.362982)
		(property "Reference" "R6246"
			(at 0 0 0)
			(layer "F.SilkS")
			(hide yes)
			(effects
				(font
					(size 1.27 1.27)
				)
			)
		)
		(property "Value" ""
			(at 0 0 0)
			(layer "F.Fab")
			(effects
				(font
					(size 1.27 1.27)
				)
			)
		)
		(duplicate_pad_numbers_are_jumpers no)
		(fp_line
			(start -0.7874 -0.4064)
			(end 0.7874 -0.4064)
			(stroke
				(width 0.1524)
				(type default)
			)
			(layer "F.SilkS")
		)
		(fp_line
			(start -0.7874 0.4064)
			(end -0.7874 -0.4064)
			(stroke
				(width 0.1524)
				(type default)
			)
			(layer "F.SilkS")
		)
		(fp_line
			(start 0.7874 -0.4064)
			(end 0.7874 0.4064)
			(stroke
				(width 0.1524)
				(type default)
			)
			(layer "F.SilkS")
		)
		(fp_line
			(start 0.7874 0.4064)
			(end -0.7874 0.4064)
			(stroke
				(width 0.1524)
				(type default)
			)
			(layer "F.SilkS")
		)
		(fp_line
			(start -0.67945 -0.305054)
			(end -0.12065 -0.305054)
			(stroke
				(width 0.1)
				(type default)
			)
			(layer "F.Fab")
		)
		(fp_line
			(start -0.67945 0.3048)
			(end -0.67945 -0.305054)
			(stroke
				(width 0.1)
				(type default)
			)
			(layer "F.Fab")
		)
		(fp_line
			(start -0.12065 -0.305054)
			(end -0.12065 -0.2794)
			(stroke
				(width 0.1)
				(type default)
			)
			(layer "F.Fab")
		)
		(fp_line
			(start -0.12065 -0.2794)
			(end 0.12065 -0.2794)
			(stroke
				(width 0.1)
				(type default)
			)
			(layer "F.Fab")
		)
		(fp_line
			(start -0.12065 0.2794)
			(end -0.12065 0.3048)
			(stroke
				(width 0.1)
				(type default)
			)
			(layer "F.Fab")
		)
		(fp_line
			(start -0.12065 0.3048)
			(end -0.67945 0.3048)
			(stroke
				(width 0.1)
				(type default)
			)
			(layer "F.Fab")
		)
		(fp_line
			(start 0.120396 0.2794)
			(end -0.12065 0.2794)
			(stroke
				(width 0.1)
				(type default)
			)
			(layer "F.Fab")
		)
		(fp_line
			(start 0.120396 0.3048)
			(end 0.120396 0.2794)
			(stroke
				(width 0.1)
				(type default)
			)
			(layer "F.Fab")
		)
		(fp_line
			(start 0.12065 -0.3048)
			(end 0.67945 -0.3048)
			(stroke
				(width 0.1)
				(type default)
			)
			(layer "F.Fab")
		)
		(fp_line
			(start 0.12065 -0.2794)
			(end 0.12065 -0.3048)
			(stroke
				(width 0.1)
				(type default)
			)
			(layer "F.Fab")
		)
		(fp_line
			(start 0.67945 -0.3048)
			(end 0.67945 0.3048)
			(stroke
				(width 0.1)
				(type default)
			)
			(layer "F.Fab")
		)
		(fp_line
			(start 0.67945 0.3048)
			(end 0.120396 0.3048)
			(stroke
				(width 0.1)
				(type default)
			)
			(layer "F.Fab")
		)
		(pad "1" smd circle
			(at -0.40005 0)
			(size 0 0)
			(layers "F.Cu" "F.Mask" "F.Paste")
			(net "SMB_BIC_I2C6_MUX_VR_R_SDA")
		)
		(pad "2" smd circle
			(at 0.40005 0)
			(size 0 0)
			(layers "F.Cu" "F.Mask" "F.Paste")
			(net "SMB_HOTSWAP_SDA_R")
		)
	)
	(footprint ""
		(layer "F.Cu")
		(at 92.195904 -103.259128)
		(property "Reference" "C413"
			(at 0 0 0)
			(layer "F.SilkS")
			(hide yes)
			(effects
				(font
					(size 1.27 1.27)
				)
			)
		)
		(property "Value" ""
			(at 0 0 0)
			(layer "F.Fab")
			(effects
				(font
					(size 1.27 1.27)
				)
			)
		)
		(duplicate_pad_numbers_are_jumpers no)
		(fp_line
			(start -0.7874 -0.4064)
			(end 0.7874 -0.4064)
			(stroke
				(width 0.1524)
				(type default)
			)
			(layer "F.SilkS")
		)
		(fp_line
			(start -0.7874 0.4064)
			(end -0.7874 -0.4064)
			(stroke
				(width 0.1524)
				(type default)
			)
			(layer "F.SilkS")
		)
		(fp_line
			(start 0.7874 -0.4064)
			(end 0.7874 0.4064)
			(stroke
				(width 0.1524)
				(type default)
			)
			(layer "F.SilkS")
		)
		(fp_line
			(start 0.7874 0.4064)
			(end -0.7874 0.4064)
			(stroke
				(width 0.1524)
				(type default)
			)
			(layer "F.SilkS")
		)
		(fp_line
			(start -0.67945 -0.305054)
			(end -0.12065 -0.305054)
			(stroke
				(width 0.1)
				(type default)
			)
			(layer "F.Fab")
		)
		(fp_line
			(start -0.67945 0.3048)
			(end -0.67945 -0.305054)
			(stroke
				(width 0.1)
				(type default)
			)
			(layer "F.Fab")
		)
		(fp_line
			(start -0.12065 -0.305054)
			(end -0.12065 -0.2794)
			(stroke
				(width 0.1)
				(type default)
			)
			(layer "F.Fab")
		)
		(fp_line
			(start -0.12065 -0.2794)
			(end 0.12065 -0.2794)
			(stroke
				(width 0.1)
				(type default)
			)
			(layer "F.Fab")
		)
		(fp_line
			(start -0.12065 0.2794)
			(end -0.12065 0.3048)
			(stroke
				(width 0.1)
				(type default)
			)
			(layer "F.Fab")
		)
		(fp_line
			(start -0.12065 0.3048)
			(end -0.67945 0.3048)
			(stroke
				(width 0.1)
				(type default)
			)
			(layer "F.Fab")
		)
		(fp_line
			(start 0.120396 0.2794)
			(end -0.12065 0.2794)
			(stroke
				(width 0.1)
				(type default)
			)
			(layer "F.Fab")
		)
		(fp_line
			(start 0.120396 0.3048)
			(end 0.120396 0.2794)
			(stroke
				(width 0.1)
				(type default)
			)
			(layer "F.Fab")
		)
		(fp_line
			(start 0.12065 -0.3048)
			(end 0.67945 -0.3048)
			(stroke
				(width 0.1)
				(type default)
			)
			(layer "F.Fab")
		)
		(fp_line
			(start 0.12065 -0.2794)
			(end 0.12065 -0.3048)
			(stroke
				(width 0.1)
				(type default)
			)
			(layer "F.Fab")
		)
		(fp_line
			(start 0.67945 -0.3048)
			(end 0.67945 0.3048)
			(stroke
				(width 0.1)
				(type default)
			)
			(layer "F.Fab")
		)
		(fp_line
			(start 0.67945 0.3048)
			(end 0.120396 0.3048)
			(stroke
				(width 0.1)
				(type default)
			)
			(layer "F.Fab")
		)
		(pad "1" smd circle
			(at -0.40005 0)
			(size 0 0)
			(layers "F.Cu" "F.Mask" "F.Paste")
			(net "P12V_NIC1_R")
		)
		(pad "2" smd circle
			(at 0.40005 0)
			(size 0 0)
			(layers "F.Cu" "F.Mask" "F.Paste")
			(net "GND")
		)
	)
	(footprint ""
		(layer "F.Cu")
		(at 245.16588 -308.162452 90)
		(property "Reference" "PC262"
			(at 0 0 90)
			(layer "F.SilkS")
			(hide yes)
			(effects
				(font
					(size 1.27 1.27)
				)
			)
		)
		(property "Value" ""
			(at 0 0 90)
			(layer "F.Fab")
			(effects
				(font
					(size 1.27 1.27)
				)
			)
		)
		(duplicate_pad_numbers_are_jumpers no)
		(fp_line
			(start 0.7874 -0.4064)
			(end 0.7874 0.4064)
			(stroke
				(width 0.1524)
				(type default)
			)
			(layer "F.SilkS")
		)
		(fp_line
			(start -0.7874 -0.4064)
			(end 0.7874 -0.4064)
			(stroke
				(width 0.1524)
				(type default)
			)
			(layer "F.SilkS")
		)
		(fp_line
			(start 0.7874 0.4064)
			(end -0.7874 0.4064)
			(stroke
				(width 0.1524)
				(type default)
			)
			(layer "F.SilkS")
		)
		(fp_line
			(start -0.7874 0.4064)
			(end -0.7874 -0.4064)
			(stroke
				(width 0.1524)
				(type default)
			)
			(layer "F.SilkS")
		)
		(fp_line
			(start -0.12065 -0.305054)
			(end -0.12065 -0.2794)
			(stroke
				(width 0.1)
				(type default)
			)
			(layer "F.Fab")
		)
		(fp_line
			(start -0.67945 -0.305054)
			(end -0.12065 -0.305054)
			(stroke
				(width 0.1)
				(type default)
			)
			(layer "F.Fab")
		)
		(fp_line
			(start 0.67945 -0.3048)
			(end 0.67945 0.3048)
			(stroke
				(width 0.1)
				(type default)
			)
			(layer "F.Fab")
		)
		(fp_line
			(start 0.12065 -0.3048)
			(end 0.67945 -0.3048)
			(stroke
				(width 0.1)
				(type default)
			)
			(layer "F.Fab")
		)
		(fp_line
			(start 0.12065 -0.2794)
			(end 0.12065 -0.3048)
			(stroke
				(width 0.1)
				(type default)
			)
			(layer "F.Fab")
		)
		(fp_line
			(start -0.12065 -0.2794)
			(end 0.12065 -0.2794)
			(stroke
				(width 0.1)
				(type default)
			)
			(layer "F.Fab")
		)
		(fp_line
			(start 0.120396 0.2794)
			(end -0.12065 0.2794)
			(stroke
				(width 0.1)
				(type default)
			)
			(layer "F.Fab")
		)
		(fp_line
			(start -0.12065 0.2794)
			(end -0.12065 0.3048)
			(stroke
				(width 0.1)
				(type default)
			)
			(layer "F.Fab")
		)
		(fp_line
			(start 0.67945 0.3048)
			(end 0.120396 0.3048)
			(stroke
				(width 0.1)
				(type default)
			)
			(layer "F.Fab")
		)
		(fp_line
			(start 0.120396 0.3048)
			(end 0.120396 0.2794)
			(stroke
				(width 0.1)
				(type default)
			)
			(layer "F.Fab")
		)
		(fp_line
			(start -0.12065 0.3048)
			(end -0.67945 0.3048)
			(stroke
				(width 0.1)
				(type default)
			)
			(layer "F.Fab")
		)
		(fp_line
			(start -0.67945 0.3048)
			(end -0.67945 -0.305054)
			(stroke
				(width 0.1)
				(type default)
			)
			(layer "F.Fab")
		)
		(pad "1" smd circle
			(at -0.40005 0 90)
			(size 0 0)
			(layers "F.Cu" "F.Mask" "F.Paste")
			(net "P1V25_PEX2_REF")
		)
		(pad "2" smd circle
			(at 0.40005 0 90)
			(size 0 0)
			(layers "F.Cu" "F.Mask" "F.Paste")
			(net "SH_P1V25_PEX2_FB_N")
		)
	)
	(footprint ""
		(layer "F.Cu")
		(at 379.201934 -32.849312 90)
		(property "Reference" "R5698"
			(at 0 0 90)
			(layer "F.SilkS")
			(hide yes)
			(effects
				(font
					(size 1.27 1.27)
				)
			)
		)
		(property "Value" ""
			(at 0 0 90)
			(layer "F.Fab")
			(effects
				(font
					(size 1.27 1.27)
				)
			)
		)
		(duplicate_pad_numbers_are_jumpers no)
		(fp_line
			(start 0.7874 -0.4064)
			(end 0.7874 0.4064)
			(stroke
				(width 0.1524)
				(type default)
			)
			(layer "F.SilkS")
		)
		(fp_line
			(start -0.7874 -0.4064)
			(end 0.7874 -0.4064)
			(stroke
				(width 0.1524)
				(type default)
			)
			(layer "F.SilkS")
		)
		(fp_line
			(start 0.7874 0.4064)
			(end -0.7874 0.4064)
			(stroke
				(width 0.1524)
				(type default)
			)
			(layer "F.SilkS")
		)
		(fp_line
			(start -0.7874 0.4064)
			(end -0.7874 -0.4064)
			(stroke
				(width 0.1524)
				(type default)
			)
			(layer "F.SilkS")
		)
		(fp_line
			(start -0.12065 -0.305054)
			(end -0.12065 -0.2794)
			(stroke
				(width 0.1)
				(type default)
			)
			(layer "F.Fab")
		)
		(fp_line
			(start -0.67945 -0.305054)
			(end -0.12065 -0.305054)
			(stroke
				(width 0.1)
				(type default)
			)
			(layer "F.Fab")
		)
		(fp_line
			(start 0.67945 -0.3048)
			(end 0.67945 0.3048)
			(stroke
				(width 0.1)
				(type default)
			)
			(layer "F.Fab")
		)
		(fp_line
			(start 0.12065 -0.3048)
			(end 0.67945 -0.3048)
			(stroke
				(width 0.1)
				(type default)
			)
			(layer "F.Fab")
		)
		(fp_line
			(start 0.12065 -0.2794)
			(end 0.12065 -0.3048)
			(stroke
				(width 0.1)
				(type default)
			)
			(layer "F.Fab")
		)
		(fp_line
			(start -0.12065 -0.2794)
			(end 0.12065 -0.2794)
			(stroke
				(width 0.1)
				(type default)
			)
			(layer "F.Fab")
		)
		(fp_line
			(start 0.120396 0.2794)
			(end -0.12065 0.2794)
			(stroke
				(width 0.1)
				(type default)
			)
			(layer "F.Fab")
		)
		(fp_line
			(start -0.12065 0.2794)
			(end -0.12065 0.3048)
			(stroke
				(width 0.1)
				(type default)
			)
			(layer "F.Fab")
		)
		(fp_line
			(start 0.67945 0.3048)
			(end 0.120396 0.3048)
			(stroke
				(width 0.1)
				(type default)
			)
			(layer "F.Fab")
		)
		(fp_line
			(start 0.120396 0.3048)
			(end 0.120396 0.2794)
			(stroke
				(width 0.1)
				(type default)
			)
			(layer "F.Fab")
		)
		(fp_line
			(start -0.12065 0.3048)
			(end -0.67945 0.3048)
			(stroke
				(width 0.1)
				(type default)
			)
			(layer "F.Fab")
		)
		(fp_line
			(start -0.67945 0.3048)
			(end -0.67945 -0.305054)
			(stroke
				(width 0.1)
				(type default)
			)
			(layer "F.Fab")
		)
		(pad "1" smd circle
			(at -0.40005 0 90)
			(size 0 0)
			(layers "F.Cu" "F.Mask" "F.Paste")
			(net "RST_SMB_SSD13_ISO_R_N")
		)
		(pad "2" smd circle
			(at 0.40005 0 90)
			(size 0 0)
			(layers "F.Cu" "F.Mask" "F.Paste")
			(net "RST_SMB_SSD13_ISO_N")
		)
	)
	(footprint ""
		(layer "F.Cu")
		(at 271.480534 -102.888796)
		(property "Reference" "C481"
			(at 0 0 0)
			(layer "F.SilkS")
			(hide yes)
			(effects
				(font
					(size 1.27 1.27)
				)
			)
		)
		(property "Value" ""
			(at 0 0 0)
			(layer "F.Fab")
			(effects
				(font
					(size 1.27 1.27)
				)
			)
		)
		(duplicate_pad_numbers_are_jumpers no)
		(fp_line
			(start -0.299974 -0.150114)
			(end 0.299974 -0.150114)
			(stroke
				(width 0.1)
				(type default)
			)
			(layer "F.Fab")
		)
		(fp_line
			(start -0.299974 0.150114)
			(end -0.299974 -0.150114)
			(stroke
				(width 0.1)
				(type default)
			)
			(layer "F.Fab")
		)
		(fp_line
			(start 0.299974 -0.150114)
			(end 0.299974 0.150114)
			(stroke
				(width 0.1)
				(type default)
			)
			(layer "F.Fab")
		)
		(fp_line
			(start 0.299974 0.150114)
			(end -0.299974 0.150114)
			(stroke
				(width 0.1)
				(type default)
			)
			(layer "F.Fab")
		)
		(pad "1" smd rect
			(at -0.2667 0)
			(size 0.3048 0.381)
			(layers "F.Cu" "F.Mask" "F.Paste")
			(net "P5E_PEX2_STN1_TX_DP<18>")
		)
		(pad "2" smd rect
			(at 0.2667 0)
			(size 0.3048 0.381)
			(layers "F.Cu" "F.Mask" "F.Paste")
			(net "P5E_PEX2_STN1_TX_C_DP<18>")
		)
	)
	(footprint ""
		(layer "F.Cu")
		(at 56.155336 -376.29592 90)
		(property "Reference" "C4013"
			(at 0 0 90)
			(layer "F.SilkS")
			(hide yes)
			(effects
				(font
					(size 1.27 1.27)
				)
			)
		)
		(property "Value" ""
			(at 0 0 90)
			(layer "F.Fab")
			(effects
				(font
					(size 1.27 1.27)
				)
			)
		)
		(duplicate_pad_numbers_are_jumpers no)
		(fp_line
			(start 0.7874 -0.4064)
			(end 0.7874 0.4064)
			(stroke
				(width 0.1524)
				(type default)
			)
			(layer "F.SilkS")
		)
		(fp_line
			(start -0.7874 -0.4064)
			(end 0.7874 -0.4064)
			(stroke
				(width 0.1524)
				(type default)
			)
			(layer "F.SilkS")
		)
		(fp_line
			(start 0.7874 0.4064)
			(end -0.7874 0.4064)
			(stroke
				(width 0.1524)
				(type default)
			)
			(layer "F.SilkS")
		)
		(fp_line
			(start -0.7874 0.4064)
			(end -0.7874 -0.4064)
			(stroke
				(width 0.1524)
				(type default)
			)
			(layer "F.SilkS")
		)
		(fp_line
			(start -0.12065 -0.305054)
			(end -0.12065 -0.2794)
			(stroke
				(width 0.1)
				(type default)
			)
			(layer "F.Fab")
		)
		(fp_line
			(start -0.67945 -0.305054)
			(end -0.12065 -0.305054)
			(stroke
				(width 0.1)
				(type default)
			)
			(layer "F.Fab")
		)
		(fp_line
			(start 0.67945 -0.3048)
			(end 0.67945 0.3048)
			(stroke
				(width 0.1)
				(type default)
			)
			(layer "F.Fab")
		)
		(fp_line
			(start 0.12065 -0.3048)
			(end 0.67945 -0.3048)
			(stroke
				(width 0.1)
				(type default)
			)
			(layer "F.Fab")
		)
		(fp_line
			(start 0.12065 -0.2794)
			(end 0.12065 -0.3048)
			(stroke
				(width 0.1)
				(type default)
			)
			(layer "F.Fab")
		)
		(fp_line
			(start -0.12065 -0.2794)
			(end 0.12065 -0.2794)
			(stroke
				(width 0.1)
				(type default)
			)
			(layer "F.Fab")
		)
		(fp_line
			(start 0.120396 0.2794)
			(end -0.12065 0.2794)
			(stroke
				(width 0.1)
				(type default)
			)
			(layer "F.Fab")
		)
		(fp_line
			(start -0.12065 0.2794)
			(end -0.12065 0.3048)
			(stroke
				(width 0.1)
				(type default)
			)
			(layer "F.Fab")
		)
		(fp_line
			(start 0.67945 0.3048)
			(end 0.120396 0.3048)
			(stroke
				(width 0.1)
				(type default)
			)
			(layer "F.Fab")
		)
		(fp_line
			(start 0.120396 0.3048)
			(end 0.120396 0.2794)
			(stroke
				(width 0.1)
				(type default)
			)
			(layer "F.Fab")
		)
		(fp_line
			(start -0.12065 0.3048)
			(end -0.67945 0.3048)
			(stroke
				(width 0.1)
				(type default)
			)
			(layer "F.Fab")
		)
		(fp_line
			(start -0.67945 0.3048)
			(end -0.67945 -0.305054)
			(stroke
				(width 0.1)
				(type default)
			)
			(layer "F.Fab")
		)
		(pad "1" smd circle
			(at -0.40005 0 90)
			(size 0 0)
			(layers "F.Cu" "F.Mask" "F.Paste")
			(net "GND")
		)
		(pad "2" smd circle
			(at 0.40005 0 90)
			(size 0 0)
			(layers "F.Cu" "F.Mask" "F.Paste")
			(net "GPU_BASE_PWR_GD")
		)
	)
	(footprint ""
		(layer "F.Cu")
		(at 361.188 -175.006 180)
		(property "Reference" "R4709"
			(at 0 0 180)
			(layer "F.SilkS")
			(hide yes)
			(effects
				(font
					(size 1.27 1.27)
				)
			)
		)
		(property "Value" ""
			(at 0 0 180)
			(layer "F.Fab")
			(effects
				(font
					(size 1.27 1.27)
				)
			)
		)
		(duplicate_pad_numbers_are_jumpers no)
		(fp_line
			(start 0.7874 0.4064)
			(end -0.7874 0.4064)
			(stroke
				(width 0.1524)
				(type default)
			)
			(layer "F.SilkS")
		)
		(fp_line
			(start 0.7874 -0.4064)
			(end 0.7874 0.4064)
			(stroke
				(width 0.1524)
				(type default)
			)
			(layer "F.SilkS")
		)
		(fp_line
			(start -0.7874 0.4064)
			(end -0.7874 -0.4064)
			(stroke
				(width 0.1524)
				(type default)
			)
			(layer "F.SilkS")
		)
		(fp_line
			(start -0.7874 -0.4064)
			(end 0.7874 -0.4064)
			(stroke
				(width 0.1524)
				(type default)
			)
			(layer "F.SilkS")
		)
		(fp_line
			(start 0.67945 0.3048)
			(end 0.120396 0.3048)
			(stroke
				(width 0.1)
				(type default)
			)
			(layer "F.Fab")
		)
		(fp_line
			(start 0.67945 -0.3048)
			(end 0.67945 0.3048)
			(stroke
				(width 0.1)
				(type default)
			)
			(layer "F.Fab")
		)
		(fp_line
			(start 0.12065 -0.2794)
			(end 0.12065 -0.3048)
			(stroke
				(width 0.1)
				(type default)
			)
			(layer "F.Fab")
		)
		(fp_line
			(start 0.12065 -0.3048)
			(end 0.67945 -0.3048)
			(stroke
				(width 0.1)
				(type default)
			)
			(layer "F.Fab")
		)
		(fp_line
			(start 0.120396 0.3048)
			(end 0.120396 0.2794)
			(stroke
				(width 0.1)
				(type default)
			)
			(layer "F.Fab")
		)
		(fp_line
			(start 0.120396 0.2794)
			(end -0.12065 0.2794)
			(stroke
				(width 0.1)
				(type default)
			)
			(layer "F.Fab")
		)
		(fp_line
			(start -0.12065 0.3048)
			(end -0.67945 0.3048)
			(stroke
				(width 0.1)
				(type default)
			)
			(layer "F.Fab")
		)
		(fp_line
			(start -0.12065 0.2794)
			(end -0.12065 0.3048)
			(stroke
				(width 0.1)
				(type default)
			)
			(layer "F.Fab")
		)
		(fp_line
			(start -0.12065 -0.2794)
			(end 0.12065 -0.2794)
			(stroke
				(width 0.1)
				(type default)
			)
			(layer "F.Fab")
		)
		(fp_line
			(start -0.12065 -0.305054)
			(end -0.12065 -0.2794)
			(stroke
				(width 0.1)
				(type default)
			)
			(layer "F.Fab")
		)
		(fp_line
			(start -0.67945 0.3048)
			(end -0.67945 -0.305054)
			(stroke
				(width 0.1)
				(type default)
			)
			(layer "F.Fab")
		)
		(fp_line
			(start -0.67945 -0.305054)
			(end -0.12065 -0.305054)
			(stroke
				(width 0.1)
				(type default)
			)
			(layer "F.Fab")
		)
		(pad "1" smd circle
			(at -0.40005 0 180)
			(size 0 0)
			(layers "F.Cu" "F.Mask" "F.Paste")
			(net "PRSNT_SSD7_FPGA_PCA9555_N")
		)
		(pad "2" smd circle
			(at 0.40005 0 180)
			(size 0 0)
			(layers "F.Cu" "F.Mask" "F.Paste")
			(net "PRSNT_SSD7_FPGA_R_N")
		)
	)
	(footprint ""
		(layer "F.Cu")
		(at 179.98186 -184.9247)
		(property "Reference" "R6657"
			(at 0 0 0)
			(layer "F.SilkS")
			(hide yes)
			(effects
				(font
					(size 1.27 1.27)
				)
			)
		)
		(property "Value" ""
			(at 0 0 0)
			(layer "F.Fab")
			(effects
				(font
					(size 1.27 1.27)
				)
			)
		)
		(duplicate_pad_numbers_are_jumpers no)
		(fp_line
			(start -0.7874 -0.4064)
			(end 0.7874 -0.4064)
			(stroke
				(width 0.1524)
				(type default)
			)
			(layer "F.SilkS")
		)
		(fp_line
			(start -0.7874 0.4064)
			(end -0.7874 -0.4064)
			(stroke
				(width 0.1524)
				(type default)
			)
			(layer "F.SilkS")
		)
		(fp_line
			(start 0.7874 -0.4064)
			(end 0.7874 0.4064)
			(stroke
				(width 0.1524)
				(type default)
			)
			(layer "F.SilkS")
		)
		(fp_line
			(start 0.7874 0.4064)
			(end -0.7874 0.4064)
			(stroke
				(width 0.1524)
				(type default)
			)
			(layer "F.SilkS")
		)
		(fp_line
			(start -0.67945 -0.305054)
			(end -0.12065 -0.305054)
			(stroke
				(width 0.1)
				(type default)
			)
			(layer "F.Fab")
		)
		(fp_line
			(start -0.67945 0.3048)
			(end -0.67945 -0.305054)
			(stroke
				(width 0.1)
				(type default)
			)
			(layer "F.Fab")
		)
		(fp_line
			(start -0.12065 -0.305054)
			(end -0.12065 -0.2794)
			(stroke
				(width 0.1)
				(type default)
			)
			(layer "F.Fab")
		)
		(fp_line
			(start -0.12065 -0.2794)
			(end 0.12065 -0.2794)
			(stroke
				(width 0.1)
				(type default)
			)
			(layer "F.Fab")
		)
		(fp_line
			(start -0.12065 0.2794)
			(end -0.12065 0.3048)
			(stroke
				(width 0.1)
				(type default)
			)
			(layer "F.Fab")
		)
		(fp_line
			(start -0.12065 0.3048)
			(end -0.67945 0.3048)
			(stroke
				(width 0.1)
				(type default)
			)
			(layer "F.Fab")
		)
		(fp_line
			(start 0.120396 0.2794)
			(end -0.12065 0.2794)
			(stroke
				(width 0.1)
				(type default)
			)
			(layer "F.Fab")
		)
		(fp_line
			(start 0.120396 0.3048)
			(end 0.120396 0.2794)
			(stroke
				(width 0.1)
				(type default)
			)
			(layer "F.Fab")
		)
		(fp_line
			(start 0.12065 -0.3048)
			(end 0.67945 -0.3048)
			(stroke
				(width 0.1)
				(type default)
			)
			(layer "F.Fab")
		)
		(fp_line
			(start 0.12065 -0.2794)
			(end 0.12065 -0.3048)
			(stroke
				(width 0.1)
				(type default)
			)
			(layer "F.Fab")
		)
		(fp_line
			(start 0.67945 -0.3048)
			(end 0.67945 0.3048)
			(stroke
				(width 0.1)
				(type default)
			)
			(layer "F.Fab")
		)
		(fp_line
			(start 0.67945 0.3048)
			(end 0.120396 0.3048)
			(stroke
				(width 0.1)
				(type default)
			)
			(layer "F.Fab")
		)
		(pad "1" smd circle
			(at -0.40005 0)
			(size 0 0)
			(layers "F.Cu" "F.Mask" "F.Paste")
			(net "SPI_BIC1_LS01_EN_N")
		)
		(pad "2" smd circle
			(at 0.40005 0)
			(size 0 0)
			(layers "F.Cu" "F.Mask" "F.Paste")
			(net "P1V8_PEX")
		)
	)
	(footprint ""
		(layer "F.Cu")
		(at 231.844596 -276.519386)
		(property "Reference" "R785"
			(at 0 0 0)
			(layer "F.SilkS")
			(hide yes)
			(effects
				(font
					(size 1.27 1.27)
				)
			)
		)
		(property "Value" ""
			(at 0 0 0)
			(layer "F.Fab")
			(effects
				(font
					(size 1.27 1.27)
				)
			)
		)
		(duplicate_pad_numbers_are_jumpers no)
		(fp_line
			(start -0.7874 -0.4064)
			(end 0.7874 -0.4064)
			(stroke
				(width 0.1524)
				(type default)
			)
			(layer "F.SilkS")
		)
		(fp_line
			(start -0.7874 0.4064)
			(end -0.7874 -0.4064)
			(stroke
				(width 0.1524)
				(type default)
			)
			(layer "F.SilkS")
		)
		(fp_line
			(start 0.7874 -0.4064)
			(end 0.7874 0.4064)
			(stroke
				(width 0.1524)
				(type default)
			)
			(layer "F.SilkS")
		)
		(fp_line
			(start 0.7874 0.4064)
			(end -0.7874 0.4064)
			(stroke
				(width 0.1524)
				(type default)
			)
			(layer "F.SilkS")
		)
		(fp_line
			(start -0.67945 -0.305054)
			(end -0.12065 -0.305054)
			(stroke
				(width 0.1)
				(type default)
			)
			(layer "F.Fab")
		)
		(fp_line
			(start -0.67945 0.3048)
			(end -0.67945 -0.305054)
			(stroke
				(width 0.1)
				(type default)
			)
			(layer "F.Fab")
		)
		(fp_line
			(start -0.12065 -0.305054)
			(end -0.12065 -0.2794)
			(stroke
				(width 0.1)
				(type default)
			)
			(layer "F.Fab")
		)
		(fp_line
			(start -0.12065 -0.2794)
			(end 0.12065 -0.2794)
			(stroke
				(width 0.1)
				(type default)
			)
			(layer "F.Fab")
		)
		(fp_line
			(start -0.12065 0.2794)
			(end -0.12065 0.3048)
			(stroke
				(width 0.1)
				(type default)
			)
			(layer "F.Fab")
		)
		(fp_line
			(start -0.12065 0.3048)
			(end -0.67945 0.3048)
			(stroke
				(width 0.1)
				(type default)
			)
			(layer "F.Fab")
		)
		(fp_line
			(start 0.120396 0.2794)
			(end -0.12065 0.2794)
			(stroke
				(width 0.1)
				(type default)
			)
			(layer "F.Fab")
		)
		(fp_line
			(start 0.120396 0.3048)
			(end 0.120396 0.2794)
			(stroke
				(width 0.1)
				(type default)
			)
			(layer "F.Fab")
		)
		(fp_line
			(start 0.12065 -0.3048)
			(end 0.67945 -0.3048)
			(stroke
				(width 0.1)
				(type default)
			)
			(layer "F.Fab")
		)
		(fp_line
			(start 0.12065 -0.2794)
			(end 0.12065 -0.3048)
			(stroke
				(width 0.1)
				(type default)
			)
			(layer "F.Fab")
		)
		(fp_line
			(start 0.67945 -0.3048)
			(end 0.67945 0.3048)
			(stroke
				(width 0.1)
				(type default)
			)
			(layer "F.Fab")
		)
		(fp_line
			(start 0.67945 0.3048)
			(end 0.120396 0.3048)
			(stroke
				(width 0.1)
				(type default)
			)
			(layer "F.Fab")
		)
		(pad "1" smd circle
			(at -0.40005 0)
			(size 0 0)
			(layers "F.Cu" "F.Mask" "F.Paste")
			(net "PEX1_P1V25_ADC_A0")
		)
		(pad "2" smd circle
			(at 0.40005 0)
			(size 0 0)
			(layers "F.Cu" "F.Mask" "F.Paste")
			(net "GND")
		)
	)
	(footprint ""
		(layer "F.Cu")
		(at 265.823954 -238.454184)
		(property "Reference" "ME8"
			(at -0.0762 -7.441438 0)
			(unlocked yes)
			(layer "F.SilkS")
			(effects
				(font
					(size 0.7874 0.5842)
					(thickness 0.1524)
				)
				(justify left)
			)
		)
		(property "Value" ""
			(at 0 0 0)
			(layer "F.Fab")
			(effects
				(font
					(size 1.27 1.27)
				)
			)
		)
		(duplicate_pad_numbers_are_jumpers no)
		(fp_line
			(start 0 -6.500114)
			(end 0 -4.976114)
			(stroke
				(width 0.1524)
				(type default)
			)
			(layer "F.SilkS")
		)
		(fp_line
			(start 0 -1.524)
			(end 0 0)
			(stroke
				(width 0.1524)
				(type default)
			)
			(layer "F.SilkS")
		)
		(fp_line
			(start 0 0)
			(end 1.524 0)
			(stroke
				(width 0.1524)
				(type default)
			)
			(layer "F.SilkS")
		)
		(fp_line
			(start 1.524 -6.500114)
			(end 0 -6.500114)
			(stroke
				(width 0.1524)
				(type default)
			)
			(layer "F.SilkS")
		)
		(fp_line
			(start 37.976048 -6.500114)
			(end 39.500048 -6.500114)
			(stroke
				(width 0.1524)
				(type default)
			)
			(layer "F.SilkS")
		)
		(fp_line
			(start 39.500048 -6.500114)
			(end 39.500048 -4.976114)
			(stroke
				(width 0.1524)
				(type default)
			)
			(layer "F.SilkS")
		)
		(fp_line
			(start 39.500048 -1.524)
			(end 39.500048 0)
			(stroke
				(width 0.1524)
				(type default)
			)
			(layer "F.SilkS")
		)
		(fp_line
			(start 39.500048 0)
			(end 37.976048 0)
			(stroke
				(width 0.1524)
				(type default)
			)
			(layer "F.SilkS")
		)
		(fp_text user "Rework version"
			(at 6.656324 -3.15468 0)
			(unlocked yes)
			(layer "F.SilkS")
			(effects
				(font
					(size 1.905 1.4224)
					(thickness 0.1524)
				)
				(justify left)
			)
		)
	)
	(footprint ""
		(layer "F.Cu")
		(at 89.327482 -343.952322 90)
		(property "Reference" "C101"
			(at 0 0 90)
			(layer "F.SilkS")
			(hide yes)
			(effects
				(font
					(size 1.27 1.27)
				)
			)
		)
		(property "Value" ""
			(at 0 0 90)
			(layer "F.Fab")
			(effects
				(font
					(size 1.27 1.27)
				)
			)
		)
		(duplicate_pad_numbers_are_jumpers no)
		(fp_line
			(start 0.299974 -0.150114)
			(end 0.299974 0.150114)
			(stroke
				(width 0.1)
				(type default)
			)
			(layer "F.Fab")
		)
		(fp_line
			(start -0.299974 -0.150114)
			(end 0.299974 -0.150114)
			(stroke
				(width 0.1)
				(type default)
			)
			(layer "F.Fab")
		)
		(fp_line
			(start 0.299974 0.150114)
			(end -0.299974 0.150114)
			(stroke
				(width 0.1)
				(type default)
			)
			(layer "F.Fab")
		)
		(fp_line
			(start -0.299974 0.150114)
			(end -0.299974 -0.150114)
			(stroke
				(width 0.1)
				(type default)
			)
			(layer "F.Fab")
		)
		(pad "1" smd rect
			(at -0.2667 0 90)
			(size 0.3048 0.381)
			(layers "F.Cu" "F.Mask" "F.Paste")
			(net "P5E_PEX0_STN5_TX_DP<93>")
		)
		(pad "2" smd rect
			(at 0.2667 0 90)
			(size 0.3048 0.381)
			(layers "F.Cu" "F.Mask" "F.Paste")
			(net "P5E_PEX0_STN5_TX_C_DP<93>")
		)
	)
	(footprint ""
		(layer "F.Cu")
		(at 57.656222 -61.487812 180)
		(property "Reference" "R5846"
			(at 0 0 180)
			(layer "F.SilkS")
			(hide yes)
			(effects
				(font
					(size 1.27 1.27)
				)
			)
		)
		(property "Value" ""
			(at 0 0 180)
			(layer "F.Fab")
			(effects
				(font
					(size 1.27 1.27)
				)
			)
		)
		(duplicate_pad_numbers_are_jumpers no)
		(fp_line
			(start 0.7874 0.4064)
			(end -0.7874 0.4064)
			(stroke
				(width 0.1524)
				(type default)
			)
			(layer "F.SilkS")
		)
		(fp_line
			(start 0.7874 -0.4064)
			(end 0.7874 0.4064)
			(stroke
				(width 0.1524)
				(type default)
			)
			(layer "F.SilkS")
		)
		(fp_line
			(start -0.7874 0.4064)
			(end -0.7874 -0.4064)
			(stroke
				(width 0.1524)
				(type default)
			)
			(layer "F.SilkS")
		)
		(fp_line
			(start -0.7874 -0.4064)
			(end 0.7874 -0.4064)
			(stroke
				(width 0.1524)
				(type default)
			)
			(layer "F.SilkS")
		)
		(fp_line
			(start 0.67945 0.3048)
			(end 0.120396 0.3048)
			(stroke
				(width 0.1)
				(type default)
			)
			(layer "F.Fab")
		)
		(fp_line
			(start 0.67945 -0.3048)
			(end 0.67945 0.3048)
			(stroke
				(width 0.1)
				(type default)
			)
			(layer "F.Fab")
		)
		(fp_line
			(start 0.12065 -0.2794)
			(end 0.12065 -0.3048)
			(stroke
				(width 0.1)
				(type default)
			)
			(layer "F.Fab")
		)
		(fp_line
			(start 0.12065 -0.3048)
			(end 0.67945 -0.3048)
			(stroke
				(width 0.1)
				(type default)
			)
			(layer "F.Fab")
		)
		(fp_line
			(start 0.120396 0.3048)
			(end 0.120396 0.2794)
			(stroke
				(width 0.1)
				(type default)
			)
			(layer "F.Fab")
		)
		(fp_line
			(start 0.120396 0.2794)
			(end -0.12065 0.2794)
			(stroke
				(width 0.1)
				(type default)
			)
			(layer "F.Fab")
		)
		(fp_line
			(start -0.12065 0.3048)
			(end -0.67945 0.3048)
			(stroke
				(width 0.1)
				(type default)
			)
			(layer "F.Fab")
		)
		(fp_line
			(start -0.12065 0.2794)
			(end -0.12065 0.3048)
			(stroke
				(width 0.1)
				(type default)
			)
			(layer "F.Fab")
		)
		(fp_line
			(start -0.12065 -0.2794)
			(end 0.12065 -0.2794)
			(stroke
				(width 0.1)
				(type default)
			)
			(layer "F.Fab")
		)
		(fp_line
			(start -0.12065 -0.305054)
			(end -0.12065 -0.2794)
			(stroke
				(width 0.1)
				(type default)
			)
			(layer "F.Fab")
		)
		(fp_line
			(start -0.67945 0.3048)
			(end -0.67945 -0.305054)
			(stroke
				(width 0.1)
				(type default)
			)
			(layer "F.Fab")
		)
		(fp_line
			(start -0.67945 -0.305054)
			(end -0.12065 -0.305054)
			(stroke
				(width 0.1)
				(type default)
			)
			(layer "F.Fab")
		)
		(pad "1" smd circle
			(at -0.40005 0 180)
			(size 0 0)
			(layers "F.Cu" "F.Mask" "F.Paste")
			(net "P3V3_AUX")
		)
		(pad "2" smd circle
			(at 0.40005 0 180)
			(size 0 0)
			(layers "F.Cu" "F.Mask" "F.Paste")
			(net "PWRGD_P12V_SSD2_D")
		)
	)
	(footprint ""
		(layer "F.Cu")
		(at 447.312288 -405.070818 90)
		(property "Reference" "R5602"
			(at 0 0 90)
			(layer "F.SilkS")
			(hide yes)
			(effects
				(font
					(size 1.27 1.27)
				)
			)
		)
		(property "Value" ""
			(at 0 0 90)
			(layer "F.Fab")
			(effects
				(font
					(size 1.27 1.27)
				)
			)
		)
		(duplicate_pad_numbers_are_jumpers no)
		(fp_line
			(start 0.7874 -0.4064)
			(end 0.7874 0.4064)
			(stroke
				(width 0.1524)
				(type default)
			)
			(layer "F.SilkS")
		)
		(fp_line
			(start -0.7874 -0.4064)
			(end 0.7874 -0.4064)
			(stroke
				(width 0.1524)
				(type default)
			)
			(layer "F.SilkS")
		)
		(fp_line
			(start 0.7874 0.4064)
			(end -0.7874 0.4064)
			(stroke
				(width 0.1524)
				(type default)
			)
			(layer "F.SilkS")
		)
		(fp_line
			(start -0.7874 0.4064)
			(end -0.7874 -0.4064)
			(stroke
				(width 0.1524)
				(type default)
			)
			(layer "F.SilkS")
		)
		(fp_line
			(start -0.12065 -0.305054)
			(end -0.12065 -0.2794)
			(stroke
				(width 0.1)
				(type default)
			)
			(layer "F.Fab")
		)
		(fp_line
			(start -0.67945 -0.305054)
			(end -0.12065 -0.305054)
			(stroke
				(width 0.1)
				(type default)
			)
			(layer "F.Fab")
		)
		(fp_line
			(start 0.67945 -0.3048)
			(end 0.67945 0.3048)
			(stroke
				(width 0.1)
				(type default)
			)
			(layer "F.Fab")
		)
		(fp_line
			(start 0.12065 -0.3048)
			(end 0.67945 -0.3048)
			(stroke
				(width 0.1)
				(type default)
			)
			(layer "F.Fab")
		)
		(fp_line
			(start 0.12065 -0.2794)
			(end 0.12065 -0.3048)
			(stroke
				(width 0.1)
				(type default)
			)
			(layer "F.Fab")
		)
		(fp_line
			(start -0.12065 -0.2794)
			(end 0.12065 -0.2794)
			(stroke
				(width 0.1)
				(type default)
			)
			(layer "F.Fab")
		)
		(fp_line
			(start 0.120396 0.2794)
			(end -0.12065 0.2794)
			(stroke
				(width 0.1)
				(type default)
			)
			(layer "F.Fab")
		)
		(fp_line
			(start -0.12065 0.2794)
			(end -0.12065 0.3048)
			(stroke
				(width 0.1)
				(type default)
			)
			(layer "F.Fab")
		)
		(fp_line
			(start 0.67945 0.3048)
			(end 0.120396 0.3048)
			(stroke
				(width 0.1)
				(type default)
			)
			(layer "F.Fab")
		)
		(fp_line
			(start 0.120396 0.3048)
			(end 0.120396 0.2794)
			(stroke
				(width 0.1)
				(type default)
			)
			(layer "F.Fab")
		)
		(fp_line
			(start -0.12065 0.3048)
			(end -0.67945 0.3048)
			(stroke
				(width 0.1)
				(type default)
			)
			(layer "F.Fab")
		)
		(fp_line
			(start -0.67945 0.3048)
			(end -0.67945 -0.305054)
			(stroke
				(width 0.1)
				(type default)
			)
			(layer "F.Fab")
		)
		(pad "1" smd circle
			(at -0.40005 0 90)
			(size 0 0)
			(layers "F.Cu" "F.Mask" "F.Paste")
			(net "SMB_BIC_I2C6_MUX_THERMAL_R_SDA")
		)
		(pad "2" smd circle
			(at 0.40005 0 90)
			(size 0 0)
			(layers "F.Cu" "F.Mask" "F.Paste")
			(net "SMB_LM75_1_SDA")
		)
	)
	(footprint ""
		(layer "F.Cu")
		(at 378.852684 -91.1098 180)
		(property "Reference" "R1758"
			(at 0 0 180)
			(layer "F.SilkS")
			(hide yes)
			(effects
				(font
					(size 1.27 1.27)
				)
			)
		)
		(property "Value" ""
			(at 0 0 180)
			(layer "F.Fab")
			(effects
				(font
					(size 1.27 1.27)
				)
			)
		)
		(duplicate_pad_numbers_are_jumpers no)
		(fp_line
			(start 0.7874 0.4064)
			(end -0.7874 0.4064)
			(stroke
				(width 0.1524)
				(type default)
			)
			(layer "F.SilkS")
		)
		(fp_line
			(start 0.7874 -0.4064)
			(end 0.7874 0.4064)
			(stroke
				(width 0.1524)
				(type default)
			)
			(layer "F.SilkS")
		)
		(fp_line
			(start -0.7874 0.4064)
			(end -0.7874 -0.4064)
			(stroke
				(width 0.1524)
				(type default)
			)
			(layer "F.SilkS")
		)
		(fp_line
			(start -0.7874 -0.4064)
			(end 0.7874 -0.4064)
			(stroke
				(width 0.1524)
				(type default)
			)
			(layer "F.SilkS")
		)
		(fp_line
			(start 0.67945 0.3048)
			(end 0.120396 0.3048)
			(stroke
				(width 0.1)
				(type default)
			)
			(layer "F.Fab")
		)
		(fp_line
			(start 0.67945 -0.3048)
			(end 0.67945 0.3048)
			(stroke
				(width 0.1)
				(type default)
			)
			(layer "F.Fab")
		)
		(fp_line
			(start 0.12065 -0.2794)
			(end 0.12065 -0.3048)
			(stroke
				(width 0.1)
				(type default)
			)
			(layer "F.Fab")
		)
		(fp_line
			(start 0.12065 -0.3048)
			(end 0.67945 -0.3048)
			(stroke
				(width 0.1)
				(type default)
			)
			(layer "F.Fab")
		)
		(fp_line
			(start 0.120396 0.3048)
			(end 0.120396 0.2794)
			(stroke
				(width 0.1)
				(type default)
			)
			(layer "F.Fab")
		)
		(fp_line
			(start 0.120396 0.2794)
			(end -0.12065 0.2794)
			(stroke
				(width 0.1)
				(type default)
			)
			(layer "F.Fab")
		)
		(fp_line
			(start -0.12065 0.3048)
			(end -0.67945 0.3048)
			(stroke
				(width 0.1)
				(type default)
			)
			(layer "F.Fab")
		)
		(fp_line
			(start -0.12065 0.2794)
			(end -0.12065 0.3048)
			(stroke
				(width 0.1)
				(type default)
			)
			(layer "F.Fab")
		)
		(fp_line
			(start -0.12065 -0.2794)
			(end 0.12065 -0.2794)
			(stroke
				(width 0.1)
				(type default)
			)
			(layer "F.Fab")
		)
		(fp_line
			(start -0.12065 -0.305054)
			(end -0.12065 -0.2794)
			(stroke
				(width 0.1)
				(type default)
			)
			(layer "F.Fab")
		)
		(fp_line
			(start -0.67945 0.3048)
			(end -0.67945 -0.305054)
			(stroke
				(width 0.1)
				(type default)
			)
			(layer "F.Fab")
		)
		(fp_line
			(start -0.67945 -0.305054)
			(end -0.12065 -0.305054)
			(stroke
				(width 0.1)
				(type default)
			)
			(layer "F.Fab")
		)
		(pad "1" smd circle
			(at -0.40005 0 180)
			(size 0 0)
			(layers "F.Cu" "F.Mask" "F.Paste")
			(net "BIC_I2C6_MUX_A0")
		)
		(pad "2" smd circle
			(at 0.40005 0 180)
			(size 0 0)
			(layers "F.Cu" "F.Mask" "F.Paste")
			(net "GND")
		)
	)
	(footprint ""
		(layer "F.Cu")
		(at 155.682442 -252.356874 -90)
		(property "Reference" "R3961"
			(at 0 0 270)
			(layer "F.SilkS")
			(hide yes)
			(effects
				(font
					(size 1.27 1.27)
				)
			)
		)
		(property "Value" ""
			(at 0 0 270)
			(layer "F.Fab")
			(effects
				(font
					(size 1.27 1.27)
				)
			)
		)
		(duplicate_pad_numbers_are_jumpers no)
		(fp_line
			(start -0.7874 0.4064)
			(end -0.7874 -0.4064)
			(stroke
				(width 0.1524)
				(type default)
			)
			(layer "F.SilkS")
		)
		(fp_line
			(start 0.7874 0.4064)
			(end -0.7874 0.4064)
			(stroke
				(width 0.1524)
				(type default)
			)
			(layer "F.SilkS")
		)
		(fp_line
			(start -0.7874 -0.4064)
			(end 0.7874 -0.4064)
			(stroke
				(width 0.1524)
				(type default)
			)
			(layer "F.SilkS")
		)
		(fp_line
			(start 0.7874 -0.4064)
			(end 0.7874 0.4064)
			(stroke
				(width 0.1524)
				(type default)
			)
			(layer "F.SilkS")
		)
		(fp_line
			(start -0.67945 0.3048)
			(end -0.67945 -0.305054)
			(stroke
				(width 0.1)
				(type default)
			)
			(layer "F.Fab")
		)
		(fp_line
			(start -0.12065 0.3048)
			(end -0.67945 0.3048)
			(stroke
				(width 0.1)
				(type default)
			)
			(layer "F.Fab")
		)
		(fp_line
			(start 0.120396 0.3048)
			(end 0.120396 0.2794)
			(stroke
				(width 0.1)
				(type default)
			)
			(layer "F.Fab")
		)
		(fp_line
			(start 0.67945 0.3048)
			(end 0.120396 0.3048)
			(stroke
				(width 0.1)
				(type default)
			)
			(layer "F.Fab")
		)
		(fp_line
			(start -0.12065 0.2794)
			(end -0.12065 0.3048)
			(stroke
				(width 0.1)
				(type default)
			)
			(layer "F.Fab")
		)
		(fp_line
			(start 0.120396 0.2794)
			(end -0.12065 0.2794)
			(stroke
				(width 0.1)
				(type default)
			)
			(layer "F.Fab")
		)
		(fp_line
			(start -0.12065 -0.2794)
			(end 0.12065 -0.2794)
			(stroke
				(width 0.1)
				(type default)
			)
			(layer "F.Fab")
		)
		(fp_line
			(start 0.12065 -0.2794)
			(end 0.12065 -0.3048)
			(stroke
				(width 0.1)
				(type default)
			)
			(layer "F.Fab")
		)
		(fp_line
			(start 0.12065 -0.3048)
			(end 0.67945 -0.3048)
			(stroke
				(width 0.1)
				(type default)
			)
			(layer "F.Fab")
		)
		(fp_line
			(start 0.67945 -0.3048)
			(end 0.67945 0.3048)
			(stroke
				(width 0.1)
				(type default)
			)
			(layer "F.Fab")
		)
		(fp_line
			(start -0.67945 -0.305054)
			(end -0.12065 -0.305054)
			(stroke
				(width 0.1)
				(type default)
			)
			(layer "F.Fab")
		)
		(fp_line
			(start -0.12065 -0.305054)
			(end -0.12065 -0.2794)
			(stroke
				(width 0.1)
				(type default)
			)
			(layer "F.Fab")
		)
		(pad "1" smd circle
			(at -0.40005 0 270)
			(size 0 0)
			(layers "F.Cu" "F.Mask" "F.Paste")
			(net "PEX1_PCA9555_INT_R_N")
		)
		(pad "2" smd circle
			(at 0.40005 0 270)
			(size 0 0)
			(layers "F.Cu" "F.Mask" "F.Paste")
			(net "P1V8_PEX")
		)
	)
	(footprint ""
		(layer "F.Cu")
		(at 320.675508 -122.931682 -90)
		(property "Reference" "PD55"
			(at 4.110482 2.107438 90)
			(unlocked yes)
			(layer "F.SilkS")
			(effects
				(font
					(size 0.7874 0.5842)
					(thickness 0.1524)
				)
				(justify left)
			)
		)
		(property "Value" ""
			(at 0 0 270)
			(layer "F.Fab")
			(effects
				(font
					(size 1.27 1.27)
				)
			)
		)
		(duplicate_pad_numbers_are_jumpers no)
		(fp_line
			(start -3.400044 1.459992)
			(end -3.400044 -1.459992)
			(stroke
				(width 0.1524)
				(type default)
			)
			(layer "F.SilkS")
		)
		(fp_line
			(start 4.107942 1.459992)
			(end -3.400044 1.459992)
			(stroke
				(width 0.1524)
				(type default)
			)
			(layer "F.SilkS")
		)
		(fp_line
			(start -3.400044 -1.459992)
			(end 4.107942 -1.459992)
			(stroke
				(width 0.1524)
				(type default)
			)
			(layer "F.SilkS")
		)
		(fp_line
			(start 4.107942 -1.459992)
			(end 4.107942 1.459992)
			(stroke
				(width 0.1524)
				(type default)
			)
			(layer "F.SilkS")
		)
		(fp_rect
			(start 4.107942 1.459992)
			(end 3.308096 -1.459992)
			(stroke
				(width 0)
				(type default)
			)
			(fill yes)
			(layer "F.SilkS")
		)
		(fp_line
			(start -2.29997 1.459992)
			(end -2.29997 -1.459992)
			(stroke
				(width 0.1)
				(type default)
			)
			(layer "F.Fab")
		)
		(fp_line
			(start 2.29997 1.459992)
			(end -2.29997 1.459992)
			(stroke
				(width 0.1)
				(type default)
			)
			(layer "F.Fab")
		)
		(fp_line
			(start -2.29997 -1.459992)
			(end 2.29997 -1.459992)
			(stroke
				(width 0.1)
				(type default)
			)
			(layer "F.Fab")
		)
		(fp_line
			(start 2.29997 -1.459992)
			(end 2.29997 1.459992)
			(stroke
				(width 0.1)
				(type default)
			)
			(layer "F.Fab")
		)
		(fp_text user "-"
			(at 5.4102 0.29845 90)
			(unlocked yes)
			(layer "F.SilkS")
			(effects
				(font
					(size 1.905 1.4224)
					(thickness 0.1524)
				)
				(justify left)
			)
		)
		(fp_text user "+"
			(at -4.7752 -0.12065 270)
			(unlocked yes)
			(layer "F.SilkS")
			(effects
				(font
					(size 1.905 1.4224)
					(thickness 0.1524)
				)
				(justify left)
			)
		)
		(fp_text user "-"
			(at 5.4102 0.29845 90)
			(unlocked yes)
			(layer "F.Fab")
			(effects
				(font
					(size 1.905 1.4224)
					(thickness 0.1524)
				)
				(justify left)
			)
		)
		(fp_text user "+"
			(at -4.7752 -0.12065 270)
			(unlocked yes)
			(layer "F.Fab")
			(effects
				(font
					(size 1.905 1.4224)
					(thickness 0.1524)
				)
				(justify left)
			)
		)
		(pad "A" smd rect
			(at -1.999996 0)
			(size 1.7018 2.5146)
			(layers "F.Cu" "F.Mask" "F.Paste")
			(net "GND")
		)
		(pad "C" smd rect
			(at 1.999996 0)
			(size 1.7018 2.5146)
			(layers "F.Cu" "F.Mask" "F.Paste")
			(net "P3V3_NIC5")
		)
	)
	(footprint ""
		(layer "F.Cu")
		(at 359.859326 -259.1435 180)
		(property "Reference" "PR7170"
			(at 0 0 180)
			(layer "F.SilkS")
			(hide yes)
			(effects
				(font
					(size 1.27 1.27)
				)
			)
		)
		(property "Value" ""
			(at 0 0 180)
			(layer "F.Fab")
			(effects
				(font
					(size 1.27 1.27)
				)
			)
		)
		(duplicate_pad_numbers_are_jumpers no)
		(fp_line
			(start 0.7874 0.4064)
			(end -0.7874 0.4064)
			(stroke
				(width 0.1524)
				(type default)
			)
			(layer "F.SilkS")
		)
		(fp_line
			(start 0.7874 -0.4064)
			(end 0.7874 0.4064)
			(stroke
				(width 0.1524)
				(type default)
			)
			(layer "F.SilkS")
		)
		(fp_line
			(start -0.7874 0.4064)
			(end -0.7874 -0.4064)
			(stroke
				(width 0.1524)
				(type default)
			)
			(layer "F.SilkS")
		)
		(fp_line
			(start -0.7874 -0.4064)
			(end 0.7874 -0.4064)
			(stroke
				(width 0.1524)
				(type default)
			)
			(layer "F.SilkS")
		)
		(fp_line
			(start 0.67945 0.3048)
			(end 0.120396 0.3048)
			(stroke
				(width 0.1)
				(type default)
			)
			(layer "F.Fab")
		)
		(fp_line
			(start 0.67945 -0.3048)
			(end 0.67945 0.3048)
			(stroke
				(width 0.1)
				(type default)
			)
			(layer "F.Fab")
		)
		(fp_line
			(start 0.12065 -0.2794)
			(end 0.12065 -0.3048)
			(stroke
				(width 0.1)
				(type default)
			)
			(layer "F.Fab")
		)
		(fp_line
			(start 0.12065 -0.3048)
			(end 0.67945 -0.3048)
			(stroke
				(width 0.1)
				(type default)
			)
			(layer "F.Fab")
		)
		(fp_line
			(start 0.120396 0.3048)
			(end 0.120396 0.2794)
			(stroke
				(width 0.1)
				(type default)
			)
			(layer "F.Fab")
		)
		(fp_line
			(start 0.120396 0.2794)
			(end -0.12065 0.2794)
			(stroke
				(width 0.1)
				(type default)
			)
			(layer "F.Fab")
		)
		(fp_line
			(start -0.12065 0.3048)
			(end -0.67945 0.3048)
			(stroke
				(width 0.1)
				(type default)
			)
			(layer "F.Fab")
		)
		(fp_line
			(start -0.12065 0.2794)
			(end -0.12065 0.3048)
			(stroke
				(width 0.1)
				(type default)
			)
			(layer "F.Fab")
		)
		(fp_line
			(start -0.12065 -0.2794)
			(end 0.12065 -0.2794)
			(stroke
				(width 0.1)
				(type default)
			)
			(layer "F.Fab")
		)
		(fp_line
			(start -0.12065 -0.305054)
			(end -0.12065 -0.2794)
			(stroke
				(width 0.1)
				(type default)
			)
			(layer "F.Fab")
		)
		(fp_line
			(start -0.67945 0.3048)
			(end -0.67945 -0.305054)
			(stroke
				(width 0.1)
				(type default)
			)
			(layer "F.Fab")
		)
		(fp_line
			(start -0.67945 -0.305054)
			(end -0.12065 -0.305054)
			(stroke
				(width 0.1)
				(type default)
			)
			(layer "F.Fab")
		)
		(pad "1" smd circle
			(at -0.40005 0 180)
			(size 0 0)
			(layers "F.Cu" "F.Mask" "F.Paste")
			(net "GND")
		)
		(pad "2" smd circle
			(at 0.40005 0 180)
			(size 0 0)
			(layers "F.Cu" "F.Mask" "F.Paste")
			(net "NC_P0V8_PEX2_SVID_ALERT_N_R")
		)
	)
	(footprint ""
		(layer "F.Cu")
		(at 91.379294 -300.641004 -90)
		(property "Reference" "R3881"
			(at 0 0 270)
			(layer "F.SilkS")
			(hide yes)
			(effects
				(font
					(size 1.27 1.27)
				)
			)
		)
		(property "Value" ""
			(at 0 0 270)
			(layer "F.Fab")
			(effects
				(font
					(size 1.27 1.27)
				)
			)
		)
		(duplicate_pad_numbers_are_jumpers no)
		(fp_line
			(start -0.7874 0.4064)
			(end -0.7874 -0.4064)
			(stroke
				(width 0.1524)
				(type default)
			)
			(layer "F.SilkS")
		)
		(fp_line
			(start 0.7874 0.4064)
			(end -0.7874 0.4064)
			(stroke
				(width 0.1524)
				(type default)
			)
			(layer "F.SilkS")
		)
		(fp_line
			(start -0.7874 -0.4064)
			(end 0.7874 -0.4064)
			(stroke
				(width 0.1524)
				(type default)
			)
			(layer "F.SilkS")
		)
		(fp_line
			(start 0.7874 -0.4064)
			(end 0.7874 0.4064)
			(stroke
				(width 0.1524)
				(type default)
			)
			(layer "F.SilkS")
		)
		(fp_line
			(start -0.67945 0.3048)
			(end -0.67945 -0.305054)
			(stroke
				(width 0.1)
				(type default)
			)
			(layer "F.Fab")
		)
		(fp_line
			(start -0.12065 0.3048)
			(end -0.67945 0.3048)
			(stroke
				(width 0.1)
				(type default)
			)
			(layer "F.Fab")
		)
		(fp_line
			(start 0.120396 0.3048)
			(end 0.120396 0.2794)
			(stroke
				(width 0.1)
				(type default)
			)
			(layer "F.Fab")
		)
		(fp_line
			(start 0.67945 0.3048)
			(end 0.120396 0.3048)
			(stroke
				(width 0.1)
				(type default)
			)
			(layer "F.Fab")
		)
		(fp_line
			(start -0.12065 0.2794)
			(end -0.12065 0.3048)
			(stroke
				(width 0.1)
				(type default)
			)
			(layer "F.Fab")
		)
		(fp_line
			(start 0.120396 0.2794)
			(end -0.12065 0.2794)
			(stroke
				(width 0.1)
				(type default)
			)
			(layer "F.Fab")
		)
		(fp_line
			(start -0.12065 -0.2794)
			(end 0.12065 -0.2794)
			(stroke
				(width 0.1)
				(type default)
			)
			(layer "F.Fab")
		)
		(fp_line
			(start 0.12065 -0.2794)
			(end 0.12065 -0.3048)
			(stroke
				(width 0.1)
				(type default)
			)
			(layer "F.Fab")
		)
		(fp_line
			(start 0.12065 -0.3048)
			(end 0.67945 -0.3048)
			(stroke
				(width 0.1)
				(type default)
			)
			(layer "F.Fab")
		)
		(fp_line
			(start 0.67945 -0.3048)
			(end 0.67945 0.3048)
			(stroke
				(width 0.1)
				(type default)
			)
			(layer "F.Fab")
		)
		(fp_line
			(start -0.67945 -0.305054)
			(end -0.12065 -0.305054)
			(stroke
				(width 0.1)
				(type default)
			)
			(layer "F.Fab")
		)
		(fp_line
			(start -0.12065 -0.305054)
			(end -0.12065 -0.2794)
			(stroke
				(width 0.1)
				(type default)
			)
			(layer "F.Fab")
		)
		(pad "1" smd circle
			(at -0.40005 0 270)
			(size 0 0)
			(layers "F.Cu" "F.Mask" "F.Paste")
			(net "I2C0_PEX0_SCL")
		)
		(pad "2" smd circle
			(at 0.40005 0 270)
			(size 0 0)
			(layers "F.Cu" "F.Mask" "F.Paste")
			(net "I2C_PEX0_HOST_SCL")
		)
	)
	(footprint ""
		(layer "F.Cu")
		(at 264.611358 -299.645832 -90)
		(property "Reference" "R4579"
			(at 0 0 270)
			(layer "F.SilkS")
			(hide yes)
			(effects
				(font
					(size 1.27 1.27)
				)
			)
		)
		(property "Value" ""
			(at 0 0 270)
			(layer "F.Fab")
			(effects
				(font
					(size 1.27 1.27)
				)
			)
		)
		(duplicate_pad_numbers_are_jumpers no)
		(fp_line
			(start -0.7874 0.4064)
			(end -0.7874 -0.4064)
			(stroke
				(width 0.1524)
				(type default)
			)
			(layer "F.SilkS")
		)
		(fp_line
			(start 0.7874 0.4064)
			(end -0.7874 0.4064)
			(stroke
				(width 0.1524)
				(type default)
			)
			(layer "F.SilkS")
		)
		(fp_line
			(start -0.7874 -0.4064)
			(end 0.7874 -0.4064)
			(stroke
				(width 0.1524)
				(type default)
			)
			(layer "F.SilkS")
		)
		(fp_line
			(start 0.7874 -0.4064)
			(end 0.7874 0.4064)
			(stroke
				(width 0.1524)
				(type default)
			)
			(layer "F.SilkS")
		)
		(fp_line
			(start -0.67945 0.3048)
			(end -0.67945 -0.305054)
			(stroke
				(width 0.1)
				(type default)
			)
			(layer "F.Fab")
		)
		(fp_line
			(start -0.12065 0.3048)
			(end -0.67945 0.3048)
			(stroke
				(width 0.1)
				(type default)
			)
			(layer "F.Fab")
		)
		(fp_line
			(start 0.120396 0.3048)
			(end 0.120396 0.2794)
			(stroke
				(width 0.1)
				(type default)
			)
			(layer "F.Fab")
		)
		(fp_line
			(start 0.67945 0.3048)
			(end 0.120396 0.3048)
			(stroke
				(width 0.1)
				(type default)
			)
			(layer "F.Fab")
		)
		(fp_line
			(start -0.12065 0.2794)
			(end -0.12065 0.3048)
			(stroke
				(width 0.1)
				(type default)
			)
			(layer "F.Fab")
		)
		(fp_line
			(start 0.120396 0.2794)
			(end -0.12065 0.2794)
			(stroke
				(width 0.1)
				(type default)
			)
			(layer "F.Fab")
		)
		(fp_line
			(start -0.12065 -0.2794)
			(end 0.12065 -0.2794)
			(stroke
				(width 0.1)
				(type default)
			)
			(layer "F.Fab")
		)
		(fp_line
			(start 0.12065 -0.2794)
			(end 0.12065 -0.3048)
			(stroke
				(width 0.1)
				(type default)
			)
			(layer "F.Fab")
		)
		(fp_line
			(start 0.12065 -0.3048)
			(end 0.67945 -0.3048)
			(stroke
				(width 0.1)
				(type default)
			)
			(layer "F.Fab")
		)
		(fp_line
			(start 0.67945 -0.3048)
			(end 0.67945 0.3048)
			(stroke
				(width 0.1)
				(type default)
			)
			(layer "F.Fab")
		)
		(fp_line
			(start -0.67945 -0.305054)
			(end -0.12065 -0.305054)
			(stroke
				(width 0.1)
				(type default)
			)
			(layer "F.Fab")
		)
		(fp_line
			(start -0.12065 -0.305054)
			(end -0.12065 -0.2794)
			(stroke
				(width 0.1)
				(type default)
			)
			(layer "F.Fab")
		)
		(pad "1" smd circle
			(at -0.40005 0 270)
			(size 0 0)
			(layers "F.Cu" "F.Mask" "F.Paste")
			(net "PCEPLL1_VDDA18_PEX2")
		)
		(pad "2" smd circle
			(at 0.40005 0 270)
			(size 0 0)
			(layers "F.Cu" "F.Mask" "F.Paste")
			(net "PCEPLL1_VDDA18_PEX2_R")
		)
	)
	(footprint ""
		(layer "F.Cu")
		(at 348.982792 -240.691162 -90)
		(property "Reference" "R3549"
			(at 0 0 270)
			(layer "F.SilkS")
			(hide yes)
			(effects
				(font
					(size 1.27 1.27)
				)
			)
		)
		(property "Value" ""
			(at 0 0 270)
			(layer "F.Fab")
			(effects
				(font
					(size 1.27 1.27)
				)
			)
		)
		(duplicate_pad_numbers_are_jumpers no)
		(fp_line
			(start -0.7874 0.4064)
			(end -0.7874 -0.4064)
			(stroke
				(width 0.1524)
				(type default)
			)
			(layer "F.SilkS")
		)
		(fp_line
			(start 0.7874 0.4064)
			(end -0.7874 0.4064)
			(stroke
				(width 0.1524)
				(type default)
			)
			(layer "F.SilkS")
		)
		(fp_line
			(start -0.7874 -0.4064)
			(end 0.7874 -0.4064)
			(stroke
				(width 0.1524)
				(type default)
			)
			(layer "F.SilkS")
		)
		(fp_line
			(start 0.7874 -0.4064)
			(end 0.7874 0.4064)
			(stroke
				(width 0.1524)
				(type default)
			)
			(layer "F.SilkS")
		)
		(fp_line
			(start -0.67945 0.3048)
			(end -0.67945 -0.305054)
			(stroke
				(width 0.1)
				(type default)
			)
			(layer "F.Fab")
		)
		(fp_line
			(start -0.12065 0.3048)
			(end -0.67945 0.3048)
			(stroke
				(width 0.1)
				(type default)
			)
			(layer "F.Fab")
		)
		(fp_line
			(start 0.120396 0.3048)
			(end 0.120396 0.2794)
			(stroke
				(width 0.1)
				(type default)
			)
			(layer "F.Fab")
		)
		(fp_line
			(start 0.67945 0.3048)
			(end 0.120396 0.3048)
			(stroke
				(width 0.1)
				(type default)
			)
			(layer "F.Fab")
		)
		(fp_line
			(start -0.12065 0.2794)
			(end -0.12065 0.3048)
			(stroke
				(width 0.1)
				(type default)
			)
			(layer "F.Fab")
		)
		(fp_line
			(start 0.120396 0.2794)
			(end -0.12065 0.2794)
			(stroke
				(width 0.1)
				(type default)
			)
			(layer "F.Fab")
		)
		(fp_line
			(start -0.12065 -0.2794)
			(end 0.12065 -0.2794)
			(stroke
				(width 0.1)
				(type default)
			)
			(layer "F.Fab")
		)
		(fp_line
			(start 0.12065 -0.2794)
			(end 0.12065 -0.3048)
			(stroke
				(width 0.1)
				(type default)
			)
			(layer "F.Fab")
		)
		(fp_line
			(start 0.12065 -0.3048)
			(end 0.67945 -0.3048)
			(stroke
				(width 0.1)
				(type default)
			)
			(layer "F.Fab")
		)
		(fp_line
			(start 0.67945 -0.3048)
			(end 0.67945 0.3048)
			(stroke
				(width 0.1)
				(type default)
			)
			(layer "F.Fab")
		)
		(fp_line
			(start -0.67945 -0.305054)
			(end -0.12065 -0.305054)
			(stroke
				(width 0.1)
				(type default)
			)
			(layer "F.Fab")
		)
		(fp_line
			(start -0.12065 -0.305054)
			(end -0.12065 -0.2794)
			(stroke
				(width 0.1)
				(type default)
			)
			(layer "F.Fab")
		)
		(pad "1" smd circle
			(at -0.40005 0 270)
			(size 0 0)
			(layers "F.Cu" "F.Mask" "F.Paste")
			(net "SSD4_PWR_EN_R")
		)
		(pad "2" smd circle
			(at 0.40005 0 270)
			(size 0 0)
			(layers "F.Cu" "F.Mask" "F.Paste")
			(net "SSD4_PWR_EN")
		)
	)
	(footprint ""
		(layer "F.Cu")
		(at 355.854 -177.546)
		(property "Reference" "R4743"
			(at 0 0 0)
			(layer "F.SilkS")
			(hide yes)
			(effects
				(font
					(size 1.27 1.27)
				)
			)
		)
		(property "Value" ""
			(at 0 0 0)
			(layer "F.Fab")
			(effects
				(font
					(size 1.27 1.27)
				)
			)
		)
		(duplicate_pad_numbers_are_jumpers no)
		(fp_line
			(start -0.7874 -0.4064)
			(end 0.7874 -0.4064)
			(stroke
				(width 0.1524)
				(type default)
			)
			(layer "F.SilkS")
		)
		(fp_line
			(start -0.7874 0.4064)
			(end -0.7874 -0.4064)
			(stroke
				(width 0.1524)
				(type default)
			)
			(layer "F.SilkS")
		)
		(fp_line
			(start 0.7874 -0.4064)
			(end 0.7874 0.4064)
			(stroke
				(width 0.1524)
				(type default)
			)
			(layer "F.SilkS")
		)
		(fp_line
			(start 0.7874 0.4064)
			(end -0.7874 0.4064)
			(stroke
				(width 0.1524)
				(type default)
			)
			(layer "F.SilkS")
		)
		(fp_line
			(start -0.67945 -0.305054)
			(end -0.12065 -0.305054)
			(stroke
				(width 0.1)
				(type default)
			)
			(layer "F.Fab")
		)
		(fp_line
			(start -0.67945 0.3048)
			(end -0.67945 -0.305054)
			(stroke
				(width 0.1)
				(type default)
			)
			(layer "F.Fab")
		)
		(fp_line
			(start -0.12065 -0.305054)
			(end -0.12065 -0.2794)
			(stroke
				(width 0.1)
				(type default)
			)
			(layer "F.Fab")
		)
		(fp_line
			(start -0.12065 -0.2794)
			(end 0.12065 -0.2794)
			(stroke
				(width 0.1)
				(type default)
			)
			(layer "F.Fab")
		)
		(fp_line
			(start -0.12065 0.2794)
			(end -0.12065 0.3048)
			(stroke
				(width 0.1)
				(type default)
			)
			(layer "F.Fab")
		)
		(fp_line
			(start -0.12065 0.3048)
			(end -0.67945 0.3048)
			(stroke
				(width 0.1)
				(type default)
			)
			(layer "F.Fab")
		)
		(fp_line
			(start 0.120396 0.2794)
			(end -0.12065 0.2794)
			(stroke
				(width 0.1)
				(type default)
			)
			(layer "F.Fab")
		)
		(fp_line
			(start 0.120396 0.3048)
			(end 0.120396 0.2794)
			(stroke
				(width 0.1)
				(type default)
			)
			(layer "F.Fab")
		)
		(fp_line
			(start 0.12065 -0.3048)
			(end 0.67945 -0.3048)
			(stroke
				(width 0.1)
				(type default)
			)
			(layer "F.Fab")
		)
		(fp_line
			(start 0.12065 -0.2794)
			(end 0.12065 -0.3048)
			(stroke
				(width 0.1)
				(type default)
			)
			(layer "F.Fab")
		)
		(fp_line
			(start 0.67945 -0.3048)
			(end 0.67945 0.3048)
			(stroke
				(width 0.1)
				(type default)
			)
			(layer "F.Fab")
		)
		(fp_line
			(start 0.67945 0.3048)
			(end 0.120396 0.3048)
			(stroke
				(width 0.1)
				(type default)
			)
			(layer "F.Fab")
		)
		(pad "1" smd circle
			(at -0.40005 0)
			(size 0 0)
			(layers "F.Cu" "F.Mask" "F.Paste")
			(net "NIC4_PEX_PWR_EN_R")
		)
		(pad "2" smd circle
			(at 0.40005 0)
			(size 0 0)
			(layers "F.Cu" "F.Mask" "F.Paste")
			(net "GND")
		)
	)
	(footprint ""
		(layer "F.Cu")
		(at 439.93435 -310.478932 -45)
		(property "Reference" "R3946"
			(at 0 0 315)
			(layer "F.SilkS")
			(hide yes)
			(effects
				(font
					(size 1.27 1.27)
				)
			)
		)
		(property "Value" ""
			(at 0 0 315)
			(layer "F.Fab")
			(effects
				(font
					(size 1.27 1.27)
				)
			)
		)
		(duplicate_pad_numbers_are_jumpers no)
		(fp_line
			(start -0.787389 0.406267)
			(end -0.787389 -0.406267)
			(stroke
				(width 0.1524)
				(type default)
			)
			(layer "F.SilkS")
		)
		(fp_line
			(start -0.787389 -0.406267)
			(end 0.787389 -0.406267)
			(stroke
				(width 0.1524)
				(type default)
			)
			(layer "F.SilkS")
		)
		(fp_line
			(start 0.787389 0.406267)
			(end -0.787389 0.406267)
			(stroke
				(width 0.1524)
				(type default)
			)
			(layer "F.SilkS")
		)
		(fp_line
			(start 0.787389 -0.406267)
			(end 0.787389 0.406267)
			(stroke
				(width 0.1524)
				(type default)
			)
			(layer "F.SilkS")
		)
		(fp_line
			(start -0.679446 0.30479)
			(end -0.679446 -0.305149)
			(stroke
				(width 0.1)
				(type default)
			)
			(layer "F.Fab")
		)
		(fp_line
			(start -0.120515 0.30479)
			(end -0.679446 0.30479)
			(stroke
				(width 0.1)
				(type default)
			)
			(layer "F.Fab")
		)
		(fp_line
			(start -0.120695 0.279466)
			(end -0.120515 0.30479)
			(stroke
				(width 0.1)
				(type default)
			)
			(layer "F.Fab")
		)
		(fp_line
			(start -0.679446 -0.305149)
			(end -0.120695 -0.304969)
			(stroke
				(width 0.1)
				(type default)
			)
			(layer "F.Fab")
		)
		(fp_line
			(start 0.120515 0.30479)
			(end 0.120335 0.279466)
			(stroke
				(width 0.1)
				(type default)
			)
			(layer "F.Fab")
		)
		(fp_line
			(start 0.120335 0.279466)
			(end -0.120695 0.279466)
			(stroke
				(width 0.1)
				(type default)
			)
			(layer "F.Fab")
		)
		(fp_line
			(start -0.120695 -0.279466)
			(end 0.120695 -0.279466)
			(stroke
				(width 0.1)
				(type default)
			)
			(layer "F.Fab")
		)
		(fp_line
			(start -0.120695 -0.304969)
			(end -0.120695 -0.279466)
			(stroke
				(width 0.1)
				(type default)
			)
			(layer "F.Fab")
		)
		(fp_line
			(start 0.679446 0.30479)
			(end 0.120515 0.30479)
			(stroke
				(width 0.1)
				(type default)
			)
			(layer "F.Fab")
		)
		(fp_line
			(start 0.120695 -0.279466)
			(end 0.120515 -0.30479)
			(stroke
				(width 0.1)
				(type default)
			)
			(layer "F.Fab")
		)
		(fp_line
			(start 0.120515 -0.30479)
			(end 0.679446 -0.30479)
			(stroke
				(width 0.1)
				(type default)
			)
			(layer "F.Fab")
		)
		(fp_line
			(start 0.679446 -0.30479)
			(end 0.679446 0.30479)
			(stroke
				(width 0.1)
				(type default)
			)
			(layer "F.Fab")
		)
		(pad "1" smd circle
			(at -0.40005 0 315)
			(size 0 0)
			(layers "F.Cu" "F.Mask" "F.Paste")
			(net "PU_PEX3_SIO_BLINK")
		)
		(pad "2" smd circle
			(at 0.40005 0 315)
			(size 0 0)
			(layers "F.Cu" "F.Mask" "F.Paste")
			(net "P1V8_PEX")
		)
	)
	(footprint ""
		(layer "F.Cu")
		(at 376.138694 -311.156604 -90)
		(property "Reference" "R1399"
			(at 0 0 270)
			(layer "F.SilkS")
			(hide yes)
			(effects
				(font
					(size 1.27 1.27)
				)
			)
		)
		(property "Value" ""
			(at 0 0 270)
			(layer "F.Fab")
			(effects
				(font
					(size 1.27 1.27)
				)
			)
		)
		(duplicate_pad_numbers_are_jumpers no)
		(fp_line
			(start -0.7874 0.4064)
			(end -0.7874 -0.4064)
			(stroke
				(width 0.1524)
				(type default)
			)
			(layer "F.SilkS")
		)
		(fp_line
			(start 0.7874 0.4064)
			(end -0.7874 0.4064)
			(stroke
				(width 0.1524)
				(type default)
			)
			(layer "F.SilkS")
		)
		(fp_line
			(start -0.7874 -0.4064)
			(end 0.7874 -0.4064)
			(stroke
				(width 0.1524)
				(type default)
			)
			(layer "F.SilkS")
		)
		(fp_line
			(start 0.7874 -0.4064)
			(end 0.7874 0.4064)
			(stroke
				(width 0.1524)
				(type default)
			)
			(layer "F.SilkS")
		)
		(fp_line
			(start -0.67945 0.3048)
			(end -0.67945 -0.305054)
			(stroke
				(width 0.1)
				(type default)
			)
			(layer "F.Fab")
		)
		(fp_line
			(start -0.12065 0.3048)
			(end -0.67945 0.3048)
			(stroke
				(width 0.1)
				(type default)
			)
			(layer "F.Fab")
		)
		(fp_line
			(start 0.120396 0.3048)
			(end 0.120396 0.2794)
			(stroke
				(width 0.1)
				(type default)
			)
			(layer "F.Fab")
		)
		(fp_line
			(start 0.67945 0.3048)
			(end 0.120396 0.3048)
			(stroke
				(width 0.1)
				(type default)
			)
			(layer "F.Fab")
		)
		(fp_line
			(start -0.12065 0.2794)
			(end -0.12065 0.3048)
			(stroke
				(width 0.1)
				(type default)
			)
			(layer "F.Fab")
		)
		(fp_line
			(start 0.120396 0.2794)
			(end -0.12065 0.2794)
			(stroke
				(width 0.1)
				(type default)
			)
			(layer "F.Fab")
		)
		(fp_line
			(start -0.12065 -0.2794)
			(end 0.12065 -0.2794)
			(stroke
				(width 0.1)
				(type default)
			)
			(layer "F.Fab")
		)
		(fp_line
			(start 0.12065 -0.2794)
			(end 0.12065 -0.3048)
			(stroke
				(width 0.1)
				(type default)
			)
			(layer "F.Fab")
		)
		(fp_line
			(start 0.12065 -0.3048)
			(end 0.67945 -0.3048)
			(stroke
				(width 0.1)
				(type default)
			)
			(layer "F.Fab")
		)
		(fp_line
			(start 0.67945 -0.3048)
			(end 0.67945 0.3048)
			(stroke
				(width 0.1)
				(type default)
			)
			(layer "F.Fab")
		)
		(fp_line
			(start -0.67945 -0.305054)
			(end -0.12065 -0.305054)
			(stroke
				(width 0.1)
				(type default)
			)
			(layer "F.Fab")
		)
		(fp_line
			(start -0.12065 -0.305054)
			(end -0.12065 -0.2794)
			(stroke
				(width 0.1)
				(type default)
			)
			(layer "F.Fab")
		)
		(pad "1" smd circle
			(at -0.40005 0 270)
			(size 0 0)
			(layers "F.Cu" "F.Mask" "F.Paste")
			(net "PEX3_DBG_SEL1")
		)
		(pad "2" smd circle
			(at 0.40005 0 270)
			(size 0 0)
			(layers "F.Cu" "F.Mask" "F.Paste")
			(net "P1V8_PEX")
		)
	)
	(footprint ""
		(layer "F.Cu")
		(at 45.093128 -350.098614 90)
		(property "Reference" "C168"
			(at 0 0 90)
			(layer "F.SilkS")
			(hide yes)
			(effects
				(font
					(size 1.27 1.27)
				)
			)
		)
		(property "Value" ""
			(at 0 0 90)
			(layer "F.Fab")
			(effects
				(font
					(size 1.27 1.27)
				)
			)
		)
		(duplicate_pad_numbers_are_jumpers no)
		(fp_line
			(start 0.299974 -0.150114)
			(end 0.299974 0.150114)
			(stroke
				(width 0.1)
				(type default)
			)
			(layer "F.Fab")
		)
		(fp_line
			(start -0.299974 -0.150114)
			(end 0.299974 -0.150114)
			(stroke
				(width 0.1)
				(type default)
			)
			(layer "F.Fab")
		)
		(fp_line
			(start 0.299974 0.150114)
			(end -0.299974 0.150114)
			(stroke
				(width 0.1)
				(type default)
			)
			(layer "F.Fab")
		)
		(fp_line
			(start -0.299974 0.150114)
			(end -0.299974 -0.150114)
			(stroke
				(width 0.1)
				(type default)
			)
			(layer "F.Fab")
		)
		(pad "1" smd rect
			(at -0.2667 0 90)
			(size 0.3048 0.381)
			(layers "F.Cu" "F.Mask" "F.Paste")
			(net "P5E_PEX0_STN7_TX_DN<124>")
		)
		(pad "2" smd rect
			(at 0.2667 0 90)
			(size 0.3048 0.381)
			(layers "F.Cu" "F.Mask" "F.Paste")
			(net "P5E_PEX0_STN7_TX_C_DN<124>")
		)
	)
	(footprint ""
		(layer "F.Cu")
		(at 491.53953 -547.603172 180)
		(property "Reference" "J39_OTH"
			(at -3.2385 -1.402334 0)
			(unlocked yes)
			(layer "B.SilkS")
			(effects
				(font
					(size 0.7874 0.5842)
					(thickness 0.1524)
				)
				(justify mirror)
			)
		)
		(property "Value" ""
			(at 0 0 180)
			(layer "F.Fab")
			(effects
				(font
					(size 1.27 1.27)
				)
			)
		)
		(duplicate_pad_numbers_are_jumpers no)
		(pad "1" thru_hole circle
			(at 0 0 180)
			(size 0.4572 0.4572)
			(drill 0.2032)
			(layers "*.Cu" "*.Mask")
			(remove_unused_layers no)
			(net "Net_9097")
			(clearance 0.127)
			(thermal_gap 0.127)
			(padstack
				(mode front_inner_back)
				(layer "Inner"
					(shape circle)
					(size 0.4572 0.4572)
					(clearance 0.127)
				)
				(layer "B.Cu"
					(shape circle)
					(size 0.508 0.508)
					(clearance 0.1016)
				)
			)
		)
	)
	(footprint ""
		(layer "F.Cu")
		(at 123.67514 -99.463606 180)
		(property "Reference" "R1566"
			(at 0 0 180)
			(layer "F.SilkS")
			(hide yes)
			(effects
				(font
					(size 1.27 1.27)
				)
			)
		)
		(property "Value" ""
			(at 0 0 180)
			(layer "F.Fab")
			(effects
				(font
					(size 1.27 1.27)
				)
			)
		)
		(duplicate_pad_numbers_are_jumpers no)
		(fp_line
			(start 0.7874 0.4064)
			(end -0.7874 0.4064)
			(stroke
				(width 0.1524)
				(type default)
			)
			(layer "F.SilkS")
		)
		(fp_line
			(start 0.7874 -0.4064)
			(end 0.7874 0.4064)
			(stroke
				(width 0.1524)
				(type default)
			)
			(layer "F.SilkS")
		)
		(fp_line
			(start -0.7874 0.4064)
			(end -0.7874 -0.4064)
			(stroke
				(width 0.1524)
				(type default)
			)
			(layer "F.SilkS")
		)
		(fp_line
			(start -0.7874 -0.4064)
			(end 0.7874 -0.4064)
			(stroke
				(width 0.1524)
				(type default)
			)
			(layer "F.SilkS")
		)
		(fp_line
			(start 0.67945 0.3048)
			(end 0.120396 0.3048)
			(stroke
				(width 0.1)
				(type default)
			)
			(layer "F.Fab")
		)
		(fp_line
			(start 0.67945 -0.3048)
			(end 0.67945 0.3048)
			(stroke
				(width 0.1)
				(type default)
			)
			(layer "F.Fab")
		)
		(fp_line
			(start 0.12065 -0.2794)
			(end 0.12065 -0.3048)
			(stroke
				(width 0.1)
				(type default)
			)
			(layer "F.Fab")
		)
		(fp_line
			(start 0.12065 -0.3048)
			(end 0.67945 -0.3048)
			(stroke
				(width 0.1)
				(type default)
			)
			(layer "F.Fab")
		)
		(fp_line
			(start 0.120396 0.3048)
			(end 0.120396 0.2794)
			(stroke
				(width 0.1)
				(type default)
			)
			(layer "F.Fab")
		)
		(fp_line
			(start 0.120396 0.2794)
			(end -0.12065 0.2794)
			(stroke
				(width 0.1)
				(type default)
			)
			(layer "F.Fab")
		)
		(fp_line
			(start -0.12065 0.3048)
			(end -0.67945 0.3048)
			(stroke
				(width 0.1)
				(type default)
			)
			(layer "F.Fab")
		)
		(fp_line
			(start -0.12065 0.2794)
			(end -0.12065 0.3048)
			(stroke
				(width 0.1)
				(type default)
			)
			(layer "F.Fab")
		)
		(fp_line
			(start -0.12065 -0.2794)
			(end 0.12065 -0.2794)
			(stroke
				(width 0.1)
				(type default)
			)
			(layer "F.Fab")
		)
		(fp_line
			(start -0.12065 -0.305054)
			(end -0.12065 -0.2794)
			(stroke
				(width 0.1)
				(type default)
			)
			(layer "F.Fab")
		)
		(fp_line
			(start -0.67945 0.3048)
			(end -0.67945 -0.305054)
			(stroke
				(width 0.1)
				(type default)
			)
			(layer "F.Fab")
		)
		(fp_line
			(start -0.67945 -0.305054)
			(end -0.12065 -0.305054)
			(stroke
				(width 0.1)
				(type default)
			)
			(layer "F.Fab")
		)
		(pad "1" smd circle
			(at -0.40005 0 180)
			(size 0 0)
			(layers "F.Cu" "F.Mask" "F.Paste")
			(net "BIC_I2C9_SSD_MUX0_A0")
		)
		(pad "2" smd circle
			(at 0.40005 0 180)
			(size 0 0)
			(layers "F.Cu" "F.Mask" "F.Paste")
			(net "GND")
		)
	)
	(footprint ""
		(layer "F.Cu")
		(at 127.381508 -350.098614 90)
		(property "Reference" "C354"
			(at 0 0 90)
			(layer "F.SilkS")
			(hide yes)
			(effects
				(font
					(size 1.27 1.27)
				)
			)
		)
		(property "Value" ""
			(at 0 0 90)
			(layer "F.Fab")
			(effects
				(font
					(size 1.27 1.27)
				)
			)
		)
		(duplicate_pad_numbers_are_jumpers no)
		(fp_line
			(start 0.299974 -0.150114)
			(end 0.299974 0.150114)
			(stroke
				(width 0.1)
				(type default)
			)
			(layer "F.Fab")
		)
		(fp_line
			(start -0.299974 -0.150114)
			(end 0.299974 -0.150114)
			(stroke
				(width 0.1)
				(type default)
			)
			(layer "F.Fab")
		)
		(fp_line
			(start 0.299974 0.150114)
			(end -0.299974 0.150114)
			(stroke
				(width 0.1)
				(type default)
			)
			(layer "F.Fab")
		)
		(fp_line
			(start -0.299974 0.150114)
			(end -0.299974 -0.150114)
			(stroke
				(width 0.1)
				(type default)
			)
			(layer "F.Fab")
		)
		(pad "1" smd rect
			(at -0.2667 0 90)
			(size 0.3048 0.381)
			(layers "F.Cu" "F.Mask" "F.Paste")
			(net "P5E_PEX1_STN6_TX_DP<104>")
		)
		(pad "2" smd rect
			(at 0.2667 0 90)
			(size 0.3048 0.381)
			(layers "F.Cu" "F.Mask" "F.Paste")
			(net "P5E_PEX1_STN6_TX_C_DP<104>")
		)
	)
	(footprint ""
		(layer "F.Cu")
		(at 97.25787 -72.766682 90)
		(property "Reference" "PC653"
			(at 0 0 90)
			(layer "F.SilkS")
			(hide yes)
			(effects
				(font
					(size 1.27 1.27)
				)
			)
		)
		(property "Value" ""
			(at 0 0 90)
			(layer "F.Fab")
			(effects
				(font
					(size 1.27 1.27)
				)
			)
		)
		(duplicate_pad_numbers_are_jumpers no)
		(fp_line
			(start 0.7874 -0.4064)
			(end 0.7874 0.4064)
			(stroke
				(width 0.1524)
				(type default)
			)
			(layer "F.SilkS")
		)
		(fp_line
			(start -0.7874 -0.4064)
			(end 0.7874 -0.4064)
			(stroke
				(width 0.1524)
				(type default)
			)
			(layer "F.SilkS")
		)
		(fp_line
			(start 0.7874 0.4064)
			(end -0.7874 0.4064)
			(stroke
				(width 0.1524)
				(type default)
			)
			(layer "F.SilkS")
		)
		(fp_line
			(start -0.7874 0.4064)
			(end -0.7874 -0.4064)
			(stroke
				(width 0.1524)
				(type default)
			)
			(layer "F.SilkS")
		)
		(fp_line
			(start -0.12065 -0.305054)
			(end -0.12065 -0.2794)
			(stroke
				(width 0.1)
				(type default)
			)
			(layer "F.Fab")
		)
		(fp_line
			(start -0.67945 -0.305054)
			(end -0.12065 -0.305054)
			(stroke
				(width 0.1)
				(type default)
			)
			(layer "F.Fab")
		)
		(fp_line
			(start 0.67945 -0.3048)
			(end 0.67945 0.3048)
			(stroke
				(width 0.1)
				(type default)
			)
			(layer "F.Fab")
		)
		(fp_line
			(start 0.12065 -0.3048)
			(end 0.67945 -0.3048)
			(stroke
				(width 0.1)
				(type default)
			)
			(layer "F.Fab")
		)
		(fp_line
			(start 0.12065 -0.2794)
			(end 0.12065 -0.3048)
			(stroke
				(width 0.1)
				(type default)
			)
			(layer "F.Fab")
		)
		(fp_line
			(start -0.12065 -0.2794)
			(end 0.12065 -0.2794)
			(stroke
				(width 0.1)
				(type default)
			)
			(layer "F.Fab")
		)
		(fp_line
			(start 0.120396 0.2794)
			(end -0.12065 0.2794)
			(stroke
				(width 0.1)
				(type default)
			)
			(layer "F.Fab")
		)
		(fp_line
			(start -0.12065 0.2794)
			(end -0.12065 0.3048)
			(stroke
				(width 0.1)
				(type default)
			)
			(layer "F.Fab")
		)
		(fp_line
			(start 0.67945 0.3048)
			(end 0.120396 0.3048)
			(stroke
				(width 0.1)
				(type default)
			)
			(layer "F.Fab")
		)
		(fp_line
			(start 0.120396 0.3048)
			(end 0.120396 0.2794)
			(stroke
				(width 0.1)
				(type default)
			)
			(layer "F.Fab")
		)
		(fp_line
			(start -0.12065 0.3048)
			(end -0.67945 0.3048)
			(stroke
				(width 0.1)
				(type default)
			)
			(layer "F.Fab")
		)
		(fp_line
			(start -0.67945 0.3048)
			(end -0.67945 -0.305054)
			(stroke
				(width 0.1)
				(type default)
			)
			(layer "F.Fab")
		)
		(pad "1" smd circle
			(at -0.40005 0 90)
			(size 0 0)
			(layers "F.Cu" "F.Mask" "F.Paste")
			(net "P12V_SSD3_CO_MODE")
		)
		(pad "2" smd circle
			(at 0.40005 0 90)
			(size 0 0)
			(layers "F.Cu" "F.Mask" "F.Paste")
			(net "GND")
		)
	)
	(footprint ""
		(layer "F.Cu")
		(at 320.235834 -303.61128 90)
		(property "Reference" "R6719"
			(at 0 0 90)
			(layer "F.SilkS")
			(hide yes)
			(effects
				(font
					(size 1.27 1.27)
				)
			)
		)
		(property "Value" ""
			(at 0 0 90)
			(layer "F.Fab")
			(effects
				(font
					(size 1.27 1.27)
				)
			)
		)
		(duplicate_pad_numbers_are_jumpers no)
		(fp_line
			(start 0.7874 -0.4064)
			(end 0.7874 0.4064)
			(stroke
				(width 0.1524)
				(type default)
			)
			(layer "F.SilkS")
		)
		(fp_line
			(start -0.7874 -0.4064)
			(end 0.7874 -0.4064)
			(stroke
				(width 0.1524)
				(type default)
			)
			(layer "F.SilkS")
		)
		(fp_line
			(start 0.7874 0.4064)
			(end -0.7874 0.4064)
			(stroke
				(width 0.1524)
				(type default)
			)
			(layer "F.SilkS")
		)
		(fp_line
			(start -0.7874 0.4064)
			(end -0.7874 -0.4064)
			(stroke
				(width 0.1524)
				(type default)
			)
			(layer "F.SilkS")
		)
		(fp_line
			(start -0.12065 -0.305054)
			(end -0.12065 -0.2794)
			(stroke
				(width 0.1)
				(type default)
			)
			(layer "F.Fab")
		)
		(fp_line
			(start -0.67945 -0.305054)
			(end -0.12065 -0.305054)
			(stroke
				(width 0.1)
				(type default)
			)
			(layer "F.Fab")
		)
		(fp_line
			(start 0.67945 -0.3048)
			(end 0.67945 0.3048)
			(stroke
				(width 0.1)
				(type default)
			)
			(layer "F.Fab")
		)
		(fp_line
			(start 0.12065 -0.3048)
			(end 0.67945 -0.3048)
			(stroke
				(width 0.1)
				(type default)
			)
			(layer "F.Fab")
		)
		(fp_line
			(start 0.12065 -0.2794)
			(end 0.12065 -0.3048)
			(stroke
				(width 0.1)
				(type default)
			)
			(layer "F.Fab")
		)
		(fp_line
			(start -0.12065 -0.2794)
			(end 0.12065 -0.2794)
			(stroke
				(width 0.1)
				(type default)
			)
			(layer "F.Fab")
		)
		(fp_line
			(start 0.120396 0.2794)
			(end -0.12065 0.2794)
			(stroke
				(width 0.1)
				(type default)
			)
			(layer "F.Fab")
		)
		(fp_line
			(start -0.12065 0.2794)
			(end -0.12065 0.3048)
			(stroke
				(width 0.1)
				(type default)
			)
			(layer "F.Fab")
		)
		(fp_line
			(start 0.67945 0.3048)
			(end 0.120396 0.3048)
			(stroke
				(width 0.1)
				(type default)
			)
			(layer "F.Fab")
		)
		(fp_line
			(start 0.120396 0.3048)
			(end 0.120396 0.2794)
			(stroke
				(width 0.1)
				(type default)
			)
			(layer "F.Fab")
		)
		(fp_line
			(start -0.12065 0.3048)
			(end -0.67945 0.3048)
			(stroke
				(width 0.1)
				(type default)
			)
			(layer "F.Fab")
		)
		(fp_line
			(start -0.67945 0.3048)
			(end -0.67945 -0.305054)
			(stroke
				(width 0.1)
				(type default)
			)
			(layer "F.Fab")
		)
		(pad "1" smd circle
			(at -0.40005 0 90)
			(size 0 0)
			(layers "F.Cu" "F.Mask" "F.Paste")
			(net "SMB_PEX2_SLAVE1_SDA")
		)
		(pad "2" smd circle
			(at 0.40005 0 90)
			(size 0 0)
			(layers "F.Cu" "F.Mask" "F.Paste")
			(net "SMB_PEX2_R_SDA")
		)
	)
	(footprint ""
		(layer "F.Cu")
		(at 300.187868 -45.704252 90)
		(property "Reference" "R615"
			(at 0 0 90)
			(layer "F.SilkS")
			(hide yes)
			(effects
				(font
					(size 1.27 1.27)
				)
			)
		)
		(property "Value" ""
			(at 0 0 90)
			(layer "F.Fab")
			(effects
				(font
					(size 1.27 1.27)
				)
			)
		)
		(duplicate_pad_numbers_are_jumpers no)
		(fp_line
			(start 3.937508 -1.8796)
			(end -3.937508 -1.8796)
			(stroke
				(width 0.1524)
				(type default)
			)
			(layer "F.SilkS")
		)
		(fp_line
			(start -3.937508 -1.8796)
			(end -3.937508 1.8796)
			(stroke
				(width 0.1524)
				(type default)
			)
			(layer "F.SilkS")
		)
		(fp_line
			(start 3.937508 1.8796)
			(end 3.937508 -1.8796)
			(stroke
				(width 0.1524)
				(type default)
			)
			(layer "F.SilkS")
		)
		(fp_line
			(start -3.937508 1.8796)
			(end 3.937508 1.8796)
			(stroke
				(width 0.1524)
				(type default)
			)
			(layer "F.SilkS")
		)
		(fp_line
			(start 3.275076 -1.674876)
			(end -3.275076 -1.674876)
			(stroke
				(width 0.1)
				(type default)
			)
			(layer "F.Fab")
		)
		(fp_line
			(start -3.275076 -1.674876)
			(end -3.275076 1.674876)
			(stroke
				(width 0.1)
				(type default)
			)
			(layer "F.Fab")
		)
		(fp_line
			(start 3.275076 1.674876)
			(end 3.275076 -1.674876)
			(stroke
				(width 0.1)
				(type default)
			)
			(layer "F.Fab")
		)
		(fp_line
			(start -3.275076 1.674876)
			(end 3.275076 1.674876)
			(stroke
				(width 0.1)
				(type default)
			)
			(layer "F.Fab")
		)
		(pad "1" smd rect
			(at -2.350008 0 90)
			(size 2.921 3.5052)
			(layers "F.Cu" "F.Mask" "F.Paste")
			(net "P12V_SSD10")
		)
		(pad "2" smd rect
			(at 2.350008 0 90)
			(size 2.921 3.5052)
			(layers "F.Cu" "F.Mask" "F.Paste")
			(net "P12V_SSD10_R")
		)
	)
	(footprint ""
		(layer "F.Cu")
		(at 370.185696 -27.092148 -90)
		(property "Reference" "R5751"
			(at 0 0 270)
			(layer "F.SilkS")
			(hide yes)
			(effects
				(font
					(size 1.27 1.27)
				)
			)
		)
		(property "Value" ""
			(at 0 0 270)
			(layer "F.Fab")
			(effects
				(font
					(size 1.27 1.27)
				)
			)
		)
		(duplicate_pad_numbers_are_jumpers no)
		(fp_line
			(start -0.7874 0.4064)
			(end -0.7874 -0.4064)
			(stroke
				(width 0.1524)
				(type default)
			)
			(layer "F.SilkS")
		)
		(fp_line
			(start 0.7874 0.4064)
			(end -0.7874 0.4064)
			(stroke
				(width 0.1524)
				(type default)
			)
			(layer "F.SilkS")
		)
		(fp_line
			(start -0.7874 -0.4064)
			(end 0.7874 -0.4064)
			(stroke
				(width 0.1524)
				(type default)
			)
			(layer "F.SilkS")
		)
		(fp_line
			(start 0.7874 -0.4064)
			(end 0.7874 0.4064)
			(stroke
				(width 0.1524)
				(type default)
			)
			(layer "F.SilkS")
		)
		(fp_line
			(start -0.67945 0.3048)
			(end -0.67945 -0.305054)
			(stroke
				(width 0.1)
				(type default)
			)
			(layer "F.Fab")
		)
		(fp_line
			(start -0.12065 0.3048)
			(end -0.67945 0.3048)
			(stroke
				(width 0.1)
				(type default)
			)
			(layer "F.Fab")
		)
		(fp_line
			(start 0.120396 0.3048)
			(end 0.120396 0.2794)
			(stroke
				(width 0.1)
				(type default)
			)
			(layer "F.Fab")
		)
		(fp_line
			(start 0.67945 0.3048)
			(end 0.120396 0.3048)
			(stroke
				(width 0.1)
				(type default)
			)
			(layer "F.Fab")
		)
		(fp_line
			(start -0.12065 0.2794)
			(end -0.12065 0.3048)
			(stroke
				(width 0.1)
				(type default)
			)
			(layer "F.Fab")
		)
		(fp_line
			(start 0.120396 0.2794)
			(end -0.12065 0.2794)
			(stroke
				(width 0.1)
				(type default)
			)
			(layer "F.Fab")
		)
		(fp_line
			(start -0.12065 -0.2794)
			(end 0.12065 -0.2794)
			(stroke
				(width 0.1)
				(type default)
			)
			(layer "F.Fab")
		)
		(fp_line
			(start 0.12065 -0.2794)
			(end 0.12065 -0.3048)
			(stroke
				(width 0.1)
				(type default)
			)
			(layer "F.Fab")
		)
		(fp_line
			(start 0.12065 -0.3048)
			(end 0.67945 -0.3048)
			(stroke
				(width 0.1)
				(type default)
			)
			(layer "F.Fab")
		)
		(fp_line
			(start 0.67945 -0.3048)
			(end 0.67945 0.3048)
			(stroke
				(width 0.1)
				(type default)
			)
			(layer "F.Fab")
		)
		(fp_line
			(start -0.67945 -0.305054)
			(end -0.12065 -0.305054)
			(stroke
				(width 0.1)
				(type default)
			)
			(layer "F.Fab")
		)
		(fp_line
			(start -0.12065 -0.305054)
			(end -0.12065 -0.2794)
			(stroke
				(width 0.1)
				(type default)
			)
			(layer "F.Fab")
		)
		(pad "1" smd circle
			(at -0.40005 0 270)
			(size 0 0)
			(layers "F.Cu" "F.Mask" "F.Paste")
			(net "P3V3_SSD12")
		)
		(pad "2" smd circle
			(at 0.40005 0 270)
			(size 0 0)
			(layers "F.Cu" "F.Mask" "F.Paste")
			(net "SSD12_LED_ISO_N")
		)
	)
	(footprint ""
		(layer "F.Cu")
		(at 217.756486 -20.467574 180)
		(property "Reference" "R1678"
			(at 0 0 180)
			(layer "F.SilkS")
			(hide yes)
			(effects
				(font
					(size 1.27 1.27)
				)
			)
		)
		(property "Value" ""
			(at 0 0 180)
			(layer "F.Fab")
			(effects
				(font
					(size 1.27 1.27)
				)
			)
		)
		(duplicate_pad_numbers_are_jumpers no)
		(fp_line
			(start 0.7874 0.4064)
			(end -0.7874 0.4064)
			(stroke
				(width 0.1524)
				(type default)
			)
			(layer "F.SilkS")
		)
		(fp_line
			(start 0.7874 -0.4064)
			(end 0.7874 0.4064)
			(stroke
				(width 0.1524)
				(type default)
			)
			(layer "F.SilkS")
		)
		(fp_line
			(start -0.7874 0.4064)
			(end -0.7874 -0.4064)
			(stroke
				(width 0.1524)
				(type default)
			)
			(layer "F.SilkS")
		)
		(fp_line
			(start -0.7874 -0.4064)
			(end 0.7874 -0.4064)
			(stroke
				(width 0.1524)
				(type default)
			)
			(layer "F.SilkS")
		)
		(fp_line
			(start 0.67945 0.3048)
			(end 0.120396 0.3048)
			(stroke
				(width 0.1)
				(type default)
			)
			(layer "F.Fab")
		)
		(fp_line
			(start 0.67945 -0.3048)
			(end 0.67945 0.3048)
			(stroke
				(width 0.1)
				(type default)
			)
			(layer "F.Fab")
		)
		(fp_line
			(start 0.12065 -0.2794)
			(end 0.12065 -0.3048)
			(stroke
				(width 0.1)
				(type default)
			)
			(layer "F.Fab")
		)
		(fp_line
			(start 0.12065 -0.3048)
			(end 0.67945 -0.3048)
			(stroke
				(width 0.1)
				(type default)
			)
			(layer "F.Fab")
		)
		(fp_line
			(start 0.120396 0.3048)
			(end 0.120396 0.2794)
			(stroke
				(width 0.1)
				(type default)
			)
			(layer "F.Fab")
		)
		(fp_line
			(start 0.120396 0.2794)
			(end -0.12065 0.2794)
			(stroke
				(width 0.1)
				(type default)
			)
			(layer "F.Fab")
		)
		(fp_line
			(start -0.12065 0.3048)
			(end -0.67945 0.3048)
			(stroke
				(width 0.1)
				(type default)
			)
			(layer "F.Fab")
		)
		(fp_line
			(start -0.12065 0.2794)
			(end -0.12065 0.3048)
			(stroke
				(width 0.1)
				(type default)
			)
			(layer "F.Fab")
		)
		(fp_line
			(start -0.12065 -0.2794)
			(end 0.12065 -0.2794)
			(stroke
				(width 0.1)
				(type default)
			)
			(layer "F.Fab")
		)
		(fp_line
			(start -0.12065 -0.305054)
			(end -0.12065 -0.2794)
			(stroke
				(width 0.1)
				(type default)
			)
			(layer "F.Fab")
		)
		(fp_line
			(start -0.67945 0.3048)
			(end -0.67945 -0.305054)
			(stroke
				(width 0.1)
				(type default)
			)
			(layer "F.Fab")
		)
		(fp_line
			(start -0.67945 -0.305054)
			(end -0.12065 -0.305054)
			(stroke
				(width 0.1)
				(type default)
			)
			(layer "F.Fab")
		)
		(pad "1" smd circle
			(at -0.40005 0 180)
			(size 0 0)
			(layers "F.Cu" "F.Mask" "F.Paste")
			(net "P3V3_SSD7")
		)
		(pad "2" smd circle
			(at 0.40005 0 180)
			(size 0 0)
			(layers "F.Cu" "F.Mask" "F.Paste")
			(net "SMB_ISO_SSD7_SDA")
		)
	)
	(footprint ""
		(layer "F.Cu")
		(at 374.674384 -252.356874 -90)
		(property "Reference" "R1427"
			(at 0 0 270)
			(layer "F.SilkS")
			(hide yes)
			(effects
				(font
					(size 1.27 1.27)
				)
			)
		)
		(property "Value" ""
			(at 0 0 270)
			(layer "F.Fab")
			(effects
				(font
					(size 1.27 1.27)
				)
			)
		)
		(duplicate_pad_numbers_are_jumpers no)
		(fp_line
			(start -0.7874 0.4064)
			(end -0.7874 -0.4064)
			(stroke
				(width 0.1524)
				(type default)
			)
			(layer "F.SilkS")
		)
		(fp_line
			(start 0.7874 0.4064)
			(end -0.7874 0.4064)
			(stroke
				(width 0.1524)
				(type default)
			)
			(layer "F.SilkS")
		)
		(fp_line
			(start -0.7874 -0.4064)
			(end 0.7874 -0.4064)
			(stroke
				(width 0.1524)
				(type default)
			)
			(layer "F.SilkS")
		)
		(fp_line
			(start 0.7874 -0.4064)
			(end 0.7874 0.4064)
			(stroke
				(width 0.1524)
				(type default)
			)
			(layer "F.SilkS")
		)
		(fp_line
			(start -0.67945 0.3048)
			(end -0.67945 -0.305054)
			(stroke
				(width 0.1)
				(type default)
			)
			(layer "F.Fab")
		)
		(fp_line
			(start -0.12065 0.3048)
			(end -0.67945 0.3048)
			(stroke
				(width 0.1)
				(type default)
			)
			(layer "F.Fab")
		)
		(fp_line
			(start 0.120396 0.3048)
			(end 0.120396 0.2794)
			(stroke
				(width 0.1)
				(type default)
			)
			(layer "F.Fab")
		)
		(fp_line
			(start 0.67945 0.3048)
			(end 0.120396 0.3048)
			(stroke
				(width 0.1)
				(type default)
			)
			(layer "F.Fab")
		)
		(fp_line
			(start -0.12065 0.2794)
			(end -0.12065 0.3048)
			(stroke
				(width 0.1)
				(type default)
			)
			(layer "F.Fab")
		)
		(fp_line
			(start 0.120396 0.2794)
			(end -0.12065 0.2794)
			(stroke
				(width 0.1)
				(type default)
			)
			(layer "F.Fab")
		)
		(fp_line
			(start -0.12065 -0.2794)
			(end 0.12065 -0.2794)
			(stroke
				(width 0.1)
				(type default)
			)
			(layer "F.Fab")
		)
		(fp_line
			(start 0.12065 -0.2794)
			(end 0.12065 -0.3048)
			(stroke
				(width 0.1)
				(type default)
			)
			(layer "F.Fab")
		)
		(fp_line
			(start 0.12065 -0.3048)
			(end 0.67945 -0.3048)
			(stroke
				(width 0.1)
				(type default)
			)
			(layer "F.Fab")
		)
		(fp_line
			(start 0.67945 -0.3048)
			(end 0.67945 0.3048)
			(stroke
				(width 0.1)
				(type default)
			)
			(layer "F.Fab")
		)
		(fp_line
			(start -0.67945 -0.305054)
			(end -0.12065 -0.305054)
			(stroke
				(width 0.1)
				(type default)
			)
			(layer "F.Fab")
		)
		(fp_line
			(start -0.12065 -0.305054)
			(end -0.12065 -0.2794)
			(stroke
				(width 0.1)
				(type default)
			)
			(layer "F.Fab")
		)
		(pad "1" smd circle
			(at -0.40005 0 270)
			(size 0 0)
			(layers "F.Cu" "F.Mask" "F.Paste")
			(net "GND")
		)
		(pad "2" smd circle
			(at 0.40005 0 270)
			(size 0 0)
			(layers "F.Cu" "F.Mask" "F.Paste")
			(net "PEX3_MODE_SEL2")
		)
	)
	(footprint ""
		(layer "F.Cu")
		(at 214.775034 -56.977534 180)
		(property "Reference" "PC388"
			(at 0 0 180)
			(layer "F.SilkS")
			(hide yes)
			(effects
				(font
					(size 1.27 1.27)
				)
			)
		)
		(property "Value" ""
			(at 0 0 180)
			(layer "F.Fab")
			(effects
				(font
					(size 1.27 1.27)
				)
			)
		)
		(duplicate_pad_numbers_are_jumpers no)
		(fp_line
			(start 0.7874 0.4064)
			(end -0.7874 0.4064)
			(stroke
				(width 0.1524)
				(type default)
			)
			(layer "F.SilkS")
		)
		(fp_line
			(start 0.7874 -0.4064)
			(end 0.7874 0.4064)
			(stroke
				(width 0.1524)
				(type default)
			)
			(layer "F.SilkS")
		)
		(fp_line
			(start -0.7874 0.4064)
			(end -0.7874 -0.4064)
			(stroke
				(width 0.1524)
				(type default)
			)
			(layer "F.SilkS")
		)
		(fp_line
			(start -0.7874 -0.4064)
			(end 0.7874 -0.4064)
			(stroke
				(width 0.1524)
				(type default)
			)
			(layer "F.SilkS")
		)
		(fp_line
			(start 0.67945 0.3048)
			(end 0.120396 0.3048)
			(stroke
				(width 0.1)
				(type default)
			)
			(layer "F.Fab")
		)
		(fp_line
			(start 0.67945 -0.3048)
			(end 0.67945 0.3048)
			(stroke
				(width 0.1)
				(type default)
			)
			(layer "F.Fab")
		)
		(fp_line
			(start 0.12065 -0.2794)
			(end 0.12065 -0.3048)
			(stroke
				(width 0.1)
				(type default)
			)
			(layer "F.Fab")
		)
		(fp_line
			(start 0.12065 -0.3048)
			(end 0.67945 -0.3048)
			(stroke
				(width 0.1)
				(type default)
			)
			(layer "F.Fab")
		)
		(fp_line
			(start 0.120396 0.3048)
			(end 0.120396 0.2794)
			(stroke
				(width 0.1)
				(type default)
			)
			(layer "F.Fab")
		)
		(fp_line
			(start 0.120396 0.2794)
			(end -0.12065 0.2794)
			(stroke
				(width 0.1)
				(type default)
			)
			(layer "F.Fab")
		)
		(fp_line
			(start -0.12065 0.3048)
			(end -0.67945 0.3048)
			(stroke
				(width 0.1)
				(type default)
			)
			(layer "F.Fab")
		)
		(fp_line
			(start -0.12065 0.2794)
			(end -0.12065 0.3048)
			(stroke
				(width 0.1)
				(type default)
			)
			(layer "F.Fab")
		)
		(fp_line
			(start -0.12065 -0.2794)
			(end 0.12065 -0.2794)
			(stroke
				(width 0.1)
				(type default)
			)
			(layer "F.Fab")
		)
		(fp_line
			(start -0.12065 -0.305054)
			(end -0.12065 -0.2794)
			(stroke
				(width 0.1)
				(type default)
			)
			(layer "F.Fab")
		)
		(fp_line
			(start -0.67945 0.3048)
			(end -0.67945 -0.305054)
			(stroke
				(width 0.1)
				(type default)
			)
			(layer "F.Fab")
		)
		(fp_line
			(start -0.67945 -0.305054)
			(end -0.12065 -0.305054)
			(stroke
				(width 0.1)
				(type default)
			)
			(layer "F.Fab")
		)
		(pad "1" smd circle
			(at -0.40005 0 180)
			(size 0 0)
			(layers "F.Cu" "F.Mask" "F.Paste")
			(net "P12V_AUX")
		)
		(pad "2" smd circle
			(at 0.40005 0 180)
			(size 0 0)
			(layers "F.Cu" "F.Mask" "F.Paste")
			(net "GND")
		)
	)
	(footprint ""
		(layer "F.Cu")
		(at 338.963 -234.061 90)
		(property "Reference" "R3586"
			(at 0 0 90)
			(layer "F.SilkS")
			(hide yes)
			(effects
				(font
					(size 1.27 1.27)
				)
			)
		)
		(property "Value" ""
			(at 0 0 90)
			(layer "F.Fab")
			(effects
				(font
					(size 1.27 1.27)
				)
			)
		)
		(duplicate_pad_numbers_are_jumpers no)
		(fp_line
			(start 0.7874 -0.4064)
			(end 0.7874 0.4064)
			(stroke
				(width 0.1524)
				(type default)
			)
			(layer "F.SilkS")
		)
		(fp_line
			(start -0.7874 -0.4064)
			(end 0.7874 -0.4064)
			(stroke
				(width 0.1524)
				(type default)
			)
			(layer "F.SilkS")
		)
		(fp_line
			(start 0.7874 0.4064)
			(end -0.7874 0.4064)
			(stroke
				(width 0.1524)
				(type default)
			)
			(layer "F.SilkS")
		)
		(fp_line
			(start -0.7874 0.4064)
			(end -0.7874 -0.4064)
			(stroke
				(width 0.1524)
				(type default)
			)
			(layer "F.SilkS")
		)
		(fp_line
			(start -0.12065 -0.305054)
			(end -0.12065 -0.2794)
			(stroke
				(width 0.1)
				(type default)
			)
			(layer "F.Fab")
		)
		(fp_line
			(start -0.67945 -0.305054)
			(end -0.12065 -0.305054)
			(stroke
				(width 0.1)
				(type default)
			)
			(layer "F.Fab")
		)
		(fp_line
			(start 0.67945 -0.3048)
			(end 0.67945 0.3048)
			(stroke
				(width 0.1)
				(type default)
			)
			(layer "F.Fab")
		)
		(fp_line
			(start 0.12065 -0.3048)
			(end 0.67945 -0.3048)
			(stroke
				(width 0.1)
				(type default)
			)
			(layer "F.Fab")
		)
		(fp_line
			(start 0.12065 -0.2794)
			(end 0.12065 -0.3048)
			(stroke
				(width 0.1)
				(type default)
			)
			(layer "F.Fab")
		)
		(fp_line
			(start -0.12065 -0.2794)
			(end 0.12065 -0.2794)
			(stroke
				(width 0.1)
				(type default)
			)
			(layer "F.Fab")
		)
		(fp_line
			(start 0.120396 0.2794)
			(end -0.12065 0.2794)
			(stroke
				(width 0.1)
				(type default)
			)
			(layer "F.Fab")
		)
		(fp_line
			(start -0.12065 0.2794)
			(end -0.12065 0.3048)
			(stroke
				(width 0.1)
				(type default)
			)
			(layer "F.Fab")
		)
		(fp_line
			(start 0.67945 0.3048)
			(end 0.120396 0.3048)
			(stroke
				(width 0.1)
				(type default)
			)
			(layer "F.Fab")
		)
		(fp_line
			(start 0.120396 0.3048)
			(end 0.120396 0.2794)
			(stroke
				(width 0.1)
				(type default)
			)
			(layer "F.Fab")
		)
		(fp_line
			(start -0.12065 0.3048)
			(end -0.67945 0.3048)
			(stroke
				(width 0.1)
				(type default)
			)
			(layer "F.Fab")
		)
		(fp_line
			(start -0.67945 0.3048)
			(end -0.67945 -0.305054)
			(stroke
				(width 0.1)
				(type default)
			)
			(layer "F.Fab")
		)
		(pad "1" smd circle
			(at -0.40005 0 90)
			(size 0 0)
			(layers "F.Cu" "F.Mask" "F.Paste")
			(net "SSD0_CLK_EN_N")
		)
		(pad "2" smd circle
			(at 0.40005 0 90)
			(size 0 0)
			(layers "F.Cu" "F.Mask" "F.Paste")
			(net "SSD0_CLK_EN_R_N")
		)
	)
	(footprint ""
		(layer "F.Cu")
		(at 446.855596 -254.5969 -90)
		(property "Reference" "C4408"
			(at 0 0 270)
			(layer "F.SilkS")
			(hide yes)
			(effects
				(font
					(size 1.27 1.27)
				)
			)
		)
		(property "Value" ""
			(at 0 0 270)
			(layer "F.Fab")
			(effects
				(font
					(size 1.27 1.27)
				)
			)
		)
		(duplicate_pad_numbers_are_jumpers no)
		(fp_line
			(start -1.2954 0.5842)
			(end -1.2954 -0.5842)
			(stroke
				(width 0.1524)
				(type default)
			)
			(layer "F.SilkS")
		)
		(fp_line
			(start 1.2954 0.5842)
			(end -1.2954 0.5842)
			(stroke
				(width 0.1524)
				(type default)
			)
			(layer "F.SilkS")
		)
		(fp_line
			(start -1.2954 -0.5842)
			(end 1.2954 -0.5842)
			(stroke
				(width 0.1524)
				(type default)
			)
			(layer "F.SilkS")
		)
		(fp_line
			(start 1.2954 -0.5842)
			(end 1.2954 0.5842)
			(stroke
				(width 0.1524)
				(type default)
			)
			(layer "F.SilkS")
		)
		(fp_line
			(start -0.8636 0.4572)
			(end -0.8636 0.4064)
			(stroke
				(width 0.1)
				(type default)
			)
			(layer "F.Fab")
		)
		(fp_line
			(start 0.8636 0.4572)
			(end -0.8636 0.4572)
			(stroke
				(width 0.1)
				(type default)
			)
			(layer "F.Fab")
		)
		(fp_line
			(start -1.1938 0.4064)
			(end -1.1938 -0.4064)
			(stroke
				(width 0.1)
				(type default)
			)
			(layer "F.Fab")
		)
		(fp_line
			(start -0.8636 0.4064)
			(end -1.1938 0.4064)
			(stroke
				(width 0.1)
				(type default)
			)
			(layer "F.Fab")
		)
		(fp_line
			(start 0.8636 0.4064)
			(end 0.8636 0.4572)
			(stroke
				(width 0.1)
				(type default)
			)
			(layer "F.Fab")
		)
		(fp_line
			(start 1.1938 0.4064)
			(end 0.8636 0.4064)
			(stroke
				(width 0.1)
				(type default)
			)
			(layer "F.Fab")
		)
		(fp_line
			(start -1.1938 -0.4064)
			(end -0.8636 -0.4064)
			(stroke
				(width 0.1)
				(type default)
			)
			(layer "F.Fab")
		)
		(fp_line
			(start -0.8636 -0.4064)
			(end -0.8636 -0.4572)
			(stroke
				(width 0.1)
				(type default)
			)
			(layer "F.Fab")
		)
		(fp_line
			(start 0.8636 -0.4064)
			(end 1.1938 -0.4064)
			(stroke
				(width 0.1)
				(type default)
			)
			(layer "F.Fab")
		)
		(fp_line
			(start 1.1938 -0.4064)
			(end 1.1938 0.4064)
			(stroke
				(width 0.1)
				(type default)
			)
			(layer "F.Fab")
		)
		(fp_line
			(start -0.8636 -0.4572)
			(end 0.8636 -0.4572)
			(stroke
				(width 0.1)
				(type default)
			)
			(layer "F.Fab")
		)
		(fp_line
			(start 0.8636 -0.4572)
			(end 0.8636 -0.4064)
			(stroke
				(width 0.1)
				(type default)
			)
			(layer "F.Fab")
		)
		(pad "1" smd rect
			(at -0.7366 0 180)
			(size 0.7112 0.8128)
			(layers "F.Cu" "F.Mask" "F.Paste")
			(net "P1V25_SERDES_VDDPLL_PEX3_C6")
		)
		(pad "2" smd rect
			(at 0.7366 0 180)
			(size 0.7112 0.8128)
			(layers "F.Cu" "F.Mask" "F.Paste")
			(net "GND")
		)
	)
	(footprint ""
		(layer "F.Cu")
		(at 133.77672 -280.344118)
		(property "Reference" "PC106"
			(at 0 0 0)
			(layer "F.SilkS")
			(hide yes)
			(effects
				(font
					(size 1.27 1.27)
				)
			)
		)
		(property "Value" ""
			(at 0 0 0)
			(layer "F.Fab")
			(effects
				(font
					(size 1.27 1.27)
				)
			)
		)
		(duplicate_pad_numbers_are_jumpers no)
		(fp_line
			(start -0.7874 -0.4064)
			(end 0.7874 -0.4064)
			(stroke
				(width 0.1524)
				(type default)
			)
			(layer "F.SilkS")
		)
		(fp_line
			(start -0.7874 0.4064)
			(end -0.7874 -0.4064)
			(stroke
				(width 0.1524)
				(type default)
			)
			(layer "F.SilkS")
		)
		(fp_line
			(start 0.7874 -0.4064)
			(end 0.7874 0.4064)
			(stroke
				(width 0.1524)
				(type default)
			)
			(layer "F.SilkS")
		)
		(fp_line
			(start 0.7874 0.4064)
			(end -0.7874 0.4064)
			(stroke
				(width 0.1524)
				(type default)
			)
			(layer "F.SilkS")
		)
		(fp_line
			(start -0.67945 -0.305054)
			(end -0.12065 -0.305054)
			(stroke
				(width 0.1)
				(type default)
			)
			(layer "F.Fab")
		)
		(fp_line
			(start -0.67945 0.3048)
			(end -0.67945 -0.305054)
			(stroke
				(width 0.1)
				(type default)
			)
			(layer "F.Fab")
		)
		(fp_line
			(start -0.12065 -0.305054)
			(end -0.12065 -0.2794)
			(stroke
				(width 0.1)
				(type default)
			)
			(layer "F.Fab")
		)
		(fp_line
			(start -0.12065 -0.2794)
			(end 0.12065 -0.2794)
			(stroke
				(width 0.1)
				(type default)
			)
			(layer "F.Fab")
		)
		(fp_line
			(start -0.12065 0.2794)
			(end -0.12065 0.3048)
			(stroke
				(width 0.1)
				(type default)
			)
			(layer "F.Fab")
		)
		(fp_line
			(start -0.12065 0.3048)
			(end -0.67945 0.3048)
			(stroke
				(width 0.1)
				(type default)
			)
			(layer "F.Fab")
		)
		(fp_line
			(start 0.120396 0.2794)
			(end -0.12065 0.2794)
			(stroke
				(width 0.1)
				(type default)
			)
			(layer "F.Fab")
		)
		(fp_line
			(start 0.120396 0.3048)
			(end 0.120396 0.2794)
			(stroke
				(width 0.1)
				(type default)
			)
			(layer "F.Fab")
		)
		(fp_line
			(start 0.12065 -0.3048)
			(end 0.67945 -0.3048)
			(stroke
				(width 0.1)
				(type default)
			)
			(layer "F.Fab")
		)
		(fp_line
			(start 0.12065 -0.2794)
			(end 0.12065 -0.3048)
			(stroke
				(width 0.1)
				(type default)
			)
			(layer "F.Fab")
		)
		(fp_line
			(start 0.67945 -0.3048)
			(end 0.67945 0.3048)
			(stroke
				(width 0.1)
				(type default)
			)
			(layer "F.Fab")
		)
		(fp_line
			(start 0.67945 0.3048)
			(end 0.120396 0.3048)
			(stroke
				(width 0.1)
				(type default)
			)
			(layer "F.Fab")
		)
		(pad "1" smd circle
			(at -0.40005 0)
			(size 0 0)
			(layers "F.Cu" "F.Mask" "F.Paste")
			(net "P0V8_PEX0_VREF")
		)
		(pad "2" smd circle
			(at 0.40005 0)
			(size 0 0)
			(layers "F.Cu" "F.Mask" "F.Paste")
			(net "GND")
		)
	)
	(footprint ""
		(layer "F.Cu")
		(at 416.287966 -45.704252 90)
		(property "Reference" "R661"
			(at 0 0 90)
			(layer "F.SilkS")
			(hide yes)
			(effects
				(font
					(size 1.27 1.27)
				)
			)
		)
		(property "Value" ""
			(at 0 0 90)
			(layer "F.Fab")
			(effects
				(font
					(size 1.27 1.27)
				)
			)
		)
		(duplicate_pad_numbers_are_jumpers no)
		(fp_line
			(start 3.937508 -1.8796)
			(end -3.937508 -1.8796)
			(stroke
				(width 0.1524)
				(type default)
			)
			(layer "F.SilkS")
		)
		(fp_line
			(start -3.937508 -1.8796)
			(end -3.937508 1.8796)
			(stroke
				(width 0.1524)
				(type default)
			)
			(layer "F.SilkS")
		)
		(fp_line
			(start 3.937508 1.8796)
			(end 3.937508 -1.8796)
			(stroke
				(width 0.1524)
				(type default)
			)
			(layer "F.SilkS")
		)
		(fp_line
			(start -3.937508 1.8796)
			(end 3.937508 1.8796)
			(stroke
				(width 0.1524)
				(type default)
			)
			(layer "F.SilkS")
		)
		(fp_line
			(start 3.275076 -1.674876)
			(end -3.275076 -1.674876)
			(stroke
				(width 0.1)
				(type default)
			)
			(layer "F.Fab")
		)
		(fp_line
			(start -3.275076 -1.674876)
			(end -3.275076 1.674876)
			(stroke
				(width 0.1)
				(type default)
			)
			(layer "F.Fab")
		)
		(fp_line
			(start 3.275076 1.674876)
			(end 3.275076 -1.674876)
			(stroke
				(width 0.1)
				(type default)
			)
			(layer "F.Fab")
		)
		(fp_line
			(start -3.275076 1.674876)
			(end 3.275076 1.674876)
			(stroke
				(width 0.1)
				(type default)
			)
			(layer "F.Fab")
		)
		(pad "1" smd rect
			(at -2.350008 0 90)
			(size 2.921 3.5052)
			(layers "F.Cu" "F.Mask" "F.Paste")
			(net "P12V_SSD14")
		)
		(pad "2" smd rect
			(at 2.350008 0 90)
			(size 2.921 3.5052)
			(layers "F.Cu" "F.Mask" "F.Paste")
			(net "P12V_SSD14_R")
		)
	)
	(footprint ""
		(layer "F.Cu")
		(at 287.075118 -63.086234)
		(property "Reference" "R6008"
			(at 0 0 0)
			(layer "F.SilkS")
			(hide yes)
			(effects
				(font
					(size 1.27 1.27)
				)
			)
		)
		(property "Value" ""
			(at 0 0 0)
			(layer "F.Fab")
			(effects
				(font
					(size 1.27 1.27)
				)
			)
		)
		(duplicate_pad_numbers_are_jumpers no)
		(fp_line
			(start -0.7874 -0.4064)
			(end 0.7874 -0.4064)
			(stroke
				(width 0.1524)
				(type default)
			)
			(layer "F.SilkS")
		)
		(fp_line
			(start -0.7874 0.4064)
			(end -0.7874 -0.4064)
			(stroke
				(width 0.1524)
				(type default)
			)
			(layer "F.SilkS")
		)
		(fp_line
			(start 0.7874 -0.4064)
			(end 0.7874 0.4064)
			(stroke
				(width 0.1524)
				(type default)
			)
			(layer "F.SilkS")
		)
		(fp_line
			(start 0.7874 0.4064)
			(end -0.7874 0.4064)
			(stroke
				(width 0.1524)
				(type default)
			)
			(layer "F.SilkS")
		)
		(fp_line
			(start -0.67945 -0.305054)
			(end -0.12065 -0.305054)
			(stroke
				(width 0.1)
				(type default)
			)
			(layer "F.Fab")
		)
		(fp_line
			(start -0.67945 0.3048)
			(end -0.67945 -0.305054)
			(stroke
				(width 0.1)
				(type default)
			)
			(layer "F.Fab")
		)
		(fp_line
			(start -0.12065 -0.305054)
			(end -0.12065 -0.2794)
			(stroke
				(width 0.1)
				(type default)
			)
			(layer "F.Fab")
		)
		(fp_line
			(start -0.12065 -0.2794)
			(end 0.12065 -0.2794)
			(stroke
				(width 0.1)
				(type default)
			)
			(layer "F.Fab")
		)
		(fp_line
			(start -0.12065 0.2794)
			(end -0.12065 0.3048)
			(stroke
				(width 0.1)
				(type default)
			)
			(layer "F.Fab")
		)
		(fp_line
			(start -0.12065 0.3048)
			(end -0.67945 0.3048)
			(stroke
				(width 0.1)
				(type default)
			)
			(layer "F.Fab")
		)
		(fp_line
			(start 0.120396 0.2794)
			(end -0.12065 0.2794)
			(stroke
				(width 0.1)
				(type default)
			)
			(layer "F.Fab")
		)
		(fp_line
			(start 0.120396 0.3048)
			(end 0.120396 0.2794)
			(stroke
				(width 0.1)
				(type default)
			)
			(layer "F.Fab")
		)
		(fp_line
			(start 0.12065 -0.3048)
			(end 0.67945 -0.3048)
			(stroke
				(width 0.1)
				(type default)
			)
			(layer "F.Fab")
		)
		(fp_line
			(start 0.12065 -0.2794)
			(end 0.12065 -0.3048)
			(stroke
				(width 0.1)
				(type default)
			)
			(layer "F.Fab")
		)
		(fp_line
			(start 0.67945 -0.3048)
			(end 0.67945 0.3048)
			(stroke
				(width 0.1)
				(type default)
			)
			(layer "F.Fab")
		)
		(fp_line
			(start 0.67945 0.3048)
			(end 0.120396 0.3048)
			(stroke
				(width 0.1)
				(type default)
			)
			(layer "F.Fab")
		)
		(pad "1" smd circle
			(at -0.40005 0)
			(size 0 0)
			(layers "F.Cu" "F.Mask" "F.Paste")
			(net "P12V_SSD10_R")
		)
		(pad "2" smd circle
			(at 0.40005 0)
			(size 0 0)
			(layers "F.Cu" "F.Mask" "F.Paste")
			(net "P12V_SSD10_PG_G1")
		)
	)
	(footprint ""
		(layer "F.Cu")
		(at 378.738384 -252.356874 -90)
		(property "Reference" "R1425"
			(at 0 0 270)
			(layer "F.SilkS")
			(hide yes)
			(effects
				(font
					(size 1.27 1.27)
				)
			)
		)
		(property "Value" ""
			(at 0 0 270)
			(layer "F.Fab")
			(effects
				(font
					(size 1.27 1.27)
				)
			)
		)
		(duplicate_pad_numbers_are_jumpers no)
		(fp_line
			(start -0.7874 0.4064)
			(end -0.7874 -0.4064)
			(stroke
				(width 0.1524)
				(type default)
			)
			(layer "F.SilkS")
		)
		(fp_line
			(start 0.7874 0.4064)
			(end -0.7874 0.4064)
			(stroke
				(width 0.1524)
				(type default)
			)
			(layer "F.SilkS")
		)
		(fp_line
			(start -0.7874 -0.4064)
			(end 0.7874 -0.4064)
			(stroke
				(width 0.1524)
				(type default)
			)
			(layer "F.SilkS")
		)
		(fp_line
			(start 0.7874 -0.4064)
			(end 0.7874 0.4064)
			(stroke
				(width 0.1524)
				(type default)
			)
			(layer "F.SilkS")
		)
		(fp_line
			(start -0.67945 0.3048)
			(end -0.67945 -0.305054)
			(stroke
				(width 0.1)
				(type default)
			)
			(layer "F.Fab")
		)
		(fp_line
			(start -0.12065 0.3048)
			(end -0.67945 0.3048)
			(stroke
				(width 0.1)
				(type default)
			)
			(layer "F.Fab")
		)
		(fp_line
			(start 0.120396 0.3048)
			(end 0.120396 0.2794)
			(stroke
				(width 0.1)
				(type default)
			)
			(layer "F.Fab")
		)
		(fp_line
			(start 0.67945 0.3048)
			(end 0.120396 0.3048)
			(stroke
				(width 0.1)
				(type default)
			)
			(layer "F.Fab")
		)
		(fp_line
			(start -0.12065 0.2794)
			(end -0.12065 0.3048)
			(stroke
				(width 0.1)
				(type default)
			)
			(layer "F.Fab")
		)
		(fp_line
			(start 0.120396 0.2794)
			(end -0.12065 0.2794)
			(stroke
				(width 0.1)
				(type default)
			)
			(layer "F.Fab")
		)
		(fp_line
			(start -0.12065 -0.2794)
			(end 0.12065 -0.2794)
			(stroke
				(width 0.1)
				(type default)
			)
			(layer "F.Fab")
		)
		(fp_line
			(start 0.12065 -0.2794)
			(end 0.12065 -0.3048)
			(stroke
				(width 0.1)
				(type default)
			)
			(layer "F.Fab")
		)
		(fp_line
			(start 0.12065 -0.3048)
			(end 0.67945 -0.3048)
			(stroke
				(width 0.1)
				(type default)
			)
			(layer "F.Fab")
		)
		(fp_line
			(start 0.67945 -0.3048)
			(end 0.67945 0.3048)
			(stroke
				(width 0.1)
				(type default)
			)
			(layer "F.Fab")
		)
		(fp_line
			(start -0.67945 -0.305054)
			(end -0.12065 -0.305054)
			(stroke
				(width 0.1)
				(type default)
			)
			(layer "F.Fab")
		)
		(fp_line
			(start -0.12065 -0.305054)
			(end -0.12065 -0.2794)
			(stroke
				(width 0.1)
				(type default)
			)
			(layer "F.Fab")
		)
		(pad "1" smd circle
			(at -0.40005 0 270)
			(size 0 0)
			(layers "F.Cu" "F.Mask" "F.Paste")
			(net "GND")
		)
		(pad "2" smd circle
			(at 0.40005 0 270)
			(size 0 0)
			(layers "F.Cu" "F.Mask" "F.Paste")
			(net "PEX3_MODE_SEL0")
		)
	)
	(footprint ""
		(layer "F.Cu")
		(at 154.707844 -159.4104 180)
		(property "Reference" "R104"
			(at 0 0 180)
			(layer "F.SilkS")
			(hide yes)
			(effects
				(font
					(size 1.27 1.27)
				)
			)
		)
		(property "Value" ""
			(at 0 0 180)
			(layer "F.Fab")
			(effects
				(font
					(size 1.27 1.27)
				)
			)
		)
		(duplicate_pad_numbers_are_jumpers no)
		(fp_line
			(start 0.7874 0.4064)
			(end -0.7874 0.4064)
			(stroke
				(width 0.1524)
				(type default)
			)
			(layer "F.SilkS")
		)
		(fp_line
			(start 0.7874 -0.4064)
			(end 0.7874 0.4064)
			(stroke
				(width 0.1524)
				(type default)
			)
			(layer "F.SilkS")
		)
		(fp_line
			(start -0.7874 0.4064)
			(end -0.7874 -0.4064)
			(stroke
				(width 0.1524)
				(type default)
			)
			(layer "F.SilkS")
		)
		(fp_line
			(start -0.7874 -0.4064)
			(end 0.7874 -0.4064)
			(stroke
				(width 0.1524)
				(type default)
			)
			(layer "F.SilkS")
		)
		(fp_line
			(start 0.67945 0.3048)
			(end 0.120396 0.3048)
			(stroke
				(width 0.1)
				(type default)
			)
			(layer "F.Fab")
		)
		(fp_line
			(start 0.67945 -0.3048)
			(end 0.67945 0.3048)
			(stroke
				(width 0.1)
				(type default)
			)
			(layer "F.Fab")
		)
		(fp_line
			(start 0.12065 -0.2794)
			(end 0.12065 -0.3048)
			(stroke
				(width 0.1)
				(type default)
			)
			(layer "F.Fab")
		)
		(fp_line
			(start 0.12065 -0.3048)
			(end 0.67945 -0.3048)
			(stroke
				(width 0.1)
				(type default)
			)
			(layer "F.Fab")
		)
		(fp_line
			(start 0.120396 0.3048)
			(end 0.120396 0.2794)
			(stroke
				(width 0.1)
				(type default)
			)
			(layer "F.Fab")
		)
		(fp_line
			(start 0.120396 0.2794)
			(end -0.12065 0.2794)
			(stroke
				(width 0.1)
				(type default)
			)
			(layer "F.Fab")
		)
		(fp_line
			(start -0.12065 0.3048)
			(end -0.67945 0.3048)
			(stroke
				(width 0.1)
				(type default)
			)
			(layer "F.Fab")
		)
		(fp_line
			(start -0.12065 0.2794)
			(end -0.12065 0.3048)
			(stroke
				(width 0.1)
				(type default)
			)
			(layer "F.Fab")
		)
		(fp_line
			(start -0.12065 -0.2794)
			(end 0.12065 -0.2794)
			(stroke
				(width 0.1)
				(type default)
			)
			(layer "F.Fab")
		)
		(fp_line
			(start -0.12065 -0.305054)
			(end -0.12065 -0.2794)
			(stroke
				(width 0.1)
				(type default)
			)
			(layer "F.Fab")
		)
		(fp_line
			(start -0.67945 0.3048)
			(end -0.67945 -0.305054)
			(stroke
				(width 0.1)
				(type default)
			)
			(layer "F.Fab")
		)
		(fp_line
			(start -0.67945 -0.305054)
			(end -0.12065 -0.305054)
			(stroke
				(width 0.1)
				(type default)
			)
			(layer "F.Fab")
		)
		(pad "1" smd circle
			(at -0.40005 0 180)
			(size 0 0)
			(layers "F.Cu" "F.Mask" "F.Paste")
			(net "NIC2_MAIN_PWR_EN_R")
		)
		(pad "2" smd circle
			(at 0.40005 0 180)
			(size 0 0)
			(layers "F.Cu" "F.Mask" "F.Paste")
			(net "NIC2_MAIN_PWR_EN")
		)
	)
	(footprint ""
		(layer "F.Cu")
		(at 240.24971 -159.844994 180)
		(property "Reference" "PR7028"
			(at 0 0 180)
			(layer "F.SilkS")
			(hide yes)
			(effects
				(font
					(size 1.27 1.27)
				)
			)
		)
		(property "Value" ""
			(at 0 0 180)
			(layer "F.Fab")
			(effects
				(font
					(size 1.27 1.27)
				)
			)
		)
		(duplicate_pad_numbers_are_jumpers no)
		(fp_line
			(start 0.7874 0.4064)
			(end -0.7874 0.4064)
			(stroke
				(width 0.1524)
				(type default)
			)
			(layer "F.SilkS")
		)
		(fp_line
			(start 0.7874 -0.4064)
			(end 0.7874 0.4064)
			(stroke
				(width 0.1524)
				(type default)
			)
			(layer "F.SilkS")
		)
		(fp_line
			(start -0.7874 0.4064)
			(end -0.7874 -0.4064)
			(stroke
				(width 0.1524)
				(type default)
			)
			(layer "F.SilkS")
		)
		(fp_line
			(start -0.7874 -0.4064)
			(end 0.7874 -0.4064)
			(stroke
				(width 0.1524)
				(type default)
			)
			(layer "F.SilkS")
		)
		(fp_line
			(start 0.67945 0.3048)
			(end 0.120396 0.3048)
			(stroke
				(width 0.1)
				(type default)
			)
			(layer "F.Fab")
		)
		(fp_line
			(start 0.67945 -0.3048)
			(end 0.67945 0.3048)
			(stroke
				(width 0.1)
				(type default)
			)
			(layer "F.Fab")
		)
		(fp_line
			(start 0.12065 -0.2794)
			(end 0.12065 -0.3048)
			(stroke
				(width 0.1)
				(type default)
			)
			(layer "F.Fab")
		)
		(fp_line
			(start 0.12065 -0.3048)
			(end 0.67945 -0.3048)
			(stroke
				(width 0.1)
				(type default)
			)
			(layer "F.Fab")
		)
		(fp_line
			(start 0.120396 0.3048)
			(end 0.120396 0.2794)
			(stroke
				(width 0.1)
				(type default)
			)
			(layer "F.Fab")
		)
		(fp_line
			(start 0.120396 0.2794)
			(end -0.12065 0.2794)
			(stroke
				(width 0.1)
				(type default)
			)
			(layer "F.Fab")
		)
		(fp_line
			(start -0.12065 0.3048)
			(end -0.67945 0.3048)
			(stroke
				(width 0.1)
				(type default)
			)
			(layer "F.Fab")
		)
		(fp_line
			(start -0.12065 0.2794)
			(end -0.12065 0.3048)
			(stroke
				(width 0.1)
				(type default)
			)
			(layer "F.Fab")
		)
		(fp_line
			(start -0.12065 -0.2794)
			(end 0.12065 -0.2794)
			(stroke
				(width 0.1)
				(type default)
			)
			(layer "F.Fab")
		)
		(fp_line
			(start -0.12065 -0.305054)
			(end -0.12065 -0.2794)
			(stroke
				(width 0.1)
				(type default)
			)
			(layer "F.Fab")
		)
		(fp_line
			(start -0.67945 0.3048)
			(end -0.67945 -0.305054)
			(stroke
				(width 0.1)
				(type default)
			)
			(layer "F.Fab")
		)
		(fp_line
			(start -0.67945 -0.305054)
			(end -0.12065 -0.305054)
			(stroke
				(width 0.1)
				(type default)
			)
			(layer "F.Fab")
		)
		(pad "1" smd circle
			(at -0.40005 0 180)
			(size 0 0)
			(layers "F.Cu" "F.Mask" "F.Paste")
			(net "P12V_NIC4_CO_FLTB")
		)
		(pad "2" smd circle
			(at 0.40005 0 180)
			(size 0 0)
			(layers "F.Cu" "F.Mask" "F.Paste")
			(net "P3V3_AUX")
		)
	)
	(footprint ""
		(layer "F.Cu")
		(at 217.767916 -19.453098)
		(property "Reference" "R1682"
			(at 0 0 0)
			(layer "F.SilkS")
			(hide yes)
			(effects
				(font
					(size 1.27 1.27)
				)
			)
		)
		(property "Value" ""
			(at 0 0 0)
			(layer "F.Fab")
			(effects
				(font
					(size 1.27 1.27)
				)
			)
		)
		(duplicate_pad_numbers_are_jumpers no)
		(fp_line
			(start -0.7874 -0.4064)
			(end 0.7874 -0.4064)
			(stroke
				(width 0.1524)
				(type default)
			)
			(layer "F.SilkS")
		)
		(fp_line
			(start -0.7874 0.4064)
			(end -0.7874 -0.4064)
			(stroke
				(width 0.1524)
				(type default)
			)
			(layer "F.SilkS")
		)
		(fp_line
			(start 0.7874 -0.4064)
			(end 0.7874 0.4064)
			(stroke
				(width 0.1524)
				(type default)
			)
			(layer "F.SilkS")
		)
		(fp_line
			(start 0.7874 0.4064)
			(end -0.7874 0.4064)
			(stroke
				(width 0.1524)
				(type default)
			)
			(layer "F.SilkS")
		)
		(fp_line
			(start -0.67945 -0.305054)
			(end -0.12065 -0.305054)
			(stroke
				(width 0.1)
				(type default)
			)
			(layer "F.Fab")
		)
		(fp_line
			(start -0.67945 0.3048)
			(end -0.67945 -0.305054)
			(stroke
				(width 0.1)
				(type default)
			)
			(layer "F.Fab")
		)
		(fp_line
			(start -0.12065 -0.305054)
			(end -0.12065 -0.2794)
			(stroke
				(width 0.1)
				(type default)
			)
			(layer "F.Fab")
		)
		(fp_line
			(start -0.12065 -0.2794)
			(end 0.12065 -0.2794)
			(stroke
				(width 0.1)
				(type default)
			)
			(layer "F.Fab")
		)
		(fp_line
			(start -0.12065 0.2794)
			(end -0.12065 0.3048)
			(stroke
				(width 0.1)
				(type default)
			)
			(layer "F.Fab")
		)
		(fp_line
			(start -0.12065 0.3048)
			(end -0.67945 0.3048)
			(stroke
				(width 0.1)
				(type default)
			)
			(layer "F.Fab")
		)
		(fp_line
			(start 0.120396 0.2794)
			(end -0.12065 0.2794)
			(stroke
				(width 0.1)
				(type default)
			)
			(layer "F.Fab")
		)
		(fp_line
			(start 0.120396 0.3048)
			(end 0.120396 0.2794)
			(stroke
				(width 0.1)
				(type default)
			)
			(layer "F.Fab")
		)
		(fp_line
			(start 0.12065 -0.3048)
			(end 0.67945 -0.3048)
			(stroke
				(width 0.1)
				(type default)
			)
			(layer "F.Fab")
		)
		(fp_line
			(start 0.12065 -0.2794)
			(end 0.12065 -0.3048)
			(stroke
				(width 0.1)
				(type default)
			)
			(layer "F.Fab")
		)
		(fp_line
			(start 0.67945 -0.3048)
			(end 0.67945 0.3048)
			(stroke
				(width 0.1)
				(type default)
			)
			(layer "F.Fab")
		)
		(fp_line
			(start 0.67945 0.3048)
			(end 0.120396 0.3048)
			(stroke
				(width 0.1)
				(type default)
			)
			(layer "F.Fab")
		)
		(pad "1" smd circle
			(at -0.40005 0)
			(size 0 0)
			(layers "F.Cu" "F.Mask" "F.Paste")
			(net "SMB_ISO_SSD7_R_SDA")
		)
		(pad "2" smd circle
			(at 0.40005 0)
			(size 0 0)
			(layers "F.Cu" "F.Mask" "F.Paste")
			(net "SMB_ISO_SSD7_SDA")
		)
	)
	(footprint ""
		(layer "F.Cu")
		(at 98.434398 -30.03169 180)
		(property "Reference" "C94"
			(at 0 0 180)
			(layer "F.SilkS")
			(hide yes)
			(effects
				(font
					(size 1.27 1.27)
				)
			)
		)
		(property "Value" ""
			(at 0 0 180)
			(layer "F.Fab")
			(effects
				(font
					(size 1.27 1.27)
				)
			)
		)
		(duplicate_pad_numbers_are_jumpers no)
		(fp_line
			(start 0.299974 0.150114)
			(end -0.299974 0.150114)
			(stroke
				(width 0.1)
				(type default)
			)
			(layer "F.Fab")
		)
		(fp_line
			(start 0.299974 -0.150114)
			(end 0.299974 0.150114)
			(stroke
				(width 0.1)
				(type default)
			)
			(layer "F.Fab")
		)
		(fp_line
			(start -0.299974 0.150114)
			(end -0.299974 -0.150114)
			(stroke
				(width 0.1)
				(type default)
			)
			(layer "F.Fab")
		)
		(fp_line
			(start -0.299974 -0.150114)
			(end 0.299974 -0.150114)
			(stroke
				(width 0.1)
				(type default)
			)
			(layer "F.Fab")
		)
		(pad "1" smd rect
			(at -0.2667 0 180)
			(size 0.3048 0.381)
			(layers "F.Cu" "F.Mask" "F.Paste")
			(net "P5E_PEX0_STN2_TX_DN<33>")
		)
		(pad "2" smd rect
			(at 0.2667 0 180)
			(size 0.3048 0.381)
			(layers "F.Cu" "F.Mask" "F.Paste")
			(net "P5E_PEX0_STN2_TX_C_DN<33>")
		)
	)
	(footprint ""
		(layer "F.Cu")
		(at 437.30164 -304.036476 90)
		(property "Reference" "R1450"
			(at 0 0 90)
			(layer "F.SilkS")
			(hide yes)
			(effects
				(font
					(size 1.27 1.27)
				)
			)
		)
		(property "Value" ""
			(at 0 0 90)
			(layer "F.Fab")
			(effects
				(font
					(size 1.27 1.27)
				)
			)
		)
		(duplicate_pad_numbers_are_jumpers no)
		(fp_line
			(start 0.7874 -0.4064)
			(end 0.7874 0.4064)
			(stroke
				(width 0.1524)
				(type default)
			)
			(layer "F.SilkS")
		)
		(fp_line
			(start -0.7874 -0.4064)
			(end 0.7874 -0.4064)
			(stroke
				(width 0.1524)
				(type default)
			)
			(layer "F.SilkS")
		)
		(fp_line
			(start 0.7874 0.4064)
			(end -0.7874 0.4064)
			(stroke
				(width 0.1524)
				(type default)
			)
			(layer "F.SilkS")
		)
		(fp_line
			(start -0.7874 0.4064)
			(end -0.7874 -0.4064)
			(stroke
				(width 0.1524)
				(type default)
			)
			(layer "F.SilkS")
		)
		(fp_line
			(start -0.12065 -0.305054)
			(end -0.12065 -0.2794)
			(stroke
				(width 0.1)
				(type default)
			)
			(layer "F.Fab")
		)
		(fp_line
			(start -0.67945 -0.305054)
			(end -0.12065 -0.305054)
			(stroke
				(width 0.1)
				(type default)
			)
			(layer "F.Fab")
		)
		(fp_line
			(start 0.67945 -0.3048)
			(end 0.67945 0.3048)
			(stroke
				(width 0.1)
				(type default)
			)
			(layer "F.Fab")
		)
		(fp_line
			(start 0.12065 -0.3048)
			(end 0.67945 -0.3048)
			(stroke
				(width 0.1)
				(type default)
			)
			(layer "F.Fab")
		)
		(fp_line
			(start 0.12065 -0.2794)
			(end 0.12065 -0.3048)
			(stroke
				(width 0.1)
				(type default)
			)
			(layer "F.Fab")
		)
		(fp_line
			(start -0.12065 -0.2794)
			(end 0.12065 -0.2794)
			(stroke
				(width 0.1)
				(type default)
			)
			(layer "F.Fab")
		)
		(fp_line
			(start 0.120396 0.2794)
			(end -0.12065 0.2794)
			(stroke
				(width 0.1)
				(type default)
			)
			(layer "F.Fab")
		)
		(fp_line
			(start -0.12065 0.2794)
			(end -0.12065 0.3048)
			(stroke
				(width 0.1)
				(type default)
			)
			(layer "F.Fab")
		)
		(fp_line
			(start 0.67945 0.3048)
			(end 0.120396 0.3048)
			(stroke
				(width 0.1)
				(type default)
			)
			(layer "F.Fab")
		)
		(fp_line
			(start 0.120396 0.3048)
			(end 0.120396 0.2794)
			(stroke
				(width 0.1)
				(type default)
			)
			(layer "F.Fab")
		)
		(fp_line
			(start -0.12065 0.3048)
			(end -0.67945 0.3048)
			(stroke
				(width 0.1)
				(type default)
			)
			(layer "F.Fab")
		)
		(fp_line
			(start -0.67945 0.3048)
			(end -0.67945 -0.305054)
			(stroke
				(width 0.1)
				(type default)
			)
			(layer "F.Fab")
		)
		(pad "1" smd circle
			(at -0.40005 0 90)
			(size 0 0)
			(layers "F.Cu" "F.Mask" "F.Paste")
			(net "GND")
		)
		(pad "2" smd circle
			(at 0.40005 0 90)
			(size 0 0)
			(layers "F.Cu" "F.Mask" "F.Paste")
			(net "PEX3_SPARE4")
		)
	)
	(footprint ""
		(layer "F.Cu")
		(at 268.402816 -91.478354 180)
		(property "Reference" "R1063"
			(at 0 0 180)
			(layer "F.SilkS")
			(hide yes)
			(effects
				(font
					(size 1.27 1.27)
				)
			)
		)
		(property "Value" ""
			(at 0 0 180)
			(layer "F.Fab")
			(effects
				(font
					(size 1.27 1.27)
				)
			)
		)
		(duplicate_pad_numbers_are_jumpers no)
		(fp_line
			(start 0.7874 0.4064)
			(end -0.7874 0.4064)
			(stroke
				(width 0.1524)
				(type default)
			)
			(layer "F.SilkS")
		)
		(fp_line
			(start 0.7874 -0.4064)
			(end 0.7874 0.4064)
			(stroke
				(width 0.1524)
				(type default)
			)
			(layer "F.SilkS")
		)
		(fp_line
			(start -0.7874 0.4064)
			(end -0.7874 -0.4064)
			(stroke
				(width 0.1524)
				(type default)
			)
			(layer "F.SilkS")
		)
		(fp_line
			(start -0.7874 -0.4064)
			(end 0.7874 -0.4064)
			(stroke
				(width 0.1524)
				(type default)
			)
			(layer "F.SilkS")
		)
		(fp_line
			(start 0.67945 0.3048)
			(end 0.120396 0.3048)
			(stroke
				(width 0.1)
				(type default)
			)
			(layer "F.Fab")
		)
		(fp_line
			(start 0.67945 -0.3048)
			(end 0.67945 0.3048)
			(stroke
				(width 0.1)
				(type default)
			)
			(layer "F.Fab")
		)
		(fp_line
			(start 0.12065 -0.2794)
			(end 0.12065 -0.3048)
			(stroke
				(width 0.1)
				(type default)
			)
			(layer "F.Fab")
		)
		(fp_line
			(start 0.12065 -0.3048)
			(end 0.67945 -0.3048)
			(stroke
				(width 0.1)
				(type default)
			)
			(layer "F.Fab")
		)
		(fp_line
			(start 0.120396 0.3048)
			(end 0.120396 0.2794)
			(stroke
				(width 0.1)
				(type default)
			)
			(layer "F.Fab")
		)
		(fp_line
			(start 0.120396 0.2794)
			(end -0.12065 0.2794)
			(stroke
				(width 0.1)
				(type default)
			)
			(layer "F.Fab")
		)
		(fp_line
			(start -0.12065 0.3048)
			(end -0.67945 0.3048)
			(stroke
				(width 0.1)
				(type default)
			)
			(layer "F.Fab")
		)
		(fp_line
			(start -0.12065 0.2794)
			(end -0.12065 0.3048)
			(stroke
				(width 0.1)
				(type default)
			)
			(layer "F.Fab")
		)
		(fp_line
			(start -0.12065 -0.2794)
			(end 0.12065 -0.2794)
			(stroke
				(width 0.1)
				(type default)
			)
			(layer "F.Fab")
		)
		(fp_line
			(start -0.12065 -0.305054)
			(end -0.12065 -0.2794)
			(stroke
				(width 0.1)
				(type default)
			)
			(layer "F.Fab")
		)
		(fp_line
			(start -0.67945 0.3048)
			(end -0.67945 -0.305054)
			(stroke
				(width 0.1)
				(type default)
			)
			(layer "F.Fab")
		)
		(fp_line
			(start -0.67945 -0.305054)
			(end -0.12065 -0.305054)
			(stroke
				(width 0.1)
				(type default)
			)
			(layer "F.Fab")
		)
		(pad "1" smd circle
			(at -0.40005 0 180)
			(size 0 0)
			(layers "F.Cu" "F.Mask" "F.Paste")
			(net "GND")
		)
		(pad "2" smd circle
			(at 0.40005 0 180)
			(size 0 0)
			(layers "F.Cu" "F.Mask" "F.Paste")
			(net "FM_CK440_MXCK_25M_100M")
		)
	)
	(footprint ""
		(layer "F.Cu")
		(at 57.650126 -50.96383 180)
		(property "Reference" "PC525"
			(at 0 0 180)
			(layer "F.SilkS")
			(hide yes)
			(effects
				(font
					(size 1.27 1.27)
				)
			)
		)
		(property "Value" ""
			(at 0 0 180)
			(layer "F.Fab")
			(effects
				(font
					(size 1.27 1.27)
				)
			)
		)
		(duplicate_pad_numbers_are_jumpers no)
		(fp_line
			(start 1.524 0.762)
			(end -1.524 0.762)
			(stroke
				(width 0.1524)
				(type default)
			)
			(layer "F.SilkS")
		)
		(fp_line
			(start 1.524 -0.762)
			(end 1.524 0.762)
			(stroke
				(width 0.1524)
				(type default)
			)
			(layer "F.SilkS")
		)
		(fp_line
			(start -1.524 0.762)
			(end -1.524 -0.762)
			(stroke
				(width 0.1524)
				(type default)
			)
			(layer "F.SilkS")
		)
		(fp_line
			(start -1.524 -0.762)
			(end 1.524 -0.762)
			(stroke
				(width 0.1524)
				(type default)
			)
			(layer "F.SilkS")
		)
		(fp_line
			(start 1.1049 0.724916)
			(end 1.1049 -0.724916)
			(stroke
				(width 0.1)
				(type default)
			)
			(layer "F.Fab")
		)
		(fp_line
			(start 1.1049 -0.724916)
			(end -1.1049 -0.724916)
			(stroke
				(width 0.1)
				(type default)
			)
			(layer "F.Fab")
		)
		(fp_line
			(start -1.1049 0.724916)
			(end 1.1049 0.724916)
			(stroke
				(width 0.1)
				(type default)
			)
			(layer "F.Fab")
		)
		(fp_line
			(start -1.1049 -0.724916)
			(end -1.1049 0.724916)
			(stroke
				(width 0.1)
				(type default)
			)
			(layer "F.Fab")
		)
		(pad "1" smd rect
			(at -0.889 0)
			(size 1.016 1.27)
			(layers "F.Cu" "F.Mask" "F.Paste")
			(net "P3V3_SSD2")
		)
		(pad "2" smd rect
			(at 0.889 0)
			(size 1.016 1.27)
			(layers "F.Cu" "F.Mask" "F.Paste")
			(net "GND")
		)
	)
	(footprint ""
		(layer "F.Cu")
		(at 230.682038 -37.025072)
		(property "Reference" "R5685"
			(at 0 0 0)
			(layer "F.SilkS")
			(hide yes)
			(effects
				(font
					(size 1.27 1.27)
				)
			)
		)
		(property "Value" ""
			(at 0 0 0)
			(layer "F.Fab")
			(effects
				(font
					(size 1.27 1.27)
				)
			)
		)
		(duplicate_pad_numbers_are_jumpers no)
		(fp_line
			(start -0.7874 -0.4064)
			(end 0.7874 -0.4064)
			(stroke
				(width 0.1524)
				(type default)
			)
			(layer "F.SilkS")
		)
		(fp_line
			(start -0.7874 0.4064)
			(end -0.7874 -0.4064)
			(stroke
				(width 0.1524)
				(type default)
			)
			(layer "F.SilkS")
		)
		(fp_line
			(start 0.7874 -0.4064)
			(end 0.7874 0.4064)
			(stroke
				(width 0.1524)
				(type default)
			)
			(layer "F.SilkS")
		)
		(fp_line
			(start 0.7874 0.4064)
			(end -0.7874 0.4064)
			(stroke
				(width 0.1524)
				(type default)
			)
			(layer "F.SilkS")
		)
		(fp_line
			(start -0.67945 -0.305054)
			(end -0.12065 -0.305054)
			(stroke
				(width 0.1)
				(type default)
			)
			(layer "F.Fab")
		)
		(fp_line
			(start -0.67945 0.3048)
			(end -0.67945 -0.305054)
			(stroke
				(width 0.1)
				(type default)
			)
			(layer "F.Fab")
		)
		(fp_line
			(start -0.12065 -0.305054)
			(end -0.12065 -0.2794)
			(stroke
				(width 0.1)
				(type default)
			)
			(layer "F.Fab")
		)
		(fp_line
			(start -0.12065 -0.2794)
			(end 0.12065 -0.2794)
			(stroke
				(width 0.1)
				(type default)
			)
			(layer "F.Fab")
		)
		(fp_line
			(start -0.12065 0.2794)
			(end -0.12065 0.3048)
			(stroke
				(width 0.1)
				(type default)
			)
			(layer "F.Fab")
		)
		(fp_line
			(start -0.12065 0.3048)
			(end -0.67945 0.3048)
			(stroke
				(width 0.1)
				(type default)
			)
			(layer "F.Fab")
		)
		(fp_line
			(start 0.120396 0.2794)
			(end -0.12065 0.2794)
			(stroke
				(width 0.1)
				(type default)
			)
			(layer "F.Fab")
		)
		(fp_line
			(start 0.120396 0.3048)
			(end 0.120396 0.2794)
			(stroke
				(width 0.1)
				(type default)
			)
			(layer "F.Fab")
		)
		(fp_line
			(start 0.12065 -0.3048)
			(end 0.67945 -0.3048)
			(stroke
				(width 0.1)
				(type default)
			)
			(layer "F.Fab")
		)
		(fp_line
			(start 0.12065 -0.2794)
			(end 0.12065 -0.3048)
			(stroke
				(width 0.1)
				(type default)
			)
			(layer "F.Fab")
		)
		(fp_line
			(start 0.67945 -0.3048)
			(end 0.67945 0.3048)
			(stroke
				(width 0.1)
				(type default)
			)
			(layer "F.Fab")
		)
		(fp_line
			(start 0.67945 0.3048)
			(end 0.120396 0.3048)
			(stroke
				(width 0.1)
				(type default)
			)
			(layer "F.Fab")
		)
		(pad "1" smd circle
			(at -0.40005 0)
			(size 0 0)
			(layers "F.Cu" "F.Mask" "F.Paste")
			(net "RST_SMB_SSD_R_N")
		)
		(pad "2" smd circle
			(at 0.40005 0)
			(size 0 0)
			(layers "F.Cu" "F.Mask" "F.Paste")
			(net "RST_SMB_SSD8_N")
		)
	)
	(footprint ""
		(layer "F.Cu")
		(at 384.938524 -111.895382)
		(property "Reference" "C682"
			(at 0 0 0)
			(layer "F.SilkS")
			(hide yes)
			(effects
				(font
					(size 1.27 1.27)
				)
			)
		)
		(property "Value" ""
			(at 0 0 0)
			(layer "F.Fab")
			(effects
				(font
					(size 1.27 1.27)
				)
			)
		)
		(duplicate_pad_numbers_are_jumpers no)
		(fp_line
			(start -0.299974 -0.150114)
			(end 0.299974 -0.150114)
			(stroke
				(width 0.1)
				(type default)
			)
			(layer "F.Fab")
		)
		(fp_line
			(start -0.299974 0.150114)
			(end -0.299974 -0.150114)
			(stroke
				(width 0.1)
				(type default)
			)
			(layer "F.Fab")
		)
		(fp_line
			(start 0.299974 -0.150114)
			(end 0.299974 0.150114)
			(stroke
				(width 0.1)
				(type default)
			)
			(layer "F.Fab")
		)
		(fp_line
			(start 0.299974 0.150114)
			(end -0.299974 0.150114)
			(stroke
				(width 0.1)
				(type default)
			)
			(layer "F.Fab")
		)
		(pad "1" smd rect
			(at -0.2667 0)
			(size 0.3048 0.381)
			(layers "F.Cu" "F.Mask" "F.Paste")
			(net "P5E_PEX3_STN1_TX_DN<23>")
		)
		(pad "2" smd rect
			(at 0.2667 0)
			(size 0.3048 0.381)
			(layers "F.Cu" "F.Mask" "F.Paste")
			(net "P5E_PEX3_STN1_TX_C_DN<23>")
		)
	)
	(footprint ""
		(layer "F.Cu")
		(at 140.074142 -180.977286 180)
		(property "Reference" "R1106"
			(at 0 0 180)
			(layer "F.SilkS")
			(hide yes)
			(effects
				(font
					(size 1.27 1.27)
				)
			)
		)
		(property "Value" ""
			(at 0 0 180)
			(layer "F.Fab")
			(effects
				(font
					(size 1.27 1.27)
				)
			)
		)
		(duplicate_pad_numbers_are_jumpers no)
		(fp_line
			(start 0.7874 0.4064)
			(end -0.7874 0.4064)
			(stroke
				(width 0.1524)
				(type default)
			)
			(layer "F.SilkS")
		)
		(fp_line
			(start 0.67945 0.3048)
			(end 0.120396 0.3048)
			(stroke
				(width 0.1)
				(type default)
			)
			(layer "F.Fab")
		)
		(fp_line
			(start 0.67945 -0.3048)
			(end 0.67945 0.3048)
			(stroke
				(width 0.1)
				(type default)
			)
			(layer "F.Fab")
		)
		(fp_line
			(start 0.12065 -0.2794)
			(end 0.12065 -0.3048)
			(stroke
				(width 0.1)
				(type default)
			)
			(layer "F.Fab")
		)
		(fp_line
			(start 0.12065 -0.3048)
			(end 0.67945 -0.3048)
			(stroke
				(width 0.1)
				(type default)
			)
			(layer "F.Fab")
		)
		(fp_line
			(start 0.120396 0.3048)
			(end 0.120396 0.2794)
			(stroke
				(width 0.1)
				(type default)
			)
			(layer "F.Fab")
		)
		(fp_line
			(start 0.120396 0.2794)
			(end -0.12065 0.2794)
			(stroke
				(width 0.1)
				(type default)
			)
			(layer "F.Fab")
		)
		(fp_line
			(start -0.12065 0.3048)
			(end -0.67945 0.3048)
			(stroke
				(width 0.1)
				(type default)
			)
			(layer "F.Fab")
		)
		(fp_line
			(start -0.12065 0.2794)
			(end -0.12065 0.3048)
			(stroke
				(width 0.1)
				(type default)
			)
			(layer "F.Fab")
		)
		(fp_line
			(start -0.12065 -0.2794)
			(end 0.12065 -0.2794)
			(stroke
				(width 0.1)
				(type default)
			)
			(layer "F.Fab")
		)
		(fp_line
			(start -0.12065 -0.305054)
			(end -0.12065 -0.2794)
			(stroke
				(width 0.1)
				(type default)
			)
			(layer "F.Fab")
		)
		(fp_line
			(start -0.67945 0.3048)
			(end -0.67945 -0.305054)
			(stroke
				(width 0.1)
				(type default)
			)
			(layer "F.Fab")
		)
		(fp_line
			(start -0.67945 -0.305054)
			(end -0.12065 -0.305054)
			(stroke
				(width 0.1)
				(type default)
			)
			(layer "F.Fab")
		)
		(pad "1" smd circle
			(at -0.40005 0 180)
			(size 0 0)
			(layers "F.Cu" "F.Mask" "F.Paste")
			(net "CLK_100M_DB2000QL_NIC5_R_DN")
		)
		(pad "2" smd circle
			(at 0.40005 0 180)
			(size 0 0)
			(layers "F.Cu" "F.Mask" "F.Paste")
			(net "CLK_100M_DB2000QL_NIC5_DN")
		)
	)
	(footprint ""
		(layer "F.Cu")
		(at 38.7604 -97.1804 180)
		(property "Reference" "R8"
			(at 0 0 180)
			(layer "F.SilkS")
			(hide yes)
			(effects
				(font
					(size 1.27 1.27)
				)
			)
		)
		(property "Value" ""
			(at 0 0 180)
			(layer "F.Fab")
			(effects
				(font
					(size 1.27 1.27)
				)
			)
		)
		(duplicate_pad_numbers_are_jumpers no)
		(fp_line
			(start 0.7874 0.4064)
			(end -0.7874 0.4064)
			(stroke
				(width 0.1524)
				(type default)
			)
			(layer "F.SilkS")
		)
		(fp_line
			(start 0.7874 -0.4064)
			(end 0.7874 0.4064)
			(stroke
				(width 0.1524)
				(type default)
			)
			(layer "F.SilkS")
		)
		(fp_line
			(start -0.7874 0.4064)
			(end -0.7874 -0.4064)
			(stroke
				(width 0.1524)
				(type default)
			)
			(layer "F.SilkS")
		)
		(fp_line
			(start -0.7874 -0.4064)
			(end 0.7874 -0.4064)
			(stroke
				(width 0.1524)
				(type default)
			)
			(layer "F.SilkS")
		)
		(fp_line
			(start 0.67945 0.3048)
			(end 0.120396 0.3048)
			(stroke
				(width 0.1)
				(type default)
			)
			(layer "F.Fab")
		)
		(fp_line
			(start 0.67945 -0.3048)
			(end 0.67945 0.3048)
			(stroke
				(width 0.1)
				(type default)
			)
			(layer "F.Fab")
		)
		(fp_line
			(start 0.12065 -0.2794)
			(end 0.12065 -0.3048)
			(stroke
				(width 0.1)
				(type default)
			)
			(layer "F.Fab")
		)
		(fp_line
			(start 0.12065 -0.3048)
			(end 0.67945 -0.3048)
			(stroke
				(width 0.1)
				(type default)
			)
			(layer "F.Fab")
		)
		(fp_line
			(start 0.120396 0.3048)
			(end 0.120396 0.2794)
			(stroke
				(width 0.1)
				(type default)
			)
			(layer "F.Fab")
		)
		(fp_line
			(start 0.120396 0.2794)
			(end -0.12065 0.2794)
			(stroke
				(width 0.1)
				(type default)
			)
			(layer "F.Fab")
		)
		(fp_line
			(start -0.12065 0.3048)
			(end -0.67945 0.3048)
			(stroke
				(width 0.1)
				(type default)
			)
			(layer "F.Fab")
		)
		(fp_line
			(start -0.12065 0.2794)
			(end -0.12065 0.3048)
			(stroke
				(width 0.1)
				(type default)
			)
			(layer "F.Fab")
		)
		(fp_line
			(start -0.12065 -0.2794)
			(end 0.12065 -0.2794)
			(stroke
				(width 0.1)
				(type default)
			)
			(layer "F.Fab")
		)
		(fp_line
			(start -0.12065 -0.305054)
			(end -0.12065 -0.2794)
			(stroke
				(width 0.1)
				(type default)
			)
			(layer "F.Fab")
		)
		(fp_line
			(start -0.67945 0.3048)
			(end -0.67945 -0.305054)
			(stroke
				(width 0.1)
				(type default)
			)
			(layer "F.Fab")
		)
		(fp_line
			(start -0.67945 -0.305054)
			(end -0.12065 -0.305054)
			(stroke
				(width 0.1)
				(type default)
			)
			(layer "F.Fab")
		)
		(pad "1" smd circle
			(at -0.40005 0 180)
			(size 0 0)
			(layers "F.Cu" "F.Mask" "F.Paste")
			(net "PRSNTB3_NIC0_N")
		)
		(pad "2" smd circle
			(at 0.40005 0 180)
			(size 0 0)
			(layers "F.Cu" "F.Mask" "F.Paste")
			(net "P3V3_AUX")
		)
	)
	(footprint ""
		(layer "F.Cu")
		(at 330.327 -245.237 -90)
		(property "Reference" "R1785"
			(at 0 0 270)
			(layer "F.SilkS")
			(hide yes)
			(effects
				(font
					(size 1.27 1.27)
				)
			)
		)
		(property "Value" ""
			(at 0 0 270)
			(layer "F.Fab")
			(effects
				(font
					(size 1.27 1.27)
				)
			)
		)
		(duplicate_pad_numbers_are_jumpers no)
		(fp_line
			(start -0.7874 0.4064)
			(end -0.7874 -0.4064)
			(stroke
				(width 0.1524)
				(type default)
			)
			(layer "F.SilkS")
		)
		(fp_line
			(start 0.7874 0.4064)
			(end -0.7874 0.4064)
			(stroke
				(width 0.1524)
				(type default)
			)
			(layer "F.SilkS")
		)
		(fp_line
			(start -0.7874 -0.4064)
			(end 0.7874 -0.4064)
			(stroke
				(width 0.1524)
				(type default)
			)
			(layer "F.SilkS")
		)
		(fp_line
			(start 0.7874 -0.4064)
			(end 0.7874 0.4064)
			(stroke
				(width 0.1524)
				(type default)
			)
			(layer "F.SilkS")
		)
		(fp_line
			(start -0.67945 0.3048)
			(end -0.67945 -0.305054)
			(stroke
				(width 0.1)
				(type default)
			)
			(layer "F.Fab")
		)
		(fp_line
			(start -0.12065 0.3048)
			(end -0.67945 0.3048)
			(stroke
				(width 0.1)
				(type default)
			)
			(layer "F.Fab")
		)
		(fp_line
			(start 0.120396 0.3048)
			(end 0.120396 0.2794)
			(stroke
				(width 0.1)
				(type default)
			)
			(layer "F.Fab")
		)
		(fp_line
			(start 0.67945 0.3048)
			(end 0.120396 0.3048)
			(stroke
				(width 0.1)
				(type default)
			)
			(layer "F.Fab")
		)
		(fp_line
			(start -0.12065 0.2794)
			(end -0.12065 0.3048)
			(stroke
				(width 0.1)
				(type default)
			)
			(layer "F.Fab")
		)
		(fp_line
			(start 0.120396 0.2794)
			(end -0.12065 0.2794)
			(stroke
				(width 0.1)
				(type default)
			)
			(layer "F.Fab")
		)
		(fp_line
			(start -0.12065 -0.2794)
			(end 0.12065 -0.2794)
			(stroke
				(width 0.1)
				(type default)
			)
			(layer "F.Fab")
		)
		(fp_line
			(start 0.12065 -0.2794)
			(end 0.12065 -0.3048)
			(stroke
				(width 0.1)
				(type default)
			)
			(layer "F.Fab")
		)
		(fp_line
			(start 0.12065 -0.3048)
			(end 0.67945 -0.3048)
			(stroke
				(width 0.1)
				(type default)
			)
			(layer "F.Fab")
		)
		(fp_line
			(start 0.67945 -0.3048)
			(end 0.67945 0.3048)
			(stroke
				(width 0.1)
				(type default)
			)
			(layer "F.Fab")
		)
		(fp_line
			(start -0.67945 -0.305054)
			(end -0.12065 -0.305054)
			(stroke
				(width 0.1)
				(type default)
			)
			(layer "F.Fab")
		)
		(fp_line
			(start -0.12065 -0.305054)
			(end -0.12065 -0.2794)
			(stroke
				(width 0.1)
				(type default)
			)
			(layer "F.Fab")
		)
		(pad "1" smd circle
			(at -0.40005 0 270)
			(size 0 0)
			(layers "F.Cu" "F.Mask" "F.Paste")
			(net "P3V3_AUX")
		)
		(pad "2" smd circle
			(at 0.40005 0 270)
			(size 0 0)
			(layers "F.Cu" "F.Mask" "F.Paste")
			(net "RST_MB_PERST_1_N")
		)
	)
	(footprint ""
		(layer "F.Cu")
		(at 374.543828 -47.92091)
		(property "Reference" "R636"
			(at 0 0 0)
			(layer "F.SilkS")
			(hide yes)
			(effects
				(font
					(size 1.27 1.27)
				)
			)
		)
		(property "Value" ""
			(at 0 0 0)
			(layer "F.Fab")
			(effects
				(font
					(size 1.27 1.27)
				)
			)
		)
		(duplicate_pad_numbers_are_jumpers no)
		(fp_line
			(start -0.7874 -0.4064)
			(end 0.7874 -0.4064)
			(stroke
				(width 0.1524)
				(type default)
			)
			(layer "F.SilkS")
		)
		(fp_line
			(start -0.7874 0.4064)
			(end -0.7874 -0.4064)
			(stroke
				(width 0.1524)
				(type default)
			)
			(layer "F.SilkS")
		)
		(fp_line
			(start 0.7874 -0.4064)
			(end 0.7874 0.4064)
			(stroke
				(width 0.1524)
				(type default)
			)
			(layer "F.SilkS")
		)
		(fp_line
			(start 0.7874 0.4064)
			(end -0.7874 0.4064)
			(stroke
				(width 0.1524)
				(type default)
			)
			(layer "F.SilkS")
		)
		(fp_line
			(start -0.67945 -0.305054)
			(end -0.12065 -0.305054)
			(stroke
				(width 0.1)
				(type default)
			)
			(layer "F.Fab")
		)
		(fp_line
			(start -0.67945 0.3048)
			(end -0.67945 -0.305054)
			(stroke
				(width 0.1)
				(type default)
			)
			(layer "F.Fab")
		)
		(fp_line
			(start -0.12065 -0.305054)
			(end -0.12065 -0.2794)
			(stroke
				(width 0.1)
				(type default)
			)
			(layer "F.Fab")
		)
		(fp_line
			(start -0.12065 -0.2794)
			(end 0.12065 -0.2794)
			(stroke
				(width 0.1)
				(type default)
			)
			(layer "F.Fab")
		)
		(fp_line
			(start -0.12065 0.2794)
			(end -0.12065 0.3048)
			(stroke
				(width 0.1)
				(type default)
			)
			(layer "F.Fab")
		)
		(fp_line
			(start -0.12065 0.3048)
			(end -0.67945 0.3048)
			(stroke
				(width 0.1)
				(type default)
			)
			(layer "F.Fab")
		)
		(fp_line
			(start 0.120396 0.2794)
			(end -0.12065 0.2794)
			(stroke
				(width 0.1)
				(type default)
			)
			(layer "F.Fab")
		)
		(fp_line
			(start 0.120396 0.3048)
			(end 0.120396 0.2794)
			(stroke
				(width 0.1)
				(type default)
			)
			(layer "F.Fab")
		)
		(fp_line
			(start 0.12065 -0.3048)
			(end 0.67945 -0.3048)
			(stroke
				(width 0.1)
				(type default)
			)
			(layer "F.Fab")
		)
		(fp_line
			(start 0.12065 -0.2794)
			(end 0.12065 -0.3048)
			(stroke
				(width 0.1)
				(type default)
			)
			(layer "F.Fab")
		)
		(fp_line
			(start 0.67945 -0.3048)
			(end 0.67945 0.3048)
			(stroke
				(width 0.1)
				(type default)
			)
			(layer "F.Fab")
		)
		(fp_line
			(start 0.67945 0.3048)
			(end 0.120396 0.3048)
			(stroke
				(width 0.1)
				(type default)
			)
			(layer "F.Fab")
		)
		(pad "1" smd circle
			(at -0.40005 0)
			(size 0 0)
			(layers "F.Cu" "F.Mask" "F.Paste")
			(net "P3V3_AUX")
		)
		(pad "2" smd circle
			(at 0.40005 0)
			(size 0 0)
			(layers "F.Cu" "F.Mask" "F.Paste")
			(net "SSD_8_15_ADC_ALERT_N")
		)
	)
	(footprint ""
		(layer "F.Cu")
		(at 332.045564 -350.098614 90)
		(property "Reference" "C532"
			(at 0 0 90)
			(layer "F.SilkS")
			(hide yes)
			(effects
				(font
					(size 1.27 1.27)
				)
			)
		)
		(property "Value" ""
			(at 0 0 90)
			(layer "F.Fab")
			(effects
				(font
					(size 1.27 1.27)
				)
			)
		)
		(duplicate_pad_numbers_are_jumpers no)
		(fp_line
			(start 0.299974 -0.150114)
			(end 0.299974 0.150114)
			(stroke
				(width 0.1)
				(type default)
			)
			(layer "F.Fab")
		)
		(fp_line
			(start -0.299974 -0.150114)
			(end 0.299974 -0.150114)
			(stroke
				(width 0.1)
				(type default)
			)
			(layer "F.Fab")
		)
		(fp_line
			(start 0.299974 0.150114)
			(end -0.299974 0.150114)
			(stroke
				(width 0.1)
				(type default)
			)
			(layer "F.Fab")
		)
		(fp_line
			(start -0.299974 0.150114)
			(end -0.299974 -0.150114)
			(stroke
				(width 0.1)
				(type default)
			)
			(layer "F.Fab")
		)
		(pad "1" smd rect
			(at -0.2667 0 90)
			(size 0.3048 0.381)
			(layers "F.Cu" "F.Mask" "F.Paste")
			(net "P5E_PEX2_STN5_TX_DN<89>")
		)
		(pad "2" smd rect
			(at 0.2667 0 90)
			(size 0.3048 0.381)
			(layers "F.Cu" "F.Mask" "F.Paste")
			(net "P5E_PEX2_STN5_TX_C_DN<89>")
		)
	)
	(footprint ""
		(layer "F.Cu")
		(at 456.399138 -385.543806)
		(property "Reference" "H43"
			(at -2.5146 -3.645154 0)
			(unlocked yes)
			(layer "F.SilkS")
			(effects
				(font
					(size 0.7874 0.5842)
					(thickness 0.1524)
				)
				(justify left)
			)
		)
		(property "Value" ""
			(at 0 0 0)
			(layer "F.Fab")
			(effects
				(font
					(size 1.27 1.27)
				)
			)
		)
		(duplicate_pad_numbers_are_jumpers no)
		(fp_circle
			(center 0 0)
			(end 2.4003 0)
			(stroke
				(width 0.1524)
				(type default)
			)
			(fill no)
			(layer "F.SilkS")
		)
		(fp_circle
			(center 0 0)
			(end 6.5913 0)
			(stroke
				(width 0.1524)
				(type default)
			)
			(fill no)
			(layer "B.SilkS")
		)
		(fp_circle
			(center 0 0)
			(end 6.5913 0)
			(stroke
				(width 0.1)
				(type default)
			)
			(fill no)
			(layer "B.Fab")
		)
		(fp_circle
			(center 0 0)
			(end 2.4003 0)
			(stroke
				(width 0.1)
				(type default)
			)
			(fill no)
			(layer "F.Fab")
		)
		(pad "" np_thru_hole circle
			(at 0 0)
			(size 3.175 3.175)
			(drill 3.175)
			(layers "*.Cu" "*.Mask")
			(clearance 0.381)
			(thermal_gap 0.381)
		)
		(zone
			(layers "F.Cu" "B.Cu" "In1.Cu" "In2.Cu" "In3.Cu" "In4.Cu" "In5.Cu" "In6.Cu"
				"In7.Cu" "In8.Cu" "In9.Cu" "In10.Cu" "In11.Cu" "In12.Cu" "In13.Cu" "In14.Cu"
				"In15.Cu" "In16.Cu"
			)
			(hatch none 0.5)
			(connect_pads
				(clearance 0)
			)
			(min_thickness 0.25)
			(keepout
				(tracks not_allowed)
				(vias allowed)
				(pads allowed)
				(copperpour not_allowed)
				(footprints allowed)
			)
			(placement
				(enabled no)
				(sheetname "")
			)
			(fill
				(thermal_gap 0.5)
				(thermal_bridge_width 0.5)
				(island_removal_mode 0)
			)
			(polygon
				(pts
					(arc
						(start 458.494638 -385.543806)
						(mid 454.303638 -385.543806)
						(end 458.494638 -385.543806)
					)
				)
			)
		)
	)
	(footprint ""
		(layer "F.Cu")
		(at 9.319768 -162.003994 90)
		(property "Reference" "PR6877"
			(at 0 0 90)
			(layer "F.SilkS")
			(hide yes)
			(effects
				(font
					(size 1.27 1.27)
				)
			)
		)
		(property "Value" ""
			(at 0 0 90)
			(layer "F.Fab")
			(effects
				(font
					(size 1.27 1.27)
				)
			)
		)
		(duplicate_pad_numbers_are_jumpers no)
		(fp_line
			(start 0.7874 -0.4064)
			(end 0.7874 0.4064)
			(stroke
				(width 0.1524)
				(type default)
			)
			(layer "F.SilkS")
		)
		(fp_line
			(start -0.7874 -0.4064)
			(end 0.7874 -0.4064)
			(stroke
				(width 0.1524)
				(type default)
			)
			(layer "F.SilkS")
		)
		(fp_line
			(start 0.7874 0.4064)
			(end -0.7874 0.4064)
			(stroke
				(width 0.1524)
				(type default)
			)
			(layer "F.SilkS")
		)
		(fp_line
			(start -0.7874 0.4064)
			(end -0.7874 -0.4064)
			(stroke
				(width 0.1524)
				(type default)
			)
			(layer "F.SilkS")
		)
		(fp_line
			(start -0.12065 -0.305054)
			(end -0.12065 -0.2794)
			(stroke
				(width 0.1)
				(type default)
			)
			(layer "F.Fab")
		)
		(fp_line
			(start -0.67945 -0.305054)
			(end -0.12065 -0.305054)
			(stroke
				(width 0.1)
				(type default)
			)
			(layer "F.Fab")
		)
		(fp_line
			(start 0.67945 -0.3048)
			(end 0.67945 0.3048)
			(stroke
				(width 0.1)
				(type default)
			)
			(layer "F.Fab")
		)
		(fp_line
			(start 0.12065 -0.3048)
			(end 0.67945 -0.3048)
			(stroke
				(width 0.1)
				(type default)
			)
			(layer "F.Fab")
		)
		(fp_line
			(start 0.12065 -0.2794)
			(end 0.12065 -0.3048)
			(stroke
				(width 0.1)
				(type default)
			)
			(layer "F.Fab")
		)
		(fp_line
			(start -0.12065 -0.2794)
			(end 0.12065 -0.2794)
			(stroke
				(width 0.1)
				(type default)
			)
			(layer "F.Fab")
		)
		(fp_line
			(start 0.120396 0.2794)
			(end -0.12065 0.2794)
			(stroke
				(width 0.1)
				(type default)
			)
			(layer "F.Fab")
		)
		(fp_line
			(start -0.12065 0.2794)
			(end -0.12065 0.3048)
			(stroke
				(width 0.1)
				(type default)
			)
			(layer "F.Fab")
		)
		(fp_line
			(start 0.67945 0.3048)
			(end 0.120396 0.3048)
			(stroke
				(width 0.1)
				(type default)
			)
			(layer "F.Fab")
		)
		(fp_line
			(start 0.120396 0.3048)
			(end 0.120396 0.2794)
			(stroke
				(width 0.1)
				(type default)
			)
			(layer "F.Fab")
		)
		(fp_line
			(start -0.12065 0.3048)
			(end -0.67945 0.3048)
			(stroke
				(width 0.1)
				(type default)
			)
			(layer "F.Fab")
		)
		(fp_line
			(start -0.67945 0.3048)
			(end -0.67945 -0.305054)
			(stroke
				(width 0.1)
				(type default)
			)
			(layer "F.Fab")
		)
		(pad "1" smd circle
			(at -0.40005 0 90)
			(size 0 0)
			(layers "F.Cu" "F.Mask" "F.Paste")
			(net "P12V_NIC0_CO_IMON_VR")
		)
		(pad "2" smd circle
			(at 0.40005 0 90)
			(size 0 0)
			(layers "F.Cu" "F.Mask" "F.Paste")
			(net "GND")
		)
	)
	(footprint ""
		(layer "F.Cu")
		(at 28.04922 -296.996612 -90)
		(property "Reference" "C3054"
			(at 0 0 270)
			(layer "F.SilkS")
			(hide yes)
			(effects
				(font
					(size 1.27 1.27)
				)
			)
		)
		(property "Value" ""
			(at 0 0 270)
			(layer "F.Fab")
			(effects
				(font
					(size 1.27 1.27)
				)
			)
		)
		(duplicate_pad_numbers_are_jumpers no)
		(fp_line
			(start -0.299974 0.150114)
			(end -0.299974 -0.150114)
			(stroke
				(width 0.1)
				(type default)
			)
			(layer "F.Fab")
		)
		(fp_line
			(start 0.299974 0.150114)
			(end -0.299974 0.150114)
			(stroke
				(width 0.1)
				(type default)
			)
			(layer "F.Fab")
		)
		(fp_line
			(start -0.299974 -0.150114)
			(end 0.299974 -0.150114)
			(stroke
				(width 0.1)
				(type default)
			)
			(layer "F.Fab")
		)
		(fp_line
			(start 0.299974 -0.150114)
			(end 0.299974 0.150114)
			(stroke
				(width 0.1)
				(type default)
			)
			(layer "F.Fab")
		)
		(pad "1" smd rect
			(at -0.2667 0 270)
			(size 0.3048 0.381)
			(layers "F.Cu" "F.Mask" "F.Paste")
			(net "P1V8_PLL0_PEX0")
		)
		(pad "2" smd rect
			(at 0.2667 0 270)
			(size 0.3048 0.381)
			(layers "F.Cu" "F.Mask" "F.Paste")
			(net "GND")
		)
	)
	(footprint ""
		(layer "F.Cu")
		(at 33.103312 -59.571636 90)
		(property "Reference" "PR261"
			(at 0 0 90)
			(layer "F.SilkS")
			(hide yes)
			(effects
				(font
					(size 1.27 1.27)
				)
			)
		)
		(property "Value" ""
			(at 0 0 90)
			(layer "F.Fab")
			(effects
				(font
					(size 1.27 1.27)
				)
			)
		)
		(duplicate_pad_numbers_are_jumpers no)
		(fp_line
			(start 0.7874 -0.4064)
			(end 0.7874 0.4064)
			(stroke
				(width 0.1524)
				(type default)
			)
			(layer "F.SilkS")
		)
		(fp_line
			(start -0.7874 -0.4064)
			(end 0.7874 -0.4064)
			(stroke
				(width 0.1524)
				(type default)
			)
			(layer "F.SilkS")
		)
		(fp_line
			(start 0.7874 0.4064)
			(end -0.7874 0.4064)
			(stroke
				(width 0.1524)
				(type default)
			)
			(layer "F.SilkS")
		)
		(fp_line
			(start -0.7874 0.4064)
			(end -0.7874 -0.4064)
			(stroke
				(width 0.1524)
				(type default)
			)
			(layer "F.SilkS")
		)
		(fp_line
			(start -0.12065 -0.305054)
			(end -0.12065 -0.2794)
			(stroke
				(width 0.1)
				(type default)
			)
			(layer "F.Fab")
		)
		(fp_line
			(start -0.67945 -0.305054)
			(end -0.12065 -0.305054)
			(stroke
				(width 0.1)
				(type default)
			)
			(layer "F.Fab")
		)
		(fp_line
			(start 0.67945 -0.3048)
			(end 0.67945 0.3048)
			(stroke
				(width 0.1)
				(type default)
			)
			(layer "F.Fab")
		)
		(fp_line
			(start 0.12065 -0.3048)
			(end 0.67945 -0.3048)
			(stroke
				(width 0.1)
				(type default)
			)
			(layer "F.Fab")
		)
		(fp_line
			(start 0.12065 -0.2794)
			(end 0.12065 -0.3048)
			(stroke
				(width 0.1)
				(type default)
			)
			(layer "F.Fab")
		)
		(fp_line
			(start -0.12065 -0.2794)
			(end 0.12065 -0.2794)
			(stroke
				(width 0.1)
				(type default)
			)
			(layer "F.Fab")
		)
		(fp_line
			(start 0.120396 0.2794)
			(end -0.12065 0.2794)
			(stroke
				(width 0.1)
				(type default)
			)
			(layer "F.Fab")
		)
		(fp_line
			(start -0.12065 0.2794)
			(end -0.12065 0.3048)
			(stroke
				(width 0.1)
				(type default)
			)
			(layer "F.Fab")
		)
		(fp_line
			(start 0.67945 0.3048)
			(end 0.120396 0.3048)
			(stroke
				(width 0.1)
				(type default)
			)
			(layer "F.Fab")
		)
		(fp_line
			(start 0.120396 0.3048)
			(end 0.120396 0.2794)
			(stroke
				(width 0.1)
				(type default)
			)
			(layer "F.Fab")
		)
		(fp_line
			(start -0.12065 0.3048)
			(end -0.67945 0.3048)
			(stroke
				(width 0.1)
				(type default)
			)
			(layer "F.Fab")
		)
		(fp_line
			(start -0.67945 0.3048)
			(end -0.67945 -0.305054)
			(stroke
				(width 0.1)
				(type default)
			)
			(layer "F.Fab")
		)
		(pad "1" smd circle
			(at -0.40005 0 90)
			(size 0 0)
			(layers "F.Cu" "F.Mask" "F.Paste")
			(net "P3V3_SSD1_OCP")
		)
		(pad "2" smd circle
			(at 0.40005 0 90)
			(size 0 0)
			(layers "F.Cu" "F.Mask" "F.Paste")
			(net "GND")
		)
	)
	(footprint ""
		(layer "F.Cu")
		(at 361.734862 -133.088126 180)
		(property "Reference" "PC305"
			(at 0 0 180)
			(layer "F.SilkS")
			(hide yes)
			(effects
				(font
					(size 1.27 1.27)
				)
			)
		)
		(property "Value" ""
			(at 0 0 180)
			(layer "F.Fab")
			(effects
				(font
					(size 1.27 1.27)
				)
			)
		)
		(duplicate_pad_numbers_are_jumpers no)
		(fp_line
			(start 1.524 0.762)
			(end -1.524 0.762)
			(stroke
				(width 0.1524)
				(type default)
			)
			(layer "F.SilkS")
		)
		(fp_line
			(start 1.524 -0.762)
			(end 1.524 0.762)
			(stroke
				(width 0.1524)
				(type default)
			)
			(layer "F.SilkS")
		)
		(fp_line
			(start -1.524 0.762)
			(end -1.524 -0.762)
			(stroke
				(width 0.1524)
				(type default)
			)
			(layer "F.SilkS")
		)
		(fp_line
			(start -1.524 -0.762)
			(end 1.524 -0.762)
			(stroke
				(width 0.1524)
				(type default)
			)
			(layer "F.SilkS")
		)
		(fp_line
			(start 1.1049 0.724916)
			(end 1.1049 -0.724916)
			(stroke
				(width 0.1)
				(type default)
			)
			(layer "F.Fab")
		)
		(fp_line
			(start 1.1049 -0.724916)
			(end -1.1049 -0.724916)
			(stroke
				(width 0.1)
				(type default)
			)
			(layer "F.Fab")
		)
		(fp_line
			(start -1.1049 0.724916)
			(end 1.1049 0.724916)
			(stroke
				(width 0.1)
				(type default)
			)
			(layer "F.Fab")
		)
		(fp_line
			(start -1.1049 -0.724916)
			(end -1.1049 0.724916)
			(stroke
				(width 0.1)
				(type default)
			)
			(layer "F.Fab")
		)
		(pad "1" smd rect
			(at -0.889 0)
			(size 1.016 1.27)
			(layers "F.Cu" "F.Mask" "F.Paste")
			(net "GND")
		)
		(pad "2" smd rect
			(at 0.889 0)
			(size 1.016 1.27)
			(layers "F.Cu" "F.Mask" "F.Paste")
			(net "P12V_AUX")
		)
	)
	(footprint ""
		(layer "F.Cu")
		(at 457.185014 -209.270092 90)
		(property "Reference" "J54"
			(at -4.139692 2.251456 90)
			(unlocked yes)
			(layer "F.SilkS")
			(effects
				(font
					(size 0.7874 0.5842)
					(thickness 0.1524)
				)
				(justify left)
			)
		)
		(property "Value" ""
			(at 0 0 90)
			(layer "F.Fab")
			(effects
				(font
					(size 1.27 1.27)
				)
			)
		)
		(duplicate_pad_numbers_are_jumpers no)
		(fp_line
			(start 3.999992 -1.500124)
			(end 3.999992 1.500124)
			(stroke
				(width 0.1524)
				(type default)
			)
			(layer "F.SilkS")
		)
		(fp_line
			(start 3.7338 -1.500124)
			(end 3.999992 -1.500124)
			(stroke
				(width 0.1524)
				(type default)
			)
			(layer "F.SilkS")
		)
		(fp_line
			(start 1.651 -1.500124)
			(end 1.8542 -1.500124)
			(stroke
				(width 0.1524)
				(type default)
			)
			(layer "F.SilkS")
		)
		(fp_line
			(start -1.8542 -1.500124)
			(end -1.651 -1.500124)
			(stroke
				(width 0.1524)
				(type default)
			)
			(layer "F.SilkS")
		)
		(fp_line
			(start -3.999992 -1.500124)
			(end -3.7338 -1.500124)
			(stroke
				(width 0.1524)
				(type default)
			)
			(layer "F.SilkS")
		)
		(fp_line
			(start 3.999992 1.500124)
			(end 1.0414 1.500124)
			(stroke
				(width 0.1524)
				(type default)
			)
			(layer "F.SilkS")
		)
		(fp_line
			(start -1.0414 1.500124)
			(end -3.999992 1.500124)
			(stroke
				(width 0.1524)
				(type default)
			)
			(layer "F.SilkS")
		)
		(fp_line
			(start -3.999992 1.500124)
			(end -3.999992 -1.500124)
			(stroke
				(width 0.1524)
				(type default)
			)
			(layer "F.SilkS")
		)
		(fp_poly
			(pts
				(xy -1.428242 -2.594102) (xy -1.943608 -3.624834) (xy -0.912876 -3.624834)
			)
			(stroke
				(width 0)
				(type default)
			)
			(fill yes)
			(layer "F.SilkS")
		)
		(fp_line
			(start 3.999992 -1.500124)
			(end 3.999992 1.500124)
			(stroke
				(width 0.1)
				(type default)
			)
			(layer "F.Fab")
		)
		(fp_line
			(start -3.999992 -1.500124)
			(end 3.999992 -1.500124)
			(stroke
				(width 0.1)
				(type default)
			)
			(layer "F.Fab")
		)
		(fp_line
			(start 3.999992 1.500124)
			(end -3.999992 1.500124)
			(stroke
				(width 0.1)
				(type default)
			)
			(layer "F.Fab")
		)
		(fp_line
			(start -3.999992 1.500124)
			(end -3.999992 -1.500124)
			(stroke
				(width 0.1)
				(type default)
			)
			(layer "F.Fab")
		)
		(fp_poly
			(pts
				(xy -1.299972 -1.78943) (xy -1.815338 -2.820162) (xy -0.784606 -2.820162)
			)
			(stroke
				(width 0)
				(type default)
			)
			(fill yes)
			(layer "F.Fab")
		)
		(pad "1" smd rect
			(at -1.299972 -0.890016 90)
			(size 0.4318 1.4986)
			(layers "F.Cu" "F.Mask" "F.Paste")
			(net "USB_VBUS_CONN")
		)
		(pad "2" smd rect
			(at -0.649986 -0.890016 90)
			(size 0.4318 1.4986)
			(layers "F.Cu" "F.Mask" "F.Paste")
			(net "USB2_FT4232_MUX_D_DN")
		)
		(pad "3" smd rect
			(at 0 -0.890016 90)
			(size 0.4318 1.4986)
			(layers "F.Cu" "F.Mask" "F.Paste")
			(net "USB2_FT4232_MUX_D_DP")
		)
		(pad "4" smd rect
			(at 0.649986 -0.890016 90)
			(size 0.4318 1.4986)
			(layers "F.Cu" "F.Mask" "F.Paste")
			(net "Net_2681")
		)
		(pad "5" smd rect
			(at 1.299972 -0.890016 90)
			(size 0.4318 1.4986)
			(layers "F.Cu" "F.Mask" "F.Paste")
			(net "GND")
		)
		(pad "G1" thru_hole oval
			(at -2.800096 -1.139952 180)
			(size 1.1176 1.8034)
			(drill oval 0.508 1.2192)
			(layers "*.Cu" "*.Mask")
			(remove_unused_layers no)
			(net "GND")
			(clearance 0.0762)
			(thermal_gap 0.0762)
		)
		(pad "G2" thru_hole oval
			(at 2.800096 -1.139952 180)
			(size 1.1176 1.8034)
			(drill oval 0.508 1.2192)
			(layers "*.Cu" "*.Mask")
			(remove_unused_layers no)
			(net "GND")
			(clearance 0.0762)
			(thermal_gap 0.0762)
		)
		(pad "G3" thru_hole oval
			(at 0 1.009904 180)
			(size 1.1176 2.2098)
			(drill oval 0.508 1.6002)
			(layers "*.Cu" "*.Mask")
			(remove_unused_layers no)
			(net "GND")
			(clearance 0.0762)
			(thermal_gap 0.0762)
		)
	)
	(footprint ""
		(layer "F.Cu")
		(at 405.892 -383.667 90)
		(property "Reference" "R6280"
			(at 0 0 90)
			(layer "F.SilkS")
			(hide yes)
			(effects
				(font
					(size 1.27 1.27)
				)
			)
		)
		(property "Value" ""
			(at 0 0 90)
			(layer "F.Fab")
			(effects
				(font
					(size 1.27 1.27)
				)
			)
		)
		(duplicate_pad_numbers_are_jumpers no)
		(fp_line
			(start 0.7874 -0.4064)
			(end 0.7874 0.4064)
			(stroke
				(width 0.1524)
				(type default)
			)
			(layer "F.SilkS")
		)
		(fp_line
			(start -0.7874 -0.4064)
			(end 0.7874 -0.4064)
			(stroke
				(width 0.1524)
				(type default)
			)
			(layer "F.SilkS")
		)
		(fp_line
			(start 0.7874 0.4064)
			(end -0.7874 0.4064)
			(stroke
				(width 0.1524)
				(type default)
			)
			(layer "F.SilkS")
		)
		(fp_line
			(start -0.7874 0.4064)
			(end -0.7874 -0.4064)
			(stroke
				(width 0.1524)
				(type default)
			)
			(layer "F.SilkS")
		)
		(fp_line
			(start -0.12065 -0.305054)
			(end -0.12065 -0.2794)
			(stroke
				(width 0.1)
				(type default)
			)
			(layer "F.Fab")
		)
		(fp_line
			(start -0.67945 -0.305054)
			(end -0.12065 -0.305054)
			(stroke
				(width 0.1)
				(type default)
			)
			(layer "F.Fab")
		)
		(fp_line
			(start 0.67945 -0.3048)
			(end 0.67945 0.3048)
			(stroke
				(width 0.1)
				(type default)
			)
			(layer "F.Fab")
		)
		(fp_line
			(start 0.12065 -0.3048)
			(end 0.67945 -0.3048)
			(stroke
				(width 0.1)
				(type default)
			)
			(layer "F.Fab")
		)
		(fp_line
			(start 0.12065 -0.2794)
			(end 0.12065 -0.3048)
			(stroke
				(width 0.1)
				(type default)
			)
			(layer "F.Fab")
		)
		(fp_line
			(start -0.12065 -0.2794)
			(end 0.12065 -0.2794)
			(stroke
				(width 0.1)
				(type default)
			)
			(layer "F.Fab")
		)
		(fp_line
			(start 0.120396 0.2794)
			(end -0.12065 0.2794)
			(stroke
				(width 0.1)
				(type default)
			)
			(layer "F.Fab")
		)
		(fp_line
			(start -0.12065 0.2794)
			(end -0.12065 0.3048)
			(stroke
				(width 0.1)
				(type default)
			)
			(layer "F.Fab")
		)
		(fp_line
			(start 0.67945 0.3048)
			(end 0.120396 0.3048)
			(stroke
				(width 0.1)
				(type default)
			)
			(layer "F.Fab")
		)
		(fp_line
			(start 0.120396 0.3048)
			(end 0.120396 0.2794)
			(stroke
				(width 0.1)
				(type default)
			)
			(layer "F.Fab")
		)
		(fp_line
			(start -0.12065 0.3048)
			(end -0.67945 0.3048)
			(stroke
				(width 0.1)
				(type default)
			)
			(layer "F.Fab")
		)
		(fp_line
			(start -0.67945 0.3048)
			(end -0.67945 -0.305054)
			(stroke
				(width 0.1)
				(type default)
			)
			(layer "F.Fab")
		)
		(pad "1" smd circle
			(at -0.40005 0 90)
			(size 0 0)
			(layers "F.Cu" "F.Mask" "F.Paste")
			(net "I3C_MB_BMC_R_SCL")
		)
		(pad "2" smd circle
			(at 0.40005 0 90)
			(size 0 0)
			(layers "F.Cu" "F.Mask" "F.Paste")
			(net "I3C_MB_BMC_SCL")
		)
	)
	(footprint ""
		(layer "F.Cu")
		(at 262.281924 -280.189432 180)
		(property "Reference" "C3421"
			(at 0 0 180)
			(layer "F.SilkS")
			(hide yes)
			(effects
				(font
					(size 1.27 1.27)
				)
			)
		)
		(property "Value" ""
			(at 0 0 180)
			(layer "F.Fab")
			(effects
				(font
					(size 1.27 1.27)
				)
			)
		)
		(duplicate_pad_numbers_are_jumpers no)
		(fp_line
			(start 1.2954 0.5842)
			(end -1.2954 0.5842)
			(stroke
				(width 0.1524)
				(type default)
			)
			(layer "F.SilkS")
		)
		(fp_line
			(start 1.2954 -0.5842)
			(end 1.2954 0.5842)
			(stroke
				(width 0.1524)
				(type default)
			)
			(layer "F.SilkS")
		)
		(fp_line
			(start -1.2954 0.5842)
			(end -1.2954 -0.5842)
			(stroke
				(width 0.1524)
				(type default)
			)
			(layer "F.SilkS")
		)
		(fp_line
			(start -1.2954 -0.5842)
			(end 1.2954 -0.5842)
			(stroke
				(width 0.1524)
				(type default)
			)
			(layer "F.SilkS")
		)
		(fp_line
			(start 1.1938 0.4064)
			(end 0.8636 0.4064)
			(stroke
				(width 0.1)
				(type default)
			)
			(layer "F.Fab")
		)
		(fp_line
			(start 1.1938 -0.4064)
			(end 1.1938 0.4064)
			(stroke
				(width 0.1)
				(type default)
			)
			(layer "F.Fab")
		)
		(fp_line
			(start 0.8636 0.4572)
			(end -0.8636 0.4572)
			(stroke
				(width 0.1)
				(type default)
			)
			(layer "F.Fab")
		)
		(fp_line
			(start 0.8636 0.4064)
			(end 0.8636 0.4572)
			(stroke
				(width 0.1)
				(type default)
			)
			(layer "F.Fab")
		)
		(fp_line
			(start 0.8636 -0.4064)
			(end 1.1938 -0.4064)
			(stroke
				(width 0.1)
				(type default)
			)
			(layer "F.Fab")
		)
		(fp_line
			(start 0.8636 -0.4572)
			(end 0.8636 -0.4064)
			(stroke
				(width 0.1)
				(type default)
			)
			(layer "F.Fab")
		)
		(fp_line
			(start -0.8636 0.4572)
			(end -0.8636 0.4064)
			(stroke
				(width 0.1)
				(type default)
			)
			(layer "F.Fab")
		)
		(fp_line
			(start -0.8636 0.4064)
			(end -1.1938 0.4064)
			(stroke
				(width 0.1)
				(type default)
			)
			(layer "F.Fab")
		)
		(fp_line
			(start -0.8636 -0.4064)
			(end -0.8636 -0.4572)
			(stroke
				(width 0.1)
				(type default)
			)
			(layer "F.Fab")
		)
		(fp_line
			(start -0.8636 -0.4572)
			(end 0.8636 -0.4572)
			(stroke
				(width 0.1)
				(type default)
			)
			(layer "F.Fab")
		)
		(fp_line
			(start -1.1938 0.4064)
			(end -1.1938 -0.4064)
			(stroke
				(width 0.1)
				(type default)
			)
			(layer "F.Fab")
		)
		(fp_line
			(start -1.1938 -0.4064)
			(end -0.8636 -0.4064)
			(stroke
				(width 0.1)
				(type default)
			)
			(layer "F.Fab")
		)
		(pad "1" smd rect
			(at -0.7366 0 90)
			(size 0.7112 0.8128)
			(layers "F.Cu" "F.Mask" "F.Paste")
			(net "SYSPLL_VDDA18_PEX2_R")
		)
		(pad "2" smd rect
			(at 0.7366 0 90)
			(size 0.7112 0.8128)
			(layers "F.Cu" "F.Mask" "F.Paste")
			(net "GND")
		)
	)
	(footprint ""
		(layer "F.Cu")
		(at 369.189 -188.468)
		(property "Reference" "U344"
			(at -1.3462 -4.613148 0)
			(unlocked yes)
			(layer "F.SilkS")
			(effects
				(font
					(size 0.7874 0.5842)
					(thickness 0.1524)
				)
				(justify left)
			)
		)
		(property "Value" ""
			(at 0 0 0)
			(layer "F.Fab")
			(effects
				(font
					(size 1.27 1.27)
				)
			)
		)
		(duplicate_pad_numbers_are_jumpers no)
		(fp_line
			(start -2.097532 -3.949954)
			(end -2.097532 3.949954)
			(stroke
				(width 0.1524)
				(type default)
			)
			(layer "F.SilkS")
		)
		(fp_line
			(start -2.097532 3.949954)
			(end 2.097532 3.949954)
			(stroke
				(width 0.1524)
				(type default)
			)
			(layer "F.SilkS")
		)
		(fp_line
			(start -1.409954 -3.949954)
			(end -2.097532 -3.949954)
			(stroke
				(width 0.1524)
				(type default)
			)
			(layer "F.SilkS")
		)
		(fp_line
			(start 0 -2.54)
			(end -1.409954 -3.949954)
			(stroke
				(width 0.1524)
				(type default)
			)
			(layer "F.SilkS")
		)
		(fp_line
			(start 1.409954 -3.949954)
			(end 0 -2.54)
			(stroke
				(width 0.1524)
				(type default)
			)
			(layer "F.SilkS")
		)
		(fp_line
			(start 2.097532 -3.949954)
			(end 1.409954 -3.949954)
			(stroke
				(width 0.1524)
				(type default)
			)
			(layer "F.SilkS")
		)
		(fp_line
			(start 2.097532 3.949954)
			(end 2.097532 -3.949954)
			(stroke
				(width 0.1524)
				(type default)
			)
			(layer "F.SilkS")
		)
		(fp_poly
			(pts
				(xy -4.7498 -4.182872) (xy -4.7498 -3.166872) (xy -3.7338 -3.674872)
			)
			(stroke
				(width 0)
				(type default)
			)
			(fill yes)
			(layer "F.SilkS")
		)
		(fp_line
			(start -2.249932 -3.949954)
			(end -2.249932 3.949954)
			(stroke
				(width 0.1)
				(type default)
			)
			(layer "F.Fab")
		)
		(fp_line
			(start -2.249932 3.949954)
			(end 2.249932 3.949954)
			(stroke
				(width 0.1)
				(type default)
			)
			(layer "F.Fab")
		)
		(fp_line
			(start 2.249932 -3.949954)
			(end -2.249932 -3.949954)
			(stroke
				(width 0.1)
				(type default)
			)
			(layer "F.Fab")
		)
		(fp_line
			(start 2.249932 3.949954)
			(end 2.249932 -3.949954)
			(stroke
				(width 0.1)
				(type default)
			)
			(layer "F.Fab")
		)
		(fp_poly
			(pts
				(xy -4.7498 -4.182872) (xy -4.7498 -3.166872) (xy -3.7338 -3.674872)
			)
			(stroke
				(width 0)
				(type default)
			)
			(fill yes)
			(layer "F.Fab")
		)
		(pad "1" smd rect
			(at -2.925064 -3.674872 270)
			(size 0.6096 1.3716)
			(layers "F.Cu" "F.Mask" "F.Paste")
			(net "PEX0_PCA9555_1_INT_N")
		)
		(pad "2" smd rect
			(at -2.925064 -2.925064 270)
			(size 0.4064 1.3716)
			(layers "F.Cu" "F.Mask" "F.Paste")
			(net "PCA9555_1_PEX0_A1")
		)
		(pad "3" smd rect
			(at -2.925064 -2.275078 270)
			(size 0.4064 1.3716)
			(layers "F.Cu" "F.Mask" "F.Paste")
			(net "PCA9555_1_PEX0_A2")
		)
		(pad "4" smd rect
			(at -2.925064 -1.625092 270)
			(size 0.4064 1.3716)
			(layers "F.Cu" "F.Mask" "F.Paste")
			(net "PRSNT_SSD2_FPGA_PCA9555_N")
		)
		(pad "5" smd rect
			(at -2.925064 -0.975106 270)
			(size 0.4064 1.3716)
			(layers "F.Cu" "F.Mask" "F.Paste")
			(net "SSD2_PEX_PWR_EN")
		)
		(pad "6" smd rect
			(at -2.925064 -0.32512 270)
			(size 0.4064 1.3716)
			(layers "F.Cu" "F.Mask" "F.Paste")
			(net "RST_PEX_SSD2_PERST_N")
		)
		(pad "7" smd rect
			(at -2.925064 0.32512 270)
			(size 0.4064 1.3716)
			(layers "F.Cu" "F.Mask" "F.Paste")
			(net "Net_1168")
		)
		(pad "8" smd rect
			(at -2.925064 0.975106 270)
			(size 0.4064 1.3716)
			(layers "F.Cu" "F.Mask" "F.Paste")
			(net "PRSNT_SSD3_FPGA_PCA9555_N")
		)
		(pad "9" smd rect
			(at -2.925064 1.625092 270)
			(size 0.4064 1.3716)
			(layers "F.Cu" "F.Mask" "F.Paste")
			(net "SSD3_PEX_PWR_EN")
		)
		(pad "10" smd rect
			(at -2.925064 2.275078 270)
			(size 0.4064 1.3716)
			(layers "F.Cu" "F.Mask" "F.Paste")
			(net "RST_PEX_SSD3_PERST_N")
		)
		(pad "11" smd rect
			(at -2.925064 2.925064 270)
			(size 0.4064 1.3716)
			(layers "F.Cu" "F.Mask" "F.Paste")
			(net "Net_1166")
		)
		(pad "12" smd rect
			(at -2.925064 3.674872 270)
			(size 0.6096 1.3716)
			(layers "F.Cu" "F.Mask" "F.Paste")
			(net "GND")
		)
		(pad "13" smd rect
			(at 2.925064 3.674872 270)
			(size 0.6096 1.3716)
			(layers "F.Cu" "F.Mask" "F.Paste")
			(net "PRSNT_NIC1_FPGA_PCA9555_N")
		)
		(pad "14" smd rect
			(at 2.925064 2.925064 270)
			(size 0.4064 1.3716)
			(layers "F.Cu" "F.Mask" "F.Paste")
			(net "NIC1_PEX_PWR_EN")
		)
		(pad "15" smd rect
			(at 2.925064 2.275078 270)
			(size 0.4064 1.3716)
			(layers "F.Cu" "F.Mask" "F.Paste")
			(net "RST_PEX_NIC1_PERST_N")
		)
		(pad "16" smd rect
			(at 2.925064 1.625092 270)
			(size 0.4064 1.3716)
			(layers "F.Cu" "F.Mask" "F.Paste")
			(net "Net_1167")
		)
		(pad "17" smd rect
			(at 2.925064 0.975106 270)
			(size 0.4064 1.3716)
			(layers "F.Cu" "F.Mask" "F.Paste")
			(net "Net_8988")
		)
		(pad "18" smd rect
			(at 2.925064 0.32512 270)
			(size 0.4064 1.3716)
			(layers "F.Cu" "F.Mask" "F.Paste")
			(net "Net_8987")
		)
		(pad "19" smd rect
			(at 2.925064 -0.32512 270)
			(size 0.4064 1.3716)
			(layers "F.Cu" "F.Mask" "F.Paste")
			(net "Net_8986")
		)
		(pad "20" smd rect
			(at 2.925064 -0.975106 270)
			(size 0.4064 1.3716)
			(layers "F.Cu" "F.Mask" "F.Paste")
			(net "Net_8985")
		)
		(pad "21" smd rect
			(at 2.925064 -1.625092 270)
			(size 0.4064 1.3716)
			(layers "F.Cu" "F.Mask" "F.Paste")
			(net "PCA9555_1_PEX0_A0")
		)
		(pad "22" smd rect
			(at 2.925064 -2.275078 270)
			(size 0.4064 1.3716)
			(layers "F.Cu" "F.Mask" "F.Paste")
			(net "SMB_PEX0_PCA9555_SCL")
		)
		(pad "23" smd rect
			(at 2.925064 -2.925064 270)
			(size 0.4064 1.3716)
			(layers "F.Cu" "F.Mask" "F.Paste")
			(net "SMB_PEX0_PCA9555_SDA")
		)
		(pad "24" smd rect
			(at 2.925064 -3.674872 270)
			(size 0.6096 1.3716)
			(layers "F.Cu" "F.Mask" "F.Paste")
			(net "P3V3_AUX")
		)
	)
	(footprint ""
		(layer "F.Cu")
		(at 143.764762 -239.853978 -90)
		(property "Reference" "C4420"
			(at 0 0 270)
			(layer "F.SilkS")
			(hide yes)
			(effects
				(font
					(size 1.27 1.27)
				)
			)
		)
		(property "Value" ""
			(at 0 0 270)
			(layer "F.Fab")
			(effects
				(font
					(size 1.27 1.27)
				)
			)
		)
		(duplicate_pad_numbers_are_jumpers no)
		(fp_line
			(start -1.524 0.762)
			(end -1.524 -0.762)
			(stroke
				(width 0.1524)
				(type default)
			)
			(layer "F.SilkS")
		)
		(fp_line
			(start 1.524 0.762)
			(end -1.524 0.762)
			(stroke
				(width 0.1524)
				(type default)
			)
			(layer "F.SilkS")
		)
		(fp_line
			(start -1.524 -0.762)
			(end 1.524 -0.762)
			(stroke
				(width 0.1524)
				(type default)
			)
			(layer "F.SilkS")
		)
		(fp_line
			(start 1.524 -0.762)
			(end 1.524 0.762)
			(stroke
				(width 0.1524)
				(type default)
			)
			(layer "F.SilkS")
		)
		(fp_line
			(start -1.1049 0.724916)
			(end 1.1049 0.724916)
			(stroke
				(width 0.1)
				(type default)
			)
			(layer "F.Fab")
		)
		(fp_line
			(start 1.1049 0.724916)
			(end 1.1049 -0.724916)
			(stroke
				(width 0.1)
				(type default)
			)
			(layer "F.Fab")
		)
		(fp_line
			(start -1.1049 -0.724916)
			(end -1.1049 0.724916)
			(stroke
				(width 0.1)
				(type default)
			)
			(layer "F.Fab")
		)
		(fp_line
			(start 1.1049 -0.724916)
			(end -1.1049 -0.724916)
			(stroke
				(width 0.1)
				(type default)
			)
			(layer "F.Fab")
		)
		(pad "1" smd rect
			(at -0.889 0 90)
			(size 1.016 1.27)
			(layers "F.Cu" "F.Mask" "F.Paste")
			(net "P3V3_AUX")
		)
		(pad "2" smd rect
			(at 0.889 0 90)
			(size 1.016 1.27)
			(layers "F.Cu" "F.Mask" "F.Paste")
			(net "GND")
		)
	)
	(footprint ""
		(layer "F.Cu")
		(at 284.226 -84.836 180)
		(property "Reference" "R485"
			(at 0 0 180)
			(layer "F.SilkS")
			(hide yes)
			(effects
				(font
					(size 1.27 1.27)
				)
			)
		)
		(property "Value" ""
			(at 0 0 180)
			(layer "F.Fab")
			(effects
				(font
					(size 1.27 1.27)
				)
			)
		)
		(duplicate_pad_numbers_are_jumpers no)
		(fp_line
			(start 0.7874 0.4064)
			(end -0.7874 0.4064)
			(stroke
				(width 0.1524)
				(type default)
			)
			(layer "F.SilkS")
		)
		(fp_line
			(start 0.7874 -0.4064)
			(end 0.7874 0.4064)
			(stroke
				(width 0.1524)
				(type default)
			)
			(layer "F.SilkS")
		)
		(fp_line
			(start -0.7874 0.4064)
			(end -0.7874 -0.4064)
			(stroke
				(width 0.1524)
				(type default)
			)
			(layer "F.SilkS")
		)
		(fp_line
			(start -0.7874 -0.4064)
			(end 0.7874 -0.4064)
			(stroke
				(width 0.1524)
				(type default)
			)
			(layer "F.SilkS")
		)
		(fp_line
			(start 0.67945 0.3048)
			(end 0.120396 0.3048)
			(stroke
				(width 0.1)
				(type default)
			)
			(layer "F.Fab")
		)
		(fp_line
			(start 0.67945 -0.3048)
			(end 0.67945 0.3048)
			(stroke
				(width 0.1)
				(type default)
			)
			(layer "F.Fab")
		)
		(fp_line
			(start 0.12065 -0.2794)
			(end 0.12065 -0.3048)
			(stroke
				(width 0.1)
				(type default)
			)
			(layer "F.Fab")
		)
		(fp_line
			(start 0.12065 -0.3048)
			(end 0.67945 -0.3048)
			(stroke
				(width 0.1)
				(type default)
			)
			(layer "F.Fab")
		)
		(fp_line
			(start 0.120396 0.3048)
			(end 0.120396 0.2794)
			(stroke
				(width 0.1)
				(type default)
			)
			(layer "F.Fab")
		)
		(fp_line
			(start 0.120396 0.2794)
			(end -0.12065 0.2794)
			(stroke
				(width 0.1)
				(type default)
			)
			(layer "F.Fab")
		)
		(fp_line
			(start -0.12065 0.3048)
			(end -0.67945 0.3048)
			(stroke
				(width 0.1)
				(type default)
			)
			(layer "F.Fab")
		)
		(fp_line
			(start -0.12065 0.2794)
			(end -0.12065 0.3048)
			(stroke
				(width 0.1)
				(type default)
			)
			(layer "F.Fab")
		)
		(fp_line
			(start -0.12065 -0.2794)
			(end 0.12065 -0.2794)
			(stroke
				(width 0.1)
				(type default)
			)
			(layer "F.Fab")
		)
		(fp_line
			(start -0.12065 -0.305054)
			(end -0.12065 -0.2794)
			(stroke
				(width 0.1)
				(type default)
			)
			(layer "F.Fab")
		)
		(fp_line
			(start -0.67945 0.3048)
			(end -0.67945 -0.305054)
			(stroke
				(width 0.1)
				(type default)
			)
			(layer "F.Fab")
		)
		(fp_line
			(start -0.67945 -0.305054)
			(end -0.12065 -0.305054)
			(stroke
				(width 0.1)
				(type default)
			)
			(layer "F.Fab")
		)
		(pad "1" smd circle
			(at -0.40005 0 180)
			(size 0 0)
			(layers "F.Cu" "F.Mask" "F.Paste")
			(net "BB_FRU_A1")
		)
		(pad "2" smd circle
			(at 0.40005 0 180)
			(size 0 0)
			(layers "F.Cu" "F.Mask" "F.Paste")
			(net "P3V3_AUX")
		)
	)
	(footprint ""
		(layer "F.Cu")
		(at 455.912982 -111.785654 180)
		(property "Reference" "PU106"
			(at 4.045712 -2.362454 90)
			(unlocked yes)
			(layer "F.SilkS")
			(effects
				(font
					(size 0.7874 0.5842)
					(thickness 0.1524)
				)
				(justify left)
			)
		)
		(property "Value" ""
			(at 0 0 180)
			(layer "F.Fab")
			(effects
				(font
					(size 1.27 1.27)
				)
			)
		)
		(duplicate_pad_numbers_are_jumpers no)
		(fp_line
			(start 1.549908 2.549906)
			(end 1.549908 2.253996)
			(stroke
				(width 0.1524)
				(type default)
			)
			(layer "F.SilkS")
		)
		(fp_line
			(start 1.549908 -2.253996)
			(end 1.549908 -2.549906)
			(stroke
				(width 0.1524)
				(type default)
			)
			(layer "F.SilkS")
		)
		(fp_line
			(start 1.549908 -2.549906)
			(end 0.752094 -2.549906)
			(stroke
				(width 0.1524)
				(type default)
			)
			(layer "F.SilkS")
		)
		(fp_line
			(start 0.753872 2.549906)
			(end 1.549908 2.549906)
			(stroke
				(width 0.1524)
				(type default)
			)
			(layer "F.SilkS")
		)
		(fp_line
			(start 0.2413 -2.549906)
			(end -0.2413 -2.549906)
			(stroke
				(width 0.1524)
				(type default)
			)
			(layer "F.SilkS")
		)
		(fp_line
			(start -0.245872 2.549906)
			(end 0.245872 2.549906)
			(stroke
				(width 0.1524)
				(type default)
			)
			(layer "F.SilkS")
		)
		(fp_line
			(start -0.752094 -2.549906)
			(end -1.549908 -2.549906)
			(stroke
				(width 0.1524)
				(type default)
			)
			(layer "F.SilkS")
		)
		(fp_line
			(start -1.549908 2.549906)
			(end -0.753872 2.549906)
			(stroke
				(width 0.1524)
				(type default)
			)
			(layer "F.SilkS")
		)
		(fp_line
			(start -1.549908 2.253996)
			(end -1.549908 2.549906)
			(stroke
				(width 0.1524)
				(type default)
			)
			(layer "F.SilkS")
		)
		(fp_line
			(start -1.549908 -2.549906)
			(end -1.549908 -2.251964)
			(stroke
				(width 0.1524)
				(type default)
			)
			(layer "F.SilkS")
		)
		(fp_poly
			(pts
				(xy -2.367026 -1.999996) (xy -3.218688 -1.574292) (xy -3.218688 -2.4257)
			)
			(stroke
				(width 0)
				(type default)
			)
			(fill yes)
			(layer "F.SilkS")
		)
		(fp_line
			(start 1.549908 2.549906)
			(end 1.549908 -2.549906)
			(stroke
				(width 0.1)
				(type default)
			)
			(layer "F.Fab")
		)
		(fp_line
			(start 1.549908 -2.549906)
			(end -1.549908 -2.549906)
			(stroke
				(width 0.1)
				(type default)
			)
			(layer "F.Fab")
		)
		(fp_line
			(start -1.549908 2.549906)
			(end 1.549908 2.549906)
			(stroke
				(width 0.1)
				(type default)
			)
			(layer "F.Fab")
		)
		(fp_line
			(start -1.549908 -2.549906)
			(end -1.549908 2.549906)
			(stroke
				(width 0.1)
				(type default)
			)
			(layer "F.Fab")
		)
		(fp_poly
			(pts
				(xy -1.891538 -1.999996) (xy -2.7432 -1.574292) (xy -2.7432 -2.4257)
			)
			(stroke
				(width 0)
				(type default)
			)
			(fill yes)
			(layer "F.Fab")
		)
		(fp_text user "12"
			(at 2.552954 0.973836 90)
			(unlocked yes)
			(layer "F.SilkS")
			(effects
				(font
					(size 0.635 0.4064)
					(thickness 0.1524)
				)
			)
		)
		(fp_text user "20"
			(at 2.055368 -2.7686 90)
			(unlocked yes)
			(layer "F.SilkS")
			(effects
				(font
					(size 0.635 0.4064)
					(thickness 0.1524)
				)
			)
		)
		(fp_text user "11"
			(at 1.22936 2.978912 0)
			(unlocked yes)
			(layer "F.SilkS")
			(effects
				(font
					(size 0.635 0.4064)
					(thickness 0.1524)
				)
			)
		)
		(fp_text user "10"
			(at -1.325626 3.103118 0)
			(unlocked yes)
			(layer "F.SilkS")
			(effects
				(font
					(size 0.635 0.4064)
					(thickness 0.1524)
				)
			)
		)
		(fp_text user "21_22"
			(at -1.44653 -3.602228 0)
			(unlocked yes)
			(layer "F.SilkS")
			(effects
				(font
					(size 0.635 0.4064)
					(thickness 0.1524)
				)
			)
		)
		(fp_text user "9"
			(at -2.181098 2.411476 0)
			(unlocked yes)
			(layer "F.SilkS")
			(effects
				(font
					(size 0.635 0.4064)
					(thickness 0.1524)
				)
			)
		)
		(fp_text user "12"
			(at 2.207768 2.7178 90)
			(unlocked yes)
			(layer "F.Fab")
			(effects
				(font
					(size 0.635 0.4064)
					(thickness 0.1524)
				)
			)
		)
		(fp_text user "20"
			(at 2.055368 -2.7686 90)
			(unlocked yes)
			(layer "F.Fab")
			(effects
				(font
					(size 0.635 0.4064)
					(thickness 0.1524)
				)
			)
		)
		(fp_text user "11"
			(at 1.1938 3.329432 180)
			(unlocked yes)
			(layer "F.Fab")
			(effects
				(font
					(size 0.635 0.4064)
					(thickness 0.1524)
				)
			)
		)
		(fp_text user "21_22"
			(at -0.0762 -3.401568 180)
			(unlocked yes)
			(layer "F.Fab")
			(effects
				(font
					(size 0.635 0.4064)
					(thickness 0.1524)
				)
			)
		)
		(fp_text user "10"
			(at -1.4224 3.253232 180)
			(unlocked yes)
			(layer "F.Fab")
			(effects
				(font
					(size 0.635 0.4064)
					(thickness 0.1524)
				)
			)
		)
		(fp_text user "9"
			(at -2.338832 2.5908 90)
			(unlocked yes)
			(layer "F.Fab")
			(effects
				(font
					(size 0.635 0.4064)
					(thickness 0.1524)
				)
			)
		)
		(pad "1" smd circle
			(at -1.374902 -1.999996 90)
			(size 0 0)
			(layers "F.Cu" "F.Mask" "F.Paste")
			(net "P12V_NIC7_CO_EN")
		)
		(pad "2" smd rect
			(at -1.400048 -1.500124 90)
			(size 0.254 0.8128)
			(layers "F.Cu" "F.Mask" "F.Paste")
			(net "GND")
		)
		(pad "3" smd rect
			(at -1.400048 -0.999998 90)
			(size 0.254 0.8128)
			(layers "F.Cu" "F.Mask" "F.Paste")
			(net "GND")
		)
		(pad "4" smd rect
			(at -1.400048 -0.499872 90)
			(size 0.254 0.8128)
			(layers "F.Cu" "F.Mask" "F.Paste")
			(net "P12V_NIC7_CO_TIMER")
		)
		(pad "5" smd rect
			(at -1.400048 0 90)
			(size 0.254 0.8128)
			(layers "F.Cu" "F.Mask" "F.Paste")
			(net "P12V_NIC7_CO_ISET")
		)
		(pad "6" smd rect
			(at -1.400048 0.499872 90)
			(size 0.254 0.8128)
			(layers "F.Cu" "F.Mask" "F.Paste")
			(net "P12V_NIC7_CO_SS")
		)
		(pad "7" smd rect
			(at -1.400048 0.999998 90)
			(size 0.254 0.8128)
			(layers "F.Cu" "F.Mask" "F.Paste")
			(net "GND")
		)
		(pad "8" smd rect
			(at -1.400048 1.500124 90)
			(size 0.254 0.8128)
			(layers "F.Cu" "F.Mask" "F.Paste")
			(net "P12V_NIC7_CO_IMON_VR")
		)
		(pad "9" smd rect
			(at -1.400048 1.999996 90)
			(size 0.254 0.8128)
			(layers "F.Cu" "F.Mask" "F.Paste")
			(net "P12V_NIC7_CO_FLTB")
		)
		(pad "10" smd rect
			(at -0.499872 2.400046 180)
			(size 0.254 0.8128)
			(layers "F.Cu" "F.Mask" "F.Paste")
			(net "PWRGD_P12V_NIC7_CO")
		)
		(pad "11" smd rect
			(at 0.499872 2.400046 180)
			(size 0.254 0.8128)
			(layers "F.Cu" "F.Mask" "F.Paste")
			(net "P12V_NIC7_CO_OV_FB")
		)
		(pad "12" smd rect
			(at 1.400048 1.999996 90)
			(size 0.254 0.8128)
			(layers "F.Cu" "F.Mask" "F.Paste")
			(net "P12V_NIC7_CO_AVIN_PD")
		)
		(pad "13" smd rect
			(at 1.400048 1.500124 90)
			(size 0.254 0.8128)
			(layers "F.Cu" "F.Mask" "F.Paste")
			(net "P12V_NIC7_R")
		)
		(pad "14" smd rect
			(at 1.400048 0.999998 90)
			(size 0.254 0.8128)
			(layers "F.Cu" "F.Mask" "F.Paste")
			(net "P12V_NIC7_R")
		)
		(pad "15" smd rect
			(at 1.400048 0.499872 90)
			(size 0.254 0.8128)
			(layers "F.Cu" "F.Mask" "F.Paste")
			(net "P12V_NIC7_R")
		)
		(pad "16" smd rect
			(at 1.400048 0 90)
			(size 0.254 0.8128)
			(layers "F.Cu" "F.Mask" "F.Paste")
			(net "P12V_NIC7_R")
		)
		(pad "17" smd rect
			(at 1.400048 -0.499872 90)
			(size 0.254 0.8128)
			(layers "F.Cu" "F.Mask" "F.Paste")
			(net "P12V_NIC7_R")
		)
		(pad "18" smd rect
			(at 1.400048 -0.999998 90)
			(size 0.254 0.8128)
			(layers "F.Cu" "F.Mask" "F.Paste")
			(net "P12V_NIC7_R")
		)
		(pad "19" smd rect
			(at 1.400048 -1.500124 90)
			(size 0.254 0.8128)
			(layers "F.Cu" "F.Mask" "F.Paste")
			(net "P12V_NIC7_R")
		)
		(pad "20" smd rect
			(at 1.400048 -1.999996 90)
			(size 0.254 0.8128)
			(layers "F.Cu" "F.Mask" "F.Paste")
			(net "P12V_NIC7_R")
		)
		(pad "21_22" smd circle
			(at 0.499872 -2.337562 90)
			(size 0 0)
			(layers "F.Cu" "F.Mask" "F.Paste")
			(net "P12V_AUX")
		)
		(pad "23" smd rect
			(at 0 -1.100074 90)
			(size 0.254 1.27)
			(layers "F.Cu" "F.Mask" "F.Paste")
			(net "P12V_AUX")
		)
		(pad "24" smd rect
			(at 0 -0.199898 90)
			(size 0.254 1.27)
			(layers "F.Cu" "F.Mask" "F.Paste")
			(net "P12V_AUX")
		)
		(pad "25" smd rect
			(at 0 0.700024 90)
			(size 0.254 1.27)
			(layers "F.Cu" "F.Mask" "F.Paste")
			(net "P12V_AUX")
		)
		(pad "26" smd rect
			(at 0 1.599946 90)
			(size 0.254 1.27)
			(layers "F.Cu" "F.Mask" "F.Paste")
			(net "P12V_AUX")
		)
	)
	(footprint ""
		(layer "F.Cu")
		(at 146.253454 -281.789632)
		(property "Reference" "L112"
			(at 0 0 0)
			(layer "F.SilkS")
			(hide yes)
			(effects
				(font
					(size 1.27 1.27)
				)
			)
		)
		(property "Value" ""
			(at 0 0 0)
			(layer "F.Fab")
			(effects
				(font
					(size 1.27 1.27)
				)
			)
		)
		(duplicate_pad_numbers_are_jumpers no)
		(fp_line
			(start -1.63576 -0.8128)
			(end -1.63576 0.8128)
			(stroke
				(width 0.1524)
				(type default)
			)
			(layer "F.SilkS")
		)
		(fp_line
			(start -1.63576 -0.8128)
			(end 1.63576 -0.8128)
			(stroke
				(width 0.1524)
				(type default)
			)
			(layer "F.SilkS")
		)
		(fp_line
			(start 1.63576 -0.8128)
			(end 1.63576 0.8128)
			(stroke
				(width 0.1524)
				(type default)
			)
			(layer "F.SilkS")
		)
		(fp_line
			(start 1.63576 0.8128)
			(end -1.63576 0.8128)
			(stroke
				(width 0.1524)
				(type default)
			)
			(layer "F.SilkS")
		)
		(fp_line
			(start -1.56083 -0.738632)
			(end -1.56083 0.7366)
			(stroke
				(width 0.1)
				(type default)
			)
			(layer "F.Fab")
		)
		(fp_line
			(start -1.56083 0.7366)
			(end -1.524 0.7366)
			(stroke
				(width 0.1)
				(type default)
			)
			(layer "F.Fab")
		)
		(fp_line
			(start -1.524 0.7366)
			(end 1.524 0.7366)
			(stroke
				(width 0.1)
				(type default)
			)
			(layer "F.Fab")
		)
		(fp_line
			(start 1.524 0.7366)
			(end 1.560576 0.7366)
			(stroke
				(width 0.1)
				(type default)
			)
			(layer "F.Fab")
		)
		(fp_line
			(start 1.560576 -0.738632)
			(end -1.56083 -0.738632)
			(stroke
				(width 0.1)
				(type default)
			)
			(layer "F.Fab")
		)
		(fp_line
			(start 1.560576 0.7366)
			(end 1.560576 -0.738632)
			(stroke
				(width 0.1)
				(type default)
			)
			(layer "F.Fab")
		)
		(pad "1" smd rect
			(at -0.94996 0 180)
			(size 1.1176 1.3716)
			(layers "F.Cu" "F.Mask" "F.Paste")
			(net "P1V8_PLL0_PEX1")
		)
		(pad "2" smd rect
			(at 0.94996 0 180)
			(size 1.1176 1.3716)
			(layers "F.Cu" "F.Mask" "F.Paste")
			(net "SYSPLL_VDDA18_PEX1")
		)
	)
	(footprint ""
		(layer "F.Cu")
		(at 433.190904 -55.663846 90)
		(property "Reference" "PU68"
			(at -1.304036 2.97561 90)
			(unlocked yes)
			(layer "F.SilkS")
			(effects
				(font
					(size 0.7874 0.5842)
					(thickness 0.1524)
				)
				(justify left)
			)
		)
		(property "Value" ""
			(at 0 0 90)
			(layer "F.Fab")
			(effects
				(font
					(size 1.27 1.27)
				)
			)
		)
		(duplicate_pad_numbers_are_jumpers no)
		(fp_line
			(start 1.943608 -1.549908)
			(end 1.943608 1.549908)
			(stroke
				(width 0.1524)
				(type default)
			)
			(layer "F.SilkS")
		)
		(fp_line
			(start -1.943608 -1.549908)
			(end 1.943608 -1.549908)
			(stroke
				(width 0.1524)
				(type default)
			)
			(layer "F.SilkS")
		)
		(fp_line
			(start 1.943608 1.549908)
			(end -1.943608 1.549908)
			(stroke
				(width 0.1524)
				(type default)
			)
			(layer "F.SilkS")
		)
		(fp_line
			(start -1.943608 1.549908)
			(end -1.943608 -1.549908)
			(stroke
				(width 0.1524)
				(type default)
			)
			(layer "F.SilkS")
		)
		(fp_poly
			(pts
				(xy -2.019808 -1.549908) (xy -1.257808 -1.549908) (xy -1.257808 -1.880108) (xy -2.019808 -1.880108)
			)
			(stroke
				(width 0)
				(type default)
			)
			(fill yes)
			(layer "F.SilkS")
		)
		(fp_line
			(start 1.549908 -1.549908)
			(end 1.549908 1.549908)
			(stroke
				(width 0.1)
				(type default)
			)
			(layer "F.Fab")
		)
		(fp_line
			(start -1.549908 -1.549908)
			(end 1.549908 -1.549908)
			(stroke
				(width 0.1)
				(type default)
			)
			(layer "F.Fab")
		)
		(fp_line
			(start 1.549908 1.549908)
			(end -1.549908 1.549908)
			(stroke
				(width 0.1)
				(type default)
			)
			(layer "F.Fab")
		)
		(fp_line
			(start -1.549908 1.549908)
			(end -1.549908 -1.549908)
			(stroke
				(width 0.1)
				(type default)
			)
			(layer "F.Fab")
		)
		(fp_poly
			(pts
				(xy -2.019808 -1.549908) (xy -1.257808 -1.549908) (xy -1.257808 -1.880108) (xy -2.019808 -1.880108)
			)
			(stroke
				(width 0)
				(type default)
			)
			(fill yes)
			(layer "F.Fab")
		)
		(pad "1" smd rect
			(at -1.500124 -1.249934)
			(size 0.2794 0.6096)
			(layers "F.Cu" "F.Mask" "F.Paste")
			(net "P3V3_SSD15")
		)
		(pad "2" smd rect
			(at -1.500124 -0.750062)
			(size 0.2794 0.6096)
			(layers "F.Cu" "F.Mask" "F.Paste")
			(net "P3V3_SSD15")
		)
		(pad "3" smd rect
			(at -1.500124 -0.249936)
			(size 0.2794 0.6096)
			(layers "F.Cu" "F.Mask" "F.Paste")
			(net "P3V3_SSD15")
		)
		(pad "4" smd rect
			(at -1.500124 0.249936)
			(size 0.2794 0.6096)
			(layers "F.Cu" "F.Mask" "F.Paste")
			(net "P3V3_SSD15")
		)
		(pad "5" smd rect
			(at -1.500124 0.750062)
			(size 0.2794 0.6096)
			(layers "F.Cu" "F.Mask" "F.Paste")
			(net "P3V3_SSD15")
		)
		(pad "6" smd rect
			(at -1.500124 1.249934)
			(size 0.2794 0.6096)
			(layers "F.Cu" "F.Mask" "F.Paste")
			(net "GND")
		)
		(pad "7" smd rect
			(at 1.500124 1.249934)
			(size 0.2794 0.6096)
			(layers "F.Cu" "F.Mask" "F.Paste")
			(net "P3V3_SSD15_SS")
		)
		(pad "8" smd rect
			(at 1.500124 0.750062)
			(size 0.2794 0.6096)
			(layers "F.Cu" "F.Mask" "F.Paste")
			(net "PWRGD_P3V3_SSD15")
		)
		(pad "9" smd rect
			(at 1.500124 0.249936)
			(size 0.2794 0.6096)
			(layers "F.Cu" "F.Mask" "F.Paste")
			(net "P3V3_SSD15_OCP")
		)
		(pad "10" smd rect
			(at 1.500124 -0.249936)
			(size 0.2794 0.6096)
			(layers "F.Cu" "F.Mask" "F.Paste")
			(net "P5V_AUX")
		)
		(pad "11" smd rect
			(at 1.500124 -0.750062)
			(size 0.2794 0.6096)
			(layers "F.Cu" "F.Mask" "F.Paste")
			(net "SSD15_AUX_P3V3_EN_R")
		)
		(pad "12" smd rect
			(at 1.500124 -1.249934)
			(size 0.2794 0.6096)
			(layers "F.Cu" "F.Mask" "F.Paste")
			(net "P3V3_AUX")
		)
		(pad "13" smd rect
			(at 0 0 90)
			(size 1.9812 2.7178)
			(layers "F.Cu" "F.Mask" "F.Paste")
			(net "P3V3_AUX")
		)
		(zone
			(layer "F.Cu")
			(hatch none 0.5)
			(connect_pads
				(clearance 0)
			)
			(min_thickness 0.25)
			(keepout
				(tracks not_allowed)
				(vias allowed)
				(pads allowed)
				(copperpour not_allowed)
				(footprints allowed)
			)
			(placement
				(enabled no)
				(sheetname "")
			)
			(fill
				(thermal_gap 0.5)
				(thermal_bridge_width 0.5)
				(island_removal_mode 0)
			)
			(polygon
				(pts
					(xy 431.641504 -56.806846) (xy 431.768504 -56.806846) (xy 434.740304 -56.806846) (xy 434.740812 -56.806846)
					(xy 434.740812 -54.520846) (xy 434.740304 -54.520846) (xy 434.613304 -54.520846) (xy 433.190904 -54.520846)
					(xy 433.190904 -54.622446) (xy 434.613304 -54.622446) (xy 434.613304 -56.705246) (xy 431.768504 -56.705246)
					(xy 431.768504 -54.622446) (xy 433.165504 -54.622446) (xy 433.165504 -54.520846) (xy 431.768504 -54.520846)
					(xy 431.641504 -54.520846) (xy 431.640996 -54.520846) (xy 431.640996 -56.806846)
				)
			)
		)
	)
	(footprint ""
		(layer "F.Cu")
		(at 120.626886 -53.697124 -90)
		(property "Reference" "PC508"
			(at 0 0 270)
			(layer "F.SilkS")
			(hide yes)
			(effects
				(font
					(size 1.27 1.27)
				)
			)
		)
		(property "Value" ""
			(at 0 0 270)
			(layer "F.Fab")
			(effects
				(font
					(size 1.27 1.27)
				)
			)
		)
		(duplicate_pad_numbers_are_jumpers no)
		(fp_line
			(start -0.7874 0.4064)
			(end -0.7874 -0.4064)
			(stroke
				(width 0.1524)
				(type default)
			)
			(layer "F.SilkS")
		)
		(fp_line
			(start 0.7874 0.4064)
			(end -0.7874 0.4064)
			(stroke
				(width 0.1524)
				(type default)
			)
			(layer "F.SilkS")
		)
		(fp_line
			(start -0.7874 -0.4064)
			(end 0.7874 -0.4064)
			(stroke
				(width 0.1524)
				(type default)
			)
			(layer "F.SilkS")
		)
		(fp_line
			(start 0.7874 -0.4064)
			(end 0.7874 0.4064)
			(stroke
				(width 0.1524)
				(type default)
			)
			(layer "F.SilkS")
		)
		(fp_line
			(start -0.67945 0.3048)
			(end -0.67945 -0.305054)
			(stroke
				(width 0.1)
				(type default)
			)
			(layer "F.Fab")
		)
		(fp_line
			(start -0.12065 0.3048)
			(end -0.67945 0.3048)
			(stroke
				(width 0.1)
				(type default)
			)
			(layer "F.Fab")
		)
		(fp_line
			(start 0.120396 0.3048)
			(end 0.120396 0.2794)
			(stroke
				(width 0.1)
				(type default)
			)
			(layer "F.Fab")
		)
		(fp_line
			(start 0.67945 0.3048)
			(end 0.120396 0.3048)
			(stroke
				(width 0.1)
				(type default)
			)
			(layer "F.Fab")
		)
		(fp_line
			(start -0.12065 0.2794)
			(end -0.12065 0.3048)
			(stroke
				(width 0.1)
				(type default)
			)
			(layer "F.Fab")
		)
		(fp_line
			(start 0.120396 0.2794)
			(end -0.12065 0.2794)
			(stroke
				(width 0.1)
				(type default)
			)
			(layer "F.Fab")
		)
		(fp_line
			(start -0.12065 -0.2794)
			(end 0.12065 -0.2794)
			(stroke
				(width 0.1)
				(type default)
			)
			(layer "F.Fab")
		)
		(fp_line
			(start 0.12065 -0.2794)
			(end 0.12065 -0.3048)
			(stroke
				(width 0.1)
				(type default)
			)
			(layer "F.Fab")
		)
		(fp_line
			(start 0.12065 -0.3048)
			(end 0.67945 -0.3048)
			(stroke
				(width 0.1)
				(type default)
			)
			(layer "F.Fab")
		)
		(fp_line
			(start 0.67945 -0.3048)
			(end 0.67945 0.3048)
			(stroke
				(width 0.1)
				(type default)
			)
			(layer "F.Fab")
		)
		(fp_line
			(start -0.67945 -0.305054)
			(end -0.12065 -0.305054)
			(stroke
				(width 0.1)
				(type default)
			)
			(layer "F.Fab")
		)
		(fp_line
			(start -0.12065 -0.305054)
			(end -0.12065 -0.2794)
			(stroke
				(width 0.1)
				(type default)
			)
			(layer "F.Fab")
		)
		(pad "1" smd circle
			(at -0.40005 0 270)
			(size 0 0)
			(layers "F.Cu" "F.Mask" "F.Paste")
			(net "P3V3_AUX")
		)
		(pad "2" smd circle
			(at 0.40005 0 270)
			(size 0 0)
			(layers "F.Cu" "F.Mask" "F.Paste")
			(net "GND")
		)
	)
	(footprint ""
		(layer "F.Cu")
		(at 338.17179 -284.8991 180)
		(property "Reference" "PU12"
			(at -29.782262 -2.645156 90)
			(unlocked yes)
			(layer "F.SilkS")
			(effects
				(font
					(size 0.7874 0.5842)
					(thickness 0.1524)
				)
				(justify left)
			)
		)
		(property "Value" ""
			(at 0 0 180)
			(layer "F.Fab")
			(effects
				(font
					(size 1.27 1.27)
				)
			)
		)
		(duplicate_pad_numbers_are_jumpers no)
		(fp_line
			(start 2.500122 2.999994)
			(end 2.2987 2.999994)
			(stroke
				(width 0.1524)
				(type default)
			)
			(layer "F.SilkS")
		)
		(fp_line
			(start 2.500122 2.339594)
			(end 2.500122 2.999994)
			(stroke
				(width 0.1524)
				(type default)
			)
			(layer "F.SilkS")
		)
		(fp_line
			(start 2.500122 -2.999994)
			(end 2.500122 -2.44348)
			(stroke
				(width 0.1524)
				(type default)
			)
			(layer "F.SilkS")
		)
		(fp_line
			(start 2.31394 -2.999994)
			(end 2.500122 -2.999994)
			(stroke
				(width 0.1524)
				(type default)
			)
			(layer "F.SilkS")
		)
		(fp_line
			(start -2.2987 2.999994)
			(end -2.500122 2.999994)
			(stroke
				(width 0.1524)
				(type default)
			)
			(layer "F.SilkS")
		)
		(fp_line
			(start -2.500122 2.999994)
			(end -2.500122 2.339594)
			(stroke
				(width 0.1524)
				(type default)
			)
			(layer "F.SilkS")
		)
		(fp_line
			(start -2.500122 0.6604)
			(end -2.500122 0.229108)
			(stroke
				(width 0.1524)
				(type default)
			)
			(layer "F.SilkS")
		)
		(fp_line
			(start -2.500122 -2.529078)
			(end -2.500122 -2.999994)
			(stroke
				(width 0.1524)
				(type default)
			)
			(layer "F.SilkS")
		)
		(fp_line
			(start -2.500122 -2.999994)
			(end -2.24409 -2.999994)
			(stroke
				(width 0.1524)
				(type default)
			)
			(layer "F.SilkS")
		)
		(fp_poly
			(pts
				(xy -3.912616 -4.4958) (xy -4.631182 -3.777234) (xy -3.55346 -3.418078)
			)
			(stroke
				(width 0)
				(type default)
			)
			(fill yes)
			(layer "F.SilkS")
		)
		(fp_line
			(start 2.500122 2.999994)
			(end -2.500122 2.999994)
			(stroke
				(width 0.1)
				(type default)
			)
			(layer "F.Fab")
		)
		(fp_line
			(start 2.500122 -2.999994)
			(end 2.500122 2.999994)
			(stroke
				(width 0.1)
				(type default)
			)
			(layer "F.Fab")
		)
		(fp_line
			(start -2.500122 2.999994)
			(end -2.500122 -2.999994)
			(stroke
				(width 0.1)
				(type default)
			)
			(layer "F.Fab")
		)
		(fp_line
			(start -2.500122 -2.999994)
			(end 2.500122 -2.999994)
			(stroke
				(width 0.1)
				(type default)
			)
			(layer "F.Fab")
		)
		(fp_poly
			(pts
				(xy -4.218432 -2.783078) (xy -4.218432 -1.767078) (xy -3.202432 -2.275078)
			)
			(stroke
				(width 0)
				(type default)
			)
			(fill yes)
			(layer "F.Fab")
		)
		(pad "1" smd rect
			(at -2.400046 -2.275078 270)
			(size 0.2286 0.6096)
			(layers "F.Cu" "F.Mask" "F.Paste")
			(net "SW_P0V8_PEX2_VOS1")
		)
		(pad "2" smd rect
			(at -2.400046 -1.82499 270)
			(size 0.2286 0.6096)
			(layers "F.Cu" "F.Mask" "F.Paste")
			(net "GND")
		)
		(pad "3" smd rect
			(at -2.400046 -1.374902 270)
			(size 0.2286 0.6096)
			(layers "F.Cu" "F.Mask" "F.Paste")
			(net "P0V8_PEX2_VCC1")
		)
		(pad "4" smd rect
			(at -2.400046 -0.925068 270)
			(size 0.2286 0.6096)
			(layers "F.Cu" "F.Mask" "F.Paste")
			(net "P0V8_PEX2_PVCC")
		)
		(pad "5" smd rect
			(at -2.400046 -0.47498 270)
			(size 0.2286 0.6096)
			(layers "F.Cu" "F.Mask" "F.Paste")
			(net "GND")
		)
		(pad "6" smd rect
			(at -2.400046 -0.024892 270)
			(size 0.2286 0.6096)
			(layers "F.Cu" "F.Mask" "F.Paste")
			(net "NC_P0V8_PEX2_PH1_NC1")
		)
		(pad "7_9-20_24" smd circle
			(at 0 1.150112 270)
			(size 0 0)
			(layers "F.Cu" "F.Mask" "F.Paste")
			(net "GND")
		)
		(pad "10_19" smd rect
			(at 0 2.899918 270)
			(size 0.6096 4.318)
			(layers "F.Cu" "F.Mask" "F.Paste")
			(net "SW_P0V8_PEX2_PH1")
		)
		(pad "25_29" smd rect
			(at 1.549908 -1.279906 90)
			(size 2.0574 2.3114)
			(layers "F.Cu" "F.Mask" "F.Paste")
			(net "SW_P12V_P0V8_PEX2_FLT")
		)
		(pad "30" smd rect
			(at 2.05994 -2.899918 180)
			(size 0.2286 0.6096)
			(layers "F.Cu" "F.Mask" "F.Paste")
			(net "SW_P12V_P0V8_PEX2_FLT")
		)
		(pad "31" smd rect
			(at 1.610106 -2.899918 180)
			(size 0.2286 0.6096)
			(layers "F.Cu" "F.Mask" "F.Paste")
			(net "NC_P0V8_PEX2_PH1_NC3")
		)
		(pad "32" smd rect
			(at 1.160018 -2.899918 180)
			(size 0.2286 0.6096)
			(layers "F.Cu" "F.Mask" "F.Paste")
			(net "SW_P0V8_PEX2_PHASE1")
		)
		(pad "33" smd rect
			(at 0.70993 -2.899918 180)
			(size 0.2286 0.6096)
			(layers "F.Cu" "F.Mask" "F.Paste")
			(net "SW_P0V8_PEX2_BOOT1")
		)
		(pad "34" smd rect
			(at 0.260096 -2.899918 180)
			(size 0.2286 0.6096)
			(layers "F.Cu" "F.Mask" "F.Paste")
			(net "P0V8_PEX2_PWM1")
		)
		(pad "35" smd rect
			(at -0.189992 -2.899918 180)
			(size 0.2286 0.6096)
			(layers "F.Cu" "F.Mask" "F.Paste")
			(net "P0V8_PEX2_EN1")
		)
		(pad "36" smd rect
			(at -0.64008 -2.899918 180)
			(size 0.2286 0.6096)
			(layers "F.Cu" "F.Mask" "F.Paste")
			(net "P0V8_PEX2_TSEN")
		)
		(pad "37" smd rect
			(at -1.089914 -2.899918 180)
			(size 0.2286 0.6096)
			(layers "F.Cu" "F.Mask" "F.Paste")
			(net "P0V8_PEX2_LSET1")
		)
		(pad "38" smd rect
			(at -1.540002 -2.899918 180)
			(size 0.2286 0.6096)
			(layers "F.Cu" "F.Mask" "F.Paste")
			(net "P0V8_PEX2_ISEN1")
		)
		(pad "39" smd rect
			(at -1.99009 -2.899918 180)
			(size 0.2286 0.6096)
			(layers "F.Cu" "F.Mask" "F.Paste")
			(net "P0V8_PEX2_VREF")
		)
		(pad "40" smd rect
			(at -0.87503 -1.27508 180)
			(size 1.7526 1.9558)
			(layers "F.Cu" "F.Mask" "F.Paste")
			(net "GND")
		)
		(pad "41" smd rect
			(at -1.525016 0.249936 90)
			(size 0.3048 0.4572)
			(layers "F.Cu" "F.Mask" "F.Paste")
			(net "NC_P0V8_PEX2_PH1_NC2")
		)
		(zone
			(layer "F.Cu")
			(hatch none 0.5)
			(connect_pads
				(clearance 0)
			)
			(min_thickness 0.25)
			(keepout
				(tracks not_allowed)
				(vias allowed)
				(pads allowed)
				(copperpour not_allowed)
				(footprints allowed)
			)
			(placement
				(enabled no)
				(sheetname "")
			)
			(fill
				(thermal_gap 0.5)
				(thermal_bridge_width 0.5)
				(island_removal_mode 0)
			)
			(polygon
				(pts
					(xy 340.671912 -287.899094) (xy 340.671912 -287.149794) (xy 335.671668 -287.149794) (xy 335.671668 -287.899094)
					(xy 335.96199 -287.899094) (xy 335.96199 -287.443418) (xy 340.38159 -287.443418) (xy 340.38159 -287.899094)
				)
			)
		)
	)
	(footprint ""
		(layer "F.Cu")
		(at 138.985244 -92.385642 180)
		(property "Reference" "R1569"
			(at 0 0 180)
			(layer "F.SilkS")
			(hide yes)
			(effects
				(font
					(size 1.27 1.27)
				)
			)
		)
		(property "Value" ""
			(at 0 0 180)
			(layer "F.Fab")
			(effects
				(font
					(size 1.27 1.27)
				)
			)
		)
		(duplicate_pad_numbers_are_jumpers no)
		(fp_line
			(start 0.7874 0.4064)
			(end -0.7874 0.4064)
			(stroke
				(width 0.1524)
				(type default)
			)
			(layer "F.SilkS")
		)
		(fp_line
			(start 0.7874 -0.4064)
			(end 0.7874 0.4064)
			(stroke
				(width 0.1524)
				(type default)
			)
			(layer "F.SilkS")
		)
		(fp_line
			(start -0.7874 0.4064)
			(end -0.7874 -0.4064)
			(stroke
				(width 0.1524)
				(type default)
			)
			(layer "F.SilkS")
		)
		(fp_line
			(start -0.7874 -0.4064)
			(end 0.7874 -0.4064)
			(stroke
				(width 0.1524)
				(type default)
			)
			(layer "F.SilkS")
		)
		(fp_line
			(start 0.67945 0.3048)
			(end 0.120396 0.3048)
			(stroke
				(width 0.1)
				(type default)
			)
			(layer "F.Fab")
		)
		(fp_line
			(start 0.67945 -0.3048)
			(end 0.67945 0.3048)
			(stroke
				(width 0.1)
				(type default)
			)
			(layer "F.Fab")
		)
		(fp_line
			(start 0.12065 -0.2794)
			(end 0.12065 -0.3048)
			(stroke
				(width 0.1)
				(type default)
			)
			(layer "F.Fab")
		)
		(fp_line
			(start 0.12065 -0.3048)
			(end 0.67945 -0.3048)
			(stroke
				(width 0.1)
				(type default)
			)
			(layer "F.Fab")
		)
		(fp_line
			(start 0.120396 0.3048)
			(end 0.120396 0.2794)
			(stroke
				(width 0.1)
				(type default)
			)
			(layer "F.Fab")
		)
		(fp_line
			(start 0.120396 0.2794)
			(end -0.12065 0.2794)
			(stroke
				(width 0.1)
				(type default)
			)
			(layer "F.Fab")
		)
		(fp_line
			(start -0.12065 0.3048)
			(end -0.67945 0.3048)
			(stroke
				(width 0.1)
				(type default)
			)
			(layer "F.Fab")
		)
		(fp_line
			(start -0.12065 0.2794)
			(end -0.12065 0.3048)
			(stroke
				(width 0.1)
				(type default)
			)
			(layer "F.Fab")
		)
		(fp_line
			(start -0.12065 -0.2794)
			(end 0.12065 -0.2794)
			(stroke
				(width 0.1)
				(type default)
			)
			(layer "F.Fab")
		)
		(fp_line
			(start -0.12065 -0.305054)
			(end -0.12065 -0.2794)
			(stroke
				(width 0.1)
				(type default)
			)
			(layer "F.Fab")
		)
		(fp_line
			(start -0.67945 0.3048)
			(end -0.67945 -0.305054)
			(stroke
				(width 0.1)
				(type default)
			)
			(layer "F.Fab")
		)
		(fp_line
			(start -0.67945 -0.305054)
			(end -0.12065 -0.305054)
			(stroke
				(width 0.1)
				(type default)
			)
			(layer "F.Fab")
		)
		(pad "1" smd circle
			(at -0.40005 0 180)
			(size 0 0)
			(layers "F.Cu" "F.Mask" "F.Paste")
			(net "P3V3_AUX")
		)
		(pad "2" smd circle
			(at 0.40005 0 180)
			(size 0 0)
			(layers "F.Cu" "F.Mask" "F.Paste")
			(net "SMB_BIC_I2C9_MUX0_SSD6_R_SDA")
		)
	)
	(footprint ""
		(layer "F.Cu")
		(at 238.324898 -84.351368 90)
		(property "Reference" "R6624"
			(at 0 0 90)
			(layer "F.SilkS")
			(hide yes)
			(effects
				(font
					(size 1.27 1.27)
				)
			)
		)
		(property "Value" ""
			(at 0 0 90)
			(layer "F.Fab")
			(effects
				(font
					(size 1.27 1.27)
				)
			)
		)
		(duplicate_pad_numbers_are_jumpers no)
		(fp_line
			(start 0.7874 -0.4064)
			(end 0.7874 0.4064)
			(stroke
				(width 0.1524)
				(type default)
			)
			(layer "F.SilkS")
		)
		(fp_line
			(start -0.7874 -0.4064)
			(end 0.7874 -0.4064)
			(stroke
				(width 0.1524)
				(type default)
			)
			(layer "F.SilkS")
		)
		(fp_line
			(start -0.018288 0.4064)
			(end -0.7874 0.4064)
			(stroke
				(width 0.1524)
				(type default)
			)
			(layer "F.SilkS")
		)
		(fp_line
			(start -0.12065 -0.305054)
			(end -0.12065 -0.2794)
			(stroke
				(width 0.1)
				(type default)
			)
			(layer "F.Fab")
		)
		(fp_line
			(start -0.67945 -0.305054)
			(end -0.12065 -0.305054)
			(stroke
				(width 0.1)
				(type default)
			)
			(layer "F.Fab")
		)
		(fp_line
			(start 0.67945 -0.3048)
			(end 0.67945 0.3048)
			(stroke
				(width 0.1)
				(type default)
			)
			(layer "F.Fab")
		)
		(fp_line
			(start 0.12065 -0.3048)
			(end 0.67945 -0.3048)
			(stroke
				(width 0.1)
				(type default)
			)
			(layer "F.Fab")
		)
		(fp_line
			(start 0.12065 -0.2794)
			(end 0.12065 -0.3048)
			(stroke
				(width 0.1)
				(type default)
			)
			(layer "F.Fab")
		)
		(fp_line
			(start -0.12065 -0.2794)
			(end 0.12065 -0.2794)
			(stroke
				(width 0.1)
				(type default)
			)
			(layer "F.Fab")
		)
		(fp_line
			(start 0.120396 0.2794)
			(end -0.12065 0.2794)
			(stroke
				(width 0.1)
				(type default)
			)
			(layer "F.Fab")
		)
		(fp_line
			(start -0.12065 0.2794)
			(end -0.12065 0.3048)
			(stroke
				(width 0.1)
				(type default)
			)
			(layer "F.Fab")
		)
		(fp_line
			(start 0.67945 0.3048)
			(end 0.120396 0.3048)
			(stroke
				(width 0.1)
				(type default)
			)
			(layer "F.Fab")
		)
		(fp_line
			(start 0.120396 0.3048)
			(end 0.120396 0.2794)
			(stroke
				(width 0.1)
				(type default)
			)
			(layer "F.Fab")
		)
		(fp_line
			(start -0.12065 0.3048)
			(end -0.67945 0.3048)
			(stroke
				(width 0.1)
				(type default)
			)
			(layer "F.Fab")
		)
		(fp_line
			(start -0.67945 0.3048)
			(end -0.67945 -0.305054)
			(stroke
				(width 0.1)
				(type default)
			)
			(layer "F.Fab")
		)
		(pad "1" smd rect
			(at -0.40005 0 270)
			(size 0.4572 0.508)
			(layers "F.Cu" "F.Mask" "F.Paste")
			(net "USB2_CP2108_CLI_DN")
		)
		(pad "2" smd rect
			(at 0.40005 0 270)
			(size 0.4572 0.508)
			(layers "F.Cu" "F.Mask" "F.Paste")
			(net "USB2_FT4232_CLI_R_DN")
		)
	)
	(footprint ""
		(layer "F.Cu")
		(at 103.376984 -392.15441 90)
		(property "Reference" "U353"
			(at -5.013198 -4.722114 90)
			(unlocked yes)
			(layer "F.SilkS")
			(effects
				(font
					(size 0.7874 0.5842)
					(thickness 0.1524)
				)
				(justify left)
			)
		)
		(property "Value" ""
			(at 0 0 90)
			(layer "F.Fab")
			(effects
				(font
					(size 1.27 1.27)
				)
			)
		)
		(duplicate_pad_numbers_are_jumpers no)
		(fp_line
			(start 0 -2.921)
			(end 0 -3.302)
			(stroke
				(width 0.1524)
				(type default)
			)
			(layer "F.SilkS")
		)
		(fp_line
			(start 2.500122 -2.500122)
			(end 2.500122 -1.778)
			(stroke
				(width 0.1524)
				(type default)
			)
			(layer "F.SilkS")
		)
		(fp_line
			(start 1.778 -2.500122)
			(end 2.500122 -2.500122)
			(stroke
				(width 0.1524)
				(type default)
			)
			(layer "F.SilkS")
		)
		(fp_line
			(start -2.500122 -2.500122)
			(end -1.778 -2.500122)
			(stroke
				(width 0.1524)
				(type default)
			)
			(layer "F.SilkS")
		)
		(fp_line
			(start -2.500122 -1.778)
			(end -2.500122 -2.500122)
			(stroke
				(width 0.1524)
				(type default)
			)
			(layer "F.SilkS")
		)
		(fp_line
			(start 2.921 -1.016)
			(end 3.683 -1.016)
			(stroke
				(width 0.1524)
				(type default)
			)
			(layer "F.SilkS")
		)
		(fp_line
			(start -2.921 0.508)
			(end -3.302 0.508)
			(stroke
				(width 0.1524)
				(type default)
			)
			(layer "F.SilkS")
		)
		(fp_line
			(start 2.921 1.524)
			(end 3.302 1.524)
			(stroke
				(width 0.1524)
				(type default)
			)
			(layer "F.SilkS")
		)
		(fp_line
			(start 2.500122 1.778)
			(end 2.500122 2.500122)
			(stroke
				(width 0.1524)
				(type default)
			)
			(layer "F.SilkS")
		)
		(fp_line
			(start 2.500122 2.500122)
			(end 1.778 2.500122)
			(stroke
				(width 0.1524)
				(type default)
			)
			(layer "F.SilkS")
		)
		(fp_line
			(start -1.778 2.500122)
			(end -2.500122 2.500122)
			(stroke
				(width 0.1524)
				(type default)
			)
			(layer "F.SilkS")
		)
		(fp_line
			(start -2.500122 2.500122)
			(end -2.500122 1.778)
			(stroke
				(width 0.1524)
				(type default)
			)
			(layer "F.SilkS")
		)
		(fp_line
			(start -0.508 2.921)
			(end -0.508 3.683)
			(stroke
				(width 0.1524)
				(type default)
			)
			(layer "F.SilkS")
		)
		(fp_poly
			(pts
				(xy -2.618994 -2.869946) (xy -3.052064 -2.003552) (xy -3.485388 -2.869946)
			)
			(stroke
				(width 0)
				(type default)
			)
			(fill yes)
			(layer "F.SilkS")
		)
		(fp_line
			(start 0 -2.921)
			(end 0 -3.302)
			(stroke
				(width 0.1)
				(type default)
			)
			(layer "F.Fab")
		)
		(fp_line
			(start 2.500122 -2.500122)
			(end 2.500122 2.500122)
			(stroke
				(width 0.1)
				(type default)
			)
			(layer "F.Fab")
		)
		(fp_line
			(start -2.500122 -2.500122)
			(end 2.500122 -2.500122)
			(stroke
				(width 0.1)
				(type default)
			)
			(layer "F.Fab")
		)
		(fp_line
			(start 2.921 -1.016)
			(end 3.683 -1.016)
			(stroke
				(width 0.1)
				(type default)
			)
			(layer "F.Fab")
		)
		(fp_line
			(start -2.921 0.508)
			(end -3.302 0.508)
			(stroke
				(width 0.1)
				(type default)
			)
			(layer "F.Fab")
		)
		(fp_line
			(start 2.921 1.524)
			(end 3.302 1.524)
			(stroke
				(width 0.1)
				(type default)
			)
			(layer "F.Fab")
		)
		(fp_line
			(start 2.500122 2.500122)
			(end -2.500122 2.500122)
			(stroke
				(width 0.1)
				(type default)
			)
			(layer "F.Fab")
		)
		(fp_line
			(start -2.500122 2.500122)
			(end -2.500122 -2.500122)
			(stroke
				(width 0.1)
				(type default)
			)
			(layer "F.Fab")
		)
		(fp_line
			(start -0.508 2.921)
			(end -0.508 3.683)
			(stroke
				(width 0.1)
				(type default)
			)
			(layer "F.Fab")
		)
		(fp_poly
			(pts
				(xy -3.7592 -1.933194) (xy -2.892806 -1.500124) (xy -3.7592 -1.0668)
			)
			(stroke
				(width 0)
				(type default)
			)
			(fill yes)
			(layer "F.Fab")
		)
		(fp_text user "28"
			(at -3.095752 -3.512312 90)
			(unlocked yes)
			(layer "F.SilkS")
			(effects
				(font
					(size 0.635 0.4064)
					(thickness 0.1524)
				)
			)
		)
		(fp_text user "22"
			(at 2.2352 -3.172968 90)
			(unlocked yes)
			(layer "F.SilkS")
			(effects
				(font
					(size 0.635 0.4064)
					(thickness 0.1524)
				)
			)
		)
		(fp_text user "21"
			(at 3.3909 -2.769362 0)
			(unlocked yes)
			(layer "F.SilkS")
			(effects
				(font
					(size 0.635 0.4064)
					(thickness 0.1524)
				)
			)
		)
		(fp_text user "15"
			(at 3.074416 2.158492 0)
			(unlocked yes)
			(layer "F.SilkS")
			(effects
				(font
					(size 0.635 0.4064)
					(thickness 0.1524)
				)
			)
		)
		(fp_text user "7"
			(at -3.162808 2.626868 0)
			(unlocked yes)
			(layer "F.SilkS")
			(effects
				(font
					(size 0.635 0.4064)
					(thickness 0.1524)
				)
			)
		)
		(fp_text user "8"
			(at -2.172462 3.042666 0)
			(unlocked yes)
			(layer "F.SilkS")
			(effects
				(font
					(size 0.635 0.4064)
					(thickness 0.1524)
				)
			)
		)
		(fp_text user "14"
			(at 2.581148 3.24993 0)
			(unlocked yes)
			(layer "F.SilkS")
			(effects
				(font
					(size 0.635 0.4064)
					(thickness 0.1524)
				)
			)
		)
		(fp_text user "22"
			(at 2.2352 -3.172968 90)
			(unlocked yes)
			(layer "F.Fab")
			(effects
				(font
					(size 0.635 0.4064)
					(thickness 0.1524)
				)
			)
		)
		(fp_text user "28"
			(at -2.2098 -3.172968 90)
			(unlocked yes)
			(layer "F.Fab")
			(effects
				(font
					(size 0.635 0.4064)
					(thickness 0.1524)
				)
			)
		)
		(fp_text user "21"
			(at 3.227832 -2.2606 180)
			(unlocked yes)
			(layer "F.Fab")
			(effects
				(font
					(size 0.635 0.4064)
					(thickness 0.1524)
				)
			)
		)
		(fp_text user "7"
			(at -3.147568 1.8034 180)
			(unlocked yes)
			(layer "F.Fab")
			(effects
				(font
					(size 0.635 0.4064)
					(thickness 0.1524)
				)
			)
		)
		(fp_text user "15"
			(at 3.253232 2.2352 180)
			(unlocked yes)
			(layer "F.Fab")
			(effects
				(font
					(size 0.635 0.4064)
					(thickness 0.1524)
				)
			)
		)
		(fp_text user "14"
			(at 2.1336 3.253232 90)
			(unlocked yes)
			(layer "F.Fab")
			(effects
				(font
					(size 0.635 0.4064)
					(thickness 0.1524)
				)
			)
		)
		(fp_text user "8"
			(at -1.8796 3.253232 90)
			(unlocked yes)
			(layer "F.Fab")
			(effects
				(font
					(size 0.635 0.4064)
					(thickness 0.1524)
				)
			)
		)
		(pad "1" smd rect
			(at -2.412492 -1.500124 180)
			(size 0.254 0.7366)
			(layers "F.Cu" "F.Mask" "F.Paste")
			(net "USB2_MB_BMC_R_DN")
		)
		(pad "2" smd rect
			(at -2.412492 -0.999998 180)
			(size 0.254 0.7366)
			(layers "F.Cu" "F.Mask" "F.Paste")
			(net "USB2_MB_BMC_R_DP")
		)
		(pad "3" smd rect
			(at -2.412492 -0.499872 180)
			(size 0.254 0.7366)
			(layers "F.Cu" "F.Mask" "F.Paste")
			(net "USB2_BIC_R_DN")
		)
		(pad "4" smd rect
			(at -2.412492 0 180)
			(size 0.254 0.7366)
			(layers "F.Cu" "F.Mask" "F.Paste")
			(net "USB2_BIC_R_DP")
		)
		(pad "5" smd rect
			(at -2.412492 0.499872 180)
			(size 0.254 0.7366)
			(layers "F.Cu" "F.Mask" "F.Paste")
			(net "P3V3_BIC_USB_HUB")
		)
		(pad "6" smd rect
			(at -2.412492 0.999998 180)
			(size 0.254 0.7366)
			(layers "F.Cu" "F.Mask" "F.Paste")
			(net "USB2_GPU_HMC_R_DN")
		)
		(pad "7" smd rect
			(at -2.412492 1.500124 180)
			(size 0.254 0.7366)
			(layers "F.Cu" "F.Mask" "F.Paste")
			(net "USB2_GPU_HMC_R_DP")
		)
		(pad "8" smd rect
			(at -1.500124 2.412492 90)
			(size 0.254 0.7366)
			(layers "F.Cu" "F.Mask" "F.Paste")
			(net "BIC_USB_HUB_RREF")
		)
		(pad "9" smd rect
			(at -0.999998 2.412492 90)
			(size 0.254 0.7366)
			(layers "F.Cu" "F.Mask" "F.Paste")
			(net "P3V3_BIC_USB_HUB")
		)
		(pad "10" smd rect
			(at -0.499872 2.412492 90)
			(size 0.254 0.7366)
			(layers "F.Cu" "F.Mask" "F.Paste")
			(net "BIC_USB_HUB_XIN")
		)
		(pad "11" smd rect
			(at 0 2.412492 90)
			(size 0.254 0.7366)
			(layers "F.Cu" "F.Mask" "F.Paste")
			(net "BIC_USB_HUB_XOUT")
		)
		(pad "12" smd rect
			(at 0.499872 2.412492 90)
			(size 0.254 0.7366)
			(layers "F.Cu" "F.Mask" "F.Paste")
			(net "Net_9079")
		)
		(pad "13" smd rect
			(at 0.999998 2.412492 90)
			(size 0.254 0.7366)
			(layers "F.Cu" "F.Mask" "F.Paste")
			(net "Net_9077")
		)
		(pad "14" smd rect
			(at 1.500124 2.412492 90)
			(size 0.254 0.7366)
			(layers "F.Cu" "F.Mask" "F.Paste")
			(net "P3V3_BIC_USB_HUB")
		)
		(pad "15" smd rect
			(at 2.412492 1.500124 180)
			(size 0.254 0.7366)
			(layers "F.Cu" "F.Mask" "F.Paste")
			(net "Net_9078")
		)
		(pad "16" smd rect
			(at 2.412492 0.999998 180)
			(size 0.254 0.7366)
			(layers "F.Cu" "F.Mask" "F.Paste")
			(net "Net_9076")
		)
		(pad "17" smd rect
			(at 2.412492 0.499872 180)
			(size 0.254 0.7366)
			(layers "F.Cu" "F.Mask" "F.Paste")
			(net "RST_BIC_USB_HUB_R1_N")
		)
		(pad "18" smd rect
			(at 2.412492 0 180)
			(size 0.254 0.7366)
			(layers "F.Cu" "F.Mask" "F.Paste")
			(net "BIC_USB_HUB_TEST")
		)
		(pad "19" smd rect
			(at 2.412492 -0.499872 180)
			(size 0.254 0.7366)
			(layers "F.Cu" "F.Mask" "F.Paste")
			(net "BIC_USB_HUB_OVCUR4")
		)
		(pad "20" smd rect
			(at 2.412492 -0.999998 180)
			(size 0.254 0.7366)
			(layers "F.Cu" "F.Mask" "F.Paste")
			(net "BIC_USB_HUB_OVCUR3")
		)
		(pad "21" smd rect
			(at 2.412492 -1.500124 180)
			(size 0.254 0.7366)
			(layers "F.Cu" "F.Mask" "F.Paste")
			(net "P3V3_BIC_USB_HUB")
		)
		(pad "22" smd rect
			(at 1.500124 -2.412492 90)
			(size 0.254 0.7366)
			(layers "F.Cu" "F.Mask" "F.Paste")
			(net "BIC_USB_HUB_PSELF")
		)
		(pad "23" smd rect
			(at 0.999998 -2.412492 90)
			(size 0.254 0.7366)
			(layers "F.Cu" "F.Mask" "F.Paste")
			(net "BIC_USB_HUB_PGANG")
		)
		(pad "24" smd rect
			(at 0.499872 -2.412492 90)
			(size 0.254 0.7366)
			(layers "F.Cu" "F.Mask" "F.Paste")
			(net "BIC_USB_HUB_OVCUR2")
		)
		(pad "25" smd rect
			(at 0 -2.412492 90)
			(size 0.254 0.7366)
			(layers "F.Cu" "F.Mask" "F.Paste")
			(net "BIC_USB_HUB_OVCUR1")
		)
		(pad "26" smd rect
			(at -0.499872 -2.412492 90)
			(size 0.254 0.7366)
			(layers "F.Cu" "F.Mask" "F.Paste")
			(net "Net_9075")
		)
		(pad "27" smd rect
			(at -0.999998 -2.412492 90)
			(size 0.254 0.7366)
			(layers "F.Cu" "F.Mask" "F.Paste")
			(net "P3V3_BIC_USB_HUB")
		)
		(pad "28" smd rect
			(at -1.500124 -2.412492 90)
			(size 0.254 0.7366)
			(layers "F.Cu" "F.Mask" "F.Paste")
			(net "P3V3_BIC_USB_HUB")
		)
		(pad "TH" smd rect
			(at 0 0 90)
			(size 3.556 3.556)
			(layers "F.Cu" "F.Mask" "F.Paste")
			(net "GND")
		)
		(zone
			(layer "F.Cu")
			(hatch none 0.5)
			(connect_pads
				(clearance 0)
			)
			(min_thickness 0.25)
			(keepout
				(tracks not_allowed)
				(vias allowed)
				(pads allowed)
				(copperpour not_allowed)
				(footprints allowed)
			)
			(placement
				(enabled no)
				(sheetname "")
			)
			(fill
				(thermal_gap 0.5)
				(thermal_bridge_width 0.5)
				(island_removal_mode 0)
			)
			(polygon
				(pts
					(xy 101.395784 -393.09421) (xy 101.548184 -393.09421) (xy 101.548184 -390.32561) (xy 105.205784 -390.32561)
					(xy 105.205784 -393.98321) (xy 101.548184 -393.98321) (xy 101.548184 -393.11961) (xy 101.395784 -393.11961)
					(xy 101.395784 -394.13561) (xy 105.358184 -394.13561) (xy 105.358184 -390.17321) (xy 101.395784 -390.17321)
				)
			)
		)
	)
	(footprint ""
		(layer "F.Cu")
		(at 370.571776 -152.71115 90)
		(property "Reference" "R747"
			(at 0 0 90)
			(layer "F.SilkS")
			(hide yes)
			(effects
				(font
					(size 1.27 1.27)
				)
			)
		)
		(property "Value" ""
			(at 0 0 90)
			(layer "F.Fab")
			(effects
				(font
					(size 1.27 1.27)
				)
			)
		)
		(duplicate_pad_numbers_are_jumpers no)
		(fp_line
			(start 0.7874 -0.4064)
			(end 0.7874 0.4064)
			(stroke
				(width 0.1524)
				(type default)
			)
			(layer "F.SilkS")
		)
		(fp_line
			(start -0.7874 -0.4064)
			(end 0.7874 -0.4064)
			(stroke
				(width 0.1524)
				(type default)
			)
			(layer "F.SilkS")
		)
		(fp_line
			(start 0.7874 0.4064)
			(end -0.7874 0.4064)
			(stroke
				(width 0.1524)
				(type default)
			)
			(layer "F.SilkS")
		)
		(fp_line
			(start -0.7874 0.4064)
			(end -0.7874 -0.4064)
			(stroke
				(width 0.1524)
				(type default)
			)
			(layer "F.SilkS")
		)
		(fp_line
			(start -0.12065 -0.305054)
			(end -0.12065 -0.2794)
			(stroke
				(width 0.1)
				(type default)
			)
			(layer "F.Fab")
		)
		(fp_line
			(start -0.67945 -0.305054)
			(end -0.12065 -0.305054)
			(stroke
				(width 0.1)
				(type default)
			)
			(layer "F.Fab")
		)
		(fp_line
			(start 0.67945 -0.3048)
			(end 0.67945 0.3048)
			(stroke
				(width 0.1)
				(type default)
			)
			(layer "F.Fab")
		)
		(fp_line
			(start 0.12065 -0.3048)
			(end 0.67945 -0.3048)
			(stroke
				(width 0.1)
				(type default)
			)
			(layer "F.Fab")
		)
		(fp_line
			(start 0.12065 -0.2794)
			(end 0.12065 -0.3048)
			(stroke
				(width 0.1)
				(type default)
			)
			(layer "F.Fab")
		)
		(fp_line
			(start -0.12065 -0.2794)
			(end 0.12065 -0.2794)
			(stroke
				(width 0.1)
				(type default)
			)
			(layer "F.Fab")
		)
		(fp_line
			(start 0.120396 0.2794)
			(end -0.12065 0.2794)
			(stroke
				(width 0.1)
				(type default)
			)
			(layer "F.Fab")
		)
		(fp_line
			(start -0.12065 0.2794)
			(end -0.12065 0.3048)
			(stroke
				(width 0.1)
				(type default)
			)
			(layer "F.Fab")
		)
		(fp_line
			(start 0.67945 0.3048)
			(end 0.120396 0.3048)
			(stroke
				(width 0.1)
				(type default)
			)
			(layer "F.Fab")
		)
		(fp_line
			(start 0.120396 0.3048)
			(end 0.120396 0.2794)
			(stroke
				(width 0.1)
				(type default)
			)
			(layer "F.Fab")
		)
		(fp_line
			(start -0.12065 0.3048)
			(end -0.67945 0.3048)
			(stroke
				(width 0.1)
				(type default)
			)
			(layer "F.Fab")
		)
		(fp_line
			(start -0.67945 0.3048)
			(end -0.67945 -0.305054)
			(stroke
				(width 0.1)
				(type default)
			)
			(layer "F.Fab")
		)
		(pad "1" smd circle
			(at -0.40005 0 90)
			(size 0 0)
			(layers "F.Cu" "F.Mask" "F.Paste")
			(net "NIC6_ADC_A1")
		)
		(pad "2" smd circle
			(at 0.40005 0 90)
			(size 0 0)
			(layers "F.Cu" "F.Mask" "F.Paste")
			(net "P3V3_AUX")
		)
	)
	(footprint ""
		(layer "F.Cu")
		(at 338.074 -164.973 180)
		(property "Reference" "R4774"
			(at 0 0 180)
			(layer "F.SilkS")
			(hide yes)
			(effects
				(font
					(size 1.27 1.27)
				)
			)
		)
		(property "Value" ""
			(at 0 0 180)
			(layer "F.Fab")
			(effects
				(font
					(size 1.27 1.27)
				)
			)
		)
		(duplicate_pad_numbers_are_jumpers no)
		(fp_line
			(start 0.7874 0.4064)
			(end -0.7874 0.4064)
			(stroke
				(width 0.1524)
				(type default)
			)
			(layer "F.SilkS")
		)
		(fp_line
			(start 0.7874 -0.4064)
			(end 0.7874 0.4064)
			(stroke
				(width 0.1524)
				(type default)
			)
			(layer "F.SilkS")
		)
		(fp_line
			(start -0.7874 0.4064)
			(end -0.7874 -0.4064)
			(stroke
				(width 0.1524)
				(type default)
			)
			(layer "F.SilkS")
		)
		(fp_line
			(start -0.7874 -0.4064)
			(end 0.7874 -0.4064)
			(stroke
				(width 0.1524)
				(type default)
			)
			(layer "F.SilkS")
		)
		(fp_line
			(start 0.67945 0.3048)
			(end 0.120396 0.3048)
			(stroke
				(width 0.1)
				(type default)
			)
			(layer "F.Fab")
		)
		(fp_line
			(start 0.67945 -0.3048)
			(end 0.67945 0.3048)
			(stroke
				(width 0.1)
				(type default)
			)
			(layer "F.Fab")
		)
		(fp_line
			(start 0.12065 -0.2794)
			(end 0.12065 -0.3048)
			(stroke
				(width 0.1)
				(type default)
			)
			(layer "F.Fab")
		)
		(fp_line
			(start 0.12065 -0.3048)
			(end 0.67945 -0.3048)
			(stroke
				(width 0.1)
				(type default)
			)
			(layer "F.Fab")
		)
		(fp_line
			(start 0.120396 0.3048)
			(end 0.120396 0.2794)
			(stroke
				(width 0.1)
				(type default)
			)
			(layer "F.Fab")
		)
		(fp_line
			(start 0.120396 0.2794)
			(end -0.12065 0.2794)
			(stroke
				(width 0.1)
				(type default)
			)
			(layer "F.Fab")
		)
		(fp_line
			(start -0.12065 0.3048)
			(end -0.67945 0.3048)
			(stroke
				(width 0.1)
				(type default)
			)
			(layer "F.Fab")
		)
		(fp_line
			(start -0.12065 0.2794)
			(end -0.12065 0.3048)
			(stroke
				(width 0.1)
				(type default)
			)
			(layer "F.Fab")
		)
		(fp_line
			(start -0.12065 -0.2794)
			(end 0.12065 -0.2794)
			(stroke
				(width 0.1)
				(type default)
			)
			(layer "F.Fab")
		)
		(fp_line
			(start -0.12065 -0.305054)
			(end -0.12065 -0.2794)
			(stroke
				(width 0.1)
				(type default)
			)
			(layer "F.Fab")
		)
		(fp_line
			(start -0.67945 0.3048)
			(end -0.67945 -0.305054)
			(stroke
				(width 0.1)
				(type default)
			)
			(layer "F.Fab")
		)
		(fp_line
			(start -0.67945 -0.305054)
			(end -0.12065 -0.305054)
			(stroke
				(width 0.1)
				(type default)
			)
			(layer "F.Fab")
		)
		(pad "1" smd circle
			(at -0.40005 0 180)
			(size 0 0)
			(layers "F.Cu" "F.Mask" "F.Paste")
			(net "RST_PEX_SSD11_PERST_N")
		)
		(pad "2" smd circle
			(at 0.40005 0 180)
			(size 0 0)
			(layers "F.Cu" "F.Mask" "F.Paste")
			(net "RST_PEX_SSD11_PERST_R_N")
		)
	)
	(footprint ""
		(layer "F.Cu")
		(at 32.890968 -55.663846 90)
		(property "Reference" "PU56"
			(at -1.414018 3.158998 90)
			(unlocked yes)
			(layer "F.SilkS")
			(effects
				(font
					(size 0.7874 0.5842)
					(thickness 0.1524)
				)
				(justify left)
			)
		)
		(property "Value" ""
			(at 0 0 90)
			(layer "F.Fab")
			(effects
				(font
					(size 1.27 1.27)
				)
			)
		)
		(duplicate_pad_numbers_are_jumpers no)
		(fp_line
			(start 1.943608 -1.549908)
			(end 1.943608 1.549908)
			(stroke
				(width 0.1524)
				(type default)
			)
			(layer "F.SilkS")
		)
		(fp_line
			(start -1.943608 -1.549908)
			(end 1.943608 -1.549908)
			(stroke
				(width 0.1524)
				(type default)
			)
			(layer "F.SilkS")
		)
		(fp_line
			(start 1.943608 1.549908)
			(end -1.943608 1.549908)
			(stroke
				(width 0.1524)
				(type default)
			)
			(layer "F.SilkS")
		)
		(fp_line
			(start -1.943608 1.549908)
			(end -1.943608 -1.549908)
			(stroke
				(width 0.1524)
				(type default)
			)
			(layer "F.SilkS")
		)
		(fp_poly
			(pts
				(xy -2.019808 -1.549908) (xy -1.257808 -1.549908) (xy -1.257808 -1.880108) (xy -2.019808 -1.880108)
			)
			(stroke
				(width 0)
				(type default)
			)
			(fill yes)
			(layer "F.SilkS")
		)
		(fp_line
			(start 1.549908 -1.549908)
			(end 1.549908 1.549908)
			(stroke
				(width 0.1)
				(type default)
			)
			(layer "F.Fab")
		)
		(fp_line
			(start -1.549908 -1.549908)
			(end 1.549908 -1.549908)
			(stroke
				(width 0.1)
				(type default)
			)
			(layer "F.Fab")
		)
		(fp_line
			(start 1.549908 1.549908)
			(end -1.549908 1.549908)
			(stroke
				(width 0.1)
				(type default)
			)
			(layer "F.Fab")
		)
		(fp_line
			(start -1.549908 1.549908)
			(end -1.549908 -1.549908)
			(stroke
				(width 0.1)
				(type default)
			)
			(layer "F.Fab")
		)
		(fp_poly
			(pts
				(xy -2.019808 -1.549908) (xy -1.257808 -1.549908) (xy -1.257808 -1.880108) (xy -2.019808 -1.880108)
			)
			(stroke
				(width 0)
				(type default)
			)
			(fill yes)
			(layer "F.Fab")
		)
		(pad "1" smd rect
			(at -1.500124 -1.249934)
			(size 0.2794 0.6096)
			(layers "F.Cu" "F.Mask" "F.Paste")
			(net "P3V3_SSD1")
		)
		(pad "2" smd rect
			(at -1.500124 -0.750062)
			(size 0.2794 0.6096)
			(layers "F.Cu" "F.Mask" "F.Paste")
			(net "P3V3_SSD1")
		)
		(pad "3" smd rect
			(at -1.500124 -0.249936)
			(size 0.2794 0.6096)
			(layers "F.Cu" "F.Mask" "F.Paste")
			(net "P3V3_SSD1")
		)
		(pad "4" smd rect
			(at -1.500124 0.249936)
			(size 0.2794 0.6096)
			(layers "F.Cu" "F.Mask" "F.Paste")
			(net "P3V3_SSD1")
		)
		(pad "5" smd rect
			(at -1.500124 0.750062)
			(size 0.2794 0.6096)
			(layers "F.Cu" "F.Mask" "F.Paste")
			(net "P3V3_SSD1")
		)
		(pad "6" smd rect
			(at -1.500124 1.249934)
			(size 0.2794 0.6096)
			(layers "F.Cu" "F.Mask" "F.Paste")
			(net "GND")
		)
		(pad "7" smd rect
			(at 1.500124 1.249934)
			(size 0.2794 0.6096)
			(layers "F.Cu" "F.Mask" "F.Paste")
			(net "P3V3_SSD1_SS")
		)
		(pad "8" smd rect
			(at 1.500124 0.750062)
			(size 0.2794 0.6096)
			(layers "F.Cu" "F.Mask" "F.Paste")
			(net "PWRGD_P3V3_SSD1")
		)
		(pad "9" smd rect
			(at 1.500124 0.249936)
			(size 0.2794 0.6096)
			(layers "F.Cu" "F.Mask" "F.Paste")
			(net "P3V3_SSD1_OCP")
		)
		(pad "10" smd rect
			(at 1.500124 -0.249936)
			(size 0.2794 0.6096)
			(layers "F.Cu" "F.Mask" "F.Paste")
			(net "P5V_AUX")
		)
		(pad "11" smd rect
			(at 1.500124 -0.750062)
			(size 0.2794 0.6096)
			(layers "F.Cu" "F.Mask" "F.Paste")
			(net "SSD1_AUX_P3V3_EN_R")
		)
		(pad "12" smd rect
			(at 1.500124 -1.249934)
			(size 0.2794 0.6096)
			(layers "F.Cu" "F.Mask" "F.Paste")
			(net "P3V3_AUX")
		)
		(pad "13" smd rect
			(at 0 0 90)
			(size 1.9812 2.7178)
			(layers "F.Cu" "F.Mask" "F.Paste")
			(net "P3V3_AUX")
		)
		(zone
			(layer "F.Cu")
			(hatch none 0.5)
			(connect_pads
				(clearance 0)
			)
			(min_thickness 0.25)
			(keepout
				(tracks not_allowed)
				(vias allowed)
				(pads allowed)
				(copperpour not_allowed)
				(footprints allowed)
			)
			(placement
				(enabled no)
				(sheetname "")
			)
			(fill
				(thermal_gap 0.5)
				(thermal_bridge_width 0.5)
				(island_removal_mode 0)
			)
			(polygon
				(pts
					(xy 31.341568 -56.806846) (xy 31.468568 -56.806846) (xy 34.440368 -56.806846) (xy 34.440876 -56.806846)
					(xy 34.440876 -54.520846) (xy 34.440368 -54.520846) (xy 34.313368 -54.520846) (xy 32.890968 -54.520846)
					(xy 32.890968 -54.622446) (xy 34.313368 -54.622446) (xy 34.313368 -56.705246) (xy 31.468568 -56.705246)
					(xy 31.468568 -54.622446) (xy 32.865568 -54.622446) (xy 32.865568 -54.520846) (xy 31.468568 -54.520846)
					(xy 31.341568 -54.520846) (xy 31.34106 -54.520846) (xy 31.34106 -56.806846)
				)
			)
		)
	)
	(footprint ""
		(layer "F.Cu")
		(at 420.73449 -30.03169 180)
		(property "Reference" "C719"
			(at 0 0 180)
			(layer "F.SilkS")
			(hide yes)
			(effects
				(font
					(size 1.27 1.27)
				)
			)
		)
		(property "Value" ""
			(at 0 0 180)
			(layer "F.Fab")
			(effects
				(font
					(size 1.27 1.27)
				)
			)
		)
		(duplicate_pad_numbers_are_jumpers no)
		(fp_line
			(start 0.299974 0.150114)
			(end -0.299974 0.150114)
			(stroke
				(width 0.1)
				(type default)
			)
			(layer "F.Fab")
		)
		(fp_line
			(start 0.299974 -0.150114)
			(end 0.299974 0.150114)
			(stroke
				(width 0.1)
				(type default)
			)
			(layer "F.Fab")
		)
		(fp_line
			(start -0.299974 0.150114)
			(end -0.299974 -0.150114)
			(stroke
				(width 0.1)
				(type default)
			)
			(layer "F.Fab")
		)
		(fp_line
			(start -0.299974 -0.150114)
			(end 0.299974 -0.150114)
			(stroke
				(width 0.1)
				(type default)
			)
			(layer "F.Fab")
		)
		(pad "1" smd rect
			(at -0.2667 0 180)
			(size 0.3048 0.381)
			(layers "F.Cu" "F.Mask" "F.Paste")
			(net "P5E_PEX3_STN2_TX_DN<37>")
		)
		(pad "2" smd rect
			(at 0.2667 0 180)
			(size 0.3048 0.381)
			(layers "F.Cu" "F.Mask" "F.Paste")
			(net "P5E_PEX3_STN2_TX_C_DN<37>")
		)
	)
	(footprint ""
		(layer "F.Cu")
		(at 234.949746 -120.381268 90)
		(property "Reference" "R5833"
			(at 0 0 90)
			(layer "F.SilkS")
			(hide yes)
			(effects
				(font
					(size 1.27 1.27)
				)
			)
		)
		(property "Value" ""
			(at 0 0 90)
			(layer "F.Fab")
			(effects
				(font
					(size 1.27 1.27)
				)
			)
		)
		(duplicate_pad_numbers_are_jumpers no)
		(fp_line
			(start 0.7874 -0.4064)
			(end 0.7874 0.4064)
			(stroke
				(width 0.1524)
				(type default)
			)
			(layer "F.SilkS")
		)
		(fp_line
			(start -0.7874 -0.4064)
			(end 0.7874 -0.4064)
			(stroke
				(width 0.1524)
				(type default)
			)
			(layer "F.SilkS")
		)
		(fp_line
			(start 0.7874 0.4064)
			(end -0.7874 0.4064)
			(stroke
				(width 0.1524)
				(type default)
			)
			(layer "F.SilkS")
		)
		(fp_line
			(start -0.7874 0.4064)
			(end -0.7874 -0.4064)
			(stroke
				(width 0.1524)
				(type default)
			)
			(layer "F.SilkS")
		)
		(fp_line
			(start -0.12065 -0.305054)
			(end -0.12065 -0.2794)
			(stroke
				(width 0.1)
				(type default)
			)
			(layer "F.Fab")
		)
		(fp_line
			(start -0.67945 -0.305054)
			(end -0.12065 -0.305054)
			(stroke
				(width 0.1)
				(type default)
			)
			(layer "F.Fab")
		)
		(fp_line
			(start 0.67945 -0.3048)
			(end 0.67945 0.3048)
			(stroke
				(width 0.1)
				(type default)
			)
			(layer "F.Fab")
		)
		(fp_line
			(start 0.12065 -0.3048)
			(end 0.67945 -0.3048)
			(stroke
				(width 0.1)
				(type default)
			)
			(layer "F.Fab")
		)
		(fp_line
			(start 0.12065 -0.2794)
			(end 0.12065 -0.3048)
			(stroke
				(width 0.1)
				(type default)
			)
			(layer "F.Fab")
		)
		(fp_line
			(start -0.12065 -0.2794)
			(end 0.12065 -0.2794)
			(stroke
				(width 0.1)
				(type default)
			)
			(layer "F.Fab")
		)
		(fp_line
			(start 0.120396 0.2794)
			(end -0.12065 0.2794)
			(stroke
				(width 0.1)
				(type default)
			)
			(layer "F.Fab")
		)
		(fp_line
			(start -0.12065 0.2794)
			(end -0.12065 0.3048)
			(stroke
				(width 0.1)
				(type default)
			)
			(layer "F.Fab")
		)
		(fp_line
			(start 0.67945 0.3048)
			(end 0.120396 0.3048)
			(stroke
				(width 0.1)
				(type default)
			)
			(layer "F.Fab")
		)
		(fp_line
			(start 0.120396 0.3048)
			(end 0.120396 0.2794)
			(stroke
				(width 0.1)
				(type default)
			)
			(layer "F.Fab")
		)
		(fp_line
			(start -0.12065 0.3048)
			(end -0.67945 0.3048)
			(stroke
				(width 0.1)
				(type default)
			)
			(layer "F.Fab")
		)
		(fp_line
			(start -0.67945 0.3048)
			(end -0.67945 -0.305054)
			(stroke
				(width 0.1)
				(type default)
			)
			(layer "F.Fab")
		)
		(pad "1" smd circle
			(at -0.40005 0 90)
			(size 0 0)
			(layers "F.Cu" "F.Mask" "F.Paste")
			(net "PWRGD_P12V_NIC3_CO")
		)
		(pad "2" smd circle
			(at 0.40005 0 90)
			(size 0 0)
			(layers "F.Cu" "F.Mask" "F.Paste")
			(net "PWRGD_P12V_NIC3_R")
		)
	)
	(footprint ""
		(layer "F.Cu")
		(at 212.047074 -55.63489 90)
		(property "Reference" "PC856"
			(at 0 0 90)
			(layer "F.SilkS")
			(hide yes)
			(effects
				(font
					(size 1.27 1.27)
				)
			)
		)
		(property "Value" ""
			(at 0 0 90)
			(layer "F.Fab")
			(effects
				(font
					(size 1.27 1.27)
				)
			)
		)
		(duplicate_pad_numbers_are_jumpers no)
		(fp_line
			(start 1.524 -0.762)
			(end 1.524 0.762)
			(stroke
				(width 0.1524)
				(type default)
			)
			(layer "F.SilkS")
		)
		(fp_line
			(start -1.524 -0.762)
			(end 1.524 -0.762)
			(stroke
				(width 0.1524)
				(type default)
			)
			(layer "F.SilkS")
		)
		(fp_line
			(start 1.524 0.762)
			(end -1.524 0.762)
			(stroke
				(width 0.1524)
				(type default)
			)
			(layer "F.SilkS")
		)
		(fp_line
			(start -1.524 0.762)
			(end -1.524 -0.762)
			(stroke
				(width 0.1524)
				(type default)
			)
			(layer "F.SilkS")
		)
		(fp_line
			(start 1.1049 -0.724916)
			(end -1.1049 -0.724916)
			(stroke
				(width 0.1)
				(type default)
			)
			(layer "F.Fab")
		)
		(fp_line
			(start -1.1049 -0.724916)
			(end -1.1049 0.724916)
			(stroke
				(width 0.1)
				(type default)
			)
			(layer "F.Fab")
		)
		(fp_line
			(start 1.1049 0.724916)
			(end 1.1049 -0.724916)
			(stroke
				(width 0.1)
				(type default)
			)
			(layer "F.Fab")
		)
		(fp_line
			(start -1.1049 0.724916)
			(end 1.1049 0.724916)
			(stroke
				(width 0.1)
				(type default)
			)
			(layer "F.Fab")
		)
		(pad "1" smd rect
			(at -0.889 0 270)
			(size 1.016 1.27)
			(layers "F.Cu" "F.Mask" "F.Paste")
			(net "P12V_SSD7_R")
		)
		(pad "2" smd rect
			(at 0.889 0 270)
			(size 1.016 1.27)
			(layers "F.Cu" "F.Mask" "F.Paste")
			(net "GND")
		)
	)
	(footprint ""
		(layer "F.Cu")
		(at 38.608 -162.044126 180)
		(property "Reference" "R22"
			(at 0 0 180)
			(layer "F.SilkS")
			(hide yes)
			(effects
				(font
					(size 1.27 1.27)
				)
			)
		)
		(property "Value" ""
			(at 0 0 180)
			(layer "F.Fab")
			(effects
				(font
					(size 1.27 1.27)
				)
			)
		)
		(duplicate_pad_numbers_are_jumpers no)
		(fp_line
			(start 0.7874 0.4064)
			(end -0.7874 0.4064)
			(stroke
				(width 0.1524)
				(type default)
			)
			(layer "F.SilkS")
		)
		(fp_line
			(start 0.7874 -0.4064)
			(end 0.7874 0.4064)
			(stroke
				(width 0.1524)
				(type default)
			)
			(layer "F.SilkS")
		)
		(fp_line
			(start -0.7874 0.4064)
			(end -0.7874 -0.4064)
			(stroke
				(width 0.1524)
				(type default)
			)
			(layer "F.SilkS")
		)
		(fp_line
			(start -0.7874 -0.4064)
			(end 0.7874 -0.4064)
			(stroke
				(width 0.1524)
				(type default)
			)
			(layer "F.SilkS")
		)
		(fp_line
			(start 0.67945 0.3048)
			(end 0.120396 0.3048)
			(stroke
				(width 0.1)
				(type default)
			)
			(layer "F.Fab")
		)
		(fp_line
			(start 0.67945 -0.3048)
			(end 0.67945 0.3048)
			(stroke
				(width 0.1)
				(type default)
			)
			(layer "F.Fab")
		)
		(fp_line
			(start 0.12065 -0.2794)
			(end 0.12065 -0.3048)
			(stroke
				(width 0.1)
				(type default)
			)
			(layer "F.Fab")
		)
		(fp_line
			(start 0.12065 -0.3048)
			(end 0.67945 -0.3048)
			(stroke
				(width 0.1)
				(type default)
			)
			(layer "F.Fab")
		)
		(fp_line
			(start 0.120396 0.3048)
			(end 0.120396 0.2794)
			(stroke
				(width 0.1)
				(type default)
			)
			(layer "F.Fab")
		)
		(fp_line
			(start 0.120396 0.2794)
			(end -0.12065 0.2794)
			(stroke
				(width 0.1)
				(type default)
			)
			(layer "F.Fab")
		)
		(fp_line
			(start -0.12065 0.3048)
			(end -0.67945 0.3048)
			(stroke
				(width 0.1)
				(type default)
			)
			(layer "F.Fab")
		)
		(fp_line
			(start -0.12065 0.2794)
			(end -0.12065 0.3048)
			(stroke
				(width 0.1)
				(type default)
			)
			(layer "F.Fab")
		)
		(fp_line
			(start -0.12065 -0.2794)
			(end 0.12065 -0.2794)
			(stroke
				(width 0.1)
				(type default)
			)
			(layer "F.Fab")
		)
		(fp_line
			(start -0.12065 -0.305054)
			(end -0.12065 -0.2794)
			(stroke
				(width 0.1)
				(type default)
			)
			(layer "F.Fab")
		)
		(fp_line
			(start -0.67945 0.3048)
			(end -0.67945 -0.305054)
			(stroke
				(width 0.1)
				(type default)
			)
			(layer "F.Fab")
		)
		(fp_line
			(start -0.67945 -0.305054)
			(end -0.12065 -0.305054)
			(stroke
				(width 0.1)
				(type default)
			)
			(layer "F.Fab")
		)
		(pad "1" smd circle
			(at -0.40005 0 180)
			(size 0 0)
			(layers "F.Cu" "F.Mask" "F.Paste")
			(net "PWRGD_NIC0_PWR_GOOD")
		)
		(pad "2" smd circle
			(at 0.40005 0 180)
			(size 0 0)
			(layers "F.Cu" "F.Mask" "F.Paste")
			(net "GND")
		)
	)
	(footprint ""
		(layer "F.Cu")
		(at 452.543672 -43.85691)
		(property "Reference" "R673"
			(at 0 0 0)
			(layer "F.SilkS")
			(hide yes)
			(effects
				(font
					(size 1.27 1.27)
				)
			)
		)
		(property "Value" ""
			(at 0 0 0)
			(layer "F.Fab")
			(effects
				(font
					(size 1.27 1.27)
				)
			)
		)
		(duplicate_pad_numbers_are_jumpers no)
		(fp_line
			(start -0.7874 -0.4064)
			(end 0.7874 -0.4064)
			(stroke
				(width 0.1524)
				(type default)
			)
			(layer "F.SilkS")
		)
		(fp_line
			(start -0.7874 0.4064)
			(end -0.7874 -0.4064)
			(stroke
				(width 0.1524)
				(type default)
			)
			(layer "F.SilkS")
		)
		(fp_line
			(start 0.7874 -0.4064)
			(end 0.7874 0.4064)
			(stroke
				(width 0.1524)
				(type default)
			)
			(layer "F.SilkS")
		)
		(fp_line
			(start 0.7874 0.4064)
			(end -0.7874 0.4064)
			(stroke
				(width 0.1524)
				(type default)
			)
			(layer "F.SilkS")
		)
		(fp_line
			(start -0.67945 -0.305054)
			(end -0.12065 -0.305054)
			(stroke
				(width 0.1)
				(type default)
			)
			(layer "F.Fab")
		)
		(fp_line
			(start -0.67945 0.3048)
			(end -0.67945 -0.305054)
			(stroke
				(width 0.1)
				(type default)
			)
			(layer "F.Fab")
		)
		(fp_line
			(start -0.12065 -0.305054)
			(end -0.12065 -0.2794)
			(stroke
				(width 0.1)
				(type default)
			)
			(layer "F.Fab")
		)
		(fp_line
			(start -0.12065 -0.2794)
			(end 0.12065 -0.2794)
			(stroke
				(width 0.1)
				(type default)
			)
			(layer "F.Fab")
		)
		(fp_line
			(start -0.12065 0.2794)
			(end -0.12065 0.3048)
			(stroke
				(width 0.1)
				(type default)
			)
			(layer "F.Fab")
		)
		(fp_line
			(start -0.12065 0.3048)
			(end -0.67945 0.3048)
			(stroke
				(width 0.1)
				(type default)
			)
			(layer "F.Fab")
		)
		(fp_line
			(start 0.120396 0.2794)
			(end -0.12065 0.2794)
			(stroke
				(width 0.1)
				(type default)
			)
			(layer "F.Fab")
		)
		(fp_line
			(start 0.120396 0.3048)
			(end 0.120396 0.2794)
			(stroke
				(width 0.1)
				(type default)
			)
			(layer "F.Fab")
		)
		(fp_line
			(start 0.12065 -0.3048)
			(end 0.67945 -0.3048)
			(stroke
				(width 0.1)
				(type default)
			)
			(layer "F.Fab")
		)
		(fp_line
			(start 0.12065 -0.2794)
			(end 0.12065 -0.3048)
			(stroke
				(width 0.1)
				(type default)
			)
			(layer "F.Fab")
		)
		(fp_line
			(start 0.67945 -0.3048)
			(end 0.67945 0.3048)
			(stroke
				(width 0.1)
				(type default)
			)
			(layer "F.Fab")
		)
		(fp_line
			(start 0.67945 0.3048)
			(end 0.120396 0.3048)
			(stroke
				(width 0.1)
				(type default)
			)
			(layer "F.Fab")
		)
		(pad "1" smd circle
			(at -0.40005 0)
			(size 0 0)
			(layers "F.Cu" "F.Mask" "F.Paste")
			(net "SSD15_ADC_A1")
		)
		(pad "2" smd circle
			(at 0.40005 0)
			(size 0 0)
			(layers "F.Cu" "F.Mask" "F.Paste")
			(net "GND")
		)
	)
	(footprint ""
		(layer "F.Cu")
		(at 259.951474 -260.840982)
		(property "Reference" "R4587"
			(at 0 0 0)
			(layer "F.SilkS")
			(hide yes)
			(effects
				(font
					(size 1.27 1.27)
				)
			)
		)
		(property "Value" ""
			(at 0 0 0)
			(layer "F.Fab")
			(effects
				(font
					(size 1.27 1.27)
				)
			)
		)
		(duplicate_pad_numbers_are_jumpers no)
		(fp_line
			(start -0.7874 -0.4064)
			(end 0.7874 -0.4064)
			(stroke
				(width 0.1524)
				(type default)
			)
			(layer "F.SilkS")
		)
		(fp_line
			(start -0.7874 0.4064)
			(end -0.7874 -0.4064)
			(stroke
				(width 0.1524)
				(type default)
			)
			(layer "F.SilkS")
		)
		(fp_line
			(start 0.7874 -0.4064)
			(end 0.7874 0.4064)
			(stroke
				(width 0.1524)
				(type default)
			)
			(layer "F.SilkS")
		)
		(fp_line
			(start 0.7874 0.4064)
			(end -0.7874 0.4064)
			(stroke
				(width 0.1524)
				(type default)
			)
			(layer "F.SilkS")
		)
		(fp_line
			(start -0.67945 -0.305054)
			(end -0.12065 -0.305054)
			(stroke
				(width 0.1)
				(type default)
			)
			(layer "F.Fab")
		)
		(fp_line
			(start -0.67945 0.3048)
			(end -0.67945 -0.305054)
			(stroke
				(width 0.1)
				(type default)
			)
			(layer "F.Fab")
		)
		(fp_line
			(start -0.12065 -0.305054)
			(end -0.12065 -0.2794)
			(stroke
				(width 0.1)
				(type default)
			)
			(layer "F.Fab")
		)
		(fp_line
			(start -0.12065 -0.2794)
			(end 0.12065 -0.2794)
			(stroke
				(width 0.1)
				(type default)
			)
			(layer "F.Fab")
		)
		(fp_line
			(start -0.12065 0.2794)
			(end -0.12065 0.3048)
			(stroke
				(width 0.1)
				(type default)
			)
			(layer "F.Fab")
		)
		(fp_line
			(start -0.12065 0.3048)
			(end -0.67945 0.3048)
			(stroke
				(width 0.1)
				(type default)
			)
			(layer "F.Fab")
		)
		(fp_line
			(start 0.120396 0.2794)
			(end -0.12065 0.2794)
			(stroke
				(width 0.1)
				(type default)
			)
			(layer "F.Fab")
		)
		(fp_line
			(start 0.120396 0.3048)
			(end 0.120396 0.2794)
			(stroke
				(width 0.1)
				(type default)
			)
			(layer "F.Fab")
		)
		(fp_line
			(start 0.12065 -0.3048)
			(end 0.67945 -0.3048)
			(stroke
				(width 0.1)
				(type default)
			)
			(layer "F.Fab")
		)
		(fp_line
			(start 0.12065 -0.2794)
			(end 0.12065 -0.3048)
			(stroke
				(width 0.1)
				(type default)
			)
			(layer "F.Fab")
		)
		(fp_line
			(start 0.67945 -0.3048)
			(end 0.67945 0.3048)
			(stroke
				(width 0.1)
				(type default)
			)
			(layer "F.Fab")
		)
		(fp_line
			(start 0.67945 0.3048)
			(end 0.120396 0.3048)
			(stroke
				(width 0.1)
				(type default)
			)
			(layer "F.Fab")
		)
		(pad "1" smd circle
			(at -0.40005 0)
			(size 0 0)
			(layers "F.Cu" "F.Mask" "F.Paste")
			(net "P1V8_VDDA_PEX2")
		)
		(pad "2" smd circle
			(at 0.40005 0)
			(size 0 0)
			(layers "F.Cu" "F.Mask" "F.Paste")
			(net "P1V8_VDDA_PEX2_R")
		)
	)
	(footprint ""
		(layer "F.Cu")
		(at 426.567854 -53.051456)
		(property "Reference" "R4471"
			(at 0 0 0)
			(layer "F.SilkS")
			(hide yes)
			(effects
				(font
					(size 1.27 1.27)
				)
			)
		)
		(property "Value" ""
			(at 0 0 0)
			(layer "F.Fab")
			(effects
				(font
					(size 1.27 1.27)
				)
			)
		)
		(duplicate_pad_numbers_are_jumpers no)
		(fp_line
			(start -0.7874 -0.4064)
			(end 0.7874 -0.4064)
			(stroke
				(width 0.1524)
				(type default)
			)
			(layer "F.SilkS")
		)
		(fp_line
			(start -0.7874 0.4064)
			(end -0.7874 -0.4064)
			(stroke
				(width 0.1524)
				(type default)
			)
			(layer "F.SilkS")
		)
		(fp_line
			(start 0.7874 -0.4064)
			(end 0.7874 0.4064)
			(stroke
				(width 0.1524)
				(type default)
			)
			(layer "F.SilkS")
		)
		(fp_line
			(start 0.7874 0.4064)
			(end -0.7874 0.4064)
			(stroke
				(width 0.1524)
				(type default)
			)
			(layer "F.SilkS")
		)
		(fp_line
			(start -0.67945 -0.305054)
			(end -0.12065 -0.305054)
			(stroke
				(width 0.1)
				(type default)
			)
			(layer "F.Fab")
		)
		(fp_line
			(start -0.67945 0.3048)
			(end -0.67945 -0.305054)
			(stroke
				(width 0.1)
				(type default)
			)
			(layer "F.Fab")
		)
		(fp_line
			(start -0.12065 -0.305054)
			(end -0.12065 -0.2794)
			(stroke
				(width 0.1)
				(type default)
			)
			(layer "F.Fab")
		)
		(fp_line
			(start -0.12065 -0.2794)
			(end 0.12065 -0.2794)
			(stroke
				(width 0.1)
				(type default)
			)
			(layer "F.Fab")
		)
		(fp_line
			(start -0.12065 0.2794)
			(end -0.12065 0.3048)
			(stroke
				(width 0.1)
				(type default)
			)
			(layer "F.Fab")
		)
		(fp_line
			(start -0.12065 0.3048)
			(end -0.67945 0.3048)
			(stroke
				(width 0.1)
				(type default)
			)
			(layer "F.Fab")
		)
		(fp_line
			(start 0.120396 0.2794)
			(end -0.12065 0.2794)
			(stroke
				(width 0.1)
				(type default)
			)
			(layer "F.Fab")
		)
		(fp_line
			(start 0.120396 0.3048)
			(end 0.120396 0.2794)
			(stroke
				(width 0.1)
				(type default)
			)
			(layer "F.Fab")
		)
		(fp_line
			(start 0.12065 -0.3048)
			(end 0.67945 -0.3048)
			(stroke
				(width 0.1)
				(type default)
			)
			(layer "F.Fab")
		)
		(fp_line
			(start 0.12065 -0.2794)
			(end 0.12065 -0.3048)
			(stroke
				(width 0.1)
				(type default)
			)
			(layer "F.Fab")
		)
		(fp_line
			(start 0.67945 -0.3048)
			(end 0.67945 0.3048)
			(stroke
				(width 0.1)
				(type default)
			)
			(layer "F.Fab")
		)
		(fp_line
			(start 0.67945 0.3048)
			(end 0.120396 0.3048)
			(stroke
				(width 0.1)
				(type default)
			)
			(layer "F.Fab")
		)
		(pad "1" smd circle
			(at -0.40005 0)
			(size 0 0)
			(layers "F.Cu" "F.Mask" "F.Paste")
			(net "PWRGD_P12V_SSD14")
		)
		(pad "2" smd circle
			(at 0.40005 0)
			(size 0 0)
			(layers "F.Cu" "F.Mask" "F.Paste")
			(net "PWRGD_P12V_SSD14_R")
		)
	)
	(footprint ""
		(layer "F.Cu")
		(at 162.5346 -33.631886 180)
		(property "Reference" "C285"
			(at 0 0 180)
			(layer "F.SilkS")
			(hide yes)
			(effects
				(font
					(size 1.27 1.27)
				)
			)
		)
		(property "Value" ""
			(at 0 0 180)
			(layer "F.Fab")
			(effects
				(font
					(size 1.27 1.27)
				)
			)
		)
		(duplicate_pad_numbers_are_jumpers no)
		(fp_line
			(start 0.299974 0.150114)
			(end -0.299974 0.150114)
			(stroke
				(width 0.1)
				(type default)
			)
			(layer "F.Fab")
		)
		(fp_line
			(start 0.299974 -0.150114)
			(end 0.299974 0.150114)
			(stroke
				(width 0.1)
				(type default)
			)
			(layer "F.Fab")
		)
		(fp_line
			(start -0.299974 0.150114)
			(end -0.299974 -0.150114)
			(stroke
				(width 0.1)
				(type default)
			)
			(layer "F.Fab")
		)
		(fp_line
			(start -0.299974 -0.150114)
			(end 0.299974 -0.150114)
			(stroke
				(width 0.1)
				(type default)
			)
			(layer "F.Fab")
		)
		(pad "1" smd rect
			(at -0.2667 0 180)
			(size 0.3048 0.381)
			(layers "F.Cu" "F.Mask" "F.Paste")
			(net "P5E_PEX1_STN2_TX_DN<43>")
		)
		(pad "2" smd rect
			(at 0.2667 0 180)
			(size 0.3048 0.381)
			(layers "F.Cu" "F.Mask" "F.Paste")
			(net "P5E_PEX1_STN2_TX_C_DN<43>")
		)
	)
	(footprint ""
		(layer "F.Cu")
		(at 258.44373 -44.87291)
		(property "Reference" "R595"
			(at 0 0 0)
			(layer "F.SilkS")
			(hide yes)
			(effects
				(font
					(size 1.27 1.27)
				)
			)
		)
		(property "Value" ""
			(at 0 0 0)
			(layer "F.Fab")
			(effects
				(font
					(size 1.27 1.27)
				)
			)
		)
		(duplicate_pad_numbers_are_jumpers no)
		(fp_line
			(start -0.7874 -0.4064)
			(end 0.7874 -0.4064)
			(stroke
				(width 0.1524)
				(type default)
			)
			(layer "F.SilkS")
		)
		(fp_line
			(start -0.7874 0.4064)
			(end -0.7874 -0.4064)
			(stroke
				(width 0.1524)
				(type default)
			)
			(layer "F.SilkS")
		)
		(fp_line
			(start 0.7874 -0.4064)
			(end 0.7874 0.4064)
			(stroke
				(width 0.1524)
				(type default)
			)
			(layer "F.SilkS")
		)
		(fp_line
			(start 0.7874 0.4064)
			(end -0.7874 0.4064)
			(stroke
				(width 0.1524)
				(type default)
			)
			(layer "F.SilkS")
		)
		(fp_line
			(start -0.67945 -0.305054)
			(end -0.12065 -0.305054)
			(stroke
				(width 0.1)
				(type default)
			)
			(layer "F.Fab")
		)
		(fp_line
			(start -0.67945 0.3048)
			(end -0.67945 -0.305054)
			(stroke
				(width 0.1)
				(type default)
			)
			(layer "F.Fab")
		)
		(fp_line
			(start -0.12065 -0.305054)
			(end -0.12065 -0.2794)
			(stroke
				(width 0.1)
				(type default)
			)
			(layer "F.Fab")
		)
		(fp_line
			(start -0.12065 -0.2794)
			(end 0.12065 -0.2794)
			(stroke
				(width 0.1)
				(type default)
			)
			(layer "F.Fab")
		)
		(fp_line
			(start -0.12065 0.2794)
			(end -0.12065 0.3048)
			(stroke
				(width 0.1)
				(type default)
			)
			(layer "F.Fab")
		)
		(fp_line
			(start -0.12065 0.3048)
			(end -0.67945 0.3048)
			(stroke
				(width 0.1)
				(type default)
			)
			(layer "F.Fab")
		)
		(fp_line
			(start 0.120396 0.2794)
			(end -0.12065 0.2794)
			(stroke
				(width 0.1)
				(type default)
			)
			(layer "F.Fab")
		)
		(fp_line
			(start 0.120396 0.3048)
			(end 0.120396 0.2794)
			(stroke
				(width 0.1)
				(type default)
			)
			(layer "F.Fab")
		)
		(fp_line
			(start 0.12065 -0.3048)
			(end 0.67945 -0.3048)
			(stroke
				(width 0.1)
				(type default)
			)
			(layer "F.Fab")
		)
		(fp_line
			(start 0.12065 -0.2794)
			(end 0.12065 -0.3048)
			(stroke
				(width 0.1)
				(type default)
			)
			(layer "F.Fab")
		)
		(fp_line
			(start 0.67945 -0.3048)
			(end 0.67945 0.3048)
			(stroke
				(width 0.1)
				(type default)
			)
			(layer "F.Fab")
		)
		(fp_line
			(start 0.67945 0.3048)
			(end 0.120396 0.3048)
			(stroke
				(width 0.1)
				(type default)
			)
			(layer "F.Fab")
		)
		(pad "1" smd circle
			(at -0.40005 0)
			(size 0 0)
			(layers "F.Cu" "F.Mask" "F.Paste")
			(net "SSD8_ADC_A0")
		)
		(pad "2" smd circle
			(at 0.40005 0)
			(size 0 0)
			(layers "F.Cu" "F.Mask" "F.Paste")
			(net "P3V3_AUX")
		)
	)
	(footprint ""
		(layer "F.Cu")
		(at 211.511388 -369.44935)
		(property "Reference" "PR11"
			(at 0 0 0)
			(layer "F.SilkS")
			(hide yes)
			(effects
				(font
					(size 1.27 1.27)
				)
			)
		)
		(property "Value" ""
			(at 0 0 0)
			(layer "F.Fab")
			(effects
				(font
					(size 1.27 1.27)
				)
			)
		)
		(duplicate_pad_numbers_are_jumpers no)
		(fp_line
			(start -0.7874 -0.4064)
			(end 0.7874 -0.4064)
			(stroke
				(width 0.1524)
				(type default)
			)
			(layer "F.SilkS")
		)
		(fp_line
			(start -0.7874 0.4064)
			(end -0.7874 -0.4064)
			(stroke
				(width 0.1524)
				(type default)
			)
			(layer "F.SilkS")
		)
		(fp_line
			(start 0.7874 -0.4064)
			(end 0.7874 0.4064)
			(stroke
				(width 0.1524)
				(type default)
			)
			(layer "F.SilkS")
		)
		(fp_line
			(start 0.7874 0.4064)
			(end -0.7874 0.4064)
			(stroke
				(width 0.1524)
				(type default)
			)
			(layer "F.SilkS")
		)
		(fp_line
			(start -0.67945 -0.305054)
			(end -0.12065 -0.305054)
			(stroke
				(width 0.1)
				(type default)
			)
			(layer "F.Fab")
		)
		(fp_line
			(start -0.67945 0.3048)
			(end -0.67945 -0.305054)
			(stroke
				(width 0.1)
				(type default)
			)
			(layer "F.Fab")
		)
		(fp_line
			(start -0.12065 -0.305054)
			(end -0.12065 -0.2794)
			(stroke
				(width 0.1)
				(type default)
			)
			(layer "F.Fab")
		)
		(fp_line
			(start -0.12065 -0.2794)
			(end 0.12065 -0.2794)
			(stroke
				(width 0.1)
				(type default)
			)
			(layer "F.Fab")
		)
		(fp_line
			(start -0.12065 0.2794)
			(end -0.12065 0.3048)
			(stroke
				(width 0.1)
				(type default)
			)
			(layer "F.Fab")
		)
		(fp_line
			(start -0.12065 0.3048)
			(end -0.67945 0.3048)
			(stroke
				(width 0.1)
				(type default)
			)
			(layer "F.Fab")
		)
		(fp_line
			(start 0.120396 0.2794)
			(end -0.12065 0.2794)
			(stroke
				(width 0.1)
				(type default)
			)
			(layer "F.Fab")
		)
		(fp_line
			(start 0.120396 0.3048)
			(end 0.120396 0.2794)
			(stroke
				(width 0.1)
				(type default)
			)
			(layer "F.Fab")
		)
		(fp_line
			(start 0.12065 -0.3048)
			(end 0.67945 -0.3048)
			(stroke
				(width 0.1)
				(type default)
			)
			(layer "F.Fab")
		)
		(fp_line
			(start 0.12065 -0.2794)
			(end 0.12065 -0.3048)
			(stroke
				(width 0.1)
				(type default)
			)
			(layer "F.Fab")
		)
		(fp_line
			(start 0.67945 -0.3048)
			(end 0.67945 0.3048)
			(stroke
				(width 0.1)
				(type default)
			)
			(layer "F.Fab")
		)
		(fp_line
			(start 0.67945 0.3048)
			(end 0.120396 0.3048)
			(stroke
				(width 0.1)
				(type default)
			)
			(layer "F.Fab")
		)
		(pad "1" smd circle
			(at -0.40005 0)
			(size 0 0)
			(layers "F.Cu" "F.Mask" "F.Paste")
			(net "HSC_MODE")
		)
		(pad "2" smd circle
			(at 0.40005 0)
			(size 0 0)
			(layers "F.Cu" "F.Mask" "F.Paste")
			(net "AGND_HSC")
		)
	)
	(footprint ""
		(layer "F.Cu")
		(at 142.684246 -29.222954 -90)
		(property "Reference" "PC919"
			(at 0 0 270)
			(layer "F.SilkS")
			(hide yes)
			(effects
				(font
					(size 1.27 1.27)
				)
			)
		)
		(property "Value" ""
			(at 0 0 270)
			(layer "F.Fab")
			(effects
				(font
					(size 1.27 1.27)
				)
			)
		)
		(duplicate_pad_numbers_are_jumpers no)
		(fp_line
			(start -0.7874 0.4064)
			(end -0.7874 -0.4064)
			(stroke
				(width 0.1524)
				(type default)
			)
			(layer "F.SilkS")
		)
		(fp_line
			(start 0.7874 0.4064)
			(end -0.7874 0.4064)
			(stroke
				(width 0.1524)
				(type default)
			)
			(layer "F.SilkS")
		)
		(fp_line
			(start -0.7874 -0.4064)
			(end 0.7874 -0.4064)
			(stroke
				(width 0.1524)
				(type default)
			)
			(layer "F.SilkS")
		)
		(fp_line
			(start 0.7874 -0.4064)
			(end 0.7874 0.4064)
			(stroke
				(width 0.1524)
				(type default)
			)
			(layer "F.SilkS")
		)
		(fp_line
			(start -0.67945 0.3048)
			(end -0.67945 -0.305054)
			(stroke
				(width 0.1)
				(type default)
			)
			(layer "F.Fab")
		)
		(fp_line
			(start -0.12065 0.3048)
			(end -0.67945 0.3048)
			(stroke
				(width 0.1)
				(type default)
			)
			(layer "F.Fab")
		)
		(fp_line
			(start 0.120396 0.3048)
			(end 0.120396 0.2794)
			(stroke
				(width 0.1)
				(type default)
			)
			(layer "F.Fab")
		)
		(fp_line
			(start 0.67945 0.3048)
			(end 0.120396 0.3048)
			(stroke
				(width 0.1)
				(type default)
			)
			(layer "F.Fab")
		)
		(fp_line
			(start -0.12065 0.2794)
			(end -0.12065 0.3048)
			(stroke
				(width 0.1)
				(type default)
			)
			(layer "F.Fab")
		)
		(fp_line
			(start 0.120396 0.2794)
			(end -0.12065 0.2794)
			(stroke
				(width 0.1)
				(type default)
			)
			(layer "F.Fab")
		)
		(fp_line
			(start -0.12065 -0.2794)
			(end 0.12065 -0.2794)
			(stroke
				(width 0.1)
				(type default)
			)
			(layer "F.Fab")
		)
		(fp_line
			(start 0.12065 -0.2794)
			(end 0.12065 -0.3048)
			(stroke
				(width 0.1)
				(type default)
			)
			(layer "F.Fab")
		)
		(fp_line
			(start 0.12065 -0.3048)
			(end 0.67945 -0.3048)
			(stroke
				(width 0.1)
				(type default)
			)
			(layer "F.Fab")
		)
		(fp_line
			(start 0.67945 -0.3048)
			(end 0.67945 0.3048)
			(stroke
				(width 0.1)
				(type default)
			)
			(layer "F.Fab")
		)
		(fp_line
			(start -0.67945 -0.305054)
			(end -0.12065 -0.305054)
			(stroke
				(width 0.1)
				(type default)
			)
			(layer "F.Fab")
		)
		(fp_line
			(start -0.12065 -0.305054)
			(end -0.12065 -0.2794)
			(stroke
				(width 0.1)
				(type default)
			)
			(layer "F.Fab")
		)
		(pad "1" smd circle
			(at -0.40005 0 270)
			(size 0 0)
			(layers "F.Cu" "F.Mask" "F.Paste")
			(net "P3V3_AUX")
		)
		(pad "2" smd circle
			(at 0.40005 0 270)
			(size 0 0)
			(layers "F.Cu" "F.Mask" "F.Paste")
			(net "GND")
		)
	)
	(footprint ""
		(layer "F.Cu")
		(at 177.705512 -350.098614 90)
		(property "Reference" "C386"
			(at 0 0 90)
			(layer "F.SilkS")
			(hide yes)
			(effects
				(font
					(size 1.27 1.27)
				)
			)
		)
		(property "Value" ""
			(at 0 0 90)
			(layer "F.Fab")
			(effects
				(font
					(size 1.27 1.27)
				)
			)
		)
		(duplicate_pad_numbers_are_jumpers no)
		(fp_line
			(start 0.299974 -0.150114)
			(end 0.299974 0.150114)
			(stroke
				(width 0.1)
				(type default)
			)
			(layer "F.Fab")
		)
		(fp_line
			(start -0.299974 -0.150114)
			(end 0.299974 -0.150114)
			(stroke
				(width 0.1)
				(type default)
			)
			(layer "F.Fab")
		)
		(fp_line
			(start 0.299974 0.150114)
			(end -0.299974 0.150114)
			(stroke
				(width 0.1)
				(type default)
			)
			(layer "F.Fab")
		)
		(fp_line
			(start -0.299974 0.150114)
			(end -0.299974 -0.150114)
			(stroke
				(width 0.1)
				(type default)
			)
			(layer "F.Fab")
		)
		(pad "1" smd rect
			(at -0.2667 0 90)
			(size 0.3048 0.381)
			(layers "F.Cu" "F.Mask" "F.Paste")
			(net "P5E_PEX1_STN7_TX_DP<120>")
		)
		(pad "2" smd rect
			(at 0.2667 0 90)
			(size 0.3048 0.381)
			(layers "F.Cu" "F.Mask" "F.Paste")
			(net "P5E_PEX1_STN7_TX_C_DP<120>")
		)
	)
	(footprint ""
		(layer "F.Cu")
		(at 149.954234 -307.415438 45)
		(property "Reference" "R1285"
			(at 0 0 45)
			(layer "F.SilkS")
			(hide yes)
			(effects
				(font
					(size 1.27 1.27)
				)
			)
		)
		(property "Value" ""
			(at 0 0 45)
			(layer "F.Fab")
			(effects
				(font
					(size 1.27 1.27)
				)
			)
		)
		(duplicate_pad_numbers_are_jumpers no)
		(fp_line
			(start -0.787389 -0.406267)
			(end 0.787389 -0.406267)
			(stroke
				(width 0.1524)
				(type default)
			)
			(layer "F.SilkS")
		)
		(fp_line
			(start -0.787389 0.406267)
			(end -0.787389 -0.406267)
			(stroke
				(width 0.1524)
				(type default)
			)
			(layer "F.SilkS")
		)
		(fp_line
			(start 0.787389 -0.406267)
			(end 0.787389 0.406267)
			(stroke
				(width 0.1524)
				(type default)
			)
			(layer "F.SilkS")
		)
		(fp_line
			(start 0.787389 0.406267)
			(end -0.787389 0.406267)
			(stroke
				(width 0.1524)
				(type default)
			)
			(layer "F.SilkS")
		)
		(fp_line
			(start -0.679446 -0.305149)
			(end -0.120695 -0.304969)
			(stroke
				(width 0.1)
				(type default)
			)
			(layer "F.Fab")
		)
		(fp_line
			(start -0.120695 -0.304969)
			(end -0.120695 -0.279466)
			(stroke
				(width 0.1)
				(type default)
			)
			(layer "F.Fab")
		)
		(fp_line
			(start -0.120695 -0.279466)
			(end 0.120695 -0.279466)
			(stroke
				(width 0.1)
				(type default)
			)
			(layer "F.Fab")
		)
		(fp_line
			(start -0.679446 0.30479)
			(end -0.679446 -0.305149)
			(stroke
				(width 0.1)
				(type default)
			)
			(layer "F.Fab")
		)
		(fp_line
			(start 0.120515 -0.30479)
			(end 0.679446 -0.30479)
			(stroke
				(width 0.1)
				(type default)
			)
			(layer "F.Fab")
		)
		(fp_line
			(start 0.120695 -0.279466)
			(end 0.120515 -0.30479)
			(stroke
				(width 0.1)
				(type default)
			)
			(layer "F.Fab")
		)
		(fp_line
			(start -0.120695 0.279466)
			(end -0.120515 0.30479)
			(stroke
				(width 0.1)
				(type default)
			)
			(layer "F.Fab")
		)
		(fp_line
			(start -0.120515 0.30479)
			(end -0.679446 0.30479)
			(stroke
				(width 0.1)
				(type default)
			)
			(layer "F.Fab")
		)
		(fp_line
			(start 0.679446 -0.30479)
			(end 0.679446 0.30479)
			(stroke
				(width 0.1)
				(type default)
			)
			(layer "F.Fab")
		)
		(fp_line
			(start 0.120335 0.279466)
			(end -0.120695 0.279466)
			(stroke
				(width 0.1)
				(type default)
			)
			(layer "F.Fab")
		)
		(fp_line
			(start 0.120515 0.30479)
			(end 0.120335 0.279466)
			(stroke
				(width 0.1)
				(type default)
			)
			(layer "F.Fab")
		)
		(fp_line
			(start 0.679446 0.30479)
			(end 0.120515 0.30479)
			(stroke
				(width 0.1)
				(type default)
			)
			(layer "F.Fab")
		)
		(pad "1" smd circle
			(at -0.40005 0 45)
			(size 0 0)
			(layers "F.Cu" "F.Mask" "F.Paste")
			(net "GND")
		)
		(pad "2" smd circle
			(at 0.40005 0 45)
			(size 0 0)
			(layers "F.Cu" "F.Mask" "F.Paste")
			(net "PEX1_DBG_MODE1")
		)
	)
	(footprint ""
		(layer "F.Cu")
		(at 90.915744 -309.760366 135)
		(property "Reference" "R1251"
			(at 0 0 135)
			(layer "F.SilkS")
			(hide yes)
			(effects
				(font
					(size 1.27 1.27)
				)
			)
		)
		(property "Value" ""
			(at 0 0 135)
			(layer "F.Fab")
			(effects
				(font
					(size 1.27 1.27)
				)
			)
		)
		(duplicate_pad_numbers_are_jumpers no)
		(fp_line
			(start 0.787389 -0.406267)
			(end 0.787389 0.406267)
			(stroke
				(width 0.1524)
				(type default)
			)
			(layer "F.SilkS")
		)
		(fp_line
			(start 0.787389 0.406267)
			(end -0.787389 0.406267)
			(stroke
				(width 0.1524)
				(type default)
			)
			(layer "F.SilkS")
		)
		(fp_line
			(start -0.787389 -0.406267)
			(end 0.787389 -0.406267)
			(stroke
				(width 0.1524)
				(type default)
			)
			(layer "F.SilkS")
		)
		(fp_line
			(start -0.787389 0.406267)
			(end -0.787389 -0.406267)
			(stroke
				(width 0.1524)
				(type default)
			)
			(layer "F.SilkS")
		)
		(fp_line
			(start 0.679446 -0.30479)
			(end 0.679446 0.30479)
			(stroke
				(width 0.1)
				(type default)
			)
			(layer "F.Fab")
		)
		(fp_line
			(start 0.120515 -0.30479)
			(end 0.679446 -0.30479)
			(stroke
				(width 0.1)
				(type default)
			)
			(layer "F.Fab")
		)
		(fp_line
			(start 0.120695 -0.279466)
			(end 0.120515 -0.30479)
			(stroke
				(width 0.1)
				(type default)
			)
			(layer "F.Fab")
		)
		(fp_line
			(start 0.679446 0.30479)
			(end 0.120515 0.30479)
			(stroke
				(width 0.1)
				(type default)
			)
			(layer "F.Fab")
		)
		(fp_line
			(start -0.120695 -0.304969)
			(end -0.120695 -0.279466)
			(stroke
				(width 0.1)
				(type default)
			)
			(layer "F.Fab")
		)
		(fp_line
			(start -0.120695 -0.279466)
			(end 0.120695 -0.279466)
			(stroke
				(width 0.1)
				(type default)
			)
			(layer "F.Fab")
		)
		(fp_line
			(start 0.120335 0.279466)
			(end -0.120695 0.279466)
			(stroke
				(width 0.1)
				(type default)
			)
			(layer "F.Fab")
		)
		(fp_line
			(start 0.120515 0.30479)
			(end 0.120335 0.279466)
			(stroke
				(width 0.1)
				(type default)
			)
			(layer "F.Fab")
		)
		(fp_line
			(start -0.679446 -0.305149)
			(end -0.120695 -0.304969)
			(stroke
				(width 0.1)
				(type default)
			)
			(layer "F.Fab")
		)
		(fp_line
			(start -0.120695 0.279466)
			(end -0.120515 0.30479)
			(stroke
				(width 0.1)
				(type default)
			)
			(layer "F.Fab")
		)
		(fp_line
			(start -0.120515 0.30479)
			(end -0.679446 0.30479)
			(stroke
				(width 0.1)
				(type default)
			)
			(layer "F.Fab")
		)
		(fp_line
			(start -0.679446 0.30479)
			(end -0.679446 -0.305149)
			(stroke
				(width 0.1)
				(type default)
			)
			(layer "F.Fab")
		)
		(pad "1" smd circle
			(at -0.40005 0 135)
			(size 0 0)
			(layers "F.Cu" "F.Mask" "F.Paste")
			(net "GND")
		)
		(pad "2" smd circle
			(at 0.40005 0 135)
			(size 0 0)
			(layers "F.Cu" "F.Mask" "F.Paste")
			(net "PEX0_SPARE0")
		)
	)
	(footprint ""
		(layer "F.Cu")
		(at 110.562898 -284.834838 90)
		(property "Reference" "PC76"
			(at 0 0 90)
			(layer "F.SilkS")
			(hide yes)
			(effects
				(font
					(size 1.27 1.27)
				)
			)
		)
		(property "Value" ""
			(at 0 0 90)
			(layer "F.Fab")
			(effects
				(font
					(size 1.27 1.27)
				)
			)
		)
		(duplicate_pad_numbers_are_jumpers no)
		(fp_line
			(start 0.7874 -0.4064)
			(end 0.7874 0.4064)
			(stroke
				(width 0.1524)
				(type default)
			)
			(layer "F.SilkS")
		)
		(fp_line
			(start -0.7874 -0.4064)
			(end 0.7874 -0.4064)
			(stroke
				(width 0.1524)
				(type default)
			)
			(layer "F.SilkS")
		)
		(fp_line
			(start 0.7874 0.4064)
			(end -0.7874 0.4064)
			(stroke
				(width 0.1524)
				(type default)
			)
			(layer "F.SilkS")
		)
		(fp_line
			(start -0.7874 0.4064)
			(end -0.7874 -0.4064)
			(stroke
				(width 0.1524)
				(type default)
			)
			(layer "F.SilkS")
		)
		(fp_line
			(start -0.12065 -0.305054)
			(end -0.12065 -0.2794)
			(stroke
				(width 0.1)
				(type default)
			)
			(layer "F.Fab")
		)
		(fp_line
			(start -0.67945 -0.305054)
			(end -0.12065 -0.305054)
			(stroke
				(width 0.1)
				(type default)
			)
			(layer "F.Fab")
		)
		(fp_line
			(start 0.67945 -0.3048)
			(end 0.67945 0.3048)
			(stroke
				(width 0.1)
				(type default)
			)
			(layer "F.Fab")
		)
		(fp_line
			(start 0.12065 -0.3048)
			(end 0.67945 -0.3048)
			(stroke
				(width 0.1)
				(type default)
			)
			(layer "F.Fab")
		)
		(fp_line
			(start 0.12065 -0.2794)
			(end 0.12065 -0.3048)
			(stroke
				(width 0.1)
				(type default)
			)
			(layer "F.Fab")
		)
		(fp_line
			(start -0.12065 -0.2794)
			(end 0.12065 -0.2794)
			(stroke
				(width 0.1)
				(type default)
			)
			(layer "F.Fab")
		)
		(fp_line
			(start 0.120396 0.2794)
			(end -0.12065 0.2794)
			(stroke
				(width 0.1)
				(type default)
			)
			(layer "F.Fab")
		)
		(fp_line
			(start -0.12065 0.2794)
			(end -0.12065 0.3048)
			(stroke
				(width 0.1)
				(type default)
			)
			(layer "F.Fab")
		)
		(fp_line
			(start 0.67945 0.3048)
			(end 0.120396 0.3048)
			(stroke
				(width 0.1)
				(type default)
			)
			(layer "F.Fab")
		)
		(fp_line
			(start 0.120396 0.3048)
			(end 0.120396 0.2794)
			(stroke
				(width 0.1)
				(type default)
			)
			(layer "F.Fab")
		)
		(fp_line
			(start -0.12065 0.3048)
			(end -0.67945 0.3048)
			(stroke
				(width 0.1)
				(type default)
			)
			(layer "F.Fab")
		)
		(fp_line
			(start -0.67945 0.3048)
			(end -0.67945 -0.305054)
			(stroke
				(width 0.1)
				(type default)
			)
			(layer "F.Fab")
		)
		(pad "1" smd circle
			(at -0.40005 0 90)
			(size 0 0)
			(layers "F.Cu" "F.Mask" "F.Paste")
			(net "SW_P12V_P0V8_PEX0_FLT")
		)
		(pad "2" smd circle
			(at 0.40005 0 90)
			(size 0 0)
			(layers "F.Cu" "F.Mask" "F.Paste")
			(net "GND")
		)
	)
	(footprint ""
		(layer "F.Cu")
		(at 358.417876 -398.178528 -90)
		(property "Reference" "R6704"
			(at 0 0 270)
			(layer "F.SilkS")
			(hide yes)
			(effects
				(font
					(size 1.27 1.27)
				)
			)
		)
		(property "Value" ""
			(at 0 0 270)
			(layer "F.Fab")
			(effects
				(font
					(size 1.27 1.27)
				)
			)
		)
		(duplicate_pad_numbers_are_jumpers no)
		(fp_line
			(start -0.7874 0.4064)
			(end -0.7874 -0.4064)
			(stroke
				(width 0.1524)
				(type default)
			)
			(layer "F.SilkS")
		)
		(fp_line
			(start 0.7874 0.4064)
			(end -0.7874 0.4064)
			(stroke
				(width 0.1524)
				(type default)
			)
			(layer "F.SilkS")
		)
		(fp_line
			(start -0.7874 -0.4064)
			(end 0.7874 -0.4064)
			(stroke
				(width 0.1524)
				(type default)
			)
			(layer "F.SilkS")
		)
		(fp_line
			(start 0.7874 -0.4064)
			(end 0.7874 0.4064)
			(stroke
				(width 0.1524)
				(type default)
			)
			(layer "F.SilkS")
		)
		(fp_line
			(start -0.67945 0.3048)
			(end -0.67945 -0.305054)
			(stroke
				(width 0.1)
				(type default)
			)
			(layer "F.Fab")
		)
		(fp_line
			(start -0.12065 0.3048)
			(end -0.67945 0.3048)
			(stroke
				(width 0.1)
				(type default)
			)
			(layer "F.Fab")
		)
		(fp_line
			(start 0.120396 0.3048)
			(end 0.120396 0.2794)
			(stroke
				(width 0.1)
				(type default)
			)
			(layer "F.Fab")
		)
		(fp_line
			(start 0.67945 0.3048)
			(end 0.120396 0.3048)
			(stroke
				(width 0.1)
				(type default)
			)
			(layer "F.Fab")
		)
		(fp_line
			(start -0.12065 0.2794)
			(end -0.12065 0.3048)
			(stroke
				(width 0.1)
				(type default)
			)
			(layer "F.Fab")
		)
		(fp_line
			(start 0.120396 0.2794)
			(end -0.12065 0.2794)
			(stroke
				(width 0.1)
				(type default)
			)
			(layer "F.Fab")
		)
		(fp_line
			(start -0.12065 -0.2794)
			(end 0.12065 -0.2794)
			(stroke
				(width 0.1)
				(type default)
			)
			(layer "F.Fab")
		)
		(fp_line
			(start 0.12065 -0.2794)
			(end 0.12065 -0.3048)
			(stroke
				(width 0.1)
				(type default)
			)
			(layer "F.Fab")
		)
		(fp_line
			(start 0.12065 -0.3048)
			(end 0.67945 -0.3048)
			(stroke
				(width 0.1)
				(type default)
			)
			(layer "F.Fab")
		)
		(fp_line
			(start 0.67945 -0.3048)
			(end 0.67945 0.3048)
			(stroke
				(width 0.1)
				(type default)
			)
			(layer "F.Fab")
		)
		(fp_line
			(start -0.67945 -0.305054)
			(end -0.12065 -0.305054)
			(stroke
				(width 0.1)
				(type default)
			)
			(layer "F.Fab")
		)
		(fp_line
			(start -0.12065 -0.305054)
			(end -0.12065 -0.2794)
			(stroke
				(width 0.1)
				(type default)
			)
			(layer "F.Fab")
		)
		(pad "1" smd circle
			(at -0.40005 0 270)
			(size 0 0)
			(layers "F.Cu" "F.Mask" "F.Paste")
			(net "MB_3V3IO_RSVD3_ISO_R")
		)
		(pad "2" smd circle
			(at 0.40005 0 270)
			(size 0 0)
			(layers "F.Cu" "F.Mask" "F.Paste")
			(net "MB_3V3IO_RSVD3_ISO")
		)
	)
	(footprint ""
		(layer "F.Cu")
		(at 350.647 -185.42 90)
		(property "Reference" "C3601"
			(at 0 0 90)
			(layer "F.SilkS")
			(hide yes)
			(effects
				(font
					(size 1.27 1.27)
				)
			)
		)
		(property "Value" ""
			(at 0 0 90)
			(layer "F.Fab")
			(effects
				(font
					(size 1.27 1.27)
				)
			)
		)
		(duplicate_pad_numbers_are_jumpers no)
		(fp_line
			(start 0.7874 -0.4064)
			(end 0.7874 0.4064)
			(stroke
				(width 0.1524)
				(type default)
			)
			(layer "F.SilkS")
		)
		(fp_line
			(start -0.7874 -0.4064)
			(end 0.7874 -0.4064)
			(stroke
				(width 0.1524)
				(type default)
			)
			(layer "F.SilkS")
		)
		(fp_line
			(start 0.7874 0.4064)
			(end -0.7874 0.4064)
			(stroke
				(width 0.1524)
				(type default)
			)
			(layer "F.SilkS")
		)
		(fp_line
			(start -0.7874 0.4064)
			(end -0.7874 -0.4064)
			(stroke
				(width 0.1524)
				(type default)
			)
			(layer "F.SilkS")
		)
		(fp_line
			(start -0.12065 -0.305054)
			(end -0.12065 -0.2794)
			(stroke
				(width 0.1)
				(type default)
			)
			(layer "F.Fab")
		)
		(fp_line
			(start -0.67945 -0.305054)
			(end -0.12065 -0.305054)
			(stroke
				(width 0.1)
				(type default)
			)
			(layer "F.Fab")
		)
		(fp_line
			(start 0.67945 -0.3048)
			(end 0.67945 0.3048)
			(stroke
				(width 0.1)
				(type default)
			)
			(layer "F.Fab")
		)
		(fp_line
			(start 0.12065 -0.3048)
			(end 0.67945 -0.3048)
			(stroke
				(width 0.1)
				(type default)
			)
			(layer "F.Fab")
		)
		(fp_line
			(start 0.12065 -0.2794)
			(end 0.12065 -0.3048)
			(stroke
				(width 0.1)
				(type default)
			)
			(layer "F.Fab")
		)
		(fp_line
			(start -0.12065 -0.2794)
			(end 0.12065 -0.2794)
			(stroke
				(width 0.1)
				(type default)
			)
			(layer "F.Fab")
		)
		(fp_line
			(start 0.120396 0.2794)
			(end -0.12065 0.2794)
			(stroke
				(width 0.1)
				(type default)
			)
			(layer "F.Fab")
		)
		(fp_line
			(start -0.12065 0.2794)
			(end -0.12065 0.3048)
			(stroke
				(width 0.1)
				(type default)
			)
			(layer "F.Fab")
		)
		(fp_line
			(start 0.67945 0.3048)
			(end 0.120396 0.3048)
			(stroke
				(width 0.1)
				(type default)
			)
			(layer "F.Fab")
		)
		(fp_line
			(start 0.120396 0.3048)
			(end 0.120396 0.2794)
			(stroke
				(width 0.1)
				(type default)
			)
			(layer "F.Fab")
		)
		(fp_line
			(start -0.12065 0.3048)
			(end -0.67945 0.3048)
			(stroke
				(width 0.1)
				(type default)
			)
			(layer "F.Fab")
		)
		(fp_line
			(start -0.67945 0.3048)
			(end -0.67945 -0.305054)
			(stroke
				(width 0.1)
				(type default)
			)
			(layer "F.Fab")
		)
		(pad "1" smd circle
			(at -0.40005 0 90)
			(size 0 0)
			(layers "F.Cu" "F.Mask" "F.Paste")
			(net "P3V3_AUX")
		)
		(pad "2" smd circle
			(at 0.40005 0 90)
			(size 0 0)
			(layers "F.Cu" "F.Mask" "F.Paste")
			(net "GND")
		)
	)
	(footprint ""
		(layer "F.Cu")
		(at 396.185644 -25.1587 -90)
		(property "Reference" "R5754"
			(at 0 0 270)
			(layer "F.SilkS")
			(hide yes)
			(effects
				(font
					(size 1.27 1.27)
				)
			)
		)
		(property "Value" ""
			(at 0 0 270)
			(layer "F.Fab")
			(effects
				(font
					(size 1.27 1.27)
				)
			)
		)
		(duplicate_pad_numbers_are_jumpers no)
		(fp_line
			(start -0.7874 0.4064)
			(end -0.7874 -0.4064)
			(stroke
				(width 0.1524)
				(type default)
			)
			(layer "F.SilkS")
		)
		(fp_line
			(start 0.7874 0.4064)
			(end -0.7874 0.4064)
			(stroke
				(width 0.1524)
				(type default)
			)
			(layer "F.SilkS")
		)
		(fp_line
			(start -0.7874 -0.4064)
			(end 0.7874 -0.4064)
			(stroke
				(width 0.1524)
				(type default)
			)
			(layer "F.SilkS")
		)
		(fp_line
			(start 0.7874 -0.4064)
			(end 0.7874 0.4064)
			(stroke
				(width 0.1524)
				(type default)
			)
			(layer "F.SilkS")
		)
		(fp_line
			(start -0.67945 0.3048)
			(end -0.67945 -0.305054)
			(stroke
				(width 0.1)
				(type default)
			)
			(layer "F.Fab")
		)
		(fp_line
			(start -0.12065 0.3048)
			(end -0.67945 0.3048)
			(stroke
				(width 0.1)
				(type default)
			)
			(layer "F.Fab")
		)
		(fp_line
			(start 0.120396 0.3048)
			(end 0.120396 0.2794)
			(stroke
				(width 0.1)
				(type default)
			)
			(layer "F.Fab")
		)
		(fp_line
			(start 0.67945 0.3048)
			(end 0.120396 0.3048)
			(stroke
				(width 0.1)
				(type default)
			)
			(layer "F.Fab")
		)
		(fp_line
			(start -0.12065 0.2794)
			(end -0.12065 0.3048)
			(stroke
				(width 0.1)
				(type default)
			)
			(layer "F.Fab")
		)
		(fp_line
			(start 0.120396 0.2794)
			(end -0.12065 0.2794)
			(stroke
				(width 0.1)
				(type default)
			)
			(layer "F.Fab")
		)
		(fp_line
			(start -0.12065 -0.2794)
			(end 0.12065 -0.2794)
			(stroke
				(width 0.1)
				(type default)
			)
			(layer "F.Fab")
		)
		(fp_line
			(start 0.12065 -0.2794)
			(end 0.12065 -0.3048)
			(stroke
				(width 0.1)
				(type default)
			)
			(layer "F.Fab")
		)
		(fp_line
			(start 0.12065 -0.3048)
			(end 0.67945 -0.3048)
			(stroke
				(width 0.1)
				(type default)
			)
			(layer "F.Fab")
		)
		(fp_line
			(start 0.67945 -0.3048)
			(end 0.67945 0.3048)
			(stroke
				(width 0.1)
				(type default)
			)
			(layer "F.Fab")
		)
		(fp_line
			(start -0.67945 -0.305054)
			(end -0.12065 -0.305054)
			(stroke
				(width 0.1)
				(type default)
			)
			(layer "F.Fab")
		)
		(fp_line
			(start -0.12065 -0.305054)
			(end -0.12065 -0.2794)
			(stroke
				(width 0.1)
				(type default)
			)
			(layer "F.Fab")
		)
		(pad "1" smd circle
			(at -0.40005 0 270)
			(size 0 0)
			(layers "F.Cu" "F.Mask" "F.Paste")
			(net "SSD13_LED_ISO_N")
		)
		(pad "2" smd circle
			(at 0.40005 0 270)
			(size 0 0)
			(layers "F.Cu" "F.Mask" "F.Paste")
			(net "SSD13_LED_ISO_R_N")
		)
	)
	(footprint ""
		(layer "F.Cu")
		(at 265.311382 -261.434834)
		(property "Reference" "L123"
			(at 0 0 0)
			(layer "F.SilkS")
			(hide yes)
			(effects
				(font
					(size 1.27 1.27)
				)
			)
		)
		(property "Value" ""
			(at 0 0 0)
			(layer "F.Fab")
			(effects
				(font
					(size 1.27 1.27)
				)
			)
		)
		(duplicate_pad_numbers_are_jumpers no)
		(fp_line
			(start -1.63576 -0.8128)
			(end -1.63576 0.8128)
			(stroke
				(width 0.1524)
				(type default)
			)
			(layer "F.SilkS")
		)
		(fp_line
			(start -1.63576 -0.8128)
			(end 1.63576 -0.8128)
			(stroke
				(width 0.1524)
				(type default)
			)
			(layer "F.SilkS")
		)
		(fp_line
			(start 1.63576 -0.8128)
			(end 1.63576 0.8128)
			(stroke
				(width 0.1524)
				(type default)
			)
			(layer "F.SilkS")
		)
		(fp_line
			(start 1.63576 0.8128)
			(end -1.63576 0.8128)
			(stroke
				(width 0.1524)
				(type default)
			)
			(layer "F.SilkS")
		)
		(fp_line
			(start -1.56083 -0.738632)
			(end -1.56083 0.7366)
			(stroke
				(width 0.1)
				(type default)
			)
			(layer "F.Fab")
		)
		(fp_line
			(start -1.56083 0.7366)
			(end -1.524 0.7366)
			(stroke
				(width 0.1)
				(type default)
			)
			(layer "F.Fab")
		)
		(fp_line
			(start -1.524 0.7366)
			(end 1.524 0.7366)
			(stroke
				(width 0.1)
				(type default)
			)
			(layer "F.Fab")
		)
		(fp_line
			(start 1.524 0.7366)
			(end 1.560576 0.7366)
			(stroke
				(width 0.1)
				(type default)
			)
			(layer "F.Fab")
		)
		(fp_line
			(start 1.560576 -0.738632)
			(end -1.56083 -0.738632)
			(stroke
				(width 0.1)
				(type default)
			)
			(layer "F.Fab")
		)
		(fp_line
			(start 1.560576 0.7366)
			(end 1.560576 -0.738632)
			(stroke
				(width 0.1)
				(type default)
			)
			(layer "F.Fab")
		)
		(pad "1" smd rect
			(at -0.94996 0 180)
			(size 1.1176 1.3716)
			(layers "F.Cu" "F.Mask" "F.Paste")
			(net "P1V8_PLL0_PEX2")
		)
		(pad "2" smd rect
			(at 0.94996 0 180)
			(size 1.1176 1.3716)
			(layers "F.Cu" "F.Mask" "F.Paste")
			(net "PCEPLL3_VDDA18_PEX2")
		)
	)
	(footprint ""
		(layer "F.Cu")
		(at 20.125436 -42.849038 180)
		(property "Reference" "R513"
			(at 0 0 180)
			(layer "F.SilkS")
			(hide yes)
			(effects
				(font
					(size 1.27 1.27)
				)
			)
		)
		(property "Value" ""
			(at 0 0 180)
			(layer "F.Fab")
			(effects
				(font
					(size 1.27 1.27)
				)
			)
		)
		(duplicate_pad_numbers_are_jumpers no)
		(fp_line
			(start 0.7874 0.4064)
			(end -0.7874 0.4064)
			(stroke
				(width 0.1524)
				(type default)
			)
			(layer "F.SilkS")
		)
		(fp_line
			(start 0.7874 -0.4064)
			(end 0.7874 0.4064)
			(stroke
				(width 0.1524)
				(type default)
			)
			(layer "F.SilkS")
		)
		(fp_line
			(start -0.7874 0.4064)
			(end -0.7874 -0.4064)
			(stroke
				(width 0.1524)
				(type default)
			)
			(layer "F.SilkS")
		)
		(fp_line
			(start -0.7874 -0.4064)
			(end 0.7874 -0.4064)
			(stroke
				(width 0.1524)
				(type default)
			)
			(layer "F.SilkS")
		)
		(fp_line
			(start 0.67945 0.3048)
			(end 0.120396 0.3048)
			(stroke
				(width 0.1)
				(type default)
			)
			(layer "F.Fab")
		)
		(fp_line
			(start 0.67945 -0.3048)
			(end 0.67945 0.3048)
			(stroke
				(width 0.1)
				(type default)
			)
			(layer "F.Fab")
		)
		(fp_line
			(start 0.12065 -0.2794)
			(end 0.12065 -0.3048)
			(stroke
				(width 0.1)
				(type default)
			)
			(layer "F.Fab")
		)
		(fp_line
			(start 0.12065 -0.3048)
			(end 0.67945 -0.3048)
			(stroke
				(width 0.1)
				(type default)
			)
			(layer "F.Fab")
		)
		(fp_line
			(start 0.120396 0.3048)
			(end 0.120396 0.2794)
			(stroke
				(width 0.1)
				(type default)
			)
			(layer "F.Fab")
		)
		(fp_line
			(start 0.120396 0.2794)
			(end -0.12065 0.2794)
			(stroke
				(width 0.1)
				(type default)
			)
			(layer "F.Fab")
		)
		(fp_line
			(start -0.12065 0.3048)
			(end -0.67945 0.3048)
			(stroke
				(width 0.1)
				(type default)
			)
			(layer "F.Fab")
		)
		(fp_line
			(start -0.12065 0.2794)
			(end -0.12065 0.3048)
			(stroke
				(width 0.1)
				(type default)
			)
			(layer "F.Fab")
		)
		(fp_line
			(start -0.12065 -0.2794)
			(end 0.12065 -0.2794)
			(stroke
				(width 0.1)
				(type default)
			)
			(layer "F.Fab")
		)
		(fp_line
			(start -0.12065 -0.305054)
			(end -0.12065 -0.2794)
			(stroke
				(width 0.1)
				(type default)
			)
			(layer "F.Fab")
		)
		(fp_line
			(start -0.67945 0.3048)
			(end -0.67945 -0.305054)
			(stroke
				(width 0.1)
				(type default)
			)
			(layer "F.Fab")
		)
		(fp_line
			(start -0.67945 -0.305054)
			(end -0.12065 -0.305054)
			(stroke
				(width 0.1)
				(type default)
			)
			(layer "F.Fab")
		)
		(pad "1" smd circle
			(at -0.40005 0 180)
			(size 0 0)
			(layers "F.Cu" "F.Mask" "F.Paste")
			(net "P12V_SSD0_R")
		)
		(pad "2" smd circle
			(at 0.40005 0 180)
			(size 0 0)
			(layers "F.Cu" "F.Mask" "F.Paste")
			(net "P12V_SSD0_VIN_P")
		)
	)
	(footprint ""
		(layer "F.Cu")
		(at 146.253454 -288.190432)
		(property "Reference" "L110"
			(at 0 0 0)
			(layer "F.SilkS")
			(hide yes)
			(effects
				(font
					(size 1.27 1.27)
				)
			)
		)
		(property "Value" ""
			(at 0 0 0)
			(layer "F.Fab")
			(effects
				(font
					(size 1.27 1.27)
				)
			)
		)
		(duplicate_pad_numbers_are_jumpers no)
		(fp_line
			(start -1.63576 -0.8128)
			(end -1.63576 0.8128)
			(stroke
				(width 0.1524)
				(type default)
			)
			(layer "F.SilkS")
		)
		(fp_line
			(start -1.63576 -0.8128)
			(end 1.63576 -0.8128)
			(stroke
				(width 0.1524)
				(type default)
			)
			(layer "F.SilkS")
		)
		(fp_line
			(start 1.63576 -0.8128)
			(end 1.63576 0.8128)
			(stroke
				(width 0.1524)
				(type default)
			)
			(layer "F.SilkS")
		)
		(fp_line
			(start 1.63576 0.8128)
			(end -1.63576 0.8128)
			(stroke
				(width 0.1524)
				(type default)
			)
			(layer "F.SilkS")
		)
		(fp_line
			(start -1.56083 -0.738632)
			(end -1.56083 0.7366)
			(stroke
				(width 0.1)
				(type default)
			)
			(layer "F.Fab")
		)
		(fp_line
			(start -1.56083 0.7366)
			(end -1.524 0.7366)
			(stroke
				(width 0.1)
				(type default)
			)
			(layer "F.Fab")
		)
		(fp_line
			(start -1.524 0.7366)
			(end 1.524 0.7366)
			(stroke
				(width 0.1)
				(type default)
			)
			(layer "F.Fab")
		)
		(fp_line
			(start 1.524 0.7366)
			(end 1.560576 0.7366)
			(stroke
				(width 0.1)
				(type default)
			)
			(layer "F.Fab")
		)
		(fp_line
			(start 1.560576 -0.738632)
			(end -1.56083 -0.738632)
			(stroke
				(width 0.1)
				(type default)
			)
			(layer "F.Fab")
		)
		(fp_line
			(start 1.560576 0.7366)
			(end 1.560576 -0.738632)
			(stroke
				(width 0.1)
				(type default)
			)
			(layer "F.Fab")
		)
		(pad "1" smd rect
			(at -0.94996 0 180)
			(size 1.1176 1.3716)
			(layers "F.Cu" "F.Mask" "F.Paste")
			(net "P1V8_PLL0_PEX1")
		)
		(pad "2" smd rect
			(at 0.94996 0 180)
			(size 1.1176 1.3716)
			(layers "F.Cu" "F.Mask" "F.Paste")
			(net "PCEPLL6_VDDA18_PEX1")
		)
	)
	(footprint ""
		(layer "F.Cu")
		(at 14.618462 -305.87569 90)
		(property "Reference" "PC222"
			(at 0 0 90)
			(layer "F.SilkS")
			(hide yes)
			(effects
				(font
					(size 1.27 1.27)
				)
			)
		)
		(property "Value" ""
			(at 0 0 90)
			(layer "F.Fab")
			(effects
				(font
					(size 1.27 1.27)
				)
			)
		)
		(duplicate_pad_numbers_are_jumpers no)
		(fp_line
			(start 0.7874 -0.4064)
			(end 0.7874 0.4064)
			(stroke
				(width 0.1524)
				(type default)
			)
			(layer "F.SilkS")
		)
		(fp_line
			(start -0.7874 -0.4064)
			(end 0.7874 -0.4064)
			(stroke
				(width 0.1524)
				(type default)
			)
			(layer "F.SilkS")
		)
		(fp_line
			(start 0.7874 0.4064)
			(end -0.7874 0.4064)
			(stroke
				(width 0.1524)
				(type default)
			)
			(layer "F.SilkS")
		)
		(fp_line
			(start -0.7874 0.4064)
			(end -0.7874 -0.4064)
			(stroke
				(width 0.1524)
				(type default)
			)
			(layer "F.SilkS")
		)
		(fp_line
			(start -0.12065 -0.305054)
			(end -0.12065 -0.2794)
			(stroke
				(width 0.1)
				(type default)
			)
			(layer "F.Fab")
		)
		(fp_line
			(start -0.67945 -0.305054)
			(end -0.12065 -0.305054)
			(stroke
				(width 0.1)
				(type default)
			)
			(layer "F.Fab")
		)
		(fp_line
			(start 0.67945 -0.3048)
			(end 0.67945 0.3048)
			(stroke
				(width 0.1)
				(type default)
			)
			(layer "F.Fab")
		)
		(fp_line
			(start 0.12065 -0.3048)
			(end 0.67945 -0.3048)
			(stroke
				(width 0.1)
				(type default)
			)
			(layer "F.Fab")
		)
		(fp_line
			(start 0.12065 -0.2794)
			(end 0.12065 -0.3048)
			(stroke
				(width 0.1)
				(type default)
			)
			(layer "F.Fab")
		)
		(fp_line
			(start -0.12065 -0.2794)
			(end 0.12065 -0.2794)
			(stroke
				(width 0.1)
				(type default)
			)
			(layer "F.Fab")
		)
		(fp_line
			(start 0.120396 0.2794)
			(end -0.12065 0.2794)
			(stroke
				(width 0.1)
				(type default)
			)
			(layer "F.Fab")
		)
		(fp_line
			(start -0.12065 0.2794)
			(end -0.12065 0.3048)
			(stroke
				(width 0.1)
				(type default)
			)
			(layer "F.Fab")
		)
		(fp_line
			(start 0.67945 0.3048)
			(end 0.120396 0.3048)
			(stroke
				(width 0.1)
				(type default)
			)
			(layer "F.Fab")
		)
		(fp_line
			(start 0.120396 0.3048)
			(end 0.120396 0.2794)
			(stroke
				(width 0.1)
				(type default)
			)
			(layer "F.Fab")
		)
		(fp_line
			(start -0.12065 0.3048)
			(end -0.67945 0.3048)
			(stroke
				(width 0.1)
				(type default)
			)
			(layer "F.Fab")
		)
		(fp_line
			(start -0.67945 0.3048)
			(end -0.67945 -0.305054)
			(stroke
				(width 0.1)
				(type default)
			)
			(layer "F.Fab")
		)
		(pad "1" smd circle
			(at -0.40005 0 90)
			(size 0 0)
			(layers "F.Cu" "F.Mask" "F.Paste")
			(net "P1V25_PEX0_REF")
		)
		(pad "2" smd circle
			(at 0.40005 0 90)
			(size 0 0)
			(layers "F.Cu" "F.Mask" "F.Paste")
			(net "SH_P1V25_PEX0_FB_N")
		)
	)
	(footprint ""
		(layer "F.Cu")
		(at 4.872736 -37.795962 -90)
		(property "Reference" "PR6919"
			(at 0 0 270)
			(layer "F.SilkS")
			(hide yes)
			(effects
				(font
					(size 1.27 1.27)
				)
			)
		)
		(property "Value" ""
			(at 0 0 270)
			(layer "F.Fab")
			(effects
				(font
					(size 1.27 1.27)
				)
			)
		)
		(duplicate_pad_numbers_are_jumpers no)
		(fp_line
			(start -0.7874 0.4064)
			(end -0.7874 -0.4064)
			(stroke
				(width 0.1524)
				(type default)
			)
			(layer "F.SilkS")
		)
		(fp_line
			(start 0.7874 0.4064)
			(end -0.7874 0.4064)
			(stroke
				(width 0.1524)
				(type default)
			)
			(layer "F.SilkS")
		)
		(fp_line
			(start -0.7874 -0.4064)
			(end 0.7874 -0.4064)
			(stroke
				(width 0.1524)
				(type default)
			)
			(layer "F.SilkS")
		)
		(fp_line
			(start 0.7874 -0.4064)
			(end 0.7874 0.4064)
			(stroke
				(width 0.1524)
				(type default)
			)
			(layer "F.SilkS")
		)
		(fp_line
			(start -0.67945 0.3048)
			(end -0.67945 -0.305054)
			(stroke
				(width 0.1)
				(type default)
			)
			(layer "F.Fab")
		)
		(fp_line
			(start -0.12065 0.3048)
			(end -0.67945 0.3048)
			(stroke
				(width 0.1)
				(type default)
			)
			(layer "F.Fab")
		)
		(fp_line
			(start 0.120396 0.3048)
			(end 0.120396 0.2794)
			(stroke
				(width 0.1)
				(type default)
			)
			(layer "F.Fab")
		)
		(fp_line
			(start 0.67945 0.3048)
			(end 0.120396 0.3048)
			(stroke
				(width 0.1)
				(type default)
			)
			(layer "F.Fab")
		)
		(fp_line
			(start -0.12065 0.2794)
			(end -0.12065 0.3048)
			(stroke
				(width 0.1)
				(type default)
			)
			(layer "F.Fab")
		)
		(fp_line
			(start 0.120396 0.2794)
			(end -0.12065 0.2794)
			(stroke
				(width 0.1)
				(type default)
			)
			(layer "F.Fab")
		)
		(fp_line
			(start -0.12065 -0.2794)
			(end 0.12065 -0.2794)
			(stroke
				(width 0.1)
				(type default)
			)
			(layer "F.Fab")
		)
		(fp_line
			(start 0.12065 -0.2794)
			(end 0.12065 -0.3048)
			(stroke
				(width 0.1)
				(type default)
			)
			(layer "F.Fab")
		)
		(fp_line
			(start 0.12065 -0.3048)
			(end 0.67945 -0.3048)
			(stroke
				(width 0.1)
				(type default)
			)
			(layer "F.Fab")
		)
		(fp_line
			(start 0.67945 -0.3048)
			(end 0.67945 0.3048)
			(stroke
				(width 0.1)
				(type default)
			)
			(layer "F.Fab")
		)
		(fp_line
			(start -0.67945 -0.305054)
			(end -0.12065 -0.305054)
			(stroke
				(width 0.1)
				(type default)
			)
			(layer "F.Fab")
		)
		(fp_line
			(start -0.12065 -0.305054)
			(end -0.12065 -0.2794)
			(stroke
				(width 0.1)
				(type default)
			)
			(layer "F.Fab")
		)
		(pad "1" smd circle
			(at -0.40005 0 270)
			(size 0 0)
			(layers "F.Cu" "F.Mask" "F.Paste")
			(net "P3V3_SSD0_CO_MODE")
		)
		(pad "2" smd circle
			(at 0.40005 0 270)
			(size 0 0)
			(layers "F.Cu" "F.Mask" "F.Paste")
			(net "GND")
		)
	)
	(footprint ""
		(layer "F.Cu")
		(at 174.596552 -356.244906 90)
		(property "Reference" "C388"
			(at 0 0 90)
			(layer "F.SilkS")
			(hide yes)
			(effects
				(font
					(size 1.27 1.27)
				)
			)
		)
		(property "Value" ""
			(at 0 0 90)
			(layer "F.Fab")
			(effects
				(font
					(size 1.27 1.27)
				)
			)
		)
		(duplicate_pad_numbers_are_jumpers no)
		(fp_line
			(start 0.299974 -0.150114)
			(end 0.299974 0.150114)
			(stroke
				(width 0.1)
				(type default)
			)
			(layer "F.Fab")
		)
		(fp_line
			(start -0.299974 -0.150114)
			(end 0.299974 -0.150114)
			(stroke
				(width 0.1)
				(type default)
			)
			(layer "F.Fab")
		)
		(fp_line
			(start 0.299974 0.150114)
			(end -0.299974 0.150114)
			(stroke
				(width 0.1)
				(type default)
			)
			(layer "F.Fab")
		)
		(fp_line
			(start -0.299974 0.150114)
			(end -0.299974 -0.150114)
			(stroke
				(width 0.1)
				(type default)
			)
			(layer "F.Fab")
		)
		(pad "1" smd rect
			(at -0.2667 0 90)
			(size 0.3048 0.381)
			(layers "F.Cu" "F.Mask" "F.Paste")
			(net "P5E_PEX1_STN7_TX_DP<119>")
		)
		(pad "2" smd rect
			(at 0.2667 0 90)
			(size 0.3048 0.381)
			(layers "F.Cu" "F.Mask" "F.Paste")
			(net "P5E_PEX1_STN7_TX_C_DP<119>")
		)
	)
	(footprint ""
		(layer "F.Cu")
		(at 233.871008 -82.518758 90)
		(property "Reference" "R6603"
			(at 0 0 90)
			(layer "F.SilkS")
			(hide yes)
			(effects
				(font
					(size 1.27 1.27)
				)
			)
		)
		(property "Value" ""
			(at 0 0 90)
			(layer "F.Fab")
			(effects
				(font
					(size 1.27 1.27)
				)
			)
		)
		(duplicate_pad_numbers_are_jumpers no)
		(fp_line
			(start 0.7874 -0.4064)
			(end 0.7874 0.4064)
			(stroke
				(width 0.1524)
				(type default)
			)
			(layer "F.SilkS")
		)
		(fp_line
			(start -0.7874 -0.4064)
			(end 0.003048 -0.4064)
			(stroke
				(width 0.1524)
				(type default)
			)
			(layer "F.SilkS")
		)
		(fp_line
			(start 0.7874 0.4064)
			(end -0.7874 0.4064)
			(stroke
				(width 0.1524)
				(type default)
			)
			(layer "F.SilkS")
		)
		(fp_line
			(start -0.12065 -0.305054)
			(end -0.12065 -0.2794)
			(stroke
				(width 0.1)
				(type default)
			)
			(layer "F.Fab")
		)
		(fp_line
			(start -0.67945 -0.305054)
			(end -0.12065 -0.305054)
			(stroke
				(width 0.1)
				(type default)
			)
			(layer "F.Fab")
		)
		(fp_line
			(start 0.67945 -0.3048)
			(end 0.67945 0.3048)
			(stroke
				(width 0.1)
				(type default)
			)
			(layer "F.Fab")
		)
		(fp_line
			(start 0.12065 -0.3048)
			(end 0.67945 -0.3048)
			(stroke
				(width 0.1)
				(type default)
			)
			(layer "F.Fab")
		)
		(fp_line
			(start 0.12065 -0.2794)
			(end 0.12065 -0.3048)
			(stroke
				(width 0.1)
				(type default)
			)
			(layer "F.Fab")
		)
		(fp_line
			(start -0.12065 -0.2794)
			(end 0.12065 -0.2794)
			(stroke
				(width 0.1)
				(type default)
			)
			(layer "F.Fab")
		)
		(fp_line
			(start 0.120396 0.2794)
			(end -0.12065 0.2794)
			(stroke
				(width 0.1)
				(type default)
			)
			(layer "F.Fab")
		)
		(fp_line
			(start -0.12065 0.2794)
			(end -0.12065 0.3048)
			(stroke
				(width 0.1)
				(type default)
			)
			(layer "F.Fab")
		)
		(fp_line
			(start 0.67945 0.3048)
			(end 0.120396 0.3048)
			(stroke
				(width 0.1)
				(type default)
			)
			(layer "F.Fab")
		)
		(fp_line
			(start 0.120396 0.3048)
			(end 0.120396 0.2794)
			(stroke
				(width 0.1)
				(type default)
			)
			(layer "F.Fab")
		)
		(fp_line
			(start -0.12065 0.3048)
			(end -0.67945 0.3048)
			(stroke
				(width 0.1)
				(type default)
			)
			(layer "F.Fab")
		)
		(fp_line
			(start -0.67945 0.3048)
			(end -0.67945 -0.305054)
			(stroke
				(width 0.1)
				(type default)
			)
			(layer "F.Fab")
		)
		(pad "1" smd rect
			(at -0.40005 0 270)
			(size 0.4572 0.508)
			(layers "F.Cu" "F.Mask" "F.Paste")
			(net "USB2_CP2108_SDB_DP")
		)
		(pad "2" smd rect
			(at 0.40005 0 270)
			(size 0.4572 0.508)
			(layers "F.Cu" "F.Mask" "F.Paste")
			(net "USB2_FT4232_SDB_R_DP")
		)
	)
	(footprint ""
		(layer "F.Cu")
		(at 16.928846 -208.944972 180)
		(property "Reference" "C4416"
			(at 0 0 180)
			(layer "F.SilkS")
			(hide yes)
			(effects
				(font
					(size 1.27 1.27)
				)
			)
		)
		(property "Value" ""
			(at 0 0 180)
			(layer "F.Fab")
			(effects
				(font
					(size 1.27 1.27)
				)
			)
		)
		(duplicate_pad_numbers_are_jumpers no)
		(fp_line
			(start 1.524 0.762)
			(end -1.524 0.762)
			(stroke
				(width 0.1524)
				(type default)
			)
			(layer "F.SilkS")
		)
		(fp_line
			(start 1.524 -0.762)
			(end 1.524 0.762)
			(stroke
				(width 0.1524)
				(type default)
			)
			(layer "F.SilkS")
		)
		(fp_line
			(start -1.524 0.762)
			(end -1.524 -0.762)
			(stroke
				(width 0.1524)
				(type default)
			)
			(layer "F.SilkS")
		)
		(fp_line
			(start -1.524 -0.762)
			(end 1.524 -0.762)
			(stroke
				(width 0.1524)
				(type default)
			)
			(layer "F.SilkS")
		)
		(fp_line
			(start 1.1049 0.724916)
			(end 1.1049 -0.724916)
			(stroke
				(width 0.1)
				(type default)
			)
			(layer "F.Fab")
		)
		(fp_line
			(start 1.1049 -0.724916)
			(end -1.1049 -0.724916)
			(stroke
				(width 0.1)
				(type default)
			)
			(layer "F.Fab")
		)
		(fp_line
			(start -1.1049 0.724916)
			(end 1.1049 0.724916)
			(stroke
				(width 0.1)
				(type default)
			)
			(layer "F.Fab")
		)
		(fp_line
			(start -1.1049 -0.724916)
			(end -1.1049 0.724916)
			(stroke
				(width 0.1)
				(type default)
			)
			(layer "F.Fab")
		)
		(pad "1" smd rect
			(at -0.889 0)
			(size 1.016 1.27)
			(layers "F.Cu" "F.Mask" "F.Paste")
			(net "P1V8_PLL0_PEX0")
		)
		(pad "2" smd rect
			(at 0.889 0)
			(size 1.016 1.27)
			(layers "F.Cu" "F.Mask" "F.Paste")
			(net "GND")
		)
	)
	(footprint ""
		(layer "F.Cu")
		(at 28.1051 -307.084984 45)
		(property "Reference" "R1167"
			(at 0 0 45)
			(layer "F.SilkS")
			(hide yes)
			(effects
				(font
					(size 1.27 1.27)
				)
			)
		)
		(property "Value" ""
			(at 0 0 45)
			(layer "F.Fab")
			(effects
				(font
					(size 1.27 1.27)
				)
			)
		)
		(duplicate_pad_numbers_are_jumpers no)
		(fp_line
			(start -0.787389 -0.406267)
			(end 0.787389 -0.406267)
			(stroke
				(width 0.1524)
				(type default)
			)
			(layer "F.SilkS")
		)
		(fp_line
			(start -0.787389 0.406267)
			(end -0.787389 -0.406267)
			(stroke
				(width 0.1524)
				(type default)
			)
			(layer "F.SilkS")
		)
		(fp_line
			(start 0.787389 -0.406267)
			(end 0.787389 0.406267)
			(stroke
				(width 0.1524)
				(type default)
			)
			(layer "F.SilkS")
		)
		(fp_line
			(start 0.787389 0.406267)
			(end -0.787389 0.406267)
			(stroke
				(width 0.1524)
				(type default)
			)
			(layer "F.SilkS")
		)
		(fp_line
			(start -0.679446 -0.305149)
			(end -0.120695 -0.304969)
			(stroke
				(width 0.1)
				(type default)
			)
			(layer "F.Fab")
		)
		(fp_line
			(start -0.120695 -0.304969)
			(end -0.120695 -0.279466)
			(stroke
				(width 0.1)
				(type default)
			)
			(layer "F.Fab")
		)
		(fp_line
			(start -0.120695 -0.279466)
			(end 0.120695 -0.279466)
			(stroke
				(width 0.1)
				(type default)
			)
			(layer "F.Fab")
		)
		(fp_line
			(start -0.679446 0.30479)
			(end -0.679446 -0.305149)
			(stroke
				(width 0.1)
				(type default)
			)
			(layer "F.Fab")
		)
		(fp_line
			(start 0.120515 -0.30479)
			(end 0.679446 -0.30479)
			(stroke
				(width 0.1)
				(type default)
			)
			(layer "F.Fab")
		)
		(fp_line
			(start 0.120695 -0.279466)
			(end 0.120515 -0.30479)
			(stroke
				(width 0.1)
				(type default)
			)
			(layer "F.Fab")
		)
		(fp_line
			(start -0.120695 0.279466)
			(end -0.120515 0.30479)
			(stroke
				(width 0.1)
				(type default)
			)
			(layer "F.Fab")
		)
		(fp_line
			(start -0.120515 0.30479)
			(end -0.679446 0.30479)
			(stroke
				(width 0.1)
				(type default)
			)
			(layer "F.Fab")
		)
		(fp_line
			(start 0.679446 -0.30479)
			(end 0.679446 0.30479)
			(stroke
				(width 0.1)
				(type default)
			)
			(layer "F.Fab")
		)
		(fp_line
			(start 0.120335 0.279466)
			(end -0.120695 0.279466)
			(stroke
				(width 0.1)
				(type default)
			)
			(layer "F.Fab")
		)
		(fp_line
			(start 0.120515 0.30479)
			(end 0.120335 0.279466)
			(stroke
				(width 0.1)
				(type default)
			)
			(layer "F.Fab")
		)
		(fp_line
			(start 0.679446 0.30479)
			(end 0.120515 0.30479)
			(stroke
				(width 0.1)
				(type default)
			)
			(layer "F.Fab")
		)
		(pad "1" smd circle
			(at -0.40005 0 45)
			(size 0 0)
			(layers "F.Cu" "F.Mask" "F.Paste")
			(net "GND")
		)
		(pad "2" smd circle
			(at 0.40005 0 45)
			(size 0 0)
			(layers "F.Cu" "F.Mask" "F.Paste")
			(net "PEX0_DBG_SEL0")
		)
	)
	(footprint ""
		(layer "F.Cu")
		(at 349.722694 -293.816786 -90)
		(property "Reference" "PC163"
			(at 0 0 270)
			(layer "F.SilkS")
			(hide yes)
			(effects
				(font
					(size 1.27 1.27)
				)
			)
		)
		(property "Value" ""
			(at 0 0 270)
			(layer "F.Fab")
			(effects
				(font
					(size 1.27 1.27)
				)
			)
		)
		(duplicate_pad_numbers_are_jumpers no)
		(fp_line
			(start -0.7874 0.4064)
			(end -0.7874 -0.4064)
			(stroke
				(width 0.1524)
				(type default)
			)
			(layer "F.SilkS")
		)
		(fp_line
			(start 0.7874 0.4064)
			(end -0.7874 0.4064)
			(stroke
				(width 0.1524)
				(type default)
			)
			(layer "F.SilkS")
		)
		(fp_line
			(start -0.7874 -0.4064)
			(end 0.7874 -0.4064)
			(stroke
				(width 0.1524)
				(type default)
			)
			(layer "F.SilkS")
		)
		(fp_line
			(start 0.7874 -0.4064)
			(end 0.7874 0.4064)
			(stroke
				(width 0.1524)
				(type default)
			)
			(layer "F.SilkS")
		)
		(fp_line
			(start -0.67945 0.3048)
			(end -0.67945 -0.305054)
			(stroke
				(width 0.1)
				(type default)
			)
			(layer "F.Fab")
		)
		(fp_line
			(start -0.12065 0.3048)
			(end -0.67945 0.3048)
			(stroke
				(width 0.1)
				(type default)
			)
			(layer "F.Fab")
		)
		(fp_line
			(start 0.120396 0.3048)
			(end 0.120396 0.2794)
			(stroke
				(width 0.1)
				(type default)
			)
			(layer "F.Fab")
		)
		(fp_line
			(start 0.67945 0.3048)
			(end 0.120396 0.3048)
			(stroke
				(width 0.1)
				(type default)
			)
			(layer "F.Fab")
		)
		(fp_line
			(start -0.12065 0.2794)
			(end -0.12065 0.3048)
			(stroke
				(width 0.1)
				(type default)
			)
			(layer "F.Fab")
		)
		(fp_line
			(start 0.120396 0.2794)
			(end -0.12065 0.2794)
			(stroke
				(width 0.1)
				(type default)
			)
			(layer "F.Fab")
		)
		(fp_line
			(start -0.12065 -0.2794)
			(end 0.12065 -0.2794)
			(stroke
				(width 0.1)
				(type default)
			)
			(layer "F.Fab")
		)
		(fp_line
			(start 0.12065 -0.2794)
			(end 0.12065 -0.3048)
			(stroke
				(width 0.1)
				(type default)
			)
			(layer "F.Fab")
		)
		(fp_line
			(start 0.12065 -0.3048)
			(end 0.67945 -0.3048)
			(stroke
				(width 0.1)
				(type default)
			)
			(layer "F.Fab")
		)
		(fp_line
			(start 0.67945 -0.3048)
			(end 0.67945 0.3048)
			(stroke
				(width 0.1)
				(type default)
			)
			(layer "F.Fab")
		)
		(fp_line
			(start -0.67945 -0.305054)
			(end -0.12065 -0.305054)
			(stroke
				(width 0.1)
				(type default)
			)
			(layer "F.Fab")
		)
		(fp_line
			(start -0.12065 -0.305054)
			(end -0.12065 -0.2794)
			(stroke
				(width 0.1)
				(type default)
			)
			(layer "F.Fab")
		)
		(pad "1" smd circle
			(at -0.40005 0 270)
			(size 0 0)
			(layers "F.Cu" "F.Mask" "F.Paste")
			(net "P0V8_PEX2")
		)
		(pad "2" smd circle
			(at 0.40005 0 270)
			(size 0 0)
			(layers "F.Cu" "F.Mask" "F.Paste")
			(net "GND")
		)
	)
	(footprint ""
		(layer "F.Cu")
		(at 80.019398 -153.390346 180)
		(property "Reference" "C4"
			(at 0 0 180)
			(layer "F.SilkS")
			(hide yes)
			(effects
				(font
					(size 1.27 1.27)
				)
			)
		)
		(property "Value" ""
			(at 0 0 180)
			(layer "F.Fab")
			(effects
				(font
					(size 1.27 1.27)
				)
			)
		)
		(duplicate_pad_numbers_are_jumpers no)
		(fp_line
			(start 0.299974 0.150114)
			(end -0.299974 0.150114)
			(stroke
				(width 0.1)
				(type default)
			)
			(layer "F.Fab")
		)
		(fp_line
			(start 0.299974 -0.150114)
			(end 0.299974 0.150114)
			(stroke
				(width 0.1)
				(type default)
			)
			(layer "F.Fab")
		)
		(fp_line
			(start -0.299974 0.150114)
			(end -0.299974 -0.150114)
			(stroke
				(width 0.1)
				(type default)
			)
			(layer "F.Fab")
		)
		(fp_line
			(start -0.299974 -0.150114)
			(end 0.299974 -0.150114)
			(stroke
				(width 0.1)
				(type default)
			)
			(layer "F.Fab")
		)
		(pad "1" smd rect
			(at -0.2667 0 180)
			(size 0.3048 0.381)
			(layers "F.Cu" "F.Mask" "F.Paste")
			(net "P5E_PEX0_STN0_TX_DP<14>")
		)
		(pad "2" smd rect
			(at 0.2667 0 180)
			(size 0.3048 0.381)
			(layers "F.Cu" "F.Mask" "F.Paste")
			(net "P5E_PEX0_STN0_TX_C_DP<14>")
		)
	)
	(footprint ""
		(layer "F.Cu")
		(at 353.174554 -279.101804)
		(property "Reference" "PC171"
			(at 0 0 0)
			(layer "F.SilkS")
			(hide yes)
			(effects
				(font
					(size 1.27 1.27)
				)
			)
		)
		(property "Value" ""
			(at 0 0 0)
			(layer "F.Fab")
			(effects
				(font
					(size 1.27 1.27)
				)
			)
		)
		(duplicate_pad_numbers_are_jumpers no)
		(fp_line
			(start -0.7874 -0.4064)
			(end 0.7874 -0.4064)
			(stroke
				(width 0.1524)
				(type default)
			)
			(layer "F.SilkS")
		)
		(fp_line
			(start -0.7874 0.4064)
			(end -0.7874 -0.4064)
			(stroke
				(width 0.1524)
				(type default)
			)
			(layer "F.SilkS")
		)
		(fp_line
			(start 0.7874 -0.4064)
			(end 0.7874 0.4064)
			(stroke
				(width 0.1524)
				(type default)
			)
			(layer "F.SilkS")
		)
		(fp_line
			(start 0.7874 0.4064)
			(end -0.7874 0.4064)
			(stroke
				(width 0.1524)
				(type default)
			)
			(layer "F.SilkS")
		)
		(fp_line
			(start -0.67945 -0.305054)
			(end -0.12065 -0.305054)
			(stroke
				(width 0.1)
				(type default)
			)
			(layer "F.Fab")
		)
		(fp_line
			(start -0.67945 0.3048)
			(end -0.67945 -0.305054)
			(stroke
				(width 0.1)
				(type default)
			)
			(layer "F.Fab")
		)
		(fp_line
			(start -0.12065 -0.305054)
			(end -0.12065 -0.2794)
			(stroke
				(width 0.1)
				(type default)
			)
			(layer "F.Fab")
		)
		(fp_line
			(start -0.12065 -0.2794)
			(end 0.12065 -0.2794)
			(stroke
				(width 0.1)
				(type default)
			)
			(layer "F.Fab")
		)
		(fp_line
			(start -0.12065 0.2794)
			(end -0.12065 0.3048)
			(stroke
				(width 0.1)
				(type default)
			)
			(layer "F.Fab")
		)
		(fp_line
			(start -0.12065 0.3048)
			(end -0.67945 0.3048)
			(stroke
				(width 0.1)
				(type default)
			)
			(layer "F.Fab")
		)
		(fp_line
			(start 0.120396 0.2794)
			(end -0.12065 0.2794)
			(stroke
				(width 0.1)
				(type default)
			)
			(layer "F.Fab")
		)
		(fp_line
			(start 0.120396 0.3048)
			(end 0.120396 0.2794)
			(stroke
				(width 0.1)
				(type default)
			)
			(layer "F.Fab")
		)
		(fp_line
			(start 0.12065 -0.3048)
			(end 0.67945 -0.3048)
			(stroke
				(width 0.1)
				(type default)
			)
			(layer "F.Fab")
		)
		(fp_line
			(start 0.12065 -0.2794)
			(end 0.12065 -0.3048)
			(stroke
				(width 0.1)
				(type default)
			)
			(layer "F.Fab")
		)
		(fp_line
			(start 0.67945 -0.3048)
			(end 0.67945 0.3048)
			(stroke
				(width 0.1)
				(type default)
			)
			(layer "F.Fab")
		)
		(fp_line
			(start 0.67945 0.3048)
			(end 0.120396 0.3048)
			(stroke
				(width 0.1)
				(type default)
			)
			(layer "F.Fab")
		)
		(pad "1" smd circle
			(at -0.40005 0)
			(size 0 0)
			(layers "F.Cu" "F.Mask" "F.Paste")
			(net "SW_P12V_P0V8_PEX3_FLT")
		)
		(pad "2" smd circle
			(at 0.40005 0)
			(size 0 0)
			(layers "F.Cu" "F.Mask" "F.Paste")
			(net "GND")
		)
	)
	(footprint ""
		(layer "F.Cu")
		(at 322.051934 -289.230816 90)
		(property "Reference" "R3986"
			(at 0 0 90)
			(layer "F.SilkS")
			(hide yes)
			(effects
				(font
					(size 1.27 1.27)
				)
			)
		)
		(property "Value" ""
			(at 0 0 90)
			(layer "F.Fab")
			(effects
				(font
					(size 1.27 1.27)
				)
			)
		)
		(duplicate_pad_numbers_are_jumpers no)
		(fp_line
			(start 0.7874 -0.4064)
			(end 0.7874 0.4064)
			(stroke
				(width 0.1524)
				(type default)
			)
			(layer "F.SilkS")
		)
		(fp_line
			(start -0.7874 -0.4064)
			(end 0.7874 -0.4064)
			(stroke
				(width 0.1524)
				(type default)
			)
			(layer "F.SilkS")
		)
		(fp_line
			(start 0.7874 0.4064)
			(end -0.7874 0.4064)
			(stroke
				(width 0.1524)
				(type default)
			)
			(layer "F.SilkS")
		)
		(fp_line
			(start -0.7874 0.4064)
			(end -0.7874 -0.4064)
			(stroke
				(width 0.1524)
				(type default)
			)
			(layer "F.SilkS")
		)
		(fp_line
			(start -0.12065 -0.305054)
			(end -0.12065 -0.2794)
			(stroke
				(width 0.1)
				(type default)
			)
			(layer "F.Fab")
		)
		(fp_line
			(start -0.67945 -0.305054)
			(end -0.12065 -0.305054)
			(stroke
				(width 0.1)
				(type default)
			)
			(layer "F.Fab")
		)
		(fp_line
			(start 0.67945 -0.3048)
			(end 0.67945 0.3048)
			(stroke
				(width 0.1)
				(type default)
			)
			(layer "F.Fab")
		)
		(fp_line
			(start 0.12065 -0.3048)
			(end 0.67945 -0.3048)
			(stroke
				(width 0.1)
				(type default)
			)
			(layer "F.Fab")
		)
		(fp_line
			(start 0.12065 -0.2794)
			(end 0.12065 -0.3048)
			(stroke
				(width 0.1)
				(type default)
			)
			(layer "F.Fab")
		)
		(fp_line
			(start -0.12065 -0.2794)
			(end 0.12065 -0.2794)
			(stroke
				(width 0.1)
				(type default)
			)
			(layer "F.Fab")
		)
		(fp_line
			(start 0.120396 0.2794)
			(end -0.12065 0.2794)
			(stroke
				(width 0.1)
				(type default)
			)
			(layer "F.Fab")
		)
		(fp_line
			(start -0.12065 0.2794)
			(end -0.12065 0.3048)
			(stroke
				(width 0.1)
				(type default)
			)
			(layer "F.Fab")
		)
		(fp_line
			(start 0.67945 0.3048)
			(end 0.120396 0.3048)
			(stroke
				(width 0.1)
				(type default)
			)
			(layer "F.Fab")
		)
		(fp_line
			(start 0.120396 0.3048)
			(end 0.120396 0.2794)
			(stroke
				(width 0.1)
				(type default)
			)
			(layer "F.Fab")
		)
		(fp_line
			(start -0.12065 0.3048)
			(end -0.67945 0.3048)
			(stroke
				(width 0.1)
				(type default)
			)
			(layer "F.Fab")
		)
		(fp_line
			(start -0.67945 0.3048)
			(end -0.67945 -0.305054)
			(stroke
				(width 0.1)
				(type default)
			)
			(layer "F.Fab")
		)
		(pad "1" smd circle
			(at -0.40005 0 90)
			(size 0 0)
			(layers "F.Cu" "F.Mask" "F.Paste")
			(net "SMB_PEX2_FPGA_SDA")
		)
		(pad "2" smd circle
			(at 0.40005 0 90)
			(size 0 0)
			(layers "F.Cu" "F.Mask" "F.Paste")
			(net "SMB_PEX2_HOST_LS_SDA")
		)
	)
	(footprint ""
		(layer "F.Cu")
		(at 364.28807 -45.704252 90)
		(property "Reference" "R638"
			(at 0 0 90)
			(layer "F.SilkS")
			(hide yes)
			(effects
				(font
					(size 1.27 1.27)
				)
			)
		)
		(property "Value" ""
			(at 0 0 90)
			(layer "F.Fab")
			(effects
				(font
					(size 1.27 1.27)
				)
			)
		)
		(duplicate_pad_numbers_are_jumpers no)
		(fp_line
			(start 3.937508 -1.8796)
			(end -3.937508 -1.8796)
			(stroke
				(width 0.1524)
				(type default)
			)
			(layer "F.SilkS")
		)
		(fp_line
			(start -3.937508 -1.8796)
			(end -3.937508 1.8796)
			(stroke
				(width 0.1524)
				(type default)
			)
			(layer "F.SilkS")
		)
		(fp_line
			(start 3.937508 1.8796)
			(end 3.937508 -1.8796)
			(stroke
				(width 0.1524)
				(type default)
			)
			(layer "F.SilkS")
		)
		(fp_line
			(start -3.937508 1.8796)
			(end 3.937508 1.8796)
			(stroke
				(width 0.1524)
				(type default)
			)
			(layer "F.SilkS")
		)
		(fp_line
			(start 3.275076 -1.674876)
			(end -3.275076 -1.674876)
			(stroke
				(width 0.1)
				(type default)
			)
			(layer "F.Fab")
		)
		(fp_line
			(start -3.275076 -1.674876)
			(end -3.275076 1.674876)
			(stroke
				(width 0.1)
				(type default)
			)
			(layer "F.Fab")
		)
		(fp_line
			(start 3.275076 1.674876)
			(end 3.275076 -1.674876)
			(stroke
				(width 0.1)
				(type default)
			)
			(layer "F.Fab")
		)
		(fp_line
			(start -3.275076 1.674876)
			(end 3.275076 1.674876)
			(stroke
				(width 0.1)
				(type default)
			)
			(layer "F.Fab")
		)
		(pad "1" smd rect
			(at -2.350008 0 90)
			(size 2.921 3.5052)
			(layers "F.Cu" "F.Mask" "F.Paste")
			(net "P12V_SSD12")
		)
		(pad "2" smd rect
			(at 2.350008 0 90)
			(size 2.921 3.5052)
			(layers "F.Cu" "F.Mask" "F.Paste")
			(net "P12V_SSD12_R")
		)
	)
	(footprint ""
		(layer "F.Cu")
		(at 263.654286 -250.070874 -90)
		(property "Reference" "R1340"
			(at 0 0 270)
			(layer "F.SilkS")
			(hide yes)
			(effects
				(font
					(size 1.27 1.27)
				)
			)
		)
		(property "Value" ""
			(at 0 0 270)
			(layer "F.Fab")
			(effects
				(font
					(size 1.27 1.27)
				)
			)
		)
		(duplicate_pad_numbers_are_jumpers no)
		(fp_line
			(start -0.7874 0.4064)
			(end -0.7874 -0.4064)
			(stroke
				(width 0.1524)
				(type default)
			)
			(layer "F.SilkS")
		)
		(fp_line
			(start 0.7874 0.4064)
			(end -0.7874 0.4064)
			(stroke
				(width 0.1524)
				(type default)
			)
			(layer "F.SilkS")
		)
		(fp_line
			(start -0.7874 -0.4064)
			(end 0.7874 -0.4064)
			(stroke
				(width 0.1524)
				(type default)
			)
			(layer "F.SilkS")
		)
		(fp_line
			(start 0.7874 -0.4064)
			(end 0.7874 0.4064)
			(stroke
				(width 0.1524)
				(type default)
			)
			(layer "F.SilkS")
		)
		(fp_line
			(start -0.67945 0.3048)
			(end -0.67945 -0.305054)
			(stroke
				(width 0.1)
				(type default)
			)
			(layer "F.Fab")
		)
		(fp_line
			(start -0.12065 0.3048)
			(end -0.67945 0.3048)
			(stroke
				(width 0.1)
				(type default)
			)
			(layer "F.Fab")
		)
		(fp_line
			(start 0.120396 0.3048)
			(end 0.120396 0.2794)
			(stroke
				(width 0.1)
				(type default)
			)
			(layer "F.Fab")
		)
		(fp_line
			(start 0.67945 0.3048)
			(end 0.120396 0.3048)
			(stroke
				(width 0.1)
				(type default)
			)
			(layer "F.Fab")
		)
		(fp_line
			(start -0.12065 0.2794)
			(end -0.12065 0.3048)
			(stroke
				(width 0.1)
				(type default)
			)
			(layer "F.Fab")
		)
		(fp_line
			(start 0.120396 0.2794)
			(end -0.12065 0.2794)
			(stroke
				(width 0.1)
				(type default)
			)
			(layer "F.Fab")
		)
		(fp_line
			(start -0.12065 -0.2794)
			(end 0.12065 -0.2794)
			(stroke
				(width 0.1)
				(type default)
			)
			(layer "F.Fab")
		)
		(fp_line
			(start 0.12065 -0.2794)
			(end 0.12065 -0.3048)
			(stroke
				(width 0.1)
				(type default)
			)
			(layer "F.Fab")
		)
		(fp_line
			(start 0.12065 -0.3048)
			(end 0.67945 -0.3048)
			(stroke
				(width 0.1)
				(type default)
			)
			(layer "F.Fab")
		)
		(fp_line
			(start 0.67945 -0.3048)
			(end 0.67945 0.3048)
			(stroke
				(width 0.1)
				(type default)
			)
			(layer "F.Fab")
		)
		(fp_line
			(start -0.67945 -0.305054)
			(end -0.12065 -0.305054)
			(stroke
				(width 0.1)
				(type default)
			)
			(layer "F.Fab")
		)
		(fp_line
			(start -0.12065 -0.305054)
			(end -0.12065 -0.2794)
			(stroke
				(width 0.1)
				(type default)
			)
			(layer "F.Fab")
		)
		(pad "1" smd circle
			(at -0.40005 0 270)
			(size 0 0)
			(layers "F.Cu" "F.Mask" "F.Paste")
			(net "PEX2_MODE_SEL4")
		)
		(pad "2" smd circle
			(at 0.40005 0 270)
			(size 0 0)
			(layers "F.Cu" "F.Mask" "F.Paste")
			(net "P1V8_PEX")
		)
	)
	(footprint ""
		(layer "F.Cu")
		(at 309.81142 -71.458074 -90)
		(property "Reference" "PD109"
			(at 4.351274 -2.71145 90)
			(unlocked yes)
			(layer "F.SilkS")
			(effects
				(font
					(size 0.7874 0.5842)
					(thickness 0.1524)
				)
				(justify left)
			)
		)
		(property "Value" ""
			(at 0 0 270)
			(layer "F.Fab")
			(effects
				(font
					(size 1.27 1.27)
				)
			)
		)
		(duplicate_pad_numbers_are_jumpers no)
		(fp_line
			(start -3.656584 1.970024)
			(end 4.240784 1.970024)
			(stroke
				(width 0.1524)
				(type default)
			)
			(layer "F.SilkS")
		)
		(fp_line
			(start 4.240784 1.970024)
			(end 4.240784 -1.970024)
			(stroke
				(width 0.1524)
				(type default)
			)
			(layer "F.SilkS")
		)
		(fp_line
			(start -3.656584 -1.970024)
			(end -3.656584 1.970024)
			(stroke
				(width 0.1524)
				(type default)
			)
			(layer "F.SilkS")
		)
		(fp_line
			(start 4.240784 -1.970024)
			(end -3.656584 -1.970024)
			(stroke
				(width 0.1524)
				(type default)
			)
			(layer "F.SilkS")
		)
		(fp_poly
			(pts
				(xy 3.580384 1.970024) (xy 3.580384 -1.970024) (xy 4.240784 -1.970024) (xy 4.240784 1.970024)
			)
			(stroke
				(width 0)
				(type default)
			)
			(fill yes)
			(layer "F.SilkS")
		)
		(fp_line
			(start -2.3749 1.970024)
			(end 2.3749 1.970024)
			(stroke
				(width 0.1)
				(type default)
			)
			(layer "F.Fab")
		)
		(fp_line
			(start 2.3749 1.970024)
			(end 2.3749 -1.970024)
			(stroke
				(width 0.1)
				(type default)
			)
			(layer "F.Fab")
		)
		(fp_line
			(start -2.3749 -1.970024)
			(end -2.3749 1.970024)
			(stroke
				(width 0.1)
				(type default)
			)
			(layer "F.Fab")
		)
		(fp_line
			(start 2.3749 -1.970024)
			(end -2.3749 -1.970024)
			(stroke
				(width 0.1)
				(type default)
			)
			(layer "F.Fab")
		)
		(fp_text user "+"
			(at -4.9784 -0.23495 270)
			(unlocked yes)
			(layer "F.Fab")
			(effects
				(font
					(size 1.905 1.4224)
					(thickness 0.1524)
				)
				(justify left)
			)
		)
		(fp_text user "-"
			(at 4.1656 -0.23495 270)
			(unlocked yes)
			(layer "F.Fab")
			(effects
				(font
					(size 1.905 1.4224)
					(thickness 0.1524)
				)
				(justify left)
			)
		)
		(pad "A" smd rect
			(at -2.450084 0 270)
			(size 2.159 2.2606)
			(layers "F.Cu" "F.Mask" "F.Paste")
			(net "GND")
		)
		(pad "C" smd rect
			(at 2.450084 0 270)
			(size 2.159 2.2606)
			(layers "F.Cu" "F.Mask" "F.Paste")
			(net "P12V_AUX")
		)
	)
	(footprint ""
		(layer "F.Cu")
		(at 352.232214 -142.494)
		(property "Reference" "R4839"
			(at 0 0 0)
			(layer "F.SilkS")
			(hide yes)
			(effects
				(font
					(size 1.27 1.27)
				)
			)
		)
		(property "Value" ""
			(at 0 0 0)
			(layer "F.Fab")
			(effects
				(font
					(size 1.27 1.27)
				)
			)
		)
		(duplicate_pad_numbers_are_jumpers no)
		(fp_line
			(start -0.7874 -0.4064)
			(end 0.7874 -0.4064)
			(stroke
				(width 0.1524)
				(type default)
			)
			(layer "F.SilkS")
		)
		(fp_line
			(start -0.7874 0.4064)
			(end -0.7874 -0.4064)
			(stroke
				(width 0.1524)
				(type default)
			)
			(layer "F.SilkS")
		)
		(fp_line
			(start 0.7874 -0.4064)
			(end 0.7874 0.4064)
			(stroke
				(width 0.1524)
				(type default)
			)
			(layer "F.SilkS")
		)
		(fp_line
			(start 0.7874 0.4064)
			(end -0.7874 0.4064)
			(stroke
				(width 0.1524)
				(type default)
			)
			(layer "F.SilkS")
		)
		(fp_line
			(start -0.67945 -0.305054)
			(end -0.12065 -0.305054)
			(stroke
				(width 0.1)
				(type default)
			)
			(layer "F.Fab")
		)
		(fp_line
			(start -0.67945 0.3048)
			(end -0.67945 -0.305054)
			(stroke
				(width 0.1)
				(type default)
			)
			(layer "F.Fab")
		)
		(fp_line
			(start -0.12065 -0.305054)
			(end -0.12065 -0.2794)
			(stroke
				(width 0.1)
				(type default)
			)
			(layer "F.Fab")
		)
		(fp_line
			(start -0.12065 -0.2794)
			(end 0.12065 -0.2794)
			(stroke
				(width 0.1)
				(type default)
			)
			(layer "F.Fab")
		)
		(fp_line
			(start -0.12065 0.2794)
			(end -0.12065 0.3048)
			(stroke
				(width 0.1)
				(type default)
			)
			(layer "F.Fab")
		)
		(fp_line
			(start -0.12065 0.3048)
			(end -0.67945 0.3048)
			(stroke
				(width 0.1)
				(type default)
			)
			(layer "F.Fab")
		)
		(fp_line
			(start 0.120396 0.2794)
			(end -0.12065 0.2794)
			(stroke
				(width 0.1)
				(type default)
			)
			(layer "F.Fab")
		)
		(fp_line
			(start 0.120396 0.3048)
			(end 0.120396 0.2794)
			(stroke
				(width 0.1)
				(type default)
			)
			(layer "F.Fab")
		)
		(fp_line
			(start 0.12065 -0.3048)
			(end 0.67945 -0.3048)
			(stroke
				(width 0.1)
				(type default)
			)
			(layer "F.Fab")
		)
		(fp_line
			(start 0.12065 -0.2794)
			(end 0.12065 -0.3048)
			(stroke
				(width 0.1)
				(type default)
			)
			(layer "F.Fab")
		)
		(fp_line
			(start 0.67945 -0.3048)
			(end 0.67945 0.3048)
			(stroke
				(width 0.1)
				(type default)
			)
			(layer "F.Fab")
		)
		(fp_line
			(start 0.67945 0.3048)
			(end 0.120396 0.3048)
			(stroke
				(width 0.1)
				(type default)
			)
			(layer "F.Fab")
		)
		(pad "1" smd circle
			(at -0.40005 0)
			(size 0 0)
			(layers "F.Cu" "F.Mask" "F.Paste")
			(net "PRSNT_NIC7_FPGA_PCA9555_N")
		)
		(pad "2" smd circle
			(at 0.40005 0)
			(size 0 0)
			(layers "F.Cu" "F.Mask" "F.Paste")
			(net "PRSNT_NIC7_FPGA_R_N")
		)
	)
	(footprint ""
		(layer "F.Cu")
		(at 196.595238 -35.48253)
		(property "Reference" "U388"
			(at -2.588768 0.78613 90)
			(unlocked yes)
			(layer "F.SilkS")
			(effects
				(font
					(size 0.7874 0.5842)
					(thickness 0.1524)
				)
				(justify left)
			)
		)
		(property "Value" ""
			(at 0 0 0)
			(layer "F.Fab")
			(effects
				(font
					(size 1.27 1.27)
				)
			)
		)
		(duplicate_pad_numbers_are_jumpers no)
		(fp_line
			(start -1.3462 -1.1938)
			(end -1.3462 1.1684)
			(stroke
				(width 0.1524)
				(type default)
			)
			(layer "F.SilkS")
		)
		(fp_line
			(start -1.3462 1.1938)
			(end 1.3462 1.1938)
			(stroke
				(width 0.1524)
				(type default)
			)
			(layer "F.SilkS")
		)
		(fp_line
			(start 1.3462 -1.1938)
			(end -1.3462 -1.1938)
			(stroke
				(width 0.1524)
				(type default)
			)
			(layer "F.SilkS")
		)
		(fp_line
			(start 1.3462 1.1938)
			(end 1.3462 -1.1938)
			(stroke
				(width 0.1524)
				(type default)
			)
			(layer "F.SilkS")
		)
		(fp_poly
			(pts
				(xy -1.447038 -0.760476) (xy -2.052066 -0.457962) (xy -2.052066 -1.06299)
			)
			(stroke
				(width 0)
				(type default)
			)
			(fill yes)
			(layer "F.SilkS")
		)
		(fp_line
			(start -0.674878 -1.124966)
			(end -0.674878 1.124966)
			(stroke
				(width 0.1)
				(type default)
			)
			(layer "F.Fab")
		)
		(fp_line
			(start -0.674878 1.124966)
			(end 0.674878 1.124966)
			(stroke
				(width 0.1)
				(type default)
			)
			(layer "F.Fab")
		)
		(fp_line
			(start 0.674878 -1.124966)
			(end -0.674878 -1.124966)
			(stroke
				(width 0.1)
				(type default)
			)
			(layer "F.Fab")
		)
		(fp_line
			(start 0.674878 1.124966)
			(end 0.674878 -1.124966)
			(stroke
				(width 0.1)
				(type default)
			)
			(layer "F.Fab")
		)
		(fp_poly
			(pts
				(xy -1.447038 -0.760476) (xy -2.052066 -0.457962) (xy -2.052066 -1.06299)
			)
			(stroke
				(width 0)
				(type default)
			)
			(fill yes)
			(layer "F.Fab")
		)
		(pad "1" smd rect
			(at -0.899922 -0.750062)
			(size 0.6096 0.6096)
			(layers "F.Cu" "F.Mask" "F.Paste")
			(net "PWRGD_P3V3_SSD7_R")
		)
		(pad "2" smd rect
			(at -0.899922 0 90)
			(size 0.4064 0.6096)
			(layers "F.Cu" "F.Mask" "F.Paste")
			(net "RST_SMB_SSD7_N")
		)
		(pad "3" smd rect
			(at -0.899922 0.750062)
			(size 0.6096 0.6096)
			(layers "F.Cu" "F.Mask" "F.Paste")
			(net "GND")
		)
		(pad "4" smd rect
			(at 0.899922 0.750062)
			(size 0.6096 0.6096)
			(layers "F.Cu" "F.Mask" "F.Paste")
			(net "RST_SMB_SSD7_ISO_N")
		)
		(pad "5" smd rect
			(at 0.899922 -0.750062)
			(size 0.6096 0.6096)
			(layers "F.Cu" "F.Mask" "F.Paste")
			(net "P3V3_AUX")
		)
	)
	(footprint ""
		(layer "F.Cu")
		(at 117.700298 -72.700134)
		(property "Reference" "H49"
			(at -4.721606 -5.20573 0)
			(unlocked yes)
			(layer "F.SilkS")
			(effects
				(font
					(size 0.7874 0.5842)
					(thickness 0.1524)
				)
				(justify left)
			)
		)
		(property "Value" ""
			(at 0 0 0)
			(layer "F.Fab")
			(effects
				(font
					(size 1.27 1.27)
				)
			)
		)
		(duplicate_pad_numbers_are_jumpers no)
		(pad "1" thru_hole circle
			(at 0 0)
			(size 10.0076 10.0076)
			(drill 5.6134)
			(layers "*.Cu" "*.Mask")
			(remove_unused_layers no)
			(net "GND")
			(clearance -1.9431)
		)
	)
	(footprint ""
		(layer "F.Cu")
		(at 220.36786 -52.035456 180)
		(property "Reference" "R868"
			(at 0 0 180)
			(layer "F.SilkS")
			(hide yes)
			(effects
				(font
					(size 1.27 1.27)
				)
			)
		)
		(property "Value" ""
			(at 0 0 180)
			(layer "F.Fab")
			(effects
				(font
					(size 1.27 1.27)
				)
			)
		)
		(duplicate_pad_numbers_are_jumpers no)
		(fp_line
			(start 0.7874 0.4064)
			(end -0.7874 0.4064)
			(stroke
				(width 0.1524)
				(type default)
			)
			(layer "F.SilkS")
		)
		(fp_line
			(start 0.7874 -0.4064)
			(end 0.7874 0.4064)
			(stroke
				(width 0.1524)
				(type default)
			)
			(layer "F.SilkS")
		)
		(fp_line
			(start -0.7874 0.4064)
			(end -0.7874 -0.4064)
			(stroke
				(width 0.1524)
				(type default)
			)
			(layer "F.SilkS")
		)
		(fp_line
			(start -0.7874 -0.4064)
			(end 0.7874 -0.4064)
			(stroke
				(width 0.1524)
				(type default)
			)
			(layer "F.SilkS")
		)
		(fp_line
			(start 0.67945 0.3048)
			(end 0.120396 0.3048)
			(stroke
				(width 0.1)
				(type default)
			)
			(layer "F.Fab")
		)
		(fp_line
			(start 0.67945 -0.3048)
			(end 0.67945 0.3048)
			(stroke
				(width 0.1)
				(type default)
			)
			(layer "F.Fab")
		)
		(fp_line
			(start 0.12065 -0.2794)
			(end 0.12065 -0.3048)
			(stroke
				(width 0.1)
				(type default)
			)
			(layer "F.Fab")
		)
		(fp_line
			(start 0.12065 -0.3048)
			(end 0.67945 -0.3048)
			(stroke
				(width 0.1)
				(type default)
			)
			(layer "F.Fab")
		)
		(fp_line
			(start 0.120396 0.3048)
			(end 0.120396 0.2794)
			(stroke
				(width 0.1)
				(type default)
			)
			(layer "F.Fab")
		)
		(fp_line
			(start 0.120396 0.2794)
			(end -0.12065 0.2794)
			(stroke
				(width 0.1)
				(type default)
			)
			(layer "F.Fab")
		)
		(fp_line
			(start -0.12065 0.3048)
			(end -0.67945 0.3048)
			(stroke
				(width 0.1)
				(type default)
			)
			(layer "F.Fab")
		)
		(fp_line
			(start -0.12065 0.2794)
			(end -0.12065 0.3048)
			(stroke
				(width 0.1)
				(type default)
			)
			(layer "F.Fab")
		)
		(fp_line
			(start -0.12065 -0.2794)
			(end 0.12065 -0.2794)
			(stroke
				(width 0.1)
				(type default)
			)
			(layer "F.Fab")
		)
		(fp_line
			(start -0.12065 -0.305054)
			(end -0.12065 -0.2794)
			(stroke
				(width 0.1)
				(type default)
			)
			(layer "F.Fab")
		)
		(fp_line
			(start -0.67945 0.3048)
			(end -0.67945 -0.305054)
			(stroke
				(width 0.1)
				(type default)
			)
			(layer "F.Fab")
		)
		(fp_line
			(start -0.67945 -0.305054)
			(end -0.12065 -0.305054)
			(stroke
				(width 0.1)
				(type default)
			)
			(layer "F.Fab")
		)
		(pad "1" smd circle
			(at -0.40005 0 180)
			(size 0 0)
			(layers "F.Cu" "F.Mask" "F.Paste")
			(net "P3V3_AUX")
		)
		(pad "2" smd circle
			(at 0.40005 0 180)
			(size 0 0)
			(layers "F.Cu" "F.Mask" "F.Paste")
			(net "PWRGD_P12V_SSD7")
		)
	)
	(footprint ""
		(layer "F.Cu")
		(at 418.596572 -343.952322 90)
		(property "Reference" "C2447"
			(at 0 0 90)
			(layer "F.SilkS")
			(hide yes)
			(effects
				(font
					(size 1.27 1.27)
				)
			)
		)
		(property "Value" ""
			(at 0 0 90)
			(layer "F.Fab")
			(effects
				(font
					(size 1.27 1.27)
				)
			)
		)
		(duplicate_pad_numbers_are_jumpers no)
		(fp_line
			(start 0.299974 -0.150114)
			(end 0.299974 0.150114)
			(stroke
				(width 0.1)
				(type default)
			)
			(layer "F.Fab")
		)
		(fp_line
			(start -0.299974 -0.150114)
			(end 0.299974 -0.150114)
			(stroke
				(width 0.1)
				(type default)
			)
			(layer "F.Fab")
		)
		(fp_line
			(start 0.299974 0.150114)
			(end -0.299974 0.150114)
			(stroke
				(width 0.1)
				(type default)
			)
			(layer "F.Fab")
		)
		(fp_line
			(start -0.299974 0.150114)
			(end -0.299974 -0.150114)
			(stroke
				(width 0.1)
				(type default)
			)
			(layer "F.Fab")
		)
		(pad "1" smd rect
			(at -0.2667 0 90)
			(size 0.3048 0.381)
			(layers "F.Cu" "F.Mask" "F.Paste")
			(net "P5E_PEX3_STN4_TX_DP<75>")
		)
		(pad "2" smd rect
			(at 0.2667 0 90)
			(size 0.3048 0.381)
			(layers "F.Cu" "F.Mask" "F.Paste")
			(net "P5E_PEX3_STN4_TX_C_DP<75>")
		)
	)
	(footprint ""
		(layer "F.Cu")
		(at 58.686192 -387.750812)
		(property "Reference" "R1829"
			(at 0 0 0)
			(layer "F.SilkS")
			(hide yes)
			(effects
				(font
					(size 1.27 1.27)
				)
			)
		)
		(property "Value" ""
			(at 0 0 0)
			(layer "F.Fab")
			(effects
				(font
					(size 1.27 1.27)
				)
			)
		)
		(duplicate_pad_numbers_are_jumpers no)
		(fp_line
			(start -0.7874 -0.4064)
			(end 0.7874 -0.4064)
			(stroke
				(width 0.1524)
				(type default)
			)
			(layer "F.SilkS")
		)
		(fp_line
			(start -0.7874 0.4064)
			(end -0.7874 -0.4064)
			(stroke
				(width 0.1524)
				(type default)
			)
			(layer "F.SilkS")
		)
		(fp_line
			(start 0.7874 -0.4064)
			(end 0.7874 0.4064)
			(stroke
				(width 0.1524)
				(type default)
			)
			(layer "F.SilkS")
		)
		(fp_line
			(start 0.7874 0.4064)
			(end -0.7874 0.4064)
			(stroke
				(width 0.1524)
				(type default)
			)
			(layer "F.SilkS")
		)
		(fp_line
			(start -0.67945 -0.305054)
			(end -0.12065 -0.305054)
			(stroke
				(width 0.1)
				(type default)
			)
			(layer "F.Fab")
		)
		(fp_line
			(start -0.67945 0.3048)
			(end -0.67945 -0.305054)
			(stroke
				(width 0.1)
				(type default)
			)
			(layer "F.Fab")
		)
		(fp_line
			(start -0.12065 -0.305054)
			(end -0.12065 -0.2794)
			(stroke
				(width 0.1)
				(type default)
			)
			(layer "F.Fab")
		)
		(fp_line
			(start -0.12065 -0.2794)
			(end 0.12065 -0.2794)
			(stroke
				(width 0.1)
				(type default)
			)
			(layer "F.Fab")
		)
		(fp_line
			(start -0.12065 0.2794)
			(end -0.12065 0.3048)
			(stroke
				(width 0.1)
				(type default)
			)
			(layer "F.Fab")
		)
		(fp_line
			(start -0.12065 0.3048)
			(end -0.67945 0.3048)
			(stroke
				(width 0.1)
				(type default)
			)
			(layer "F.Fab")
		)
		(fp_line
			(start 0.120396 0.2794)
			(end -0.12065 0.2794)
			(stroke
				(width 0.1)
				(type default)
			)
			(layer "F.Fab")
		)
		(fp_line
			(start 0.120396 0.3048)
			(end 0.120396 0.2794)
			(stroke
				(width 0.1)
				(type default)
			)
			(layer "F.Fab")
		)
		(fp_line
			(start 0.12065 -0.3048)
			(end 0.67945 -0.3048)
			(stroke
				(width 0.1)
				(type default)
			)
			(layer "F.Fab")
		)
		(fp_line
			(start 0.12065 -0.2794)
			(end 0.12065 -0.3048)
			(stroke
				(width 0.1)
				(type default)
			)
			(layer "F.Fab")
		)
		(fp_line
			(start 0.67945 -0.3048)
			(end 0.67945 0.3048)
			(stroke
				(width 0.1)
				(type default)
			)
			(layer "F.Fab")
		)
		(fp_line
			(start 0.67945 0.3048)
			(end 0.120396 0.3048)
			(stroke
				(width 0.1)
				(type default)
			)
			(layer "F.Fab")
		)
		(pad "1" smd circle
			(at -0.40005 0)
			(size 0 0)
			(layers "F.Cu" "F.Mask" "F.Paste")
			(net "GPU_PWR_BRAKE_R_N")
		)
		(pad "2" smd circle
			(at 0.40005 0)
			(size 0 0)
			(layers "F.Cu" "F.Mask" "F.Paste")
			(net "GPU_PWR_BRAKE_N")
		)
	)
	(footprint ""
		(layer "F.Cu")
		(at 334.227932 -275.813774 180)
		(property "Reference" "PC6617"
			(at 0 0 180)
			(layer "F.SilkS")
			(hide yes)
			(effects
				(font
					(size 1.27 1.27)
				)
			)
		)
		(property "Value" ""
			(at 0 0 180)
			(layer "F.Fab")
			(effects
				(font
					(size 1.27 1.27)
				)
			)
		)
		(duplicate_pad_numbers_are_jumpers no)
		(fp_line
			(start 1.524 0.762)
			(end -1.524 0.762)
			(stroke
				(width 0.1524)
				(type default)
			)
			(layer "F.SilkS")
		)
		(fp_line
			(start 1.524 -0.762)
			(end 1.524 0.762)
			(stroke
				(width 0.1524)
				(type default)
			)
			(layer "F.SilkS")
		)
		(fp_line
			(start -1.524 0.762)
			(end -1.524 -0.762)
			(stroke
				(width 0.1524)
				(type default)
			)
			(layer "F.SilkS")
		)
		(fp_line
			(start -1.524 -0.762)
			(end 1.524 -0.762)
			(stroke
				(width 0.1524)
				(type default)
			)
			(layer "F.SilkS")
		)
		(fp_line
			(start 1.1049 0.724916)
			(end 1.1049 -0.724916)
			(stroke
				(width 0.1)
				(type default)
			)
			(layer "F.Fab")
		)
		(fp_line
			(start 1.1049 -0.724916)
			(end -1.1049 -0.724916)
			(stroke
				(width 0.1)
				(type default)
			)
			(layer "F.Fab")
		)
		(fp_line
			(start -1.1049 0.724916)
			(end 1.1049 0.724916)
			(stroke
				(width 0.1)
				(type default)
			)
			(layer "F.Fab")
		)
		(fp_line
			(start -1.1049 -0.724916)
			(end -1.1049 0.724916)
			(stroke
				(width 0.1)
				(type default)
			)
			(layer "F.Fab")
		)
		(pad "1" smd rect
			(at -0.889 0)
			(size 1.016 1.27)
			(layers "F.Cu" "F.Mask" "F.Paste")
			(net "SW_P12V_P0V8_PEX2_FLT")
		)
		(pad "2" smd rect
			(at 0.889 0)
			(size 1.016 1.27)
			(layers "F.Cu" "F.Mask" "F.Paste")
			(net "GND")
		)
	)
	(footprint ""
		(layer "F.Cu")
		(at 427.42612 -37.929566 90)
		(property "Reference" "R5585"
			(at 0 0 90)
			(layer "F.SilkS")
			(hide yes)
			(effects
				(font
					(size 1.27 1.27)
				)
			)
		)
		(property "Value" ""
			(at 0 0 90)
			(layer "F.Fab")
			(effects
				(font
					(size 1.27 1.27)
				)
			)
		)
		(duplicate_pad_numbers_are_jumpers no)
		(fp_line
			(start 0.7874 -0.4064)
			(end 0.7874 0.4064)
			(stroke
				(width 0.1524)
				(type default)
			)
			(layer "F.SilkS")
		)
		(fp_line
			(start -0.7874 -0.4064)
			(end 0.7874 -0.4064)
			(stroke
				(width 0.1524)
				(type default)
			)
			(layer "F.SilkS")
		)
		(fp_line
			(start 0.7874 0.4064)
			(end -0.7874 0.4064)
			(stroke
				(width 0.1524)
				(type default)
			)
			(layer "F.SilkS")
		)
		(fp_line
			(start -0.7874 0.4064)
			(end -0.7874 -0.4064)
			(stroke
				(width 0.1524)
				(type default)
			)
			(layer "F.SilkS")
		)
		(fp_line
			(start -0.12065 -0.305054)
			(end -0.12065 -0.2794)
			(stroke
				(width 0.1)
				(type default)
			)
			(layer "F.Fab")
		)
		(fp_line
			(start -0.67945 -0.305054)
			(end -0.12065 -0.305054)
			(stroke
				(width 0.1)
				(type default)
			)
			(layer "F.Fab")
		)
		(fp_line
			(start 0.67945 -0.3048)
			(end 0.67945 0.3048)
			(stroke
				(width 0.1)
				(type default)
			)
			(layer "F.Fab")
		)
		(fp_line
			(start 0.12065 -0.3048)
			(end 0.67945 -0.3048)
			(stroke
				(width 0.1)
				(type default)
			)
			(layer "F.Fab")
		)
		(fp_line
			(start 0.12065 -0.2794)
			(end 0.12065 -0.3048)
			(stroke
				(width 0.1)
				(type default)
			)
			(layer "F.Fab")
		)
		(fp_line
			(start -0.12065 -0.2794)
			(end 0.12065 -0.2794)
			(stroke
				(width 0.1)
				(type default)
			)
			(layer "F.Fab")
		)
		(fp_line
			(start 0.120396 0.2794)
			(end -0.12065 0.2794)
			(stroke
				(width 0.1)
				(type default)
			)
			(layer "F.Fab")
		)
		(fp_line
			(start -0.12065 0.2794)
			(end -0.12065 0.3048)
			(stroke
				(width 0.1)
				(type default)
			)
			(layer "F.Fab")
		)
		(fp_line
			(start 0.67945 0.3048)
			(end 0.120396 0.3048)
			(stroke
				(width 0.1)
				(type default)
			)
			(layer "F.Fab")
		)
		(fp_line
			(start 0.120396 0.3048)
			(end 0.120396 0.2794)
			(stroke
				(width 0.1)
				(type default)
			)
			(layer "F.Fab")
		)
		(fp_line
			(start -0.12065 0.3048)
			(end -0.67945 0.3048)
			(stroke
				(width 0.1)
				(type default)
			)
			(layer "F.Fab")
		)
		(fp_line
			(start -0.67945 0.3048)
			(end -0.67945 -0.305054)
			(stroke
				(width 0.1)
				(type default)
			)
			(layer "F.Fab")
		)
		(pad "1" smd circle
			(at -0.40005 0 90)
			(size 0 0)
			(layers "F.Cu" "F.Mask" "F.Paste")
			(net "SSD15_AUX_P3V3_EN_R")
		)
		(pad "2" smd circle
			(at 0.40005 0 90)
			(size 0 0)
			(layers "F.Cu" "F.Mask" "F.Paste")
			(net "SSD15_AUX_P3V3_EN")
		)
	)
	(footprint ""
		(layer "F.Cu")
		(at 76.273914 -26.31186 -90)
		(property "Reference" "U400"
			(at -0.00254 -2.264156 90)
			(unlocked yes)
			(layer "F.SilkS")
			(effects
				(font
					(size 0.7874 0.5842)
					(thickness 0.1524)
				)
			)
		)
		(property "Value" ""
			(at 0 0 270)
			(layer "F.Fab")
			(effects
				(font
					(size 1.27 1.27)
				)
			)
		)
		(duplicate_pad_numbers_are_jumpers no)
		(fp_line
			(start -1.949958 1.610106)
			(end -1.949958 -1.610106)
			(stroke
				(width 0.1524)
				(type default)
			)
			(layer "F.SilkS")
		)
		(fp_line
			(start 1.949958 1.610106)
			(end -1.949958 1.610106)
			(stroke
				(width 0.1524)
				(type default)
			)
			(layer "F.SilkS")
		)
		(fp_line
			(start 1.949958 -1.560068)
			(end 1.949958 1.610106)
			(stroke
				(width 0.1524)
				(type default)
			)
			(layer "F.SilkS")
		)
		(fp_line
			(start -1.949958 -1.610106)
			(end 1.949958 -1.610106)
			(stroke
				(width 0.1524)
				(type default)
			)
			(layer "F.SilkS")
		)
		(fp_line
			(start -0.750062 1.560068)
			(end -0.750062 -1.560068)
			(stroke
				(width 0.1)
				(type default)
			)
			(layer "F.Fab")
		)
		(fp_line
			(start 0.750062 1.560068)
			(end -0.750062 1.560068)
			(stroke
				(width 0.1)
				(type default)
			)
			(layer "F.Fab")
		)
		(fp_line
			(start -0.750062 -1.560068)
			(end 0.750062 -1.560068)
			(stroke
				(width 0.1)
				(type default)
			)
			(layer "F.Fab")
		)
		(fp_line
			(start 0.750062 -1.560068)
			(end 0.750062 1.560068)
			(stroke
				(width 0.1)
				(type default)
			)
			(layer "F.Fab")
		)
		(pad "D" smd rect
			(at 1.100074 0 180)
			(size 1.016 1.4224)
			(layers "F.Cu" "F.Mask" "F.Paste")
			(net "SSD2_LED_ISO_N")
		)
		(pad "G" smd rect
			(at -1.100074 -0.94996 180)
			(size 1.016 1.4224)
			(layers "F.Cu" "F.Mask" "F.Paste")
			(net "SSD2_LED_R")
		)
		(pad "S" smd rect
			(at -1.100074 0.94996 180)
			(size 1.016 1.4224)
			(layers "F.Cu" "F.Mask" "F.Paste")
			(net "GND")
		)
	)
	(footprint ""
		(layer "F.Cu")
		(at 207.376268 -297.46448 180)
		(property "Reference" "R3942"
			(at 0 0 180)
			(layer "F.SilkS")
			(hide yes)
			(effects
				(font
					(size 1.27 1.27)
				)
			)
		)
		(property "Value" ""
			(at 0 0 180)
			(layer "F.Fab")
			(effects
				(font
					(size 1.27 1.27)
				)
			)
		)
		(duplicate_pad_numbers_are_jumpers no)
		(fp_line
			(start 0.7874 0.4064)
			(end -0.7874 0.4064)
			(stroke
				(width 0.1524)
				(type default)
			)
			(layer "F.SilkS")
		)
		(fp_line
			(start 0.7874 -0.4064)
			(end 0.7874 0.4064)
			(stroke
				(width 0.1524)
				(type default)
			)
			(layer "F.SilkS")
		)
		(fp_line
			(start -0.7874 0.4064)
			(end -0.7874 -0.4064)
			(stroke
				(width 0.1524)
				(type default)
			)
			(layer "F.SilkS")
		)
		(fp_line
			(start -0.7874 -0.4064)
			(end 0.7874 -0.4064)
			(stroke
				(width 0.1524)
				(type default)
			)
			(layer "F.SilkS")
		)
		(fp_line
			(start 0.67945 0.3048)
			(end 0.120396 0.3048)
			(stroke
				(width 0.1)
				(type default)
			)
			(layer "F.Fab")
		)
		(fp_line
			(start 0.67945 -0.3048)
			(end 0.67945 0.3048)
			(stroke
				(width 0.1)
				(type default)
			)
			(layer "F.Fab")
		)
		(fp_line
			(start 0.12065 -0.2794)
			(end 0.12065 -0.3048)
			(stroke
				(width 0.1)
				(type default)
			)
			(layer "F.Fab")
		)
		(fp_line
			(start 0.12065 -0.3048)
			(end 0.67945 -0.3048)
			(stroke
				(width 0.1)
				(type default)
			)
			(layer "F.Fab")
		)
		(fp_line
			(start 0.120396 0.3048)
			(end 0.120396 0.2794)
			(stroke
				(width 0.1)
				(type default)
			)
			(layer "F.Fab")
		)
		(fp_line
			(start 0.120396 0.2794)
			(end -0.12065 0.2794)
			(stroke
				(width 0.1)
				(type default)
			)
			(layer "F.Fab")
		)
		(fp_line
			(start -0.12065 0.3048)
			(end -0.67945 0.3048)
			(stroke
				(width 0.1)
				(type default)
			)
			(layer "F.Fab")
		)
		(fp_line
			(start -0.12065 0.2794)
			(end -0.12065 0.3048)
			(stroke
				(width 0.1)
				(type default)
			)
			(layer "F.Fab")
		)
		(fp_line
			(start -0.12065 -0.2794)
			(end 0.12065 -0.2794)
			(stroke
				(width 0.1)
				(type default)
			)
			(layer "F.Fab")
		)
		(fp_line
			(start -0.12065 -0.305054)
			(end -0.12065 -0.2794)
			(stroke
				(width 0.1)
				(type default)
			)
			(layer "F.Fab")
		)
		(fp_line
			(start -0.67945 0.3048)
			(end -0.67945 -0.305054)
			(stroke
				(width 0.1)
				(type default)
			)
			(layer "F.Fab")
		)
		(fp_line
			(start -0.67945 -0.305054)
			(end -0.12065 -0.305054)
			(stroke
				(width 0.1)
				(type default)
			)
			(layer "F.Fab")
		)
		(pad "1" smd circle
			(at -0.40005 0 180)
			(size 0 0)
			(layers "F.Cu" "F.Mask" "F.Paste")
			(net "SMB_PEX1_HOST_LS_SCL")
		)
		(pad "2" smd circle
			(at 0.40005 0 180)
			(size 0 0)
			(layers "F.Cu" "F.Mask" "F.Paste")
			(net "I2C_PEX1_HOST_R_SCL")
		)
	)
	(footprint ""
		(layer "F.Cu")
		(at 248.819924 -88.039448 180)
		(property "Reference" "R1466"
			(at 0 0 180)
			(layer "F.SilkS")
			(hide yes)
			(effects
				(font
					(size 1.27 1.27)
				)
			)
		)
		(property "Value" ""
			(at 0 0 180)
			(layer "F.Fab")
			(effects
				(font
					(size 1.27 1.27)
				)
			)
		)
		(duplicate_pad_numbers_are_jumpers no)
		(fp_line
			(start 0.7874 0.4064)
			(end -0.7874 0.4064)
			(stroke
				(width 0.1524)
				(type default)
			)
			(layer "F.SilkS")
		)
		(fp_line
			(start 0.7874 -0.4064)
			(end 0.7874 0.4064)
			(stroke
				(width 0.1524)
				(type default)
			)
			(layer "F.SilkS")
		)
		(fp_line
			(start -0.7874 0.4064)
			(end -0.7874 -0.4064)
			(stroke
				(width 0.1524)
				(type default)
			)
			(layer "F.SilkS")
		)
		(fp_line
			(start -0.7874 -0.4064)
			(end 0.7874 -0.4064)
			(stroke
				(width 0.1524)
				(type default)
			)
			(layer "F.SilkS")
		)
		(fp_line
			(start 0.67945 0.3048)
			(end 0.120396 0.3048)
			(stroke
				(width 0.1)
				(type default)
			)
			(layer "F.Fab")
		)
		(fp_line
			(start 0.67945 -0.3048)
			(end 0.67945 0.3048)
			(stroke
				(width 0.1)
				(type default)
			)
			(layer "F.Fab")
		)
		(fp_line
			(start 0.12065 -0.2794)
			(end 0.12065 -0.3048)
			(stroke
				(width 0.1)
				(type default)
			)
			(layer "F.Fab")
		)
		(fp_line
			(start 0.12065 -0.3048)
			(end 0.67945 -0.3048)
			(stroke
				(width 0.1)
				(type default)
			)
			(layer "F.Fab")
		)
		(fp_line
			(start 0.120396 0.3048)
			(end 0.120396 0.2794)
			(stroke
				(width 0.1)
				(type default)
			)
			(layer "F.Fab")
		)
		(fp_line
			(start 0.120396 0.2794)
			(end -0.12065 0.2794)
			(stroke
				(width 0.1)
				(type default)
			)
			(layer "F.Fab")
		)
		(fp_line
			(start -0.12065 0.3048)
			(end -0.67945 0.3048)
			(stroke
				(width 0.1)
				(type default)
			)
			(layer "F.Fab")
		)
		(fp_line
			(start -0.12065 0.2794)
			(end -0.12065 0.3048)
			(stroke
				(width 0.1)
				(type default)
			)
			(layer "F.Fab")
		)
		(fp_line
			(start -0.12065 -0.2794)
			(end 0.12065 -0.2794)
			(stroke
				(width 0.1)
				(type default)
			)
			(layer "F.Fab")
		)
		(fp_line
			(start -0.12065 -0.305054)
			(end -0.12065 -0.2794)
			(stroke
				(width 0.1)
				(type default)
			)
			(layer "F.Fab")
		)
		(fp_line
			(start -0.67945 0.3048)
			(end -0.67945 -0.305054)
			(stroke
				(width 0.1)
				(type default)
			)
			(layer "F.Fab")
		)
		(fp_line
			(start -0.67945 -0.305054)
			(end -0.12065 -0.305054)
			(stroke
				(width 0.1)
				(type default)
			)
			(layer "F.Fab")
		)
		(pad "1" smd circle
			(at -0.40005 0 180)
			(size 0 0)
			(layers "F.Cu" "F.Mask" "F.Paste")
			(net "SMB_CK440_CLK_SDA")
		)
		(pad "2" smd circle
			(at 0.40005 0 180)
			(size 0 0)
			(layers "F.Cu" "F.Mask" "F.Paste")
			(net "SMB_CLK_ISO_R_SDA")
		)
	)
	(footprint ""
		(layer "F.Cu")
		(at 328.295 -233.553)
		(property "Reference" "R4385"
			(at 0 0 0)
			(layer "F.SilkS")
			(hide yes)
			(effects
				(font
					(size 1.27 1.27)
				)
			)
		)
		(property "Value" ""
			(at 0 0 0)
			(layer "F.Fab")
			(effects
				(font
					(size 1.27 1.27)
				)
			)
		)
		(duplicate_pad_numbers_are_jumpers no)
		(fp_line
			(start -0.7874 -0.4064)
			(end 0.7874 -0.4064)
			(stroke
				(width 0.1524)
				(type default)
			)
			(layer "F.SilkS")
		)
		(fp_line
			(start -0.7874 0.4064)
			(end -0.7874 -0.4064)
			(stroke
				(width 0.1524)
				(type default)
			)
			(layer "F.SilkS")
		)
		(fp_line
			(start 0.7874 -0.4064)
			(end 0.7874 0.4064)
			(stroke
				(width 0.1524)
				(type default)
			)
			(layer "F.SilkS")
		)
		(fp_line
			(start 0.7874 0.4064)
			(end -0.7874 0.4064)
			(stroke
				(width 0.1524)
				(type default)
			)
			(layer "F.SilkS")
		)
		(fp_line
			(start -0.67945 -0.305054)
			(end -0.12065 -0.305054)
			(stroke
				(width 0.1)
				(type default)
			)
			(layer "F.Fab")
		)
		(fp_line
			(start -0.67945 0.3048)
			(end -0.67945 -0.305054)
			(stroke
				(width 0.1)
				(type default)
			)
			(layer "F.Fab")
		)
		(fp_line
			(start -0.12065 -0.305054)
			(end -0.12065 -0.2794)
			(stroke
				(width 0.1)
				(type default)
			)
			(layer "F.Fab")
		)
		(fp_line
			(start -0.12065 -0.2794)
			(end 0.12065 -0.2794)
			(stroke
				(width 0.1)
				(type default)
			)
			(layer "F.Fab")
		)
		(fp_line
			(start -0.12065 0.2794)
			(end -0.12065 0.3048)
			(stroke
				(width 0.1)
				(type default)
			)
			(layer "F.Fab")
		)
		(fp_line
			(start -0.12065 0.3048)
			(end -0.67945 0.3048)
			(stroke
				(width 0.1)
				(type default)
			)
			(layer "F.Fab")
		)
		(fp_line
			(start 0.120396 0.2794)
			(end -0.12065 0.2794)
			(stroke
				(width 0.1)
				(type default)
			)
			(layer "F.Fab")
		)
		(fp_line
			(start 0.120396 0.3048)
			(end 0.120396 0.2794)
			(stroke
				(width 0.1)
				(type default)
			)
			(layer "F.Fab")
		)
		(fp_line
			(start 0.12065 -0.3048)
			(end 0.67945 -0.3048)
			(stroke
				(width 0.1)
				(type default)
			)
			(layer "F.Fab")
		)
		(fp_line
			(start 0.12065 -0.2794)
			(end 0.12065 -0.3048)
			(stroke
				(width 0.1)
				(type default)
			)
			(layer "F.Fab")
		)
		(fp_line
			(start 0.67945 -0.3048)
			(end 0.67945 0.3048)
			(stroke
				(width 0.1)
				(type default)
			)
			(layer "F.Fab")
		)
		(fp_line
			(start 0.67945 0.3048)
			(end 0.120396 0.3048)
			(stroke
				(width 0.1)
				(type default)
			)
			(layer "F.Fab")
		)
		(pad "1" smd circle
			(at -0.40005 0)
			(size 0 0)
			(layers "F.Cu" "F.Mask" "F.Paste")
			(net "RST_PEX_SYS_BUF_N")
		)
		(pad "2" smd circle
			(at 0.40005 0)
			(size 0 0)
			(layers "F.Cu" "F.Mask" "F.Paste")
			(net "P1V8_PEX")
		)
	)
	(footprint ""
		(layer "F.Cu")
		(at 205.102206 -306.074572 90)
		(property "Reference" "R1303"
			(at 0 0 90)
			(layer "F.SilkS")
			(hide yes)
			(effects
				(font
					(size 1.27 1.27)
				)
			)
		)
		(property "Value" ""
			(at 0 0 90)
			(layer "F.Fab")
			(effects
				(font
					(size 1.27 1.27)
				)
			)
		)
		(duplicate_pad_numbers_are_jumpers no)
		(fp_line
			(start 0.7874 -0.4064)
			(end 0.7874 0.4064)
			(stroke
				(width 0.1524)
				(type default)
			)
			(layer "F.SilkS")
		)
		(fp_line
			(start -0.7874 -0.4064)
			(end 0.7874 -0.4064)
			(stroke
				(width 0.1524)
				(type default)
			)
			(layer "F.SilkS")
		)
		(fp_line
			(start 0.7874 0.4064)
			(end -0.7874 0.4064)
			(stroke
				(width 0.1524)
				(type default)
			)
			(layer "F.SilkS")
		)
		(fp_line
			(start -0.7874 0.4064)
			(end -0.7874 -0.4064)
			(stroke
				(width 0.1524)
				(type default)
			)
			(layer "F.SilkS")
		)
		(fp_line
			(start -0.12065 -0.305054)
			(end -0.12065 -0.2794)
			(stroke
				(width 0.1)
				(type default)
			)
			(layer "F.Fab")
		)
		(fp_line
			(start -0.67945 -0.305054)
			(end -0.12065 -0.305054)
			(stroke
				(width 0.1)
				(type default)
			)
			(layer "F.Fab")
		)
		(fp_line
			(start 0.67945 -0.3048)
			(end 0.67945 0.3048)
			(stroke
				(width 0.1)
				(type default)
			)
			(layer "F.Fab")
		)
		(fp_line
			(start 0.12065 -0.3048)
			(end 0.67945 -0.3048)
			(stroke
				(width 0.1)
				(type default)
			)
			(layer "F.Fab")
		)
		(fp_line
			(start 0.12065 -0.2794)
			(end 0.12065 -0.3048)
			(stroke
				(width 0.1)
				(type default)
			)
			(layer "F.Fab")
		)
		(fp_line
			(start -0.12065 -0.2794)
			(end 0.12065 -0.2794)
			(stroke
				(width 0.1)
				(type default)
			)
			(layer "F.Fab")
		)
		(fp_line
			(start 0.120396 0.2794)
			(end -0.12065 0.2794)
			(stroke
				(width 0.1)
				(type default)
			)
			(layer "F.Fab")
		)
		(fp_line
			(start -0.12065 0.2794)
			(end -0.12065 0.3048)
			(stroke
				(width 0.1)
				(type default)
			)
			(layer "F.Fab")
		)
		(fp_line
			(start 0.67945 0.3048)
			(end 0.120396 0.3048)
			(stroke
				(width 0.1)
				(type default)
			)
			(layer "F.Fab")
		)
		(fp_line
			(start 0.120396 0.3048)
			(end 0.120396 0.2794)
			(stroke
				(width 0.1)
				(type default)
			)
			(layer "F.Fab")
		)
		(fp_line
			(start -0.12065 0.3048)
			(end -0.67945 0.3048)
			(stroke
				(width 0.1)
				(type default)
			)
			(layer "F.Fab")
		)
		(fp_line
			(start -0.67945 0.3048)
			(end -0.67945 -0.305054)
			(stroke
				(width 0.1)
				(type default)
			)
			(layer "F.Fab")
		)
		(pad "1" smd circle
			(at -0.40005 0 90)
			(size 0 0)
			(layers "F.Cu" "F.Mask" "F.Paste")
			(net "PEX1_SPARE4")
		)
		(pad "2" smd circle
			(at 0.40005 0 90)
			(size 0 0)
			(layers "F.Cu" "F.Mask" "F.Paste")
			(net "P1V8_PEX")
		)
	)
	(footprint ""
		(layer "F.Cu")
		(at 359.156 -190.246 180)
		(property "Reference" "R4613"
			(at 0 0 180)
			(layer "F.SilkS")
			(hide yes)
			(effects
				(font
					(size 1.27 1.27)
				)
			)
		)
		(property "Value" ""
			(at 0 0 180)
			(layer "F.Fab")
			(effects
				(font
					(size 1.27 1.27)
				)
			)
		)
		(duplicate_pad_numbers_are_jumpers no)
		(fp_line
			(start 0.7874 0.4064)
			(end -0.7874 0.4064)
			(stroke
				(width 0.1524)
				(type default)
			)
			(layer "F.SilkS")
		)
		(fp_line
			(start 0.7874 -0.4064)
			(end 0.7874 0.4064)
			(stroke
				(width 0.1524)
				(type default)
			)
			(layer "F.SilkS")
		)
		(fp_line
			(start -0.7874 0.4064)
			(end -0.7874 -0.4064)
			(stroke
				(width 0.1524)
				(type default)
			)
			(layer "F.SilkS")
		)
		(fp_line
			(start -0.7874 -0.4064)
			(end 0.7874 -0.4064)
			(stroke
				(width 0.1524)
				(type default)
			)
			(layer "F.SilkS")
		)
		(fp_line
			(start 0.67945 0.3048)
			(end 0.120396 0.3048)
			(stroke
				(width 0.1)
				(type default)
			)
			(layer "F.Fab")
		)
		(fp_line
			(start 0.67945 -0.3048)
			(end 0.67945 0.3048)
			(stroke
				(width 0.1)
				(type default)
			)
			(layer "F.Fab")
		)
		(fp_line
			(start 0.12065 -0.2794)
			(end 0.12065 -0.3048)
			(stroke
				(width 0.1)
				(type default)
			)
			(layer "F.Fab")
		)
		(fp_line
			(start 0.12065 -0.3048)
			(end 0.67945 -0.3048)
			(stroke
				(width 0.1)
				(type default)
			)
			(layer "F.Fab")
		)
		(fp_line
			(start 0.120396 0.3048)
			(end 0.120396 0.2794)
			(stroke
				(width 0.1)
				(type default)
			)
			(layer "F.Fab")
		)
		(fp_line
			(start 0.120396 0.2794)
			(end -0.12065 0.2794)
			(stroke
				(width 0.1)
				(type default)
			)
			(layer "F.Fab")
		)
		(fp_line
			(start -0.12065 0.3048)
			(end -0.67945 0.3048)
			(stroke
				(width 0.1)
				(type default)
			)
			(layer "F.Fab")
		)
		(fp_line
			(start -0.12065 0.2794)
			(end -0.12065 0.3048)
			(stroke
				(width 0.1)
				(type default)
			)
			(layer "F.Fab")
		)
		(fp_line
			(start -0.12065 -0.2794)
			(end 0.12065 -0.2794)
			(stroke
				(width 0.1)
				(type default)
			)
			(layer "F.Fab")
		)
		(fp_line
			(start -0.12065 -0.305054)
			(end -0.12065 -0.2794)
			(stroke
				(width 0.1)
				(type default)
			)
			(layer "F.Fab")
		)
		(fp_line
			(start -0.67945 0.3048)
			(end -0.67945 -0.305054)
			(stroke
				(width 0.1)
				(type default)
			)
			(layer "F.Fab")
		)
		(fp_line
			(start -0.67945 -0.305054)
			(end -0.12065 -0.305054)
			(stroke
				(width 0.1)
				(type default)
			)
			(layer "F.Fab")
		)
		(pad "1" smd circle
			(at -0.40005 0 180)
			(size 0 0)
			(layers "F.Cu" "F.Mask" "F.Paste")
			(net "SSD2_PEX_PWR_EN_R")
		)
		(pad "2" smd circle
			(at 0.40005 0 180)
			(size 0 0)
			(layers "F.Cu" "F.Mask" "F.Paste")
			(net "GND")
		)
	)
	(footprint ""
		(layer "F.Cu")
		(at 378.382022 -296.191432 180)
		(property "Reference" "C3552"
			(at 0 0 180)
			(layer "F.SilkS")
			(hide yes)
			(effects
				(font
					(size 1.27 1.27)
				)
			)
		)
		(property "Value" ""
			(at 0 0 180)
			(layer "F.Fab")
			(effects
				(font
					(size 1.27 1.27)
				)
			)
		)
		(duplicate_pad_numbers_are_jumpers no)
		(fp_line
			(start 1.2954 0.5842)
			(end -1.2954 0.5842)
			(stroke
				(width 0.1524)
				(type default)
			)
			(layer "F.SilkS")
		)
		(fp_line
			(start 1.2954 -0.5842)
			(end 1.2954 0.5842)
			(stroke
				(width 0.1524)
				(type default)
			)
			(layer "F.SilkS")
		)
		(fp_line
			(start -1.2954 0.5842)
			(end -1.2954 -0.5842)
			(stroke
				(width 0.1524)
				(type default)
			)
			(layer "F.SilkS")
		)
		(fp_line
			(start -1.2954 -0.5842)
			(end 1.2954 -0.5842)
			(stroke
				(width 0.1524)
				(type default)
			)
			(layer "F.SilkS")
		)
		(fp_line
			(start 1.1938 0.4064)
			(end 0.8636 0.4064)
			(stroke
				(width 0.1)
				(type default)
			)
			(layer "F.Fab")
		)
		(fp_line
			(start 1.1938 -0.4064)
			(end 1.1938 0.4064)
			(stroke
				(width 0.1)
				(type default)
			)
			(layer "F.Fab")
		)
		(fp_line
			(start 0.8636 0.4572)
			(end -0.8636 0.4572)
			(stroke
				(width 0.1)
				(type default)
			)
			(layer "F.Fab")
		)
		(fp_line
			(start 0.8636 0.4064)
			(end 0.8636 0.4572)
			(stroke
				(width 0.1)
				(type default)
			)
			(layer "F.Fab")
		)
		(fp_line
			(start 0.8636 -0.4064)
			(end 1.1938 -0.4064)
			(stroke
				(width 0.1)
				(type default)
			)
			(layer "F.Fab")
		)
		(fp_line
			(start 0.8636 -0.4572)
			(end 0.8636 -0.4064)
			(stroke
				(width 0.1)
				(type default)
			)
			(layer "F.Fab")
		)
		(fp_line
			(start -0.8636 0.4572)
			(end -0.8636 0.4064)
			(stroke
				(width 0.1)
				(type default)
			)
			(layer "F.Fab")
		)
		(fp_line
			(start -0.8636 0.4064)
			(end -1.1938 0.4064)
			(stroke
				(width 0.1)
				(type default)
			)
			(layer "F.Fab")
		)
		(fp_line
			(start -0.8636 -0.4064)
			(end -0.8636 -0.4572)
			(stroke
				(width 0.1)
				(type default)
			)
			(layer "F.Fab")
		)
		(fp_line
			(start -0.8636 -0.4572)
			(end 0.8636 -0.4572)
			(stroke
				(width 0.1)
				(type default)
			)
			(layer "F.Fab")
		)
		(fp_line
			(start -1.1938 0.4064)
			(end -1.1938 -0.4064)
			(stroke
				(width 0.1)
				(type default)
			)
			(layer "F.Fab")
		)
		(fp_line
			(start -1.1938 -0.4064)
			(end -0.8636 -0.4064)
			(stroke
				(width 0.1)
				(type default)
			)
			(layer "F.Fab")
		)
		(pad "1" smd rect
			(at -0.7366 0 90)
			(size 0.7112 0.8128)
			(layers "F.Cu" "F.Mask" "F.Paste")
			(net "PCEPLL0_VDDA18_PEX3_R")
		)
		(pad "2" smd rect
			(at 0.7366 0 90)
			(size 0.7112 0.8128)
			(layers "F.Cu" "F.Mask" "F.Paste")
			(net "GND")
		)
	)
	(footprint ""
		(layer "F.Cu")
		(at 7.189216 -15.119858 180)
		(property "Reference" "C3872"
			(at 0 0 180)
			(layer "F.SilkS")
			(hide yes)
			(effects
				(font
					(size 1.27 1.27)
				)
			)
		)
		(property "Value" ""
			(at 0 0 180)
			(layer "F.Fab")
			(effects
				(font
					(size 1.27 1.27)
				)
			)
		)
		(duplicate_pad_numbers_are_jumpers no)
		(fp_line
			(start 0.7874 0.4064)
			(end -0.7874 0.4064)
			(stroke
				(width 0.1524)
				(type default)
			)
			(layer "F.SilkS")
		)
		(fp_line
			(start 0.7874 -0.4064)
			(end 0.7874 0.4064)
			(stroke
				(width 0.1524)
				(type default)
			)
			(layer "F.SilkS")
		)
		(fp_line
			(start -0.7874 0.4064)
			(end -0.7874 -0.4064)
			(stroke
				(width 0.1524)
				(type default)
			)
			(layer "F.SilkS")
		)
		(fp_line
			(start -0.7874 -0.4064)
			(end 0.7874 -0.4064)
			(stroke
				(width 0.1524)
				(type default)
			)
			(layer "F.SilkS")
		)
		(fp_line
			(start 0.67945 0.3048)
			(end 0.120396 0.3048)
			(stroke
				(width 0.1)
				(type default)
			)
			(layer "F.Fab")
		)
		(fp_line
			(start 0.67945 -0.3048)
			(end 0.67945 0.3048)
			(stroke
				(width 0.1)
				(type default)
			)
			(layer "F.Fab")
		)
		(fp_line
			(start 0.12065 -0.2794)
			(end 0.12065 -0.3048)
			(stroke
				(width 0.1)
				(type default)
			)
			(layer "F.Fab")
		)
		(fp_line
			(start 0.12065 -0.3048)
			(end 0.67945 -0.3048)
			(stroke
				(width 0.1)
				(type default)
			)
			(layer "F.Fab")
		)
		(fp_line
			(start 0.120396 0.3048)
			(end 0.120396 0.2794)
			(stroke
				(width 0.1)
				(type default)
			)
			(layer "F.Fab")
		)
		(fp_line
			(start 0.120396 0.2794)
			(end -0.12065 0.2794)
			(stroke
				(width 0.1)
				(type default)
			)
			(layer "F.Fab")
		)
		(fp_line
			(start -0.12065 0.3048)
			(end -0.67945 0.3048)
			(stroke
				(width 0.1)
				(type default)
			)
			(layer "F.Fab")
		)
		(fp_line
			(start -0.12065 0.2794)
			(end -0.12065 0.3048)
			(stroke
				(width 0.1)
				(type default)
			)
			(layer "F.Fab")
		)
		(fp_line
			(start -0.12065 -0.2794)
			(end 0.12065 -0.2794)
			(stroke
				(width 0.1)
				(type default)
			)
			(layer "F.Fab")
		)
		(fp_line
			(start -0.12065 -0.305054)
			(end -0.12065 -0.2794)
			(stroke
				(width 0.1)
				(type default)
			)
			(layer "F.Fab")
		)
		(fp_line
			(start -0.67945 0.3048)
			(end -0.67945 -0.305054)
			(stroke
				(width 0.1)
				(type default)
			)
			(layer "F.Fab")
		)
		(fp_line
			(start -0.67945 -0.305054)
			(end -0.12065 -0.305054)
			(stroke
				(width 0.1)
				(type default)
			)
			(layer "F.Fab")
		)
		(pad "1" smd circle
			(at -0.40005 0 180)
			(size 0 0)
			(layers "F.Cu" "F.Mask" "F.Paste")
			(net "P12V_SSD0")
		)
		(pad "2" smd circle
			(at 0.40005 0 180)
			(size 0 0)
			(layers "F.Cu" "F.Mask" "F.Paste")
			(net "GND")
		)
	)
	(footprint ""
		(layer "F.Cu")
		(at 186.822588 -44.341542 90)
		(property "Reference" "R580"
			(at 0 0 90)
			(layer "F.SilkS")
			(hide yes)
			(effects
				(font
					(size 1.27 1.27)
				)
			)
		)
		(property "Value" ""
			(at 0 0 90)
			(layer "F.Fab")
			(effects
				(font
					(size 1.27 1.27)
				)
			)
		)
		(duplicate_pad_numbers_are_jumpers no)
		(fp_line
			(start 0.7874 -0.4064)
			(end 0.7874 0.4064)
			(stroke
				(width 0.1524)
				(type default)
			)
			(layer "F.SilkS")
		)
		(fp_line
			(start -0.7874 -0.4064)
			(end 0.7874 -0.4064)
			(stroke
				(width 0.1524)
				(type default)
			)
			(layer "F.SilkS")
		)
		(fp_line
			(start 0.7874 0.4064)
			(end -0.7874 0.4064)
			(stroke
				(width 0.1524)
				(type default)
			)
			(layer "F.SilkS")
		)
		(fp_line
			(start -0.7874 0.4064)
			(end -0.7874 -0.4064)
			(stroke
				(width 0.1524)
				(type default)
			)
			(layer "F.SilkS")
		)
		(fp_line
			(start -0.12065 -0.305054)
			(end -0.12065 -0.2794)
			(stroke
				(width 0.1)
				(type default)
			)
			(layer "F.Fab")
		)
		(fp_line
			(start -0.67945 -0.305054)
			(end -0.12065 -0.305054)
			(stroke
				(width 0.1)
				(type default)
			)
			(layer "F.Fab")
		)
		(fp_line
			(start 0.67945 -0.3048)
			(end 0.67945 0.3048)
			(stroke
				(width 0.1)
				(type default)
			)
			(layer "F.Fab")
		)
		(fp_line
			(start 0.12065 -0.3048)
			(end 0.67945 -0.3048)
			(stroke
				(width 0.1)
				(type default)
			)
			(layer "F.Fab")
		)
		(fp_line
			(start 0.12065 -0.2794)
			(end 0.12065 -0.3048)
			(stroke
				(width 0.1)
				(type default)
			)
			(layer "F.Fab")
		)
		(fp_line
			(start -0.12065 -0.2794)
			(end 0.12065 -0.2794)
			(stroke
				(width 0.1)
				(type default)
			)
			(layer "F.Fab")
		)
		(fp_line
			(start 0.120396 0.2794)
			(end -0.12065 0.2794)
			(stroke
				(width 0.1)
				(type default)
			)
			(layer "F.Fab")
		)
		(fp_line
			(start -0.12065 0.2794)
			(end -0.12065 0.3048)
			(stroke
				(width 0.1)
				(type default)
			)
			(layer "F.Fab")
		)
		(fp_line
			(start 0.67945 0.3048)
			(end 0.120396 0.3048)
			(stroke
				(width 0.1)
				(type default)
			)
			(layer "F.Fab")
		)
		(fp_line
			(start 0.120396 0.3048)
			(end 0.120396 0.2794)
			(stroke
				(width 0.1)
				(type default)
			)
			(layer "F.Fab")
		)
		(fp_line
			(start -0.12065 0.3048)
			(end -0.67945 0.3048)
			(stroke
				(width 0.1)
				(type default)
			)
			(layer "F.Fab")
		)
		(fp_line
			(start -0.67945 0.3048)
			(end -0.67945 -0.305054)
			(stroke
				(width 0.1)
				(type default)
			)
			(layer "F.Fab")
		)
		(pad "1" smd circle
			(at -0.40005 0 90)
			(size 0 0)
			(layers "F.Cu" "F.Mask" "F.Paste")
			(net "P12V_SSD6")
		)
		(pad "2" smd circle
			(at 0.40005 0 90)
			(size 0 0)
			(layers "F.Cu" "F.Mask" "F.Paste")
			(net "P12V_SSD6_VIN_N")
		)
	)
	(footprint ""
		(layer "F.Cu")
		(at 21.872956 -173.255178)
		(property "Reference" "PR58"
			(at 0 0 0)
			(layer "F.SilkS")
			(hide yes)
			(effects
				(font
					(size 1.27 1.27)
				)
			)
		)
		(property "Value" ""
			(at 0 0 0)
			(layer "F.Fab")
			(effects
				(font
					(size 1.27 1.27)
				)
			)
		)
		(duplicate_pad_numbers_are_jumpers no)
		(fp_line
			(start -0.7874 -0.4064)
			(end 0.7874 -0.4064)
			(stroke
				(width 0.1524)
				(type default)
			)
			(layer "F.SilkS")
		)
		(fp_line
			(start -0.7874 0.4064)
			(end -0.7874 -0.4064)
			(stroke
				(width 0.1524)
				(type default)
			)
			(layer "F.SilkS")
		)
		(fp_line
			(start 0.7874 -0.4064)
			(end 0.7874 0.4064)
			(stroke
				(width 0.1524)
				(type default)
			)
			(layer "F.SilkS")
		)
		(fp_line
			(start 0.7874 0.4064)
			(end -0.7874 0.4064)
			(stroke
				(width 0.1524)
				(type default)
			)
			(layer "F.SilkS")
		)
		(fp_line
			(start -0.67945 -0.305054)
			(end -0.12065 -0.305054)
			(stroke
				(width 0.1)
				(type default)
			)
			(layer "F.Fab")
		)
		(fp_line
			(start -0.67945 0.3048)
			(end -0.67945 -0.305054)
			(stroke
				(width 0.1)
				(type default)
			)
			(layer "F.Fab")
		)
		(fp_line
			(start -0.12065 -0.305054)
			(end -0.12065 -0.2794)
			(stroke
				(width 0.1)
				(type default)
			)
			(layer "F.Fab")
		)
		(fp_line
			(start -0.12065 -0.2794)
			(end 0.12065 -0.2794)
			(stroke
				(width 0.1)
				(type default)
			)
			(layer "F.Fab")
		)
		(fp_line
			(start -0.12065 0.2794)
			(end -0.12065 0.3048)
			(stroke
				(width 0.1)
				(type default)
			)
			(layer "F.Fab")
		)
		(fp_line
			(start -0.12065 0.3048)
			(end -0.67945 0.3048)
			(stroke
				(width 0.1)
				(type default)
			)
			(layer "F.Fab")
		)
		(fp_line
			(start 0.120396 0.2794)
			(end -0.12065 0.2794)
			(stroke
				(width 0.1)
				(type default)
			)
			(layer "F.Fab")
		)
		(fp_line
			(start 0.120396 0.3048)
			(end 0.120396 0.2794)
			(stroke
				(width 0.1)
				(type default)
			)
			(layer "F.Fab")
		)
		(fp_line
			(start 0.12065 -0.3048)
			(end 0.67945 -0.3048)
			(stroke
				(width 0.1)
				(type default)
			)
			(layer "F.Fab")
		)
		(fp_line
			(start 0.12065 -0.2794)
			(end 0.12065 -0.3048)
			(stroke
				(width 0.1)
				(type default)
			)
			(layer "F.Fab")
		)
		(fp_line
			(start 0.67945 -0.3048)
			(end 0.67945 0.3048)
			(stroke
				(width 0.1)
				(type default)
			)
			(layer "F.Fab")
		)
		(fp_line
			(start 0.67945 0.3048)
			(end 0.120396 0.3048)
			(stroke
				(width 0.1)
				(type default)
			)
			(layer "F.Fab")
		)
		(pad "1" smd circle
			(at -0.40005 0)
			(size 0 0)
			(layers "F.Cu" "F.Mask" "F.Paste")
			(net "P5V_AUX_FB")
		)
		(pad "2" smd circle
			(at 0.40005 0)
			(size 0 0)
			(layers "F.Cu" "F.Mask" "F.Paste")
			(net "GND")
		)
	)
	(footprint ""
		(layer "F.Cu")
		(at 112.583976 -277.644352)
		(property "Reference" "PC80"
			(at 0 0 0)
			(layer "F.SilkS")
			(hide yes)
			(effects
				(font
					(size 1.27 1.27)
				)
			)
		)
		(property "Value" ""
			(at 0 0 0)
			(layer "F.Fab")
			(effects
				(font
					(size 1.27 1.27)
				)
			)
		)
		(duplicate_pad_numbers_are_jumpers no)
		(fp_line
			(start -1.524 -0.762)
			(end 1.524 -0.762)
			(stroke
				(width 0.1524)
				(type default)
			)
			(layer "F.SilkS")
		)
		(fp_line
			(start -1.524 0.762)
			(end -1.524 -0.762)
			(stroke
				(width 0.1524)
				(type default)
			)
			(layer "F.SilkS")
		)
		(fp_line
			(start 1.524 -0.762)
			(end 1.524 0.762)
			(stroke
				(width 0.1524)
				(type default)
			)
			(layer "F.SilkS")
		)
		(fp_line
			(start 1.524 0.762)
			(end -1.524 0.762)
			(stroke
				(width 0.1524)
				(type default)
			)
			(layer "F.SilkS")
		)
		(fp_line
			(start -1.1049 -0.724916)
			(end -1.1049 0.724916)
			(stroke
				(width 0.1)
				(type default)
			)
			(layer "F.Fab")
		)
		(fp_line
			(start -1.1049 0.724916)
			(end 1.1049 0.724916)
			(stroke
				(width 0.1)
				(type default)
			)
			(layer "F.Fab")
		)
		(fp_line
			(start 1.1049 -0.724916)
			(end -1.1049 -0.724916)
			(stroke
				(width 0.1)
				(type default)
			)
			(layer "F.Fab")
		)
		(fp_line
			(start 1.1049 0.724916)
			(end 1.1049 -0.724916)
			(stroke
				(width 0.1)
				(type default)
			)
			(layer "F.Fab")
		)
		(pad "1" smd rect
			(at -0.889 0 180)
			(size 1.016 1.27)
			(layers "F.Cu" "F.Mask" "F.Paste")
			(net "SW_P12V_P0V8_PEX0_FLT")
		)
		(pad "2" smd rect
			(at 0.889 0 180)
			(size 1.016 1.27)
			(layers "F.Cu" "F.Mask" "F.Paste")
			(net "GND")
		)
	)
	(footprint ""
		(layer "F.Cu")
		(at 98.514408 -66.32194 90)
		(property "Reference" "R5845"
			(at 0 0 90)
			(layer "F.SilkS")
			(hide yes)
			(effects
				(font
					(size 1.27 1.27)
				)
			)
		)
		(property "Value" ""
			(at 0 0 90)
			(layer "F.Fab")
			(effects
				(font
					(size 1.27 1.27)
				)
			)
		)
		(duplicate_pad_numbers_are_jumpers no)
		(fp_line
			(start 0.7874 -0.4064)
			(end 0.7874 0.4064)
			(stroke
				(width 0.1524)
				(type default)
			)
			(layer "F.SilkS")
		)
		(fp_line
			(start -0.7874 -0.4064)
			(end 0.7874 -0.4064)
			(stroke
				(width 0.1524)
				(type default)
			)
			(layer "F.SilkS")
		)
		(fp_line
			(start 0.7874 0.4064)
			(end -0.7874 0.4064)
			(stroke
				(width 0.1524)
				(type default)
			)
			(layer "F.SilkS")
		)
		(fp_line
			(start -0.7874 0.4064)
			(end -0.7874 -0.4064)
			(stroke
				(width 0.1524)
				(type default)
			)
			(layer "F.SilkS")
		)
		(fp_line
			(start -0.12065 -0.305054)
			(end -0.12065 -0.2794)
			(stroke
				(width 0.1)
				(type default)
			)
			(layer "F.Fab")
		)
		(fp_line
			(start -0.67945 -0.305054)
			(end -0.12065 -0.305054)
			(stroke
				(width 0.1)
				(type default)
			)
			(layer "F.Fab")
		)
		(fp_line
			(start 0.67945 -0.3048)
			(end 0.67945 0.3048)
			(stroke
				(width 0.1)
				(type default)
			)
			(layer "F.Fab")
		)
		(fp_line
			(start 0.12065 -0.3048)
			(end 0.67945 -0.3048)
			(stroke
				(width 0.1)
				(type default)
			)
			(layer "F.Fab")
		)
		(fp_line
			(start 0.12065 -0.2794)
			(end 0.12065 -0.3048)
			(stroke
				(width 0.1)
				(type default)
			)
			(layer "F.Fab")
		)
		(fp_line
			(start -0.12065 -0.2794)
			(end 0.12065 -0.2794)
			(stroke
				(width 0.1)
				(type default)
			)
			(layer "F.Fab")
		)
		(fp_line
			(start 0.120396 0.2794)
			(end -0.12065 0.2794)
			(stroke
				(width 0.1)
				(type default)
			)
			(layer "F.Fab")
		)
		(fp_line
			(start -0.12065 0.2794)
			(end -0.12065 0.3048)
			(stroke
				(width 0.1)
				(type default)
			)
			(layer "F.Fab")
		)
		(fp_line
			(start 0.67945 0.3048)
			(end 0.120396 0.3048)
			(stroke
				(width 0.1)
				(type default)
			)
			(layer "F.Fab")
		)
		(fp_line
			(start 0.120396 0.3048)
			(end 0.120396 0.2794)
			(stroke
				(width 0.1)
				(type default)
			)
			(layer "F.Fab")
		)
		(fp_line
			(start -0.12065 0.3048)
			(end -0.67945 0.3048)
			(stroke
				(width 0.1)
				(type default)
			)
			(layer "F.Fab")
		)
		(fp_line
			(start -0.67945 0.3048)
			(end -0.67945 -0.305054)
			(stroke
				(width 0.1)
				(type default)
			)
			(layer "F.Fab")
		)
		(pad "1" smd circle
			(at -0.40005 0 90)
			(size 0 0)
			(layers "F.Cu" "F.Mask" "F.Paste")
			(net "SSD3_PWR_EN_R")
		)
		(pad "2" smd circle
			(at 0.40005 0 90)
			(size 0 0)
			(layers "F.Cu" "F.Mask" "F.Paste")
			(net "P12V_SSD3_CO_EN")
		)
	)
	(footprint ""
		(layer "F.Cu")
		(at 172.401992 -350.098614 90)
		(property "Reference" "C393"
			(at 0 0 90)
			(layer "F.SilkS")
			(hide yes)
			(effects
				(font
					(size 1.27 1.27)
				)
			)
		)
		(property "Value" ""
			(at 0 0 90)
			(layer "F.Fab")
			(effects
				(font
					(size 1.27 1.27)
				)
			)
		)
		(duplicate_pad_numbers_are_jumpers no)
		(fp_line
			(start 0.299974 -0.150114)
			(end 0.299974 0.150114)
			(stroke
				(width 0.1)
				(type default)
			)
			(layer "F.Fab")
		)
		(fp_line
			(start -0.299974 -0.150114)
			(end 0.299974 -0.150114)
			(stroke
				(width 0.1)
				(type default)
			)
			(layer "F.Fab")
		)
		(fp_line
			(start 0.299974 0.150114)
			(end -0.299974 0.150114)
			(stroke
				(width 0.1)
				(type default)
			)
			(layer "F.Fab")
		)
		(fp_line
			(start -0.299974 0.150114)
			(end -0.299974 -0.150114)
			(stroke
				(width 0.1)
				(type default)
			)
			(layer "F.Fab")
		)
		(pad "1" smd rect
			(at -0.2667 0 90)
			(size 0.3048 0.381)
			(layers "F.Cu" "F.Mask" "F.Paste")
			(net "P5E_PEX1_STN7_TX_DN<117>")
		)
		(pad "2" smd rect
			(at 0.2667 0 90)
			(size 0.3048 0.381)
			(layers "F.Cu" "F.Mask" "F.Paste")
			(net "P5E_PEX1_STN7_TX_C_DN<117>")
		)
	)
	(footprint ""
		(layer "F.Cu")
		(at 394.574014 -72.766682 90)
		(property "Reference" "PR7089"
			(at 0 0 90)
			(layer "F.SilkS")
			(hide yes)
			(effects
				(font
					(size 1.27 1.27)
				)
			)
		)
		(property "Value" ""
			(at 0 0 90)
			(layer "F.Fab")
			(effects
				(font
					(size 1.27 1.27)
				)
			)
		)
		(duplicate_pad_numbers_are_jumpers no)
		(fp_line
			(start 0.7874 -0.4064)
			(end 0.7874 0.4064)
			(stroke
				(width 0.1524)
				(type default)
			)
			(layer "F.SilkS")
		)
		(fp_line
			(start -0.7874 -0.4064)
			(end 0.7874 -0.4064)
			(stroke
				(width 0.1524)
				(type default)
			)
			(layer "F.SilkS")
		)
		(fp_line
			(start 0.7874 0.4064)
			(end -0.7874 0.4064)
			(stroke
				(width 0.1524)
				(type default)
			)
			(layer "F.SilkS")
		)
		(fp_line
			(start -0.7874 0.4064)
			(end -0.7874 -0.4064)
			(stroke
				(width 0.1524)
				(type default)
			)
			(layer "F.SilkS")
		)
		(fp_line
			(start -0.12065 -0.305054)
			(end -0.12065 -0.2794)
			(stroke
				(width 0.1)
				(type default)
			)
			(layer "F.Fab")
		)
		(fp_line
			(start -0.67945 -0.305054)
			(end -0.12065 -0.305054)
			(stroke
				(width 0.1)
				(type default)
			)
			(layer "F.Fab")
		)
		(fp_line
			(start 0.67945 -0.3048)
			(end 0.67945 0.3048)
			(stroke
				(width 0.1)
				(type default)
			)
			(layer "F.Fab")
		)
		(fp_line
			(start 0.12065 -0.3048)
			(end 0.67945 -0.3048)
			(stroke
				(width 0.1)
				(type default)
			)
			(layer "F.Fab")
		)
		(fp_line
			(start 0.12065 -0.2794)
			(end 0.12065 -0.3048)
			(stroke
				(width 0.1)
				(type default)
			)
			(layer "F.Fab")
		)
		(fp_line
			(start -0.12065 -0.2794)
			(end 0.12065 -0.2794)
			(stroke
				(width 0.1)
				(type default)
			)
			(layer "F.Fab")
		)
		(fp_line
			(start 0.120396 0.2794)
			(end -0.12065 0.2794)
			(stroke
				(width 0.1)
				(type default)
			)
			(layer "F.Fab")
		)
		(fp_line
			(start -0.12065 0.2794)
			(end -0.12065 0.3048)
			(stroke
				(width 0.1)
				(type default)
			)
			(layer "F.Fab")
		)
		(fp_line
			(start 0.67945 0.3048)
			(end 0.120396 0.3048)
			(stroke
				(width 0.1)
				(type default)
			)
			(layer "F.Fab")
		)
		(fp_line
			(start 0.120396 0.3048)
			(end 0.120396 0.2794)
			(stroke
				(width 0.1)
				(type default)
			)
			(layer "F.Fab")
		)
		(fp_line
			(start -0.12065 0.3048)
			(end -0.67945 0.3048)
			(stroke
				(width 0.1)
				(type default)
			)
			(layer "F.Fab")
		)
		(fp_line
			(start -0.67945 0.3048)
			(end -0.67945 -0.305054)
			(stroke
				(width 0.1)
				(type default)
			)
			(layer "F.Fab")
		)
		(pad "1" smd circle
			(at -0.40005 0 90)
			(size 0 0)
			(layers "F.Cu" "F.Mask" "F.Paste")
			(net "P12V_SSD13_CO_MODE")
		)
		(pad "2" smd circle
			(at 0.40005 0 90)
			(size 0 0)
			(layers "F.Cu" "F.Mask" "F.Paste")
			(net "GND")
		)
	)
	(footprint ""
		(layer "F.Cu")
		(at 176.063402 -177.456592 90)
		(property "Reference" "C4498"
			(at 0 0 90)
			(layer "F.SilkS")
			(hide yes)
			(effects
				(font
					(size 1.27 1.27)
				)
			)
		)
		(property "Value" ""
			(at 0 0 90)
			(layer "F.Fab")
			(effects
				(font
					(size 1.27 1.27)
				)
			)
		)
		(duplicate_pad_numbers_are_jumpers no)
		(fp_line
			(start 0.7874 -0.4064)
			(end 0.7874 0.4064)
			(stroke
				(width 0.1524)
				(type default)
			)
			(layer "F.SilkS")
		)
		(fp_line
			(start -0.7874 -0.4064)
			(end 0.7874 -0.4064)
			(stroke
				(width 0.1524)
				(type default)
			)
			(layer "F.SilkS")
		)
		(fp_line
			(start 0.7874 0.4064)
			(end -0.7874 0.4064)
			(stroke
				(width 0.1524)
				(type default)
			)
			(layer "F.SilkS")
		)
		(fp_line
			(start -0.7874 0.4064)
			(end -0.7874 -0.4064)
			(stroke
				(width 0.1524)
				(type default)
			)
			(layer "F.SilkS")
		)
		(fp_line
			(start -0.12065 -0.305054)
			(end -0.12065 -0.2794)
			(stroke
				(width 0.1)
				(type default)
			)
			(layer "F.Fab")
		)
		(fp_line
			(start -0.67945 -0.305054)
			(end -0.12065 -0.305054)
			(stroke
				(width 0.1)
				(type default)
			)
			(layer "F.Fab")
		)
		(fp_line
			(start 0.67945 -0.3048)
			(end 0.67945 0.3048)
			(stroke
				(width 0.1)
				(type default)
			)
			(layer "F.Fab")
		)
		(fp_line
			(start 0.12065 -0.3048)
			(end 0.67945 -0.3048)
			(stroke
				(width 0.1)
				(type default)
			)
			(layer "F.Fab")
		)
		(fp_line
			(start 0.12065 -0.2794)
			(end 0.12065 -0.3048)
			(stroke
				(width 0.1)
				(type default)
			)
			(layer "F.Fab")
		)
		(fp_line
			(start -0.12065 -0.2794)
			(end 0.12065 -0.2794)
			(stroke
				(width 0.1)
				(type default)
			)
			(layer "F.Fab")
		)
		(fp_line
			(start 0.120396 0.2794)
			(end -0.12065 0.2794)
			(stroke
				(width 0.1)
				(type default)
			)
			(layer "F.Fab")
		)
		(fp_line
			(start -0.12065 0.2794)
			(end -0.12065 0.3048)
			(stroke
				(width 0.1)
				(type default)
			)
			(layer "F.Fab")
		)
		(fp_line
			(start 0.67945 0.3048)
			(end 0.120396 0.3048)
			(stroke
				(width 0.1)
				(type default)
			)
			(layer "F.Fab")
		)
		(fp_line
			(start 0.120396 0.3048)
			(end 0.120396 0.2794)
			(stroke
				(width 0.1)
				(type default)
			)
			(layer "F.Fab")
		)
		(fp_line
			(start -0.12065 0.3048)
			(end -0.67945 0.3048)
			(stroke
				(width 0.1)
				(type default)
			)
			(layer "F.Fab")
		)
		(fp_line
			(start -0.67945 0.3048)
			(end -0.67945 -0.305054)
			(stroke
				(width 0.1)
				(type default)
			)
			(layer "F.Fab")
		)
		(pad "1" smd circle
			(at -0.40005 0 90)
			(size 0 0)
			(layers "F.Cu" "F.Mask" "F.Paste")
			(net "NIC3_CLK_EN_R_N")
		)
		(pad "2" smd circle
			(at 0.40005 0 90)
			(size 0 0)
			(layers "F.Cu" "F.Mask" "F.Paste")
			(net "GND")
		)
	)
	(footprint ""
		(layer "F.Cu")
		(at 341.372444 -356.244906 90)
		(property "Reference" "C522"
			(at 0 0 90)
			(layer "F.SilkS")
			(hide yes)
			(effects
				(font
					(size 1.27 1.27)
				)
			)
		)
		(property "Value" ""
			(at 0 0 90)
			(layer "F.Fab")
			(effects
				(font
					(size 1.27 1.27)
				)
			)
		)
		(duplicate_pad_numbers_are_jumpers no)
		(fp_line
			(start 0.299974 -0.150114)
			(end 0.299974 0.150114)
			(stroke
				(width 0.1)
				(type default)
			)
			(layer "F.Fab")
		)
		(fp_line
			(start -0.299974 -0.150114)
			(end 0.299974 -0.150114)
			(stroke
				(width 0.1)
				(type default)
			)
			(layer "F.Fab")
		)
		(fp_line
			(start 0.299974 0.150114)
			(end -0.299974 0.150114)
			(stroke
				(width 0.1)
				(type default)
			)
			(layer "F.Fab")
		)
		(fp_line
			(start -0.299974 0.150114)
			(end -0.299974 -0.150114)
			(stroke
				(width 0.1)
				(type default)
			)
			(layer "F.Fab")
		)
		(pad "1" smd rect
			(at -0.2667 0 90)
			(size 0.3048 0.381)
			(layers "F.Cu" "F.Mask" "F.Paste")
			(net "P5E_PEX2_STN5_TX_DN<94>")
		)
		(pad "2" smd rect
			(at 0.2667 0 90)
			(size 0.3048 0.381)
			(layers "F.Cu" "F.Mask" "F.Paste")
			(net "P5E_PEX2_STN5_TX_C_DN<94>")
		)
	)
	(footprint ""
		(layer "F.Cu")
		(at 336.55 -205.232 -90)
		(property "Reference" "R4122"
			(at 0 0 270)
			(layer "F.SilkS")
			(hide yes)
			(effects
				(font
					(size 1.27 1.27)
				)
			)
		)
		(property "Value" ""
			(at 0 0 270)
			(layer "F.Fab")
			(effects
				(font
					(size 1.27 1.27)
				)
			)
		)
		(duplicate_pad_numbers_are_jumpers no)
		(fp_line
			(start -0.7874 0.4064)
			(end -0.7874 -0.4064)
			(stroke
				(width 0.1524)
				(type default)
			)
			(layer "F.SilkS")
		)
		(fp_line
			(start 0.7874 0.4064)
			(end -0.7874 0.4064)
			(stroke
				(width 0.1524)
				(type default)
			)
			(layer "F.SilkS")
		)
		(fp_line
			(start -0.7874 -0.4064)
			(end 0.7874 -0.4064)
			(stroke
				(width 0.1524)
				(type default)
			)
			(layer "F.SilkS")
		)
		(fp_line
			(start 0.7874 -0.4064)
			(end 0.7874 0.4064)
			(stroke
				(width 0.1524)
				(type default)
			)
			(layer "F.SilkS")
		)
		(fp_line
			(start -0.67945 0.3048)
			(end -0.67945 -0.305054)
			(stroke
				(width 0.1)
				(type default)
			)
			(layer "F.Fab")
		)
		(fp_line
			(start -0.12065 0.3048)
			(end -0.67945 0.3048)
			(stroke
				(width 0.1)
				(type default)
			)
			(layer "F.Fab")
		)
		(fp_line
			(start 0.120396 0.3048)
			(end 0.120396 0.2794)
			(stroke
				(width 0.1)
				(type default)
			)
			(layer "F.Fab")
		)
		(fp_line
			(start 0.67945 0.3048)
			(end 0.120396 0.3048)
			(stroke
				(width 0.1)
				(type default)
			)
			(layer "F.Fab")
		)
		(fp_line
			(start -0.12065 0.2794)
			(end -0.12065 0.3048)
			(stroke
				(width 0.1)
				(type default)
			)
			(layer "F.Fab")
		)
		(fp_line
			(start 0.120396 0.2794)
			(end -0.12065 0.2794)
			(stroke
				(width 0.1)
				(type default)
			)
			(layer "F.Fab")
		)
		(fp_line
			(start -0.12065 -0.2794)
			(end 0.12065 -0.2794)
			(stroke
				(width 0.1)
				(type default)
			)
			(layer "F.Fab")
		)
		(fp_line
			(start 0.12065 -0.2794)
			(end 0.12065 -0.3048)
			(stroke
				(width 0.1)
				(type default)
			)
			(layer "F.Fab")
		)
		(fp_line
			(start 0.12065 -0.3048)
			(end 0.67945 -0.3048)
			(stroke
				(width 0.1)
				(type default)
			)
			(layer "F.Fab")
		)
		(fp_line
			(start 0.67945 -0.3048)
			(end 0.67945 0.3048)
			(stroke
				(width 0.1)
				(type default)
			)
			(layer "F.Fab")
		)
		(fp_line
			(start -0.67945 -0.305054)
			(end -0.12065 -0.305054)
			(stroke
				(width 0.1)
				(type default)
			)
			(layer "F.Fab")
		)
		(fp_line
			(start -0.12065 -0.305054)
			(end -0.12065 -0.2794)
			(stroke
				(width 0.1)
				(type default)
			)
			(layer "F.Fab")
		)
		(pad "1" smd circle
			(at -0.40005 0 270)
			(size 0 0)
			(layers "F.Cu" "F.Mask" "F.Paste")
			(net "SSD9_CLK_EN_N")
		)
		(pad "2" smd circle
			(at 0.40005 0 270)
			(size 0 0)
			(layers "F.Cu" "F.Mask" "F.Paste")
			(net "SSD9_CLK_EN_R_N")
		)
	)
	(footprint ""
		(layer "F.Cu")
		(at 456.149202 -247.791224 180)
		(property "Reference" "U433"
			(at 1.255014 -4.651248 0)
			(unlocked yes)
			(layer "F.SilkS")
			(effects
				(font
					(size 0.7874 0.5842)
					(thickness 0.1524)
				)
				(justify left)
			)
		)
		(property "Value" ""
			(at 0 0 180)
			(layer "F.Fab")
			(effects
				(font
					(size 1.27 1.27)
				)
			)
		)
		(duplicate_pad_numbers_are_jumpers no)
		(fp_line
			(start 1.525016 1.525016)
			(end 1.525016 1.3208)
			(stroke
				(width 0.1524)
				(type default)
			)
			(layer "F.SilkS")
		)
		(fp_line
			(start 1.525016 1.525016)
			(end -1.525016 1.525016)
			(stroke
				(width 0.1524)
				(type default)
			)
			(layer "F.SilkS")
		)
		(fp_line
			(start 1.525016 -1.3208)
			(end 1.525016 -1.525016)
			(stroke
				(width 0.1524)
				(type default)
			)
			(layer "F.SilkS")
		)
		(fp_line
			(start 1.525016 -1.525016)
			(end 0.9398 -1.525016)
			(stroke
				(width 0.1524)
				(type default)
			)
			(layer "F.SilkS")
		)
		(fp_line
			(start 1.525016 -1.525016)
			(end -1.525016 -1.525016)
			(stroke
				(width 0.1524)
				(type default)
			)
			(layer "F.SilkS")
		)
		(fp_line
			(start 0.9906 1.525016)
			(end 1.525016 1.525016)
			(stroke
				(width 0.1524)
				(type default)
			)
			(layer "F.SilkS")
		)
		(fp_line
			(start -0.8636 -1.525016)
			(end -1.525016 -1.525016)
			(stroke
				(width 0.1524)
				(type default)
			)
			(layer "F.SilkS")
		)
		(fp_line
			(start -1.525016 1.525016)
			(end -0.889 1.525016)
			(stroke
				(width 0.1524)
				(type default)
			)
			(layer "F.SilkS")
		)
		(fp_line
			(start -1.525016 1.3208)
			(end -1.525016 1.525016)
			(stroke
				(width 0.1524)
				(type default)
			)
			(layer "F.SilkS")
		)
		(fp_line
			(start -1.525016 -1.525016)
			(end -1.525016 -1.3208)
			(stroke
				(width 0.1524)
				(type default)
			)
			(layer "F.SilkS")
		)
		(fp_poly
			(pts
				(xy -2.260854 -0.979424) (xy -1.96088 -1.8796) (xy -2.560828 -1.8796)
			)
			(stroke
				(width 0)
				(type default)
			)
			(fill yes)
			(layer "F.SilkS")
		)
		(fp_line
			(start 1.525016 1.525016)
			(end -1.525016 1.525016)
			(stroke
				(width 0.1)
				(type default)
			)
			(layer "F.Fab")
		)
		(fp_line
			(start 1.525016 -1.525016)
			(end 1.525016 1.525016)
			(stroke
				(width 0.1)
				(type default)
			)
			(layer "F.Fab")
		)
		(fp_line
			(start -1.525016 1.525016)
			(end -1.525016 -1.525016)
			(stroke
				(width 0.1)
				(type default)
			)
			(layer "F.Fab")
		)
		(fp_line
			(start -1.525016 -1.525016)
			(end 1.525016 -1.525016)
			(stroke
				(width 0.1)
				(type default)
			)
			(layer "F.Fab")
		)
		(fp_poly
			(pts
				(xy -2.0701 -0.999998) (xy -2.977896 -1.302512) (xy -2.977896 -0.697484)
			)
			(stroke
				(width 0)
				(type default)
			)
			(fill yes)
			(layer "F.Fab")
		)
		(pad "1" smd rect
			(at -1.550162 -0.999998 90)
			(size 0.2794 0.9144)
			(layers "F.Cu" "F.Mask" "F.Paste")
			(net "P1V8_PLL0_PEX3")
		)
		(pad "2" smd rect
			(at -1.550162 -0.500126 90)
			(size 0.2794 0.9144)
			(layers "F.Cu" "F.Mask" "F.Paste")
			(net "P1V8_PLL0_PEX3")
		)
		(pad "3" smd rect
			(at -1.550162 0 90)
			(size 0.2794 0.9144)
			(layers "F.Cu" "F.Mask" "F.Paste")
			(net "P1V8_PLL0_PEX3")
		)
		(pad "4" smd rect
			(at -1.550162 0.500126 90)
			(size 0.2794 0.9144)
			(layers "F.Cu" "F.Mask" "F.Paste")
			(net "P1V8_PLL_PEX3_ADJ")
		)
		(pad "5" smd rect
			(at -1.550162 0.999998 270)
			(size 0.2794 0.9144)
			(layers "F.Cu" "F.Mask" "F.Paste")
			(net "PWRGD_PEX3_P1V8_PLL")
		)
		(pad "6" smd rect
			(at 1.550162 0.999998 270)
			(size 0.2794 0.9144)
			(layers "F.Cu" "F.Mask" "F.Paste")
			(net "PEX3_P1V8_PLL_EN")
		)
		(pad "7" smd rect
			(at 1.550162 0.500126 90)
			(size 0.2794 0.9144)
			(layers "F.Cu" "F.Mask" "F.Paste")
			(net "P3V3_AUX")
		)
		(pad "8" smd rect
			(at 1.550162 0 90)
			(size 0.2794 0.9144)
			(layers "F.Cu" "F.Mask" "F.Paste")
			(net "P3V3_AUX")
		)
		(pad "9" smd rect
			(at 1.550162 -0.500126 90)
			(size 0.2794 0.9144)
			(layers "F.Cu" "F.Mask" "F.Paste")
			(net "P3V3_AUX")
		)
		(pad "10" smd rect
			(at 1.550162 -0.999998 90)
			(size 0.2794 0.9144)
			(layers "F.Cu" "F.Mask" "F.Paste")
			(net "P5V_AUX")
		)
		(pad "TH" smd rect
			(at 0 0 180)
			(size 1.7526 2.667)
			(layers "F.Cu" "F.Mask" "F.Paste")
			(net "GND")
		)
	)
	(footprint ""
		(layer "F.Cu")
		(at 442.794136 -115.394486)
		(property "Reference" "PR7106"
			(at 0 0 0)
			(layer "F.SilkS")
			(hide yes)
			(effects
				(font
					(size 1.27 1.27)
				)
			)
		)
		(property "Value" ""
			(at 0 0 0)
			(layer "F.Fab")
			(effects
				(font
					(size 1.27 1.27)
				)
			)
		)
		(duplicate_pad_numbers_are_jumpers no)
		(fp_line
			(start -0.7874 -0.4064)
			(end 0.7874 -0.4064)
			(stroke
				(width 0.1524)
				(type default)
			)
			(layer "F.SilkS")
		)
		(fp_line
			(start -0.7874 0.4064)
			(end -0.7874 -0.4064)
			(stroke
				(width 0.1524)
				(type default)
			)
			(layer "F.SilkS")
		)
		(fp_line
			(start 0.7874 -0.4064)
			(end 0.7874 0.4064)
			(stroke
				(width 0.1524)
				(type default)
			)
			(layer "F.SilkS")
		)
		(fp_line
			(start 0.7874 0.4064)
			(end -0.7874 0.4064)
			(stroke
				(width 0.1524)
				(type default)
			)
			(layer "F.SilkS")
		)
		(fp_line
			(start -0.67945 -0.305054)
			(end -0.12065 -0.305054)
			(stroke
				(width 0.1)
				(type default)
			)
			(layer "F.Fab")
		)
		(fp_line
			(start -0.67945 0.3048)
			(end -0.67945 -0.305054)
			(stroke
				(width 0.1)
				(type default)
			)
			(layer "F.Fab")
		)
		(fp_line
			(start -0.12065 -0.305054)
			(end -0.12065 -0.2794)
			(stroke
				(width 0.1)
				(type default)
			)
			(layer "F.Fab")
		)
		(fp_line
			(start -0.12065 -0.2794)
			(end 0.12065 -0.2794)
			(stroke
				(width 0.1)
				(type default)
			)
			(layer "F.Fab")
		)
		(fp_line
			(start -0.12065 0.2794)
			(end -0.12065 0.3048)
			(stroke
				(width 0.1)
				(type default)
			)
			(layer "F.Fab")
		)
		(fp_line
			(start -0.12065 0.3048)
			(end -0.67945 0.3048)
			(stroke
				(width 0.1)
				(type default)
			)
			(layer "F.Fab")
		)
		(fp_line
			(start 0.120396 0.2794)
			(end -0.12065 0.2794)
			(stroke
				(width 0.1)
				(type default)
			)
			(layer "F.Fab")
		)
		(fp_line
			(start 0.120396 0.3048)
			(end 0.120396 0.2794)
			(stroke
				(width 0.1)
				(type default)
			)
			(layer "F.Fab")
		)
		(fp_line
			(start 0.12065 -0.3048)
			(end 0.67945 -0.3048)
			(stroke
				(width 0.1)
				(type default)
			)
			(layer "F.Fab")
		)
		(fp_line
			(start 0.12065 -0.2794)
			(end 0.12065 -0.3048)
			(stroke
				(width 0.1)
				(type default)
			)
			(layer "F.Fab")
		)
		(fp_line
			(start 0.67945 -0.3048)
			(end 0.67945 0.3048)
			(stroke
				(width 0.1)
				(type default)
			)
			(layer "F.Fab")
		)
		(fp_line
			(start 0.67945 0.3048)
			(end 0.120396 0.3048)
			(stroke
				(width 0.1)
				(type default)
			)
			(layer "F.Fab")
		)
		(pad "1" smd circle
			(at -0.40005 0)
			(size 0 0)
			(layers "F.Cu" "F.Mask" "F.Paste")
			(net "P3V3_NIC7_CO_ILIMIT")
		)
		(pad "2" smd circle
			(at 0.40005 0)
			(size 0 0)
			(layers "F.Cu" "F.Mask" "F.Paste")
			(net "GND")
		)
	)
	(footprint ""
		(layer "F.Cu")
		(at 155.380436 -106.488738)
		(property "Reference" "C266"
			(at 0 0 0)
			(layer "F.SilkS")
			(hide yes)
			(effects
				(font
					(size 1.27 1.27)
				)
			)
		)
		(property "Value" ""
			(at 0 0 0)
			(layer "F.Fab")
			(effects
				(font
					(size 1.27 1.27)
				)
			)
		)
		(duplicate_pad_numbers_are_jumpers no)
		(fp_line
			(start -0.299974 -0.150114)
			(end 0.299974 -0.150114)
			(stroke
				(width 0.1)
				(type default)
			)
			(layer "F.Fab")
		)
		(fp_line
			(start -0.299974 0.150114)
			(end -0.299974 -0.150114)
			(stroke
				(width 0.1)
				(type default)
			)
			(layer "F.Fab")
		)
		(fp_line
			(start 0.299974 -0.150114)
			(end 0.299974 0.150114)
			(stroke
				(width 0.1)
				(type default)
			)
			(layer "F.Fab")
		)
		(fp_line
			(start 0.299974 0.150114)
			(end -0.299974 0.150114)
			(stroke
				(width 0.1)
				(type default)
			)
			(layer "F.Fab")
		)
		(pad "1" smd rect
			(at -0.2667 0)
			(size 0.3048 0.381)
			(layers "F.Cu" "F.Mask" "F.Paste")
			(net "P5E_PEX1_STN1_TX_DP<20>")
		)
		(pad "2" smd rect
			(at 0.2667 0)
			(size 0.3048 0.381)
			(layers "F.Cu" "F.Mask" "F.Paste")
			(net "P5E_PEX1_STN1_TX_C_DP<20>")
		)
	)
	(footprint ""
		(layer "F.Cu")
		(at 136.355328 -35.876738)
		(property "Reference" "R6057"
			(at 0 0 0)
			(layer "F.SilkS")
			(hide yes)
			(effects
				(font
					(size 1.27 1.27)
				)
			)
		)
		(property "Value" ""
			(at 0 0 0)
			(layer "F.Fab")
			(effects
				(font
					(size 1.27 1.27)
				)
			)
		)
		(duplicate_pad_numbers_are_jumpers no)
		(fp_line
			(start -0.7874 -0.4064)
			(end 0.7874 -0.4064)
			(stroke
				(width 0.1524)
				(type default)
			)
			(layer "F.SilkS")
		)
		(fp_line
			(start -0.7874 0.4064)
			(end -0.7874 -0.4064)
			(stroke
				(width 0.1524)
				(type default)
			)
			(layer "F.SilkS")
		)
		(fp_line
			(start 0.7874 -0.4064)
			(end 0.7874 0.4064)
			(stroke
				(width 0.1524)
				(type default)
			)
			(layer "F.SilkS")
		)
		(fp_line
			(start 0.7874 0.4064)
			(end -0.7874 0.4064)
			(stroke
				(width 0.1524)
				(type default)
			)
			(layer "F.SilkS")
		)
		(fp_line
			(start -0.67945 -0.305054)
			(end -0.12065 -0.305054)
			(stroke
				(width 0.1)
				(type default)
			)
			(layer "F.Fab")
		)
		(fp_line
			(start -0.67945 0.3048)
			(end -0.67945 -0.305054)
			(stroke
				(width 0.1)
				(type default)
			)
			(layer "F.Fab")
		)
		(fp_line
			(start -0.12065 -0.305054)
			(end -0.12065 -0.2794)
			(stroke
				(width 0.1)
				(type default)
			)
			(layer "F.Fab")
		)
		(fp_line
			(start -0.12065 -0.2794)
			(end 0.12065 -0.2794)
			(stroke
				(width 0.1)
				(type default)
			)
			(layer "F.Fab")
		)
		(fp_line
			(start -0.12065 0.2794)
			(end -0.12065 0.3048)
			(stroke
				(width 0.1)
				(type default)
			)
			(layer "F.Fab")
		)
		(fp_line
			(start -0.12065 0.3048)
			(end -0.67945 0.3048)
			(stroke
				(width 0.1)
				(type default)
			)
			(layer "F.Fab")
		)
		(fp_line
			(start 0.120396 0.2794)
			(end -0.12065 0.2794)
			(stroke
				(width 0.1)
				(type default)
			)
			(layer "F.Fab")
		)
		(fp_line
			(start 0.120396 0.3048)
			(end 0.120396 0.2794)
			(stroke
				(width 0.1)
				(type default)
			)
			(layer "F.Fab")
		)
		(fp_line
			(start 0.12065 -0.3048)
			(end 0.67945 -0.3048)
			(stroke
				(width 0.1)
				(type default)
			)
			(layer "F.Fab")
		)
		(fp_line
			(start 0.12065 -0.2794)
			(end 0.12065 -0.3048)
			(stroke
				(width 0.1)
				(type default)
			)
			(layer "F.Fab")
		)
		(fp_line
			(start 0.67945 -0.3048)
			(end 0.67945 0.3048)
			(stroke
				(width 0.1)
				(type default)
			)
			(layer "F.Fab")
		)
		(fp_line
			(start 0.67945 0.3048)
			(end 0.120396 0.3048)
			(stroke
				(width 0.1)
				(type default)
			)
			(layer "F.Fab")
		)
		(pad "1" smd circle
			(at -0.40005 0)
			(size 0 0)
			(layers "F.Cu" "F.Mask" "F.Paste")
			(net "P3V3_AUX")
		)
		(pad "2" smd circle
			(at 0.40005 0)
			(size 0 0)
			(layers "F.Cu" "F.Mask" "F.Paste")
			(net "PWRGD_P3V3_SSD5_D")
		)
	)
	(footprint ""
		(layer "F.Cu")
		(at 406.50414 -370.794026 -90)
		(property "Reference" "Q242"
			(at 0.686308 -3.06832 0)
			(unlocked yes)
			(layer "F.SilkS")
			(effects
				(font
					(size 0.7874 0.5842)
					(thickness 0.1524)
				)
			)
		)
		(property "Value" ""
			(at 0 0 270)
			(layer "F.Fab")
			(effects
				(font
					(size 1.27 1.27)
				)
			)
		)
		(duplicate_pad_numbers_are_jumpers no)
		(fp_line
			(start -1.376172 1.199896)
			(end -1.376172 -1.199896)
			(stroke
				(width 0.1524)
				(type default)
			)
			(layer "F.SilkS")
		)
		(fp_line
			(start 1.376172 1.199896)
			(end -1.376172 1.199896)
			(stroke
				(width 0.1524)
				(type default)
			)
			(layer "F.SilkS")
		)
		(fp_line
			(start 0 -0.762)
			(end 0.508 -1.199896)
			(stroke
				(width 0.1524)
				(type default)
			)
			(layer "F.SilkS")
		)
		(fp_line
			(start -1.376172 -1.199896)
			(end -0.508 -1.199896)
			(stroke
				(width 0.1524)
				(type default)
			)
			(layer "F.SilkS")
		)
		(fp_line
			(start -0.508 -1.199896)
			(end 0 -0.762)
			(stroke
				(width 0.1524)
				(type default)
			)
			(layer "F.SilkS")
		)
		(fp_line
			(start 0.508 -1.199896)
			(end 1.376172 -1.199896)
			(stroke
				(width 0.1524)
				(type default)
			)
			(layer "F.SilkS")
		)
		(fp_line
			(start 1.376172 -1.199896)
			(end 1.376172 1.199896)
			(stroke
				(width 0.1524)
				(type default)
			)
			(layer "F.SilkS")
		)
		(fp_poly
			(pts
				(xy -0.982726 -1.440434) (xy -0.601726 -2.202434) (xy -1.363726 -2.202434)
			)
			(stroke
				(width 0)
				(type default)
			)
			(fill yes)
			(layer "F.SilkS")
		)
		(fp_line
			(start -0.674878 1.100074)
			(end -0.674878 -1.100074)
			(stroke
				(width 0.1)
				(type default)
			)
			(layer "F.Fab")
		)
		(fp_line
			(start 0.674878 1.100074)
			(end -0.674878 1.100074)
			(stroke
				(width 0.1)
				(type default)
			)
			(layer "F.Fab")
		)
		(fp_line
			(start -0.674878 -1.100074)
			(end 0.674878 -1.100074)
			(stroke
				(width 0.1)
				(type default)
			)
			(layer "F.Fab")
		)
		(fp_line
			(start 0.674878 -1.100074)
			(end 0.674878 1.100074)
			(stroke
				(width 0.1)
				(type default)
			)
			(layer "F.Fab")
		)
		(fp_poly
			(pts
				(xy -1.4605 -0.7493) (xy -2.2225 -1.1303) (xy -2.2225 -0.3683)
			)
			(stroke
				(width 0)
				(type default)
			)
			(fill yes)
			(layer "F.Fab")
		)
		(pad "1" smd rect
			(at -0.899922 -0.750062 180)
			(size 0.6096 0.6096)
			(layers "F.Cu" "F.Mask" "F.Paste")
			(net "GND")
		)
		(pad "2" smd rect
			(at -0.899922 0 180)
			(size 0.4064 0.6096)
			(layers "F.Cu" "F.Mask" "F.Paste")
			(net "GPU_3V3IO_RSVD4")
		)
		(pad "3" smd rect
			(at -0.899922 0.750062 180)
			(size 0.6096 0.6096)
			(layers "F.Cu" "F.Mask" "F.Paste")
			(net "GPU_3V3IO_RSVD4_ISO")
		)
		(pad "4" smd rect
			(at 0.899922 0.750062 180)
			(size 0.6096 0.6096)
			(layers "F.Cu" "F.Mask" "F.Paste")
			(net "GND")
		)
		(pad "5" smd rect
			(at 0.899922 0 180)
			(size 0.4064 0.6096)
			(layers "F.Cu" "F.Mask" "F.Paste")
			(net "GPU_3V3IO_RSVD4_N")
		)
		(pad "6" smd rect
			(at 0.899922 -0.750062 180)
			(size 0.6096 0.6096)
			(layers "F.Cu" "F.Mask" "F.Paste")
			(net "GPU_3V3IO_RSVD4_N")
		)
	)
	(footprint ""
		(layer "F.Cu")
		(at 242.310412 -125.979428)
		(property "Reference" "R879"
			(at 0 0 0)
			(layer "F.SilkS")
			(hide yes)
			(effects
				(font
					(size 1.27 1.27)
				)
			)
		)
		(property "Value" ""
			(at 0 0 0)
			(layer "F.Fab")
			(effects
				(font
					(size 1.27 1.27)
				)
			)
		)
		(duplicate_pad_numbers_are_jumpers no)
		(fp_line
			(start -0.7874 -0.4064)
			(end 0.7874 -0.4064)
			(stroke
				(width 0.1524)
				(type default)
			)
			(layer "F.SilkS")
		)
		(fp_line
			(start -0.7874 0.4064)
			(end -0.7874 -0.4064)
			(stroke
				(width 0.1524)
				(type default)
			)
			(layer "F.SilkS")
		)
		(fp_line
			(start 0.7874 -0.4064)
			(end 0.7874 0.4064)
			(stroke
				(width 0.1524)
				(type default)
			)
			(layer "F.SilkS")
		)
		(fp_line
			(start 0.7874 0.4064)
			(end -0.7874 0.4064)
			(stroke
				(width 0.1524)
				(type default)
			)
			(layer "F.SilkS")
		)
		(fp_line
			(start -0.67945 -0.305054)
			(end -0.12065 -0.305054)
			(stroke
				(width 0.1)
				(type default)
			)
			(layer "F.Fab")
		)
		(fp_line
			(start -0.67945 0.3048)
			(end -0.67945 -0.305054)
			(stroke
				(width 0.1)
				(type default)
			)
			(layer "F.Fab")
		)
		(fp_line
			(start -0.12065 -0.305054)
			(end -0.12065 -0.2794)
			(stroke
				(width 0.1)
				(type default)
			)
			(layer "F.Fab")
		)
		(fp_line
			(start -0.12065 -0.2794)
			(end 0.12065 -0.2794)
			(stroke
				(width 0.1)
				(type default)
			)
			(layer "F.Fab")
		)
		(fp_line
			(start -0.12065 0.2794)
			(end -0.12065 0.3048)
			(stroke
				(width 0.1)
				(type default)
			)
			(layer "F.Fab")
		)
		(fp_line
			(start -0.12065 0.3048)
			(end -0.67945 0.3048)
			(stroke
				(width 0.1)
				(type default)
			)
			(layer "F.Fab")
		)
		(fp_line
			(start 0.120396 0.2794)
			(end -0.12065 0.2794)
			(stroke
				(width 0.1)
				(type default)
			)
			(layer "F.Fab")
		)
		(fp_line
			(start 0.120396 0.3048)
			(end 0.120396 0.2794)
			(stroke
				(width 0.1)
				(type default)
			)
			(layer "F.Fab")
		)
		(fp_line
			(start 0.12065 -0.3048)
			(end 0.67945 -0.3048)
			(stroke
				(width 0.1)
				(type default)
			)
			(layer "F.Fab")
		)
		(fp_line
			(start 0.12065 -0.2794)
			(end 0.12065 -0.3048)
			(stroke
				(width 0.1)
				(type default)
			)
			(layer "F.Fab")
		)
		(fp_line
			(start 0.67945 -0.3048)
			(end 0.67945 0.3048)
			(stroke
				(width 0.1)
				(type default)
			)
			(layer "F.Fab")
		)
		(fp_line
			(start 0.67945 0.3048)
			(end 0.120396 0.3048)
			(stroke
				(width 0.1)
				(type default)
			)
			(layer "F.Fab")
		)
		(pad "1" smd circle
			(at -0.40005 0)
			(size 0 0)
			(layers "F.Cu" "F.Mask" "F.Paste")
			(net "P3V3_NIC4")
		)
		(pad "2" smd circle
			(at 0.40005 0)
			(size 0 0)
			(layers "F.Cu" "F.Mask" "F.Paste")
			(net "PWRGD_P3V3_NIC4")
		)
	)
	(footprint ""
		(layer "F.Cu")
		(at 34.851848 -343.952322 90)
		(property "Reference" "C177"
			(at 0 0 90)
			(layer "F.SilkS")
			(hide yes)
			(effects
				(font
					(size 1.27 1.27)
				)
			)
		)
		(property "Value" ""
			(at 0 0 90)
			(layer "F.Fab")
			(effects
				(font
					(size 1.27 1.27)
				)
			)
		)
		(duplicate_pad_numbers_are_jumpers no)
		(fp_line
			(start 0.299974 -0.150114)
			(end 0.299974 0.150114)
			(stroke
				(width 0.1)
				(type default)
			)
			(layer "F.Fab")
		)
		(fp_line
			(start -0.299974 -0.150114)
			(end 0.299974 -0.150114)
			(stroke
				(width 0.1)
				(type default)
			)
			(layer "F.Fab")
		)
		(fp_line
			(start 0.299974 0.150114)
			(end -0.299974 0.150114)
			(stroke
				(width 0.1)
				(type default)
			)
			(layer "F.Fab")
		)
		(fp_line
			(start -0.299974 0.150114)
			(end -0.299974 -0.150114)
			(stroke
				(width 0.1)
				(type default)
			)
			(layer "F.Fab")
		)
		(pad "1" smd rect
			(at -0.2667 0 90)
			(size 0.3048 0.381)
			(layers "F.Cu" "F.Mask" "F.Paste")
			(net "P5E_PEX0_STN7_TX_DP<119>")
		)
		(pad "2" smd rect
			(at 0.2667 0 90)
			(size 0.3048 0.381)
			(layers "F.Cu" "F.Mask" "F.Paste")
			(net "P5E_PEX0_STN7_TX_C_DP<119>")
		)
	)
	(footprint ""
		(layer "F.Cu")
		(at 116.684298 -29.222954 -90)
		(property "Reference" "PC918"
			(at 0 0 270)
			(layer "F.SilkS")
			(hide yes)
			(effects
				(font
					(size 1.27 1.27)
				)
			)
		)
		(property "Value" ""
			(at 0 0 270)
			(layer "F.Fab")
			(effects
				(font
					(size 1.27 1.27)
				)
			)
		)
		(duplicate_pad_numbers_are_jumpers no)
		(fp_line
			(start -0.7874 0.4064)
			(end -0.7874 -0.4064)
			(stroke
				(width 0.1524)
				(type default)
			)
			(layer "F.SilkS")
		)
		(fp_line
			(start 0.7874 0.4064)
			(end -0.7874 0.4064)
			(stroke
				(width 0.1524)
				(type default)
			)
			(layer "F.SilkS")
		)
		(fp_line
			(start -0.7874 -0.4064)
			(end 0.7874 -0.4064)
			(stroke
				(width 0.1524)
				(type default)
			)
			(layer "F.SilkS")
		)
		(fp_line
			(start 0.7874 -0.4064)
			(end 0.7874 0.4064)
			(stroke
				(width 0.1524)
				(type default)
			)
			(layer "F.SilkS")
		)
		(fp_line
			(start -0.67945 0.3048)
			(end -0.67945 -0.305054)
			(stroke
				(width 0.1)
				(type default)
			)
			(layer "F.Fab")
		)
		(fp_line
			(start -0.12065 0.3048)
			(end -0.67945 0.3048)
			(stroke
				(width 0.1)
				(type default)
			)
			(layer "F.Fab")
		)
		(fp_line
			(start 0.120396 0.3048)
			(end 0.120396 0.2794)
			(stroke
				(width 0.1)
				(type default)
			)
			(layer "F.Fab")
		)
		(fp_line
			(start 0.67945 0.3048)
			(end 0.120396 0.3048)
			(stroke
				(width 0.1)
				(type default)
			)
			(layer "F.Fab")
		)
		(fp_line
			(start -0.12065 0.2794)
			(end -0.12065 0.3048)
			(stroke
				(width 0.1)
				(type default)
			)
			(layer "F.Fab")
		)
		(fp_line
			(start 0.120396 0.2794)
			(end -0.12065 0.2794)
			(stroke
				(width 0.1)
				(type default)
			)
			(layer "F.Fab")
		)
		(fp_line
			(start -0.12065 -0.2794)
			(end 0.12065 -0.2794)
			(stroke
				(width 0.1)
				(type default)
			)
			(layer "F.Fab")
		)
		(fp_line
			(start 0.12065 -0.2794)
			(end 0.12065 -0.3048)
			(stroke
				(width 0.1)
				(type default)
			)
			(layer "F.Fab")
		)
		(fp_line
			(start 0.12065 -0.3048)
			(end 0.67945 -0.3048)
			(stroke
				(width 0.1)
				(type default)
			)
			(layer "F.Fab")
		)
		(fp_line
			(start 0.67945 -0.3048)
			(end 0.67945 0.3048)
			(stroke
				(width 0.1)
				(type default)
			)
			(layer "F.Fab")
		)
		(fp_line
			(start -0.67945 -0.305054)
			(end -0.12065 -0.305054)
			(stroke
				(width 0.1)
				(type default)
			)
			(layer "F.Fab")
		)
		(fp_line
			(start -0.12065 -0.305054)
			(end -0.12065 -0.2794)
			(stroke
				(width 0.1)
				(type default)
			)
			(layer "F.Fab")
		)
		(pad "1" smd circle
			(at -0.40005 0 270)
			(size 0 0)
			(layers "F.Cu" "F.Mask" "F.Paste")
			(net "P3V3_AUX")
		)
		(pad "2" smd circle
			(at 0.40005 0 270)
			(size 0 0)
			(layers "F.Cu" "F.Mask" "F.Paste")
			(net "GND")
		)
	)
	(footprint ""
		(layer "F.Cu")
		(at 427.614842 -79.58201 90)
		(property "Reference" "R406"
			(at 0 0 90)
			(layer "F.SilkS")
			(hide yes)
			(effects
				(font
					(size 1.27 1.27)
				)
			)
		)
		(property "Value" ""
			(at 0 0 90)
			(layer "F.Fab")
			(effects
				(font
					(size 1.27 1.27)
				)
			)
		)
		(duplicate_pad_numbers_are_jumpers no)
		(fp_line
			(start 0.7874 -0.4064)
			(end 0.7874 0.4064)
			(stroke
				(width 0.1524)
				(type default)
			)
			(layer "F.SilkS")
		)
		(fp_line
			(start -0.7874 -0.4064)
			(end 0.7874 -0.4064)
			(stroke
				(width 0.1524)
				(type default)
			)
			(layer "F.SilkS")
		)
		(fp_line
			(start 0.7874 0.4064)
			(end -0.7874 0.4064)
			(stroke
				(width 0.1524)
				(type default)
			)
			(layer "F.SilkS")
		)
		(fp_line
			(start -0.7874 0.4064)
			(end -0.7874 -0.4064)
			(stroke
				(width 0.1524)
				(type default)
			)
			(layer "F.SilkS")
		)
		(fp_line
			(start -0.12065 -0.305054)
			(end -0.12065 -0.2794)
			(stroke
				(width 0.1)
				(type default)
			)
			(layer "F.Fab")
		)
		(fp_line
			(start -0.67945 -0.305054)
			(end -0.12065 -0.305054)
			(stroke
				(width 0.1)
				(type default)
			)
			(layer "F.Fab")
		)
		(fp_line
			(start 0.67945 -0.3048)
			(end 0.67945 0.3048)
			(stroke
				(width 0.1)
				(type default)
			)
			(layer "F.Fab")
		)
		(fp_line
			(start 0.12065 -0.3048)
			(end 0.67945 -0.3048)
			(stroke
				(width 0.1)
				(type default)
			)
			(layer "F.Fab")
		)
		(fp_line
			(start 0.12065 -0.2794)
			(end 0.12065 -0.3048)
			(stroke
				(width 0.1)
				(type default)
			)
			(layer "F.Fab")
		)
		(fp_line
			(start -0.12065 -0.2794)
			(end 0.12065 -0.2794)
			(stroke
				(width 0.1)
				(type default)
			)
			(layer "F.Fab")
		)
		(fp_line
			(start 0.120396 0.2794)
			(end -0.12065 0.2794)
			(stroke
				(width 0.1)
				(type default)
			)
			(layer "F.Fab")
		)
		(fp_line
			(start -0.12065 0.2794)
			(end -0.12065 0.3048)
			(stroke
				(width 0.1)
				(type default)
			)
			(layer "F.Fab")
		)
		(fp_line
			(start 0.67945 0.3048)
			(end 0.120396 0.3048)
			(stroke
				(width 0.1)
				(type default)
			)
			(layer "F.Fab")
		)
		(fp_line
			(start 0.120396 0.3048)
			(end 0.120396 0.2794)
			(stroke
				(width 0.1)
				(type default)
			)
			(layer "F.Fab")
		)
		(fp_line
			(start -0.12065 0.3048)
			(end -0.67945 0.3048)
			(stroke
				(width 0.1)
				(type default)
			)
			(layer "F.Fab")
		)
		(fp_line
			(start -0.67945 0.3048)
			(end -0.67945 -0.305054)
			(stroke
				(width 0.1)
				(type default)
			)
			(layer "F.Fab")
		)
		(pad "1" smd circle
			(at -0.40005 0 90)
			(size 0 0)
			(layers "F.Cu" "F.Mask" "F.Paste")
			(net "P3V3_NIC7")
		)
		(pad "2" smd circle
			(at 0.40005 0 90)
			(size 0 0)
			(layers "F.Cu" "F.Mask" "F.Paste")
			(net "HP_NIC7_PWRGD")
		)
	)
	(footprint ""
		(layer "F.Cu")
		(at 197.983602 -61.487812 180)
		(property "Reference" "R5985"
			(at 0 0 180)
			(layer "F.SilkS")
			(hide yes)
			(effects
				(font
					(size 1.27 1.27)
				)
			)
		)
		(property "Value" ""
			(at 0 0 180)
			(layer "F.Fab")
			(effects
				(font
					(size 1.27 1.27)
				)
			)
		)
		(duplicate_pad_numbers_are_jumpers no)
		(fp_line
			(start 0.7874 0.4064)
			(end -0.7874 0.4064)
			(stroke
				(width 0.1524)
				(type default)
			)
			(layer "F.SilkS")
		)
		(fp_line
			(start 0.7874 -0.4064)
			(end 0.7874 0.4064)
			(stroke
				(width 0.1524)
				(type default)
			)
			(layer "F.SilkS")
		)
		(fp_line
			(start -0.7874 0.4064)
			(end -0.7874 -0.4064)
			(stroke
				(width 0.1524)
				(type default)
			)
			(layer "F.SilkS")
		)
		(fp_line
			(start -0.7874 -0.4064)
			(end 0.7874 -0.4064)
			(stroke
				(width 0.1524)
				(type default)
			)
			(layer "F.SilkS")
		)
		(fp_line
			(start 0.67945 0.3048)
			(end 0.120396 0.3048)
			(stroke
				(width 0.1)
				(type default)
			)
			(layer "F.Fab")
		)
		(fp_line
			(start 0.67945 -0.3048)
			(end 0.67945 0.3048)
			(stroke
				(width 0.1)
				(type default)
			)
			(layer "F.Fab")
		)
		(fp_line
			(start 0.12065 -0.2794)
			(end 0.12065 -0.3048)
			(stroke
				(width 0.1)
				(type default)
			)
			(layer "F.Fab")
		)
		(fp_line
			(start 0.12065 -0.3048)
			(end 0.67945 -0.3048)
			(stroke
				(width 0.1)
				(type default)
			)
			(layer "F.Fab")
		)
		(fp_line
			(start 0.120396 0.3048)
			(end 0.120396 0.2794)
			(stroke
				(width 0.1)
				(type default)
			)
			(layer "F.Fab")
		)
		(fp_line
			(start 0.120396 0.2794)
			(end -0.12065 0.2794)
			(stroke
				(width 0.1)
				(type default)
			)
			(layer "F.Fab")
		)
		(fp_line
			(start -0.12065 0.3048)
			(end -0.67945 0.3048)
			(stroke
				(width 0.1)
				(type default)
			)
			(layer "F.Fab")
		)
		(fp_line
			(start -0.12065 0.2794)
			(end -0.12065 0.3048)
			(stroke
				(width 0.1)
				(type default)
			)
			(layer "F.Fab")
		)
		(fp_line
			(start -0.12065 -0.2794)
			(end 0.12065 -0.2794)
			(stroke
				(width 0.1)
				(type default)
			)
			(layer "F.Fab")
		)
		(fp_line
			(start -0.12065 -0.305054)
			(end -0.12065 -0.2794)
			(stroke
				(width 0.1)
				(type default)
			)
			(layer "F.Fab")
		)
		(fp_line
			(start -0.67945 0.3048)
			(end -0.67945 -0.305054)
			(stroke
				(width 0.1)
				(type default)
			)
			(layer "F.Fab")
		)
		(fp_line
			(start -0.67945 -0.305054)
			(end -0.12065 -0.305054)
			(stroke
				(width 0.1)
				(type default)
			)
			(layer "F.Fab")
		)
		(pad "1" smd circle
			(at -0.40005 0 180)
			(size 0 0)
			(layers "F.Cu" "F.Mask" "F.Paste")
			(net "PWRGD_P12V_SSD7_D")
		)
		(pad "2" smd circle
			(at 0.40005 0 180)
			(size 0 0)
			(layers "F.Cu" "F.Mask" "F.Paste")
			(net "PWRGD_P12V_SSD7_R")
		)
	)
	(footprint ""
		(layer "F.Cu")
		(at 90.241882 -343.952322 90)
		(property "Reference" "C102"
			(at 0 0 90)
			(layer "F.SilkS")
			(hide yes)
			(effects
				(font
					(size 1.27 1.27)
				)
			)
		)
		(property "Value" ""
			(at 0 0 90)
			(layer "F.Fab")
			(effects
				(font
					(size 1.27 1.27)
				)
			)
		)
		(duplicate_pad_numbers_are_jumpers no)
		(fp_line
			(start 0.299974 -0.150114)
			(end 0.299974 0.150114)
			(stroke
				(width 0.1)
				(type default)
			)
			(layer "F.Fab")
		)
		(fp_line
			(start -0.299974 -0.150114)
			(end 0.299974 -0.150114)
			(stroke
				(width 0.1)
				(type default)
			)
			(layer "F.Fab")
		)
		(fp_line
			(start 0.299974 0.150114)
			(end -0.299974 0.150114)
			(stroke
				(width 0.1)
				(type default)
			)
			(layer "F.Fab")
		)
		(fp_line
			(start -0.299974 0.150114)
			(end -0.299974 -0.150114)
			(stroke
				(width 0.1)
				(type default)
			)
			(layer "F.Fab")
		)
		(pad "1" smd rect
			(at -0.2667 0 90)
			(size 0.3048 0.381)
			(layers "F.Cu" "F.Mask" "F.Paste")
			(net "P5E_PEX0_STN5_TX_DN<93>")
		)
		(pad "2" smd rect
			(at 0.2667 0 90)
			(size 0.3048 0.381)
			(layers "F.Cu" "F.Mask" "F.Paste")
			(net "P5E_PEX0_STN5_TX_C_DN<93>")
		)
	)
	(footprint ""
		(layer "F.Cu")
		(at 362.351574 -241.697002 180)
		(property "Reference" "R6406"
			(at 0 0 180)
			(layer "F.SilkS")
			(hide yes)
			(effects
				(font
					(size 1.27 1.27)
				)
			)
		)
		(property "Value" ""
			(at 0 0 180)
			(layer "F.Fab")
			(effects
				(font
					(size 1.27 1.27)
				)
			)
		)
		(duplicate_pad_numbers_are_jumpers no)
		(fp_line
			(start 0.7874 0.4064)
			(end -0.7874 0.4064)
			(stroke
				(width 0.1524)
				(type default)
			)
			(layer "F.SilkS")
		)
		(fp_line
			(start 0.7874 -0.4064)
			(end 0.7874 0.4064)
			(stroke
				(width 0.1524)
				(type default)
			)
			(layer "F.SilkS")
		)
		(fp_line
			(start -0.7874 0.4064)
			(end -0.7874 -0.4064)
			(stroke
				(width 0.1524)
				(type default)
			)
			(layer "F.SilkS")
		)
		(fp_line
			(start -0.7874 -0.4064)
			(end 0.7874 -0.4064)
			(stroke
				(width 0.1524)
				(type default)
			)
			(layer "F.SilkS")
		)
		(fp_line
			(start 0.67945 0.3048)
			(end 0.120396 0.3048)
			(stroke
				(width 0.1)
				(type default)
			)
			(layer "F.Fab")
		)
		(fp_line
			(start 0.67945 -0.3048)
			(end 0.67945 0.3048)
			(stroke
				(width 0.1)
				(type default)
			)
			(layer "F.Fab")
		)
		(fp_line
			(start 0.12065 -0.2794)
			(end 0.12065 -0.3048)
			(stroke
				(width 0.1)
				(type default)
			)
			(layer "F.Fab")
		)
		(fp_line
			(start 0.12065 -0.3048)
			(end 0.67945 -0.3048)
			(stroke
				(width 0.1)
				(type default)
			)
			(layer "F.Fab")
		)
		(fp_line
			(start 0.120396 0.3048)
			(end 0.120396 0.2794)
			(stroke
				(width 0.1)
				(type default)
			)
			(layer "F.Fab")
		)
		(fp_line
			(start 0.120396 0.2794)
			(end -0.12065 0.2794)
			(stroke
				(width 0.1)
				(type default)
			)
			(layer "F.Fab")
		)
		(fp_line
			(start -0.12065 0.3048)
			(end -0.67945 0.3048)
			(stroke
				(width 0.1)
				(type default)
			)
			(layer "F.Fab")
		)
		(fp_line
			(start -0.12065 0.2794)
			(end -0.12065 0.3048)
			(stroke
				(width 0.1)
				(type default)
			)
			(layer "F.Fab")
		)
		(fp_line
			(start -0.12065 -0.2794)
			(end 0.12065 -0.2794)
			(stroke
				(width 0.1)
				(type default)
			)
			(layer "F.Fab")
		)
		(fp_line
			(start -0.12065 -0.305054)
			(end -0.12065 -0.2794)
			(stroke
				(width 0.1)
				(type default)
			)
			(layer "F.Fab")
		)
		(fp_line
			(start -0.67945 0.3048)
			(end -0.67945 -0.305054)
			(stroke
				(width 0.1)
				(type default)
			)
			(layer "F.Fab")
		)
		(fp_line
			(start -0.67945 -0.305054)
			(end -0.12065 -0.305054)
			(stroke
				(width 0.1)
				(type default)
			)
			(layer "F.Fab")
		)
		(pad "1" smd circle
			(at -0.40005 0 180)
			(size 0 0)
			(layers "F.Cu" "F.Mask" "F.Paste")
			(net "PWRGD_P12V_AUX_R1")
		)
		(pad "2" smd circle
			(at 0.40005 0 180)
			(size 0 0)
			(layers "F.Cu" "F.Mask" "F.Paste")
			(net "PWRGD_P12V_AUX_R")
		)
	)
	(footprint ""
		(layer "F.Cu")
		(at 364.947454 -397.425672 90)
		(property "Reference" "R6705"
			(at 0 0 90)
			(layer "F.SilkS")
			(hide yes)
			(effects
				(font
					(size 1.27 1.27)
				)
			)
		)
		(property "Value" ""
			(at 0 0 90)
			(layer "F.Fab")
			(effects
				(font
					(size 1.27 1.27)
				)
			)
		)
		(duplicate_pad_numbers_are_jumpers no)
		(fp_line
			(start 0.7874 -0.4064)
			(end 0.7874 0.4064)
			(stroke
				(width 0.1524)
				(type default)
			)
			(layer "F.SilkS")
		)
		(fp_line
			(start -0.7874 -0.4064)
			(end 0.7874 -0.4064)
			(stroke
				(width 0.1524)
				(type default)
			)
			(layer "F.SilkS")
		)
		(fp_line
			(start 0.7874 0.4064)
			(end -0.7874 0.4064)
			(stroke
				(width 0.1524)
				(type default)
			)
			(layer "F.SilkS")
		)
		(fp_line
			(start -0.7874 0.4064)
			(end -0.7874 -0.4064)
			(stroke
				(width 0.1524)
				(type default)
			)
			(layer "F.SilkS")
		)
		(fp_line
			(start -0.12065 -0.305054)
			(end -0.12065 -0.2794)
			(stroke
				(width 0.1)
				(type default)
			)
			(layer "F.Fab")
		)
		(fp_line
			(start -0.67945 -0.305054)
			(end -0.12065 -0.305054)
			(stroke
				(width 0.1)
				(type default)
			)
			(layer "F.Fab")
		)
		(fp_line
			(start 0.67945 -0.3048)
			(end 0.67945 0.3048)
			(stroke
				(width 0.1)
				(type default)
			)
			(layer "F.Fab")
		)
		(fp_line
			(start 0.12065 -0.3048)
			(end 0.67945 -0.3048)
			(stroke
				(width 0.1)
				(type default)
			)
			(layer "F.Fab")
		)
		(fp_line
			(start 0.12065 -0.2794)
			(end 0.12065 -0.3048)
			(stroke
				(width 0.1)
				(type default)
			)
			(layer "F.Fab")
		)
		(fp_line
			(start -0.12065 -0.2794)
			(end 0.12065 -0.2794)
			(stroke
				(width 0.1)
				(type default)
			)
			(layer "F.Fab")
		)
		(fp_line
			(start 0.120396 0.2794)
			(end -0.12065 0.2794)
			(stroke
				(width 0.1)
				(type default)
			)
			(layer "F.Fab")
		)
		(fp_line
			(start -0.12065 0.2794)
			(end -0.12065 0.3048)
			(stroke
				(width 0.1)
				(type default)
			)
			(layer "F.Fab")
		)
		(fp_line
			(start 0.67945 0.3048)
			(end 0.120396 0.3048)
			(stroke
				(width 0.1)
				(type default)
			)
			(layer "F.Fab")
		)
		(fp_line
			(start 0.120396 0.3048)
			(end 0.120396 0.2794)
			(stroke
				(width 0.1)
				(type default)
			)
			(layer "F.Fab")
		)
		(fp_line
			(start -0.12065 0.3048)
			(end -0.67945 0.3048)
			(stroke
				(width 0.1)
				(type default)
			)
			(layer "F.Fab")
		)
		(fp_line
			(start -0.67945 0.3048)
			(end -0.67945 -0.305054)
			(stroke
				(width 0.1)
				(type default)
			)
			(layer "F.Fab")
		)
		(pad "1" smd circle
			(at -0.40005 0 90)
			(size 0 0)
			(layers "F.Cu" "F.Mask" "F.Paste")
			(net "MB_3V3IO_RSVD3")
		)
		(pad "2" smd circle
			(at 0.40005 0 90)
			(size 0 0)
			(layers "F.Cu" "F.Mask" "F.Paste")
			(net "GND")
		)
	)
	(footprint ""
		(layer "F.Cu")
		(at 36.638484 -111.895382)
		(property "Reference" "C49"
			(at 0 0 0)
			(layer "F.SilkS")
			(hide yes)
			(effects
				(font
					(size 1.27 1.27)
				)
			)
		)
		(property "Value" ""
			(at 0 0 0)
			(layer "F.Fab")
			(effects
				(font
					(size 1.27 1.27)
				)
			)
		)
		(duplicate_pad_numbers_are_jumpers no)
		(fp_line
			(start -0.299974 -0.150114)
			(end 0.299974 -0.150114)
			(stroke
				(width 0.1)
				(type default)
			)
			(layer "F.Fab")
		)
		(fp_line
			(start -0.299974 0.150114)
			(end -0.299974 -0.150114)
			(stroke
				(width 0.1)
				(type default)
			)
			(layer "F.Fab")
		)
		(fp_line
			(start 0.299974 -0.150114)
			(end 0.299974 0.150114)
			(stroke
				(width 0.1)
				(type default)
			)
			(layer "F.Fab")
		)
		(fp_line
			(start 0.299974 0.150114)
			(end -0.299974 0.150114)
			(stroke
				(width 0.1)
				(type default)
			)
			(layer "F.Fab")
		)
		(pad "1" smd rect
			(at -0.2667 0)
			(size 0.3048 0.381)
			(layers "F.Cu" "F.Mask" "F.Paste")
			(net "P5E_PEX0_STN1_TX_DN<23>")
		)
		(pad "2" smd rect
			(at 0.2667 0)
			(size 0.3048 0.381)
			(layers "F.Cu" "F.Mask" "F.Paste")
			(net "P5E_PEX0_STN1_TX_C_DN<23>")
		)
	)
	(footprint ""
		(layer "F.Cu")
		(at 301.992284 -28.225242 180)
		(property "Reference" "C510"
			(at 0 0 180)
			(layer "F.SilkS")
			(hide yes)
			(effects
				(font
					(size 1.27 1.27)
				)
			)
		)
		(property "Value" ""
			(at 0 0 180)
			(layer "F.Fab")
			(effects
				(font
					(size 1.27 1.27)
				)
			)
		)
		(duplicate_pad_numbers_are_jumpers no)
		(fp_line
			(start 0.299974 0.150114)
			(end -0.299974 0.150114)
			(stroke
				(width 0.1)
				(type default)
			)
			(layer "F.Fab")
		)
		(fp_line
			(start 0.299974 -0.150114)
			(end 0.299974 0.150114)
			(stroke
				(width 0.1)
				(type default)
			)
			(layer "F.Fab")
		)
		(fp_line
			(start -0.299974 0.150114)
			(end -0.299974 -0.150114)
			(stroke
				(width 0.1)
				(type default)
			)
			(layer "F.Fab")
		)
		(fp_line
			(start -0.299974 -0.150114)
			(end 0.299974 -0.150114)
			(stroke
				(width 0.1)
				(type default)
			)
			(layer "F.Fab")
		)
		(pad "1" smd rect
			(at -0.2667 0 180)
			(size 0.3048 0.381)
			(layers "F.Cu" "F.Mask" "F.Paste")
			(net "P5E_PEX2_STN2_TX_DN<36>")
		)
		(pad "2" smd rect
			(at 0.2667 0 180)
			(size 0.3048 0.381)
			(layers "F.Cu" "F.Mask" "F.Paste")
			(net "P5E_PEX2_STN2_TX_C_DN<36>")
		)
	)
	(footprint ""
		(layer "F.Cu")
		(at 183.923432 -356.22103 90)
		(property "Reference" "C2534"
			(at 0 0 90)
			(layer "F.SilkS")
			(hide yes)
			(effects
				(font
					(size 1.27 1.27)
				)
			)
		)
		(property "Value" ""
			(at 0 0 90)
			(layer "F.Fab")
			(effects
				(font
					(size 1.27 1.27)
				)
			)
		)
		(duplicate_pad_numbers_are_jumpers no)
		(fp_line
			(start 0.299974 -0.150114)
			(end 0.299974 0.150114)
			(stroke
				(width 0.1)
				(type default)
			)
			(layer "F.Fab")
		)
		(fp_line
			(start -0.299974 -0.150114)
			(end 0.299974 -0.150114)
			(stroke
				(width 0.1)
				(type default)
			)
			(layer "F.Fab")
		)
		(fp_line
			(start 0.299974 0.150114)
			(end -0.299974 0.150114)
			(stroke
				(width 0.1)
				(type default)
			)
			(layer "F.Fab")
		)
		(fp_line
			(start -0.299974 0.150114)
			(end -0.299974 -0.150114)
			(stroke
				(width 0.1)
				(type default)
			)
			(layer "F.Fab")
		)
		(pad "1" smd rect
			(at -0.2667 0 90)
			(size 0.3048 0.381)
			(layers "F.Cu" "F.Mask" "F.Paste")
			(net "P5E_PEX1_STN4_TX_DP<68>")
		)
		(pad "2" smd rect
			(at 0.2667 0 90)
			(size 0.3048 0.381)
			(layers "F.Cu" "F.Mask" "F.Paste")
			(net "P5E_PEX1_STN4_TX_C_DP<68>")
		)
	)
	(footprint ""
		(layer "F.Cu")
		(at 19.062446 -210.748372 90)
		(property "Reference" "R6566"
			(at 0 0 90)
			(layer "F.SilkS")
			(hide yes)
			(effects
				(font
					(size 1.27 1.27)
				)
			)
		)
		(property "Value" ""
			(at 0 0 90)
			(layer "F.Fab")
			(effects
				(font
					(size 1.27 1.27)
				)
			)
		)
		(duplicate_pad_numbers_are_jumpers no)
		(fp_line
			(start 0.7874 -0.4064)
			(end 0.7874 0.4064)
			(stroke
				(width 0.1524)
				(type default)
			)
			(layer "F.SilkS")
		)
		(fp_line
			(start -0.7874 -0.4064)
			(end 0.7874 -0.4064)
			(stroke
				(width 0.1524)
				(type default)
			)
			(layer "F.SilkS")
		)
		(fp_line
			(start 0.7874 0.4064)
			(end -0.7874 0.4064)
			(stroke
				(width 0.1524)
				(type default)
			)
			(layer "F.SilkS")
		)
		(fp_line
			(start -0.7874 0.4064)
			(end -0.7874 -0.4064)
			(stroke
				(width 0.1524)
				(type default)
			)
			(layer "F.SilkS")
		)
		(fp_line
			(start -0.12065 -0.305054)
			(end -0.12065 -0.2794)
			(stroke
				(width 0.1)
				(type default)
			)
			(layer "F.Fab")
		)
		(fp_line
			(start -0.67945 -0.305054)
			(end -0.12065 -0.305054)
			(stroke
				(width 0.1)
				(type default)
			)
			(layer "F.Fab")
		)
		(fp_line
			(start 0.67945 -0.3048)
			(end 0.67945 0.3048)
			(stroke
				(width 0.1)
				(type default)
			)
			(layer "F.Fab")
		)
		(fp_line
			(start 0.12065 -0.3048)
			(end 0.67945 -0.3048)
			(stroke
				(width 0.1)
				(type default)
			)
			(layer "F.Fab")
		)
		(fp_line
			(start 0.12065 -0.2794)
			(end 0.12065 -0.3048)
			(stroke
				(width 0.1)
				(type default)
			)
			(layer "F.Fab")
		)
		(fp_line
			(start -0.12065 -0.2794)
			(end 0.12065 -0.2794)
			(stroke
				(width 0.1)
				(type default)
			)
			(layer "F.Fab")
		)
		(fp_line
			(start 0.120396 0.2794)
			(end -0.12065 0.2794)
			(stroke
				(width 0.1)
				(type default)
			)
			(layer "F.Fab")
		)
		(fp_line
			(start -0.12065 0.2794)
			(end -0.12065 0.3048)
			(stroke
				(width 0.1)
				(type default)
			)
			(layer "F.Fab")
		)
		(fp_line
			(start 0.67945 0.3048)
			(end 0.120396 0.3048)
			(stroke
				(width 0.1)
				(type default)
			)
			(layer "F.Fab")
		)
		(fp_line
			(start 0.120396 0.3048)
			(end 0.120396 0.2794)
			(stroke
				(width 0.1)
				(type default)
			)
			(layer "F.Fab")
		)
		(fp_line
			(start -0.12065 0.3048)
			(end -0.67945 0.3048)
			(stroke
				(width 0.1)
				(type default)
			)
			(layer "F.Fab")
		)
		(fp_line
			(start -0.67945 0.3048)
			(end -0.67945 -0.305054)
			(stroke
				(width 0.1)
				(type default)
			)
			(layer "F.Fab")
		)
		(pad "1" smd circle
			(at -0.40005 0 90)
			(size 0 0)
			(layers "F.Cu" "F.Mask" "F.Paste")
			(net "P1V8_PLL0_PEX0")
		)
		(pad "2" smd circle
			(at 0.40005 0 90)
			(size 0 0)
			(layers "F.Cu" "F.Mask" "F.Paste")
			(net "P1V8_PLL_PEX0_ADJ")
		)
	)
	(footprint ""
		(layer "F.Cu")
		(at 103.06431 -29.079952 180)
		(property "Reference" "R6201"
			(at 0 0 180)
			(layer "F.SilkS")
			(hide yes)
			(effects
				(font
					(size 1.27 1.27)
				)
			)
		)
		(property "Value" ""
			(at 0 0 180)
			(layer "F.Fab")
			(effects
				(font
					(size 1.27 1.27)
				)
			)
		)
		(duplicate_pad_numbers_are_jumpers no)
		(fp_line
			(start 0.7874 0.4064)
			(end -0.7874 0.4064)
			(stroke
				(width 0.1524)
				(type default)
			)
			(layer "F.SilkS")
		)
		(fp_line
			(start 0.7874 -0.4064)
			(end 0.7874 0.4064)
			(stroke
				(width 0.1524)
				(type default)
			)
			(layer "F.SilkS")
		)
		(fp_line
			(start -0.7874 0.4064)
			(end -0.7874 -0.4064)
			(stroke
				(width 0.1524)
				(type default)
			)
			(layer "F.SilkS")
		)
		(fp_line
			(start -0.7874 -0.4064)
			(end 0.7874 -0.4064)
			(stroke
				(width 0.1524)
				(type default)
			)
			(layer "F.SilkS")
		)
		(fp_line
			(start 0.67945 0.3048)
			(end 0.120396 0.3048)
			(stroke
				(width 0.1)
				(type default)
			)
			(layer "F.Fab")
		)
		(fp_line
			(start 0.67945 -0.3048)
			(end 0.67945 0.3048)
			(stroke
				(width 0.1)
				(type default)
			)
			(layer "F.Fab")
		)
		(fp_line
			(start 0.12065 -0.2794)
			(end 0.12065 -0.3048)
			(stroke
				(width 0.1)
				(type default)
			)
			(layer "F.Fab")
		)
		(fp_line
			(start 0.12065 -0.3048)
			(end 0.67945 -0.3048)
			(stroke
				(width 0.1)
				(type default)
			)
			(layer "F.Fab")
		)
		(fp_line
			(start 0.120396 0.3048)
			(end 0.120396 0.2794)
			(stroke
				(width 0.1)
				(type default)
			)
			(layer "F.Fab")
		)
		(fp_line
			(start 0.120396 0.2794)
			(end -0.12065 0.2794)
			(stroke
				(width 0.1)
				(type default)
			)
			(layer "F.Fab")
		)
		(fp_line
			(start -0.12065 0.3048)
			(end -0.67945 0.3048)
			(stroke
				(width 0.1)
				(type default)
			)
			(layer "F.Fab")
		)
		(fp_line
			(start -0.12065 0.2794)
			(end -0.12065 0.3048)
			(stroke
				(width 0.1)
				(type default)
			)
			(layer "F.Fab")
		)
		(fp_line
			(start -0.12065 -0.2794)
			(end 0.12065 -0.2794)
			(stroke
				(width 0.1)
				(type default)
			)
			(layer "F.Fab")
		)
		(fp_line
			(start -0.12065 -0.305054)
			(end -0.12065 -0.2794)
			(stroke
				(width 0.1)
				(type default)
			)
			(layer "F.Fab")
		)
		(fp_line
			(start -0.67945 0.3048)
			(end -0.67945 -0.305054)
			(stroke
				(width 0.1)
				(type default)
			)
			(layer "F.Fab")
		)
		(fp_line
			(start -0.67945 -0.305054)
			(end -0.12065 -0.305054)
			(stroke
				(width 0.1)
				(type default)
			)
			(layer "F.Fab")
		)
		(pad "1" smd circle
			(at -0.40005 0 180)
			(size 0 0)
			(layers "F.Cu" "F.Mask" "F.Paste")
			(net "GND")
		)
		(pad "2" smd circle
			(at 0.40005 0 180)
			(size 0 0)
			(layers "F.Cu" "F.Mask" "F.Paste")
			(net "SSD3_PWRDIS_R")
		)
	)
	(footprint ""
		(layer "F.Cu")
		(at 268.838426 -109.20984)
		(property "Reference" "C476"
			(at 0 0 0)
			(layer "F.SilkS")
			(hide yes)
			(effects
				(font
					(size 1.27 1.27)
				)
			)
		)
		(property "Value" ""
			(at 0 0 0)
			(layer "F.Fab")
			(effects
				(font
					(size 1.27 1.27)
				)
			)
		)
		(duplicate_pad_numbers_are_jumpers no)
		(fp_line
			(start -0.299974 -0.150114)
			(end 0.299974 -0.150114)
			(stroke
				(width 0.1)
				(type default)
			)
			(layer "F.Fab")
		)
		(fp_line
			(start -0.299974 0.150114)
			(end -0.299974 -0.150114)
			(stroke
				(width 0.1)
				(type default)
			)
			(layer "F.Fab")
		)
		(fp_line
			(start 0.299974 -0.150114)
			(end 0.299974 0.150114)
			(stroke
				(width 0.1)
				(type default)
			)
			(layer "F.Fab")
		)
		(fp_line
			(start 0.299974 0.150114)
			(end -0.299974 0.150114)
			(stroke
				(width 0.1)
				(type default)
			)
			(layer "F.Fab")
		)
		(pad "1" smd rect
			(at -0.2667 0)
			(size 0.3048 0.381)
			(layers "F.Cu" "F.Mask" "F.Paste")
			(net "P5E_PEX2_STN1_TX_DP<21>")
		)
		(pad "2" smd rect
			(at 0.2667 0)
			(size 0.3048 0.381)
			(layers "F.Cu" "F.Mask" "F.Paste")
			(net "P5E_PEX2_STN1_TX_C_DP<21>")
		)
	)
	(footprint ""
		(layer "F.Cu")
		(at 400.543776 -43.85691)
		(property "Reference" "R651"
			(at 0 0 0)
			(layer "F.SilkS")
			(hide yes)
			(effects
				(font
					(size 1.27 1.27)
				)
			)
		)
		(property "Value" ""
			(at 0 0 0)
			(layer "F.Fab")
			(effects
				(font
					(size 1.27 1.27)
				)
			)
		)
		(duplicate_pad_numbers_are_jumpers no)
		(fp_line
			(start -0.7874 -0.4064)
			(end 0.7874 -0.4064)
			(stroke
				(width 0.1524)
				(type default)
			)
			(layer "F.SilkS")
		)
		(fp_line
			(start -0.7874 0.4064)
			(end -0.7874 -0.4064)
			(stroke
				(width 0.1524)
				(type default)
			)
			(layer "F.SilkS")
		)
		(fp_line
			(start 0.7874 -0.4064)
			(end 0.7874 0.4064)
			(stroke
				(width 0.1524)
				(type default)
			)
			(layer "F.SilkS")
		)
		(fp_line
			(start 0.7874 0.4064)
			(end -0.7874 0.4064)
			(stroke
				(width 0.1524)
				(type default)
			)
			(layer "F.SilkS")
		)
		(fp_line
			(start -0.67945 -0.305054)
			(end -0.12065 -0.305054)
			(stroke
				(width 0.1)
				(type default)
			)
			(layer "F.Fab")
		)
		(fp_line
			(start -0.67945 0.3048)
			(end -0.67945 -0.305054)
			(stroke
				(width 0.1)
				(type default)
			)
			(layer "F.Fab")
		)
		(fp_line
			(start -0.12065 -0.305054)
			(end -0.12065 -0.2794)
			(stroke
				(width 0.1)
				(type default)
			)
			(layer "F.Fab")
		)
		(fp_line
			(start -0.12065 -0.2794)
			(end 0.12065 -0.2794)
			(stroke
				(width 0.1)
				(type default)
			)
			(layer "F.Fab")
		)
		(fp_line
			(start -0.12065 0.2794)
			(end -0.12065 0.3048)
			(stroke
				(width 0.1)
				(type default)
			)
			(layer "F.Fab")
		)
		(fp_line
			(start -0.12065 0.3048)
			(end -0.67945 0.3048)
			(stroke
				(width 0.1)
				(type default)
			)
			(layer "F.Fab")
		)
		(fp_line
			(start 0.120396 0.2794)
			(end -0.12065 0.2794)
			(stroke
				(width 0.1)
				(type default)
			)
			(layer "F.Fab")
		)
		(fp_line
			(start 0.120396 0.3048)
			(end 0.120396 0.2794)
			(stroke
				(width 0.1)
				(type default)
			)
			(layer "F.Fab")
		)
		(fp_line
			(start 0.12065 -0.3048)
			(end 0.67945 -0.3048)
			(stroke
				(width 0.1)
				(type default)
			)
			(layer "F.Fab")
		)
		(fp_line
			(start 0.12065 -0.2794)
			(end 0.12065 -0.3048)
			(stroke
				(width 0.1)
				(type default)
			)
			(layer "F.Fab")
		)
		(fp_line
			(start 0.67945 -0.3048)
			(end 0.67945 0.3048)
			(stroke
				(width 0.1)
				(type default)
			)
			(layer "F.Fab")
		)
		(fp_line
			(start 0.67945 0.3048)
			(end 0.120396 0.3048)
			(stroke
				(width 0.1)
				(type default)
			)
			(layer "F.Fab")
		)
		(pad "1" smd circle
			(at -0.40005 0)
			(size 0 0)
			(layers "F.Cu" "F.Mask" "F.Paste")
			(net "SSD13_ADC_A1")
		)
		(pad "2" smd circle
			(at 0.40005 0)
			(size 0 0)
			(layers "F.Cu" "F.Mask" "F.Paste")
			(net "GND")
		)
	)
	(footprint ""
		(layer "F.Cu")
		(at 399.698718 -180.372766 180)
		(property "Reference" "R356"
			(at 0 0 180)
			(layer "F.SilkS")
			(hide yes)
			(effects
				(font
					(size 1.27 1.27)
				)
			)
		)
		(property "Value" ""
			(at 0 0 180)
			(layer "F.Fab")
			(effects
				(font
					(size 1.27 1.27)
				)
			)
		)
		(duplicate_pad_numbers_are_jumpers no)
		(fp_line
			(start 0.7874 0.4064)
			(end -0.7874 0.4064)
			(stroke
				(width 0.1524)
				(type default)
			)
			(layer "F.SilkS")
		)
		(fp_line
			(start 0.7874 -0.4064)
			(end 0.7874 0.4064)
			(stroke
				(width 0.1524)
				(type default)
			)
			(layer "F.SilkS")
		)
		(fp_line
			(start -0.7874 0.4064)
			(end -0.7874 -0.4064)
			(stroke
				(width 0.1524)
				(type default)
			)
			(layer "F.SilkS")
		)
		(fp_line
			(start -0.7874 -0.4064)
			(end 0.7874 -0.4064)
			(stroke
				(width 0.1524)
				(type default)
			)
			(layer "F.SilkS")
		)
		(fp_line
			(start 0.67945 0.3048)
			(end 0.120396 0.3048)
			(stroke
				(width 0.1)
				(type default)
			)
			(layer "F.Fab")
		)
		(fp_line
			(start 0.67945 -0.3048)
			(end 0.67945 0.3048)
			(stroke
				(width 0.1)
				(type default)
			)
			(layer "F.Fab")
		)
		(fp_line
			(start 0.12065 -0.2794)
			(end 0.12065 -0.3048)
			(stroke
				(width 0.1)
				(type default)
			)
			(layer "F.Fab")
		)
		(fp_line
			(start 0.12065 -0.3048)
			(end 0.67945 -0.3048)
			(stroke
				(width 0.1)
				(type default)
			)
			(layer "F.Fab")
		)
		(fp_line
			(start 0.120396 0.3048)
			(end 0.120396 0.2794)
			(stroke
				(width 0.1)
				(type default)
			)
			(layer "F.Fab")
		)
		(fp_line
			(start 0.120396 0.2794)
			(end -0.12065 0.2794)
			(stroke
				(width 0.1)
				(type default)
			)
			(layer "F.Fab")
		)
		(fp_line
			(start -0.12065 0.3048)
			(end -0.67945 0.3048)
			(stroke
				(width 0.1)
				(type default)
			)
			(layer "F.Fab")
		)
		(fp_line
			(start -0.12065 0.2794)
			(end -0.12065 0.3048)
			(stroke
				(width 0.1)
				(type default)
			)
			(layer "F.Fab")
		)
		(fp_line
			(start -0.12065 -0.2794)
			(end 0.12065 -0.2794)
			(stroke
				(width 0.1)
				(type default)
			)
			(layer "F.Fab")
		)
		(fp_line
			(start -0.12065 -0.305054)
			(end -0.12065 -0.2794)
			(stroke
				(width 0.1)
				(type default)
			)
			(layer "F.Fab")
		)
		(fp_line
			(start -0.67945 0.3048)
			(end -0.67945 -0.305054)
			(stroke
				(width 0.1)
				(type default)
			)
			(layer "F.Fab")
		)
		(fp_line
			(start -0.67945 -0.305054)
			(end -0.12065 -0.305054)
			(stroke
				(width 0.1)
				(type default)
			)
			(layer "F.Fab")
		)
		(pad "1" smd circle
			(at -0.40005 0 180)
			(size 0 0)
			(layers "F.Cu" "F.Mask" "F.Paste")
			(net "P3V3_AUX")
		)
		(pad "2" smd circle
			(at 0.40005 0 180)
			(size 0 0)
			(layers "F.Cu" "F.Mask" "F.Paste")
			(net "HP_NIC6_HSC_PWRGD_N")
		)
	)
	(footprint ""
		(layer "F.Cu")
		(at 251.97943 -92.096336 -90)
		(property "Reference" "R1066"
			(at 0 0 270)
			(layer "F.SilkS")
			(hide yes)
			(effects
				(font
					(size 1.27 1.27)
				)
			)
		)
		(property "Value" ""
			(at 0 0 270)
			(layer "F.Fab")
			(effects
				(font
					(size 1.27 1.27)
				)
			)
		)
		(duplicate_pad_numbers_are_jumpers no)
		(fp_line
			(start -0.7874 0.4064)
			(end -0.7874 -0.4064)
			(stroke
				(width 0.1524)
				(type default)
			)
			(layer "F.SilkS")
		)
		(fp_line
			(start 0.7874 0.4064)
			(end -0.7874 0.4064)
			(stroke
				(width 0.1524)
				(type default)
			)
			(layer "F.SilkS")
		)
		(fp_line
			(start -0.7874 -0.4064)
			(end 0.7874 -0.4064)
			(stroke
				(width 0.1524)
				(type default)
			)
			(layer "F.SilkS")
		)
		(fp_line
			(start 0.7874 -0.4064)
			(end 0.7874 0.4064)
			(stroke
				(width 0.1524)
				(type default)
			)
			(layer "F.SilkS")
		)
		(fp_line
			(start -0.67945 0.3048)
			(end -0.67945 -0.305054)
			(stroke
				(width 0.1)
				(type default)
			)
			(layer "F.Fab")
		)
		(fp_line
			(start -0.12065 0.3048)
			(end -0.67945 0.3048)
			(stroke
				(width 0.1)
				(type default)
			)
			(layer "F.Fab")
		)
		(fp_line
			(start 0.120396 0.3048)
			(end 0.120396 0.2794)
			(stroke
				(width 0.1)
				(type default)
			)
			(layer "F.Fab")
		)
		(fp_line
			(start 0.67945 0.3048)
			(end 0.120396 0.3048)
			(stroke
				(width 0.1)
				(type default)
			)
			(layer "F.Fab")
		)
		(fp_line
			(start -0.12065 0.2794)
			(end -0.12065 0.3048)
			(stroke
				(width 0.1)
				(type default)
			)
			(layer "F.Fab")
		)
		(fp_line
			(start 0.120396 0.2794)
			(end -0.12065 0.2794)
			(stroke
				(width 0.1)
				(type default)
			)
			(layer "F.Fab")
		)
		(fp_line
			(start -0.12065 -0.2794)
			(end 0.12065 -0.2794)
			(stroke
				(width 0.1)
				(type default)
			)
			(layer "F.Fab")
		)
		(fp_line
			(start 0.12065 -0.2794)
			(end 0.12065 -0.3048)
			(stroke
				(width 0.1)
				(type default)
			)
			(layer "F.Fab")
		)
		(fp_line
			(start 0.12065 -0.3048)
			(end 0.67945 -0.3048)
			(stroke
				(width 0.1)
				(type default)
			)
			(layer "F.Fab")
		)
		(fp_line
			(start 0.67945 -0.3048)
			(end 0.67945 0.3048)
			(stroke
				(width 0.1)
				(type default)
			)
			(layer "F.Fab")
		)
		(fp_line
			(start -0.67945 -0.305054)
			(end -0.12065 -0.305054)
			(stroke
				(width 0.1)
				(type default)
			)
			(layer "F.Fab")
		)
		(fp_line
			(start -0.12065 -0.305054)
			(end -0.12065 -0.2794)
			(stroke
				(width 0.1)
				(type default)
			)
			(layer "F.Fab")
		)
		(pad "1" smd circle
			(at -0.40005 0 270)
			(size 0 0)
			(layers "F.Cu" "F.Mask" "F.Paste")
			(net "GND")
		)
		(pad "2" smd circle
			(at 0.40005 0 270)
			(size 0 0)
			(layers "F.Cu" "F.Mask" "F.Paste")
			(net "PD_CK440_SBI_CLK")
		)
	)
	(footprint ""
		(layer "F.Cu")
		(at 122.675904 -36.915598 -90)
		(property "Reference" "R5553"
			(at 0 0 270)
			(layer "F.SilkS")
			(hide yes)
			(effects
				(font
					(size 1.27 1.27)
				)
			)
		)
		(property "Value" ""
			(at 0 0 270)
			(layer "F.Fab")
			(effects
				(font
					(size 1.27 1.27)
				)
			)
		)
		(duplicate_pad_numbers_are_jumpers no)
		(fp_line
			(start -0.7874 0.4064)
			(end -0.7874 -0.4064)
			(stroke
				(width 0.1524)
				(type default)
			)
			(layer "F.SilkS")
		)
		(fp_line
			(start 0.7874 0.4064)
			(end -0.7874 0.4064)
			(stroke
				(width 0.1524)
				(type default)
			)
			(layer "F.SilkS")
		)
		(fp_line
			(start -0.7874 -0.4064)
			(end 0.7874 -0.4064)
			(stroke
				(width 0.1524)
				(type default)
			)
			(layer "F.SilkS")
		)
		(fp_line
			(start 0.7874 -0.4064)
			(end 0.7874 0.4064)
			(stroke
				(width 0.1524)
				(type default)
			)
			(layer "F.SilkS")
		)
		(fp_line
			(start -0.67945 0.3048)
			(end -0.67945 -0.305054)
			(stroke
				(width 0.1)
				(type default)
			)
			(layer "F.Fab")
		)
		(fp_line
			(start -0.12065 0.3048)
			(end -0.67945 0.3048)
			(stroke
				(width 0.1)
				(type default)
			)
			(layer "F.Fab")
		)
		(fp_line
			(start 0.120396 0.3048)
			(end 0.120396 0.2794)
			(stroke
				(width 0.1)
				(type default)
			)
			(layer "F.Fab")
		)
		(fp_line
			(start 0.67945 0.3048)
			(end 0.120396 0.3048)
			(stroke
				(width 0.1)
				(type default)
			)
			(layer "F.Fab")
		)
		(fp_line
			(start -0.12065 0.2794)
			(end -0.12065 0.3048)
			(stroke
				(width 0.1)
				(type default)
			)
			(layer "F.Fab")
		)
		(fp_line
			(start 0.120396 0.2794)
			(end -0.12065 0.2794)
			(stroke
				(width 0.1)
				(type default)
			)
			(layer "F.Fab")
		)
		(fp_line
			(start -0.12065 -0.2794)
			(end 0.12065 -0.2794)
			(stroke
				(width 0.1)
				(type default)
			)
			(layer "F.Fab")
		)
		(fp_line
			(start 0.12065 -0.2794)
			(end 0.12065 -0.3048)
			(stroke
				(width 0.1)
				(type default)
			)
			(layer "F.Fab")
		)
		(fp_line
			(start 0.12065 -0.3048)
			(end 0.67945 -0.3048)
			(stroke
				(width 0.1)
				(type default)
			)
			(layer "F.Fab")
		)
		(fp_line
			(start 0.67945 -0.3048)
			(end 0.67945 0.3048)
			(stroke
				(width 0.1)
				(type default)
			)
			(layer "F.Fab")
		)
		(fp_line
			(start -0.67945 -0.305054)
			(end -0.12065 -0.305054)
			(stroke
				(width 0.1)
				(type default)
			)
			(layer "F.Fab")
		)
		(fp_line
			(start -0.12065 -0.305054)
			(end -0.12065 -0.2794)
			(stroke
				(width 0.1)
				(type default)
			)
			(layer "F.Fab")
		)
		(pad "1" smd circle
			(at -0.40005 0 270)
			(size 0 0)
			(layers "F.Cu" "F.Mask" "F.Paste")
			(net "PRSNT_SSD4_R1_N")
		)
		(pad "2" smd circle
			(at 0.40005 0 270)
			(size 0 0)
			(layers "F.Cu" "F.Mask" "F.Paste")
			(net "PRSNT_SSD4_R_N")
		)
	)
	(footprint ""
		(layer "F.Cu")
		(at 460.508858 -308.21884 -90)
		(property "Reference" "PC981"
			(at 0 0 270)
			(layer "F.SilkS")
			(hide yes)
			(effects
				(font
					(size 1.27 1.27)
				)
			)
		)
		(property "Value" ""
			(at 0 0 270)
			(layer "F.Fab")
			(effects
				(font
					(size 1.27 1.27)
				)
			)
		)
		(duplicate_pad_numbers_are_jumpers no)
		(fp_line
			(start -0.7874 0.4064)
			(end -0.7874 -0.4064)
			(stroke
				(width 0.1524)
				(type default)
			)
			(layer "F.SilkS")
		)
		(fp_line
			(start 0.7874 0.4064)
			(end -0.7874 0.4064)
			(stroke
				(width 0.1524)
				(type default)
			)
			(layer "F.SilkS")
		)
		(fp_line
			(start -0.7874 -0.4064)
			(end 0.7874 -0.4064)
			(stroke
				(width 0.1524)
				(type default)
			)
			(layer "F.SilkS")
		)
		(fp_line
			(start 0.7874 -0.4064)
			(end 0.7874 0.4064)
			(stroke
				(width 0.1524)
				(type default)
			)
			(layer "F.SilkS")
		)
		(fp_line
			(start -0.67945 0.3048)
			(end -0.67945 -0.305054)
			(stroke
				(width 0.1)
				(type default)
			)
			(layer "F.Fab")
		)
		(fp_line
			(start -0.12065 0.3048)
			(end -0.67945 0.3048)
			(stroke
				(width 0.1)
				(type default)
			)
			(layer "F.Fab")
		)
		(fp_line
			(start 0.120396 0.3048)
			(end 0.120396 0.2794)
			(stroke
				(width 0.1)
				(type default)
			)
			(layer "F.Fab")
		)
		(fp_line
			(start 0.67945 0.3048)
			(end 0.120396 0.3048)
			(stroke
				(width 0.1)
				(type default)
			)
			(layer "F.Fab")
		)
		(fp_line
			(start -0.12065 0.2794)
			(end -0.12065 0.3048)
			(stroke
				(width 0.1)
				(type default)
			)
			(layer "F.Fab")
		)
		(fp_line
			(start 0.120396 0.2794)
			(end -0.12065 0.2794)
			(stroke
				(width 0.1)
				(type default)
			)
			(layer "F.Fab")
		)
		(fp_line
			(start -0.12065 -0.2794)
			(end 0.12065 -0.2794)
			(stroke
				(width 0.1)
				(type default)
			)
			(layer "F.Fab")
		)
		(fp_line
			(start 0.12065 -0.2794)
			(end 0.12065 -0.3048)
			(stroke
				(width 0.1)
				(type default)
			)
			(layer "F.Fab")
		)
		(fp_line
			(start 0.12065 -0.3048)
			(end 0.67945 -0.3048)
			(stroke
				(width 0.1)
				(type default)
			)
			(layer "F.Fab")
		)
		(fp_line
			(start 0.67945 -0.3048)
			(end 0.67945 0.3048)
			(stroke
				(width 0.1)
				(type default)
			)
			(layer "F.Fab")
		)
		(fp_line
			(start -0.67945 -0.305054)
			(end -0.12065 -0.305054)
			(stroke
				(width 0.1)
				(type default)
			)
			(layer "F.Fab")
		)
		(fp_line
			(start -0.12065 -0.305054)
			(end -0.12065 -0.2794)
			(stroke
				(width 0.1)
				(type default)
			)
			(layer "F.Fab")
		)
		(pad "1" smd circle
			(at -0.40005 0 270)
			(size 0 0)
			(layers "F.Cu" "F.Mask" "F.Paste")
			(net "SH_P1V25_PEX3_FB_P")
		)
		(pad "2" smd circle
			(at 0.40005 0 270)
			(size 0 0)
			(layers "F.Cu" "F.Mask" "F.Paste")
			(net "SH_P1V25_PEX3_FB_N")
		)
	)
	(footprint ""
		(layer "F.Cu")
		(at 265.487658 -282.018232)
		(property "Reference" "C3415"
			(at 0 0 0)
			(layer "F.SilkS")
			(hide yes)
			(effects
				(font
					(size 1.27 1.27)
				)
			)
		)
		(property "Value" ""
			(at 0 0 0)
			(layer "F.Fab")
			(effects
				(font
					(size 1.27 1.27)
				)
			)
		)
		(duplicate_pad_numbers_are_jumpers no)
		(fp_line
			(start -1.2954 -0.5842)
			(end 1.2954 -0.5842)
			(stroke
				(width 0.1524)
				(type default)
			)
			(layer "F.SilkS")
		)
		(fp_line
			(start -1.2954 0.5842)
			(end -1.2954 -0.5842)
			(stroke
				(width 0.1524)
				(type default)
			)
			(layer "F.SilkS")
		)
		(fp_line
			(start 1.2954 -0.5842)
			(end 1.2954 0.5842)
			(stroke
				(width 0.1524)
				(type default)
			)
			(layer "F.SilkS")
		)
		(fp_line
			(start 1.2954 0.5842)
			(end -1.2954 0.5842)
			(stroke
				(width 0.1524)
				(type default)
			)
			(layer "F.SilkS")
		)
		(fp_line
			(start -1.1938 -0.4064)
			(end -0.8636 -0.4064)
			(stroke
				(width 0.1)
				(type default)
			)
			(layer "F.Fab")
		)
		(fp_line
			(start -1.1938 0.4064)
			(end -1.1938 -0.4064)
			(stroke
				(width 0.1)
				(type default)
			)
			(layer "F.Fab")
		)
		(fp_line
			(start -0.8636 -0.4572)
			(end 0.8636 -0.4572)
			(stroke
				(width 0.1)
				(type default)
			)
			(layer "F.Fab")
		)
		(fp_line
			(start -0.8636 -0.4064)
			(end -0.8636 -0.4572)
			(stroke
				(width 0.1)
				(type default)
			)
			(layer "F.Fab")
		)
		(fp_line
			(start -0.8636 0.4064)
			(end -1.1938 0.4064)
			(stroke
				(width 0.1)
				(type default)
			)
			(layer "F.Fab")
		)
		(fp_line
			(start -0.8636 0.4572)
			(end -0.8636 0.4064)
			(stroke
				(width 0.1)
				(type default)
			)
			(layer "F.Fab")
		)
		(fp_line
			(start 0.8636 -0.4572)
			(end 0.8636 -0.4064)
			(stroke
				(width 0.1)
				(type default)
			)
			(layer "F.Fab")
		)
		(fp_line
			(start 0.8636 -0.4064)
			(end 1.1938 -0.4064)
			(stroke
				(width 0.1)
				(type default)
			)
			(layer "F.Fab")
		)
		(fp_line
			(start 0.8636 0.4064)
			(end 0.8636 0.4572)
			(stroke
				(width 0.1)
				(type default)
			)
			(layer "F.Fab")
		)
		(fp_line
			(start 0.8636 0.4572)
			(end -0.8636 0.4572)
			(stroke
				(width 0.1)
				(type default)
			)
			(layer "F.Fab")
		)
		(fp_line
			(start 1.1938 -0.4064)
			(end 1.1938 0.4064)
			(stroke
				(width 0.1)
				(type default)
			)
			(layer "F.Fab")
		)
		(fp_line
			(start 1.1938 0.4064)
			(end 0.8636 0.4064)
			(stroke
				(width 0.1)
				(type default)
			)
			(layer "F.Fab")
		)
		(pad "1" smd rect
			(at -0.7366 0 270)
			(size 0.7112 0.8128)
			(layers "F.Cu" "F.Mask" "F.Paste")
			(net "SYSPLL_VDDA18_PEX2")
		)
		(pad "2" smd rect
			(at 0.7366 0 270)
			(size 0.7112 0.8128)
			(layers "F.Cu" "F.Mask" "F.Paste")
			(net "GND")
		)
	)
	(footprint ""
		(layer "F.Cu")
		(at 431.889408 -63.56223)
		(property "Reference" "Q211"
			(at 0.384302 -2.492756 0)
			(unlocked yes)
			(layer "F.SilkS")
			(effects
				(font
					(size 0.7874 0.5842)
					(thickness 0.1524)
				)
			)
		)
		(property "Value" ""
			(at 0 0 0)
			(layer "F.Fab")
			(effects
				(font
					(size 1.27 1.27)
				)
			)
		)
		(duplicate_pad_numbers_are_jumpers no)
		(fp_line
			(start -1.376172 -1.199896)
			(end -0.508 -1.199896)
			(stroke
				(width 0.1524)
				(type default)
			)
			(layer "F.SilkS")
		)
		(fp_line
			(start -1.376172 1.199896)
			(end -1.376172 -1.199896)
			(stroke
				(width 0.1524)
				(type default)
			)
			(layer "F.SilkS")
		)
		(fp_line
			(start -0.508 -1.199896)
			(end 0 -0.762)
			(stroke
				(width 0.1524)
				(type default)
			)
			(layer "F.SilkS")
		)
		(fp_line
			(start 0 -0.762)
			(end 0.508 -1.199896)
			(stroke
				(width 0.1524)
				(type default)
			)
			(layer "F.SilkS")
		)
		(fp_line
			(start 0.508 -1.199896)
			(end 1.376172 -1.199896)
			(stroke
				(width 0.1524)
				(type default)
			)
			(layer "F.SilkS")
		)
		(fp_line
			(start 1.376172 -1.199896)
			(end 1.376172 1.199896)
			(stroke
				(width 0.1524)
				(type default)
			)
			(layer "F.SilkS")
		)
		(fp_line
			(start 1.376172 1.199896)
			(end -1.376172 1.199896)
			(stroke
				(width 0.1524)
				(type default)
			)
			(layer "F.SilkS")
		)
		(fp_poly
			(pts
				(xy -1.561846 -1.107948) (xy -1.83134 -1.916176) (xy -2.370074 -1.377442)
			)
			(stroke
				(width 0)
				(type default)
			)
			(fill yes)
			(layer "F.SilkS")
		)
		(fp_line
			(start -0.674878 -1.100074)
			(end 0.674878 -1.100074)
			(stroke
				(width 0.1)
				(type default)
			)
			(layer "F.Fab")
		)
		(fp_line
			(start -0.674878 1.100074)
			(end -0.674878 -1.100074)
			(stroke
				(width 0.1)
				(type default)
			)
			(layer "F.Fab")
		)
		(fp_line
			(start 0.674878 -1.100074)
			(end 0.674878 1.100074)
			(stroke
				(width 0.1)
				(type default)
			)
			(layer "F.Fab")
		)
		(fp_line
			(start 0.674878 1.100074)
			(end -0.674878 1.100074)
			(stroke
				(width 0.1)
				(type default)
			)
			(layer "F.Fab")
		)
		(fp_poly
			(pts
				(xy -1.4605 -0.7493) (xy -2.2225 -1.1303) (xy -2.2225 -0.3683)
			)
			(stroke
				(width 0)
				(type default)
			)
			(fill yes)
			(layer "F.Fab")
		)
		(pad "1" smd rect
			(at -0.899922 -0.750062 270)
			(size 0.6096 0.6096)
			(layers "F.Cu" "F.Mask" "F.Paste")
			(net "GND")
		)
		(pad "2" smd rect
			(at -0.899922 0 270)
			(size 0.4064 0.6096)
			(layers "F.Cu" "F.Mask" "F.Paste")
			(net "P12V_SSD15_PG_G1")
		)
		(pad "3" smd rect
			(at -0.899922 0.750062 270)
			(size 0.6096 0.6096)
			(layers "F.Cu" "F.Mask" "F.Paste")
			(net "PWRGD_P12V_SSD15_D")
		)
		(pad "4" smd rect
			(at 0.899922 0.750062 270)
			(size 0.6096 0.6096)
			(layers "F.Cu" "F.Mask" "F.Paste")
			(net "GND")
		)
		(pad "5" smd rect
			(at 0.899922 0 270)
			(size 0.4064 0.6096)
			(layers "F.Cu" "F.Mask" "F.Paste")
			(net "P12V_SSD15_PG_G2")
		)
		(pad "6" smd rect
			(at 0.899922 -0.750062 270)
			(size 0.6096 0.6096)
			(layers "F.Cu" "F.Mask" "F.Paste")
			(net "P12V_SSD15_PG_G2")
		)
	)
	(footprint ""
		(layer "F.Cu")
		(at 460.524098 -530.228048)
		(property "Reference" "SCREW_8"
			(at -0.5842 -1.31953 0)
			(unlocked yes)
			(layer "B.SilkS")
			(effects
				(font
					(size 0.7874 0.5842)
					(thickness 0.1524)
				)
				(justify left mirror)
			)
		)
		(property "Value" ""
			(at 0 0 0)
			(layer "F.Fab")
			(effects
				(font
					(size 1.27 1.27)
				)
			)
		)
		(duplicate_pad_numbers_are_jumpers no)
		(pad "1" thru_hole circle
			(at 0 0)
			(size 0.4572 0.4572)
			(drill 0.2032)
			(layers "*.Cu" "*.Mask")
			(remove_unused_layers no)
			(net "Net_9293")
			(clearance 0.127)
			(thermal_gap 0.127)
			(padstack
				(mode front_inner_back)
				(layer "Inner"
					(shape circle)
					(size 0.4572 0.4572)
					(clearance 0.127)
				)
				(layer "B.Cu"
					(shape circle)
					(size 0.508 0.508)
					(clearance 0.1016)
				)
			)
		)
	)
	(footprint ""
		(layer "F.Cu")
		(at 322.221098 -298.87291 -90)
		(property "Reference" "R4018"
			(at 0 0 270)
			(layer "F.SilkS")
			(hide yes)
			(effects
				(font
					(size 1.27 1.27)
				)
			)
		)
		(property "Value" ""
			(at 0 0 270)
			(layer "F.Fab")
			(effects
				(font
					(size 1.27 1.27)
				)
			)
		)
		(duplicate_pad_numbers_are_jumpers no)
		(fp_line
			(start -0.7874 0.4064)
			(end -0.7874 -0.4064)
			(stroke
				(width 0.1524)
				(type default)
			)
			(layer "F.SilkS")
		)
		(fp_line
			(start 0.7874 0.4064)
			(end -0.7874 0.4064)
			(stroke
				(width 0.1524)
				(type default)
			)
			(layer "F.SilkS")
		)
		(fp_line
			(start -0.7874 -0.4064)
			(end 0.7874 -0.4064)
			(stroke
				(width 0.1524)
				(type default)
			)
			(layer "F.SilkS")
		)
		(fp_line
			(start 0.7874 -0.4064)
			(end 0.7874 0.4064)
			(stroke
				(width 0.1524)
				(type default)
			)
			(layer "F.SilkS")
		)
		(fp_line
			(start -0.67945 0.3048)
			(end -0.67945 -0.305054)
			(stroke
				(width 0.1)
				(type default)
			)
			(layer "F.Fab")
		)
		(fp_line
			(start -0.12065 0.3048)
			(end -0.67945 0.3048)
			(stroke
				(width 0.1)
				(type default)
			)
			(layer "F.Fab")
		)
		(fp_line
			(start 0.120396 0.3048)
			(end 0.120396 0.2794)
			(stroke
				(width 0.1)
				(type default)
			)
			(layer "F.Fab")
		)
		(fp_line
			(start 0.67945 0.3048)
			(end 0.120396 0.3048)
			(stroke
				(width 0.1)
				(type default)
			)
			(layer "F.Fab")
		)
		(fp_line
			(start -0.12065 0.2794)
			(end -0.12065 0.3048)
			(stroke
				(width 0.1)
				(type default)
			)
			(layer "F.Fab")
		)
		(fp_line
			(start 0.120396 0.2794)
			(end -0.12065 0.2794)
			(stroke
				(width 0.1)
				(type default)
			)
			(layer "F.Fab")
		)
		(fp_line
			(start -0.12065 -0.2794)
			(end 0.12065 -0.2794)
			(stroke
				(width 0.1)
				(type default)
			)
			(layer "F.Fab")
		)
		(fp_line
			(start 0.12065 -0.2794)
			(end 0.12065 -0.3048)
			(stroke
				(width 0.1)
				(type default)
			)
			(layer "F.Fab")
		)
		(fp_line
			(start 0.12065 -0.3048)
			(end 0.67945 -0.3048)
			(stroke
				(width 0.1)
				(type default)
			)
			(layer "F.Fab")
		)
		(fp_line
			(start 0.67945 -0.3048)
			(end 0.67945 0.3048)
			(stroke
				(width 0.1)
				(type default)
			)
			(layer "F.Fab")
		)
		(fp_line
			(start -0.67945 -0.305054)
			(end -0.12065 -0.305054)
			(stroke
				(width 0.1)
				(type default)
			)
			(layer "F.Fab")
		)
		(fp_line
			(start -0.12065 -0.305054)
			(end -0.12065 -0.2794)
			(stroke
				(width 0.1)
				(type default)
			)
			(layer "F.Fab")
		)
		(pad "1" smd circle
			(at -0.40005 0 270)
			(size 0 0)
			(layers "F.Cu" "F.Mask" "F.Paste")
			(net "P1V8_PEX")
		)
		(pad "2" smd circle
			(at 0.40005 0 270)
			(size 0 0)
			(layers "F.Cu" "F.Mask" "F.Paste")
			(net "I2C_PEX2_HOST_R_SDA")
		)
	)
	(footprint ""
		(layer "F.Cu")
		(at 348.88424 -29.222954 -90)
		(property "Reference" "PC948"
			(at 0 0 270)
			(layer "F.SilkS")
			(hide yes)
			(effects
				(font
					(size 1.27 1.27)
				)
			)
		)
		(property "Value" ""
			(at 0 0 270)
			(layer "F.Fab")
			(effects
				(font
					(size 1.27 1.27)
				)
			)
		)
		(duplicate_pad_numbers_are_jumpers no)
		(fp_line
			(start -0.7874 0.4064)
			(end -0.7874 -0.4064)
			(stroke
				(width 0.1524)
				(type default)
			)
			(layer "F.SilkS")
		)
		(fp_line
			(start 0.7874 0.4064)
			(end -0.7874 0.4064)
			(stroke
				(width 0.1524)
				(type default)
			)
			(layer "F.SilkS")
		)
		(fp_line
			(start -0.7874 -0.4064)
			(end 0.7874 -0.4064)
			(stroke
				(width 0.1524)
				(type default)
			)
			(layer "F.SilkS")
		)
		(fp_line
			(start 0.7874 -0.4064)
			(end 0.7874 0.4064)
			(stroke
				(width 0.1524)
				(type default)
			)
			(layer "F.SilkS")
		)
		(fp_line
			(start -0.67945 0.3048)
			(end -0.67945 -0.305054)
			(stroke
				(width 0.1)
				(type default)
			)
			(layer "F.Fab")
		)
		(fp_line
			(start -0.12065 0.3048)
			(end -0.67945 0.3048)
			(stroke
				(width 0.1)
				(type default)
			)
			(layer "F.Fab")
		)
		(fp_line
			(start 0.120396 0.3048)
			(end 0.120396 0.2794)
			(stroke
				(width 0.1)
				(type default)
			)
			(layer "F.Fab")
		)
		(fp_line
			(start 0.67945 0.3048)
			(end 0.120396 0.3048)
			(stroke
				(width 0.1)
				(type default)
			)
			(layer "F.Fab")
		)
		(fp_line
			(start -0.12065 0.2794)
			(end -0.12065 0.3048)
			(stroke
				(width 0.1)
				(type default)
			)
			(layer "F.Fab")
		)
		(fp_line
			(start 0.120396 0.2794)
			(end -0.12065 0.2794)
			(stroke
				(width 0.1)
				(type default)
			)
			(layer "F.Fab")
		)
		(fp_line
			(start -0.12065 -0.2794)
			(end 0.12065 -0.2794)
			(stroke
				(width 0.1)
				(type default)
			)
			(layer "F.Fab")
		)
		(fp_line
			(start 0.12065 -0.2794)
			(end 0.12065 -0.3048)
			(stroke
				(width 0.1)
				(type default)
			)
			(layer "F.Fab")
		)
		(fp_line
			(start 0.12065 -0.3048)
			(end 0.67945 -0.3048)
			(stroke
				(width 0.1)
				(type default)
			)
			(layer "F.Fab")
		)
		(fp_line
			(start 0.67945 -0.3048)
			(end 0.67945 0.3048)
			(stroke
				(width 0.1)
				(type default)
			)
			(layer "F.Fab")
		)
		(fp_line
			(start -0.67945 -0.305054)
			(end -0.12065 -0.305054)
			(stroke
				(width 0.1)
				(type default)
			)
			(layer "F.Fab")
		)
		(fp_line
			(start -0.12065 -0.305054)
			(end -0.12065 -0.2794)
			(stroke
				(width 0.1)
				(type default)
			)
			(layer "F.Fab")
		)
		(pad "1" smd circle
			(at -0.40005 0 270)
			(size 0 0)
			(layers "F.Cu" "F.Mask" "F.Paste")
			(net "P3V3_AUX")
		)
		(pad "2" smd circle
			(at 0.40005 0 270)
			(size 0 0)
			(layers "F.Cu" "F.Mask" "F.Paste")
			(net "GND")
		)
	)
	(footprint ""
		(layer "F.Cu")
		(at 246.870728 -112.139476 -90)
		(property "Reference" "PR7100"
			(at 0 0 270)
			(layer "F.SilkS")
			(hide yes)
			(effects
				(font
					(size 1.27 1.27)
				)
			)
		)
		(property "Value" ""
			(at 0 0 270)
			(layer "F.Fab")
			(effects
				(font
					(size 1.27 1.27)
				)
			)
		)
		(duplicate_pad_numbers_are_jumpers no)
		(fp_line
			(start -0.7874 0.4064)
			(end -0.7874 -0.4064)
			(stroke
				(width 0.1524)
				(type default)
			)
			(layer "F.SilkS")
		)
		(fp_line
			(start 0.7874 0.4064)
			(end -0.7874 0.4064)
			(stroke
				(width 0.1524)
				(type default)
			)
			(layer "F.SilkS")
		)
		(fp_line
			(start -0.7874 -0.4064)
			(end 0.7874 -0.4064)
			(stroke
				(width 0.1524)
				(type default)
			)
			(layer "F.SilkS")
		)
		(fp_line
			(start 0.7874 -0.4064)
			(end 0.7874 0.4064)
			(stroke
				(width 0.1524)
				(type default)
			)
			(layer "F.SilkS")
		)
		(fp_line
			(start -0.67945 0.3048)
			(end -0.67945 -0.305054)
			(stroke
				(width 0.1)
				(type default)
			)
			(layer "F.Fab")
		)
		(fp_line
			(start -0.12065 0.3048)
			(end -0.67945 0.3048)
			(stroke
				(width 0.1)
				(type default)
			)
			(layer "F.Fab")
		)
		(fp_line
			(start 0.120396 0.3048)
			(end 0.120396 0.2794)
			(stroke
				(width 0.1)
				(type default)
			)
			(layer "F.Fab")
		)
		(fp_line
			(start 0.67945 0.3048)
			(end 0.120396 0.3048)
			(stroke
				(width 0.1)
				(type default)
			)
			(layer "F.Fab")
		)
		(fp_line
			(start -0.12065 0.2794)
			(end -0.12065 0.3048)
			(stroke
				(width 0.1)
				(type default)
			)
			(layer "F.Fab")
		)
		(fp_line
			(start 0.120396 0.2794)
			(end -0.12065 0.2794)
			(stroke
				(width 0.1)
				(type default)
			)
			(layer "F.Fab")
		)
		(fp_line
			(start -0.12065 -0.2794)
			(end 0.12065 -0.2794)
			(stroke
				(width 0.1)
				(type default)
			)
			(layer "F.Fab")
		)
		(fp_line
			(start 0.12065 -0.2794)
			(end 0.12065 -0.3048)
			(stroke
				(width 0.1)
				(type default)
			)
			(layer "F.Fab")
		)
		(fp_line
			(start 0.12065 -0.3048)
			(end 0.67945 -0.3048)
			(stroke
				(width 0.1)
				(type default)
			)
			(layer "F.Fab")
		)
		(fp_line
			(start 0.67945 -0.3048)
			(end 0.67945 0.3048)
			(stroke
				(width 0.1)
				(type default)
			)
			(layer "F.Fab")
		)
		(fp_line
			(start -0.67945 -0.305054)
			(end -0.12065 -0.305054)
			(stroke
				(width 0.1)
				(type default)
			)
			(layer "F.Fab")
		)
		(fp_line
			(start -0.12065 -0.305054)
			(end -0.12065 -0.2794)
			(stroke
				(width 0.1)
				(type default)
			)
			(layer "F.Fab")
		)
		(pad "1" smd circle
			(at -0.40005 0 270)
			(size 0 0)
			(layers "F.Cu" "F.Mask" "F.Paste")
			(net "P3V3_NIC4_CO_ILIMIT")
		)
		(pad "2" smd circle
			(at 0.40005 0 270)
			(size 0 0)
			(layers "F.Cu" "F.Mask" "F.Paste")
			(net "GND")
		)
	)
	(footprint ""
		(layer "F.Cu")
		(at 33.319974 -20.72005)
		(property "Reference" "H108"
			(at 4.382262 2.165858 0)
			(unlocked yes)
			(layer "B.SilkS")
			(effects
				(font
					(size 0.7874 0.5842)
					(thickness 0.1524)
				)
				(justify left mirror)
			)
		)
		(property "Value" ""
			(at 0 0 0)
			(layer "F.Fab")
			(effects
				(font
					(size 1.27 1.27)
				)
			)
		)
		(duplicate_pad_numbers_are_jumpers no)
		(pad "1" thru_hole rect
			(at 0 0)
			(size 4.2164 5.0038)
			(drill 2.0066
				(offset 0.099822 0)
			)
			(layers "*.Cu" "*.Mask")
			(remove_unused_layers no)
			(net "Net_8555")
			(clearance -0.8509)
			(padstack
				(mode front_inner_back)
				(layer "Inner"
					(shape circle)
					(size 4.0132 4.0132)
					(clearance -0.7493)
				)
				(layer "B.Cu"
					(shape circle)
					(size 4.0132 4.0132)
					(clearance -0.7493)
				)
			)
		)
	)
	(footprint ""
		(layer "F.Cu")
		(at 375.426224 -37.929566 90)
		(property "Reference" "R5573"
			(at 0 0 90)
			(layer "F.SilkS")
			(hide yes)
			(effects
				(font
					(size 1.27 1.27)
				)
			)
		)
		(property "Value" ""
			(at 0 0 90)
			(layer "F.Fab")
			(effects
				(font
					(size 1.27 1.27)
				)
			)
		)
		(duplicate_pad_numbers_are_jumpers no)
		(fp_line
			(start 0.7874 -0.4064)
			(end 0.7874 0.4064)
			(stroke
				(width 0.1524)
				(type default)
			)
			(layer "F.SilkS")
		)
		(fp_line
			(start -0.7874 -0.4064)
			(end 0.7874 -0.4064)
			(stroke
				(width 0.1524)
				(type default)
			)
			(layer "F.SilkS")
		)
		(fp_line
			(start 0.7874 0.4064)
			(end -0.7874 0.4064)
			(stroke
				(width 0.1524)
				(type default)
			)
			(layer "F.SilkS")
		)
		(fp_line
			(start -0.7874 0.4064)
			(end -0.7874 -0.4064)
			(stroke
				(width 0.1524)
				(type default)
			)
			(layer "F.SilkS")
		)
		(fp_line
			(start -0.12065 -0.305054)
			(end -0.12065 -0.2794)
			(stroke
				(width 0.1)
				(type default)
			)
			(layer "F.Fab")
		)
		(fp_line
			(start -0.67945 -0.305054)
			(end -0.12065 -0.305054)
			(stroke
				(width 0.1)
				(type default)
			)
			(layer "F.Fab")
		)
		(fp_line
			(start 0.67945 -0.3048)
			(end 0.67945 0.3048)
			(stroke
				(width 0.1)
				(type default)
			)
			(layer "F.Fab")
		)
		(fp_line
			(start 0.12065 -0.3048)
			(end 0.67945 -0.3048)
			(stroke
				(width 0.1)
				(type default)
			)
			(layer "F.Fab")
		)
		(fp_line
			(start 0.12065 -0.2794)
			(end 0.12065 -0.3048)
			(stroke
				(width 0.1)
				(type default)
			)
			(layer "F.Fab")
		)
		(fp_line
			(start -0.12065 -0.2794)
			(end 0.12065 -0.2794)
			(stroke
				(width 0.1)
				(type default)
			)
			(layer "F.Fab")
		)
		(fp_line
			(start 0.120396 0.2794)
			(end -0.12065 0.2794)
			(stroke
				(width 0.1)
				(type default)
			)
			(layer "F.Fab")
		)
		(fp_line
			(start -0.12065 0.2794)
			(end -0.12065 0.3048)
			(stroke
				(width 0.1)
				(type default)
			)
			(layer "F.Fab")
		)
		(fp_line
			(start 0.67945 0.3048)
			(end 0.120396 0.3048)
			(stroke
				(width 0.1)
				(type default)
			)
			(layer "F.Fab")
		)
		(fp_line
			(start 0.120396 0.3048)
			(end 0.120396 0.2794)
			(stroke
				(width 0.1)
				(type default)
			)
			(layer "F.Fab")
		)
		(fp_line
			(start -0.12065 0.3048)
			(end -0.67945 0.3048)
			(stroke
				(width 0.1)
				(type default)
			)
			(layer "F.Fab")
		)
		(fp_line
			(start -0.67945 0.3048)
			(end -0.67945 -0.305054)
			(stroke
				(width 0.1)
				(type default)
			)
			(layer "F.Fab")
		)
		(pad "1" smd circle
			(at -0.40005 0 90)
			(size 0 0)
			(layers "F.Cu" "F.Mask" "F.Paste")
			(net "SSD13_AUX_P3V3_EN_R")
		)
		(pad "2" smd circle
			(at 0.40005 0 90)
			(size 0 0)
			(layers "F.Cu" "F.Mask" "F.Paste")
			(net "SSD13_AUX_P3V3_EN")
		)
	)
	(footprint ""
		(layer "F.Cu")
		(at 213.935056 -214.32266)
		(property "Reference" "R4878"
			(at 0 0 0)
			(layer "F.SilkS")
			(hide yes)
			(effects
				(font
					(size 1.27 1.27)
				)
			)
		)
		(property "Value" ""
			(at 0 0 0)
			(layer "F.Fab")
			(effects
				(font
					(size 1.27 1.27)
				)
			)
		)
		(duplicate_pad_numbers_are_jumpers no)
		(fp_line
			(start -0.7874 -0.4064)
			(end 0.7874 -0.4064)
			(stroke
				(width 0.1524)
				(type default)
			)
			(layer "F.SilkS")
		)
		(fp_line
			(start -0.7874 0.4064)
			(end -0.7874 -0.4064)
			(stroke
				(width 0.1524)
				(type default)
			)
			(layer "F.SilkS")
		)
		(fp_line
			(start 0.7874 -0.4064)
			(end 0.7874 0.4064)
			(stroke
				(width 0.1524)
				(type default)
			)
			(layer "F.SilkS")
		)
		(fp_line
			(start 0.7874 0.4064)
			(end -0.7874 0.4064)
			(stroke
				(width 0.1524)
				(type default)
			)
			(layer "F.SilkS")
		)
		(fp_line
			(start -0.67945 -0.305054)
			(end -0.12065 -0.305054)
			(stroke
				(width 0.1)
				(type default)
			)
			(layer "F.Fab")
		)
		(fp_line
			(start -0.67945 0.3048)
			(end -0.67945 -0.305054)
			(stroke
				(width 0.1)
				(type default)
			)
			(layer "F.Fab")
		)
		(fp_line
			(start -0.12065 -0.305054)
			(end -0.12065 -0.2794)
			(stroke
				(width 0.1)
				(type default)
			)
			(layer "F.Fab")
		)
		(fp_line
			(start -0.12065 -0.2794)
			(end 0.12065 -0.2794)
			(stroke
				(width 0.1)
				(type default)
			)
			(layer "F.Fab")
		)
		(fp_line
			(start -0.12065 0.2794)
			(end -0.12065 0.3048)
			(stroke
				(width 0.1)
				(type default)
			)
			(layer "F.Fab")
		)
		(fp_line
			(start -0.12065 0.3048)
			(end -0.67945 0.3048)
			(stroke
				(width 0.1)
				(type default)
			)
			(layer "F.Fab")
		)
		(fp_line
			(start 0.120396 0.2794)
			(end -0.12065 0.2794)
			(stroke
				(width 0.1)
				(type default)
			)
			(layer "F.Fab")
		)
		(fp_line
			(start 0.120396 0.3048)
			(end 0.120396 0.2794)
			(stroke
				(width 0.1)
				(type default)
			)
			(layer "F.Fab")
		)
		(fp_line
			(start 0.12065 -0.3048)
			(end 0.67945 -0.3048)
			(stroke
				(width 0.1)
				(type default)
			)
			(layer "F.Fab")
		)
		(fp_line
			(start 0.12065 -0.2794)
			(end 0.12065 -0.3048)
			(stroke
				(width 0.1)
				(type default)
			)
			(layer "F.Fab")
		)
		(fp_line
			(start 0.67945 -0.3048)
			(end 0.67945 0.3048)
			(stroke
				(width 0.1)
				(type default)
			)
			(layer "F.Fab")
		)
		(fp_line
			(start 0.67945 0.3048)
			(end 0.120396 0.3048)
			(stroke
				(width 0.1)
				(type default)
			)
			(layer "F.Fab")
		)
		(pad "1" smd circle
			(at -0.40005 0)
			(size 0 0)
			(layers "F.Cu" "F.Mask" "F.Paste")
			(net "P1V2_AUX")
		)
		(pad "2" smd circle
			(at 0.40005 0)
			(size 0 0)
			(layers "F.Cu" "F.Mask" "F.Paste")
			(net "SMB_NIC6_SDA")
		)
	)
	(footprint ""
		(layer "F.Cu")
		(at 72.483726 -6.897624)
		(property "Reference" "R5808"
			(at 0 0 0)
			(layer "F.SilkS")
			(hide yes)
			(effects
				(font
					(size 1.27 1.27)
				)
			)
		)
		(property "Value" ""
			(at 0 0 0)
			(layer "F.Fab")
			(effects
				(font
					(size 1.27 1.27)
				)
			)
		)
		(duplicate_pad_numbers_are_jumpers no)
		(fp_line
			(start -0.7874 -0.4064)
			(end 0.7874 -0.4064)
			(stroke
				(width 0.1524)
				(type default)
			)
			(layer "F.SilkS")
		)
		(fp_line
			(start -0.7874 0.4064)
			(end -0.7874 -0.4064)
			(stroke
				(width 0.1524)
				(type default)
			)
			(layer "F.SilkS")
		)
		(fp_line
			(start 0.7874 -0.4064)
			(end 0.7874 0.4064)
			(stroke
				(width 0.1524)
				(type default)
			)
			(layer "F.SilkS")
		)
		(fp_line
			(start 0.7874 0.4064)
			(end -0.7874 0.4064)
			(stroke
				(width 0.1524)
				(type default)
			)
			(layer "F.SilkS")
		)
		(fp_line
			(start -0.67945 -0.305054)
			(end -0.12065 -0.305054)
			(stroke
				(width 0.1)
				(type default)
			)
			(layer "F.Fab")
		)
		(fp_line
			(start -0.67945 0.3048)
			(end -0.67945 -0.305054)
			(stroke
				(width 0.1)
				(type default)
			)
			(layer "F.Fab")
		)
		(fp_line
			(start -0.12065 -0.305054)
			(end -0.12065 -0.2794)
			(stroke
				(width 0.1)
				(type default)
			)
			(layer "F.Fab")
		)
		(fp_line
			(start -0.12065 -0.2794)
			(end 0.12065 -0.2794)
			(stroke
				(width 0.1)
				(type default)
			)
			(layer "F.Fab")
		)
		(fp_line
			(start -0.12065 0.2794)
			(end -0.12065 0.3048)
			(stroke
				(width 0.1)
				(type default)
			)
			(layer "F.Fab")
		)
		(fp_line
			(start -0.12065 0.3048)
			(end -0.67945 0.3048)
			(stroke
				(width 0.1)
				(type default)
			)
			(layer "F.Fab")
		)
		(fp_line
			(start 0.120396 0.2794)
			(end -0.12065 0.2794)
			(stroke
				(width 0.1)
				(type default)
			)
			(layer "F.Fab")
		)
		(fp_line
			(start 0.120396 0.3048)
			(end 0.120396 0.2794)
			(stroke
				(width 0.1)
				(type default)
			)
			(layer "F.Fab")
		)
		(fp_line
			(start 0.12065 -0.3048)
			(end 0.67945 -0.3048)
			(stroke
				(width 0.1)
				(type default)
			)
			(layer "F.Fab")
		)
		(fp_line
			(start 0.12065 -0.2794)
			(end 0.12065 -0.3048)
			(stroke
				(width 0.1)
				(type default)
			)
			(layer "F.Fab")
		)
		(fp_line
			(start 0.67945 -0.3048)
			(end 0.67945 0.3048)
			(stroke
				(width 0.1)
				(type default)
			)
			(layer "F.Fab")
		)
		(fp_line
			(start 0.67945 0.3048)
			(end 0.120396 0.3048)
			(stroke
				(width 0.1)
				(type default)
			)
			(layer "F.Fab")
		)
		(pad "1" smd circle
			(at -0.40005 0)
			(size 0 0)
			(layers "F.Cu" "F.Mask" "F.Paste")
			(net "SMB_BIC_I2C6_MUX_THERMAL_R_SDA")
		)
		(pad "2" smd circle
			(at 0.40005 0)
			(size 0 0)
			(layers "F.Cu" "F.Mask" "F.Paste")
			(net "SMB_LM75_2_SDA")
		)
	)
	(footprint ""
		(layer "F.Cu")
		(at 428.319438 -123.184666 180)
		(property "Reference" "C660"
			(at 0 0 180)
			(layer "F.SilkS")
			(hide yes)
			(effects
				(font
					(size 1.27 1.27)
				)
			)
		)
		(property "Value" ""
			(at 0 0 180)
			(layer "F.Fab")
			(effects
				(font
					(size 1.27 1.27)
				)
			)
		)
		(duplicate_pad_numbers_are_jumpers no)
		(fp_line
			(start 0.299974 0.150114)
			(end -0.299974 0.150114)
			(stroke
				(width 0.1)
				(type default)
			)
			(layer "F.Fab")
		)
		(fp_line
			(start 0.299974 -0.150114)
			(end 0.299974 0.150114)
			(stroke
				(width 0.1)
				(type default)
			)
			(layer "F.Fab")
		)
		(fp_line
			(start -0.299974 0.150114)
			(end -0.299974 -0.150114)
			(stroke
				(width 0.1)
				(type default)
			)
			(layer "F.Fab")
		)
		(fp_line
			(start -0.299974 -0.150114)
			(end 0.299974 -0.150114)
			(stroke
				(width 0.1)
				(type default)
			)
			(layer "F.Fab")
		)
		(pad "1" smd rect
			(at -0.2667 0 180)
			(size 0.3048 0.381)
			(layers "F.Cu" "F.Mask" "F.Paste")
			(net "P5E_PEX3_STN0_TX_DP<2>")
		)
		(pad "2" smd rect
			(at 0.2667 0 180)
			(size 0.3048 0.381)
			(layers "F.Cu" "F.Mask" "F.Paste")
			(net "P5E_PEX3_STN0_TX_C_DP<2>")
		)
	)
	(footprint ""
		(layer "F.Cu")
		(at 460.340964 -521.743686 180)
		(property "Reference" "SCREW_4"
			(at -3.2385 -1.402334 0)
			(unlocked yes)
			(layer "B.SilkS")
			(effects
				(font
					(size 0.7874 0.5842)
					(thickness 0.1524)
				)
				(justify mirror)
			)
		)
		(property "Value" ""
			(at 0 0 180)
			(layer "F.Fab")
			(effects
				(font
					(size 1.27 1.27)
				)
			)
		)
		(duplicate_pad_numbers_are_jumpers no)
		(pad "1" thru_hole circle
			(at 0 0 180)
			(size 0.4572 0.4572)
			(drill 0.2032)
			(layers "*.Cu" "*.Mask")
			(remove_unused_layers no)
			(net "Net_9160")
			(clearance 0.127)
			(thermal_gap 0.127)
			(padstack
				(mode front_inner_back)
				(layer "Inner"
					(shape circle)
					(size 0.4572 0.4572)
					(clearance 0.127)
				)
				(layer "B.Cu"
					(shape circle)
					(size 0.508 0.508)
					(clearance 0.1016)
				)
			)
		)
	)
	(footprint ""
		(layer "F.Cu")
		(at 26.952702 -262.649208 90)
		(property "Reference" "C3016"
			(at 0 0 90)
			(layer "F.SilkS")
			(hide yes)
			(effects
				(font
					(size 1.27 1.27)
				)
			)
		)
		(property "Value" ""
			(at 0 0 90)
			(layer "F.Fab")
			(effects
				(font
					(size 1.27 1.27)
				)
			)
		)
		(duplicate_pad_numbers_are_jumpers no)
		(fp_line
			(start 0.299974 -0.150114)
			(end 0.299974 0.150114)
			(stroke
				(width 0.1)
				(type default)
			)
			(layer "F.Fab")
		)
		(fp_line
			(start -0.299974 -0.150114)
			(end 0.299974 -0.150114)
			(stroke
				(width 0.1)
				(type default)
			)
			(layer "F.Fab")
		)
		(fp_line
			(start 0.299974 0.150114)
			(end -0.299974 0.150114)
			(stroke
				(width 0.1)
				(type default)
			)
			(layer "F.Fab")
		)
		(fp_line
			(start -0.299974 0.150114)
			(end -0.299974 -0.150114)
			(stroke
				(width 0.1)
				(type default)
			)
			(layer "F.Fab")
		)
		(pad "1" smd rect
			(at -0.2667 0 90)
			(size 0.3048 0.381)
			(layers "F.Cu" "F.Mask" "F.Paste")
			(net "P1V8_PLL0_PEX0")
		)
		(pad "2" smd rect
			(at 0.2667 0 90)
			(size 0.3048 0.381)
			(layers "F.Cu" "F.Mask" "F.Paste")
			(net "GND")
		)
	)
	(footprint ""
		(layer "F.Cu")
		(at 446.734438 -33.631886 180)
		(property "Reference" "C723"
			(at 0 0 180)
			(layer "F.SilkS")
			(hide yes)
			(effects
				(font
					(size 1.27 1.27)
				)
			)
		)
		(property "Value" ""
			(at 0 0 180)
			(layer "F.Fab")
			(effects
				(font
					(size 1.27 1.27)
				)
			)
		)
		(duplicate_pad_numbers_are_jumpers no)
		(fp_line
			(start 0.299974 0.150114)
			(end -0.299974 0.150114)
			(stroke
				(width 0.1)
				(type default)
			)
			(layer "F.Fab")
		)
		(fp_line
			(start 0.299974 -0.150114)
			(end 0.299974 0.150114)
			(stroke
				(width 0.1)
				(type default)
			)
			(layer "F.Fab")
		)
		(fp_line
			(start -0.299974 0.150114)
			(end -0.299974 -0.150114)
			(stroke
				(width 0.1)
				(type default)
			)
			(layer "F.Fab")
		)
		(fp_line
			(start -0.299974 -0.150114)
			(end 0.299974 -0.150114)
			(stroke
				(width 0.1)
				(type default)
			)
			(layer "F.Fab")
		)
		(pad "1" smd rect
			(at -0.2667 0 180)
			(size 0.3048 0.381)
			(layers "F.Cu" "F.Mask" "F.Paste")
			(net "P5E_PEX3_STN2_TX_DN<35>")
		)
		(pad "2" smd rect
			(at 0.2667 0 180)
			(size 0.3048 0.381)
			(layers "F.Cu" "F.Mask" "F.Paste")
			(net "P5E_PEX3_STN2_TX_C_DN<35>")
		)
	)
	(footprint ""
		(layer "F.Cu")
		(at 347.966792 -240.691162 90)
		(property "Reference" "R3527"
			(at 0 0 90)
			(layer "F.SilkS")
			(hide yes)
			(effects
				(font
					(size 1.27 1.27)
				)
			)
		)
		(property "Value" ""
			(at 0 0 90)
			(layer "F.Fab")
			(effects
				(font
					(size 1.27 1.27)
				)
			)
		)
		(duplicate_pad_numbers_are_jumpers no)
		(fp_line
			(start 0.7874 -0.4064)
			(end 0.7874 0.4064)
			(stroke
				(width 0.1524)
				(type default)
			)
			(layer "F.SilkS")
		)
		(fp_line
			(start -0.7874 -0.4064)
			(end 0.7874 -0.4064)
			(stroke
				(width 0.1524)
				(type default)
			)
			(layer "F.SilkS")
		)
		(fp_line
			(start 0.7874 0.4064)
			(end -0.7874 0.4064)
			(stroke
				(width 0.1524)
				(type default)
			)
			(layer "F.SilkS")
		)
		(fp_line
			(start -0.7874 0.4064)
			(end -0.7874 -0.4064)
			(stroke
				(width 0.1524)
				(type default)
			)
			(layer "F.SilkS")
		)
		(fp_line
			(start -0.12065 -0.305054)
			(end -0.12065 -0.2794)
			(stroke
				(width 0.1)
				(type default)
			)
			(layer "F.Fab")
		)
		(fp_line
			(start -0.67945 -0.305054)
			(end -0.12065 -0.305054)
			(stroke
				(width 0.1)
				(type default)
			)
			(layer "F.Fab")
		)
		(fp_line
			(start 0.67945 -0.3048)
			(end 0.67945 0.3048)
			(stroke
				(width 0.1)
				(type default)
			)
			(layer "F.Fab")
		)
		(fp_line
			(start 0.12065 -0.3048)
			(end 0.67945 -0.3048)
			(stroke
				(width 0.1)
				(type default)
			)
			(layer "F.Fab")
		)
		(fp_line
			(start 0.12065 -0.2794)
			(end 0.12065 -0.3048)
			(stroke
				(width 0.1)
				(type default)
			)
			(layer "F.Fab")
		)
		(fp_line
			(start -0.12065 -0.2794)
			(end 0.12065 -0.2794)
			(stroke
				(width 0.1)
				(type default)
			)
			(layer "F.Fab")
		)
		(fp_line
			(start 0.120396 0.2794)
			(end -0.12065 0.2794)
			(stroke
				(width 0.1)
				(type default)
			)
			(layer "F.Fab")
		)
		(fp_line
			(start -0.12065 0.2794)
			(end -0.12065 0.3048)
			(stroke
				(width 0.1)
				(type default)
			)
			(layer "F.Fab")
		)
		(fp_line
			(start 0.67945 0.3048)
			(end 0.120396 0.3048)
			(stroke
				(width 0.1)
				(type default)
			)
			(layer "F.Fab")
		)
		(fp_line
			(start 0.120396 0.3048)
			(end 0.120396 0.2794)
			(stroke
				(width 0.1)
				(type default)
			)
			(layer "F.Fab")
		)
		(fp_line
			(start -0.12065 0.3048)
			(end -0.67945 0.3048)
			(stroke
				(width 0.1)
				(type default)
			)
			(layer "F.Fab")
		)
		(fp_line
			(start -0.67945 0.3048)
			(end -0.67945 -0.305054)
			(stroke
				(width 0.1)
				(type default)
			)
			(layer "F.Fab")
		)
		(pad "1" smd circle
			(at -0.40005 0 90)
			(size 0 0)
			(layers "F.Cu" "F.Mask" "F.Paste")
			(net "SSD2_CLK_EN_N")
		)
		(pad "2" smd circle
			(at 0.40005 0 90)
			(size 0 0)
			(layers "F.Cu" "F.Mask" "F.Paste")
			(net "SSD2_CLK_EN_R_N")
		)
	)
	(footprint ""
		(layer "F.Cu")
		(at 230.749094 -174.69358)
		(property "Reference" "R3148"
			(at 0 0 0)
			(layer "F.SilkS")
			(hide yes)
			(effects
				(font
					(size 1.27 1.27)
				)
			)
		)
		(property "Value" ""
			(at 0 0 0)
			(layer "F.Fab")
			(effects
				(font
					(size 1.27 1.27)
				)
			)
		)
		(duplicate_pad_numbers_are_jumpers no)
		(fp_line
			(start -0.7874 -0.4064)
			(end 0.7874 -0.4064)
			(stroke
				(width 0.1524)
				(type default)
			)
			(layer "F.SilkS")
		)
		(fp_line
			(start -0.7874 0.4064)
			(end -0.7874 -0.4064)
			(stroke
				(width 0.1524)
				(type default)
			)
			(layer "F.SilkS")
		)
		(fp_line
			(start 0.7874 -0.4064)
			(end 0.7874 0.4064)
			(stroke
				(width 0.1524)
				(type default)
			)
			(layer "F.SilkS")
		)
		(fp_line
			(start 0.7874 0.4064)
			(end -0.7874 0.4064)
			(stroke
				(width 0.1524)
				(type default)
			)
			(layer "F.SilkS")
		)
		(fp_line
			(start -0.67945 -0.305054)
			(end -0.12065 -0.305054)
			(stroke
				(width 0.1)
				(type default)
			)
			(layer "F.Fab")
		)
		(fp_line
			(start -0.67945 0.3048)
			(end -0.67945 -0.305054)
			(stroke
				(width 0.1)
				(type default)
			)
			(layer "F.Fab")
		)
		(fp_line
			(start -0.12065 -0.305054)
			(end -0.12065 -0.2794)
			(stroke
				(width 0.1)
				(type default)
			)
			(layer "F.Fab")
		)
		(fp_line
			(start -0.12065 -0.2794)
			(end 0.12065 -0.2794)
			(stroke
				(width 0.1)
				(type default)
			)
			(layer "F.Fab")
		)
		(fp_line
			(start -0.12065 0.2794)
			(end -0.12065 0.3048)
			(stroke
				(width 0.1)
				(type default)
			)
			(layer "F.Fab")
		)
		(fp_line
			(start -0.12065 0.3048)
			(end -0.67945 0.3048)
			(stroke
				(width 0.1)
				(type default)
			)
			(layer "F.Fab")
		)
		(fp_line
			(start 0.120396 0.2794)
			(end -0.12065 0.2794)
			(stroke
				(width 0.1)
				(type default)
			)
			(layer "F.Fab")
		)
		(fp_line
			(start 0.120396 0.3048)
			(end 0.120396 0.2794)
			(stroke
				(width 0.1)
				(type default)
			)
			(layer "F.Fab")
		)
		(fp_line
			(start 0.12065 -0.3048)
			(end 0.67945 -0.3048)
			(stroke
				(width 0.1)
				(type default)
			)
			(layer "F.Fab")
		)
		(fp_line
			(start 0.12065 -0.2794)
			(end 0.12065 -0.3048)
			(stroke
				(width 0.1)
				(type default)
			)
			(layer "F.Fab")
		)
		(fp_line
			(start 0.67945 -0.3048)
			(end 0.67945 0.3048)
			(stroke
				(width 0.1)
				(type default)
			)
			(layer "F.Fab")
		)
		(fp_line
			(start 0.67945 0.3048)
			(end 0.120396 0.3048)
			(stroke
				(width 0.1)
				(type default)
			)
			(layer "F.Fab")
		)
		(pad "1" smd circle
			(at -0.40005 0)
			(size 0 0)
			(layers "F.Cu" "F.Mask" "F.Paste")
			(net "ADM1085_ENOUT")
		)
		(pad "2" smd circle
			(at 0.40005 0)
			(size 0 0)
			(layers "F.Cu" "F.Mask" "F.Paste")
			(net "P3V3_AUX")
		)
	)
	(footprint ""
		(layer "F.Cu")
		(at 69.792342 -31.825184 180)
		(property "Reference" "C84"
			(at 0 0 180)
			(layer "F.SilkS")
			(hide yes)
			(effects
				(font
					(size 1.27 1.27)
				)
			)
		)
		(property "Value" ""
			(at 0 0 180)
			(layer "F.Fab")
			(effects
				(font
					(size 1.27 1.27)
				)
			)
		)
		(duplicate_pad_numbers_are_jumpers no)
		(fp_line
			(start 0.299974 0.150114)
			(end -0.299974 0.150114)
			(stroke
				(width 0.1)
				(type default)
			)
			(layer "F.Fab")
		)
		(fp_line
			(start 0.299974 -0.150114)
			(end 0.299974 0.150114)
			(stroke
				(width 0.1)
				(type default)
			)
			(layer "F.Fab")
		)
		(fp_line
			(start -0.299974 0.150114)
			(end -0.299974 -0.150114)
			(stroke
				(width 0.1)
				(type default)
			)
			(layer "F.Fab")
		)
		(fp_line
			(start -0.299974 -0.150114)
			(end 0.299974 -0.150114)
			(stroke
				(width 0.1)
				(type default)
			)
			(layer "F.Fab")
		)
		(pad "1" smd rect
			(at -0.2667 0 180)
			(size 0.3048 0.381)
			(layers "F.Cu" "F.Mask" "F.Paste")
			(net "P5E_PEX0_STN2_TX_DN<38>")
		)
		(pad "2" smd rect
			(at 0.2667 0 180)
			(size 0.3048 0.381)
			(layers "F.Cu" "F.Mask" "F.Paste")
			(net "P5E_PEX0_STN2_TX_C_DN<38>")
		)
	)
	(footprint ""
		(layer "F.Cu")
		(at 214.225378 -42.849038 180)
		(property "Reference" "R590"
			(at 0 0 180)
			(layer "F.SilkS")
			(hide yes)
			(effects
				(font
					(size 1.27 1.27)
				)
			)
		)
		(property "Value" ""
			(at 0 0 180)
			(layer "F.Fab")
			(effects
				(font
					(size 1.27 1.27)
				)
			)
		)
		(duplicate_pad_numbers_are_jumpers no)
		(fp_line
			(start 0.7874 0.4064)
			(end -0.7874 0.4064)
			(stroke
				(width 0.1524)
				(type default)
			)
			(layer "F.SilkS")
		)
		(fp_line
			(start 0.7874 -0.4064)
			(end 0.7874 0.4064)
			(stroke
				(width 0.1524)
				(type default)
			)
			(layer "F.SilkS")
		)
		(fp_line
			(start -0.7874 0.4064)
			(end -0.7874 -0.4064)
			(stroke
				(width 0.1524)
				(type default)
			)
			(layer "F.SilkS")
		)
		(fp_line
			(start -0.7874 -0.4064)
			(end 0.7874 -0.4064)
			(stroke
				(width 0.1524)
				(type default)
			)
			(layer "F.SilkS")
		)
		(fp_line
			(start 0.67945 0.3048)
			(end 0.120396 0.3048)
			(stroke
				(width 0.1)
				(type default)
			)
			(layer "F.Fab")
		)
		(fp_line
			(start 0.67945 -0.3048)
			(end 0.67945 0.3048)
			(stroke
				(width 0.1)
				(type default)
			)
			(layer "F.Fab")
		)
		(fp_line
			(start 0.12065 -0.2794)
			(end 0.12065 -0.3048)
			(stroke
				(width 0.1)
				(type default)
			)
			(layer "F.Fab")
		)
		(fp_line
			(start 0.12065 -0.3048)
			(end 0.67945 -0.3048)
			(stroke
				(width 0.1)
				(type default)
			)
			(layer "F.Fab")
		)
		(fp_line
			(start 0.120396 0.3048)
			(end 0.120396 0.2794)
			(stroke
				(width 0.1)
				(type default)
			)
			(layer "F.Fab")
		)
		(fp_line
			(start 0.120396 0.2794)
			(end -0.12065 0.2794)
			(stroke
				(width 0.1)
				(type default)
			)
			(layer "F.Fab")
		)
		(fp_line
			(start -0.12065 0.3048)
			(end -0.67945 0.3048)
			(stroke
				(width 0.1)
				(type default)
			)
			(layer "F.Fab")
		)
		(fp_line
			(start -0.12065 0.2794)
			(end -0.12065 0.3048)
			(stroke
				(width 0.1)
				(type default)
			)
			(layer "F.Fab")
		)
		(fp_line
			(start -0.12065 -0.2794)
			(end 0.12065 -0.2794)
			(stroke
				(width 0.1)
				(type default)
			)
			(layer "F.Fab")
		)
		(fp_line
			(start -0.12065 -0.305054)
			(end -0.12065 -0.2794)
			(stroke
				(width 0.1)
				(type default)
			)
			(layer "F.Fab")
		)
		(fp_line
			(start -0.67945 0.3048)
			(end -0.67945 -0.305054)
			(stroke
				(width 0.1)
				(type default)
			)
			(layer "F.Fab")
		)
		(fp_line
			(start -0.67945 -0.305054)
			(end -0.12065 -0.305054)
			(stroke
				(width 0.1)
				(type default)
			)
			(layer "F.Fab")
		)
		(pad "1" smd circle
			(at -0.40005 0 180)
			(size 0 0)
			(layers "F.Cu" "F.Mask" "F.Paste")
			(net "P12V_SSD7_R")
		)
		(pad "2" smd circle
			(at 0.40005 0 180)
			(size 0 0)
			(layers "F.Cu" "F.Mask" "F.Paste")
			(net "P12V_SSD7_VIN_P")
		)
	)
	(footprint ""
		(layer "F.Cu")
		(at 36.638484 -108.29544)
		(property "Reference" "C53"
			(at 0 0 0)
			(layer "F.SilkS")
			(hide yes)
			(effects
				(font
					(size 1.27 1.27)
				)
			)
		)
		(property "Value" ""
			(at 0 0 0)
			(layer "F.Fab")
			(effects
				(font
					(size 1.27 1.27)
				)
			)
		)
		(duplicate_pad_numbers_are_jumpers no)
		(fp_line
			(start -0.299974 -0.150114)
			(end 0.299974 -0.150114)
			(stroke
				(width 0.1)
				(type default)
			)
			(layer "F.Fab")
		)
		(fp_line
			(start -0.299974 0.150114)
			(end -0.299974 -0.150114)
			(stroke
				(width 0.1)
				(type default)
			)
			(layer "F.Fab")
		)
		(fp_line
			(start 0.299974 -0.150114)
			(end 0.299974 0.150114)
			(stroke
				(width 0.1)
				(type default)
			)
			(layer "F.Fab")
		)
		(fp_line
			(start 0.299974 0.150114)
			(end -0.299974 0.150114)
			(stroke
				(width 0.1)
				(type default)
			)
			(layer "F.Fab")
		)
		(pad "1" smd rect
			(at -0.2667 0)
			(size 0.3048 0.381)
			(layers "F.Cu" "F.Mask" "F.Paste")
			(net "P5E_PEX0_STN1_TX_DN<21>")
		)
		(pad "2" smd rect
			(at 0.2667 0)
			(size 0.3048 0.381)
			(layers "F.Cu" "F.Mask" "F.Paste")
			(net "P5E_PEX0_STN1_TX_C_DN<21>")
		)
	)
	(footprint ""
		(layer "F.Cu")
		(at 398.493488 -172.004482 -90)
		(property "Reference" "U41"
			(at 1.062482 2.303018 90)
			(unlocked yes)
			(layer "F.SilkS")
			(effects
				(font
					(size 0.7874 0.5842)
					(thickness 0.1524)
				)
				(justify left)
			)
		)
		(property "Value" ""
			(at 0 0 270)
			(layer "F.Fab")
			(effects
				(font
					(size 1.27 1.27)
				)
			)
		)
		(duplicate_pad_numbers_are_jumpers no)
		(fp_line
			(start -2.0574 1.651)
			(end -2.0574 -1.651)
			(stroke
				(width 0.1524)
				(type default)
			)
			(layer "F.SilkS")
		)
		(fp_line
			(start 2.0574 1.651)
			(end -2.0574 1.651)
			(stroke
				(width 0.1524)
				(type default)
			)
			(layer "F.SilkS")
		)
		(fp_line
			(start 0 -1.016)
			(end 0.381 -1.651)
			(stroke
				(width 0.1524)
				(type default)
			)
			(layer "F.SilkS")
		)
		(fp_line
			(start -2.0574 -1.651)
			(end -0.381 -1.651)
			(stroke
				(width 0.1524)
				(type default)
			)
			(layer "F.SilkS")
		)
		(fp_line
			(start -0.381 -1.651)
			(end 0 -1.016)
			(stroke
				(width 0.1524)
				(type default)
			)
			(layer "F.SilkS")
		)
		(fp_line
			(start 0.381 -1.651)
			(end 2.0574 -1.651)
			(stroke
				(width 0.1524)
				(type default)
			)
			(layer "F.SilkS")
		)
		(fp_line
			(start 2.0574 -1.651)
			(end 2.0574 1.651)
			(stroke
				(width 0.1524)
				(type default)
			)
			(layer "F.SilkS")
		)
		(fp_poly
			(pts
				(xy -2.71272 -0.719328) (xy -2.71272 -1.344168) (xy -2.159 -1.016)
			)
			(stroke
				(width 0)
				(type default)
			)
			(fill yes)
			(layer "F.SilkS")
		)
		(fp_line
			(start -0.899922 1.549908)
			(end -0.899922 1.199896)
			(stroke
				(width 0.1)
				(type default)
			)
			(layer "F.Fab")
		)
		(fp_line
			(start 0.899922 1.549908)
			(end -0.899922 1.549908)
			(stroke
				(width 0.1)
				(type default)
			)
			(layer "F.Fab")
		)
		(fp_line
			(start -1.599946 1.199896)
			(end -1.599946 -1.199896)
			(stroke
				(width 0.1)
				(type default)
			)
			(layer "F.Fab")
		)
		(fp_line
			(start -0.899922 1.199896)
			(end -1.599946 1.199896)
			(stroke
				(width 0.1)
				(type default)
			)
			(layer "F.Fab")
		)
		(fp_line
			(start 0.899922 1.199896)
			(end 0.899922 1.549908)
			(stroke
				(width 0.1)
				(type default)
			)
			(layer "F.Fab")
		)
		(fp_line
			(start 1.599946 1.199896)
			(end 0.899922 1.199896)
			(stroke
				(width 0.1)
				(type default)
			)
			(layer "F.Fab")
		)
		(fp_line
			(start -1.599946 -1.199896)
			(end -0.899922 -1.199896)
			(stroke
				(width 0.1)
				(type default)
			)
			(layer "F.Fab")
		)
		(fp_line
			(start -0.899922 -1.199896)
			(end -0.899922 -1.549908)
			(stroke
				(width 0.1)
				(type default)
			)
			(layer "F.Fab")
		)
		(fp_line
			(start 0.899922 -1.199896)
			(end 1.599946 -1.199896)
			(stroke
				(width 0.1)
				(type default)
			)
			(layer "F.Fab")
		)
		(fp_line
			(start 1.599946 -1.199896)
			(end 1.599946 1.199896)
			(stroke
				(width 0.1)
				(type default)
			)
			(layer "F.Fab")
		)
		(fp_line
			(start -0.899922 -1.549908)
			(end 0.899922 -1.549908)
			(stroke
				(width 0.1)
				(type default)
			)
			(layer "F.Fab")
		)
		(fp_line
			(start 0.899922 -1.549908)
			(end 0.899922 -1.199896)
			(stroke
				(width 0.1)
				(type default)
			)
			(layer "F.Fab")
		)
		(fp_poly
			(pts
				(xy -2.71272 -0.719328) (xy -2.71272 -1.344168) (xy -2.159 -1.016)
			)
			(stroke
				(width 0)
				(type default)
			)
			(fill yes)
			(layer "F.Fab")
		)
		(pad "1" smd rect
			(at -1.225042 -0.94996 180)
			(size 0.5588 1.3462)
			(layers "F.Cu" "F.Mask" "F.Paste")
			(net "HP_NIC6_PWRGD_R")
		)
		(pad "2" smd rect
			(at -1.225042 0 180)
			(size 0.5588 1.3462)
			(layers "F.Cu" "F.Mask" "F.Paste")
			(net "RST_NIC6_PERST_R_N")
		)
		(pad "3" smd rect
			(at -1.225042 0.94996 180)
			(size 0.5588 1.3462)
			(layers "F.Cu" "F.Mask" "F.Paste")
			(net "GND")
		)
		(pad "4" smd rect
			(at 1.225042 0.94996 180)
			(size 0.5588 1.3462)
			(layers "F.Cu" "F.Mask" "F.Paste")
			(net "RST_HP_NIC6_N")
		)
		(pad "5" smd rect
			(at 1.225042 -0.94996 180)
			(size 0.5588 1.3462)
			(layers "F.Cu" "F.Mask" "F.Paste")
			(net "P3V3_AUX")
		)
	)
	(footprint ""
		(layer "F.Cu")
		(at 452.1581 -236.029246)
		(property "Reference" "C4441"
			(at 0 0 0)
			(layer "F.SilkS")
			(hide yes)
			(effects
				(font
					(size 1.27 1.27)
				)
			)
		)
		(property "Value" ""
			(at 0 0 0)
			(layer "F.Fab")
			(effects
				(font
					(size 1.27 1.27)
				)
			)
		)
		(duplicate_pad_numbers_are_jumpers no)
		(fp_line
			(start -1.2954 -0.5842)
			(end 1.2954 -0.5842)
			(stroke
				(width 0.1524)
				(type default)
			)
			(layer "F.SilkS")
		)
		(fp_line
			(start -1.2954 0.5842)
			(end -1.2954 -0.5842)
			(stroke
				(width 0.1524)
				(type default)
			)
			(layer "F.SilkS")
		)
		(fp_line
			(start 1.2954 -0.5842)
			(end 1.2954 0.5842)
			(stroke
				(width 0.1524)
				(type default)
			)
			(layer "F.SilkS")
		)
		(fp_line
			(start 1.2954 0.5842)
			(end -1.2954 0.5842)
			(stroke
				(width 0.1524)
				(type default)
			)
			(layer "F.SilkS")
		)
		(fp_line
			(start -1.1938 -0.4064)
			(end -0.8636 -0.4064)
			(stroke
				(width 0.1)
				(type default)
			)
			(layer "F.Fab")
		)
		(fp_line
			(start -1.1938 0.4064)
			(end -1.1938 -0.4064)
			(stroke
				(width 0.1)
				(type default)
			)
			(layer "F.Fab")
		)
		(fp_line
			(start -0.8636 -0.4572)
			(end 0.8636 -0.4572)
			(stroke
				(width 0.1)
				(type default)
			)
			(layer "F.Fab")
		)
		(fp_line
			(start -0.8636 -0.4064)
			(end -0.8636 -0.4572)
			(stroke
				(width 0.1)
				(type default)
			)
			(layer "F.Fab")
		)
		(fp_line
			(start -0.8636 0.4064)
			(end -1.1938 0.4064)
			(stroke
				(width 0.1)
				(type default)
			)
			(layer "F.Fab")
		)
		(fp_line
			(start -0.8636 0.4572)
			(end -0.8636 0.4064)
			(stroke
				(width 0.1)
				(type default)
			)
			(layer "F.Fab")
		)
		(fp_line
			(start 0.8636 -0.4572)
			(end 0.8636 -0.4064)
			(stroke
				(width 0.1)
				(type default)
			)
			(layer "F.Fab")
		)
		(fp_line
			(start 0.8636 -0.4064)
			(end 1.1938 -0.4064)
			(stroke
				(width 0.1)
				(type default)
			)
			(layer "F.Fab")
		)
		(fp_line
			(start 0.8636 0.4064)
			(end 0.8636 0.4572)
			(stroke
				(width 0.1)
				(type default)
			)
			(layer "F.Fab")
		)
		(fp_line
			(start 0.8636 0.4572)
			(end -0.8636 0.4572)
			(stroke
				(width 0.1)
				(type default)
			)
			(layer "F.Fab")
		)
		(fp_line
			(start 1.1938 -0.4064)
			(end 1.1938 0.4064)
			(stroke
				(width 0.1)
				(type default)
			)
			(layer "F.Fab")
		)
		(fp_line
			(start 1.1938 0.4064)
			(end 0.8636 0.4064)
			(stroke
				(width 0.1)
				(type default)
			)
			(layer "F.Fab")
		)
		(pad "1" smd rect
			(at -0.7366 0 270)
			(size 0.7112 0.8128)
			(layers "F.Cu" "F.Mask" "F.Paste")
			(net "P3V3_AUX")
		)
		(pad "2" smd rect
			(at 0.7366 0 270)
			(size 0.7112 0.8128)
			(layers "F.Cu" "F.Mask" "F.Paste")
			(net "GND")
		)
	)
	(footprint ""
		(layer "F.Cu")
		(at 321.678808 -308.323488 135)
		(property "Reference" "R1390"
			(at 0 0 135)
			(layer "F.SilkS")
			(hide yes)
			(effects
				(font
					(size 1.27 1.27)
				)
			)
		)
		(property "Value" ""
			(at 0 0 135)
			(layer "F.Fab")
			(effects
				(font
					(size 1.27 1.27)
				)
			)
		)
		(duplicate_pad_numbers_are_jumpers no)
		(fp_line
			(start 0.787389 -0.406267)
			(end 0.787389 0.406267)
			(stroke
				(width 0.1524)
				(type default)
			)
			(layer "F.SilkS")
		)
		(fp_line
			(start 0.787389 0.406267)
			(end -0.787389 0.406267)
			(stroke
				(width 0.1524)
				(type default)
			)
			(layer "F.SilkS")
		)
		(fp_line
			(start -0.787389 -0.406267)
			(end 0.787389 -0.406267)
			(stroke
				(width 0.1524)
				(type default)
			)
			(layer "F.SilkS")
		)
		(fp_line
			(start -0.787389 0.406267)
			(end -0.787389 -0.406267)
			(stroke
				(width 0.1524)
				(type default)
			)
			(layer "F.SilkS")
		)
		(fp_line
			(start 0.679446 -0.30479)
			(end 0.679446 0.30479)
			(stroke
				(width 0.1)
				(type default)
			)
			(layer "F.Fab")
		)
		(fp_line
			(start 0.120515 -0.30479)
			(end 0.679446 -0.30479)
			(stroke
				(width 0.1)
				(type default)
			)
			(layer "F.Fab")
		)
		(fp_line
			(start 0.120695 -0.279466)
			(end 0.120515 -0.30479)
			(stroke
				(width 0.1)
				(type default)
			)
			(layer "F.Fab")
		)
		(fp_line
			(start 0.679446 0.30479)
			(end 0.120515 0.30479)
			(stroke
				(width 0.1)
				(type default)
			)
			(layer "F.Fab")
		)
		(fp_line
			(start -0.120695 -0.304969)
			(end -0.120695 -0.279466)
			(stroke
				(width 0.1)
				(type default)
			)
			(layer "F.Fab")
		)
		(fp_line
			(start -0.120695 -0.279466)
			(end 0.120695 -0.279466)
			(stroke
				(width 0.1)
				(type default)
			)
			(layer "F.Fab")
		)
		(fp_line
			(start 0.120335 0.279466)
			(end -0.120695 0.279466)
			(stroke
				(width 0.1)
				(type default)
			)
			(layer "F.Fab")
		)
		(fp_line
			(start 0.120515 0.30479)
			(end 0.120335 0.279466)
			(stroke
				(width 0.1)
				(type default)
			)
			(layer "F.Fab")
		)
		(fp_line
			(start -0.679446 -0.305149)
			(end -0.120695 -0.304969)
			(stroke
				(width 0.1)
				(type default)
			)
			(layer "F.Fab")
		)
		(fp_line
			(start -0.120695 0.279466)
			(end -0.120515 0.30479)
			(stroke
				(width 0.1)
				(type default)
			)
			(layer "F.Fab")
		)
		(fp_line
			(start -0.120515 0.30479)
			(end -0.679446 0.30479)
			(stroke
				(width 0.1)
				(type default)
			)
			(layer "F.Fab")
		)
		(fp_line
			(start -0.679446 0.30479)
			(end -0.679446 -0.305149)
			(stroke
				(width 0.1)
				(type default)
			)
			(layer "F.Fab")
		)
		(pad "1" smd circle
			(at -0.40005 0 135)
			(size 0 0)
			(layers "F.Cu" "F.Mask" "F.Paste")
			(net "GND")
		)
		(pad "2" smd circle
			(at 0.40005 0 135)
			(size 0 0)
			(layers "F.Cu" "F.Mask" "F.Paste")
			(net "PEX2_SPARE7")
		)
	)
	(footprint ""
		(layer "F.Cu")
		(at 336.466942 -57.332626)
		(property "Reference" "R6830"
			(at 0 0 0)
			(layer "F.SilkS")
			(hide yes)
			(effects
				(font
					(size 1.27 1.27)
				)
			)
		)
		(property "Value" ""
			(at 0 0 0)
			(layer "F.Fab")
			(effects
				(font
					(size 1.27 1.27)
				)
			)
		)
		(duplicate_pad_numbers_are_jumpers no)
		(fp_line
			(start -0.7874 -0.4064)
			(end 0.7874 -0.4064)
			(stroke
				(width 0.1524)
				(type default)
			)
			(layer "F.SilkS")
		)
		(fp_line
			(start -0.7874 0.4064)
			(end -0.7874 -0.4064)
			(stroke
				(width 0.1524)
				(type default)
			)
			(layer "F.SilkS")
		)
		(fp_line
			(start 0.7874 -0.4064)
			(end 0.7874 0.4064)
			(stroke
				(width 0.1524)
				(type default)
			)
			(layer "F.SilkS")
		)
		(fp_line
			(start 0.7874 0.4064)
			(end -0.7874 0.4064)
			(stroke
				(width 0.1524)
				(type default)
			)
			(layer "F.SilkS")
		)
		(fp_line
			(start -0.67945 -0.305054)
			(end -0.12065 -0.305054)
			(stroke
				(width 0.1)
				(type default)
			)
			(layer "F.Fab")
		)
		(fp_line
			(start -0.67945 0.3048)
			(end -0.67945 -0.305054)
			(stroke
				(width 0.1)
				(type default)
			)
			(layer "F.Fab")
		)
		(fp_line
			(start -0.12065 -0.305054)
			(end -0.12065 -0.2794)
			(stroke
				(width 0.1)
				(type default)
			)
			(layer "F.Fab")
		)
		(fp_line
			(start -0.12065 -0.2794)
			(end 0.12065 -0.2794)
			(stroke
				(width 0.1)
				(type default)
			)
			(layer "F.Fab")
		)
		(fp_line
			(start -0.12065 0.2794)
			(end -0.12065 0.3048)
			(stroke
				(width 0.1)
				(type default)
			)
			(layer "F.Fab")
		)
		(fp_line
			(start -0.12065 0.3048)
			(end -0.67945 0.3048)
			(stroke
				(width 0.1)
				(type default)
			)
			(layer "F.Fab")
		)
		(fp_line
			(start 0.120396 0.2794)
			(end -0.12065 0.2794)
			(stroke
				(width 0.1)
				(type default)
			)
			(layer "F.Fab")
		)
		(fp_line
			(start 0.120396 0.3048)
			(end 0.120396 0.2794)
			(stroke
				(width 0.1)
				(type default)
			)
			(layer "F.Fab")
		)
		(fp_line
			(start 0.12065 -0.3048)
			(end 0.67945 -0.3048)
			(stroke
				(width 0.1)
				(type default)
			)
			(layer "F.Fab")
		)
		(fp_line
			(start 0.12065 -0.2794)
			(end 0.12065 -0.3048)
			(stroke
				(width 0.1)
				(type default)
			)
			(layer "F.Fab")
		)
		(fp_line
			(start 0.67945 -0.3048)
			(end 0.67945 0.3048)
			(stroke
				(width 0.1)
				(type default)
			)
			(layer "F.Fab")
		)
		(fp_line
			(start 0.67945 0.3048)
			(end 0.120396 0.3048)
			(stroke
				(width 0.1)
				(type default)
			)
			(layer "F.Fab")
		)
		(pad "1" smd circle
			(at -0.40005 0)
			(size 0 0)
			(layers "F.Cu" "F.Mask" "F.Paste")
			(net "SSD11_PWR_EN_R")
		)
		(pad "2" smd circle
			(at 0.40005 0)
			(size 0 0)
			(layers "F.Cu" "F.Mask" "F.Paste")
			(net "GND")
		)
	)
	(footprint ""
		(layer "F.Cu")
		(at 123.67514 -96.034606)
		(property "Reference" "R1577"
			(at 0 0 0)
			(layer "F.SilkS")
			(hide yes)
			(effects
				(font
					(size 1.27 1.27)
				)
			)
		)
		(property "Value" ""
			(at 0 0 0)
			(layer "F.Fab")
			(effects
				(font
					(size 1.27 1.27)
				)
			)
		)
		(duplicate_pad_numbers_are_jumpers no)
		(fp_line
			(start -0.7874 -0.4064)
			(end 0.7874 -0.4064)
			(stroke
				(width 0.1524)
				(type default)
			)
			(layer "F.SilkS")
		)
		(fp_line
			(start -0.7874 0.4064)
			(end -0.7874 -0.4064)
			(stroke
				(width 0.1524)
				(type default)
			)
			(layer "F.SilkS")
		)
		(fp_line
			(start 0.7874 -0.4064)
			(end 0.7874 0.4064)
			(stroke
				(width 0.1524)
				(type default)
			)
			(layer "F.SilkS")
		)
		(fp_line
			(start 0.7874 0.4064)
			(end -0.7874 0.4064)
			(stroke
				(width 0.1524)
				(type default)
			)
			(layer "F.SilkS")
		)
		(fp_line
			(start -0.67945 -0.305054)
			(end -0.12065 -0.305054)
			(stroke
				(width 0.1)
				(type default)
			)
			(layer "F.Fab")
		)
		(fp_line
			(start -0.67945 0.3048)
			(end -0.67945 -0.305054)
			(stroke
				(width 0.1)
				(type default)
			)
			(layer "F.Fab")
		)
		(fp_line
			(start -0.12065 -0.305054)
			(end -0.12065 -0.2794)
			(stroke
				(width 0.1)
				(type default)
			)
			(layer "F.Fab")
		)
		(fp_line
			(start -0.12065 -0.2794)
			(end 0.12065 -0.2794)
			(stroke
				(width 0.1)
				(type default)
			)
			(layer "F.Fab")
		)
		(fp_line
			(start -0.12065 0.2794)
			(end -0.12065 0.3048)
			(stroke
				(width 0.1)
				(type default)
			)
			(layer "F.Fab")
		)
		(fp_line
			(start -0.12065 0.3048)
			(end -0.67945 0.3048)
			(stroke
				(width 0.1)
				(type default)
			)
			(layer "F.Fab")
		)
		(fp_line
			(start 0.120396 0.2794)
			(end -0.12065 0.2794)
			(stroke
				(width 0.1)
				(type default)
			)
			(layer "F.Fab")
		)
		(fp_line
			(start 0.120396 0.3048)
			(end 0.120396 0.2794)
			(stroke
				(width 0.1)
				(type default)
			)
			(layer "F.Fab")
		)
		(fp_line
			(start 0.12065 -0.3048)
			(end 0.67945 -0.3048)
			(stroke
				(width 0.1)
				(type default)
			)
			(layer "F.Fab")
		)
		(fp_line
			(start 0.12065 -0.2794)
			(end 0.12065 -0.3048)
			(stroke
				(width 0.1)
				(type default)
			)
			(layer "F.Fab")
		)
		(fp_line
			(start 0.67945 -0.3048)
			(end 0.67945 0.3048)
			(stroke
				(width 0.1)
				(type default)
			)
			(layer "F.Fab")
		)
		(fp_line
			(start 0.67945 0.3048)
			(end 0.120396 0.3048)
			(stroke
				(width 0.1)
				(type default)
			)
			(layer "F.Fab")
		)
		(pad "1" smd circle
			(at -0.40005 0)
			(size 0 0)
			(layers "F.Cu" "F.Mask" "F.Paste")
			(net "SMB_BIC_I2C9_MUX0_SSD0_R_SCL")
		)
		(pad "2" smd circle
			(at 0.40005 0)
			(size 0 0)
			(layers "F.Cu" "F.Mask" "F.Paste")
			(net "SMB_BIC_I2C9_MUX0_SSD0_SCL")
		)
	)
	(footprint ""
		(layer "F.Cu")
		(at 356.551738 -398.044924 90)
		(property "Reference" "C4456"
			(at 0 0 90)
			(layer "F.SilkS")
			(hide yes)
			(effects
				(font
					(size 1.27 1.27)
				)
			)
		)
		(property "Value" ""
			(at 0 0 90)
			(layer "F.Fab")
			(effects
				(font
					(size 1.27 1.27)
				)
			)
		)
		(duplicate_pad_numbers_are_jumpers no)
		(fp_line
			(start 0.299974 -0.150114)
			(end 0.299974 0.150114)
			(stroke
				(width 0.1)
				(type default)
			)
			(layer "F.Fab")
		)
		(fp_line
			(start -0.299974 -0.150114)
			(end 0.299974 -0.150114)
			(stroke
				(width 0.1)
				(type default)
			)
			(layer "F.Fab")
		)
		(fp_line
			(start 0.299974 0.150114)
			(end -0.299974 0.150114)
			(stroke
				(width 0.1)
				(type default)
			)
			(layer "F.Fab")
		)
		(fp_line
			(start -0.299974 0.150114)
			(end -0.299974 -0.150114)
			(stroke
				(width 0.1)
				(type default)
			)
			(layer "F.Fab")
		)
		(pad "1" smd rect
			(at -0.2667 0 90)
			(size 0.3048 0.381)
			(layers "F.Cu" "F.Mask" "F.Paste")
			(net "MB_3V3IO_RSVD3_ISO")
		)
		(pad "2" smd rect
			(at 0.2667 0 90)
			(size 0.3048 0.381)
			(layers "F.Cu" "F.Mask" "F.Paste")
			(net "GND")
		)
	)
	(footprint ""
		(layer "F.Cu")
		(at 45.093128 -356.244906 90)
		(property "Reference" "C2177"
			(at 0 0 90)
			(layer "F.SilkS")
			(hide yes)
			(effects
				(font
					(size 1.27 1.27)
				)
			)
		)
		(property "Value" ""
			(at 0 0 90)
			(layer "F.Fab")
			(effects
				(font
					(size 1.27 1.27)
				)
			)
		)
		(duplicate_pad_numbers_are_jumpers no)
		(fp_line
			(start 0.299974 -0.150114)
			(end 0.299974 0.150114)
			(stroke
				(width 0.1)
				(type default)
			)
			(layer "F.Fab")
		)
		(fp_line
			(start -0.299974 -0.150114)
			(end 0.299974 -0.150114)
			(stroke
				(width 0.1)
				(type default)
			)
			(layer "F.Fab")
		)
		(fp_line
			(start 0.299974 0.150114)
			(end -0.299974 0.150114)
			(stroke
				(width 0.1)
				(type default)
			)
			(layer "F.Fab")
		)
		(fp_line
			(start -0.299974 0.150114)
			(end -0.299974 -0.150114)
			(stroke
				(width 0.1)
				(type default)
			)
			(layer "F.Fab")
		)
		(pad "1" smd rect
			(at -0.2667 0 90)
			(size 0.3048 0.381)
			(layers "F.Cu" "F.Mask" "F.Paste")
			(net "P5E_PEX0_STN4_TX_DN<67>")
		)
		(pad "2" smd rect
			(at 0.2667 0 90)
			(size 0.3048 0.381)
			(layers "F.Cu" "F.Mask" "F.Paste")
			(net "P5E_PEX0_STN4_TX_C_DN<67>")
		)
	)
	(footprint ""
		(layer "F.Cu")
		(at 190.12789 -35.876738)
		(property "Reference" "R6071"
			(at 0 0 0)
			(layer "F.SilkS")
			(hide yes)
			(effects
				(font
					(size 1.27 1.27)
				)
			)
		)
		(property "Value" ""
			(at 0 0 0)
			(layer "F.Fab")
			(effects
				(font
					(size 1.27 1.27)
				)
			)
		)
		(duplicate_pad_numbers_are_jumpers no)
		(fp_line
			(start -0.7874 -0.4064)
			(end 0.7874 -0.4064)
			(stroke
				(width 0.1524)
				(type default)
			)
			(layer "F.SilkS")
		)
		(fp_line
			(start -0.7874 0.4064)
			(end -0.7874 -0.4064)
			(stroke
				(width 0.1524)
				(type default)
			)
			(layer "F.SilkS")
		)
		(fp_line
			(start 0.7874 -0.4064)
			(end 0.7874 0.4064)
			(stroke
				(width 0.1524)
				(type default)
			)
			(layer "F.SilkS")
		)
		(fp_line
			(start 0.7874 0.4064)
			(end -0.7874 0.4064)
			(stroke
				(width 0.1524)
				(type default)
			)
			(layer "F.SilkS")
		)
		(fp_line
			(start -0.67945 -0.305054)
			(end -0.12065 -0.305054)
			(stroke
				(width 0.1)
				(type default)
			)
			(layer "F.Fab")
		)
		(fp_line
			(start -0.67945 0.3048)
			(end -0.67945 -0.305054)
			(stroke
				(width 0.1)
				(type default)
			)
			(layer "F.Fab")
		)
		(fp_line
			(start -0.12065 -0.305054)
			(end -0.12065 -0.2794)
			(stroke
				(width 0.1)
				(type default)
			)
			(layer "F.Fab")
		)
		(fp_line
			(start -0.12065 -0.2794)
			(end 0.12065 -0.2794)
			(stroke
				(width 0.1)
				(type default)
			)
			(layer "F.Fab")
		)
		(fp_line
			(start -0.12065 0.2794)
			(end -0.12065 0.3048)
			(stroke
				(width 0.1)
				(type default)
			)
			(layer "F.Fab")
		)
		(fp_line
			(start -0.12065 0.3048)
			(end -0.67945 0.3048)
			(stroke
				(width 0.1)
				(type default)
			)
			(layer "F.Fab")
		)
		(fp_line
			(start 0.120396 0.2794)
			(end -0.12065 0.2794)
			(stroke
				(width 0.1)
				(type default)
			)
			(layer "F.Fab")
		)
		(fp_line
			(start 0.120396 0.3048)
			(end 0.120396 0.2794)
			(stroke
				(width 0.1)
				(type default)
			)
			(layer "F.Fab")
		)
		(fp_line
			(start 0.12065 -0.3048)
			(end 0.67945 -0.3048)
			(stroke
				(width 0.1)
				(type default)
			)
			(layer "F.Fab")
		)
		(fp_line
			(start 0.12065 -0.2794)
			(end 0.12065 -0.3048)
			(stroke
				(width 0.1)
				(type default)
			)
			(layer "F.Fab")
		)
		(fp_line
			(start 0.67945 -0.3048)
			(end 0.67945 0.3048)
			(stroke
				(width 0.1)
				(type default)
			)
			(layer "F.Fab")
		)
		(fp_line
			(start 0.67945 0.3048)
			(end 0.120396 0.3048)
			(stroke
				(width 0.1)
				(type default)
			)
			(layer "F.Fab")
		)
		(pad "1" smd circle
			(at -0.40005 0)
			(size 0 0)
			(layers "F.Cu" "F.Mask" "F.Paste")
			(net "PWRGD_P3V3_SSD7_D")
		)
		(pad "2" smd circle
			(at 0.40005 0)
			(size 0 0)
			(layers "F.Cu" "F.Mask" "F.Paste")
			(net "PWRGD_P3V3_SSD7_R")
		)
	)
	(footprint ""
		(layer "F.Cu")
		(at 339.598 -205.232 -90)
		(property "Reference" "R4132"
			(at 0 0 270)
			(layer "F.SilkS")
			(hide yes)
			(effects
				(font
					(size 1.27 1.27)
				)
			)
		)
		(property "Value" ""
			(at 0 0 270)
			(layer "F.Fab")
			(effects
				(font
					(size 1.27 1.27)
				)
			)
		)
		(duplicate_pad_numbers_are_jumpers no)
		(fp_line
			(start -0.7874 0.4064)
			(end -0.7874 -0.4064)
			(stroke
				(width 0.1524)
				(type default)
			)
			(layer "F.SilkS")
		)
		(fp_line
			(start 0.7874 0.4064)
			(end -0.7874 0.4064)
			(stroke
				(width 0.1524)
				(type default)
			)
			(layer "F.SilkS")
		)
		(fp_line
			(start -0.7874 -0.4064)
			(end 0.7874 -0.4064)
			(stroke
				(width 0.1524)
				(type default)
			)
			(layer "F.SilkS")
		)
		(fp_line
			(start 0.7874 -0.4064)
			(end 0.7874 0.4064)
			(stroke
				(width 0.1524)
				(type default)
			)
			(layer "F.SilkS")
		)
		(fp_line
			(start -0.67945 0.3048)
			(end -0.67945 -0.305054)
			(stroke
				(width 0.1)
				(type default)
			)
			(layer "F.Fab")
		)
		(fp_line
			(start -0.12065 0.3048)
			(end -0.67945 0.3048)
			(stroke
				(width 0.1)
				(type default)
			)
			(layer "F.Fab")
		)
		(fp_line
			(start 0.120396 0.3048)
			(end 0.120396 0.2794)
			(stroke
				(width 0.1)
				(type default)
			)
			(layer "F.Fab")
		)
		(fp_line
			(start 0.67945 0.3048)
			(end 0.120396 0.3048)
			(stroke
				(width 0.1)
				(type default)
			)
			(layer "F.Fab")
		)
		(fp_line
			(start -0.12065 0.2794)
			(end -0.12065 0.3048)
			(stroke
				(width 0.1)
				(type default)
			)
			(layer "F.Fab")
		)
		(fp_line
			(start 0.120396 0.2794)
			(end -0.12065 0.2794)
			(stroke
				(width 0.1)
				(type default)
			)
			(layer "F.Fab")
		)
		(fp_line
			(start -0.12065 -0.2794)
			(end 0.12065 -0.2794)
			(stroke
				(width 0.1)
				(type default)
			)
			(layer "F.Fab")
		)
		(fp_line
			(start 0.12065 -0.2794)
			(end 0.12065 -0.3048)
			(stroke
				(width 0.1)
				(type default)
			)
			(layer "F.Fab")
		)
		(fp_line
			(start 0.12065 -0.3048)
			(end 0.67945 -0.3048)
			(stroke
				(width 0.1)
				(type default)
			)
			(layer "F.Fab")
		)
		(fp_line
			(start 0.67945 -0.3048)
			(end 0.67945 0.3048)
			(stroke
				(width 0.1)
				(type default)
			)
			(layer "F.Fab")
		)
		(fp_line
			(start -0.67945 -0.305054)
			(end -0.12065 -0.305054)
			(stroke
				(width 0.1)
				(type default)
			)
			(layer "F.Fab")
		)
		(fp_line
			(start -0.12065 -0.305054)
			(end -0.12065 -0.2794)
			(stroke
				(width 0.1)
				(type default)
			)
			(layer "F.Fab")
		)
		(pad "1" smd circle
			(at -0.40005 0 270)
			(size 0 0)
			(layers "F.Cu" "F.Mask" "F.Paste")
			(net "SSD12_PWRDIS")
		)
		(pad "2" smd circle
			(at 0.40005 0 270)
			(size 0 0)
			(layers "F.Cu" "F.Mask" "F.Paste")
			(net "SSD12_PWRDIS_R")
		)
	)
	(footprint ""
		(layer "F.Cu")
		(at 356.349808 -158.828994 180)
		(property "Reference" "R5968"
			(at 0 0 180)
			(layer "F.SilkS")
			(hide yes)
			(effects
				(font
					(size 1.27 1.27)
				)
			)
		)
		(property "Value" ""
			(at 0 0 180)
			(layer "F.Fab")
			(effects
				(font
					(size 1.27 1.27)
				)
			)
		)
		(duplicate_pad_numbers_are_jumpers no)
		(fp_line
			(start 0.7874 0.4064)
			(end -0.7874 0.4064)
			(stroke
				(width 0.1524)
				(type default)
			)
			(layer "F.SilkS")
		)
		(fp_line
			(start 0.7874 -0.4064)
			(end 0.7874 0.4064)
			(stroke
				(width 0.1524)
				(type default)
			)
			(layer "F.SilkS")
		)
		(fp_line
			(start -0.7874 0.4064)
			(end -0.7874 -0.4064)
			(stroke
				(width 0.1524)
				(type default)
			)
			(layer "F.SilkS")
		)
		(fp_line
			(start -0.7874 -0.4064)
			(end 0.7874 -0.4064)
			(stroke
				(width 0.1524)
				(type default)
			)
			(layer "F.SilkS")
		)
		(fp_line
			(start 0.67945 0.3048)
			(end 0.120396 0.3048)
			(stroke
				(width 0.1)
				(type default)
			)
			(layer "F.Fab")
		)
		(fp_line
			(start 0.67945 -0.3048)
			(end 0.67945 0.3048)
			(stroke
				(width 0.1)
				(type default)
			)
			(layer "F.Fab")
		)
		(fp_line
			(start 0.12065 -0.2794)
			(end 0.12065 -0.3048)
			(stroke
				(width 0.1)
				(type default)
			)
			(layer "F.Fab")
		)
		(fp_line
			(start 0.12065 -0.3048)
			(end 0.67945 -0.3048)
			(stroke
				(width 0.1)
				(type default)
			)
			(layer "F.Fab")
		)
		(fp_line
			(start 0.120396 0.3048)
			(end 0.120396 0.2794)
			(stroke
				(width 0.1)
				(type default)
			)
			(layer "F.Fab")
		)
		(fp_line
			(start 0.120396 0.2794)
			(end -0.12065 0.2794)
			(stroke
				(width 0.1)
				(type default)
			)
			(layer "F.Fab")
		)
		(fp_line
			(start -0.12065 0.3048)
			(end -0.67945 0.3048)
			(stroke
				(width 0.1)
				(type default)
			)
			(layer "F.Fab")
		)
		(fp_line
			(start -0.12065 0.2794)
			(end -0.12065 0.3048)
			(stroke
				(width 0.1)
				(type default)
			)
			(layer "F.Fab")
		)
		(fp_line
			(start -0.12065 -0.2794)
			(end 0.12065 -0.2794)
			(stroke
				(width 0.1)
				(type default)
			)
			(layer "F.Fab")
		)
		(fp_line
			(start -0.12065 -0.305054)
			(end -0.12065 -0.2794)
			(stroke
				(width 0.1)
				(type default)
			)
			(layer "F.Fab")
		)
		(fp_line
			(start -0.67945 0.3048)
			(end -0.67945 -0.305054)
			(stroke
				(width 0.1)
				(type default)
			)
			(layer "F.Fab")
		)
		(fp_line
			(start -0.67945 -0.305054)
			(end -0.12065 -0.305054)
			(stroke
				(width 0.1)
				(type default)
			)
			(layer "F.Fab")
		)
		(pad "1" smd circle
			(at -0.40005 0 180)
			(size 0 0)
			(layers "F.Cu" "F.Mask" "F.Paste")
			(net "PWRGD_P12V_NIC6_CO")
		)
		(pad "2" smd circle
			(at 0.40005 0 180)
			(size 0 0)
			(layers "F.Cu" "F.Mask" "F.Paste")
			(net "PWRGD_P12V_NIC6_R")
		)
	)
	(footprint ""
		(layer "F.Cu")
		(at 336.042 -146.939)
		(property "Reference" "R4789"
			(at 0 0 0)
			(layer "F.SilkS")
			(hide yes)
			(effects
				(font
					(size 1.27 1.27)
				)
			)
		)
		(property "Value" ""
			(at 0 0 0)
			(layer "F.Fab")
			(effects
				(font
					(size 1.27 1.27)
				)
			)
		)
		(duplicate_pad_numbers_are_jumpers no)
		(fp_line
			(start -0.7874 -0.4064)
			(end 0.7874 -0.4064)
			(stroke
				(width 0.1524)
				(type default)
			)
			(layer "F.SilkS")
		)
		(fp_line
			(start -0.7874 0.4064)
			(end -0.7874 -0.4064)
			(stroke
				(width 0.1524)
				(type default)
			)
			(layer "F.SilkS")
		)
		(fp_line
			(start 0.7874 -0.4064)
			(end 0.7874 0.4064)
			(stroke
				(width 0.1524)
				(type default)
			)
			(layer "F.SilkS")
		)
		(fp_line
			(start 0.7874 0.4064)
			(end -0.7874 0.4064)
			(stroke
				(width 0.1524)
				(type default)
			)
			(layer "F.SilkS")
		)
		(fp_line
			(start -0.67945 -0.305054)
			(end -0.12065 -0.305054)
			(stroke
				(width 0.1)
				(type default)
			)
			(layer "F.Fab")
		)
		(fp_line
			(start -0.67945 0.3048)
			(end -0.67945 -0.305054)
			(stroke
				(width 0.1)
				(type default)
			)
			(layer "F.Fab")
		)
		(fp_line
			(start -0.12065 -0.305054)
			(end -0.12065 -0.2794)
			(stroke
				(width 0.1)
				(type default)
			)
			(layer "F.Fab")
		)
		(fp_line
			(start -0.12065 -0.2794)
			(end 0.12065 -0.2794)
			(stroke
				(width 0.1)
				(type default)
			)
			(layer "F.Fab")
		)
		(fp_line
			(start -0.12065 0.2794)
			(end -0.12065 0.3048)
			(stroke
				(width 0.1)
				(type default)
			)
			(layer "F.Fab")
		)
		(fp_line
			(start -0.12065 0.3048)
			(end -0.67945 0.3048)
			(stroke
				(width 0.1)
				(type default)
			)
			(layer "F.Fab")
		)
		(fp_line
			(start 0.120396 0.2794)
			(end -0.12065 0.2794)
			(stroke
				(width 0.1)
				(type default)
			)
			(layer "F.Fab")
		)
		(fp_line
			(start 0.120396 0.3048)
			(end 0.120396 0.2794)
			(stroke
				(width 0.1)
				(type default)
			)
			(layer "F.Fab")
		)
		(fp_line
			(start 0.12065 -0.3048)
			(end 0.67945 -0.3048)
			(stroke
				(width 0.1)
				(type default)
			)
			(layer "F.Fab")
		)
		(fp_line
			(start 0.12065 -0.2794)
			(end 0.12065 -0.3048)
			(stroke
				(width 0.1)
				(type default)
			)
			(layer "F.Fab")
		)
		(fp_line
			(start 0.67945 -0.3048)
			(end 0.67945 0.3048)
			(stroke
				(width 0.1)
				(type default)
			)
			(layer "F.Fab")
		)
		(fp_line
			(start 0.67945 0.3048)
			(end 0.120396 0.3048)
			(stroke
				(width 0.1)
				(type default)
			)
			(layer "F.Fab")
		)
		(pad "1" smd circle
			(at -0.40005 0)
			(size 0 0)
			(layers "F.Cu" "F.Mask" "F.Paste")
			(net "P3V3_AUX")
		)
		(pad "2" smd circle
			(at 0.40005 0)
			(size 0 0)
			(layers "F.Cu" "F.Mask" "F.Paste")
			(net "SSD14_PEX_PWR_EN_R")
		)
	)
	(footprint ""
		(layer "F.Cu")
		(at 159.946594 -450.961252 180)
		(property "Reference" "X71"
			(at -0.1778 -1.92913 180)
			(unlocked yes)
			(layer "F.SilkS")
			(effects
				(font
					(size 0.7874 0.5842)
					(thickness 0.1524)
				)
				(justify left)
			)
		)
		(property "Value" ""
			(at 0 0 180)
			(layer "F.Fab")
			(effects
				(font
					(size 1.27 1.27)
				)
			)
		)
		(property "Device Type" "TP_TDR_4P_FTS_MPKT4_H025P0200_IO_TP15_TP_TDR_4P_DIP"
			(at 1.30175 1.27 270)
			(unlocked yes)
			(layer "F.Fab")
			(hide yes)
			(effects
				(font
					(size 0.635 0.4064)
					(thickness 0.1524)
				)
			)
		)
		(property "User Part Number" "TP15"
			(at 1.30175 1.27 270)
			(unlocked yes)
			(layer "Cmts.User")
			(hide yes)
			(effects
				(font
					(size 0.635 0.4064)
					(thickness 0.1524)
				)
			)
		)
		(duplicate_pad_numbers_are_jumpers no)
		(fp_line
			(start 2.54 3.81)
			(end 2.54 3.6703)
			(stroke
				(width 0.1524)
				(type default)
			)
			(layer "F.SilkS")
		)
		(fp_line
			(start 2.54 1.4097)
			(end 2.54 1.1303)
			(stroke
				(width 0.1524)
				(type default)
			)
			(layer "F.SilkS")
		)
		(fp_line
			(start 2.54 -1.1303)
			(end 2.54 -1.27)
			(stroke
				(width 0.1524)
				(type default)
			)
			(layer "F.SilkS")
		)
		(fp_line
			(start 2.54 -1.27)
			(end 0 -1.27)
			(stroke
				(width 0.1524)
				(type default)
			)
			(layer "F.SilkS")
		)
		(fp_line
			(start 0 3.81)
			(end 2.54 3.81)
			(stroke
				(width 0.1524)
				(type default)
			)
			(layer "F.SilkS")
		)
		(fp_line
			(start 0 3.175)
			(end 0 3.81)
			(stroke
				(width 0.1524)
				(type default)
			)
			(layer "F.SilkS")
		)
		(fp_line
			(start 0 0.635)
			(end 0 1.905)
			(stroke
				(width 0.1524)
				(type default)
			)
			(layer "F.SilkS")
		)
		(fp_line
			(start 0 -1.27)
			(end 0 -0.635)
			(stroke
				(width 0.1524)
				(type default)
			)
			(layer "F.SilkS")
		)
		(fp_poly
			(pts
				(xy -0.761746 0) (xy -2.285746 -0.762) (xy -2.285746 0.762)
			)
			(stroke
				(width 0)
				(type default)
			)
			(fill yes)
			(layer "F.SilkS")
		)
		(fp_line
			(start 2.54 3.81)
			(end 2.54 -1.27)
			(stroke
				(width 0.1)
				(type default)
			)
			(layer "F.Fab")
		)
		(fp_line
			(start 2.54 -1.27)
			(end 0 -1.27)
			(stroke
				(width 0.1)
				(type default)
			)
			(layer "F.Fab")
		)
		(fp_line
			(start 0 3.81)
			(end 2.54 3.81)
			(stroke
				(width 0.1)
				(type default)
			)
			(layer "F.Fab")
		)
		(fp_line
			(start 0 -1.27)
			(end 0 3.81)
			(stroke
				(width 0.1)
				(type default)
			)
			(layer "F.Fab")
		)
		(fp_poly
			(pts
				(xy -0.761746 0) (xy -2.285746 -0.762) (xy -2.285746 0.762)
			)
			(stroke
				(width 0)
				(type default)
			)
			(fill yes)
			(layer "F.Fab")
		)
		(pad "1" thru_hole circle
			(at 0 0 180)
			(size 1.0033 1.0033)
			(drill 0.249936)
			(layers "*.Cu" "*.Mask")
			(remove_unused_layers no)
			(net "TDR_DIFF_100_IN2_DIN")
			(clearance 0.10795)
			(thermal_gap 0.10795)
			(padstack
				(mode front_inner_back)
				(layer "Inner"
					(shape circle)
					(size 0.8001 0.8001)
					(clearance 0.1524)
				)
				(layer "B.Cu"
					(shape circle)
					(size 1.0033 1.0033)
					(clearance 0.10795)
				)
			)
		)
		(pad "2" thru_hole circle
			(at 2.54 0 180)
			(size 1.9939 1.9939)
			(drill 0.249936)
			(layers "*.Cu" "*.Mask")
			(remove_unused_layers no)
			(net "COUPON_GND1")
			(clearance 0.10795)
			(thermal_gap 0.10795)
			(padstack
				(mode front_inner_back)
				(layer "Inner"
					(shape circle)
					(size 0.8001 0.8001)
					(clearance 0.1524)
				)
				(layer "B.Cu"
					(shape circle)
					(size 1.9939 1.9939)
					(clearance 0.10795)
				)
			)
		)
		(pad "3" thru_hole circle
			(at 2.54 2.54 180)
			(size 1.9939 1.9939)
			(drill 0.249936)
			(layers "*.Cu" "*.Mask")
			(remove_unused_layers no)
			(net "COUPON_GND1")
			(clearance 0.10795)
			(thermal_gap 0.10795)
			(padstack
				(mode front_inner_back)
				(layer "Inner"
					(shape circle)
					(size 0.8001 0.8001)
					(clearance 0.1524)
				)
				(layer "B.Cu"
					(shape circle)
					(size 1.9939 1.9939)
					(clearance 0.10795)
				)
			)
		)
		(pad "4" thru_hole circle
			(at 0 2.54 180)
			(size 1.0033 1.0033)
			(drill 0.249936)
			(layers "*.Cu" "*.Mask")
			(remove_unused_layers no)
			(net "TDR_DIFF_100_IN2_DIP")
			(clearance 0.10795)
			(thermal_gap 0.10795)
			(padstack
				(mode front_inner_back)
				(layer "Inner"
					(shape circle)
					(size 0.8001 0.8001)
					(clearance 0.1524)
				)
				(layer "B.Cu"
					(shape circle)
					(size 1.0033 1.0033)
					(clearance 0.10795)
				)
			)
		)
	)
	(footprint ""
		(layer "F.Cu")
		(at 20.434554 -30.03169 180)
		(property "Reference" "C70"
			(at 0 0 180)
			(layer "F.SilkS")
			(hide yes)
			(effects
				(font
					(size 1.27 1.27)
				)
			)
		)
		(property "Value" ""
			(at 0 0 180)
			(layer "F.Fab")
			(effects
				(font
					(size 1.27 1.27)
				)
			)
		)
		(duplicate_pad_numbers_are_jumpers no)
		(fp_line
			(start 0.299974 0.150114)
			(end -0.299974 0.150114)
			(stroke
				(width 0.1)
				(type default)
			)
			(layer "F.Fab")
		)
		(fp_line
			(start 0.299974 -0.150114)
			(end 0.299974 0.150114)
			(stroke
				(width 0.1)
				(type default)
			)
			(layer "F.Fab")
		)
		(fp_line
			(start -0.299974 0.150114)
			(end -0.299974 -0.150114)
			(stroke
				(width 0.1)
				(type default)
			)
			(layer "F.Fab")
		)
		(fp_line
			(start -0.299974 -0.150114)
			(end 0.299974 -0.150114)
			(stroke
				(width 0.1)
				(type default)
			)
			(layer "F.Fab")
		)
		(pad "1" smd rect
			(at -0.2667 0 180)
			(size 0.3048 0.381)
			(layers "F.Cu" "F.Mask" "F.Paste")
			(net "P5E_PEX0_STN2_TX_DN<45>")
		)
		(pad "2" smd rect
			(at 0.2667 0 180)
			(size 0.3048 0.381)
			(layers "F.Cu" "F.Mask" "F.Paste")
			(net "P5E_PEX0_STN2_TX_C_DN<45>")
		)
	)
	(footprint ""
		(layer "F.Cu")
		(at 99.8855 -25.1587 -90)
		(property "Reference" "R5738"
			(at 0 0 270)
			(layer "F.SilkS")
			(hide yes)
			(effects
				(font
					(size 1.27 1.27)
				)
			)
		)
		(property "Value" ""
			(at 0 0 270)
			(layer "F.Fab")
			(effects
				(font
					(size 1.27 1.27)
				)
			)
		)
		(duplicate_pad_numbers_are_jumpers no)
		(fp_line
			(start -0.7874 0.4064)
			(end -0.7874 -0.4064)
			(stroke
				(width 0.1524)
				(type default)
			)
			(layer "F.SilkS")
		)
		(fp_line
			(start 0.7874 0.4064)
			(end -0.7874 0.4064)
			(stroke
				(width 0.1524)
				(type default)
			)
			(layer "F.SilkS")
		)
		(fp_line
			(start -0.7874 -0.4064)
			(end 0.7874 -0.4064)
			(stroke
				(width 0.1524)
				(type default)
			)
			(layer "F.SilkS")
		)
		(fp_line
			(start 0.7874 -0.4064)
			(end 0.7874 0.4064)
			(stroke
				(width 0.1524)
				(type default)
			)
			(layer "F.SilkS")
		)
		(fp_line
			(start -0.67945 0.3048)
			(end -0.67945 -0.305054)
			(stroke
				(width 0.1)
				(type default)
			)
			(layer "F.Fab")
		)
		(fp_line
			(start -0.12065 0.3048)
			(end -0.67945 0.3048)
			(stroke
				(width 0.1)
				(type default)
			)
			(layer "F.Fab")
		)
		(fp_line
			(start 0.120396 0.3048)
			(end 0.120396 0.2794)
			(stroke
				(width 0.1)
				(type default)
			)
			(layer "F.Fab")
		)
		(fp_line
			(start 0.67945 0.3048)
			(end 0.120396 0.3048)
			(stroke
				(width 0.1)
				(type default)
			)
			(layer "F.Fab")
		)
		(fp_line
			(start -0.12065 0.2794)
			(end -0.12065 0.3048)
			(stroke
				(width 0.1)
				(type default)
			)
			(layer "F.Fab")
		)
		(fp_line
			(start 0.120396 0.2794)
			(end -0.12065 0.2794)
			(stroke
				(width 0.1)
				(type default)
			)
			(layer "F.Fab")
		)
		(fp_line
			(start -0.12065 -0.2794)
			(end 0.12065 -0.2794)
			(stroke
				(width 0.1)
				(type default)
			)
			(layer "F.Fab")
		)
		(fp_line
			(start 0.12065 -0.2794)
			(end 0.12065 -0.3048)
			(stroke
				(width 0.1)
				(type default)
			)
			(layer "F.Fab")
		)
		(fp_line
			(start 0.12065 -0.3048)
			(end 0.67945 -0.3048)
			(stroke
				(width 0.1)
				(type default)
			)
			(layer "F.Fab")
		)
		(fp_line
			(start 0.67945 -0.3048)
			(end 0.67945 0.3048)
			(stroke
				(width 0.1)
				(type default)
			)
			(layer "F.Fab")
		)
		(fp_line
			(start -0.67945 -0.305054)
			(end -0.12065 -0.305054)
			(stroke
				(width 0.1)
				(type default)
			)
			(layer "F.Fab")
		)
		(fp_line
			(start -0.12065 -0.305054)
			(end -0.12065 -0.2794)
			(stroke
				(width 0.1)
				(type default)
			)
			(layer "F.Fab")
		)
		(pad "1" smd circle
			(at -0.40005 0 270)
			(size 0 0)
			(layers "F.Cu" "F.Mask" "F.Paste")
			(net "SSD3_LED_ISO_N")
		)
		(pad "2" smd circle
			(at 0.40005 0 270)
			(size 0 0)
			(layers "F.Cu" "F.Mask" "F.Paste")
			(net "SSD3_LED_ISO_R_N")
		)
	)
	(footprint ""
		(layer "F.Cu")
		(at 340.614 -201.168 -90)
		(property "Reference" "R4127"
			(at 0 0 270)
			(layer "F.SilkS")
			(hide yes)
			(effects
				(font
					(size 1.27 1.27)
				)
			)
		)
		(property "Value" ""
			(at 0 0 270)
			(layer "F.Fab")
			(effects
				(font
					(size 1.27 1.27)
				)
			)
		)
		(duplicate_pad_numbers_are_jumpers no)
		(fp_line
			(start -0.7874 0.4064)
			(end -0.7874 -0.4064)
			(stroke
				(width 0.1524)
				(type default)
			)
			(layer "F.SilkS")
		)
		(fp_line
			(start 0.7874 0.4064)
			(end -0.7874 0.4064)
			(stroke
				(width 0.1524)
				(type default)
			)
			(layer "F.SilkS")
		)
		(fp_line
			(start -0.7874 -0.4064)
			(end 0.7874 -0.4064)
			(stroke
				(width 0.1524)
				(type default)
			)
			(layer "F.SilkS")
		)
		(fp_line
			(start 0.7874 -0.4064)
			(end 0.7874 0.4064)
			(stroke
				(width 0.1524)
				(type default)
			)
			(layer "F.SilkS")
		)
		(fp_line
			(start -0.67945 0.3048)
			(end -0.67945 -0.305054)
			(stroke
				(width 0.1)
				(type default)
			)
			(layer "F.Fab")
		)
		(fp_line
			(start -0.12065 0.3048)
			(end -0.67945 0.3048)
			(stroke
				(width 0.1)
				(type default)
			)
			(layer "F.Fab")
		)
		(fp_line
			(start 0.120396 0.3048)
			(end 0.120396 0.2794)
			(stroke
				(width 0.1)
				(type default)
			)
			(layer "F.Fab")
		)
		(fp_line
			(start 0.67945 0.3048)
			(end 0.120396 0.3048)
			(stroke
				(width 0.1)
				(type default)
			)
			(layer "F.Fab")
		)
		(fp_line
			(start -0.12065 0.2794)
			(end -0.12065 0.3048)
			(stroke
				(width 0.1)
				(type default)
			)
			(layer "F.Fab")
		)
		(fp_line
			(start 0.120396 0.2794)
			(end -0.12065 0.2794)
			(stroke
				(width 0.1)
				(type default)
			)
			(layer "F.Fab")
		)
		(fp_line
			(start -0.12065 -0.2794)
			(end 0.12065 -0.2794)
			(stroke
				(width 0.1)
				(type default)
			)
			(layer "F.Fab")
		)
		(fp_line
			(start 0.12065 -0.2794)
			(end 0.12065 -0.3048)
			(stroke
				(width 0.1)
				(type default)
			)
			(layer "F.Fab")
		)
		(fp_line
			(start 0.12065 -0.3048)
			(end 0.67945 -0.3048)
			(stroke
				(width 0.1)
				(type default)
			)
			(layer "F.Fab")
		)
		(fp_line
			(start 0.67945 -0.3048)
			(end 0.67945 0.3048)
			(stroke
				(width 0.1)
				(type default)
			)
			(layer "F.Fab")
		)
		(fp_line
			(start -0.67945 -0.305054)
			(end -0.12065 -0.305054)
			(stroke
				(width 0.1)
				(type default)
			)
			(layer "F.Fab")
		)
		(fp_line
			(start -0.12065 -0.305054)
			(end -0.12065 -0.2794)
			(stroke
				(width 0.1)
				(type default)
			)
			(layer "F.Fab")
		)
		(pad "1" smd circle
			(at -0.40005 0 270)
			(size 0 0)
			(layers "F.Cu" "F.Mask" "F.Paste")
			(net "SSD11_PWR_EN")
		)
		(pad "2" smd circle
			(at 0.40005 0 270)
			(size 0 0)
			(layers "F.Cu" "F.Mask" "F.Paste")
			(net "SSD11_PWR_EN_R")
		)
	)
	(footprint ""
		(layer "F.Cu")
		(at 57.754266 -48.21809)
		(property "Reference" "PD65"
			(at -3.195066 2.24536 0)
			(unlocked yes)
			(layer "F.SilkS")
			(effects
				(font
					(size 0.7874 0.5842)
					(thickness 0.1524)
				)
				(justify left)
			)
		)
		(property "Value" ""
			(at 0 0 0)
			(layer "F.Fab")
			(effects
				(font
					(size 1.27 1.27)
				)
			)
		)
		(duplicate_pad_numbers_are_jumpers no)
		(fp_line
			(start -3.400044 -1.459992)
			(end 4.107942 -1.459992)
			(stroke
				(width 0.1524)
				(type default)
			)
			(layer "F.SilkS")
		)
		(fp_line
			(start -3.400044 1.459992)
			(end -3.400044 -1.459992)
			(stroke
				(width 0.1524)
				(type default)
			)
			(layer "F.SilkS")
		)
		(fp_line
			(start 4.107942 -1.459992)
			(end 4.107942 1.459992)
			(stroke
				(width 0.1524)
				(type default)
			)
			(layer "F.SilkS")
		)
		(fp_line
			(start 4.107942 1.459992)
			(end -3.400044 1.459992)
			(stroke
				(width 0.1524)
				(type default)
			)
			(layer "F.SilkS")
		)
		(fp_poly
			(pts
				(xy 4.107942 -1.459992) (xy 4.107942 1.459992) (xy 3.308096 1.459992) (xy 3.308096 -1.459992)
			)
			(stroke
				(width 0)
				(type default)
			)
			(fill yes)
			(layer "F.SilkS")
		)
		(fp_line
			(start -2.29997 -1.459992)
			(end 2.29997 -1.459992)
			(stroke
				(width 0.1)
				(type default)
			)
			(layer "F.Fab")
		)
		(fp_line
			(start -2.29997 1.459992)
			(end -2.29997 -1.459992)
			(stroke
				(width 0.1)
				(type default)
			)
			(layer "F.Fab")
		)
		(fp_line
			(start 2.29997 -1.459992)
			(end 2.29997 1.459992)
			(stroke
				(width 0.1)
				(type default)
			)
			(layer "F.Fab")
		)
		(fp_line
			(start 2.29997 1.459992)
			(end -2.29997 1.459992)
			(stroke
				(width 0.1)
				(type default)
			)
			(layer "F.Fab")
		)
		(fp_text user "+"
			(at -4.7752 -0.12065 0)
			(unlocked yes)
			(layer "F.SilkS")
			(effects
				(font
					(size 1.905 1.4224)
					(thickness 0.1524)
				)
				(justify left)
			)
		)
		(fp_text user "-"
			(at 5.4102 0.29845 180)
			(unlocked yes)
			(layer "F.SilkS")
			(effects
				(font
					(size 1.905 1.4224)
					(thickness 0.1524)
				)
				(justify left)
			)
		)
		(fp_text user "+"
			(at -4.7752 -0.12065 0)
			(unlocked yes)
			(layer "F.Fab")
			(effects
				(font
					(size 1.905 1.4224)
					(thickness 0.1524)
				)
				(justify left)
			)
		)
		(fp_text user "-"
			(at 5.4102 0.29845 180)
			(unlocked yes)
			(layer "F.Fab")
			(effects
				(font
					(size 1.905 1.4224)
					(thickness 0.1524)
				)
				(justify left)
			)
		)
		(pad "A" smd rect
			(at -1.999996 0 90)
			(size 1.7018 2.5146)
			(layers "F.Cu" "F.Mask" "F.Paste")
			(net "GND")
		)
		(pad "C" smd rect
			(at 1.999996 0 90)
			(size 1.7018 2.5146)
			(layers "F.Cu" "F.Mask" "F.Paste")
			(net "P3V3_SSD2")
		)
	)
	(footprint ""
		(layer "F.Cu")
		(at 198.120762 -370.348764 180)
		(property "Reference" "PC7"
			(at 0 0 180)
			(layer "F.SilkS")
			(hide yes)
			(effects
				(font
					(size 1.27 1.27)
				)
			)
		)
		(property "Value" ""
			(at 0 0 180)
			(layer "F.Fab")
			(effects
				(font
					(size 1.27 1.27)
				)
			)
		)
		(duplicate_pad_numbers_are_jumpers no)
		(fp_line
			(start 0.7874 0.4064)
			(end -0.7874 0.4064)
			(stroke
				(width 0.1524)
				(type default)
			)
			(layer "F.SilkS")
		)
		(fp_line
			(start 0.7874 -0.4064)
			(end 0.7874 0.4064)
			(stroke
				(width 0.1524)
				(type default)
			)
			(layer "F.SilkS")
		)
		(fp_line
			(start -0.7874 0.4064)
			(end -0.7874 -0.4064)
			(stroke
				(width 0.1524)
				(type default)
			)
			(layer "F.SilkS")
		)
		(fp_line
			(start -0.7874 -0.4064)
			(end 0.7874 -0.4064)
			(stroke
				(width 0.1524)
				(type default)
			)
			(layer "F.SilkS")
		)
		(fp_line
			(start 0.67945 0.3048)
			(end 0.120396 0.3048)
			(stroke
				(width 0.1)
				(type default)
			)
			(layer "F.Fab")
		)
		(fp_line
			(start 0.67945 -0.3048)
			(end 0.67945 0.3048)
			(stroke
				(width 0.1)
				(type default)
			)
			(layer "F.Fab")
		)
		(fp_line
			(start 0.12065 -0.2794)
			(end 0.12065 -0.3048)
			(stroke
				(width 0.1)
				(type default)
			)
			(layer "F.Fab")
		)
		(fp_line
			(start 0.12065 -0.3048)
			(end 0.67945 -0.3048)
			(stroke
				(width 0.1)
				(type default)
			)
			(layer "F.Fab")
		)
		(fp_line
			(start 0.120396 0.3048)
			(end 0.120396 0.2794)
			(stroke
				(width 0.1)
				(type default)
			)
			(layer "F.Fab")
		)
		(fp_line
			(start 0.120396 0.2794)
			(end -0.12065 0.2794)
			(stroke
				(width 0.1)
				(type default)
			)
			(layer "F.Fab")
		)
		(fp_line
			(start -0.12065 0.3048)
			(end -0.67945 0.3048)
			(stroke
				(width 0.1)
				(type default)
			)
			(layer "F.Fab")
		)
		(fp_line
			(start -0.12065 0.2794)
			(end -0.12065 0.3048)
			(stroke
				(width 0.1)
				(type default)
			)
			(layer "F.Fab")
		)
		(fp_line
			(start -0.12065 -0.2794)
			(end 0.12065 -0.2794)
			(stroke
				(width 0.1)
				(type default)
			)
			(layer "F.Fab")
		)
		(fp_line
			(start -0.12065 -0.305054)
			(end -0.12065 -0.2794)
			(stroke
				(width 0.1)
				(type default)
			)
			(layer "F.Fab")
		)
		(fp_line
			(start -0.67945 0.3048)
			(end -0.67945 -0.305054)
			(stroke
				(width 0.1)
				(type default)
			)
			(layer "F.Fab")
		)
		(fp_line
			(start -0.67945 -0.305054)
			(end -0.12065 -0.305054)
			(stroke
				(width 0.1)
				(type default)
			)
			(layer "F.Fab")
		)
		(pad "1" smd circle
			(at -0.40005 0 180)
			(size 0 0)
			(layers "F.Cu" "F.Mask" "F.Paste")
			(net "HSC_VTEMP")
		)
		(pad "2" smd circle
			(at 0.40005 0 180)
			(size 0 0)
			(layers "F.Cu" "F.Mask" "F.Paste")
			(net "AGND_HSC")
		)
	)
	(footprint ""
		(layer "F.Cu")
		(at 112.751108 -343.952322 90)
		(property "Reference" "C341"
			(at 0 0 90)
			(layer "F.SilkS")
			(hide yes)
			(effects
				(font
					(size 1.27 1.27)
				)
			)
		)
		(property "Value" ""
			(at 0 0 90)
			(layer "F.Fab")
			(effects
				(font
					(size 1.27 1.27)
				)
			)
		)
		(duplicate_pad_numbers_are_jumpers no)
		(fp_line
			(start 0.299974 -0.150114)
			(end 0.299974 0.150114)
			(stroke
				(width 0.1)
				(type default)
			)
			(layer "F.Fab")
		)
		(fp_line
			(start -0.299974 -0.150114)
			(end 0.299974 -0.150114)
			(stroke
				(width 0.1)
				(type default)
			)
			(layer "F.Fab")
		)
		(fp_line
			(start 0.299974 0.150114)
			(end -0.299974 0.150114)
			(stroke
				(width 0.1)
				(type default)
			)
			(layer "F.Fab")
		)
		(fp_line
			(start -0.299974 0.150114)
			(end -0.299974 -0.150114)
			(stroke
				(width 0.1)
				(type default)
			)
			(layer "F.Fab")
		)
		(pad "1" smd rect
			(at -0.2667 0 90)
			(size 0.3048 0.381)
			(layers "F.Cu" "F.Mask" "F.Paste")
			(net "P5E_PEX1_STN6_TX_DN<111>")
		)
		(pad "2" smd rect
			(at 0.2667 0 90)
			(size 0.3048 0.381)
			(layers "F.Cu" "F.Mask" "F.Paste")
			(net "P5E_PEX1_STN6_TX_C_DN<111>")
		)
	)
	(footprint ""
		(layer "F.Cu")
		(at 80.019398 -150.70455 180)
		(property "Reference" "C7"
			(at 0 0 180)
			(layer "F.SilkS")
			(hide yes)
			(effects
				(font
					(size 1.27 1.27)
				)
			)
		)
		(property "Value" ""
			(at 0 0 180)
			(layer "F.Fab")
			(effects
				(font
					(size 1.27 1.27)
				)
			)
		)
		(duplicate_pad_numbers_are_jumpers no)
		(fp_line
			(start 0.299974 0.150114)
			(end -0.299974 0.150114)
			(stroke
				(width 0.1)
				(type default)
			)
			(layer "F.Fab")
		)
		(fp_line
			(start 0.299974 -0.150114)
			(end 0.299974 0.150114)
			(stroke
				(width 0.1)
				(type default)
			)
			(layer "F.Fab")
		)
		(fp_line
			(start -0.299974 0.150114)
			(end -0.299974 -0.150114)
			(stroke
				(width 0.1)
				(type default)
			)
			(layer "F.Fab")
		)
		(fp_line
			(start -0.299974 -0.150114)
			(end 0.299974 -0.150114)
			(stroke
				(width 0.1)
				(type default)
			)
			(layer "F.Fab")
		)
		(pad "1" smd rect
			(at -0.2667 0 180)
			(size 0.3048 0.381)
			(layers "F.Cu" "F.Mask" "F.Paste")
			(net "P5E_PEX0_STN0_TX_DN<12>")
		)
		(pad "2" smd rect
			(at 0.2667 0 180)
			(size 0.3048 0.381)
			(layers "F.Cu" "F.Mask" "F.Paste")
			(net "P5E_PEX0_STN0_TX_C_DN<12>")
		)
	)
	(footprint ""
		(layer "F.Cu")
		(at 246.988838 -119.120666 90)
		(property "Reference" "PC905"
			(at 0 0 90)
			(layer "F.SilkS")
			(hide yes)
			(effects
				(font
					(size 1.27 1.27)
				)
			)
		)
		(property "Value" ""
			(at 0 0 90)
			(layer "F.Fab")
			(effects
				(font
					(size 1.27 1.27)
				)
			)
		)
		(duplicate_pad_numbers_are_jumpers no)
		(fp_line
			(start 0.7874 -0.4064)
			(end 0.7874 0.4064)
			(stroke
				(width 0.1524)
				(type default)
			)
			(layer "F.SilkS")
		)
		(fp_line
			(start -0.7874 -0.4064)
			(end 0.7874 -0.4064)
			(stroke
				(width 0.1524)
				(type default)
			)
			(layer "F.SilkS")
		)
		(fp_line
			(start 0.7874 0.4064)
			(end -0.7874 0.4064)
			(stroke
				(width 0.1524)
				(type default)
			)
			(layer "F.SilkS")
		)
		(fp_line
			(start -0.7874 0.4064)
			(end -0.7874 -0.4064)
			(stroke
				(width 0.1524)
				(type default)
			)
			(layer "F.SilkS")
		)
		(fp_line
			(start -0.12065 -0.305054)
			(end -0.12065 -0.2794)
			(stroke
				(width 0.1)
				(type default)
			)
			(layer "F.Fab")
		)
		(fp_line
			(start -0.67945 -0.305054)
			(end -0.12065 -0.305054)
			(stroke
				(width 0.1)
				(type default)
			)
			(layer "F.Fab")
		)
		(fp_line
			(start 0.67945 -0.3048)
			(end 0.67945 0.3048)
			(stroke
				(width 0.1)
				(type default)
			)
			(layer "F.Fab")
		)
		(fp_line
			(start 0.12065 -0.3048)
			(end 0.67945 -0.3048)
			(stroke
				(width 0.1)
				(type default)
			)
			(layer "F.Fab")
		)
		(fp_line
			(start 0.12065 -0.2794)
			(end 0.12065 -0.3048)
			(stroke
				(width 0.1)
				(type default)
			)
			(layer "F.Fab")
		)
		(fp_line
			(start -0.12065 -0.2794)
			(end 0.12065 -0.2794)
			(stroke
				(width 0.1)
				(type default)
			)
			(layer "F.Fab")
		)
		(fp_line
			(start 0.120396 0.2794)
			(end -0.12065 0.2794)
			(stroke
				(width 0.1)
				(type default)
			)
			(layer "F.Fab")
		)
		(fp_line
			(start -0.12065 0.2794)
			(end -0.12065 0.3048)
			(stroke
				(width 0.1)
				(type default)
			)
			(layer "F.Fab")
		)
		(fp_line
			(start 0.67945 0.3048)
			(end 0.120396 0.3048)
			(stroke
				(width 0.1)
				(type default)
			)
			(layer "F.Fab")
		)
		(fp_line
			(start 0.120396 0.3048)
			(end 0.120396 0.2794)
			(stroke
				(width 0.1)
				(type default)
			)
			(layer "F.Fab")
		)
		(fp_line
			(start -0.12065 0.3048)
			(end -0.67945 0.3048)
			(stroke
				(width 0.1)
				(type default)
			)
			(layer "F.Fab")
		)
		(fp_line
			(start -0.67945 0.3048)
			(end -0.67945 -0.305054)
			(stroke
				(width 0.1)
				(type default)
			)
			(layer "F.Fab")
		)
		(pad "1" smd circle
			(at -0.40005 0 90)
			(size 0 0)
			(layers "F.Cu" "F.Mask" "F.Paste")
			(net "P3V3_NIC4_CO_DV_DT")
		)
		(pad "2" smd circle
			(at 0.40005 0 90)
			(size 0 0)
			(layers "F.Cu" "F.Mask" "F.Paste")
			(net "GND")
		)
	)
	(footprint ""
		(layer "F.Cu")
		(at 279.489916 -72.766682 90)
		(property "Reference" "PR7078"
			(at 0 0 90)
			(layer "F.SilkS")
			(hide yes)
			(effects
				(font
					(size 1.27 1.27)
				)
			)
		)
		(property "Value" ""
			(at 0 0 90)
			(layer "F.Fab")
			(effects
				(font
					(size 1.27 1.27)
				)
			)
		)
		(duplicate_pad_numbers_are_jumpers no)
		(fp_line
			(start 0.7874 -0.4064)
			(end 0.7874 0.4064)
			(stroke
				(width 0.1524)
				(type default)
			)
			(layer "F.SilkS")
		)
		(fp_line
			(start -0.7874 -0.4064)
			(end 0.7874 -0.4064)
			(stroke
				(width 0.1524)
				(type default)
			)
			(layer "F.SilkS")
		)
		(fp_line
			(start 0.7874 0.4064)
			(end -0.7874 0.4064)
			(stroke
				(width 0.1524)
				(type default)
			)
			(layer "F.SilkS")
		)
		(fp_line
			(start -0.7874 0.4064)
			(end -0.7874 -0.4064)
			(stroke
				(width 0.1524)
				(type default)
			)
			(layer "F.SilkS")
		)
		(fp_line
			(start -0.12065 -0.305054)
			(end -0.12065 -0.2794)
			(stroke
				(width 0.1)
				(type default)
			)
			(layer "F.Fab")
		)
		(fp_line
			(start -0.67945 -0.305054)
			(end -0.12065 -0.305054)
			(stroke
				(width 0.1)
				(type default)
			)
			(layer "F.Fab")
		)
		(fp_line
			(start 0.67945 -0.3048)
			(end 0.67945 0.3048)
			(stroke
				(width 0.1)
				(type default)
			)
			(layer "F.Fab")
		)
		(fp_line
			(start 0.12065 -0.3048)
			(end 0.67945 -0.3048)
			(stroke
				(width 0.1)
				(type default)
			)
			(layer "F.Fab")
		)
		(fp_line
			(start 0.12065 -0.2794)
			(end 0.12065 -0.3048)
			(stroke
				(width 0.1)
				(type default)
			)
			(layer "F.Fab")
		)
		(fp_line
			(start -0.12065 -0.2794)
			(end 0.12065 -0.2794)
			(stroke
				(width 0.1)
				(type default)
			)
			(layer "F.Fab")
		)
		(fp_line
			(start 0.120396 0.2794)
			(end -0.12065 0.2794)
			(stroke
				(width 0.1)
				(type default)
			)
			(layer "F.Fab")
		)
		(fp_line
			(start -0.12065 0.2794)
			(end -0.12065 0.3048)
			(stroke
				(width 0.1)
				(type default)
			)
			(layer "F.Fab")
		)
		(fp_line
			(start 0.67945 0.3048)
			(end 0.120396 0.3048)
			(stroke
				(width 0.1)
				(type default)
			)
			(layer "F.Fab")
		)
		(fp_line
			(start 0.120396 0.3048)
			(end 0.120396 0.2794)
			(stroke
				(width 0.1)
				(type default)
			)
			(layer "F.Fab")
		)
		(fp_line
			(start -0.12065 0.3048)
			(end -0.67945 0.3048)
			(stroke
				(width 0.1)
				(type default)
			)
			(layer "F.Fab")
		)
		(fp_line
			(start -0.67945 0.3048)
			(end -0.67945 -0.305054)
			(stroke
				(width 0.1)
				(type default)
			)
			(layer "F.Fab")
		)
		(pad "1" smd circle
			(at -0.40005 0 90)
			(size 0 0)
			(layers "F.Cu" "F.Mask" "F.Paste")
			(net "P12V_SSD9_CO_ILIMIT")
		)
		(pad "2" smd circle
			(at 0.40005 0 90)
			(size 0 0)
			(layers "F.Cu" "F.Mask" "F.Paste")
			(net "GND")
		)
	)
	(footprint ""
		(layer "F.Cu")
		(at 32.470344 -250.070874 -90)
		(property "Reference" "R1160"
			(at 0 0 270)
			(layer "F.SilkS")
			(hide yes)
			(effects
				(font
					(size 1.27 1.27)
				)
			)
		)
		(property "Value" ""
			(at 0 0 270)
			(layer "F.Fab")
			(effects
				(font
					(size 1.27 1.27)
				)
			)
		)
		(duplicate_pad_numbers_are_jumpers no)
		(fp_line
			(start -0.7874 0.4064)
			(end -0.7874 -0.4064)
			(stroke
				(width 0.1524)
				(type default)
			)
			(layer "F.SilkS")
		)
		(fp_line
			(start 0.7874 0.4064)
			(end -0.7874 0.4064)
			(stroke
				(width 0.1524)
				(type default)
			)
			(layer "F.SilkS")
		)
		(fp_line
			(start -0.7874 -0.4064)
			(end 0.7874 -0.4064)
			(stroke
				(width 0.1524)
				(type default)
			)
			(layer "F.SilkS")
		)
		(fp_line
			(start 0.7874 -0.4064)
			(end 0.7874 0.4064)
			(stroke
				(width 0.1524)
				(type default)
			)
			(layer "F.SilkS")
		)
		(fp_line
			(start -0.67945 0.3048)
			(end -0.67945 -0.305054)
			(stroke
				(width 0.1)
				(type default)
			)
			(layer "F.Fab")
		)
		(fp_line
			(start -0.12065 0.3048)
			(end -0.67945 0.3048)
			(stroke
				(width 0.1)
				(type default)
			)
			(layer "F.Fab")
		)
		(fp_line
			(start 0.120396 0.3048)
			(end 0.120396 0.2794)
			(stroke
				(width 0.1)
				(type default)
			)
			(layer "F.Fab")
		)
		(fp_line
			(start 0.67945 0.3048)
			(end 0.120396 0.3048)
			(stroke
				(width 0.1)
				(type default)
			)
			(layer "F.Fab")
		)
		(fp_line
			(start -0.12065 0.2794)
			(end -0.12065 0.3048)
			(stroke
				(width 0.1)
				(type default)
			)
			(layer "F.Fab")
		)
		(fp_line
			(start 0.120396 0.2794)
			(end -0.12065 0.2794)
			(stroke
				(width 0.1)
				(type default)
			)
			(layer "F.Fab")
		)
		(fp_line
			(start -0.12065 -0.2794)
			(end 0.12065 -0.2794)
			(stroke
				(width 0.1)
				(type default)
			)
			(layer "F.Fab")
		)
		(fp_line
			(start 0.12065 -0.2794)
			(end 0.12065 -0.3048)
			(stroke
				(width 0.1)
				(type default)
			)
			(layer "F.Fab")
		)
		(fp_line
			(start 0.12065 -0.3048)
			(end 0.67945 -0.3048)
			(stroke
				(width 0.1)
				(type default)
			)
			(layer "F.Fab")
		)
		(fp_line
			(start 0.67945 -0.3048)
			(end 0.67945 0.3048)
			(stroke
				(width 0.1)
				(type default)
			)
			(layer "F.Fab")
		)
		(fp_line
			(start -0.67945 -0.305054)
			(end -0.12065 -0.305054)
			(stroke
				(width 0.1)
				(type default)
			)
			(layer "F.Fab")
		)
		(fp_line
			(start -0.12065 -0.305054)
			(end -0.12065 -0.2794)
			(stroke
				(width 0.1)
				(type default)
			)
			(layer "F.Fab")
		)
		(pad "1" smd circle
			(at -0.40005 0 270)
			(size 0 0)
			(layers "F.Cu" "F.Mask" "F.Paste")
			(net "PEX0_MODE_SEL8")
		)
		(pad "2" smd circle
			(at 0.40005 0 270)
			(size 0 0)
			(layers "F.Cu" "F.Mask" "F.Paste")
			(net "P1V8_PEX")
		)
	)
	(footprint ""
		(layer "F.Cu")
		(at 148.517102 -308.852062 -135)
		(property "Reference" "R1326"
			(at 0 0 225)
			(layer "F.SilkS")
			(hide yes)
			(effects
				(font
					(size 1.27 1.27)
				)
			)
		)
		(property "Value" ""
			(at 0 0 225)
			(layer "F.Fab")
			(effects
				(font
					(size 1.27 1.27)
				)
			)
		)
		(duplicate_pad_numbers_are_jumpers no)
		(fp_line
			(start 0.787389 0.406267)
			(end -0.787389 0.406267)
			(stroke
				(width 0.1524)
				(type default)
			)
			(layer "F.SilkS")
		)
		(fp_line
			(start 0.787389 -0.406267)
			(end 0.787389 0.406267)
			(stroke
				(width 0.1524)
				(type default)
			)
			(layer "F.SilkS")
		)
		(fp_line
			(start -0.787389 0.406267)
			(end -0.787389 -0.406267)
			(stroke
				(width 0.1524)
				(type default)
			)
			(layer "F.SilkS")
		)
		(fp_line
			(start -0.787389 -0.406267)
			(end 0.787389 -0.406267)
			(stroke
				(width 0.1524)
				(type default)
			)
			(layer "F.SilkS")
		)
		(fp_line
			(start 0.679446 0.30479)
			(end 0.120515 0.30479)
			(stroke
				(width 0.1)
				(type default)
			)
			(layer "F.Fab")
		)
		(fp_line
			(start 0.120515 0.30479)
			(end 0.120335 0.279466)
			(stroke
				(width 0.1)
				(type default)
			)
			(layer "F.Fab")
		)
		(fp_line
			(start 0.120335 0.279466)
			(end -0.120695 0.279466)
			(stroke
				(width 0.1)
				(type default)
			)
			(layer "F.Fab")
		)
		(fp_line
			(start 0.679446 -0.30479)
			(end 0.679446 0.30479)
			(stroke
				(width 0.1)
				(type default)
			)
			(layer "F.Fab")
		)
		(fp_line
			(start -0.120515 0.30479)
			(end -0.679446 0.30479)
			(stroke
				(width 0.1)
				(type default)
			)
			(layer "F.Fab")
		)
		(fp_line
			(start -0.120695 0.279466)
			(end -0.120515 0.30479)
			(stroke
				(width 0.1)
				(type default)
			)
			(layer "F.Fab")
		)
		(fp_line
			(start 0.120695 -0.279466)
			(end 0.120515 -0.30479)
			(stroke
				(width 0.1)
				(type default)
			)
			(layer "F.Fab")
		)
		(fp_line
			(start 0.120515 -0.30479)
			(end 0.679446 -0.30479)
			(stroke
				(width 0.1)
				(type default)
			)
			(layer "F.Fab")
		)
		(fp_line
			(start -0.679446 0.30479)
			(end -0.679446 -0.305149)
			(stroke
				(width 0.1)
				(type default)
			)
			(layer "F.Fab")
		)
		(fp_line
			(start -0.120695 -0.279466)
			(end 0.120695 -0.279466)
			(stroke
				(width 0.1)
				(type default)
			)
			(layer "F.Fab")
		)
		(fp_line
			(start -0.120695 -0.304969)
			(end -0.120695 -0.279466)
			(stroke
				(width 0.1)
				(type default)
			)
			(layer "F.Fab")
		)
		(fp_line
			(start -0.679446 -0.305149)
			(end -0.120695 -0.304969)
			(stroke
				(width 0.1)
				(type default)
			)
			(layer "F.Fab")
		)
		(pad "1" smd circle
			(at -0.40005 0 225)
			(size 0 0)
			(layers "F.Cu" "F.Mask" "F.Paste")
			(net "PU_PEX1_ATPG_MODE_L")
		)
		(pad "2" smd circle
			(at 0.40005 0 225)
			(size 0 0)
			(layers "F.Cu" "F.Mask" "F.Paste")
			(net "P1V8_PEX")
		)
	)
	(footprint ""
		(layer "F.Cu")
		(at 445.954658 -22.867366 90)
		(property "Reference" "C3983"
			(at 0 0 90)
			(layer "F.SilkS")
			(hide yes)
			(effects
				(font
					(size 1.27 1.27)
				)
			)
		)
		(property "Value" ""
			(at 0 0 90)
			(layer "F.Fab")
			(effects
				(font
					(size 1.27 1.27)
				)
			)
		)
		(duplicate_pad_numbers_are_jumpers no)
		(fp_line
			(start 0.7874 -0.4064)
			(end 0.7874 0.4064)
			(stroke
				(width 0.1524)
				(type default)
			)
			(layer "F.SilkS")
		)
		(fp_line
			(start -0.7874 -0.4064)
			(end 0.7874 -0.4064)
			(stroke
				(width 0.1524)
				(type default)
			)
			(layer "F.SilkS")
		)
		(fp_line
			(start 0.7874 0.4064)
			(end -0.7874 0.4064)
			(stroke
				(width 0.1524)
				(type default)
			)
			(layer "F.SilkS")
		)
		(fp_line
			(start -0.7874 0.4064)
			(end -0.7874 -0.4064)
			(stroke
				(width 0.1524)
				(type default)
			)
			(layer "F.SilkS")
		)
		(fp_line
			(start -0.12065 -0.305054)
			(end -0.12065 -0.2794)
			(stroke
				(width 0.1)
				(type default)
			)
			(layer "F.Fab")
		)
		(fp_line
			(start -0.67945 -0.305054)
			(end -0.12065 -0.305054)
			(stroke
				(width 0.1)
				(type default)
			)
			(layer "F.Fab")
		)
		(fp_line
			(start 0.67945 -0.3048)
			(end 0.67945 0.3048)
			(stroke
				(width 0.1)
				(type default)
			)
			(layer "F.Fab")
		)
		(fp_line
			(start 0.12065 -0.3048)
			(end 0.67945 -0.3048)
			(stroke
				(width 0.1)
				(type default)
			)
			(layer "F.Fab")
		)
		(fp_line
			(start 0.12065 -0.2794)
			(end 0.12065 -0.3048)
			(stroke
				(width 0.1)
				(type default)
			)
			(layer "F.Fab")
		)
		(fp_line
			(start -0.12065 -0.2794)
			(end 0.12065 -0.2794)
			(stroke
				(width 0.1)
				(type default)
			)
			(layer "F.Fab")
		)
		(fp_line
			(start 0.120396 0.2794)
			(end -0.12065 0.2794)
			(stroke
				(width 0.1)
				(type default)
			)
			(layer "F.Fab")
		)
		(fp_line
			(start -0.12065 0.2794)
			(end -0.12065 0.3048)
			(stroke
				(width 0.1)
				(type default)
			)
			(layer "F.Fab")
		)
		(fp_line
			(start 0.67945 0.3048)
			(end 0.120396 0.3048)
			(stroke
				(width 0.1)
				(type default)
			)
			(layer "F.Fab")
		)
		(fp_line
			(start 0.120396 0.3048)
			(end 0.120396 0.2794)
			(stroke
				(width 0.1)
				(type default)
			)
			(layer "F.Fab")
		)
		(fp_line
			(start -0.12065 0.3048)
			(end -0.67945 0.3048)
			(stroke
				(width 0.1)
				(type default)
			)
			(layer "F.Fab")
		)
		(fp_line
			(start -0.67945 0.3048)
			(end -0.67945 -0.305054)
			(stroke
				(width 0.1)
				(type default)
			)
			(layer "F.Fab")
		)
		(pad "1" smd circle
			(at -0.40005 0 90)
			(size 0 0)
			(layers "F.Cu" "F.Mask" "F.Paste")
			(net "P12V_SSD15")
		)
		(pad "2" smd circle
			(at 0.40005 0 90)
			(size 0 0)
			(layers "F.Cu" "F.Mask" "F.Paste")
			(net "GND")
		)
	)
	(footprint ""
		(layer "F.Cu")
		(at 387.580632 -110.088934)
		(property "Reference" "C684"
			(at 0 0 0)
			(layer "F.SilkS")
			(hide yes)
			(effects
				(font
					(size 1.27 1.27)
				)
			)
		)
		(property "Value" ""
			(at 0 0 0)
			(layer "F.Fab")
			(effects
				(font
					(size 1.27 1.27)
				)
			)
		)
		(duplicate_pad_numbers_are_jumpers no)
		(fp_line
			(start -0.299974 -0.150114)
			(end 0.299974 -0.150114)
			(stroke
				(width 0.1)
				(type default)
			)
			(layer "F.Fab")
		)
		(fp_line
			(start -0.299974 0.150114)
			(end -0.299974 -0.150114)
			(stroke
				(width 0.1)
				(type default)
			)
			(layer "F.Fab")
		)
		(fp_line
			(start 0.299974 -0.150114)
			(end 0.299974 0.150114)
			(stroke
				(width 0.1)
				(type default)
			)
			(layer "F.Fab")
		)
		(fp_line
			(start 0.299974 0.150114)
			(end -0.299974 0.150114)
			(stroke
				(width 0.1)
				(type default)
			)
			(layer "F.Fab")
		)
		(pad "1" smd rect
			(at -0.2667 0)
			(size 0.3048 0.381)
			(layers "F.Cu" "F.Mask" "F.Paste")
			(net "P5E_PEX3_STN1_TX_DP<22>")
		)
		(pad "2" smd rect
			(at 0.2667 0)
			(size 0.3048 0.381)
			(layers "F.Cu" "F.Mask" "F.Paste")
			(net "P5E_PEX3_STN1_TX_C_DP<22>")
		)
	)
	(footprint ""
		(layer "F.Cu")
		(at 142.305024 -197.529196 -90)
		(property "Reference" "R5775"
			(at 0 0 270)
			(layer "F.SilkS")
			(hide yes)
			(effects
				(font
					(size 1.27 1.27)
				)
			)
		)
		(property "Value" ""
			(at 0 0 270)
			(layer "F.Fab")
			(effects
				(font
					(size 1.27 1.27)
				)
			)
		)
		(duplicate_pad_numbers_are_jumpers no)
		(fp_line
			(start -0.7874 0.4064)
			(end -0.7874 -0.4064)
			(stroke
				(width 0.1524)
				(type default)
			)
			(layer "F.SilkS")
		)
		(fp_line
			(start 0.7874 0.4064)
			(end -0.7874 0.4064)
			(stroke
				(width 0.1524)
				(type default)
			)
			(layer "F.SilkS")
		)
		(fp_line
			(start -0.7874 -0.4064)
			(end 0.7874 -0.4064)
			(stroke
				(width 0.1524)
				(type default)
			)
			(layer "F.SilkS")
		)
		(fp_line
			(start 0.7874 -0.4064)
			(end 0.7874 0.4064)
			(stroke
				(width 0.1524)
				(type default)
			)
			(layer "F.SilkS")
		)
		(fp_line
			(start -0.67945 0.3048)
			(end -0.67945 -0.305054)
			(stroke
				(width 0.1)
				(type default)
			)
			(layer "F.Fab")
		)
		(fp_line
			(start -0.12065 0.3048)
			(end -0.67945 0.3048)
			(stroke
				(width 0.1)
				(type default)
			)
			(layer "F.Fab")
		)
		(fp_line
			(start 0.120396 0.3048)
			(end 0.120396 0.2794)
			(stroke
				(width 0.1)
				(type default)
			)
			(layer "F.Fab")
		)
		(fp_line
			(start 0.67945 0.3048)
			(end 0.120396 0.3048)
			(stroke
				(width 0.1)
				(type default)
			)
			(layer "F.Fab")
		)
		(fp_line
			(start -0.12065 0.2794)
			(end -0.12065 0.3048)
			(stroke
				(width 0.1)
				(type default)
			)
			(layer "F.Fab")
		)
		(fp_line
			(start 0.120396 0.2794)
			(end -0.12065 0.2794)
			(stroke
				(width 0.1)
				(type default)
			)
			(layer "F.Fab")
		)
		(fp_line
			(start -0.12065 -0.2794)
			(end 0.12065 -0.2794)
			(stroke
				(width 0.1)
				(type default)
			)
			(layer "F.Fab")
		)
		(fp_line
			(start 0.12065 -0.2794)
			(end 0.12065 -0.3048)
			(stroke
				(width 0.1)
				(type default)
			)
			(layer "F.Fab")
		)
		(fp_line
			(start 0.12065 -0.3048)
			(end 0.67945 -0.3048)
			(stroke
				(width 0.1)
				(type default)
			)
			(layer "F.Fab")
		)
		(fp_line
			(start 0.67945 -0.3048)
			(end 0.67945 0.3048)
			(stroke
				(width 0.1)
				(type default)
			)
			(layer "F.Fab")
		)
		(fp_line
			(start -0.67945 -0.305054)
			(end -0.12065 -0.305054)
			(stroke
				(width 0.1)
				(type default)
			)
			(layer "F.Fab")
		)
		(fp_line
			(start -0.12065 -0.305054)
			(end -0.12065 -0.2794)
			(stroke
				(width 0.1)
				(type default)
			)
			(layer "F.Fab")
		)
		(pad "1" smd circle
			(at -0.40005 0 270)
			(size 0 0)
			(layers "F.Cu" "F.Mask" "F.Paste")
			(net "RST_FT4232_CLI_R_N")
		)
		(pad "2" smd circle
			(at 0.40005 0 270)
			(size 0 0)
			(layers "F.Cu" "F.Mask" "F.Paste")
			(net "RST_FT4232_R_N")
		)
	)
	(footprint ""
		(layer "F.Cu")
		(at 235.623608 -146.704812)
		(property "Reference" "R4222"
			(at 0 0 0)
			(layer "F.SilkS")
			(hide yes)
			(effects
				(font
					(size 1.27 1.27)
				)
			)
		)
		(property "Value" ""
			(at 0 0 0)
			(layer "F.Fab")
			(effects
				(font
					(size 1.27 1.27)
				)
			)
		)
		(duplicate_pad_numbers_are_jumpers no)
		(fp_line
			(start -0.7874 -0.4064)
			(end 0.7874 -0.4064)
			(stroke
				(width 0.1524)
				(type default)
			)
			(layer "F.SilkS")
		)
		(fp_line
			(start -0.7874 0.4064)
			(end -0.7874 -0.4064)
			(stroke
				(width 0.1524)
				(type default)
			)
			(layer "F.SilkS")
		)
		(fp_line
			(start 0.7874 -0.4064)
			(end 0.7874 0.4064)
			(stroke
				(width 0.1524)
				(type default)
			)
			(layer "F.SilkS")
		)
		(fp_line
			(start 0.7874 0.4064)
			(end -0.7874 0.4064)
			(stroke
				(width 0.1524)
				(type default)
			)
			(layer "F.SilkS")
		)
		(fp_line
			(start -0.67945 -0.305054)
			(end -0.12065 -0.305054)
			(stroke
				(width 0.1)
				(type default)
			)
			(layer "F.Fab")
		)
		(fp_line
			(start -0.67945 0.3048)
			(end -0.67945 -0.305054)
			(stroke
				(width 0.1)
				(type default)
			)
			(layer "F.Fab")
		)
		(fp_line
			(start -0.12065 -0.305054)
			(end -0.12065 -0.2794)
			(stroke
				(width 0.1)
				(type default)
			)
			(layer "F.Fab")
		)
		(fp_line
			(start -0.12065 -0.2794)
			(end 0.12065 -0.2794)
			(stroke
				(width 0.1)
				(type default)
			)
			(layer "F.Fab")
		)
		(fp_line
			(start -0.12065 0.2794)
			(end -0.12065 0.3048)
			(stroke
				(width 0.1)
				(type default)
			)
			(layer "F.Fab")
		)
		(fp_line
			(start -0.12065 0.3048)
			(end -0.67945 0.3048)
			(stroke
				(width 0.1)
				(type default)
			)
			(layer "F.Fab")
		)
		(fp_line
			(start 0.120396 0.2794)
			(end -0.12065 0.2794)
			(stroke
				(width 0.1)
				(type default)
			)
			(layer "F.Fab")
		)
		(fp_line
			(start 0.120396 0.3048)
			(end 0.120396 0.2794)
			(stroke
				(width 0.1)
				(type default)
			)
			(layer "F.Fab")
		)
		(fp_line
			(start 0.12065 -0.3048)
			(end 0.67945 -0.3048)
			(stroke
				(width 0.1)
				(type default)
			)
			(layer "F.Fab")
		)
		(fp_line
			(start 0.12065 -0.2794)
			(end 0.12065 -0.3048)
			(stroke
				(width 0.1)
				(type default)
			)
			(layer "F.Fab")
		)
		(fp_line
			(start 0.67945 -0.3048)
			(end 0.67945 0.3048)
			(stroke
				(width 0.1)
				(type default)
			)
			(layer "F.Fab")
		)
		(fp_line
			(start 0.67945 0.3048)
			(end 0.120396 0.3048)
			(stroke
				(width 0.1)
				(type default)
			)
			(layer "F.Fab")
		)
		(pad "1" smd circle
			(at -0.40005 0)
			(size 0 0)
			(layers "F.Cu" "F.Mask" "F.Paste")
			(net "CLK_GEN_CK440_PEX_OE5_N")
		)
		(pad "2" smd circle
			(at 0.40005 0)
			(size 0 0)
			(layers "F.Cu" "F.Mask" "F.Paste")
			(net "P3V3")
		)
	)
	(footprint ""
		(layer "F.Cu")
		(at 438.71134 -107.29976)
		(property "Reference" "R758"
			(at 0 0 0)
			(layer "F.SilkS")
			(hide yes)
			(effects
				(font
					(size 1.27 1.27)
				)
			)
		)
		(property "Value" ""
			(at 0 0 0)
			(layer "F.Fab")
			(effects
				(font
					(size 1.27 1.27)
				)
			)
		)
		(duplicate_pad_numbers_are_jumpers no)
		(fp_line
			(start -3.937508 -1.8796)
			(end -3.937508 1.8796)
			(stroke
				(width 0.1524)
				(type default)
			)
			(layer "F.SilkS")
		)
		(fp_line
			(start -3.937508 1.8796)
			(end 3.937508 1.8796)
			(stroke
				(width 0.1524)
				(type default)
			)
			(layer "F.SilkS")
		)
		(fp_line
			(start 3.937508 -1.8796)
			(end -3.937508 -1.8796)
			(stroke
				(width 0.1524)
				(type default)
			)
			(layer "F.SilkS")
		)
		(fp_line
			(start 3.937508 1.8796)
			(end 3.937508 -1.8796)
			(stroke
				(width 0.1524)
				(type default)
			)
			(layer "F.SilkS")
		)
		(fp_line
			(start -3.275076 -1.674876)
			(end -3.275076 1.674876)
			(stroke
				(width 0.1)
				(type default)
			)
			(layer "F.Fab")
		)
		(fp_line
			(start -3.275076 1.674876)
			(end 3.275076 1.674876)
			(stroke
				(width 0.1)
				(type default)
			)
			(layer "F.Fab")
		)
		(fp_line
			(start 3.275076 -1.674876)
			(end -3.275076 -1.674876)
			(stroke
				(width 0.1)
				(type default)
			)
			(layer "F.Fab")
		)
		(fp_line
			(start 3.275076 1.674876)
			(end 3.275076 -1.674876)
			(stroke
				(width 0.1)
				(type default)
			)
			(layer "F.Fab")
		)
		(pad "1" smd rect
			(at -2.350008 0)
			(size 2.921 3.5052)
			(layers "F.Cu" "F.Mask" "F.Paste")
			(net "P12V_NIC7")
		)
		(pad "2" smd rect
			(at 2.350008 0)
			(size 2.921 3.5052)
			(layers "F.Cu" "F.Mask" "F.Paste")
			(net "P12V_NIC7_R")
		)
	)
	(footprint ""
		(layer "F.Cu")
		(at 28.406344 -252.356874 -90)
		(property "Reference" "R1188"
			(at 0 0 270)
			(layer "F.SilkS")
			(hide yes)
			(effects
				(font
					(size 1.27 1.27)
				)
			)
		)
		(property "Value" ""
			(at 0 0 270)
			(layer "F.Fab")
			(effects
				(font
					(size 1.27 1.27)
				)
			)
		)
		(duplicate_pad_numbers_are_jumpers no)
		(fp_line
			(start -0.7874 0.4064)
			(end -0.7874 -0.4064)
			(stroke
				(width 0.1524)
				(type default)
			)
			(layer "F.SilkS")
		)
		(fp_line
			(start 0.7874 0.4064)
			(end -0.7874 0.4064)
			(stroke
				(width 0.1524)
				(type default)
			)
			(layer "F.SilkS")
		)
		(fp_line
			(start -0.7874 -0.4064)
			(end 0.7874 -0.4064)
			(stroke
				(width 0.1524)
				(type default)
			)
			(layer "F.SilkS")
		)
		(fp_line
			(start 0.7874 -0.4064)
			(end 0.7874 0.4064)
			(stroke
				(width 0.1524)
				(type default)
			)
			(layer "F.SilkS")
		)
		(fp_line
			(start -0.67945 0.3048)
			(end -0.67945 -0.305054)
			(stroke
				(width 0.1)
				(type default)
			)
			(layer "F.Fab")
		)
		(fp_line
			(start -0.12065 0.3048)
			(end -0.67945 0.3048)
			(stroke
				(width 0.1)
				(type default)
			)
			(layer "F.Fab")
		)
		(fp_line
			(start 0.120396 0.3048)
			(end 0.120396 0.2794)
			(stroke
				(width 0.1)
				(type default)
			)
			(layer "F.Fab")
		)
		(fp_line
			(start 0.67945 0.3048)
			(end 0.120396 0.3048)
			(stroke
				(width 0.1)
				(type default)
			)
			(layer "F.Fab")
		)
		(fp_line
			(start -0.12065 0.2794)
			(end -0.12065 0.3048)
			(stroke
				(width 0.1)
				(type default)
			)
			(layer "F.Fab")
		)
		(fp_line
			(start 0.120396 0.2794)
			(end -0.12065 0.2794)
			(stroke
				(width 0.1)
				(type default)
			)
			(layer "F.Fab")
		)
		(fp_line
			(start -0.12065 -0.2794)
			(end 0.12065 -0.2794)
			(stroke
				(width 0.1)
				(type default)
			)
			(layer "F.Fab")
		)
		(fp_line
			(start 0.12065 -0.2794)
			(end 0.12065 -0.3048)
			(stroke
				(width 0.1)
				(type default)
			)
			(layer "F.Fab")
		)
		(fp_line
			(start 0.12065 -0.3048)
			(end 0.67945 -0.3048)
			(stroke
				(width 0.1)
				(type default)
			)
			(layer "F.Fab")
		)
		(fp_line
			(start 0.67945 -0.3048)
			(end 0.67945 0.3048)
			(stroke
				(width 0.1)
				(type default)
			)
			(layer "F.Fab")
		)
		(fp_line
			(start -0.67945 -0.305054)
			(end -0.12065 -0.305054)
			(stroke
				(width 0.1)
				(type default)
			)
			(layer "F.Fab")
		)
		(fp_line
			(start -0.12065 -0.305054)
			(end -0.12065 -0.2794)
			(stroke
				(width 0.1)
				(type default)
			)
			(layer "F.Fab")
		)
		(pad "1" smd circle
			(at -0.40005 0 270)
			(size 0 0)
			(layers "F.Cu" "F.Mask" "F.Paste")
			(net "GND")
		)
		(pad "2" smd circle
			(at 0.40005 0 270)
			(size 0 0)
			(layers "F.Cu" "F.Mask" "F.Paste")
			(net "PEX0_DBG_MODE3")
		)
	)
	(footprint ""
		(layer "F.Cu")
		(at 227.31476 -314.424314)
		(property "Reference" "PC225"
			(at 0 0 0)
			(layer "F.SilkS")
			(hide yes)
			(effects
				(font
					(size 1.27 1.27)
				)
			)
		)
		(property "Value" ""
			(at 0 0 0)
			(layer "F.Fab")
			(effects
				(font
					(size 1.27 1.27)
				)
			)
		)
		(duplicate_pad_numbers_are_jumpers no)
		(fp_line
			(start -1.524 -0.762)
			(end 1.524 -0.762)
			(stroke
				(width 0.1524)
				(type default)
			)
			(layer "F.SilkS")
		)
		(fp_line
			(start -1.524 0.762)
			(end -1.524 -0.762)
			(stroke
				(width 0.1524)
				(type default)
			)
			(layer "F.SilkS")
		)
		(fp_line
			(start 1.524 -0.762)
			(end 1.524 0.762)
			(stroke
				(width 0.1524)
				(type default)
			)
			(layer "F.SilkS")
		)
		(fp_line
			(start 1.524 0.762)
			(end -1.524 0.762)
			(stroke
				(width 0.1524)
				(type default)
			)
			(layer "F.SilkS")
		)
		(fp_line
			(start -1.1049 -0.724916)
			(end -1.1049 0.724916)
			(stroke
				(width 0.1)
				(type default)
			)
			(layer "F.Fab")
		)
		(fp_line
			(start -1.1049 0.724916)
			(end 1.1049 0.724916)
			(stroke
				(width 0.1)
				(type default)
			)
			(layer "F.Fab")
		)
		(fp_line
			(start 1.1049 -0.724916)
			(end -1.1049 -0.724916)
			(stroke
				(width 0.1)
				(type default)
			)
			(layer "F.Fab")
		)
		(fp_line
			(start 1.1049 0.724916)
			(end 1.1049 -0.724916)
			(stroke
				(width 0.1)
				(type default)
			)
			(layer "F.Fab")
		)
		(pad "1" smd rect
			(at -0.889 0 180)
			(size 1.016 1.27)
			(layers "F.Cu" "F.Mask" "F.Paste")
			(net "SW_P12V_P1V25_PEX1_FLT")
		)
		(pad "2" smd rect
			(at 0.889 0 180)
			(size 1.016 1.27)
			(layers "F.Cu" "F.Mask" "F.Paste")
			(net "GND")
		)
	)
	(footprint ""
		(layer "F.Cu")
		(at 238.21898 -224.48266 180)
		(property "Reference" "C4437"
			(at 0 0 180)
			(layer "F.SilkS")
			(hide yes)
			(effects
				(font
					(size 1.27 1.27)
				)
			)
		)
		(property "Value" ""
			(at 0 0 180)
			(layer "F.Fab")
			(effects
				(font
					(size 1.27 1.27)
				)
			)
		)
		(duplicate_pad_numbers_are_jumpers no)
		(fp_line
			(start 0.7874 0.4064)
			(end -0.7874 0.4064)
			(stroke
				(width 0.1524)
				(type default)
			)
			(layer "F.SilkS")
		)
		(fp_line
			(start 0.7874 -0.4064)
			(end 0.7874 0.4064)
			(stroke
				(width 0.1524)
				(type default)
			)
			(layer "F.SilkS")
		)
		(fp_line
			(start -0.7874 0.4064)
			(end -0.7874 -0.4064)
			(stroke
				(width 0.1524)
				(type default)
			)
			(layer "F.SilkS")
		)
		(fp_line
			(start -0.7874 -0.4064)
			(end 0.7874 -0.4064)
			(stroke
				(width 0.1524)
				(type default)
			)
			(layer "F.SilkS")
		)
		(fp_line
			(start 0.67945 0.3048)
			(end 0.120396 0.3048)
			(stroke
				(width 0.1)
				(type default)
			)
			(layer "F.Fab")
		)
		(fp_line
			(start 0.67945 -0.3048)
			(end 0.67945 0.3048)
			(stroke
				(width 0.1)
				(type default)
			)
			(layer "F.Fab")
		)
		(fp_line
			(start 0.12065 -0.2794)
			(end 0.12065 -0.3048)
			(stroke
				(width 0.1)
				(type default)
			)
			(layer "F.Fab")
		)
		(fp_line
			(start 0.12065 -0.3048)
			(end 0.67945 -0.3048)
			(stroke
				(width 0.1)
				(type default)
			)
			(layer "F.Fab")
		)
		(fp_line
			(start 0.120396 0.3048)
			(end 0.120396 0.2794)
			(stroke
				(width 0.1)
				(type default)
			)
			(layer "F.Fab")
		)
		(fp_line
			(start 0.120396 0.2794)
			(end -0.12065 0.2794)
			(stroke
				(width 0.1)
				(type default)
			)
			(layer "F.Fab")
		)
		(fp_line
			(start -0.12065 0.3048)
			(end -0.67945 0.3048)
			(stroke
				(width 0.1)
				(type default)
			)
			(layer "F.Fab")
		)
		(fp_line
			(start -0.12065 0.2794)
			(end -0.12065 0.3048)
			(stroke
				(width 0.1)
				(type default)
			)
			(layer "F.Fab")
		)
		(fp_line
			(start -0.12065 -0.2794)
			(end 0.12065 -0.2794)
			(stroke
				(width 0.1)
				(type default)
			)
			(layer "F.Fab")
		)
		(fp_line
			(start -0.12065 -0.305054)
			(end -0.12065 -0.2794)
			(stroke
				(width 0.1)
				(type default)
			)
			(layer "F.Fab")
		)
		(fp_line
			(start -0.67945 0.3048)
			(end -0.67945 -0.305054)
			(stroke
				(width 0.1)
				(type default)
			)
			(layer "F.Fab")
		)
		(fp_line
			(start -0.67945 -0.305054)
			(end -0.12065 -0.305054)
			(stroke
				(width 0.1)
				(type default)
			)
			(layer "F.Fab")
		)
		(pad "1" smd circle
			(at -0.40005 0 180)
			(size 0 0)
			(layers "F.Cu" "F.Mask" "F.Paste")
			(net "P1V8_PLL0_PEX3_SCALED")
		)
		(pad "2" smd circle
			(at 0.40005 0 180)
			(size 0 0)
			(layers "F.Cu" "F.Mask" "F.Paste")
			(net "GND")
		)
	)
	(footprint ""
		(layer "F.Cu")
		(at 10.045446 -255.046734 -90)
		(property "Reference" "R6463"
			(at 0 0 270)
			(layer "F.SilkS")
			(hide yes)
			(effects
				(font
					(size 1.27 1.27)
				)
			)
		)
		(property "Value" ""
			(at 0 0 270)
			(layer "F.Fab")
			(effects
				(font
					(size 1.27 1.27)
				)
			)
		)
		(duplicate_pad_numbers_are_jumpers no)
		(fp_line
			(start -0.7874 0.4064)
			(end -0.7874 -0.4064)
			(stroke
				(width 0.1524)
				(type default)
			)
			(layer "F.SilkS")
		)
		(fp_line
			(start 0.7874 0.4064)
			(end -0.7874 0.4064)
			(stroke
				(width 0.1524)
				(type default)
			)
			(layer "F.SilkS")
		)
		(fp_line
			(start -0.7874 -0.4064)
			(end 0.7874 -0.4064)
			(stroke
				(width 0.1524)
				(type default)
			)
			(layer "F.SilkS")
		)
		(fp_line
			(start 0.7874 -0.4064)
			(end 0.7874 0.4064)
			(stroke
				(width 0.1524)
				(type default)
			)
			(layer "F.SilkS")
		)
		(fp_line
			(start -0.67945 0.3048)
			(end -0.67945 -0.305054)
			(stroke
				(width 0.1)
				(type default)
			)
			(layer "F.Fab")
		)
		(fp_line
			(start -0.12065 0.3048)
			(end -0.67945 0.3048)
			(stroke
				(width 0.1)
				(type default)
			)
			(layer "F.Fab")
		)
		(fp_line
			(start 0.120396 0.3048)
			(end 0.120396 0.2794)
			(stroke
				(width 0.1)
				(type default)
			)
			(layer "F.Fab")
		)
		(fp_line
			(start 0.67945 0.3048)
			(end 0.120396 0.3048)
			(stroke
				(width 0.1)
				(type default)
			)
			(layer "F.Fab")
		)
		(fp_line
			(start -0.12065 0.2794)
			(end -0.12065 0.3048)
			(stroke
				(width 0.1)
				(type default)
			)
			(layer "F.Fab")
		)
		(fp_line
			(start 0.120396 0.2794)
			(end -0.12065 0.2794)
			(stroke
				(width 0.1)
				(type default)
			)
			(layer "F.Fab")
		)
		(fp_line
			(start -0.12065 -0.2794)
			(end 0.12065 -0.2794)
			(stroke
				(width 0.1)
				(type default)
			)
			(layer "F.Fab")
		)
		(fp_line
			(start 0.12065 -0.2794)
			(end 0.12065 -0.3048)
			(stroke
				(width 0.1)
				(type default)
			)
			(layer "F.Fab")
		)
		(fp_line
			(start 0.12065 -0.3048)
			(end 0.67945 -0.3048)
			(stroke
				(width 0.1)
				(type default)
			)
			(layer "F.Fab")
		)
		(fp_line
			(start 0.67945 -0.3048)
			(end 0.67945 0.3048)
			(stroke
				(width 0.1)
				(type default)
			)
			(layer "F.Fab")
		)
		(fp_line
			(start -0.67945 -0.305054)
			(end -0.12065 -0.305054)
			(stroke
				(width 0.1)
				(type default)
			)
			(layer "F.Fab")
		)
		(fp_line
			(start -0.12065 -0.305054)
			(end -0.12065 -0.2794)
			(stroke
				(width 0.1)
				(type default)
			)
			(layer "F.Fab")
		)
		(pad "1" smd circle
			(at -0.40005 0 270)
			(size 0 0)
			(layers "F.Cu" "F.Mask" "F.Paste")
			(net "P1V25_SERDES_VDDPLL_PEX0")
		)
		(pad "2" smd circle
			(at 0.40005 0 270)
			(size 0 0)
			(layers "F.Cu" "F.Mask" "F.Paste")
			(net "P1V25_SERDES_VDDPLL_PEX0_C2")
		)
	)
	(footprint ""
		(layer "F.Cu")
		(at 209.166206 -306.074572 90)
		(property "Reference" "R4177"
			(at 0 0 90)
			(layer "F.SilkS")
			(hide yes)
			(effects
				(font
					(size 1.27 1.27)
				)
			)
		)
		(property "Value" ""
			(at 0 0 90)
			(layer "F.Fab")
			(effects
				(font
					(size 1.27 1.27)
				)
			)
		)
		(duplicate_pad_numbers_are_jumpers no)
		(fp_line
			(start 0.7874 -0.4064)
			(end 0.7874 0.4064)
			(stroke
				(width 0.1524)
				(type default)
			)
			(layer "F.SilkS")
		)
		(fp_line
			(start -0.7874 -0.4064)
			(end 0.7874 -0.4064)
			(stroke
				(width 0.1524)
				(type default)
			)
			(layer "F.SilkS")
		)
		(fp_line
			(start 0.7874 0.4064)
			(end -0.7874 0.4064)
			(stroke
				(width 0.1524)
				(type default)
			)
			(layer "F.SilkS")
		)
		(fp_line
			(start -0.7874 0.4064)
			(end -0.7874 -0.4064)
			(stroke
				(width 0.1524)
				(type default)
			)
			(layer "F.SilkS")
		)
		(fp_line
			(start -0.12065 -0.305054)
			(end -0.12065 -0.2794)
			(stroke
				(width 0.1)
				(type default)
			)
			(layer "F.Fab")
		)
		(fp_line
			(start -0.67945 -0.305054)
			(end -0.12065 -0.305054)
			(stroke
				(width 0.1)
				(type default)
			)
			(layer "F.Fab")
		)
		(fp_line
			(start 0.67945 -0.3048)
			(end 0.67945 0.3048)
			(stroke
				(width 0.1)
				(type default)
			)
			(layer "F.Fab")
		)
		(fp_line
			(start 0.12065 -0.3048)
			(end 0.67945 -0.3048)
			(stroke
				(width 0.1)
				(type default)
			)
			(layer "F.Fab")
		)
		(fp_line
			(start 0.12065 -0.2794)
			(end 0.12065 -0.3048)
			(stroke
				(width 0.1)
				(type default)
			)
			(layer "F.Fab")
		)
		(fp_line
			(start -0.12065 -0.2794)
			(end 0.12065 -0.2794)
			(stroke
				(width 0.1)
				(type default)
			)
			(layer "F.Fab")
		)
		(fp_line
			(start 0.120396 0.2794)
			(end -0.12065 0.2794)
			(stroke
				(width 0.1)
				(type default)
			)
			(layer "F.Fab")
		)
		(fp_line
			(start -0.12065 0.2794)
			(end -0.12065 0.3048)
			(stroke
				(width 0.1)
				(type default)
			)
			(layer "F.Fab")
		)
		(fp_line
			(start 0.67945 0.3048)
			(end 0.120396 0.3048)
			(stroke
				(width 0.1)
				(type default)
			)
			(layer "F.Fab")
		)
		(fp_line
			(start 0.120396 0.3048)
			(end 0.120396 0.2794)
			(stroke
				(width 0.1)
				(type default)
			)
			(layer "F.Fab")
		)
		(fp_line
			(start -0.12065 0.3048)
			(end -0.67945 0.3048)
			(stroke
				(width 0.1)
				(type default)
			)
			(layer "F.Fab")
		)
		(fp_line
			(start -0.67945 0.3048)
			(end -0.67945 -0.305054)
			(stroke
				(width 0.1)
				(type default)
			)
			(layer "F.Fab")
		)
		(pad "1" smd circle
			(at -0.40005 0 90)
			(size 0 0)
			(layers "F.Cu" "F.Mask" "F.Paste")
			(net "PEX1_EXT_GPIO_LATCH_N")
		)
		(pad "2" smd circle
			(at 0.40005 0 90)
			(size 0 0)
			(layers "F.Cu" "F.Mask" "F.Paste")
			(net "P1V8_PEX")
		)
	)
	(footprint ""
		(layer "F.Cu")
		(at 459.067916 -277.91537 180)
		(property "Reference" "U95"
			(at -2.934462 -5.574792 0)
			(unlocked yes)
			(layer "F.SilkS")
			(effects
				(font
					(size 0.7874 0.5842)
					(thickness 0.1524)
				)
			)
		)
		(property "Value" ""
			(at 0 0 180)
			(layer "F.Fab")
			(effects
				(font
					(size 1.27 1.27)
				)
			)
		)
		(duplicate_pad_numbers_are_jumpers no)
		(fp_line
			(start 1.500124 1.500124)
			(end 1.004062 1.500124)
			(stroke
				(width 0.1524)
				(type default)
			)
			(layer "F.SilkS")
		)
		(fp_line
			(start 1.500124 1.004062)
			(end 1.500124 1.500124)
			(stroke
				(width 0.1524)
				(type default)
			)
			(layer "F.SilkS")
		)
		(fp_line
			(start 1.500124 -1.500124)
			(end 1.500124 -1.004062)
			(stroke
				(width 0.1524)
				(type default)
			)
			(layer "F.SilkS")
		)
		(fp_line
			(start 1.004062 -1.500124)
			(end 1.500124 -1.500124)
			(stroke
				(width 0.1524)
				(type default)
			)
			(layer "F.SilkS")
		)
		(fp_line
			(start -1.004062 1.500124)
			(end -1.500124 1.500124)
			(stroke
				(width 0.1524)
				(type default)
			)
			(layer "F.SilkS")
		)
		(fp_line
			(start -1.500124 1.500124)
			(end -1.500124 1.004062)
			(stroke
				(width 0.1524)
				(type default)
			)
			(layer "F.SilkS")
		)
		(fp_line
			(start -1.500124 -1.004062)
			(end -1.500124 -1.500124)
			(stroke
				(width 0.1524)
				(type default)
			)
			(layer "F.SilkS")
		)
		(fp_line
			(start -1.500124 -1.500124)
			(end -1.004062 -1.500124)
			(stroke
				(width 0.1524)
				(type default)
			)
			(layer "F.SilkS")
		)
		(fp_poly
			(pts
				(xy -1.308608 -2.198116) (xy -2.324608 -2.198116) (xy -1.816608 -1.182116)
			)
			(stroke
				(width 0)
				(type default)
			)
			(fill yes)
			(layer "F.SilkS")
		)
		(fp_line
			(start 1.500124 1.500124)
			(end -1.500124 1.500124)
			(stroke
				(width 0.1)
				(type default)
			)
			(layer "F.Fab")
		)
		(fp_line
			(start 1.500124 -1.500124)
			(end 1.500124 1.500124)
			(stroke
				(width 0.1)
				(type default)
			)
			(layer "F.Fab")
		)
		(fp_line
			(start -1.500124 1.500124)
			(end -1.500124 -1.500124)
			(stroke
				(width 0.1)
				(type default)
			)
			(layer "F.Fab")
		)
		(fp_line
			(start -1.500124 -1.500124)
			(end 1.500124 -1.500124)
			(stroke
				(width 0.1)
				(type default)
			)
			(layer "F.Fab")
		)
		(fp_poly
			(pts
				(xy -2.847848 -1.258062) (xy -2.847848 -0.242062) (xy -1.831848 -0.750062)
			)
			(stroke
				(width 0)
				(type default)
			)
			(fill yes)
			(layer "F.Fab")
		)
		(pad "1" smd rect
			(at -1.400048 -0.750062 90)
			(size 0.2286 0.6096)
			(layers "F.Cu" "F.Mask" "F.Paste")
			(net "PEX3_P1V25_ADC_A1")
		)
		(pad "2" smd rect
			(at -1.400048 -0.249936 90)
			(size 0.2286 0.6096)
			(layers "F.Cu" "F.Mask" "F.Paste")
			(net "PEX3_P1V25_ADC_A0")
		)
		(pad "3" smd rect
			(at -1.400048 0.249936 90)
			(size 0.2286 0.6096)
			(layers "F.Cu" "F.Mask" "F.Paste")
			(net "PEX3_P1V25_ADC_ALERT_N")
		)
		(pad "4" smd rect
			(at -1.400048 0.750062 90)
			(size 0.2286 0.6096)
			(layers "F.Cu" "F.Mask" "F.Paste")
			(net "SMB_PEX3_P1V25_ADC_SDA")
		)
		(pad "5" smd rect
			(at -0.750062 1.400048 180)
			(size 0.2286 0.6096)
			(layers "F.Cu" "F.Mask" "F.Paste")
			(net "SMB_PEX3_P1V25_ADC_SCL")
		)
		(pad "6" smd rect
			(at -0.249936 1.400048 180)
			(size 0.2286 0.6096)
			(layers "F.Cu" "F.Mask" "F.Paste")
			(net "Net_8600")
		)
		(pad "7" smd rect
			(at 0.249936 1.400048 180)
			(size 0.2286 0.6096)
			(layers "F.Cu" "F.Mask" "F.Paste")
			(net "Net_8599")
		)
		(pad "8" smd rect
			(at 0.750062 1.400048 180)
			(size 0.2286 0.6096)
			(layers "F.Cu" "F.Mask" "F.Paste")
			(net "Net_8598")
		)
		(pad "9" smd rect
			(at 1.400048 0.750062 90)
			(size 0.2286 0.6096)
			(layers "F.Cu" "F.Mask" "F.Paste")
			(net "P3V3_AUX")
		)
		(pad "10" smd rect
			(at 1.400048 0.249936 90)
			(size 0.2286 0.6096)
			(layers "F.Cu" "F.Mask" "F.Paste")
			(net "GND")
		)
		(pad "11" smd rect
			(at 1.400048 -0.249936 90)
			(size 0.2286 0.6096)
			(layers "F.Cu" "F.Mask" "F.Paste")
			(net "P1V25_PEX3_R")
		)
		(pad "12" smd rect
			(at 1.400048 -0.750062 90)
			(size 0.2286 0.6096)
			(layers "F.Cu" "F.Mask" "F.Paste")
			(net "P12V_PEX3_P1V25_VIN_N")
		)
		(pad "13" smd rect
			(at 0.750062 -1.400048 180)
			(size 0.2286 0.6096)
			(layers "F.Cu" "F.Mask" "F.Paste")
			(net "P12V_PEX3_P1V25_VIN_P")
		)
		(pad "14" smd rect
			(at 0.249936 -1.400048 180)
			(size 0.2286 0.6096)
			(layers "F.Cu" "F.Mask" "F.Paste")
			(net "Net_8597")
		)
		(pad "15" smd rect
			(at -0.249936 -1.400048 180)
			(size 0.2286 0.6096)
			(layers "F.Cu" "F.Mask" "F.Paste")
			(net "Net_8596")
		)
		(pad "16" smd rect
			(at -0.750062 -1.400048 180)
			(size 0.2286 0.6096)
			(layers "F.Cu" "F.Mask" "F.Paste")
			(net "Net_8595")
		)
		(pad "TH" smd rect
			(at 0 0 180)
			(size 1.7018 1.7018)
			(layers "F.Cu" "F.Mask" "F.Paste")
			(net "GND")
		)
		(zone
			(layer "F.Cu")
			(hatch none 0.5)
			(connect_pads
				(clearance 0)
			)
			(min_thickness 0.25)
			(keepout
				(tracks not_allowed)
				(vias allowed)
				(pads allowed)
				(copperpour not_allowed)
				(footprints allowed)
			)
			(placement
				(enabled no)
				(sheetname "")
			)
			(fill
				(thermal_gap 0.5)
				(thermal_bridge_width 0.5)
				(island_removal_mode 0)
			)
			(polygon
				(pts
					(xy 460.112364 -277.88997) (xy 460.112364 -276.870922) (xy 458.023468 -276.870922) (xy 458.023468 -278.959818)
					(xy 460.112364 -278.959818) (xy 460.112364 -277.91537) (xy 459.969616 -277.91537) (xy 459.969616 -278.81707)
					(xy 458.166216 -278.81707) (xy 458.166216 -277.01367) (xy 459.969616 -277.01367) (xy 459.969616 -277.88997)
				)
			)
		)
	)
	(footprint ""
		(layer "F.Cu")
		(at 361.89031 -261.814564 180)
		(property "Reference" "R838"
			(at 0 0 180)
			(layer "F.SilkS")
			(hide yes)
			(effects
				(font
					(size 1.27 1.27)
				)
			)
		)
		(property "Value" ""
			(at 0 0 180)
			(layer "F.Fab")
			(effects
				(font
					(size 1.27 1.27)
				)
			)
		)
		(duplicate_pad_numbers_are_jumpers no)
		(fp_line
			(start 0.7874 0.4064)
			(end -0.7874 0.4064)
			(stroke
				(width 0.1524)
				(type default)
			)
			(layer "F.SilkS")
		)
		(fp_line
			(start 0.7874 -0.4064)
			(end 0.7874 0.4064)
			(stroke
				(width 0.1524)
				(type default)
			)
			(layer "F.SilkS")
		)
		(fp_line
			(start -0.7874 0.4064)
			(end -0.7874 -0.4064)
			(stroke
				(width 0.1524)
				(type default)
			)
			(layer "F.SilkS")
		)
		(fp_line
			(start -0.7874 -0.4064)
			(end 0.7874 -0.4064)
			(stroke
				(width 0.1524)
				(type default)
			)
			(layer "F.SilkS")
		)
		(fp_line
			(start 0.67945 0.3048)
			(end 0.120396 0.3048)
			(stroke
				(width 0.1)
				(type default)
			)
			(layer "F.Fab")
		)
		(fp_line
			(start 0.67945 -0.3048)
			(end 0.67945 0.3048)
			(stroke
				(width 0.1)
				(type default)
			)
			(layer "F.Fab")
		)
		(fp_line
			(start 0.12065 -0.2794)
			(end 0.12065 -0.3048)
			(stroke
				(width 0.1)
				(type default)
			)
			(layer "F.Fab")
		)
		(fp_line
			(start 0.12065 -0.3048)
			(end 0.67945 -0.3048)
			(stroke
				(width 0.1)
				(type default)
			)
			(layer "F.Fab")
		)
		(fp_line
			(start 0.120396 0.3048)
			(end 0.120396 0.2794)
			(stroke
				(width 0.1)
				(type default)
			)
			(layer "F.Fab")
		)
		(fp_line
			(start 0.120396 0.2794)
			(end -0.12065 0.2794)
			(stroke
				(width 0.1)
				(type default)
			)
			(layer "F.Fab")
		)
		(fp_line
			(start -0.12065 0.3048)
			(end -0.67945 0.3048)
			(stroke
				(width 0.1)
				(type default)
			)
			(layer "F.Fab")
		)
		(fp_line
			(start -0.12065 0.2794)
			(end -0.12065 0.3048)
			(stroke
				(width 0.1)
				(type default)
			)
			(layer "F.Fab")
		)
		(fp_line
			(start -0.12065 -0.2794)
			(end 0.12065 -0.2794)
			(stroke
				(width 0.1)
				(type default)
			)
			(layer "F.Fab")
		)
		(fp_line
			(start -0.12065 -0.305054)
			(end -0.12065 -0.2794)
			(stroke
				(width 0.1)
				(type default)
			)
			(layer "F.Fab")
		)
		(fp_line
			(start -0.67945 0.3048)
			(end -0.67945 -0.305054)
			(stroke
				(width 0.1)
				(type default)
			)
			(layer "F.Fab")
		)
		(fp_line
			(start -0.67945 -0.305054)
			(end -0.12065 -0.305054)
			(stroke
				(width 0.1)
				(type default)
			)
			(layer "F.Fab")
		)
		(pad "1" smd circle
			(at -0.40005 0 180)
			(size 0 0)
			(layers "F.Cu" "F.Mask" "F.Paste")
			(net "PWR_EN_PEX_R")
		)
		(pad "2" smd circle
			(at 0.40005 0 180)
			(size 0 0)
			(layers "F.Cu" "F.Mask" "F.Paste")
			(net "FM_P0V8_PEX3_EN_R")
		)
	)
	(footprint ""
		(layer "F.Cu")
		(at 314.861448 -136.20115 180)
		(property "Reference" "C439"
			(at 0 0 180)
			(layer "F.SilkS")
			(hide yes)
			(effects
				(font
					(size 1.27 1.27)
				)
			)
		)
		(property "Value" ""
			(at 0 0 180)
			(layer "F.Fab")
			(effects
				(font
					(size 1.27 1.27)
				)
			)
		)
		(duplicate_pad_numbers_are_jumpers no)
		(fp_line
			(start 0.299974 0.150114)
			(end -0.299974 0.150114)
			(stroke
				(width 0.1)
				(type default)
			)
			(layer "F.Fab")
		)
		(fp_line
			(start 0.299974 -0.150114)
			(end 0.299974 0.150114)
			(stroke
				(width 0.1)
				(type default)
			)
			(layer "F.Fab")
		)
		(fp_line
			(start -0.299974 0.150114)
			(end -0.299974 -0.150114)
			(stroke
				(width 0.1)
				(type default)
			)
			(layer "F.Fab")
		)
		(fp_line
			(start -0.299974 -0.150114)
			(end 0.299974 -0.150114)
			(stroke
				(width 0.1)
				(type default)
			)
			(layer "F.Fab")
		)
		(pad "1" smd rect
			(at -0.2667 0 180)
			(size 0.3048 0.381)
			(layers "F.Cu" "F.Mask" "F.Paste")
			(net "P5E_PEX2_STN0_TX_DP<7>")
		)
		(pad "2" smd rect
			(at 0.2667 0 180)
			(size 0.3048 0.381)
			(layers "F.Cu" "F.Mask" "F.Paste")
			(net "P5E_PEX2_STN0_TX_C_DP<7>")
		)
	)
	(footprint ""
		(layer "F.Cu")
		(at 451.36435 -29.079952 180)
		(property "Reference" "R6213"
			(at 0 0 180)
			(layer "F.SilkS")
			(hide yes)
			(effects
				(font
					(size 1.27 1.27)
				)
			)
		)
		(property "Value" ""
			(at 0 0 180)
			(layer "F.Fab")
			(effects
				(font
					(size 1.27 1.27)
				)
			)
		)
		(duplicate_pad_numbers_are_jumpers no)
		(fp_line
			(start 0.7874 0.4064)
			(end -0.7874 0.4064)
			(stroke
				(width 0.1524)
				(type default)
			)
			(layer "F.SilkS")
		)
		(fp_line
			(start 0.7874 -0.4064)
			(end 0.7874 0.4064)
			(stroke
				(width 0.1524)
				(type default)
			)
			(layer "F.SilkS")
		)
		(fp_line
			(start -0.7874 0.4064)
			(end -0.7874 -0.4064)
			(stroke
				(width 0.1524)
				(type default)
			)
			(layer "F.SilkS")
		)
		(fp_line
			(start -0.7874 -0.4064)
			(end 0.7874 -0.4064)
			(stroke
				(width 0.1524)
				(type default)
			)
			(layer "F.SilkS")
		)
		(fp_line
			(start 0.67945 0.3048)
			(end 0.120396 0.3048)
			(stroke
				(width 0.1)
				(type default)
			)
			(layer "F.Fab")
		)
		(fp_line
			(start 0.67945 -0.3048)
			(end 0.67945 0.3048)
			(stroke
				(width 0.1)
				(type default)
			)
			(layer "F.Fab")
		)
		(fp_line
			(start 0.12065 -0.2794)
			(end 0.12065 -0.3048)
			(stroke
				(width 0.1)
				(type default)
			)
			(layer "F.Fab")
		)
		(fp_line
			(start 0.12065 -0.3048)
			(end 0.67945 -0.3048)
			(stroke
				(width 0.1)
				(type default)
			)
			(layer "F.Fab")
		)
		(fp_line
			(start 0.120396 0.3048)
			(end 0.120396 0.2794)
			(stroke
				(width 0.1)
				(type default)
			)
			(layer "F.Fab")
		)
		(fp_line
			(start 0.120396 0.2794)
			(end -0.12065 0.2794)
			(stroke
				(width 0.1)
				(type default)
			)
			(layer "F.Fab")
		)
		(fp_line
			(start -0.12065 0.3048)
			(end -0.67945 0.3048)
			(stroke
				(width 0.1)
				(type default)
			)
			(layer "F.Fab")
		)
		(fp_line
			(start -0.12065 0.2794)
			(end -0.12065 0.3048)
			(stroke
				(width 0.1)
				(type default)
			)
			(layer "F.Fab")
		)
		(fp_line
			(start -0.12065 -0.2794)
			(end 0.12065 -0.2794)
			(stroke
				(width 0.1)
				(type default)
			)
			(layer "F.Fab")
		)
		(fp_line
			(start -0.12065 -0.305054)
			(end -0.12065 -0.2794)
			(stroke
				(width 0.1)
				(type default)
			)
			(layer "F.Fab")
		)
		(fp_line
			(start -0.67945 0.3048)
			(end -0.67945 -0.305054)
			(stroke
				(width 0.1)
				(type default)
			)
			(layer "F.Fab")
		)
		(fp_line
			(start -0.67945 -0.305054)
			(end -0.12065 -0.305054)
			(stroke
				(width 0.1)
				(type default)
			)
			(layer "F.Fab")
		)
		(pad "1" smd circle
			(at -0.40005 0 180)
			(size 0 0)
			(layers "F.Cu" "F.Mask" "F.Paste")
			(net "GND")
		)
		(pad "2" smd circle
			(at 0.40005 0 180)
			(size 0 0)
			(layers "F.Cu" "F.Mask" "F.Paste")
			(net "SSD15_PWRDIS_R")
		)
	)
	(footprint ""
		(layer "F.Cu")
		(at 33.486344 -252.356874 -90)
		(property "Reference" "R1187"
			(at 0 0 270)
			(layer "F.SilkS")
			(hide yes)
			(effects
				(font
					(size 1.27 1.27)
				)
			)
		)
		(property "Value" ""
			(at 0 0 270)
			(layer "F.Fab")
			(effects
				(font
					(size 1.27 1.27)
				)
			)
		)
		(duplicate_pad_numbers_are_jumpers no)
		(fp_line
			(start -0.7874 0.4064)
			(end -0.7874 -0.4064)
			(stroke
				(width 0.1524)
				(type default)
			)
			(layer "F.SilkS")
		)
		(fp_line
			(start 0.7874 0.4064)
			(end -0.7874 0.4064)
			(stroke
				(width 0.1524)
				(type default)
			)
			(layer "F.SilkS")
		)
		(fp_line
			(start -0.7874 -0.4064)
			(end 0.7874 -0.4064)
			(stroke
				(width 0.1524)
				(type default)
			)
			(layer "F.SilkS")
		)
		(fp_line
			(start 0.7874 -0.4064)
			(end 0.7874 0.4064)
			(stroke
				(width 0.1524)
				(type default)
			)
			(layer "F.SilkS")
		)
		(fp_line
			(start -0.67945 0.3048)
			(end -0.67945 -0.305054)
			(stroke
				(width 0.1)
				(type default)
			)
			(layer "F.Fab")
		)
		(fp_line
			(start -0.12065 0.3048)
			(end -0.67945 0.3048)
			(stroke
				(width 0.1)
				(type default)
			)
			(layer "F.Fab")
		)
		(fp_line
			(start 0.120396 0.3048)
			(end 0.120396 0.2794)
			(stroke
				(width 0.1)
				(type default)
			)
			(layer "F.Fab")
		)
		(fp_line
			(start 0.67945 0.3048)
			(end 0.120396 0.3048)
			(stroke
				(width 0.1)
				(type default)
			)
			(layer "F.Fab")
		)
		(fp_line
			(start -0.12065 0.2794)
			(end -0.12065 0.3048)
			(stroke
				(width 0.1)
				(type default)
			)
			(layer "F.Fab")
		)
		(fp_line
			(start 0.120396 0.2794)
			(end -0.12065 0.2794)
			(stroke
				(width 0.1)
				(type default)
			)
			(layer "F.Fab")
		)
		(fp_line
			(start -0.12065 -0.2794)
			(end 0.12065 -0.2794)
			(stroke
				(width 0.1)
				(type default)
			)
			(layer "F.Fab")
		)
		(fp_line
			(start 0.12065 -0.2794)
			(end 0.12065 -0.3048)
			(stroke
				(width 0.1)
				(type default)
			)
			(layer "F.Fab")
		)
		(fp_line
			(start 0.12065 -0.3048)
			(end 0.67945 -0.3048)
			(stroke
				(width 0.1)
				(type default)
			)
			(layer "F.Fab")
		)
		(fp_line
			(start 0.67945 -0.3048)
			(end 0.67945 0.3048)
			(stroke
				(width 0.1)
				(type default)
			)
			(layer "F.Fab")
		)
		(fp_line
			(start -0.67945 -0.305054)
			(end -0.12065 -0.305054)
			(stroke
				(width 0.1)
				(type default)
			)
			(layer "F.Fab")
		)
		(fp_line
			(start -0.12065 -0.305054)
			(end -0.12065 -0.2794)
			(stroke
				(width 0.1)
				(type default)
			)
			(layer "F.Fab")
		)
		(pad "1" smd circle
			(at -0.40005 0 270)
			(size 0 0)
			(layers "F.Cu" "F.Mask" "F.Paste")
			(net "GND")
		)
		(pad "2" smd circle
			(at 0.40005 0 270)
			(size 0 0)
			(layers "F.Cu" "F.Mask" "F.Paste")
			(net "PEX0_DBG_MODE2")
		)
	)
	(footprint ""
		(layer "F.Cu")
		(at 230.749094 -173.67758 180)
		(property "Reference" "R3149"
			(at 0 0 180)
			(layer "F.SilkS")
			(hide yes)
			(effects
				(font
					(size 1.27 1.27)
				)
			)
		)
		(property "Value" ""
			(at 0 0 180)
			(layer "F.Fab")
			(effects
				(font
					(size 1.27 1.27)
				)
			)
		)
		(duplicate_pad_numbers_are_jumpers no)
		(fp_line
			(start 0.7874 0.4064)
			(end -0.7874 0.4064)
			(stroke
				(width 0.1524)
				(type default)
			)
			(layer "F.SilkS")
		)
		(fp_line
			(start 0.7874 -0.4064)
			(end 0.7874 0.4064)
			(stroke
				(width 0.1524)
				(type default)
			)
			(layer "F.SilkS")
		)
		(fp_line
			(start -0.7874 0.4064)
			(end -0.7874 -0.4064)
			(stroke
				(width 0.1524)
				(type default)
			)
			(layer "F.SilkS")
		)
		(fp_line
			(start -0.7874 -0.4064)
			(end 0.7874 -0.4064)
			(stroke
				(width 0.1524)
				(type default)
			)
			(layer "F.SilkS")
		)
		(fp_line
			(start 0.67945 0.3048)
			(end 0.120396 0.3048)
			(stroke
				(width 0.1)
				(type default)
			)
			(layer "F.Fab")
		)
		(fp_line
			(start 0.67945 -0.3048)
			(end 0.67945 0.3048)
			(stroke
				(width 0.1)
				(type default)
			)
			(layer "F.Fab")
		)
		(fp_line
			(start 0.12065 -0.2794)
			(end 0.12065 -0.3048)
			(stroke
				(width 0.1)
				(type default)
			)
			(layer "F.Fab")
		)
		(fp_line
			(start 0.12065 -0.3048)
			(end 0.67945 -0.3048)
			(stroke
				(width 0.1)
				(type default)
			)
			(layer "F.Fab")
		)
		(fp_line
			(start 0.120396 0.3048)
			(end 0.120396 0.2794)
			(stroke
				(width 0.1)
				(type default)
			)
			(layer "F.Fab")
		)
		(fp_line
			(start 0.120396 0.2794)
			(end -0.12065 0.2794)
			(stroke
				(width 0.1)
				(type default)
			)
			(layer "F.Fab")
		)
		(fp_line
			(start -0.12065 0.3048)
			(end -0.67945 0.3048)
			(stroke
				(width 0.1)
				(type default)
			)
			(layer "F.Fab")
		)
		(fp_line
			(start -0.12065 0.2794)
			(end -0.12065 0.3048)
			(stroke
				(width 0.1)
				(type default)
			)
			(layer "F.Fab")
		)
		(fp_line
			(start -0.12065 -0.2794)
			(end 0.12065 -0.2794)
			(stroke
				(width 0.1)
				(type default)
			)
			(layer "F.Fab")
		)
		(fp_line
			(start -0.12065 -0.305054)
			(end -0.12065 -0.2794)
			(stroke
				(width 0.1)
				(type default)
			)
			(layer "F.Fab")
		)
		(fp_line
			(start -0.67945 0.3048)
			(end -0.67945 -0.305054)
			(stroke
				(width 0.1)
				(type default)
			)
			(layer "F.Fab")
		)
		(fp_line
			(start -0.67945 -0.305054)
			(end -0.12065 -0.305054)
			(stroke
				(width 0.1)
				(type default)
			)
			(layer "F.Fab")
		)
		(pad "1" smd circle
			(at -0.40005 0 180)
			(size 0 0)
			(layers "F.Cu" "F.Mask" "F.Paste")
			(net "PWRGD_P1V2_AUX_DLY")
		)
		(pad "2" smd circle
			(at 0.40005 0 180)
			(size 0 0)
			(layers "F.Cu" "F.Mask" "F.Paste")
			(net "ADM1085_ENOUT")
		)
	)
	(footprint ""
		(layer "F.Cu")
		(at 393.546838 -38.49116 180)
		(property "Reference" "R6124"
			(at 0 0 180)
			(layer "F.SilkS")
			(hide yes)
			(effects
				(font
					(size 1.27 1.27)
				)
			)
		)
		(property "Value" ""
			(at 0 0 180)
			(layer "F.Fab")
			(effects
				(font
					(size 1.27 1.27)
				)
			)
		)
		(duplicate_pad_numbers_are_jumpers no)
		(fp_line
			(start 0.7874 0.4064)
			(end -0.7874 0.4064)
			(stroke
				(width 0.1524)
				(type default)
			)
			(layer "F.SilkS")
		)
		(fp_line
			(start 0.7874 -0.4064)
			(end 0.7874 0.4064)
			(stroke
				(width 0.1524)
				(type default)
			)
			(layer "F.SilkS")
		)
		(fp_line
			(start -0.7874 0.4064)
			(end -0.7874 -0.4064)
			(stroke
				(width 0.1524)
				(type default)
			)
			(layer "F.SilkS")
		)
		(fp_line
			(start -0.7874 -0.4064)
			(end 0.7874 -0.4064)
			(stroke
				(width 0.1524)
				(type default)
			)
			(layer "F.SilkS")
		)
		(fp_line
			(start 0.67945 0.3048)
			(end 0.120396 0.3048)
			(stroke
				(width 0.1)
				(type default)
			)
			(layer "F.Fab")
		)
		(fp_line
			(start 0.67945 -0.3048)
			(end 0.67945 0.3048)
			(stroke
				(width 0.1)
				(type default)
			)
			(layer "F.Fab")
		)
		(fp_line
			(start 0.12065 -0.2794)
			(end 0.12065 -0.3048)
			(stroke
				(width 0.1)
				(type default)
			)
			(layer "F.Fab")
		)
		(fp_line
			(start 0.12065 -0.3048)
			(end 0.67945 -0.3048)
			(stroke
				(width 0.1)
				(type default)
			)
			(layer "F.Fab")
		)
		(fp_line
			(start 0.120396 0.3048)
			(end 0.120396 0.2794)
			(stroke
				(width 0.1)
				(type default)
			)
			(layer "F.Fab")
		)
		(fp_line
			(start 0.120396 0.2794)
			(end -0.12065 0.2794)
			(stroke
				(width 0.1)
				(type default)
			)
			(layer "F.Fab")
		)
		(fp_line
			(start -0.12065 0.3048)
			(end -0.67945 0.3048)
			(stroke
				(width 0.1)
				(type default)
			)
			(layer "F.Fab")
		)
		(fp_line
			(start -0.12065 0.2794)
			(end -0.12065 0.3048)
			(stroke
				(width 0.1)
				(type default)
			)
			(layer "F.Fab")
		)
		(fp_line
			(start -0.12065 -0.2794)
			(end 0.12065 -0.2794)
			(stroke
				(width 0.1)
				(type default)
			)
			(layer "F.Fab")
		)
		(fp_line
			(start -0.12065 -0.305054)
			(end -0.12065 -0.2794)
			(stroke
				(width 0.1)
				(type default)
			)
			(layer "F.Fab")
		)
		(fp_line
			(start -0.67945 0.3048)
			(end -0.67945 -0.305054)
			(stroke
				(width 0.1)
				(type default)
			)
			(layer "F.Fab")
		)
		(fp_line
			(start -0.67945 -0.305054)
			(end -0.12065 -0.305054)
			(stroke
				(width 0.1)
				(type default)
			)
			(layer "F.Fab")
		)
		(pad "1" smd circle
			(at -0.40005 0 180)
			(size 0 0)
			(layers "F.Cu" "F.Mask" "F.Paste")
			(net "P3V3_SSD14_PG_G1")
		)
		(pad "2" smd circle
			(at 0.40005 0 180)
			(size 0 0)
			(layers "F.Cu" "F.Mask" "F.Paste")
			(net "GND")
		)
	)
	(footprint ""
		(layer "F.Cu")
		(at 204.591158 -80.611472)
		(property "Reference" "R4334"
			(at 0 0 0)
			(layer "F.SilkS")
			(hide yes)
			(effects
				(font
					(size 1.27 1.27)
				)
			)
		)
		(property "Value" ""
			(at 0 0 0)
			(layer "F.Fab")
			(effects
				(font
					(size 1.27 1.27)
				)
			)
		)
		(duplicate_pad_numbers_are_jumpers no)
		(fp_line
			(start -0.7874 -0.4064)
			(end 0.7874 -0.4064)
			(stroke
				(width 0.1524)
				(type default)
			)
			(layer "F.SilkS")
		)
		(fp_line
			(start -0.7874 0.4064)
			(end -0.7874 -0.4064)
			(stroke
				(width 0.1524)
				(type default)
			)
			(layer "F.SilkS")
		)
		(fp_line
			(start 0.7874 -0.4064)
			(end 0.7874 0.4064)
			(stroke
				(width 0.1524)
				(type default)
			)
			(layer "F.SilkS")
		)
		(fp_line
			(start 0.7874 0.4064)
			(end -0.7874 0.4064)
			(stroke
				(width 0.1524)
				(type default)
			)
			(layer "F.SilkS")
		)
		(fp_line
			(start -0.67945 -0.305054)
			(end -0.12065 -0.305054)
			(stroke
				(width 0.1)
				(type default)
			)
			(layer "F.Fab")
		)
		(fp_line
			(start -0.67945 0.3048)
			(end -0.67945 -0.305054)
			(stroke
				(width 0.1)
				(type default)
			)
			(layer "F.Fab")
		)
		(fp_line
			(start -0.12065 -0.305054)
			(end -0.12065 -0.2794)
			(stroke
				(width 0.1)
				(type default)
			)
			(layer "F.Fab")
		)
		(fp_line
			(start -0.12065 -0.2794)
			(end 0.12065 -0.2794)
			(stroke
				(width 0.1)
				(type default)
			)
			(layer "F.Fab")
		)
		(fp_line
			(start -0.12065 0.2794)
			(end -0.12065 0.3048)
			(stroke
				(width 0.1)
				(type default)
			)
			(layer "F.Fab")
		)
		(fp_line
			(start -0.12065 0.3048)
			(end -0.67945 0.3048)
			(stroke
				(width 0.1)
				(type default)
			)
			(layer "F.Fab")
		)
		(fp_line
			(start 0.120396 0.2794)
			(end -0.12065 0.2794)
			(stroke
				(width 0.1)
				(type default)
			)
			(layer "F.Fab")
		)
		(fp_line
			(start 0.120396 0.3048)
			(end 0.120396 0.2794)
			(stroke
				(width 0.1)
				(type default)
			)
			(layer "F.Fab")
		)
		(fp_line
			(start 0.12065 -0.3048)
			(end 0.67945 -0.3048)
			(stroke
				(width 0.1)
				(type default)
			)
			(layer "F.Fab")
		)
		(fp_line
			(start 0.12065 -0.2794)
			(end 0.12065 -0.3048)
			(stroke
				(width 0.1)
				(type default)
			)
			(layer "F.Fab")
		)
		(fp_line
			(start 0.67945 -0.3048)
			(end 0.67945 0.3048)
			(stroke
				(width 0.1)
				(type default)
			)
			(layer "F.Fab")
		)
		(fp_line
			(start 0.67945 0.3048)
			(end 0.120396 0.3048)
			(stroke
				(width 0.1)
				(type default)
			)
			(layer "F.Fab")
		)
		(pad "1" smd circle
			(at -0.40005 0)
			(size 0 0)
			(layers "F.Cu" "F.Mask" "F.Paste")
			(net "P3V3_AUX")
		)
		(pad "2" smd circle
			(at 0.40005 0)
			(size 0 0)
			(layers "F.Cu" "F.Mask" "F.Paste")
			(net "SSD4_LED_R")
		)
	)
	(footprint ""
		(layer "F.Cu")
		(at 247.359678 -152.71115 -90)
		(property "Reference" "R731"
			(at 0 0 270)
			(layer "F.SilkS")
			(hide yes)
			(effects
				(font
					(size 1.27 1.27)
				)
			)
		)
		(property "Value" ""
			(at 0 0 270)
			(layer "F.Fab")
			(effects
				(font
					(size 1.27 1.27)
				)
			)
		)
		(duplicate_pad_numbers_are_jumpers no)
		(fp_line
			(start -0.7874 0.4064)
			(end -0.7874 -0.4064)
			(stroke
				(width 0.1524)
				(type default)
			)
			(layer "F.SilkS")
		)
		(fp_line
			(start 0.7874 0.4064)
			(end -0.7874 0.4064)
			(stroke
				(width 0.1524)
				(type default)
			)
			(layer "F.SilkS")
		)
		(fp_line
			(start -0.7874 -0.4064)
			(end 0.7874 -0.4064)
			(stroke
				(width 0.1524)
				(type default)
			)
			(layer "F.SilkS")
		)
		(fp_line
			(start 0.7874 -0.4064)
			(end 0.7874 0.4064)
			(stroke
				(width 0.1524)
				(type default)
			)
			(layer "F.SilkS")
		)
		(fp_line
			(start -0.67945 0.3048)
			(end -0.67945 -0.305054)
			(stroke
				(width 0.1)
				(type default)
			)
			(layer "F.Fab")
		)
		(fp_line
			(start -0.12065 0.3048)
			(end -0.67945 0.3048)
			(stroke
				(width 0.1)
				(type default)
			)
			(layer "F.Fab")
		)
		(fp_line
			(start 0.120396 0.3048)
			(end 0.120396 0.2794)
			(stroke
				(width 0.1)
				(type default)
			)
			(layer "F.Fab")
		)
		(fp_line
			(start 0.67945 0.3048)
			(end 0.120396 0.3048)
			(stroke
				(width 0.1)
				(type default)
			)
			(layer "F.Fab")
		)
		(fp_line
			(start -0.12065 0.2794)
			(end -0.12065 0.3048)
			(stroke
				(width 0.1)
				(type default)
			)
			(layer "F.Fab")
		)
		(fp_line
			(start 0.120396 0.2794)
			(end -0.12065 0.2794)
			(stroke
				(width 0.1)
				(type default)
			)
			(layer "F.Fab")
		)
		(fp_line
			(start -0.12065 -0.2794)
			(end 0.12065 -0.2794)
			(stroke
				(width 0.1)
				(type default)
			)
			(layer "F.Fab")
		)
		(fp_line
			(start 0.12065 -0.2794)
			(end 0.12065 -0.3048)
			(stroke
				(width 0.1)
				(type default)
			)
			(layer "F.Fab")
		)
		(fp_line
			(start 0.12065 -0.3048)
			(end 0.67945 -0.3048)
			(stroke
				(width 0.1)
				(type default)
			)
			(layer "F.Fab")
		)
		(fp_line
			(start 0.67945 -0.3048)
			(end 0.67945 0.3048)
			(stroke
				(width 0.1)
				(type default)
			)
			(layer "F.Fab")
		)
		(fp_line
			(start -0.67945 -0.305054)
			(end -0.12065 -0.305054)
			(stroke
				(width 0.1)
				(type default)
			)
			(layer "F.Fab")
		)
		(fp_line
			(start -0.12065 -0.305054)
			(end -0.12065 -0.2794)
			(stroke
				(width 0.1)
				(type default)
			)
			(layer "F.Fab")
		)
		(pad "1" smd circle
			(at -0.40005 0 270)
			(size 0 0)
			(layers "F.Cu" "F.Mask" "F.Paste")
			(net "SMB_BIC_I2C6_MUX_NIC_ADC_R_SCL")
		)
		(pad "2" smd circle
			(at 0.40005 0 270)
			(size 0 0)
			(layers "F.Cu" "F.Mask" "F.Paste")
			(net "SMB_NIC4_ADC_SCL")
		)
	)
	(footprint ""
		(layer "F.Cu")
		(at 236.004608 -77.53477 180)
		(property "Reference" "R1004"
			(at 0 0 180)
			(layer "F.SilkS")
			(hide yes)
			(effects
				(font
					(size 1.27 1.27)
				)
			)
		)
		(property "Value" ""
			(at 0 0 180)
			(layer "F.Fab")
			(effects
				(font
					(size 1.27 1.27)
				)
			)
		)
		(duplicate_pad_numbers_are_jumpers no)
		(fp_line
			(start 0.7874 0.4064)
			(end -0.7874 0.4064)
			(stroke
				(width 0.1524)
				(type default)
			)
			(layer "F.SilkS")
		)
		(fp_line
			(start 0.7874 -0.4064)
			(end 0.7874 0.4064)
			(stroke
				(width 0.1524)
				(type default)
			)
			(layer "F.SilkS")
		)
		(fp_line
			(start -0.7874 0.4064)
			(end -0.7874 -0.4064)
			(stroke
				(width 0.1524)
				(type default)
			)
			(layer "F.SilkS")
		)
		(fp_line
			(start -0.7874 -0.4064)
			(end 0.7874 -0.4064)
			(stroke
				(width 0.1524)
				(type default)
			)
			(layer "F.SilkS")
		)
		(fp_line
			(start 0.67945 0.3048)
			(end 0.120396 0.3048)
			(stroke
				(width 0.1)
				(type default)
			)
			(layer "F.Fab")
		)
		(fp_line
			(start 0.67945 -0.3048)
			(end 0.67945 0.3048)
			(stroke
				(width 0.1)
				(type default)
			)
			(layer "F.Fab")
		)
		(fp_line
			(start 0.12065 -0.2794)
			(end 0.12065 -0.3048)
			(stroke
				(width 0.1)
				(type default)
			)
			(layer "F.Fab")
		)
		(fp_line
			(start 0.12065 -0.3048)
			(end 0.67945 -0.3048)
			(stroke
				(width 0.1)
				(type default)
			)
			(layer "F.Fab")
		)
		(fp_line
			(start 0.120396 0.3048)
			(end 0.120396 0.2794)
			(stroke
				(width 0.1)
				(type default)
			)
			(layer "F.Fab")
		)
		(fp_line
			(start 0.120396 0.2794)
			(end -0.12065 0.2794)
			(stroke
				(width 0.1)
				(type default)
			)
			(layer "F.Fab")
		)
		(fp_line
			(start -0.12065 0.3048)
			(end -0.67945 0.3048)
			(stroke
				(width 0.1)
				(type default)
			)
			(layer "F.Fab")
		)
		(fp_line
			(start -0.12065 0.2794)
			(end -0.12065 0.3048)
			(stroke
				(width 0.1)
				(type default)
			)
			(layer "F.Fab")
		)
		(fp_line
			(start -0.12065 -0.2794)
			(end 0.12065 -0.2794)
			(stroke
				(width 0.1)
				(type default)
			)
			(layer "F.Fab")
		)
		(fp_line
			(start -0.12065 -0.305054)
			(end -0.12065 -0.2794)
			(stroke
				(width 0.1)
				(type default)
			)
			(layer "F.Fab")
		)
		(fp_line
			(start -0.67945 0.3048)
			(end -0.67945 -0.305054)
			(stroke
				(width 0.1)
				(type default)
			)
			(layer "F.Fab")
		)
		(fp_line
			(start -0.67945 -0.305054)
			(end -0.12065 -0.305054)
			(stroke
				(width 0.1)
				(type default)
			)
			(layer "F.Fab")
		)
		(pad "1" smd circle
			(at -0.40005 0 180)
			(size 0 0)
			(layers "F.Cu" "F.Mask" "F.Paste")
			(net "P3V3_AUX")
		)
		(pad "2" smd circle
			(at 0.40005 0 180)
			(size 0 0)
			(layers "F.Cu" "F.Mask" "F.Paste")
			(net "PWRGD_P3V3_AUX_MUX_N")
		)
	)
	(footprint ""
		(layer "F.Cu")
		(at 238.124746 -119.111268)
		(property "Reference" "PR6902"
			(at 0 0 0)
			(layer "F.SilkS")
			(hide yes)
			(effects
				(font
					(size 1.27 1.27)
				)
			)
		)
		(property "Value" ""
			(at 0 0 0)
			(layer "F.Fab")
			(effects
				(font
					(size 1.27 1.27)
				)
			)
		)
		(duplicate_pad_numbers_are_jumpers no)
		(fp_line
			(start -0.7874 -0.4064)
			(end 0.7874 -0.4064)
			(stroke
				(width 0.1524)
				(type default)
			)
			(layer "F.SilkS")
		)
		(fp_line
			(start -0.7874 0.4064)
			(end -0.7874 -0.4064)
			(stroke
				(width 0.1524)
				(type default)
			)
			(layer "F.SilkS")
		)
		(fp_line
			(start 0.7874 -0.4064)
			(end 0.7874 0.4064)
			(stroke
				(width 0.1524)
				(type default)
			)
			(layer "F.SilkS")
		)
		(fp_line
			(start 0.7874 0.4064)
			(end -0.7874 0.4064)
			(stroke
				(width 0.1524)
				(type default)
			)
			(layer "F.SilkS")
		)
		(fp_line
			(start -0.67945 -0.305054)
			(end -0.12065 -0.305054)
			(stroke
				(width 0.1)
				(type default)
			)
			(layer "F.Fab")
		)
		(fp_line
			(start -0.67945 0.3048)
			(end -0.67945 -0.305054)
			(stroke
				(width 0.1)
				(type default)
			)
			(layer "F.Fab")
		)
		(fp_line
			(start -0.12065 -0.305054)
			(end -0.12065 -0.2794)
			(stroke
				(width 0.1)
				(type default)
			)
			(layer "F.Fab")
		)
		(fp_line
			(start -0.12065 -0.2794)
			(end 0.12065 -0.2794)
			(stroke
				(width 0.1)
				(type default)
			)
			(layer "F.Fab")
		)
		(fp_line
			(start -0.12065 0.2794)
			(end -0.12065 0.3048)
			(stroke
				(width 0.1)
				(type default)
			)
			(layer "F.Fab")
		)
		(fp_line
			(start -0.12065 0.3048)
			(end -0.67945 0.3048)
			(stroke
				(width 0.1)
				(type default)
			)
			(layer "F.Fab")
		)
		(fp_line
			(start 0.120396 0.2794)
			(end -0.12065 0.2794)
			(stroke
				(width 0.1)
				(type default)
			)
			(layer "F.Fab")
		)
		(fp_line
			(start 0.120396 0.3048)
			(end 0.120396 0.2794)
			(stroke
				(width 0.1)
				(type default)
			)
			(layer "F.Fab")
		)
		(fp_line
			(start 0.12065 -0.3048)
			(end 0.67945 -0.3048)
			(stroke
				(width 0.1)
				(type default)
			)
			(layer "F.Fab")
		)
		(fp_line
			(start 0.12065 -0.2794)
			(end 0.12065 -0.3048)
			(stroke
				(width 0.1)
				(type default)
			)
			(layer "F.Fab")
		)
		(fp_line
			(start 0.67945 -0.3048)
			(end 0.67945 0.3048)
			(stroke
				(width 0.1)
				(type default)
			)
			(layer "F.Fab")
		)
		(fp_line
			(start 0.67945 0.3048)
			(end 0.120396 0.3048)
			(stroke
				(width 0.1)
				(type default)
			)
			(layer "F.Fab")
		)
		(pad "1" smd circle
			(at -0.40005 0)
			(size 0 0)
			(layers "F.Cu" "F.Mask" "F.Paste")
			(net "P12V_NIC3_CO_IMON_VR")
		)
		(pad "2" smd circle
			(at 0.40005 0)
			(size 0 0)
			(layers "F.Cu" "F.Mask" "F.Paste")
			(net "GND")
		)
	)
	(footprint ""
		(layer "F.Cu")
		(at 88.288114 -100.459032 90)
		(property "Reference" "R700"
			(at 0 0 90)
			(layer "F.SilkS")
			(hide yes)
			(effects
				(font
					(size 1.27 1.27)
				)
			)
		)
		(property "Value" ""
			(at 0 0 90)
			(layer "F.Fab")
			(effects
				(font
					(size 1.27 1.27)
				)
			)
		)
		(duplicate_pad_numbers_are_jumpers no)
		(fp_line
			(start 0.7874 -0.4064)
			(end 0.7874 0.4064)
			(stroke
				(width 0.1524)
				(type default)
			)
			(layer "F.SilkS")
		)
		(fp_line
			(start -0.7874 -0.4064)
			(end 0.7874 -0.4064)
			(stroke
				(width 0.1524)
				(type default)
			)
			(layer "F.SilkS")
		)
		(fp_line
			(start 0.7874 0.4064)
			(end -0.7874 0.4064)
			(stroke
				(width 0.1524)
				(type default)
			)
			(layer "F.SilkS")
		)
		(fp_line
			(start -0.7874 0.4064)
			(end -0.7874 -0.4064)
			(stroke
				(width 0.1524)
				(type default)
			)
			(layer "F.SilkS")
		)
		(fp_line
			(start -0.12065 -0.305054)
			(end -0.12065 -0.2794)
			(stroke
				(width 0.1)
				(type default)
			)
			(layer "F.Fab")
		)
		(fp_line
			(start -0.67945 -0.305054)
			(end -0.12065 -0.305054)
			(stroke
				(width 0.1)
				(type default)
			)
			(layer "F.Fab")
		)
		(fp_line
			(start 0.67945 -0.3048)
			(end 0.67945 0.3048)
			(stroke
				(width 0.1)
				(type default)
			)
			(layer "F.Fab")
		)
		(fp_line
			(start 0.12065 -0.3048)
			(end 0.67945 -0.3048)
			(stroke
				(width 0.1)
				(type default)
			)
			(layer "F.Fab")
		)
		(fp_line
			(start 0.12065 -0.2794)
			(end 0.12065 -0.3048)
			(stroke
				(width 0.1)
				(type default)
			)
			(layer "F.Fab")
		)
		(fp_line
			(start -0.12065 -0.2794)
			(end 0.12065 -0.2794)
			(stroke
				(width 0.1)
				(type default)
			)
			(layer "F.Fab")
		)
		(fp_line
			(start 0.120396 0.2794)
			(end -0.12065 0.2794)
			(stroke
				(width 0.1)
				(type default)
			)
			(layer "F.Fab")
		)
		(fp_line
			(start -0.12065 0.2794)
			(end -0.12065 0.3048)
			(stroke
				(width 0.1)
				(type default)
			)
			(layer "F.Fab")
		)
		(fp_line
			(start 0.67945 0.3048)
			(end 0.120396 0.3048)
			(stroke
				(width 0.1)
				(type default)
			)
			(layer "F.Fab")
		)
		(fp_line
			(start 0.120396 0.3048)
			(end 0.120396 0.2794)
			(stroke
				(width 0.1)
				(type default)
			)
			(layer "F.Fab")
		)
		(fp_line
			(start -0.12065 0.3048)
			(end -0.67945 0.3048)
			(stroke
				(width 0.1)
				(type default)
			)
			(layer "F.Fab")
		)
		(fp_line
			(start -0.67945 0.3048)
			(end -0.67945 -0.305054)
			(stroke
				(width 0.1)
				(type default)
			)
			(layer "F.Fab")
		)
		(pad "1" smd circle
			(at -0.40005 0 90)
			(size 0 0)
			(layers "F.Cu" "F.Mask" "F.Paste")
			(net "P12V_NIC1_R")
		)
		(pad "2" smd circle
			(at 0.40005 0 90)
			(size 0 0)
			(layers "F.Cu" "F.Mask" "F.Paste")
			(net "P12V_NIC1_VIN_P")
		)
	)
	(footprint ""
		(layer "F.Cu")
		(at 144.389856 -192.144396 -90)
		(property "Reference" "R6673"
			(at 0 0 270)
			(layer "F.SilkS")
			(hide yes)
			(effects
				(font
					(size 1.27 1.27)
				)
			)
		)
		(property "Value" ""
			(at 0 0 270)
			(layer "F.Fab")
			(effects
				(font
					(size 1.27 1.27)
				)
			)
		)
		(duplicate_pad_numbers_are_jumpers no)
		(fp_line
			(start -0.7874 0.4064)
			(end -0.7874 -0.4064)
			(stroke
				(width 0.1524)
				(type default)
			)
			(layer "F.SilkS")
		)
		(fp_line
			(start 0.7874 0.4064)
			(end -0.7874 0.4064)
			(stroke
				(width 0.1524)
				(type default)
			)
			(layer "F.SilkS")
		)
		(fp_line
			(start -0.7874 -0.4064)
			(end 0.7874 -0.4064)
			(stroke
				(width 0.1524)
				(type default)
			)
			(layer "F.SilkS")
		)
		(fp_line
			(start 0.7874 -0.4064)
			(end 0.7874 0.4064)
			(stroke
				(width 0.1524)
				(type default)
			)
			(layer "F.SilkS")
		)
		(fp_line
			(start -0.67945 0.3048)
			(end -0.67945 -0.305054)
			(stroke
				(width 0.1)
				(type default)
			)
			(layer "F.Fab")
		)
		(fp_line
			(start -0.12065 0.3048)
			(end -0.67945 0.3048)
			(stroke
				(width 0.1)
				(type default)
			)
			(layer "F.Fab")
		)
		(fp_line
			(start 0.120396 0.3048)
			(end 0.120396 0.2794)
			(stroke
				(width 0.1)
				(type default)
			)
			(layer "F.Fab")
		)
		(fp_line
			(start 0.67945 0.3048)
			(end 0.120396 0.3048)
			(stroke
				(width 0.1)
				(type default)
			)
			(layer "F.Fab")
		)
		(fp_line
			(start -0.12065 0.2794)
			(end -0.12065 0.3048)
			(stroke
				(width 0.1)
				(type default)
			)
			(layer "F.Fab")
		)
		(fp_line
			(start 0.120396 0.2794)
			(end -0.12065 0.2794)
			(stroke
				(width 0.1)
				(type default)
			)
			(layer "F.Fab")
		)
		(fp_line
			(start -0.12065 -0.2794)
			(end 0.12065 -0.2794)
			(stroke
				(width 0.1)
				(type default)
			)
			(layer "F.Fab")
		)
		(fp_line
			(start 0.12065 -0.2794)
			(end 0.12065 -0.3048)
			(stroke
				(width 0.1)
				(type default)
			)
			(layer "F.Fab")
		)
		(fp_line
			(start 0.12065 -0.3048)
			(end 0.67945 -0.3048)
			(stroke
				(width 0.1)
				(type default)
			)
			(layer "F.Fab")
		)
		(fp_line
			(start 0.67945 -0.3048)
			(end 0.67945 0.3048)
			(stroke
				(width 0.1)
				(type default)
			)
			(layer "F.Fab")
		)
		(fp_line
			(start -0.67945 -0.305054)
			(end -0.12065 -0.305054)
			(stroke
				(width 0.1)
				(type default)
			)
			(layer "F.Fab")
		)
		(fp_line
			(start -0.12065 -0.305054)
			(end -0.12065 -0.2794)
			(stroke
				(width 0.1)
				(type default)
			)
			(layer "F.Fab")
		)
		(pad "1" smd circle
			(at -0.40005 0 270)
			(size 0 0)
			(layers "F.Cu" "F.Mask" "F.Paste")
			(net "NIC4_CLK_EN_BUF_R_N")
		)
		(pad "2" smd circle
			(at 0.40005 0 270)
			(size 0 0)
			(layers "F.Cu" "F.Mask" "F.Paste")
			(net "P3V3")
		)
	)
	(footprint ""
		(layer "F.Cu")
		(at 284.659324 -22.955504 90)
		(property "Reference" "R1700"
			(at 0 0 90)
			(layer "F.SilkS")
			(hide yes)
			(effects
				(font
					(size 1.27 1.27)
				)
			)
		)
		(property "Value" ""
			(at 0 0 90)
			(layer "F.Fab")
			(effects
				(font
					(size 1.27 1.27)
				)
			)
		)
		(duplicate_pad_numbers_are_jumpers no)
		(fp_line
			(start 0.7874 -0.4064)
			(end 0.7874 0.4064)
			(stroke
				(width 0.1524)
				(type default)
			)
			(layer "F.SilkS")
		)
		(fp_line
			(start -0.7874 -0.4064)
			(end 0.7874 -0.4064)
			(stroke
				(width 0.1524)
				(type default)
			)
			(layer "F.SilkS")
		)
		(fp_line
			(start 0.7874 0.4064)
			(end -0.7874 0.4064)
			(stroke
				(width 0.1524)
				(type default)
			)
			(layer "F.SilkS")
		)
		(fp_line
			(start -0.7874 0.4064)
			(end -0.7874 -0.4064)
			(stroke
				(width 0.1524)
				(type default)
			)
			(layer "F.SilkS")
		)
		(fp_line
			(start -0.12065 -0.305054)
			(end -0.12065 -0.2794)
			(stroke
				(width 0.1)
				(type default)
			)
			(layer "F.Fab")
		)
		(fp_line
			(start -0.67945 -0.305054)
			(end -0.12065 -0.305054)
			(stroke
				(width 0.1)
				(type default)
			)
			(layer "F.Fab")
		)
		(fp_line
			(start 0.67945 -0.3048)
			(end 0.67945 0.3048)
			(stroke
				(width 0.1)
				(type default)
			)
			(layer "F.Fab")
		)
		(fp_line
			(start 0.12065 -0.3048)
			(end 0.67945 -0.3048)
			(stroke
				(width 0.1)
				(type default)
			)
			(layer "F.Fab")
		)
		(fp_line
			(start 0.12065 -0.2794)
			(end 0.12065 -0.3048)
			(stroke
				(width 0.1)
				(type default)
			)
			(layer "F.Fab")
		)
		(fp_line
			(start -0.12065 -0.2794)
			(end 0.12065 -0.2794)
			(stroke
				(width 0.1)
				(type default)
			)
			(layer "F.Fab")
		)
		(fp_line
			(start 0.120396 0.2794)
			(end -0.12065 0.2794)
			(stroke
				(width 0.1)
				(type default)
			)
			(layer "F.Fab")
		)
		(fp_line
			(start -0.12065 0.2794)
			(end -0.12065 0.3048)
			(stroke
				(width 0.1)
				(type default)
			)
			(layer "F.Fab")
		)
		(fp_line
			(start 0.67945 0.3048)
			(end 0.120396 0.3048)
			(stroke
				(width 0.1)
				(type default)
			)
			(layer "F.Fab")
		)
		(fp_line
			(start 0.120396 0.3048)
			(end 0.120396 0.2794)
			(stroke
				(width 0.1)
				(type default)
			)
			(layer "F.Fab")
		)
		(fp_line
			(start -0.12065 0.3048)
			(end -0.67945 0.3048)
			(stroke
				(width 0.1)
				(type default)
			)
			(layer "F.Fab")
		)
		(fp_line
			(start -0.67945 0.3048)
			(end -0.67945 -0.305054)
			(stroke
				(width 0.1)
				(type default)
			)
			(layer "F.Fab")
		)
		(pad "1" smd circle
			(at -0.40005 0 90)
			(size 0 0)
			(layers "F.Cu" "F.Mask" "F.Paste")
			(net "SMB_BIC_I2C9_MUX1_SSD9_R_SCL")
		)
		(pad "2" smd circle
			(at 0.40005 0 90)
			(size 0 0)
			(layers "F.Cu" "F.Mask" "F.Paste")
			(net "SMB_ISO_SSD9_SCL")
		)
	)
	(footprint ""
		(layer "F.Cu")
		(at 427.42612 -39.73576 -90)
		(property "Reference" "R5584"
			(at 0 0 270)
			(layer "F.SilkS")
			(hide yes)
			(effects
				(font
					(size 1.27 1.27)
				)
			)
		)
		(property "Value" ""
			(at 0 0 270)
			(layer "F.Fab")
			(effects
				(font
					(size 1.27 1.27)
				)
			)
		)
		(duplicate_pad_numbers_are_jumpers no)
		(fp_line
			(start -0.7874 0.4064)
			(end -0.7874 -0.4064)
			(stroke
				(width 0.1524)
				(type default)
			)
			(layer "F.SilkS")
		)
		(fp_line
			(start 0.7874 0.4064)
			(end -0.7874 0.4064)
			(stroke
				(width 0.1524)
				(type default)
			)
			(layer "F.SilkS")
		)
		(fp_line
			(start -0.7874 -0.4064)
			(end 0.7874 -0.4064)
			(stroke
				(width 0.1524)
				(type default)
			)
			(layer "F.SilkS")
		)
		(fp_line
			(start 0.7874 -0.4064)
			(end 0.7874 0.4064)
			(stroke
				(width 0.1524)
				(type default)
			)
			(layer "F.SilkS")
		)
		(fp_line
			(start -0.67945 0.3048)
			(end -0.67945 -0.305054)
			(stroke
				(width 0.1)
				(type default)
			)
			(layer "F.Fab")
		)
		(fp_line
			(start -0.12065 0.3048)
			(end -0.67945 0.3048)
			(stroke
				(width 0.1)
				(type default)
			)
			(layer "F.Fab")
		)
		(fp_line
			(start 0.120396 0.3048)
			(end 0.120396 0.2794)
			(stroke
				(width 0.1)
				(type default)
			)
			(layer "F.Fab")
		)
		(fp_line
			(start 0.67945 0.3048)
			(end 0.120396 0.3048)
			(stroke
				(width 0.1)
				(type default)
			)
			(layer "F.Fab")
		)
		(fp_line
			(start -0.12065 0.2794)
			(end -0.12065 0.3048)
			(stroke
				(width 0.1)
				(type default)
			)
			(layer "F.Fab")
		)
		(fp_line
			(start 0.120396 0.2794)
			(end -0.12065 0.2794)
			(stroke
				(width 0.1)
				(type default)
			)
			(layer "F.Fab")
		)
		(fp_line
			(start -0.12065 -0.2794)
			(end 0.12065 -0.2794)
			(stroke
				(width 0.1)
				(type default)
			)
			(layer "F.Fab")
		)
		(fp_line
			(start 0.12065 -0.2794)
			(end 0.12065 -0.3048)
			(stroke
				(width 0.1)
				(type default)
			)
			(layer "F.Fab")
		)
		(fp_line
			(start 0.12065 -0.3048)
			(end 0.67945 -0.3048)
			(stroke
				(width 0.1)
				(type default)
			)
			(layer "F.Fab")
		)
		(fp_line
			(start 0.67945 -0.3048)
			(end 0.67945 0.3048)
			(stroke
				(width 0.1)
				(type default)
			)
			(layer "F.Fab")
		)
		(fp_line
			(start -0.67945 -0.305054)
			(end -0.12065 -0.305054)
			(stroke
				(width 0.1)
				(type default)
			)
			(layer "F.Fab")
		)
		(fp_line
			(start -0.12065 -0.305054)
			(end -0.12065 -0.2794)
			(stroke
				(width 0.1)
				(type default)
			)
			(layer "F.Fab")
		)
		(pad "1" smd circle
			(at -0.40005 0 270)
			(size 0 0)
			(layers "F.Cu" "F.Mask" "F.Paste")
			(net "P3V3_AUX")
		)
		(pad "2" smd circle
			(at 0.40005 0 270)
			(size 0 0)
			(layers "F.Cu" "F.Mask" "F.Paste")
			(net "SSD15_AUX_P3V3_EN")
		)
	)
	(footprint ""
		(layer "F.Cu")
		(at 71.73849 -44.341542 90)
		(property "Reference" "C209"
			(at 0 0 90)
			(layer "F.SilkS")
			(hide yes)
			(effects
				(font
					(size 1.27 1.27)
				)
			)
		)
		(property "Value" ""
			(at 0 0 90)
			(layer "F.Fab")
			(effects
				(font
					(size 1.27 1.27)
				)
			)
		)
		(duplicate_pad_numbers_are_jumpers no)
		(fp_line
			(start 0.7874 -0.4064)
			(end 0.7874 0.4064)
			(stroke
				(width 0.1524)
				(type default)
			)
			(layer "F.SilkS")
		)
		(fp_line
			(start -0.7874 -0.4064)
			(end 0.7874 -0.4064)
			(stroke
				(width 0.1524)
				(type default)
			)
			(layer "F.SilkS")
		)
		(fp_line
			(start 0.7874 0.4064)
			(end -0.7874 0.4064)
			(stroke
				(width 0.1524)
				(type default)
			)
			(layer "F.SilkS")
		)
		(fp_line
			(start -0.7874 0.4064)
			(end -0.7874 -0.4064)
			(stroke
				(width 0.1524)
				(type default)
			)
			(layer "F.SilkS")
		)
		(fp_line
			(start -0.12065 -0.305054)
			(end -0.12065 -0.2794)
			(stroke
				(width 0.1)
				(type default)
			)
			(layer "F.Fab")
		)
		(fp_line
			(start -0.67945 -0.305054)
			(end -0.12065 -0.305054)
			(stroke
				(width 0.1)
				(type default)
			)
			(layer "F.Fab")
		)
		(fp_line
			(start 0.67945 -0.3048)
			(end 0.67945 0.3048)
			(stroke
				(width 0.1)
				(type default)
			)
			(layer "F.Fab")
		)
		(fp_line
			(start 0.12065 -0.3048)
			(end 0.67945 -0.3048)
			(stroke
				(width 0.1)
				(type default)
			)
			(layer "F.Fab")
		)
		(fp_line
			(start 0.12065 -0.2794)
			(end 0.12065 -0.3048)
			(stroke
				(width 0.1)
				(type default)
			)
			(layer "F.Fab")
		)
		(fp_line
			(start -0.12065 -0.2794)
			(end 0.12065 -0.2794)
			(stroke
				(width 0.1)
				(type default)
			)
			(layer "F.Fab")
		)
		(fp_line
			(start 0.120396 0.2794)
			(end -0.12065 0.2794)
			(stroke
				(width 0.1)
				(type default)
			)
			(layer "F.Fab")
		)
		(fp_line
			(start -0.12065 0.2794)
			(end -0.12065 0.3048)
			(stroke
				(width 0.1)
				(type default)
			)
			(layer "F.Fab")
		)
		(fp_line
			(start 0.67945 0.3048)
			(end 0.120396 0.3048)
			(stroke
				(width 0.1)
				(type default)
			)
			(layer "F.Fab")
		)
		(fp_line
			(start 0.120396 0.3048)
			(end 0.120396 0.2794)
			(stroke
				(width 0.1)
				(type default)
			)
			(layer "F.Fab")
		)
		(fp_line
			(start -0.12065 0.3048)
			(end -0.67945 0.3048)
			(stroke
				(width 0.1)
				(type default)
			)
			(layer "F.Fab")
		)
		(fp_line
			(start -0.67945 0.3048)
			(end -0.67945 -0.305054)
			(stroke
				(width 0.1)
				(type default)
			)
			(layer "F.Fab")
		)
		(pad "1" smd circle
			(at -0.40005 0 90)
			(size 0 0)
			(layers "F.Cu" "F.Mask" "F.Paste")
			(net "P12V_SSD2_VIN_P")
		)
		(pad "2" smd circle
			(at 0.40005 0 90)
			(size 0 0)
			(layers "F.Cu" "F.Mask" "F.Paste")
			(net "P12V_SSD2_VIN_N")
		)
	)
	(footprint ""
		(layer "F.Cu")
		(at 263.904984 -347.997018 -90)
		(property "Reference" "R6655"
			(at 0 0 270)
			(layer "F.SilkS")
			(hide yes)
			(effects
				(font
					(size 1.27 1.27)
				)
			)
		)
		(property "Value" ""
			(at 0 0 270)
			(layer "F.Fab")
			(effects
				(font
					(size 1.27 1.27)
				)
			)
		)
		(duplicate_pad_numbers_are_jumpers no)
		(fp_line
			(start -0.7874 0.4064)
			(end -0.7874 -0.4064)
			(stroke
				(width 0.1524)
				(type default)
			)
			(layer "F.SilkS")
		)
		(fp_line
			(start 0.7874 0.4064)
			(end -0.7874 0.4064)
			(stroke
				(width 0.1524)
				(type default)
			)
			(layer "F.SilkS")
		)
		(fp_line
			(start -0.7874 -0.4064)
			(end 0.7874 -0.4064)
			(stroke
				(width 0.1524)
				(type default)
			)
			(layer "F.SilkS")
		)
		(fp_line
			(start 0.7874 -0.4064)
			(end 0.7874 0.4064)
			(stroke
				(width 0.1524)
				(type default)
			)
			(layer "F.SilkS")
		)
		(fp_line
			(start -0.67945 0.3048)
			(end -0.67945 -0.305054)
			(stroke
				(width 0.1)
				(type default)
			)
			(layer "F.Fab")
		)
		(fp_line
			(start -0.12065 0.3048)
			(end -0.67945 0.3048)
			(stroke
				(width 0.1)
				(type default)
			)
			(layer "F.Fab")
		)
		(fp_line
			(start 0.120396 0.3048)
			(end 0.120396 0.2794)
			(stroke
				(width 0.1)
				(type default)
			)
			(layer "F.Fab")
		)
		(fp_line
			(start 0.67945 0.3048)
			(end 0.120396 0.3048)
			(stroke
				(width 0.1)
				(type default)
			)
			(layer "F.Fab")
		)
		(fp_line
			(start -0.12065 0.2794)
			(end -0.12065 0.3048)
			(stroke
				(width 0.1)
				(type default)
			)
			(layer "F.Fab")
		)
		(fp_line
			(start 0.120396 0.2794)
			(end -0.12065 0.2794)
			(stroke
				(width 0.1)
				(type default)
			)
			(layer "F.Fab")
		)
		(fp_line
			(start -0.12065 -0.2794)
			(end 0.12065 -0.2794)
			(stroke
				(width 0.1)
				(type default)
			)
			(layer "F.Fab")
		)
		(fp_line
			(start 0.12065 -0.2794)
			(end 0.12065 -0.3048)
			(stroke
				(width 0.1)
				(type default)
			)
			(layer "F.Fab")
		)
		(fp_line
			(start 0.12065 -0.3048)
			(end 0.67945 -0.3048)
			(stroke
				(width 0.1)
				(type default)
			)
			(layer "F.Fab")
		)
		(fp_line
			(start 0.67945 -0.3048)
			(end 0.67945 0.3048)
			(stroke
				(width 0.1)
				(type default)
			)
			(layer "F.Fab")
		)
		(fp_line
			(start -0.67945 -0.305054)
			(end -0.12065 -0.305054)
			(stroke
				(width 0.1)
				(type default)
			)
			(layer "F.Fab")
		)
		(fp_line
			(start -0.12065 -0.305054)
			(end -0.12065 -0.2794)
			(stroke
				(width 0.1)
				(type default)
			)
			(layer "F.Fab")
		)
		(pad "1" smd circle
			(at -0.40005 0 270)
			(size 0 0)
			(layers "F.Cu" "F.Mask" "F.Paste")
			(net "A_HSC_LOW_DRAIN")
		)
		(pad "2" smd circle
			(at 0.40005 0 270)
			(size 0 0)
			(layers "F.Cu" "F.Mask" "F.Paste")
			(net "HSC_D_OC_R")
		)
	)
	(footprint ""
		(layer "F.Cu")
		(at 162.587686 -25.342342 -90)
		(property "Reference" "R425"
			(at 0 0 270)
			(layer "F.SilkS")
			(hide yes)
			(effects
				(font
					(size 1.27 1.27)
				)
			)
		)
		(property "Value" ""
			(at 0 0 270)
			(layer "F.Fab")
			(effects
				(font
					(size 1.27 1.27)
				)
			)
		)
		(duplicate_pad_numbers_are_jumpers no)
		(fp_line
			(start -0.7874 0.4064)
			(end -0.7874 -0.4064)
			(stroke
				(width 0.1524)
				(type default)
			)
			(layer "F.SilkS")
		)
		(fp_line
			(start 0.7874 0.4064)
			(end -0.7874 0.4064)
			(stroke
				(width 0.1524)
				(type default)
			)
			(layer "F.SilkS")
		)
		(fp_line
			(start -0.7874 -0.4064)
			(end 0.7874 -0.4064)
			(stroke
				(width 0.1524)
				(type default)
			)
			(layer "F.SilkS")
		)
		(fp_line
			(start 0.7874 -0.4064)
			(end 0.7874 0.4064)
			(stroke
				(width 0.1524)
				(type default)
			)
			(layer "F.SilkS")
		)
		(fp_line
			(start -0.67945 0.3048)
			(end -0.67945 -0.305054)
			(stroke
				(width 0.1)
				(type default)
			)
			(layer "F.Fab")
		)
		(fp_line
			(start -0.12065 0.3048)
			(end -0.67945 0.3048)
			(stroke
				(width 0.1)
				(type default)
			)
			(layer "F.Fab")
		)
		(fp_line
			(start 0.120396 0.3048)
			(end 0.120396 0.2794)
			(stroke
				(width 0.1)
				(type default)
			)
			(layer "F.Fab")
		)
		(fp_line
			(start 0.67945 0.3048)
			(end 0.120396 0.3048)
			(stroke
				(width 0.1)
				(type default)
			)
			(layer "F.Fab")
		)
		(fp_line
			(start -0.12065 0.2794)
			(end -0.12065 0.3048)
			(stroke
				(width 0.1)
				(type default)
			)
			(layer "F.Fab")
		)
		(fp_line
			(start 0.120396 0.2794)
			(end -0.12065 0.2794)
			(stroke
				(width 0.1)
				(type default)
			)
			(layer "F.Fab")
		)
		(fp_line
			(start -0.12065 -0.2794)
			(end 0.12065 -0.2794)
			(stroke
				(width 0.1)
				(type default)
			)
			(layer "F.Fab")
		)
		(fp_line
			(start 0.12065 -0.2794)
			(end 0.12065 -0.3048)
			(stroke
				(width 0.1)
				(type default)
			)
			(layer "F.Fab")
		)
		(fp_line
			(start 0.12065 -0.3048)
			(end 0.67945 -0.3048)
			(stroke
				(width 0.1)
				(type default)
			)
			(layer "F.Fab")
		)
		(fp_line
			(start 0.67945 -0.3048)
			(end 0.67945 0.3048)
			(stroke
				(width 0.1)
				(type default)
			)
			(layer "F.Fab")
		)
		(fp_line
			(start -0.67945 -0.305054)
			(end -0.12065 -0.305054)
			(stroke
				(width 0.1)
				(type default)
			)
			(layer "F.Fab")
		)
		(fp_line
			(start -0.12065 -0.305054)
			(end -0.12065 -0.2794)
			(stroke
				(width 0.1)
				(type default)
			)
			(layer "F.Fab")
		)
		(pad "1" smd circle
			(at -0.40005 0 270)
			(size 0 0)
			(layers "F.Cu" "F.Mask" "F.Paste")
			(net "GND")
		)
		(pad "2" smd circle
			(at 0.40005 0 270)
			(size 0 0)
			(layers "F.Cu" "F.Mask" "F.Paste")
			(net "DUALPORT_N_SSD5")
		)
	)
	(footprint ""
		(layer "F.Cu")
		(at 18.787872 -168.679368 90)
		(property "Reference" "PC19"
			(at 0 0 90)
			(layer "F.SilkS")
			(hide yes)
			(effects
				(font
					(size 1.27 1.27)
				)
			)
		)
		(property "Value" ""
			(at 0 0 90)
			(layer "F.Fab")
			(effects
				(font
					(size 1.27 1.27)
				)
			)
		)
		(duplicate_pad_numbers_are_jumpers no)
		(fp_line
			(start 0.7874 -0.4064)
			(end 0.7874 0.4064)
			(stroke
				(width 0.1524)
				(type default)
			)
			(layer "F.SilkS")
		)
		(fp_line
			(start -0.7874 -0.4064)
			(end 0.7874 -0.4064)
			(stroke
				(width 0.1524)
				(type default)
			)
			(layer "F.SilkS")
		)
		(fp_line
			(start 0.7874 0.4064)
			(end -0.7874 0.4064)
			(stroke
				(width 0.1524)
				(type default)
			)
			(layer "F.SilkS")
		)
		(fp_line
			(start -0.7874 0.4064)
			(end -0.7874 -0.4064)
			(stroke
				(width 0.1524)
				(type default)
			)
			(layer "F.SilkS")
		)
		(fp_line
			(start -0.12065 -0.305054)
			(end -0.12065 -0.2794)
			(stroke
				(width 0.1)
				(type default)
			)
			(layer "F.Fab")
		)
		(fp_line
			(start -0.67945 -0.305054)
			(end -0.12065 -0.305054)
			(stroke
				(width 0.1)
				(type default)
			)
			(layer "F.Fab")
		)
		(fp_line
			(start 0.67945 -0.3048)
			(end 0.67945 0.3048)
			(stroke
				(width 0.1)
				(type default)
			)
			(layer "F.Fab")
		)
		(fp_line
			(start 0.12065 -0.3048)
			(end 0.67945 -0.3048)
			(stroke
				(width 0.1)
				(type default)
			)
			(layer "F.Fab")
		)
		(fp_line
			(start 0.12065 -0.2794)
			(end 0.12065 -0.3048)
			(stroke
				(width 0.1)
				(type default)
			)
			(layer "F.Fab")
		)
		(fp_line
			(start -0.12065 -0.2794)
			(end 0.12065 -0.2794)
			(stroke
				(width 0.1)
				(type default)
			)
			(layer "F.Fab")
		)
		(fp_line
			(start 0.120396 0.2794)
			(end -0.12065 0.2794)
			(stroke
				(width 0.1)
				(type default)
			)
			(layer "F.Fab")
		)
		(fp_line
			(start -0.12065 0.2794)
			(end -0.12065 0.3048)
			(stroke
				(width 0.1)
				(type default)
			)
			(layer "F.Fab")
		)
		(fp_line
			(start 0.67945 0.3048)
			(end 0.120396 0.3048)
			(stroke
				(width 0.1)
				(type default)
			)
			(layer "F.Fab")
		)
		(fp_line
			(start 0.120396 0.3048)
			(end 0.120396 0.2794)
			(stroke
				(width 0.1)
				(type default)
			)
			(layer "F.Fab")
		)
		(fp_line
			(start -0.12065 0.3048)
			(end -0.67945 0.3048)
			(stroke
				(width 0.1)
				(type default)
			)
			(layer "F.Fab")
		)
		(fp_line
			(start -0.67945 0.3048)
			(end -0.67945 -0.305054)
			(stroke
				(width 0.1)
				(type default)
			)
			(layer "F.Fab")
		)
		(pad "1" smd circle
			(at -0.40005 0 90)
			(size 0 0)
			(layers "F.Cu" "F.Mask" "F.Paste")
			(net "SW_P5V_AUX_BT")
		)
		(pad "2" smd circle
			(at 0.40005 0 90)
			(size 0 0)
			(layers "F.Cu" "F.Mask" "F.Paste")
			(net "SW_P5V_AUX_PH")
		)
	)
	(footprint ""
		(layer "F.Cu")
		(at 182.548784 -198.109332 180)
		(property "Reference" "C2096"
			(at 0 0 180)
			(layer "F.SilkS")
			(hide yes)
			(effects
				(font
					(size 1.27 1.27)
				)
			)
		)
		(property "Value" ""
			(at 0 0 180)
			(layer "F.Fab")
			(effects
				(font
					(size 1.27 1.27)
				)
			)
		)
		(duplicate_pad_numbers_are_jumpers no)
		(fp_line
			(start 0.7874 0.4064)
			(end -0.7874 0.4064)
			(stroke
				(width 0.1524)
				(type default)
			)
			(layer "F.SilkS")
		)
		(fp_line
			(start 0.7874 -0.4064)
			(end 0.7874 0.4064)
			(stroke
				(width 0.1524)
				(type default)
			)
			(layer "F.SilkS")
		)
		(fp_line
			(start -0.7874 0.4064)
			(end -0.7874 -0.4064)
			(stroke
				(width 0.1524)
				(type default)
			)
			(layer "F.SilkS")
		)
		(fp_line
			(start -0.7874 -0.4064)
			(end 0.7874 -0.4064)
			(stroke
				(width 0.1524)
				(type default)
			)
			(layer "F.SilkS")
		)
		(fp_line
			(start 0.67945 0.3048)
			(end 0.120396 0.3048)
			(stroke
				(width 0.1)
				(type default)
			)
			(layer "F.Fab")
		)
		(fp_line
			(start 0.67945 -0.3048)
			(end 0.67945 0.3048)
			(stroke
				(width 0.1)
				(type default)
			)
			(layer "F.Fab")
		)
		(fp_line
			(start 0.12065 -0.2794)
			(end 0.12065 -0.3048)
			(stroke
				(width 0.1)
				(type default)
			)
			(layer "F.Fab")
		)
		(fp_line
			(start 0.12065 -0.3048)
			(end 0.67945 -0.3048)
			(stroke
				(width 0.1)
				(type default)
			)
			(layer "F.Fab")
		)
		(fp_line
			(start 0.120396 0.3048)
			(end 0.120396 0.2794)
			(stroke
				(width 0.1)
				(type default)
			)
			(layer "F.Fab")
		)
		(fp_line
			(start 0.120396 0.2794)
			(end -0.12065 0.2794)
			(stroke
				(width 0.1)
				(type default)
			)
			(layer "F.Fab")
		)
		(fp_line
			(start -0.12065 0.3048)
			(end -0.67945 0.3048)
			(stroke
				(width 0.1)
				(type default)
			)
			(layer "F.Fab")
		)
		(fp_line
			(start -0.12065 0.2794)
			(end -0.12065 0.3048)
			(stroke
				(width 0.1)
				(type default)
			)
			(layer "F.Fab")
		)
		(fp_line
			(start -0.12065 -0.2794)
			(end 0.12065 -0.2794)
			(stroke
				(width 0.1)
				(type default)
			)
			(layer "F.Fab")
		)
		(fp_line
			(start -0.12065 -0.305054)
			(end -0.12065 -0.2794)
			(stroke
				(width 0.1)
				(type default)
			)
			(layer "F.Fab")
		)
		(fp_line
			(start -0.67945 0.3048)
			(end -0.67945 -0.305054)
			(stroke
				(width 0.1)
				(type default)
			)
			(layer "F.Fab")
		)
		(fp_line
			(start -0.67945 -0.305054)
			(end -0.12065 -0.305054)
			(stroke
				(width 0.1)
				(type default)
			)
			(layer "F.Fab")
		)
		(pad "1" smd circle
			(at -0.40005 0 180)
			(size 0 0)
			(layers "F.Cu" "F.Mask" "F.Paste")
			(net "GND")
		)
		(pad "2" smd circle
			(at 0.40005 0 180)
			(size 0 0)
			(layers "F.Cu" "F.Mask" "F.Paste")
			(net "P3V3_AUX")
		)
	)
	(footprint ""
		(layer "F.Cu")
		(at 405.950166 -50.96383 180)
		(property "Reference" "PC575"
			(at 0 0 180)
			(layer "F.SilkS")
			(hide yes)
			(effects
				(font
					(size 1.27 1.27)
				)
			)
		)
		(property "Value" ""
			(at 0 0 180)
			(layer "F.Fab")
			(effects
				(font
					(size 1.27 1.27)
				)
			)
		)
		(duplicate_pad_numbers_are_jumpers no)
		(fp_line
			(start 1.524 0.762)
			(end -1.524 0.762)
			(stroke
				(width 0.1524)
				(type default)
			)
			(layer "F.SilkS")
		)
		(fp_line
			(start 1.524 -0.762)
			(end 1.524 0.762)
			(stroke
				(width 0.1524)
				(type default)
			)
			(layer "F.SilkS")
		)
		(fp_line
			(start -1.524 0.762)
			(end -1.524 -0.762)
			(stroke
				(width 0.1524)
				(type default)
			)
			(layer "F.SilkS")
		)
		(fp_line
			(start -1.524 -0.762)
			(end 1.524 -0.762)
			(stroke
				(width 0.1524)
				(type default)
			)
			(layer "F.SilkS")
		)
		(fp_line
			(start 1.1049 0.724916)
			(end 1.1049 -0.724916)
			(stroke
				(width 0.1)
				(type default)
			)
			(layer "F.Fab")
		)
		(fp_line
			(start 1.1049 -0.724916)
			(end -1.1049 -0.724916)
			(stroke
				(width 0.1)
				(type default)
			)
			(layer "F.Fab")
		)
		(fp_line
			(start -1.1049 0.724916)
			(end 1.1049 0.724916)
			(stroke
				(width 0.1)
				(type default)
			)
			(layer "F.Fab")
		)
		(fp_line
			(start -1.1049 -0.724916)
			(end -1.1049 0.724916)
			(stroke
				(width 0.1)
				(type default)
			)
			(layer "F.Fab")
		)
		(pad "1" smd rect
			(at -0.889 0)
			(size 1.016 1.27)
			(layers "F.Cu" "F.Mask" "F.Paste")
			(net "P3V3_SSD14")
		)
		(pad "2" smd rect
			(at 0.889 0)
			(size 1.016 1.27)
			(layers "F.Cu" "F.Mask" "F.Paste")
			(net "GND")
		)
	)
	(footprint ""
		(layer "F.Cu")
		(at 234.493816 -372.8974)
		(property "Reference" "PR39"
			(at 0 0 0)
			(layer "F.SilkS")
			(hide yes)
			(effects
				(font
					(size 1.27 1.27)
				)
			)
		)
		(property "Value" ""
			(at 0 0 0)
			(layer "F.Fab")
			(effects
				(font
					(size 1.27 1.27)
				)
			)
		)
		(duplicate_pad_numbers_are_jumpers no)
		(fp_line
			(start -0.7874 -0.4064)
			(end 0.7874 -0.4064)
			(stroke
				(width 0.1524)
				(type default)
			)
			(layer "F.SilkS")
		)
		(fp_line
			(start -0.7874 0.4064)
			(end -0.7874 -0.4064)
			(stroke
				(width 0.1524)
				(type default)
			)
			(layer "F.SilkS")
		)
		(fp_line
			(start 0.7874 -0.4064)
			(end 0.7874 0.4064)
			(stroke
				(width 0.1524)
				(type default)
			)
			(layer "F.SilkS")
		)
		(fp_line
			(start 0.7874 0.4064)
			(end -0.7874 0.4064)
			(stroke
				(width 0.1524)
				(type default)
			)
			(layer "F.SilkS")
		)
		(fp_line
			(start -0.67945 -0.305054)
			(end -0.12065 -0.305054)
			(stroke
				(width 0.1)
				(type default)
			)
			(layer "F.Fab")
		)
		(fp_line
			(start -0.67945 0.3048)
			(end -0.67945 -0.305054)
			(stroke
				(width 0.1)
				(type default)
			)
			(layer "F.Fab")
		)
		(fp_line
			(start -0.12065 -0.305054)
			(end -0.12065 -0.2794)
			(stroke
				(width 0.1)
				(type default)
			)
			(layer "F.Fab")
		)
		(fp_line
			(start -0.12065 -0.2794)
			(end 0.12065 -0.2794)
			(stroke
				(width 0.1)
				(type default)
			)
			(layer "F.Fab")
		)
		(fp_line
			(start -0.12065 0.2794)
			(end -0.12065 0.3048)
			(stroke
				(width 0.1)
				(type default)
			)
			(layer "F.Fab")
		)
		(fp_line
			(start -0.12065 0.3048)
			(end -0.67945 0.3048)
			(stroke
				(width 0.1)
				(type default)
			)
			(layer "F.Fab")
		)
		(fp_line
			(start 0.120396 0.2794)
			(end -0.12065 0.2794)
			(stroke
				(width 0.1)
				(type default)
			)
			(layer "F.Fab")
		)
		(fp_line
			(start 0.120396 0.3048)
			(end 0.120396 0.2794)
			(stroke
				(width 0.1)
				(type default)
			)
			(layer "F.Fab")
		)
		(fp_line
			(start 0.12065 -0.3048)
			(end 0.67945 -0.3048)
			(stroke
				(width 0.1)
				(type default)
			)
			(layer "F.Fab")
		)
		(fp_line
			(start 0.12065 -0.2794)
			(end 0.12065 -0.3048)
			(stroke
				(width 0.1)
				(type default)
			)
			(layer "F.Fab")
		)
		(fp_line
			(start 0.67945 -0.3048)
			(end 0.67945 0.3048)
			(stroke
				(width 0.1)
				(type default)
			)
			(layer "F.Fab")
		)
		(fp_line
			(start 0.67945 0.3048)
			(end 0.120396 0.3048)
			(stroke
				(width 0.1)
				(type default)
			)
			(layer "F.Fab")
		)
		(pad "1" smd circle
			(at -0.40005 0)
			(size 0 0)
			(layers "F.Cu" "F.Mask" "F.Paste")
			(net "HSC_FLT_TYPE_2")
		)
		(pad "2" smd circle
			(at 0.40005 0)
			(size 0 0)
			(layers "F.Cu" "F.Mask" "F.Paste")
			(net "HSC_FLT_TYPE_R")
		)
	)
	(footprint ""
		(layer "F.Cu")
		(at 207.479392 -300.641004 -90)
		(property "Reference" "R3927"
			(at 0 0 270)
			(layer "F.SilkS")
			(hide yes)
			(effects
				(font
					(size 1.27 1.27)
				)
			)
		)
		(property "Value" ""
			(at 0 0 270)
			(layer "F.Fab")
			(effects
				(font
					(size 1.27 1.27)
				)
			)
		)
		(duplicate_pad_numbers_are_jumpers no)
		(fp_line
			(start -0.7874 0.4064)
			(end -0.7874 -0.4064)
			(stroke
				(width 0.1524)
				(type default)
			)
			(layer "F.SilkS")
		)
		(fp_line
			(start 0.7874 0.4064)
			(end -0.7874 0.4064)
			(stroke
				(width 0.1524)
				(type default)
			)
			(layer "F.SilkS")
		)
		(fp_line
			(start -0.7874 -0.4064)
			(end 0.7874 -0.4064)
			(stroke
				(width 0.1524)
				(type default)
			)
			(layer "F.SilkS")
		)
		(fp_line
			(start 0.7874 -0.4064)
			(end 0.7874 0.4064)
			(stroke
				(width 0.1524)
				(type default)
			)
			(layer "F.SilkS")
		)
		(fp_line
			(start -0.67945 0.3048)
			(end -0.67945 -0.305054)
			(stroke
				(width 0.1)
				(type default)
			)
			(layer "F.Fab")
		)
		(fp_line
			(start -0.12065 0.3048)
			(end -0.67945 0.3048)
			(stroke
				(width 0.1)
				(type default)
			)
			(layer "F.Fab")
		)
		(fp_line
			(start 0.120396 0.3048)
			(end 0.120396 0.2794)
			(stroke
				(width 0.1)
				(type default)
			)
			(layer "F.Fab")
		)
		(fp_line
			(start 0.67945 0.3048)
			(end 0.120396 0.3048)
			(stroke
				(width 0.1)
				(type default)
			)
			(layer "F.Fab")
		)
		(fp_line
			(start -0.12065 0.2794)
			(end -0.12065 0.3048)
			(stroke
				(width 0.1)
				(type default)
			)
			(layer "F.Fab")
		)
		(fp_line
			(start 0.120396 0.2794)
			(end -0.12065 0.2794)
			(stroke
				(width 0.1)
				(type default)
			)
			(layer "F.Fab")
		)
		(fp_line
			(start -0.12065 -0.2794)
			(end 0.12065 -0.2794)
			(stroke
				(width 0.1)
				(type default)
			)
			(layer "F.Fab")
		)
		(fp_line
			(start 0.12065 -0.2794)
			(end 0.12065 -0.3048)
			(stroke
				(width 0.1)
				(type default)
			)
			(layer "F.Fab")
		)
		(fp_line
			(start 0.12065 -0.3048)
			(end 0.67945 -0.3048)
			(stroke
				(width 0.1)
				(type default)
			)
			(layer "F.Fab")
		)
		(fp_line
			(start 0.67945 -0.3048)
			(end 0.67945 0.3048)
			(stroke
				(width 0.1)
				(type default)
			)
			(layer "F.Fab")
		)
		(fp_line
			(start -0.67945 -0.305054)
			(end -0.12065 -0.305054)
			(stroke
				(width 0.1)
				(type default)
			)
			(layer "F.Fab")
		)
		(fp_line
			(start -0.12065 -0.305054)
			(end -0.12065 -0.2794)
			(stroke
				(width 0.1)
				(type default)
			)
			(layer "F.Fab")
		)
		(pad "1" smd circle
			(at -0.40005 0 270)
			(size 0 0)
			(layers "F.Cu" "F.Mask" "F.Paste")
			(net "I2C0_PEX1_SCL")
		)
		(pad "2" smd circle
			(at 0.40005 0 270)
			(size 0 0)
			(layers "F.Cu" "F.Mask" "F.Paste")
			(net "I2C_PEX1_HOST_SCL")
		)
	)
	(footprint ""
		(layer "F.Cu")
		(at 106.596942 -115.646454 180)
		(property "Reference" "PR6874"
			(at 0 0 180)
			(layer "F.SilkS")
			(hide yes)
			(effects
				(font
					(size 1.27 1.27)
				)
			)
		)
		(property "Value" ""
			(at 0 0 180)
			(layer "F.Fab")
			(effects
				(font
					(size 1.27 1.27)
				)
			)
		)
		(duplicate_pad_numbers_are_jumpers no)
		(fp_line
			(start 0.7874 0.4064)
			(end -0.7874 0.4064)
			(stroke
				(width 0.1524)
				(type default)
			)
			(layer "F.SilkS")
		)
		(fp_line
			(start 0.7874 -0.4064)
			(end 0.7874 0.4064)
			(stroke
				(width 0.1524)
				(type default)
			)
			(layer "F.SilkS")
		)
		(fp_line
			(start -0.7874 0.4064)
			(end -0.7874 -0.4064)
			(stroke
				(width 0.1524)
				(type default)
			)
			(layer "F.SilkS")
		)
		(fp_line
			(start -0.7874 -0.4064)
			(end 0.7874 -0.4064)
			(stroke
				(width 0.1524)
				(type default)
			)
			(layer "F.SilkS")
		)
		(fp_line
			(start 0.67945 0.3048)
			(end 0.120396 0.3048)
			(stroke
				(width 0.1)
				(type default)
			)
			(layer "F.Fab")
		)
		(fp_line
			(start 0.67945 -0.3048)
			(end 0.67945 0.3048)
			(stroke
				(width 0.1)
				(type default)
			)
			(layer "F.Fab")
		)
		(fp_line
			(start 0.12065 -0.2794)
			(end 0.12065 -0.3048)
			(stroke
				(width 0.1)
				(type default)
			)
			(layer "F.Fab")
		)
		(fp_line
			(start 0.12065 -0.3048)
			(end 0.67945 -0.3048)
			(stroke
				(width 0.1)
				(type default)
			)
			(layer "F.Fab")
		)
		(fp_line
			(start 0.120396 0.3048)
			(end 0.120396 0.2794)
			(stroke
				(width 0.1)
				(type default)
			)
			(layer "F.Fab")
		)
		(fp_line
			(start 0.120396 0.2794)
			(end -0.12065 0.2794)
			(stroke
				(width 0.1)
				(type default)
			)
			(layer "F.Fab")
		)
		(fp_line
			(start -0.12065 0.3048)
			(end -0.67945 0.3048)
			(stroke
				(width 0.1)
				(type default)
			)
			(layer "F.Fab")
		)
		(fp_line
			(start -0.12065 0.2794)
			(end -0.12065 0.3048)
			(stroke
				(width 0.1)
				(type default)
			)
			(layer "F.Fab")
		)
		(fp_line
			(start -0.12065 -0.2794)
			(end 0.12065 -0.2794)
			(stroke
				(width 0.1)
				(type default)
			)
			(layer "F.Fab")
		)
		(fp_line
			(start -0.12065 -0.305054)
			(end -0.12065 -0.2794)
			(stroke
				(width 0.1)
				(type default)
			)
			(layer "F.Fab")
		)
		(fp_line
			(start -0.67945 0.3048)
			(end -0.67945 -0.305054)
			(stroke
				(width 0.1)
				(type default)
			)
			(layer "F.Fab")
		)
		(fp_line
			(start -0.67945 -0.305054)
			(end -0.12065 -0.305054)
			(stroke
				(width 0.1)
				(type default)
			)
			(layer "F.Fab")
		)
		(pad "1" smd circle
			(at -0.40005 0 180)
			(size 0 0)
			(layers "F.Cu" "F.Mask" "F.Paste")
			(net "P12V_NIC1_CO_OV_FB")
		)
		(pad "2" smd circle
			(at 0.40005 0 180)
			(size 0 0)
			(layers "F.Cu" "F.Mask" "F.Paste")
			(net "GND")
		)
	)
	(footprint ""
		(layer "F.Cu")
		(at 342.763094 -284.834838 90)
		(property "Reference" "PC157"
			(at 0 0 90)
			(layer "F.SilkS")
			(hide yes)
			(effects
				(font
					(size 1.27 1.27)
				)
			)
		)
		(property "Value" ""
			(at 0 0 90)
			(layer "F.Fab")
			(effects
				(font
					(size 1.27 1.27)
				)
			)
		)
		(duplicate_pad_numbers_are_jumpers no)
		(fp_line
			(start 0.7874 -0.4064)
			(end 0.7874 0.4064)
			(stroke
				(width 0.1524)
				(type default)
			)
			(layer "F.SilkS")
		)
		(fp_line
			(start -0.7874 -0.4064)
			(end 0.7874 -0.4064)
			(stroke
				(width 0.1524)
				(type default)
			)
			(layer "F.SilkS")
		)
		(fp_line
			(start 0.7874 0.4064)
			(end -0.7874 0.4064)
			(stroke
				(width 0.1524)
				(type default)
			)
			(layer "F.SilkS")
		)
		(fp_line
			(start -0.7874 0.4064)
			(end -0.7874 -0.4064)
			(stroke
				(width 0.1524)
				(type default)
			)
			(layer "F.SilkS")
		)
		(fp_line
			(start -0.12065 -0.305054)
			(end -0.12065 -0.2794)
			(stroke
				(width 0.1)
				(type default)
			)
			(layer "F.Fab")
		)
		(fp_line
			(start -0.67945 -0.305054)
			(end -0.12065 -0.305054)
			(stroke
				(width 0.1)
				(type default)
			)
			(layer "F.Fab")
		)
		(fp_line
			(start 0.67945 -0.3048)
			(end 0.67945 0.3048)
			(stroke
				(width 0.1)
				(type default)
			)
			(layer "F.Fab")
		)
		(fp_line
			(start 0.12065 -0.3048)
			(end 0.67945 -0.3048)
			(stroke
				(width 0.1)
				(type default)
			)
			(layer "F.Fab")
		)
		(fp_line
			(start 0.12065 -0.2794)
			(end 0.12065 -0.3048)
			(stroke
				(width 0.1)
				(type default)
			)
			(layer "F.Fab")
		)
		(fp_line
			(start -0.12065 -0.2794)
			(end 0.12065 -0.2794)
			(stroke
				(width 0.1)
				(type default)
			)
			(layer "F.Fab")
		)
		(fp_line
			(start 0.120396 0.2794)
			(end -0.12065 0.2794)
			(stroke
				(width 0.1)
				(type default)
			)
			(layer "F.Fab")
		)
		(fp_line
			(start -0.12065 0.2794)
			(end -0.12065 0.3048)
			(stroke
				(width 0.1)
				(type default)
			)
			(layer "F.Fab")
		)
		(fp_line
			(start 0.67945 0.3048)
			(end 0.120396 0.3048)
			(stroke
				(width 0.1)
				(type default)
			)
			(layer "F.Fab")
		)
		(fp_line
			(start 0.120396 0.3048)
			(end 0.120396 0.2794)
			(stroke
				(width 0.1)
				(type default)
			)
			(layer "F.Fab")
		)
		(fp_line
			(start -0.12065 0.3048)
			(end -0.67945 0.3048)
			(stroke
				(width 0.1)
				(type default)
			)
			(layer "F.Fab")
		)
		(fp_line
			(start -0.67945 0.3048)
			(end -0.67945 -0.305054)
			(stroke
				(width 0.1)
				(type default)
			)
			(layer "F.Fab")
		)
		(pad "1" smd circle
			(at -0.40005 0 90)
			(size 0 0)
			(layers "F.Cu" "F.Mask" "F.Paste")
			(net "SW_P12V_P0V8_PEX2_FLT")
		)
		(pad "2" smd circle
			(at 0.40005 0 90)
			(size 0 0)
			(layers "F.Cu" "F.Mask" "F.Paste")
			(net "GND")
		)
	)
	(footprint ""
		(layer "F.Cu")
		(at 344.511884 -114.960654)
		(property "Reference" "PR7038"
			(at 0 0 0)
			(layer "F.SilkS")
			(hide yes)
			(effects
				(font
					(size 1.27 1.27)
				)
			)
		)
		(property "Value" ""
			(at 0 0 0)
			(layer "F.Fab")
			(effects
				(font
					(size 1.27 1.27)
				)
			)
		)
		(duplicate_pad_numbers_are_jumpers no)
		(fp_line
			(start -0.7874 -0.4064)
			(end 0.7874 -0.4064)
			(stroke
				(width 0.1524)
				(type default)
			)
			(layer "F.SilkS")
		)
		(fp_line
			(start -0.7874 0.4064)
			(end -0.7874 -0.4064)
			(stroke
				(width 0.1524)
				(type default)
			)
			(layer "F.SilkS")
		)
		(fp_line
			(start 0.7874 -0.4064)
			(end 0.7874 0.4064)
			(stroke
				(width 0.1524)
				(type default)
			)
			(layer "F.SilkS")
		)
		(fp_line
			(start 0.7874 0.4064)
			(end -0.7874 0.4064)
			(stroke
				(width 0.1524)
				(type default)
			)
			(layer "F.SilkS")
		)
		(fp_line
			(start -0.67945 -0.305054)
			(end -0.12065 -0.305054)
			(stroke
				(width 0.1)
				(type default)
			)
			(layer "F.Fab")
		)
		(fp_line
			(start -0.67945 0.3048)
			(end -0.67945 -0.305054)
			(stroke
				(width 0.1)
				(type default)
			)
			(layer "F.Fab")
		)
		(fp_line
			(start -0.12065 -0.305054)
			(end -0.12065 -0.2794)
			(stroke
				(width 0.1)
				(type default)
			)
			(layer "F.Fab")
		)
		(fp_line
			(start -0.12065 -0.2794)
			(end 0.12065 -0.2794)
			(stroke
				(width 0.1)
				(type default)
			)
			(layer "F.Fab")
		)
		(fp_line
			(start -0.12065 0.2794)
			(end -0.12065 0.3048)
			(stroke
				(width 0.1)
				(type default)
			)
			(layer "F.Fab")
		)
		(fp_line
			(start -0.12065 0.3048)
			(end -0.67945 0.3048)
			(stroke
				(width 0.1)
				(type default)
			)
			(layer "F.Fab")
		)
		(fp_line
			(start 0.120396 0.2794)
			(end -0.12065 0.2794)
			(stroke
				(width 0.1)
				(type default)
			)
			(layer "F.Fab")
		)
		(fp_line
			(start 0.120396 0.3048)
			(end 0.120396 0.2794)
			(stroke
				(width 0.1)
				(type default)
			)
			(layer "F.Fab")
		)
		(fp_line
			(start 0.12065 -0.3048)
			(end 0.67945 -0.3048)
			(stroke
				(width 0.1)
				(type default)
			)
			(layer "F.Fab")
		)
		(fp_line
			(start 0.12065 -0.2794)
			(end 0.12065 -0.3048)
			(stroke
				(width 0.1)
				(type default)
			)
			(layer "F.Fab")
		)
		(fp_line
			(start 0.67945 -0.3048)
			(end 0.67945 0.3048)
			(stroke
				(width 0.1)
				(type default)
			)
			(layer "F.Fab")
		)
		(fp_line
			(start 0.67945 0.3048)
			(end 0.120396 0.3048)
			(stroke
				(width 0.1)
				(type default)
			)
			(layer "F.Fab")
		)
		(pad "1" smd circle
			(at -0.40005 0)
			(size 0 0)
			(layers "F.Cu" "F.Mask" "F.Paste")
			(net "P12V_NIC5_CO_IMON_VR")
		)
		(pad "2" smd circle
			(at 0.40005 0)
			(size 0 0)
			(layers "F.Cu" "F.Mask" "F.Paste")
			(net "GND")
		)
	)
	(footprint ""
		(layer "F.Cu")
		(at 247.34266 -70.844918 -90)
		(property "Reference" "PD38"
			(at 4.042918 2.23139 90)
			(unlocked yes)
			(layer "F.SilkS")
			(effects
				(font
					(size 0.7874 0.5842)
					(thickness 0.1524)
				)
				(justify left)
			)
		)
		(property "Value" ""
			(at 0 0 270)
			(layer "F.Fab")
			(effects
				(font
					(size 1.27 1.27)
				)
			)
		)
		(duplicate_pad_numbers_are_jumpers no)
		(fp_line
			(start -3.400044 1.459992)
			(end -3.400044 -1.459992)
			(stroke
				(width 0.1524)
				(type default)
			)
			(layer "F.SilkS")
		)
		(fp_line
			(start 4.107942 1.459992)
			(end -3.400044 1.459992)
			(stroke
				(width 0.1524)
				(type default)
			)
			(layer "F.SilkS")
		)
		(fp_line
			(start -3.400044 -1.459992)
			(end 4.107942 -1.459992)
			(stroke
				(width 0.1524)
				(type default)
			)
			(layer "F.SilkS")
		)
		(fp_line
			(start 4.107942 -1.459992)
			(end 4.107942 1.459992)
			(stroke
				(width 0.1524)
				(type default)
			)
			(layer "F.SilkS")
		)
		(fp_poly
			(pts
				(xy 4.107942 -1.459992) (xy 4.107942 1.459992) (xy 3.308096 1.459992) (xy 3.308096 -1.459992)
			)
			(stroke
				(width 0)
				(type default)
			)
			(fill yes)
			(layer "F.SilkS")
		)
		(fp_line
			(start -2.29997 1.459992)
			(end -2.29997 -1.459992)
			(stroke
				(width 0.1)
				(type default)
			)
			(layer "F.Fab")
		)
		(fp_line
			(start 2.29997 1.459992)
			(end -2.29997 1.459992)
			(stroke
				(width 0.1)
				(type default)
			)
			(layer "F.Fab")
		)
		(fp_line
			(start -2.29997 -1.459992)
			(end 2.29997 -1.459992)
			(stroke
				(width 0.1)
				(type default)
			)
			(layer "F.Fab")
		)
		(fp_line
			(start 2.29997 -1.459992)
			(end 2.29997 1.459992)
			(stroke
				(width 0.1)
				(type default)
			)
			(layer "F.Fab")
		)
		(fp_text user "-"
			(at 5.4102 0.29845 90)
			(unlocked yes)
			(layer "F.SilkS")
			(effects
				(font
					(size 1.905 1.4224)
					(thickness 0.1524)
				)
				(justify left)
			)
		)
		(fp_text user "+"
			(at -4.838954 -1.180592 270)
			(unlocked yes)
			(layer "F.SilkS")
			(effects
				(font
					(size 1.905 1.4224)
					(thickness 0.1524)
				)
				(justify left)
			)
		)
		(fp_text user "-"
			(at 5.4102 0.29845 90)
			(unlocked yes)
			(layer "F.Fab")
			(effects
				(font
					(size 1.905 1.4224)
					(thickness 0.1524)
				)
				(justify left)
			)
		)
		(fp_text user "+"
			(at -4.7752 -0.12065 270)
			(unlocked yes)
			(layer "F.Fab")
			(effects
				(font
					(size 1.905 1.4224)
					(thickness 0.1524)
				)
				(justify left)
			)
		)
		(pad "A" smd rect
			(at -1.999996 0)
			(size 1.7018 2.5146)
			(layers "F.Cu" "F.Mask" "F.Paste")
			(net "GND")
		)
		(pad "C" smd rect
			(at 1.999996 0)
			(size 1.7018 2.5146)
			(layers "F.Cu" "F.Mask" "F.Paste")
			(net "P12V_SSD8_R")
		)
	)
	(footprint ""
		(layer "F.Cu")
		(at 283.811472 -71.458074 -90)
		(property "Reference" "PD112"
			(at 4.300474 -2.752598 90)
			(unlocked yes)
			(layer "F.SilkS")
			(effects
				(font
					(size 0.7874 0.5842)
					(thickness 0.1524)
				)
				(justify left)
			)
		)
		(property "Value" ""
			(at 0 0 270)
			(layer "F.Fab")
			(effects
				(font
					(size 1.27 1.27)
				)
			)
		)
		(duplicate_pad_numbers_are_jumpers no)
		(fp_line
			(start -3.656584 1.970024)
			(end 4.240784 1.970024)
			(stroke
				(width 0.1524)
				(type default)
			)
			(layer "F.SilkS")
		)
		(fp_line
			(start 4.240784 1.970024)
			(end 4.240784 -1.970024)
			(stroke
				(width 0.1524)
				(type default)
			)
			(layer "F.SilkS")
		)
		(fp_line
			(start -3.656584 -1.970024)
			(end -3.656584 1.970024)
			(stroke
				(width 0.1524)
				(type default)
			)
			(layer "F.SilkS")
		)
		(fp_line
			(start 4.240784 -1.970024)
			(end -3.656584 -1.970024)
			(stroke
				(width 0.1524)
				(type default)
			)
			(layer "F.SilkS")
		)
		(fp_poly
			(pts
				(xy 3.580384 1.970024) (xy 3.580384 -1.970024) (xy 4.240784 -1.970024) (xy 4.240784 1.970024)
			)
			(stroke
				(width 0)
				(type default)
			)
			(fill yes)
			(layer "F.SilkS")
		)
		(fp_line
			(start -2.3749 1.970024)
			(end 2.3749 1.970024)
			(stroke
				(width 0.1)
				(type default)
			)
			(layer "F.Fab")
		)
		(fp_line
			(start 2.3749 1.970024)
			(end 2.3749 -1.970024)
			(stroke
				(width 0.1)
				(type default)
			)
			(layer "F.Fab")
		)
		(fp_line
			(start -2.3749 -1.970024)
			(end -2.3749 1.970024)
			(stroke
				(width 0.1)
				(type default)
			)
			(layer "F.Fab")
		)
		(fp_line
			(start 2.3749 -1.970024)
			(end -2.3749 -1.970024)
			(stroke
				(width 0.1)
				(type default)
			)
			(layer "F.Fab")
		)
		(fp_text user "+"
			(at -4.9784 -0.23495 270)
			(unlocked yes)
			(layer "F.Fab")
			(effects
				(font
					(size 1.905 1.4224)
					(thickness 0.1524)
				)
				(justify left)
			)
		)
		(fp_text user "-"
			(at 4.1656 -0.23495 270)
			(unlocked yes)
			(layer "F.Fab")
			(effects
				(font
					(size 1.905 1.4224)
					(thickness 0.1524)
				)
				(justify left)
			)
		)
		(pad "A" smd rect
			(at -2.450084 0 270)
			(size 2.159 2.2606)
			(layers "F.Cu" "F.Mask" "F.Paste")
			(net "GND")
		)
		(pad "C" smd rect
			(at 2.450084 0 270)
			(size 2.159 2.2606)
			(layers "F.Cu" "F.Mask" "F.Paste")
			(net "P12V_AUX")
		)
	)
	(footprint ""
		(layer "F.Cu")
		(at 338.266024 18.035524)
		(property "Reference" "DE04F_2"
			(at -3.6068 -2.962148 0)
			(unlocked yes)
			(layer "F.SilkS")
			(effects
				(font
					(size 0.7874 0.5842)
					(thickness 0.1524)
				)
				(justify left)
			)
		)
		(property "Value" ""
			(at 0 0 0)
			(layer "F.Fab")
			(effects
				(font
					(size 1.27 1.27)
				)
			)
		)
		(duplicate_pad_numbers_are_jumpers no)
		(fp_line
			(start -1.2192 -2.1082)
			(end 1.2192 -2.1082)
			(stroke
				(width 0.1524)
				(type default)
			)
			(layer "F.SilkS")
		)
		(fp_line
			(start -1.2192 2.1082)
			(end -1.2192 -2.1082)
			(stroke
				(width 0.1524)
				(type default)
			)
			(layer "F.SilkS")
		)
		(fp_line
			(start 1.2192 -2.1082)
			(end 1.2192 2.1082)
			(stroke
				(width 0.1524)
				(type default)
			)
			(layer "F.SilkS")
		)
		(fp_line
			(start 1.2192 2.1082)
			(end -1.2192 2.1082)
			(stroke
				(width 0.1524)
				(type default)
			)
			(layer "F.SilkS")
		)
		(pad "" np_thru_hole circle
			(at -2.8829 -1.27 270)
			(size 1.0414 1.0414)
			(drill 1.0414)
			(layers "*.Cu" "*.Mask")
			(clearance 0.381)
			(thermal_gap 0.381)
		)
		(pad "" np_thru_hole circle
			(at -2.8829 1.27 270)
			(size 1.0414 1.0414)
			(drill 1.0414)
			(layers "*.Cu" "*.Mask")
			(clearance 0.381)
			(thermal_gap 0.381)
		)
		(pad "" np_thru_hole circle
			(at 3.4671 -1.27 270)
			(size 1.0414 1.0414)
			(drill 1.0414)
			(layers "*.Cu" "*.Mask")
			(clearance 0.381)
			(thermal_gap 0.381)
		)
		(pad "" np_thru_hole circle
			(at 3.4671 1.27 270)
			(size 1.0414 1.0414)
			(drill 1.0414)
			(layers "*.Cu" "*.Mask")
			(clearance 0.381)
			(thermal_gap 0.381)
		)
		(pad "1" smd rect
			(at 0.8255 -0.249936 270)
			(size 0.3048 0.508)
			(layers "F.Cu" "F.Mask" "F.Paste")
			(net "85_5INCH_IN2_DP")
		)
		(pad "2" smd rect
			(at 0.8255 0.249936 270)
			(size 0.3048 0.508)
			(layers "F.Cu" "F.Mask" "F.Paste")
			(net "85_5INCH_IN2_DN")
		)
		(pad "3" smd circle
			(at 0 0)
			(size 0 0)
			(layers "F.Cu" "F.Mask" "F.Paste")
			(net "COUPON_GND2")
		)
		(zone
			(layer "F.Cu")
			(hatch none 0.5)
			(connect_pads
				(clearance 0)
			)
			(min_thickness 0.25)
			(keepout
				(tracks not_allowed)
				(vias allowed)
				(pads allowed)
				(copperpour not_allowed)
				(footprints allowed)
			)
			(placement
				(enabled no)
				(sheetname "")
			)
			(fill
				(thermal_gap 0.5)
				(thermal_bridge_width 0.5)
				(island_removal_mode 0)
			)
			(polygon
				(pts
					(xy 339.383624 17.486884) (xy 339.383624 17.582388) (xy 338.786724 17.582388) (xy 338.786724 17.988788)
					(xy 339.383624 17.988788) (xy 339.383624 18.08226) (xy 338.786724 18.08226) (xy 338.786724 18.48866)
					(xy 339.383624 18.48866) (xy 339.383624 18.584164) (xy 338.685124 18.584164) (xy 338.685124 17.486884)
				)
			)
		)
		(zone
			(layers "F.Cu" "B.Cu" "In1.Cu" "In2.Cu" "In3.Cu" "In4.Cu" "In5.Cu" "In6.Cu"
				"In7.Cu" "In8.Cu" "In9.Cu" "In10.Cu" "In11.Cu" "In12.Cu" "In13.Cu" "In14.Cu"
				"In15.Cu" "In16.Cu"
			)
			(hatch none 0.5)
			(connect_pads
				(clearance 0)
			)
			(min_thickness 0.25)
			(keepout
				(tracks not_allowed)
				(vias allowed)
				(pads allowed)
				(copperpour not_allowed)
				(footprints allowed)
			)
			(placement
				(enabled no)
				(sheetname "")
			)
			(fill
				(thermal_gap 0.5)
				(thermal_bridge_width 0.5)
				(island_removal_mode 0)
			)
			(polygon
				(pts
					(arc
						(start 336.310224 16.765524)
						(mid 334.456024 16.765524)
						(end 336.310224 16.765524)
					)
				)
			)
		)
		(zone
			(layers "F.Cu" "B.Cu" "In1.Cu" "In2.Cu" "In3.Cu" "In4.Cu" "In5.Cu" "In6.Cu"
				"In7.Cu" "In8.Cu" "In9.Cu" "In10.Cu" "In11.Cu" "In12.Cu" "In13.Cu" "In14.Cu"
				"In15.Cu" "In16.Cu"
			)
			(hatch none 0.5)
			(connect_pads
				(clearance 0)
			)
			(min_thickness 0.25)
			(keepout
				(tracks not_allowed)
				(vias allowed)
				(pads allowed)
				(copperpour not_allowed)
				(footprints allowed)
			)
			(placement
				(enabled no)
				(sheetname "")
			)
			(fill
				(thermal_gap 0.5)
				(thermal_bridge_width 0.5)
				(island_removal_mode 0)
			)
			(polygon
				(pts
					(arc
						(start 336.310224 19.305524)
						(mid 334.456024 19.305524)
						(end 336.310224 19.305524)
					)
				)
			)
		)
		(zone
			(layers "F.Cu" "B.Cu" "In1.Cu" "In2.Cu" "In3.Cu" "In4.Cu" "In5.Cu" "In6.Cu"
				"In7.Cu" "In8.Cu" "In9.Cu" "In10.Cu" "In11.Cu" "In12.Cu" "In13.Cu" "In14.Cu"
				"In15.Cu" "In16.Cu"
			)
			(hatch none 0.5)
			(connect_pads
				(clearance 0)
			)
			(min_thickness 0.25)
			(keepout
				(tracks not_allowed)
				(vias allowed)
				(pads allowed)
				(copperpour not_allowed)
				(footprints allowed)
			)
			(placement
				(enabled no)
				(sheetname "")
			)
			(fill
				(thermal_gap 0.5)
				(thermal_bridge_width 0.5)
				(island_removal_mode 0)
			)
			(polygon
				(pts
					(arc
						(start 342.660224 16.765524)
						(mid 340.806024 16.765524)
						(end 342.660224 16.765524)
					)
				)
			)
		)
		(zone
			(layers "F.Cu" "B.Cu" "In1.Cu" "In2.Cu" "In3.Cu" "In4.Cu" "In5.Cu" "In6.Cu"
				"In7.Cu" "In8.Cu" "In9.Cu" "In10.Cu" "In11.Cu" "In12.Cu" "In13.Cu" "In14.Cu"
				"In15.Cu" "In16.Cu"
			)
			(hatch none 0.5)
			(connect_pads
				(clearance 0)
			)
			(min_thickness 0.25)
			(keepout
				(tracks not_allowed)
				(vias allowed)
				(pads allowed)
				(copperpour not_allowed)
				(footprints allowed)
			)
			(placement
				(enabled no)
				(sheetname "")
			)
			(fill
				(thermal_gap 0.5)
				(thermal_bridge_width 0.5)
				(island_removal_mode 0)
			)
			(polygon
				(pts
					(arc
						(start 342.660224 19.305524)
						(mid 340.806024 19.305524)
						(end 342.660224 19.305524)
					)
				)
			)
		)
	)
	(footprint ""
		(layer "F.Cu")
		(at 147.554442 -250.070874 -90)
		(property "Reference" "R1273"
			(at 0 0 270)
			(layer "F.SilkS")
			(hide yes)
			(effects
				(font
					(size 1.27 1.27)
				)
			)
		)
		(property "Value" ""
			(at 0 0 270)
			(layer "F.Fab")
			(effects
				(font
					(size 1.27 1.27)
				)
			)
		)
		(duplicate_pad_numbers_are_jumpers no)
		(fp_line
			(start -0.7874 0.4064)
			(end -0.7874 -0.4064)
			(stroke
				(width 0.1524)
				(type default)
			)
			(layer "F.SilkS")
		)
		(fp_line
			(start 0.7874 0.4064)
			(end -0.7874 0.4064)
			(stroke
				(width 0.1524)
				(type default)
			)
			(layer "F.SilkS")
		)
		(fp_line
			(start -0.7874 -0.4064)
			(end 0.7874 -0.4064)
			(stroke
				(width 0.1524)
				(type default)
			)
			(layer "F.SilkS")
		)
		(fp_line
			(start 0.7874 -0.4064)
			(end 0.7874 0.4064)
			(stroke
				(width 0.1524)
				(type default)
			)
			(layer "F.SilkS")
		)
		(fp_line
			(start -0.67945 0.3048)
			(end -0.67945 -0.305054)
			(stroke
				(width 0.1)
				(type default)
			)
			(layer "F.Fab")
		)
		(fp_line
			(start -0.12065 0.3048)
			(end -0.67945 0.3048)
			(stroke
				(width 0.1)
				(type default)
			)
			(layer "F.Fab")
		)
		(fp_line
			(start 0.120396 0.3048)
			(end 0.120396 0.2794)
			(stroke
				(width 0.1)
				(type default)
			)
			(layer "F.Fab")
		)
		(fp_line
			(start 0.67945 0.3048)
			(end 0.120396 0.3048)
			(stroke
				(width 0.1)
				(type default)
			)
			(layer "F.Fab")
		)
		(fp_line
			(start -0.12065 0.2794)
			(end -0.12065 0.3048)
			(stroke
				(width 0.1)
				(type default)
			)
			(layer "F.Fab")
		)
		(fp_line
			(start 0.120396 0.2794)
			(end -0.12065 0.2794)
			(stroke
				(width 0.1)
				(type default)
			)
			(layer "F.Fab")
		)
		(fp_line
			(start -0.12065 -0.2794)
			(end 0.12065 -0.2794)
			(stroke
				(width 0.1)
				(type default)
			)
			(layer "F.Fab")
		)
		(fp_line
			(start 0.12065 -0.2794)
			(end 0.12065 -0.3048)
			(stroke
				(width 0.1)
				(type default)
			)
			(layer "F.Fab")
		)
		(fp_line
			(start 0.12065 -0.3048)
			(end 0.67945 -0.3048)
			(stroke
				(width 0.1)
				(type default)
			)
			(layer "F.Fab")
		)
		(fp_line
			(start 0.67945 -0.3048)
			(end 0.67945 0.3048)
			(stroke
				(width 0.1)
				(type default)
			)
			(layer "F.Fab")
		)
		(fp_line
			(start -0.67945 -0.305054)
			(end -0.12065 -0.305054)
			(stroke
				(width 0.1)
				(type default)
			)
			(layer "F.Fab")
		)
		(fp_line
			(start -0.12065 -0.305054)
			(end -0.12065 -0.2794)
			(stroke
				(width 0.1)
				(type default)
			)
			(layer "F.Fab")
		)
		(pad "1" smd circle
			(at -0.40005 0 270)
			(size 0 0)
			(layers "F.Cu" "F.Mask" "F.Paste")
			(net "PEX1_MODE_SEL4")
		)
		(pad "2" smd circle
			(at 0.40005 0 270)
			(size 0 0)
			(layers "F.Cu" "F.Mask" "F.Paste")
			(net "P1V8_PEX")
		)
	)
	(footprint ""
		(layer "F.Cu")
		(at 368.096292 -47.20082 90)
		(property "Reference" "C334"
			(at 0 0 90)
			(layer "F.SilkS")
			(hide yes)
			(effects
				(font
					(size 1.27 1.27)
				)
			)
		)
		(property "Value" ""
			(at 0 0 90)
			(layer "F.Fab")
			(effects
				(font
					(size 1.27 1.27)
				)
			)
		)
		(duplicate_pad_numbers_are_jumpers no)
		(fp_line
			(start 0.7874 -0.4064)
			(end 0.7874 0.4064)
			(stroke
				(width 0.1524)
				(type default)
			)
			(layer "F.SilkS")
		)
		(fp_line
			(start -0.7874 -0.4064)
			(end 0.7874 -0.4064)
			(stroke
				(width 0.1524)
				(type default)
			)
			(layer "F.SilkS")
		)
		(fp_line
			(start 0.7874 0.4064)
			(end -0.7874 0.4064)
			(stroke
				(width 0.1524)
				(type default)
			)
			(layer "F.SilkS")
		)
		(fp_line
			(start -0.7874 0.4064)
			(end -0.7874 -0.4064)
			(stroke
				(width 0.1524)
				(type default)
			)
			(layer "F.SilkS")
		)
		(fp_line
			(start -0.12065 -0.305054)
			(end -0.12065 -0.2794)
			(stroke
				(width 0.1)
				(type default)
			)
			(layer "F.Fab")
		)
		(fp_line
			(start -0.67945 -0.305054)
			(end -0.12065 -0.305054)
			(stroke
				(width 0.1)
				(type default)
			)
			(layer "F.Fab")
		)
		(fp_line
			(start 0.67945 -0.3048)
			(end 0.67945 0.3048)
			(stroke
				(width 0.1)
				(type default)
			)
			(layer "F.Fab")
		)
		(fp_line
			(start 0.12065 -0.3048)
			(end 0.67945 -0.3048)
			(stroke
				(width 0.1)
				(type default)
			)
			(layer "F.Fab")
		)
		(fp_line
			(start 0.12065 -0.2794)
			(end 0.12065 -0.3048)
			(stroke
				(width 0.1)
				(type default)
			)
			(layer "F.Fab")
		)
		(fp_line
			(start -0.12065 -0.2794)
			(end 0.12065 -0.2794)
			(stroke
				(width 0.1)
				(type default)
			)
			(layer "F.Fab")
		)
		(fp_line
			(start 0.120396 0.2794)
			(end -0.12065 0.2794)
			(stroke
				(width 0.1)
				(type default)
			)
			(layer "F.Fab")
		)
		(fp_line
			(start -0.12065 0.2794)
			(end -0.12065 0.3048)
			(stroke
				(width 0.1)
				(type default)
			)
			(layer "F.Fab")
		)
		(fp_line
			(start 0.67945 0.3048)
			(end 0.120396 0.3048)
			(stroke
				(width 0.1)
				(type default)
			)
			(layer "F.Fab")
		)
		(fp_line
			(start 0.120396 0.3048)
			(end 0.120396 0.2794)
			(stroke
				(width 0.1)
				(type default)
			)
			(layer "F.Fab")
		)
		(fp_line
			(start -0.12065 0.3048)
			(end -0.67945 0.3048)
			(stroke
				(width 0.1)
				(type default)
			)
			(layer "F.Fab")
		)
		(fp_line
			(start -0.67945 0.3048)
			(end -0.67945 -0.305054)
			(stroke
				(width 0.1)
				(type default)
			)
			(layer "F.Fab")
		)
		(pad "1" smd circle
			(at -0.40005 0 90)
			(size 0 0)
			(layers "F.Cu" "F.Mask" "F.Paste")
			(net "P12V_SSD12_R")
		)
		(pad "2" smd circle
			(at 0.40005 0 90)
			(size 0 0)
			(layers "F.Cu" "F.Mask" "F.Paste")
			(net "GND")
		)
	)
	(footprint ""
		(layer "F.Cu")
		(at 374.705372 -258.582922 90)
		(property "Reference" "L145"
			(at 0 0 90)
			(layer "F.SilkS")
			(hide yes)
			(effects
				(font
					(size 1.27 1.27)
				)
			)
		)
		(property "Value" ""
			(at 0 0 90)
			(layer "F.Fab")
			(effects
				(font
					(size 1.27 1.27)
				)
			)
		)
		(duplicate_pad_numbers_are_jumpers no)
		(fp_line
			(start 1.63576 -0.8128)
			(end 1.63576 0.8128)
			(stroke
				(width 0.1524)
				(type default)
			)
			(layer "F.SilkS")
		)
		(fp_line
			(start -1.63576 -0.8128)
			(end 1.63576 -0.8128)
			(stroke
				(width 0.1524)
				(type default)
			)
			(layer "F.SilkS")
		)
		(fp_line
			(start -1.63576 -0.8128)
			(end -1.63576 0.8128)
			(stroke
				(width 0.1524)
				(type default)
			)
			(layer "F.SilkS")
		)
		(fp_line
			(start 1.63576 0.8128)
			(end -1.63576 0.8128)
			(stroke
				(width 0.1524)
				(type default)
			)
			(layer "F.SilkS")
		)
		(fp_line
			(start 1.560576 -0.738632)
			(end -1.56083 -0.738632)
			(stroke
				(width 0.1)
				(type default)
			)
			(layer "F.Fab")
		)
		(fp_line
			(start -1.56083 -0.738632)
			(end -1.56083 0.7366)
			(stroke
				(width 0.1)
				(type default)
			)
			(layer "F.Fab")
		)
		(fp_line
			(start 1.560576 0.7366)
			(end 1.560576 -0.738632)
			(stroke
				(width 0.1)
				(type default)
			)
			(layer "F.Fab")
		)
		(fp_line
			(start 1.524 0.7366)
			(end 1.560576 0.7366)
			(stroke
				(width 0.1)
				(type default)
			)
			(layer "F.Fab")
		)
		(fp_line
			(start -1.524 0.7366)
			(end 1.524 0.7366)
			(stroke
				(width 0.1)
				(type default)
			)
			(layer "F.Fab")
		)
		(fp_line
			(start -1.56083 0.7366)
			(end -1.524 0.7366)
			(stroke
				(width 0.1)
				(type default)
			)
			(layer "F.Fab")
		)
		(pad "1" smd rect
			(at -0.94996 0 270)
			(size 1.1176 1.3716)
			(layers "F.Cu" "F.Mask" "F.Paste")
			(net "P1V8_PLL0_PEX3")
		)
		(pad "2" smd rect
			(at 0.94996 0 270)
			(size 1.1176 1.3716)
			(layers "F.Cu" "F.Mask" "F.Paste")
			(net "P1V8_VDDA_PEX3")
		)
	)
	(footprint ""
		(layer "F.Cu")
		(at 457.726034 -305.241706)
		(property "Reference" "PC271"
			(at 0 0 0)
			(layer "F.SilkS")
			(hide yes)
			(effects
				(font
					(size 1.27 1.27)
				)
			)
		)
		(property "Value" ""
			(at 0 0 0)
			(layer "F.Fab")
			(effects
				(font
					(size 1.27 1.27)
				)
			)
		)
		(duplicate_pad_numbers_are_jumpers no)
		(fp_line
			(start -0.7874 -0.4064)
			(end 0.7874 -0.4064)
			(stroke
				(width 0.1524)
				(type default)
			)
			(layer "F.SilkS")
		)
		(fp_line
			(start -0.7874 0.4064)
			(end -0.7874 -0.4064)
			(stroke
				(width 0.1524)
				(type default)
			)
			(layer "F.SilkS")
		)
		(fp_line
			(start 0.7874 -0.4064)
			(end 0.7874 0.4064)
			(stroke
				(width 0.1524)
				(type default)
			)
			(layer "F.SilkS")
		)
		(fp_line
			(start 0.7874 0.4064)
			(end -0.7874 0.4064)
			(stroke
				(width 0.1524)
				(type default)
			)
			(layer "F.SilkS")
		)
		(fp_line
			(start -0.67945 -0.305054)
			(end -0.12065 -0.305054)
			(stroke
				(width 0.1)
				(type default)
			)
			(layer "F.Fab")
		)
		(fp_line
			(start -0.67945 0.3048)
			(end -0.67945 -0.305054)
			(stroke
				(width 0.1)
				(type default)
			)
			(layer "F.Fab")
		)
		(fp_line
			(start -0.12065 -0.305054)
			(end -0.12065 -0.2794)
			(stroke
				(width 0.1)
				(type default)
			)
			(layer "F.Fab")
		)
		(fp_line
			(start -0.12065 -0.2794)
			(end 0.12065 -0.2794)
			(stroke
				(width 0.1)
				(type default)
			)
			(layer "F.Fab")
		)
		(fp_line
			(start -0.12065 0.2794)
			(end -0.12065 0.3048)
			(stroke
				(width 0.1)
				(type default)
			)
			(layer "F.Fab")
		)
		(fp_line
			(start -0.12065 0.3048)
			(end -0.67945 0.3048)
			(stroke
				(width 0.1)
				(type default)
			)
			(layer "F.Fab")
		)
		(fp_line
			(start 0.120396 0.2794)
			(end -0.12065 0.2794)
			(stroke
				(width 0.1)
				(type default)
			)
			(layer "F.Fab")
		)
		(fp_line
			(start 0.120396 0.3048)
			(end 0.120396 0.2794)
			(stroke
				(width 0.1)
				(type default)
			)
			(layer "F.Fab")
		)
		(fp_line
			(start 0.12065 -0.3048)
			(end 0.67945 -0.3048)
			(stroke
				(width 0.1)
				(type default)
			)
			(layer "F.Fab")
		)
		(fp_line
			(start 0.12065 -0.2794)
			(end 0.12065 -0.3048)
			(stroke
				(width 0.1)
				(type default)
			)
			(layer "F.Fab")
		)
		(fp_line
			(start 0.67945 -0.3048)
			(end 0.67945 0.3048)
			(stroke
				(width 0.1)
				(type default)
			)
			(layer "F.Fab")
		)
		(fp_line
			(start 0.67945 0.3048)
			(end 0.120396 0.3048)
			(stroke
				(width 0.1)
				(type default)
			)
			(layer "F.Fab")
		)
		(pad "1" smd circle
			(at -0.40005 0)
			(size 0 0)
			(layers "F.Cu" "F.Mask" "F.Paste")
			(net "SW_P1V25_PEX3_BT")
		)
		(pad "2" smd circle
			(at 0.40005 0)
			(size 0 0)
			(layers "F.Cu" "F.Mask" "F.Paste")
			(net "SW_P1V25_PEX3_PH")
		)
	)
	(footprint ""
		(layer "F.Cu")
		(at 358.013 -220.472 180)
		(property "Reference" "R3648"
			(at 0 0 180)
			(layer "F.SilkS")
			(hide yes)
			(effects
				(font
					(size 1.27 1.27)
				)
			)
		)
		(property "Value" ""
			(at 0 0 180)
			(layer "F.Fab")
			(effects
				(font
					(size 1.27 1.27)
				)
			)
		)
		(duplicate_pad_numbers_are_jumpers no)
		(fp_line
			(start 0.7874 0.4064)
			(end -0.7874 0.4064)
			(stroke
				(width 0.1524)
				(type default)
			)
			(layer "F.SilkS")
		)
		(fp_line
			(start 0.7874 -0.4064)
			(end 0.7874 0.4064)
			(stroke
				(width 0.1524)
				(type default)
			)
			(layer "F.SilkS")
		)
		(fp_line
			(start -0.7874 0.4064)
			(end -0.7874 -0.4064)
			(stroke
				(width 0.1524)
				(type default)
			)
			(layer "F.SilkS")
		)
		(fp_line
			(start -0.7874 -0.4064)
			(end 0.7874 -0.4064)
			(stroke
				(width 0.1524)
				(type default)
			)
			(layer "F.SilkS")
		)
		(fp_line
			(start 0.67945 0.3048)
			(end 0.120396 0.3048)
			(stroke
				(width 0.1)
				(type default)
			)
			(layer "F.Fab")
		)
		(fp_line
			(start 0.67945 -0.3048)
			(end 0.67945 0.3048)
			(stroke
				(width 0.1)
				(type default)
			)
			(layer "F.Fab")
		)
		(fp_line
			(start 0.12065 -0.2794)
			(end 0.12065 -0.3048)
			(stroke
				(width 0.1)
				(type default)
			)
			(layer "F.Fab")
		)
		(fp_line
			(start 0.12065 -0.3048)
			(end 0.67945 -0.3048)
			(stroke
				(width 0.1)
				(type default)
			)
			(layer "F.Fab")
		)
		(fp_line
			(start 0.120396 0.3048)
			(end 0.120396 0.2794)
			(stroke
				(width 0.1)
				(type default)
			)
			(layer "F.Fab")
		)
		(fp_line
			(start 0.120396 0.2794)
			(end -0.12065 0.2794)
			(stroke
				(width 0.1)
				(type default)
			)
			(layer "F.Fab")
		)
		(fp_line
			(start -0.12065 0.3048)
			(end -0.67945 0.3048)
			(stroke
				(width 0.1)
				(type default)
			)
			(layer "F.Fab")
		)
		(fp_line
			(start -0.12065 0.2794)
			(end -0.12065 0.3048)
			(stroke
				(width 0.1)
				(type default)
			)
			(layer "F.Fab")
		)
		(fp_line
			(start -0.12065 -0.2794)
			(end 0.12065 -0.2794)
			(stroke
				(width 0.1)
				(type default)
			)
			(layer "F.Fab")
		)
		(fp_line
			(start -0.12065 -0.305054)
			(end -0.12065 -0.2794)
			(stroke
				(width 0.1)
				(type default)
			)
			(layer "F.Fab")
		)
		(fp_line
			(start -0.67945 0.3048)
			(end -0.67945 -0.305054)
			(stroke
				(width 0.1)
				(type default)
			)
			(layer "F.Fab")
		)
		(fp_line
			(start -0.67945 -0.305054)
			(end -0.12065 -0.305054)
			(stroke
				(width 0.1)
				(type default)
			)
			(layer "F.Fab")
		)
		(pad "1" smd circle
			(at -0.40005 0 180)
			(size 0 0)
			(layers "F.Cu" "F.Mask" "F.Paste")
			(net "NIC5_CLK_EN_R_N")
		)
		(pad "2" smd circle
			(at 0.40005 0 180)
			(size 0 0)
			(layers "F.Cu" "F.Mask" "F.Paste")
			(net "NIC5_CLK_EN_N")
		)
	)
	(footprint ""
		(layer "F.Cu")
		(at 353.247452 -36.686998 90)
		(property "Reference" "C3672"
			(at 0 0 90)
			(layer "F.SilkS")
			(hide yes)
			(effects
				(font
					(size 1.27 1.27)
				)
			)
		)
		(property "Value" ""
			(at 0 0 90)
			(layer "F.Fab")
			(effects
				(font
					(size 1.27 1.27)
				)
			)
		)
		(duplicate_pad_numbers_are_jumpers no)
		(fp_line
			(start 0.7874 -0.4064)
			(end 0.7874 0.4064)
			(stroke
				(width 0.1524)
				(type default)
			)
			(layer "F.SilkS")
		)
		(fp_line
			(start -0.7874 -0.4064)
			(end 0.7874 -0.4064)
			(stroke
				(width 0.1524)
				(type default)
			)
			(layer "F.SilkS")
		)
		(fp_line
			(start 0.7874 0.4064)
			(end -0.7874 0.4064)
			(stroke
				(width 0.1524)
				(type default)
			)
			(layer "F.SilkS")
		)
		(fp_line
			(start -0.7874 0.4064)
			(end -0.7874 -0.4064)
			(stroke
				(width 0.1524)
				(type default)
			)
			(layer "F.SilkS")
		)
		(fp_line
			(start -0.12065 -0.305054)
			(end -0.12065 -0.2794)
			(stroke
				(width 0.1)
				(type default)
			)
			(layer "F.Fab")
		)
		(fp_line
			(start -0.67945 -0.305054)
			(end -0.12065 -0.305054)
			(stroke
				(width 0.1)
				(type default)
			)
			(layer "F.Fab")
		)
		(fp_line
			(start 0.67945 -0.3048)
			(end 0.67945 0.3048)
			(stroke
				(width 0.1)
				(type default)
			)
			(layer "F.Fab")
		)
		(fp_line
			(start 0.12065 -0.3048)
			(end 0.67945 -0.3048)
			(stroke
				(width 0.1)
				(type default)
			)
			(layer "F.Fab")
		)
		(fp_line
			(start 0.12065 -0.2794)
			(end 0.12065 -0.3048)
			(stroke
				(width 0.1)
				(type default)
			)
			(layer "F.Fab")
		)
		(fp_line
			(start -0.12065 -0.2794)
			(end 0.12065 -0.2794)
			(stroke
				(width 0.1)
				(type default)
			)
			(layer "F.Fab")
		)
		(fp_line
			(start 0.120396 0.2794)
			(end -0.12065 0.2794)
			(stroke
				(width 0.1)
				(type default)
			)
			(layer "F.Fab")
		)
		(fp_line
			(start -0.12065 0.2794)
			(end -0.12065 0.3048)
			(stroke
				(width 0.1)
				(type default)
			)
			(layer "F.Fab")
		)
		(fp_line
			(start 0.67945 0.3048)
			(end 0.120396 0.3048)
			(stroke
				(width 0.1)
				(type default)
			)
			(layer "F.Fab")
		)
		(fp_line
			(start 0.120396 0.3048)
			(end 0.120396 0.2794)
			(stroke
				(width 0.1)
				(type default)
			)
			(layer "F.Fab")
		)
		(fp_line
			(start -0.12065 0.3048)
			(end -0.67945 0.3048)
			(stroke
				(width 0.1)
				(type default)
			)
			(layer "F.Fab")
		)
		(fp_line
			(start -0.67945 0.3048)
			(end -0.67945 -0.305054)
			(stroke
				(width 0.1)
				(type default)
			)
			(layer "F.Fab")
		)
		(pad "1" smd circle
			(at -0.40005 0 90)
			(size 0 0)
			(layers "F.Cu" "F.Mask" "F.Paste")
			(net "P3V3_AUX")
		)
		(pad "2" smd circle
			(at 0.40005 0 90)
			(size 0 0)
			(layers "F.Cu" "F.Mask" "F.Paste")
			(net "GND")
		)
	)
	(footprint ""
		(layer "F.Cu")
		(at 259.152644 -262.649208 90)
		(property "Reference" "C3412"
			(at 0 0 90)
			(layer "F.SilkS")
			(hide yes)
			(effects
				(font
					(size 1.27 1.27)
				)
			)
		)
		(property "Value" ""
			(at 0 0 90)
			(layer "F.Fab")
			(effects
				(font
					(size 1.27 1.27)
				)
			)
		)
		(duplicate_pad_numbers_are_jumpers no)
		(fp_line
			(start 0.299974 -0.150114)
			(end 0.299974 0.150114)
			(stroke
				(width 0.1)
				(type default)
			)
			(layer "F.Fab")
		)
		(fp_line
			(start -0.299974 -0.150114)
			(end 0.299974 -0.150114)
			(stroke
				(width 0.1)
				(type default)
			)
			(layer "F.Fab")
		)
		(fp_line
			(start 0.299974 0.150114)
			(end -0.299974 0.150114)
			(stroke
				(width 0.1)
				(type default)
			)
			(layer "F.Fab")
		)
		(fp_line
			(start -0.299974 0.150114)
			(end -0.299974 -0.150114)
			(stroke
				(width 0.1)
				(type default)
			)
			(layer "F.Fab")
		)
		(pad "1" smd rect
			(at -0.2667 0 90)
			(size 0.3048 0.381)
			(layers "F.Cu" "F.Mask" "F.Paste")
			(net "P1V8_PLL0_PEX2")
		)
		(pad "2" smd rect
			(at 0.2667 0 90)
			(size 0.3048 0.381)
			(layers "F.Cu" "F.Mask" "F.Paste")
			(net "GND")
		)
	)
	(footprint ""
		(layer "F.Cu")
		(at 334.315308 -42.853102 180)
		(property "Reference" "R5902"
			(at 0 0 180)
			(layer "F.SilkS")
			(hide yes)
			(effects
				(font
					(size 1.27 1.27)
				)
			)
		)
		(property "Value" ""
			(at 0 0 180)
			(layer "F.Fab")
			(effects
				(font
					(size 1.27 1.27)
				)
			)
		)
		(duplicate_pad_numbers_are_jumpers no)
		(fp_line
			(start 0.7874 0.4064)
			(end -0.7874 0.4064)
			(stroke
				(width 0.1524)
				(type default)
			)
			(layer "F.SilkS")
		)
		(fp_line
			(start 0.7874 -0.4064)
			(end 0.7874 0.4064)
			(stroke
				(width 0.1524)
				(type default)
			)
			(layer "F.SilkS")
		)
		(fp_line
			(start -0.7874 0.4064)
			(end -0.7874 -0.4064)
			(stroke
				(width 0.1524)
				(type default)
			)
			(layer "F.SilkS")
		)
		(fp_line
			(start -0.7874 -0.4064)
			(end 0.7874 -0.4064)
			(stroke
				(width 0.1524)
				(type default)
			)
			(layer "F.SilkS")
		)
		(fp_line
			(start 0.67945 0.3048)
			(end 0.120396 0.3048)
			(stroke
				(width 0.1)
				(type default)
			)
			(layer "F.Fab")
		)
		(fp_line
			(start 0.67945 -0.3048)
			(end 0.67945 0.3048)
			(stroke
				(width 0.1)
				(type default)
			)
			(layer "F.Fab")
		)
		(fp_line
			(start 0.12065 -0.2794)
			(end 0.12065 -0.3048)
			(stroke
				(width 0.1)
				(type default)
			)
			(layer "F.Fab")
		)
		(fp_line
			(start 0.12065 -0.3048)
			(end 0.67945 -0.3048)
			(stroke
				(width 0.1)
				(type default)
			)
			(layer "F.Fab")
		)
		(fp_line
			(start 0.120396 0.3048)
			(end 0.120396 0.2794)
			(stroke
				(width 0.1)
				(type default)
			)
			(layer "F.Fab")
		)
		(fp_line
			(start 0.120396 0.2794)
			(end -0.12065 0.2794)
			(stroke
				(width 0.1)
				(type default)
			)
			(layer "F.Fab")
		)
		(fp_line
			(start -0.12065 0.3048)
			(end -0.67945 0.3048)
			(stroke
				(width 0.1)
				(type default)
			)
			(layer "F.Fab")
		)
		(fp_line
			(start -0.12065 0.2794)
			(end -0.12065 0.3048)
			(stroke
				(width 0.1)
				(type default)
			)
			(layer "F.Fab")
		)
		(fp_line
			(start -0.12065 -0.2794)
			(end 0.12065 -0.2794)
			(stroke
				(width 0.1)
				(type default)
			)
			(layer "F.Fab")
		)
		(fp_line
			(start -0.12065 -0.305054)
			(end -0.12065 -0.2794)
			(stroke
				(width 0.1)
				(type default)
			)
			(layer "F.Fab")
		)
		(fp_line
			(start -0.67945 0.3048)
			(end -0.67945 -0.305054)
			(stroke
				(width 0.1)
				(type default)
			)
			(layer "F.Fab")
		)
		(fp_line
			(start -0.67945 -0.305054)
			(end -0.12065 -0.305054)
			(stroke
				(width 0.1)
				(type default)
			)
			(layer "F.Fab")
		)
		(pad "1" smd circle
			(at -0.40005 0 180)
			(size 0 0)
			(layers "F.Cu" "F.Mask" "F.Paste")
			(net "SSD11_ADC_A1")
		)
		(pad "2" smd circle
			(at 0.40005 0 180)
			(size 0 0)
			(layers "F.Cu" "F.Mask" "F.Paste")
			(net "SMB_SSD11_ADC_SDA")
		)
	)
	(footprint ""
		(layer "F.Cu")
		(at 217.235786 -222.366586 180)
		(property "Reference" "R1491"
			(at 0 0 180)
			(layer "F.SilkS")
			(hide yes)
			(effects
				(font
					(size 1.27 1.27)
				)
			)
		)
		(property "Value" ""
			(at 0 0 180)
			(layer "F.Fab")
			(effects
				(font
					(size 1.27 1.27)
				)
			)
		)
		(duplicate_pad_numbers_are_jumpers no)
		(fp_line
			(start 0.7874 0.4064)
			(end -0.7874 0.4064)
			(stroke
				(width 0.1524)
				(type default)
			)
			(layer "F.SilkS")
		)
		(fp_line
			(start 0.7874 -0.4064)
			(end 0.7874 0.4064)
			(stroke
				(width 0.1524)
				(type default)
			)
			(layer "F.SilkS")
		)
		(fp_line
			(start -0.7874 0.4064)
			(end -0.7874 -0.4064)
			(stroke
				(width 0.1524)
				(type default)
			)
			(layer "F.SilkS")
		)
		(fp_line
			(start -0.7874 -0.4064)
			(end 0.7874 -0.4064)
			(stroke
				(width 0.1524)
				(type default)
			)
			(layer "F.SilkS")
		)
		(fp_line
			(start 0.67945 0.3048)
			(end 0.120396 0.3048)
			(stroke
				(width 0.1)
				(type default)
			)
			(layer "F.Fab")
		)
		(fp_line
			(start 0.67945 -0.3048)
			(end 0.67945 0.3048)
			(stroke
				(width 0.1)
				(type default)
			)
			(layer "F.Fab")
		)
		(fp_line
			(start 0.12065 -0.2794)
			(end 0.12065 -0.3048)
			(stroke
				(width 0.1)
				(type default)
			)
			(layer "F.Fab")
		)
		(fp_line
			(start 0.12065 -0.3048)
			(end 0.67945 -0.3048)
			(stroke
				(width 0.1)
				(type default)
			)
			(layer "F.Fab")
		)
		(fp_line
			(start 0.120396 0.3048)
			(end 0.120396 0.2794)
			(stroke
				(width 0.1)
				(type default)
			)
			(layer "F.Fab")
		)
		(fp_line
			(start 0.120396 0.2794)
			(end -0.12065 0.2794)
			(stroke
				(width 0.1)
				(type default)
			)
			(layer "F.Fab")
		)
		(fp_line
			(start -0.12065 0.3048)
			(end -0.67945 0.3048)
			(stroke
				(width 0.1)
				(type default)
			)
			(layer "F.Fab")
		)
		(fp_line
			(start -0.12065 0.2794)
			(end -0.12065 0.3048)
			(stroke
				(width 0.1)
				(type default)
			)
			(layer "F.Fab")
		)
		(fp_line
			(start -0.12065 -0.2794)
			(end 0.12065 -0.2794)
			(stroke
				(width 0.1)
				(type default)
			)
			(layer "F.Fab")
		)
		(fp_line
			(start -0.12065 -0.305054)
			(end -0.12065 -0.2794)
			(stroke
				(width 0.1)
				(type default)
			)
			(layer "F.Fab")
		)
		(fp_line
			(start -0.67945 0.3048)
			(end -0.67945 -0.305054)
			(stroke
				(width 0.1)
				(type default)
			)
			(layer "F.Fab")
		)
		(fp_line
			(start -0.67945 -0.305054)
			(end -0.12065 -0.305054)
			(stroke
				(width 0.1)
				(type default)
			)
			(layer "F.Fab")
		)
		(pad "1" smd circle
			(at -0.40005 0 180)
			(size 0 0)
			(layers "F.Cu" "F.Mask" "F.Paste")
			(net "SMB_BIC_I2C9_SSD_MUX_SCL")
		)
		(pad "2" smd circle
			(at 0.40005 0 180)
			(size 0 0)
			(layers "F.Cu" "F.Mask" "F.Paste")
			(net "SMB_BIC_I2C9_SSD_MUX_R_SCL")
		)
	)
	(footprint ""
		(layer "F.Cu")
		(at 132.352796 -159.173418 90)
		(property "Reference" "PC619"
			(at 0 0 90)
			(layer "F.SilkS")
			(hide yes)
			(effects
				(font
					(size 1.27 1.27)
				)
			)
		)
		(property "Value" ""
			(at 0 0 90)
			(layer "F.Fab")
			(effects
				(font
					(size 1.27 1.27)
				)
			)
		)
		(duplicate_pad_numbers_are_jumpers no)
		(fp_line
			(start 0.7874 -0.4064)
			(end 0.7874 0.4064)
			(stroke
				(width 0.1524)
				(type default)
			)
			(layer "F.SilkS")
		)
		(fp_line
			(start -0.7874 -0.4064)
			(end 0.7874 -0.4064)
			(stroke
				(width 0.1524)
				(type default)
			)
			(layer "F.SilkS")
		)
		(fp_line
			(start 0.7874 0.4064)
			(end -0.7874 0.4064)
			(stroke
				(width 0.1524)
				(type default)
			)
			(layer "F.SilkS")
		)
		(fp_line
			(start -0.7874 0.4064)
			(end -0.7874 -0.4064)
			(stroke
				(width 0.1524)
				(type default)
			)
			(layer "F.SilkS")
		)
		(fp_line
			(start -0.12065 -0.305054)
			(end -0.12065 -0.2794)
			(stroke
				(width 0.1)
				(type default)
			)
			(layer "F.Fab")
		)
		(fp_line
			(start -0.67945 -0.305054)
			(end -0.12065 -0.305054)
			(stroke
				(width 0.1)
				(type default)
			)
			(layer "F.Fab")
		)
		(fp_line
			(start 0.67945 -0.3048)
			(end 0.67945 0.3048)
			(stroke
				(width 0.1)
				(type default)
			)
			(layer "F.Fab")
		)
		(fp_line
			(start 0.12065 -0.3048)
			(end 0.67945 -0.3048)
			(stroke
				(width 0.1)
				(type default)
			)
			(layer "F.Fab")
		)
		(fp_line
			(start 0.12065 -0.2794)
			(end 0.12065 -0.3048)
			(stroke
				(width 0.1)
				(type default)
			)
			(layer "F.Fab")
		)
		(fp_line
			(start -0.12065 -0.2794)
			(end 0.12065 -0.2794)
			(stroke
				(width 0.1)
				(type default)
			)
			(layer "F.Fab")
		)
		(fp_line
			(start 0.120396 0.2794)
			(end -0.12065 0.2794)
			(stroke
				(width 0.1)
				(type default)
			)
			(layer "F.Fab")
		)
		(fp_line
			(start -0.12065 0.2794)
			(end -0.12065 0.3048)
			(stroke
				(width 0.1)
				(type default)
			)
			(layer "F.Fab")
		)
		(fp_line
			(start 0.67945 0.3048)
			(end 0.120396 0.3048)
			(stroke
				(width 0.1)
				(type default)
			)
			(layer "F.Fab")
		)
		(fp_line
			(start 0.120396 0.3048)
			(end 0.120396 0.2794)
			(stroke
				(width 0.1)
				(type default)
			)
			(layer "F.Fab")
		)
		(fp_line
			(start -0.12065 0.3048)
			(end -0.67945 0.3048)
			(stroke
				(width 0.1)
				(type default)
			)
			(layer "F.Fab")
		)
		(fp_line
			(start -0.67945 0.3048)
			(end -0.67945 -0.305054)
			(stroke
				(width 0.1)
				(type default)
			)
			(layer "F.Fab")
		)
		(pad "1" smd circle
			(at -0.40005 0 90)
			(size 0 0)
			(layers "F.Cu" "F.Mask" "F.Paste")
			(net "P12V_AUX")
		)
		(pad "2" smd circle
			(at 0.40005 0 90)
			(size 0 0)
			(layers "F.Cu" "F.Mask" "F.Paste")
			(net "GND")
		)
	)
	(footprint ""
		(layer "F.Cu")
		(at 353.95027 -50.96383 180)
		(property "Reference" "PC551"
			(at 0 0 180)
			(layer "F.SilkS")
			(hide yes)
			(effects
				(font
					(size 1.27 1.27)
				)
			)
		)
		(property "Value" ""
			(at 0 0 180)
			(layer "F.Fab")
			(effects
				(font
					(size 1.27 1.27)
				)
			)
		)
		(duplicate_pad_numbers_are_jumpers no)
		(fp_line
			(start 1.524 0.762)
			(end -1.524 0.762)
			(stroke
				(width 0.1524)
				(type default)
			)
			(layer "F.SilkS")
		)
		(fp_line
			(start 1.524 -0.762)
			(end 1.524 0.762)
			(stroke
				(width 0.1524)
				(type default)
			)
			(layer "F.SilkS")
		)
		(fp_line
			(start -1.524 0.762)
			(end -1.524 -0.762)
			(stroke
				(width 0.1524)
				(type default)
			)
			(layer "F.SilkS")
		)
		(fp_line
			(start -1.524 -0.762)
			(end 1.524 -0.762)
			(stroke
				(width 0.1524)
				(type default)
			)
			(layer "F.SilkS")
		)
		(fp_line
			(start 1.1049 0.724916)
			(end 1.1049 -0.724916)
			(stroke
				(width 0.1)
				(type default)
			)
			(layer "F.Fab")
		)
		(fp_line
			(start 1.1049 -0.724916)
			(end -1.1049 -0.724916)
			(stroke
				(width 0.1)
				(type default)
			)
			(layer "F.Fab")
		)
		(fp_line
			(start -1.1049 0.724916)
			(end 1.1049 0.724916)
			(stroke
				(width 0.1)
				(type default)
			)
			(layer "F.Fab")
		)
		(fp_line
			(start -1.1049 -0.724916)
			(end -1.1049 0.724916)
			(stroke
				(width 0.1)
				(type default)
			)
			(layer "F.Fab")
		)
		(pad "1" smd rect
			(at -0.889 0)
			(size 1.016 1.27)
			(layers "F.Cu" "F.Mask" "F.Paste")
			(net "P3V3_SSD12")
		)
		(pad "2" smd rect
			(at 0.889 0)
			(size 1.016 1.27)
			(layers "F.Cu" "F.Mask" "F.Paste")
			(net "GND")
		)
	)
	(footprint ""
		(layer "F.Cu")
		(at 45.526706 -55.418228 90)
		(property "Reference" "PC368"
			(at 0 0 90)
			(layer "F.SilkS")
			(hide yes)
			(effects
				(font
					(size 1.27 1.27)
				)
			)
		)
		(property "Value" ""
			(at 0 0 90)
			(layer "F.Fab")
			(effects
				(font
					(size 1.27 1.27)
				)
			)
		)
		(duplicate_pad_numbers_are_jumpers no)
		(fp_line
			(start 0.7874 -0.4064)
			(end 0.7874 0.4064)
			(stroke
				(width 0.1524)
				(type default)
			)
			(layer "F.SilkS")
		)
		(fp_line
			(start -0.7874 -0.4064)
			(end 0.7874 -0.4064)
			(stroke
				(width 0.1524)
				(type default)
			)
			(layer "F.SilkS")
		)
		(fp_line
			(start 0.7874 0.4064)
			(end -0.7874 0.4064)
			(stroke
				(width 0.1524)
				(type default)
			)
			(layer "F.SilkS")
		)
		(fp_line
			(start -0.7874 0.4064)
			(end -0.7874 -0.4064)
			(stroke
				(width 0.1524)
				(type default)
			)
			(layer "F.SilkS")
		)
		(fp_line
			(start -0.12065 -0.305054)
			(end -0.12065 -0.2794)
			(stroke
				(width 0.1)
				(type default)
			)
			(layer "F.Fab")
		)
		(fp_line
			(start -0.67945 -0.305054)
			(end -0.12065 -0.305054)
			(stroke
				(width 0.1)
				(type default)
			)
			(layer "F.Fab")
		)
		(fp_line
			(start 0.67945 -0.3048)
			(end 0.67945 0.3048)
			(stroke
				(width 0.1)
				(type default)
			)
			(layer "F.Fab")
		)
		(fp_line
			(start 0.12065 -0.3048)
			(end 0.67945 -0.3048)
			(stroke
				(width 0.1)
				(type default)
			)
			(layer "F.Fab")
		)
		(fp_line
			(start 0.12065 -0.2794)
			(end 0.12065 -0.3048)
			(stroke
				(width 0.1)
				(type default)
			)
			(layer "F.Fab")
		)
		(fp_line
			(start -0.12065 -0.2794)
			(end 0.12065 -0.2794)
			(stroke
				(width 0.1)
				(type default)
			)
			(layer "F.Fab")
		)
		(fp_line
			(start 0.120396 0.2794)
			(end -0.12065 0.2794)
			(stroke
				(width 0.1)
				(type default)
			)
			(layer "F.Fab")
		)
		(fp_line
			(start -0.12065 0.2794)
			(end -0.12065 0.3048)
			(stroke
				(width 0.1)
				(type default)
			)
			(layer "F.Fab")
		)
		(fp_line
			(start 0.67945 0.3048)
			(end 0.120396 0.3048)
			(stroke
				(width 0.1)
				(type default)
			)
			(layer "F.Fab")
		)
		(fp_line
			(start 0.120396 0.3048)
			(end 0.120396 0.2794)
			(stroke
				(width 0.1)
				(type default)
			)
			(layer "F.Fab")
		)
		(fp_line
			(start -0.12065 0.3048)
			(end -0.67945 0.3048)
			(stroke
				(width 0.1)
				(type default)
			)
			(layer "F.Fab")
		)
		(fp_line
			(start -0.67945 0.3048)
			(end -0.67945 -0.305054)
			(stroke
				(width 0.1)
				(type default)
			)
			(layer "F.Fab")
		)
		(pad "1" smd circle
			(at -0.40005 0 90)
			(size 0 0)
			(layers "F.Cu" "F.Mask" "F.Paste")
			(net "P12V_SSD1_R")
		)
		(pad "2" smd circle
			(at 0.40005 0 90)
			(size 0 0)
			(layers "F.Cu" "F.Mask" "F.Paste")
			(net "GND")
		)
	)
	(footprint ""
		(layer "F.Cu")
		(at 92.019628 -298.792646 -90)
		(property "Reference" "R3886"
			(at 0 0 270)
			(layer "F.SilkS")
			(hide yes)
			(effects
				(font
					(size 1.27 1.27)
				)
			)
		)
		(property "Value" ""
			(at 0 0 270)
			(layer "F.Fab")
			(effects
				(font
					(size 1.27 1.27)
				)
			)
		)
		(duplicate_pad_numbers_are_jumpers no)
		(fp_line
			(start -0.7874 0.4064)
			(end -0.7874 -0.4064)
			(stroke
				(width 0.1524)
				(type default)
			)
			(layer "F.SilkS")
		)
		(fp_line
			(start 0.7874 0.4064)
			(end -0.7874 0.4064)
			(stroke
				(width 0.1524)
				(type default)
			)
			(layer "F.SilkS")
		)
		(fp_line
			(start -0.7874 -0.4064)
			(end 0.7874 -0.4064)
			(stroke
				(width 0.1524)
				(type default)
			)
			(layer "F.SilkS")
		)
		(fp_line
			(start 0.7874 -0.4064)
			(end 0.7874 0.4064)
			(stroke
				(width 0.1524)
				(type default)
			)
			(layer "F.SilkS")
		)
		(fp_line
			(start -0.67945 0.3048)
			(end -0.67945 -0.305054)
			(stroke
				(width 0.1)
				(type default)
			)
			(layer "F.Fab")
		)
		(fp_line
			(start -0.12065 0.3048)
			(end -0.67945 0.3048)
			(stroke
				(width 0.1)
				(type default)
			)
			(layer "F.Fab")
		)
		(fp_line
			(start 0.120396 0.3048)
			(end 0.120396 0.2794)
			(stroke
				(width 0.1)
				(type default)
			)
			(layer "F.Fab")
		)
		(fp_line
			(start 0.67945 0.3048)
			(end 0.120396 0.3048)
			(stroke
				(width 0.1)
				(type default)
			)
			(layer "F.Fab")
		)
		(fp_line
			(start -0.12065 0.2794)
			(end -0.12065 0.3048)
			(stroke
				(width 0.1)
				(type default)
			)
			(layer "F.Fab")
		)
		(fp_line
			(start 0.120396 0.2794)
			(end -0.12065 0.2794)
			(stroke
				(width 0.1)
				(type default)
			)
			(layer "F.Fab")
		)
		(fp_line
			(start -0.12065 -0.2794)
			(end 0.12065 -0.2794)
			(stroke
				(width 0.1)
				(type default)
			)
			(layer "F.Fab")
		)
		(fp_line
			(start 0.12065 -0.2794)
			(end 0.12065 -0.3048)
			(stroke
				(width 0.1)
				(type default)
			)
			(layer "F.Fab")
		)
		(fp_line
			(start 0.12065 -0.3048)
			(end 0.67945 -0.3048)
			(stroke
				(width 0.1)
				(type default)
			)
			(layer "F.Fab")
		)
		(fp_line
			(start 0.67945 -0.3048)
			(end 0.67945 0.3048)
			(stroke
				(width 0.1)
				(type default)
			)
			(layer "F.Fab")
		)
		(fp_line
			(start -0.67945 -0.305054)
			(end -0.12065 -0.305054)
			(stroke
				(width 0.1)
				(type default)
			)
			(layer "F.Fab")
		)
		(fp_line
			(start -0.12065 -0.305054)
			(end -0.12065 -0.2794)
			(stroke
				(width 0.1)
				(type default)
			)
			(layer "F.Fab")
		)
		(pad "1" smd circle
			(at -0.40005 0 270)
			(size 0 0)
			(layers "F.Cu" "F.Mask" "F.Paste")
			(net "I2C_PEX0_HOST_SCL")
		)
		(pad "2" smd circle
			(at 0.40005 0 270)
			(size 0 0)
			(layers "F.Cu" "F.Mask" "F.Paste")
			(net "I2C_PEX0_HOST_R_SCL")
		)
	)
	(footprint ""
		(layer "F.Cu")
		(at 142.343886 -48.93691 180)
		(property "Reference" "R556"
			(at 0 0 180)
			(layer "F.SilkS")
			(hide yes)
			(effects
				(font
					(size 1.27 1.27)
				)
			)
		)
		(property "Value" ""
			(at 0 0 180)
			(layer "F.Fab")
			(effects
				(font
					(size 1.27 1.27)
				)
			)
		)
		(duplicate_pad_numbers_are_jumpers no)
		(fp_line
			(start 0.7874 0.4064)
			(end -0.7874 0.4064)
			(stroke
				(width 0.1524)
				(type default)
			)
			(layer "F.SilkS")
		)
		(fp_line
			(start 0.7874 -0.4064)
			(end 0.7874 0.4064)
			(stroke
				(width 0.1524)
				(type default)
			)
			(layer "F.SilkS")
		)
		(fp_line
			(start -0.7874 0.4064)
			(end -0.7874 -0.4064)
			(stroke
				(width 0.1524)
				(type default)
			)
			(layer "F.SilkS")
		)
		(fp_line
			(start -0.7874 -0.4064)
			(end 0.7874 -0.4064)
			(stroke
				(width 0.1524)
				(type default)
			)
			(layer "F.SilkS")
		)
		(fp_line
			(start 0.67945 0.3048)
			(end 0.120396 0.3048)
			(stroke
				(width 0.1)
				(type default)
			)
			(layer "F.Fab")
		)
		(fp_line
			(start 0.67945 -0.3048)
			(end 0.67945 0.3048)
			(stroke
				(width 0.1)
				(type default)
			)
			(layer "F.Fab")
		)
		(fp_line
			(start 0.12065 -0.2794)
			(end 0.12065 -0.3048)
			(stroke
				(width 0.1)
				(type default)
			)
			(layer "F.Fab")
		)
		(fp_line
			(start 0.12065 -0.3048)
			(end 0.67945 -0.3048)
			(stroke
				(width 0.1)
				(type default)
			)
			(layer "F.Fab")
		)
		(fp_line
			(start 0.120396 0.3048)
			(end 0.120396 0.2794)
			(stroke
				(width 0.1)
				(type default)
			)
			(layer "F.Fab")
		)
		(fp_line
			(start 0.120396 0.2794)
			(end -0.12065 0.2794)
			(stroke
				(width 0.1)
				(type default)
			)
			(layer "F.Fab")
		)
		(fp_line
			(start -0.12065 0.3048)
			(end -0.67945 0.3048)
			(stroke
				(width 0.1)
				(type default)
			)
			(layer "F.Fab")
		)
		(fp_line
			(start -0.12065 0.2794)
			(end -0.12065 0.3048)
			(stroke
				(width 0.1)
				(type default)
			)
			(layer "F.Fab")
		)
		(fp_line
			(start -0.12065 -0.2794)
			(end 0.12065 -0.2794)
			(stroke
				(width 0.1)
				(type default)
			)
			(layer "F.Fab")
		)
		(fp_line
			(start -0.12065 -0.305054)
			(end -0.12065 -0.2794)
			(stroke
				(width 0.1)
				(type default)
			)
			(layer "F.Fab")
		)
		(fp_line
			(start -0.67945 0.3048)
			(end -0.67945 -0.305054)
			(stroke
				(width 0.1)
				(type default)
			)
			(layer "F.Fab")
		)
		(fp_line
			(start -0.67945 -0.305054)
			(end -0.12065 -0.305054)
			(stroke
				(width 0.1)
				(type default)
			)
			(layer "F.Fab")
		)
		(pad "1" smd circle
			(at -0.40005 0 180)
			(size 0 0)
			(layers "F.Cu" "F.Mask" "F.Paste")
			(net "SMB_BIC_I2C6_MUX_SSD_0_7_ADC_R_SDA")
		)
		(pad "2" smd circle
			(at 0.40005 0 180)
			(size 0 0)
			(layers "F.Cu" "F.Mask" "F.Paste")
			(net "SMB_SSD4_ADC_SDA")
		)
	)
	(footprint ""
		(layer "F.Cu")
		(at 126.169166 -118.343426 90)
		(property "Reference" "R5958"
			(at 0 0 90)
			(layer "F.SilkS")
			(hide yes)
			(effects
				(font
					(size 1.27 1.27)
				)
			)
		)
		(property "Value" ""
			(at 0 0 90)
			(layer "F.Fab")
			(effects
				(font
					(size 1.27 1.27)
				)
			)
		)
		(duplicate_pad_numbers_are_jumpers no)
		(fp_line
			(start 0.7874 -0.4064)
			(end 0.7874 0.4064)
			(stroke
				(width 0.1524)
				(type default)
			)
			(layer "F.SilkS")
		)
		(fp_line
			(start -0.7874 -0.4064)
			(end 0.7874 -0.4064)
			(stroke
				(width 0.1524)
				(type default)
			)
			(layer "F.SilkS")
		)
		(fp_line
			(start 0.7874 0.4064)
			(end -0.7874 0.4064)
			(stroke
				(width 0.1524)
				(type default)
			)
			(layer "F.SilkS")
		)
		(fp_line
			(start -0.7874 0.4064)
			(end -0.7874 -0.4064)
			(stroke
				(width 0.1524)
				(type default)
			)
			(layer "F.SilkS")
		)
		(fp_line
			(start -0.12065 -0.305054)
			(end -0.12065 -0.2794)
			(stroke
				(width 0.1)
				(type default)
			)
			(layer "F.Fab")
		)
		(fp_line
			(start -0.67945 -0.305054)
			(end -0.12065 -0.305054)
			(stroke
				(width 0.1)
				(type default)
			)
			(layer "F.Fab")
		)
		(fp_line
			(start 0.67945 -0.3048)
			(end 0.67945 0.3048)
			(stroke
				(width 0.1)
				(type default)
			)
			(layer "F.Fab")
		)
		(fp_line
			(start 0.12065 -0.3048)
			(end 0.67945 -0.3048)
			(stroke
				(width 0.1)
				(type default)
			)
			(layer "F.Fab")
		)
		(fp_line
			(start 0.12065 -0.2794)
			(end 0.12065 -0.3048)
			(stroke
				(width 0.1)
				(type default)
			)
			(layer "F.Fab")
		)
		(fp_line
			(start -0.12065 -0.2794)
			(end 0.12065 -0.2794)
			(stroke
				(width 0.1)
				(type default)
			)
			(layer "F.Fab")
		)
		(fp_line
			(start 0.120396 0.2794)
			(end -0.12065 0.2794)
			(stroke
				(width 0.1)
				(type default)
			)
			(layer "F.Fab")
		)
		(fp_line
			(start -0.12065 0.2794)
			(end -0.12065 0.3048)
			(stroke
				(width 0.1)
				(type default)
			)
			(layer "F.Fab")
		)
		(fp_line
			(start 0.67945 0.3048)
			(end 0.120396 0.3048)
			(stroke
				(width 0.1)
				(type default)
			)
			(layer "F.Fab")
		)
		(fp_line
			(start 0.120396 0.3048)
			(end 0.120396 0.2794)
			(stroke
				(width 0.1)
				(type default)
			)
			(layer "F.Fab")
		)
		(fp_line
			(start -0.12065 0.3048)
			(end -0.67945 0.3048)
			(stroke
				(width 0.1)
				(type default)
			)
			(layer "F.Fab")
		)
		(fp_line
			(start -0.67945 0.3048)
			(end -0.67945 -0.305054)
			(stroke
				(width 0.1)
				(type default)
			)
			(layer "F.Fab")
		)
		(pad "1" smd circle
			(at -0.40005 0 90)
			(size 0 0)
			(layers "F.Cu" "F.Mask" "F.Paste")
			(net "PWRGD_P3V3_NIC2_D")
		)
		(pad "2" smd circle
			(at 0.40005 0 90)
			(size 0 0)
			(layers "F.Cu" "F.Mask" "F.Paste")
			(net "PWRGD_P3V3_NIC2_R")
		)
	)
	(footprint ""
		(layer "F.Cu")
		(at 455.818494 -120.53824 180)
		(property "Reference" "R6049"
			(at 0 0 180)
			(layer "F.SilkS")
			(hide yes)
			(effects
				(font
					(size 1.27 1.27)
				)
			)
		)
		(property "Value" ""
			(at 0 0 180)
			(layer "F.Fab")
			(effects
				(font
					(size 1.27 1.27)
				)
			)
		)
		(duplicate_pad_numbers_are_jumpers no)
		(fp_line
			(start 0.7874 0.4064)
			(end -0.7874 0.4064)
			(stroke
				(width 0.1524)
				(type default)
			)
			(layer "F.SilkS")
		)
		(fp_line
			(start 0.7874 -0.4064)
			(end 0.7874 0.4064)
			(stroke
				(width 0.1524)
				(type default)
			)
			(layer "F.SilkS")
		)
		(fp_line
			(start -0.7874 0.4064)
			(end -0.7874 -0.4064)
			(stroke
				(width 0.1524)
				(type default)
			)
			(layer "F.SilkS")
		)
		(fp_line
			(start -0.7874 -0.4064)
			(end 0.7874 -0.4064)
			(stroke
				(width 0.1524)
				(type default)
			)
			(layer "F.SilkS")
		)
		(fp_line
			(start 0.67945 0.3048)
			(end 0.120396 0.3048)
			(stroke
				(width 0.1)
				(type default)
			)
			(layer "F.Fab")
		)
		(fp_line
			(start 0.67945 -0.3048)
			(end 0.67945 0.3048)
			(stroke
				(width 0.1)
				(type default)
			)
			(layer "F.Fab")
		)
		(fp_line
			(start 0.12065 -0.2794)
			(end 0.12065 -0.3048)
			(stroke
				(width 0.1)
				(type default)
			)
			(layer "F.Fab")
		)
		(fp_line
			(start 0.12065 -0.3048)
			(end 0.67945 -0.3048)
			(stroke
				(width 0.1)
				(type default)
			)
			(layer "F.Fab")
		)
		(fp_line
			(start 0.120396 0.3048)
			(end 0.120396 0.2794)
			(stroke
				(width 0.1)
				(type default)
			)
			(layer "F.Fab")
		)
		(fp_line
			(start 0.120396 0.2794)
			(end -0.12065 0.2794)
			(stroke
				(width 0.1)
				(type default)
			)
			(layer "F.Fab")
		)
		(fp_line
			(start -0.12065 0.3048)
			(end -0.67945 0.3048)
			(stroke
				(width 0.1)
				(type default)
			)
			(layer "F.Fab")
		)
		(fp_line
			(start -0.12065 0.2794)
			(end -0.12065 0.3048)
			(stroke
				(width 0.1)
				(type default)
			)
			(layer "F.Fab")
		)
		(fp_line
			(start -0.12065 -0.2794)
			(end 0.12065 -0.2794)
			(stroke
				(width 0.1)
				(type default)
			)
			(layer "F.Fab")
		)
		(fp_line
			(start -0.12065 -0.305054)
			(end -0.12065 -0.2794)
			(stroke
				(width 0.1)
				(type default)
			)
			(layer "F.Fab")
		)
		(fp_line
			(start -0.67945 0.3048)
			(end -0.67945 -0.305054)
			(stroke
				(width 0.1)
				(type default)
			)
			(layer "F.Fab")
		)
		(fp_line
			(start -0.67945 -0.305054)
			(end -0.12065 -0.305054)
			(stroke
				(width 0.1)
				(type default)
			)
			(layer "F.Fab")
		)
		(pad "1" smd circle
			(at -0.40005 0 180)
			(size 0 0)
			(layers "F.Cu" "F.Mask" "F.Paste")
			(net "P5V_AUX")
		)
		(pad "2" smd circle
			(at 0.40005 0 180)
			(size 0 0)
			(layers "F.Cu" "F.Mask" "F.Paste")
			(net "P3V3_NIC7_PG_G2")
		)
	)
	(footprint ""
		(layer "F.Cu")
		(at 71.471536 -25.342342 -90)
		(property "Reference" "R415"
			(at 0 0 270)
			(layer "F.SilkS")
			(hide yes)
			(effects
				(font
					(size 1.27 1.27)
				)
			)
		)
		(property "Value" ""
			(at 0 0 270)
			(layer "F.Fab")
			(effects
				(font
					(size 1.27 1.27)
				)
			)
		)
		(duplicate_pad_numbers_are_jumpers no)
		(fp_line
			(start -0.7874 0.4064)
			(end -0.7874 -0.4064)
			(stroke
				(width 0.1524)
				(type default)
			)
			(layer "F.SilkS")
		)
		(fp_line
			(start 0.7874 0.4064)
			(end -0.7874 0.4064)
			(stroke
				(width 0.1524)
				(type default)
			)
			(layer "F.SilkS")
		)
		(fp_line
			(start -0.7874 -0.4064)
			(end 0.7874 -0.4064)
			(stroke
				(width 0.1524)
				(type default)
			)
			(layer "F.SilkS")
		)
		(fp_line
			(start 0.7874 -0.4064)
			(end 0.7874 0.4064)
			(stroke
				(width 0.1524)
				(type default)
			)
			(layer "F.SilkS")
		)
		(fp_line
			(start -0.67945 0.3048)
			(end -0.67945 -0.305054)
			(stroke
				(width 0.1)
				(type default)
			)
			(layer "F.Fab")
		)
		(fp_line
			(start -0.12065 0.3048)
			(end -0.67945 0.3048)
			(stroke
				(width 0.1)
				(type default)
			)
			(layer "F.Fab")
		)
		(fp_line
			(start 0.120396 0.3048)
			(end 0.120396 0.2794)
			(stroke
				(width 0.1)
				(type default)
			)
			(layer "F.Fab")
		)
		(fp_line
			(start 0.67945 0.3048)
			(end 0.120396 0.3048)
			(stroke
				(width 0.1)
				(type default)
			)
			(layer "F.Fab")
		)
		(fp_line
			(start -0.12065 0.2794)
			(end -0.12065 0.3048)
			(stroke
				(width 0.1)
				(type default)
			)
			(layer "F.Fab")
		)
		(fp_line
			(start 0.120396 0.2794)
			(end -0.12065 0.2794)
			(stroke
				(width 0.1)
				(type default)
			)
			(layer "F.Fab")
		)
		(fp_line
			(start -0.12065 -0.2794)
			(end 0.12065 -0.2794)
			(stroke
				(width 0.1)
				(type default)
			)
			(layer "F.Fab")
		)
		(fp_line
			(start 0.12065 -0.2794)
			(end 0.12065 -0.3048)
			(stroke
				(width 0.1)
				(type default)
			)
			(layer "F.Fab")
		)
		(fp_line
			(start 0.12065 -0.3048)
			(end 0.67945 -0.3048)
			(stroke
				(width 0.1)
				(type default)
			)
			(layer "F.Fab")
		)
		(fp_line
			(start 0.67945 -0.3048)
			(end 0.67945 0.3048)
			(stroke
				(width 0.1)
				(type default)
			)
			(layer "F.Fab")
		)
		(fp_line
			(start -0.67945 -0.305054)
			(end -0.12065 -0.305054)
			(stroke
				(width 0.1)
				(type default)
			)
			(layer "F.Fab")
		)
		(fp_line
			(start -0.12065 -0.305054)
			(end -0.12065 -0.2794)
			(stroke
				(width 0.1)
				(type default)
			)
			(layer "F.Fab")
		)
		(pad "1" smd circle
			(at -0.40005 0 270)
			(size 0 0)
			(layers "F.Cu" "F.Mask" "F.Paste")
			(net "P3V3_SSD2")
		)
		(pad "2" smd circle
			(at 0.40005 0 270)
			(size 0 0)
			(layers "F.Cu" "F.Mask" "F.Paste")
			(net "DUALPORT_N_SSD2")
		)
	)
	(footprint ""
		(layer "F.Cu")
		(at 323.893434 -215.42883 180)
		(property "Reference" "R6645"
			(at 0 0 180)
			(layer "F.SilkS")
			(hide yes)
			(effects
				(font
					(size 1.27 1.27)
				)
			)
		)
		(property "Value" ""
			(at 0 0 180)
			(layer "F.Fab")
			(effects
				(font
					(size 1.27 1.27)
				)
			)
		)
		(duplicate_pad_numbers_are_jumpers no)
		(fp_line
			(start 0.7874 0.4064)
			(end -0.7874 0.4064)
			(stroke
				(width 0.1524)
				(type default)
			)
			(layer "F.SilkS")
		)
		(fp_line
			(start 0.7874 -0.4064)
			(end 0.7874 0.4064)
			(stroke
				(width 0.1524)
				(type default)
			)
			(layer "F.SilkS")
		)
		(fp_line
			(start -0.7874 0.4064)
			(end -0.7874 -0.4064)
			(stroke
				(width 0.1524)
				(type default)
			)
			(layer "F.SilkS")
		)
		(fp_line
			(start -0.7874 -0.4064)
			(end 0.7874 -0.4064)
			(stroke
				(width 0.1524)
				(type default)
			)
			(layer "F.SilkS")
		)
		(fp_line
			(start 0.67945 0.3048)
			(end 0.120396 0.3048)
			(stroke
				(width 0.1)
				(type default)
			)
			(layer "F.Fab")
		)
		(fp_line
			(start 0.67945 -0.3048)
			(end 0.67945 0.3048)
			(stroke
				(width 0.1)
				(type default)
			)
			(layer "F.Fab")
		)
		(fp_line
			(start 0.12065 -0.2794)
			(end 0.12065 -0.3048)
			(stroke
				(width 0.1)
				(type default)
			)
			(layer "F.Fab")
		)
		(fp_line
			(start 0.12065 -0.3048)
			(end 0.67945 -0.3048)
			(stroke
				(width 0.1)
				(type default)
			)
			(layer "F.Fab")
		)
		(fp_line
			(start 0.120396 0.3048)
			(end 0.120396 0.2794)
			(stroke
				(width 0.1)
				(type default)
			)
			(layer "F.Fab")
		)
		(fp_line
			(start 0.120396 0.2794)
			(end -0.12065 0.2794)
			(stroke
				(width 0.1)
				(type default)
			)
			(layer "F.Fab")
		)
		(fp_line
			(start -0.12065 0.3048)
			(end -0.67945 0.3048)
			(stroke
				(width 0.1)
				(type default)
			)
			(layer "F.Fab")
		)
		(fp_line
			(start -0.12065 0.2794)
			(end -0.12065 0.3048)
			(stroke
				(width 0.1)
				(type default)
			)
			(layer "F.Fab")
		)
		(fp_line
			(start -0.12065 -0.2794)
			(end 0.12065 -0.2794)
			(stroke
				(width 0.1)
				(type default)
			)
			(layer "F.Fab")
		)
		(fp_line
			(start -0.12065 -0.305054)
			(end -0.12065 -0.2794)
			(stroke
				(width 0.1)
				(type default)
			)
			(layer "F.Fab")
		)
		(fp_line
			(start -0.67945 0.3048)
			(end -0.67945 -0.305054)
			(stroke
				(width 0.1)
				(type default)
			)
			(layer "F.Fab")
		)
		(fp_line
			(start -0.67945 -0.305054)
			(end -0.12065 -0.305054)
			(stroke
				(width 0.1)
				(type default)
			)
			(layer "F.Fab")
		)
		(pad "1" smd circle
			(at -0.40005 0 180)
			(size 0 0)
			(layers "F.Cu" "F.Mask" "F.Paste")
			(net "HSC_D_OC_FPGA_N")
		)
		(pad "2" smd circle
			(at 0.40005 0 180)
			(size 0 0)
			(layers "F.Cu" "F.Mask" "F.Paste")
			(net "HSC_D_OC_BUF_R_N")
		)
	)
	(footprint ""
		(layer "F.Cu")
		(at 106.614214 -215.047576)
		(property "Reference" "PC285"
			(at 0 0 0)
			(layer "F.SilkS")
			(hide yes)
			(effects
				(font
					(size 1.27 1.27)
				)
			)
		)
		(property "Value" ""
			(at 0 0 0)
			(layer "F.Fab")
			(effects
				(font
					(size 1.27 1.27)
				)
			)
		)
		(duplicate_pad_numbers_are_jumpers no)
		(fp_line
			(start -1.524 -0.762)
			(end 1.524 -0.762)
			(stroke
				(width 0.1524)
				(type default)
			)
			(layer "F.SilkS")
		)
		(fp_line
			(start -1.524 0.762)
			(end -1.524 -0.762)
			(stroke
				(width 0.1524)
				(type default)
			)
			(layer "F.SilkS")
		)
		(fp_line
			(start 1.524 -0.762)
			(end 1.524 0.762)
			(stroke
				(width 0.1524)
				(type default)
			)
			(layer "F.SilkS")
		)
		(fp_line
			(start 1.524 0.762)
			(end -1.524 0.762)
			(stroke
				(width 0.1524)
				(type default)
			)
			(layer "F.SilkS")
		)
		(fp_line
			(start -1.1049 -0.724916)
			(end -1.1049 0.724916)
			(stroke
				(width 0.1)
				(type default)
			)
			(layer "F.Fab")
		)
		(fp_line
			(start -1.1049 0.724916)
			(end 1.1049 0.724916)
			(stroke
				(width 0.1)
				(type default)
			)
			(layer "F.Fab")
		)
		(fp_line
			(start 1.1049 -0.724916)
			(end -1.1049 -0.724916)
			(stroke
				(width 0.1)
				(type default)
			)
			(layer "F.Fab")
		)
		(fp_line
			(start 1.1049 0.724916)
			(end 1.1049 -0.724916)
			(stroke
				(width 0.1)
				(type default)
			)
			(layer "F.Fab")
		)
		(pad "1" smd rect
			(at -0.889 0 180)
			(size 1.016 1.27)
			(layers "F.Cu" "F.Mask" "F.Paste")
			(net "SW_P12V_P1V8_PEX_FLT")
		)
		(pad "2" smd rect
			(at 0.889 0 180)
			(size 1.016 1.27)
			(layers "F.Cu" "F.Mask" "F.Paste")
			(net "GND")
		)
	)
	(footprint ""
		(layer "F.Cu")
		(at 379.307344 -257.439414 -90)
		(property "Reference" "C3576"
			(at 0 0 270)
			(layer "F.SilkS")
			(hide yes)
			(effects
				(font
					(size 1.27 1.27)
				)
			)
		)
		(property "Value" ""
			(at 0 0 270)
			(layer "F.Fab")
			(effects
				(font
					(size 1.27 1.27)
				)
			)
		)
		(duplicate_pad_numbers_are_jumpers no)
		(fp_line
			(start -0.299974 0.150114)
			(end -0.299974 -0.150114)
			(stroke
				(width 0.1)
				(type default)
			)
			(layer "F.Fab")
		)
		(fp_line
			(start 0.299974 0.150114)
			(end -0.299974 0.150114)
			(stroke
				(width 0.1)
				(type default)
			)
			(layer "F.Fab")
		)
		(fp_line
			(start -0.299974 -0.150114)
			(end 0.299974 -0.150114)
			(stroke
				(width 0.1)
				(type default)
			)
			(layer "F.Fab")
		)
		(fp_line
			(start 0.299974 -0.150114)
			(end 0.299974 0.150114)
			(stroke
				(width 0.1)
				(type default)
			)
			(layer "F.Fab")
		)
		(pad "1" smd rect
			(at -0.2667 0 270)
			(size 0.3048 0.381)
			(layers "F.Cu" "F.Mask" "F.Paste")
			(net "P1V8_PLL0_PEX3")
		)
		(pad "2" smd rect
			(at 0.2667 0 270)
			(size 0.3048 0.381)
			(layers "F.Cu" "F.Mask" "F.Paste")
			(net "GND")
		)
	)
	(footprint ""
		(layer "F.Cu")
		(at 406.781 -383.667 90)
		(property "Reference" "R6279"
			(at 0 0 90)
			(layer "F.SilkS")
			(hide yes)
			(effects
				(font
					(size 1.27 1.27)
				)
			)
		)
		(property "Value" ""
			(at 0 0 90)
			(layer "F.Fab")
			(effects
				(font
					(size 1.27 1.27)
				)
			)
		)
		(duplicate_pad_numbers_are_jumpers no)
		(fp_line
			(start 0.7874 -0.4064)
			(end 0.7874 0.4064)
			(stroke
				(width 0.1524)
				(type default)
			)
			(layer "F.SilkS")
		)
		(fp_line
			(start -0.7874 -0.4064)
			(end 0.7874 -0.4064)
			(stroke
				(width 0.1524)
				(type default)
			)
			(layer "F.SilkS")
		)
		(fp_line
			(start 0.7874 0.4064)
			(end -0.7874 0.4064)
			(stroke
				(width 0.1524)
				(type default)
			)
			(layer "F.SilkS")
		)
		(fp_line
			(start -0.7874 0.4064)
			(end -0.7874 -0.4064)
			(stroke
				(width 0.1524)
				(type default)
			)
			(layer "F.SilkS")
		)
		(fp_line
			(start -0.12065 -0.305054)
			(end -0.12065 -0.2794)
			(stroke
				(width 0.1)
				(type default)
			)
			(layer "F.Fab")
		)
		(fp_line
			(start -0.67945 -0.305054)
			(end -0.12065 -0.305054)
			(stroke
				(width 0.1)
				(type default)
			)
			(layer "F.Fab")
		)
		(fp_line
			(start 0.67945 -0.3048)
			(end 0.67945 0.3048)
			(stroke
				(width 0.1)
				(type default)
			)
			(layer "F.Fab")
		)
		(fp_line
			(start 0.12065 -0.3048)
			(end 0.67945 -0.3048)
			(stroke
				(width 0.1)
				(type default)
			)
			(layer "F.Fab")
		)
		(fp_line
			(start 0.12065 -0.2794)
			(end 0.12065 -0.3048)
			(stroke
				(width 0.1)
				(type default)
			)
			(layer "F.Fab")
		)
		(fp_line
			(start -0.12065 -0.2794)
			(end 0.12065 -0.2794)
			(stroke
				(width 0.1)
				(type default)
			)
			(layer "F.Fab")
		)
		(fp_line
			(start 0.120396 0.2794)
			(end -0.12065 0.2794)
			(stroke
				(width 0.1)
				(type default)
			)
			(layer "F.Fab")
		)
		(fp_line
			(start -0.12065 0.2794)
			(end -0.12065 0.3048)
			(stroke
				(width 0.1)
				(type default)
			)
			(layer "F.Fab")
		)
		(fp_line
			(start 0.67945 0.3048)
			(end 0.120396 0.3048)
			(stroke
				(width 0.1)
				(type default)
			)
			(layer "F.Fab")
		)
		(fp_line
			(start 0.120396 0.3048)
			(end 0.120396 0.2794)
			(stroke
				(width 0.1)
				(type default)
			)
			(layer "F.Fab")
		)
		(fp_line
			(start -0.12065 0.3048)
			(end -0.67945 0.3048)
			(stroke
				(width 0.1)
				(type default)
			)
			(layer "F.Fab")
		)
		(fp_line
			(start -0.67945 0.3048)
			(end -0.67945 -0.305054)
			(stroke
				(width 0.1)
				(type default)
			)
			(layer "F.Fab")
		)
		(pad "1" smd circle
			(at -0.40005 0 90)
			(size 0 0)
			(layers "F.Cu" "F.Mask" "F.Paste")
			(net "I3C_MB_BMC_R_SDA")
		)
		(pad "2" smd circle
			(at 0.40005 0 90)
			(size 0 0)
			(layers "F.Cu" "F.Mask" "F.Paste")
			(net "I3C_MB_BMC_SDA")
		)
	)
	(footprint ""
		(layer "F.Cu")
		(at 331.73035 -66.32194 -90)
		(property "Reference" "PC877"
			(at 0 0 270)
			(layer "F.SilkS")
			(hide yes)
			(effects
				(font
					(size 1.27 1.27)
				)
			)
		)
		(property "Value" ""
			(at 0 0 270)
			(layer "F.Fab")
			(effects
				(font
					(size 1.27 1.27)
				)
			)
		)
		(duplicate_pad_numbers_are_jumpers no)
		(fp_line
			(start -0.7874 0.4064)
			(end -0.7874 -0.4064)
			(stroke
				(width 0.1524)
				(type default)
			)
			(layer "F.SilkS")
		)
		(fp_line
			(start 0.7874 0.4064)
			(end -0.7874 0.4064)
			(stroke
				(width 0.1524)
				(type default)
			)
			(layer "F.SilkS")
		)
		(fp_line
			(start -0.7874 -0.4064)
			(end 0.7874 -0.4064)
			(stroke
				(width 0.1524)
				(type default)
			)
			(layer "F.SilkS")
		)
		(fp_line
			(start 0.7874 -0.4064)
			(end 0.7874 0.4064)
			(stroke
				(width 0.1524)
				(type default)
			)
			(layer "F.SilkS")
		)
		(fp_line
			(start -0.67945 0.3048)
			(end -0.67945 -0.305054)
			(stroke
				(width 0.1)
				(type default)
			)
			(layer "F.Fab")
		)
		(fp_line
			(start -0.12065 0.3048)
			(end -0.67945 0.3048)
			(stroke
				(width 0.1)
				(type default)
			)
			(layer "F.Fab")
		)
		(fp_line
			(start 0.120396 0.3048)
			(end 0.120396 0.2794)
			(stroke
				(width 0.1)
				(type default)
			)
			(layer "F.Fab")
		)
		(fp_line
			(start 0.67945 0.3048)
			(end 0.120396 0.3048)
			(stroke
				(width 0.1)
				(type default)
			)
			(layer "F.Fab")
		)
		(fp_line
			(start -0.12065 0.2794)
			(end -0.12065 0.3048)
			(stroke
				(width 0.1)
				(type default)
			)
			(layer "F.Fab")
		)
		(fp_line
			(start 0.120396 0.2794)
			(end -0.12065 0.2794)
			(stroke
				(width 0.1)
				(type default)
			)
			(layer "F.Fab")
		)
		(fp_line
			(start -0.12065 -0.2794)
			(end 0.12065 -0.2794)
			(stroke
				(width 0.1)
				(type default)
			)
			(layer "F.Fab")
		)
		(fp_line
			(start 0.12065 -0.2794)
			(end 0.12065 -0.3048)
			(stroke
				(width 0.1)
				(type default)
			)
			(layer "F.Fab")
		)
		(fp_line
			(start 0.12065 -0.3048)
			(end 0.67945 -0.3048)
			(stroke
				(width 0.1)
				(type default)
			)
			(layer "F.Fab")
		)
		(fp_line
			(start 0.67945 -0.3048)
			(end 0.67945 0.3048)
			(stroke
				(width 0.1)
				(type default)
			)
			(layer "F.Fab")
		)
		(fp_line
			(start -0.67945 -0.305054)
			(end -0.12065 -0.305054)
			(stroke
				(width 0.1)
				(type default)
			)
			(layer "F.Fab")
		)
		(fp_line
			(start -0.12065 -0.305054)
			(end -0.12065 -0.2794)
			(stroke
				(width 0.1)
				(type default)
			)
			(layer "F.Fab")
		)
		(pad "1" smd circle
			(at -0.40005 0 270)
			(size 0 0)
			(layers "F.Cu" "F.Mask" "F.Paste")
			(net "P12V_SSD11_CO_DV_DT")
		)
		(pad "2" smd circle
			(at 0.40005 0 270)
			(size 0 0)
			(layers "F.Cu" "F.Mask" "F.Paste")
			(net "GND")
		)
	)
	(footprint ""
		(layer "F.Cu")
		(at 117.226334 -37.929566 90)
		(property "Reference" "R5552"
			(at 0 0 90)
			(layer "F.SilkS")
			(hide yes)
			(effects
				(font
					(size 1.27 1.27)
				)
			)
		)
		(property "Value" ""
			(at 0 0 90)
			(layer "F.Fab")
			(effects
				(font
					(size 1.27 1.27)
				)
			)
		)
		(duplicate_pad_numbers_are_jumpers no)
		(fp_line
			(start 0.7874 -0.4064)
			(end 0.7874 0.4064)
			(stroke
				(width 0.1524)
				(type default)
			)
			(layer "F.SilkS")
		)
		(fp_line
			(start -0.7874 -0.4064)
			(end 0.7874 -0.4064)
			(stroke
				(width 0.1524)
				(type default)
			)
			(layer "F.SilkS")
		)
		(fp_line
			(start 0.7874 0.4064)
			(end -0.7874 0.4064)
			(stroke
				(width 0.1524)
				(type default)
			)
			(layer "F.SilkS")
		)
		(fp_line
			(start -0.7874 0.4064)
			(end -0.7874 -0.4064)
			(stroke
				(width 0.1524)
				(type default)
			)
			(layer "F.SilkS")
		)
		(fp_line
			(start -0.12065 -0.305054)
			(end -0.12065 -0.2794)
			(stroke
				(width 0.1)
				(type default)
			)
			(layer "F.Fab")
		)
		(fp_line
			(start -0.67945 -0.305054)
			(end -0.12065 -0.305054)
			(stroke
				(width 0.1)
				(type default)
			)
			(layer "F.Fab")
		)
		(fp_line
			(start 0.67945 -0.3048)
			(end 0.67945 0.3048)
			(stroke
				(width 0.1)
				(type default)
			)
			(layer "F.Fab")
		)
		(fp_line
			(start 0.12065 -0.3048)
			(end 0.67945 -0.3048)
			(stroke
				(width 0.1)
				(type default)
			)
			(layer "F.Fab")
		)
		(fp_line
			(start 0.12065 -0.2794)
			(end 0.12065 -0.3048)
			(stroke
				(width 0.1)
				(type default)
			)
			(layer "F.Fab")
		)
		(fp_line
			(start -0.12065 -0.2794)
			(end 0.12065 -0.2794)
			(stroke
				(width 0.1)
				(type default)
			)
			(layer "F.Fab")
		)
		(fp_line
			(start 0.120396 0.2794)
			(end -0.12065 0.2794)
			(stroke
				(width 0.1)
				(type default)
			)
			(layer "F.Fab")
		)
		(fp_line
			(start -0.12065 0.2794)
			(end -0.12065 0.3048)
			(stroke
				(width 0.1)
				(type default)
			)
			(layer "F.Fab")
		)
		(fp_line
			(start 0.67945 0.3048)
			(end 0.120396 0.3048)
			(stroke
				(width 0.1)
				(type default)
			)
			(layer "F.Fab")
		)
		(fp_line
			(start 0.120396 0.3048)
			(end 0.120396 0.2794)
			(stroke
				(width 0.1)
				(type default)
			)
			(layer "F.Fab")
		)
		(fp_line
			(start -0.12065 0.3048)
			(end -0.67945 0.3048)
			(stroke
				(width 0.1)
				(type default)
			)
			(layer "F.Fab")
		)
		(fp_line
			(start -0.67945 0.3048)
			(end -0.67945 -0.305054)
			(stroke
				(width 0.1)
				(type default)
			)
			(layer "F.Fab")
		)
		(pad "1" smd circle
			(at -0.40005 0 90)
			(size 0 0)
			(layers "F.Cu" "F.Mask" "F.Paste")
			(net "SSD4_AUX_P3V3_EN_R")
		)
		(pad "2" smd circle
			(at 0.40005 0 90)
			(size 0 0)
			(layers "F.Cu" "F.Mask" "F.Paste")
			(net "SSD4_AUX_P3V3_EN")
		)
	)
	(footprint ""
		(layer "F.Cu")
		(at 152.461468 -391.18159 -90)
		(property "Reference" "C4052"
			(at 0 0 270)
			(layer "F.SilkS")
			(hide yes)
			(effects
				(font
					(size 1.27 1.27)
				)
			)
		)
		(property "Value" ""
			(at 0 0 270)
			(layer "F.Fab")
			(effects
				(font
					(size 1.27 1.27)
				)
			)
		)
		(duplicate_pad_numbers_are_jumpers no)
		(fp_line
			(start -0.7874 0.4064)
			(end -0.7874 -0.4064)
			(stroke
				(width 0.1524)
				(type default)
			)
			(layer "F.SilkS")
		)
		(fp_line
			(start 0.7874 0.4064)
			(end -0.7874 0.4064)
			(stroke
				(width 0.1524)
				(type default)
			)
			(layer "F.SilkS")
		)
		(fp_line
			(start -0.7874 -0.4064)
			(end 0.7874 -0.4064)
			(stroke
				(width 0.1524)
				(type default)
			)
			(layer "F.SilkS")
		)
		(fp_line
			(start 0.7874 -0.4064)
			(end 0.7874 0.4064)
			(stroke
				(width 0.1524)
				(type default)
			)
			(layer "F.SilkS")
		)
		(fp_line
			(start -0.67945 0.3048)
			(end -0.67945 -0.305054)
			(stroke
				(width 0.1)
				(type default)
			)
			(layer "F.Fab")
		)
		(fp_line
			(start -0.12065 0.3048)
			(end -0.67945 0.3048)
			(stroke
				(width 0.1)
				(type default)
			)
			(layer "F.Fab")
		)
		(fp_line
			(start 0.120396 0.3048)
			(end 0.120396 0.2794)
			(stroke
				(width 0.1)
				(type default)
			)
			(layer "F.Fab")
		)
		(fp_line
			(start 0.67945 0.3048)
			(end 0.120396 0.3048)
			(stroke
				(width 0.1)
				(type default)
			)
			(layer "F.Fab")
		)
		(fp_line
			(start -0.12065 0.2794)
			(end -0.12065 0.3048)
			(stroke
				(width 0.1)
				(type default)
			)
			(layer "F.Fab")
		)
		(fp_line
			(start 0.120396 0.2794)
			(end -0.12065 0.2794)
			(stroke
				(width 0.1)
				(type default)
			)
			(layer "F.Fab")
		)
		(fp_line
			(start -0.12065 -0.2794)
			(end 0.12065 -0.2794)
			(stroke
				(width 0.1)
				(type default)
			)
			(layer "F.Fab")
		)
		(fp_line
			(start 0.12065 -0.2794)
			(end 0.12065 -0.3048)
			(stroke
				(width 0.1)
				(type default)
			)
			(layer "F.Fab")
		)
		(fp_line
			(start 0.12065 -0.3048)
			(end 0.67945 -0.3048)
			(stroke
				(width 0.1)
				(type default)
			)
			(layer "F.Fab")
		)
		(fp_line
			(start 0.67945 -0.3048)
			(end 0.67945 0.3048)
			(stroke
				(width 0.1)
				(type default)
			)
			(layer "F.Fab")
		)
		(fp_line
			(start -0.67945 -0.305054)
			(end -0.12065 -0.305054)
			(stroke
				(width 0.1)
				(type default)
			)
			(layer "F.Fab")
		)
		(fp_line
			(start -0.12065 -0.305054)
			(end -0.12065 -0.2794)
			(stroke
				(width 0.1)
				(type default)
			)
			(layer "F.Fab")
		)
		(pad "1" smd circle
			(at -0.40005 0 270)
			(size 0 0)
			(layers "F.Cu" "F.Mask" "F.Paste")
			(net "GND")
		)
		(pad "2" smd circle
			(at 0.40005 0 270)
			(size 0 0)
			(layers "F.Cu" "F.Mask" "F.Paste")
			(net "GPU_FPGA_EROT_RECOV_N")
		)
	)
	(footprint ""
		(layer "F.Cu")
		(at 371.16258 -343.952322 90)
		(property "Reference" "C762"
			(at 0 0 90)
			(layer "F.SilkS")
			(hide yes)
			(effects
				(font
					(size 1.27 1.27)
				)
			)
		)
		(property "Value" ""
			(at 0 0 90)
			(layer "F.Fab")
			(effects
				(font
					(size 1.27 1.27)
				)
			)
		)
		(duplicate_pad_numbers_are_jumpers no)
		(fp_line
			(start 0.299974 -0.150114)
			(end 0.299974 0.150114)
			(stroke
				(width 0.1)
				(type default)
			)
			(layer "F.Fab")
		)
		(fp_line
			(start -0.299974 -0.150114)
			(end 0.299974 -0.150114)
			(stroke
				(width 0.1)
				(type default)
			)
			(layer "F.Fab")
		)
		(fp_line
			(start 0.299974 0.150114)
			(end -0.299974 0.150114)
			(stroke
				(width 0.1)
				(type default)
			)
			(layer "F.Fab")
		)
		(fp_line
			(start -0.299974 0.150114)
			(end -0.299974 -0.150114)
			(stroke
				(width 0.1)
				(type default)
			)
			(layer "F.Fab")
		)
		(pad "1" smd rect
			(at -0.2667 0 90)
			(size 0.3048 0.381)
			(layers "F.Cu" "F.Mask" "F.Paste")
			(net "P5E_PEX3_STN6_TX_DP<111>")
		)
		(pad "2" smd rect
			(at 0.2667 0 90)
			(size 0.3048 0.381)
			(layers "F.Cu" "F.Mask" "F.Paste")
			(net "P5E_PEX3_STN6_TX_C_DP<111>")
		)
	)
	(footprint ""
		(layer "F.Cu")
		(at 326.30237 -227.711 90)
		(property "Reference" "R6177"
			(at 0 0 90)
			(layer "F.SilkS")
			(hide yes)
			(effects
				(font
					(size 1.27 1.27)
				)
			)
		)
		(property "Value" ""
			(at 0 0 90)
			(layer "F.Fab")
			(effects
				(font
					(size 1.27 1.27)
				)
			)
		)
		(duplicate_pad_numbers_are_jumpers no)
		(fp_line
			(start 0.7874 -0.4064)
			(end 0.7874 0.4064)
			(stroke
				(width 0.1524)
				(type default)
			)
			(layer "F.SilkS")
		)
		(fp_line
			(start -0.7874 -0.4064)
			(end 0.7874 -0.4064)
			(stroke
				(width 0.1524)
				(type default)
			)
			(layer "F.SilkS")
		)
		(fp_line
			(start 0.7874 0.4064)
			(end -0.7874 0.4064)
			(stroke
				(width 0.1524)
				(type default)
			)
			(layer "F.SilkS")
		)
		(fp_line
			(start -0.7874 0.4064)
			(end -0.7874 -0.4064)
			(stroke
				(width 0.1524)
				(type default)
			)
			(layer "F.SilkS")
		)
		(fp_line
			(start -0.12065 -0.305054)
			(end -0.12065 -0.2794)
			(stroke
				(width 0.1)
				(type default)
			)
			(layer "F.Fab")
		)
		(fp_line
			(start -0.67945 -0.305054)
			(end -0.12065 -0.305054)
			(stroke
				(width 0.1)
				(type default)
			)
			(layer "F.Fab")
		)
		(fp_line
			(start 0.67945 -0.3048)
			(end 0.67945 0.3048)
			(stroke
				(width 0.1)
				(type default)
			)
			(layer "F.Fab")
		)
		(fp_line
			(start 0.12065 -0.3048)
			(end 0.67945 -0.3048)
			(stroke
				(width 0.1)
				(type default)
			)
			(layer "F.Fab")
		)
		(fp_line
			(start 0.12065 -0.2794)
			(end 0.12065 -0.3048)
			(stroke
				(width 0.1)
				(type default)
			)
			(layer "F.Fab")
		)
		(fp_line
			(start -0.12065 -0.2794)
			(end 0.12065 -0.2794)
			(stroke
				(width 0.1)
				(type default)
			)
			(layer "F.Fab")
		)
		(fp_line
			(start 0.120396 0.2794)
			(end -0.12065 0.2794)
			(stroke
				(width 0.1)
				(type default)
			)
			(layer "F.Fab")
		)
		(fp_line
			(start -0.12065 0.2794)
			(end -0.12065 0.3048)
			(stroke
				(width 0.1)
				(type default)
			)
			(layer "F.Fab")
		)
		(fp_line
			(start 0.67945 0.3048)
			(end 0.120396 0.3048)
			(stroke
				(width 0.1)
				(type default)
			)
			(layer "F.Fab")
		)
		(fp_line
			(start 0.120396 0.3048)
			(end 0.120396 0.2794)
			(stroke
				(width 0.1)
				(type default)
			)
			(layer "F.Fab")
		)
		(fp_line
			(start -0.12065 0.3048)
			(end -0.67945 0.3048)
			(stroke
				(width 0.1)
				(type default)
			)
			(layer "F.Fab")
		)
		(fp_line
			(start -0.67945 0.3048)
			(end -0.67945 -0.305054)
			(stroke
				(width 0.1)
				(type default)
			)
			(layer "F.Fab")
		)
		(pad "1" smd circle
			(at -0.40005 0 90)
			(size 0 0)
			(layers "F.Cu" "F.Mask" "F.Paste")
			(net "GND")
		)
		(pad "2" smd circle
			(at 0.40005 0 90)
			(size 0 0)
			(layers "F.Cu" "F.Mask" "F.Paste")
			(net "RST_PEX_SYS_R_N")
		)
	)
	(footprint ""
		(layer "F.Cu")
		(at 68.479162 -350.098614 90)
		(property "Reference" "C122"
			(at 0 0 90)
			(layer "F.SilkS")
			(hide yes)
			(effects
				(font
					(size 1.27 1.27)
				)
			)
		)
		(property "Value" ""
			(at 0 0 90)
			(layer "F.Fab")
			(effects
				(font
					(size 1.27 1.27)
				)
			)
		)
		(duplicate_pad_numbers_are_jumpers no)
		(fp_line
			(start 0.299974 -0.150114)
			(end 0.299974 0.150114)
			(stroke
				(width 0.1)
				(type default)
			)
			(layer "F.Fab")
		)
		(fp_line
			(start -0.299974 -0.150114)
			(end 0.299974 -0.150114)
			(stroke
				(width 0.1)
				(type default)
			)
			(layer "F.Fab")
		)
		(fp_line
			(start 0.299974 0.150114)
			(end -0.299974 0.150114)
			(stroke
				(width 0.1)
				(type default)
			)
			(layer "F.Fab")
		)
		(fp_line
			(start -0.299974 0.150114)
			(end -0.299974 -0.150114)
			(stroke
				(width 0.1)
				(type default)
			)
			(layer "F.Fab")
		)
		(pad "1" smd rect
			(at -0.2667 0 90)
			(size 0.3048 0.381)
			(layers "F.Cu" "F.Mask" "F.Paste")
			(net "P5E_PEX0_STN5_TX_DN<83>")
		)
		(pad "2" smd rect
			(at 0.2667 0 90)
			(size 0.3048 0.381)
			(layers "F.Cu" "F.Mask" "F.Paste")
			(net "P5E_PEX0_STN5_TX_C_DN<83>")
		)
	)
	(footprint ""
		(layer "F.Cu")
		(at 220.36786 -51.019456)
		(property "Reference" "PC399"
			(at 0 0 0)
			(layer "F.SilkS")
			(hide yes)
			(effects
				(font
					(size 1.27 1.27)
				)
			)
		)
		(property "Value" ""
			(at 0 0 0)
			(layer "F.Fab")
			(effects
				(font
					(size 1.27 1.27)
				)
			)
		)
		(duplicate_pad_numbers_are_jumpers no)
		(fp_line
			(start -0.7874 -0.4064)
			(end 0.7874 -0.4064)
			(stroke
				(width 0.1524)
				(type default)
			)
			(layer "F.SilkS")
		)
		(fp_line
			(start -0.7874 0.4064)
			(end -0.7874 -0.4064)
			(stroke
				(width 0.1524)
				(type default)
			)
			(layer "F.SilkS")
		)
		(fp_line
			(start 0.7874 -0.4064)
			(end 0.7874 0.4064)
			(stroke
				(width 0.1524)
				(type default)
			)
			(layer "F.SilkS")
		)
		(fp_line
			(start 0.7874 0.4064)
			(end -0.7874 0.4064)
			(stroke
				(width 0.1524)
				(type default)
			)
			(layer "F.SilkS")
		)
		(fp_line
			(start -0.6858 -0.3048)
			(end -0.1016 -0.3048)
			(stroke
				(width 0.1)
				(type default)
			)
			(layer "F.Fab")
		)
		(fp_line
			(start -0.6858 0.3048)
			(end -0.6858 -0.3048)
			(stroke
				(width 0.1)
				(type default)
			)
			(layer "F.Fab")
		)
		(fp_line
			(start -0.1016 -0.3048)
			(end -0.1016 -0.2794)
			(stroke
				(width 0.1)
				(type default)
			)
			(layer "F.Fab")
		)
		(fp_line
			(start -0.1016 -0.2794)
			(end 0.1016 -0.2794)
			(stroke
				(width 0.1)
				(type default)
			)
			(layer "F.Fab")
		)
		(fp_line
			(start -0.1016 0.2794)
			(end -0.1016 0.3048)
			(stroke
				(width 0.1)
				(type default)
			)
			(layer "F.Fab")
		)
		(fp_line
			(start -0.1016 0.3048)
			(end -0.6858 0.3048)
			(stroke
				(width 0.1)
				(type default)
			)
			(layer "F.Fab")
		)
		(fp_line
			(start 0.1016 -0.3048)
			(end 0.6858 -0.3048)
			(stroke
				(width 0.1)
				(type default)
			)
			(layer "F.Fab")
		)
		(fp_line
			(start 0.1016 -0.2794)
			(end 0.1016 -0.3048)
			(stroke
				(width 0.1)
				(type default)
			)
			(layer "F.Fab")
		)
		(fp_line
			(start 0.1016 0.2794)
			(end -0.1016 0.2794)
			(stroke
				(width 0.1)
				(type default)
			)
			(layer "F.Fab")
		)
		(fp_line
			(start 0.1016 0.3048)
			(end 0.1016 0.2794)
			(stroke
				(width 0.1)
				(type default)
			)
			(layer "F.Fab")
		)
		(fp_line
			(start 0.6858 -0.3048)
			(end 0.6858 0.3048)
			(stroke
				(width 0.1)
				(type default)
			)
			(layer "F.Fab")
		)
		(fp_line
			(start 0.6858 0.3048)
			(end 0.1016 0.3048)
			(stroke
				(width 0.1)
				(type default)
			)
			(layer "F.Fab")
		)
		(pad "1" smd rect
			(at -0.40005 0 180)
			(size 0.4572 0.508)
			(layers "F.Cu" "F.Mask" "F.Paste")
			(net "P12V_SSD7_SS")
		)
		(pad "2" smd rect
			(at 0.40005 0 180)
			(size 0.4572 0.508)
			(layers "F.Cu" "F.Mask" "F.Paste")
			(net "GND")
		)
	)
	(footprint ""
		(layer "F.Cu")
		(at 276.039834 -70.52437 90)
		(property "Reference" "PC864"
			(at 0 0 90)
			(layer "F.SilkS")
			(hide yes)
			(effects
				(font
					(size 1.27 1.27)
				)
			)
		)
		(property "Value" ""
			(at 0 0 90)
			(layer "F.Fab")
			(effects
				(font
					(size 1.27 1.27)
				)
			)
		)
		(duplicate_pad_numbers_are_jumpers no)
		(fp_line
			(start 1.524 -0.762)
			(end 1.524 0.762)
			(stroke
				(width 0.1524)
				(type default)
			)
			(layer "F.SilkS")
		)
		(fp_line
			(start -1.524 -0.762)
			(end 1.524 -0.762)
			(stroke
				(width 0.1524)
				(type default)
			)
			(layer "F.SilkS")
		)
		(fp_line
			(start 1.524 0.762)
			(end -1.524 0.762)
			(stroke
				(width 0.1524)
				(type default)
			)
			(layer "F.SilkS")
		)
		(fp_line
			(start -1.524 0.762)
			(end -1.524 -0.762)
			(stroke
				(width 0.1524)
				(type default)
			)
			(layer "F.SilkS")
		)
		(fp_line
			(start 1.1049 -0.724916)
			(end -1.1049 -0.724916)
			(stroke
				(width 0.1)
				(type default)
			)
			(layer "F.Fab")
		)
		(fp_line
			(start -1.1049 -0.724916)
			(end -1.1049 0.724916)
			(stroke
				(width 0.1)
				(type default)
			)
			(layer "F.Fab")
		)
		(fp_line
			(start 1.1049 0.724916)
			(end 1.1049 -0.724916)
			(stroke
				(width 0.1)
				(type default)
			)
			(layer "F.Fab")
		)
		(fp_line
			(start -1.1049 0.724916)
			(end 1.1049 0.724916)
			(stroke
				(width 0.1)
				(type default)
			)
			(layer "F.Fab")
		)
		(pad "1" smd rect
			(at -0.889 0 270)
			(size 1.016 1.27)
			(layers "F.Cu" "F.Mask" "F.Paste")
			(net "P12V_SSD9_R")
		)
		(pad "2" smd rect
			(at 0.889 0 270)
			(size 1.016 1.27)
			(layers "F.Cu" "F.Mask" "F.Paste")
			(net "GND")
		)
	)
	(footprint ""
		(layer "F.Cu")
		(at 58.684922 -383.652268 180)
		(property "Reference" "R1802"
			(at 0 0 180)
			(layer "F.SilkS")
			(hide yes)
			(effects
				(font
					(size 1.27 1.27)
				)
			)
		)
		(property "Value" ""
			(at 0 0 180)
			(layer "F.Fab")
			(effects
				(font
					(size 1.27 1.27)
				)
			)
		)
		(duplicate_pad_numbers_are_jumpers no)
		(fp_line
			(start 0.7874 0.4064)
			(end -0.7874 0.4064)
			(stroke
				(width 0.1524)
				(type default)
			)
			(layer "F.SilkS")
		)
		(fp_line
			(start 0.7874 -0.4064)
			(end 0.7874 0.4064)
			(stroke
				(width 0.1524)
				(type default)
			)
			(layer "F.SilkS")
		)
		(fp_line
			(start -0.7874 0.4064)
			(end -0.7874 -0.4064)
			(stroke
				(width 0.1524)
				(type default)
			)
			(layer "F.SilkS")
		)
		(fp_line
			(start -0.7874 -0.4064)
			(end 0.7874 -0.4064)
			(stroke
				(width 0.1524)
				(type default)
			)
			(layer "F.SilkS")
		)
		(fp_line
			(start 0.67945 0.3048)
			(end 0.120396 0.3048)
			(stroke
				(width 0.1)
				(type default)
			)
			(layer "F.Fab")
		)
		(fp_line
			(start 0.67945 -0.3048)
			(end 0.67945 0.3048)
			(stroke
				(width 0.1)
				(type default)
			)
			(layer "F.Fab")
		)
		(fp_line
			(start 0.12065 -0.2794)
			(end 0.12065 -0.3048)
			(stroke
				(width 0.1)
				(type default)
			)
			(layer "F.Fab")
		)
		(fp_line
			(start 0.12065 -0.3048)
			(end 0.67945 -0.3048)
			(stroke
				(width 0.1)
				(type default)
			)
			(layer "F.Fab")
		)
		(fp_line
			(start 0.120396 0.3048)
			(end 0.120396 0.2794)
			(stroke
				(width 0.1)
				(type default)
			)
			(layer "F.Fab")
		)
		(fp_line
			(start 0.120396 0.2794)
			(end -0.12065 0.2794)
			(stroke
				(width 0.1)
				(type default)
			)
			(layer "F.Fab")
		)
		(fp_line
			(start -0.12065 0.3048)
			(end -0.67945 0.3048)
			(stroke
				(width 0.1)
				(type default)
			)
			(layer "F.Fab")
		)
		(fp_line
			(start -0.12065 0.2794)
			(end -0.12065 0.3048)
			(stroke
				(width 0.1)
				(type default)
			)
			(layer "F.Fab")
		)
		(fp_line
			(start -0.12065 -0.2794)
			(end 0.12065 -0.2794)
			(stroke
				(width 0.1)
				(type default)
			)
			(layer "F.Fab")
		)
		(fp_line
			(start -0.12065 -0.305054)
			(end -0.12065 -0.2794)
			(stroke
				(width 0.1)
				(type default)
			)
			(layer "F.Fab")
		)
		(fp_line
			(start -0.67945 0.3048)
			(end -0.67945 -0.305054)
			(stroke
				(width 0.1)
				(type default)
			)
			(layer "F.Fab")
		)
		(fp_line
			(start -0.67945 -0.305054)
			(end -0.12065 -0.305054)
			(stroke
				(width 0.1)
				(type default)
			)
			(layer "F.Fab")
		)
		(pad "1" smd circle
			(at -0.40005 0 180)
			(size 0 0)
			(layers "F.Cu" "F.Mask" "F.Paste")
			(net "PRSNT_SWB_C_N")
		)
		(pad "2" smd circle
			(at 0.40005 0 180)
			(size 0 0)
			(layers "F.Cu" "F.Mask" "F.Paste")
			(net "GND")
		)
	)
	(footprint ""
		(layer "F.Cu")
		(at 400.05762 -350.098614 90)
		(property "Reference" "C735"
			(at 0 0 90)
			(layer "F.SilkS")
			(hide yes)
			(effects
				(font
					(size 1.27 1.27)
				)
			)
		)
		(property "Value" ""
			(at 0 0 90)
			(layer "F.Fab")
			(effects
				(font
					(size 1.27 1.27)
				)
			)
		)
		(duplicate_pad_numbers_are_jumpers no)
		(fp_line
			(start 0.299974 -0.150114)
			(end 0.299974 0.150114)
			(stroke
				(width 0.1)
				(type default)
			)
			(layer "F.Fab")
		)
		(fp_line
			(start -0.299974 -0.150114)
			(end 0.299974 -0.150114)
			(stroke
				(width 0.1)
				(type default)
			)
			(layer "F.Fab")
		)
		(fp_line
			(start 0.299974 0.150114)
			(end -0.299974 0.150114)
			(stroke
				(width 0.1)
				(type default)
			)
			(layer "F.Fab")
		)
		(fp_line
			(start -0.299974 0.150114)
			(end -0.299974 -0.150114)
			(stroke
				(width 0.1)
				(type default)
			)
			(layer "F.Fab")
		)
		(pad "1" smd rect
			(at -0.2667 0 90)
			(size 0.3048 0.381)
			(layers "F.Cu" "F.Mask" "F.Paste")
			(net "P5E_PEX3_STN5_TX_DN<93>")
		)
		(pad "2" smd rect
			(at 0.2667 0 90)
			(size 0.3048 0.381)
			(layers "F.Cu" "F.Mask" "F.Paste")
			(net "P5E_PEX3_STN5_TX_C_DN<93>")
		)
	)
	(footprint ""
		(layer "F.Cu")
		(at 359.156 -172.974)
		(property "Reference" "R4670"
			(at 0 0 0)
			(layer "F.SilkS")
			(hide yes)
			(effects
				(font
					(size 1.27 1.27)
				)
			)
		)
		(property "Value" ""
			(at 0 0 0)
			(layer "F.Fab")
			(effects
				(font
					(size 1.27 1.27)
				)
			)
		)
		(duplicate_pad_numbers_are_jumpers no)
		(fp_line
			(start -0.7874 -0.4064)
			(end 0.7874 -0.4064)
			(stroke
				(width 0.1524)
				(type default)
			)
			(layer "F.SilkS")
		)
		(fp_line
			(start -0.7874 0.4064)
			(end -0.7874 -0.4064)
			(stroke
				(width 0.1524)
				(type default)
			)
			(layer "F.SilkS")
		)
		(fp_line
			(start 0.7874 -0.4064)
			(end 0.7874 0.4064)
			(stroke
				(width 0.1524)
				(type default)
			)
			(layer "F.SilkS")
		)
		(fp_line
			(start 0.7874 0.4064)
			(end -0.7874 0.4064)
			(stroke
				(width 0.1524)
				(type default)
			)
			(layer "F.SilkS")
		)
		(fp_line
			(start -0.67945 -0.305054)
			(end -0.12065 -0.305054)
			(stroke
				(width 0.1)
				(type default)
			)
			(layer "F.Fab")
		)
		(fp_line
			(start -0.67945 0.3048)
			(end -0.67945 -0.305054)
			(stroke
				(width 0.1)
				(type default)
			)
			(layer "F.Fab")
		)
		(fp_line
			(start -0.12065 -0.305054)
			(end -0.12065 -0.2794)
			(stroke
				(width 0.1)
				(type default)
			)
			(layer "F.Fab")
		)
		(fp_line
			(start -0.12065 -0.2794)
			(end 0.12065 -0.2794)
			(stroke
				(width 0.1)
				(type default)
			)
			(layer "F.Fab")
		)
		(fp_line
			(start -0.12065 0.2794)
			(end -0.12065 0.3048)
			(stroke
				(width 0.1)
				(type default)
			)
			(layer "F.Fab")
		)
		(fp_line
			(start -0.12065 0.3048)
			(end -0.67945 0.3048)
			(stroke
				(width 0.1)
				(type default)
			)
			(layer "F.Fab")
		)
		(fp_line
			(start 0.120396 0.2794)
			(end -0.12065 0.2794)
			(stroke
				(width 0.1)
				(type default)
			)
			(layer "F.Fab")
		)
		(fp_line
			(start 0.120396 0.3048)
			(end 0.120396 0.2794)
			(stroke
				(width 0.1)
				(type default)
			)
			(layer "F.Fab")
		)
		(fp_line
			(start 0.12065 -0.3048)
			(end 0.67945 -0.3048)
			(stroke
				(width 0.1)
				(type default)
			)
			(layer "F.Fab")
		)
		(fp_line
			(start 0.12065 -0.2794)
			(end 0.12065 -0.3048)
			(stroke
				(width 0.1)
				(type default)
			)
			(layer "F.Fab")
		)
		(fp_line
			(start 0.67945 -0.3048)
			(end 0.67945 0.3048)
			(stroke
				(width 0.1)
				(type default)
			)
			(layer "F.Fab")
		)
		(fp_line
			(start 0.67945 0.3048)
			(end 0.120396 0.3048)
			(stroke
				(width 0.1)
				(type default)
			)
			(layer "F.Fab")
		)
		(pad "1" smd circle
			(at -0.40005 0)
			(size 0 0)
			(layers "F.Cu" "F.Mask" "F.Paste")
			(net "P3V3_AUX")
		)
		(pad "2" smd circle
			(at 0.40005 0)
			(size 0 0)
			(layers "F.Cu" "F.Mask" "F.Paste")
			(net "RST_PEX_SSD7_PERST_R_N")
		)
	)
	(footprint ""
		(layer "F.Cu")
		(at 219.202 -208.788 180)
		(property "Reference" "C2555"
			(at 0 0 180)
			(layer "F.SilkS")
			(hide yes)
			(effects
				(font
					(size 1.27 1.27)
				)
			)
		)
		(property "Value" ""
			(at 0 0 180)
			(layer "F.Fab")
			(effects
				(font
					(size 1.27 1.27)
				)
			)
		)
		(duplicate_pad_numbers_are_jumpers no)
		(fp_line
			(start 0.7874 0.4064)
			(end -0.7874 0.4064)
			(stroke
				(width 0.1524)
				(type default)
			)
			(layer "F.SilkS")
		)
		(fp_line
			(start 0.7874 -0.4064)
			(end 0.7874 0.4064)
			(stroke
				(width 0.1524)
				(type default)
			)
			(layer "F.SilkS")
		)
		(fp_line
			(start -0.7874 0.4064)
			(end -0.7874 -0.4064)
			(stroke
				(width 0.1524)
				(type default)
			)
			(layer "F.SilkS")
		)
		(fp_line
			(start -0.7874 -0.4064)
			(end 0.7874 -0.4064)
			(stroke
				(width 0.1524)
				(type default)
			)
			(layer "F.SilkS")
		)
		(fp_line
			(start 0.67945 0.3048)
			(end 0.120396 0.3048)
			(stroke
				(width 0.1)
				(type default)
			)
			(layer "F.Fab")
		)
		(fp_line
			(start 0.67945 -0.3048)
			(end 0.67945 0.3048)
			(stroke
				(width 0.1)
				(type default)
			)
			(layer "F.Fab")
		)
		(fp_line
			(start 0.12065 -0.2794)
			(end 0.12065 -0.3048)
			(stroke
				(width 0.1)
				(type default)
			)
			(layer "F.Fab")
		)
		(fp_line
			(start 0.12065 -0.3048)
			(end 0.67945 -0.3048)
			(stroke
				(width 0.1)
				(type default)
			)
			(layer "F.Fab")
		)
		(fp_line
			(start 0.120396 0.3048)
			(end 0.120396 0.2794)
			(stroke
				(width 0.1)
				(type default)
			)
			(layer "F.Fab")
		)
		(fp_line
			(start 0.120396 0.2794)
			(end -0.12065 0.2794)
			(stroke
				(width 0.1)
				(type default)
			)
			(layer "F.Fab")
		)
		(fp_line
			(start -0.12065 0.3048)
			(end -0.67945 0.3048)
			(stroke
				(width 0.1)
				(type default)
			)
			(layer "F.Fab")
		)
		(fp_line
			(start -0.12065 0.2794)
			(end -0.12065 0.3048)
			(stroke
				(width 0.1)
				(type default)
			)
			(layer "F.Fab")
		)
		(fp_line
			(start -0.12065 -0.2794)
			(end 0.12065 -0.2794)
			(stroke
				(width 0.1)
				(type default)
			)
			(layer "F.Fab")
		)
		(fp_line
			(start -0.12065 -0.305054)
			(end -0.12065 -0.2794)
			(stroke
				(width 0.1)
				(type default)
			)
			(layer "F.Fab")
		)
		(fp_line
			(start -0.67945 0.3048)
			(end -0.67945 -0.305054)
			(stroke
				(width 0.1)
				(type default)
			)
			(layer "F.Fab")
		)
		(fp_line
			(start -0.67945 -0.305054)
			(end -0.12065 -0.305054)
			(stroke
				(width 0.1)
				(type default)
			)
			(layer "F.Fab")
		)
		(pad "1" smd circle
			(at -0.40005 0 180)
			(size 0 0)
			(layers "F.Cu" "F.Mask" "F.Paste")
			(net "GND")
		)
		(pad "2" smd circle
			(at 0.40005 0 180)
			(size 0 0)
			(layers "F.Cu" "F.Mask" "F.Paste")
			(net "P3V3_NIC4")
		)
	)
	(footprint ""
		(layer "F.Cu")
		(at 19.838924 -167.891714 -90)
		(property "Reference" "PC17"
			(at 0 0 270)
			(layer "F.SilkS")
			(hide yes)
			(effects
				(font
					(size 1.27 1.27)
				)
			)
		)
		(property "Value" ""
			(at 0 0 270)
			(layer "F.Fab")
			(effects
				(font
					(size 1.27 1.27)
				)
			)
		)
		(duplicate_pad_numbers_are_jumpers no)
		(fp_line
			(start -0.7874 0.4064)
			(end -0.7874 -0.4064)
			(stroke
				(width 0.1524)
				(type default)
			)
			(layer "F.SilkS")
		)
		(fp_line
			(start 0.7874 0.4064)
			(end -0.7874 0.4064)
			(stroke
				(width 0.1524)
				(type default)
			)
			(layer "F.SilkS")
		)
		(fp_line
			(start -0.7874 -0.4064)
			(end 0.7874 -0.4064)
			(stroke
				(width 0.1524)
				(type default)
			)
			(layer "F.SilkS")
		)
		(fp_line
			(start 0.7874 -0.4064)
			(end 0.7874 0.4064)
			(stroke
				(width 0.1524)
				(type default)
			)
			(layer "F.SilkS")
		)
		(fp_line
			(start -0.67945 0.3048)
			(end -0.67945 -0.305054)
			(stroke
				(width 0.1)
				(type default)
			)
			(layer "F.Fab")
		)
		(fp_line
			(start -0.12065 0.3048)
			(end -0.67945 0.3048)
			(stroke
				(width 0.1)
				(type default)
			)
			(layer "F.Fab")
		)
		(fp_line
			(start 0.120396 0.3048)
			(end 0.120396 0.2794)
			(stroke
				(width 0.1)
				(type default)
			)
			(layer "F.Fab")
		)
		(fp_line
			(start 0.67945 0.3048)
			(end 0.120396 0.3048)
			(stroke
				(width 0.1)
				(type default)
			)
			(layer "F.Fab")
		)
		(fp_line
			(start -0.12065 0.2794)
			(end -0.12065 0.3048)
			(stroke
				(width 0.1)
				(type default)
			)
			(layer "F.Fab")
		)
		(fp_line
			(start 0.120396 0.2794)
			(end -0.12065 0.2794)
			(stroke
				(width 0.1)
				(type default)
			)
			(layer "F.Fab")
		)
		(fp_line
			(start -0.12065 -0.2794)
			(end 0.12065 -0.2794)
			(stroke
				(width 0.1)
				(type default)
			)
			(layer "F.Fab")
		)
		(fp_line
			(start 0.12065 -0.2794)
			(end 0.12065 -0.3048)
			(stroke
				(width 0.1)
				(type default)
			)
			(layer "F.Fab")
		)
		(fp_line
			(start 0.12065 -0.3048)
			(end 0.67945 -0.3048)
			(stroke
				(width 0.1)
				(type default)
			)
			(layer "F.Fab")
		)
		(fp_line
			(start 0.67945 -0.3048)
			(end 0.67945 0.3048)
			(stroke
				(width 0.1)
				(type default)
			)
			(layer "F.Fab")
		)
		(fp_line
			(start -0.67945 -0.305054)
			(end -0.12065 -0.305054)
			(stroke
				(width 0.1)
				(type default)
			)
			(layer "F.Fab")
		)
		(fp_line
			(start -0.12065 -0.305054)
			(end -0.12065 -0.2794)
			(stroke
				(width 0.1)
				(type default)
			)
			(layer "F.Fab")
		)
		(pad "1" smd circle
			(at -0.40005 0 270)
			(size 0 0)
			(layers "F.Cu" "F.Mask" "F.Paste")
			(net "SW_P12V_P5V_AUX_FLT")
		)
		(pad "2" smd circle
			(at 0.40005 0 270)
			(size 0 0)
			(layers "F.Cu" "F.Mask" "F.Paste")
			(net "GND")
		)
	)
	(footprint ""
		(layer "F.Cu")
		(at 97.738438 -44.341542 90)
		(property "Reference" "C308"
			(at 0 0 90)
			(layer "F.SilkS")
			(hide yes)
			(effects
				(font
					(size 1.27 1.27)
				)
			)
		)
		(property "Value" ""
			(at 0 0 90)
			(layer "F.Fab")
			(effects
				(font
					(size 1.27 1.27)
				)
			)
		)
		(duplicate_pad_numbers_are_jumpers no)
		(fp_line
			(start 0.7874 -0.4064)
			(end 0.7874 0.4064)
			(stroke
				(width 0.1524)
				(type default)
			)
			(layer "F.SilkS")
		)
		(fp_line
			(start -0.7874 -0.4064)
			(end 0.7874 -0.4064)
			(stroke
				(width 0.1524)
				(type default)
			)
			(layer "F.SilkS")
		)
		(fp_line
			(start 0.7874 0.4064)
			(end -0.7874 0.4064)
			(stroke
				(width 0.1524)
				(type default)
			)
			(layer "F.SilkS")
		)
		(fp_line
			(start -0.7874 0.4064)
			(end -0.7874 -0.4064)
			(stroke
				(width 0.1524)
				(type default)
			)
			(layer "F.SilkS")
		)
		(fp_line
			(start -0.12065 -0.305054)
			(end -0.12065 -0.2794)
			(stroke
				(width 0.1)
				(type default)
			)
			(layer "F.Fab")
		)
		(fp_line
			(start -0.67945 -0.305054)
			(end -0.12065 -0.305054)
			(stroke
				(width 0.1)
				(type default)
			)
			(layer "F.Fab")
		)
		(fp_line
			(start 0.67945 -0.3048)
			(end 0.67945 0.3048)
			(stroke
				(width 0.1)
				(type default)
			)
			(layer "F.Fab")
		)
		(fp_line
			(start 0.12065 -0.3048)
			(end 0.67945 -0.3048)
			(stroke
				(width 0.1)
				(type default)
			)
			(layer "F.Fab")
		)
		(fp_line
			(start 0.12065 -0.2794)
			(end 0.12065 -0.3048)
			(stroke
				(width 0.1)
				(type default)
			)
			(layer "F.Fab")
		)
		(fp_line
			(start -0.12065 -0.2794)
			(end 0.12065 -0.2794)
			(stroke
				(width 0.1)
				(type default)
			)
			(layer "F.Fab")
		)
		(fp_line
			(start 0.120396 0.2794)
			(end -0.12065 0.2794)
			(stroke
				(width 0.1)
				(type default)
			)
			(layer "F.Fab")
		)
		(fp_line
			(start -0.12065 0.2794)
			(end -0.12065 0.3048)
			(stroke
				(width 0.1)
				(type default)
			)
			(layer "F.Fab")
		)
		(fp_line
			(start 0.67945 0.3048)
			(end 0.120396 0.3048)
			(stroke
				(width 0.1)
				(type default)
			)
			(layer "F.Fab")
		)
		(fp_line
			(start 0.120396 0.3048)
			(end 0.120396 0.2794)
			(stroke
				(width 0.1)
				(type default)
			)
			(layer "F.Fab")
		)
		(fp_line
			(start -0.12065 0.3048)
			(end -0.67945 0.3048)
			(stroke
				(width 0.1)
				(type default)
			)
			(layer "F.Fab")
		)
		(fp_line
			(start -0.67945 0.3048)
			(end -0.67945 -0.305054)
			(stroke
				(width 0.1)
				(type default)
			)
			(layer "F.Fab")
		)
		(pad "1" smd circle
			(at -0.40005 0 90)
			(size 0 0)
			(layers "F.Cu" "F.Mask" "F.Paste")
			(net "P12V_SSD3_VIN_P")
		)
		(pad "2" smd circle
			(at 0.40005 0 90)
			(size 0 0)
			(layers "F.Cu" "F.Mask" "F.Paste")
			(net "P12V_SSD3_VIN_N")
		)
	)
	(footprint ""
		(layer "F.Cu")
		(at 377.949714 -320.900044)
		(property "Reference" "H95"
			(at -6.547358 -7.430008 0)
			(unlocked yes)
			(layer "F.SilkS")
			(effects
				(font
					(size 0.7874 0.5842)
					(thickness 0.1524)
				)
				(justify left)
			)
		)
		(property "Value" ""
			(at 0 0 0)
			(layer "F.Fab")
			(effects
				(font
					(size 1.27 1.27)
				)
			)
		)
		(duplicate_pad_numbers_are_jumpers no)
		(fp_arc
			(start 5.586984 5.725922)
			(mid -7.372531 -3.10691)
			(end 7.999984 0)
			(stroke
				(width 0.1524)
				(type default)
			)
			(layer "F.SilkS")
		)
		(fp_arc
			(start -6.82498 -4.172966)
			(mid 2.167755 -7.700511)
			(end 7.999984 0)
			(stroke
				(width 0.1524)
				(type default)
			)
			(layer "B.SilkS")
		)
		(fp_arc
			(start -6.018022 5.2705)
			(mid -7.86291 1.472295)
			(end -7.51713 -2.736088)
			(stroke
				(width 0.1524)
				(type default)
			)
			(layer "B.SilkS")
		)
		(fp_arc
			(start 5.690108 5.623306)
			(mid 1.770476 7.801371)
			(end -2.705354 7.528306)
			(stroke
				(width 0.1524)
				(type default)
			)
			(layer "B.SilkS")
		)
		(fp_arc
			(start 7.999984 0)
			(mid 7.997304 0.206063)
			(end 7.989316 0.411988)
			(stroke
				(width 0.1524)
				(type default)
			)
			(layer "B.SilkS")
		)
		(fp_circle
			(center 0 0)
			(end 7.999984 0)
			(stroke
				(width 0.1)
				(type default)
			)
			(fill no)
			(layer "B.Fab")
		)
		(fp_circle
			(center 0 0)
			(end 7.999984 0)
			(stroke
				(width 0.1)
				(type default)
			)
			(fill no)
			(layer "F.Fab")
		)
		(pad "" np_thru_hole circle
			(at 0 0)
			(size 4.5212 4.5212)
			(drill 4.5212)
			(layers "*.Cu" "*.Mask")
			(clearance 0.381)
			(thermal_gap 0.381)
		)
		(pad "2" thru_hole circle
			(at 3.6322 0)
			(size 0.762 0.762)
			(drill 0.5588)
			(layers "*.Cu" "*.Mask")
			(remove_unused_layers no)
			(net "GND")
			(clearance 0.1524)
			(thermal_gap 0.1524)
		)
		(pad "3" thru_hole circle
			(at 2.568448 -2.568448)
			(size 0.762 0.762)
			(drill 0.5588)
			(layers "*.Cu" "*.Mask")
			(remove_unused_layers no)
			(net "GND")
			(clearance 0.1524)
			(thermal_gap 0.1524)
		)
		(pad "4" thru_hole circle
			(at 0 -3.6322)
			(size 0.762 0.762)
			(drill 0.5588)
			(layers "*.Cu" "*.Mask")
			(remove_unused_layers no)
			(net "GND")
			(clearance 0.1524)
			(thermal_gap 0.1524)
		)
		(pad "5" thru_hole circle
			(at -2.568448 -2.568448)
			(size 0.762 0.762)
			(drill 0.5588)
			(layers "*.Cu" "*.Mask")
			(remove_unused_layers no)
			(net "GND")
			(clearance 0.1524)
			(thermal_gap 0.1524)
		)
		(pad "6" thru_hole circle
			(at -3.6322 0)
			(size 0.762 0.762)
			(drill 0.5588)
			(layers "*.Cu" "*.Mask")
			(remove_unused_layers no)
			(net "GND")
			(clearance 0.1524)
			(thermal_gap 0.1524)
		)
		(pad "7" thru_hole circle
			(at -2.568448 2.568448)
			(size 0.762 0.762)
			(drill 0.5588)
			(layers "*.Cu" "*.Mask")
			(remove_unused_layers no)
			(net "GND")
			(clearance 0.1524)
			(thermal_gap 0.1524)
		)
		(pad "8" thru_hole circle
			(at 0 3.6322)
			(size 0.762 0.762)
			(drill 0.5588)
			(layers "*.Cu" "*.Mask")
			(remove_unused_layers no)
			(net "GND")
			(clearance 0.1524)
			(thermal_gap 0.1524)
		)
		(pad "9" thru_hole circle
			(at 2.568448 2.568448)
			(size 0.762 0.762)
			(drill 0.5588)
			(layers "*.Cu" "*.Mask")
			(remove_unused_layers no)
			(net "GND")
			(clearance 0.1524)
			(thermal_gap 0.1524)
		)
		(zone
			(layer "F.Cu")
			(hatch none 0.5)
			(connect_pads
				(clearance 0)
			)
			(min_thickness 0.25)
			(keepout
				(tracks not_allowed)
				(vias allowed)
				(pads allowed)
				(copperpour not_allowed)
				(footprints allowed)
			)
			(placement
				(enabled no)
				(sheetname "")
			)
			(fill
				(thermal_gap 0.5)
				(thermal_bridge_width 0.5)
				(island_removal_mode 0)
			)
			(polygon
				(pts
					(arc
						(start 377.949714 -312.90006)
						(mid 369.94973 -320.900044)
						(end 377.949714 -328.900028)
					)
					(arc
						(start 377.949714 -325.649844)
						(mid 373.199914 -320.900044)
						(end 377.949714 -316.150244)
					)
				)
			)
		)
		(zone
			(layer "F.Cu")
			(hatch none 0.5)
			(connect_pads
				(clearance 0)
			)
			(min_thickness 0.25)
			(keepout
				(tracks not_allowed)
				(vias allowed)
				(pads allowed)
				(copperpour not_allowed)
				(footprints allowed)
			)
			(placement
				(enabled no)
				(sheetname "")
			)
			(fill
				(thermal_gap 0.5)
				(thermal_bridge_width 0.5)
				(island_removal_mode 0)
			)
			(polygon
				(pts
					(arc
						(start 377.949714 -312.90006)
						(mid 385.949698 -320.900044)
						(end 377.949714 -328.900028)
					)
					(arc
						(start 377.949714 -325.649844)
						(mid 382.699514 -320.900044)
						(end 377.949714 -316.150244)
					)
				)
			)
		)
		(zone
			(layers "F.Cu" "B.Cu" "In1.Cu" "In2.Cu" "In3.Cu" "In4.Cu" "In5.Cu" "In6.Cu"
				"In7.Cu" "In8.Cu" "In9.Cu" "In10.Cu" "In11.Cu" "In12.Cu" "In13.Cu" "In14.Cu"
				"In15.Cu" "In16.Cu"
			)
			(hatch none 0.5)
			(connect_pads
				(clearance 0)
			)
			(min_thickness 0.25)
			(keepout
				(tracks not_allowed)
				(vias allowed)
				(pads allowed)
				(copperpour not_allowed)
				(footprints allowed)
			)
			(placement
				(enabled no)
				(sheetname "")
			)
			(fill
				(thermal_gap 0.5)
				(thermal_bridge_width 0.5)
				(island_removal_mode 0)
			)
			(polygon
				(pts
					(arc
						(start 380.715774 -320.900044)
						(mid 375.183654 -320.900044)
						(end 380.715774 -320.900044)
					)
				)
			)
		)
		(zone
			(layer "B.Cu")
			(hatch none 0.5)
			(connect_pads
				(clearance 0)
			)
			(min_thickness 0.25)
			(keepout
				(tracks not_allowed)
				(vias allowed)
				(pads allowed)
				(copperpour not_allowed)
				(footprints allowed)
			)
			(placement
				(enabled no)
				(sheetname "")
			)
			(fill
				(thermal_gap 0.5)
				(thermal_bridge_width 0.5)
				(island_removal_mode 0)
			)
			(polygon
				(pts
					(arc
						(start 377.949714 -315.896244)
						(mid 372.945914 -320.900044)
						(end 377.949714 -325.903844)
					)
					(arc
						(start 377.949714 -325.421244)
						(mid 373.428514 -320.900044)
						(end 377.949714 -316.378844)
					)
				)
			)
		)
		(zone
			(layer "B.Cu")
			(hatch none 0.5)
			(connect_pads
				(clearance 0)
			)
			(min_thickness 0.25)
			(keepout
				(tracks not_allowed)
				(vias allowed)
				(pads allowed)
				(copperpour not_allowed)
				(footprints allowed)
			)
			(placement
				(enabled no)
				(sheetname "")
			)
			(fill
				(thermal_gap 0.5)
				(thermal_bridge_width 0.5)
				(island_removal_mode 0)
			)
			(polygon
				(pts
					(arc
						(start 377.949714 -315.896244)
						(mid 382.953514 -320.900044)
						(end 377.949714 -325.903844)
					)
					(arc
						(start 377.949714 -325.421244)
						(mid 382.470914 -320.900044)
						(end 377.949714 -316.378844)
					)
				)
			)
		)
	)
	(footprint ""
		(layer "F.Cu")
		(at 33.287716 -288.419032)
		(property "Reference" "C3055"
			(at 0 0 0)
			(layer "F.SilkS")
			(hide yes)
			(effects
				(font
					(size 1.27 1.27)
				)
			)
		)
		(property "Value" ""
			(at 0 0 0)
			(layer "F.Fab")
			(effects
				(font
					(size 1.27 1.27)
				)
			)
		)
		(duplicate_pad_numbers_are_jumpers no)
		(fp_line
			(start -1.2954 -0.5842)
			(end 1.2954 -0.5842)
			(stroke
				(width 0.1524)
				(type default)
			)
			(layer "F.SilkS")
		)
		(fp_line
			(start -1.2954 0.5842)
			(end -1.2954 -0.5842)
			(stroke
				(width 0.1524)
				(type default)
			)
			(layer "F.SilkS")
		)
		(fp_line
			(start 1.2954 -0.5842)
			(end 1.2954 0.5842)
			(stroke
				(width 0.1524)
				(type default)
			)
			(layer "F.SilkS")
		)
		(fp_line
			(start 1.2954 0.5842)
			(end -1.2954 0.5842)
			(stroke
				(width 0.1524)
				(type default)
			)
			(layer "F.SilkS")
		)
		(fp_line
			(start -1.1938 -0.4064)
			(end -0.8636 -0.4064)
			(stroke
				(width 0.1)
				(type default)
			)
			(layer "F.Fab")
		)
		(fp_line
			(start -1.1938 0.4064)
			(end -1.1938 -0.4064)
			(stroke
				(width 0.1)
				(type default)
			)
			(layer "F.Fab")
		)
		(fp_line
			(start -0.8636 -0.4572)
			(end 0.8636 -0.4572)
			(stroke
				(width 0.1)
				(type default)
			)
			(layer "F.Fab")
		)
		(fp_line
			(start -0.8636 -0.4064)
			(end -0.8636 -0.4572)
			(stroke
				(width 0.1)
				(type default)
			)
			(layer "F.Fab")
		)
		(fp_line
			(start -0.8636 0.4064)
			(end -1.1938 0.4064)
			(stroke
				(width 0.1)
				(type default)
			)
			(layer "F.Fab")
		)
		(fp_line
			(start -0.8636 0.4572)
			(end -0.8636 0.4064)
			(stroke
				(width 0.1)
				(type default)
			)
			(layer "F.Fab")
		)
		(fp_line
			(start 0.8636 -0.4572)
			(end 0.8636 -0.4064)
			(stroke
				(width 0.1)
				(type default)
			)
			(layer "F.Fab")
		)
		(fp_line
			(start 0.8636 -0.4064)
			(end 1.1938 -0.4064)
			(stroke
				(width 0.1)
				(type default)
			)
			(layer "F.Fab")
		)
		(fp_line
			(start 0.8636 0.4064)
			(end 0.8636 0.4572)
			(stroke
				(width 0.1)
				(type default)
			)
			(layer "F.Fab")
		)
		(fp_line
			(start 0.8636 0.4572)
			(end -0.8636 0.4572)
			(stroke
				(width 0.1)
				(type default)
			)
			(layer "F.Fab")
		)
		(fp_line
			(start 1.1938 -0.4064)
			(end 1.1938 0.4064)
			(stroke
				(width 0.1)
				(type default)
			)
			(layer "F.Fab")
		)
		(fp_line
			(start 1.1938 0.4064)
			(end 0.8636 0.4064)
			(stroke
				(width 0.1)
				(type default)
			)
			(layer "F.Fab")
		)
		(pad "1" smd rect
			(at -0.7366 0 270)
			(size 0.7112 0.8128)
			(layers "F.Cu" "F.Mask" "F.Paste")
			(net "PCEPLL6_VDDA18_PEX0")
		)
		(pad "2" smd rect
			(at 0.7366 0 270)
			(size 0.7112 0.8128)
			(layers "F.Cu" "F.Mask" "F.Paste")
			(net "GND")
		)
	)
	(footprint ""
		(layer "F.Cu")
		(at 154.707844 -163.061396 180)
		(property "Reference" "R106"
			(at 0 0 180)
			(layer "F.SilkS")
			(hide yes)
			(effects
				(font
					(size 1.27 1.27)
				)
			)
		)
		(property "Value" ""
			(at 0 0 180)
			(layer "F.Fab")
			(effects
				(font
					(size 1.27 1.27)
				)
			)
		)
		(duplicate_pad_numbers_are_jumpers no)
		(fp_line
			(start 0.7874 0.4064)
			(end -0.7874 0.4064)
			(stroke
				(width 0.1524)
				(type default)
			)
			(layer "F.SilkS")
		)
		(fp_line
			(start 0.7874 -0.4064)
			(end 0.7874 0.4064)
			(stroke
				(width 0.1524)
				(type default)
			)
			(layer "F.SilkS")
		)
		(fp_line
			(start -0.7874 0.4064)
			(end -0.7874 -0.4064)
			(stroke
				(width 0.1524)
				(type default)
			)
			(layer "F.SilkS")
		)
		(fp_line
			(start -0.7874 -0.4064)
			(end 0.7874 -0.4064)
			(stroke
				(width 0.1524)
				(type default)
			)
			(layer "F.SilkS")
		)
		(fp_line
			(start 0.67945 0.3048)
			(end 0.120396 0.3048)
			(stroke
				(width 0.1)
				(type default)
			)
			(layer "F.Fab")
		)
		(fp_line
			(start 0.67945 -0.3048)
			(end 0.67945 0.3048)
			(stroke
				(width 0.1)
				(type default)
			)
			(layer "F.Fab")
		)
		(fp_line
			(start 0.12065 -0.2794)
			(end 0.12065 -0.3048)
			(stroke
				(width 0.1)
				(type default)
			)
			(layer "F.Fab")
		)
		(fp_line
			(start 0.12065 -0.3048)
			(end 0.67945 -0.3048)
			(stroke
				(width 0.1)
				(type default)
			)
			(layer "F.Fab")
		)
		(fp_line
			(start 0.120396 0.3048)
			(end 0.120396 0.2794)
			(stroke
				(width 0.1)
				(type default)
			)
			(layer "F.Fab")
		)
		(fp_line
			(start 0.120396 0.2794)
			(end -0.12065 0.2794)
			(stroke
				(width 0.1)
				(type default)
			)
			(layer "F.Fab")
		)
		(fp_line
			(start -0.12065 0.3048)
			(end -0.67945 0.3048)
			(stroke
				(width 0.1)
				(type default)
			)
			(layer "F.Fab")
		)
		(fp_line
			(start -0.12065 0.2794)
			(end -0.12065 0.3048)
			(stroke
				(width 0.1)
				(type default)
			)
			(layer "F.Fab")
		)
		(fp_line
			(start -0.12065 -0.2794)
			(end 0.12065 -0.2794)
			(stroke
				(width 0.1)
				(type default)
			)
			(layer "F.Fab")
		)
		(fp_line
			(start -0.12065 -0.305054)
			(end -0.12065 -0.2794)
			(stroke
				(width 0.1)
				(type default)
			)
			(layer "F.Fab")
		)
		(fp_line
			(start -0.67945 0.3048)
			(end -0.67945 -0.305054)
			(stroke
				(width 0.1)
				(type default)
			)
			(layer "F.Fab")
		)
		(fp_line
			(start -0.67945 -0.305054)
			(end -0.12065 -0.305054)
			(stroke
				(width 0.1)
				(type default)
			)
			(layer "F.Fab")
		)
		(pad "1" smd circle
			(at -0.40005 0 180)
			(size 0 0)
			(layers "F.Cu" "F.Mask" "F.Paste")
			(net "PWRGD_NIC2_PWR_GOOD")
		)
		(pad "2" smd circle
			(at 0.40005 0 180)
			(size 0 0)
			(layers "F.Cu" "F.Mask" "F.Paste")
			(net "PWRGD_NIC2_PWR_GOOD_R")
		)
	)
	(footprint ""
		(layer "F.Cu")
		(at 227.566982 -155.998672 -90)
		(property "Reference" "R4209"
			(at 0 0 270)
			(layer "F.SilkS")
			(hide yes)
			(effects
				(font
					(size 1.27 1.27)
				)
			)
		)
		(property "Value" ""
			(at 0 0 270)
			(layer "F.Fab")
			(effects
				(font
					(size 1.27 1.27)
				)
			)
		)
		(duplicate_pad_numbers_are_jumpers no)
		(fp_line
			(start -0.7874 0.4064)
			(end -0.7874 -0.4064)
			(stroke
				(width 0.1524)
				(type default)
			)
			(layer "F.SilkS")
		)
		(fp_line
			(start 0.7874 0.4064)
			(end -0.7874 0.4064)
			(stroke
				(width 0.1524)
				(type default)
			)
			(layer "F.SilkS")
		)
		(fp_line
			(start -0.7874 -0.4064)
			(end 0.7874 -0.4064)
			(stroke
				(width 0.1524)
				(type default)
			)
			(layer "F.SilkS")
		)
		(fp_line
			(start 0.7874 -0.4064)
			(end 0.7874 0.4064)
			(stroke
				(width 0.1524)
				(type default)
			)
			(layer "F.SilkS")
		)
		(fp_line
			(start -0.67945 0.3048)
			(end -0.67945 -0.305054)
			(stroke
				(width 0.1)
				(type default)
			)
			(layer "F.Fab")
		)
		(fp_line
			(start -0.12065 0.3048)
			(end -0.67945 0.3048)
			(stroke
				(width 0.1)
				(type default)
			)
			(layer "F.Fab")
		)
		(fp_line
			(start 0.120396 0.3048)
			(end 0.120396 0.2794)
			(stroke
				(width 0.1)
				(type default)
			)
			(layer "F.Fab")
		)
		(fp_line
			(start 0.67945 0.3048)
			(end 0.120396 0.3048)
			(stroke
				(width 0.1)
				(type default)
			)
			(layer "F.Fab")
		)
		(fp_line
			(start -0.12065 0.2794)
			(end -0.12065 0.3048)
			(stroke
				(width 0.1)
				(type default)
			)
			(layer "F.Fab")
		)
		(fp_line
			(start 0.120396 0.2794)
			(end -0.12065 0.2794)
			(stroke
				(width 0.1)
				(type default)
			)
			(layer "F.Fab")
		)
		(fp_line
			(start -0.12065 -0.2794)
			(end 0.12065 -0.2794)
			(stroke
				(width 0.1)
				(type default)
			)
			(layer "F.Fab")
		)
		(fp_line
			(start 0.12065 -0.2794)
			(end 0.12065 -0.3048)
			(stroke
				(width 0.1)
				(type default)
			)
			(layer "F.Fab")
		)
		(fp_line
			(start 0.12065 -0.3048)
			(end 0.67945 -0.3048)
			(stroke
				(width 0.1)
				(type default)
			)
			(layer "F.Fab")
		)
		(fp_line
			(start 0.67945 -0.3048)
			(end 0.67945 0.3048)
			(stroke
				(width 0.1)
				(type default)
			)
			(layer "F.Fab")
		)
		(fp_line
			(start -0.67945 -0.305054)
			(end -0.12065 -0.305054)
			(stroke
				(width 0.1)
				(type default)
			)
			(layer "F.Fab")
		)
		(fp_line
			(start -0.12065 -0.305054)
			(end -0.12065 -0.2794)
			(stroke
				(width 0.1)
				(type default)
			)
			(layer "F.Fab")
		)
		(pad "1" smd circle
			(at -0.40005 0 270)
			(size 0 0)
			(layers "F.Cu" "F.Mask" "F.Paste")
			(net "GND")
		)
		(pad "2" smd circle
			(at 0.40005 0 270)
			(size 0 0)
			(layers "F.Cu" "F.Mask" "F.Paste")
			(net "PEX_REF_CLK_GEN_EN_N")
		)
	)
	(footprint ""
		(layer "F.Cu")
		(at 353.822 -177.546)
		(property "Reference" "R4757"
			(at 0 0 0)
			(layer "F.SilkS")
			(hide yes)
			(effects
				(font
					(size 1.27 1.27)
				)
			)
		)
		(property "Value" ""
			(at 0 0 0)
			(layer "F.Fab")
			(effects
				(font
					(size 1.27 1.27)
				)
			)
		)
		(duplicate_pad_numbers_are_jumpers no)
		(fp_line
			(start -0.7874 -0.4064)
			(end 0.7874 -0.4064)
			(stroke
				(width 0.1524)
				(type default)
			)
			(layer "F.SilkS")
		)
		(fp_line
			(start -0.7874 0.4064)
			(end -0.7874 -0.4064)
			(stroke
				(width 0.1524)
				(type default)
			)
			(layer "F.SilkS")
		)
		(fp_line
			(start 0.7874 -0.4064)
			(end 0.7874 0.4064)
			(stroke
				(width 0.1524)
				(type default)
			)
			(layer "F.SilkS")
		)
		(fp_line
			(start 0.7874 0.4064)
			(end -0.7874 0.4064)
			(stroke
				(width 0.1524)
				(type default)
			)
			(layer "F.SilkS")
		)
		(fp_line
			(start -0.67945 -0.305054)
			(end -0.12065 -0.305054)
			(stroke
				(width 0.1)
				(type default)
			)
			(layer "F.Fab")
		)
		(fp_line
			(start -0.67945 0.3048)
			(end -0.67945 -0.305054)
			(stroke
				(width 0.1)
				(type default)
			)
			(layer "F.Fab")
		)
		(fp_line
			(start -0.12065 -0.305054)
			(end -0.12065 -0.2794)
			(stroke
				(width 0.1)
				(type default)
			)
			(layer "F.Fab")
		)
		(fp_line
			(start -0.12065 -0.2794)
			(end 0.12065 -0.2794)
			(stroke
				(width 0.1)
				(type default)
			)
			(layer "F.Fab")
		)
		(fp_line
			(start -0.12065 0.2794)
			(end -0.12065 0.3048)
			(stroke
				(width 0.1)
				(type default)
			)
			(layer "F.Fab")
		)
		(fp_line
			(start -0.12065 0.3048)
			(end -0.67945 0.3048)
			(stroke
				(width 0.1)
				(type default)
			)
			(layer "F.Fab")
		)
		(fp_line
			(start 0.120396 0.2794)
			(end -0.12065 0.2794)
			(stroke
				(width 0.1)
				(type default)
			)
			(layer "F.Fab")
		)
		(fp_line
			(start 0.120396 0.3048)
			(end 0.120396 0.2794)
			(stroke
				(width 0.1)
				(type default)
			)
			(layer "F.Fab")
		)
		(fp_line
			(start 0.12065 -0.3048)
			(end 0.67945 -0.3048)
			(stroke
				(width 0.1)
				(type default)
			)
			(layer "F.Fab")
		)
		(fp_line
			(start 0.12065 -0.2794)
			(end 0.12065 -0.3048)
			(stroke
				(width 0.1)
				(type default)
			)
			(layer "F.Fab")
		)
		(fp_line
			(start 0.67945 -0.3048)
			(end 0.67945 0.3048)
			(stroke
				(width 0.1)
				(type default)
			)
			(layer "F.Fab")
		)
		(fp_line
			(start 0.67945 0.3048)
			(end 0.120396 0.3048)
			(stroke
				(width 0.1)
				(type default)
			)
			(layer "F.Fab")
		)
		(pad "1" smd circle
			(at -0.40005 0)
			(size 0 0)
			(layers "F.Cu" "F.Mask" "F.Paste")
			(net "PRSNT_NIC4_FPGA_PCA9555_N")
		)
		(pad "2" smd circle
			(at 0.40005 0)
			(size 0 0)
			(layers "F.Cu" "F.Mask" "F.Paste")
			(net "PRSNT_NIC4_FPGA_R_N")
		)
	)
	(footprint ""
		(layer "F.Cu")
		(at 219.457778 -257.975862 -90)
		(property "Reference" "R6504"
			(at 0 0 270)
			(layer "F.SilkS")
			(hide yes)
			(effects
				(font
					(size 1.27 1.27)
				)
			)
		)
		(property "Value" ""
			(at 0 0 270)
			(layer "F.Fab")
			(effects
				(font
					(size 1.27 1.27)
				)
			)
		)
		(duplicate_pad_numbers_are_jumpers no)
		(fp_line
			(start -0.7874 0.4064)
			(end -0.7874 -0.4064)
			(stroke
				(width 0.1524)
				(type default)
			)
			(layer "F.SilkS")
		)
		(fp_line
			(start 0.7874 0.4064)
			(end -0.7874 0.4064)
			(stroke
				(width 0.1524)
				(type default)
			)
			(layer "F.SilkS")
		)
		(fp_line
			(start -0.7874 -0.4064)
			(end 0.7874 -0.4064)
			(stroke
				(width 0.1524)
				(type default)
			)
			(layer "F.SilkS")
		)
		(fp_line
			(start 0.7874 -0.4064)
			(end 0.7874 0.4064)
			(stroke
				(width 0.1524)
				(type default)
			)
			(layer "F.SilkS")
		)
		(fp_line
			(start -0.67945 0.3048)
			(end -0.67945 -0.305054)
			(stroke
				(width 0.1)
				(type default)
			)
			(layer "F.Fab")
		)
		(fp_line
			(start -0.12065 0.3048)
			(end -0.67945 0.3048)
			(stroke
				(width 0.1)
				(type default)
			)
			(layer "F.Fab")
		)
		(fp_line
			(start 0.120396 0.3048)
			(end 0.120396 0.2794)
			(stroke
				(width 0.1)
				(type default)
			)
			(layer "F.Fab")
		)
		(fp_line
			(start 0.67945 0.3048)
			(end 0.120396 0.3048)
			(stroke
				(width 0.1)
				(type default)
			)
			(layer "F.Fab")
		)
		(fp_line
			(start -0.12065 0.2794)
			(end -0.12065 0.3048)
			(stroke
				(width 0.1)
				(type default)
			)
			(layer "F.Fab")
		)
		(fp_line
			(start 0.120396 0.2794)
			(end -0.12065 0.2794)
			(stroke
				(width 0.1)
				(type default)
			)
			(layer "F.Fab")
		)
		(fp_line
			(start -0.12065 -0.2794)
			(end 0.12065 -0.2794)
			(stroke
				(width 0.1)
				(type default)
			)
			(layer "F.Fab")
		)
		(fp_line
			(start 0.12065 -0.2794)
			(end 0.12065 -0.3048)
			(stroke
				(width 0.1)
				(type default)
			)
			(layer "F.Fab")
		)
		(fp_line
			(start 0.12065 -0.3048)
			(end 0.67945 -0.3048)
			(stroke
				(width 0.1)
				(type default)
			)
			(layer "F.Fab")
		)
		(fp_line
			(start 0.67945 -0.3048)
			(end 0.67945 0.3048)
			(stroke
				(width 0.1)
				(type default)
			)
			(layer "F.Fab")
		)
		(fp_line
			(start -0.67945 -0.305054)
			(end -0.12065 -0.305054)
			(stroke
				(width 0.1)
				(type default)
			)
			(layer "F.Fab")
		)
		(fp_line
			(start -0.12065 -0.305054)
			(end -0.12065 -0.2794)
			(stroke
				(width 0.1)
				(type default)
			)
			(layer "F.Fab")
		)
		(pad "1" smd circle
			(at -0.40005 0 270)
			(size 0 0)
			(layers "F.Cu" "F.Mask" "F.Paste")
			(net "P1V25_SERDES_VDDPLL_PEX1")
		)
		(pad "2" smd circle
			(at 0.40005 0 270)
			(size 0 0)
			(layers "F.Cu" "F.Mask" "F.Paste")
			(net "P1V25_SERDES_VDDPLL_PEX1_C11")
		)
	)
	(footprint ""
		(layer "F.Cu")
		(at 457.436982 -116.230654 90)
		(property "Reference" "R5969"
			(at 0 0 90)
			(layer "F.SilkS")
			(hide yes)
			(effects
				(font
					(size 1.27 1.27)
				)
			)
		)
		(property "Value" ""
			(at 0 0 90)
			(layer "F.Fab")
			(effects
				(font
					(size 1.27 1.27)
				)
			)
		)
		(duplicate_pad_numbers_are_jumpers no)
		(fp_line
			(start 0.7874 -0.4064)
			(end 0.7874 0.4064)
			(stroke
				(width 0.1524)
				(type default)
			)
			(layer "F.SilkS")
		)
		(fp_line
			(start -0.7874 -0.4064)
			(end 0.7874 -0.4064)
			(stroke
				(width 0.1524)
				(type default)
			)
			(layer "F.SilkS")
		)
		(fp_line
			(start 0.7874 0.4064)
			(end -0.7874 0.4064)
			(stroke
				(width 0.1524)
				(type default)
			)
			(layer "F.SilkS")
		)
		(fp_line
			(start -0.7874 0.4064)
			(end -0.7874 -0.4064)
			(stroke
				(width 0.1524)
				(type default)
			)
			(layer "F.SilkS")
		)
		(fp_line
			(start -0.12065 -0.305054)
			(end -0.12065 -0.2794)
			(stroke
				(width 0.1)
				(type default)
			)
			(layer "F.Fab")
		)
		(fp_line
			(start -0.67945 -0.305054)
			(end -0.12065 -0.305054)
			(stroke
				(width 0.1)
				(type default)
			)
			(layer "F.Fab")
		)
		(fp_line
			(start 0.67945 -0.3048)
			(end 0.67945 0.3048)
			(stroke
				(width 0.1)
				(type default)
			)
			(layer "F.Fab")
		)
		(fp_line
			(start 0.12065 -0.3048)
			(end 0.67945 -0.3048)
			(stroke
				(width 0.1)
				(type default)
			)
			(layer "F.Fab")
		)
		(fp_line
			(start 0.12065 -0.2794)
			(end 0.12065 -0.3048)
			(stroke
				(width 0.1)
				(type default)
			)
			(layer "F.Fab")
		)
		(fp_line
			(start -0.12065 -0.2794)
			(end 0.12065 -0.2794)
			(stroke
				(width 0.1)
				(type default)
			)
			(layer "F.Fab")
		)
		(fp_line
			(start 0.120396 0.2794)
			(end -0.12065 0.2794)
			(stroke
				(width 0.1)
				(type default)
			)
			(layer "F.Fab")
		)
		(fp_line
			(start -0.12065 0.2794)
			(end -0.12065 0.3048)
			(stroke
				(width 0.1)
				(type default)
			)
			(layer "F.Fab")
		)
		(fp_line
			(start 0.67945 0.3048)
			(end 0.120396 0.3048)
			(stroke
				(width 0.1)
				(type default)
			)
			(layer "F.Fab")
		)
		(fp_line
			(start 0.120396 0.3048)
			(end 0.120396 0.2794)
			(stroke
				(width 0.1)
				(type default)
			)
			(layer "F.Fab")
		)
		(fp_line
			(start -0.12065 0.3048)
			(end -0.67945 0.3048)
			(stroke
				(width 0.1)
				(type default)
			)
			(layer "F.Fab")
		)
		(fp_line
			(start -0.67945 0.3048)
			(end -0.67945 -0.305054)
			(stroke
				(width 0.1)
				(type default)
			)
			(layer "F.Fab")
		)
		(pad "1" smd circle
			(at -0.40005 0 90)
			(size 0 0)
			(layers "F.Cu" "F.Mask" "F.Paste")
			(net "PWRGD_P12V_NIC7_CO")
		)
		(pad "2" smd circle
			(at 0.40005 0 90)
			(size 0 0)
			(layers "F.Cu" "F.Mask" "F.Paste")
			(net "PWRGD_P12V_NIC7_R")
		)
	)
	(footprint ""
		(layer "F.Cu")
		(at 308.681882 -38.041072 180)
		(property "Reference" "R6097"
			(at 0 0 180)
			(layer "F.SilkS")
			(hide yes)
			(effects
				(font
					(size 1.27 1.27)
				)
			)
		)
		(property "Value" ""
			(at 0 0 180)
			(layer "F.Fab")
			(effects
				(font
					(size 1.27 1.27)
				)
			)
		)
		(duplicate_pad_numbers_are_jumpers no)
		(fp_line
			(start 0.7874 0.4064)
			(end -0.7874 0.4064)
			(stroke
				(width 0.1524)
				(type default)
			)
			(layer "F.SilkS")
		)
		(fp_line
			(start 0.7874 -0.4064)
			(end 0.7874 0.4064)
			(stroke
				(width 0.1524)
				(type default)
			)
			(layer "F.SilkS")
		)
		(fp_line
			(start -0.7874 0.4064)
			(end -0.7874 -0.4064)
			(stroke
				(width 0.1524)
				(type default)
			)
			(layer "F.SilkS")
		)
		(fp_line
			(start -0.7874 -0.4064)
			(end 0.7874 -0.4064)
			(stroke
				(width 0.1524)
				(type default)
			)
			(layer "F.SilkS")
		)
		(fp_line
			(start 0.67945 0.3048)
			(end 0.120396 0.3048)
			(stroke
				(width 0.1)
				(type default)
			)
			(layer "F.Fab")
		)
		(fp_line
			(start 0.67945 -0.3048)
			(end 0.67945 0.3048)
			(stroke
				(width 0.1)
				(type default)
			)
			(layer "F.Fab")
		)
		(fp_line
			(start 0.12065 -0.2794)
			(end 0.12065 -0.3048)
			(stroke
				(width 0.1)
				(type default)
			)
			(layer "F.Fab")
		)
		(fp_line
			(start 0.12065 -0.3048)
			(end 0.67945 -0.3048)
			(stroke
				(width 0.1)
				(type default)
			)
			(layer "F.Fab")
		)
		(fp_line
			(start 0.120396 0.3048)
			(end 0.120396 0.2794)
			(stroke
				(width 0.1)
				(type default)
			)
			(layer "F.Fab")
		)
		(fp_line
			(start 0.120396 0.2794)
			(end -0.12065 0.2794)
			(stroke
				(width 0.1)
				(type default)
			)
			(layer "F.Fab")
		)
		(fp_line
			(start -0.12065 0.3048)
			(end -0.67945 0.3048)
			(stroke
				(width 0.1)
				(type default)
			)
			(layer "F.Fab")
		)
		(fp_line
			(start -0.12065 0.2794)
			(end -0.12065 0.3048)
			(stroke
				(width 0.1)
				(type default)
			)
			(layer "F.Fab")
		)
		(fp_line
			(start -0.12065 -0.2794)
			(end 0.12065 -0.2794)
			(stroke
				(width 0.1)
				(type default)
			)
			(layer "F.Fab")
		)
		(fp_line
			(start -0.12065 -0.305054)
			(end -0.12065 -0.2794)
			(stroke
				(width 0.1)
				(type default)
			)
			(layer "F.Fab")
		)
		(fp_line
			(start -0.67945 0.3048)
			(end -0.67945 -0.305054)
			(stroke
				(width 0.1)
				(type default)
			)
			(layer "F.Fab")
		)
		(fp_line
			(start -0.67945 -0.305054)
			(end -0.12065 -0.305054)
			(stroke
				(width 0.1)
				(type default)
			)
			(layer "F.Fab")
		)
		(pad "1" smd circle
			(at -0.40005 0 180)
			(size 0 0)
			(layers "F.Cu" "F.Mask" "F.Paste")
			(net "P5V_AUX")
		)
		(pad "2" smd circle
			(at 0.40005 0 180)
			(size 0 0)
			(layers "F.Cu" "F.Mask" "F.Paste")
			(net "P3V3_SSD11_PG_G2")
		)
	)
	(footprint ""
		(layer "F.Cu")
		(at 336.042 -180.975)
		(property "Reference" "R4730"
			(at 0 0 0)
			(layer "F.SilkS")
			(hide yes)
			(effects
				(font
					(size 1.27 1.27)
				)
			)
		)
		(property "Value" ""
			(at 0 0 0)
			(layer "F.Fab")
			(effects
				(font
					(size 1.27 1.27)
				)
			)
		)
		(duplicate_pad_numbers_are_jumpers no)
		(fp_line
			(start -0.7874 -0.4064)
			(end 0.7874 -0.4064)
			(stroke
				(width 0.1524)
				(type default)
			)
			(layer "F.SilkS")
		)
		(fp_line
			(start -0.7874 0.4064)
			(end -0.7874 -0.4064)
			(stroke
				(width 0.1524)
				(type default)
			)
			(layer "F.SilkS")
		)
		(fp_line
			(start 0.7874 -0.4064)
			(end 0.7874 0.4064)
			(stroke
				(width 0.1524)
				(type default)
			)
			(layer "F.SilkS")
		)
		(fp_line
			(start 0.7874 0.4064)
			(end -0.7874 0.4064)
			(stroke
				(width 0.1524)
				(type default)
			)
			(layer "F.SilkS")
		)
		(fp_line
			(start -0.67945 -0.305054)
			(end -0.12065 -0.305054)
			(stroke
				(width 0.1)
				(type default)
			)
			(layer "F.Fab")
		)
		(fp_line
			(start -0.67945 0.3048)
			(end -0.67945 -0.305054)
			(stroke
				(width 0.1)
				(type default)
			)
			(layer "F.Fab")
		)
		(fp_line
			(start -0.12065 -0.305054)
			(end -0.12065 -0.2794)
			(stroke
				(width 0.1)
				(type default)
			)
			(layer "F.Fab")
		)
		(fp_line
			(start -0.12065 -0.2794)
			(end 0.12065 -0.2794)
			(stroke
				(width 0.1)
				(type default)
			)
			(layer "F.Fab")
		)
		(fp_line
			(start -0.12065 0.2794)
			(end -0.12065 0.3048)
			(stroke
				(width 0.1)
				(type default)
			)
			(layer "F.Fab")
		)
		(fp_line
			(start -0.12065 0.3048)
			(end -0.67945 0.3048)
			(stroke
				(width 0.1)
				(type default)
			)
			(layer "F.Fab")
		)
		(fp_line
			(start 0.120396 0.2794)
			(end -0.12065 0.2794)
			(stroke
				(width 0.1)
				(type default)
			)
			(layer "F.Fab")
		)
		(fp_line
			(start 0.120396 0.3048)
			(end 0.120396 0.2794)
			(stroke
				(width 0.1)
				(type default)
			)
			(layer "F.Fab")
		)
		(fp_line
			(start 0.12065 -0.3048)
			(end 0.67945 -0.3048)
			(stroke
				(width 0.1)
				(type default)
			)
			(layer "F.Fab")
		)
		(fp_line
			(start 0.12065 -0.2794)
			(end 0.12065 -0.3048)
			(stroke
				(width 0.1)
				(type default)
			)
			(layer "F.Fab")
		)
		(fp_line
			(start 0.67945 -0.3048)
			(end 0.67945 0.3048)
			(stroke
				(width 0.1)
				(type default)
			)
			(layer "F.Fab")
		)
		(fp_line
			(start 0.67945 0.3048)
			(end 0.120396 0.3048)
			(stroke
				(width 0.1)
				(type default)
			)
			(layer "F.Fab")
		)
		(pad "1" smd circle
			(at -0.40005 0)
			(size 0 0)
			(layers "F.Cu" "F.Mask" "F.Paste")
			(net "P3V3_AUX")
		)
		(pad "2" smd circle
			(at 0.40005 0)
			(size 0 0)
			(layers "F.Cu" "F.Mask" "F.Paste")
			(net "RST_PEX_SSD8_PERST_R_N")
		)
	)
	(footprint ""
		(layer "F.Cu")
		(at 204.752194 -114.892836 180)
		(property "Reference" "PC792"
			(at 0 0 180)
			(layer "F.SilkS")
			(hide yes)
			(effects
				(font
					(size 1.27 1.27)
				)
			)
		)
		(property "Value" ""
			(at 0 0 180)
			(layer "F.Fab")
			(effects
				(font
					(size 1.27 1.27)
				)
			)
		)
		(duplicate_pad_numbers_are_jumpers no)
		(fp_line
			(start 0.7874 0.4064)
			(end -0.7874 0.4064)
			(stroke
				(width 0.1524)
				(type default)
			)
			(layer "F.SilkS")
		)
		(fp_line
			(start 0.7874 -0.4064)
			(end 0.7874 0.4064)
			(stroke
				(width 0.1524)
				(type default)
			)
			(layer "F.SilkS")
		)
		(fp_line
			(start -0.7874 0.4064)
			(end -0.7874 -0.4064)
			(stroke
				(width 0.1524)
				(type default)
			)
			(layer "F.SilkS")
		)
		(fp_line
			(start -0.7874 -0.4064)
			(end 0.7874 -0.4064)
			(stroke
				(width 0.1524)
				(type default)
			)
			(layer "F.SilkS")
		)
		(fp_line
			(start 0.67945 0.3048)
			(end 0.120396 0.3048)
			(stroke
				(width 0.1)
				(type default)
			)
			(layer "F.Fab")
		)
		(fp_line
			(start 0.67945 -0.3048)
			(end 0.67945 0.3048)
			(stroke
				(width 0.1)
				(type default)
			)
			(layer "F.Fab")
		)
		(fp_line
			(start 0.12065 -0.2794)
			(end 0.12065 -0.3048)
			(stroke
				(width 0.1)
				(type default)
			)
			(layer "F.Fab")
		)
		(fp_line
			(start 0.12065 -0.3048)
			(end 0.67945 -0.3048)
			(stroke
				(width 0.1)
				(type default)
			)
			(layer "F.Fab")
		)
		(fp_line
			(start 0.120396 0.3048)
			(end 0.120396 0.2794)
			(stroke
				(width 0.1)
				(type default)
			)
			(layer "F.Fab")
		)
		(fp_line
			(start 0.120396 0.2794)
			(end -0.12065 0.2794)
			(stroke
				(width 0.1)
				(type default)
			)
			(layer "F.Fab")
		)
		(fp_line
			(start -0.12065 0.3048)
			(end -0.67945 0.3048)
			(stroke
				(width 0.1)
				(type default)
			)
			(layer "F.Fab")
		)
		(fp_line
			(start -0.12065 0.2794)
			(end -0.12065 0.3048)
			(stroke
				(width 0.1)
				(type default)
			)
			(layer "F.Fab")
		)
		(fp_line
			(start -0.12065 -0.2794)
			(end 0.12065 -0.2794)
			(stroke
				(width 0.1)
				(type default)
			)
			(layer "F.Fab")
		)
		(fp_line
			(start -0.12065 -0.305054)
			(end -0.12065 -0.2794)
			(stroke
				(width 0.1)
				(type default)
			)
			(layer "F.Fab")
		)
		(fp_line
			(start -0.67945 0.3048)
			(end -0.67945 -0.305054)
			(stroke
				(width 0.1)
				(type default)
			)
			(layer "F.Fab")
		)
		(fp_line
			(start -0.67945 -0.305054)
			(end -0.12065 -0.305054)
			(stroke
				(width 0.1)
				(type default)
			)
			(layer "F.Fab")
		)
		(pad "1" smd circle
			(at -0.40005 0 180)
			(size 0 0)
			(layers "F.Cu" "F.Mask" "F.Paste")
			(net "P3V3_NIC3_CO_GATE")
		)
		(pad "2" smd circle
			(at 0.40005 0 180)
			(size 0 0)
			(layers "F.Cu" "F.Mask" "F.Paste")
			(net "GND")
		)
	)
	(footprint ""
		(layer "F.Cu")
		(at 347.726 -205.232 90)
		(property "Reference" "R4149"
			(at 0 0 90)
			(layer "F.SilkS")
			(hide yes)
			(effects
				(font
					(size 1.27 1.27)
				)
			)
		)
		(property "Value" ""
			(at 0 0 90)
			(layer "F.Fab")
			(effects
				(font
					(size 1.27 1.27)
				)
			)
		)
		(duplicate_pad_numbers_are_jumpers no)
		(fp_line
			(start 0.7874 -0.4064)
			(end 0.7874 0.4064)
			(stroke
				(width 0.1524)
				(type default)
			)
			(layer "F.SilkS")
		)
		(fp_line
			(start -0.7874 -0.4064)
			(end 0.7874 -0.4064)
			(stroke
				(width 0.1524)
				(type default)
			)
			(layer "F.SilkS")
		)
		(fp_line
			(start 0.7874 0.4064)
			(end -0.7874 0.4064)
			(stroke
				(width 0.1524)
				(type default)
			)
			(layer "F.SilkS")
		)
		(fp_line
			(start -0.7874 0.4064)
			(end -0.7874 -0.4064)
			(stroke
				(width 0.1524)
				(type default)
			)
			(layer "F.SilkS")
		)
		(fp_line
			(start -0.12065 -0.305054)
			(end -0.12065 -0.2794)
			(stroke
				(width 0.1)
				(type default)
			)
			(layer "F.Fab")
		)
		(fp_line
			(start -0.67945 -0.305054)
			(end -0.12065 -0.305054)
			(stroke
				(width 0.1)
				(type default)
			)
			(layer "F.Fab")
		)
		(fp_line
			(start 0.67945 -0.3048)
			(end 0.67945 0.3048)
			(stroke
				(width 0.1)
				(type default)
			)
			(layer "F.Fab")
		)
		(fp_line
			(start 0.12065 -0.3048)
			(end 0.67945 -0.3048)
			(stroke
				(width 0.1)
				(type default)
			)
			(layer "F.Fab")
		)
		(fp_line
			(start 0.12065 -0.2794)
			(end 0.12065 -0.3048)
			(stroke
				(width 0.1)
				(type default)
			)
			(layer "F.Fab")
		)
		(fp_line
			(start -0.12065 -0.2794)
			(end 0.12065 -0.2794)
			(stroke
				(width 0.1)
				(type default)
			)
			(layer "F.Fab")
		)
		(fp_line
			(start 0.120396 0.2794)
			(end -0.12065 0.2794)
			(stroke
				(width 0.1)
				(type default)
			)
			(layer "F.Fab")
		)
		(fp_line
			(start -0.12065 0.2794)
			(end -0.12065 0.3048)
			(stroke
				(width 0.1)
				(type default)
			)
			(layer "F.Fab")
		)
		(fp_line
			(start 0.67945 0.3048)
			(end 0.120396 0.3048)
			(stroke
				(width 0.1)
				(type default)
			)
			(layer "F.Fab")
		)
		(fp_line
			(start 0.120396 0.3048)
			(end 0.120396 0.2794)
			(stroke
				(width 0.1)
				(type default)
			)
			(layer "F.Fab")
		)
		(fp_line
			(start -0.12065 0.3048)
			(end -0.67945 0.3048)
			(stroke
				(width 0.1)
				(type default)
			)
			(layer "F.Fab")
		)
		(fp_line
			(start -0.67945 0.3048)
			(end -0.67945 -0.305054)
			(stroke
				(width 0.1)
				(type default)
			)
			(layer "F.Fab")
		)
		(pad "1" smd circle
			(at -0.40005 0 90)
			(size 0 0)
			(layers "F.Cu" "F.Mask" "F.Paste")
			(net "PRSNT_SSD2_FPGA_R_N")
		)
		(pad "2" smd circle
			(at 0.40005 0 90)
			(size 0 0)
			(layers "F.Cu" "F.Mask" "F.Paste")
			(net "PRSNT_SSD2_FPGA_N")
		)
	)
	(footprint ""
		(layer "F.Cu")
		(at 57.341262 -390.07161 -90)
		(property "Reference" "R1828"
			(at 0 0 270)
			(layer "F.SilkS")
			(hide yes)
			(effects
				(font
					(size 1.27 1.27)
				)
			)
		)
		(property "Value" ""
			(at 0 0 270)
			(layer "F.Fab")
			(effects
				(font
					(size 1.27 1.27)
				)
			)
		)
		(duplicate_pad_numbers_are_jumpers no)
		(fp_line
			(start -0.7874 0.4064)
			(end -0.7874 -0.4064)
			(stroke
				(width 0.1524)
				(type default)
			)
			(layer "F.SilkS")
		)
		(fp_line
			(start 0.7874 0.4064)
			(end -0.7874 0.4064)
			(stroke
				(width 0.1524)
				(type default)
			)
			(layer "F.SilkS")
		)
		(fp_line
			(start -0.7874 -0.4064)
			(end 0.7874 -0.4064)
			(stroke
				(width 0.1524)
				(type default)
			)
			(layer "F.SilkS")
		)
		(fp_line
			(start 0.7874 -0.4064)
			(end 0.7874 0.4064)
			(stroke
				(width 0.1524)
				(type default)
			)
			(layer "F.SilkS")
		)
		(fp_line
			(start -0.67945 0.3048)
			(end -0.67945 -0.305054)
			(stroke
				(width 0.1)
				(type default)
			)
			(layer "F.Fab")
		)
		(fp_line
			(start -0.12065 0.3048)
			(end -0.67945 0.3048)
			(stroke
				(width 0.1)
				(type default)
			)
			(layer "F.Fab")
		)
		(fp_line
			(start 0.120396 0.3048)
			(end 0.120396 0.2794)
			(stroke
				(width 0.1)
				(type default)
			)
			(layer "F.Fab")
		)
		(fp_line
			(start 0.67945 0.3048)
			(end 0.120396 0.3048)
			(stroke
				(width 0.1)
				(type default)
			)
			(layer "F.Fab")
		)
		(fp_line
			(start -0.12065 0.2794)
			(end -0.12065 0.3048)
			(stroke
				(width 0.1)
				(type default)
			)
			(layer "F.Fab")
		)
		(fp_line
			(start 0.120396 0.2794)
			(end -0.12065 0.2794)
			(stroke
				(width 0.1)
				(type default)
			)
			(layer "F.Fab")
		)
		(fp_line
			(start -0.12065 -0.2794)
			(end 0.12065 -0.2794)
			(stroke
				(width 0.1)
				(type default)
			)
			(layer "F.Fab")
		)
		(fp_line
			(start 0.12065 -0.2794)
			(end 0.12065 -0.3048)
			(stroke
				(width 0.1)
				(type default)
			)
			(layer "F.Fab")
		)
		(fp_line
			(start 0.12065 -0.3048)
			(end 0.67945 -0.3048)
			(stroke
				(width 0.1)
				(type default)
			)
			(layer "F.Fab")
		)
		(fp_line
			(start 0.67945 -0.3048)
			(end 0.67945 0.3048)
			(stroke
				(width 0.1)
				(type default)
			)
			(layer "F.Fab")
		)
		(fp_line
			(start -0.67945 -0.305054)
			(end -0.12065 -0.305054)
			(stroke
				(width 0.1)
				(type default)
			)
			(layer "F.Fab")
		)
		(fp_line
			(start -0.12065 -0.305054)
			(end -0.12065 -0.2794)
			(stroke
				(width 0.1)
				(type default)
			)
			(layer "F.Fab")
		)
		(pad "1" smd circle
			(at -0.40005 0 270)
			(size 0 0)
			(layers "F.Cu" "F.Mask" "F.Paste")
			(net "GPU_PEX_STRAP0_R")
		)
		(pad "2" smd circle
			(at 0.40005 0 270)
			(size 0 0)
			(layers "F.Cu" "F.Mask" "F.Paste")
			(net "GPU_PEX_STRAP0")
		)
	)
	(footprint ""
		(layer "F.Cu")
		(at 286.695134 -35.48253)
		(property "Reference" "U393"
			(at -2.569464 1.09093 90)
			(unlocked yes)
			(layer "F.SilkS")
			(effects
				(font
					(size 0.7874 0.5842)
					(thickness 0.1524)
				)
				(justify left)
			)
		)
		(property "Value" ""
			(at 0 0 0)
			(layer "F.Fab")
			(effects
				(font
					(size 1.27 1.27)
				)
			)
		)
		(duplicate_pad_numbers_are_jumpers no)
		(fp_line
			(start -1.3462 -1.1938)
			(end -1.3462 1.1684)
			(stroke
				(width 0.1524)
				(type default)
			)
			(layer "F.SilkS")
		)
		(fp_line
			(start -1.3462 1.1938)
			(end 1.3462 1.1938)
			(stroke
				(width 0.1524)
				(type default)
			)
			(layer "F.SilkS")
		)
		(fp_line
			(start 1.3462 -1.1938)
			(end -1.3462 -1.1938)
			(stroke
				(width 0.1524)
				(type default)
			)
			(layer "F.SilkS")
		)
		(fp_line
			(start 1.3462 1.1938)
			(end 1.3462 -1.1938)
			(stroke
				(width 0.1524)
				(type default)
			)
			(layer "F.SilkS")
		)
		(fp_poly
			(pts
				(xy -1.447038 -0.760476) (xy -2.052066 -0.457962) (xy -2.052066 -1.06299)
			)
			(stroke
				(width 0)
				(type default)
			)
			(fill yes)
			(layer "F.SilkS")
		)
		(fp_line
			(start -0.674878 -1.124966)
			(end -0.674878 1.124966)
			(stroke
				(width 0.1)
				(type default)
			)
			(layer "F.Fab")
		)
		(fp_line
			(start -0.674878 1.124966)
			(end 0.674878 1.124966)
			(stroke
				(width 0.1)
				(type default)
			)
			(layer "F.Fab")
		)
		(fp_line
			(start 0.674878 -1.124966)
			(end -0.674878 -1.124966)
			(stroke
				(width 0.1)
				(type default)
			)
			(layer "F.Fab")
		)
		(fp_line
			(start 0.674878 1.124966)
			(end 0.674878 -1.124966)
			(stroke
				(width 0.1)
				(type default)
			)
			(layer "F.Fab")
		)
		(fp_poly
			(pts
				(xy -1.447038 -0.760476) (xy -2.052066 -0.457962) (xy -2.052066 -1.06299)
			)
			(stroke
				(width 0)
				(type default)
			)
			(fill yes)
			(layer "F.Fab")
		)
		(pad "1" smd rect
			(at -0.899922 -0.750062)
			(size 0.6096 0.6096)
			(layers "F.Cu" "F.Mask" "F.Paste")
			(net "PWRGD_P3V3_SSD10_R")
		)
		(pad "2" smd rect
			(at -0.899922 0 90)
			(size 0.4064 0.6096)
			(layers "F.Cu" "F.Mask" "F.Paste")
			(net "RST_SMB_SSD10_N")
		)
		(pad "3" smd rect
			(at -0.899922 0.750062)
			(size 0.6096 0.6096)
			(layers "F.Cu" "F.Mask" "F.Paste")
			(net "GND")
		)
		(pad "4" smd rect
			(at 0.899922 0.750062)
			(size 0.6096 0.6096)
			(layers "F.Cu" "F.Mask" "F.Paste")
			(net "RST_SMB_SSD10_ISO_N")
		)
		(pad "5" smd rect
			(at 0.899922 -0.750062)
			(size 0.6096 0.6096)
			(layers "F.Cu" "F.Mask" "F.Paste")
			(net "P3V3_AUX")
		)
	)
	(footprint ""
		(layer "F.Cu")
		(at 378.453396 -291.390832)
		(property "Reference" "L140"
			(at 0 0 0)
			(layer "F.SilkS")
			(hide yes)
			(effects
				(font
					(size 1.27 1.27)
				)
			)
		)
		(property "Value" ""
			(at 0 0 0)
			(layer "F.Fab")
			(effects
				(font
					(size 1.27 1.27)
				)
			)
		)
		(duplicate_pad_numbers_are_jumpers no)
		(fp_line
			(start -1.63576 -0.8128)
			(end -1.63576 0.8128)
			(stroke
				(width 0.1524)
				(type default)
			)
			(layer "F.SilkS")
		)
		(fp_line
			(start -1.63576 -0.8128)
			(end 1.63576 -0.8128)
			(stroke
				(width 0.1524)
				(type default)
			)
			(layer "F.SilkS")
		)
		(fp_line
			(start 1.63576 -0.8128)
			(end 1.63576 0.8128)
			(stroke
				(width 0.1524)
				(type default)
			)
			(layer "F.SilkS")
		)
		(fp_line
			(start 1.63576 0.8128)
			(end -1.63576 0.8128)
			(stroke
				(width 0.1524)
				(type default)
			)
			(layer "F.SilkS")
		)
		(fp_line
			(start -1.56083 -0.738632)
			(end -1.56083 0.7366)
			(stroke
				(width 0.1)
				(type default)
			)
			(layer "F.Fab")
		)
		(fp_line
			(start -1.56083 0.7366)
			(end -1.524 0.7366)
			(stroke
				(width 0.1)
				(type default)
			)
			(layer "F.Fab")
		)
		(fp_line
			(start -1.524 0.7366)
			(end 1.524 0.7366)
			(stroke
				(width 0.1)
				(type default)
			)
			(layer "F.Fab")
		)
		(fp_line
			(start 1.524 0.7366)
			(end 1.560576 0.7366)
			(stroke
				(width 0.1)
				(type default)
			)
			(layer "F.Fab")
		)
		(fp_line
			(start 1.560576 -0.738632)
			(end -1.56083 -0.738632)
			(stroke
				(width 0.1)
				(type default)
			)
			(layer "F.Fab")
		)
		(fp_line
			(start 1.560576 0.7366)
			(end 1.560576 -0.738632)
			(stroke
				(width 0.1)
				(type default)
			)
			(layer "F.Fab")
		)
		(pad "1" smd rect
			(at -0.94996 0 180)
			(size 1.1176 1.3716)
			(layers "F.Cu" "F.Mask" "F.Paste")
			(net "P1V8_PLL0_PEX3")
		)
		(pad "2" smd rect
			(at 0.94996 0 180)
			(size 1.1176 1.3716)
			(layers "F.Cu" "F.Mask" "F.Paste")
			(net "PCEPLL4_VDDA18_PEX3")
		)
	)
	(footprint ""
		(layer "F.Cu")
		(at 219.014294 -180.12918)
		(property "Reference" "R6804"
			(at 0 0 0)
			(layer "F.SilkS")
			(hide yes)
			(effects
				(font
					(size 1.27 1.27)
				)
			)
		)
		(property "Value" ""
			(at 0 0 0)
			(layer "F.Fab")
			(effects
				(font
					(size 1.27 1.27)
				)
			)
		)
		(duplicate_pad_numbers_are_jumpers no)
		(fp_line
			(start -0.7874 -0.4064)
			(end 0.7874 -0.4064)
			(stroke
				(width 0.1524)
				(type default)
			)
			(layer "F.SilkS")
		)
		(fp_line
			(start -0.7874 0.4064)
			(end -0.7874 -0.4064)
			(stroke
				(width 0.1524)
				(type default)
			)
			(layer "F.SilkS")
		)
		(fp_line
			(start 0.7874 -0.4064)
			(end 0.7874 0.4064)
			(stroke
				(width 0.1524)
				(type default)
			)
			(layer "F.SilkS")
		)
		(fp_line
			(start 0.7874 0.4064)
			(end -0.7874 0.4064)
			(stroke
				(width 0.1524)
				(type default)
			)
			(layer "F.SilkS")
		)
		(fp_line
			(start -0.67945 -0.305054)
			(end -0.12065 -0.305054)
			(stroke
				(width 0.1)
				(type default)
			)
			(layer "F.Fab")
		)
		(fp_line
			(start -0.67945 0.3048)
			(end -0.67945 -0.305054)
			(stroke
				(width 0.1)
				(type default)
			)
			(layer "F.Fab")
		)
		(fp_line
			(start -0.12065 -0.305054)
			(end -0.12065 -0.2794)
			(stroke
				(width 0.1)
				(type default)
			)
			(layer "F.Fab")
		)
		(fp_line
			(start -0.12065 -0.2794)
			(end 0.12065 -0.2794)
			(stroke
				(width 0.1)
				(type default)
			)
			(layer "F.Fab")
		)
		(fp_line
			(start -0.12065 0.2794)
			(end -0.12065 0.3048)
			(stroke
				(width 0.1)
				(type default)
			)
			(layer "F.Fab")
		)
		(fp_line
			(start -0.12065 0.3048)
			(end -0.67945 0.3048)
			(stroke
				(width 0.1)
				(type default)
			)
			(layer "F.Fab")
		)
		(fp_line
			(start 0.120396 0.2794)
			(end -0.12065 0.2794)
			(stroke
				(width 0.1)
				(type default)
			)
			(layer "F.Fab")
		)
		(fp_line
			(start 0.120396 0.3048)
			(end 0.120396 0.2794)
			(stroke
				(width 0.1)
				(type default)
			)
			(layer "F.Fab")
		)
		(fp_line
			(start 0.12065 -0.3048)
			(end 0.67945 -0.3048)
			(stroke
				(width 0.1)
				(type default)
			)
			(layer "F.Fab")
		)
		(fp_line
			(start 0.12065 -0.2794)
			(end 0.12065 -0.3048)
			(stroke
				(width 0.1)
				(type default)
			)
			(layer "F.Fab")
		)
		(fp_line
			(start 0.67945 -0.3048)
			(end 0.67945 0.3048)
			(stroke
				(width 0.1)
				(type default)
			)
			(layer "F.Fab")
		)
		(fp_line
			(start 0.67945 0.3048)
			(end 0.120396 0.3048)
			(stroke
				(width 0.1)
				(type default)
			)
			(layer "F.Fab")
		)
		(pad "1" smd circle
			(at -0.40005 0)
			(size 0 0)
			(layers "F.Cu" "F.Mask" "F.Paste")
			(net "RST_FW_BIC_PLTRST_R")
		)
		(pad "2" smd circle
			(at 0.40005 0)
			(size 0 0)
			(layers "F.Cu" "F.Mask" "F.Paste")
			(net "RST_FW_BIC_PLTRST_C")
		)
	)
	(footprint ""
		(layer "F.Cu")
		(at 408.554682 -198.603108 -90)
		(property "Reference" "R6435"
			(at 0 0 270)
			(layer "F.SilkS")
			(hide yes)
			(effects
				(font
					(size 1.27 1.27)
				)
			)
		)
		(property "Value" ""
			(at 0 0 270)
			(layer "F.Fab")
			(effects
				(font
					(size 1.27 1.27)
				)
			)
		)
		(duplicate_pad_numbers_are_jumpers no)
		(fp_line
			(start -0.7874 0.4064)
			(end -0.7874 -0.4064)
			(stroke
				(width 0.1524)
				(type default)
			)
			(layer "F.SilkS")
		)
		(fp_line
			(start 0.7874 0.4064)
			(end -0.7874 0.4064)
			(stroke
				(width 0.1524)
				(type default)
			)
			(layer "F.SilkS")
		)
		(fp_line
			(start -0.7874 -0.4064)
			(end 0.7874 -0.4064)
			(stroke
				(width 0.1524)
				(type default)
			)
			(layer "F.SilkS")
		)
		(fp_line
			(start 0.7874 -0.4064)
			(end 0.7874 0.4064)
			(stroke
				(width 0.1524)
				(type default)
			)
			(layer "F.SilkS")
		)
		(fp_line
			(start -0.67945 0.3048)
			(end -0.67945 -0.305054)
			(stroke
				(width 0.1)
				(type default)
			)
			(layer "F.Fab")
		)
		(fp_line
			(start -0.12065 0.3048)
			(end -0.67945 0.3048)
			(stroke
				(width 0.1)
				(type default)
			)
			(layer "F.Fab")
		)
		(fp_line
			(start 0.120396 0.3048)
			(end 0.120396 0.2794)
			(stroke
				(width 0.1)
				(type default)
			)
			(layer "F.Fab")
		)
		(fp_line
			(start 0.67945 0.3048)
			(end 0.120396 0.3048)
			(stroke
				(width 0.1)
				(type default)
			)
			(layer "F.Fab")
		)
		(fp_line
			(start -0.12065 0.2794)
			(end -0.12065 0.3048)
			(stroke
				(width 0.1)
				(type default)
			)
			(layer "F.Fab")
		)
		(fp_line
			(start 0.120396 0.2794)
			(end -0.12065 0.2794)
			(stroke
				(width 0.1)
				(type default)
			)
			(layer "F.Fab")
		)
		(fp_line
			(start -0.12065 -0.2794)
			(end 0.12065 -0.2794)
			(stroke
				(width 0.1)
				(type default)
			)
			(layer "F.Fab")
		)
		(fp_line
			(start 0.12065 -0.2794)
			(end 0.12065 -0.3048)
			(stroke
				(width 0.1)
				(type default)
			)
			(layer "F.Fab")
		)
		(fp_line
			(start 0.12065 -0.3048)
			(end 0.67945 -0.3048)
			(stroke
				(width 0.1)
				(type default)
			)
			(layer "F.Fab")
		)
		(fp_line
			(start 0.67945 -0.3048)
			(end 0.67945 0.3048)
			(stroke
				(width 0.1)
				(type default)
			)
			(layer "F.Fab")
		)
		(fp_line
			(start -0.67945 -0.305054)
			(end -0.12065 -0.305054)
			(stroke
				(width 0.1)
				(type default)
			)
			(layer "F.Fab")
		)
		(fp_line
			(start -0.12065 -0.305054)
			(end -0.12065 -0.2794)
			(stroke
				(width 0.1)
				(type default)
			)
			(layer "F.Fab")
		)
		(pad "1" smd circle
			(at -0.40005 0 270)
			(size 0 0)
			(layers "F.Cu" "F.Mask" "F.Paste")
			(net "FPGA_PEX1_MODE_SEL2_ISO")
		)
		(pad "2" smd circle
			(at 0.40005 0 270)
			(size 0 0)
			(layers "F.Cu" "F.Mask" "F.Paste")
			(net "PEX1_MODE_SEL2")
		)
	)
	(footprint ""
		(layer "F.Cu")
		(at 365.506 -210.947 180)
		(property "Reference" "R4624"
			(at 0 0 180)
			(layer "F.SilkS")
			(hide yes)
			(effects
				(font
					(size 1.27 1.27)
				)
			)
		)
		(property "Value" ""
			(at 0 0 180)
			(layer "F.Fab")
			(effects
				(font
					(size 1.27 1.27)
				)
			)
		)
		(duplicate_pad_numbers_are_jumpers no)
		(fp_line
			(start 0.7874 0.4064)
			(end -0.7874 0.4064)
			(stroke
				(width 0.1524)
				(type default)
			)
			(layer "F.SilkS")
		)
		(fp_line
			(start 0.7874 -0.4064)
			(end 0.7874 0.4064)
			(stroke
				(width 0.1524)
				(type default)
			)
			(layer "F.SilkS")
		)
		(fp_line
			(start -0.7874 0.4064)
			(end -0.7874 -0.4064)
			(stroke
				(width 0.1524)
				(type default)
			)
			(layer "F.SilkS")
		)
		(fp_line
			(start -0.7874 -0.4064)
			(end 0.7874 -0.4064)
			(stroke
				(width 0.1524)
				(type default)
			)
			(layer "F.SilkS")
		)
		(fp_line
			(start 0.67945 0.3048)
			(end 0.120396 0.3048)
			(stroke
				(width 0.1)
				(type default)
			)
			(layer "F.Fab")
		)
		(fp_line
			(start 0.67945 -0.3048)
			(end 0.67945 0.3048)
			(stroke
				(width 0.1)
				(type default)
			)
			(layer "F.Fab")
		)
		(fp_line
			(start 0.12065 -0.2794)
			(end 0.12065 -0.3048)
			(stroke
				(width 0.1)
				(type default)
			)
			(layer "F.Fab")
		)
		(fp_line
			(start 0.12065 -0.3048)
			(end 0.67945 -0.3048)
			(stroke
				(width 0.1)
				(type default)
			)
			(layer "F.Fab")
		)
		(fp_line
			(start 0.120396 0.3048)
			(end 0.120396 0.2794)
			(stroke
				(width 0.1)
				(type default)
			)
			(layer "F.Fab")
		)
		(fp_line
			(start 0.120396 0.2794)
			(end -0.12065 0.2794)
			(stroke
				(width 0.1)
				(type default)
			)
			(layer "F.Fab")
		)
		(fp_line
			(start -0.12065 0.3048)
			(end -0.67945 0.3048)
			(stroke
				(width 0.1)
				(type default)
			)
			(layer "F.Fab")
		)
		(fp_line
			(start -0.12065 0.2794)
			(end -0.12065 0.3048)
			(stroke
				(width 0.1)
				(type default)
			)
			(layer "F.Fab")
		)
		(fp_line
			(start -0.12065 -0.2794)
			(end 0.12065 -0.2794)
			(stroke
				(width 0.1)
				(type default)
			)
			(layer "F.Fab")
		)
		(fp_line
			(start -0.12065 -0.305054)
			(end -0.12065 -0.2794)
			(stroke
				(width 0.1)
				(type default)
			)
			(layer "F.Fab")
		)
		(fp_line
			(start -0.67945 0.3048)
			(end -0.67945 -0.305054)
			(stroke
				(width 0.1)
				(type default)
			)
			(layer "F.Fab")
		)
		(fp_line
			(start -0.67945 -0.305054)
			(end -0.12065 -0.305054)
			(stroke
				(width 0.1)
				(type default)
			)
			(layer "F.Fab")
		)
		(pad "1" smd circle
			(at -0.40005 0 180)
			(size 0 0)
			(layers "F.Cu" "F.Mask" "F.Paste")
			(net "SSD0_PEX_PWR_EN")
		)
		(pad "2" smd circle
			(at 0.40005 0 180)
			(size 0 0)
			(layers "F.Cu" "F.Mask" "F.Paste")
			(net "SSD0_PEX_PWR_EN_R")
		)
	)
	(footprint ""
		(layer "F.Cu")
		(at 67.142614 -70.844918 -90)
		(property "Reference" "PD90"
			(at 4.042918 2.117344 90)
			(unlocked yes)
			(layer "F.SilkS")
			(effects
				(font
					(size 0.7874 0.5842)
					(thickness 0.1524)
				)
				(justify left)
			)
		)
		(property "Value" ""
			(at 0 0 270)
			(layer "F.Fab")
			(effects
				(font
					(size 1.27 1.27)
				)
			)
		)
		(duplicate_pad_numbers_are_jumpers no)
		(fp_line
			(start -3.400044 1.459992)
			(end -3.400044 -1.459992)
			(stroke
				(width 0.1524)
				(type default)
			)
			(layer "F.SilkS")
		)
		(fp_line
			(start 4.107942 1.459992)
			(end -3.400044 1.459992)
			(stroke
				(width 0.1524)
				(type default)
			)
			(layer "F.SilkS")
		)
		(fp_line
			(start -3.400044 -1.459992)
			(end 4.107942 -1.459992)
			(stroke
				(width 0.1524)
				(type default)
			)
			(layer "F.SilkS")
		)
		(fp_line
			(start 4.107942 -1.459992)
			(end 4.107942 1.459992)
			(stroke
				(width 0.1524)
				(type default)
			)
			(layer "F.SilkS")
		)
		(fp_poly
			(pts
				(xy 4.107942 -1.459992) (xy 4.107942 1.459992) (xy 3.308096 1.459992) (xy 3.308096 -1.459992)
			)
			(stroke
				(width 0)
				(type default)
			)
			(fill yes)
			(layer "F.SilkS")
		)
		(fp_line
			(start -2.29997 1.459992)
			(end -2.29997 -1.459992)
			(stroke
				(width 0.1)
				(type default)
			)
			(layer "F.Fab")
		)
		(fp_line
			(start 2.29997 1.459992)
			(end -2.29997 1.459992)
			(stroke
				(width 0.1)
				(type default)
			)
			(layer "F.Fab")
		)
		(fp_line
			(start -2.29997 -1.459992)
			(end 2.29997 -1.459992)
			(stroke
				(width 0.1)
				(type default)
			)
			(layer "F.Fab")
		)
		(fp_line
			(start 2.29997 -1.459992)
			(end 2.29997 1.459992)
			(stroke
				(width 0.1)
				(type default)
			)
			(layer "F.Fab")
		)
		(fp_text user "-"
			(at 5.4102 0.29845 90)
			(unlocked yes)
			(layer "F.SilkS")
			(effects
				(font
					(size 1.905 1.4224)
					(thickness 0.1524)
				)
				(justify left)
			)
		)
		(fp_text user "+"
			(at -5.250688 0.221488 270)
			(unlocked yes)
			(layer "F.SilkS")
			(effects
				(font
					(size 1.905 1.4224)
					(thickness 0.1524)
				)
				(justify left)
			)
		)
		(fp_text user "-"
			(at 5.4102 0.29845 90)
			(unlocked yes)
			(layer "F.Fab")
			(effects
				(font
					(size 1.905 1.4224)
					(thickness 0.1524)
				)
				(justify left)
			)
		)
		(fp_text user "+"
			(at -4.7752 -0.12065 270)
			(unlocked yes)
			(layer "F.Fab")
			(effects
				(font
					(size 1.905 1.4224)
					(thickness 0.1524)
				)
				(justify left)
			)
		)
		(pad "A" smd rect
			(at -1.999996 0)
			(size 1.7018 2.5146)
			(layers "F.Cu" "F.Mask" "F.Paste")
			(net "GND")
		)
		(pad "C" smd rect
			(at 1.999996 0)
			(size 1.7018 2.5146)
			(layers "F.Cu" "F.Mask" "F.Paste")
			(net "P12V_SSD2_R")
		)
	)
	(footprint ""
		(layer "F.Cu")
		(at 257.179318 -262.645652 90)
		(property "Reference" "C3419"
			(at 0 0 90)
			(layer "F.SilkS")
			(hide yes)
			(effects
				(font
					(size 1.27 1.27)
				)
			)
		)
		(property "Value" ""
			(at 0 0 90)
			(layer "F.Fab")
			(effects
				(font
					(size 1.27 1.27)
				)
			)
		)
		(duplicate_pad_numbers_are_jumpers no)
		(fp_line
			(start 0.299974 -0.150114)
			(end 0.299974 0.150114)
			(stroke
				(width 0.1)
				(type default)
			)
			(layer "F.Fab")
		)
		(fp_line
			(start -0.299974 -0.150114)
			(end 0.299974 -0.150114)
			(stroke
				(width 0.1)
				(type default)
			)
			(layer "F.Fab")
		)
		(fp_line
			(start 0.299974 0.150114)
			(end -0.299974 0.150114)
			(stroke
				(width 0.1)
				(type default)
			)
			(layer "F.Fab")
		)
		(fp_line
			(start -0.299974 0.150114)
			(end -0.299974 -0.150114)
			(stroke
				(width 0.1)
				(type default)
			)
			(layer "F.Fab")
		)
		(pad "1" smd rect
			(at -0.2667 0 90)
			(size 0.3048 0.381)
			(layers "F.Cu" "F.Mask" "F.Paste")
			(net "P1V8_VDDA_PEX2")
		)
		(pad "2" smd rect
			(at 0.2667 0 90)
			(size 0.3048 0.381)
			(layers "F.Cu" "F.Mask" "F.Paste")
			(net "GND")
		)
	)
	(footprint ""
		(layer "F.Cu")
		(at 121.930668 -280.44902 -90)
		(property "Reference" "PR108"
			(at 0 0 270)
			(layer "F.SilkS")
			(hide yes)
			(effects
				(font
					(size 1.27 1.27)
				)
			)
		)
		(property "Value" ""
			(at 0 0 270)
			(layer "F.Fab")
			(effects
				(font
					(size 1.27 1.27)
				)
			)
		)
		(duplicate_pad_numbers_are_jumpers no)
		(fp_line
			(start -0.7874 0.4064)
			(end -0.7874 -0.4064)
			(stroke
				(width 0.1524)
				(type default)
			)
			(layer "F.SilkS")
		)
		(fp_line
			(start 0.7874 0.4064)
			(end -0.7874 0.4064)
			(stroke
				(width 0.1524)
				(type default)
			)
			(layer "F.SilkS")
		)
		(fp_line
			(start -0.7874 -0.4064)
			(end 0.7874 -0.4064)
			(stroke
				(width 0.1524)
				(type default)
			)
			(layer "F.SilkS")
		)
		(fp_line
			(start 0.7874 -0.4064)
			(end 0.7874 0.4064)
			(stroke
				(width 0.1524)
				(type default)
			)
			(layer "F.SilkS")
		)
		(fp_line
			(start -0.67945 0.3048)
			(end -0.67945 -0.305054)
			(stroke
				(width 0.1)
				(type default)
			)
			(layer "F.Fab")
		)
		(fp_line
			(start -0.12065 0.3048)
			(end -0.67945 0.3048)
			(stroke
				(width 0.1)
				(type default)
			)
			(layer "F.Fab")
		)
		(fp_line
			(start 0.120396 0.3048)
			(end 0.120396 0.2794)
			(stroke
				(width 0.1)
				(type default)
			)
			(layer "F.Fab")
		)
		(fp_line
			(start 0.67945 0.3048)
			(end 0.120396 0.3048)
			(stroke
				(width 0.1)
				(type default)
			)
			(layer "F.Fab")
		)
		(fp_line
			(start -0.12065 0.2794)
			(end -0.12065 0.3048)
			(stroke
				(width 0.1)
				(type default)
			)
			(layer "F.Fab")
		)
		(fp_line
			(start 0.120396 0.2794)
			(end -0.12065 0.2794)
			(stroke
				(width 0.1)
				(type default)
			)
			(layer "F.Fab")
		)
		(fp_line
			(start -0.12065 -0.2794)
			(end 0.12065 -0.2794)
			(stroke
				(width 0.1)
				(type default)
			)
			(layer "F.Fab")
		)
		(fp_line
			(start 0.12065 -0.2794)
			(end 0.12065 -0.3048)
			(stroke
				(width 0.1)
				(type default)
			)
			(layer "F.Fab")
		)
		(fp_line
			(start 0.12065 -0.3048)
			(end 0.67945 -0.3048)
			(stroke
				(width 0.1)
				(type default)
			)
			(layer "F.Fab")
		)
		(fp_line
			(start 0.67945 -0.3048)
			(end 0.67945 0.3048)
			(stroke
				(width 0.1)
				(type default)
			)
			(layer "F.Fab")
		)
		(fp_line
			(start -0.67945 -0.305054)
			(end -0.12065 -0.305054)
			(stroke
				(width 0.1)
				(type default)
			)
			(layer "F.Fab")
		)
		(fp_line
			(start -0.12065 -0.305054)
			(end -0.12065 -0.2794)
			(stroke
				(width 0.1)
				(type default)
			)
			(layer "F.Fab")
		)
		(pad "1" smd circle
			(at -0.40005 0 270)
			(size 0 0)
			(layers "F.Cu" "F.Mask" "F.Paste")
			(net "SW_P0V8_PEX1_BOOT1")
		)
		(pad "2" smd circle
			(at 0.40005 0 270)
			(size 0 0)
			(layers "F.Cu" "F.Mask" "F.Paste")
			(net "SW_P0V8_PEX1_BOOT1_R")
		)
	)
	(footprint ""
		(layer "F.Cu")
		(at 249.822716 -22.867366 90)
		(property "Reference" "C3931"
			(at 0 0 90)
			(layer "F.SilkS")
			(hide yes)
			(effects
				(font
					(size 1.27 1.27)
				)
			)
		)
		(property "Value" ""
			(at 0 0 90)
			(layer "F.Fab")
			(effects
				(font
					(size 1.27 1.27)
				)
			)
		)
		(duplicate_pad_numbers_are_jumpers no)
		(fp_line
			(start 0.7874 -0.4064)
			(end 0.7874 0.4064)
			(stroke
				(width 0.1524)
				(type default)
			)
			(layer "F.SilkS")
		)
		(fp_line
			(start -0.7874 -0.4064)
			(end 0.7874 -0.4064)
			(stroke
				(width 0.1524)
				(type default)
			)
			(layer "F.SilkS")
		)
		(fp_line
			(start 0.7874 0.4064)
			(end -0.7874 0.4064)
			(stroke
				(width 0.1524)
				(type default)
			)
			(layer "F.SilkS")
		)
		(fp_line
			(start -0.7874 0.4064)
			(end -0.7874 -0.4064)
			(stroke
				(width 0.1524)
				(type default)
			)
			(layer "F.SilkS")
		)
		(fp_line
			(start -0.12065 -0.305054)
			(end -0.12065 -0.2794)
			(stroke
				(width 0.1)
				(type default)
			)
			(layer "F.Fab")
		)
		(fp_line
			(start -0.67945 -0.305054)
			(end -0.12065 -0.305054)
			(stroke
				(width 0.1)
				(type default)
			)
			(layer "F.Fab")
		)
		(fp_line
			(start 0.67945 -0.3048)
			(end 0.67945 0.3048)
			(stroke
				(width 0.1)
				(type default)
			)
			(layer "F.Fab")
		)
		(fp_line
			(start 0.12065 -0.3048)
			(end 0.67945 -0.3048)
			(stroke
				(width 0.1)
				(type default)
			)
			(layer "F.Fab")
		)
		(fp_line
			(start 0.12065 -0.2794)
			(end 0.12065 -0.3048)
			(stroke
				(width 0.1)
				(type default)
			)
			(layer "F.Fab")
		)
		(fp_line
			(start -0.12065 -0.2794)
			(end 0.12065 -0.2794)
			(stroke
				(width 0.1)
				(type default)
			)
			(layer "F.Fab")
		)
		(fp_line
			(start 0.120396 0.2794)
			(end -0.12065 0.2794)
			(stroke
				(width 0.1)
				(type default)
			)
			(layer "F.Fab")
		)
		(fp_line
			(start -0.12065 0.2794)
			(end -0.12065 0.3048)
			(stroke
				(width 0.1)
				(type default)
			)
			(layer "F.Fab")
		)
		(fp_line
			(start 0.67945 0.3048)
			(end 0.120396 0.3048)
			(stroke
				(width 0.1)
				(type default)
			)
			(layer "F.Fab")
		)
		(fp_line
			(start 0.120396 0.3048)
			(end 0.120396 0.2794)
			(stroke
				(width 0.1)
				(type default)
			)
			(layer "F.Fab")
		)
		(fp_line
			(start -0.12065 0.3048)
			(end -0.67945 0.3048)
			(stroke
				(width 0.1)
				(type default)
			)
			(layer "F.Fab")
		)
		(fp_line
			(start -0.67945 0.3048)
			(end -0.67945 -0.305054)
			(stroke
				(width 0.1)
				(type default)
			)
			(layer "F.Fab")
		)
		(pad "1" smd circle
			(at -0.40005 0 90)
			(size 0 0)
			(layers "F.Cu" "F.Mask" "F.Paste")
			(net "P12V_SSD8")
		)
		(pad "2" smd circle
			(at 0.40005 0 90)
			(size 0 0)
			(layers "F.Cu" "F.Mask" "F.Paste")
			(net "GND")
		)
	)
	(footprint ""
		(layer "F.Cu")
		(at 353.147884 -40.037258 90)
		(property "Reference" "U372"
			(at 0.196342 2.402586 90)
			(unlocked yes)
			(layer "F.SilkS")
			(effects
				(font
					(size 0.7874 0.5842)
					(thickness 0.1524)
				)
			)
		)
		(property "Value" ""
			(at 0 0 90)
			(layer "F.Fab")
			(effects
				(font
					(size 1.27 1.27)
				)
			)
		)
		(duplicate_pad_numbers_are_jumpers no)
		(fp_line
			(start -1.949958 -1.610106)
			(end 1.949958 -1.610106)
			(stroke
				(width 0.1524)
				(type default)
			)
			(layer "F.SilkS")
		)
		(fp_line
			(start 1.949958 -1.560068)
			(end 1.949958 1.610106)
			(stroke
				(width 0.1524)
				(type default)
			)
			(layer "F.SilkS")
		)
		(fp_line
			(start 1.949958 1.610106)
			(end -1.949958 1.610106)
			(stroke
				(width 0.1524)
				(type default)
			)
			(layer "F.SilkS")
		)
		(fp_line
			(start -1.949958 1.610106)
			(end -1.949958 -1.610106)
			(stroke
				(width 0.1524)
				(type default)
			)
			(layer "F.SilkS")
		)
		(fp_line
			(start 0.750062 -1.560068)
			(end 0.750062 1.560068)
			(stroke
				(width 0.1)
				(type default)
			)
			(layer "F.Fab")
		)
		(fp_line
			(start -0.750062 -1.560068)
			(end 0.750062 -1.560068)
			(stroke
				(width 0.1)
				(type default)
			)
			(layer "F.Fab")
		)
		(fp_line
			(start 0.750062 1.560068)
			(end -0.750062 1.560068)
			(stroke
				(width 0.1)
				(type default)
			)
			(layer "F.Fab")
		)
		(fp_line
			(start -0.750062 1.560068)
			(end -0.750062 -1.560068)
			(stroke
				(width 0.1)
				(type default)
			)
			(layer "F.Fab")
		)
		(pad "D" smd rect
			(at 1.100074 0)
			(size 1.016 1.4224)
			(layers "F.Cu" "F.Mask" "F.Paste")
			(net "SSD12_AUX_P3V3_EN")
		)
		(pad "G" smd rect
			(at -1.100074 -0.94996)
			(size 1.016 1.4224)
			(layers "F.Cu" "F.Mask" "F.Paste")
			(net "PRSNT_SSD12_R1_N")
		)
		(pad "S" smd rect
			(at -1.100074 0.94996)
			(size 1.016 1.4224)
			(layers "F.Cu" "F.Mask" "F.Paste")
			(net "GND")
		)
	)
	(footprint ""
		(layer "F.Cu")
		(at 336.467704 -52.035456 180)
		(property "Reference" "R876"
			(at 0 0 180)
			(layer "F.SilkS")
			(hide yes)
			(effects
				(font
					(size 1.27 1.27)
				)
			)
		)
		(property "Value" ""
			(at 0 0 180)
			(layer "F.Fab")
			(effects
				(font
					(size 1.27 1.27)
				)
			)
		)
		(duplicate_pad_numbers_are_jumpers no)
		(fp_line
			(start 0.7874 0.4064)
			(end -0.7874 0.4064)
			(stroke
				(width 0.1524)
				(type default)
			)
			(layer "F.SilkS")
		)
		(fp_line
			(start 0.7874 -0.4064)
			(end 0.7874 0.4064)
			(stroke
				(width 0.1524)
				(type default)
			)
			(layer "F.SilkS")
		)
		(fp_line
			(start -0.7874 0.4064)
			(end -0.7874 -0.4064)
			(stroke
				(width 0.1524)
				(type default)
			)
			(layer "F.SilkS")
		)
		(fp_line
			(start -0.7874 -0.4064)
			(end 0.7874 -0.4064)
			(stroke
				(width 0.1524)
				(type default)
			)
			(layer "F.SilkS")
		)
		(fp_line
			(start 0.67945 0.3048)
			(end 0.120396 0.3048)
			(stroke
				(width 0.1)
				(type default)
			)
			(layer "F.Fab")
		)
		(fp_line
			(start 0.67945 -0.3048)
			(end 0.67945 0.3048)
			(stroke
				(width 0.1)
				(type default)
			)
			(layer "F.Fab")
		)
		(fp_line
			(start 0.12065 -0.2794)
			(end 0.12065 -0.3048)
			(stroke
				(width 0.1)
				(type default)
			)
			(layer "F.Fab")
		)
		(fp_line
			(start 0.12065 -0.3048)
			(end 0.67945 -0.3048)
			(stroke
				(width 0.1)
				(type default)
			)
			(layer "F.Fab")
		)
		(fp_line
			(start 0.120396 0.3048)
			(end 0.120396 0.2794)
			(stroke
				(width 0.1)
				(type default)
			)
			(layer "F.Fab")
		)
		(fp_line
			(start 0.120396 0.2794)
			(end -0.12065 0.2794)
			(stroke
				(width 0.1)
				(type default)
			)
			(layer "F.Fab")
		)
		(fp_line
			(start -0.12065 0.3048)
			(end -0.67945 0.3048)
			(stroke
				(width 0.1)
				(type default)
			)
			(layer "F.Fab")
		)
		(fp_line
			(start -0.12065 0.2794)
			(end -0.12065 0.3048)
			(stroke
				(width 0.1)
				(type default)
			)
			(layer "F.Fab")
		)
		(fp_line
			(start -0.12065 -0.2794)
			(end 0.12065 -0.2794)
			(stroke
				(width 0.1)
				(type default)
			)
			(layer "F.Fab")
		)
		(fp_line
			(start -0.12065 -0.305054)
			(end -0.12065 -0.2794)
			(stroke
				(width 0.1)
				(type default)
			)
			(layer "F.Fab")
		)
		(fp_line
			(start -0.67945 0.3048)
			(end -0.67945 -0.305054)
			(stroke
				(width 0.1)
				(type default)
			)
			(layer "F.Fab")
		)
		(fp_line
			(start -0.67945 -0.305054)
			(end -0.12065 -0.305054)
			(stroke
				(width 0.1)
				(type default)
			)
			(layer "F.Fab")
		)
		(pad "1" smd circle
			(at -0.40005 0 180)
			(size 0 0)
			(layers "F.Cu" "F.Mask" "F.Paste")
			(net "P3V3_AUX")
		)
		(pad "2" smd circle
			(at 0.40005 0 180)
			(size 0 0)
			(layers "F.Cu" "F.Mask" "F.Paste")
			(net "PWRGD_P12V_SSD11")
		)
	)
	(footprint ""
		(layer "F.Cu")
		(at 403.657816 -27.006296 -90)
		(property "Reference" "PR7127"
			(at 0 0 270)
			(layer "F.SilkS")
			(hide yes)
			(effects
				(font
					(size 1.27 1.27)
				)
			)
		)
		(property "Value" ""
			(at 0 0 270)
			(layer "F.Fab")
			(effects
				(font
					(size 1.27 1.27)
				)
			)
		)
		(duplicate_pad_numbers_are_jumpers no)
		(fp_line
			(start -0.7874 0.4064)
			(end -0.7874 -0.4064)
			(stroke
				(width 0.1524)
				(type default)
			)
			(layer "F.SilkS")
		)
		(fp_line
			(start 0.7874 0.4064)
			(end -0.7874 0.4064)
			(stroke
				(width 0.1524)
				(type default)
			)
			(layer "F.SilkS")
		)
		(fp_line
			(start -0.7874 -0.4064)
			(end 0.7874 -0.4064)
			(stroke
				(width 0.1524)
				(type default)
			)
			(layer "F.SilkS")
		)
		(fp_line
			(start 0.7874 -0.4064)
			(end 0.7874 0.4064)
			(stroke
				(width 0.1524)
				(type default)
			)
			(layer "F.SilkS")
		)
		(fp_line
			(start -0.67945 0.3048)
			(end -0.67945 -0.305054)
			(stroke
				(width 0.1)
				(type default)
			)
			(layer "F.Fab")
		)
		(fp_line
			(start -0.12065 0.3048)
			(end -0.67945 0.3048)
			(stroke
				(width 0.1)
				(type default)
			)
			(layer "F.Fab")
		)
		(fp_line
			(start 0.120396 0.3048)
			(end 0.120396 0.2794)
			(stroke
				(width 0.1)
				(type default)
			)
			(layer "F.Fab")
		)
		(fp_line
			(start 0.67945 0.3048)
			(end 0.120396 0.3048)
			(stroke
				(width 0.1)
				(type default)
			)
			(layer "F.Fab")
		)
		(fp_line
			(start -0.12065 0.2794)
			(end -0.12065 0.3048)
			(stroke
				(width 0.1)
				(type default)
			)
			(layer "F.Fab")
		)
		(fp_line
			(start 0.120396 0.2794)
			(end -0.12065 0.2794)
			(stroke
				(width 0.1)
				(type default)
			)
			(layer "F.Fab")
		)
		(fp_line
			(start -0.12065 -0.2794)
			(end 0.12065 -0.2794)
			(stroke
				(width 0.1)
				(type default)
			)
			(layer "F.Fab")
		)
		(fp_line
			(start 0.12065 -0.2794)
			(end 0.12065 -0.3048)
			(stroke
				(width 0.1)
				(type default)
			)
			(layer "F.Fab")
		)
		(fp_line
			(start 0.12065 -0.3048)
			(end 0.67945 -0.3048)
			(stroke
				(width 0.1)
				(type default)
			)
			(layer "F.Fab")
		)
		(fp_line
			(start 0.67945 -0.3048)
			(end 0.67945 0.3048)
			(stroke
				(width 0.1)
				(type default)
			)
			(layer "F.Fab")
		)
		(fp_line
			(start -0.67945 -0.305054)
			(end -0.12065 -0.305054)
			(stroke
				(width 0.1)
				(type default)
			)
			(layer "F.Fab")
		)
		(fp_line
			(start -0.12065 -0.305054)
			(end -0.12065 -0.2794)
			(stroke
				(width 0.1)
				(type default)
			)
			(layer "F.Fab")
		)
		(pad "1" smd circle
			(at -0.40005 0 270)
			(size 0 0)
			(layers "F.Cu" "F.Mask" "F.Paste")
			(net "P3V3_SSD14_CO_MODE")
		)
		(pad "2" smd circle
			(at 0.40005 0 270)
			(size 0 0)
			(layers "F.Cu" "F.Mask" "F.Paste")
			(net "GND")
		)
	)
	(footprint ""
		(layer "F.Cu")
		(at 331.778102 -89.269316 180)
		(property "Reference" "C2681"
			(at 0 0 180)
			(layer "F.SilkS")
			(hide yes)
			(effects
				(font
					(size 1.27 1.27)
				)
			)
		)
		(property "Value" ""
			(at 0 0 180)
			(layer "F.Fab")
			(effects
				(font
					(size 1.27 1.27)
				)
			)
		)
		(duplicate_pad_numbers_are_jumpers no)
		(fp_line
			(start 1.2954 0.5842)
			(end -1.2954 0.5842)
			(stroke
				(width 0.1524)
				(type default)
			)
			(layer "F.SilkS")
		)
		(fp_line
			(start 1.2954 -0.5842)
			(end 1.2954 0.5842)
			(stroke
				(width 0.1524)
				(type default)
			)
			(layer "F.SilkS")
		)
		(fp_line
			(start -1.2954 0.5842)
			(end -1.2954 -0.5842)
			(stroke
				(width 0.1524)
				(type default)
			)
			(layer "F.SilkS")
		)
		(fp_line
			(start -1.2954 -0.5842)
			(end 1.2954 -0.5842)
			(stroke
				(width 0.1524)
				(type default)
			)
			(layer "F.SilkS")
		)
		(fp_line
			(start 1.1938 0.4064)
			(end 0.8636 0.4064)
			(stroke
				(width 0.1)
				(type default)
			)
			(layer "F.Fab")
		)
		(fp_line
			(start 1.1938 -0.4064)
			(end 1.1938 0.4064)
			(stroke
				(width 0.1)
				(type default)
			)
			(layer "F.Fab")
		)
		(fp_line
			(start 0.8636 0.4572)
			(end -0.8636 0.4572)
			(stroke
				(width 0.1)
				(type default)
			)
			(layer "F.Fab")
		)
		(fp_line
			(start 0.8636 0.4064)
			(end 0.8636 0.4572)
			(stroke
				(width 0.1)
				(type default)
			)
			(layer "F.Fab")
		)
		(fp_line
			(start 0.8636 -0.4064)
			(end 1.1938 -0.4064)
			(stroke
				(width 0.1)
				(type default)
			)
			(layer "F.Fab")
		)
		(fp_line
			(start 0.8636 -0.4572)
			(end 0.8636 -0.4064)
			(stroke
				(width 0.1)
				(type default)
			)
			(layer "F.Fab")
		)
		(fp_line
			(start -0.8636 0.4572)
			(end -0.8636 0.4064)
			(stroke
				(width 0.1)
				(type default)
			)
			(layer "F.Fab")
		)
		(fp_line
			(start -0.8636 0.4064)
			(end -1.1938 0.4064)
			(stroke
				(width 0.1)
				(type default)
			)
			(layer "F.Fab")
		)
		(fp_line
			(start -0.8636 -0.4064)
			(end -0.8636 -0.4572)
			(stroke
				(width 0.1)
				(type default)
			)
			(layer "F.Fab")
		)
		(fp_line
			(start -0.8636 -0.4572)
			(end 0.8636 -0.4572)
			(stroke
				(width 0.1)
				(type default)
			)
			(layer "F.Fab")
		)
		(fp_line
			(start -1.1938 0.4064)
			(end -1.1938 -0.4064)
			(stroke
				(width 0.1)
				(type default)
			)
			(layer "F.Fab")
		)
		(fp_line
			(start -1.1938 -0.4064)
			(end -0.8636 -0.4064)
			(stroke
				(width 0.1)
				(type default)
			)
			(layer "F.Fab")
		)
		(pad "1" smd rect
			(at -0.7366 0 90)
			(size 0.7112 0.8128)
			(layers "F.Cu" "F.Mask" "F.Paste")
			(net "P3V3_VDDAR_9ZXL0851_8_15")
		)
		(pad "2" smd rect
			(at 0.7366 0 90)
			(size 0.7112 0.8128)
			(layers "F.Cu" "F.Mask" "F.Paste")
			(net "GND")
		)
	)
	(footprint ""
		(layer "F.Cu")
		(at 283.416502 -343.952322 90)
		(property "Reference" "C599"
			(at 0 0 90)
			(layer "F.SilkS")
			(hide yes)
			(effects
				(font
					(size 1.27 1.27)
				)
			)
		)
		(property "Value" ""
			(at 0 0 90)
			(layer "F.Fab")
			(effects
				(font
					(size 1.27 1.27)
				)
			)
		)
		(duplicate_pad_numbers_are_jumpers no)
		(fp_line
			(start 0.299974 -0.150114)
			(end 0.299974 0.150114)
			(stroke
				(width 0.1)
				(type default)
			)
			(layer "F.Fab")
		)
		(fp_line
			(start -0.299974 -0.150114)
			(end 0.299974 -0.150114)
			(stroke
				(width 0.1)
				(type default)
			)
			(layer "F.Fab")
		)
		(fp_line
			(start 0.299974 0.150114)
			(end -0.299974 0.150114)
			(stroke
				(width 0.1)
				(type default)
			)
			(layer "F.Fab")
		)
		(fp_line
			(start -0.299974 0.150114)
			(end -0.299974 -0.150114)
			(stroke
				(width 0.1)
				(type default)
			)
			(layer "F.Fab")
		)
		(pad "1" smd rect
			(at -0.2667 0 90)
			(size 0.3048 0.381)
			(layers "F.Cu" "F.Mask" "F.Paste")
			(net "P5E_PEX2_STN7_TX_DP<119>")
		)
		(pad "2" smd rect
			(at 0.2667 0 90)
			(size 0.3048 0.381)
			(layers "F.Cu" "F.Mask" "F.Paste")
			(net "P5E_PEX2_STN7_TX_C_DP<119>")
		)
	)
	(footprint ""
		(layer "F.Cu")
		(at 180.8099 -198.997062 180)
		(property "Reference" "C2095"
			(at 0 0 180)
			(layer "F.SilkS")
			(hide yes)
			(effects
				(font
					(size 1.27 1.27)
				)
			)
		)
		(property "Value" ""
			(at 0 0 180)
			(layer "F.Fab")
			(effects
				(font
					(size 1.27 1.27)
				)
			)
		)
		(duplicate_pad_numbers_are_jumpers no)
		(fp_line
			(start 0.7874 0.4064)
			(end -0.7874 0.4064)
			(stroke
				(width 0.1524)
				(type default)
			)
			(layer "F.SilkS")
		)
		(fp_line
			(start 0.7874 -0.4064)
			(end 0.7874 0.4064)
			(stroke
				(width 0.1524)
				(type default)
			)
			(layer "F.SilkS")
		)
		(fp_line
			(start -0.7874 0.4064)
			(end -0.7874 -0.4064)
			(stroke
				(width 0.1524)
				(type default)
			)
			(layer "F.SilkS")
		)
		(fp_line
			(start -0.7874 -0.4064)
			(end 0.7874 -0.4064)
			(stroke
				(width 0.1524)
				(type default)
			)
			(layer "F.SilkS")
		)
		(fp_line
			(start 0.67945 0.3048)
			(end 0.120396 0.3048)
			(stroke
				(width 0.1)
				(type default)
			)
			(layer "F.Fab")
		)
		(fp_line
			(start 0.67945 -0.3048)
			(end 0.67945 0.3048)
			(stroke
				(width 0.1)
				(type default)
			)
			(layer "F.Fab")
		)
		(fp_line
			(start 0.12065 -0.2794)
			(end 0.12065 -0.3048)
			(stroke
				(width 0.1)
				(type default)
			)
			(layer "F.Fab")
		)
		(fp_line
			(start 0.12065 -0.3048)
			(end 0.67945 -0.3048)
			(stroke
				(width 0.1)
				(type default)
			)
			(layer "F.Fab")
		)
		(fp_line
			(start 0.120396 0.3048)
			(end 0.120396 0.2794)
			(stroke
				(width 0.1)
				(type default)
			)
			(layer "F.Fab")
		)
		(fp_line
			(start 0.120396 0.2794)
			(end -0.12065 0.2794)
			(stroke
				(width 0.1)
				(type default)
			)
			(layer "F.Fab")
		)
		(fp_line
			(start -0.12065 0.3048)
			(end -0.67945 0.3048)
			(stroke
				(width 0.1)
				(type default)
			)
			(layer "F.Fab")
		)
		(fp_line
			(start -0.12065 0.2794)
			(end -0.12065 0.3048)
			(stroke
				(width 0.1)
				(type default)
			)
			(layer "F.Fab")
		)
		(fp_line
			(start -0.12065 -0.2794)
			(end 0.12065 -0.2794)
			(stroke
				(width 0.1)
				(type default)
			)
			(layer "F.Fab")
		)
		(fp_line
			(start -0.12065 -0.305054)
			(end -0.12065 -0.2794)
			(stroke
				(width 0.1)
				(type default)
			)
			(layer "F.Fab")
		)
		(fp_line
			(start -0.67945 0.3048)
			(end -0.67945 -0.305054)
			(stroke
				(width 0.1)
				(type default)
			)
			(layer "F.Fab")
		)
		(fp_line
			(start -0.67945 -0.305054)
			(end -0.12065 -0.305054)
			(stroke
				(width 0.1)
				(type default)
			)
			(layer "F.Fab")
		)
		(pad "1" smd circle
			(at -0.40005 0 180)
			(size 0 0)
			(layers "F.Cu" "F.Mask" "F.Paste")
			(net "GND")
		)
		(pad "2" smd circle
			(at 0.40005 0 180)
			(size 0 0)
			(layers "F.Cu" "F.Mask" "F.Paste")
			(net "P1V8_PEX")
		)
	)
	(footprint ""
		(layer "F.Cu")
		(at 84.57565 -36.915598 -90)
		(property "Reference" "R5550"
			(at 0 0 270)
			(layer "F.SilkS")
			(hide yes)
			(effects
				(font
					(size 1.27 1.27)
				)
			)
		)
		(property "Value" ""
			(at 0 0 270)
			(layer "F.Fab")
			(effects
				(font
					(size 1.27 1.27)
				)
			)
		)
		(duplicate_pad_numbers_are_jumpers no)
		(fp_line
			(start -0.7874 0.4064)
			(end -0.7874 -0.4064)
			(stroke
				(width 0.1524)
				(type default)
			)
			(layer "F.SilkS")
		)
		(fp_line
			(start 0.7874 0.4064)
			(end -0.7874 0.4064)
			(stroke
				(width 0.1524)
				(type default)
			)
			(layer "F.SilkS")
		)
		(fp_line
			(start -0.7874 -0.4064)
			(end 0.7874 -0.4064)
			(stroke
				(width 0.1524)
				(type default)
			)
			(layer "F.SilkS")
		)
		(fp_line
			(start 0.7874 -0.4064)
			(end 0.7874 0.4064)
			(stroke
				(width 0.1524)
				(type default)
			)
			(layer "F.SilkS")
		)
		(fp_line
			(start -0.67945 0.3048)
			(end -0.67945 -0.305054)
			(stroke
				(width 0.1)
				(type default)
			)
			(layer "F.Fab")
		)
		(fp_line
			(start -0.12065 0.3048)
			(end -0.67945 0.3048)
			(stroke
				(width 0.1)
				(type default)
			)
			(layer "F.Fab")
		)
		(fp_line
			(start 0.120396 0.3048)
			(end 0.120396 0.2794)
			(stroke
				(width 0.1)
				(type default)
			)
			(layer "F.Fab")
		)
		(fp_line
			(start 0.67945 0.3048)
			(end 0.120396 0.3048)
			(stroke
				(width 0.1)
				(type default)
			)
			(layer "F.Fab")
		)
		(fp_line
			(start -0.12065 0.2794)
			(end -0.12065 0.3048)
			(stroke
				(width 0.1)
				(type default)
			)
			(layer "F.Fab")
		)
		(fp_line
			(start 0.120396 0.2794)
			(end -0.12065 0.2794)
			(stroke
				(width 0.1)
				(type default)
			)
			(layer "F.Fab")
		)
		(fp_line
			(start -0.12065 -0.2794)
			(end 0.12065 -0.2794)
			(stroke
				(width 0.1)
				(type default)
			)
			(layer "F.Fab")
		)
		(fp_line
			(start 0.12065 -0.2794)
			(end 0.12065 -0.3048)
			(stroke
				(width 0.1)
				(type default)
			)
			(layer "F.Fab")
		)
		(fp_line
			(start 0.12065 -0.3048)
			(end 0.67945 -0.3048)
			(stroke
				(width 0.1)
				(type default)
			)
			(layer "F.Fab")
		)
		(fp_line
			(start 0.67945 -0.3048)
			(end 0.67945 0.3048)
			(stroke
				(width 0.1)
				(type default)
			)
			(layer "F.Fab")
		)
		(fp_line
			(start -0.67945 -0.305054)
			(end -0.12065 -0.305054)
			(stroke
				(width 0.1)
				(type default)
			)
			(layer "F.Fab")
		)
		(fp_line
			(start -0.12065 -0.305054)
			(end -0.12065 -0.2794)
			(stroke
				(width 0.1)
				(type default)
			)
			(layer "F.Fab")
		)
		(pad "1" smd circle
			(at -0.40005 0 270)
			(size 0 0)
			(layers "F.Cu" "F.Mask" "F.Paste")
			(net "PRSNT_SSD3_R1_N")
		)
		(pad "2" smd circle
			(at 0.40005 0 270)
			(size 0 0)
			(layers "F.Cu" "F.Mask" "F.Paste")
			(net "PRSNT_SSD3_R_N")
		)
	)
	(footprint ""
		(layer "F.Cu")
		(at 241.624612 -62.617858 -90)
		(property "Reference" "R5992"
			(at 0 0 270)
			(layer "F.SilkS")
			(hide yes)
			(effects
				(font
					(size 1.27 1.27)
				)
			)
		)
		(property "Value" ""
			(at 0 0 270)
			(layer "F.Fab")
			(effects
				(font
					(size 1.27 1.27)
				)
			)
		)
		(duplicate_pad_numbers_are_jumpers no)
		(fp_line
			(start -0.7874 0.4064)
			(end -0.7874 -0.4064)
			(stroke
				(width 0.1524)
				(type default)
			)
			(layer "F.SilkS")
		)
		(fp_line
			(start 0.7874 0.4064)
			(end -0.7874 0.4064)
			(stroke
				(width 0.1524)
				(type default)
			)
			(layer "F.SilkS")
		)
		(fp_line
			(start -0.7874 -0.4064)
			(end 0.7874 -0.4064)
			(stroke
				(width 0.1524)
				(type default)
			)
			(layer "F.SilkS")
		)
		(fp_line
			(start 0.7874 -0.4064)
			(end 0.7874 0.4064)
			(stroke
				(width 0.1524)
				(type default)
			)
			(layer "F.SilkS")
		)
		(fp_line
			(start -0.67945 0.3048)
			(end -0.67945 -0.305054)
			(stroke
				(width 0.1)
				(type default)
			)
			(layer "F.Fab")
		)
		(fp_line
			(start -0.12065 0.3048)
			(end -0.67945 0.3048)
			(stroke
				(width 0.1)
				(type default)
			)
			(layer "F.Fab")
		)
		(fp_line
			(start 0.120396 0.3048)
			(end 0.120396 0.2794)
			(stroke
				(width 0.1)
				(type default)
			)
			(layer "F.Fab")
		)
		(fp_line
			(start 0.67945 0.3048)
			(end 0.120396 0.3048)
			(stroke
				(width 0.1)
				(type default)
			)
			(layer "F.Fab")
		)
		(fp_line
			(start -0.12065 0.2794)
			(end -0.12065 0.3048)
			(stroke
				(width 0.1)
				(type default)
			)
			(layer "F.Fab")
		)
		(fp_line
			(start 0.120396 0.2794)
			(end -0.12065 0.2794)
			(stroke
				(width 0.1)
				(type default)
			)
			(layer "F.Fab")
		)
		(fp_line
			(start -0.12065 -0.2794)
			(end 0.12065 -0.2794)
			(stroke
				(width 0.1)
				(type default)
			)
			(layer "F.Fab")
		)
		(fp_line
			(start 0.12065 -0.2794)
			(end 0.12065 -0.3048)
			(stroke
				(width 0.1)
				(type default)
			)
			(layer "F.Fab")
		)
		(fp_line
			(start 0.12065 -0.3048)
			(end 0.67945 -0.3048)
			(stroke
				(width 0.1)
				(type default)
			)
			(layer "F.Fab")
		)
		(fp_line
			(start 0.67945 -0.3048)
			(end 0.67945 0.3048)
			(stroke
				(width 0.1)
				(type default)
			)
			(layer "F.Fab")
		)
		(fp_line
			(start -0.67945 -0.305054)
			(end -0.12065 -0.305054)
			(stroke
				(width 0.1)
				(type default)
			)
			(layer "F.Fab")
		)
		(fp_line
			(start -0.12065 -0.305054)
			(end -0.12065 -0.2794)
			(stroke
				(width 0.1)
				(type default)
			)
			(layer "F.Fab")
		)
		(pad "1" smd circle
			(at -0.40005 0 270)
			(size 0 0)
			(layers "F.Cu" "F.Mask" "F.Paste")
			(net "P3V3_AUX")
		)
		(pad "2" smd circle
			(at 0.40005 0 270)
			(size 0 0)
			(layers "F.Cu" "F.Mask" "F.Paste")
			(net "PWRGD_P12V_SSD8_D")
		)
	)
	(footprint ""
		(layer "F.Cu")
		(at 197.102476 -89.1159)
		(property "Reference" "C902"
			(at 0 0 0)
			(layer "F.SilkS")
			(hide yes)
			(effects
				(font
					(size 1.27 1.27)
				)
			)
		)
		(property "Value" ""
			(at 0 0 0)
			(layer "F.Fab")
			(effects
				(font
					(size 1.27 1.27)
				)
			)
		)
		(duplicate_pad_numbers_are_jumpers no)
		(fp_line
			(start -0.7874 -0.4064)
			(end 0.7874 -0.4064)
			(stroke
				(width 0.1524)
				(type default)
			)
			(layer "F.SilkS")
		)
		(fp_line
			(start -0.7874 0.4064)
			(end -0.7874 -0.4064)
			(stroke
				(width 0.1524)
				(type default)
			)
			(layer "F.SilkS")
		)
		(fp_line
			(start 0.7874 -0.4064)
			(end 0.7874 0.4064)
			(stroke
				(width 0.1524)
				(type default)
			)
			(layer "F.SilkS")
		)
		(fp_line
			(start 0.7874 0.4064)
			(end -0.7874 0.4064)
			(stroke
				(width 0.1524)
				(type default)
			)
			(layer "F.SilkS")
		)
		(fp_line
			(start -0.67945 -0.305054)
			(end -0.12065 -0.305054)
			(stroke
				(width 0.1)
				(type default)
			)
			(layer "F.Fab")
		)
		(fp_line
			(start -0.67945 0.3048)
			(end -0.67945 -0.305054)
			(stroke
				(width 0.1)
				(type default)
			)
			(layer "F.Fab")
		)
		(fp_line
			(start -0.12065 -0.305054)
			(end -0.12065 -0.2794)
			(stroke
				(width 0.1)
				(type default)
			)
			(layer "F.Fab")
		)
		(fp_line
			(start -0.12065 -0.2794)
			(end 0.12065 -0.2794)
			(stroke
				(width 0.1)
				(type default)
			)
			(layer "F.Fab")
		)
		(fp_line
			(start -0.12065 0.2794)
			(end -0.12065 0.3048)
			(stroke
				(width 0.1)
				(type default)
			)
			(layer "F.Fab")
		)
		(fp_line
			(start -0.12065 0.3048)
			(end -0.67945 0.3048)
			(stroke
				(width 0.1)
				(type default)
			)
			(layer "F.Fab")
		)
		(fp_line
			(start 0.120396 0.2794)
			(end -0.12065 0.2794)
			(stroke
				(width 0.1)
				(type default)
			)
			(layer "F.Fab")
		)
		(fp_line
			(start 0.120396 0.3048)
			(end 0.120396 0.2794)
			(stroke
				(width 0.1)
				(type default)
			)
			(layer "F.Fab")
		)
		(fp_line
			(start 0.12065 -0.3048)
			(end 0.67945 -0.3048)
			(stroke
				(width 0.1)
				(type default)
			)
			(layer "F.Fab")
		)
		(fp_line
			(start 0.12065 -0.2794)
			(end 0.12065 -0.3048)
			(stroke
				(width 0.1)
				(type default)
			)
			(layer "F.Fab")
		)
		(fp_line
			(start 0.67945 -0.3048)
			(end 0.67945 0.3048)
			(stroke
				(width 0.1)
				(type default)
			)
			(layer "F.Fab")
		)
		(fp_line
			(start 0.67945 0.3048)
			(end 0.120396 0.3048)
			(stroke
				(width 0.1)
				(type default)
			)
			(layer "F.Fab")
		)
		(pad "1" smd circle
			(at -0.40005 0)
			(size 0 0)
			(layers "F.Cu" "F.Mask" "F.Paste")
			(net "P3V3_AUX")
		)
		(pad "2" smd circle
			(at 0.40005 0)
			(size 0 0)
			(layers "F.Cu" "F.Mask" "F.Paste")
			(net "GND")
		)
	)
	(footprint ""
		(layer "F.Cu")
		(at 366.566196 -282.421584 -90)
		(property "Reference" "PC194"
			(at 0 0 270)
			(layer "F.SilkS")
			(hide yes)
			(effects
				(font
					(size 1.27 1.27)
				)
			)
		)
		(property "Value" ""
			(at 0 0 270)
			(layer "F.Fab")
			(effects
				(font
					(size 1.27 1.27)
				)
			)
		)
		(duplicate_pad_numbers_are_jumpers no)
		(fp_line
			(start -0.7874 0.4064)
			(end -0.7874 -0.4064)
			(stroke
				(width 0.1524)
				(type default)
			)
			(layer "F.SilkS")
		)
		(fp_line
			(start 0.7874 0.4064)
			(end -0.7874 0.4064)
			(stroke
				(width 0.1524)
				(type default)
			)
			(layer "F.SilkS")
		)
		(fp_line
			(start -0.7874 -0.4064)
			(end 0.7874 -0.4064)
			(stroke
				(width 0.1524)
				(type default)
			)
			(layer "F.SilkS")
		)
		(fp_line
			(start 0.7874 -0.4064)
			(end 0.7874 0.4064)
			(stroke
				(width 0.1524)
				(type default)
			)
			(layer "F.SilkS")
		)
		(fp_line
			(start -0.67945 0.3048)
			(end -0.67945 -0.305054)
			(stroke
				(width 0.1)
				(type default)
			)
			(layer "F.Fab")
		)
		(fp_line
			(start -0.12065 0.3048)
			(end -0.67945 0.3048)
			(stroke
				(width 0.1)
				(type default)
			)
			(layer "F.Fab")
		)
		(fp_line
			(start 0.120396 0.3048)
			(end 0.120396 0.2794)
			(stroke
				(width 0.1)
				(type default)
			)
			(layer "F.Fab")
		)
		(fp_line
			(start 0.67945 0.3048)
			(end 0.120396 0.3048)
			(stroke
				(width 0.1)
				(type default)
			)
			(layer "F.Fab")
		)
		(fp_line
			(start -0.12065 0.2794)
			(end -0.12065 0.3048)
			(stroke
				(width 0.1)
				(type default)
			)
			(layer "F.Fab")
		)
		(fp_line
			(start 0.120396 0.2794)
			(end -0.12065 0.2794)
			(stroke
				(width 0.1)
				(type default)
			)
			(layer "F.Fab")
		)
		(fp_line
			(start -0.12065 -0.2794)
			(end 0.12065 -0.2794)
			(stroke
				(width 0.1)
				(type default)
			)
			(layer "F.Fab")
		)
		(fp_line
			(start 0.12065 -0.2794)
			(end 0.12065 -0.3048)
			(stroke
				(width 0.1)
				(type default)
			)
			(layer "F.Fab")
		)
		(fp_line
			(start 0.12065 -0.3048)
			(end 0.67945 -0.3048)
			(stroke
				(width 0.1)
				(type default)
			)
			(layer "F.Fab")
		)
		(fp_line
			(start 0.67945 -0.3048)
			(end 0.67945 0.3048)
			(stroke
				(width 0.1)
				(type default)
			)
			(layer "F.Fab")
		)
		(fp_line
			(start -0.67945 -0.305054)
			(end -0.12065 -0.305054)
			(stroke
				(width 0.1)
				(type default)
			)
			(layer "F.Fab")
		)
		(fp_line
			(start -0.12065 -0.305054)
			(end -0.12065 -0.2794)
			(stroke
				(width 0.1)
				(type default)
			)
			(layer "F.Fab")
		)
		(pad "1" smd circle
			(at -0.40005 0 270)
			(size 0 0)
			(layers "F.Cu" "F.Mask" "F.Paste")
			(net "P0V8_PEX3_VCC2")
		)
		(pad "2" smd circle
			(at 0.40005 0 270)
			(size 0 0)
			(layers "F.Cu" "F.Mask" "F.Paste")
			(net "GND")
		)
	)
	(footprint ""
		(layer "F.Cu")
		(at 38.7604 -116.7384)
		(property "Reference" "R39"
			(at 0 0 0)
			(layer "F.SilkS")
			(hide yes)
			(effects
				(font
					(size 1.27 1.27)
				)
			)
		)
		(property "Value" ""
			(at 0 0 0)
			(layer "F.Fab")
			(effects
				(font
					(size 1.27 1.27)
				)
			)
		)
		(duplicate_pad_numbers_are_jumpers no)
		(fp_line
			(start -0.7874 -0.4064)
			(end 0.7874 -0.4064)
			(stroke
				(width 0.1524)
				(type default)
			)
			(layer "F.SilkS")
		)
		(fp_line
			(start -0.7874 0.4064)
			(end -0.7874 -0.4064)
			(stroke
				(width 0.1524)
				(type default)
			)
			(layer "F.SilkS")
		)
		(fp_line
			(start 0.7874 -0.4064)
			(end 0.7874 0.4064)
			(stroke
				(width 0.1524)
				(type default)
			)
			(layer "F.SilkS")
		)
		(fp_line
			(start 0.7874 0.4064)
			(end -0.7874 0.4064)
			(stroke
				(width 0.1524)
				(type default)
			)
			(layer "F.SilkS")
		)
		(fp_line
			(start -0.67945 -0.305054)
			(end -0.12065 -0.305054)
			(stroke
				(width 0.1)
				(type default)
			)
			(layer "F.Fab")
		)
		(fp_line
			(start -0.67945 0.3048)
			(end -0.67945 -0.305054)
			(stroke
				(width 0.1)
				(type default)
			)
			(layer "F.Fab")
		)
		(fp_line
			(start -0.12065 -0.305054)
			(end -0.12065 -0.2794)
			(stroke
				(width 0.1)
				(type default)
			)
			(layer "F.Fab")
		)
		(fp_line
			(start -0.12065 -0.2794)
			(end 0.12065 -0.2794)
			(stroke
				(width 0.1)
				(type default)
			)
			(layer "F.Fab")
		)
		(fp_line
			(start -0.12065 0.2794)
			(end -0.12065 0.3048)
			(stroke
				(width 0.1)
				(type default)
			)
			(layer "F.Fab")
		)
		(fp_line
			(start -0.12065 0.3048)
			(end -0.67945 0.3048)
			(stroke
				(width 0.1)
				(type default)
			)
			(layer "F.Fab")
		)
		(fp_line
			(start 0.120396 0.2794)
			(end -0.12065 0.2794)
			(stroke
				(width 0.1)
				(type default)
			)
			(layer "F.Fab")
		)
		(fp_line
			(start 0.120396 0.3048)
			(end 0.120396 0.2794)
			(stroke
				(width 0.1)
				(type default)
			)
			(layer "F.Fab")
		)
		(fp_line
			(start 0.12065 -0.3048)
			(end 0.67945 -0.3048)
			(stroke
				(width 0.1)
				(type default)
			)
			(layer "F.Fab")
		)
		(fp_line
			(start 0.12065 -0.2794)
			(end 0.12065 -0.3048)
			(stroke
				(width 0.1)
				(type default)
			)
			(layer "F.Fab")
		)
		(fp_line
			(start 0.67945 -0.3048)
			(end 0.67945 0.3048)
			(stroke
				(width 0.1)
				(type default)
			)
			(layer "F.Fab")
		)
		(fp_line
			(start 0.67945 0.3048)
			(end 0.120396 0.3048)
			(stroke
				(width 0.1)
				(type default)
			)
			(layer "F.Fab")
		)
		(pad "1" smd circle
			(at -0.40005 0)
			(size 0 0)
			(layers "F.Cu" "F.Mask" "F.Paste")
			(net "PRSNT_NIC0_N")
		)
		(pad "2" smd circle
			(at 0.40005 0)
			(size 0 0)
			(layers "F.Cu" "F.Mask" "F.Paste")
			(net "PRSNTB0_NIC0_N")
		)
	)
	(footprint ""
		(layer "F.Cu")
		(at 115.860068 -343.952322 90)
		(property "Reference" "C359"
			(at 0 0 90)
			(layer "F.SilkS")
			(hide yes)
			(effects
				(font
					(size 1.27 1.27)
				)
			)
		)
		(property "Value" ""
			(at 0 0 90)
			(layer "F.Fab")
			(effects
				(font
					(size 1.27 1.27)
				)
			)
		)
		(duplicate_pad_numbers_are_jumpers no)
		(fp_line
			(start 0.299974 -0.150114)
			(end 0.299974 0.150114)
			(stroke
				(width 0.1)
				(type default)
			)
			(layer "F.Fab")
		)
		(fp_line
			(start -0.299974 -0.150114)
			(end 0.299974 -0.150114)
			(stroke
				(width 0.1)
				(type default)
			)
			(layer "F.Fab")
		)
		(fp_line
			(start 0.299974 0.150114)
			(end -0.299974 0.150114)
			(stroke
				(width 0.1)
				(type default)
			)
			(layer "F.Fab")
		)
		(fp_line
			(start -0.299974 0.150114)
			(end -0.299974 -0.150114)
			(stroke
				(width 0.1)
				(type default)
			)
			(layer "F.Fab")
		)
		(pad "1" smd rect
			(at -0.2667 0 90)
			(size 0.3048 0.381)
			(layers "F.Cu" "F.Mask" "F.Paste")
			(net "P5E_PEX1_STN6_TX_DN<102>")
		)
		(pad "2" smd rect
			(at 0.2667 0 90)
			(size 0.3048 0.381)
			(layers "F.Cu" "F.Mask" "F.Paste")
			(net "P5E_PEX1_STN6_TX_C_DN<102>")
		)
	)
	(footprint ""
		(layer "F.Cu")
		(at 330.859384 -61.612526)
		(property "Reference" "PD49"
			(at -3.7084 -2.733548 0)
			(unlocked yes)
			(layer "F.SilkS")
			(effects
				(font
					(size 0.7874 0.5842)
					(thickness 0.1524)
				)
				(justify left)
			)
		)
		(property "Value" ""
			(at 0 0 0)
			(layer "F.Fab")
			(effects
				(font
					(size 1.27 1.27)
				)
			)
		)
		(duplicate_pad_numbers_are_jumpers no)
		(fp_line
			(start -3.656584 -1.970024)
			(end -3.656584 1.970024)
			(stroke
				(width 0.1524)
				(type default)
			)
			(layer "F.SilkS")
		)
		(fp_line
			(start -3.656584 1.970024)
			(end 4.240784 1.970024)
			(stroke
				(width 0.1524)
				(type default)
			)
			(layer "F.SilkS")
		)
		(fp_line
			(start 4.240784 -1.970024)
			(end -3.656584 -1.970024)
			(stroke
				(width 0.1524)
				(type default)
			)
			(layer "F.SilkS")
		)
		(fp_line
			(start 4.240784 1.970024)
			(end 4.240784 -1.970024)
			(stroke
				(width 0.1524)
				(type default)
			)
			(layer "F.SilkS")
		)
		(fp_poly
			(pts
				(xy 3.580384 1.970024) (xy 3.580384 -1.970024) (xy 4.240784 -1.970024) (xy 4.240784 1.970024)
			)
			(stroke
				(width 0)
				(type default)
			)
			(fill yes)
			(layer "F.SilkS")
		)
		(fp_line
			(start -2.3749 -1.970024)
			(end -2.3749 1.970024)
			(stroke
				(width 0.1)
				(type default)
			)
			(layer "F.Fab")
		)
		(fp_line
			(start -2.3749 1.970024)
			(end 2.3749 1.970024)
			(stroke
				(width 0.1)
				(type default)
			)
			(layer "F.Fab")
		)
		(fp_line
			(start 2.3749 -1.970024)
			(end -2.3749 -1.970024)
			(stroke
				(width 0.1)
				(type default)
			)
			(layer "F.Fab")
		)
		(fp_line
			(start 2.3749 1.970024)
			(end 2.3749 -1.970024)
			(stroke
				(width 0.1)
				(type default)
			)
			(layer "F.Fab")
		)
		(fp_text user "+"
			(at -4.9784 -0.23495 0)
			(unlocked yes)
			(layer "F.Fab")
			(effects
				(font
					(size 1.905 1.4224)
					(thickness 0.1524)
				)
				(justify left)
			)
		)
		(fp_text user "-"
			(at 4.1656 -0.23495 0)
			(unlocked yes)
			(layer "F.Fab")
			(effects
				(font
					(size 1.905 1.4224)
					(thickness 0.1524)
				)
				(justify left)
			)
		)
		(pad "A" smd rect
			(at -2.450084 0)
			(size 2.159 2.2606)
			(layers "F.Cu" "F.Mask" "F.Paste")
			(net "GND")
		)
		(pad "C" smd rect
			(at 2.450084 0)
			(size 2.159 2.2606)
			(layers "F.Cu" "F.Mask" "F.Paste")
			(net "P12V_AUX")
		)
	)
	(footprint ""
		(layer "F.Cu")
		(at 121.689622 -63.56223)
		(property "Reference" "Q200"
			(at 2.617978 -1.8161 0)
			(unlocked yes)
			(layer "F.SilkS")
			(effects
				(font
					(size 0.7874 0.5842)
					(thickness 0.1524)
				)
			)
		)
		(property "Value" ""
			(at 0 0 0)
			(layer "F.Fab")
			(effects
				(font
					(size 1.27 1.27)
				)
			)
		)
		(duplicate_pad_numbers_are_jumpers no)
		(fp_line
			(start -1.376172 -1.199896)
			(end -0.508 -1.199896)
			(stroke
				(width 0.1524)
				(type default)
			)
			(layer "F.SilkS")
		)
		(fp_line
			(start -1.376172 1.199896)
			(end -1.376172 -1.199896)
			(stroke
				(width 0.1524)
				(type default)
			)
			(layer "F.SilkS")
		)
		(fp_line
			(start -0.508 -1.199896)
			(end 0 -0.762)
			(stroke
				(width 0.1524)
				(type default)
			)
			(layer "F.SilkS")
		)
		(fp_line
			(start 0 -0.762)
			(end 0.508 -1.199896)
			(stroke
				(width 0.1524)
				(type default)
			)
			(layer "F.SilkS")
		)
		(fp_line
			(start 0.508 -1.199896)
			(end 1.376172 -1.199896)
			(stroke
				(width 0.1524)
				(type default)
			)
			(layer "F.SilkS")
		)
		(fp_line
			(start 1.376172 -1.199896)
			(end 1.376172 1.199896)
			(stroke
				(width 0.1524)
				(type default)
			)
			(layer "F.SilkS")
		)
		(fp_line
			(start 1.376172 1.199896)
			(end -1.376172 1.199896)
			(stroke
				(width 0.1524)
				(type default)
			)
			(layer "F.SilkS")
		)
		(fp_poly
			(pts
				(xy -0.47117 -1.199896) (xy 0.337058 -1.469136) (xy -0.20193 -2.008124)
			)
			(stroke
				(width 0)
				(type default)
			)
			(fill yes)
			(layer "F.SilkS")
		)
		(fp_line
			(start -0.674878 -1.100074)
			(end 0.674878 -1.100074)
			(stroke
				(width 0.1)
				(type default)
			)
			(layer "F.Fab")
		)
		(fp_line
			(start -0.674878 1.100074)
			(end -0.674878 -1.100074)
			(stroke
				(width 0.1)
				(type default)
			)
			(layer "F.Fab")
		)
		(fp_line
			(start 0.674878 -1.100074)
			(end 0.674878 1.100074)
			(stroke
				(width 0.1)
				(type default)
			)
			(layer "F.Fab")
		)
		(fp_line
			(start 0.674878 1.100074)
			(end -0.674878 1.100074)
			(stroke
				(width 0.1)
				(type default)
			)
			(layer "F.Fab")
		)
		(fp_poly
			(pts
				(xy -1.4605 -0.7493) (xy -2.2225 -1.1303) (xy -2.2225 -0.3683)
			)
			(stroke
				(width 0)
				(type default)
			)
			(fill yes)
			(layer "F.Fab")
		)
		(pad "1" smd rect
			(at -0.899922 -0.750062 270)
			(size 0.6096 0.6096)
			(layers "F.Cu" "F.Mask" "F.Paste")
			(net "GND")
		)
		(pad "2" smd rect
			(at -0.899922 0 270)
			(size 0.4064 0.6096)
			(layers "F.Cu" "F.Mask" "F.Paste")
			(net "P12V_SSD4_PG_G1")
		)
		(pad "3" smd rect
			(at -0.899922 0.750062 270)
			(size 0.6096 0.6096)
			(layers "F.Cu" "F.Mask" "F.Paste")
			(net "PWRGD_P12V_SSD4_D")
		)
		(pad "4" smd rect
			(at 0.899922 0.750062 270)
			(size 0.6096 0.6096)
			(layers "F.Cu" "F.Mask" "F.Paste")
			(net "GND")
		)
		(pad "5" smd rect
			(at 0.899922 0 270)
			(size 0.4064 0.6096)
			(layers "F.Cu" "F.Mask" "F.Paste")
			(net "P12V_SSD4_PG_G2")
		)
		(pad "6" smd rect
			(at 0.899922 -0.750062 270)
			(size 0.6096 0.6096)
			(layers "F.Cu" "F.Mask" "F.Paste")
			(net "P12V_SSD4_PG_G2")
		)
	)
	(footprint ""
		(layer "F.Cu")
		(at 95.105728 -243.792248 180)
		(property "Reference" "R816"
			(at 0 0 180)
			(layer "F.SilkS")
			(hide yes)
			(effects
				(font
					(size 1.27 1.27)
				)
			)
		)
		(property "Value" ""
			(at 0 0 180)
			(layer "F.Fab")
			(effects
				(font
					(size 1.27 1.27)
				)
			)
		)
		(duplicate_pad_numbers_are_jumpers no)
		(fp_line
			(start 0.7874 0.4064)
			(end -0.7874 0.4064)
			(stroke
				(width 0.1524)
				(type default)
			)
			(layer "F.SilkS")
		)
		(fp_line
			(start 0.7874 -0.4064)
			(end 0.7874 0.4064)
			(stroke
				(width 0.1524)
				(type default)
			)
			(layer "F.SilkS")
		)
		(fp_line
			(start -0.7874 0.4064)
			(end -0.7874 -0.4064)
			(stroke
				(width 0.1524)
				(type default)
			)
			(layer "F.SilkS")
		)
		(fp_line
			(start -0.7874 -0.4064)
			(end 0.7874 -0.4064)
			(stroke
				(width 0.1524)
				(type default)
			)
			(layer "F.SilkS")
		)
		(fp_line
			(start 0.67945 0.3048)
			(end 0.120396 0.3048)
			(stroke
				(width 0.1)
				(type default)
			)
			(layer "F.Fab")
		)
		(fp_line
			(start 0.67945 -0.3048)
			(end 0.67945 0.3048)
			(stroke
				(width 0.1)
				(type default)
			)
			(layer "F.Fab")
		)
		(fp_line
			(start 0.12065 -0.2794)
			(end 0.12065 -0.3048)
			(stroke
				(width 0.1)
				(type default)
			)
			(layer "F.Fab")
		)
		(fp_line
			(start 0.12065 -0.3048)
			(end 0.67945 -0.3048)
			(stroke
				(width 0.1)
				(type default)
			)
			(layer "F.Fab")
		)
		(fp_line
			(start 0.120396 0.3048)
			(end 0.120396 0.2794)
			(stroke
				(width 0.1)
				(type default)
			)
			(layer "F.Fab")
		)
		(fp_line
			(start 0.120396 0.2794)
			(end -0.12065 0.2794)
			(stroke
				(width 0.1)
				(type default)
			)
			(layer "F.Fab")
		)
		(fp_line
			(start -0.12065 0.3048)
			(end -0.67945 0.3048)
			(stroke
				(width 0.1)
				(type default)
			)
			(layer "F.Fab")
		)
		(fp_line
			(start -0.12065 0.2794)
			(end -0.12065 0.3048)
			(stroke
				(width 0.1)
				(type default)
			)
			(layer "F.Fab")
		)
		(fp_line
			(start -0.12065 -0.2794)
			(end 0.12065 -0.2794)
			(stroke
				(width 0.1)
				(type default)
			)
			(layer "F.Fab")
		)
		(fp_line
			(start -0.12065 -0.305054)
			(end -0.12065 -0.2794)
			(stroke
				(width 0.1)
				(type default)
			)
			(layer "F.Fab")
		)
		(fp_line
			(start -0.67945 0.3048)
			(end -0.67945 -0.305054)
			(stroke
				(width 0.1)
				(type default)
			)
			(layer "F.Fab")
		)
		(fp_line
			(start -0.67945 -0.305054)
			(end -0.12065 -0.305054)
			(stroke
				(width 0.1)
				(type default)
			)
			(layer "F.Fab")
		)
		(pad "1" smd circle
			(at -0.40005 0 180)
			(size 0 0)
			(layers "F.Cu" "F.Mask" "F.Paste")
			(net "PEX_P1V8_ADC_A0")
		)
		(pad "2" smd circle
			(at 0.40005 0 180)
			(size 0 0)
			(layers "F.Cu" "F.Mask" "F.Paste")
			(net "GND")
		)
	)
	(footprint ""
		(layer "F.Cu")
		(at 15.887446 -211.737956 180)
		(property "Reference" "U430"
			(at -4.162806 0.952246 0)
			(unlocked yes)
			(layer "F.SilkS")
			(effects
				(font
					(size 0.7874 0.5842)
					(thickness 0.1524)
				)
				(justify left)
			)
		)
		(property "Value" ""
			(at 0 0 180)
			(layer "F.Fab")
			(effects
				(font
					(size 1.27 1.27)
				)
			)
		)
		(duplicate_pad_numbers_are_jumpers no)
		(fp_line
			(start 1.525016 1.525016)
			(end 1.525016 1.3208)
			(stroke
				(width 0.1524)
				(type default)
			)
			(layer "F.SilkS")
		)
		(fp_line
			(start 1.525016 1.525016)
			(end -1.525016 1.525016)
			(stroke
				(width 0.1524)
				(type default)
			)
			(layer "F.SilkS")
		)
		(fp_line
			(start 1.525016 -1.3208)
			(end 1.525016 -1.525016)
			(stroke
				(width 0.1524)
				(type default)
			)
			(layer "F.SilkS")
		)
		(fp_line
			(start 1.525016 -1.525016)
			(end 0.9398 -1.525016)
			(stroke
				(width 0.1524)
				(type default)
			)
			(layer "F.SilkS")
		)
		(fp_line
			(start 1.525016 -1.525016)
			(end -1.525016 -1.525016)
			(stroke
				(width 0.1524)
				(type default)
			)
			(layer "F.SilkS")
		)
		(fp_line
			(start 0.9906 1.525016)
			(end 1.525016 1.525016)
			(stroke
				(width 0.1524)
				(type default)
			)
			(layer "F.SilkS")
		)
		(fp_line
			(start -0.8636 -1.525016)
			(end -1.525016 -1.525016)
			(stroke
				(width 0.1524)
				(type default)
			)
			(layer "F.SilkS")
		)
		(fp_line
			(start -1.525016 1.525016)
			(end -0.889 1.525016)
			(stroke
				(width 0.1524)
				(type default)
			)
			(layer "F.SilkS")
		)
		(fp_line
			(start -1.525016 1.3208)
			(end -1.525016 1.525016)
			(stroke
				(width 0.1524)
				(type default)
			)
			(layer "F.SilkS")
		)
		(fp_line
			(start -1.525016 -1.525016)
			(end -1.525016 -1.3208)
			(stroke
				(width 0.1524)
				(type default)
			)
			(layer "F.SilkS")
		)
		(fp_poly
			(pts
				(xy -2.234438 -1.001268) (xy -1.934464 -1.901444) (xy -2.534412 -1.901444)
			)
			(stroke
				(width 0)
				(type default)
			)
			(fill yes)
			(layer "F.SilkS")
		)
		(fp_line
			(start 1.525016 1.525016)
			(end -1.525016 1.525016)
			(stroke
				(width 0.1)
				(type default)
			)
			(layer "F.Fab")
		)
		(fp_line
			(start 1.525016 -1.525016)
			(end 1.525016 1.525016)
			(stroke
				(width 0.1)
				(type default)
			)
			(layer "F.Fab")
		)
		(fp_line
			(start -1.525016 1.525016)
			(end -1.525016 -1.525016)
			(stroke
				(width 0.1)
				(type default)
			)
			(layer "F.Fab")
		)
		(fp_line
			(start -1.525016 -1.525016)
			(end 1.525016 -1.525016)
			(stroke
				(width 0.1)
				(type default)
			)
			(layer "F.Fab")
		)
		(fp_poly
			(pts
				(xy -2.0701 -0.999998) (xy -2.977896 -1.302512) (xy -2.977896 -0.697484)
			)
			(stroke
				(width 0)
				(type default)
			)
			(fill yes)
			(layer "F.Fab")
		)
		(pad "1" smd rect
			(at -1.550162 -0.999998 90)
			(size 0.2794 0.9144)
			(layers "F.Cu" "F.Mask" "F.Paste")
			(net "P1V8_PLL0_PEX0")
		)
		(pad "2" smd rect
			(at -1.550162 -0.500126 90)
			(size 0.2794 0.9144)
			(layers "F.Cu" "F.Mask" "F.Paste")
			(net "P1V8_PLL0_PEX0")
		)
		(pad "3" smd rect
			(at -1.550162 0 90)
			(size 0.2794 0.9144)
			(layers "F.Cu" "F.Mask" "F.Paste")
			(net "P1V8_PLL0_PEX0")
		)
		(pad "4" smd rect
			(at -1.550162 0.500126 90)
			(size 0.2794 0.9144)
			(layers "F.Cu" "F.Mask" "F.Paste")
			(net "P1V8_PLL_PEX0_ADJ")
		)
		(pad "5" smd rect
			(at -1.550162 0.999998 270)
			(size 0.2794 0.9144)
			(layers "F.Cu" "F.Mask" "F.Paste")
			(net "PWRGD_PEX0_P1V8_PLL")
		)
		(pad "6" smd rect
			(at 1.550162 0.999998 270)
			(size 0.2794 0.9144)
			(layers "F.Cu" "F.Mask" "F.Paste")
			(net "PEX0_P1V8_PLL_EN")
		)
		(pad "7" smd rect
			(at 1.550162 0.500126 90)
			(size 0.2794 0.9144)
			(layers "F.Cu" "F.Mask" "F.Paste")
			(net "P3V3_AUX")
		)
		(pad "8" smd rect
			(at 1.550162 0 90)
			(size 0.2794 0.9144)
			(layers "F.Cu" "F.Mask" "F.Paste")
			(net "P3V3_AUX")
		)
		(pad "9" smd rect
			(at 1.550162 -0.500126 90)
			(size 0.2794 0.9144)
			(layers "F.Cu" "F.Mask" "F.Paste")
			(net "P3V3_AUX")
		)
		(pad "10" smd rect
			(at 1.550162 -0.999998 90)
			(size 0.2794 0.9144)
			(layers "F.Cu" "F.Mask" "F.Paste")
			(net "P5V_AUX")
		)
		(pad "TH" smd rect
			(at 0 0 180)
			(size 1.7526 2.667)
			(layers "F.Cu" "F.Mask" "F.Paste")
			(net "GND")
		)
		(zone
			(layer "F.Cu")
			(hatch none 0.5)
			(connect_pads
				(clearance 0)
			)
			(min_thickness 0.25)
			(keepout
				(tracks not_allowed)
				(vias allowed)
				(pads allowed)
				(copperpour not_allowed)
				(footprints allowed)
			)
			(placement
				(enabled no)
				(sheetname "")
			)
			(fill
				(thermal_gap 0.5)
				(thermal_bridge_width 0.5)
				(island_removal_mode 0)
			)
			(polygon
				(pts
					(xy 16.904208 -210.204558) (xy 16.904208 -213.252558) (xy 14.872208 -213.252558) (xy 14.872208 -210.204558)
					(xy 16.802608 -210.204558) (xy 16.802608 -210.331558) (xy 14.948408 -210.331558) (xy 14.948408 -213.150958)
					(xy 16.828008 -213.150958) (xy 16.828008 -210.204558)
				)
			)
		)
	)
	(footprint ""
		(layer "F.Cu")
		(at 215.784176 -369.000786 90)
		(property "Reference" "PC10"
			(at 0 0 90)
			(layer "F.SilkS")
			(hide yes)
			(effects
				(font
					(size 1.27 1.27)
				)
			)
		)
		(property "Value" ""
			(at 0 0 90)
			(layer "F.Fab")
			(effects
				(font
					(size 1.27 1.27)
				)
			)
		)
		(duplicate_pad_numbers_are_jumpers no)
		(fp_line
			(start 0.7874 -0.4064)
			(end 0.7874 0.4064)
			(stroke
				(width 0.1524)
				(type default)
			)
			(layer "F.SilkS")
		)
		(fp_line
			(start -0.7874 -0.4064)
			(end 0.7874 -0.4064)
			(stroke
				(width 0.1524)
				(type default)
			)
			(layer "F.SilkS")
		)
		(fp_line
			(start 0.7874 0.4064)
			(end -0.7874 0.4064)
			(stroke
				(width 0.1524)
				(type default)
			)
			(layer "F.SilkS")
		)
		(fp_line
			(start -0.7874 0.4064)
			(end -0.7874 -0.4064)
			(stroke
				(width 0.1524)
				(type default)
			)
			(layer "F.SilkS")
		)
		(fp_line
			(start -0.12065 -0.305054)
			(end -0.12065 -0.2794)
			(stroke
				(width 0.1)
				(type default)
			)
			(layer "F.Fab")
		)
		(fp_line
			(start -0.67945 -0.305054)
			(end -0.12065 -0.305054)
			(stroke
				(width 0.1)
				(type default)
			)
			(layer "F.Fab")
		)
		(fp_line
			(start 0.67945 -0.3048)
			(end 0.67945 0.3048)
			(stroke
				(width 0.1)
				(type default)
			)
			(layer "F.Fab")
		)
		(fp_line
			(start 0.12065 -0.3048)
			(end 0.67945 -0.3048)
			(stroke
				(width 0.1)
				(type default)
			)
			(layer "F.Fab")
		)
		(fp_line
			(start 0.12065 -0.2794)
			(end 0.12065 -0.3048)
			(stroke
				(width 0.1)
				(type default)
			)
			(layer "F.Fab")
		)
		(fp_line
			(start -0.12065 -0.2794)
			(end 0.12065 -0.2794)
			(stroke
				(width 0.1)
				(type default)
			)
			(layer "F.Fab")
		)
		(fp_line
			(start 0.120396 0.2794)
			(end -0.12065 0.2794)
			(stroke
				(width 0.1)
				(type default)
			)
			(layer "F.Fab")
		)
		(fp_line
			(start -0.12065 0.2794)
			(end -0.12065 0.3048)
			(stroke
				(width 0.1)
				(type default)
			)
			(layer "F.Fab")
		)
		(fp_line
			(start 0.67945 0.3048)
			(end 0.120396 0.3048)
			(stroke
				(width 0.1)
				(type default)
			)
			(layer "F.Fab")
		)
		(fp_line
			(start 0.120396 0.3048)
			(end 0.120396 0.2794)
			(stroke
				(width 0.1)
				(type default)
			)
			(layer "F.Fab")
		)
		(fp_line
			(start -0.12065 0.3048)
			(end -0.67945 0.3048)
			(stroke
				(width 0.1)
				(type default)
			)
			(layer "F.Fab")
		)
		(fp_line
			(start -0.67945 0.3048)
			(end -0.67945 -0.305054)
			(stroke
				(width 0.1)
				(type default)
			)
			(layer "F.Fab")
		)
		(pad "1" smd circle
			(at -0.40005 0 90)
			(size 0 0)
			(layers "F.Cu" "F.Mask" "F.Paste")
			(net "HSC_VDD_1")
		)
		(pad "2" smd circle
			(at 0.40005 0 90)
			(size 0 0)
			(layers "F.Cu" "F.Mask" "F.Paste")
			(net "AGND_HSC")
		)
	)
	(footprint ""
		(layer "F.Cu")
		(at 460.611982 -110.515654)
		(property "Reference" "PC836"
			(at 0 0 0)
			(layer "F.SilkS")
			(hide yes)
			(effects
				(font
					(size 1.27 1.27)
				)
			)
		)
		(property "Value" ""
			(at 0 0 0)
			(layer "F.Fab")
			(effects
				(font
					(size 1.27 1.27)
				)
			)
		)
		(duplicate_pad_numbers_are_jumpers no)
		(fp_line
			(start -0.7874 -0.4064)
			(end 0.7874 -0.4064)
			(stroke
				(width 0.1524)
				(type default)
			)
			(layer "F.SilkS")
		)
		(fp_line
			(start -0.7874 0.4064)
			(end -0.7874 -0.4064)
			(stroke
				(width 0.1524)
				(type default)
			)
			(layer "F.SilkS")
		)
		(fp_line
			(start 0.7874 -0.4064)
			(end 0.7874 0.4064)
			(stroke
				(width 0.1524)
				(type default)
			)
			(layer "F.SilkS")
		)
		(fp_line
			(start 0.7874 0.4064)
			(end -0.7874 0.4064)
			(stroke
				(width 0.1524)
				(type default)
			)
			(layer "F.SilkS")
		)
		(fp_line
			(start -0.67945 -0.305054)
			(end -0.12065 -0.305054)
			(stroke
				(width 0.1)
				(type default)
			)
			(layer "F.Fab")
		)
		(fp_line
			(start -0.67945 0.3048)
			(end -0.67945 -0.305054)
			(stroke
				(width 0.1)
				(type default)
			)
			(layer "F.Fab")
		)
		(fp_line
			(start -0.12065 -0.305054)
			(end -0.12065 -0.2794)
			(stroke
				(width 0.1)
				(type default)
			)
			(layer "F.Fab")
		)
		(fp_line
			(start -0.12065 -0.2794)
			(end 0.12065 -0.2794)
			(stroke
				(width 0.1)
				(type default)
			)
			(layer "F.Fab")
		)
		(fp_line
			(start -0.12065 0.2794)
			(end -0.12065 0.3048)
			(stroke
				(width 0.1)
				(type default)
			)
			(layer "F.Fab")
		)
		(fp_line
			(start -0.12065 0.3048)
			(end -0.67945 0.3048)
			(stroke
				(width 0.1)
				(type default)
			)
			(layer "F.Fab")
		)
		(fp_line
			(start 0.120396 0.2794)
			(end -0.12065 0.2794)
			(stroke
				(width 0.1)
				(type default)
			)
			(layer "F.Fab")
		)
		(fp_line
			(start 0.120396 0.3048)
			(end 0.120396 0.2794)
			(stroke
				(width 0.1)
				(type default)
			)
			(layer "F.Fab")
		)
		(fp_line
			(start 0.12065 -0.3048)
			(end 0.67945 -0.3048)
			(stroke
				(width 0.1)
				(type default)
			)
			(layer "F.Fab")
		)
		(fp_line
			(start 0.12065 -0.2794)
			(end 0.12065 -0.3048)
			(stroke
				(width 0.1)
				(type default)
			)
			(layer "F.Fab")
		)
		(fp_line
			(start 0.67945 -0.3048)
			(end 0.67945 0.3048)
			(stroke
				(width 0.1)
				(type default)
			)
			(layer "F.Fab")
		)
		(fp_line
			(start 0.67945 0.3048)
			(end 0.120396 0.3048)
			(stroke
				(width 0.1)
				(type default)
			)
			(layer "F.Fab")
		)
		(pad "1" smd circle
			(at -0.40005 0)
			(size 0 0)
			(layers "F.Cu" "F.Mask" "F.Paste")
			(net "P12V_NIC7_CO_TIMER")
		)
		(pad "2" smd circle
			(at 0.40005 0)
			(size 0 0)
			(layers "F.Cu" "F.Mask" "F.Paste")
			(net "GND")
		)
	)
	(footprint ""
		(layer "F.Cu")
		(at 346.075 -146.177)
		(property "Reference" "U350"
			(at -1.4478 -4.613148 0)
			(unlocked yes)
			(layer "F.SilkS")
			(effects
				(font
					(size 0.7874 0.5842)
					(thickness 0.1524)
				)
				(justify left)
			)
		)
		(property "Value" ""
			(at 0 0 0)
			(layer "F.Fab")
			(effects
				(font
					(size 1.27 1.27)
				)
			)
		)
		(duplicate_pad_numbers_are_jumpers no)
		(fp_line
			(start -2.097532 -3.949954)
			(end -2.097532 3.949954)
			(stroke
				(width 0.1524)
				(type default)
			)
			(layer "F.SilkS")
		)
		(fp_line
			(start -2.097532 3.949954)
			(end 2.097532 3.949954)
			(stroke
				(width 0.1524)
				(type default)
			)
			(layer "F.SilkS")
		)
		(fp_line
			(start -1.409954 -3.949954)
			(end -2.097532 -3.949954)
			(stroke
				(width 0.1524)
				(type default)
			)
			(layer "F.SilkS")
		)
		(fp_line
			(start 0 -2.54)
			(end -1.409954 -3.949954)
			(stroke
				(width 0.1524)
				(type default)
			)
			(layer "F.SilkS")
		)
		(fp_line
			(start 1.409954 -3.949954)
			(end 0 -2.54)
			(stroke
				(width 0.1524)
				(type default)
			)
			(layer "F.SilkS")
		)
		(fp_line
			(start 2.097532 -3.949954)
			(end 1.409954 -3.949954)
			(stroke
				(width 0.1524)
				(type default)
			)
			(layer "F.SilkS")
		)
		(fp_line
			(start 2.097532 3.949954)
			(end 2.097532 -3.949954)
			(stroke
				(width 0.1524)
				(type default)
			)
			(layer "F.SilkS")
		)
		(fp_poly
			(pts
				(xy -4.7498 -4.182872) (xy -4.7498 -3.166872) (xy -3.7338 -3.674872)
			)
			(stroke
				(width 0)
				(type default)
			)
			(fill yes)
			(layer "F.SilkS")
		)
		(fp_line
			(start -2.249932 -3.949954)
			(end -2.249932 3.949954)
			(stroke
				(width 0.1)
				(type default)
			)
			(layer "F.Fab")
		)
		(fp_line
			(start -2.249932 3.949954)
			(end 2.249932 3.949954)
			(stroke
				(width 0.1)
				(type default)
			)
			(layer "F.Fab")
		)
		(fp_line
			(start 2.249932 -3.949954)
			(end -2.249932 -3.949954)
			(stroke
				(width 0.1)
				(type default)
			)
			(layer "F.Fab")
		)
		(fp_line
			(start 2.249932 3.949954)
			(end 2.249932 -3.949954)
			(stroke
				(width 0.1)
				(type default)
			)
			(layer "F.Fab")
		)
		(fp_poly
			(pts
				(xy -4.7498 -4.182872) (xy -4.7498 -3.166872) (xy -3.7338 -3.674872)
			)
			(stroke
				(width 0)
				(type default)
			)
			(fill yes)
			(layer "F.Fab")
		)
		(pad "1" smd rect
			(at -2.925064 -3.674872 270)
			(size 0.6096 1.3716)
			(layers "F.Cu" "F.Mask" "F.Paste")
			(net "PEX3_PCA9555_1_INT_N")
		)
		(pad "2" smd rect
			(at -2.925064 -2.925064 270)
			(size 0.4064 1.3716)
			(layers "F.Cu" "F.Mask" "F.Paste")
			(net "PCA9555_1_PEX3_A1")
		)
		(pad "3" smd rect
			(at -2.925064 -2.275078 270)
			(size 0.4064 1.3716)
			(layers "F.Cu" "F.Mask" "F.Paste")
			(net "PCA9555_1_PEX3_A2")
		)
		(pad "4" smd rect
			(at -2.925064 -1.625092 270)
			(size 0.4064 1.3716)
			(layers "F.Cu" "F.Mask" "F.Paste")
			(net "PRSNT_SSD14_FPGA_PCA9555_N")
		)
		(pad "5" smd rect
			(at -2.925064 -0.975106 270)
			(size 0.4064 1.3716)
			(layers "F.Cu" "F.Mask" "F.Paste")
			(net "SSD14_PEX_PWR_EN")
		)
		(pad "6" smd rect
			(at -2.925064 -0.32512 270)
			(size 0.4064 1.3716)
			(layers "F.Cu" "F.Mask" "F.Paste")
			(net "RST_PEX_SSD14_PERST_N")
		)
		(pad "7" smd rect
			(at -2.925064 0.32512 270)
			(size 0.4064 1.3716)
			(layers "F.Cu" "F.Mask" "F.Paste")
			(net "Net_1191")
		)
		(pad "8" smd rect
			(at -2.925064 0.975106 270)
			(size 0.4064 1.3716)
			(layers "F.Cu" "F.Mask" "F.Paste")
			(net "PRSNT_SSD15_FPGA_PCA9555_N")
		)
		(pad "9" smd rect
			(at -2.925064 1.625092 270)
			(size 0.4064 1.3716)
			(layers "F.Cu" "F.Mask" "F.Paste")
			(net "SSD15_PEX_PWR_EN")
		)
		(pad "10" smd rect
			(at -2.925064 2.275078 270)
			(size 0.4064 1.3716)
			(layers "F.Cu" "F.Mask" "F.Paste")
			(net "RST_PEX_SSD15_PERST_N")
		)
		(pad "11" smd rect
			(at -2.925064 2.925064 270)
			(size 0.4064 1.3716)
			(layers "F.Cu" "F.Mask" "F.Paste")
			(net "Net_1189")
		)
		(pad "12" smd rect
			(at -2.925064 3.674872 270)
			(size 0.6096 1.3716)
			(layers "F.Cu" "F.Mask" "F.Paste")
			(net "GND")
		)
		(pad "13" smd rect
			(at 2.925064 3.674872 270)
			(size 0.6096 1.3716)
			(layers "F.Cu" "F.Mask" "F.Paste")
			(net "PRSNT_NIC7_FPGA_PCA9555_N")
		)
		(pad "14" smd rect
			(at 2.925064 2.925064 270)
			(size 0.4064 1.3716)
			(layers "F.Cu" "F.Mask" "F.Paste")
			(net "NIC7_PEX_PWR_EN")
		)
		(pad "15" smd rect
			(at 2.925064 2.275078 270)
			(size 0.4064 1.3716)
			(layers "F.Cu" "F.Mask" "F.Paste")
			(net "RST_PEX_NIC7_PERST_N")
		)
		(pad "16" smd rect
			(at 2.925064 1.625092 270)
			(size 0.4064 1.3716)
			(layers "F.Cu" "F.Mask" "F.Paste")
			(net "Net_1190")
		)
		(pad "17" smd rect
			(at 2.925064 0.975106 270)
			(size 0.4064 1.3716)
			(layers "F.Cu" "F.Mask" "F.Paste")
			(net "Net_8964")
		)
		(pad "18" smd rect
			(at 2.925064 0.32512 270)
			(size 0.4064 1.3716)
			(layers "F.Cu" "F.Mask" "F.Paste")
			(net "Net_8963")
		)
		(pad "19" smd rect
			(at 2.925064 -0.32512 270)
			(size 0.4064 1.3716)
			(layers "F.Cu" "F.Mask" "F.Paste")
			(net "Net_8962")
		)
		(pad "20" smd rect
			(at 2.925064 -0.975106 270)
			(size 0.4064 1.3716)
			(layers "F.Cu" "F.Mask" "F.Paste")
			(net "Net_8961")
		)
		(pad "21" smd rect
			(at 2.925064 -1.625092 270)
			(size 0.4064 1.3716)
			(layers "F.Cu" "F.Mask" "F.Paste")
			(net "PCA9555_1_PEX3_A0")
		)
		(pad "22" smd rect
			(at 2.925064 -2.275078 270)
			(size 0.4064 1.3716)
			(layers "F.Cu" "F.Mask" "F.Paste")
			(net "SMB_PEX3_PCA9555_SCL")
		)
		(pad "23" smd rect
			(at 2.925064 -2.925064 270)
			(size 0.4064 1.3716)
			(layers "F.Cu" "F.Mask" "F.Paste")
			(net "SMB_PEX3_PCA9555_SDA")
		)
		(pad "24" smd rect
			(at 2.925064 -3.674872 270)
			(size 0.6096 1.3716)
			(layers "F.Cu" "F.Mask" "F.Paste")
			(net "P3V3_AUX")
		)
	)
	(footprint ""
		(layer "F.Cu")
		(at 160.73882 -22.867366 90)
		(property "Reference" "C3910"
			(at 0 0 90)
			(layer "F.SilkS")
			(hide yes)
			(effects
				(font
					(size 1.27 1.27)
				)
			)
		)
		(property "Value" ""
			(at 0 0 90)
			(layer "F.Fab")
			(effects
				(font
					(size 1.27 1.27)
				)
			)
		)
		(duplicate_pad_numbers_are_jumpers no)
		(fp_line
			(start 0.7874 -0.4064)
			(end 0.7874 0.4064)
			(stroke
				(width 0.1524)
				(type default)
			)
			(layer "F.SilkS")
		)
		(fp_line
			(start -0.7874 -0.4064)
			(end 0.7874 -0.4064)
			(stroke
				(width 0.1524)
				(type default)
			)
			(layer "F.SilkS")
		)
		(fp_line
			(start 0.7874 0.4064)
			(end -0.7874 0.4064)
			(stroke
				(width 0.1524)
				(type default)
			)
			(layer "F.SilkS")
		)
		(fp_line
			(start -0.7874 0.4064)
			(end -0.7874 -0.4064)
			(stroke
				(width 0.1524)
				(type default)
			)
			(layer "F.SilkS")
		)
		(fp_line
			(start -0.12065 -0.305054)
			(end -0.12065 -0.2794)
			(stroke
				(width 0.1)
				(type default)
			)
			(layer "F.Fab")
		)
		(fp_line
			(start -0.67945 -0.305054)
			(end -0.12065 -0.305054)
			(stroke
				(width 0.1)
				(type default)
			)
			(layer "F.Fab")
		)
		(fp_line
			(start 0.67945 -0.3048)
			(end 0.67945 0.3048)
			(stroke
				(width 0.1)
				(type default)
			)
			(layer "F.Fab")
		)
		(fp_line
			(start 0.12065 -0.3048)
			(end 0.67945 -0.3048)
			(stroke
				(width 0.1)
				(type default)
			)
			(layer "F.Fab")
		)
		(fp_line
			(start 0.12065 -0.2794)
			(end 0.12065 -0.3048)
			(stroke
				(width 0.1)
				(type default)
			)
			(layer "F.Fab")
		)
		(fp_line
			(start -0.12065 -0.2794)
			(end 0.12065 -0.2794)
			(stroke
				(width 0.1)
				(type default)
			)
			(layer "F.Fab")
		)
		(fp_line
			(start 0.120396 0.2794)
			(end -0.12065 0.2794)
			(stroke
				(width 0.1)
				(type default)
			)
			(layer "F.Fab")
		)
		(fp_line
			(start -0.12065 0.2794)
			(end -0.12065 0.3048)
			(stroke
				(width 0.1)
				(type default)
			)
			(layer "F.Fab")
		)
		(fp_line
			(start 0.67945 0.3048)
			(end 0.120396 0.3048)
			(stroke
				(width 0.1)
				(type default)
			)
			(layer "F.Fab")
		)
		(fp_line
			(start 0.120396 0.3048)
			(end 0.120396 0.2794)
			(stroke
				(width 0.1)
				(type default)
			)
			(layer "F.Fab")
		)
		(fp_line
			(start -0.12065 0.3048)
			(end -0.67945 0.3048)
			(stroke
				(width 0.1)
				(type default)
			)
			(layer "F.Fab")
		)
		(fp_line
			(start -0.67945 0.3048)
			(end -0.67945 -0.305054)
			(stroke
				(width 0.1)
				(type default)
			)
			(layer "F.Fab")
		)
		(pad "1" smd circle
			(at -0.40005 0 90)
			(size 0 0)
			(layers "F.Cu" "F.Mask" "F.Paste")
			(net "P12V_SSD5")
		)
		(pad "2" smd circle
			(at 0.40005 0 90)
			(size 0 0)
			(layers "F.Cu" "F.Mask" "F.Paste")
			(net "GND")
		)
	)
	(footprint ""
		(layer "F.Cu")
		(at 38.608 -153.3144 180)
		(property "Reference" "R25"
			(at 0 0 180)
			(layer "F.SilkS")
			(hide yes)
			(effects
				(font
					(size 1.27 1.27)
				)
			)
		)
		(property "Value" ""
			(at 0 0 180)
			(layer "F.Fab")
			(effects
				(font
					(size 1.27 1.27)
				)
			)
		)
		(duplicate_pad_numbers_are_jumpers no)
		(fp_line
			(start 0.7874 0.4064)
			(end -0.7874 0.4064)
			(stroke
				(width 0.1524)
				(type default)
			)
			(layer "F.SilkS")
		)
		(fp_line
			(start 0.7874 -0.4064)
			(end 0.7874 0.4064)
			(stroke
				(width 0.1524)
				(type default)
			)
			(layer "F.SilkS")
		)
		(fp_line
			(start -0.7874 0.4064)
			(end -0.7874 -0.4064)
			(stroke
				(width 0.1524)
				(type default)
			)
			(layer "F.SilkS")
		)
		(fp_line
			(start -0.7874 -0.4064)
			(end 0.7874 -0.4064)
			(stroke
				(width 0.1524)
				(type default)
			)
			(layer "F.SilkS")
		)
		(fp_line
			(start 0.67945 0.3048)
			(end 0.120396 0.3048)
			(stroke
				(width 0.1)
				(type default)
			)
			(layer "F.Fab")
		)
		(fp_line
			(start 0.67945 -0.3048)
			(end 0.67945 0.3048)
			(stroke
				(width 0.1)
				(type default)
			)
			(layer "F.Fab")
		)
		(fp_line
			(start 0.12065 -0.2794)
			(end 0.12065 -0.3048)
			(stroke
				(width 0.1)
				(type default)
			)
			(layer "F.Fab")
		)
		(fp_line
			(start 0.12065 -0.3048)
			(end 0.67945 -0.3048)
			(stroke
				(width 0.1)
				(type default)
			)
			(layer "F.Fab")
		)
		(fp_line
			(start 0.120396 0.3048)
			(end 0.120396 0.2794)
			(stroke
				(width 0.1)
				(type default)
			)
			(layer "F.Fab")
		)
		(fp_line
			(start 0.120396 0.2794)
			(end -0.12065 0.2794)
			(stroke
				(width 0.1)
				(type default)
			)
			(layer "F.Fab")
		)
		(fp_line
			(start -0.12065 0.3048)
			(end -0.67945 0.3048)
			(stroke
				(width 0.1)
				(type default)
			)
			(layer "F.Fab")
		)
		(fp_line
			(start -0.12065 0.2794)
			(end -0.12065 0.3048)
			(stroke
				(width 0.1)
				(type default)
			)
			(layer "F.Fab")
		)
		(fp_line
			(start -0.12065 -0.2794)
			(end 0.12065 -0.2794)
			(stroke
				(width 0.1)
				(type default)
			)
			(layer "F.Fab")
		)
		(fp_line
			(start -0.12065 -0.305054)
			(end -0.12065 -0.2794)
			(stroke
				(width 0.1)
				(type default)
			)
			(layer "F.Fab")
		)
		(fp_line
			(start -0.67945 0.3048)
			(end -0.67945 -0.305054)
			(stroke
				(width 0.1)
				(type default)
			)
			(layer "F.Fab")
		)
		(fp_line
			(start -0.67945 -0.305054)
			(end -0.12065 -0.305054)
			(stroke
				(width 0.1)
				(type default)
			)
			(layer "F.Fab")
		)
		(pad "1" smd circle
			(at -0.40005 0 180)
			(size 0 0)
			(layers "F.Cu" "F.Mask" "F.Paste")
			(net "NIC0_SLOT_ID0")
		)
		(pad "2" smd circle
			(at 0.40005 0 180)
			(size 0 0)
			(layers "F.Cu" "F.Mask" "F.Paste")
			(net "P3V3_NIC0")
		)
	)
	(footprint ""
		(layer "F.Cu")
		(at 33.287716 -298.020232)
		(property "Reference" "C3021"
			(at 0 0 0)
			(layer "F.SilkS")
			(hide yes)
			(effects
				(font
					(size 1.27 1.27)
				)
			)
		)
		(property "Value" ""
			(at 0 0 0)
			(layer "F.Fab")
			(effects
				(font
					(size 1.27 1.27)
				)
			)
		)
		(duplicate_pad_numbers_are_jumpers no)
		(fp_line
			(start -1.2954 -0.5842)
			(end 1.2954 -0.5842)
			(stroke
				(width 0.1524)
				(type default)
			)
			(layer "F.SilkS")
		)
		(fp_line
			(start -1.2954 0.5842)
			(end -1.2954 -0.5842)
			(stroke
				(width 0.1524)
				(type default)
			)
			(layer "F.SilkS")
		)
		(fp_line
			(start 1.2954 -0.5842)
			(end 1.2954 0.5842)
			(stroke
				(width 0.1524)
				(type default)
			)
			(layer "F.SilkS")
		)
		(fp_line
			(start 1.2954 0.5842)
			(end -1.2954 0.5842)
			(stroke
				(width 0.1524)
				(type default)
			)
			(layer "F.SilkS")
		)
		(fp_line
			(start -1.1938 -0.4064)
			(end -0.8636 -0.4064)
			(stroke
				(width 0.1)
				(type default)
			)
			(layer "F.Fab")
		)
		(fp_line
			(start -1.1938 0.4064)
			(end -1.1938 -0.4064)
			(stroke
				(width 0.1)
				(type default)
			)
			(layer "F.Fab")
		)
		(fp_line
			(start -0.8636 -0.4572)
			(end 0.8636 -0.4572)
			(stroke
				(width 0.1)
				(type default)
			)
			(layer "F.Fab")
		)
		(fp_line
			(start -0.8636 -0.4064)
			(end -0.8636 -0.4572)
			(stroke
				(width 0.1)
				(type default)
			)
			(layer "F.Fab")
		)
		(fp_line
			(start -0.8636 0.4064)
			(end -1.1938 0.4064)
			(stroke
				(width 0.1)
				(type default)
			)
			(layer "F.Fab")
		)
		(fp_line
			(start -0.8636 0.4572)
			(end -0.8636 0.4064)
			(stroke
				(width 0.1)
				(type default)
			)
			(layer "F.Fab")
		)
		(fp_line
			(start 0.8636 -0.4572)
			(end 0.8636 -0.4064)
			(stroke
				(width 0.1)
				(type default)
			)
			(layer "F.Fab")
		)
		(fp_line
			(start 0.8636 -0.4064)
			(end 1.1938 -0.4064)
			(stroke
				(width 0.1)
				(type default)
			)
			(layer "F.Fab")
		)
		(fp_line
			(start 0.8636 0.4064)
			(end 0.8636 0.4572)
			(stroke
				(width 0.1)
				(type default)
			)
			(layer "F.Fab")
		)
		(fp_line
			(start 0.8636 0.4572)
			(end -0.8636 0.4572)
			(stroke
				(width 0.1)
				(type default)
			)
			(layer "F.Fab")
		)
		(fp_line
			(start 1.1938 -0.4064)
			(end 1.1938 0.4064)
			(stroke
				(width 0.1)
				(type default)
			)
			(layer "F.Fab")
		)
		(fp_line
			(start 1.1938 0.4064)
			(end 0.8636 0.4064)
			(stroke
				(width 0.1)
				(type default)
			)
			(layer "F.Fab")
		)
		(pad "1" smd rect
			(at -0.7366 0 270)
			(size 0.7112 0.8128)
			(layers "F.Cu" "F.Mask" "F.Paste")
			(net "PCEPLL0_VDDA18_PEX0")
		)
		(pad "2" smd rect
			(at 0.7366 0 270)
			(size 0.7112 0.8128)
			(layers "F.Cu" "F.Mask" "F.Paste")
			(net "GND")
		)
	)
	(footprint ""
		(layer "F.Cu")
		(at 239.460278 -65.072006 -90)
		(property "Reference" "R5996"
			(at 0 0 270)
			(layer "F.SilkS")
			(hide yes)
			(effects
				(font
					(size 1.27 1.27)
				)
			)
		)
		(property "Value" ""
			(at 0 0 270)
			(layer "F.Fab")
			(effects
				(font
					(size 1.27 1.27)
				)
			)
		)
		(duplicate_pad_numbers_are_jumpers no)
		(fp_line
			(start -0.7874 0.4064)
			(end -0.7874 -0.4064)
			(stroke
				(width 0.1524)
				(type default)
			)
			(layer "F.SilkS")
		)
		(fp_line
			(start 0.7874 0.4064)
			(end -0.7874 0.4064)
			(stroke
				(width 0.1524)
				(type default)
			)
			(layer "F.SilkS")
		)
		(fp_line
			(start -0.7874 -0.4064)
			(end 0.7874 -0.4064)
			(stroke
				(width 0.1524)
				(type default)
			)
			(layer "F.SilkS")
		)
		(fp_line
			(start 0.7874 -0.4064)
			(end 0.7874 0.4064)
			(stroke
				(width 0.1524)
				(type default)
			)
			(layer "F.SilkS")
		)
		(fp_line
			(start -0.67945 0.3048)
			(end -0.67945 -0.305054)
			(stroke
				(width 0.1)
				(type default)
			)
			(layer "F.Fab")
		)
		(fp_line
			(start -0.12065 0.3048)
			(end -0.67945 0.3048)
			(stroke
				(width 0.1)
				(type default)
			)
			(layer "F.Fab")
		)
		(fp_line
			(start 0.120396 0.3048)
			(end 0.120396 0.2794)
			(stroke
				(width 0.1)
				(type default)
			)
			(layer "F.Fab")
		)
		(fp_line
			(start 0.67945 0.3048)
			(end 0.120396 0.3048)
			(stroke
				(width 0.1)
				(type default)
			)
			(layer "F.Fab")
		)
		(fp_line
			(start -0.12065 0.2794)
			(end -0.12065 0.3048)
			(stroke
				(width 0.1)
				(type default)
			)
			(layer "F.Fab")
		)
		(fp_line
			(start 0.120396 0.2794)
			(end -0.12065 0.2794)
			(stroke
				(width 0.1)
				(type default)
			)
			(layer "F.Fab")
		)
		(fp_line
			(start -0.12065 -0.2794)
			(end 0.12065 -0.2794)
			(stroke
				(width 0.1)
				(type default)
			)
			(layer "F.Fab")
		)
		(fp_line
			(start 0.12065 -0.2794)
			(end 0.12065 -0.3048)
			(stroke
				(width 0.1)
				(type default)
			)
			(layer "F.Fab")
		)
		(fp_line
			(start 0.12065 -0.3048)
			(end 0.67945 -0.3048)
			(stroke
				(width 0.1)
				(type default)
			)
			(layer "F.Fab")
		)
		(fp_line
			(start 0.67945 -0.3048)
			(end 0.67945 0.3048)
			(stroke
				(width 0.1)
				(type default)
			)
			(layer "F.Fab")
		)
		(fp_line
			(start -0.67945 -0.305054)
			(end -0.12065 -0.305054)
			(stroke
				(width 0.1)
				(type default)
			)
			(layer "F.Fab")
		)
		(fp_line
			(start -0.12065 -0.305054)
			(end -0.12065 -0.2794)
			(stroke
				(width 0.1)
				(type default)
			)
			(layer "F.Fab")
		)
		(pad "1" smd circle
			(at -0.40005 0 270)
			(size 0 0)
			(layers "F.Cu" "F.Mask" "F.Paste")
			(net "P5V_AUX")
		)
		(pad "2" smd circle
			(at 0.40005 0 270)
			(size 0 0)
			(layers "F.Cu" "F.Mask" "F.Paste")
			(net "P12V_SSD8_PG_G2")
		)
	)
	(footprint ""
		(layer "F.Cu")
		(at 404.12924 -116.5352 180)
		(property "Reference" "R346"
			(at 0 0 180)
			(layer "F.SilkS")
			(hide yes)
			(effects
				(font
					(size 1.27 1.27)
				)
			)
		)
		(property "Value" ""
			(at 0 0 180)
			(layer "F.Fab")
			(effects
				(font
					(size 1.27 1.27)
				)
			)
		)
		(duplicate_pad_numbers_are_jumpers no)
		(fp_line
			(start 0.7874 0.4064)
			(end -0.7874 0.4064)
			(stroke
				(width 0.1524)
				(type default)
			)
			(layer "F.SilkS")
		)
		(fp_line
			(start 0.7874 -0.4064)
			(end 0.7874 0.4064)
			(stroke
				(width 0.1524)
				(type default)
			)
			(layer "F.SilkS")
		)
		(fp_line
			(start -0.7874 0.4064)
			(end -0.7874 -0.4064)
			(stroke
				(width 0.1524)
				(type default)
			)
			(layer "F.SilkS")
		)
		(fp_line
			(start -0.7874 -0.4064)
			(end 0.7874 -0.4064)
			(stroke
				(width 0.1524)
				(type default)
			)
			(layer "F.SilkS")
		)
		(fp_line
			(start 0.67945 0.3048)
			(end 0.120396 0.3048)
			(stroke
				(width 0.1)
				(type default)
			)
			(layer "F.Fab")
		)
		(fp_line
			(start 0.67945 -0.3048)
			(end 0.67945 0.3048)
			(stroke
				(width 0.1)
				(type default)
			)
			(layer "F.Fab")
		)
		(fp_line
			(start 0.12065 -0.2794)
			(end 0.12065 -0.3048)
			(stroke
				(width 0.1)
				(type default)
			)
			(layer "F.Fab")
		)
		(fp_line
			(start 0.12065 -0.3048)
			(end 0.67945 -0.3048)
			(stroke
				(width 0.1)
				(type default)
			)
			(layer "F.Fab")
		)
		(fp_line
			(start 0.120396 0.3048)
			(end 0.120396 0.2794)
			(stroke
				(width 0.1)
				(type default)
			)
			(layer "F.Fab")
		)
		(fp_line
			(start 0.120396 0.2794)
			(end -0.12065 0.2794)
			(stroke
				(width 0.1)
				(type default)
			)
			(layer "F.Fab")
		)
		(fp_line
			(start -0.12065 0.3048)
			(end -0.67945 0.3048)
			(stroke
				(width 0.1)
				(type default)
			)
			(layer "F.Fab")
		)
		(fp_line
			(start -0.12065 0.2794)
			(end -0.12065 0.3048)
			(stroke
				(width 0.1)
				(type default)
			)
			(layer "F.Fab")
		)
		(fp_line
			(start -0.12065 -0.2794)
			(end 0.12065 -0.2794)
			(stroke
				(width 0.1)
				(type default)
			)
			(layer "F.Fab")
		)
		(fp_line
			(start -0.12065 -0.305054)
			(end -0.12065 -0.2794)
			(stroke
				(width 0.1)
				(type default)
			)
			(layer "F.Fab")
		)
		(fp_line
			(start -0.67945 0.3048)
			(end -0.67945 -0.305054)
			(stroke
				(width 0.1)
				(type default)
			)
			(layer "F.Fab")
		)
		(fp_line
			(start -0.67945 -0.305054)
			(end -0.12065 -0.305054)
			(stroke
				(width 0.1)
				(type default)
			)
			(layer "F.Fab")
		)
		(pad "1" smd circle
			(at -0.40005 0 180)
			(size 0 0)
			(layers "F.Cu" "F.Mask" "F.Paste")
			(net "PRSNT_NIC6_N")
		)
		(pad "2" smd circle
			(at 0.40005 0 180)
			(size 0 0)
			(layers "F.Cu" "F.Mask" "F.Paste")
			(net "PRSNTB1_NIC6_N")
		)
	)
	(footprint ""
		(layer "F.Cu")
		(at 101.930454 -121.80824 180)
		(property "Reference" "R5865"
			(at 0 0 180)
			(layer "F.SilkS")
			(hide yes)
			(effects
				(font
					(size 1.27 1.27)
				)
			)
		)
		(property "Value" ""
			(at 0 0 180)
			(layer "F.Fab")
			(effects
				(font
					(size 1.27 1.27)
				)
			)
		)
		(duplicate_pad_numbers_are_jumpers no)
		(fp_line
			(start 0.7874 0.4064)
			(end -0.7874 0.4064)
			(stroke
				(width 0.1524)
				(type default)
			)
			(layer "F.SilkS")
		)
		(fp_line
			(start 0.7874 -0.4064)
			(end 0.7874 0.4064)
			(stroke
				(width 0.1524)
				(type default)
			)
			(layer "F.SilkS")
		)
		(fp_line
			(start -0.7874 0.4064)
			(end -0.7874 -0.4064)
			(stroke
				(width 0.1524)
				(type default)
			)
			(layer "F.SilkS")
		)
		(fp_line
			(start -0.7874 -0.4064)
			(end 0.7874 -0.4064)
			(stroke
				(width 0.1524)
				(type default)
			)
			(layer "F.SilkS")
		)
		(fp_line
			(start 0.67945 0.3048)
			(end 0.120396 0.3048)
			(stroke
				(width 0.1)
				(type default)
			)
			(layer "F.Fab")
		)
		(fp_line
			(start 0.67945 -0.3048)
			(end 0.67945 0.3048)
			(stroke
				(width 0.1)
				(type default)
			)
			(layer "F.Fab")
		)
		(fp_line
			(start 0.12065 -0.2794)
			(end 0.12065 -0.3048)
			(stroke
				(width 0.1)
				(type default)
			)
			(layer "F.Fab")
		)
		(fp_line
			(start 0.12065 -0.3048)
			(end 0.67945 -0.3048)
			(stroke
				(width 0.1)
				(type default)
			)
			(layer "F.Fab")
		)
		(fp_line
			(start 0.120396 0.3048)
			(end 0.120396 0.2794)
			(stroke
				(width 0.1)
				(type default)
			)
			(layer "F.Fab")
		)
		(fp_line
			(start 0.120396 0.2794)
			(end -0.12065 0.2794)
			(stroke
				(width 0.1)
				(type default)
			)
			(layer "F.Fab")
		)
		(fp_line
			(start -0.12065 0.3048)
			(end -0.67945 0.3048)
			(stroke
				(width 0.1)
				(type default)
			)
			(layer "F.Fab")
		)
		(fp_line
			(start -0.12065 0.2794)
			(end -0.12065 0.3048)
			(stroke
				(width 0.1)
				(type default)
			)
			(layer "F.Fab")
		)
		(fp_line
			(start -0.12065 -0.2794)
			(end 0.12065 -0.2794)
			(stroke
				(width 0.1)
				(type default)
			)
			(layer "F.Fab")
		)
		(fp_line
			(start -0.12065 -0.305054)
			(end -0.12065 -0.2794)
			(stroke
				(width 0.1)
				(type default)
			)
			(layer "F.Fab")
		)
		(fp_line
			(start -0.67945 0.3048)
			(end -0.67945 -0.305054)
			(stroke
				(width 0.1)
				(type default)
			)
			(layer "F.Fab")
		)
		(fp_line
			(start -0.67945 -0.305054)
			(end -0.12065 -0.305054)
			(stroke
				(width 0.1)
				(type default)
			)
			(layer "F.Fab")
		)
		(pad "1" smd circle
			(at -0.40005 0 180)
			(size 0 0)
			(layers "F.Cu" "F.Mask" "F.Paste")
			(net "P3V3_NIC1_PG_G1")
		)
		(pad "2" smd circle
			(at 0.40005 0 180)
			(size 0 0)
			(layers "F.Cu" "F.Mask" "F.Paste")
			(net "GND")
		)
	)
	(footprint ""
		(layer "F.Cu")
		(at 200.809098 -27.04973 180)
		(property "Reference" "C2770"
			(at 0 0 180)
			(layer "F.SilkS")
			(hide yes)
			(effects
				(font
					(size 1.27 1.27)
				)
			)
		)
		(property "Value" ""
			(at 0 0 180)
			(layer "F.Fab")
			(effects
				(font
					(size 1.27 1.27)
				)
			)
		)
		(duplicate_pad_numbers_are_jumpers no)
		(fp_line
			(start 0.7874 0.4064)
			(end -0.7874 0.4064)
			(stroke
				(width 0.1524)
				(type default)
			)
			(layer "F.SilkS")
		)
		(fp_line
			(start 0.7874 -0.4064)
			(end 0.7874 0.4064)
			(stroke
				(width 0.1524)
				(type default)
			)
			(layer "F.SilkS")
		)
		(fp_line
			(start -0.7874 0.4064)
			(end -0.7874 -0.4064)
			(stroke
				(width 0.1524)
				(type default)
			)
			(layer "F.SilkS")
		)
		(fp_line
			(start -0.7874 -0.4064)
			(end 0.7874 -0.4064)
			(stroke
				(width 0.1524)
				(type default)
			)
			(layer "F.SilkS")
		)
		(fp_line
			(start 0.67945 0.3048)
			(end 0.120396 0.3048)
			(stroke
				(width 0.1)
				(type default)
			)
			(layer "F.Fab")
		)
		(fp_line
			(start 0.67945 -0.3048)
			(end 0.67945 0.3048)
			(stroke
				(width 0.1)
				(type default)
			)
			(layer "F.Fab")
		)
		(fp_line
			(start 0.12065 -0.2794)
			(end 0.12065 -0.3048)
			(stroke
				(width 0.1)
				(type default)
			)
			(layer "F.Fab")
		)
		(fp_line
			(start 0.12065 -0.3048)
			(end 0.67945 -0.3048)
			(stroke
				(width 0.1)
				(type default)
			)
			(layer "F.Fab")
		)
		(fp_line
			(start 0.120396 0.3048)
			(end 0.120396 0.2794)
			(stroke
				(width 0.1)
				(type default)
			)
			(layer "F.Fab")
		)
		(fp_line
			(start 0.120396 0.2794)
			(end -0.12065 0.2794)
			(stroke
				(width 0.1)
				(type default)
			)
			(layer "F.Fab")
		)
		(fp_line
			(start -0.12065 0.3048)
			(end -0.67945 0.3048)
			(stroke
				(width 0.1)
				(type default)
			)
			(layer "F.Fab")
		)
		(fp_line
			(start -0.12065 0.2794)
			(end -0.12065 0.3048)
			(stroke
				(width 0.1)
				(type default)
			)
			(layer "F.Fab")
		)
		(fp_line
			(start -0.12065 -0.2794)
			(end 0.12065 -0.2794)
			(stroke
				(width 0.1)
				(type default)
			)
			(layer "F.Fab")
		)
		(fp_line
			(start -0.12065 -0.305054)
			(end -0.12065 -0.2794)
			(stroke
				(width 0.1)
				(type default)
			)
			(layer "F.Fab")
		)
		(fp_line
			(start -0.67945 0.3048)
			(end -0.67945 -0.305054)
			(stroke
				(width 0.1)
				(type default)
			)
			(layer "F.Fab")
		)
		(fp_line
			(start -0.67945 -0.305054)
			(end -0.12065 -0.305054)
			(stroke
				(width 0.1)
				(type default)
			)
			(layer "F.Fab")
		)
		(pad "1" smd circle
			(at -0.40005 0 180)
			(size 0 0)
			(layers "F.Cu" "F.Mask" "F.Paste")
			(net "PRSNT_SSD7_R_N")
		)
		(pad "2" smd circle
			(at 0.40005 0 180)
			(size 0 0)
			(layers "F.Cu" "F.Mask" "F.Paste")
			(net "GND")
		)
	)
	(footprint ""
		(layer "F.Cu")
		(at 405.956262 -61.487812 180)
		(property "Reference" "R6022"
			(at 0 0 180)
			(layer "F.SilkS")
			(hide yes)
			(effects
				(font
					(size 1.27 1.27)
				)
			)
		)
		(property "Value" ""
			(at 0 0 180)
			(layer "F.Fab")
			(effects
				(font
					(size 1.27 1.27)
				)
			)
		)
		(duplicate_pad_numbers_are_jumpers no)
		(fp_line
			(start 0.7874 0.4064)
			(end -0.7874 0.4064)
			(stroke
				(width 0.1524)
				(type default)
			)
			(layer "F.SilkS")
		)
		(fp_line
			(start 0.7874 -0.4064)
			(end 0.7874 0.4064)
			(stroke
				(width 0.1524)
				(type default)
			)
			(layer "F.SilkS")
		)
		(fp_line
			(start -0.7874 0.4064)
			(end -0.7874 -0.4064)
			(stroke
				(width 0.1524)
				(type default)
			)
			(layer "F.SilkS")
		)
		(fp_line
			(start -0.7874 -0.4064)
			(end 0.7874 -0.4064)
			(stroke
				(width 0.1524)
				(type default)
			)
			(layer "F.SilkS")
		)
		(fp_line
			(start 0.67945 0.3048)
			(end 0.120396 0.3048)
			(stroke
				(width 0.1)
				(type default)
			)
			(layer "F.Fab")
		)
		(fp_line
			(start 0.67945 -0.3048)
			(end 0.67945 0.3048)
			(stroke
				(width 0.1)
				(type default)
			)
			(layer "F.Fab")
		)
		(fp_line
			(start 0.12065 -0.2794)
			(end 0.12065 -0.3048)
			(stroke
				(width 0.1)
				(type default)
			)
			(layer "F.Fab")
		)
		(fp_line
			(start 0.12065 -0.3048)
			(end 0.67945 -0.3048)
			(stroke
				(width 0.1)
				(type default)
			)
			(layer "F.Fab")
		)
		(fp_line
			(start 0.120396 0.3048)
			(end 0.120396 0.2794)
			(stroke
				(width 0.1)
				(type default)
			)
			(layer "F.Fab")
		)
		(fp_line
			(start 0.120396 0.2794)
			(end -0.12065 0.2794)
			(stroke
				(width 0.1)
				(type default)
			)
			(layer "F.Fab")
		)
		(fp_line
			(start -0.12065 0.3048)
			(end -0.67945 0.3048)
			(stroke
				(width 0.1)
				(type default)
			)
			(layer "F.Fab")
		)
		(fp_line
			(start -0.12065 0.2794)
			(end -0.12065 0.3048)
			(stroke
				(width 0.1)
				(type default)
			)
			(layer "F.Fab")
		)
		(fp_line
			(start -0.12065 -0.2794)
			(end 0.12065 -0.2794)
			(stroke
				(width 0.1)
				(type default)
			)
			(layer "F.Fab")
		)
		(fp_line
			(start -0.12065 -0.305054)
			(end -0.12065 -0.2794)
			(stroke
				(width 0.1)
				(type default)
			)
			(layer "F.Fab")
		)
		(fp_line
			(start -0.67945 0.3048)
			(end -0.67945 -0.305054)
			(stroke
				(width 0.1)
				(type default)
			)
			(layer "F.Fab")
		)
		(fp_line
			(start -0.67945 -0.305054)
			(end -0.12065 -0.305054)
			(stroke
				(width 0.1)
				(type default)
			)
			(layer "F.Fab")
		)
		(pad "1" smd circle
			(at -0.40005 0 180)
			(size 0 0)
			(layers "F.Cu" "F.Mask" "F.Paste")
			(net "P3V3_AUX")
		)
		(pad "2" smd circle
			(at 0.40005 0 180)
			(size 0 0)
			(layers "F.Cu" "F.Mask" "F.Paste")
			(net "PWRGD_P12V_SSD14_D")
		)
	)
	(footprint ""
		(layer "F.Cu")
		(at 370.361972 -241.54892 180)
		(property "Reference" "C4189"
			(at 0 0 180)
			(layer "F.SilkS")
			(hide yes)
			(effects
				(font
					(size 1.27 1.27)
				)
			)
		)
		(property "Value" ""
			(at 0 0 180)
			(layer "F.Fab")
			(effects
				(font
					(size 1.27 1.27)
				)
			)
		)
		(duplicate_pad_numbers_are_jumpers no)
		(fp_line
			(start 0.7874 0.4064)
			(end -0.7874 0.4064)
			(stroke
				(width 0.1524)
				(type default)
			)
			(layer "F.SilkS")
		)
		(fp_line
			(start 0.7874 -0.4064)
			(end 0.7874 0.4064)
			(stroke
				(width 0.1524)
				(type default)
			)
			(layer "F.SilkS")
		)
		(fp_line
			(start -0.7874 0.4064)
			(end -0.7874 -0.4064)
			(stroke
				(width 0.1524)
				(type default)
			)
			(layer "F.SilkS")
		)
		(fp_line
			(start -0.7874 -0.4064)
			(end 0.7874 -0.4064)
			(stroke
				(width 0.1524)
				(type default)
			)
			(layer "F.SilkS")
		)
		(fp_line
			(start 0.67945 0.3048)
			(end 0.120396 0.3048)
			(stroke
				(width 0.1)
				(type default)
			)
			(layer "F.Fab")
		)
		(fp_line
			(start 0.67945 -0.3048)
			(end 0.67945 0.3048)
			(stroke
				(width 0.1)
				(type default)
			)
			(layer "F.Fab")
		)
		(fp_line
			(start 0.12065 -0.2794)
			(end 0.12065 -0.3048)
			(stroke
				(width 0.1)
				(type default)
			)
			(layer "F.Fab")
		)
		(fp_line
			(start 0.12065 -0.3048)
			(end 0.67945 -0.3048)
			(stroke
				(width 0.1)
				(type default)
			)
			(layer "F.Fab")
		)
		(fp_line
			(start 0.120396 0.3048)
			(end 0.120396 0.2794)
			(stroke
				(width 0.1)
				(type default)
			)
			(layer "F.Fab")
		)
		(fp_line
			(start 0.120396 0.2794)
			(end -0.12065 0.2794)
			(stroke
				(width 0.1)
				(type default)
			)
			(layer "F.Fab")
		)
		(fp_line
			(start -0.12065 0.3048)
			(end -0.67945 0.3048)
			(stroke
				(width 0.1)
				(type default)
			)
			(layer "F.Fab")
		)
		(fp_line
			(start -0.12065 0.2794)
			(end -0.12065 0.3048)
			(stroke
				(width 0.1)
				(type default)
			)
			(layer "F.Fab")
		)
		(fp_line
			(start -0.12065 -0.2794)
			(end 0.12065 -0.2794)
			(stroke
				(width 0.1)
				(type default)
			)
			(layer "F.Fab")
		)
		(fp_line
			(start -0.12065 -0.305054)
			(end -0.12065 -0.2794)
			(stroke
				(width 0.1)
				(type default)
			)
			(layer "F.Fab")
		)
		(fp_line
			(start -0.67945 0.3048)
			(end -0.67945 -0.305054)
			(stroke
				(width 0.1)
				(type default)
			)
			(layer "F.Fab")
		)
		(fp_line
			(start -0.67945 -0.305054)
			(end -0.12065 -0.305054)
			(stroke
				(width 0.1)
				(type default)
			)
			(layer "F.Fab")
		)
		(pad "1" smd circle
			(at -0.40005 0 180)
			(size 0 0)
			(layers "F.Cu" "F.Mask" "F.Paste")
			(net "GND")
		)
		(pad "2" smd circle
			(at 0.40005 0 180)
			(size 0 0)
			(layers "F.Cu" "F.Mask" "F.Paste")
			(net "P3V3_AUX")
		)
	)
	(footprint ""
		(layer "F.Cu")
		(at 134.513828 -343.952322 90)
		(property "Reference" "C2270"
			(at 0 0 90)
			(layer "F.SilkS")
			(hide yes)
			(effects
				(font
					(size 1.27 1.27)
				)
			)
		)
		(property "Value" ""
			(at 0 0 90)
			(layer "F.Fab")
			(effects
				(font
					(size 1.27 1.27)
				)
			)
		)
		(duplicate_pad_numbers_are_jumpers no)
		(fp_line
			(start 0.299974 -0.150114)
			(end 0.299974 0.150114)
			(stroke
				(width 0.1)
				(type default)
			)
			(layer "F.Fab")
		)
		(fp_line
			(start -0.299974 -0.150114)
			(end 0.299974 -0.150114)
			(stroke
				(width 0.1)
				(type default)
			)
			(layer "F.Fab")
		)
		(fp_line
			(start 0.299974 0.150114)
			(end -0.299974 0.150114)
			(stroke
				(width 0.1)
				(type default)
			)
			(layer "F.Fab")
		)
		(fp_line
			(start -0.299974 0.150114)
			(end -0.299974 -0.150114)
			(stroke
				(width 0.1)
				(type default)
			)
			(layer "F.Fab")
		)
		(pad "1" smd rect
			(at -0.2667 0 90)
			(size 0.3048 0.381)
			(layers "F.Cu" "F.Mask" "F.Paste")
			(net "P5E_PEX1_STN5_TX_DN<82>")
		)
		(pad "2" smd rect
			(at 0.2667 0 90)
			(size 0.3048 0.381)
			(layers "F.Cu" "F.Mask" "F.Paste")
			(net "P5E_PEX1_STN5_TX_C_DN<82>")
		)
	)
	(footprint ""
		(layer "F.Cu")
		(at 378.382022 -280.189432 180)
		(property "Reference" "C3595"
			(at 0 0 180)
			(layer "F.SilkS")
			(hide yes)
			(effects
				(font
					(size 1.27 1.27)
				)
			)
		)
		(property "Value" ""
			(at 0 0 180)
			(layer "F.Fab")
			(effects
				(font
					(size 1.27 1.27)
				)
			)
		)
		(duplicate_pad_numbers_are_jumpers no)
		(fp_line
			(start 1.2954 0.5842)
			(end -1.2954 0.5842)
			(stroke
				(width 0.1524)
				(type default)
			)
			(layer "F.SilkS")
		)
		(fp_line
			(start 1.2954 -0.5842)
			(end 1.2954 0.5842)
			(stroke
				(width 0.1524)
				(type default)
			)
			(layer "F.SilkS")
		)
		(fp_line
			(start -1.2954 0.5842)
			(end -1.2954 -0.5842)
			(stroke
				(width 0.1524)
				(type default)
			)
			(layer "F.SilkS")
		)
		(fp_line
			(start -1.2954 -0.5842)
			(end 1.2954 -0.5842)
			(stroke
				(width 0.1524)
				(type default)
			)
			(layer "F.SilkS")
		)
		(fp_line
			(start 1.1938 0.4064)
			(end 0.8636 0.4064)
			(stroke
				(width 0.1)
				(type default)
			)
			(layer "F.Fab")
		)
		(fp_line
			(start 1.1938 -0.4064)
			(end 1.1938 0.4064)
			(stroke
				(width 0.1)
				(type default)
			)
			(layer "F.Fab")
		)
		(fp_line
			(start 0.8636 0.4572)
			(end -0.8636 0.4572)
			(stroke
				(width 0.1)
				(type default)
			)
			(layer "F.Fab")
		)
		(fp_line
			(start 0.8636 0.4064)
			(end 0.8636 0.4572)
			(stroke
				(width 0.1)
				(type default)
			)
			(layer "F.Fab")
		)
		(fp_line
			(start 0.8636 -0.4064)
			(end 1.1938 -0.4064)
			(stroke
				(width 0.1)
				(type default)
			)
			(layer "F.Fab")
		)
		(fp_line
			(start 0.8636 -0.4572)
			(end 0.8636 -0.4064)
			(stroke
				(width 0.1)
				(type default)
			)
			(layer "F.Fab")
		)
		(fp_line
			(start -0.8636 0.4572)
			(end -0.8636 0.4064)
			(stroke
				(width 0.1)
				(type default)
			)
			(layer "F.Fab")
		)
		(fp_line
			(start -0.8636 0.4064)
			(end -1.1938 0.4064)
			(stroke
				(width 0.1)
				(type default)
			)
			(layer "F.Fab")
		)
		(fp_line
			(start -0.8636 -0.4064)
			(end -0.8636 -0.4572)
			(stroke
				(width 0.1)
				(type default)
			)
			(layer "F.Fab")
		)
		(fp_line
			(start -0.8636 -0.4572)
			(end 0.8636 -0.4572)
			(stroke
				(width 0.1)
				(type default)
			)
			(layer "F.Fab")
		)
		(fp_line
			(start -1.1938 0.4064)
			(end -1.1938 -0.4064)
			(stroke
				(width 0.1)
				(type default)
			)
			(layer "F.Fab")
		)
		(fp_line
			(start -1.1938 -0.4064)
			(end -0.8636 -0.4064)
			(stroke
				(width 0.1)
				(type default)
			)
			(layer "F.Fab")
		)
		(pad "1" smd rect
			(at -0.7366 0 90)
			(size 0.7112 0.8128)
			(layers "F.Cu" "F.Mask" "F.Paste")
			(net "SYSPLL_VDDA18_PEX3_R")
		)
		(pad "2" smd rect
			(at 0.7366 0 90)
			(size 0.7112 0.8128)
			(layers "F.Cu" "F.Mask" "F.Paste")
			(net "GND")
		)
	)
	(footprint ""
		(layer "F.Cu")
		(at 338.796884 -116.611654 180)
		(property "Reference" "PR7031"
			(at 0 0 180)
			(layer "F.SilkS")
			(hide yes)
			(effects
				(font
					(size 1.27 1.27)
				)
			)
		)
		(property "Value" ""
			(at 0 0 180)
			(layer "F.Fab")
			(effects
				(font
					(size 1.27 1.27)
				)
			)
		)
		(duplicate_pad_numbers_are_jumpers no)
		(fp_line
			(start 0.7874 0.4064)
			(end -0.7874 0.4064)
			(stroke
				(width 0.1524)
				(type default)
			)
			(layer "F.SilkS")
		)
		(fp_line
			(start 0.7874 -0.4064)
			(end 0.7874 0.4064)
			(stroke
				(width 0.1524)
				(type default)
			)
			(layer "F.SilkS")
		)
		(fp_line
			(start -0.7874 0.4064)
			(end -0.7874 -0.4064)
			(stroke
				(width 0.1524)
				(type default)
			)
			(layer "F.SilkS")
		)
		(fp_line
			(start -0.7874 -0.4064)
			(end 0.7874 -0.4064)
			(stroke
				(width 0.1524)
				(type default)
			)
			(layer "F.SilkS")
		)
		(fp_line
			(start 0.67945 0.3048)
			(end 0.120396 0.3048)
			(stroke
				(width 0.1)
				(type default)
			)
			(layer "F.Fab")
		)
		(fp_line
			(start 0.67945 -0.3048)
			(end 0.67945 0.3048)
			(stroke
				(width 0.1)
				(type default)
			)
			(layer "F.Fab")
		)
		(fp_line
			(start 0.12065 -0.2794)
			(end 0.12065 -0.3048)
			(stroke
				(width 0.1)
				(type default)
			)
			(layer "F.Fab")
		)
		(fp_line
			(start 0.12065 -0.3048)
			(end 0.67945 -0.3048)
			(stroke
				(width 0.1)
				(type default)
			)
			(layer "F.Fab")
		)
		(fp_line
			(start 0.120396 0.3048)
			(end 0.120396 0.2794)
			(stroke
				(width 0.1)
				(type default)
			)
			(layer "F.Fab")
		)
		(fp_line
			(start 0.120396 0.2794)
			(end -0.12065 0.2794)
			(stroke
				(width 0.1)
				(type default)
			)
			(layer "F.Fab")
		)
		(fp_line
			(start -0.12065 0.3048)
			(end -0.67945 0.3048)
			(stroke
				(width 0.1)
				(type default)
			)
			(layer "F.Fab")
		)
		(fp_line
			(start -0.12065 0.2794)
			(end -0.12065 0.3048)
			(stroke
				(width 0.1)
				(type default)
			)
			(layer "F.Fab")
		)
		(fp_line
			(start -0.12065 -0.2794)
			(end 0.12065 -0.2794)
			(stroke
				(width 0.1)
				(type default)
			)
			(layer "F.Fab")
		)
		(fp_line
			(start -0.12065 -0.305054)
			(end -0.12065 -0.2794)
			(stroke
				(width 0.1)
				(type default)
			)
			(layer "F.Fab")
		)
		(fp_line
			(start -0.67945 0.3048)
			(end -0.67945 -0.305054)
			(stroke
				(width 0.1)
				(type default)
			)
			(layer "F.Fab")
		)
		(fp_line
			(start -0.67945 -0.305054)
			(end -0.12065 -0.305054)
			(stroke
				(width 0.1)
				(type default)
			)
			(layer "F.Fab")
		)
		(pad "1" smd circle
			(at -0.40005 0 180)
			(size 0 0)
			(layers "F.Cu" "F.Mask" "F.Paste")
			(net "P12V_NIC5_CO_OV_FB")
		)
		(pad "2" smd circle
			(at 0.40005 0 180)
			(size 0 0)
			(layers "F.Cu" "F.Mask" "F.Paste")
			(net "P12V_AUX")
		)
	)
	(footprint ""
		(layer "F.Cu")
		(at 297.16476 -26.785062 180)
		(property "Reference" "J40"
			(at 4.09829 -11.087862 90)
			(unlocked yes)
			(layer "F.SilkS")
			(effects
				(font
					(size 0.7874 0.5842)
					(thickness 0.1524)
				)
			)
		)
		(property "Value" ""
			(at 0 0 180)
			(layer "F.Fab")
			(effects
				(font
					(size 1.27 1.27)
				)
			)
		)
		(duplicate_pad_numbers_are_jumpers no)
		(fp_line
			(start 3.150108 12.115038)
			(end 1.529334 12.115038)
			(stroke
				(width 0.1524)
				(type default)
			)
			(layer "F.SilkS")
		)
		(fp_line
			(start 3.074924 12.014962)
			(end 1.632204 12.014962)
			(stroke
				(width 0.1524)
				(type default)
			)
			(layer "F.SilkS")
		)
		(fp_line
			(start 1.632204 -12.014962)
			(end 3.074924 -12.014962)
			(stroke
				(width 0.1524)
				(type default)
			)
			(layer "F.SilkS")
		)
		(fp_line
			(start 1.529334 -12.115038)
			(end 3.150108 -12.115038)
			(stroke
				(width 0.1524)
				(type default)
			)
			(layer "F.SilkS")
		)
		(fp_line
			(start -1.529334 12.115038)
			(end -3.150108 12.115038)
			(stroke
				(width 0.1524)
				(type default)
			)
			(layer "F.SilkS")
		)
		(fp_line
			(start -1.632204 12.014962)
			(end -3.074924 12.014962)
			(stroke
				(width 0.1524)
				(type default)
			)
			(layer "F.SilkS")
		)
		(fp_line
			(start -3.074924 -12.014962)
			(end -1.632204 -12.014962)
			(stroke
				(width 0.1524)
				(type default)
			)
			(layer "F.SilkS")
		)
		(fp_line
			(start -3.150108 -12.115038)
			(end -1.529334 -12.115038)
			(stroke
				(width 0.1524)
				(type default)
			)
			(layer "F.SilkS")
		)
		(fp_poly
			(pts
				(xy 3.550666 -8.697722) (xy 3.973068 -9.965436) (xy 4.818126 -9.120378)
			)
			(stroke
				(width 0)
				(type default)
			)
			(fill yes)
			(layer "F.SilkS")
		)
		(fp_line
			(start 3.074924 12.014962)
			(end -3.074924 12.014962)
			(stroke
				(width 0.1)
				(type default)
			)
			(layer "F.Fab")
		)
		(fp_line
			(start 3.074924 -12.014962)
			(end 3.074924 12.014962)
			(stroke
				(width 0.1)
				(type default)
			)
			(layer "F.Fab")
		)
		(fp_line
			(start -3.074924 12.014962)
			(end -3.074924 -12.014962)
			(stroke
				(width 0.1)
				(type default)
			)
			(layer "F.Fab")
		)
		(fp_line
			(start -3.074924 -12.014962)
			(end 3.074924 -12.014962)
			(stroke
				(width 0.1)
				(type default)
			)
			(layer "F.Fab")
		)
		(fp_poly
			(pts
				(xy 3.348736 -7.994904) (xy 4.543806 -8.592566) (xy 4.543806 -7.397496)
			)
			(stroke
				(width 0)
				(type default)
			)
			(fill yes)
			(layer "F.Fab")
		)
		(pad "" np_thru_hole circle
			(at -1.75006 -9.815068 90)
			(size 1.1176 1.1176)
			(drill 1.1176)
			(layers "*.Cu" "*.Mask")
			(clearance 0.381)
			(thermal_gap 0.381)
		)
		(pad "" np_thru_hole circle
			(at 0 9.815068 90)
			(size 1.1176 1.1176)
			(drill 1.1176)
			(layers "*.Cu" "*.Mask")
			(clearance 0.381)
			(thermal_gap 0.381)
		)
		(pad "A1" smd rect
			(at 2.29997 -7.994904 90)
			(size 0.381 1.27)
			(layers "F.Cu" "F.Mask" "F.Paste")
			(net "GND")
		)
		(pad "A2" smd rect
			(at 2.29997 -7.394956 90)
			(size 0.381 1.27)
			(layers "F.Cu" "F.Mask" "F.Paste")
			(net "GND")
		)
		(pad "A3" smd rect
			(at 2.29997 -6.795008 90)
			(size 0.381 1.27)
			(layers "F.Cu" "F.Mask" "F.Paste")
			(net "GND")
		)
		(pad "A4" smd rect
			(at 2.29997 -6.19506 90)
			(size 0.381 1.27)
			(layers "F.Cu" "F.Mask" "F.Paste")
			(net "GND")
		)
		(pad "A5" smd rect
			(at 2.29997 -5.595112 90)
			(size 0.381 1.27)
			(layers "F.Cu" "F.Mask" "F.Paste")
			(net "GND")
		)
		(pad "A6" smd rect
			(at 2.29997 -4.99491 90)
			(size 0.381 1.27)
			(layers "F.Cu" "F.Mask" "F.Paste")
			(net "GND")
		)
		(pad "A7" smd rect
			(at 2.29997 -4.394962 90)
			(size 0.381 1.27)
			(layers "F.Cu" "F.Mask" "F.Paste")
			(net "SMB_ISO_SSD10_R_SCL")
		)
		(pad "A8" smd rect
			(at 2.29997 -3.795014 90)
			(size 0.381 1.27)
			(layers "F.Cu" "F.Mask" "F.Paste")
			(net "SMB_ISO_SSD10_R_SDA")
		)
		(pad "A9" smd rect
			(at 2.29997 -3.195066 90)
			(size 0.381 1.27)
			(layers "F.Cu" "F.Mask" "F.Paste")
			(net "RST_SMB_SSD10_ISO_R_N")
		)
		(pad "A10" smd rect
			(at 2.29997 -2.595118 90)
			(size 0.381 1.27)
			(layers "F.Cu" "F.Mask" "F.Paste")
			(net "SSD10_LED_ISO_R_N")
		)
		(pad "A11" smd rect
			(at 2.29997 -1.994916 90)
			(size 0.381 1.27)
			(layers "F.Cu" "F.Mask" "F.Paste")
			(net "PU_CLKREQ10")
		)
		(pad "A12" smd rect
			(at 2.29997 -1.394968 90)
			(size 0.381 1.27)
			(layers "F.Cu" "F.Mask" "F.Paste")
			(net "PRSNT_SSD10_N")
		)
		(pad "A13" smd rect
			(at 2.29997 -0.79502 90)
			(size 0.381 1.27)
			(layers "F.Cu" "F.Mask" "F.Paste")
			(net "GND")
		)
		(pad "A14" smd rect
			(at 2.29997 -0.195072 90)
			(size 0.381 1.27)
			(layers "F.Cu" "F.Mask" "F.Paste")
			(net "Net_8489")
		)
		(pad "A15" smd rect
			(at 2.29997 0.404876 90)
			(size 0.381 1.27)
			(layers "F.Cu" "F.Mask" "F.Paste")
			(net "Net_8488")
		)
		(pad "A16" smd rect
			(at 2.29997 1.005078 90)
			(size 0.381 1.27)
			(layers "F.Cu" "F.Mask" "F.Paste")
			(net "GND")
		)
		(pad "A17" smd rect
			(at 2.29997 1.605026 90)
			(size 0.381 1.27)
			(layers "F.Cu" "F.Mask" "F.Paste")
			(net "P5E_PEX2_STN2_RX_DN<36>")
		)
		(pad "A18" smd rect
			(at 2.29997 2.204974 90)
			(size 0.381 1.27)
			(layers "F.Cu" "F.Mask" "F.Paste")
			(net "P5E_PEX2_STN2_RX_DP<36>")
		)
		(pad "A19" smd rect
			(at 2.29997 2.804922 90)
			(size 0.381 1.27)
			(layers "F.Cu" "F.Mask" "F.Paste")
			(net "GND")
		)
		(pad "A20" smd rect
			(at 2.29997 3.405124 90)
			(size 0.381 1.27)
			(layers "F.Cu" "F.Mask" "F.Paste")
			(net "P5E_PEX2_STN2_RX_DN<37>")
		)
		(pad "A21" smd rect
			(at 2.29997 4.005072 90)
			(size 0.381 1.27)
			(layers "F.Cu" "F.Mask" "F.Paste")
			(net "P5E_PEX2_STN2_RX_DP<37>")
		)
		(pad "A22" smd rect
			(at 2.29997 4.60502 90)
			(size 0.381 1.27)
			(layers "F.Cu" "F.Mask" "F.Paste")
			(net "GND")
		)
		(pad "A23" smd rect
			(at 2.29997 5.204968 90)
			(size 0.381 1.27)
			(layers "F.Cu" "F.Mask" "F.Paste")
			(net "P5E_PEX2_STN2_RX_DN<38>")
		)
		(pad "A24" smd rect
			(at 2.29997 5.804916 90)
			(size 0.381 1.27)
			(layers "F.Cu" "F.Mask" "F.Paste")
			(net "P5E_PEX2_STN2_RX_DP<38>")
		)
		(pad "A25" smd rect
			(at 2.29997 6.405118 90)
			(size 0.381 1.27)
			(layers "F.Cu" "F.Mask" "F.Paste")
			(net "GND")
		)
		(pad "A26" smd rect
			(at 2.29997 7.005066 90)
			(size 0.381 1.27)
			(layers "F.Cu" "F.Mask" "F.Paste")
			(net "P5E_PEX2_STN2_RX_DN<39>")
		)
		(pad "A27" smd rect
			(at 2.29997 7.605014 90)
			(size 0.381 1.27)
			(layers "F.Cu" "F.Mask" "F.Paste")
			(net "P5E_PEX2_STN2_RX_DP<39>")
		)
		(pad "A28" smd rect
			(at 2.29997 8.204962 90)
			(size 0.381 1.27)
			(layers "F.Cu" "F.Mask" "F.Paste")
			(net "GND")
		)
		(pad "B1" smd rect
			(at -2.29997 -7.994904 90)
			(size 0.381 1.27)
			(layers "F.Cu" "F.Mask" "F.Paste")
			(net "P12V_SSD10")
		)
		(pad "B2" smd rect
			(at -2.29997 -7.394956 90)
			(size 0.381 1.27)
			(layers "F.Cu" "F.Mask" "F.Paste")
			(net "P12V_SSD10")
		)
		(pad "B3" smd rect
			(at -2.29997 -6.795008 90)
			(size 0.381 1.27)
			(layers "F.Cu" "F.Mask" "F.Paste")
			(net "P12V_SSD10")
		)
		(pad "B4" smd rect
			(at -2.29997 -6.19506 90)
			(size 0.381 1.27)
			(layers "F.Cu" "F.Mask" "F.Paste")
			(net "P12V_SSD10")
		)
		(pad "B5" smd rect
			(at -2.29997 -5.595112 90)
			(size 0.381 1.27)
			(layers "F.Cu" "F.Mask" "F.Paste")
			(net "P12V_SSD10")
		)
		(pad "B6" smd rect
			(at -2.29997 -4.99491 90)
			(size 0.381 1.27)
			(layers "F.Cu" "F.Mask" "F.Paste")
			(net "P12V_SSD10")
		)
		(pad "B7" smd rect
			(at -2.29997 -4.394962 90)
			(size 0.381 1.27)
			(layers "F.Cu" "F.Mask" "F.Paste")
			(net "Net_8490")
		)
		(pad "B8" smd rect
			(at -2.29997 -3.795014 90)
			(size 0.381 1.27)
			(layers "F.Cu" "F.Mask" "F.Paste")
			(net "Net_8487")
		)
		(pad "B9" smd rect
			(at -2.29997 -3.195066 90)
			(size 0.381 1.27)
			(layers "F.Cu" "F.Mask" "F.Paste")
			(net "DUALPORT_N_SSD10")
		)
		(pad "B10" smd rect
			(at -2.29997 -2.595118 90)
			(size 0.381 1.27)
			(layers "F.Cu" "F.Mask" "F.Paste")
			(net "RST_SSD10_PERST_R_N")
		)
		(pad "B11" smd rect
			(at -2.29997 -1.994916 90)
			(size 0.381 1.27)
			(layers "F.Cu" "F.Mask" "F.Paste")
			(net "P3V3_SSD10")
		)
		(pad "B12" smd rect
			(at -2.29997 -1.394968 90)
			(size 0.381 1.27)
			(layers "F.Cu" "F.Mask" "F.Paste")
			(net "SSD10_PWRDIS_R")
		)
		(pad "B13" smd rect
			(at -2.29997 -0.79502 90)
			(size 0.381 1.27)
			(layers "F.Cu" "F.Mask" "F.Paste")
			(net "GND")
		)
		(pad "B14" smd rect
			(at -2.29997 -0.195072 90)
			(size 0.381 1.27)
			(layers "F.Cu" "F.Mask" "F.Paste")
			(net "CLK_100M_DB800ZL_SSD10_R_DN")
		)
		(pad "B15" smd rect
			(at -2.29997 0.404876 90)
			(size 0.381 1.27)
			(layers "F.Cu" "F.Mask" "F.Paste")
			(net "CLK_100M_DB800ZL_SSD10_R_DP")
		)
		(pad "B16" smd rect
			(at -2.29997 1.005078 90)
			(size 0.381 1.27)
			(layers "F.Cu" "F.Mask" "F.Paste")
			(net "GND")
		)
		(pad "B17" smd rect
			(at -2.29997 1.605026 90)
			(size 0.381 1.27)
			(layers "F.Cu" "F.Mask" "F.Paste")
			(net "P5E_PEX2_STN2_TX_C_DN<36>")
		)
		(pad "B18" smd rect
			(at -2.29997 2.204974 90)
			(size 0.381 1.27)
			(layers "F.Cu" "F.Mask" "F.Paste")
			(net "P5E_PEX2_STN2_TX_C_DP<36>")
		)
		(pad "B19" smd rect
			(at -2.29997 2.804922 90)
			(size 0.381 1.27)
			(layers "F.Cu" "F.Mask" "F.Paste")
			(net "GND")
		)
		(pad "B20" smd rect
			(at -2.29997 3.405124 90)
			(size 0.381 1.27)
			(layers "F.Cu" "F.Mask" "F.Paste")
			(net "P5E_PEX2_STN2_TX_C_DN<37>")
		)
		(pad "B21" smd rect
			(at -2.29997 4.005072 90)
			(size 0.381 1.27)
			(layers "F.Cu" "F.Mask" "F.Paste")
			(net "P5E_PEX2_STN2_TX_C_DP<37>")
		)
		(pad "B22" smd rect
			(at -2.29997 4.60502 90)
			(size 0.381 1.27)
			(layers "F.Cu" "F.Mask" "F.Paste")
			(net "GND")
		)
		(pad "B23" smd rect
			(at -2.29997 5.204968 90)
			(size 0.381 1.27)
			(layers "F.Cu" "F.Mask" "F.Paste")
			(net "P5E_PEX2_STN2_TX_C_DN<38>")
		)
		(pad "B24" smd rect
			(at -2.29997 5.804916 90)
			(size 0.381 1.27)
			(layers "F.Cu" "F.Mask" "F.Paste")
			(net "P5E_PEX2_STN2_TX_C_DP<38>")
		)
		(pad "B25" smd rect
			(at -2.29997 6.405118 90)
			(size 0.381 1.27)
			(layers "F.Cu" "F.Mask" "F.Paste")
			(net "GND")
		)
		(pad "B26" smd rect
			(at -2.29997 7.005066 90)
			(size 0.381 1.27)
			(layers "F.Cu" "F.Mask" "F.Paste")
			(net "P5E_PEX2_STN2_TX_C_DN<39>")
		)
		(pad "B27" smd rect
			(at -2.29997 7.605014 90)
			(size 0.381 1.27)
			(layers "F.Cu" "F.Mask" "F.Paste")
			(net "P5E_PEX2_STN2_TX_C_DP<39>")
		)
		(pad "B28" smd rect
			(at -2.29997 8.204962 90)
			(size 0.381 1.27)
			(layers "F.Cu" "F.Mask" "F.Paste")
			(net "GND")
		)
		(pad "G1" thru_hole oval
			(at 0 -11.364976 90)
			(size 1.6256 3.4798)
			(drill oval 1.1176 2.4638)
			(layers "*.Cu" "*.Mask")
			(remove_unused_layers no)
			(net "GND")
			(clearance 0.127)
			(thermal_gap 0.127)
		)
		(pad "G2" thru_hole oval
			(at 0 11.364976 90)
			(size 1.6256 3.4798)
			(drill oval 1.1176 2.4638)
			(layers "*.Cu" "*.Mask")
			(remove_unused_layers no)
			(net "GND")
			(clearance 0.127)
			(thermal_gap 0.127)
		)
		(zone
			(layer "F.Cu")
			(hatch none 0.5)
			(connect_pads
				(clearance 0)
			)
			(min_thickness 0.25)
			(keepout
				(tracks not_allowed)
				(vias allowed)
				(pads allowed)
				(copperpour not_allowed)
				(footprints allowed)
			)
			(placement
				(enabled no)
				(sheetname "")
			)
			(fill
				(thermal_gap 0.5)
				(thermal_bridge_width 0.5)
				(island_removal_mode 0)
			)
			(polygon
				(pts
					(xy 298.544742 -38.850062) (xy 295.794684 -38.850062) (xy 295.794684 -35.900106) (xy 298.544742 -35.900106)
				)
			)
		)
		(zone
			(layer "F.Cu")
			(hatch none 0.5)
			(connect_pads
				(clearance 0)
			)
			(min_thickness 0.25)
			(keepout
				(tracks not_allowed)
				(vias allowed)
				(pads allowed)
				(copperpour not_allowed)
				(footprints allowed)
			)
			(placement
				(enabled no)
				(sheetname "")
			)
			(fill
				(thermal_gap 0.5)
				(thermal_bridge_width 0.5)
				(island_removal_mode 0)
			)
			(polygon
				(pts
					(xy 299.614844 -17.670018) (xy 295.784778 -17.670018) (xy 295.784778 -14.720062) (xy 299.614844 -14.720062)
				)
			)
		)
		(zone
			(layers "F.Cu" "B.Cu" "In1.Cu" "In2.Cu" "In3.Cu" "In4.Cu" "In5.Cu" "In6.Cu"
				"In7.Cu" "In8.Cu" "In9.Cu" "In10.Cu" "In11.Cu" "In12.Cu" "In13.Cu" "In14.Cu"
				"In15.Cu" "In16.Cu"
			)
			(hatch none 0.5)
			(connect_pads
				(clearance 0)
			)
			(min_thickness 0.25)
			(keepout
				(tracks not_allowed)
				(vias allowed)
				(pads allowed)
				(copperpour not_allowed)
				(footprints allowed)
			)
			(placement
				(enabled no)
				(sheetname "")
			)
			(fill
				(thermal_gap 0.5)
				(thermal_bridge_width 0.5)
				(island_removal_mode 0)
			)
			(polygon
				(pts
					(arc
						(start 298.12996 -36.60013)
						(mid 296.19956 -36.60013)
						(end 298.12996 -36.60013)
					)
				)
			)
		)
		(zone
			(layers "F.Cu" "B.Cu" "In1.Cu" "In2.Cu" "In3.Cu" "In4.Cu" "In5.Cu" "In6.Cu"
				"In7.Cu" "In8.Cu" "In9.Cu" "In10.Cu" "In11.Cu" "In12.Cu" "In13.Cu" "In14.Cu"
				"In15.Cu" "In16.Cu"
			)
			(hatch none 0.5)
			(connect_pads
				(clearance 0)
			)
			(min_thickness 0.25)
			(keepout
				(tracks not_allowed)
				(vias allowed)
				(pads allowed)
				(copperpour not_allowed)
				(footprints allowed)
			)
			(placement
				(enabled no)
				(sheetname "")
			)
			(fill
				(thermal_gap 0.5)
				(thermal_bridge_width 0.5)
				(island_removal_mode 0)
			)
			(polygon
				(pts
					(arc
						(start 299.88002 -16.969994)
						(mid 297.94962 -16.969994)
						(end 299.88002 -16.969994)
					)
				)
			)
		)
	)
	(footprint ""
		(layer "F.Cu")
		(at 377.843796 -311.725564 45)
		(property "Reference" "R1419"
			(at 0 0 45)
			(layer "F.SilkS")
			(hide yes)
			(effects
				(font
					(size 1.27 1.27)
				)
			)
		)
		(property "Value" ""
			(at 0 0 45)
			(layer "F.Fab")
			(effects
				(font
					(size 1.27 1.27)
				)
			)
		)
		(duplicate_pad_numbers_are_jumpers no)
		(fp_line
			(start -0.787389 -0.406267)
			(end 0.787389 -0.406267)
			(stroke
				(width 0.1524)
				(type default)
			)
			(layer "F.SilkS")
		)
		(fp_line
			(start -0.787389 0.406267)
			(end -0.787389 -0.406267)
			(stroke
				(width 0.1524)
				(type default)
			)
			(layer "F.SilkS")
		)
		(fp_line
			(start 0.787389 -0.406267)
			(end 0.787389 0.406267)
			(stroke
				(width 0.1524)
				(type default)
			)
			(layer "F.SilkS")
		)
		(fp_line
			(start 0.787389 0.406267)
			(end -0.787389 0.406267)
			(stroke
				(width 0.1524)
				(type default)
			)
			(layer "F.SilkS")
		)
		(fp_line
			(start -0.679446 -0.305149)
			(end -0.120695 -0.304969)
			(stroke
				(width 0.1)
				(type default)
			)
			(layer "F.Fab")
		)
		(fp_line
			(start -0.120695 -0.304969)
			(end -0.120695 -0.279466)
			(stroke
				(width 0.1)
				(type default)
			)
			(layer "F.Fab")
		)
		(fp_line
			(start -0.120695 -0.279466)
			(end 0.120695 -0.279466)
			(stroke
				(width 0.1)
				(type default)
			)
			(layer "F.Fab")
		)
		(fp_line
			(start -0.679446 0.30479)
			(end -0.679446 -0.305149)
			(stroke
				(width 0.1)
				(type default)
			)
			(layer "F.Fab")
		)
		(fp_line
			(start 0.120515 -0.30479)
			(end 0.679446 -0.30479)
			(stroke
				(width 0.1)
				(type default)
			)
			(layer "F.Fab")
		)
		(fp_line
			(start 0.120695 -0.279466)
			(end 0.120515 -0.30479)
			(stroke
				(width 0.1)
				(type default)
			)
			(layer "F.Fab")
		)
		(fp_line
			(start -0.120695 0.279466)
			(end -0.120515 0.30479)
			(stroke
				(width 0.1)
				(type default)
			)
			(layer "F.Fab")
		)
		(fp_line
			(start -0.120515 0.30479)
			(end -0.679446 0.30479)
			(stroke
				(width 0.1)
				(type default)
			)
			(layer "F.Fab")
		)
		(fp_line
			(start 0.679446 -0.30479)
			(end 0.679446 0.30479)
			(stroke
				(width 0.1)
				(type default)
			)
			(layer "F.Fab")
		)
		(fp_line
			(start 0.120335 0.279466)
			(end -0.120695 0.279466)
			(stroke
				(width 0.1)
				(type default)
			)
			(layer "F.Fab")
		)
		(fp_line
			(start 0.120515 0.30479)
			(end 0.120335 0.279466)
			(stroke
				(width 0.1)
				(type default)
			)
			(layer "F.Fab")
		)
		(fp_line
			(start 0.679446 0.30479)
			(end 0.120515 0.30479)
			(stroke
				(width 0.1)
				(type default)
			)
			(layer "F.Fab")
		)
		(pad "1" smd circle
			(at -0.40005 0 45)
			(size 0 0)
			(layers "F.Cu" "F.Mask" "F.Paste")
			(net "GND")
		)
		(pad "2" smd circle
			(at 0.40005 0 45)
			(size 0 0)
			(layers "F.Cu" "F.Mask" "F.Paste")
			(net "PEX3_DBG_SEL1")
		)
	)
	(footprint ""
		(layer "F.Cu")
		(at 430.961546 -121.391172 180)
		(property "Reference" "C662"
			(at 0 0 180)
			(layer "F.SilkS")
			(hide yes)
			(effects
				(font
					(size 1.27 1.27)
				)
			)
		)
		(property "Value" ""
			(at 0 0 180)
			(layer "F.Fab")
			(effects
				(font
					(size 1.27 1.27)
				)
			)
		)
		(duplicate_pad_numbers_are_jumpers no)
		(fp_line
			(start 0.299974 0.150114)
			(end -0.299974 0.150114)
			(stroke
				(width 0.1)
				(type default)
			)
			(layer "F.Fab")
		)
		(fp_line
			(start 0.299974 -0.150114)
			(end 0.299974 0.150114)
			(stroke
				(width 0.1)
				(type default)
			)
			(layer "F.Fab")
		)
		(fp_line
			(start -0.299974 0.150114)
			(end -0.299974 -0.150114)
			(stroke
				(width 0.1)
				(type default)
			)
			(layer "F.Fab")
		)
		(fp_line
			(start -0.299974 -0.150114)
			(end 0.299974 -0.150114)
			(stroke
				(width 0.1)
				(type default)
			)
			(layer "F.Fab")
		)
		(pad "1" smd rect
			(at -0.2667 0 180)
			(size 0.3048 0.381)
			(layers "F.Cu" "F.Mask" "F.Paste")
			(net "P5E_PEX3_STN0_TX_DP<1>")
		)
		(pad "2" smd rect
			(at 0.2667 0 180)
			(size 0.3048 0.381)
			(layers "F.Cu" "F.Mask" "F.Paste")
			(net "P5E_PEX3_STN0_TX_C_DP<1>")
		)
	)
	(footprint ""
		(layer "F.Cu")
		(at 39.280592 -121.919746)
		(property "Reference" "C46"
			(at 0 0 0)
			(layer "F.SilkS")
			(hide yes)
			(effects
				(font
					(size 1.27 1.27)
				)
			)
		)
		(property "Value" ""
			(at 0 0 0)
			(layer "F.Fab")
			(effects
				(font
					(size 1.27 1.27)
				)
			)
		)
		(duplicate_pad_numbers_are_jumpers no)
		(fp_line
			(start -0.299974 -0.150114)
			(end 0.299974 -0.150114)
			(stroke
				(width 0.1)
				(type default)
			)
			(layer "F.Fab")
		)
		(fp_line
			(start -0.299974 0.150114)
			(end -0.299974 -0.150114)
			(stroke
				(width 0.1)
				(type default)
			)
			(layer "F.Fab")
		)
		(fp_line
			(start 0.299974 -0.150114)
			(end 0.299974 0.150114)
			(stroke
				(width 0.1)
				(type default)
			)
			(layer "F.Fab")
		)
		(fp_line
			(start 0.299974 0.150114)
			(end -0.299974 0.150114)
			(stroke
				(width 0.1)
				(type default)
			)
			(layer "F.Fab")
		)
		(pad "1" smd rect
			(at -0.2667 0)
			(size 0.3048 0.381)
			(layers "F.Cu" "F.Mask" "F.Paste")
			(net "P5E_PEX0_STN1_TX_DP<25>")
		)
		(pad "2" smd rect
			(at 0.2667 0)
			(size 0.3048 0.381)
			(layers "F.Cu" "F.Mask" "F.Paste")
			(net "P5E_PEX0_STN1_TX_C_DP<25>")
		)
	)
	(footprint ""
		(layer "F.Cu")
		(at 251.608336 -142.455392 180)
		(property "Reference" "R727"
			(at 0 0 180)
			(layer "F.SilkS")
			(hide yes)
			(effects
				(font
					(size 1.27 1.27)
				)
			)
		)
		(property "Value" ""
			(at 0 0 180)
			(layer "F.Fab")
			(effects
				(font
					(size 1.27 1.27)
				)
			)
		)
		(duplicate_pad_numbers_are_jumpers no)
		(fp_line
			(start 3.937508 1.8796)
			(end 3.937508 -1.8796)
			(stroke
				(width 0.1524)
				(type default)
			)
			(layer "F.SilkS")
		)
		(fp_line
			(start 3.937508 -1.8796)
			(end -3.937508 -1.8796)
			(stroke
				(width 0.1524)
				(type default)
			)
			(layer "F.SilkS")
		)
		(fp_line
			(start -3.937508 1.8796)
			(end 3.937508 1.8796)
			(stroke
				(width 0.1524)
				(type default)
			)
			(layer "F.SilkS")
		)
		(fp_line
			(start -3.937508 -1.8796)
			(end -3.937508 1.8796)
			(stroke
				(width 0.1524)
				(type default)
			)
			(layer "F.SilkS")
		)
		(fp_line
			(start 3.275076 1.674876)
			(end 3.275076 -1.674876)
			(stroke
				(width 0.1)
				(type default)
			)
			(layer "F.Fab")
		)
		(fp_line
			(start 3.275076 -1.674876)
			(end -3.275076 -1.674876)
			(stroke
				(width 0.1)
				(type default)
			)
			(layer "F.Fab")
		)
		(fp_line
			(start -3.275076 1.674876)
			(end 3.275076 1.674876)
			(stroke
				(width 0.1)
				(type default)
			)
			(layer "F.Fab")
		)
		(fp_line
			(start -3.275076 -1.674876)
			(end -3.275076 1.674876)
			(stroke
				(width 0.1)
				(type default)
			)
			(layer "F.Fab")
		)
		(pad "1" smd rect
			(at -2.350008 0 180)
			(size 2.921 3.5052)
			(layers "F.Cu" "F.Mask" "F.Paste")
			(net "P12V_NIC4")
		)
		(pad "2" smd rect
			(at 2.350008 0 180)
			(size 2.921 3.5052)
			(layers "F.Cu" "F.Mask" "F.Paste")
			(net "P12V_NIC4_R")
		)
	)
	(footprint ""
		(layer "F.Cu")
		(at 23.330408 -356.244906 90)
		(property "Reference" "C188"
			(at 0 0 90)
			(layer "F.SilkS")
			(hide yes)
			(effects
				(font
					(size 1.27 1.27)
				)
			)
		)
		(property "Value" ""
			(at 0 0 90)
			(layer "F.Fab")
			(effects
				(font
					(size 1.27 1.27)
				)
			)
		)
		(duplicate_pad_numbers_are_jumpers no)
		(fp_line
			(start 0.299974 -0.150114)
			(end 0.299974 0.150114)
			(stroke
				(width 0.1)
				(type default)
			)
			(layer "F.Fab")
		)
		(fp_line
			(start -0.299974 -0.150114)
			(end 0.299974 -0.150114)
			(stroke
				(width 0.1)
				(type default)
			)
			(layer "F.Fab")
		)
		(fp_line
			(start 0.299974 0.150114)
			(end -0.299974 0.150114)
			(stroke
				(width 0.1)
				(type default)
			)
			(layer "F.Fab")
		)
		(fp_line
			(start -0.299974 0.150114)
			(end -0.299974 -0.150114)
			(stroke
				(width 0.1)
				(type default)
			)
			(layer "F.Fab")
		)
		(pad "1" smd rect
			(at -0.2667 0 90)
			(size 0.3048 0.381)
			(layers "F.Cu" "F.Mask" "F.Paste")
			(net "P5E_PEX0_STN7_TX_DN<114>")
		)
		(pad "2" smd rect
			(at 0.2667 0 90)
			(size 0.3048 0.381)
			(layers "F.Cu" "F.Mask" "F.Paste")
			(net "P5E_PEX0_STN7_TX_C_DN<114>")
		)
	)
	(footprint ""
		(layer "F.Cu")
		(at 274.089622 -343.952322 90)
		(property "Reference" "C2345"
			(at 0 0 90)
			(layer "F.SilkS")
			(hide yes)
			(effects
				(font
					(size 1.27 1.27)
				)
			)
		)
		(property "Value" ""
			(at 0 0 90)
			(layer "F.Fab")
			(effects
				(font
					(size 1.27 1.27)
				)
			)
		)
		(duplicate_pad_numbers_are_jumpers no)
		(fp_line
			(start 0.299974 -0.150114)
			(end 0.299974 0.150114)
			(stroke
				(width 0.1)
				(type default)
			)
			(layer "F.Fab")
		)
		(fp_line
			(start -0.299974 -0.150114)
			(end 0.299974 -0.150114)
			(stroke
				(width 0.1)
				(type default)
			)
			(layer "F.Fab")
		)
		(fp_line
			(start 0.299974 0.150114)
			(end -0.299974 0.150114)
			(stroke
				(width 0.1)
				(type default)
			)
			(layer "F.Fab")
		)
		(fp_line
			(start -0.299974 0.150114)
			(end -0.299974 -0.150114)
			(stroke
				(width 0.1)
				(type default)
			)
			(layer "F.Fab")
		)
		(pad "1" smd rect
			(at -0.2667 0 90)
			(size 0.3048 0.381)
			(layers "F.Cu" "F.Mask" "F.Paste")
			(net "P5E_PEX2_STN4_TX_DP<77>")
		)
		(pad "2" smd rect
			(at 0.2667 0 90)
			(size 0.3048 0.381)
			(layers "F.Cu" "F.Mask" "F.Paste")
			(net "P5E_PEX2_STN4_TX_C_DP<77>")
		)
	)
	(footprint ""
		(layer "F.Cu")
		(at 364.809532 -357.96601 90)
		(property "Reference" "C4168"
			(at 0 0 90)
			(layer "F.SilkS")
			(hide yes)
			(effects
				(font
					(size 1.27 1.27)
				)
			)
		)
		(property "Value" ""
			(at 0 0 90)
			(layer "F.Fab")
			(effects
				(font
					(size 1.27 1.27)
				)
			)
		)
		(duplicate_pad_numbers_are_jumpers no)
		(fp_line
			(start 0.7874 -0.4064)
			(end 0.7874 0.4064)
			(stroke
				(width 0.1524)
				(type default)
			)
			(layer "F.SilkS")
		)
		(fp_line
			(start -0.7874 -0.4064)
			(end 0.7874 -0.4064)
			(stroke
				(width 0.1524)
				(type default)
			)
			(layer "F.SilkS")
		)
		(fp_line
			(start 0.7874 0.4064)
			(end -0.7874 0.4064)
			(stroke
				(width 0.1524)
				(type default)
			)
			(layer "F.SilkS")
		)
		(fp_line
			(start -0.7874 0.4064)
			(end -0.7874 -0.4064)
			(stroke
				(width 0.1524)
				(type default)
			)
			(layer "F.SilkS")
		)
		(fp_line
			(start -0.12065 -0.305054)
			(end -0.12065 -0.2794)
			(stroke
				(width 0.1)
				(type default)
			)
			(layer "F.Fab")
		)
		(fp_line
			(start -0.67945 -0.305054)
			(end -0.12065 -0.305054)
			(stroke
				(width 0.1)
				(type default)
			)
			(layer "F.Fab")
		)
		(fp_line
			(start 0.67945 -0.3048)
			(end 0.67945 0.3048)
			(stroke
				(width 0.1)
				(type default)
			)
			(layer "F.Fab")
		)
		(fp_line
			(start 0.12065 -0.3048)
			(end 0.67945 -0.3048)
			(stroke
				(width 0.1)
				(type default)
			)
			(layer "F.Fab")
		)
		(fp_line
			(start 0.12065 -0.2794)
			(end 0.12065 -0.3048)
			(stroke
				(width 0.1)
				(type default)
			)
			(layer "F.Fab")
		)
		(fp_line
			(start -0.12065 -0.2794)
			(end 0.12065 -0.2794)
			(stroke
				(width 0.1)
				(type default)
			)
			(layer "F.Fab")
		)
		(fp_line
			(start 0.120396 0.2794)
			(end -0.12065 0.2794)
			(stroke
				(width 0.1)
				(type default)
			)
			(layer "F.Fab")
		)
		(fp_line
			(start -0.12065 0.2794)
			(end -0.12065 0.3048)
			(stroke
				(width 0.1)
				(type default)
			)
			(layer "F.Fab")
		)
		(fp_line
			(start 0.67945 0.3048)
			(end 0.120396 0.3048)
			(stroke
				(width 0.1)
				(type default)
			)
			(layer "F.Fab")
		)
		(fp_line
			(start 0.120396 0.3048)
			(end 0.120396 0.2794)
			(stroke
				(width 0.1)
				(type default)
			)
			(layer "F.Fab")
		)
		(fp_line
			(start -0.12065 0.3048)
			(end -0.67945 0.3048)
			(stroke
				(width 0.1)
				(type default)
			)
			(layer "F.Fab")
		)
		(fp_line
			(start -0.67945 0.3048)
			(end -0.67945 -0.305054)
			(stroke
				(width 0.1)
				(type default)
			)
			(layer "F.Fab")
		)
		(pad "1" smd circle
			(at -0.40005 0 90)
			(size 0 0)
			(layers "F.Cu" "F.Mask" "F.Paste")
			(net "GND")
		)
		(pad "2" smd circle
			(at 0.40005 0 90)
			(size 0 0)
			(layers "F.Cu" "F.Mask" "F.Paste")
			(net "RST_MB_BIC_N")
		)
	)
	(footprint ""
		(layer "F.Cu")
		(at 154.860244 -116.7384)
		(property "Reference" "R141"
			(at 0 0 0)
			(layer "F.SilkS")
			(hide yes)
			(effects
				(font
					(size 1.27 1.27)
				)
			)
		)
		(property "Value" ""
			(at 0 0 0)
			(layer "F.Fab")
			(effects
				(font
					(size 1.27 1.27)
				)
			)
		)
		(duplicate_pad_numbers_are_jumpers no)
		(fp_line
			(start -0.7874 -0.4064)
			(end 0.7874 -0.4064)
			(stroke
				(width 0.1524)
				(type default)
			)
			(layer "F.SilkS")
		)
		(fp_line
			(start -0.7874 0.4064)
			(end -0.7874 -0.4064)
			(stroke
				(width 0.1524)
				(type default)
			)
			(layer "F.SilkS")
		)
		(fp_line
			(start 0.7874 -0.4064)
			(end 0.7874 0.4064)
			(stroke
				(width 0.1524)
				(type default)
			)
			(layer "F.SilkS")
		)
		(fp_line
			(start 0.7874 0.4064)
			(end -0.7874 0.4064)
			(stroke
				(width 0.1524)
				(type default)
			)
			(layer "F.SilkS")
		)
		(fp_line
			(start -0.67945 -0.305054)
			(end -0.12065 -0.305054)
			(stroke
				(width 0.1)
				(type default)
			)
			(layer "F.Fab")
		)
		(fp_line
			(start -0.67945 0.3048)
			(end -0.67945 -0.305054)
			(stroke
				(width 0.1)
				(type default)
			)
			(layer "F.Fab")
		)
		(fp_line
			(start -0.12065 -0.305054)
			(end -0.12065 -0.2794)
			(stroke
				(width 0.1)
				(type default)
			)
			(layer "F.Fab")
		)
		(fp_line
			(start -0.12065 -0.2794)
			(end 0.12065 -0.2794)
			(stroke
				(width 0.1)
				(type default)
			)
			(layer "F.Fab")
		)
		(fp_line
			(start -0.12065 0.2794)
			(end -0.12065 0.3048)
			(stroke
				(width 0.1)
				(type default)
			)
			(layer "F.Fab")
		)
		(fp_line
			(start -0.12065 0.3048)
			(end -0.67945 0.3048)
			(stroke
				(width 0.1)
				(type default)
			)
			(layer "F.Fab")
		)
		(fp_line
			(start 0.120396 0.2794)
			(end -0.12065 0.2794)
			(stroke
				(width 0.1)
				(type default)
			)
			(layer "F.Fab")
		)
		(fp_line
			(start 0.120396 0.3048)
			(end 0.120396 0.2794)
			(stroke
				(width 0.1)
				(type default)
			)
			(layer "F.Fab")
		)
		(fp_line
			(start 0.12065 -0.3048)
			(end 0.67945 -0.3048)
			(stroke
				(width 0.1)
				(type default)
			)
			(layer "F.Fab")
		)
		(fp_line
			(start 0.12065 -0.2794)
			(end 0.12065 -0.3048)
			(stroke
				(width 0.1)
				(type default)
			)
			(layer "F.Fab")
		)
		(fp_line
			(start 0.67945 -0.3048)
			(end 0.67945 0.3048)
			(stroke
				(width 0.1)
				(type default)
			)
			(layer "F.Fab")
		)
		(fp_line
			(start 0.67945 0.3048)
			(end 0.120396 0.3048)
			(stroke
				(width 0.1)
				(type default)
			)
			(layer "F.Fab")
		)
		(pad "1" smd circle
			(at -0.40005 0)
			(size 0 0)
			(layers "F.Cu" "F.Mask" "F.Paste")
			(net "PRSNT_NIC2_N")
		)
		(pad "2" smd circle
			(at 0.40005 0)
			(size 0 0)
			(layers "F.Cu" "F.Mask" "F.Paste")
			(net "PRSNTB0_NIC2_N")
		)
	)
	(footprint ""
		(layer "F.Cu")
		(at 219.825316 -121.742962 180)
		(property "Reference" "R5959"
			(at 0 0 180)
			(layer "F.SilkS")
			(hide yes)
			(effects
				(font
					(size 1.27 1.27)
				)
			)
		)
		(property "Value" ""
			(at 0 0 180)
			(layer "F.Fab")
			(effects
				(font
					(size 1.27 1.27)
				)
			)
		)
		(duplicate_pad_numbers_are_jumpers no)
		(fp_line
			(start 0.7874 0.4064)
			(end -0.7874 0.4064)
			(stroke
				(width 0.1524)
				(type default)
			)
			(layer "F.SilkS")
		)
		(fp_line
			(start 0.7874 -0.4064)
			(end 0.7874 0.4064)
			(stroke
				(width 0.1524)
				(type default)
			)
			(layer "F.SilkS")
		)
		(fp_line
			(start -0.7874 0.4064)
			(end -0.7874 -0.4064)
			(stroke
				(width 0.1524)
				(type default)
			)
			(layer "F.SilkS")
		)
		(fp_line
			(start -0.7874 -0.4064)
			(end 0.7874 -0.4064)
			(stroke
				(width 0.1524)
				(type default)
			)
			(layer "F.SilkS")
		)
		(fp_line
			(start 0.67945 0.3048)
			(end 0.120396 0.3048)
			(stroke
				(width 0.1)
				(type default)
			)
			(layer "F.Fab")
		)
		(fp_line
			(start 0.67945 -0.3048)
			(end 0.67945 0.3048)
			(stroke
				(width 0.1)
				(type default)
			)
			(layer "F.Fab")
		)
		(fp_line
			(start 0.12065 -0.2794)
			(end 0.12065 -0.3048)
			(stroke
				(width 0.1)
				(type default)
			)
			(layer "F.Fab")
		)
		(fp_line
			(start 0.12065 -0.3048)
			(end 0.67945 -0.3048)
			(stroke
				(width 0.1)
				(type default)
			)
			(layer "F.Fab")
		)
		(fp_line
			(start 0.120396 0.3048)
			(end 0.120396 0.2794)
			(stroke
				(width 0.1)
				(type default)
			)
			(layer "F.Fab")
		)
		(fp_line
			(start 0.120396 0.2794)
			(end -0.12065 0.2794)
			(stroke
				(width 0.1)
				(type default)
			)
			(layer "F.Fab")
		)
		(fp_line
			(start -0.12065 0.3048)
			(end -0.67945 0.3048)
			(stroke
				(width 0.1)
				(type default)
			)
			(layer "F.Fab")
		)
		(fp_line
			(start -0.12065 0.2794)
			(end -0.12065 0.3048)
			(stroke
				(width 0.1)
				(type default)
			)
			(layer "F.Fab")
		)
		(fp_line
			(start -0.12065 -0.2794)
			(end 0.12065 -0.2794)
			(stroke
				(width 0.1)
				(type default)
			)
			(layer "F.Fab")
		)
		(fp_line
			(start -0.12065 -0.305054)
			(end -0.12065 -0.2794)
			(stroke
				(width 0.1)
				(type default)
			)
			(layer "F.Fab")
		)
		(fp_line
			(start -0.67945 0.3048)
			(end -0.67945 -0.305054)
			(stroke
				(width 0.1)
				(type default)
			)
			(layer "F.Fab")
		)
		(fp_line
			(start -0.67945 -0.305054)
			(end -0.12065 -0.305054)
			(stroke
				(width 0.1)
				(type default)
			)
			(layer "F.Fab")
		)
		(pad "1" smd circle
			(at -0.40005 0 180)
			(size 0 0)
			(layers "F.Cu" "F.Mask" "F.Paste")
			(net "PWRGD_P3V3_NIC3_D")
		)
		(pad "2" smd circle
			(at 0.40005 0 180)
			(size 0 0)
			(layers "F.Cu" "F.Mask" "F.Paste")
			(net "PWRGD_P3V3_NIC3_R")
		)
	)
	(footprint ""
		(layer "F.Cu")
		(at 63.6778 -116.550186 180)
		(property "Reference" "R58"
			(at 0 0 180)
			(layer "F.SilkS")
			(hide yes)
			(effects
				(font
					(size 1.27 1.27)
				)
			)
		)
		(property "Value" ""
			(at 0 0 180)
			(layer "F.Fab")
			(effects
				(font
					(size 1.27 1.27)
				)
			)
		)
		(duplicate_pad_numbers_are_jumpers no)
		(fp_line
			(start 0.7874 0.4064)
			(end -0.7874 0.4064)
			(stroke
				(width 0.1524)
				(type default)
			)
			(layer "F.SilkS")
		)
		(fp_line
			(start 0.7874 -0.4064)
			(end 0.7874 0.4064)
			(stroke
				(width 0.1524)
				(type default)
			)
			(layer "F.SilkS")
		)
		(fp_line
			(start -0.7874 0.4064)
			(end -0.7874 -0.4064)
			(stroke
				(width 0.1524)
				(type default)
			)
			(layer "F.SilkS")
		)
		(fp_line
			(start -0.7874 -0.4064)
			(end 0.7874 -0.4064)
			(stroke
				(width 0.1524)
				(type default)
			)
			(layer "F.SilkS")
		)
		(fp_line
			(start 0.67945 0.3048)
			(end 0.120396 0.3048)
			(stroke
				(width 0.1)
				(type default)
			)
			(layer "F.Fab")
		)
		(fp_line
			(start 0.67945 -0.3048)
			(end 0.67945 0.3048)
			(stroke
				(width 0.1)
				(type default)
			)
			(layer "F.Fab")
		)
		(fp_line
			(start 0.12065 -0.2794)
			(end 0.12065 -0.3048)
			(stroke
				(width 0.1)
				(type default)
			)
			(layer "F.Fab")
		)
		(fp_line
			(start 0.12065 -0.3048)
			(end 0.67945 -0.3048)
			(stroke
				(width 0.1)
				(type default)
			)
			(layer "F.Fab")
		)
		(fp_line
			(start 0.120396 0.3048)
			(end 0.120396 0.2794)
			(stroke
				(width 0.1)
				(type default)
			)
			(layer "F.Fab")
		)
		(fp_line
			(start 0.120396 0.2794)
			(end -0.12065 0.2794)
			(stroke
				(width 0.1)
				(type default)
			)
			(layer "F.Fab")
		)
		(fp_line
			(start -0.12065 0.3048)
			(end -0.67945 0.3048)
			(stroke
				(width 0.1)
				(type default)
			)
			(layer "F.Fab")
		)
		(fp_line
			(start -0.12065 0.2794)
			(end -0.12065 0.3048)
			(stroke
				(width 0.1)
				(type default)
			)
			(layer "F.Fab")
		)
		(fp_line
			(start -0.12065 -0.2794)
			(end 0.12065 -0.2794)
			(stroke
				(width 0.1)
				(type default)
			)
			(layer "F.Fab")
		)
		(fp_line
			(start -0.12065 -0.305054)
			(end -0.12065 -0.2794)
			(stroke
				(width 0.1)
				(type default)
			)
			(layer "F.Fab")
		)
		(fp_line
			(start -0.67945 0.3048)
			(end -0.67945 -0.305054)
			(stroke
				(width 0.1)
				(type default)
			)
			(layer "F.Fab")
		)
		(fp_line
			(start -0.67945 -0.305054)
			(end -0.12065 -0.305054)
			(stroke
				(width 0.1)
				(type default)
			)
			(layer "F.Fab")
		)
		(pad "1" smd circle
			(at -0.40005 0 180)
			(size 0 0)
			(layers "F.Cu" "F.Mask" "F.Paste")
			(net "PRSNTB2_NIC1_N")
		)
		(pad "2" smd circle
			(at 0.40005 0 180)
			(size 0 0)
			(layers "F.Cu" "F.Mask" "F.Paste")
			(net "P3V3_AUX")
		)
	)
	(footprint ""
		(layer "F.Cu")
		(at 105.951782 -108.054902 180)
		(property "Reference" "PC618"
			(at 0 0 180)
			(layer "F.SilkS")
			(hide yes)
			(effects
				(font
					(size 1.27 1.27)
				)
			)
		)
		(property "Value" ""
			(at 0 0 180)
			(layer "F.Fab")
			(effects
				(font
					(size 1.27 1.27)
				)
			)
		)
		(duplicate_pad_numbers_are_jumpers no)
		(fp_line
			(start 0.7874 0.4064)
			(end -0.7874 0.4064)
			(stroke
				(width 0.1524)
				(type default)
			)
			(layer "F.SilkS")
		)
		(fp_line
			(start 0.7874 -0.4064)
			(end 0.7874 0.4064)
			(stroke
				(width 0.1524)
				(type default)
			)
			(layer "F.SilkS")
		)
		(fp_line
			(start -0.7874 0.4064)
			(end -0.7874 -0.4064)
			(stroke
				(width 0.1524)
				(type default)
			)
			(layer "F.SilkS")
		)
		(fp_line
			(start -0.7874 -0.4064)
			(end 0.7874 -0.4064)
			(stroke
				(width 0.1524)
				(type default)
			)
			(layer "F.SilkS")
		)
		(fp_line
			(start 0.67945 0.3048)
			(end 0.120396 0.3048)
			(stroke
				(width 0.1)
				(type default)
			)
			(layer "F.Fab")
		)
		(fp_line
			(start 0.67945 -0.3048)
			(end 0.67945 0.3048)
			(stroke
				(width 0.1)
				(type default)
			)
			(layer "F.Fab")
		)
		(fp_line
			(start 0.12065 -0.2794)
			(end 0.12065 -0.3048)
			(stroke
				(width 0.1)
				(type default)
			)
			(layer "F.Fab")
		)
		(fp_line
			(start 0.12065 -0.3048)
			(end 0.67945 -0.3048)
			(stroke
				(width 0.1)
				(type default)
			)
			(layer "F.Fab")
		)
		(fp_line
			(start 0.120396 0.3048)
			(end 0.120396 0.2794)
			(stroke
				(width 0.1)
				(type default)
			)
			(layer "F.Fab")
		)
		(fp_line
			(start 0.120396 0.2794)
			(end -0.12065 0.2794)
			(stroke
				(width 0.1)
				(type default)
			)
			(layer "F.Fab")
		)
		(fp_line
			(start -0.12065 0.3048)
			(end -0.67945 0.3048)
			(stroke
				(width 0.1)
				(type default)
			)
			(layer "F.Fab")
		)
		(fp_line
			(start -0.12065 0.2794)
			(end -0.12065 0.3048)
			(stroke
				(width 0.1)
				(type default)
			)
			(layer "F.Fab")
		)
		(fp_line
			(start -0.12065 -0.2794)
			(end 0.12065 -0.2794)
			(stroke
				(width 0.1)
				(type default)
			)
			(layer "F.Fab")
		)
		(fp_line
			(start -0.12065 -0.305054)
			(end -0.12065 -0.2794)
			(stroke
				(width 0.1)
				(type default)
			)
			(layer "F.Fab")
		)
		(fp_line
			(start -0.67945 0.3048)
			(end -0.67945 -0.305054)
			(stroke
				(width 0.1)
				(type default)
			)
			(layer "F.Fab")
		)
		(fp_line
			(start -0.67945 -0.305054)
			(end -0.12065 -0.305054)
			(stroke
				(width 0.1)
				(type default)
			)
			(layer "F.Fab")
		)
		(pad "1" smd circle
			(at -0.40005 0 180)
			(size 0 0)
			(layers "F.Cu" "F.Mask" "F.Paste")
			(net "P12V_AUX")
		)
		(pad "2" smd circle
			(at 0.40005 0 180)
			(size 0 0)
			(layers "F.Cu" "F.Mask" "F.Paste")
			(net "GND")
		)
	)
	(footprint ""
		(layer "F.Cu")
		(at 196.119242 -118.670324 180)
		(property "Reference" "C243"
			(at 0 0 180)
			(layer "F.SilkS")
			(hide yes)
			(effects
				(font
					(size 1.27 1.27)
				)
			)
		)
		(property "Value" ""
			(at 0 0 180)
			(layer "F.Fab")
			(effects
				(font
					(size 1.27 1.27)
				)
			)
		)
		(duplicate_pad_numbers_are_jumpers no)
		(fp_line
			(start 0.299974 0.150114)
			(end -0.299974 0.150114)
			(stroke
				(width 0.1)
				(type default)
			)
			(layer "F.Fab")
		)
		(fp_line
			(start 0.299974 -0.150114)
			(end 0.299974 0.150114)
			(stroke
				(width 0.1)
				(type default)
			)
			(layer "F.Fab")
		)
		(fp_line
			(start -0.299974 0.150114)
			(end -0.299974 -0.150114)
			(stroke
				(width 0.1)
				(type default)
			)
			(layer "F.Fab")
		)
		(fp_line
			(start -0.299974 -0.150114)
			(end 0.299974 -0.150114)
			(stroke
				(width 0.1)
				(type default)
			)
			(layer "F.Fab")
		)
		(pad "1" smd rect
			(at -0.2667 0 180)
			(size 0.3048 0.381)
			(layers "F.Cu" "F.Mask" "F.Paste")
			(net "P5E_PEX1_STN0_TX_DN<0>")
		)
		(pad "2" smd rect
			(at 0.2667 0 180)
			(size 0.3048 0.381)
			(layers "F.Cu" "F.Mask" "F.Paste")
			(net "P5E_PEX1_STN0_TX_C_DN<0>")
		)
	)
	(footprint ""
		(layer "F.Cu")
		(at 62.709044 -212.5472 180)
		(property "Reference" "R6636"
			(at 0 0 180)
			(layer "F.SilkS")
			(hide yes)
			(effects
				(font
					(size 1.27 1.27)
				)
			)
		)
		(property "Value" ""
			(at 0 0 180)
			(layer "F.Fab")
			(effects
				(font
					(size 1.27 1.27)
				)
			)
		)
		(duplicate_pad_numbers_are_jumpers no)
		(fp_line
			(start 0.7874 0.4064)
			(end -0.7874 0.4064)
			(stroke
				(width 0.1524)
				(type default)
			)
			(layer "F.SilkS")
		)
		(fp_line
			(start 0.7874 -0.4064)
			(end 0.7874 0.4064)
			(stroke
				(width 0.1524)
				(type default)
			)
			(layer "F.SilkS")
		)
		(fp_line
			(start -0.7874 0.4064)
			(end -0.7874 -0.4064)
			(stroke
				(width 0.1524)
				(type default)
			)
			(layer "F.SilkS")
		)
		(fp_line
			(start -0.7874 -0.4064)
			(end 0.7874 -0.4064)
			(stroke
				(width 0.1524)
				(type default)
			)
			(layer "F.SilkS")
		)
		(fp_line
			(start 0.67945 0.3048)
			(end 0.120396 0.3048)
			(stroke
				(width 0.1)
				(type default)
			)
			(layer "F.Fab")
		)
		(fp_line
			(start 0.67945 -0.3048)
			(end 0.67945 0.3048)
			(stroke
				(width 0.1)
				(type default)
			)
			(layer "F.Fab")
		)
		(fp_line
			(start 0.12065 -0.2794)
			(end 0.12065 -0.3048)
			(stroke
				(width 0.1)
				(type default)
			)
			(layer "F.Fab")
		)
		(fp_line
			(start 0.12065 -0.3048)
			(end 0.67945 -0.3048)
			(stroke
				(width 0.1)
				(type default)
			)
			(layer "F.Fab")
		)
		(fp_line
			(start 0.120396 0.3048)
			(end 0.120396 0.2794)
			(stroke
				(width 0.1)
				(type default)
			)
			(layer "F.Fab")
		)
		(fp_line
			(start 0.120396 0.2794)
			(end -0.12065 0.2794)
			(stroke
				(width 0.1)
				(type default)
			)
			(layer "F.Fab")
		)
		(fp_line
			(start -0.12065 0.3048)
			(end -0.67945 0.3048)
			(stroke
				(width 0.1)
				(type default)
			)
			(layer "F.Fab")
		)
		(fp_line
			(start -0.12065 0.2794)
			(end -0.12065 0.3048)
			(stroke
				(width 0.1)
				(type default)
			)
			(layer "F.Fab")
		)
		(fp_line
			(start -0.12065 -0.2794)
			(end 0.12065 -0.2794)
			(stroke
				(width 0.1)
				(type default)
			)
			(layer "F.Fab")
		)
		(fp_line
			(start -0.12065 -0.305054)
			(end -0.12065 -0.2794)
			(stroke
				(width 0.1)
				(type default)
			)
			(layer "F.Fab")
		)
		(fp_line
			(start -0.67945 0.3048)
			(end -0.67945 -0.305054)
			(stroke
				(width 0.1)
				(type default)
			)
			(layer "F.Fab")
		)
		(fp_line
			(start -0.67945 -0.305054)
			(end -0.12065 -0.305054)
			(stroke
				(width 0.1)
				(type default)
			)
			(layer "F.Fab")
		)
		(pad "1" smd circle
			(at -0.40005 0 180)
			(size 0 0)
			(layers "F.Cu" "F.Mask" "F.Paste")
			(net "UART_PEX2_CLI_BUF_R_TX")
		)
		(pad "2" smd circle
			(at 0.40005 0 180)
			(size 0 0)
			(layers "F.Cu" "F.Mask" "F.Paste")
			(net "UART_PEX2_CLI_BUF_R1_TX")
		)
	)
	(footprint ""
		(layer "F.Cu")
		(at 404.28164 -158.8516)
		(property "Reference" "R353"
			(at 0 0 0)
			(layer "F.SilkS")
			(hide yes)
			(effects
				(font
					(size 1.27 1.27)
				)
			)
		)
		(property "Value" ""
			(at 0 0 0)
			(layer "F.Fab")
			(effects
				(font
					(size 1.27 1.27)
				)
			)
		)
		(duplicate_pad_numbers_are_jumpers no)
		(fp_line
			(start -0.7874 -0.4064)
			(end 0.7874 -0.4064)
			(stroke
				(width 0.1524)
				(type default)
			)
			(layer "F.SilkS")
		)
		(fp_line
			(start -0.7874 0.4064)
			(end -0.7874 -0.4064)
			(stroke
				(width 0.1524)
				(type default)
			)
			(layer "F.SilkS")
		)
		(fp_line
			(start 0.7874 -0.4064)
			(end 0.7874 0.4064)
			(stroke
				(width 0.1524)
				(type default)
			)
			(layer "F.SilkS")
		)
		(fp_line
			(start 0.7874 0.4064)
			(end -0.7874 0.4064)
			(stroke
				(width 0.1524)
				(type default)
			)
			(layer "F.SilkS")
		)
		(fp_line
			(start -0.67945 -0.305054)
			(end -0.12065 -0.305054)
			(stroke
				(width 0.1)
				(type default)
			)
			(layer "F.Fab")
		)
		(fp_line
			(start -0.67945 0.3048)
			(end -0.67945 -0.305054)
			(stroke
				(width 0.1)
				(type default)
			)
			(layer "F.Fab")
		)
		(fp_line
			(start -0.12065 -0.305054)
			(end -0.12065 -0.2794)
			(stroke
				(width 0.1)
				(type default)
			)
			(layer "F.Fab")
		)
		(fp_line
			(start -0.12065 -0.2794)
			(end 0.12065 -0.2794)
			(stroke
				(width 0.1)
				(type default)
			)
			(layer "F.Fab")
		)
		(fp_line
			(start -0.12065 0.2794)
			(end -0.12065 0.3048)
			(stroke
				(width 0.1)
				(type default)
			)
			(layer "F.Fab")
		)
		(fp_line
			(start -0.12065 0.3048)
			(end -0.67945 0.3048)
			(stroke
				(width 0.1)
				(type default)
			)
			(layer "F.Fab")
		)
		(fp_line
			(start 0.120396 0.2794)
			(end -0.12065 0.2794)
			(stroke
				(width 0.1)
				(type default)
			)
			(layer "F.Fab")
		)
		(fp_line
			(start 0.120396 0.3048)
			(end 0.120396 0.2794)
			(stroke
				(width 0.1)
				(type default)
			)
			(layer "F.Fab")
		)
		(fp_line
			(start 0.12065 -0.3048)
			(end 0.67945 -0.3048)
			(stroke
				(width 0.1)
				(type default)
			)
			(layer "F.Fab")
		)
		(fp_line
			(start 0.12065 -0.2794)
			(end 0.12065 -0.3048)
			(stroke
				(width 0.1)
				(type default)
			)
			(layer "F.Fab")
		)
		(fp_line
			(start 0.67945 -0.3048)
			(end 0.67945 0.3048)
			(stroke
				(width 0.1)
				(type default)
			)
			(layer "F.Fab")
		)
		(fp_line
			(start 0.67945 0.3048)
			(end 0.120396 0.3048)
			(stroke
				(width 0.1)
				(type default)
			)
			(layer "F.Fab")
		)
		(pad "1" smd circle
			(at -0.40005 0)
			(size 0 0)
			(layers "F.Cu" "F.Mask" "F.Paste")
			(net "RST_NIC6_PERST2_R_N")
		)
		(pad "2" smd circle
			(at 0.40005 0)
			(size 0 0)
			(layers "F.Cu" "F.Mask" "F.Paste")
			(net "RST_HP_NIC6_BUF_N")
		)
	)
	(footprint ""
		(layer "F.Cu")
		(at 85.53577 -289.230816 -90)
		(property "Reference" "R6388"
			(at 0 0 270)
			(layer "F.SilkS")
			(hide yes)
			(effects
				(font
					(size 1.27 1.27)
				)
			)
		)
		(property "Value" ""
			(at 0 0 270)
			(layer "F.Fab")
			(effects
				(font
					(size 1.27 1.27)
				)
			)
		)
		(duplicate_pad_numbers_are_jumpers no)
		(fp_line
			(start -0.7874 0.4064)
			(end -0.7874 -0.4064)
			(stroke
				(width 0.1524)
				(type default)
			)
			(layer "F.SilkS")
		)
		(fp_line
			(start 0.7874 0.4064)
			(end -0.7874 0.4064)
			(stroke
				(width 0.1524)
				(type default)
			)
			(layer "F.SilkS")
		)
		(fp_line
			(start -0.7874 -0.4064)
			(end 0.7874 -0.4064)
			(stroke
				(width 0.1524)
				(type default)
			)
			(layer "F.SilkS")
		)
		(fp_line
			(start 0.7874 -0.4064)
			(end 0.7874 0.4064)
			(stroke
				(width 0.1524)
				(type default)
			)
			(layer "F.SilkS")
		)
		(fp_line
			(start -0.67945 0.3048)
			(end -0.67945 -0.305054)
			(stroke
				(width 0.1)
				(type default)
			)
			(layer "F.Fab")
		)
		(fp_line
			(start -0.12065 0.3048)
			(end -0.67945 0.3048)
			(stroke
				(width 0.1)
				(type default)
			)
			(layer "F.Fab")
		)
		(fp_line
			(start 0.120396 0.3048)
			(end 0.120396 0.2794)
			(stroke
				(width 0.1)
				(type default)
			)
			(layer "F.Fab")
		)
		(fp_line
			(start 0.67945 0.3048)
			(end 0.120396 0.3048)
			(stroke
				(width 0.1)
				(type default)
			)
			(layer "F.Fab")
		)
		(fp_line
			(start -0.12065 0.2794)
			(end -0.12065 0.3048)
			(stroke
				(width 0.1)
				(type default)
			)
			(layer "F.Fab")
		)
		(fp_line
			(start 0.120396 0.2794)
			(end -0.12065 0.2794)
			(stroke
				(width 0.1)
				(type default)
			)
			(layer "F.Fab")
		)
		(fp_line
			(start -0.12065 -0.2794)
			(end 0.12065 -0.2794)
			(stroke
				(width 0.1)
				(type default)
			)
			(layer "F.Fab")
		)
		(fp_line
			(start 0.12065 -0.2794)
			(end 0.12065 -0.3048)
			(stroke
				(width 0.1)
				(type default)
			)
			(layer "F.Fab")
		)
		(fp_line
			(start 0.12065 -0.3048)
			(end 0.67945 -0.3048)
			(stroke
				(width 0.1)
				(type default)
			)
			(layer "F.Fab")
		)
		(fp_line
			(start 0.67945 -0.3048)
			(end 0.67945 0.3048)
			(stroke
				(width 0.1)
				(type default)
			)
			(layer "F.Fab")
		)
		(fp_line
			(start -0.67945 -0.305054)
			(end -0.12065 -0.305054)
			(stroke
				(width 0.1)
				(type default)
			)
			(layer "F.Fab")
		)
		(fp_line
			(start -0.12065 -0.305054)
			(end -0.12065 -0.2794)
			(stroke
				(width 0.1)
				(type default)
			)
			(layer "F.Fab")
		)
		(pad "1" smd circle
			(at -0.40005 0 270)
			(size 0 0)
			(layers "F.Cu" "F.Mask" "F.Paste")
			(net "RST_PEX0_S0_PERST_N")
		)
		(pad "2" smd circle
			(at 0.40005 0 270)
			(size 0 0)
			(layers "F.Cu" "F.Mask" "F.Paste")
			(net "RST_PEX0_S0_PERST_R_N")
		)
	)
	(footprint ""
		(layer "F.Cu")
		(at 83.866736 -52.543456 180)
		(property "Reference" "PC538"
			(at 0 0 180)
			(layer "F.SilkS")
			(hide yes)
			(effects
				(font
					(size 1.27 1.27)
				)
			)
		)
		(property "Value" ""
			(at 0 0 180)
			(layer "F.Fab")
			(effects
				(font
					(size 1.27 1.27)
				)
			)
		)
		(duplicate_pad_numbers_are_jumpers no)
		(fp_line
			(start 0.7874 0.4064)
			(end -0.7874 0.4064)
			(stroke
				(width 0.1524)
				(type default)
			)
			(layer "F.SilkS")
		)
		(fp_line
			(start 0.7874 -0.4064)
			(end 0.7874 0.4064)
			(stroke
				(width 0.1524)
				(type default)
			)
			(layer "F.SilkS")
		)
		(fp_line
			(start -0.7874 0.4064)
			(end -0.7874 -0.4064)
			(stroke
				(width 0.1524)
				(type default)
			)
			(layer "F.SilkS")
		)
		(fp_line
			(start -0.7874 -0.4064)
			(end 0.7874 -0.4064)
			(stroke
				(width 0.1524)
				(type default)
			)
			(layer "F.SilkS")
		)
		(fp_line
			(start 0.67945 0.3048)
			(end 0.120396 0.3048)
			(stroke
				(width 0.1)
				(type default)
			)
			(layer "F.Fab")
		)
		(fp_line
			(start 0.67945 -0.3048)
			(end 0.67945 0.3048)
			(stroke
				(width 0.1)
				(type default)
			)
			(layer "F.Fab")
		)
		(fp_line
			(start 0.12065 -0.2794)
			(end 0.12065 -0.3048)
			(stroke
				(width 0.1)
				(type default)
			)
			(layer "F.Fab")
		)
		(fp_line
			(start 0.12065 -0.3048)
			(end 0.67945 -0.3048)
			(stroke
				(width 0.1)
				(type default)
			)
			(layer "F.Fab")
		)
		(fp_line
			(start 0.120396 0.3048)
			(end 0.120396 0.2794)
			(stroke
				(width 0.1)
				(type default)
			)
			(layer "F.Fab")
		)
		(fp_line
			(start 0.120396 0.2794)
			(end -0.12065 0.2794)
			(stroke
				(width 0.1)
				(type default)
			)
			(layer "F.Fab")
		)
		(fp_line
			(start -0.12065 0.3048)
			(end -0.67945 0.3048)
			(stroke
				(width 0.1)
				(type default)
			)
			(layer "F.Fab")
		)
		(fp_line
			(start -0.12065 0.2794)
			(end -0.12065 0.3048)
			(stroke
				(width 0.1)
				(type default)
			)
			(layer "F.Fab")
		)
		(fp_line
			(start -0.12065 -0.2794)
			(end 0.12065 -0.2794)
			(stroke
				(width 0.1)
				(type default)
			)
			(layer "F.Fab")
		)
		(fp_line
			(start -0.12065 -0.305054)
			(end -0.12065 -0.2794)
			(stroke
				(width 0.1)
				(type default)
			)
			(layer "F.Fab")
		)
		(fp_line
			(start -0.67945 0.3048)
			(end -0.67945 -0.305054)
			(stroke
				(width 0.1)
				(type default)
			)
			(layer "F.Fab")
		)
		(fp_line
			(start -0.67945 -0.305054)
			(end -0.12065 -0.305054)
			(stroke
				(width 0.1)
				(type default)
			)
			(layer "F.Fab")
		)
		(pad "1" smd circle
			(at -0.40005 0 180)
			(size 0 0)
			(layers "F.Cu" "F.Mask" "F.Paste")
			(net "P3V3_SSD3")
		)
		(pad "2" smd circle
			(at 0.40005 0 180)
			(size 0 0)
			(layers "F.Cu" "F.Mask" "F.Paste")
			(net "GND")
		)
	)
	(footprint ""
		(layer "F.Cu")
		(at 160.720024 -15.649956 180)
		(property "Reference" "H109"
			(at -1.27762 2.488184 0)
			(unlocked yes)
			(layer "B.SilkS")
			(effects
				(font
					(size 0.7874 0.5842)
					(thickness 0.1524)
				)
				(justify left mirror)
			)
		)
		(property "Value" ""
			(at 0 0 180)
			(layer "F.Fab")
			(effects
				(font
					(size 1.27 1.27)
				)
			)
		)
		(duplicate_pad_numbers_are_jumpers no)
		(pad "1" thru_hole rect
			(at 0 0 180)
			(size 4.2164 5.0038)
			(drill 2.0066
				(offset 0.099822 0)
			)
			(layers "*.Cu" "*.Mask")
			(remove_unused_layers no)
			(net "Net_8554")
			(clearance -0.8509)
			(padstack
				(mode front_inner_back)
				(layer "Inner"
					(shape circle)
					(size 4.0132 4.0132)
					(clearance -0.7493)
				)
				(layer "B.Cu"
					(shape circle)
					(size 4.0132 4.0132)
					(clearance -0.7493)
				)
			)
		)
	)
	(footprint ""
		(layer "F.Cu")
		(at 221.990158 -81.627472)
		(property "Reference" "R5766"
			(at 0 0 0)
			(layer "F.SilkS")
			(hide yes)
			(effects
				(font
					(size 1.27 1.27)
				)
			)
		)
		(property "Value" ""
			(at 0 0 0)
			(layer "F.Fab")
			(effects
				(font
					(size 1.27 1.27)
				)
			)
		)
		(duplicate_pad_numbers_are_jumpers no)
		(fp_line
			(start -0.7874 -0.4064)
			(end 0.7874 -0.4064)
			(stroke
				(width 0.1524)
				(type default)
			)
			(layer "F.SilkS")
		)
		(fp_line
			(start -0.7874 0.4064)
			(end -0.7874 -0.4064)
			(stroke
				(width 0.1524)
				(type default)
			)
			(layer "F.SilkS")
		)
		(fp_line
			(start 0.7874 -0.4064)
			(end 0.7874 0.4064)
			(stroke
				(width 0.1524)
				(type default)
			)
			(layer "F.SilkS")
		)
		(fp_line
			(start 0.7874 0.4064)
			(end -0.7874 0.4064)
			(stroke
				(width 0.1524)
				(type default)
			)
			(layer "F.SilkS")
		)
		(fp_line
			(start -0.67945 -0.305054)
			(end -0.12065 -0.305054)
			(stroke
				(width 0.1)
				(type default)
			)
			(layer "F.Fab")
		)
		(fp_line
			(start -0.67945 0.3048)
			(end -0.67945 -0.305054)
			(stroke
				(width 0.1)
				(type default)
			)
			(layer "F.Fab")
		)
		(fp_line
			(start -0.12065 -0.305054)
			(end -0.12065 -0.2794)
			(stroke
				(width 0.1)
				(type default)
			)
			(layer "F.Fab")
		)
		(fp_line
			(start -0.12065 -0.2794)
			(end 0.12065 -0.2794)
			(stroke
				(width 0.1)
				(type default)
			)
			(layer "F.Fab")
		)
		(fp_line
			(start -0.12065 0.2794)
			(end -0.12065 0.3048)
			(stroke
				(width 0.1)
				(type default)
			)
			(layer "F.Fab")
		)
		(fp_line
			(start -0.12065 0.3048)
			(end -0.67945 0.3048)
			(stroke
				(width 0.1)
				(type default)
			)
			(layer "F.Fab")
		)
		(fp_line
			(start 0.120396 0.2794)
			(end -0.12065 0.2794)
			(stroke
				(width 0.1)
				(type default)
			)
			(layer "F.Fab")
		)
		(fp_line
			(start 0.120396 0.3048)
			(end 0.120396 0.2794)
			(stroke
				(width 0.1)
				(type default)
			)
			(layer "F.Fab")
		)
		(fp_line
			(start 0.12065 -0.3048)
			(end 0.67945 -0.3048)
			(stroke
				(width 0.1)
				(type default)
			)
			(layer "F.Fab")
		)
		(fp_line
			(start 0.12065 -0.2794)
			(end 0.12065 -0.3048)
			(stroke
				(width 0.1)
				(type default)
			)
			(layer "F.Fab")
		)
		(fp_line
			(start 0.67945 -0.3048)
			(end 0.67945 0.3048)
			(stroke
				(width 0.1)
				(type default)
			)
			(layer "F.Fab")
		)
		(fp_line
			(start 0.67945 0.3048)
			(end 0.120396 0.3048)
			(stroke
				(width 0.1)
				(type default)
			)
			(layer "F.Fab")
		)
		(pad "1" smd circle
			(at -0.40005 0)
			(size 0 0)
			(layers "F.Cu" "F.Mask" "F.Paste")
			(net "SSD12_LED")
		)
		(pad "2" smd circle
			(at 0.40005 0)
			(size 0 0)
			(layers "F.Cu" "F.Mask" "F.Paste")
			(net "SSD12_LED_R")
		)
	)
	(footprint ""
		(layer "F.Cu")
		(at 228.578664 -207.02016 -90)
		(property "Reference" "R5293"
			(at 0 0 270)
			(layer "F.SilkS")
			(hide yes)
			(effects
				(font
					(size 1.27 1.27)
				)
			)
		)
		(property "Value" ""
			(at 0 0 270)
			(layer "F.Fab")
			(effects
				(font
					(size 1.27 1.27)
				)
			)
		)
		(duplicate_pad_numbers_are_jumpers no)
		(fp_line
			(start -0.7874 0.4064)
			(end -0.7874 -0.4064)
			(stroke
				(width 0.1524)
				(type default)
			)
			(layer "F.SilkS")
		)
		(fp_line
			(start 0.7874 0.4064)
			(end -0.7874 0.4064)
			(stroke
				(width 0.1524)
				(type default)
			)
			(layer "F.SilkS")
		)
		(fp_line
			(start -0.7874 -0.4064)
			(end 0.7874 -0.4064)
			(stroke
				(width 0.1524)
				(type default)
			)
			(layer "F.SilkS")
		)
		(fp_line
			(start 0.7874 -0.4064)
			(end 0.7874 0.4064)
			(stroke
				(width 0.1524)
				(type default)
			)
			(layer "F.SilkS")
		)
		(fp_line
			(start -0.67945 0.3048)
			(end -0.67945 -0.305054)
			(stroke
				(width 0.1)
				(type default)
			)
			(layer "F.Fab")
		)
		(fp_line
			(start -0.12065 0.3048)
			(end -0.67945 0.3048)
			(stroke
				(width 0.1)
				(type default)
			)
			(layer "F.Fab")
		)
		(fp_line
			(start 0.120396 0.3048)
			(end 0.120396 0.2794)
			(stroke
				(width 0.1)
				(type default)
			)
			(layer "F.Fab")
		)
		(fp_line
			(start 0.67945 0.3048)
			(end 0.120396 0.3048)
			(stroke
				(width 0.1)
				(type default)
			)
			(layer "F.Fab")
		)
		(fp_line
			(start -0.12065 0.2794)
			(end -0.12065 0.3048)
			(stroke
				(width 0.1)
				(type default)
			)
			(layer "F.Fab")
		)
		(fp_line
			(start 0.120396 0.2794)
			(end -0.12065 0.2794)
			(stroke
				(width 0.1)
				(type default)
			)
			(layer "F.Fab")
		)
		(fp_line
			(start -0.12065 -0.2794)
			(end 0.12065 -0.2794)
			(stroke
				(width 0.1)
				(type default)
			)
			(layer "F.Fab")
		)
		(fp_line
			(start 0.12065 -0.2794)
			(end 0.12065 -0.3048)
			(stroke
				(width 0.1)
				(type default)
			)
			(layer "F.Fab")
		)
		(fp_line
			(start 0.12065 -0.3048)
			(end 0.67945 -0.3048)
			(stroke
				(width 0.1)
				(type default)
			)
			(layer "F.Fab")
		)
		(fp_line
			(start 0.67945 -0.3048)
			(end 0.67945 0.3048)
			(stroke
				(width 0.1)
				(type default)
			)
			(layer "F.Fab")
		)
		(fp_line
			(start -0.67945 -0.305054)
			(end -0.12065 -0.305054)
			(stroke
				(width 0.1)
				(type default)
			)
			(layer "F.Fab")
		)
		(fp_line
			(start -0.12065 -0.305054)
			(end -0.12065 -0.2794)
			(stroke
				(width 0.1)
				(type default)
			)
			(layer "F.Fab")
		)
		(pad "1" smd circle
			(at -0.40005 0 270)
			(size 0 0)
			(layers "F.Cu" "F.Mask" "F.Paste")
			(net "BIC_SEL_FLASH_SW0")
		)
		(pad "2" smd circle
			(at 0.40005 0 270)
			(size 0 0)
			(layers "F.Cu" "F.Mask" "F.Paste")
			(net "BIC_SEL_FLASH_SW0_R")
		)
	)
	(footprint ""
		(layer "F.Cu")
		(at 268.838426 -123.71324)
		(property "Reference" "C466"
			(at 0 0 0)
			(layer "F.SilkS")
			(hide yes)
			(effects
				(font
					(size 1.27 1.27)
				)
			)
		)
		(property "Value" ""
			(at 0 0 0)
			(layer "F.Fab")
			(effects
				(font
					(size 1.27 1.27)
				)
			)
		)
		(duplicate_pad_numbers_are_jumpers no)
		(fp_line
			(start -0.299974 -0.150114)
			(end 0.299974 -0.150114)
			(stroke
				(width 0.1)
				(type default)
			)
			(layer "F.Fab")
		)
		(fp_line
			(start -0.299974 0.150114)
			(end -0.299974 -0.150114)
			(stroke
				(width 0.1)
				(type default)
			)
			(layer "F.Fab")
		)
		(fp_line
			(start 0.299974 -0.150114)
			(end 0.299974 0.150114)
			(stroke
				(width 0.1)
				(type default)
			)
			(layer "F.Fab")
		)
		(fp_line
			(start 0.299974 0.150114)
			(end -0.299974 0.150114)
			(stroke
				(width 0.1)
				(type default)
			)
			(layer "F.Fab")
		)
		(pad "1" smd rect
			(at -0.2667 0)
			(size 0.3048 0.381)
			(layers "F.Cu" "F.Mask" "F.Paste")
			(net "P5E_PEX2_STN1_TX_DN<26>")
		)
		(pad "2" smd rect
			(at 0.2667 0)
			(size 0.3048 0.381)
			(layers "F.Cu" "F.Mask" "F.Paste")
			(net "P5E_PEX2_STN1_TX_C_DN<26>")
		)
	)
	(footprint ""
		(layer "F.Cu")
		(at 323.884036 -227.494084 180)
		(property "Reference" "D21"
			(at 5.431536 1.316482 0)
			(unlocked yes)
			(layer "F.SilkS")
			(effects
				(font
					(size 0.7874 0.5842)
					(thickness 0.1524)
				)
			)
		)
		(property "Value" ""
			(at 0 0 180)
			(layer "F.Fab")
			(effects
				(font
					(size 1.27 1.27)
				)
			)
		)
		(duplicate_pad_numbers_are_jumpers no)
		(fp_line
			(start 1.16078 0.4826)
			(end -0.64008 0.4826)
			(stroke
				(width 0.1524)
				(type default)
			)
			(layer "F.SilkS")
		)
		(fp_line
			(start 1.16078 -0.4826)
			(end 1.16078 0.4826)
			(stroke
				(width 0.1524)
				(type default)
			)
			(layer "F.SilkS")
		)
		(fp_line
			(start 1.03378 0.4826)
			(end -0.79248 0.4826)
			(stroke
				(width 0.1524)
				(type default)
			)
			(layer "F.SilkS")
		)
		(fp_line
			(start 1.03378 -0.4826)
			(end 1.03378 0.4826)
			(stroke
				(width 0.1524)
				(type default)
			)
			(layer "F.SilkS")
		)
		(fp_line
			(start 0.90678 0.4826)
			(end -0.90678 0.4826)
			(stroke
				(width 0.1524)
				(type default)
			)
			(layer "F.SilkS")
		)
		(fp_line
			(start 0.90678 -0.4826)
			(end 0.90678 0.4826)
			(stroke
				(width 0.1524)
				(type default)
			)
			(layer "F.SilkS")
		)
		(fp_line
			(start -0.64008 -0.4826)
			(end 1.16078 -0.4826)
			(stroke
				(width 0.1524)
				(type default)
			)
			(layer "F.SilkS")
		)
		(fp_line
			(start -0.79248 -0.4826)
			(end 1.03378 -0.4826)
			(stroke
				(width 0.1524)
				(type default)
			)
			(layer "F.SilkS")
		)
		(fp_line
			(start -0.89408 -0.4826)
			(end 0.90678 -0.4826)
			(stroke
				(width 0.1524)
				(type default)
			)
			(layer "F.SilkS")
		)
		(fp_line
			(start -0.90678 0.4826)
			(end -0.90678 -0.4699)
			(stroke
				(width 0.1524)
				(type default)
			)
			(layer "F.SilkS")
		)
		(fp_line
			(start 0.499872 0.249936)
			(end -0.499872 0.249936)
			(stroke
				(width 0.1)
				(type default)
			)
			(layer "F.Fab")
		)
		(fp_line
			(start 0.499872 -0.249936)
			(end 0.499872 0.249936)
			(stroke
				(width 0.1)
				(type default)
			)
			(layer "F.Fab")
		)
		(fp_line
			(start -0.499872 0.249936)
			(end -0.499872 -0.249936)
			(stroke
				(width 0.1)
				(type default)
			)
			(layer "F.Fab")
		)
		(fp_line
			(start -0.499872 -0.249936)
			(end 0.499872 -0.249936)
			(stroke
				(width 0.1)
				(type default)
			)
			(layer "F.Fab")
		)
		(pad "A" smd rect
			(at -0.47498 0 180)
			(size 0.6096 0.7112)
			(layers "F.Cu" "F.Mask" "F.Paste")
			(net "FPGA_HEARTBEAT")
		)
		(pad "C" smd rect
			(at 0.47498 0 180)
			(size 0.6096 0.7112)
			(layers "F.Cu" "F.Mask" "F.Paste")
			(net "FPGA_HEARTBEAT_N")
		)
	)
	(footprint ""
		(layer "F.Cu")
		(at 174.596552 -350.098614 90)
		(property "Reference" "C2524"
			(at 0 0 90)
			(layer "F.SilkS")
			(hide yes)
			(effects
				(font
					(size 1.27 1.27)
				)
			)
		)
		(property "Value" ""
			(at 0 0 90)
			(layer "F.Fab")
			(effects
				(font
					(size 1.27 1.27)
				)
			)
		)
		(duplicate_pad_numbers_are_jumpers no)
		(fp_line
			(start 0.299974 -0.150114)
			(end 0.299974 0.150114)
			(stroke
				(width 0.1)
				(type default)
			)
			(layer "F.Fab")
		)
		(fp_line
			(start -0.299974 -0.150114)
			(end 0.299974 -0.150114)
			(stroke
				(width 0.1)
				(type default)
			)
			(layer "F.Fab")
		)
		(fp_line
			(start 0.299974 0.150114)
			(end -0.299974 0.150114)
			(stroke
				(width 0.1)
				(type default)
			)
			(layer "F.Fab")
		)
		(fp_line
			(start -0.299974 0.150114)
			(end -0.299974 -0.150114)
			(stroke
				(width 0.1)
				(type default)
			)
			(layer "F.Fab")
		)
		(pad "1" smd rect
			(at -0.2667 0 90)
			(size 0.3048 0.381)
			(layers "F.Cu" "F.Mask" "F.Paste")
			(net "P5E_PEX1_STN4_TX_DP<73>")
		)
		(pad "2" smd rect
			(at 0.2667 0 90)
			(size 0.3048 0.381)
			(layers "F.Cu" "F.Mask" "F.Paste")
			(net "P5E_PEX1_STN4_TX_C_DP<73>")
		)
	)
	(footprint ""
		(layer "F.Cu")
		(at 321.804284 -350.098614 90)
		(property "Reference" "C559"
			(at 0 0 90)
			(layer "F.SilkS")
			(hide yes)
			(effects
				(font
					(size 1.27 1.27)
				)
			)
		)
		(property "Value" ""
			(at 0 0 90)
			(layer "F.Fab")
			(effects
				(font
					(size 1.27 1.27)
				)
			)
		)
		(duplicate_pad_numbers_are_jumpers no)
		(fp_line
			(start 0.299974 -0.150114)
			(end 0.299974 0.150114)
			(stroke
				(width 0.1)
				(type default)
			)
			(layer "F.Fab")
		)
		(fp_line
			(start -0.299974 -0.150114)
			(end 0.299974 -0.150114)
			(stroke
				(width 0.1)
				(type default)
			)
			(layer "F.Fab")
		)
		(fp_line
			(start 0.299974 0.150114)
			(end -0.299974 0.150114)
			(stroke
				(width 0.1)
				(type default)
			)
			(layer "F.Fab")
		)
		(fp_line
			(start -0.299974 0.150114)
			(end -0.299974 -0.150114)
			(stroke
				(width 0.1)
				(type default)
			)
			(layer "F.Fab")
		)
		(pad "1" smd rect
			(at -0.2667 0 90)
			(size 0.3048 0.381)
			(layers "F.Cu" "F.Mask" "F.Paste")
			(net "P5E_PEX2_STN6_TX_DP<107>")
		)
		(pad "2" smd rect
			(at 0.2667 0 90)
			(size 0.3048 0.381)
			(layers "F.Cu" "F.Mask" "F.Paste")
			(net "P5E_PEX2_STN6_TX_C_DP<107>")
		)
	)
	(footprint ""
		(layer "F.Cu")
		(at 220.34373 -43.85691)
		(property "Reference" "R585"
			(at 0 0 0)
			(layer "F.SilkS")
			(hide yes)
			(effects
				(font
					(size 1.27 1.27)
				)
			)
		)
		(property "Value" ""
			(at 0 0 0)
			(layer "F.Fab")
			(effects
				(font
					(size 1.27 1.27)
				)
			)
		)
		(duplicate_pad_numbers_are_jumpers no)
		(fp_line
			(start -0.7874 -0.4064)
			(end 0.7874 -0.4064)
			(stroke
				(width 0.1524)
				(type default)
			)
			(layer "F.SilkS")
		)
		(fp_line
			(start -0.7874 0.4064)
			(end -0.7874 -0.4064)
			(stroke
				(width 0.1524)
				(type default)
			)
			(layer "F.SilkS")
		)
		(fp_line
			(start 0.7874 -0.4064)
			(end 0.7874 0.4064)
			(stroke
				(width 0.1524)
				(type default)
			)
			(layer "F.SilkS")
		)
		(fp_line
			(start 0.7874 0.4064)
			(end -0.7874 0.4064)
			(stroke
				(width 0.1524)
				(type default)
			)
			(layer "F.SilkS")
		)
		(fp_line
			(start -0.67945 -0.305054)
			(end -0.12065 -0.305054)
			(stroke
				(width 0.1)
				(type default)
			)
			(layer "F.Fab")
		)
		(fp_line
			(start -0.67945 0.3048)
			(end -0.67945 -0.305054)
			(stroke
				(width 0.1)
				(type default)
			)
			(layer "F.Fab")
		)
		(fp_line
			(start -0.12065 -0.305054)
			(end -0.12065 -0.2794)
			(stroke
				(width 0.1)
				(type default)
			)
			(layer "F.Fab")
		)
		(fp_line
			(start -0.12065 -0.2794)
			(end 0.12065 -0.2794)
			(stroke
				(width 0.1)
				(type default)
			)
			(layer "F.Fab")
		)
		(fp_line
			(start -0.12065 0.2794)
			(end -0.12065 0.3048)
			(stroke
				(width 0.1)
				(type default)
			)
			(layer "F.Fab")
		)
		(fp_line
			(start -0.12065 0.3048)
			(end -0.67945 0.3048)
			(stroke
				(width 0.1)
				(type default)
			)
			(layer "F.Fab")
		)
		(fp_line
			(start 0.120396 0.2794)
			(end -0.12065 0.2794)
			(stroke
				(width 0.1)
				(type default)
			)
			(layer "F.Fab")
		)
		(fp_line
			(start 0.120396 0.3048)
			(end 0.120396 0.2794)
			(stroke
				(width 0.1)
				(type default)
			)
			(layer "F.Fab")
		)
		(fp_line
			(start 0.12065 -0.3048)
			(end 0.67945 -0.3048)
			(stroke
				(width 0.1)
				(type default)
			)
			(layer "F.Fab")
		)
		(fp_line
			(start 0.12065 -0.2794)
			(end 0.12065 -0.3048)
			(stroke
				(width 0.1)
				(type default)
			)
			(layer "F.Fab")
		)
		(fp_line
			(start 0.67945 -0.3048)
			(end 0.67945 0.3048)
			(stroke
				(width 0.1)
				(type default)
			)
			(layer "F.Fab")
		)
		(fp_line
			(start 0.67945 0.3048)
			(end 0.120396 0.3048)
			(stroke
				(width 0.1)
				(type default)
			)
			(layer "F.Fab")
		)
		(pad "1" smd circle
			(at -0.40005 0)
			(size 0 0)
			(layers "F.Cu" "F.Mask" "F.Paste")
			(net "SSD7_ADC_A1")
		)
		(pad "2" smd circle
			(at 0.40005 0)
			(size 0 0)
			(layers "F.Cu" "F.Mask" "F.Paste")
			(net "GND")
		)
	)
	(footprint ""
		(layer "F.Cu")
		(at 309.307484 -81.09966)
		(property "Reference" "Q6"
			(at -0.849884 1.80213 0)
			(unlocked yes)
			(layer "F.SilkS")
			(effects
				(font
					(size 0.7874 0.5842)
					(thickness 0.1524)
				)
				(justify left)
			)
		)
		(property "Value" ""
			(at 0 0 0)
			(layer "F.Fab")
			(effects
				(font
					(size 1.27 1.27)
				)
			)
		)
		(duplicate_pad_numbers_are_jumpers no)
		(fp_line
			(start -1.38176 -1.100074)
			(end -1.38176 1.100074)
			(stroke
				(width 0.1524)
				(type default)
			)
			(layer "F.SilkS")
		)
		(fp_line
			(start -1.38176 1.100074)
			(end 1.38176 1.100074)
			(stroke
				(width 0.1524)
				(type default)
			)
			(layer "F.SilkS")
		)
		(fp_line
			(start -0.592074 -1.100074)
			(end -1.38176 -1.100074)
			(stroke
				(width 0.1524)
				(type default)
			)
			(layer "F.SilkS")
		)
		(fp_line
			(start 0 -0.508)
			(end -0.592074 -1.100074)
			(stroke
				(width 0.1524)
				(type default)
			)
			(layer "F.SilkS")
		)
		(fp_line
			(start 0.592074 -1.100074)
			(end 0 -0.508)
			(stroke
				(width 0.1524)
				(type default)
			)
			(layer "F.SilkS")
		)
		(fp_line
			(start 1.38176 -1.100074)
			(end 0.592074 -1.100074)
			(stroke
				(width 0.1524)
				(type default)
			)
			(layer "F.SilkS")
		)
		(fp_line
			(start 1.38176 1.100074)
			(end 1.38176 -1.100074)
			(stroke
				(width 0.1524)
				(type default)
			)
			(layer "F.SilkS")
		)
		(fp_poly
			(pts
				(xy -1.9431 -0.870204) (xy -1.50241 -0.649986) (xy -1.9431 -0.429768)
			)
			(stroke
				(width 0)
				(type default)
			)
			(fill yes)
			(layer "F.SilkS")
		)
		(fp_line
			(start -0.674878 -1.100074)
			(end -0.674878 1.100074)
			(stroke
				(width 0.1)
				(type default)
			)
			(layer "F.Fab")
		)
		(fp_line
			(start -0.674878 1.100074)
			(end 0.674878 1.100074)
			(stroke
				(width 0.1)
				(type default)
			)
			(layer "F.Fab")
		)
		(fp_line
			(start 0.674878 -1.100074)
			(end -0.674878 -1.100074)
			(stroke
				(width 0.1)
				(type default)
			)
			(layer "F.Fab")
		)
		(fp_line
			(start 0.674878 1.100074)
			(end 0.674878 -1.100074)
			(stroke
				(width 0.1)
				(type default)
			)
			(layer "F.Fab")
		)
		(fp_poly
			(pts
				(xy -1.9431 -0.870204) (xy -1.50241 -0.649986) (xy -1.9431 -0.429768)
			)
			(stroke
				(width 0)
				(type default)
			)
			(fill yes)
			(layer "F.Fab")
		)
		(pad "1" smd rect
			(at -0.94996 -0.649986 270)
			(size 0.4318 0.6096)
			(layers "F.Cu" "F.Mask" "F.Paste")
			(net "GND")
		)
		(pad "2" smd rect
			(at -0.94996 0 270)
			(size 0.4318 0.6096)
			(layers "F.Cu" "F.Mask" "F.Paste")
			(net "HP_NIC5_HSC_PWRGD_N")
		)
		(pad "3" smd rect
			(at -0.94996 0.649986 270)
			(size 0.4318 0.6096)
			(layers "F.Cu" "F.Mask" "F.Paste")
			(net "HP_NIC5_HSC_PWRGD_N")
		)
		(pad "4" smd rect
			(at 0.94996 0.649986 270)
			(size 0.4318 0.6096)
			(layers "F.Cu" "F.Mask" "F.Paste")
			(net "GND")
		)
		(pad "5" smd rect
			(at 0.94996 0 270)
			(size 0.4318 0.6096)
			(layers "F.Cu" "F.Mask" "F.Paste")
			(net "PWRGD_P12V_NIC5_R")
		)
		(pad "6" smd rect
			(at 0.94996 -0.649986 270)
			(size 0.4318 0.6096)
			(layers "F.Cu" "F.Mask" "F.Paste")
			(net "HP_NIC5_PWRGD_R")
		)
	)
	(footprint ""
		(layer "F.Cu")
		(at 265.487658 -294.819832)
		(property "Reference" "C3375"
			(at 0 0 0)
			(layer "F.SilkS")
			(hide yes)
			(effects
				(font
					(size 1.27 1.27)
				)
			)
		)
		(property "Value" ""
			(at 0 0 0)
			(layer "F.Fab")
			(effects
				(font
					(size 1.27 1.27)
				)
			)
		)
		(duplicate_pad_numbers_are_jumpers no)
		(fp_line
			(start -1.2954 -0.5842)
			(end 1.2954 -0.5842)
			(stroke
				(width 0.1524)
				(type default)
			)
			(layer "F.SilkS")
		)
		(fp_line
			(start -1.2954 0.5842)
			(end -1.2954 -0.5842)
			(stroke
				(width 0.1524)
				(type default)
			)
			(layer "F.SilkS")
		)
		(fp_line
			(start 1.2954 -0.5842)
			(end 1.2954 0.5842)
			(stroke
				(width 0.1524)
				(type default)
			)
			(layer "F.SilkS")
		)
		(fp_line
			(start 1.2954 0.5842)
			(end -1.2954 0.5842)
			(stroke
				(width 0.1524)
				(type default)
			)
			(layer "F.SilkS")
		)
		(fp_line
			(start -1.1938 -0.4064)
			(end -0.8636 -0.4064)
			(stroke
				(width 0.1)
				(type default)
			)
			(layer "F.Fab")
		)
		(fp_line
			(start -1.1938 0.4064)
			(end -1.1938 -0.4064)
			(stroke
				(width 0.1)
				(type default)
			)
			(layer "F.Fab")
		)
		(fp_line
			(start -0.8636 -0.4572)
			(end 0.8636 -0.4572)
			(stroke
				(width 0.1)
				(type default)
			)
			(layer "F.Fab")
		)
		(fp_line
			(start -0.8636 -0.4064)
			(end -0.8636 -0.4572)
			(stroke
				(width 0.1)
				(type default)
			)
			(layer "F.Fab")
		)
		(fp_line
			(start -0.8636 0.4064)
			(end -1.1938 0.4064)
			(stroke
				(width 0.1)
				(type default)
			)
			(layer "F.Fab")
		)
		(fp_line
			(start -0.8636 0.4572)
			(end -0.8636 0.4064)
			(stroke
				(width 0.1)
				(type default)
			)
			(layer "F.Fab")
		)
		(fp_line
			(start 0.8636 -0.4572)
			(end 0.8636 -0.4064)
			(stroke
				(width 0.1)
				(type default)
			)
			(layer "F.Fab")
		)
		(fp_line
			(start 0.8636 -0.4064)
			(end 1.1938 -0.4064)
			(stroke
				(width 0.1)
				(type default)
			)
			(layer "F.Fab")
		)
		(fp_line
			(start 0.8636 0.4064)
			(end 0.8636 0.4572)
			(stroke
				(width 0.1)
				(type default)
			)
			(layer "F.Fab")
		)
		(fp_line
			(start 0.8636 0.4572)
			(end -0.8636 0.4572)
			(stroke
				(width 0.1)
				(type default)
			)
			(layer "F.Fab")
		)
		(fp_line
			(start 1.1938 -0.4064)
			(end 1.1938 0.4064)
			(stroke
				(width 0.1)
				(type default)
			)
			(layer "F.Fab")
		)
		(fp_line
			(start 1.1938 0.4064)
			(end 0.8636 0.4064)
			(stroke
				(width 0.1)
				(type default)
			)
			(layer "F.Fab")
		)
		(pad "1" smd rect
			(at -0.7366 0 270)
			(size 0.7112 0.8128)
			(layers "F.Cu" "F.Mask" "F.Paste")
			(net "PCEPLL2_VDDA18_PEX2")
		)
		(pad "2" smd rect
			(at 0.7366 0 270)
			(size 0.7112 0.8128)
			(layers "F.Cu" "F.Mask" "F.Paste")
			(net "GND")
		)
	)
	(footprint ""
		(layer "F.Cu")
		(at 173.75632 -61.487812 180)
		(property "Reference" "R5982"
			(at 0 0 180)
			(layer "F.SilkS")
			(hide yes)
			(effects
				(font
					(size 1.27 1.27)
				)
			)
		)
		(property "Value" ""
			(at 0 0 180)
			(layer "F.Fab")
			(effects
				(font
					(size 1.27 1.27)
				)
			)
		)
		(duplicate_pad_numbers_are_jumpers no)
		(fp_line
			(start 0.7874 0.4064)
			(end -0.7874 0.4064)
			(stroke
				(width 0.1524)
				(type default)
			)
			(layer "F.SilkS")
		)
		(fp_line
			(start 0.7874 -0.4064)
			(end 0.7874 0.4064)
			(stroke
				(width 0.1524)
				(type default)
			)
			(layer "F.SilkS")
		)
		(fp_line
			(start -0.7874 0.4064)
			(end -0.7874 -0.4064)
			(stroke
				(width 0.1524)
				(type default)
			)
			(layer "F.SilkS")
		)
		(fp_line
			(start -0.7874 -0.4064)
			(end 0.7874 -0.4064)
			(stroke
				(width 0.1524)
				(type default)
			)
			(layer "F.SilkS")
		)
		(fp_line
			(start 0.67945 0.3048)
			(end 0.120396 0.3048)
			(stroke
				(width 0.1)
				(type default)
			)
			(layer "F.Fab")
		)
		(fp_line
			(start 0.67945 -0.3048)
			(end 0.67945 0.3048)
			(stroke
				(width 0.1)
				(type default)
			)
			(layer "F.Fab")
		)
		(fp_line
			(start 0.12065 -0.2794)
			(end 0.12065 -0.3048)
			(stroke
				(width 0.1)
				(type default)
			)
			(layer "F.Fab")
		)
		(fp_line
			(start 0.12065 -0.3048)
			(end 0.67945 -0.3048)
			(stroke
				(width 0.1)
				(type default)
			)
			(layer "F.Fab")
		)
		(fp_line
			(start 0.120396 0.3048)
			(end 0.120396 0.2794)
			(stroke
				(width 0.1)
				(type default)
			)
			(layer "F.Fab")
		)
		(fp_line
			(start 0.120396 0.2794)
			(end -0.12065 0.2794)
			(stroke
				(width 0.1)
				(type default)
			)
			(layer "F.Fab")
		)
		(fp_line
			(start -0.12065 0.3048)
			(end -0.67945 0.3048)
			(stroke
				(width 0.1)
				(type default)
			)
			(layer "F.Fab")
		)
		(fp_line
			(start -0.12065 0.2794)
			(end -0.12065 0.3048)
			(stroke
				(width 0.1)
				(type default)
			)
			(layer "F.Fab")
		)
		(fp_line
			(start -0.12065 -0.2794)
			(end 0.12065 -0.2794)
			(stroke
				(width 0.1)
				(type default)
			)
			(layer "F.Fab")
		)
		(fp_line
			(start -0.12065 -0.305054)
			(end -0.12065 -0.2794)
			(stroke
				(width 0.1)
				(type default)
			)
			(layer "F.Fab")
		)
		(fp_line
			(start -0.67945 0.3048)
			(end -0.67945 -0.305054)
			(stroke
				(width 0.1)
				(type default)
			)
			(layer "F.Fab")
		)
		(fp_line
			(start -0.67945 -0.305054)
			(end -0.12065 -0.305054)
			(stroke
				(width 0.1)
				(type default)
			)
			(layer "F.Fab")
		)
		(pad "1" smd circle
			(at -0.40005 0 180)
			(size 0 0)
			(layers "F.Cu" "F.Mask" "F.Paste")
			(net "P3V3_AUX")
		)
		(pad "2" smd circle
			(at 0.40005 0 180)
			(size 0 0)
			(layers "F.Cu" "F.Mask" "F.Paste")
			(net "PWRGD_P12V_SSD6_D")
		)
	)
	(footprint ""
		(layer "F.Cu")
		(at 124.14123 -172.444918 90)
		(property "Reference" "C4500"
			(at 0 0 90)
			(layer "F.SilkS")
			(hide yes)
			(effects
				(font
					(size 1.27 1.27)
				)
			)
		)
		(property "Value" ""
			(at 0 0 90)
			(layer "F.Fab")
			(effects
				(font
					(size 1.27 1.27)
				)
			)
		)
		(duplicate_pad_numbers_are_jumpers no)
		(fp_line
			(start 0.7874 -0.4064)
			(end 0.7874 0.4064)
			(stroke
				(width 0.1524)
				(type default)
			)
			(layer "F.SilkS")
		)
		(fp_line
			(start -0.7874 -0.4064)
			(end 0.7874 -0.4064)
			(stroke
				(width 0.1524)
				(type default)
			)
			(layer "F.SilkS")
		)
		(fp_line
			(start 0.7874 0.4064)
			(end -0.7874 0.4064)
			(stroke
				(width 0.1524)
				(type default)
			)
			(layer "F.SilkS")
		)
		(fp_line
			(start -0.7874 0.4064)
			(end -0.7874 -0.4064)
			(stroke
				(width 0.1524)
				(type default)
			)
			(layer "F.SilkS")
		)
		(fp_line
			(start -0.12065 -0.305054)
			(end -0.12065 -0.2794)
			(stroke
				(width 0.1)
				(type default)
			)
			(layer "F.Fab")
		)
		(fp_line
			(start -0.67945 -0.305054)
			(end -0.12065 -0.305054)
			(stroke
				(width 0.1)
				(type default)
			)
			(layer "F.Fab")
		)
		(fp_line
			(start 0.67945 -0.3048)
			(end 0.67945 0.3048)
			(stroke
				(width 0.1)
				(type default)
			)
			(layer "F.Fab")
		)
		(fp_line
			(start 0.12065 -0.3048)
			(end 0.67945 -0.3048)
			(stroke
				(width 0.1)
				(type default)
			)
			(layer "F.Fab")
		)
		(fp_line
			(start 0.12065 -0.2794)
			(end 0.12065 -0.3048)
			(stroke
				(width 0.1)
				(type default)
			)
			(layer "F.Fab")
		)
		(fp_line
			(start -0.12065 -0.2794)
			(end 0.12065 -0.2794)
			(stroke
				(width 0.1)
				(type default)
			)
			(layer "F.Fab")
		)
		(fp_line
			(start 0.120396 0.2794)
			(end -0.12065 0.2794)
			(stroke
				(width 0.1)
				(type default)
			)
			(layer "F.Fab")
		)
		(fp_line
			(start -0.12065 0.2794)
			(end -0.12065 0.3048)
			(stroke
				(width 0.1)
				(type default)
			)
			(layer "F.Fab")
		)
		(fp_line
			(start 0.67945 0.3048)
			(end 0.120396 0.3048)
			(stroke
				(width 0.1)
				(type default)
			)
			(layer "F.Fab")
		)
		(fp_line
			(start 0.120396 0.3048)
			(end 0.120396 0.2794)
			(stroke
				(width 0.1)
				(type default)
			)
			(layer "F.Fab")
		)
		(fp_line
			(start -0.12065 0.3048)
			(end -0.67945 0.3048)
			(stroke
				(width 0.1)
				(type default)
			)
			(layer "F.Fab")
		)
		(fp_line
			(start -0.67945 0.3048)
			(end -0.67945 -0.305054)
			(stroke
				(width 0.1)
				(type default)
			)
			(layer "F.Fab")
		)
		(pad "1" smd circle
			(at -0.40005 0 90)
			(size 0 0)
			(layers "F.Cu" "F.Mask" "F.Paste")
			(net "NIC1_CLK_EN_R_N")
		)
		(pad "2" smd circle
			(at 0.40005 0 90)
			(size 0 0)
			(layers "F.Cu" "F.Mask" "F.Paste")
			(net "GND")
		)
	)
	(footprint ""
		(layer "F.Cu")
		(at 136.445244 -87.813642 180)
		(property "Reference" "R1576"
			(at 0 0 180)
			(layer "F.SilkS")
			(hide yes)
			(effects
				(font
					(size 1.27 1.27)
				)
			)
		)
		(property "Value" ""
			(at 0 0 180)
			(layer "F.Fab")
			(effects
				(font
					(size 1.27 1.27)
				)
			)
		)
		(duplicate_pad_numbers_are_jumpers no)
		(fp_line
			(start 0.7874 0.4064)
			(end -0.7874 0.4064)
			(stroke
				(width 0.1524)
				(type default)
			)
			(layer "F.SilkS")
		)
		(fp_line
			(start 0.7874 -0.4064)
			(end 0.7874 0.4064)
			(stroke
				(width 0.1524)
				(type default)
			)
			(layer "F.SilkS")
		)
		(fp_line
			(start -0.7874 0.4064)
			(end -0.7874 -0.4064)
			(stroke
				(width 0.1524)
				(type default)
			)
			(layer "F.SilkS")
		)
		(fp_line
			(start -0.7874 -0.4064)
			(end 0.7874 -0.4064)
			(stroke
				(width 0.1524)
				(type default)
			)
			(layer "F.SilkS")
		)
		(fp_line
			(start 0.67945 0.3048)
			(end 0.120396 0.3048)
			(stroke
				(width 0.1)
				(type default)
			)
			(layer "F.Fab")
		)
		(fp_line
			(start 0.67945 -0.3048)
			(end 0.67945 0.3048)
			(stroke
				(width 0.1)
				(type default)
			)
			(layer "F.Fab")
		)
		(fp_line
			(start 0.12065 -0.2794)
			(end 0.12065 -0.3048)
			(stroke
				(width 0.1)
				(type default)
			)
			(layer "F.Fab")
		)
		(fp_line
			(start 0.12065 -0.3048)
			(end 0.67945 -0.3048)
			(stroke
				(width 0.1)
				(type default)
			)
			(layer "F.Fab")
		)
		(fp_line
			(start 0.120396 0.3048)
			(end 0.120396 0.2794)
			(stroke
				(width 0.1)
				(type default)
			)
			(layer "F.Fab")
		)
		(fp_line
			(start 0.120396 0.2794)
			(end -0.12065 0.2794)
			(stroke
				(width 0.1)
				(type default)
			)
			(layer "F.Fab")
		)
		(fp_line
			(start -0.12065 0.3048)
			(end -0.67945 0.3048)
			(stroke
				(width 0.1)
				(type default)
			)
			(layer "F.Fab")
		)
		(fp_line
			(start -0.12065 0.2794)
			(end -0.12065 0.3048)
			(stroke
				(width 0.1)
				(type default)
			)
			(layer "F.Fab")
		)
		(fp_line
			(start -0.12065 -0.2794)
			(end 0.12065 -0.2794)
			(stroke
				(width 0.1)
				(type default)
			)
			(layer "F.Fab")
		)
		(fp_line
			(start -0.12065 -0.305054)
			(end -0.12065 -0.2794)
			(stroke
				(width 0.1)
				(type default)
			)
			(layer "F.Fab")
		)
		(fp_line
			(start -0.67945 0.3048)
			(end -0.67945 -0.305054)
			(stroke
				(width 0.1)
				(type default)
			)
			(layer "F.Fab")
		)
		(fp_line
			(start -0.67945 -0.305054)
			(end -0.12065 -0.305054)
			(stroke
				(width 0.1)
				(type default)
			)
			(layer "F.Fab")
		)
		(pad "1" smd circle
			(at -0.40005 0 180)
			(size 0 0)
			(layers "F.Cu" "F.Mask" "F.Paste")
			(net "SMB_BIC_I2C9_MUX0_SSD4_R_SDA")
		)
		(pad "2" smd circle
			(at 0.40005 0 180)
			(size 0 0)
			(layers "F.Cu" "F.Mask" "F.Paste")
			(net "SMB_BIC_I2C9_MUX0_SSD4_SDA")
		)
	)
	(footprint ""
		(layer "F.Cu")
		(at 268.838426 -134.008876)
		(property "Reference" "C457"
			(at 0 0 0)
			(layer "F.SilkS")
			(hide yes)
			(effects
				(font
					(size 1.27 1.27)
				)
			)
		)
		(property "Value" ""
			(at 0 0 0)
			(layer "F.Fab")
			(effects
				(font
					(size 1.27 1.27)
				)
			)
		)
		(duplicate_pad_numbers_are_jumpers no)
		(fp_line
			(start -0.299974 -0.150114)
			(end 0.299974 -0.150114)
			(stroke
				(width 0.1)
				(type default)
			)
			(layer "F.Fab")
		)
		(fp_line
			(start -0.299974 0.150114)
			(end -0.299974 -0.150114)
			(stroke
				(width 0.1)
				(type default)
			)
			(layer "F.Fab")
		)
		(fp_line
			(start 0.299974 -0.150114)
			(end 0.299974 0.150114)
			(stroke
				(width 0.1)
				(type default)
			)
			(layer "F.Fab")
		)
		(fp_line
			(start 0.299974 0.150114)
			(end -0.299974 0.150114)
			(stroke
				(width 0.1)
				(type default)
			)
			(layer "F.Fab")
		)
		(pad "1" smd rect
			(at -0.2667 0)
			(size 0.3048 0.381)
			(layers "F.Cu" "F.Mask" "F.Paste")
			(net "P5E_PEX2_STN1_TX_DP<30>")
		)
		(pad "2" smd rect
			(at 0.2667 0)
			(size 0.3048 0.381)
			(layers "F.Cu" "F.Mask" "F.Paste")
			(net "P5E_PEX2_STN1_TX_C_DP<30>")
		)
	)
	(footprint ""
		(layer "F.Cu")
		(at 378.2949 -343.952322 90)
		(property "Reference" "C767"
			(at 0 0 90)
			(layer "F.SilkS")
			(hide yes)
			(effects
				(font
					(size 1.27 1.27)
				)
			)
		)
		(property "Value" ""
			(at 0 0 90)
			(layer "F.Fab")
			(effects
				(font
					(size 1.27 1.27)
				)
			)
		)
		(duplicate_pad_numbers_are_jumpers no)
		(fp_line
			(start 0.299974 -0.150114)
			(end 0.299974 0.150114)
			(stroke
				(width 0.1)
				(type default)
			)
			(layer "F.Fab")
		)
		(fp_line
			(start -0.299974 -0.150114)
			(end 0.299974 -0.150114)
			(stroke
				(width 0.1)
				(type default)
			)
			(layer "F.Fab")
		)
		(fp_line
			(start 0.299974 0.150114)
			(end -0.299974 0.150114)
			(stroke
				(width 0.1)
				(type default)
			)
			(layer "F.Fab")
		)
		(fp_line
			(start -0.299974 0.150114)
			(end -0.299974 -0.150114)
			(stroke
				(width 0.1)
				(type default)
			)
			(layer "F.Fab")
		)
		(pad "1" smd rect
			(at -0.2667 0 90)
			(size 0.3048 0.381)
			(layers "F.Cu" "F.Mask" "F.Paste")
			(net "P5E_PEX3_STN6_TX_DN<109>")
		)
		(pad "2" smd rect
			(at 0.2667 0 90)
			(size 0.3048 0.381)
			(layers "F.Cu" "F.Mask" "F.Paste")
			(net "P5E_PEX3_STN6_TX_C_DN<109>")
		)
	)
	(footprint ""
		(layer "F.Cu")
		(at 285.326074 -37.929566 90)
		(property "Reference" "R5576"
			(at 0 0 90)
			(layer "F.SilkS")
			(hide yes)
			(effects
				(font
					(size 1.27 1.27)
				)
			)
		)
		(property "Value" ""
			(at 0 0 90)
			(layer "F.Fab")
			(effects
				(font
					(size 1.27 1.27)
				)
			)
		)
		(duplicate_pad_numbers_are_jumpers no)
		(fp_line
			(start 0.7874 -0.4064)
			(end 0.7874 0.4064)
			(stroke
				(width 0.1524)
				(type default)
			)
			(layer "F.SilkS")
		)
		(fp_line
			(start -0.7874 -0.4064)
			(end 0.7874 -0.4064)
			(stroke
				(width 0.1524)
				(type default)
			)
			(layer "F.SilkS")
		)
		(fp_line
			(start 0.7874 0.4064)
			(end -0.7874 0.4064)
			(stroke
				(width 0.1524)
				(type default)
			)
			(layer "F.SilkS")
		)
		(fp_line
			(start -0.7874 0.4064)
			(end -0.7874 -0.4064)
			(stroke
				(width 0.1524)
				(type default)
			)
			(layer "F.SilkS")
		)
		(fp_line
			(start -0.12065 -0.305054)
			(end -0.12065 -0.2794)
			(stroke
				(width 0.1)
				(type default)
			)
			(layer "F.Fab")
		)
		(fp_line
			(start -0.67945 -0.305054)
			(end -0.12065 -0.305054)
			(stroke
				(width 0.1)
				(type default)
			)
			(layer "F.Fab")
		)
		(fp_line
			(start 0.67945 -0.3048)
			(end 0.67945 0.3048)
			(stroke
				(width 0.1)
				(type default)
			)
			(layer "F.Fab")
		)
		(fp_line
			(start 0.12065 -0.3048)
			(end 0.67945 -0.3048)
			(stroke
				(width 0.1)
				(type default)
			)
			(layer "F.Fab")
		)
		(fp_line
			(start 0.12065 -0.2794)
			(end 0.12065 -0.3048)
			(stroke
				(width 0.1)
				(type default)
			)
			(layer "F.Fab")
		)
		(fp_line
			(start -0.12065 -0.2794)
			(end 0.12065 -0.2794)
			(stroke
				(width 0.1)
				(type default)
			)
			(layer "F.Fab")
		)
		(fp_line
			(start 0.120396 0.2794)
			(end -0.12065 0.2794)
			(stroke
				(width 0.1)
				(type default)
			)
			(layer "F.Fab")
		)
		(fp_line
			(start -0.12065 0.2794)
			(end -0.12065 0.3048)
			(stroke
				(width 0.1)
				(type default)
			)
			(layer "F.Fab")
		)
		(fp_line
			(start 0.67945 0.3048)
			(end 0.120396 0.3048)
			(stroke
				(width 0.1)
				(type default)
			)
			(layer "F.Fab")
		)
		(fp_line
			(start 0.120396 0.3048)
			(end 0.120396 0.2794)
			(stroke
				(width 0.1)
				(type default)
			)
			(layer "F.Fab")
		)
		(fp_line
			(start -0.12065 0.3048)
			(end -0.67945 0.3048)
			(stroke
				(width 0.1)
				(type default)
			)
			(layer "F.Fab")
		)
		(fp_line
			(start -0.67945 0.3048)
			(end -0.67945 -0.305054)
			(stroke
				(width 0.1)
				(type default)
			)
			(layer "F.Fab")
		)
		(pad "1" smd circle
			(at -0.40005 0 90)
			(size 0 0)
			(layers "F.Cu" "F.Mask" "F.Paste")
			(net "SSD10_AUX_P3V3_EN_R")
		)
		(pad "2" smd circle
			(at 0.40005 0 90)
			(size 0 0)
			(layers "F.Cu" "F.Mask" "F.Paste")
			(net "SSD10_AUX_P3V3_EN")
		)
	)
	(footprint ""
		(layer "F.Cu")
		(at 263.494012 -34.248852)
		(property "Reference" "R5680"
			(at 0 0 0)
			(layer "F.SilkS")
			(hide yes)
			(effects
				(font
					(size 1.27 1.27)
				)
			)
		)
		(property "Value" ""
			(at 0 0 0)
			(layer "F.Fab")
			(effects
				(font
					(size 1.27 1.27)
				)
			)
		)
		(duplicate_pad_numbers_are_jumpers no)
		(fp_line
			(start -0.7874 -0.4064)
			(end 0.7874 -0.4064)
			(stroke
				(width 0.1524)
				(type default)
			)
			(layer "F.SilkS")
		)
		(fp_line
			(start -0.7874 0.4064)
			(end -0.7874 -0.4064)
			(stroke
				(width 0.1524)
				(type default)
			)
			(layer "F.SilkS")
		)
		(fp_line
			(start 0.7874 -0.4064)
			(end 0.7874 0.4064)
			(stroke
				(width 0.1524)
				(type default)
			)
			(layer "F.SilkS")
		)
		(fp_line
			(start 0.7874 0.4064)
			(end -0.7874 0.4064)
			(stroke
				(width 0.1524)
				(type default)
			)
			(layer "F.SilkS")
		)
		(fp_line
			(start -0.67945 -0.305054)
			(end -0.12065 -0.305054)
			(stroke
				(width 0.1)
				(type default)
			)
			(layer "F.Fab")
		)
		(fp_line
			(start -0.67945 0.3048)
			(end -0.67945 -0.305054)
			(stroke
				(width 0.1)
				(type default)
			)
			(layer "F.Fab")
		)
		(fp_line
			(start -0.12065 -0.305054)
			(end -0.12065 -0.2794)
			(stroke
				(width 0.1)
				(type default)
			)
			(layer "F.Fab")
		)
		(fp_line
			(start -0.12065 -0.2794)
			(end 0.12065 -0.2794)
			(stroke
				(width 0.1)
				(type default)
			)
			(layer "F.Fab")
		)
		(fp_line
			(start -0.12065 0.2794)
			(end -0.12065 0.3048)
			(stroke
				(width 0.1)
				(type default)
			)
			(layer "F.Fab")
		)
		(fp_line
			(start -0.12065 0.3048)
			(end -0.67945 0.3048)
			(stroke
				(width 0.1)
				(type default)
			)
			(layer "F.Fab")
		)
		(fp_line
			(start 0.120396 0.2794)
			(end -0.12065 0.2794)
			(stroke
				(width 0.1)
				(type default)
			)
			(layer "F.Fab")
		)
		(fp_line
			(start 0.120396 0.3048)
			(end 0.120396 0.2794)
			(stroke
				(width 0.1)
				(type default)
			)
			(layer "F.Fab")
		)
		(fp_line
			(start 0.12065 -0.3048)
			(end 0.67945 -0.3048)
			(stroke
				(width 0.1)
				(type default)
			)
			(layer "F.Fab")
		)
		(fp_line
			(start 0.12065 -0.2794)
			(end 0.12065 -0.3048)
			(stroke
				(width 0.1)
				(type default)
			)
			(layer "F.Fab")
		)
		(fp_line
			(start 0.67945 -0.3048)
			(end 0.67945 0.3048)
			(stroke
				(width 0.1)
				(type default)
			)
			(layer "F.Fab")
		)
		(fp_line
			(start 0.67945 0.3048)
			(end 0.120396 0.3048)
			(stroke
				(width 0.1)
				(type default)
			)
			(layer "F.Fab")
		)
		(pad "1" smd circle
			(at -0.40005 0)
			(size 0 0)
			(layers "F.Cu" "F.Mask" "F.Paste")
			(net "RST_SMB_SSD9_ISO_N")
		)
		(pad "2" smd circle
			(at 0.40005 0)
			(size 0 0)
			(layers "F.Cu" "F.Mask" "F.Paste")
			(net "P3V3_SSD9")
		)
	)
	(footprint ""
		(layer "F.Cu")
		(at 69.792342 -29.139642 180)
		(property "Reference" "C87"
			(at 0 0 180)
			(layer "F.SilkS")
			(hide yes)
			(effects
				(font
					(size 1.27 1.27)
				)
			)
		)
		(property "Value" ""
			(at 0 0 180)
			(layer "F.Fab")
			(effects
				(font
					(size 1.27 1.27)
				)
			)
		)
		(duplicate_pad_numbers_are_jumpers no)
		(fp_line
			(start 0.299974 0.150114)
			(end -0.299974 0.150114)
			(stroke
				(width 0.1)
				(type default)
			)
			(layer "F.Fab")
		)
		(fp_line
			(start 0.299974 -0.150114)
			(end 0.299974 0.150114)
			(stroke
				(width 0.1)
				(type default)
			)
			(layer "F.Fab")
		)
		(fp_line
			(start -0.299974 0.150114)
			(end -0.299974 -0.150114)
			(stroke
				(width 0.1)
				(type default)
			)
			(layer "F.Fab")
		)
		(fp_line
			(start -0.299974 -0.150114)
			(end 0.299974 -0.150114)
			(stroke
				(width 0.1)
				(type default)
			)
			(layer "F.Fab")
		)
		(pad "1" smd rect
			(at -0.2667 0 180)
			(size 0.3048 0.381)
			(layers "F.Cu" "F.Mask" "F.Paste")
			(net "P5E_PEX0_STN2_TX_DP<36>")
		)
		(pad "2" smd rect
			(at 0.2667 0 180)
			(size 0.3048 0.381)
			(layers "F.Cu" "F.Mask" "F.Paste")
			(net "P5E_PEX0_STN2_TX_C_DP<36>")
		)
	)
	(footprint ""
		(layer "F.Cu")
		(at 215.464136 -185.702956 -90)
		(property "Reference" "U351"
			(at 0.57277 -1.895602 90)
			(unlocked yes)
			(layer "F.SilkS")
			(effects
				(font
					(size 0.7874 0.5842)
					(thickness 0.1524)
				)
			)
		)
		(property "Value" ""
			(at 0 0 270)
			(layer "F.Fab")
			(effects
				(font
					(size 1.27 1.27)
				)
			)
		)
		(duplicate_pad_numbers_are_jumpers no)
		(fp_line
			(start -1.7272 1.1176)
			(end -1.7272 -1.1176)
			(stroke
				(width 0.1524)
				(type default)
			)
			(layer "F.SilkS")
		)
		(fp_line
			(start 1.7272 1.1176)
			(end -1.7272 1.1176)
			(stroke
				(width 0.1524)
				(type default)
			)
			(layer "F.SilkS")
		)
		(fp_line
			(start 0 -0.7366)
			(end -0.254 -1.1176)
			(stroke
				(width 0.1524)
				(type default)
			)
			(layer "F.SilkS")
		)
		(fp_line
			(start -0.254 -1.1176)
			(end -1.7272 -1.1176)
			(stroke
				(width 0.1524)
				(type default)
			)
			(layer "F.SilkS")
		)
		(fp_line
			(start 0.254 -1.1176)
			(end 0 -0.7366)
			(stroke
				(width 0.1524)
				(type default)
			)
			(layer "F.SilkS")
		)
		(fp_line
			(start 1.7272 -1.1176)
			(end 1.7272 1.1176)
			(stroke
				(width 0.1524)
				(type default)
			)
			(layer "F.SilkS")
		)
		(fp_line
			(start 1.7272 -1.1176)
			(end 0.254 -1.1176)
			(stroke
				(width 0.1524)
				(type default)
			)
			(layer "F.SilkS")
		)
		(fp_poly
			(pts
				(xy -1.273048 -1.267968) (xy -1.654048 -2.029968) (xy -0.892048 -2.029968)
			)
			(stroke
				(width 0)
				(type default)
			)
			(fill yes)
			(layer "F.SilkS")
		)
		(fp_line
			(start -1.5748 1.1176)
			(end 1.5748 1.1176)
			(stroke
				(width 0.1)
				(type default)
			)
			(layer "F.Fab")
		)
		(fp_line
			(start 1.5748 1.1176)
			(end 1.5748 -1.1176)
			(stroke
				(width 0.1)
				(type default)
			)
			(layer "F.Fab")
		)
		(fp_line
			(start -1.5748 -1.1176)
			(end -1.5748 1.1176)
			(stroke
				(width 0.1)
				(type default)
			)
			(layer "F.Fab")
		)
		(fp_line
			(start 1.5748 -1.1176)
			(end -1.5748 -1.1176)
			(stroke
				(width 0.1)
				(type default)
			)
			(layer "F.Fab")
		)
		(fp_poly
			(pts
				(xy -1.9558 -0.649986) (xy -2.7178 -0.268986) (xy -2.7178 -1.030986)
			)
			(stroke
				(width 0)
				(type default)
			)
			(fill yes)
			(layer "F.Fab")
		)
		(pad "1" smd rect
			(at -0.999998 -0.649986 180)
			(size 0.3556 1.1176)
			(layers "F.Cu" "F.Mask" "F.Paste")
			(net "BIC_SEL_FLASH_SW0_R")
		)
		(pad "2" smd rect
			(at -0.999998 0 180)
			(size 0.3556 1.1176)
			(layers "F.Cu" "F.Mask" "F.Paste")
			(net "GND")
		)
		(pad "3" smd rect
			(at -0.999998 0.649986 180)
			(size 0.3556 1.1176)
			(layers "F.Cu" "F.Mask" "F.Paste")
			(net "BIC_SEL_FLASH_SW1_R")
		)
		(pad "4" smd rect
			(at 0.999998 0.649986 180)
			(size 0.3556 1.1176)
			(layers "F.Cu" "F.Mask" "F.Paste")
			(net "SEL_FLASH_PEX1_BUF")
		)
		(pad "5" smd rect
			(at 0.999998 0 180)
			(size 0.3556 1.1176)
			(layers "F.Cu" "F.Mask" "F.Paste")
			(net "P3V3_AUX")
		)
		(pad "6" smd rect
			(at 0.999998 -0.649986 180)
			(size 0.3556 1.1176)
			(layers "F.Cu" "F.Mask" "F.Paste")
			(net "SEL_FLASH_PEX0_BUF")
		)
	)
	(footprint ""
		(layer "F.Cu")
		(at 135.346948 -37.47516)
		(property "Reference" "R6063"
			(at 0 0 0)
			(layer "F.SilkS")
			(hide yes)
			(effects
				(font
					(size 1.27 1.27)
				)
			)
		)
		(property "Value" ""
			(at 0 0 0)
			(layer "F.Fab")
			(effects
				(font
					(size 1.27 1.27)
				)
			)
		)
		(duplicate_pad_numbers_are_jumpers no)
		(fp_line
			(start -0.7874 -0.4064)
			(end 0.7874 -0.4064)
			(stroke
				(width 0.1524)
				(type default)
			)
			(layer "F.SilkS")
		)
		(fp_line
			(start -0.7874 0.4064)
			(end -0.7874 -0.4064)
			(stroke
				(width 0.1524)
				(type default)
			)
			(layer "F.SilkS")
		)
		(fp_line
			(start 0.7874 -0.4064)
			(end 0.7874 0.4064)
			(stroke
				(width 0.1524)
				(type default)
			)
			(layer "F.SilkS")
		)
		(fp_line
			(start 0.7874 0.4064)
			(end -0.7874 0.4064)
			(stroke
				(width 0.1524)
				(type default)
			)
			(layer "F.SilkS")
		)
		(fp_line
			(start -0.67945 -0.305054)
			(end -0.12065 -0.305054)
			(stroke
				(width 0.1)
				(type default)
			)
			(layer "F.Fab")
		)
		(fp_line
			(start -0.67945 0.3048)
			(end -0.67945 -0.305054)
			(stroke
				(width 0.1)
				(type default)
			)
			(layer "F.Fab")
		)
		(fp_line
			(start -0.12065 -0.305054)
			(end -0.12065 -0.2794)
			(stroke
				(width 0.1)
				(type default)
			)
			(layer "F.Fab")
		)
		(fp_line
			(start -0.12065 -0.2794)
			(end 0.12065 -0.2794)
			(stroke
				(width 0.1)
				(type default)
			)
			(layer "F.Fab")
		)
		(fp_line
			(start -0.12065 0.2794)
			(end -0.12065 0.3048)
			(stroke
				(width 0.1)
				(type default)
			)
			(layer "F.Fab")
		)
		(fp_line
			(start -0.12065 0.3048)
			(end -0.67945 0.3048)
			(stroke
				(width 0.1)
				(type default)
			)
			(layer "F.Fab")
		)
		(fp_line
			(start 0.120396 0.2794)
			(end -0.12065 0.2794)
			(stroke
				(width 0.1)
				(type default)
			)
			(layer "F.Fab")
		)
		(fp_line
			(start 0.120396 0.3048)
			(end 0.120396 0.2794)
			(stroke
				(width 0.1)
				(type default)
			)
			(layer "F.Fab")
		)
		(fp_line
			(start 0.12065 -0.3048)
			(end 0.67945 -0.3048)
			(stroke
				(width 0.1)
				(type default)
			)
			(layer "F.Fab")
		)
		(fp_line
			(start 0.12065 -0.2794)
			(end 0.12065 -0.3048)
			(stroke
				(width 0.1)
				(type default)
			)
			(layer "F.Fab")
		)
		(fp_line
			(start 0.67945 -0.3048)
			(end 0.67945 0.3048)
			(stroke
				(width 0.1)
				(type default)
			)
			(layer "F.Fab")
		)
		(fp_line
			(start 0.67945 0.3048)
			(end 0.120396 0.3048)
			(stroke
				(width 0.1)
				(type default)
			)
			(layer "F.Fab")
		)
		(pad "1" smd circle
			(at -0.40005 0)
			(size 0 0)
			(layers "F.Cu" "F.Mask" "F.Paste")
			(net "P3V3_SSD5")
		)
		(pad "2" smd circle
			(at 0.40005 0)
			(size 0 0)
			(layers "F.Cu" "F.Mask" "F.Paste")
			(net "P3V3_SSD5_PG_G1")
		)
	)
	(footprint ""
		(layer "F.Cu")
		(at 82.847688 -40.037258 90)
		(property "Reference" "U366"
			(at 0.196342 2.497582 90)
			(unlocked yes)
			(layer "F.SilkS")
			(effects
				(font
					(size 0.7874 0.5842)
					(thickness 0.1524)
				)
			)
		)
		(property "Value" ""
			(at 0 0 90)
			(layer "F.Fab")
			(effects
				(font
					(size 1.27 1.27)
				)
			)
		)
		(duplicate_pad_numbers_are_jumpers no)
		(fp_line
			(start -1.949958 -1.610106)
			(end 1.949958 -1.610106)
			(stroke
				(width 0.1524)
				(type default)
			)
			(layer "F.SilkS")
		)
		(fp_line
			(start 1.949958 -1.560068)
			(end 1.949958 1.610106)
			(stroke
				(width 0.1524)
				(type default)
			)
			(layer "F.SilkS")
		)
		(fp_line
			(start 1.949958 1.610106)
			(end -1.949958 1.610106)
			(stroke
				(width 0.1524)
				(type default)
			)
			(layer "F.SilkS")
		)
		(fp_line
			(start -1.949958 1.610106)
			(end -1.949958 -1.610106)
			(stroke
				(width 0.1524)
				(type default)
			)
			(layer "F.SilkS")
		)
		(fp_line
			(start 0.750062 -1.560068)
			(end 0.750062 1.560068)
			(stroke
				(width 0.1)
				(type default)
			)
			(layer "F.Fab")
		)
		(fp_line
			(start -0.750062 -1.560068)
			(end 0.750062 -1.560068)
			(stroke
				(width 0.1)
				(type default)
			)
			(layer "F.Fab")
		)
		(fp_line
			(start 0.750062 1.560068)
			(end -0.750062 1.560068)
			(stroke
				(width 0.1)
				(type default)
			)
			(layer "F.Fab")
		)
		(fp_line
			(start -0.750062 1.560068)
			(end -0.750062 -1.560068)
			(stroke
				(width 0.1)
				(type default)
			)
			(layer "F.Fab")
		)
		(pad "D" smd rect
			(at 1.100074 0)
			(size 1.016 1.4224)
			(layers "F.Cu" "F.Mask" "F.Paste")
			(net "SSD3_AUX_P3V3_EN")
		)
		(pad "G" smd rect
			(at -1.100074 -0.94996)
			(size 1.016 1.4224)
			(layers "F.Cu" "F.Mask" "F.Paste")
			(net "PRSNT_SSD3_R1_N")
		)
		(pad "S" smd rect
			(at -1.100074 0.94996)
			(size 1.016 1.4224)
			(layers "F.Cu" "F.Mask" "F.Paste")
			(net "GND")
		)
	)
	(footprint ""
		(layer "F.Cu")
		(at 270.807942 -163.061396 180)
		(property "Reference" "R208"
			(at 0 0 180)
			(layer "F.SilkS")
			(hide yes)
			(effects
				(font
					(size 1.27 1.27)
				)
			)
		)
		(property "Value" ""
			(at 0 0 180)
			(layer "F.Fab")
			(effects
				(font
					(size 1.27 1.27)
				)
			)
		)
		(duplicate_pad_numbers_are_jumpers no)
		(fp_line
			(start 0.7874 0.4064)
			(end -0.7874 0.4064)
			(stroke
				(width 0.1524)
				(type default)
			)
			(layer "F.SilkS")
		)
		(fp_line
			(start 0.7874 -0.4064)
			(end 0.7874 0.4064)
			(stroke
				(width 0.1524)
				(type default)
			)
			(layer "F.SilkS")
		)
		(fp_line
			(start -0.7874 0.4064)
			(end -0.7874 -0.4064)
			(stroke
				(width 0.1524)
				(type default)
			)
			(layer "F.SilkS")
		)
		(fp_line
			(start -0.7874 -0.4064)
			(end 0.7874 -0.4064)
			(stroke
				(width 0.1524)
				(type default)
			)
			(layer "F.SilkS")
		)
		(fp_line
			(start 0.67945 0.3048)
			(end 0.120396 0.3048)
			(stroke
				(width 0.1)
				(type default)
			)
			(layer "F.Fab")
		)
		(fp_line
			(start 0.67945 -0.3048)
			(end 0.67945 0.3048)
			(stroke
				(width 0.1)
				(type default)
			)
			(layer "F.Fab")
		)
		(fp_line
			(start 0.12065 -0.2794)
			(end 0.12065 -0.3048)
			(stroke
				(width 0.1)
				(type default)
			)
			(layer "F.Fab")
		)
		(fp_line
			(start 0.12065 -0.3048)
			(end 0.67945 -0.3048)
			(stroke
				(width 0.1)
				(type default)
			)
			(layer "F.Fab")
		)
		(fp_line
			(start 0.120396 0.3048)
			(end 0.120396 0.2794)
			(stroke
				(width 0.1)
				(type default)
			)
			(layer "F.Fab")
		)
		(fp_line
			(start 0.120396 0.2794)
			(end -0.12065 0.2794)
			(stroke
				(width 0.1)
				(type default)
			)
			(layer "F.Fab")
		)
		(fp_line
			(start -0.12065 0.3048)
			(end -0.67945 0.3048)
			(stroke
				(width 0.1)
				(type default)
			)
			(layer "F.Fab")
		)
		(fp_line
			(start -0.12065 0.2794)
			(end -0.12065 0.3048)
			(stroke
				(width 0.1)
				(type default)
			)
			(layer "F.Fab")
		)
		(fp_line
			(start -0.12065 -0.2794)
			(end 0.12065 -0.2794)
			(stroke
				(width 0.1)
				(type default)
			)
			(layer "F.Fab")
		)
		(fp_line
			(start -0.12065 -0.305054)
			(end -0.12065 -0.2794)
			(stroke
				(width 0.1)
				(type default)
			)
			(layer "F.Fab")
		)
		(fp_line
			(start -0.67945 0.3048)
			(end -0.67945 -0.305054)
			(stroke
				(width 0.1)
				(type default)
			)
			(layer "F.Fab")
		)
		(fp_line
			(start -0.67945 -0.305054)
			(end -0.12065 -0.305054)
			(stroke
				(width 0.1)
				(type default)
			)
			(layer "F.Fab")
		)
		(pad "1" smd circle
			(at -0.40005 0 180)
			(size 0 0)
			(layers "F.Cu" "F.Mask" "F.Paste")
			(net "PWRGD_NIC4_PWR_GOOD")
		)
		(pad "2" smd circle
			(at 0.40005 0 180)
			(size 0 0)
			(layers "F.Cu" "F.Mask" "F.Paste")
			(net "PWRGD_NIC4_PWR_GOOD_R")
		)
	)
	(footprint ""
		(layer "F.Cu")
		(at 304.87493 -56.977534 180)
		(property "Reference" "PC364"
			(at 0 0 180)
			(layer "F.SilkS")
			(hide yes)
			(effects
				(font
					(size 1.27 1.27)
				)
			)
		)
		(property "Value" ""
			(at 0 0 180)
			(layer "F.Fab")
			(effects
				(font
					(size 1.27 1.27)
				)
			)
		)
		(duplicate_pad_numbers_are_jumpers no)
		(fp_line
			(start 0.7874 0.4064)
			(end -0.7874 0.4064)
			(stroke
				(width 0.1524)
				(type default)
			)
			(layer "F.SilkS")
		)
		(fp_line
			(start 0.7874 -0.4064)
			(end 0.7874 0.4064)
			(stroke
				(width 0.1524)
				(type default)
			)
			(layer "F.SilkS")
		)
		(fp_line
			(start -0.7874 0.4064)
			(end -0.7874 -0.4064)
			(stroke
				(width 0.1524)
				(type default)
			)
			(layer "F.SilkS")
		)
		(fp_line
			(start -0.7874 -0.4064)
			(end 0.7874 -0.4064)
			(stroke
				(width 0.1524)
				(type default)
			)
			(layer "F.SilkS")
		)
		(fp_line
			(start 0.67945 0.3048)
			(end 0.120396 0.3048)
			(stroke
				(width 0.1)
				(type default)
			)
			(layer "F.Fab")
		)
		(fp_line
			(start 0.67945 -0.3048)
			(end 0.67945 0.3048)
			(stroke
				(width 0.1)
				(type default)
			)
			(layer "F.Fab")
		)
		(fp_line
			(start 0.12065 -0.2794)
			(end 0.12065 -0.3048)
			(stroke
				(width 0.1)
				(type default)
			)
			(layer "F.Fab")
		)
		(fp_line
			(start 0.12065 -0.3048)
			(end 0.67945 -0.3048)
			(stroke
				(width 0.1)
				(type default)
			)
			(layer "F.Fab")
		)
		(fp_line
			(start 0.120396 0.3048)
			(end 0.120396 0.2794)
			(stroke
				(width 0.1)
				(type default)
			)
			(layer "F.Fab")
		)
		(fp_line
			(start 0.120396 0.2794)
			(end -0.12065 0.2794)
			(stroke
				(width 0.1)
				(type default)
			)
			(layer "F.Fab")
		)
		(fp_line
			(start -0.12065 0.3048)
			(end -0.67945 0.3048)
			(stroke
				(width 0.1)
				(type default)
			)
			(layer "F.Fab")
		)
		(fp_line
			(start -0.12065 0.2794)
			(end -0.12065 0.3048)
			(stroke
				(width 0.1)
				(type default)
			)
			(layer "F.Fab")
		)
		(fp_line
			(start -0.12065 -0.2794)
			(end 0.12065 -0.2794)
			(stroke
				(width 0.1)
				(type default)
			)
			(layer "F.Fab")
		)
		(fp_line
			(start -0.12065 -0.305054)
			(end -0.12065 -0.2794)
			(stroke
				(width 0.1)
				(type default)
			)
			(layer "F.Fab")
		)
		(fp_line
			(start -0.67945 0.3048)
			(end -0.67945 -0.305054)
			(stroke
				(width 0.1)
				(type default)
			)
			(layer "F.Fab")
		)
		(fp_line
			(start -0.67945 -0.305054)
			(end -0.12065 -0.305054)
			(stroke
				(width 0.1)
				(type default)
			)
			(layer "F.Fab")
		)
		(pad "1" smd circle
			(at -0.40005 0 180)
			(size 0 0)
			(layers "F.Cu" "F.Mask" "F.Paste")
			(net "P12V_AUX")
		)
		(pad "2" smd circle
			(at 0.40005 0 180)
			(size 0 0)
			(layers "F.Cu" "F.Mask" "F.Paste")
			(net "GND")
		)
	)
	(footprint ""
		(layer "F.Cu")
		(at 344.675968 -279.101804)
		(property "Reference" "PC156"
			(at 0 0 0)
			(layer "F.SilkS")
			(hide yes)
			(effects
				(font
					(size 1.27 1.27)
				)
			)
		)
		(property "Value" ""
			(at 0 0 0)
			(layer "F.Fab")
			(effects
				(font
					(size 1.27 1.27)
				)
			)
		)
		(duplicate_pad_numbers_are_jumpers no)
		(fp_line
			(start -0.7874 -0.4064)
			(end 0.7874 -0.4064)
			(stroke
				(width 0.1524)
				(type default)
			)
			(layer "F.SilkS")
		)
		(fp_line
			(start -0.7874 0.4064)
			(end -0.7874 -0.4064)
			(stroke
				(width 0.1524)
				(type default)
			)
			(layer "F.SilkS")
		)
		(fp_line
			(start 0.7874 -0.4064)
			(end 0.7874 0.4064)
			(stroke
				(width 0.1524)
				(type default)
			)
			(layer "F.SilkS")
		)
		(fp_line
			(start 0.7874 0.4064)
			(end -0.7874 0.4064)
			(stroke
				(width 0.1524)
				(type default)
			)
			(layer "F.SilkS")
		)
		(fp_line
			(start -0.67945 -0.305054)
			(end -0.12065 -0.305054)
			(stroke
				(width 0.1)
				(type default)
			)
			(layer "F.Fab")
		)
		(fp_line
			(start -0.67945 0.3048)
			(end -0.67945 -0.305054)
			(stroke
				(width 0.1)
				(type default)
			)
			(layer "F.Fab")
		)
		(fp_line
			(start -0.12065 -0.305054)
			(end -0.12065 -0.2794)
			(stroke
				(width 0.1)
				(type default)
			)
			(layer "F.Fab")
		)
		(fp_line
			(start -0.12065 -0.2794)
			(end 0.12065 -0.2794)
			(stroke
				(width 0.1)
				(type default)
			)
			(layer "F.Fab")
		)
		(fp_line
			(start -0.12065 0.2794)
			(end -0.12065 0.3048)
			(stroke
				(width 0.1)
				(type default)
			)
			(layer "F.Fab")
		)
		(fp_line
			(start -0.12065 0.3048)
			(end -0.67945 0.3048)
			(stroke
				(width 0.1)
				(type default)
			)
			(layer "F.Fab")
		)
		(fp_line
			(start 0.120396 0.2794)
			(end -0.12065 0.2794)
			(stroke
				(width 0.1)
				(type default)
			)
			(layer "F.Fab")
		)
		(fp_line
			(start 0.120396 0.3048)
			(end 0.120396 0.2794)
			(stroke
				(width 0.1)
				(type default)
			)
			(layer "F.Fab")
		)
		(fp_line
			(start 0.12065 -0.3048)
			(end 0.67945 -0.3048)
			(stroke
				(width 0.1)
				(type default)
			)
			(layer "F.Fab")
		)
		(fp_line
			(start 0.12065 -0.2794)
			(end 0.12065 -0.3048)
			(stroke
				(width 0.1)
				(type default)
			)
			(layer "F.Fab")
		)
		(fp_line
			(start 0.67945 -0.3048)
			(end 0.67945 0.3048)
			(stroke
				(width 0.1)
				(type default)
			)
			(layer "F.Fab")
		)
		(fp_line
			(start 0.67945 0.3048)
			(end 0.120396 0.3048)
			(stroke
				(width 0.1)
				(type default)
			)
			(layer "F.Fab")
		)
		(pad "1" smd circle
			(at -0.40005 0)
			(size 0 0)
			(layers "F.Cu" "F.Mask" "F.Paste")
			(net "SW_P12V_P0V8_PEX2_FLT")
		)
		(pad "2" smd circle
			(at 0.40005 0)
			(size 0 0)
			(layers "F.Cu" "F.Mask" "F.Paste")
			(net "GND")
		)
	)
	(footprint ""
		(layer "F.Cu")
		(at 365.506 -207.899 180)
		(property "Reference" "R4627"
			(at 0 0 180)
			(layer "F.SilkS")
			(hide yes)
			(effects
				(font
					(size 1.27 1.27)
				)
			)
		)
		(property "Value" ""
			(at 0 0 180)
			(layer "F.Fab")
			(effects
				(font
					(size 1.27 1.27)
				)
			)
		)
		(duplicate_pad_numbers_are_jumpers no)
		(fp_line
			(start 0.7874 0.4064)
			(end -0.7874 0.4064)
			(stroke
				(width 0.1524)
				(type default)
			)
			(layer "F.SilkS")
		)
		(fp_line
			(start 0.7874 -0.4064)
			(end 0.7874 0.4064)
			(stroke
				(width 0.1524)
				(type default)
			)
			(layer "F.SilkS")
		)
		(fp_line
			(start -0.7874 0.4064)
			(end -0.7874 -0.4064)
			(stroke
				(width 0.1524)
				(type default)
			)
			(layer "F.SilkS")
		)
		(fp_line
			(start -0.7874 -0.4064)
			(end 0.7874 -0.4064)
			(stroke
				(width 0.1524)
				(type default)
			)
			(layer "F.SilkS")
		)
		(fp_line
			(start 0.67945 0.3048)
			(end 0.120396 0.3048)
			(stroke
				(width 0.1)
				(type default)
			)
			(layer "F.Fab")
		)
		(fp_line
			(start 0.67945 -0.3048)
			(end 0.67945 0.3048)
			(stroke
				(width 0.1)
				(type default)
			)
			(layer "F.Fab")
		)
		(fp_line
			(start 0.12065 -0.2794)
			(end 0.12065 -0.3048)
			(stroke
				(width 0.1)
				(type default)
			)
			(layer "F.Fab")
		)
		(fp_line
			(start 0.12065 -0.3048)
			(end 0.67945 -0.3048)
			(stroke
				(width 0.1)
				(type default)
			)
			(layer "F.Fab")
		)
		(fp_line
			(start 0.120396 0.3048)
			(end 0.120396 0.2794)
			(stroke
				(width 0.1)
				(type default)
			)
			(layer "F.Fab")
		)
		(fp_line
			(start 0.120396 0.2794)
			(end -0.12065 0.2794)
			(stroke
				(width 0.1)
				(type default)
			)
			(layer "F.Fab")
		)
		(fp_line
			(start -0.12065 0.3048)
			(end -0.67945 0.3048)
			(stroke
				(width 0.1)
				(type default)
			)
			(layer "F.Fab")
		)
		(fp_line
			(start -0.12065 0.2794)
			(end -0.12065 0.3048)
			(stroke
				(width 0.1)
				(type default)
			)
			(layer "F.Fab")
		)
		(fp_line
			(start -0.12065 -0.2794)
			(end 0.12065 -0.2794)
			(stroke
				(width 0.1)
				(type default)
			)
			(layer "F.Fab")
		)
		(fp_line
			(start -0.12065 -0.305054)
			(end -0.12065 -0.2794)
			(stroke
				(width 0.1)
				(type default)
			)
			(layer "F.Fab")
		)
		(fp_line
			(start -0.67945 0.3048)
			(end -0.67945 -0.305054)
			(stroke
				(width 0.1)
				(type default)
			)
			(layer "F.Fab")
		)
		(fp_line
			(start -0.67945 -0.305054)
			(end -0.12065 -0.305054)
			(stroke
				(width 0.1)
				(type default)
			)
			(layer "F.Fab")
		)
		(pad "1" smd circle
			(at -0.40005 0 180)
			(size 0 0)
			(layers "F.Cu" "F.Mask" "F.Paste")
			(net "PRSNT_SSD1_FPGA_PCA9555_N")
		)
		(pad "2" smd circle
			(at 0.40005 0 180)
			(size 0 0)
			(layers "F.Cu" "F.Mask" "F.Paste")
			(net "PRSNT_SSD1_FPGA_R_N")
		)
	)
	(footprint ""
		(layer "F.Cu")
		(at 248.094754 -273.471386)
		(property "Reference" "R793"
			(at 0 0 0)
			(layer "F.SilkS")
			(hide yes)
			(effects
				(font
					(size 1.27 1.27)
				)
			)
		)
		(property "Value" ""
			(at 0 0 0)
			(layer "F.Fab")
			(effects
				(font
					(size 1.27 1.27)
				)
			)
		)
		(duplicate_pad_numbers_are_jumpers no)
		(fp_line
			(start -0.7874 -0.4064)
			(end 0.7874 -0.4064)
			(stroke
				(width 0.1524)
				(type default)
			)
			(layer "F.SilkS")
		)
		(fp_line
			(start -0.7874 0.4064)
			(end -0.7874 -0.4064)
			(stroke
				(width 0.1524)
				(type default)
			)
			(layer "F.SilkS")
		)
		(fp_line
			(start 0.7874 -0.4064)
			(end 0.7874 0.4064)
			(stroke
				(width 0.1524)
				(type default)
			)
			(layer "F.SilkS")
		)
		(fp_line
			(start 0.7874 0.4064)
			(end -0.7874 0.4064)
			(stroke
				(width 0.1524)
				(type default)
			)
			(layer "F.SilkS")
		)
		(fp_line
			(start -0.67945 -0.305054)
			(end -0.12065 -0.305054)
			(stroke
				(width 0.1)
				(type default)
			)
			(layer "F.Fab")
		)
		(fp_line
			(start -0.67945 0.3048)
			(end -0.67945 -0.305054)
			(stroke
				(width 0.1)
				(type default)
			)
			(layer "F.Fab")
		)
		(fp_line
			(start -0.12065 -0.305054)
			(end -0.12065 -0.2794)
			(stroke
				(width 0.1)
				(type default)
			)
			(layer "F.Fab")
		)
		(fp_line
			(start -0.12065 -0.2794)
			(end 0.12065 -0.2794)
			(stroke
				(width 0.1)
				(type default)
			)
			(layer "F.Fab")
		)
		(fp_line
			(start -0.12065 0.2794)
			(end -0.12065 0.3048)
			(stroke
				(width 0.1)
				(type default)
			)
			(layer "F.Fab")
		)
		(fp_line
			(start -0.12065 0.3048)
			(end -0.67945 0.3048)
			(stroke
				(width 0.1)
				(type default)
			)
			(layer "F.Fab")
		)
		(fp_line
			(start 0.120396 0.2794)
			(end -0.12065 0.2794)
			(stroke
				(width 0.1)
				(type default)
			)
			(layer "F.Fab")
		)
		(fp_line
			(start 0.120396 0.3048)
			(end 0.120396 0.2794)
			(stroke
				(width 0.1)
				(type default)
			)
			(layer "F.Fab")
		)
		(fp_line
			(start 0.12065 -0.3048)
			(end 0.67945 -0.3048)
			(stroke
				(width 0.1)
				(type default)
			)
			(layer "F.Fab")
		)
		(fp_line
			(start 0.12065 -0.2794)
			(end 0.12065 -0.3048)
			(stroke
				(width 0.1)
				(type default)
			)
			(layer "F.Fab")
		)
		(fp_line
			(start 0.67945 -0.3048)
			(end 0.67945 0.3048)
			(stroke
				(width 0.1)
				(type default)
			)
			(layer "F.Fab")
		)
		(fp_line
			(start 0.67945 0.3048)
			(end 0.120396 0.3048)
			(stroke
				(width 0.1)
				(type default)
			)
			(layer "F.Fab")
		)
		(pad "1" smd circle
			(at -0.40005 0)
			(size 0 0)
			(layers "F.Cu" "F.Mask" "F.Paste")
			(net "PEX2_P1V25_ADC_A1")
		)
		(pad "2" smd circle
			(at 0.40005 0)
			(size 0 0)
			(layers "F.Cu" "F.Mask" "F.Paste")
			(net "P3V3_AUX")
		)
	)
	(footprint ""
		(layer "F.Cu")
		(at 369.495578 -87.213694 180)
		(property "Reference" "R1610"
			(at 0 0 180)
			(layer "F.SilkS")
			(hide yes)
			(effects
				(font
					(size 1.27 1.27)
				)
			)
		)
		(property "Value" ""
			(at 0 0 180)
			(layer "F.Fab")
			(effects
				(font
					(size 1.27 1.27)
				)
			)
		)
		(duplicate_pad_numbers_are_jumpers no)
		(fp_line
			(start 0.7874 0.4064)
			(end -0.7874 0.4064)
			(stroke
				(width 0.1524)
				(type default)
			)
			(layer "F.SilkS")
		)
		(fp_line
			(start 0.7874 -0.4064)
			(end 0.7874 0.4064)
			(stroke
				(width 0.1524)
				(type default)
			)
			(layer "F.SilkS")
		)
		(fp_line
			(start -0.7874 0.4064)
			(end -0.7874 -0.4064)
			(stroke
				(width 0.1524)
				(type default)
			)
			(layer "F.SilkS")
		)
		(fp_line
			(start -0.7874 -0.4064)
			(end 0.7874 -0.4064)
			(stroke
				(width 0.1524)
				(type default)
			)
			(layer "F.SilkS")
		)
		(fp_line
			(start 0.67945 0.3048)
			(end 0.120396 0.3048)
			(stroke
				(width 0.1)
				(type default)
			)
			(layer "F.Fab")
		)
		(fp_line
			(start 0.67945 -0.3048)
			(end 0.67945 0.3048)
			(stroke
				(width 0.1)
				(type default)
			)
			(layer "F.Fab")
		)
		(fp_line
			(start 0.12065 -0.2794)
			(end 0.12065 -0.3048)
			(stroke
				(width 0.1)
				(type default)
			)
			(layer "F.Fab")
		)
		(fp_line
			(start 0.12065 -0.3048)
			(end 0.67945 -0.3048)
			(stroke
				(width 0.1)
				(type default)
			)
			(layer "F.Fab")
		)
		(fp_line
			(start 0.120396 0.3048)
			(end 0.120396 0.2794)
			(stroke
				(width 0.1)
				(type default)
			)
			(layer "F.Fab")
		)
		(fp_line
			(start 0.120396 0.2794)
			(end -0.12065 0.2794)
			(stroke
				(width 0.1)
				(type default)
			)
			(layer "F.Fab")
		)
		(fp_line
			(start -0.12065 0.3048)
			(end -0.67945 0.3048)
			(stroke
				(width 0.1)
				(type default)
			)
			(layer "F.Fab")
		)
		(fp_line
			(start -0.12065 0.2794)
			(end -0.12065 0.3048)
			(stroke
				(width 0.1)
				(type default)
			)
			(layer "F.Fab")
		)
		(fp_line
			(start -0.12065 -0.2794)
			(end 0.12065 -0.2794)
			(stroke
				(width 0.1)
				(type default)
			)
			(layer "F.Fab")
		)
		(fp_line
			(start -0.12065 -0.305054)
			(end -0.12065 -0.2794)
			(stroke
				(width 0.1)
				(type default)
			)
			(layer "F.Fab")
		)
		(fp_line
			(start -0.67945 0.3048)
			(end -0.67945 -0.305054)
			(stroke
				(width 0.1)
				(type default)
			)
			(layer "F.Fab")
		)
		(fp_line
			(start -0.67945 -0.305054)
			(end -0.12065 -0.305054)
			(stroke
				(width 0.1)
				(type default)
			)
			(layer "F.Fab")
		)
		(pad "1" smd circle
			(at -0.40005 0 180)
			(size 0 0)
			(layers "F.Cu" "F.Mask" "F.Paste")
			(net "P3V3_AUX")
		)
		(pad "2" smd circle
			(at 0.40005 0 180)
			(size 0 0)
			(layers "F.Cu" "F.Mask" "F.Paste")
			(net "SMB_BIC_I2C9_MUX1_SSD14_R_SCL")
		)
	)
	(footprint ""
		(layer "F.Cu")
		(at 270.807942 -160.380934)
		(property "Reference" "R227"
			(at 0 0 0)
			(layer "F.SilkS")
			(hide yes)
			(effects
				(font
					(size 1.27 1.27)
				)
			)
		)
		(property "Value" ""
			(at 0 0 0)
			(layer "F.Fab")
			(effects
				(font
					(size 1.27 1.27)
				)
			)
		)
		(duplicate_pad_numbers_are_jumpers no)
		(fp_line
			(start -0.7874 -0.4064)
			(end 0.7874 -0.4064)
			(stroke
				(width 0.1524)
				(type default)
			)
			(layer "F.SilkS")
		)
		(fp_line
			(start -0.7874 0.4064)
			(end -0.7874 -0.4064)
			(stroke
				(width 0.1524)
				(type default)
			)
			(layer "F.SilkS")
		)
		(fp_line
			(start 0.7874 -0.4064)
			(end 0.7874 0.4064)
			(stroke
				(width 0.1524)
				(type default)
			)
			(layer "F.SilkS")
		)
		(fp_line
			(start 0.7874 0.4064)
			(end -0.7874 0.4064)
			(stroke
				(width 0.1524)
				(type default)
			)
			(layer "F.SilkS")
		)
		(fp_line
			(start -0.67945 -0.305054)
			(end -0.12065 -0.305054)
			(stroke
				(width 0.1)
				(type default)
			)
			(layer "F.Fab")
		)
		(fp_line
			(start -0.67945 0.3048)
			(end -0.67945 -0.305054)
			(stroke
				(width 0.1)
				(type default)
			)
			(layer "F.Fab")
		)
		(fp_line
			(start -0.12065 -0.305054)
			(end -0.12065 -0.2794)
			(stroke
				(width 0.1)
				(type default)
			)
			(layer "F.Fab")
		)
		(fp_line
			(start -0.12065 -0.2794)
			(end 0.12065 -0.2794)
			(stroke
				(width 0.1)
				(type default)
			)
			(layer "F.Fab")
		)
		(fp_line
			(start -0.12065 0.2794)
			(end -0.12065 0.3048)
			(stroke
				(width 0.1)
				(type default)
			)
			(layer "F.Fab")
		)
		(fp_line
			(start -0.12065 0.3048)
			(end -0.67945 0.3048)
			(stroke
				(width 0.1)
				(type default)
			)
			(layer "F.Fab")
		)
		(fp_line
			(start 0.120396 0.2794)
			(end -0.12065 0.2794)
			(stroke
				(width 0.1)
				(type default)
			)
			(layer "F.Fab")
		)
		(fp_line
			(start 0.120396 0.3048)
			(end 0.120396 0.2794)
			(stroke
				(width 0.1)
				(type default)
			)
			(layer "F.Fab")
		)
		(fp_line
			(start 0.12065 -0.3048)
			(end 0.67945 -0.3048)
			(stroke
				(width 0.1)
				(type default)
			)
			(layer "F.Fab")
		)
		(fp_line
			(start 0.12065 -0.2794)
			(end 0.12065 -0.3048)
			(stroke
				(width 0.1)
				(type default)
			)
			(layer "F.Fab")
		)
		(fp_line
			(start 0.67945 -0.3048)
			(end 0.67945 0.3048)
			(stroke
				(width 0.1)
				(type default)
			)
			(layer "F.Fab")
		)
		(fp_line
			(start 0.67945 0.3048)
			(end 0.120396 0.3048)
			(stroke
				(width 0.1)
				(type default)
			)
			(layer "F.Fab")
		)
		(pad "1" smd circle
			(at -0.40005 0)
			(size 0 0)
			(layers "F.Cu" "F.Mask" "F.Paste")
			(net "NIC4_MAIN_PWR_EN")
		)
		(pad "2" smd circle
			(at 0.40005 0)
			(size 0 0)
			(layers "F.Cu" "F.Mask" "F.Paste")
			(net "GND")
		)
	)
	(footprint ""
		(layer "F.Cu")
		(at 330.05014 -95.263716 -90)
		(property "Reference" "PR198"
			(at 0 0 270)
			(layer "F.SilkS")
			(hide yes)
			(effects
				(font
					(size 1.27 1.27)
				)
			)
		)
		(property "Value" ""
			(at 0 0 270)
			(layer "F.Fab")
			(effects
				(font
					(size 1.27 1.27)
				)
			)
		)
		(duplicate_pad_numbers_are_jumpers no)
		(fp_line
			(start -0.7874 0.4064)
			(end -0.7874 -0.4064)
			(stroke
				(width 0.1524)
				(type default)
			)
			(layer "F.SilkS")
		)
		(fp_line
			(start 0.7874 0.4064)
			(end -0.7874 0.4064)
			(stroke
				(width 0.1524)
				(type default)
			)
			(layer "F.SilkS")
		)
		(fp_line
			(start -0.7874 -0.4064)
			(end 0.7874 -0.4064)
			(stroke
				(width 0.1524)
				(type default)
			)
			(layer "F.SilkS")
		)
		(fp_line
			(start 0.7874 -0.4064)
			(end 0.7874 0.4064)
			(stroke
				(width 0.1524)
				(type default)
			)
			(layer "F.SilkS")
		)
		(fp_line
			(start -0.67945 0.3048)
			(end -0.67945 -0.305054)
			(stroke
				(width 0.1)
				(type default)
			)
			(layer "F.Fab")
		)
		(fp_line
			(start -0.12065 0.3048)
			(end -0.67945 0.3048)
			(stroke
				(width 0.1)
				(type default)
			)
			(layer "F.Fab")
		)
		(fp_line
			(start 0.120396 0.3048)
			(end 0.120396 0.2794)
			(stroke
				(width 0.1)
				(type default)
			)
			(layer "F.Fab")
		)
		(fp_line
			(start 0.67945 0.3048)
			(end 0.120396 0.3048)
			(stroke
				(width 0.1)
				(type default)
			)
			(layer "F.Fab")
		)
		(fp_line
			(start -0.12065 0.2794)
			(end -0.12065 0.3048)
			(stroke
				(width 0.1)
				(type default)
			)
			(layer "F.Fab")
		)
		(fp_line
			(start 0.120396 0.2794)
			(end -0.12065 0.2794)
			(stroke
				(width 0.1)
				(type default)
			)
			(layer "F.Fab")
		)
		(fp_line
			(start -0.12065 -0.2794)
			(end 0.12065 -0.2794)
			(stroke
				(width 0.1)
				(type default)
			)
			(layer "F.Fab")
		)
		(fp_line
			(start 0.12065 -0.2794)
			(end 0.12065 -0.3048)
			(stroke
				(width 0.1)
				(type default)
			)
			(layer "F.Fab")
		)
		(fp_line
			(start 0.12065 -0.3048)
			(end 0.67945 -0.3048)
			(stroke
				(width 0.1)
				(type default)
			)
			(layer "F.Fab")
		)
		(fp_line
			(start 0.67945 -0.3048)
			(end 0.67945 0.3048)
			(stroke
				(width 0.1)
				(type default)
			)
			(layer "F.Fab")
		)
		(fp_line
			(start -0.67945 -0.305054)
			(end -0.12065 -0.305054)
			(stroke
				(width 0.1)
				(type default)
			)
			(layer "F.Fab")
		)
		(fp_line
			(start -0.12065 -0.305054)
			(end -0.12065 -0.2794)
			(stroke
				(width 0.1)
				(type default)
			)
			(layer "F.Fab")
		)
		(pad "1" smd circle
			(at -0.40005 0 270)
			(size 0 0)
			(layers "F.Cu" "F.Mask" "F.Paste")
			(net "P12V_NIC5_OCP")
		)
		(pad "2" smd circle
			(at 0.40005 0 270)
			(size 0 0)
			(layers "F.Cu" "F.Mask" "F.Paste")
			(net "GND")
		)
	)
	(footprint ""
		(layer "F.Cu")
		(at 390.288018 -45.704252 90)
		(property "Reference" "R649"
			(at 0 0 90)
			(layer "F.SilkS")
			(hide yes)
			(effects
				(font
					(size 1.27 1.27)
				)
			)
		)
		(property "Value" ""
			(at 0 0 90)
			(layer "F.Fab")
			(effects
				(font
					(size 1.27 1.27)
				)
			)
		)
		(duplicate_pad_numbers_are_jumpers no)
		(fp_line
			(start 3.937508 -1.8796)
			(end -3.937508 -1.8796)
			(stroke
				(width 0.1524)
				(type default)
			)
			(layer "F.SilkS")
		)
		(fp_line
			(start -3.937508 -1.8796)
			(end -3.937508 1.8796)
			(stroke
				(width 0.1524)
				(type default)
			)
			(layer "F.SilkS")
		)
		(fp_line
			(start 3.937508 1.8796)
			(end 3.937508 -1.8796)
			(stroke
				(width 0.1524)
				(type default)
			)
			(layer "F.SilkS")
		)
		(fp_line
			(start -3.937508 1.8796)
			(end 3.937508 1.8796)
			(stroke
				(width 0.1524)
				(type default)
			)
			(layer "F.SilkS")
		)
		(fp_line
			(start 3.275076 -1.674876)
			(end -3.275076 -1.674876)
			(stroke
				(width 0.1)
				(type default)
			)
			(layer "F.Fab")
		)
		(fp_line
			(start -3.275076 -1.674876)
			(end -3.275076 1.674876)
			(stroke
				(width 0.1)
				(type default)
			)
			(layer "F.Fab")
		)
		(fp_line
			(start 3.275076 1.674876)
			(end 3.275076 -1.674876)
			(stroke
				(width 0.1)
				(type default)
			)
			(layer "F.Fab")
		)
		(fp_line
			(start -3.275076 1.674876)
			(end 3.275076 1.674876)
			(stroke
				(width 0.1)
				(type default)
			)
			(layer "F.Fab")
		)
		(pad "1" smd rect
			(at -2.350008 0 90)
			(size 2.921 3.5052)
			(layers "F.Cu" "F.Mask" "F.Paste")
			(net "P12V_SSD13")
		)
		(pad "2" smd rect
			(at 2.350008 0 90)
			(size 2.921 3.5052)
			(layers "F.Cu" "F.Mask" "F.Paste")
			(net "P12V_SSD13_R")
		)
	)
	(footprint ""
		(layer "F.Cu")
		(at 331.350112 -289.820096)
		(property "Reference" "H140"
			(at -1.30429 4.559808 0)
			(unlocked yes)
			(layer "F.SilkS")
			(effects
				(font
					(size 0.7874 0.5842)
					(thickness 0.1524)
				)
				(justify left)
			)
		)
		(property "Value" ""
			(at 0 0 0)
			(layer "F.Fab")
			(effects
				(font
					(size 1.27 1.27)
				)
			)
		)
		(duplicate_pad_numbers_are_jumpers no)
		(pad "1" thru_hole circle
			(at 0 0)
			(size 6.5024 6.5024)
			(drill 3.2004)
			(layers "*.Cu" "*.Mask")
			(remove_unused_layers no)
			(net "GND")
			(clearance -1.397)
		)
	)
	(footprint ""
		(layer "F.Cu")
		(at 330.63434 -30.94609 180)
		(property "Reference" "C515"
			(at 0 0 180)
			(layer "F.SilkS")
			(hide yes)
			(effects
				(font
					(size 1.27 1.27)
				)
			)
		)
		(property "Value" ""
			(at 0 0 180)
			(layer "F.Fab")
			(effects
				(font
					(size 1.27 1.27)
				)
			)
		)
		(duplicate_pad_numbers_are_jumpers no)
		(fp_line
			(start 0.299974 0.150114)
			(end -0.299974 0.150114)
			(stroke
				(width 0.1)
				(type default)
			)
			(layer "F.Fab")
		)
		(fp_line
			(start 0.299974 -0.150114)
			(end 0.299974 0.150114)
			(stroke
				(width 0.1)
				(type default)
			)
			(layer "F.Fab")
		)
		(fp_line
			(start -0.299974 0.150114)
			(end -0.299974 -0.150114)
			(stroke
				(width 0.1)
				(type default)
			)
			(layer "F.Fab")
		)
		(fp_line
			(start -0.299974 -0.150114)
			(end 0.299974 -0.150114)
			(stroke
				(width 0.1)
				(type default)
			)
			(layer "F.Fab")
		)
		(pad "1" smd rect
			(at -0.2667 0 180)
			(size 0.3048 0.381)
			(layers "F.Cu" "F.Mask" "F.Paste")
			(net "P5E_PEX2_STN2_TX_DP<33>")
		)
		(pad "2" smd rect
			(at 0.2667 0 180)
			(size 0.3048 0.381)
			(layers "F.Cu" "F.Mask" "F.Paste")
			(net "P5E_PEX2_STN2_TX_C_DP<33>")
		)
	)
	(footprint ""
		(layer "F.Cu")
		(at 452.543672 -45.88891)
		(property "Reference" "R675"
			(at 0 0 0)
			(layer "F.SilkS")
			(hide yes)
			(effects
				(font
					(size 1.27 1.27)
				)
			)
		)
		(property "Value" ""
			(at 0 0 0)
			(layer "F.Fab")
			(effects
				(font
					(size 1.27 1.27)
				)
			)
		)
		(duplicate_pad_numbers_are_jumpers no)
		(fp_line
			(start -0.7874 -0.4064)
			(end 0.7874 -0.4064)
			(stroke
				(width 0.1524)
				(type default)
			)
			(layer "F.SilkS")
		)
		(fp_line
			(start -0.7874 0.4064)
			(end -0.7874 -0.4064)
			(stroke
				(width 0.1524)
				(type default)
			)
			(layer "F.SilkS")
		)
		(fp_line
			(start 0.7874 -0.4064)
			(end 0.7874 0.4064)
			(stroke
				(width 0.1524)
				(type default)
			)
			(layer "F.SilkS")
		)
		(fp_line
			(start 0.7874 0.4064)
			(end -0.7874 0.4064)
			(stroke
				(width 0.1524)
				(type default)
			)
			(layer "F.SilkS")
		)
		(fp_line
			(start -0.67945 -0.305054)
			(end -0.12065 -0.305054)
			(stroke
				(width 0.1)
				(type default)
			)
			(layer "F.Fab")
		)
		(fp_line
			(start -0.67945 0.3048)
			(end -0.67945 -0.305054)
			(stroke
				(width 0.1)
				(type default)
			)
			(layer "F.Fab")
		)
		(fp_line
			(start -0.12065 -0.305054)
			(end -0.12065 -0.2794)
			(stroke
				(width 0.1)
				(type default)
			)
			(layer "F.Fab")
		)
		(fp_line
			(start -0.12065 -0.2794)
			(end 0.12065 -0.2794)
			(stroke
				(width 0.1)
				(type default)
			)
			(layer "F.Fab")
		)
		(fp_line
			(start -0.12065 0.2794)
			(end -0.12065 0.3048)
			(stroke
				(width 0.1)
				(type default)
			)
			(layer "F.Fab")
		)
		(fp_line
			(start -0.12065 0.3048)
			(end -0.67945 0.3048)
			(stroke
				(width 0.1)
				(type default)
			)
			(layer "F.Fab")
		)
		(fp_line
			(start 0.120396 0.2794)
			(end -0.12065 0.2794)
			(stroke
				(width 0.1)
				(type default)
			)
			(layer "F.Fab")
		)
		(fp_line
			(start 0.120396 0.3048)
			(end 0.120396 0.2794)
			(stroke
				(width 0.1)
				(type default)
			)
			(layer "F.Fab")
		)
		(fp_line
			(start 0.12065 -0.3048)
			(end 0.67945 -0.3048)
			(stroke
				(width 0.1)
				(type default)
			)
			(layer "F.Fab")
		)
		(fp_line
			(start 0.12065 -0.2794)
			(end 0.12065 -0.3048)
			(stroke
				(width 0.1)
				(type default)
			)
			(layer "F.Fab")
		)
		(fp_line
			(start 0.67945 -0.3048)
			(end 0.67945 0.3048)
			(stroke
				(width 0.1)
				(type default)
			)
			(layer "F.Fab")
		)
		(fp_line
			(start 0.67945 0.3048)
			(end 0.120396 0.3048)
			(stroke
				(width 0.1)
				(type default)
			)
			(layer "F.Fab")
		)
		(pad "1" smd circle
			(at -0.40005 0)
			(size 0 0)
			(layers "F.Cu" "F.Mask" "F.Paste")
			(net "SSD15_ADC_A0")
		)
		(pad "2" smd circle
			(at 0.40005 0)
			(size 0 0)
			(layers "F.Cu" "F.Mask" "F.Paste")
			(net "GND")
		)
	)
	(footprint ""
		(layer "F.Cu")
		(at 379.889512 -63.56223)
		(property "Reference" "Q209"
			(at -0.018796 -2.381758 0)
			(unlocked yes)
			(layer "F.SilkS")
			(effects
				(font
					(size 0.7874 0.5842)
					(thickness 0.1524)
				)
			)
		)
		(property "Value" ""
			(at 0 0 0)
			(layer "F.Fab")
			(effects
				(font
					(size 1.27 1.27)
				)
			)
		)
		(duplicate_pad_numbers_are_jumpers no)
		(fp_line
			(start -1.376172 -1.199896)
			(end -0.508 -1.199896)
			(stroke
				(width 0.1524)
				(type default)
			)
			(layer "F.SilkS")
		)
		(fp_line
			(start -1.376172 1.199896)
			(end -1.376172 -1.199896)
			(stroke
				(width 0.1524)
				(type default)
			)
			(layer "F.SilkS")
		)
		(fp_line
			(start -0.508 -1.199896)
			(end 0 -0.762)
			(stroke
				(width 0.1524)
				(type default)
			)
			(layer "F.SilkS")
		)
		(fp_line
			(start 0 -0.762)
			(end 0.508 -1.199896)
			(stroke
				(width 0.1524)
				(type default)
			)
			(layer "F.SilkS")
		)
		(fp_line
			(start 0.508 -1.199896)
			(end 1.376172 -1.199896)
			(stroke
				(width 0.1524)
				(type default)
			)
			(layer "F.SilkS")
		)
		(fp_line
			(start 1.376172 -1.199896)
			(end 1.376172 1.199896)
			(stroke
				(width 0.1524)
				(type default)
			)
			(layer "F.SilkS")
		)
		(fp_line
			(start 1.376172 1.199896)
			(end -1.376172 1.199896)
			(stroke
				(width 0.1524)
				(type default)
			)
			(layer "F.SilkS")
		)
		(fp_poly
			(pts
				(xy -1.452626 -1.070864) (xy -1.721866 -1.879092) (xy -2.260854 -1.340104)
			)
			(stroke
				(width 0)
				(type default)
			)
			(fill yes)
			(layer "F.SilkS")
		)
		(fp_line
			(start -0.674878 -1.100074)
			(end 0.674878 -1.100074)
			(stroke
				(width 0.1)
				(type default)
			)
			(layer "F.Fab")
		)
		(fp_line
			(start -0.674878 1.100074)
			(end -0.674878 -1.100074)
			(stroke
				(width 0.1)
				(type default)
			)
			(layer "F.Fab")
		)
		(fp_line
			(start 0.674878 -1.100074)
			(end 0.674878 1.100074)
			(stroke
				(width 0.1)
				(type default)
			)
			(layer "F.Fab")
		)
		(fp_line
			(start 0.674878 1.100074)
			(end -0.674878 1.100074)
			(stroke
				(width 0.1)
				(type default)
			)
			(layer "F.Fab")
		)
		(fp_poly
			(pts
				(xy -1.4605 -0.7493) (xy -2.2225 -1.1303) (xy -2.2225 -0.3683)
			)
			(stroke
				(width 0)
				(type default)
			)
			(fill yes)
			(layer "F.Fab")
		)
		(pad "1" smd rect
			(at -0.899922 -0.750062 270)
			(size 0.6096 0.6096)
			(layers "F.Cu" "F.Mask" "F.Paste")
			(net "GND")
		)
		(pad "2" smd rect
			(at -0.899922 0 270)
			(size 0.4064 0.6096)
			(layers "F.Cu" "F.Mask" "F.Paste")
			(net "P12V_SSD13_PG_G1")
		)
		(pad "3" smd rect
			(at -0.899922 0.750062 270)
			(size 0.6096 0.6096)
			(layers "F.Cu" "F.Mask" "F.Paste")
			(net "PWRGD_P12V_SSD13_D")
		)
		(pad "4" smd rect
			(at 0.899922 0.750062 270)
			(size 0.6096 0.6096)
			(layers "F.Cu" "F.Mask" "F.Paste")
			(net "GND")
		)
		(pad "5" smd rect
			(at 0.899922 0 270)
			(size 0.4064 0.6096)
			(layers "F.Cu" "F.Mask" "F.Paste")
			(net "P12V_SSD13_PG_G2")
		)
		(pad "6" smd rect
			(at 0.899922 -0.750062 270)
			(size 0.6096 0.6096)
			(layers "F.Cu" "F.Mask" "F.Paste")
			(net "P12V_SSD13_PG_G2")
		)
	)
	(footprint ""
		(layer "F.Cu")
		(at 169.759884 -199.932798)
		(property "Reference" "R3287"
			(at 0 0 0)
			(layer "F.SilkS")
			(hide yes)
			(effects
				(font
					(size 1.27 1.27)
				)
			)
		)
		(property "Value" ""
			(at 0 0 0)
			(layer "F.Fab")
			(effects
				(font
					(size 1.27 1.27)
				)
			)
		)
		(duplicate_pad_numbers_are_jumpers no)
		(fp_line
			(start -0.7874 -0.4064)
			(end 0.7874 -0.4064)
			(stroke
				(width 0.1524)
				(type default)
			)
			(layer "F.SilkS")
		)
		(fp_line
			(start -0.7874 0.4064)
			(end -0.7874 -0.4064)
			(stroke
				(width 0.1524)
				(type default)
			)
			(layer "F.SilkS")
		)
		(fp_line
			(start 0.7874 -0.4064)
			(end 0.7874 0.4064)
			(stroke
				(width 0.1524)
				(type default)
			)
			(layer "F.SilkS")
		)
		(fp_line
			(start 0.7874 0.4064)
			(end -0.7874 0.4064)
			(stroke
				(width 0.1524)
				(type default)
			)
			(layer "F.SilkS")
		)
		(fp_line
			(start -0.67945 -0.305054)
			(end -0.12065 -0.305054)
			(stroke
				(width 0.1)
				(type default)
			)
			(layer "F.Fab")
		)
		(fp_line
			(start -0.67945 0.3048)
			(end -0.67945 -0.305054)
			(stroke
				(width 0.1)
				(type default)
			)
			(layer "F.Fab")
		)
		(fp_line
			(start -0.12065 -0.305054)
			(end -0.12065 -0.2794)
			(stroke
				(width 0.1)
				(type default)
			)
			(layer "F.Fab")
		)
		(fp_line
			(start -0.12065 -0.2794)
			(end 0.12065 -0.2794)
			(stroke
				(width 0.1)
				(type default)
			)
			(layer "F.Fab")
		)
		(fp_line
			(start -0.12065 0.2794)
			(end -0.12065 0.3048)
			(stroke
				(width 0.1)
				(type default)
			)
			(layer "F.Fab")
		)
		(fp_line
			(start -0.12065 0.3048)
			(end -0.67945 0.3048)
			(stroke
				(width 0.1)
				(type default)
			)
			(layer "F.Fab")
		)
		(fp_line
			(start 0.120396 0.2794)
			(end -0.12065 0.2794)
			(stroke
				(width 0.1)
				(type default)
			)
			(layer "F.Fab")
		)
		(fp_line
			(start 0.120396 0.3048)
			(end 0.120396 0.2794)
			(stroke
				(width 0.1)
				(type default)
			)
			(layer "F.Fab")
		)
		(fp_line
			(start 0.12065 -0.3048)
			(end 0.67945 -0.3048)
			(stroke
				(width 0.1)
				(type default)
			)
			(layer "F.Fab")
		)
		(fp_line
			(start 0.12065 -0.2794)
			(end 0.12065 -0.3048)
			(stroke
				(width 0.1)
				(type default)
			)
			(layer "F.Fab")
		)
		(fp_line
			(start 0.67945 -0.3048)
			(end 0.67945 0.3048)
			(stroke
				(width 0.1)
				(type default)
			)
			(layer "F.Fab")
		)
		(fp_line
			(start 0.67945 0.3048)
			(end 0.120396 0.3048)
			(stroke
				(width 0.1)
				(type default)
			)
			(layer "F.Fab")
		)
		(pad "1" smd circle
			(at -0.40005 0)
			(size 0 0)
			(layers "F.Cu" "F.Mask" "F.Paste")
			(net "SPI_BIC1_CS0_LS01_R_N")
		)
		(pad "2" smd circle
			(at 0.40005 0)
			(size 0 0)
			(layers "F.Cu" "F.Mask" "F.Paste")
			(net "SPI_BIC1_CS0_LS01_N")
		)
	)
	(footprint ""
		(layer "F.Cu")
		(at 435.24043 -143.182848 90)
		(property "Reference" "C4005"
			(at 0 0 90)
			(layer "F.SilkS")
			(hide yes)
			(effects
				(font
					(size 1.27 1.27)
				)
			)
		)
		(property "Value" ""
			(at 0 0 90)
			(layer "F.Fab")
			(effects
				(font
					(size 1.27 1.27)
				)
			)
		)
		(duplicate_pad_numbers_are_jumpers no)
		(fp_line
			(start 0.7874 -0.4064)
			(end 0.7874 0.4064)
			(stroke
				(width 0.1524)
				(type default)
			)
			(layer "F.SilkS")
		)
		(fp_line
			(start -0.7874 -0.4064)
			(end 0.7874 -0.4064)
			(stroke
				(width 0.1524)
				(type default)
			)
			(layer "F.SilkS")
		)
		(fp_line
			(start 0.7874 0.4064)
			(end -0.7874 0.4064)
			(stroke
				(width 0.1524)
				(type default)
			)
			(layer "F.SilkS")
		)
		(fp_line
			(start -0.7874 0.4064)
			(end -0.7874 -0.4064)
			(stroke
				(width 0.1524)
				(type default)
			)
			(layer "F.SilkS")
		)
		(fp_line
			(start -0.12065 -0.305054)
			(end -0.12065 -0.2794)
			(stroke
				(width 0.1)
				(type default)
			)
			(layer "F.Fab")
		)
		(fp_line
			(start -0.67945 -0.305054)
			(end -0.12065 -0.305054)
			(stroke
				(width 0.1)
				(type default)
			)
			(layer "F.Fab")
		)
		(fp_line
			(start 0.67945 -0.3048)
			(end 0.67945 0.3048)
			(stroke
				(width 0.1)
				(type default)
			)
			(layer "F.Fab")
		)
		(fp_line
			(start 0.12065 -0.3048)
			(end 0.67945 -0.3048)
			(stroke
				(width 0.1)
				(type default)
			)
			(layer "F.Fab")
		)
		(fp_line
			(start 0.12065 -0.2794)
			(end 0.12065 -0.3048)
			(stroke
				(width 0.1)
				(type default)
			)
			(layer "F.Fab")
		)
		(fp_line
			(start -0.12065 -0.2794)
			(end 0.12065 -0.2794)
			(stroke
				(width 0.1)
				(type default)
			)
			(layer "F.Fab")
		)
		(fp_line
			(start 0.120396 0.2794)
			(end -0.12065 0.2794)
			(stroke
				(width 0.1)
				(type default)
			)
			(layer "F.Fab")
		)
		(fp_line
			(start -0.12065 0.2794)
			(end -0.12065 0.3048)
			(stroke
				(width 0.1)
				(type default)
			)
			(layer "F.Fab")
		)
		(fp_line
			(start 0.67945 0.3048)
			(end 0.120396 0.3048)
			(stroke
				(width 0.1)
				(type default)
			)
			(layer "F.Fab")
		)
		(fp_line
			(start 0.120396 0.3048)
			(end 0.120396 0.2794)
			(stroke
				(width 0.1)
				(type default)
			)
			(layer "F.Fab")
		)
		(fp_line
			(start -0.12065 0.3048)
			(end -0.67945 0.3048)
			(stroke
				(width 0.1)
				(type default)
			)
			(layer "F.Fab")
		)
		(fp_line
			(start -0.67945 0.3048)
			(end -0.67945 -0.305054)
			(stroke
				(width 0.1)
				(type default)
			)
			(layer "F.Fab")
		)
		(pad "1" smd circle
			(at -0.40005 0 90)
			(size 0 0)
			(layers "F.Cu" "F.Mask" "F.Paste")
			(net "PRSNT_NIC7_R_N")
		)
		(pad "2" smd circle
			(at 0.40005 0 90)
			(size 0 0)
			(layers "F.Cu" "F.Mask" "F.Paste")
			(net "GND")
		)
	)
	(footprint ""
		(layer "F.Cu")
		(at 55.88 -141.9352)
		(property "Reference" "R10"
			(at 0 0 0)
			(layer "F.SilkS")
			(hide yes)
			(effects
				(font
					(size 1.27 1.27)
				)
			)
		)
		(property "Value" ""
			(at 0 0 0)
			(layer "F.Fab")
			(effects
				(font
					(size 1.27 1.27)
				)
			)
		)
		(duplicate_pad_numbers_are_jumpers no)
		(fp_line
			(start -0.7874 -0.4064)
			(end 0.7874 -0.4064)
			(stroke
				(width 0.1524)
				(type default)
			)
			(layer "F.SilkS")
		)
		(fp_line
			(start -0.7874 0.4064)
			(end -0.7874 -0.4064)
			(stroke
				(width 0.1524)
				(type default)
			)
			(layer "F.SilkS")
		)
		(fp_line
			(start 0.7874 -0.4064)
			(end 0.7874 0.4064)
			(stroke
				(width 0.1524)
				(type default)
			)
			(layer "F.SilkS")
		)
		(fp_line
			(start 0.7874 0.4064)
			(end -0.7874 0.4064)
			(stroke
				(width 0.1524)
				(type default)
			)
			(layer "F.SilkS")
		)
		(fp_line
			(start -0.67945 -0.305054)
			(end -0.12065 -0.305054)
			(stroke
				(width 0.1)
				(type default)
			)
			(layer "F.Fab")
		)
		(fp_line
			(start -0.67945 0.3048)
			(end -0.67945 -0.305054)
			(stroke
				(width 0.1)
				(type default)
			)
			(layer "F.Fab")
		)
		(fp_line
			(start -0.12065 -0.305054)
			(end -0.12065 -0.2794)
			(stroke
				(width 0.1)
				(type default)
			)
			(layer "F.Fab")
		)
		(fp_line
			(start -0.12065 -0.2794)
			(end 0.12065 -0.2794)
			(stroke
				(width 0.1)
				(type default)
			)
			(layer "F.Fab")
		)
		(fp_line
			(start -0.12065 0.2794)
			(end -0.12065 0.3048)
			(stroke
				(width 0.1)
				(type default)
			)
			(layer "F.Fab")
		)
		(fp_line
			(start -0.12065 0.3048)
			(end -0.67945 0.3048)
			(stroke
				(width 0.1)
				(type default)
			)
			(layer "F.Fab")
		)
		(fp_line
			(start 0.120396 0.2794)
			(end -0.12065 0.2794)
			(stroke
				(width 0.1)
				(type default)
			)
			(layer "F.Fab")
		)
		(fp_line
			(start 0.120396 0.3048)
			(end 0.120396 0.2794)
			(stroke
				(width 0.1)
				(type default)
			)
			(layer "F.Fab")
		)
		(fp_line
			(start 0.12065 -0.3048)
			(end 0.67945 -0.3048)
			(stroke
				(width 0.1)
				(type default)
			)
			(layer "F.Fab")
		)
		(fp_line
			(start 0.12065 -0.2794)
			(end 0.12065 -0.3048)
			(stroke
				(width 0.1)
				(type default)
			)
			(layer "F.Fab")
		)
		(fp_line
			(start 0.67945 -0.3048)
			(end 0.67945 0.3048)
			(stroke
				(width 0.1)
				(type default)
			)
			(layer "F.Fab")
		)
		(fp_line
			(start 0.67945 0.3048)
			(end 0.120396 0.3048)
			(stroke
				(width 0.1)
				(type default)
			)
			(layer "F.Fab")
		)
		(pad "1" smd circle
			(at -0.40005 0)
			(size 0 0)
			(layers "F.Cu" "F.Mask" "F.Paste")
			(net "SMB_NIC0_R_SDA")
		)
		(pad "2" smd circle
			(at 0.40005 0)
			(size 0 0)
			(layers "F.Cu" "F.Mask" "F.Paste")
			(net "P3V3_NIC0")
		)
	)
	(footprint ""
		(layer "F.Cu")
		(at 445.798448 -66.32194 -90)
		(property "Reference" "PC896"
			(at 0 0 270)
			(layer "F.SilkS")
			(hide yes)
			(effects
				(font
					(size 1.27 1.27)
				)
			)
		)
		(property "Value" ""
			(at 0 0 270)
			(layer "F.Fab")
			(effects
				(font
					(size 1.27 1.27)
				)
			)
		)
		(duplicate_pad_numbers_are_jumpers no)
		(fp_line
			(start -0.7874 0.4064)
			(end -0.7874 -0.4064)
			(stroke
				(width 0.1524)
				(type default)
			)
			(layer "F.SilkS")
		)
		(fp_line
			(start 0.7874 0.4064)
			(end -0.7874 0.4064)
			(stroke
				(width 0.1524)
				(type default)
			)
			(layer "F.SilkS")
		)
		(fp_line
			(start -0.7874 -0.4064)
			(end 0.7874 -0.4064)
			(stroke
				(width 0.1524)
				(type default)
			)
			(layer "F.SilkS")
		)
		(fp_line
			(start 0.7874 -0.4064)
			(end 0.7874 0.4064)
			(stroke
				(width 0.1524)
				(type default)
			)
			(layer "F.SilkS")
		)
		(fp_line
			(start -0.67945 0.3048)
			(end -0.67945 -0.305054)
			(stroke
				(width 0.1)
				(type default)
			)
			(layer "F.Fab")
		)
		(fp_line
			(start -0.12065 0.3048)
			(end -0.67945 0.3048)
			(stroke
				(width 0.1)
				(type default)
			)
			(layer "F.Fab")
		)
		(fp_line
			(start 0.120396 0.3048)
			(end 0.120396 0.2794)
			(stroke
				(width 0.1)
				(type default)
			)
			(layer "F.Fab")
		)
		(fp_line
			(start 0.67945 0.3048)
			(end 0.120396 0.3048)
			(stroke
				(width 0.1)
				(type default)
			)
			(layer "F.Fab")
		)
		(fp_line
			(start -0.12065 0.2794)
			(end -0.12065 0.3048)
			(stroke
				(width 0.1)
				(type default)
			)
			(layer "F.Fab")
		)
		(fp_line
			(start 0.120396 0.2794)
			(end -0.12065 0.2794)
			(stroke
				(width 0.1)
				(type default)
			)
			(layer "F.Fab")
		)
		(fp_line
			(start -0.12065 -0.2794)
			(end 0.12065 -0.2794)
			(stroke
				(width 0.1)
				(type default)
			)
			(layer "F.Fab")
		)
		(fp_line
			(start 0.12065 -0.2794)
			(end 0.12065 -0.3048)
			(stroke
				(width 0.1)
				(type default)
			)
			(layer "F.Fab")
		)
		(fp_line
			(start 0.12065 -0.3048)
			(end 0.67945 -0.3048)
			(stroke
				(width 0.1)
				(type default)
			)
			(layer "F.Fab")
		)
		(fp_line
			(start 0.67945 -0.3048)
			(end 0.67945 0.3048)
			(stroke
				(width 0.1)
				(type default)
			)
			(layer "F.Fab")
		)
		(fp_line
			(start -0.67945 -0.305054)
			(end -0.12065 -0.305054)
			(stroke
				(width 0.1)
				(type default)
			)
			(layer "F.Fab")
		)
		(fp_line
			(start -0.12065 -0.305054)
			(end -0.12065 -0.2794)
			(stroke
				(width 0.1)
				(type default)
			)
			(layer "F.Fab")
		)
		(pad "1" smd circle
			(at -0.40005 0 270)
			(size 0 0)
			(layers "F.Cu" "F.Mask" "F.Paste")
			(net "P12V_SSD15_CO_GATE")
		)
		(pad "2" smd circle
			(at 0.40005 0 270)
			(size 0 0)
			(layers "F.Cu" "F.Mask" "F.Paste")
			(net "GND")
		)
	)
	(footprint ""
		(layer "F.Cu")
		(at 276.147022 -55.63489 90)
		(property "Reference" "PC417"
			(at 0 0 90)
			(layer "F.SilkS")
			(hide yes)
			(effects
				(font
					(size 1.27 1.27)
				)
			)
		)
		(property "Value" ""
			(at 0 0 90)
			(layer "F.Fab")
			(effects
				(font
					(size 1.27 1.27)
				)
			)
		)
		(duplicate_pad_numbers_are_jumpers no)
		(fp_line
			(start 1.524 -0.762)
			(end 1.524 0.762)
			(stroke
				(width 0.1524)
				(type default)
			)
			(layer "F.SilkS")
		)
		(fp_line
			(start -1.524 -0.762)
			(end 1.524 -0.762)
			(stroke
				(width 0.1524)
				(type default)
			)
			(layer "F.SilkS")
		)
		(fp_line
			(start 1.524 0.762)
			(end -1.524 0.762)
			(stroke
				(width 0.1524)
				(type default)
			)
			(layer "F.SilkS")
		)
		(fp_line
			(start -1.524 0.762)
			(end -1.524 -0.762)
			(stroke
				(width 0.1524)
				(type default)
			)
			(layer "F.SilkS")
		)
		(fp_line
			(start 1.1049 -0.724916)
			(end -1.1049 -0.724916)
			(stroke
				(width 0.1)
				(type default)
			)
			(layer "F.Fab")
		)
		(fp_line
			(start -1.1049 -0.724916)
			(end -1.1049 0.724916)
			(stroke
				(width 0.1)
				(type default)
			)
			(layer "F.Fab")
		)
		(fp_line
			(start 1.1049 0.724916)
			(end 1.1049 -0.724916)
			(stroke
				(width 0.1)
				(type default)
			)
			(layer "F.Fab")
		)
		(fp_line
			(start -1.1049 0.724916)
			(end 1.1049 0.724916)
			(stroke
				(width 0.1)
				(type default)
			)
			(layer "F.Fab")
		)
		(pad "1" smd rect
			(at -0.889 0 270)
			(size 1.016 1.27)
			(layers "F.Cu" "F.Mask" "F.Paste")
			(net "P12V_SSD9_R")
		)
		(pad "2" smd rect
			(at 0.889 0 270)
			(size 1.016 1.27)
			(layers "F.Cu" "F.Mask" "F.Paste")
			(net "GND")
		)
	)
	(footprint ""
		(layer "F.Cu")
		(at 358.000046 -209.279236 180)
		(property "Reference" "R5780"
			(at 0 0 180)
			(layer "F.SilkS")
			(hide yes)
			(effects
				(font
					(size 1.27 1.27)
				)
			)
		)
		(property "Value" ""
			(at 0 0 180)
			(layer "F.Fab")
			(effects
				(font
					(size 1.27 1.27)
				)
			)
		)
		(duplicate_pad_numbers_are_jumpers no)
		(fp_line
			(start 0.7874 0.4064)
			(end -0.7874 0.4064)
			(stroke
				(width 0.1524)
				(type default)
			)
			(layer "F.SilkS")
		)
		(fp_line
			(start 0.7874 -0.4064)
			(end 0.7874 0.4064)
			(stroke
				(width 0.1524)
				(type default)
			)
			(layer "F.SilkS")
		)
		(fp_line
			(start -0.7874 0.4064)
			(end -0.7874 -0.4064)
			(stroke
				(width 0.1524)
				(type default)
			)
			(layer "F.SilkS")
		)
		(fp_line
			(start -0.7874 -0.4064)
			(end 0.7874 -0.4064)
			(stroke
				(width 0.1524)
				(type default)
			)
			(layer "F.SilkS")
		)
		(fp_line
			(start 0.67945 0.3048)
			(end 0.120396 0.3048)
			(stroke
				(width 0.1)
				(type default)
			)
			(layer "F.Fab")
		)
		(fp_line
			(start 0.67945 -0.3048)
			(end 0.67945 0.3048)
			(stroke
				(width 0.1)
				(type default)
			)
			(layer "F.Fab")
		)
		(fp_line
			(start 0.12065 -0.2794)
			(end 0.12065 -0.3048)
			(stroke
				(width 0.1)
				(type default)
			)
			(layer "F.Fab")
		)
		(fp_line
			(start 0.12065 -0.3048)
			(end 0.67945 -0.3048)
			(stroke
				(width 0.1)
				(type default)
			)
			(layer "F.Fab")
		)
		(fp_line
			(start 0.120396 0.3048)
			(end 0.120396 0.2794)
			(stroke
				(width 0.1)
				(type default)
			)
			(layer "F.Fab")
		)
		(fp_line
			(start 0.120396 0.2794)
			(end -0.12065 0.2794)
			(stroke
				(width 0.1)
				(type default)
			)
			(layer "F.Fab")
		)
		(fp_line
			(start -0.12065 0.3048)
			(end -0.67945 0.3048)
			(stroke
				(width 0.1)
				(type default)
			)
			(layer "F.Fab")
		)
		(fp_line
			(start -0.12065 0.2794)
			(end -0.12065 0.3048)
			(stroke
				(width 0.1)
				(type default)
			)
			(layer "F.Fab")
		)
		(fp_line
			(start -0.12065 -0.2794)
			(end 0.12065 -0.2794)
			(stroke
				(width 0.1)
				(type default)
			)
			(layer "F.Fab")
		)
		(fp_line
			(start -0.12065 -0.305054)
			(end -0.12065 -0.2794)
			(stroke
				(width 0.1)
				(type default)
			)
			(layer "F.Fab")
		)
		(fp_line
			(start -0.67945 0.3048)
			(end -0.67945 -0.305054)
			(stroke
				(width 0.1)
				(type default)
			)
			(layer "F.Fab")
		)
		(fp_line
			(start -0.67945 -0.305054)
			(end -0.12065 -0.305054)
			(stroke
				(width 0.1)
				(type default)
			)
			(layer "F.Fab")
		)
		(pad "1" smd circle
			(at -0.40005 0 180)
			(size 0 0)
			(layers "F.Cu" "F.Mask" "F.Paste")
			(net "PWRGD_P1V2_AUX_FPGA_R")
		)
		(pad "2" smd circle
			(at 0.40005 0 180)
			(size 0 0)
			(layers "F.Cu" "F.Mask" "F.Paste")
			(net "PWRGD_P1V2_AUX_FPGA")
		)
	)
	(footprint ""
		(layer "F.Cu")
		(at 153.104596 -142.88897 180)
		(property "Reference" "R131"
			(at 0 0 180)
			(layer "F.SilkS")
			(hide yes)
			(effects
				(font
					(size 1.27 1.27)
				)
			)
		)
		(property "Value" ""
			(at 0 0 180)
			(layer "F.Fab")
			(effects
				(font
					(size 1.27 1.27)
				)
			)
		)
		(duplicate_pad_numbers_are_jumpers no)
		(fp_line
			(start 0.7874 0.4064)
			(end -0.7874 0.4064)
			(stroke
				(width 0.1524)
				(type default)
			)
			(layer "F.SilkS")
		)
		(fp_line
			(start 0.7874 -0.4064)
			(end 0.7874 0.4064)
			(stroke
				(width 0.1524)
				(type default)
			)
			(layer "F.SilkS")
		)
		(fp_line
			(start -0.7874 0.4064)
			(end -0.7874 -0.4064)
			(stroke
				(width 0.1524)
				(type default)
			)
			(layer "F.SilkS")
		)
		(fp_line
			(start -0.7874 -0.4064)
			(end 0.7874 -0.4064)
			(stroke
				(width 0.1524)
				(type default)
			)
			(layer "F.SilkS")
		)
		(fp_line
			(start 0.67945 0.3048)
			(end 0.120396 0.3048)
			(stroke
				(width 0.1)
				(type default)
			)
			(layer "F.Fab")
		)
		(fp_line
			(start 0.67945 -0.3048)
			(end 0.67945 0.3048)
			(stroke
				(width 0.1)
				(type default)
			)
			(layer "F.Fab")
		)
		(fp_line
			(start 0.12065 -0.2794)
			(end 0.12065 -0.3048)
			(stroke
				(width 0.1)
				(type default)
			)
			(layer "F.Fab")
		)
		(fp_line
			(start 0.12065 -0.3048)
			(end 0.67945 -0.3048)
			(stroke
				(width 0.1)
				(type default)
			)
			(layer "F.Fab")
		)
		(fp_line
			(start 0.120396 0.3048)
			(end 0.120396 0.2794)
			(stroke
				(width 0.1)
				(type default)
			)
			(layer "F.Fab")
		)
		(fp_line
			(start 0.120396 0.2794)
			(end -0.12065 0.2794)
			(stroke
				(width 0.1)
				(type default)
			)
			(layer "F.Fab")
		)
		(fp_line
			(start -0.12065 0.3048)
			(end -0.67945 0.3048)
			(stroke
				(width 0.1)
				(type default)
			)
			(layer "F.Fab")
		)
		(fp_line
			(start -0.12065 0.2794)
			(end -0.12065 0.3048)
			(stroke
				(width 0.1)
				(type default)
			)
			(layer "F.Fab")
		)
		(fp_line
			(start -0.12065 -0.2794)
			(end 0.12065 -0.2794)
			(stroke
				(width 0.1)
				(type default)
			)
			(layer "F.Fab")
		)
		(fp_line
			(start -0.12065 -0.305054)
			(end -0.12065 -0.2794)
			(stroke
				(width 0.1)
				(type default)
			)
			(layer "F.Fab")
		)
		(fp_line
			(start -0.67945 0.3048)
			(end -0.67945 -0.305054)
			(stroke
				(width 0.1)
				(type default)
			)
			(layer "F.Fab")
		)
		(fp_line
			(start -0.67945 -0.305054)
			(end -0.12065 -0.305054)
			(stroke
				(width 0.1)
				(type default)
			)
			(layer "F.Fab")
		)
		(pad "1" smd circle
			(at -0.40005 0 180)
			(size 0 0)
			(layers "F.Cu" "F.Mask" "F.Paste")
			(net "NIC2_BIF0_N")
		)
		(pad "2" smd circle
			(at 0.40005 0 180)
			(size 0 0)
			(layers "F.Cu" "F.Mask" "F.Paste")
			(net "P3V3_AUX")
		)
	)
	(footprint ""
		(layer "F.Cu")
		(at 358.013 -226.568)
		(property "Reference" "R3623"
			(at 0 0 0)
			(layer "F.SilkS")
			(hide yes)
			(effects
				(font
					(size 1.27 1.27)
				)
			)
		)
		(property "Value" ""
			(at 0 0 0)
			(layer "F.Fab")
			(effects
				(font
					(size 1.27 1.27)
				)
			)
		)
		(duplicate_pad_numbers_are_jumpers no)
		(fp_line
			(start -0.7874 -0.4064)
			(end 0.7874 -0.4064)
			(stroke
				(width 0.1524)
				(type default)
			)
			(layer "F.SilkS")
		)
		(fp_line
			(start -0.7874 0.4064)
			(end -0.7874 -0.4064)
			(stroke
				(width 0.1524)
				(type default)
			)
			(layer "F.SilkS")
		)
		(fp_line
			(start 0.7874 -0.4064)
			(end 0.7874 0.4064)
			(stroke
				(width 0.1524)
				(type default)
			)
			(layer "F.SilkS")
		)
		(fp_line
			(start 0.7874 0.4064)
			(end -0.7874 0.4064)
			(stroke
				(width 0.1524)
				(type default)
			)
			(layer "F.SilkS")
		)
		(fp_line
			(start -0.67945 -0.305054)
			(end -0.12065 -0.305054)
			(stroke
				(width 0.1)
				(type default)
			)
			(layer "F.Fab")
		)
		(fp_line
			(start -0.67945 0.3048)
			(end -0.67945 -0.305054)
			(stroke
				(width 0.1)
				(type default)
			)
			(layer "F.Fab")
		)
		(fp_line
			(start -0.12065 -0.305054)
			(end -0.12065 -0.2794)
			(stroke
				(width 0.1)
				(type default)
			)
			(layer "F.Fab")
		)
		(fp_line
			(start -0.12065 -0.2794)
			(end 0.12065 -0.2794)
			(stroke
				(width 0.1)
				(type default)
			)
			(layer "F.Fab")
		)
		(fp_line
			(start -0.12065 0.2794)
			(end -0.12065 0.3048)
			(stroke
				(width 0.1)
				(type default)
			)
			(layer "F.Fab")
		)
		(fp_line
			(start -0.12065 0.3048)
			(end -0.67945 0.3048)
			(stroke
				(width 0.1)
				(type default)
			)
			(layer "F.Fab")
		)
		(fp_line
			(start 0.120396 0.2794)
			(end -0.12065 0.2794)
			(stroke
				(width 0.1)
				(type default)
			)
			(layer "F.Fab")
		)
		(fp_line
			(start 0.120396 0.3048)
			(end 0.120396 0.2794)
			(stroke
				(width 0.1)
				(type default)
			)
			(layer "F.Fab")
		)
		(fp_line
			(start 0.12065 -0.3048)
			(end 0.67945 -0.3048)
			(stroke
				(width 0.1)
				(type default)
			)
			(layer "F.Fab")
		)
		(fp_line
			(start 0.12065 -0.2794)
			(end 0.12065 -0.3048)
			(stroke
				(width 0.1)
				(type default)
			)
			(layer "F.Fab")
		)
		(fp_line
			(start 0.67945 -0.3048)
			(end 0.67945 0.3048)
			(stroke
				(width 0.1)
				(type default)
			)
			(layer "F.Fab")
		)
		(fp_line
			(start 0.67945 0.3048)
			(end 0.120396 0.3048)
			(stroke
				(width 0.1)
				(type default)
			)
			(layer "F.Fab")
		)
		(pad "1" smd circle
			(at -0.40005 0)
			(size 0 0)
			(layers "F.Cu" "F.Mask" "F.Paste")
			(net "RST_NIC2_PERST_N")
		)
		(pad "2" smd circle
			(at 0.40005 0)
			(size 0 0)
			(layers "F.Cu" "F.Mask" "F.Paste")
			(net "RST_NIC2_PERST_R_N")
		)
	)
	(footprint ""
		(layer "F.Cu")
		(at 419.02253 -44.341542 90)
		(property "Reference" "R668"
			(at 0 0 90)
			(layer "F.SilkS")
			(hide yes)
			(effects
				(font
					(size 1.27 1.27)
				)
			)
		)
		(property "Value" ""
			(at 0 0 90)
			(layer "F.Fab")
			(effects
				(font
					(size 1.27 1.27)
				)
			)
		)
		(duplicate_pad_numbers_are_jumpers no)
		(fp_line
			(start 0.7874 -0.4064)
			(end 0.7874 0.4064)
			(stroke
				(width 0.1524)
				(type default)
			)
			(layer "F.SilkS")
		)
		(fp_line
			(start -0.7874 -0.4064)
			(end 0.7874 -0.4064)
			(stroke
				(width 0.1524)
				(type default)
			)
			(layer "F.SilkS")
		)
		(fp_line
			(start 0.7874 0.4064)
			(end -0.7874 0.4064)
			(stroke
				(width 0.1524)
				(type default)
			)
			(layer "F.SilkS")
		)
		(fp_line
			(start -0.7874 0.4064)
			(end -0.7874 -0.4064)
			(stroke
				(width 0.1524)
				(type default)
			)
			(layer "F.SilkS")
		)
		(fp_line
			(start -0.12065 -0.305054)
			(end -0.12065 -0.2794)
			(stroke
				(width 0.1)
				(type default)
			)
			(layer "F.Fab")
		)
		(fp_line
			(start -0.67945 -0.305054)
			(end -0.12065 -0.305054)
			(stroke
				(width 0.1)
				(type default)
			)
			(layer "F.Fab")
		)
		(fp_line
			(start 0.67945 -0.3048)
			(end 0.67945 0.3048)
			(stroke
				(width 0.1)
				(type default)
			)
			(layer "F.Fab")
		)
		(fp_line
			(start 0.12065 -0.3048)
			(end 0.67945 -0.3048)
			(stroke
				(width 0.1)
				(type default)
			)
			(layer "F.Fab")
		)
		(fp_line
			(start 0.12065 -0.2794)
			(end 0.12065 -0.3048)
			(stroke
				(width 0.1)
				(type default)
			)
			(layer "F.Fab")
		)
		(fp_line
			(start -0.12065 -0.2794)
			(end 0.12065 -0.2794)
			(stroke
				(width 0.1)
				(type default)
			)
			(layer "F.Fab")
		)
		(fp_line
			(start 0.120396 0.2794)
			(end -0.12065 0.2794)
			(stroke
				(width 0.1)
				(type default)
			)
			(layer "F.Fab")
		)
		(fp_line
			(start -0.12065 0.2794)
			(end -0.12065 0.3048)
			(stroke
				(width 0.1)
				(type default)
			)
			(layer "F.Fab")
		)
		(fp_line
			(start 0.67945 0.3048)
			(end 0.120396 0.3048)
			(stroke
				(width 0.1)
				(type default)
			)
			(layer "F.Fab")
		)
		(fp_line
			(start 0.120396 0.3048)
			(end 0.120396 0.2794)
			(stroke
				(width 0.1)
				(type default)
			)
			(layer "F.Fab")
		)
		(fp_line
			(start -0.12065 0.3048)
			(end -0.67945 0.3048)
			(stroke
				(width 0.1)
				(type default)
			)
			(layer "F.Fab")
		)
		(fp_line
			(start -0.67945 0.3048)
			(end -0.67945 -0.305054)
			(stroke
				(width 0.1)
				(type default)
			)
			(layer "F.Fab")
		)
		(pad "1" smd circle
			(at -0.40005 0 90)
			(size 0 0)
			(layers "F.Cu" "F.Mask" "F.Paste")
			(net "P12V_SSD14")
		)
		(pad "2" smd circle
			(at 0.40005 0 90)
			(size 0 0)
			(layers "F.Cu" "F.Mask" "F.Paste")
			(net "P12V_SSD14_VIN_N")
		)
	)
	(footprint ""
		(layer "F.Cu")
		(at 359.385362 -118.343426 -90)
		(property "Reference" "R6044"
			(at 0 0 270)
			(layer "F.SilkS")
			(hide yes)
			(effects
				(font
					(size 1.27 1.27)
				)
			)
		)
		(property "Value" ""
			(at 0 0 270)
			(layer "F.Fab")
			(effects
				(font
					(size 1.27 1.27)
				)
			)
		)
		(duplicate_pad_numbers_are_jumpers no)
		(fp_line
			(start -0.7874 0.4064)
			(end -0.7874 -0.4064)
			(stroke
				(width 0.1524)
				(type default)
			)
			(layer "F.SilkS")
		)
		(fp_line
			(start 0.7874 0.4064)
			(end -0.7874 0.4064)
			(stroke
				(width 0.1524)
				(type default)
			)
			(layer "F.SilkS")
		)
		(fp_line
			(start -0.7874 -0.4064)
			(end 0.7874 -0.4064)
			(stroke
				(width 0.1524)
				(type default)
			)
			(layer "F.SilkS")
		)
		(fp_line
			(start 0.7874 -0.4064)
			(end 0.7874 0.4064)
			(stroke
				(width 0.1524)
				(type default)
			)
			(layer "F.SilkS")
		)
		(fp_line
			(start -0.67945 0.3048)
			(end -0.67945 -0.305054)
			(stroke
				(width 0.1)
				(type default)
			)
			(layer "F.Fab")
		)
		(fp_line
			(start -0.12065 0.3048)
			(end -0.67945 0.3048)
			(stroke
				(width 0.1)
				(type default)
			)
			(layer "F.Fab")
		)
		(fp_line
			(start 0.120396 0.3048)
			(end 0.120396 0.2794)
			(stroke
				(width 0.1)
				(type default)
			)
			(layer "F.Fab")
		)
		(fp_line
			(start 0.67945 0.3048)
			(end 0.120396 0.3048)
			(stroke
				(width 0.1)
				(type default)
			)
			(layer "F.Fab")
		)
		(fp_line
			(start -0.12065 0.2794)
			(end -0.12065 0.3048)
			(stroke
				(width 0.1)
				(type default)
			)
			(layer "F.Fab")
		)
		(fp_line
			(start 0.120396 0.2794)
			(end -0.12065 0.2794)
			(stroke
				(width 0.1)
				(type default)
			)
			(layer "F.Fab")
		)
		(fp_line
			(start -0.12065 -0.2794)
			(end 0.12065 -0.2794)
			(stroke
				(width 0.1)
				(type default)
			)
			(layer "F.Fab")
		)
		(fp_line
			(start 0.12065 -0.2794)
			(end 0.12065 -0.3048)
			(stroke
				(width 0.1)
				(type default)
			)
			(layer "F.Fab")
		)
		(fp_line
			(start 0.12065 -0.3048)
			(end 0.67945 -0.3048)
			(stroke
				(width 0.1)
				(type default)
			)
			(layer "F.Fab")
		)
		(fp_line
			(start 0.67945 -0.3048)
			(end 0.67945 0.3048)
			(stroke
				(width 0.1)
				(type default)
			)
			(layer "F.Fab")
		)
		(fp_line
			(start -0.67945 -0.305054)
			(end -0.12065 -0.305054)
			(stroke
				(width 0.1)
				(type default)
			)
			(layer "F.Fab")
		)
		(fp_line
			(start -0.12065 -0.305054)
			(end -0.12065 -0.2794)
			(stroke
				(width 0.1)
				(type default)
			)
			(layer "F.Fab")
		)
		(pad "1" smd circle
			(at -0.40005 0 270)
			(size 0 0)
			(layers "F.Cu" "F.Mask" "F.Paste")
			(net "P3V3_AUX")
		)
		(pad "2" smd circle
			(at 0.40005 0 270)
			(size 0 0)
			(layers "F.Cu" "F.Mask" "F.Paste")
			(net "PWRGD_P3V3_NIC6_D")
		)
	)
	(footprint ""
		(layer "F.Cu")
		(at 82.11439 -140.134848 -90)
		(property "Reference" "R95"
			(at 0 0 270)
			(layer "F.SilkS")
			(hide yes)
			(effects
				(font
					(size 1.27 1.27)
				)
			)
		)
		(property "Value" ""
			(at 0 0 270)
			(layer "F.Fab")
			(effects
				(font
					(size 1.27 1.27)
				)
			)
		)
		(duplicate_pad_numbers_are_jumpers no)
		(fp_line
			(start -0.7874 0.4064)
			(end -0.7874 -0.4064)
			(stroke
				(width 0.1524)
				(type default)
			)
			(layer "F.SilkS")
		)
		(fp_line
			(start 0.7874 0.4064)
			(end -0.7874 0.4064)
			(stroke
				(width 0.1524)
				(type default)
			)
			(layer "F.SilkS")
		)
		(fp_line
			(start -0.7874 -0.4064)
			(end 0.7874 -0.4064)
			(stroke
				(width 0.1524)
				(type default)
			)
			(layer "F.SilkS")
		)
		(fp_line
			(start 0.7874 -0.4064)
			(end 0.7874 0.4064)
			(stroke
				(width 0.1524)
				(type default)
			)
			(layer "F.SilkS")
		)
		(fp_line
			(start -0.67945 0.3048)
			(end -0.67945 -0.305054)
			(stroke
				(width 0.1)
				(type default)
			)
			(layer "F.Fab")
		)
		(fp_line
			(start -0.12065 0.3048)
			(end -0.67945 0.3048)
			(stroke
				(width 0.1)
				(type default)
			)
			(layer "F.Fab")
		)
		(fp_line
			(start 0.120396 0.3048)
			(end 0.120396 0.2794)
			(stroke
				(width 0.1)
				(type default)
			)
			(layer "F.Fab")
		)
		(fp_line
			(start 0.67945 0.3048)
			(end 0.120396 0.3048)
			(stroke
				(width 0.1)
				(type default)
			)
			(layer "F.Fab")
		)
		(fp_line
			(start -0.12065 0.2794)
			(end -0.12065 0.3048)
			(stroke
				(width 0.1)
				(type default)
			)
			(layer "F.Fab")
		)
		(fp_line
			(start 0.120396 0.2794)
			(end -0.12065 0.2794)
			(stroke
				(width 0.1)
				(type default)
			)
			(layer "F.Fab")
		)
		(fp_line
			(start -0.12065 -0.2794)
			(end 0.12065 -0.2794)
			(stroke
				(width 0.1)
				(type default)
			)
			(layer "F.Fab")
		)
		(fp_line
			(start 0.12065 -0.2794)
			(end 0.12065 -0.3048)
			(stroke
				(width 0.1)
				(type default)
			)
			(layer "F.Fab")
		)
		(fp_line
			(start 0.12065 -0.3048)
			(end 0.67945 -0.3048)
			(stroke
				(width 0.1)
				(type default)
			)
			(layer "F.Fab")
		)
		(fp_line
			(start 0.67945 -0.3048)
			(end 0.67945 0.3048)
			(stroke
				(width 0.1)
				(type default)
			)
			(layer "F.Fab")
		)
		(fp_line
			(start -0.67945 -0.305054)
			(end -0.12065 -0.305054)
			(stroke
				(width 0.1)
				(type default)
			)
			(layer "F.Fab")
		)
		(fp_line
			(start -0.12065 -0.305054)
			(end -0.12065 -0.2794)
			(stroke
				(width 0.1)
				(type default)
			)
			(layer "F.Fab")
		)
		(pad "1" smd circle
			(at -0.40005 0 270)
			(size 0 0)
			(layers "F.Cu" "F.Mask" "F.Paste")
			(net "P3V3_AUX")
		)
		(pad "2" smd circle
			(at 0.40005 0 270)
			(size 0 0)
			(layers "F.Cu" "F.Mask" "F.Paste")
			(net "HP_NIC1_EN")
		)
	)
	(footprint ""
		(layer "F.Cu")
		(at 275.992336 -32.739584 180)
		(property "Reference" "C497"
			(at 0 0 180)
			(layer "F.SilkS")
			(hide yes)
			(effects
				(font
					(size 1.27 1.27)
				)
			)
		)
		(property "Value" ""
			(at 0 0 180)
			(layer "F.Fab")
			(effects
				(font
					(size 1.27 1.27)
				)
			)
		)
		(duplicate_pad_numbers_are_jumpers no)
		(fp_line
			(start 0.299974 0.150114)
			(end -0.299974 0.150114)
			(stroke
				(width 0.1)
				(type default)
			)
			(layer "F.Fab")
		)
		(fp_line
			(start 0.299974 -0.150114)
			(end 0.299974 0.150114)
			(stroke
				(width 0.1)
				(type default)
			)
			(layer "F.Fab")
		)
		(fp_line
			(start -0.299974 0.150114)
			(end -0.299974 -0.150114)
			(stroke
				(width 0.1)
				(type default)
			)
			(layer "F.Fab")
		)
		(fp_line
			(start -0.299974 -0.150114)
			(end 0.299974 -0.150114)
			(stroke
				(width 0.1)
				(type default)
			)
			(layer "F.Fab")
		)
		(pad "1" smd rect
			(at -0.2667 0 180)
			(size 0.3048 0.381)
			(layers "F.Cu" "F.Mask" "F.Paste")
			(net "P5E_PEX2_STN2_TX_DP<42>")
		)
		(pad "2" smd rect
			(at 0.2667 0 180)
			(size 0.3048 0.381)
			(layers "F.Cu" "F.Mask" "F.Paste")
			(net "P5E_PEX2_STN2_TX_C_DP<42>")
		)
	)
	(footprint ""
		(layer "F.Cu")
		(at 229.711504 -155.940506 -90)
		(property "Reference" "R1206"
			(at 0 0 270)
			(layer "F.SilkS")
			(hide yes)
			(effects
				(font
					(size 1.27 1.27)
				)
			)
		)
		(property "Value" ""
			(at 0 0 270)
			(layer "F.Fab")
			(effects
				(font
					(size 1.27 1.27)
				)
			)
		)
		(duplicate_pad_numbers_are_jumpers no)
		(fp_line
			(start -0.7874 -0.4064)
			(end 0.7874 -0.4064)
			(stroke
				(width 0.1524)
				(type default)
			)
			(layer "F.SilkS")
		)
		(fp_line
			(start -0.67945 0.3048)
			(end -0.67945 -0.305054)
			(stroke
				(width 0.1)
				(type default)
			)
			(layer "F.Fab")
		)
		(fp_line
			(start -0.12065 0.3048)
			(end -0.67945 0.3048)
			(stroke
				(width 0.1)
				(type default)
			)
			(layer "F.Fab")
		)
		(fp_line
			(start 0.120396 0.3048)
			(end 0.120396 0.2794)
			(stroke
				(width 0.1)
				(type default)
			)
			(layer "F.Fab")
		)
		(fp_line
			(start 0.67945 0.3048)
			(end 0.120396 0.3048)
			(stroke
				(width 0.1)
				(type default)
			)
			(layer "F.Fab")
		)
		(fp_line
			(start -0.12065 0.2794)
			(end -0.12065 0.3048)
			(stroke
				(width 0.1)
				(type default)
			)
			(layer "F.Fab")
		)
		(fp_line
			(start 0.120396 0.2794)
			(end -0.12065 0.2794)
			(stroke
				(width 0.1)
				(type default)
			)
			(layer "F.Fab")
		)
		(fp_line
			(start -0.12065 -0.2794)
			(end 0.12065 -0.2794)
			(stroke
				(width 0.1)
				(type default)
			)
			(layer "F.Fab")
		)
		(fp_line
			(start 0.12065 -0.2794)
			(end 0.12065 -0.3048)
			(stroke
				(width 0.1)
				(type default)
			)
			(layer "F.Fab")
		)
		(fp_line
			(start 0.12065 -0.3048)
			(end 0.67945 -0.3048)
			(stroke
				(width 0.1)
				(type default)
			)
			(layer "F.Fab")
		)
		(fp_line
			(start 0.67945 -0.3048)
			(end 0.67945 0.3048)
			(stroke
				(width 0.1)
				(type default)
			)
			(layer "F.Fab")
		)
		(fp_line
			(start -0.67945 -0.305054)
			(end -0.12065 -0.305054)
			(stroke
				(width 0.1)
				(type default)
			)
			(layer "F.Fab")
		)
		(fp_line
			(start -0.12065 -0.305054)
			(end -0.12065 -0.2794)
			(stroke
				(width 0.1)
				(type default)
			)
			(layer "F.Fab")
		)
		(pad "1" smd circle
			(at -0.40005 0 270)
			(size 0 0)
			(layers "F.Cu" "F.Mask" "F.Paste")
			(net "CLK_100M_PEX0_REF_R_DN")
		)
		(pad "2" smd circle
			(at 0.40005 0 270)
			(size 0 0)
			(layers "F.Cu" "F.Mask" "F.Paste")
			(net "CLK_100M_PEX0_REF_DN")
		)
	)
	(footprint ""
		(layer "F.Cu")
		(at 355.009196 -27.04973 180)
		(property "Reference" "C2775"
			(at 0 0 180)
			(layer "F.SilkS")
			(hide yes)
			(effects
				(font
					(size 1.27 1.27)
				)
			)
		)
		(property "Value" ""
			(at 0 0 180)
			(layer "F.Fab")
			(effects
				(font
					(size 1.27 1.27)
				)
			)
		)
		(duplicate_pad_numbers_are_jumpers no)
		(fp_line
			(start 0.7874 0.4064)
			(end -0.7874 0.4064)
			(stroke
				(width 0.1524)
				(type default)
			)
			(layer "F.SilkS")
		)
		(fp_line
			(start 0.7874 -0.4064)
			(end 0.7874 0.4064)
			(stroke
				(width 0.1524)
				(type default)
			)
			(layer "F.SilkS")
		)
		(fp_line
			(start -0.7874 0.4064)
			(end -0.7874 -0.4064)
			(stroke
				(width 0.1524)
				(type default)
			)
			(layer "F.SilkS")
		)
		(fp_line
			(start -0.7874 -0.4064)
			(end 0.7874 -0.4064)
			(stroke
				(width 0.1524)
				(type default)
			)
			(layer "F.SilkS")
		)
		(fp_line
			(start 0.67945 0.3048)
			(end 0.120396 0.3048)
			(stroke
				(width 0.1)
				(type default)
			)
			(layer "F.Fab")
		)
		(fp_line
			(start 0.67945 -0.3048)
			(end 0.67945 0.3048)
			(stroke
				(width 0.1)
				(type default)
			)
			(layer "F.Fab")
		)
		(fp_line
			(start 0.12065 -0.2794)
			(end 0.12065 -0.3048)
			(stroke
				(width 0.1)
				(type default)
			)
			(layer "F.Fab")
		)
		(fp_line
			(start 0.12065 -0.3048)
			(end 0.67945 -0.3048)
			(stroke
				(width 0.1)
				(type default)
			)
			(layer "F.Fab")
		)
		(fp_line
			(start 0.120396 0.3048)
			(end 0.120396 0.2794)
			(stroke
				(width 0.1)
				(type default)
			)
			(layer "F.Fab")
		)
		(fp_line
			(start 0.120396 0.2794)
			(end -0.12065 0.2794)
			(stroke
				(width 0.1)
				(type default)
			)
			(layer "F.Fab")
		)
		(fp_line
			(start -0.12065 0.3048)
			(end -0.67945 0.3048)
			(stroke
				(width 0.1)
				(type default)
			)
			(layer "F.Fab")
		)
		(fp_line
			(start -0.12065 0.2794)
			(end -0.12065 0.3048)
			(stroke
				(width 0.1)
				(type default)
			)
			(layer "F.Fab")
		)
		(fp_line
			(start -0.12065 -0.2794)
			(end 0.12065 -0.2794)
			(stroke
				(width 0.1)
				(type default)
			)
			(layer "F.Fab")
		)
		(fp_line
			(start -0.12065 -0.305054)
			(end -0.12065 -0.2794)
			(stroke
				(width 0.1)
				(type default)
			)
			(layer "F.Fab")
		)
		(fp_line
			(start -0.67945 0.3048)
			(end -0.67945 -0.305054)
			(stroke
				(width 0.1)
				(type default)
			)
			(layer "F.Fab")
		)
		(fp_line
			(start -0.67945 -0.305054)
			(end -0.12065 -0.305054)
			(stroke
				(width 0.1)
				(type default)
			)
			(layer "F.Fab")
		)
		(pad "1" smd circle
			(at -0.40005 0 180)
			(size 0 0)
			(layers "F.Cu" "F.Mask" "F.Paste")
			(net "PRSNT_SSD12_R_N")
		)
		(pad "2" smd circle
			(at 0.40005 0 180)
			(size 0 0)
			(layers "F.Cu" "F.Mask" "F.Paste")
			(net "GND")
		)
	)
	(footprint ""
		(layer "F.Cu")
		(at 78.345792 -447.279014)
		(property "Reference" "X3"
			(at -0.1778 -1.92913 0)
			(unlocked yes)
			(layer "F.SilkS")
			(effects
				(font
					(size 0.7874 0.5842)
					(thickness 0.1524)
				)
				(justify left)
			)
		)
		(property "Value" ""
			(at 0 0 0)
			(layer "F.Fab")
			(effects
				(font
					(size 1.27 1.27)
				)
			)
		)
		(property "Device Type" "TP_TDR_4P_FTS_MPKT4_H025P0200_IO_TP15_TP_TDR_4P_DIP"
			(at 1.30175 1.27 90)
			(unlocked yes)
			(layer "F.Fab")
			(hide yes)
			(effects
				(font
					(size 0.635 0.4064)
					(thickness 0.1524)
				)
			)
		)
		(property "User Part Number" "TP15"
			(at 1.30175 1.27 90)
			(unlocked yes)
			(layer "Cmts.User")
			(hide yes)
			(effects
				(font
					(size 0.635 0.4064)
					(thickness 0.1524)
				)
			)
		)
		(duplicate_pad_numbers_are_jumpers no)
		(fp_line
			(start 0 -1.27)
			(end 0 -0.635)
			(stroke
				(width 0.1524)
				(type default)
			)
			(layer "F.SilkS")
		)
		(fp_line
			(start 0 0.635)
			(end 0 1.905)
			(stroke
				(width 0.1524)
				(type default)
			)
			(layer "F.SilkS")
		)
		(fp_line
			(start 0 3.175)
			(end 0 3.81)
			(stroke
				(width 0.1524)
				(type default)
			)
			(layer "F.SilkS")
		)
		(fp_line
			(start 0 3.81)
			(end 2.54 3.81)
			(stroke
				(width 0.1524)
				(type default)
			)
			(layer "F.SilkS")
		)
		(fp_line
			(start 2.54 -1.27)
			(end 0 -1.27)
			(stroke
				(width 0.1524)
				(type default)
			)
			(layer "F.SilkS")
		)
		(fp_line
			(start 2.54 -1.1303)
			(end 2.54 -1.27)
			(stroke
				(width 0.1524)
				(type default)
			)
			(layer "F.SilkS")
		)
		(fp_line
			(start 2.54 1.4097)
			(end 2.54 1.1303)
			(stroke
				(width 0.1524)
				(type default)
			)
			(layer "F.SilkS")
		)
		(fp_line
			(start 2.54 3.81)
			(end 2.54 3.6703)
			(stroke
				(width 0.1524)
				(type default)
			)
			(layer "F.SilkS")
		)
		(fp_poly
			(pts
				(xy -0.761746 0) (xy -2.285746 -0.762) (xy -2.285746 0.762)
			)
			(stroke
				(width 0)
				(type default)
			)
			(fill yes)
			(layer "F.SilkS")
		)
		(fp_line
			(start 0 -1.27)
			(end 0 3.81)
			(stroke
				(width 0.1)
				(type default)
			)
			(layer "F.Fab")
		)
		(fp_line
			(start 0 3.81)
			(end 2.54 3.81)
			(stroke
				(width 0.1)
				(type default)
			)
			(layer "F.Fab")
		)
		(fp_line
			(start 2.54 -1.27)
			(end 0 -1.27)
			(stroke
				(width 0.1)
				(type default)
			)
			(layer "F.Fab")
		)
		(fp_line
			(start 2.54 3.81)
			(end 2.54 -1.27)
			(stroke
				(width 0.1)
				(type default)
			)
			(layer "F.Fab")
		)
		(fp_poly
			(pts
				(xy -0.761746 0) (xy -2.285746 -0.762) (xy -2.285746 0.762)
			)
			(stroke
				(width 0)
				(type default)
			)
			(fill yes)
			(layer "F.Fab")
		)
		(pad "1" thru_hole circle
			(at 0 0)
			(size 1.0033 1.0033)
			(drill 0.249936)
			(layers "*.Cu" "*.Mask")
			(remove_unused_layers no)
			(net "TDR_DIFF_85_TOP_DIN")
			(clearance 0.10795)
			(thermal_gap 0.10795)
			(padstack
				(mode front_inner_back)
				(layer "Inner"
					(shape circle)
					(size 0.8001 0.8001)
					(clearance 0.1524)
				)
				(layer "B.Cu"
					(shape circle)
					(size 1.0033 1.0033)
					(clearance 0.10795)
				)
			)
		)
		(pad "2" thru_hole circle
			(at 2.54 0)
			(size 1.9939 1.9939)
			(drill 0.249936)
			(layers "*.Cu" "*.Mask")
			(remove_unused_layers no)
			(net "COUPON_GND1")
			(clearance 0.10795)
			(thermal_gap 0.10795)
			(padstack
				(mode front_inner_back)
				(layer "Inner"
					(shape circle)
					(size 0.8001 0.8001)
					(clearance 0.1524)
				)
				(layer "B.Cu"
					(shape circle)
					(size 1.9939 1.9939)
					(clearance 0.10795)
				)
			)
		)
		(pad "3" thru_hole circle
			(at 2.54 2.54)
			(size 1.9939 1.9939)
			(drill 0.249936)
			(layers "*.Cu" "*.Mask")
			(remove_unused_layers no)
			(net "COUPON_GND1")
			(clearance 0.10795)
			(thermal_gap 0.10795)
			(padstack
				(mode front_inner_back)
				(layer "Inner"
					(shape circle)
					(size 0.8001 0.8001)
					(clearance 0.1524)
				)
				(layer "B.Cu"
					(shape circle)
					(size 1.9939 1.9939)
					(clearance 0.10795)
				)
			)
		)
		(pad "4" thru_hole circle
			(at 0 2.54)
			(size 1.0033 1.0033)
			(drill 0.249936)
			(layers "*.Cu" "*.Mask")
			(remove_unused_layers no)
			(net "TDR_DIFF_85_TOP_DIP")
			(clearance 0.10795)
			(thermal_gap 0.10795)
			(padstack
				(mode front_inner_back)
				(layer "Inner"
					(shape circle)
					(size 0.8001 0.8001)
					(clearance 0.1524)
				)
				(layer "B.Cu"
					(shape circle)
					(size 1.0033 1.0033)
					(clearance 0.10795)
				)
			)
		)
	)
	(footprint ""
		(layer "F.Cu")
		(at 188.534548 -34.546286 180)
		(property "Reference" "C292"
			(at 0 0 180)
			(layer "F.SilkS")
			(hide yes)
			(effects
				(font
					(size 1.27 1.27)
				)
			)
		)
		(property "Value" ""
			(at 0 0 180)
			(layer "F.Fab")
			(effects
				(font
					(size 1.27 1.27)
				)
			)
		)
		(duplicate_pad_numbers_are_jumpers no)
		(fp_line
			(start 0.299974 0.150114)
			(end -0.299974 0.150114)
			(stroke
				(width 0.1)
				(type default)
			)
			(layer "F.Fab")
		)
		(fp_line
			(start 0.299974 -0.150114)
			(end 0.299974 0.150114)
			(stroke
				(width 0.1)
				(type default)
			)
			(layer "F.Fab")
		)
		(fp_line
			(start -0.299974 0.150114)
			(end -0.299974 -0.150114)
			(stroke
				(width 0.1)
				(type default)
			)
			(layer "F.Fab")
		)
		(fp_line
			(start -0.299974 -0.150114)
			(end 0.299974 -0.150114)
			(stroke
				(width 0.1)
				(type default)
			)
			(layer "F.Fab")
		)
		(pad "1" smd rect
			(at -0.2667 0 180)
			(size 0.3048 0.381)
			(layers "F.Cu" "F.Mask" "F.Paste")
			(net "P5E_PEX1_STN2_TX_DP<39>")
		)
		(pad "2" smd rect
			(at 0.2667 0 180)
			(size 0.3048 0.381)
			(layers "F.Cu" "F.Mask" "F.Paste")
			(net "P5E_PEX1_STN2_TX_C_DP<39>")
		)
	)
	(footprint ""
		(layer "F.Cu")
		(at 402.909024 18.035524)
		(property "Reference" "DE05F_2"
			(at -3.6068 -2.962148 0)
			(unlocked yes)
			(layer "F.SilkS")
			(effects
				(font
					(size 0.7874 0.5842)
					(thickness 0.1524)
				)
				(justify left)
			)
		)
		(property "Value" ""
			(at 0 0 0)
			(layer "F.Fab")
			(effects
				(font
					(size 1.27 1.27)
				)
			)
		)
		(duplicate_pad_numbers_are_jumpers no)
		(fp_line
			(start -1.2192 -2.1082)
			(end 1.2192 -2.1082)
			(stroke
				(width 0.1524)
				(type default)
			)
			(layer "F.SilkS")
		)
		(fp_line
			(start -1.2192 2.1082)
			(end -1.2192 -2.1082)
			(stroke
				(width 0.1524)
				(type default)
			)
			(layer "F.SilkS")
		)
		(fp_line
			(start 1.2192 -2.1082)
			(end 1.2192 2.1082)
			(stroke
				(width 0.1524)
				(type default)
			)
			(layer "F.SilkS")
		)
		(fp_line
			(start 1.2192 2.1082)
			(end -1.2192 2.1082)
			(stroke
				(width 0.1524)
				(type default)
			)
			(layer "F.SilkS")
		)
		(pad "" np_thru_hole circle
			(at -2.8829 -1.27 270)
			(size 1.0414 1.0414)
			(drill 1.0414)
			(layers "*.Cu" "*.Mask")
			(clearance 0.381)
			(thermal_gap 0.381)
		)
		(pad "" np_thru_hole circle
			(at -2.8829 1.27 270)
			(size 1.0414 1.0414)
			(drill 1.0414)
			(layers "*.Cu" "*.Mask")
			(clearance 0.381)
			(thermal_gap 0.381)
		)
		(pad "" np_thru_hole circle
			(at 3.4671 -1.27 270)
			(size 1.0414 1.0414)
			(drill 1.0414)
			(layers "*.Cu" "*.Mask")
			(clearance 0.381)
			(thermal_gap 0.381)
		)
		(pad "" np_thru_hole circle
			(at 3.4671 1.27 270)
			(size 1.0414 1.0414)
			(drill 1.0414)
			(layers "*.Cu" "*.Mask")
			(clearance 0.381)
			(thermal_gap 0.381)
		)
		(pad "1" smd rect
			(at 0.8255 -0.249936 270)
			(size 0.3048 0.508)
			(layers "F.Cu" "F.Mask" "F.Paste")
			(net "85_5INCH_IN3_DN")
		)
		(pad "2" smd rect
			(at 0.8255 0.249936 270)
			(size 0.3048 0.508)
			(layers "F.Cu" "F.Mask" "F.Paste")
			(net "85_5INCH_IN3_DP")
		)
		(pad "3" smd circle
			(at 0 0)
			(size 0 0)
			(layers "F.Cu" "F.Mask" "F.Paste")
			(net "COUPON_GND2")
		)
		(zone
			(layer "F.Cu")
			(hatch none 0.5)
			(connect_pads
				(clearance 0)
			)
			(min_thickness 0.25)
			(keepout
				(tracks not_allowed)
				(vias allowed)
				(pads allowed)
				(copperpour not_allowed)
				(footprints allowed)
			)
			(placement
				(enabled no)
				(sheetname "")
			)
			(fill
				(thermal_gap 0.5)
				(thermal_bridge_width 0.5)
				(island_removal_mode 0)
			)
			(polygon
				(pts
					(xy 404.026624 17.486884) (xy 404.026624 17.582388) (xy 403.429724 17.582388) (xy 403.429724 17.988788)
					(xy 404.026624 17.988788) (xy 404.026624 18.08226) (xy 403.429724 18.08226) (xy 403.429724 18.48866)
					(xy 404.026624 18.48866) (xy 404.026624 18.584164) (xy 403.328124 18.584164) (xy 403.328124 17.486884)
				)
			)
		)
		(zone
			(layers "F.Cu" "B.Cu" "In1.Cu" "In2.Cu" "In3.Cu" "In4.Cu" "In5.Cu" "In6.Cu"
				"In7.Cu" "In8.Cu" "In9.Cu" "In10.Cu" "In11.Cu" "In12.Cu" "In13.Cu" "In14.Cu"
				"In15.Cu" "In16.Cu"
			)
			(hatch none 0.5)
			(connect_pads
				(clearance 0)
			)
			(min_thickness 0.25)
			(keepout
				(tracks not_allowed)
				(vias allowed)
				(pads allowed)
				(copperpour not_allowed)
				(footprints allowed)
			)
			(placement
				(enabled no)
				(sheetname "")
			)
			(fill
				(thermal_gap 0.5)
				(thermal_bridge_width 0.5)
				(island_removal_mode 0)
			)
			(polygon
				(pts
					(arc
						(start 400.953224 16.765524)
						(mid 399.099024 16.765524)
						(end 400.953224 16.765524)
					)
				)
			)
		)
		(zone
			(layers "F.Cu" "B.Cu" "In1.Cu" "In2.Cu" "In3.Cu" "In4.Cu" "In5.Cu" "In6.Cu"
				"In7.Cu" "In8.Cu" "In9.Cu" "In10.Cu" "In11.Cu" "In12.Cu" "In13.Cu" "In14.Cu"
				"In15.Cu" "In16.Cu"
			)
			(hatch none 0.5)
			(connect_pads
				(clearance 0)
			)
			(min_thickness 0.25)
			(keepout
				(tracks not_allowed)
				(vias allowed)
				(pads allowed)
				(copperpour not_allowed)
				(footprints allowed)
			)
			(placement
				(enabled no)
				(sheetname "")
			)
			(fill
				(thermal_gap 0.5)
				(thermal_bridge_width 0.5)
				(island_removal_mode 0)
			)
			(polygon
				(pts
					(arc
						(start 400.953224 19.305524)
						(mid 399.099024 19.305524)
						(end 400.953224 19.305524)
					)
				)
			)
		)
		(zone
			(layers "F.Cu" "B.Cu" "In1.Cu" "In2.Cu" "In3.Cu" "In4.Cu" "In5.Cu" "In6.Cu"
				"In7.Cu" "In8.Cu" "In9.Cu" "In10.Cu" "In11.Cu" "In12.Cu" "In13.Cu" "In14.Cu"
				"In15.Cu" "In16.Cu"
			)
			(hatch none 0.5)
			(connect_pads
				(clearance 0)
			)
			(min_thickness 0.25)
			(keepout
				(tracks not_allowed)
				(vias allowed)
				(pads allowed)
				(copperpour not_allowed)
				(footprints allowed)
			)
			(placement
				(enabled no)
				(sheetname "")
			)
			(fill
				(thermal_gap 0.5)
				(thermal_bridge_width 0.5)
				(island_removal_mode 0)
			)
			(polygon
				(pts
					(arc
						(start 407.303224 16.765524)
						(mid 405.449024 16.765524)
						(end 407.303224 16.765524)
					)
				)
			)
		)
		(zone
			(layers "F.Cu" "B.Cu" "In1.Cu" "In2.Cu" "In3.Cu" "In4.Cu" "In5.Cu" "In6.Cu"
				"In7.Cu" "In8.Cu" "In9.Cu" "In10.Cu" "In11.Cu" "In12.Cu" "In13.Cu" "In14.Cu"
				"In15.Cu" "In16.Cu"
			)
			(hatch none 0.5)
			(connect_pads
				(clearance 0)
			)
			(min_thickness 0.25)
			(keepout
				(tracks not_allowed)
				(vias allowed)
				(pads allowed)
				(copperpour not_allowed)
				(footprints allowed)
			)
			(placement
				(enabled no)
				(sheetname "")
			)
			(fill
				(thermal_gap 0.5)
				(thermal_bridge_width 0.5)
				(island_removal_mode 0)
			)
			(polygon
				(pts
					(arc
						(start 407.303224 19.305524)
						(mid 405.449024 19.305524)
						(end 407.303224 19.305524)
					)
				)
			)
		)
	)
	(footprint ""
		(layer "F.Cu")
		(at 58.995056 -100.766372 180)
		(property "Reference" "R78"
			(at 0 0 180)
			(layer "F.SilkS")
			(hide yes)
			(effects
				(font
					(size 1.27 1.27)
				)
			)
		)
		(property "Value" ""
			(at 0 0 180)
			(layer "F.Fab")
			(effects
				(font
					(size 1.27 1.27)
				)
			)
		)
		(duplicate_pad_numbers_are_jumpers no)
		(fp_line
			(start 0.7874 0.4064)
			(end -0.7874 0.4064)
			(stroke
				(width 0.1524)
				(type default)
			)
			(layer "F.SilkS")
		)
		(fp_line
			(start 0.7874 -0.4064)
			(end 0.7874 0.4064)
			(stroke
				(width 0.1524)
				(type default)
			)
			(layer "F.SilkS")
		)
		(fp_line
			(start -0.7874 0.4064)
			(end -0.7874 -0.4064)
			(stroke
				(width 0.1524)
				(type default)
			)
			(layer "F.SilkS")
		)
		(fp_line
			(start -0.7874 -0.4064)
			(end 0.7874 -0.4064)
			(stroke
				(width 0.1524)
				(type default)
			)
			(layer "F.SilkS")
		)
		(fp_line
			(start 0.67945 0.3048)
			(end 0.120396 0.3048)
			(stroke
				(width 0.1)
				(type default)
			)
			(layer "F.Fab")
		)
		(fp_line
			(start 0.67945 -0.3048)
			(end 0.67945 0.3048)
			(stroke
				(width 0.1)
				(type default)
			)
			(layer "F.Fab")
		)
		(fp_line
			(start 0.12065 -0.2794)
			(end 0.12065 -0.3048)
			(stroke
				(width 0.1)
				(type default)
			)
			(layer "F.Fab")
		)
		(fp_line
			(start 0.12065 -0.3048)
			(end 0.67945 -0.3048)
			(stroke
				(width 0.1)
				(type default)
			)
			(layer "F.Fab")
		)
		(fp_line
			(start 0.120396 0.3048)
			(end 0.120396 0.2794)
			(stroke
				(width 0.1)
				(type default)
			)
			(layer "F.Fab")
		)
		(fp_line
			(start 0.120396 0.2794)
			(end -0.12065 0.2794)
			(stroke
				(width 0.1)
				(type default)
			)
			(layer "F.Fab")
		)
		(fp_line
			(start -0.12065 0.3048)
			(end -0.67945 0.3048)
			(stroke
				(width 0.1)
				(type default)
			)
			(layer "F.Fab")
		)
		(fp_line
			(start -0.12065 0.2794)
			(end -0.12065 0.3048)
			(stroke
				(width 0.1)
				(type default)
			)
			(layer "F.Fab")
		)
		(fp_line
			(start -0.12065 -0.2794)
			(end 0.12065 -0.2794)
			(stroke
				(width 0.1)
				(type default)
			)
			(layer "F.Fab")
		)
		(fp_line
			(start -0.12065 -0.305054)
			(end -0.12065 -0.2794)
			(stroke
				(width 0.1)
				(type default)
			)
			(layer "F.Fab")
		)
		(fp_line
			(start -0.67945 0.3048)
			(end -0.67945 -0.305054)
			(stroke
				(width 0.1)
				(type default)
			)
			(layer "F.Fab")
		)
		(fp_line
			(start -0.67945 -0.305054)
			(end -0.12065 -0.305054)
			(stroke
				(width 0.1)
				(type default)
			)
			(layer "F.Fab")
		)
		(pad "1" smd circle
			(at -0.40005 0 180)
			(size 0 0)
			(layers "F.Cu" "F.Mask" "F.Paste")
			(net "NIC1_SLOT_ID1")
		)
		(pad "2" smd circle
			(at 0.40005 0 180)
			(size 0 0)
			(layers "F.Cu" "F.Mask" "F.Paste")
			(net "P3V3_NIC1")
		)
	)
	(footprint ""
		(layer "F.Cu")
		(at 112.85728 -313.620404)
		(property "Reference" "R5786"
			(at 0 0 0)
			(layer "F.SilkS")
			(hide yes)
			(effects
				(font
					(size 1.27 1.27)
				)
			)
		)
		(property "Value" ""
			(at 0 0 0)
			(layer "F.Fab")
			(effects
				(font
					(size 1.27 1.27)
				)
			)
		)
		(duplicate_pad_numbers_are_jumpers no)
		(fp_line
			(start -2.576322 -1.1303)
			(end 2.576322 -1.1303)
			(stroke
				(width 0.1524)
				(type default)
			)
			(layer "F.SilkS")
		)
		(fp_line
			(start -2.576322 1.1303)
			(end -2.576322 -1.1303)
			(stroke
				(width 0.1524)
				(type default)
			)
			(layer "F.SilkS")
		)
		(fp_line
			(start 2.576322 -1.1303)
			(end 2.576322 1.1303)
			(stroke
				(width 0.1524)
				(type default)
			)
			(layer "F.SilkS")
		)
		(fp_line
			(start 2.576322 1.1303)
			(end -2.576322 1.1303)
			(stroke
				(width 0.1524)
				(type default)
			)
			(layer "F.SilkS")
		)
		(fp_line
			(start -1.649984 -0.899922)
			(end -1.649984 0.899922)
			(stroke
				(width 0.1)
				(type default)
			)
			(layer "F.Fab")
		)
		(fp_line
			(start -1.649984 0.899922)
			(end 1.649984 0.899922)
			(stroke
				(width 0.1)
				(type default)
			)
			(layer "F.Fab")
		)
		(fp_line
			(start 1.649984 -0.899922)
			(end -1.649984 -0.899922)
			(stroke
				(width 0.1)
				(type default)
			)
			(layer "F.Fab")
		)
		(fp_line
			(start 1.649984 0.899922)
			(end 1.649984 -0.899922)
			(stroke
				(width 0.1)
				(type default)
			)
			(layer "F.Fab")
		)
		(pad "1A" smd rect
			(at -1.700022 0)
			(size 1.4986 2.0066)
			(layers "F.Cu" "F.Mask" "F.Paste")
			(net "P0V8_PEX0")
		)
		(pad "1B" smd rect
			(at -1.077722 0)
			(size 0.254 0.508)
			(layers "F.Cu" "F.Mask" "F.Paste")
			(net "P0V8_PEX0")
		)
		(pad "2A" smd rect
			(at 1.700022 0)
			(size 1.4986 2.0066)
			(layers "F.Cu" "F.Mask" "F.Paste")
			(net "P0V8_SERDES_VDDA_PEX0")
		)
		(pad "2B" smd rect
			(at 1.077722 0)
			(size 0.254 0.508)
			(layers "F.Cu" "F.Mask" "F.Paste")
			(net "P0V8_SERDES_VDDA_PEX0")
		)
	)
	(footprint ""
		(layer "F.Cu")
		(at 381.620014 -20.72005)
		(property "Reference" "H115"
			(at 1.578864 -2.588768 0)
			(unlocked yes)
			(layer "B.SilkS")
			(effects
				(font
					(size 0.7874 0.5842)
					(thickness 0.1524)
				)
				(justify left mirror)
			)
		)
		(property "Value" ""
			(at 0 0 0)
			(layer "F.Fab")
			(effects
				(font
					(size 1.27 1.27)
				)
			)
		)
		(duplicate_pad_numbers_are_jumpers no)
		(pad "1" thru_hole rect
			(at 0 0)
			(size 4.2164 5.0038)
			(drill 2.0066
				(offset 0.099822 0)
			)
			(layers "*.Cu" "*.Mask")
			(remove_unused_layers no)
			(net "Net_8548")
			(clearance -0.8509)
			(padstack
				(mode front_inner_back)
				(layer "Inner"
					(shape circle)
					(size 4.0132 4.0132)
					(clearance -0.7493)
				)
				(layer "B.Cu"
					(shape circle)
					(size 4.0132 4.0132)
					(clearance -0.7493)
				)
			)
		)
	)
	(footprint ""
		(layer "F.Cu")
		(at 218.37396 -26.31186 -90)
		(property "Reference" "U405"
			(at -0.15494 -2.40411 90)
			(unlocked yes)
			(layer "F.SilkS")
			(effects
				(font
					(size 0.7874 0.5842)
					(thickness 0.1524)
				)
			)
		)
		(property "Value" ""
			(at 0 0 270)
			(layer "F.Fab")
			(effects
				(font
					(size 1.27 1.27)
				)
			)
		)
		(duplicate_pad_numbers_are_jumpers no)
		(fp_line
			(start -1.949958 1.610106)
			(end -1.949958 -1.610106)
			(stroke
				(width 0.1524)
				(type default)
			)
			(layer "F.SilkS")
		)
		(fp_line
			(start 1.949958 1.610106)
			(end -1.949958 1.610106)
			(stroke
				(width 0.1524)
				(type default)
			)
			(layer "F.SilkS")
		)
		(fp_line
			(start 1.949958 -1.560068)
			(end 1.949958 1.610106)
			(stroke
				(width 0.1524)
				(type default)
			)
			(layer "F.SilkS")
		)
		(fp_line
			(start -1.949958 -1.610106)
			(end 1.949958 -1.610106)
			(stroke
				(width 0.1524)
				(type default)
			)
			(layer "F.SilkS")
		)
		(fp_line
			(start -0.750062 1.560068)
			(end -0.750062 -1.560068)
			(stroke
				(width 0.1)
				(type default)
			)
			(layer "F.Fab")
		)
		(fp_line
			(start 0.750062 1.560068)
			(end -0.750062 1.560068)
			(stroke
				(width 0.1)
				(type default)
			)
			(layer "F.Fab")
		)
		(fp_line
			(start -0.750062 -1.560068)
			(end 0.750062 -1.560068)
			(stroke
				(width 0.1)
				(type default)
			)
			(layer "F.Fab")
		)
		(fp_line
			(start 0.750062 -1.560068)
			(end 0.750062 1.560068)
			(stroke
				(width 0.1)
				(type default)
			)
			(layer "F.Fab")
		)
		(pad "D" smd rect
			(at 1.100074 0 180)
			(size 1.016 1.4224)
			(layers "F.Cu" "F.Mask" "F.Paste")
			(net "SSD7_LED_ISO_N")
		)
		(pad "G" smd rect
			(at -1.100074 -0.94996 180)
			(size 1.016 1.4224)
			(layers "F.Cu" "F.Mask" "F.Paste")
			(net "SSD7_LED_R")
		)
		(pad "S" smd rect
			(at -1.100074 0.94996 180)
			(size 1.016 1.4224)
			(layers "F.Cu" "F.Mask" "F.Paste")
			(net "GND")
		)
	)
	(footprint ""
		(layer "F.Cu")
		(at 166.330884 -192.820798)
		(property "Reference" "R3405"
			(at 0 0 0)
			(layer "F.SilkS")
			(hide yes)
			(effects
				(font
					(size 1.27 1.27)
				)
			)
		)
		(property "Value" ""
			(at 0 0 0)
			(layer "F.Fab")
			(effects
				(font
					(size 1.27 1.27)
				)
			)
		)
		(duplicate_pad_numbers_are_jumpers no)
		(fp_line
			(start -0.7874 -0.4064)
			(end 0.7874 -0.4064)
			(stroke
				(width 0.1524)
				(type default)
			)
			(layer "F.SilkS")
		)
		(fp_line
			(start -0.7874 0.4064)
			(end -0.7874 -0.4064)
			(stroke
				(width 0.1524)
				(type default)
			)
			(layer "F.SilkS")
		)
		(fp_line
			(start 0.7874 -0.4064)
			(end 0.7874 0.4064)
			(stroke
				(width 0.1524)
				(type default)
			)
			(layer "F.SilkS")
		)
		(fp_line
			(start 0.7874 0.4064)
			(end -0.7874 0.4064)
			(stroke
				(width 0.1524)
				(type default)
			)
			(layer "F.SilkS")
		)
		(fp_line
			(start -0.67945 -0.305054)
			(end -0.12065 -0.305054)
			(stroke
				(width 0.1)
				(type default)
			)
			(layer "F.Fab")
		)
		(fp_line
			(start -0.67945 0.3048)
			(end -0.67945 -0.305054)
			(stroke
				(width 0.1)
				(type default)
			)
			(layer "F.Fab")
		)
		(fp_line
			(start -0.12065 -0.305054)
			(end -0.12065 -0.2794)
			(stroke
				(width 0.1)
				(type default)
			)
			(layer "F.Fab")
		)
		(fp_line
			(start -0.12065 -0.2794)
			(end 0.12065 -0.2794)
			(stroke
				(width 0.1)
				(type default)
			)
			(layer "F.Fab")
		)
		(fp_line
			(start -0.12065 0.2794)
			(end -0.12065 0.3048)
			(stroke
				(width 0.1)
				(type default)
			)
			(layer "F.Fab")
		)
		(fp_line
			(start -0.12065 0.3048)
			(end -0.67945 0.3048)
			(stroke
				(width 0.1)
				(type default)
			)
			(layer "F.Fab")
		)
		(fp_line
			(start 0.120396 0.2794)
			(end -0.12065 0.2794)
			(stroke
				(width 0.1)
				(type default)
			)
			(layer "F.Fab")
		)
		(fp_line
			(start 0.120396 0.3048)
			(end 0.120396 0.2794)
			(stroke
				(width 0.1)
				(type default)
			)
			(layer "F.Fab")
		)
		(fp_line
			(start 0.12065 -0.3048)
			(end 0.67945 -0.3048)
			(stroke
				(width 0.1)
				(type default)
			)
			(layer "F.Fab")
		)
		(fp_line
			(start 0.12065 -0.2794)
			(end 0.12065 -0.3048)
			(stroke
				(width 0.1)
				(type default)
			)
			(layer "F.Fab")
		)
		(fp_line
			(start 0.67945 -0.3048)
			(end 0.67945 0.3048)
			(stroke
				(width 0.1)
				(type default)
			)
			(layer "F.Fab")
		)
		(fp_line
			(start 0.67945 0.3048)
			(end 0.120396 0.3048)
			(stroke
				(width 0.1)
				(type default)
			)
			(layer "F.Fab")
		)
		(pad "1" smd circle
			(at -0.40005 0)
			(size 0 0)
			(layers "F.Cu" "F.Mask" "F.Paste")
			(net "SPI_BIC1_MISO_LS01_R1")
		)
		(pad "2" smd circle
			(at 0.40005 0)
			(size 0 0)
			(layers "F.Cu" "F.Mask" "F.Paste")
			(net "SPI_BIC1_MISO_LS01_R")
		)
	)
	(footprint ""
		(layer "F.Cu")
		(at 168.343834 -42.84091)
		(property "Reference" "R560"
			(at 0 0 0)
			(layer "F.SilkS")
			(hide yes)
			(effects
				(font
					(size 1.27 1.27)
				)
			)
		)
		(property "Value" ""
			(at 0 0 0)
			(layer "F.Fab")
			(effects
				(font
					(size 1.27 1.27)
				)
			)
		)
		(duplicate_pad_numbers_are_jumpers no)
		(fp_line
			(start -0.7874 -0.4064)
			(end 0.7874 -0.4064)
			(stroke
				(width 0.1524)
				(type default)
			)
			(layer "F.SilkS")
		)
		(fp_line
			(start -0.7874 0.4064)
			(end -0.7874 -0.4064)
			(stroke
				(width 0.1524)
				(type default)
			)
			(layer "F.SilkS")
		)
		(fp_line
			(start 0.7874 -0.4064)
			(end 0.7874 0.4064)
			(stroke
				(width 0.1524)
				(type default)
			)
			(layer "F.SilkS")
		)
		(fp_line
			(start 0.7874 0.4064)
			(end -0.7874 0.4064)
			(stroke
				(width 0.1524)
				(type default)
			)
			(layer "F.SilkS")
		)
		(fp_line
			(start -0.67945 -0.305054)
			(end -0.12065 -0.305054)
			(stroke
				(width 0.1)
				(type default)
			)
			(layer "F.Fab")
		)
		(fp_line
			(start -0.67945 0.3048)
			(end -0.67945 -0.305054)
			(stroke
				(width 0.1)
				(type default)
			)
			(layer "F.Fab")
		)
		(fp_line
			(start -0.12065 -0.305054)
			(end -0.12065 -0.2794)
			(stroke
				(width 0.1)
				(type default)
			)
			(layer "F.Fab")
		)
		(fp_line
			(start -0.12065 -0.2794)
			(end 0.12065 -0.2794)
			(stroke
				(width 0.1)
				(type default)
			)
			(layer "F.Fab")
		)
		(fp_line
			(start -0.12065 0.2794)
			(end -0.12065 0.3048)
			(stroke
				(width 0.1)
				(type default)
			)
			(layer "F.Fab")
		)
		(fp_line
			(start -0.12065 0.3048)
			(end -0.67945 0.3048)
			(stroke
				(width 0.1)
				(type default)
			)
			(layer "F.Fab")
		)
		(fp_line
			(start 0.120396 0.2794)
			(end -0.12065 0.2794)
			(stroke
				(width 0.1)
				(type default)
			)
			(layer "F.Fab")
		)
		(fp_line
			(start 0.120396 0.3048)
			(end 0.120396 0.2794)
			(stroke
				(width 0.1)
				(type default)
			)
			(layer "F.Fab")
		)
		(fp_line
			(start 0.12065 -0.3048)
			(end 0.67945 -0.3048)
			(stroke
				(width 0.1)
				(type default)
			)
			(layer "F.Fab")
		)
		(fp_line
			(start 0.12065 -0.2794)
			(end 0.12065 -0.3048)
			(stroke
				(width 0.1)
				(type default)
			)
			(layer "F.Fab")
		)
		(fp_line
			(start 0.67945 -0.3048)
			(end 0.67945 0.3048)
			(stroke
				(width 0.1)
				(type default)
			)
			(layer "F.Fab")
		)
		(fp_line
			(start 0.67945 0.3048)
			(end 0.120396 0.3048)
			(stroke
				(width 0.1)
				(type default)
			)
			(layer "F.Fab")
		)
		(pad "1" smd circle
			(at -0.40005 0)
			(size 0 0)
			(layers "F.Cu" "F.Mask" "F.Paste")
			(net "SSD5_ADC_A1")
		)
		(pad "2" smd circle
			(at 0.40005 0)
			(size 0 0)
			(layers "F.Cu" "F.Mask" "F.Paste")
			(net "P3V3_AUX")
		)
	)
	(footprint ""
		(layer "F.Cu")
		(at 430.673764 -27.006296 -90)
		(property "Reference" "PC974"
			(at 0 0 270)
			(layer "F.SilkS")
			(hide yes)
			(effects
				(font
					(size 1.27 1.27)
				)
			)
		)
		(property "Value" ""
			(at 0 0 270)
			(layer "F.Fab")
			(effects
				(font
					(size 1.27 1.27)
				)
			)
		)
		(duplicate_pad_numbers_are_jumpers no)
		(fp_line
			(start -0.7874 0.4064)
			(end -0.7874 -0.4064)
			(stroke
				(width 0.1524)
				(type default)
			)
			(layer "F.SilkS")
		)
		(fp_line
			(start 0.7874 0.4064)
			(end -0.7874 0.4064)
			(stroke
				(width 0.1524)
				(type default)
			)
			(layer "F.SilkS")
		)
		(fp_line
			(start -0.7874 -0.4064)
			(end 0.7874 -0.4064)
			(stroke
				(width 0.1524)
				(type default)
			)
			(layer "F.SilkS")
		)
		(fp_line
			(start 0.7874 -0.4064)
			(end 0.7874 0.4064)
			(stroke
				(width 0.1524)
				(type default)
			)
			(layer "F.SilkS")
		)
		(fp_line
			(start -0.67945 0.3048)
			(end -0.67945 -0.305054)
			(stroke
				(width 0.1)
				(type default)
			)
			(layer "F.Fab")
		)
		(fp_line
			(start -0.12065 0.3048)
			(end -0.67945 0.3048)
			(stroke
				(width 0.1)
				(type default)
			)
			(layer "F.Fab")
		)
		(fp_line
			(start 0.120396 0.3048)
			(end 0.120396 0.2794)
			(stroke
				(width 0.1)
				(type default)
			)
			(layer "F.Fab")
		)
		(fp_line
			(start 0.67945 0.3048)
			(end 0.120396 0.3048)
			(stroke
				(width 0.1)
				(type default)
			)
			(layer "F.Fab")
		)
		(fp_line
			(start -0.12065 0.2794)
			(end -0.12065 0.3048)
			(stroke
				(width 0.1)
				(type default)
			)
			(layer "F.Fab")
		)
		(fp_line
			(start 0.120396 0.2794)
			(end -0.12065 0.2794)
			(stroke
				(width 0.1)
				(type default)
			)
			(layer "F.Fab")
		)
		(fp_line
			(start -0.12065 -0.2794)
			(end 0.12065 -0.2794)
			(stroke
				(width 0.1)
				(type default)
			)
			(layer "F.Fab")
		)
		(fp_line
			(start 0.12065 -0.2794)
			(end 0.12065 -0.3048)
			(stroke
				(width 0.1)
				(type default)
			)
			(layer "F.Fab")
		)
		(fp_line
			(start 0.12065 -0.3048)
			(end 0.67945 -0.3048)
			(stroke
				(width 0.1)
				(type default)
			)
			(layer "F.Fab")
		)
		(fp_line
			(start 0.67945 -0.3048)
			(end 0.67945 0.3048)
			(stroke
				(width 0.1)
				(type default)
			)
			(layer "F.Fab")
		)
		(fp_line
			(start -0.67945 -0.305054)
			(end -0.12065 -0.305054)
			(stroke
				(width 0.1)
				(type default)
			)
			(layer "F.Fab")
		)
		(fp_line
			(start -0.12065 -0.305054)
			(end -0.12065 -0.2794)
			(stroke
				(width 0.1)
				(type default)
			)
			(layer "F.Fab")
		)
		(pad "1" smd circle
			(at -0.40005 0 270)
			(size 0 0)
			(layers "F.Cu" "F.Mask" "F.Paste")
			(net "P3V3_SSD15_CO_MODE")
		)
		(pad "2" smd circle
			(at 0.40005 0 270)
			(size 0 0)
			(layers "F.Cu" "F.Mask" "F.Paste")
			(net "GND")
		)
	)
	(footprint ""
		(layer "F.Cu")
		(at 268.786102 -350.098614 90)
		(property "Reference" "C614"
			(at 0 0 90)
			(layer "F.SilkS")
			(hide yes)
			(effects
				(font
					(size 1.27 1.27)
				)
			)
		)
		(property "Value" ""
			(at 0 0 90)
			(layer "F.Fab")
			(effects
				(font
					(size 1.27 1.27)
				)
			)
		)
		(duplicate_pad_numbers_are_jumpers no)
		(fp_line
			(start 0.299974 -0.150114)
			(end 0.299974 0.150114)
			(stroke
				(width 0.1)
				(type default)
			)
			(layer "F.Fab")
		)
		(fp_line
			(start -0.299974 -0.150114)
			(end 0.299974 -0.150114)
			(stroke
				(width 0.1)
				(type default)
			)
			(layer "F.Fab")
		)
		(fp_line
			(start 0.299974 0.150114)
			(end -0.299974 0.150114)
			(stroke
				(width 0.1)
				(type default)
			)
			(layer "F.Fab")
		)
		(fp_line
			(start -0.299974 0.150114)
			(end -0.299974 -0.150114)
			(stroke
				(width 0.1)
				(type default)
			)
			(layer "F.Fab")
		)
		(pad "1" smd rect
			(at -0.2667 0 90)
			(size 0.3048 0.381)
			(layers "F.Cu" "F.Mask" "F.Paste")
			(net "P5E_PEX2_STN7_TX_DN<112>")
		)
		(pad "2" smd rect
			(at 0.2667 0 90)
			(size 0.3048 0.381)
			(layers "F.Cu" "F.Mask" "F.Paste")
			(net "P5E_PEX2_STN7_TX_C_DN<112>")
		)
	)
	(footprint ""
		(layer "F.Cu")
		(at 407.295096 -99.750372 180)
		(property "Reference" "R385"
			(at 0 0 180)
			(layer "F.SilkS")
			(hide yes)
			(effects
				(font
					(size 1.27 1.27)
				)
			)
		)
		(property "Value" ""
			(at 0 0 180)
			(layer "F.Fab")
			(effects
				(font
					(size 1.27 1.27)
				)
			)
		)
		(duplicate_pad_numbers_are_jumpers no)
		(fp_line
			(start 0.7874 0.4064)
			(end -0.7874 0.4064)
			(stroke
				(width 0.1524)
				(type default)
			)
			(layer "F.SilkS")
		)
		(fp_line
			(start 0.7874 -0.4064)
			(end 0.7874 0.4064)
			(stroke
				(width 0.1524)
				(type default)
			)
			(layer "F.SilkS")
		)
		(fp_line
			(start -0.7874 0.4064)
			(end -0.7874 -0.4064)
			(stroke
				(width 0.1524)
				(type default)
			)
			(layer "F.SilkS")
		)
		(fp_line
			(start -0.7874 -0.4064)
			(end 0.7874 -0.4064)
			(stroke
				(width 0.1524)
				(type default)
			)
			(layer "F.SilkS")
		)
		(fp_line
			(start 0.67945 0.3048)
			(end 0.120396 0.3048)
			(stroke
				(width 0.1)
				(type default)
			)
			(layer "F.Fab")
		)
		(fp_line
			(start 0.67945 -0.3048)
			(end 0.67945 0.3048)
			(stroke
				(width 0.1)
				(type default)
			)
			(layer "F.Fab")
		)
		(fp_line
			(start 0.12065 -0.2794)
			(end 0.12065 -0.3048)
			(stroke
				(width 0.1)
				(type default)
			)
			(layer "F.Fab")
		)
		(fp_line
			(start 0.12065 -0.3048)
			(end 0.67945 -0.3048)
			(stroke
				(width 0.1)
				(type default)
			)
			(layer "F.Fab")
		)
		(fp_line
			(start 0.120396 0.3048)
			(end 0.120396 0.2794)
			(stroke
				(width 0.1)
				(type default)
			)
			(layer "F.Fab")
		)
		(fp_line
			(start 0.120396 0.2794)
			(end -0.12065 0.2794)
			(stroke
				(width 0.1)
				(type default)
			)
			(layer "F.Fab")
		)
		(fp_line
			(start -0.12065 0.3048)
			(end -0.67945 0.3048)
			(stroke
				(width 0.1)
				(type default)
			)
			(layer "F.Fab")
		)
		(fp_line
			(start -0.12065 0.2794)
			(end -0.12065 0.3048)
			(stroke
				(width 0.1)
				(type default)
			)
			(layer "F.Fab")
		)
		(fp_line
			(start -0.12065 -0.2794)
			(end 0.12065 -0.2794)
			(stroke
				(width 0.1)
				(type default)
			)
			(layer "F.Fab")
		)
		(fp_line
			(start -0.12065 -0.305054)
			(end -0.12065 -0.2794)
			(stroke
				(width 0.1)
				(type default)
			)
			(layer "F.Fab")
		)
		(fp_line
			(start -0.67945 0.3048)
			(end -0.67945 -0.305054)
			(stroke
				(width 0.1)
				(type default)
			)
			(layer "F.Fab")
		)
		(fp_line
			(start -0.67945 -0.305054)
			(end -0.12065 -0.305054)
			(stroke
				(width 0.1)
				(type default)
			)
			(layer "F.Fab")
		)
		(pad "1" smd circle
			(at -0.40005 0 180)
			(size 0 0)
			(layers "F.Cu" "F.Mask" "F.Paste")
			(net "NIC7_SLOT_ID1")
		)
		(pad "2" smd circle
			(at 0.40005 0 180)
			(size 0 0)
			(layers "F.Cu" "F.Mask" "F.Paste")
			(net "GND")
		)
	)
	(footprint ""
		(layer "F.Cu")
		(at 87.006684 -294.77335 90)
		(property "Reference" "U425"
			(at -1.0922 -2.174748 90)
			(unlocked yes)
			(layer "F.SilkS")
			(effects
				(font
					(size 0.7874 0.5842)
					(thickness 0.1524)
				)
				(justify left)
			)
		)
		(property "Value" ""
			(at 0 0 90)
			(layer "F.Fab")
			(effects
				(font
					(size 1.27 1.27)
				)
			)
		)
		(duplicate_pad_numbers_are_jumpers no)
		(fp_line
			(start 1.0414 -1.575054)
			(end 1.0414 1.575054)
			(stroke
				(width 0.1524)
				(type default)
			)
			(layer "F.SilkS")
		)
		(fp_line
			(start 0.254 -1.575054)
			(end 1.0414 -1.575054)
			(stroke
				(width 0.1524)
				(type default)
			)
			(layer "F.SilkS")
		)
		(fp_line
			(start 0.2286 -1.575054)
			(end 0 -1.272032)
			(stroke
				(width 0.1524)
				(type default)
			)
			(layer "F.SilkS")
		)
		(fp_line
			(start -1.0414 -1.575054)
			(end -0.254 -1.575054)
			(stroke
				(width 0.1524)
				(type default)
			)
			(layer "F.SilkS")
		)
		(fp_line
			(start 0 -1.272032)
			(end -0.254 -1.575054)
			(stroke
				(width 0.1524)
				(type default)
			)
			(layer "F.SilkS")
		)
		(fp_line
			(start 1.0414 1.575054)
			(end -1.0414 1.575054)
			(stroke
				(width 0.1524)
				(type default)
			)
			(layer "F.SilkS")
		)
		(fp_line
			(start -1.0414 1.575054)
			(end -1.0414 -1.575054)
			(stroke
				(width 0.1524)
				(type default)
			)
			(layer "F.SilkS")
		)
		(fp_poly
			(pts
				(xy -2.710688 -0.975106) (xy -3.726688 -1.483106) (xy -3.726688 -0.467106)
			)
			(stroke
				(width 0)
				(type default)
			)
			(fill yes)
			(layer "F.SilkS")
		)
		(fp_line
			(start 1.4478 -1.5748)
			(end 1.4478 -1.2192)
			(stroke
				(width 0.1)
				(type default)
			)
			(layer "F.Fab")
		)
		(fp_line
			(start -1.4478 -1.5748)
			(end 1.4478 -1.5748)
			(stroke
				(width 0.1)
				(type default)
			)
			(layer "F.Fab")
		)
		(fp_line
			(start 2.5654 -1.2192)
			(end 2.5654 1.2192)
			(stroke
				(width 0.1)
				(type default)
			)
			(layer "F.Fab")
		)
		(fp_line
			(start 1.4478 -1.2192)
			(end 2.5654 -1.2192)
			(stroke
				(width 0.1)
				(type default)
			)
			(layer "F.Fab")
		)
		(fp_line
			(start -1.4478 -1.2192)
			(end -1.4478 -1.5748)
			(stroke
				(width 0.1)
				(type default)
			)
			(layer "F.Fab")
		)
		(fp_line
			(start -2.5654 -1.2192)
			(end -1.4478 -1.2192)
			(stroke
				(width 0.1)
				(type default)
			)
			(layer "F.Fab")
		)
		(fp_line
			(start 2.5654 1.2192)
			(end 1.4478 1.2192)
			(stroke
				(width 0.1)
				(type default)
			)
			(layer "F.Fab")
		)
		(fp_line
			(start 1.4478 1.2192)
			(end 1.4478 1.5748)
			(stroke
				(width 0.1)
				(type default)
			)
			(layer "F.Fab")
		)
		(fp_line
			(start -1.4478 1.2192)
			(end -2.5654 1.2192)
			(stroke
				(width 0.1)
				(type default)
			)
			(layer "F.Fab")
		)
		(fp_line
			(start -2.5654 1.2192)
			(end -2.5654 -1.2192)
			(stroke
				(width 0.1)
				(type default)
			)
			(layer "F.Fab")
		)
		(fp_line
			(start 1.4478 1.5748)
			(end -1.4478 1.5748)
			(stroke
				(width 0.1)
				(type default)
			)
			(layer "F.Fab")
		)
		(fp_line
			(start -1.4478 1.5748)
			(end -1.4478 1.2192)
			(stroke
				(width 0.1)
				(type default)
			)
			(layer "F.Fab")
		)
		(fp_poly
			(pts
				(xy -2.710688 -0.975106) (xy -3.726688 -1.483106) (xy -3.726688 -0.467106)
			)
			(stroke
				(width 0)
				(type default)
			)
			(fill yes)
			(layer "F.Fab")
		)
		(pad "1" smd rect
			(at -1.849882 -0.975106)
			(size 0.3556 1.3208)
			(layers "F.Cu" "F.Mask" "F.Paste")
			(net "RST_PEX0_PERST_R_N")
		)
		(pad "2" smd rect
			(at -1.849882 -0.32512)
			(size 0.3556 1.3208)
			(layers "F.Cu" "F.Mask" "F.Paste")
			(net "RST_PEX0_S0_PERST_N")
		)
		(pad "3" smd rect
			(at -1.849882 0.32512)
			(size 0.3556 1.3208)
			(layers "F.Cu" "F.Mask" "F.Paste")
			(net "RST_PEX0_PERST_R_N")
		)
		(pad "4" smd rect
			(at -1.849882 0.975106)
			(size 0.3556 1.3208)
			(layers "F.Cu" "F.Mask" "F.Paste")
			(net "GND")
		)
		(pad "5" smd rect
			(at 1.849882 0.975106)
			(size 0.3556 1.3208)
			(layers "F.Cu" "F.Mask" "F.Paste")
			(net "RST_PEX0_S1_PERST_N")
		)
		(pad "6" smd rect
			(at 1.849882 0.32512)
			(size 0.3556 1.3208)
			(layers "F.Cu" "F.Mask" "F.Paste")
			(net "RST_PEX0_PERST_R_N")
		)
		(pad "7" smd rect
			(at 1.849882 -0.32512)
			(size 0.3556 1.3208)
			(layers "F.Cu" "F.Mask" "F.Paste")
			(net "RST_PEX0_S3_PERST_N")
		)
		(pad "8" smd rect
			(at 1.849882 -0.975106)
			(size 0.3556 1.3208)
			(layers "F.Cu" "F.Mask" "F.Paste")
			(net "P1V8_PEX")
		)
	)
	(footprint ""
		(layer "F.Cu")
		(at 199.955658 -237.187232)
		(property "Reference" "J60"
			(at -1.4224 -4.562348 0)
			(unlocked yes)
			(layer "F.SilkS")
			(effects
				(font
					(size 0.7874 0.5842)
					(thickness 0.1524)
				)
				(justify left)
			)
		)
		(property "Value" ""
			(at 0 0 0)
			(layer "F.Fab")
			(effects
				(font
					(size 1.27 1.27)
				)
			)
		)
		(duplicate_pad_numbers_are_jumpers no)
		(fp_line
			(start -1.27 -3.81)
			(end 1.27 -3.81)
			(stroke
				(width 0.1524)
				(type default)
			)
			(layer "F.SilkS")
		)
		(fp_line
			(start -1.27 -0.7747)
			(end -1.27 -3.81)
			(stroke
				(width 0.1524)
				(type default)
			)
			(layer "F.SilkS")
		)
		(fp_line
			(start -1.27 3.81)
			(end -1.27 0.7747)
			(stroke
				(width 0.1524)
				(type default)
			)
			(layer "F.SilkS")
		)
		(fp_line
			(start 1.27 -3.81)
			(end 1.27 -3.3147)
			(stroke
				(width 0.1524)
				(type default)
			)
			(layer "F.SilkS")
		)
		(fp_line
			(start 1.27 -1.7653)
			(end 1.27 1.7653)
			(stroke
				(width 0.1524)
				(type default)
			)
			(layer "F.SilkS")
		)
		(fp_line
			(start 1.27 3.3147)
			(end 1.27 3.81)
			(stroke
				(width 0.1524)
				(type default)
			)
			(layer "F.SilkS")
		)
		(fp_line
			(start 1.27 3.81)
			(end -1.27 3.81)
			(stroke
				(width 0.1524)
				(type default)
			)
			(layer "F.SilkS")
		)
		(fp_poly
			(pts
				(xy 4.3942 -3.048) (xy 4.3942 -2.032) (xy 3.3782 -2.54)
			)
			(stroke
				(width 0)
				(type default)
			)
			(fill yes)
			(layer "F.SilkS")
		)
		(fp_line
			(start -1.27 -3.81)
			(end -1.27 3.81)
			(stroke
				(width 0.1)
				(type default)
			)
			(layer "F.Fab")
		)
		(fp_line
			(start -1.27 3.81)
			(end 1.27 3.81)
			(stroke
				(width 0.1)
				(type default)
			)
			(layer "F.Fab")
		)
		(fp_line
			(start 1.27 -3.81)
			(end -1.27 -3.81)
			(stroke
				(width 0.1)
				(type default)
			)
			(layer "F.Fab")
		)
		(fp_line
			(start 1.27 3.81)
			(end 1.27 -3.81)
			(stroke
				(width 0.1)
				(type default)
			)
			(layer "F.Fab")
		)
		(fp_poly
			(pts
				(xy 4.3942 -3.048) (xy 4.3942 -2.032) (xy 3.3782 -2.54)
			)
			(stroke
				(width 0)
				(type default)
			)
			(fill yes)
			(layer "F.Fab")
		)
		(fp_text user "3"
			(at 3.921252 2.54 90)
			(unlocked yes)
			(layer "F.SilkS")
			(effects
				(font
					(size 0.7874 0.5842)
					(thickness 0.1524)
				)
			)
		)
		(fp_text user "3"
			(at 3.921252 2.54 90)
			(unlocked yes)
			(layer "F.Fab")
			(effects
				(font
					(size 0.7874 0.5842)
					(thickness 0.1524)
				)
			)
		)
		(pad "1" smd rect
			(at 1.459992 -2.54 90)
			(size 1.27 3.429)
			(layers "F.Cu" "F.Mask" "F.Paste")
			(net "BIC_UART_SW_SEL1_R")
		)
		(pad "2" smd rect
			(at -1.459992 0 90)
			(size 1.27 3.429)
			(layers "F.Cu" "F.Mask" "F.Paste")
			(net "BIC_UART_SEL1")
		)
		(pad "3" smd rect
			(at 1.459992 2.54 90)
			(size 1.27 3.429)
			(layers "F.Cu" "F.Mask" "F.Paste")
			(net "BIC_UART_HW_SEL1")
		)
	)
	(footprint ""
		(layer "F.Cu")
		(at 214.675466 -69.47916 180)
		(property "Reference" "PU110"
			(at -1.937004 4.18084 90)
			(unlocked yes)
			(layer "F.SilkS")
			(effects
				(font
					(size 0.7874 0.5842)
					(thickness 0.1524)
				)
			)
		)
		(property "Value" ""
			(at 0 0 180)
			(layer "F.Fab")
			(effects
				(font
					(size 1.27 1.27)
				)
			)
		)
		(duplicate_pad_numbers_are_jumpers no)
		(fp_line
			(start 1.239774 1.495298)
			(end -1.239774 1.495298)
			(stroke
				(width 0.1524)
				(type default)
			)
			(layer "F.SilkS")
		)
		(fp_line
			(start 1.239774 -1.495298)
			(end 1.239774 1.495298)
			(stroke
				(width 0.1524)
				(type default)
			)
			(layer "F.SilkS")
		)
		(fp_line
			(start -1.239774 1.495298)
			(end -1.239774 -1.495298)
			(stroke
				(width 0.1524)
				(type default)
			)
			(layer "F.SilkS")
		)
		(fp_line
			(start -1.239774 -1.495298)
			(end 1.239774 -1.495298)
			(stroke
				(width 0.1524)
				(type default)
			)
			(layer "F.SilkS")
		)
		(fp_poly
			(pts
				(xy -1.801622 -1.255268) (xy -2.520188 -0.536956) (xy -1.442466 -0.1778)
			)
			(stroke
				(width 0)
				(type default)
			)
			(fill yes)
			(layer "F.SilkS")
		)
		(fp_line
			(start 0.8001 1.050036)
			(end -0.8001 1.050036)
			(stroke
				(width 0.1)
				(type default)
			)
			(layer "F.Fab")
		)
		(fp_line
			(start 0.8001 -1.050036)
			(end 0.8001 1.050036)
			(stroke
				(width 0.1)
				(type default)
			)
			(layer "F.Fab")
		)
		(fp_line
			(start -0.8001 1.050036)
			(end -0.8001 -1.050036)
			(stroke
				(width 0.1)
				(type default)
			)
			(layer "F.Fab")
		)
		(fp_line
			(start -0.8001 -1.050036)
			(end 0.8001 -1.050036)
			(stroke
				(width 0.1)
				(type default)
			)
			(layer "F.Fab")
		)
		(fp_poly
			(pts
				(xy -2.458974 -0.508) (xy -2.458974 0.508) (xy -1.442974 0)
			)
			(stroke
				(width 0)
				(type default)
			)
			(fill yes)
			(layer "F.Fab")
		)
		(pad "1_2" smd circle
			(at -0.374904 0 270)
			(size 0 0)
			(layers "F.Cu" "F.Mask" "F.Paste")
			(net "P12V_AUX")
		)
		(pad "3" smd rect
			(at -0.499872 0.999998 180)
			(size 0.254 0.7112)
			(layers "F.Cu" "F.Mask" "F.Paste")
			(net "GND")
		)
		(pad "4" smd rect
			(at 0 0.999998 180)
			(size 0.254 0.7112)
			(layers "F.Cu" "F.Mask" "F.Paste")
			(net "P12V_SSD7_CO_ILIMIT")
		)
		(pad "5" smd rect
			(at 0.499872 0.999998 180)
			(size 0.254 0.7112)
			(layers "F.Cu" "F.Mask" "F.Paste")
			(net "P12V_SSD7_CO_MODE")
		)
		(pad "6_7" smd circle
			(at 0.374904 0 90)
			(size 0 0)
			(layers "F.Cu" "F.Mask" "F.Paste")
			(net "P12V_SSD7_R")
		)
		(pad "8" smd rect
			(at 0.499872 -0.999998 180)
			(size 0.254 0.7112)
			(layers "F.Cu" "F.Mask" "F.Paste")
			(net "P12V_SSD7_CO_GATE")
		)
		(pad "9" smd rect
			(at 0 -0.999998 180)
			(size 0.254 0.7112)
			(layers "F.Cu" "F.Mask" "F.Paste")
			(net "P12V_SSD7_CO_EN")
		)
		(pad "10" smd rect
			(at -0.499872 -0.999998 180)
			(size 0.254 0.7112)
			(layers "F.Cu" "F.Mask" "F.Paste")
			(net "P12V_SSD7_CO_DV_DT")
		)
	)
	(footprint ""
		(layer "F.Cu")
		(at 357.988108 -208.233518 180)
		(property "Reference" "R6423"
			(at 0 0 180)
			(layer "F.SilkS")
			(hide yes)
			(effects
				(font
					(size 1.27 1.27)
				)
			)
		)
		(property "Value" ""
			(at 0 0 180)
			(layer "F.Fab")
			(effects
				(font
					(size 1.27 1.27)
				)
			)
		)
		(duplicate_pad_numbers_are_jumpers no)
		(fp_line
			(start 0.7874 0.4064)
			(end -0.7874 0.4064)
			(stroke
				(width 0.1524)
				(type default)
			)
			(layer "F.SilkS")
		)
		(fp_line
			(start 0.7874 -0.4064)
			(end 0.7874 0.4064)
			(stroke
				(width 0.1524)
				(type default)
			)
			(layer "F.SilkS")
		)
		(fp_line
			(start -0.7874 0.4064)
			(end -0.7874 -0.4064)
			(stroke
				(width 0.1524)
				(type default)
			)
			(layer "F.SilkS")
		)
		(fp_line
			(start -0.7874 -0.4064)
			(end 0.7874 -0.4064)
			(stroke
				(width 0.1524)
				(type default)
			)
			(layer "F.SilkS")
		)
		(fp_line
			(start 0.67945 0.3048)
			(end 0.120396 0.3048)
			(stroke
				(width 0.1)
				(type default)
			)
			(layer "F.Fab")
		)
		(fp_line
			(start 0.67945 -0.3048)
			(end 0.67945 0.3048)
			(stroke
				(width 0.1)
				(type default)
			)
			(layer "F.Fab")
		)
		(fp_line
			(start 0.12065 -0.2794)
			(end 0.12065 -0.3048)
			(stroke
				(width 0.1)
				(type default)
			)
			(layer "F.Fab")
		)
		(fp_line
			(start 0.12065 -0.3048)
			(end 0.67945 -0.3048)
			(stroke
				(width 0.1)
				(type default)
			)
			(layer "F.Fab")
		)
		(fp_line
			(start 0.120396 0.3048)
			(end 0.120396 0.2794)
			(stroke
				(width 0.1)
				(type default)
			)
			(layer "F.Fab")
		)
		(fp_line
			(start 0.120396 0.2794)
			(end -0.12065 0.2794)
			(stroke
				(width 0.1)
				(type default)
			)
			(layer "F.Fab")
		)
		(fp_line
			(start -0.12065 0.3048)
			(end -0.67945 0.3048)
			(stroke
				(width 0.1)
				(type default)
			)
			(layer "F.Fab")
		)
		(fp_line
			(start -0.12065 0.2794)
			(end -0.12065 0.3048)
			(stroke
				(width 0.1)
				(type default)
			)
			(layer "F.Fab")
		)
		(fp_line
			(start -0.12065 -0.2794)
			(end 0.12065 -0.2794)
			(stroke
				(width 0.1)
				(type default)
			)
			(layer "F.Fab")
		)
		(fp_line
			(start -0.12065 -0.305054)
			(end -0.12065 -0.2794)
			(stroke
				(width 0.1)
				(type default)
			)
			(layer "F.Fab")
		)
		(fp_line
			(start -0.67945 0.3048)
			(end -0.67945 -0.305054)
			(stroke
				(width 0.1)
				(type default)
			)
			(layer "F.Fab")
		)
		(fp_line
			(start -0.67945 -0.305054)
			(end -0.12065 -0.305054)
			(stroke
				(width 0.1)
				(type default)
			)
			(layer "F.Fab")
		)
		(pad "1" smd circle
			(at -0.40005 0 180)
			(size 0 0)
			(layers "F.Cu" "F.Mask" "F.Paste")
			(net "FPGA_PEX3_MODE_SEL1_R")
		)
		(pad "2" smd circle
			(at 0.40005 0 180)
			(size 0 0)
			(layers "F.Cu" "F.Mask" "F.Paste")
			(net "FPGA_PEX3_MODE_SEL1")
		)
	)
	(footprint ""
		(layer "F.Cu")
		(at 239.345724 -181.87035 90)
		(property "Reference" "U358"
			(at 1.97485 0.736346 90)
			(unlocked yes)
			(layer "F.SilkS")
			(effects
				(font
					(size 0.7874 0.5842)
					(thickness 0.1524)
				)
				(justify left)
			)
		)
		(property "Value" ""
			(at 0 0 90)
			(layer "F.Fab")
			(effects
				(font
					(size 1.27 1.27)
				)
			)
		)
		(duplicate_pad_numbers_are_jumpers no)
		(fp_line
			(start 0.700024 -1.519936)
			(end 0.700024 -1.3716)
			(stroke
				(width 0.1524)
				(type default)
			)
			(layer "F.SilkS")
		)
		(fp_line
			(start -0.700024 -1.519936)
			(end 0.700024 -1.519936)
			(stroke
				(width 0.1524)
				(type default)
			)
			(layer "F.SilkS")
		)
		(fp_line
			(start -0.700024 -1.3716)
			(end -0.700024 -1.519936)
			(stroke
				(width 0.1524)
				(type default)
			)
			(layer "F.SilkS")
		)
		(fp_line
			(start 0.700024 -0.5334)
			(end 0.700024 0.5334)
			(stroke
				(width 0.1524)
				(type default)
			)
			(layer "F.SilkS")
		)
		(fp_line
			(start -0.700024 0.5334)
			(end -0.700024 -0.127)
			(stroke
				(width 0.1524)
				(type default)
			)
			(layer "F.SilkS")
		)
		(fp_line
			(start 0.700024 1.3716)
			(end 0.700024 1.519936)
			(stroke
				(width 0.1524)
				(type default)
			)
			(layer "F.SilkS")
		)
		(fp_line
			(start 0.700024 1.519936)
			(end -0.700024 1.519936)
			(stroke
				(width 0.1524)
				(type default)
			)
			(layer "F.SilkS")
		)
		(fp_line
			(start -0.700024 1.519936)
			(end -0.700024 1.3716)
			(stroke
				(width 0.1524)
				(type default)
			)
			(layer "F.SilkS")
		)
		(fp_poly
			(pts
				(xy -2.926842 -0.517398) (xy -2.926842 -1.142238) (xy -2.373122 -0.81407)
			)
			(stroke
				(width 0)
				(type default)
			)
			(fill yes)
			(layer "F.SilkS")
		)
		(fp_line
			(start 0.700024 -1.519936)
			(end 0.700024 1.519936)
			(stroke
				(width 0.1)
				(type default)
			)
			(layer "F.Fab")
		)
		(fp_line
			(start -0.700024 -1.519936)
			(end 0.700024 -1.519936)
			(stroke
				(width 0.1)
				(type default)
			)
			(layer "F.Fab")
		)
		(fp_line
			(start 0.700024 1.519936)
			(end -0.700024 1.519936)
			(stroke
				(width 0.1)
				(type default)
			)
			(layer "F.Fab")
		)
		(fp_line
			(start -0.700024 1.519936)
			(end -0.700024 -1.519936)
			(stroke
				(width 0.1)
				(type default)
			)
			(layer "F.Fab")
		)
		(fp_poly
			(pts
				(xy -2.45872 -0.465328) (xy -2.45872 -1.090168) (xy -1.905 -0.762)
			)
			(stroke
				(width 0)
				(type default)
			)
			(fill yes)
			(layer "F.Fab")
		)
		(pad "1" smd rect
			(at -0.985012 -0.759968)
			(size 0.9652 1.4224)
			(layers "F.Cu" "F.Mask" "F.Paste")
			(net "GND")
		)
		(pad "2" smd rect
			(at -0.985012 0.96012)
			(size 0.5588 1.4224)
			(layers "F.Cu" "F.Mask" "F.Paste")
			(net "BIC_RST_RSMRST_N")
		)
		(pad "3" smd rect
			(at 0.985012 0.96012)
			(size 0.5588 1.4224)
			(layers "F.Cu" "F.Mask" "F.Paste")
			(net "Net_8960")
		)
		(pad "4" smd rect
			(at 0.985012 -0.96012)
			(size 0.5588 1.4224)
			(layers "F.Cu" "F.Mask" "F.Paste")
			(net "P3V3_AUX")
		)
	)
	(footprint ""
		(layer "F.Cu")
		(at 327.533 -240.157 90)
		(property "Reference" "R1782"
			(at 0 0 90)
			(layer "F.SilkS")
			(hide yes)
			(effects
				(font
					(size 1.27 1.27)
				)
			)
		)
		(property "Value" ""
			(at 0 0 90)
			(layer "F.Fab")
			(effects
				(font
					(size 1.27 1.27)
				)
			)
		)
		(duplicate_pad_numbers_are_jumpers no)
		(fp_line
			(start 0.7874 -0.4064)
			(end 0.7874 0.4064)
			(stroke
				(width 0.1524)
				(type default)
			)
			(layer "F.SilkS")
		)
		(fp_line
			(start -0.7874 -0.4064)
			(end 0.7874 -0.4064)
			(stroke
				(width 0.1524)
				(type default)
			)
			(layer "F.SilkS")
		)
		(fp_line
			(start 0.7874 0.4064)
			(end -0.7874 0.4064)
			(stroke
				(width 0.1524)
				(type default)
			)
			(layer "F.SilkS")
		)
		(fp_line
			(start -0.7874 0.4064)
			(end -0.7874 -0.4064)
			(stroke
				(width 0.1524)
				(type default)
			)
			(layer "F.SilkS")
		)
		(fp_line
			(start -0.12065 -0.305054)
			(end -0.12065 -0.2794)
			(stroke
				(width 0.1)
				(type default)
			)
			(layer "F.Fab")
		)
		(fp_line
			(start -0.67945 -0.305054)
			(end -0.12065 -0.305054)
			(stroke
				(width 0.1)
				(type default)
			)
			(layer "F.Fab")
		)
		(fp_line
			(start 0.67945 -0.3048)
			(end 0.67945 0.3048)
			(stroke
				(width 0.1)
				(type default)
			)
			(layer "F.Fab")
		)
		(fp_line
			(start 0.12065 -0.3048)
			(end 0.67945 -0.3048)
			(stroke
				(width 0.1)
				(type default)
			)
			(layer "F.Fab")
		)
		(fp_line
			(start 0.12065 -0.2794)
			(end 0.12065 -0.3048)
			(stroke
				(width 0.1)
				(type default)
			)
			(layer "F.Fab")
		)
		(fp_line
			(start -0.12065 -0.2794)
			(end 0.12065 -0.2794)
			(stroke
				(width 0.1)
				(type default)
			)
			(layer "F.Fab")
		)
		(fp_line
			(start 0.120396 0.2794)
			(end -0.12065 0.2794)
			(stroke
				(width 0.1)
				(type default)
			)
			(layer "F.Fab")
		)
		(fp_line
			(start -0.12065 0.2794)
			(end -0.12065 0.3048)
			(stroke
				(width 0.1)
				(type default)
			)
			(layer "F.Fab")
		)
		(fp_line
			(start 0.67945 0.3048)
			(end 0.120396 0.3048)
			(stroke
				(width 0.1)
				(type default)
			)
			(layer "F.Fab")
		)
		(fp_line
			(start 0.120396 0.3048)
			(end 0.120396 0.2794)
			(stroke
				(width 0.1)
				(type default)
			)
			(layer "F.Fab")
		)
		(fp_line
			(start -0.12065 0.3048)
			(end -0.67945 0.3048)
			(stroke
				(width 0.1)
				(type default)
			)
			(layer "F.Fab")
		)
		(fp_line
			(start -0.67945 0.3048)
			(end -0.67945 -0.305054)
			(stroke
				(width 0.1)
				(type default)
			)
			(layer "F.Fab")
		)
		(pad "1" smd circle
			(at -0.40005 0 90)
			(size 0 0)
			(layers "F.Cu" "F.Mask" "F.Paste")
			(net "PRSNT_GPU_ISO")
		)
		(pad "2" smd circle
			(at 0.40005 0 90)
			(size 0 0)
			(layers "F.Cu" "F.Mask" "F.Paste")
			(net "P3V3_AUX")
		)
	)
	(footprint ""
		(layer "F.Cu")
		(at 215.630506 -66.32194 -90)
		(property "Reference" "PC857"
			(at 0 0 270)
			(layer "F.SilkS")
			(hide yes)
			(effects
				(font
					(size 1.27 1.27)
				)
			)
		)
		(property "Value" ""
			(at 0 0 270)
			(layer "F.Fab")
			(effects
				(font
					(size 1.27 1.27)
				)
			)
		)
		(duplicate_pad_numbers_are_jumpers no)
		(fp_line
			(start -0.7874 0.4064)
			(end -0.7874 -0.4064)
			(stroke
				(width 0.1524)
				(type default)
			)
			(layer "F.SilkS")
		)
		(fp_line
			(start 0.7874 0.4064)
			(end -0.7874 0.4064)
			(stroke
				(width 0.1524)
				(type default)
			)
			(layer "F.SilkS")
		)
		(fp_line
			(start -0.7874 -0.4064)
			(end 0.7874 -0.4064)
			(stroke
				(width 0.1524)
				(type default)
			)
			(layer "F.SilkS")
		)
		(fp_line
			(start 0.7874 -0.4064)
			(end 0.7874 0.4064)
			(stroke
				(width 0.1524)
				(type default)
			)
			(layer "F.SilkS")
		)
		(fp_line
			(start -0.67945 0.3048)
			(end -0.67945 -0.305054)
			(stroke
				(width 0.1)
				(type default)
			)
			(layer "F.Fab")
		)
		(fp_line
			(start -0.12065 0.3048)
			(end -0.67945 0.3048)
			(stroke
				(width 0.1)
				(type default)
			)
			(layer "F.Fab")
		)
		(fp_line
			(start 0.120396 0.3048)
			(end 0.120396 0.2794)
			(stroke
				(width 0.1)
				(type default)
			)
			(layer "F.Fab")
		)
		(fp_line
			(start 0.67945 0.3048)
			(end 0.120396 0.3048)
			(stroke
				(width 0.1)
				(type default)
			)
			(layer "F.Fab")
		)
		(fp_line
			(start -0.12065 0.2794)
			(end -0.12065 0.3048)
			(stroke
				(width 0.1)
				(type default)
			)
			(layer "F.Fab")
		)
		(fp_line
			(start 0.120396 0.2794)
			(end -0.12065 0.2794)
			(stroke
				(width 0.1)
				(type default)
			)
			(layer "F.Fab")
		)
		(fp_line
			(start -0.12065 -0.2794)
			(end 0.12065 -0.2794)
			(stroke
				(width 0.1)
				(type default)
			)
			(layer "F.Fab")
		)
		(fp_line
			(start 0.12065 -0.2794)
			(end 0.12065 -0.3048)
			(stroke
				(width 0.1)
				(type default)
			)
			(layer "F.Fab")
		)
		(fp_line
			(start 0.12065 -0.3048)
			(end 0.67945 -0.3048)
			(stroke
				(width 0.1)
				(type default)
			)
			(layer "F.Fab")
		)
		(fp_line
			(start 0.67945 -0.3048)
			(end 0.67945 0.3048)
			(stroke
				(width 0.1)
				(type default)
			)
			(layer "F.Fab")
		)
		(fp_line
			(start -0.67945 -0.305054)
			(end -0.12065 -0.305054)
			(stroke
				(width 0.1)
				(type default)
			)
			(layer "F.Fab")
		)
		(fp_line
			(start -0.12065 -0.305054)
			(end -0.12065 -0.2794)
			(stroke
				(width 0.1)
				(type default)
			)
			(layer "F.Fab")
		)
		(pad "1" smd circle
			(at -0.40005 0 270)
			(size 0 0)
			(layers "F.Cu" "F.Mask" "F.Paste")
			(net "P12V_SSD7_CO_DV_DT")
		)
		(pad "2" smd circle
			(at 0.40005 0 270)
			(size 0 0)
			(layers "F.Cu" "F.Mask" "F.Paste")
			(net "GND")
		)
	)
	(footprint ""
		(layer "F.Cu")
		(at 482.92893 -526.47723 180)
		(property "Reference" "J37_OTH"
			(at -3.2385 -1.402334 0)
			(unlocked yes)
			(layer "B.SilkS")
			(effects
				(font
					(size 0.7874 0.5842)
					(thickness 0.1524)
				)
				(justify mirror)
			)
		)
		(property "Value" ""
			(at 0 0 180)
			(layer "F.Fab")
			(effects
				(font
					(size 1.27 1.27)
				)
			)
		)
		(duplicate_pad_numbers_are_jumpers no)
		(pad "1" thru_hole circle
			(at 0 0 180)
			(size 0.4572 0.4572)
			(drill 0.2032)
			(layers "*.Cu" "*.Mask")
			(remove_unused_layers no)
			(net "Net_9099")
			(clearance 0.127)
			(thermal_gap 0.127)
			(padstack
				(mode front_inner_back)
				(layer "Inner"
					(shape circle)
					(size 0.4572 0.4572)
					(clearance 0.127)
				)
				(layer "B.Cu"
					(shape circle)
					(size 0.508 0.508)
					(clearance 0.1016)
				)
			)
		)
	)
	(footprint ""
		(layer "F.Cu")
		(at 401.426172 -37.929566 90)
		(property "Reference" "R5579"
			(at 0 0 90)
			(layer "F.SilkS")
			(hide yes)
			(effects
				(font
					(size 1.27 1.27)
				)
			)
		)
		(property "Value" ""
			(at 0 0 90)
			(layer "F.Fab")
			(effects
				(font
					(size 1.27 1.27)
				)
			)
		)
		(duplicate_pad_numbers_are_jumpers no)
		(fp_line
			(start 0.7874 -0.4064)
			(end 0.7874 0.4064)
			(stroke
				(width 0.1524)
				(type default)
			)
			(layer "F.SilkS")
		)
		(fp_line
			(start -0.7874 -0.4064)
			(end 0.7874 -0.4064)
			(stroke
				(width 0.1524)
				(type default)
			)
			(layer "F.SilkS")
		)
		(fp_line
			(start 0.7874 0.4064)
			(end -0.7874 0.4064)
			(stroke
				(width 0.1524)
				(type default)
			)
			(layer "F.SilkS")
		)
		(fp_line
			(start -0.7874 0.4064)
			(end -0.7874 -0.4064)
			(stroke
				(width 0.1524)
				(type default)
			)
			(layer "F.SilkS")
		)
		(fp_line
			(start -0.12065 -0.305054)
			(end -0.12065 -0.2794)
			(stroke
				(width 0.1)
				(type default)
			)
			(layer "F.Fab")
		)
		(fp_line
			(start -0.67945 -0.305054)
			(end -0.12065 -0.305054)
			(stroke
				(width 0.1)
				(type default)
			)
			(layer "F.Fab")
		)
		(fp_line
			(start 0.67945 -0.3048)
			(end 0.67945 0.3048)
			(stroke
				(width 0.1)
				(type default)
			)
			(layer "F.Fab")
		)
		(fp_line
			(start 0.12065 -0.3048)
			(end 0.67945 -0.3048)
			(stroke
				(width 0.1)
				(type default)
			)
			(layer "F.Fab")
		)
		(fp_line
			(start 0.12065 -0.2794)
			(end 0.12065 -0.3048)
			(stroke
				(width 0.1)
				(type default)
			)
			(layer "F.Fab")
		)
		(fp_line
			(start -0.12065 -0.2794)
			(end 0.12065 -0.2794)
			(stroke
				(width 0.1)
				(type default)
			)
			(layer "F.Fab")
		)
		(fp_line
			(start 0.120396 0.2794)
			(end -0.12065 0.2794)
			(stroke
				(width 0.1)
				(type default)
			)
			(layer "F.Fab")
		)
		(fp_line
			(start -0.12065 0.2794)
			(end -0.12065 0.3048)
			(stroke
				(width 0.1)
				(type default)
			)
			(layer "F.Fab")
		)
		(fp_line
			(start 0.67945 0.3048)
			(end 0.120396 0.3048)
			(stroke
				(width 0.1)
				(type default)
			)
			(layer "F.Fab")
		)
		(fp_line
			(start 0.120396 0.3048)
			(end 0.120396 0.2794)
			(stroke
				(width 0.1)
				(type default)
			)
			(layer "F.Fab")
		)
		(fp_line
			(start -0.12065 0.3048)
			(end -0.67945 0.3048)
			(stroke
				(width 0.1)
				(type default)
			)
			(layer "F.Fab")
		)
		(fp_line
			(start -0.67945 0.3048)
			(end -0.67945 -0.305054)
			(stroke
				(width 0.1)
				(type default)
			)
			(layer "F.Fab")
		)
		(pad "1" smd circle
			(at -0.40005 0 90)
			(size 0 0)
			(layers "F.Cu" "F.Mask" "F.Paste")
			(net "SSD14_AUX_P3V3_EN_R")
		)
		(pad "2" smd circle
			(at 0.40005 0 90)
			(size 0 0)
			(layers "F.Cu" "F.Mask" "F.Paste")
			(net "SSD14_AUX_P3V3_EN")
		)
	)
	(footprint ""
		(layer "F.Cu")
		(at 96.722438 -44.341542 90)
		(property "Reference" "R547"
			(at 0 0 90)
			(layer "F.SilkS")
			(hide yes)
			(effects
				(font
					(size 1.27 1.27)
				)
			)
		)
		(property "Value" ""
			(at 0 0 90)
			(layer "F.Fab")
			(effects
				(font
					(size 1.27 1.27)
				)
			)
		)
		(duplicate_pad_numbers_are_jumpers no)
		(fp_line
			(start 0.7874 -0.4064)
			(end 0.7874 0.4064)
			(stroke
				(width 0.1524)
				(type default)
			)
			(layer "F.SilkS")
		)
		(fp_line
			(start -0.7874 -0.4064)
			(end 0.7874 -0.4064)
			(stroke
				(width 0.1524)
				(type default)
			)
			(layer "F.SilkS")
		)
		(fp_line
			(start 0.7874 0.4064)
			(end -0.7874 0.4064)
			(stroke
				(width 0.1524)
				(type default)
			)
			(layer "F.SilkS")
		)
		(fp_line
			(start -0.7874 0.4064)
			(end -0.7874 -0.4064)
			(stroke
				(width 0.1524)
				(type default)
			)
			(layer "F.SilkS")
		)
		(fp_line
			(start -0.12065 -0.305054)
			(end -0.12065 -0.2794)
			(stroke
				(width 0.1)
				(type default)
			)
			(layer "F.Fab")
		)
		(fp_line
			(start -0.67945 -0.305054)
			(end -0.12065 -0.305054)
			(stroke
				(width 0.1)
				(type default)
			)
			(layer "F.Fab")
		)
		(fp_line
			(start 0.67945 -0.3048)
			(end 0.67945 0.3048)
			(stroke
				(width 0.1)
				(type default)
			)
			(layer "F.Fab")
		)
		(fp_line
			(start 0.12065 -0.3048)
			(end 0.67945 -0.3048)
			(stroke
				(width 0.1)
				(type default)
			)
			(layer "F.Fab")
		)
		(fp_line
			(start 0.12065 -0.2794)
			(end 0.12065 -0.3048)
			(stroke
				(width 0.1)
				(type default)
			)
			(layer "F.Fab")
		)
		(fp_line
			(start -0.12065 -0.2794)
			(end 0.12065 -0.2794)
			(stroke
				(width 0.1)
				(type default)
			)
			(layer "F.Fab")
		)
		(fp_line
			(start 0.120396 0.2794)
			(end -0.12065 0.2794)
			(stroke
				(width 0.1)
				(type default)
			)
			(layer "F.Fab")
		)
		(fp_line
			(start -0.12065 0.2794)
			(end -0.12065 0.3048)
			(stroke
				(width 0.1)
				(type default)
			)
			(layer "F.Fab")
		)
		(fp_line
			(start 0.67945 0.3048)
			(end 0.120396 0.3048)
			(stroke
				(width 0.1)
				(type default)
			)
			(layer "F.Fab")
		)
		(fp_line
			(start 0.120396 0.3048)
			(end 0.120396 0.2794)
			(stroke
				(width 0.1)
				(type default)
			)
			(layer "F.Fab")
		)
		(fp_line
			(start -0.12065 0.3048)
			(end -0.67945 0.3048)
			(stroke
				(width 0.1)
				(type default)
			)
			(layer "F.Fab")
		)
		(fp_line
			(start -0.67945 0.3048)
			(end -0.67945 -0.305054)
			(stroke
				(width 0.1)
				(type default)
			)
			(layer "F.Fab")
		)
		(pad "1" smd circle
			(at -0.40005 0 90)
			(size 0 0)
			(layers "F.Cu" "F.Mask" "F.Paste")
			(net "P12V_SSD3")
		)
		(pad "2" smd circle
			(at 0.40005 0 90)
			(size 0 0)
			(layers "F.Cu" "F.Mask" "F.Paste")
			(net "P12V_SSD3_VIN_N")
		)
	)
	(footprint ""
		(layer "F.Cu")
		(at 215.047322 -20.35556)
		(property "Reference" "C3922"
			(at 0 0 0)
			(layer "F.SilkS")
			(hide yes)
			(effects
				(font
					(size 1.27 1.27)
				)
			)
		)
		(property "Value" ""
			(at 0 0 0)
			(layer "F.Fab")
			(effects
				(font
					(size 1.27 1.27)
				)
			)
		)
		(duplicate_pad_numbers_are_jumpers no)
		(fp_line
			(start -0.7874 -0.4064)
			(end 0.7874 -0.4064)
			(stroke
				(width 0.1524)
				(type default)
			)
			(layer "F.SilkS")
		)
		(fp_line
			(start -0.7874 0.4064)
			(end -0.7874 -0.4064)
			(stroke
				(width 0.1524)
				(type default)
			)
			(layer "F.SilkS")
		)
		(fp_line
			(start 0.7874 -0.4064)
			(end 0.7874 0.4064)
			(stroke
				(width 0.1524)
				(type default)
			)
			(layer "F.SilkS")
		)
		(fp_line
			(start 0.7874 0.4064)
			(end -0.7874 0.4064)
			(stroke
				(width 0.1524)
				(type default)
			)
			(layer "F.SilkS")
		)
		(fp_line
			(start -0.67945 -0.305054)
			(end -0.12065 -0.305054)
			(stroke
				(width 0.1)
				(type default)
			)
			(layer "F.Fab")
		)
		(fp_line
			(start -0.67945 0.3048)
			(end -0.67945 -0.305054)
			(stroke
				(width 0.1)
				(type default)
			)
			(layer "F.Fab")
		)
		(fp_line
			(start -0.12065 -0.305054)
			(end -0.12065 -0.2794)
			(stroke
				(width 0.1)
				(type default)
			)
			(layer "F.Fab")
		)
		(fp_line
			(start -0.12065 -0.2794)
			(end 0.12065 -0.2794)
			(stroke
				(width 0.1)
				(type default)
			)
			(layer "F.Fab")
		)
		(fp_line
			(start -0.12065 0.2794)
			(end -0.12065 0.3048)
			(stroke
				(width 0.1)
				(type default)
			)
			(layer "F.Fab")
		)
		(fp_line
			(start -0.12065 0.3048)
			(end -0.67945 0.3048)
			(stroke
				(width 0.1)
				(type default)
			)
			(layer "F.Fab")
		)
		(fp_line
			(start 0.120396 0.2794)
			(end -0.12065 0.2794)
			(stroke
				(width 0.1)
				(type default)
			)
			(layer "F.Fab")
		)
		(fp_line
			(start 0.120396 0.3048)
			(end 0.120396 0.2794)
			(stroke
				(width 0.1)
				(type default)
			)
			(layer "F.Fab")
		)
		(fp_line
			(start 0.12065 -0.3048)
			(end 0.67945 -0.3048)
			(stroke
				(width 0.1)
				(type default)
			)
			(layer "F.Fab")
		)
		(fp_line
			(start 0.12065 -0.2794)
			(end 0.12065 -0.3048)
			(stroke
				(width 0.1)
				(type default)
			)
			(layer "F.Fab")
		)
		(fp_line
			(start 0.67945 -0.3048)
			(end 0.67945 0.3048)
			(stroke
				(width 0.1)
				(type default)
			)
			(layer "F.Fab")
		)
		(fp_line
			(start 0.67945 0.3048)
			(end 0.120396 0.3048)
			(stroke
				(width 0.1)
				(type default)
			)
			(layer "F.Fab")
		)
		(pad "1" smd circle
			(at -0.40005 0)
			(size 0 0)
			(layers "F.Cu" "F.Mask" "F.Paste")
			(net "P12V_SSD7")
		)
		(pad "2" smd circle
			(at 0.40005 0)
			(size 0 0)
			(layers "F.Cu" "F.Mask" "F.Paste")
			(net "GND")
		)
	)
	(footprint ""
		(layer "F.Cu")
		(at 344.612976 -86.169754 180)
		(property "Reference" "R1179"
			(at 0 0 180)
			(layer "F.SilkS")
			(hide yes)
			(effects
				(font
					(size 1.27 1.27)
				)
			)
		)
		(property "Value" ""
			(at 0 0 180)
			(layer "F.Fab")
			(effects
				(font
					(size 1.27 1.27)
				)
			)
		)
		(duplicate_pad_numbers_are_jumpers no)
		(fp_line
			(start 0.7874 0.4064)
			(end -0.7874 0.4064)
			(stroke
				(width 0.1524)
				(type default)
			)
			(layer "F.SilkS")
		)
		(fp_line
			(start 0.67945 0.3048)
			(end 0.120396 0.3048)
			(stroke
				(width 0.1)
				(type default)
			)
			(layer "F.Fab")
		)
		(fp_line
			(start 0.67945 -0.3048)
			(end 0.67945 0.3048)
			(stroke
				(width 0.1)
				(type default)
			)
			(layer "F.Fab")
		)
		(fp_line
			(start 0.12065 -0.2794)
			(end 0.12065 -0.3048)
			(stroke
				(width 0.1)
				(type default)
			)
			(layer "F.Fab")
		)
		(fp_line
			(start 0.12065 -0.3048)
			(end 0.67945 -0.3048)
			(stroke
				(width 0.1)
				(type default)
			)
			(layer "F.Fab")
		)
		(fp_line
			(start 0.120396 0.3048)
			(end 0.120396 0.2794)
			(stroke
				(width 0.1)
				(type default)
			)
			(layer "F.Fab")
		)
		(fp_line
			(start 0.120396 0.2794)
			(end -0.12065 0.2794)
			(stroke
				(width 0.1)
				(type default)
			)
			(layer "F.Fab")
		)
		(fp_line
			(start -0.12065 0.3048)
			(end -0.67945 0.3048)
			(stroke
				(width 0.1)
				(type default)
			)
			(layer "F.Fab")
		)
		(fp_line
			(start -0.12065 0.2794)
			(end -0.12065 0.3048)
			(stroke
				(width 0.1)
				(type default)
			)
			(layer "F.Fab")
		)
		(fp_line
			(start -0.12065 -0.2794)
			(end 0.12065 -0.2794)
			(stroke
				(width 0.1)
				(type default)
			)
			(layer "F.Fab")
		)
		(fp_line
			(start -0.12065 -0.305054)
			(end -0.12065 -0.2794)
			(stroke
				(width 0.1)
				(type default)
			)
			(layer "F.Fab")
		)
		(fp_line
			(start -0.67945 0.3048)
			(end -0.67945 -0.305054)
			(stroke
				(width 0.1)
				(type default)
			)
			(layer "F.Fab")
		)
		(fp_line
			(start -0.67945 -0.305054)
			(end -0.12065 -0.305054)
			(stroke
				(width 0.1)
				(type default)
			)
			(layer "F.Fab")
		)
		(pad "1" smd circle
			(at -0.40005 0 180)
			(size 0 0)
			(layers "F.Cu" "F.Mask" "F.Paste")
			(net "CLK_100M_DB800ZL_SSD12_R_DN")
		)
		(pad "2" smd circle
			(at 0.40005 0 180)
			(size 0 0)
			(layers "F.Cu" "F.Mask" "F.Paste")
			(net "CLK_100M_DB800ZL_SSD12_DN")
		)
	)
	(footprint ""
		(layer "F.Cu")
		(at 489.627164 -525.080992 180)
		(property "Reference" "PEX3_HS"
			(at 0.127 -0.593598 0)
			(unlocked yes)
			(layer "F.SilkS")
			(effects
				(font
					(size 0.254 0.127)
					(thickness 0.000001)
				)
			)
		)
		(property "Value" ""
			(at 0 0 180)
			(layer "F.Fab")
			(effects
				(font
					(size 1.27 1.27)
				)
			)
		)
		(duplicate_pad_numbers_are_jumpers no)
		(pad "1" smd circle
			(at 0 0 180)
			(size 0.762 0.762)
			(layers "F.Cu" "F.Mask" "F.Paste")
			(net "Net_9121")
		)
	)
	(footprint ""
		(layer "F.Cu")
		(at 80.915002 -356.244906 90)
		(property "Reference" "C148"
			(at 0 0 90)
			(layer "F.SilkS")
			(hide yes)
			(effects
				(font
					(size 1.27 1.27)
				)
			)
		)
		(property "Value" ""
			(at 0 0 90)
			(layer "F.Fab")
			(effects
				(font
					(size 1.27 1.27)
				)
			)
		)
		(duplicate_pad_numbers_are_jumpers no)
		(fp_line
			(start 0.299974 -0.150114)
			(end 0.299974 0.150114)
			(stroke
				(width 0.1)
				(type default)
			)
			(layer "F.Fab")
		)
		(fp_line
			(start -0.299974 -0.150114)
			(end 0.299974 -0.150114)
			(stroke
				(width 0.1)
				(type default)
			)
			(layer "F.Fab")
		)
		(fp_line
			(start 0.299974 0.150114)
			(end -0.299974 0.150114)
			(stroke
				(width 0.1)
				(type default)
			)
			(layer "F.Fab")
		)
		(fp_line
			(start -0.299974 0.150114)
			(end -0.299974 -0.150114)
			(stroke
				(width 0.1)
				(type default)
			)
			(layer "F.Fab")
		)
		(pad "1" smd rect
			(at -0.2667 0 90)
			(size 0.3048 0.381)
			(layers "F.Cu" "F.Mask" "F.Paste")
			(net "P5E_PEX0_STN6_TX_DN<102>")
		)
		(pad "2" smd rect
			(at 0.2667 0 90)
			(size 0.3048 0.381)
			(layers "F.Cu" "F.Mask" "F.Paste")
			(net "P5E_PEX0_STN6_TX_C_DN<102>")
		)
	)
	(footprint ""
		(layer "F.Cu")
		(at 331.06614 -95.263716 -90)
		(property "Reference" "PC324"
			(at 0 0 270)
			(layer "F.SilkS")
			(hide yes)
			(effects
				(font
					(size 1.27 1.27)
				)
			)
		)
		(property "Value" ""
			(at 0 0 270)
			(layer "F.Fab")
			(effects
				(font
					(size 1.27 1.27)
				)
			)
		)
		(duplicate_pad_numbers_are_jumpers no)
		(fp_line
			(start -0.7874 0.4064)
			(end -0.7874 -0.4064)
			(stroke
				(width 0.1524)
				(type default)
			)
			(layer "F.SilkS")
		)
		(fp_line
			(start 0.7874 0.4064)
			(end -0.7874 0.4064)
			(stroke
				(width 0.1524)
				(type default)
			)
			(layer "F.SilkS")
		)
		(fp_line
			(start -0.7874 -0.4064)
			(end 0.7874 -0.4064)
			(stroke
				(width 0.1524)
				(type default)
			)
			(layer "F.SilkS")
		)
		(fp_line
			(start 0.7874 -0.4064)
			(end 0.7874 0.4064)
			(stroke
				(width 0.1524)
				(type default)
			)
			(layer "F.SilkS")
		)
		(fp_line
			(start -0.67945 0.3048)
			(end -0.67945 -0.305054)
			(stroke
				(width 0.1)
				(type default)
			)
			(layer "F.Fab")
		)
		(fp_line
			(start -0.12065 0.3048)
			(end -0.67945 0.3048)
			(stroke
				(width 0.1)
				(type default)
			)
			(layer "F.Fab")
		)
		(fp_line
			(start 0.120396 0.3048)
			(end 0.120396 0.2794)
			(stroke
				(width 0.1)
				(type default)
			)
			(layer "F.Fab")
		)
		(fp_line
			(start 0.67945 0.3048)
			(end 0.120396 0.3048)
			(stroke
				(width 0.1)
				(type default)
			)
			(layer "F.Fab")
		)
		(fp_line
			(start -0.12065 0.2794)
			(end -0.12065 0.3048)
			(stroke
				(width 0.1)
				(type default)
			)
			(layer "F.Fab")
		)
		(fp_line
			(start 0.120396 0.2794)
			(end -0.12065 0.2794)
			(stroke
				(width 0.1)
				(type default)
			)
			(layer "F.Fab")
		)
		(fp_line
			(start -0.12065 -0.2794)
			(end 0.12065 -0.2794)
			(stroke
				(width 0.1)
				(type default)
			)
			(layer "F.Fab")
		)
		(fp_line
			(start 0.12065 -0.2794)
			(end 0.12065 -0.3048)
			(stroke
				(width 0.1)
				(type default)
			)
			(layer "F.Fab")
		)
		(fp_line
			(start 0.12065 -0.3048)
			(end 0.67945 -0.3048)
			(stroke
				(width 0.1)
				(type default)
			)
			(layer "F.Fab")
		)
		(fp_line
			(start 0.67945 -0.3048)
			(end 0.67945 0.3048)
			(stroke
				(width 0.1)
				(type default)
			)
			(layer "F.Fab")
		)
		(fp_line
			(start -0.67945 -0.305054)
			(end -0.12065 -0.305054)
			(stroke
				(width 0.1)
				(type default)
			)
			(layer "F.Fab")
		)
		(fp_line
			(start -0.12065 -0.305054)
			(end -0.12065 -0.2794)
			(stroke
				(width 0.1)
				(type default)
			)
			(layer "F.Fab")
		)
		(pad "1" smd circle
			(at -0.40005 0 270)
			(size 0 0)
			(layers "F.Cu" "F.Mask" "F.Paste")
			(net "P5V_AUX")
		)
		(pad "2" smd circle
			(at 0.40005 0 270)
			(size 0 0)
			(layers "F.Cu" "F.Mask" "F.Paste")
			(net "GND")
		)
	)
	(footprint ""
		(layer "F.Cu")
		(at 58.709052 -26.03373)
		(property "Reference" "R4056"
			(at 0 0 0)
			(layer "F.SilkS")
			(hide yes)
			(effects
				(font
					(size 1.27 1.27)
				)
			)
		)
		(property "Value" ""
			(at 0 0 0)
			(layer "F.Fab")
			(effects
				(font
					(size 1.27 1.27)
				)
			)
		)
		(duplicate_pad_numbers_are_jumpers no)
		(fp_line
			(start -0.7874 -0.4064)
			(end 0.7874 -0.4064)
			(stroke
				(width 0.1524)
				(type default)
			)
			(layer "F.SilkS")
		)
		(fp_line
			(start -0.7874 0.4064)
			(end -0.7874 -0.4064)
			(stroke
				(width 0.1524)
				(type default)
			)
			(layer "F.SilkS")
		)
		(fp_line
			(start 0.7874 -0.4064)
			(end 0.7874 0.4064)
			(stroke
				(width 0.1524)
				(type default)
			)
			(layer "F.SilkS")
		)
		(fp_line
			(start 0.7874 0.4064)
			(end -0.7874 0.4064)
			(stroke
				(width 0.1524)
				(type default)
			)
			(layer "F.SilkS")
		)
		(fp_line
			(start -0.67945 -0.305054)
			(end -0.12065 -0.305054)
			(stroke
				(width 0.1)
				(type default)
			)
			(layer "F.Fab")
		)
		(fp_line
			(start -0.67945 0.3048)
			(end -0.67945 -0.305054)
			(stroke
				(width 0.1)
				(type default)
			)
			(layer "F.Fab")
		)
		(fp_line
			(start -0.12065 -0.305054)
			(end -0.12065 -0.2794)
			(stroke
				(width 0.1)
				(type default)
			)
			(layer "F.Fab")
		)
		(fp_line
			(start -0.12065 -0.2794)
			(end 0.12065 -0.2794)
			(stroke
				(width 0.1)
				(type default)
			)
			(layer "F.Fab")
		)
		(fp_line
			(start -0.12065 0.2794)
			(end -0.12065 0.3048)
			(stroke
				(width 0.1)
				(type default)
			)
			(layer "F.Fab")
		)
		(fp_line
			(start -0.12065 0.3048)
			(end -0.67945 0.3048)
			(stroke
				(width 0.1)
				(type default)
			)
			(layer "F.Fab")
		)
		(fp_line
			(start 0.120396 0.2794)
			(end -0.12065 0.2794)
			(stroke
				(width 0.1)
				(type default)
			)
			(layer "F.Fab")
		)
		(fp_line
			(start 0.120396 0.3048)
			(end 0.120396 0.2794)
			(stroke
				(width 0.1)
				(type default)
			)
			(layer "F.Fab")
		)
		(fp_line
			(start 0.12065 -0.3048)
			(end 0.67945 -0.3048)
			(stroke
				(width 0.1)
				(type default)
			)
			(layer "F.Fab")
		)
		(fp_line
			(start 0.12065 -0.2794)
			(end 0.12065 -0.3048)
			(stroke
				(width 0.1)
				(type default)
			)
			(layer "F.Fab")
		)
		(fp_line
			(start 0.67945 -0.3048)
			(end 0.67945 0.3048)
			(stroke
				(width 0.1)
				(type default)
			)
			(layer "F.Fab")
		)
		(fp_line
			(start 0.67945 0.3048)
			(end 0.120396 0.3048)
			(stroke
				(width 0.1)
				(type default)
			)
			(layer "F.Fab")
		)
		(pad "1" smd circle
			(at -0.40005 0)
			(size 0 0)
			(layers "F.Cu" "F.Mask" "F.Paste")
			(net "P3V3_AUX")
		)
		(pad "2" smd circle
			(at 0.40005 0)
			(size 0 0)
			(layers "F.Cu" "F.Mask" "F.Paste")
			(net "PRSNT_SSD2_R_N")
		)
	)
	(footprint ""
		(layer "F.Cu")
		(at 41.984168 -350.098614 90)
		(property "Reference" "C2173"
			(at 0 0 90)
			(layer "F.SilkS")
			(hide yes)
			(effects
				(font
					(size 1.27 1.27)
				)
			)
		)
		(property "Value" ""
			(at 0 0 90)
			(layer "F.Fab")
			(effects
				(font
					(size 1.27 1.27)
				)
			)
		)
		(duplicate_pad_numbers_are_jumpers no)
		(fp_line
			(start 0.299974 -0.150114)
			(end 0.299974 0.150114)
			(stroke
				(width 0.1)
				(type default)
			)
			(layer "F.Fab")
		)
		(fp_line
			(start -0.299974 -0.150114)
			(end 0.299974 -0.150114)
			(stroke
				(width 0.1)
				(type default)
			)
			(layer "F.Fab")
		)
		(fp_line
			(start 0.299974 0.150114)
			(end -0.299974 0.150114)
			(stroke
				(width 0.1)
				(type default)
			)
			(layer "F.Fab")
		)
		(fp_line
			(start -0.299974 0.150114)
			(end -0.299974 -0.150114)
			(stroke
				(width 0.1)
				(type default)
			)
			(layer "F.Fab")
		)
		(pad "1" smd rect
			(at -0.2667 0 90)
			(size 0.3048 0.381)
			(layers "F.Cu" "F.Mask" "F.Paste")
			(net "P5E_PEX0_STN4_TX_DN<69>")
		)
		(pad "2" smd rect
			(at 0.2667 0 90)
			(size 0.3048 0.381)
			(layers "F.Cu" "F.Mask" "F.Paste")
			(net "P5E_PEX0_STN4_TX_C_DN<69>")
		)
	)
	(footprint ""
		(layer "F.Cu")
		(at 219.202 -195.072 180)
		(property "Reference" "C2705"
			(at 0 0 180)
			(layer "F.SilkS")
			(hide yes)
			(effects
				(font
					(size 1.27 1.27)
				)
			)
		)
		(property "Value" ""
			(at 0 0 180)
			(layer "F.Fab")
			(effects
				(font
					(size 1.27 1.27)
				)
			)
		)
		(duplicate_pad_numbers_are_jumpers no)
		(fp_line
			(start 0.7874 0.4064)
			(end -0.7874 0.4064)
			(stroke
				(width 0.1524)
				(type default)
			)
			(layer "F.SilkS")
		)
		(fp_line
			(start 0.7874 -0.4064)
			(end 0.7874 0.4064)
			(stroke
				(width 0.1524)
				(type default)
			)
			(layer "F.SilkS")
		)
		(fp_line
			(start -0.7874 0.4064)
			(end -0.7874 -0.4064)
			(stroke
				(width 0.1524)
				(type default)
			)
			(layer "F.SilkS")
		)
		(fp_line
			(start -0.7874 -0.4064)
			(end 0.7874 -0.4064)
			(stroke
				(width 0.1524)
				(type default)
			)
			(layer "F.SilkS")
		)
		(fp_line
			(start 0.67945 0.3048)
			(end 0.120396 0.3048)
			(stroke
				(width 0.1)
				(type default)
			)
			(layer "F.Fab")
		)
		(fp_line
			(start 0.67945 -0.3048)
			(end 0.67945 0.3048)
			(stroke
				(width 0.1)
				(type default)
			)
			(layer "F.Fab")
		)
		(fp_line
			(start 0.12065 -0.2794)
			(end 0.12065 -0.3048)
			(stroke
				(width 0.1)
				(type default)
			)
			(layer "F.Fab")
		)
		(fp_line
			(start 0.12065 -0.3048)
			(end 0.67945 -0.3048)
			(stroke
				(width 0.1)
				(type default)
			)
			(layer "F.Fab")
		)
		(fp_line
			(start 0.120396 0.3048)
			(end 0.120396 0.2794)
			(stroke
				(width 0.1)
				(type default)
			)
			(layer "F.Fab")
		)
		(fp_line
			(start 0.120396 0.2794)
			(end -0.12065 0.2794)
			(stroke
				(width 0.1)
				(type default)
			)
			(layer "F.Fab")
		)
		(fp_line
			(start -0.12065 0.3048)
			(end -0.67945 0.3048)
			(stroke
				(width 0.1)
				(type default)
			)
			(layer "F.Fab")
		)
		(fp_line
			(start -0.12065 0.2794)
			(end -0.12065 0.3048)
			(stroke
				(width 0.1)
				(type default)
			)
			(layer "F.Fab")
		)
		(fp_line
			(start -0.12065 -0.2794)
			(end 0.12065 -0.2794)
			(stroke
				(width 0.1)
				(type default)
			)
			(layer "F.Fab")
		)
		(fp_line
			(start -0.12065 -0.305054)
			(end -0.12065 -0.2794)
			(stroke
				(width 0.1)
				(type default)
			)
			(layer "F.Fab")
		)
		(fp_line
			(start -0.67945 0.3048)
			(end -0.67945 -0.305054)
			(stroke
				(width 0.1)
				(type default)
			)
			(layer "F.Fab")
		)
		(fp_line
			(start -0.67945 -0.305054)
			(end -0.12065 -0.305054)
			(stroke
				(width 0.1)
				(type default)
			)
			(layer "F.Fab")
		)
		(pad "1" smd circle
			(at -0.40005 0 180)
			(size 0 0)
			(layers "F.Cu" "F.Mask" "F.Paste")
			(net "GND")
		)
		(pad "2" smd circle
			(at 0.40005 0 180)
			(size 0 0)
			(layers "F.Cu" "F.Mask" "F.Paste")
			(net "P3V3_NIC7")
		)
	)
	(footprint ""
		(layer "F.Cu")
		(at 206.623158 -83.659472)
		(property "Reference" "R4303"
			(at 0 0 0)
			(layer "F.SilkS")
			(hide yes)
			(effects
				(font
					(size 1.27 1.27)
				)
			)
		)
		(property "Value" ""
			(at 0 0 0)
			(layer "F.Fab")
			(effects
				(font
					(size 1.27 1.27)
				)
			)
		)
		(duplicate_pad_numbers_are_jumpers no)
		(fp_line
			(start -0.7874 -0.4064)
			(end 0.7874 -0.4064)
			(stroke
				(width 0.1524)
				(type default)
			)
			(layer "F.SilkS")
		)
		(fp_line
			(start -0.7874 0.4064)
			(end -0.7874 -0.4064)
			(stroke
				(width 0.1524)
				(type default)
			)
			(layer "F.SilkS")
		)
		(fp_line
			(start 0.7874 -0.4064)
			(end 0.7874 0.4064)
			(stroke
				(width 0.1524)
				(type default)
			)
			(layer "F.SilkS")
		)
		(fp_line
			(start 0.7874 0.4064)
			(end -0.7874 0.4064)
			(stroke
				(width 0.1524)
				(type default)
			)
			(layer "F.SilkS")
		)
		(fp_line
			(start -0.67945 -0.305054)
			(end -0.12065 -0.305054)
			(stroke
				(width 0.1)
				(type default)
			)
			(layer "F.Fab")
		)
		(fp_line
			(start -0.67945 0.3048)
			(end -0.67945 -0.305054)
			(stroke
				(width 0.1)
				(type default)
			)
			(layer "F.Fab")
		)
		(fp_line
			(start -0.12065 -0.305054)
			(end -0.12065 -0.2794)
			(stroke
				(width 0.1)
				(type default)
			)
			(layer "F.Fab")
		)
		(fp_line
			(start -0.12065 -0.2794)
			(end 0.12065 -0.2794)
			(stroke
				(width 0.1)
				(type default)
			)
			(layer "F.Fab")
		)
		(fp_line
			(start -0.12065 0.2794)
			(end -0.12065 0.3048)
			(stroke
				(width 0.1)
				(type default)
			)
			(layer "F.Fab")
		)
		(fp_line
			(start -0.12065 0.3048)
			(end -0.67945 0.3048)
			(stroke
				(width 0.1)
				(type default)
			)
			(layer "F.Fab")
		)
		(fp_line
			(start 0.120396 0.2794)
			(end -0.12065 0.2794)
			(stroke
				(width 0.1)
				(type default)
			)
			(layer "F.Fab")
		)
		(fp_line
			(start 0.120396 0.3048)
			(end 0.120396 0.2794)
			(stroke
				(width 0.1)
				(type default)
			)
			(layer "F.Fab")
		)
		(fp_line
			(start 0.12065 -0.3048)
			(end 0.67945 -0.3048)
			(stroke
				(width 0.1)
				(type default)
			)
			(layer "F.Fab")
		)
		(fp_line
			(start 0.12065 -0.2794)
			(end 0.12065 -0.3048)
			(stroke
				(width 0.1)
				(type default)
			)
			(layer "F.Fab")
		)
		(fp_line
			(start 0.67945 -0.3048)
			(end 0.67945 0.3048)
			(stroke
				(width 0.1)
				(type default)
			)
			(layer "F.Fab")
		)
		(fp_line
			(start 0.67945 0.3048)
			(end 0.120396 0.3048)
			(stroke
				(width 0.1)
				(type default)
			)
			(layer "F.Fab")
		)
		(pad "1" smd circle
			(at -0.40005 0)
			(size 0 0)
			(layers "F.Cu" "F.Mask" "F.Paste")
			(net "SSD1_LED_R")
		)
		(pad "2" smd circle
			(at 0.40005 0)
			(size 0 0)
			(layers "F.Cu" "F.Mask" "F.Paste")
			(net "SSD1_LED")
		)
	)
	(footprint ""
		(layer "F.Cu")
		(at 448.18554 -25.1587 -90)
		(property "Reference" "R5750"
			(at 0 0 270)
			(layer "F.SilkS")
			(hide yes)
			(effects
				(font
					(size 1.27 1.27)
				)
			)
		)
		(property "Value" ""
			(at 0 0 270)
			(layer "F.Fab")
			(effects
				(font
					(size 1.27 1.27)
				)
			)
		)
		(duplicate_pad_numbers_are_jumpers no)
		(fp_line
			(start -0.7874 0.4064)
			(end -0.7874 -0.4064)
			(stroke
				(width 0.1524)
				(type default)
			)
			(layer "F.SilkS")
		)
		(fp_line
			(start 0.7874 0.4064)
			(end -0.7874 0.4064)
			(stroke
				(width 0.1524)
				(type default)
			)
			(layer "F.SilkS")
		)
		(fp_line
			(start -0.7874 -0.4064)
			(end 0.7874 -0.4064)
			(stroke
				(width 0.1524)
				(type default)
			)
			(layer "F.SilkS")
		)
		(fp_line
			(start 0.7874 -0.4064)
			(end 0.7874 0.4064)
			(stroke
				(width 0.1524)
				(type default)
			)
			(layer "F.SilkS")
		)
		(fp_line
			(start -0.67945 0.3048)
			(end -0.67945 -0.305054)
			(stroke
				(width 0.1)
				(type default)
			)
			(layer "F.Fab")
		)
		(fp_line
			(start -0.12065 0.3048)
			(end -0.67945 0.3048)
			(stroke
				(width 0.1)
				(type default)
			)
			(layer "F.Fab")
		)
		(fp_line
			(start 0.120396 0.3048)
			(end 0.120396 0.2794)
			(stroke
				(width 0.1)
				(type default)
			)
			(layer "F.Fab")
		)
		(fp_line
			(start 0.67945 0.3048)
			(end 0.120396 0.3048)
			(stroke
				(width 0.1)
				(type default)
			)
			(layer "F.Fab")
		)
		(fp_line
			(start -0.12065 0.2794)
			(end -0.12065 0.3048)
			(stroke
				(width 0.1)
				(type default)
			)
			(layer "F.Fab")
		)
		(fp_line
			(start 0.120396 0.2794)
			(end -0.12065 0.2794)
			(stroke
				(width 0.1)
				(type default)
			)
			(layer "F.Fab")
		)
		(fp_line
			(start -0.12065 -0.2794)
			(end 0.12065 -0.2794)
			(stroke
				(width 0.1)
				(type default)
			)
			(layer "F.Fab")
		)
		(fp_line
			(start 0.12065 -0.2794)
			(end 0.12065 -0.3048)
			(stroke
				(width 0.1)
				(type default)
			)
			(layer "F.Fab")
		)
		(fp_line
			(start 0.12065 -0.3048)
			(end 0.67945 -0.3048)
			(stroke
				(width 0.1)
				(type default)
			)
			(layer "F.Fab")
		)
		(fp_line
			(start 0.67945 -0.3048)
			(end 0.67945 0.3048)
			(stroke
				(width 0.1)
				(type default)
			)
			(layer "F.Fab")
		)
		(fp_line
			(start -0.67945 -0.305054)
			(end -0.12065 -0.305054)
			(stroke
				(width 0.1)
				(type default)
			)
			(layer "F.Fab")
		)
		(fp_line
			(start -0.12065 -0.305054)
			(end -0.12065 -0.2794)
			(stroke
				(width 0.1)
				(type default)
			)
			(layer "F.Fab")
		)
		(pad "1" smd circle
			(at -0.40005 0 270)
			(size 0 0)
			(layers "F.Cu" "F.Mask" "F.Paste")
			(net "SSD15_LED_ISO_N")
		)
		(pad "2" smd circle
			(at 0.40005 0 270)
			(size 0 0)
			(layers "F.Cu" "F.Mask" "F.Paste")
			(net "SSD15_LED_ISO_R_N")
		)
	)
	(footprint ""
		(layer "F.Cu")
		(at 232.988866 -439.16346 180)
		(property "Reference" "X73"
			(at -0.1778 -1.92913 180)
			(unlocked yes)
			(layer "F.SilkS")
			(effects
				(font
					(size 0.7874 0.5842)
					(thickness 0.1524)
				)
				(justify left)
			)
		)
		(property "Value" ""
			(at 0 0 180)
			(layer "F.Fab")
			(effects
				(font
					(size 1.27 1.27)
				)
			)
		)
		(property "Device Type" "TP_TDR_4P_FTS_MPKT4_H025P0200_IO_TP15_TP_TDR_4P_DIP"
			(at 1.30175 1.27 270)
			(unlocked yes)
			(layer "F.Fab")
			(hide yes)
			(effects
				(font
					(size 0.635 0.4064)
					(thickness 0.1524)
				)
			)
		)
		(property "User Part Number" "TP15"
			(at 1.30175 1.27 270)
			(unlocked yes)
			(layer "Cmts.User")
			(hide yes)
			(effects
				(font
					(size 0.635 0.4064)
					(thickness 0.1524)
				)
			)
		)
		(duplicate_pad_numbers_are_jumpers no)
		(fp_line
			(start 2.54 3.81)
			(end 2.54 3.6703)
			(stroke
				(width 0.1524)
				(type default)
			)
			(layer "F.SilkS")
		)
		(fp_line
			(start 2.54 1.4097)
			(end 2.54 1.1303)
			(stroke
				(width 0.1524)
				(type default)
			)
			(layer "F.SilkS")
		)
		(fp_line
			(start 2.54 -1.1303)
			(end 2.54 -1.27)
			(stroke
				(width 0.1524)
				(type default)
			)
			(layer "F.SilkS")
		)
		(fp_line
			(start 2.54 -1.27)
			(end 0 -1.27)
			(stroke
				(width 0.1524)
				(type default)
			)
			(layer "F.SilkS")
		)
		(fp_line
			(start 0 3.81)
			(end 2.54 3.81)
			(stroke
				(width 0.1524)
				(type default)
			)
			(layer "F.SilkS")
		)
		(fp_line
			(start 0 3.175)
			(end 0 3.81)
			(stroke
				(width 0.1524)
				(type default)
			)
			(layer "F.SilkS")
		)
		(fp_line
			(start 0 0.635)
			(end 0 1.905)
			(stroke
				(width 0.1524)
				(type default)
			)
			(layer "F.SilkS")
		)
		(fp_line
			(start 0 -1.27)
			(end 0 -0.635)
			(stroke
				(width 0.1524)
				(type default)
			)
			(layer "F.SilkS")
		)
		(fp_poly
			(pts
				(xy -0.761746 0) (xy -2.285746 -0.762) (xy -2.285746 0.762)
			)
			(stroke
				(width 0)
				(type default)
			)
			(fill yes)
			(layer "F.SilkS")
		)
		(fp_line
			(start 2.54 3.81)
			(end 2.54 -1.27)
			(stroke
				(width 0.1)
				(type default)
			)
			(layer "F.Fab")
		)
		(fp_line
			(start 2.54 -1.27)
			(end 0 -1.27)
			(stroke
				(width 0.1)
				(type default)
			)
			(layer "F.Fab")
		)
		(fp_line
			(start 0 3.81)
			(end 2.54 3.81)
			(stroke
				(width 0.1)
				(type default)
			)
			(layer "F.Fab")
		)
		(fp_line
			(start 0 -1.27)
			(end 0 3.81)
			(stroke
				(width 0.1)
				(type default)
			)
			(layer "F.Fab")
		)
		(fp_poly
			(pts
				(xy -0.761746 0) (xy -2.285746 -0.762) (xy -2.285746 0.762)
			)
			(stroke
				(width 0)
				(type default)
			)
			(fill yes)
			(layer "F.Fab")
		)
		(pad "1" thru_hole circle
			(at 0 0 180)
			(size 1.0033 1.0033)
			(drill 0.249936)
			(layers "*.Cu" "*.Mask")
			(remove_unused_layers no)
			(net "TDR_DIFF_100_IN3_DIN")
			(clearance 0.10795)
			(thermal_gap 0.10795)
			(padstack
				(mode front_inner_back)
				(layer "Inner"
					(shape circle)
					(size 0.8001 0.8001)
					(clearance 0.1524)
				)
				(layer "B.Cu"
					(shape circle)
					(size 1.0033 1.0033)
					(clearance 0.10795)
				)
			)
		)
		(pad "2" thru_hole circle
			(at 2.54 0 180)
			(size 1.9939 1.9939)
			(drill 0.249936)
			(layers "*.Cu" "*.Mask")
			(remove_unused_layers no)
			(net "COUPON_GND1")
			(clearance 0.10795)
			(thermal_gap 0.10795)
			(padstack
				(mode front_inner_back)
				(layer "Inner"
					(shape circle)
					(size 0.8001 0.8001)
					(clearance 0.1524)
				)
				(layer "B.Cu"
					(shape circle)
					(size 1.9939 1.9939)
					(clearance 0.10795)
				)
			)
		)
		(pad "3" thru_hole circle
			(at 2.54 2.54 180)
			(size 1.9939 1.9939)
			(drill 0.249936)
			(layers "*.Cu" "*.Mask")
			(remove_unused_layers no)
			(net "COUPON_GND1")
			(clearance 0.10795)
			(thermal_gap 0.10795)
			(padstack
				(mode front_inner_back)
				(layer "Inner"
					(shape circle)
					(size 0.8001 0.8001)
					(clearance 0.1524)
				)
				(layer "B.Cu"
					(shape circle)
					(size 1.9939 1.9939)
					(clearance 0.10795)
				)
			)
		)
		(pad "4" thru_hole circle
			(at 0 2.54 180)
			(size 1.0033 1.0033)
			(drill 0.249936)
			(layers "*.Cu" "*.Mask")
			(remove_unused_layers no)
			(net "TDR_DIFF_100_IN3_DIP")
			(clearance 0.10795)
			(thermal_gap 0.10795)
			(padstack
				(mode front_inner_back)
				(layer "Inner"
					(shape circle)
					(size 0.8001 0.8001)
					(clearance 0.1524)
				)
				(layer "B.Cu"
					(shape circle)
					(size 1.0033 1.0033)
					(clearance 0.10795)
				)
			)
		)
	)
	(footprint ""
		(layer "F.Cu")
		(at 186.700668 -187.945776 180)
		(property "Reference" "U52"
			(at -1.014984 -2.289556 0)
			(unlocked yes)
			(layer "F.SilkS")
			(effects
				(font
					(size 0.7874 0.5842)
					(thickness 0.1524)
				)
			)
		)
		(property "Value" ""
			(at 0 0 180)
			(layer "F.Fab")
			(effects
				(font
					(size 1.27 1.27)
				)
			)
		)
		(duplicate_pad_numbers_are_jumpers no)
		(fp_line
			(start 2.036064 1.525016)
			(end -2.038096 1.525016)
			(stroke
				(width 0.1524)
				(type default)
			)
			(layer "F.SilkS")
		)
		(fp_line
			(start 2.036064 -1.525016)
			(end 2.036064 1.525016)
			(stroke
				(width 0.1524)
				(type default)
			)
			(layer "F.SilkS")
		)
		(fp_line
			(start 0 -0.6604)
			(end 0.4572 -1.4986)
			(stroke
				(width 0.1524)
				(type default)
			)
			(layer "F.SilkS")
		)
		(fp_line
			(start -0.508 -1.524)
			(end 0 -0.6604)
			(stroke
				(width 0.1524)
				(type default)
			)
			(layer "F.SilkS")
		)
		(fp_line
			(start -2.038096 1.525016)
			(end -2.038096 -1.525016)
			(stroke
				(width 0.1524)
				(type default)
			)
			(layer "F.SilkS")
		)
		(fp_line
			(start -2.038096 -1.525016)
			(end 2.036064 -1.525016)
			(stroke
				(width 0.1524)
				(type default)
			)
			(layer "F.SilkS")
		)
		(fp_poly
			(pts
				(xy -2.71272 -0.592328) (xy -2.71272 -1.217168) (xy -2.159 -0.889)
			)
			(stroke
				(width 0)
				(type default)
			)
			(fill yes)
			(layer "F.SilkS")
		)
		(fp_line
			(start 0.87503 1.525016)
			(end -0.87503 1.525016)
			(stroke
				(width 0.1)
				(type default)
			)
			(layer "F.Fab")
		)
		(fp_line
			(start 0.87503 -1.525016)
			(end 0.87503 1.525016)
			(stroke
				(width 0.1)
				(type default)
			)
			(layer "F.Fab")
		)
		(fp_line
			(start -0.87503 1.525016)
			(end -0.87503 -1.525016)
			(stroke
				(width 0.1)
				(type default)
			)
			(layer "F.Fab")
		)
		(fp_line
			(start -0.87503 -1.525016)
			(end 0.87503 -1.525016)
			(stroke
				(width 0.1)
				(type default)
			)
			(layer "F.Fab")
		)
		(fp_poly
			(pts
				(xy -2.71272 -0.592328) (xy -2.71272 -1.217168) (xy -2.159 -0.889)
			)
			(stroke
				(width 0)
				(type default)
			)
			(fill yes)
			(layer "F.Fab")
		)
		(pad "1" smd rect
			(at -1.35001 -0.94996 90)
			(size 0.6096 1.0668)
			(layers "F.Cu" "F.Mask" "F.Paste")
			(net "SEL_FLASH_PEX0_BUF_R")
		)
		(pad "2" smd rect
			(at -1.35001 0 90)
			(size 0.6096 1.0668)
			(layers "F.Cu" "F.Mask" "F.Paste")
			(net "SEL_FLASH_PEX1_BUF_R")
		)
		(pad "3" smd rect
			(at -1.35001 0.94996 90)
			(size 0.6096 1.0668)
			(layers "F.Cu" "F.Mask" "F.Paste")
			(net "GND")
		)
		(pad "4" smd rect
			(at 1.35001 0.94996 90)
			(size 0.6096 1.0668)
			(layers "F.Cu" "F.Mask" "F.Paste")
			(net "SPI_BIC1_LS01_EN")
		)
		(pad "5" smd rect
			(at 1.35001 -0.94996 90)
			(size 0.6096 1.0668)
			(layers "F.Cu" "F.Mask" "F.Paste")
			(net "P3V3_AUX")
		)
	)
	(footprint ""
		(layer "F.Cu")
		(at 91.63431 -310.478932 -45)
		(property "Reference" "R3943"
			(at 0 0 315)
			(layer "F.SilkS")
			(hide yes)
			(effects
				(font
					(size 1.27 1.27)
				)
			)
		)
		(property "Value" ""
			(at 0 0 315)
			(layer "F.Fab")
			(effects
				(font
					(size 1.27 1.27)
				)
			)
		)
		(duplicate_pad_numbers_are_jumpers no)
		(fp_line
			(start -0.787389 0.406267)
			(end -0.787389 -0.406267)
			(stroke
				(width 0.1524)
				(type default)
			)
			(layer "F.SilkS")
		)
		(fp_line
			(start -0.787389 -0.406267)
			(end 0.787389 -0.406267)
			(stroke
				(width 0.1524)
				(type default)
			)
			(layer "F.SilkS")
		)
		(fp_line
			(start 0.787389 0.406267)
			(end -0.787389 0.406267)
			(stroke
				(width 0.1524)
				(type default)
			)
			(layer "F.SilkS")
		)
		(fp_line
			(start 0.787389 -0.406267)
			(end 0.787389 0.406267)
			(stroke
				(width 0.1524)
				(type default)
			)
			(layer "F.SilkS")
		)
		(fp_line
			(start -0.679446 0.30479)
			(end -0.679446 -0.305149)
			(stroke
				(width 0.1)
				(type default)
			)
			(layer "F.Fab")
		)
		(fp_line
			(start -0.120515 0.30479)
			(end -0.679446 0.30479)
			(stroke
				(width 0.1)
				(type default)
			)
			(layer "F.Fab")
		)
		(fp_line
			(start -0.120695 0.279466)
			(end -0.120515 0.30479)
			(stroke
				(width 0.1)
				(type default)
			)
			(layer "F.Fab")
		)
		(fp_line
			(start -0.679446 -0.305149)
			(end -0.120695 -0.304969)
			(stroke
				(width 0.1)
				(type default)
			)
			(layer "F.Fab")
		)
		(fp_line
			(start 0.120515 0.30479)
			(end 0.120335 0.279466)
			(stroke
				(width 0.1)
				(type default)
			)
			(layer "F.Fab")
		)
		(fp_line
			(start 0.120335 0.279466)
			(end -0.120695 0.279466)
			(stroke
				(width 0.1)
				(type default)
			)
			(layer "F.Fab")
		)
		(fp_line
			(start -0.120695 -0.279466)
			(end 0.120695 -0.279466)
			(stroke
				(width 0.1)
				(type default)
			)
			(layer "F.Fab")
		)
		(fp_line
			(start -0.120695 -0.304969)
			(end -0.120695 -0.279466)
			(stroke
				(width 0.1)
				(type default)
			)
			(layer "F.Fab")
		)
		(fp_line
			(start 0.679446 0.30479)
			(end 0.120515 0.30479)
			(stroke
				(width 0.1)
				(type default)
			)
			(layer "F.Fab")
		)
		(fp_line
			(start 0.120695 -0.279466)
			(end 0.120515 -0.30479)
			(stroke
				(width 0.1)
				(type default)
			)
			(layer "F.Fab")
		)
		(fp_line
			(start 0.120515 -0.30479)
			(end 0.679446 -0.30479)
			(stroke
				(width 0.1)
				(type default)
			)
			(layer "F.Fab")
		)
		(fp_line
			(start 0.679446 -0.30479)
			(end 0.679446 0.30479)
			(stroke
				(width 0.1)
				(type default)
			)
			(layer "F.Fab")
		)
		(pad "1" smd circle
			(at -0.40005 0 315)
			(size 0 0)
			(layers "F.Cu" "F.Mask" "F.Paste")
			(net "PU_PEX0_SIO_BLINK")
		)
		(pad "2" smd circle
			(at 0.40005 0 315)
			(size 0 0)
			(layers "F.Cu" "F.Mask" "F.Paste")
			(net "P1V8_PEX")
		)
	)
	(footprint ""
		(layer "F.Cu")
		(at 57.294018 -35.264852)
		(property "Reference" "R5663"
			(at 0 0 0)
			(layer "F.SilkS")
			(hide yes)
			(effects
				(font
					(size 1.27 1.27)
				)
			)
		)
		(property "Value" ""
			(at 0 0 0)
			(layer "F.Fab")
			(effects
				(font
					(size 1.27 1.27)
				)
			)
		)
		(duplicate_pad_numbers_are_jumpers no)
		(fp_line
			(start -0.7874 -0.4064)
			(end 0.7874 -0.4064)
			(stroke
				(width 0.1524)
				(type default)
			)
			(layer "F.SilkS")
		)
		(fp_line
			(start -0.7874 0.4064)
			(end -0.7874 -0.4064)
			(stroke
				(width 0.1524)
				(type default)
			)
			(layer "F.SilkS")
		)
		(fp_line
			(start 0.7874 -0.4064)
			(end 0.7874 0.4064)
			(stroke
				(width 0.1524)
				(type default)
			)
			(layer "F.SilkS")
		)
		(fp_line
			(start 0.7874 0.4064)
			(end -0.7874 0.4064)
			(stroke
				(width 0.1524)
				(type default)
			)
			(layer "F.SilkS")
		)
		(fp_line
			(start -0.67945 -0.305054)
			(end -0.12065 -0.305054)
			(stroke
				(width 0.1)
				(type default)
			)
			(layer "F.Fab")
		)
		(fp_line
			(start -0.67945 0.3048)
			(end -0.67945 -0.305054)
			(stroke
				(width 0.1)
				(type default)
			)
			(layer "F.Fab")
		)
		(fp_line
			(start -0.12065 -0.305054)
			(end -0.12065 -0.2794)
			(stroke
				(width 0.1)
				(type default)
			)
			(layer "F.Fab")
		)
		(fp_line
			(start -0.12065 -0.2794)
			(end 0.12065 -0.2794)
			(stroke
				(width 0.1)
				(type default)
			)
			(layer "F.Fab")
		)
		(fp_line
			(start -0.12065 0.2794)
			(end -0.12065 0.3048)
			(stroke
				(width 0.1)
				(type default)
			)
			(layer "F.Fab")
		)
		(fp_line
			(start -0.12065 0.3048)
			(end -0.67945 0.3048)
			(stroke
				(width 0.1)
				(type default)
			)
			(layer "F.Fab")
		)
		(fp_line
			(start 0.120396 0.2794)
			(end -0.12065 0.2794)
			(stroke
				(width 0.1)
				(type default)
			)
			(layer "F.Fab")
		)
		(fp_line
			(start 0.120396 0.3048)
			(end 0.120396 0.2794)
			(stroke
				(width 0.1)
				(type default)
			)
			(layer "F.Fab")
		)
		(fp_line
			(start 0.12065 -0.3048)
			(end 0.67945 -0.3048)
			(stroke
				(width 0.1)
				(type default)
			)
			(layer "F.Fab")
		)
		(fp_line
			(start 0.12065 -0.2794)
			(end 0.12065 -0.3048)
			(stroke
				(width 0.1)
				(type default)
			)
			(layer "F.Fab")
		)
		(fp_line
			(start 0.67945 -0.3048)
			(end 0.67945 0.3048)
			(stroke
				(width 0.1)
				(type default)
			)
			(layer "F.Fab")
		)
		(fp_line
			(start 0.67945 0.3048)
			(end 0.120396 0.3048)
			(stroke
				(width 0.1)
				(type default)
			)
			(layer "F.Fab")
		)
		(pad "1" smd circle
			(at -0.40005 0)
			(size 0 0)
			(layers "F.Cu" "F.Mask" "F.Paste")
			(net "RST_SMB_SSD2_ISO_N")
		)
		(pad "2" smd circle
			(at 0.40005 0)
			(size 0 0)
			(layers "F.Cu" "F.Mask" "F.Paste")
			(net "GND")
		)
	)
	(footprint ""
		(layer "F.Cu")
		(at 149.387814 -298.020232)
		(property "Reference" "C3195"
			(at 0 0 0)
			(layer "F.SilkS")
			(hide yes)
			(effects
				(font
					(size 1.27 1.27)
				)
			)
		)
		(property "Value" ""
			(at 0 0 0)
			(layer "F.Fab")
			(effects
				(font
					(size 1.27 1.27)
				)
			)
		)
		(duplicate_pad_numbers_are_jumpers no)
		(fp_line
			(start -1.2954 -0.5842)
			(end 1.2954 -0.5842)
			(stroke
				(width 0.1524)
				(type default)
			)
			(layer "F.SilkS")
		)
		(fp_line
			(start -1.2954 0.5842)
			(end -1.2954 -0.5842)
			(stroke
				(width 0.1524)
				(type default)
			)
			(layer "F.SilkS")
		)
		(fp_line
			(start 1.2954 -0.5842)
			(end 1.2954 0.5842)
			(stroke
				(width 0.1524)
				(type default)
			)
			(layer "F.SilkS")
		)
		(fp_line
			(start 1.2954 0.5842)
			(end -1.2954 0.5842)
			(stroke
				(width 0.1524)
				(type default)
			)
			(layer "F.SilkS")
		)
		(fp_line
			(start -1.1938 -0.4064)
			(end -0.8636 -0.4064)
			(stroke
				(width 0.1)
				(type default)
			)
			(layer "F.Fab")
		)
		(fp_line
			(start -1.1938 0.4064)
			(end -1.1938 -0.4064)
			(stroke
				(width 0.1)
				(type default)
			)
			(layer "F.Fab")
		)
		(fp_line
			(start -0.8636 -0.4572)
			(end 0.8636 -0.4572)
			(stroke
				(width 0.1)
				(type default)
			)
			(layer "F.Fab")
		)
		(fp_line
			(start -0.8636 -0.4064)
			(end -0.8636 -0.4572)
			(stroke
				(width 0.1)
				(type default)
			)
			(layer "F.Fab")
		)
		(fp_line
			(start -0.8636 0.4064)
			(end -1.1938 0.4064)
			(stroke
				(width 0.1)
				(type default)
			)
			(layer "F.Fab")
		)
		(fp_line
			(start -0.8636 0.4572)
			(end -0.8636 0.4064)
			(stroke
				(width 0.1)
				(type default)
			)
			(layer "F.Fab")
		)
		(fp_line
			(start 0.8636 -0.4572)
			(end 0.8636 -0.4064)
			(stroke
				(width 0.1)
				(type default)
			)
			(layer "F.Fab")
		)
		(fp_line
			(start 0.8636 -0.4064)
			(end 1.1938 -0.4064)
			(stroke
				(width 0.1)
				(type default)
			)
			(layer "F.Fab")
		)
		(fp_line
			(start 0.8636 0.4064)
			(end 0.8636 0.4572)
			(stroke
				(width 0.1)
				(type default)
			)
			(layer "F.Fab")
		)
		(fp_line
			(start 0.8636 0.4572)
			(end -0.8636 0.4572)
			(stroke
				(width 0.1)
				(type default)
			)
			(layer "F.Fab")
		)
		(fp_line
			(start 1.1938 -0.4064)
			(end 1.1938 0.4064)
			(stroke
				(width 0.1)
				(type default)
			)
			(layer "F.Fab")
		)
		(fp_line
			(start 1.1938 0.4064)
			(end 0.8636 0.4064)
			(stroke
				(width 0.1)
				(type default)
			)
			(layer "F.Fab")
		)
		(pad "1" smd rect
			(at -0.7366 0 270)
			(size 0.7112 0.8128)
			(layers "F.Cu" "F.Mask" "F.Paste")
			(net "PCEPLL0_VDDA18_PEX1")
		)
		(pad "2" smd rect
			(at 0.7366 0 270)
			(size 0.7112 0.8128)
			(layers "F.Cu" "F.Mask" "F.Paste")
			(net "GND")
		)
	)
	(footprint ""
		(layer "F.Cu")
		(at 338.074 -172.085 180)
		(property "Reference" "R4780"
			(at 0 0 180)
			(layer "F.SilkS")
			(hide yes)
			(effects
				(font
					(size 1.27 1.27)
				)
			)
		)
		(property "Value" ""
			(at 0 0 180)
			(layer "F.Fab")
			(effects
				(font
					(size 1.27 1.27)
				)
			)
		)
		(duplicate_pad_numbers_are_jumpers no)
		(fp_line
			(start 0.7874 0.4064)
			(end -0.7874 0.4064)
			(stroke
				(width 0.1524)
				(type default)
			)
			(layer "F.SilkS")
		)
		(fp_line
			(start 0.7874 -0.4064)
			(end 0.7874 0.4064)
			(stroke
				(width 0.1524)
				(type default)
			)
			(layer "F.SilkS")
		)
		(fp_line
			(start -0.7874 0.4064)
			(end -0.7874 -0.4064)
			(stroke
				(width 0.1524)
				(type default)
			)
			(layer "F.SilkS")
		)
		(fp_line
			(start -0.7874 -0.4064)
			(end 0.7874 -0.4064)
			(stroke
				(width 0.1524)
				(type default)
			)
			(layer "F.SilkS")
		)
		(fp_line
			(start 0.67945 0.3048)
			(end 0.120396 0.3048)
			(stroke
				(width 0.1)
				(type default)
			)
			(layer "F.Fab")
		)
		(fp_line
			(start 0.67945 -0.3048)
			(end 0.67945 0.3048)
			(stroke
				(width 0.1)
				(type default)
			)
			(layer "F.Fab")
		)
		(fp_line
			(start 0.12065 -0.2794)
			(end 0.12065 -0.3048)
			(stroke
				(width 0.1)
				(type default)
			)
			(layer "F.Fab")
		)
		(fp_line
			(start 0.12065 -0.3048)
			(end 0.67945 -0.3048)
			(stroke
				(width 0.1)
				(type default)
			)
			(layer "F.Fab")
		)
		(fp_line
			(start 0.120396 0.3048)
			(end 0.120396 0.2794)
			(stroke
				(width 0.1)
				(type default)
			)
			(layer "F.Fab")
		)
		(fp_line
			(start 0.120396 0.2794)
			(end -0.12065 0.2794)
			(stroke
				(width 0.1)
				(type default)
			)
			(layer "F.Fab")
		)
		(fp_line
			(start -0.12065 0.3048)
			(end -0.67945 0.3048)
			(stroke
				(width 0.1)
				(type default)
			)
			(layer "F.Fab")
		)
		(fp_line
			(start -0.12065 0.2794)
			(end -0.12065 0.3048)
			(stroke
				(width 0.1)
				(type default)
			)
			(layer "F.Fab")
		)
		(fp_line
			(start -0.12065 -0.2794)
			(end 0.12065 -0.2794)
			(stroke
				(width 0.1)
				(type default)
			)
			(layer "F.Fab")
		)
		(fp_line
			(start -0.12065 -0.305054)
			(end -0.12065 -0.2794)
			(stroke
				(width 0.1)
				(type default)
			)
			(layer "F.Fab")
		)
		(fp_line
			(start -0.67945 0.3048)
			(end -0.67945 -0.305054)
			(stroke
				(width 0.1)
				(type default)
			)
			(layer "F.Fab")
		)
		(fp_line
			(start -0.67945 -0.305054)
			(end -0.12065 -0.305054)
			(stroke
				(width 0.1)
				(type default)
			)
			(layer "F.Fab")
		)
		(pad "1" smd circle
			(at -0.40005 0 180)
			(size 0 0)
			(layers "F.Cu" "F.Mask" "F.Paste")
			(net "GND")
		)
		(pad "2" smd circle
			(at 0.40005 0 180)
			(size 0 0)
			(layers "F.Cu" "F.Mask" "F.Paste")
			(net "PCA9555_1_PEX2_A2")
		)
	)
	(footprint ""
		(layer "F.Cu")
		(at 268.445742 -258.463034)
		(property "Reference" "C3393"
			(at 0 0 0)
			(layer "F.SilkS")
			(hide yes)
			(effects
				(font
					(size 1.27 1.27)
				)
			)
		)
		(property "Value" ""
			(at 0 0 0)
			(layer "F.Fab")
			(effects
				(font
					(size 1.27 1.27)
				)
			)
		)
		(duplicate_pad_numbers_are_jumpers no)
		(fp_line
			(start -1.2954 -0.5842)
			(end 1.2954 -0.5842)
			(stroke
				(width 0.1524)
				(type default)
			)
			(layer "F.SilkS")
		)
		(fp_line
			(start -1.2954 0.5842)
			(end -1.2954 -0.5842)
			(stroke
				(width 0.1524)
				(type default)
			)
			(layer "F.SilkS")
		)
		(fp_line
			(start 1.2954 -0.5842)
			(end 1.2954 0.5842)
			(stroke
				(width 0.1524)
				(type default)
			)
			(layer "F.SilkS")
		)
		(fp_line
			(start 1.2954 0.5842)
			(end -1.2954 0.5842)
			(stroke
				(width 0.1524)
				(type default)
			)
			(layer "F.SilkS")
		)
		(fp_line
			(start -1.1938 -0.4064)
			(end -0.8636 -0.4064)
			(stroke
				(width 0.1)
				(type default)
			)
			(layer "F.Fab")
		)
		(fp_line
			(start -1.1938 0.4064)
			(end -1.1938 -0.4064)
			(stroke
				(width 0.1)
				(type default)
			)
			(layer "F.Fab")
		)
		(fp_line
			(start -0.8636 -0.4572)
			(end 0.8636 -0.4572)
			(stroke
				(width 0.1)
				(type default)
			)
			(layer "F.Fab")
		)
		(fp_line
			(start -0.8636 -0.4064)
			(end -0.8636 -0.4572)
			(stroke
				(width 0.1)
				(type default)
			)
			(layer "F.Fab")
		)
		(fp_line
			(start -0.8636 0.4064)
			(end -1.1938 0.4064)
			(stroke
				(width 0.1)
				(type default)
			)
			(layer "F.Fab")
		)
		(fp_line
			(start -0.8636 0.4572)
			(end -0.8636 0.4064)
			(stroke
				(width 0.1)
				(type default)
			)
			(layer "F.Fab")
		)
		(fp_line
			(start 0.8636 -0.4572)
			(end 0.8636 -0.4064)
			(stroke
				(width 0.1)
				(type default)
			)
			(layer "F.Fab")
		)
		(fp_line
			(start 0.8636 -0.4064)
			(end 1.1938 -0.4064)
			(stroke
				(width 0.1)
				(type default)
			)
			(layer "F.Fab")
		)
		(fp_line
			(start 0.8636 0.4064)
			(end 0.8636 0.4572)
			(stroke
				(width 0.1)
				(type default)
			)
			(layer "F.Fab")
		)
		(fp_line
			(start 0.8636 0.4572)
			(end -0.8636 0.4572)
			(stroke
				(width 0.1)
				(type default)
			)
			(layer "F.Fab")
		)
		(fp_line
			(start 1.1938 -0.4064)
			(end 1.1938 0.4064)
			(stroke
				(width 0.1)
				(type default)
			)
			(layer "F.Fab")
		)
		(fp_line
			(start 1.1938 0.4064)
			(end 0.8636 0.4064)
			(stroke
				(width 0.1)
				(type default)
			)
			(layer "F.Fab")
		)
		(pad "1" smd rect
			(at -0.7366 0 270)
			(size 0.7112 0.8128)
			(layers "F.Cu" "F.Mask" "F.Paste")
			(net "PCEPLL5_VDDA18_PEX2")
		)
		(pad "2" smd rect
			(at 0.7366 0 270)
			(size 0.7112 0.8128)
			(layers "F.Cu" "F.Mask" "F.Paste")
			(net "GND")
		)
	)
	(footprint ""
		(layer "F.Cu")
		(at 36.638484 -122.79884)
		(property "Reference" "C43"
			(at 0 0 0)
			(layer "F.SilkS")
			(hide yes)
			(effects
				(font
					(size 1.27 1.27)
				)
			)
		)
		(property "Value" ""
			(at 0 0 0)
			(layer "F.Fab")
			(effects
				(font
					(size 1.27 1.27)
				)
			)
		)
		(duplicate_pad_numbers_are_jumpers no)
		(fp_line
			(start -0.299974 -0.150114)
			(end 0.299974 -0.150114)
			(stroke
				(width 0.1)
				(type default)
			)
			(layer "F.Fab")
		)
		(fp_line
			(start -0.299974 0.150114)
			(end -0.299974 -0.150114)
			(stroke
				(width 0.1)
				(type default)
			)
			(layer "F.Fab")
		)
		(fp_line
			(start 0.299974 -0.150114)
			(end 0.299974 0.150114)
			(stroke
				(width 0.1)
				(type default)
			)
			(layer "F.Fab")
		)
		(fp_line
			(start 0.299974 0.150114)
			(end -0.299974 0.150114)
			(stroke
				(width 0.1)
				(type default)
			)
			(layer "F.Fab")
		)
		(pad "1" smd rect
			(at -0.2667 0)
			(size 0.3048 0.381)
			(layers "F.Cu" "F.Mask" "F.Paste")
			(net "P5E_PEX0_STN1_TX_DP<26>")
		)
		(pad "2" smd rect
			(at 0.2667 0)
			(size 0.3048 0.381)
			(layers "F.Cu" "F.Mask" "F.Paste")
			(net "P5E_PEX0_STN1_TX_C_DP<26>")
		)
	)
	(footprint ""
		(layer "F.Cu")
		(at 138.747246 -54.3941)
		(property "Reference" "PU31"
			(at -1.450594 3.01244 0)
			(unlocked yes)
			(layer "F.SilkS")
			(effects
				(font
					(size 0.7874 0.5842)
					(thickness 0.1524)
				)
				(justify left)
			)
		)
		(property "Value" ""
			(at 0 0 0)
			(layer "F.Fab")
			(effects
				(font
					(size 1.27 1.27)
				)
			)
		)
		(duplicate_pad_numbers_are_jumpers no)
		(fp_line
			(start -1.943608 -1.549908)
			(end 1.943608 -1.549908)
			(stroke
				(width 0.1524)
				(type default)
			)
			(layer "F.SilkS")
		)
		(fp_line
			(start -1.943608 1.549908)
			(end -1.943608 -1.549908)
			(stroke
				(width 0.1524)
				(type default)
			)
			(layer "F.SilkS")
		)
		(fp_line
			(start 1.943608 -1.549908)
			(end 1.943608 1.549908)
			(stroke
				(width 0.1524)
				(type default)
			)
			(layer "F.SilkS")
		)
		(fp_line
			(start 1.943608 1.549908)
			(end -1.943608 1.549908)
			(stroke
				(width 0.1524)
				(type default)
			)
			(layer "F.SilkS")
		)
		(fp_poly
			(pts
				(xy -2.019808 -1.549908) (xy -1.257808 -1.549908) (xy -1.257808 -1.880108) (xy -2.019808 -1.880108)
			)
			(stroke
				(width 0)
				(type default)
			)
			(fill yes)
			(layer "F.SilkS")
		)
		(fp_line
			(start -1.549908 -1.549908)
			(end 1.549908 -1.549908)
			(stroke
				(width 0.1)
				(type default)
			)
			(layer "F.Fab")
		)
		(fp_line
			(start -1.549908 1.549908)
			(end -1.549908 -1.549908)
			(stroke
				(width 0.1)
				(type default)
			)
			(layer "F.Fab")
		)
		(fp_line
			(start 1.549908 -1.549908)
			(end 1.549908 1.549908)
			(stroke
				(width 0.1)
				(type default)
			)
			(layer "F.Fab")
		)
		(fp_line
			(start 1.549908 1.549908)
			(end -1.549908 1.549908)
			(stroke
				(width 0.1)
				(type default)
			)
			(layer "F.Fab")
		)
		(fp_poly
			(pts
				(xy -2.019808 -1.549908) (xy -1.257808 -1.549908) (xy -1.257808 -1.880108) (xy -2.019808 -1.880108)
			)
			(stroke
				(width 0)
				(type default)
			)
			(fill yes)
			(layer "F.Fab")
		)
		(pad "1" smd rect
			(at -1.500124 -1.249934 270)
			(size 0.2794 0.6096)
			(layers "F.Cu" "F.Mask" "F.Paste")
			(net "P12V_SSD4_R")
		)
		(pad "2" smd rect
			(at -1.500124 -0.750062 270)
			(size 0.2794 0.6096)
			(layers "F.Cu" "F.Mask" "F.Paste")
			(net "P12V_SSD4_R")
		)
		(pad "3" smd rect
			(at -1.500124 -0.249936 270)
			(size 0.2794 0.6096)
			(layers "F.Cu" "F.Mask" "F.Paste")
			(net "P12V_SSD4_R")
		)
		(pad "4" smd rect
			(at -1.500124 0.249936 270)
			(size 0.2794 0.6096)
			(layers "F.Cu" "F.Mask" "F.Paste")
			(net "P12V_SSD4_R")
		)
		(pad "5" smd rect
			(at -1.500124 0.750062 270)
			(size 0.2794 0.6096)
			(layers "F.Cu" "F.Mask" "F.Paste")
			(net "P12V_SSD4_R")
		)
		(pad "6" smd rect
			(at -1.500124 1.249934 270)
			(size 0.2794 0.6096)
			(layers "F.Cu" "F.Mask" "F.Paste")
			(net "GND")
		)
		(pad "7" smd rect
			(at 1.500124 1.249934 270)
			(size 0.2794 0.6096)
			(layers "F.Cu" "F.Mask" "F.Paste")
			(net "P12V_SSD4_SS")
		)
		(pad "8" smd rect
			(at 1.500124 0.750062 270)
			(size 0.2794 0.6096)
			(layers "F.Cu" "F.Mask" "F.Paste")
			(net "PWRGD_P12V_SSD4")
		)
		(pad "9" smd rect
			(at 1.500124 0.249936 270)
			(size 0.2794 0.6096)
			(layers "F.Cu" "F.Mask" "F.Paste")
			(net "P12V_SSD4_OCP")
		)
		(pad "10" smd rect
			(at 1.500124 -0.249936 270)
			(size 0.2794 0.6096)
			(layers "F.Cu" "F.Mask" "F.Paste")
			(net "P5V_AUX")
		)
		(pad "11" smd rect
			(at 1.500124 -0.750062 270)
			(size 0.2794 0.6096)
			(layers "F.Cu" "F.Mask" "F.Paste")
			(net "SSD4_PWR_EN_R")
		)
		(pad "12" smd rect
			(at 1.500124 -1.249934 270)
			(size 0.2794 0.6096)
			(layers "F.Cu" "F.Mask" "F.Paste")
			(net "P12V_AUX")
		)
		(pad "13" smd rect
			(at 0 0)
			(size 1.9812 2.7178)
			(layers "F.Cu" "F.Mask" "F.Paste")
			(net "P12V_AUX")
		)
		(zone
			(layer "F.Cu")
			(hatch none 0.5)
			(connect_pads
				(clearance 0)
			)
			(min_thickness 0.25)
			(keepout
				(tracks not_allowed)
				(vias allowed)
				(pads allowed)
				(copperpour not_allowed)
				(footprints allowed)
			)
			(placement
				(enabled no)
				(sheetname "")
			)
			(fill
				(thermal_gap 0.5)
				(thermal_bridge_width 0.5)
				(island_removal_mode 0)
			)
			(polygon
				(pts
					(xy 139.890246 -55.9435) (xy 139.890246 -55.8165) (xy 139.890246 -52.8447) (xy 139.890246 -52.844192)
					(xy 137.604246 -52.844192) (xy 137.604246 -52.8447) (xy 137.604246 -52.9717) (xy 137.604246 -54.3941)
					(xy 137.705846 -54.3941) (xy 137.705846 -52.9717) (xy 139.788646 -52.9717) (xy 139.788646 -55.8165)
					(xy 137.705846 -55.8165) (xy 137.705846 -54.4195) (xy 137.604246 -54.4195) (xy 137.604246 -55.8165)
					(xy 137.604246 -55.9435) (xy 137.604246 -55.944008) (xy 139.890246 -55.944008)
				)
			)
		)
	)
	(footprint ""
		(layer "F.Cu")
		(at 438.164732 -350.098614 90)
		(property "Reference" "C799"
			(at 0 0 90)
			(layer "F.SilkS")
			(hide yes)
			(effects
				(font
					(size 1.27 1.27)
				)
			)
		)
		(property "Value" ""
			(at 0 0 90)
			(layer "F.Fab")
			(effects
				(font
					(size 1.27 1.27)
				)
			)
		)
		(duplicate_pad_numbers_are_jumpers no)
		(fp_line
			(start 0.299974 -0.150114)
			(end 0.299974 0.150114)
			(stroke
				(width 0.1)
				(type default)
			)
			(layer "F.Fab")
		)
		(fp_line
			(start -0.299974 -0.150114)
			(end 0.299974 -0.150114)
			(stroke
				(width 0.1)
				(type default)
			)
			(layer "F.Fab")
		)
		(fp_line
			(start 0.299974 0.150114)
			(end -0.299974 0.150114)
			(stroke
				(width 0.1)
				(type default)
			)
			(layer "F.Fab")
		)
		(fp_line
			(start -0.299974 0.150114)
			(end -0.299974 -0.150114)
			(stroke
				(width 0.1)
				(type default)
			)
			(layer "F.Fab")
		)
		(pad "1" smd rect
			(at -0.2667 0 90)
			(size 0.3048 0.381)
			(layers "F.Cu" "F.Mask" "F.Paste")
			(net "P5E_PEX3_STN7_TX_DN<125>")
		)
		(pad "2" smd rect
			(at 0.2667 0 90)
			(size 0.3048 0.381)
			(layers "F.Cu" "F.Mask" "F.Paste")
			(net "P5E_PEX3_STN7_TX_C_DN<125>")
		)
	)
	(footprint ""
		(layer "F.Cu")
		(at 259.130038 -297.205908 -90)
		(property "Reference" "C3401"
			(at 0 0 270)
			(layer "F.SilkS")
			(hide yes)
			(effects
				(font
					(size 1.27 1.27)
				)
			)
		)
		(property "Value" ""
			(at 0 0 270)
			(layer "F.Fab")
			(effects
				(font
					(size 1.27 1.27)
				)
			)
		)
		(duplicate_pad_numbers_are_jumpers no)
		(fp_line
			(start -1.2954 0.5842)
			(end -1.2954 -0.5842)
			(stroke
				(width 0.1524)
				(type default)
			)
			(layer "F.SilkS")
		)
		(fp_line
			(start 1.2954 0.5842)
			(end -1.2954 0.5842)
			(stroke
				(width 0.1524)
				(type default)
			)
			(layer "F.SilkS")
		)
		(fp_line
			(start -1.2954 -0.5842)
			(end 1.2954 -0.5842)
			(stroke
				(width 0.1524)
				(type default)
			)
			(layer "F.SilkS")
		)
		(fp_line
			(start 1.2954 -0.5842)
			(end 1.2954 0.5842)
			(stroke
				(width 0.1524)
				(type default)
			)
			(layer "F.SilkS")
		)
		(fp_line
			(start -0.8636 0.4572)
			(end -0.8636 0.4064)
			(stroke
				(width 0.1)
				(type default)
			)
			(layer "F.Fab")
		)
		(fp_line
			(start 0.8636 0.4572)
			(end -0.8636 0.4572)
			(stroke
				(width 0.1)
				(type default)
			)
			(layer "F.Fab")
		)
		(fp_line
			(start -1.1938 0.4064)
			(end -1.1938 -0.4064)
			(stroke
				(width 0.1)
				(type default)
			)
			(layer "F.Fab")
		)
		(fp_line
			(start -0.8636 0.4064)
			(end -1.1938 0.4064)
			(stroke
				(width 0.1)
				(type default)
			)
			(layer "F.Fab")
		)
		(fp_line
			(start 0.8636 0.4064)
			(end 0.8636 0.4572)
			(stroke
				(width 0.1)
				(type default)
			)
			(layer "F.Fab")
		)
		(fp_line
			(start 1.1938 0.4064)
			(end 0.8636 0.4064)
			(stroke
				(width 0.1)
				(type default)
			)
			(layer "F.Fab")
		)
		(fp_line
			(start -1.1938 -0.4064)
			(end -0.8636 -0.4064)
			(stroke
				(width 0.1)
				(type default)
			)
			(layer "F.Fab")
		)
		(fp_line
			(start -0.8636 -0.4064)
			(end -0.8636 -0.4572)
			(stroke
				(width 0.1)
				(type default)
			)
			(layer "F.Fab")
		)
		(fp_line
			(start 0.8636 -0.4064)
			(end 1.1938 -0.4064)
			(stroke
				(width 0.1)
				(type default)
			)
			(layer "F.Fab")
		)
		(fp_line
			(start 1.1938 -0.4064)
			(end 1.1938 0.4064)
			(stroke
				(width 0.1)
				(type default)
			)
			(layer "F.Fab")
		)
		(fp_line
			(start -0.8636 -0.4572)
			(end 0.8636 -0.4572)
			(stroke
				(width 0.1)
				(type default)
			)
			(layer "F.Fab")
		)
		(fp_line
			(start 0.8636 -0.4572)
			(end 0.8636 -0.4064)
			(stroke
				(width 0.1)
				(type default)
			)
			(layer "F.Fab")
		)
		(pad "1" smd rect
			(at -0.7366 0 180)
			(size 0.7112 0.8128)
			(layers "F.Cu" "F.Mask" "F.Paste")
			(net "P1V8_PLL0_PEX2")
		)
		(pad "2" smd rect
			(at 0.7366 0 180)
			(size 0.7112 0.8128)
			(layers "F.Cu" "F.Mask" "F.Paste")
			(net "GND")
		)
	)
	(footprint ""
		(layer "F.Cu")
		(at 456.396852 -280.224484 180)
		(property "Reference" "C631"
			(at 0 0 180)
			(layer "F.SilkS")
			(hide yes)
			(effects
				(font
					(size 1.27 1.27)
				)
			)
		)
		(property "Value" ""
			(at 0 0 180)
			(layer "F.Fab")
			(effects
				(font
					(size 1.27 1.27)
				)
			)
		)
		(duplicate_pad_numbers_are_jumpers no)
		(fp_line
			(start 0.7874 0.4064)
			(end -0.7874 0.4064)
			(stroke
				(width 0.1524)
				(type default)
			)
			(layer "F.SilkS")
		)
		(fp_line
			(start 0.7874 -0.4064)
			(end 0.7874 0.4064)
			(stroke
				(width 0.1524)
				(type default)
			)
			(layer "F.SilkS")
		)
		(fp_line
			(start -0.7874 0.4064)
			(end -0.7874 -0.4064)
			(stroke
				(width 0.1524)
				(type default)
			)
			(layer "F.SilkS")
		)
		(fp_line
			(start -0.7874 -0.4064)
			(end 0.7874 -0.4064)
			(stroke
				(width 0.1524)
				(type default)
			)
			(layer "F.SilkS")
		)
		(fp_line
			(start 0.67945 0.3048)
			(end 0.120396 0.3048)
			(stroke
				(width 0.1)
				(type default)
			)
			(layer "F.Fab")
		)
		(fp_line
			(start 0.67945 -0.3048)
			(end 0.67945 0.3048)
			(stroke
				(width 0.1)
				(type default)
			)
			(layer "F.Fab")
		)
		(fp_line
			(start 0.12065 -0.2794)
			(end 0.12065 -0.3048)
			(stroke
				(width 0.1)
				(type default)
			)
			(layer "F.Fab")
		)
		(fp_line
			(start 0.12065 -0.3048)
			(end 0.67945 -0.3048)
			(stroke
				(width 0.1)
				(type default)
			)
			(layer "F.Fab")
		)
		(fp_line
			(start 0.120396 0.3048)
			(end 0.120396 0.2794)
			(stroke
				(width 0.1)
				(type default)
			)
			(layer "F.Fab")
		)
		(fp_line
			(start 0.120396 0.2794)
			(end -0.12065 0.2794)
			(stroke
				(width 0.1)
				(type default)
			)
			(layer "F.Fab")
		)
		(fp_line
			(start -0.12065 0.3048)
			(end -0.67945 0.3048)
			(stroke
				(width 0.1)
				(type default)
			)
			(layer "F.Fab")
		)
		(fp_line
			(start -0.12065 0.2794)
			(end -0.12065 0.3048)
			(stroke
				(width 0.1)
				(type default)
			)
			(layer "F.Fab")
		)
		(fp_line
			(start -0.12065 -0.2794)
			(end 0.12065 -0.2794)
			(stroke
				(width 0.1)
				(type default)
			)
			(layer "F.Fab")
		)
		(fp_line
			(start -0.12065 -0.305054)
			(end -0.12065 -0.2794)
			(stroke
				(width 0.1)
				(type default)
			)
			(layer "F.Fab")
		)
		(fp_line
			(start -0.67945 0.3048)
			(end -0.67945 -0.305054)
			(stroke
				(width 0.1)
				(type default)
			)
			(layer "F.Fab")
		)
		(fp_line
			(start -0.67945 -0.305054)
			(end -0.12065 -0.305054)
			(stroke
				(width 0.1)
				(type default)
			)
			(layer "F.Fab")
		)
		(pad "1" smd circle
			(at -0.40005 0 180)
			(size 0 0)
			(layers "F.Cu" "F.Mask" "F.Paste")
			(net "P3V3_AUX")
		)
		(pad "2" smd circle
			(at 0.40005 0 180)
			(size 0 0)
			(layers "F.Cu" "F.Mask" "F.Paste")
			(net "GND")
		)
	)
	(footprint ""
		(layer "F.Cu")
		(at 175.0949 -99.750372 180)
		(property "Reference" "R181"
			(at 0 0 180)
			(layer "F.SilkS")
			(hide yes)
			(effects
				(font
					(size 1.27 1.27)
				)
			)
		)
		(property "Value" ""
			(at 0 0 180)
			(layer "F.Fab")
			(effects
				(font
					(size 1.27 1.27)
				)
			)
		)
		(duplicate_pad_numbers_are_jumpers no)
		(fp_line
			(start 0.7874 0.4064)
			(end -0.7874 0.4064)
			(stroke
				(width 0.1524)
				(type default)
			)
			(layer "F.SilkS")
		)
		(fp_line
			(start 0.7874 -0.4064)
			(end 0.7874 0.4064)
			(stroke
				(width 0.1524)
				(type default)
			)
			(layer "F.SilkS")
		)
		(fp_line
			(start -0.7874 0.4064)
			(end -0.7874 -0.4064)
			(stroke
				(width 0.1524)
				(type default)
			)
			(layer "F.SilkS")
		)
		(fp_line
			(start -0.7874 -0.4064)
			(end 0.7874 -0.4064)
			(stroke
				(width 0.1524)
				(type default)
			)
			(layer "F.SilkS")
		)
		(fp_line
			(start 0.67945 0.3048)
			(end 0.120396 0.3048)
			(stroke
				(width 0.1)
				(type default)
			)
			(layer "F.Fab")
		)
		(fp_line
			(start 0.67945 -0.3048)
			(end 0.67945 0.3048)
			(stroke
				(width 0.1)
				(type default)
			)
			(layer "F.Fab")
		)
		(fp_line
			(start 0.12065 -0.2794)
			(end 0.12065 -0.3048)
			(stroke
				(width 0.1)
				(type default)
			)
			(layer "F.Fab")
		)
		(fp_line
			(start 0.12065 -0.3048)
			(end 0.67945 -0.3048)
			(stroke
				(width 0.1)
				(type default)
			)
			(layer "F.Fab")
		)
		(fp_line
			(start 0.120396 0.3048)
			(end 0.120396 0.2794)
			(stroke
				(width 0.1)
				(type default)
			)
			(layer "F.Fab")
		)
		(fp_line
			(start 0.120396 0.2794)
			(end -0.12065 0.2794)
			(stroke
				(width 0.1)
				(type default)
			)
			(layer "F.Fab")
		)
		(fp_line
			(start -0.12065 0.3048)
			(end -0.67945 0.3048)
			(stroke
				(width 0.1)
				(type default)
			)
			(layer "F.Fab")
		)
		(fp_line
			(start -0.12065 0.2794)
			(end -0.12065 0.3048)
			(stroke
				(width 0.1)
				(type default)
			)
			(layer "F.Fab")
		)
		(fp_line
			(start -0.12065 -0.2794)
			(end 0.12065 -0.2794)
			(stroke
				(width 0.1)
				(type default)
			)
			(layer "F.Fab")
		)
		(fp_line
			(start -0.12065 -0.305054)
			(end -0.12065 -0.2794)
			(stroke
				(width 0.1)
				(type default)
			)
			(layer "F.Fab")
		)
		(fp_line
			(start -0.67945 0.3048)
			(end -0.67945 -0.305054)
			(stroke
				(width 0.1)
				(type default)
			)
			(layer "F.Fab")
		)
		(fp_line
			(start -0.67945 -0.305054)
			(end -0.12065 -0.305054)
			(stroke
				(width 0.1)
				(type default)
			)
			(layer "F.Fab")
		)
		(pad "1" smd circle
			(at -0.40005 0 180)
			(size 0 0)
			(layers "F.Cu" "F.Mask" "F.Paste")
			(net "NIC3_SLOT_ID1")
		)
		(pad "2" smd circle
			(at 0.40005 0 180)
			(size 0 0)
			(layers "F.Cu" "F.Mask" "F.Paste")
			(net "GND")
		)
	)
	(footprint ""
		(layer "F.Cu")
		(at 375.18594 -356.244906 90)
		(property "Reference" "C783"
			(at 0 0 90)
			(layer "F.SilkS")
			(hide yes)
			(effects
				(font
					(size 1.27 1.27)
				)
			)
		)
		(property "Value" ""
			(at 0 0 90)
			(layer "F.Fab")
			(effects
				(font
					(size 1.27 1.27)
				)
			)
		)
		(duplicate_pad_numbers_are_jumpers no)
		(fp_line
			(start 0.299974 -0.150114)
			(end 0.299974 0.150114)
			(stroke
				(width 0.1)
				(type default)
			)
			(layer "F.Fab")
		)
		(fp_line
			(start -0.299974 -0.150114)
			(end 0.299974 -0.150114)
			(stroke
				(width 0.1)
				(type default)
			)
			(layer "F.Fab")
		)
		(fp_line
			(start 0.299974 0.150114)
			(end -0.299974 0.150114)
			(stroke
				(width 0.1)
				(type default)
			)
			(layer "F.Fab")
		)
		(fp_line
			(start -0.299974 0.150114)
			(end -0.299974 -0.150114)
			(stroke
				(width 0.1)
				(type default)
			)
			(layer "F.Fab")
		)
		(pad "1" smd rect
			(at -0.2667 0 90)
			(size 0.3048 0.381)
			(layers "F.Cu" "F.Mask" "F.Paste")
			(net "P5E_PEX3_STN6_TX_DN<101>")
		)
		(pad "2" smd rect
			(at 0.2667 0 90)
			(size 0.3048 0.381)
			(layers "F.Cu" "F.Mask" "F.Paste")
			(net "P5E_PEX3_STN6_TX_C_DN<101>")
		)
	)
	(footprint ""
		(layer "F.Cu")
		(at 428.319438 -130.794506 180)
		(property "Reference" "C656"
			(at 0 0 180)
			(layer "F.SilkS")
			(hide yes)
			(effects
				(font
					(size 1.27 1.27)
				)
			)
		)
		(property "Value" ""
			(at 0 0 180)
			(layer "F.Fab")
			(effects
				(font
					(size 1.27 1.27)
				)
			)
		)
		(duplicate_pad_numbers_are_jumpers no)
		(fp_line
			(start 0.299974 0.150114)
			(end -0.299974 0.150114)
			(stroke
				(width 0.1)
				(type default)
			)
			(layer "F.Fab")
		)
		(fp_line
			(start 0.299974 -0.150114)
			(end 0.299974 0.150114)
			(stroke
				(width 0.1)
				(type default)
			)
			(layer "F.Fab")
		)
		(fp_line
			(start -0.299974 0.150114)
			(end -0.299974 -0.150114)
			(stroke
				(width 0.1)
				(type default)
			)
			(layer "F.Fab")
		)
		(fp_line
			(start -0.299974 -0.150114)
			(end 0.299974 -0.150114)
			(stroke
				(width 0.1)
				(type default)
			)
			(layer "F.Fab")
		)
		(pad "1" smd rect
			(at -0.2667 0 180)
			(size 0.3048 0.381)
			(layers "F.Cu" "F.Mask" "F.Paste")
			(net "P5E_PEX3_STN0_TX_DP<4>")
		)
		(pad "2" smd rect
			(at 0.2667 0 180)
			(size 0.3048 0.381)
			(layers "F.Cu" "F.Mask" "F.Paste")
			(net "P5E_PEX3_STN0_TX_C_DP<4>")
		)
	)
	(footprint ""
		(layer "F.Cu")
		(at 388.898384 -250.070874 -90)
		(property "Reference" "R1406"
			(at 0 0 270)
			(layer "F.SilkS")
			(hide yes)
			(effects
				(font
					(size 1.27 1.27)
				)
			)
		)
		(property "Value" ""
			(at 0 0 270)
			(layer "F.Fab")
			(effects
				(font
					(size 1.27 1.27)
				)
			)
		)
		(duplicate_pad_numbers_are_jumpers no)
		(fp_line
			(start -0.7874 0.4064)
			(end -0.7874 -0.4064)
			(stroke
				(width 0.1524)
				(type default)
			)
			(layer "F.SilkS")
		)
		(fp_line
			(start 0.7874 0.4064)
			(end -0.7874 0.4064)
			(stroke
				(width 0.1524)
				(type default)
			)
			(layer "F.SilkS")
		)
		(fp_line
			(start -0.7874 -0.4064)
			(end 0.7874 -0.4064)
			(stroke
				(width 0.1524)
				(type default)
			)
			(layer "F.SilkS")
		)
		(fp_line
			(start 0.7874 -0.4064)
			(end 0.7874 0.4064)
			(stroke
				(width 0.1524)
				(type default)
			)
			(layer "F.SilkS")
		)
		(fp_line
			(start -0.67945 0.3048)
			(end -0.67945 -0.305054)
			(stroke
				(width 0.1)
				(type default)
			)
			(layer "F.Fab")
		)
		(fp_line
			(start -0.12065 0.3048)
			(end -0.67945 0.3048)
			(stroke
				(width 0.1)
				(type default)
			)
			(layer "F.Fab")
		)
		(fp_line
			(start 0.120396 0.3048)
			(end 0.120396 0.2794)
			(stroke
				(width 0.1)
				(type default)
			)
			(layer "F.Fab")
		)
		(fp_line
			(start 0.67945 0.3048)
			(end 0.120396 0.3048)
			(stroke
				(width 0.1)
				(type default)
			)
			(layer "F.Fab")
		)
		(fp_line
			(start -0.12065 0.2794)
			(end -0.12065 0.3048)
			(stroke
				(width 0.1)
				(type default)
			)
			(layer "F.Fab")
		)
		(fp_line
			(start 0.120396 0.2794)
			(end -0.12065 0.2794)
			(stroke
				(width 0.1)
				(type default)
			)
			(layer "F.Fab")
		)
		(fp_line
			(start -0.12065 -0.2794)
			(end 0.12065 -0.2794)
			(stroke
				(width 0.1)
				(type default)
			)
			(layer "F.Fab")
		)
		(fp_line
			(start 0.12065 -0.2794)
			(end 0.12065 -0.3048)
			(stroke
				(width 0.1)
				(type default)
			)
			(layer "F.Fab")
		)
		(fp_line
			(start 0.12065 -0.3048)
			(end 0.67945 -0.3048)
			(stroke
				(width 0.1)
				(type default)
			)
			(layer "F.Fab")
		)
		(fp_line
			(start 0.67945 -0.3048)
			(end 0.67945 0.3048)
			(stroke
				(width 0.1)
				(type default)
			)
			(layer "F.Fab")
		)
		(fp_line
			(start -0.67945 -0.305054)
			(end -0.12065 -0.305054)
			(stroke
				(width 0.1)
				(type default)
			)
			(layer "F.Fab")
		)
		(fp_line
			(start -0.12065 -0.305054)
			(end -0.12065 -0.2794)
			(stroke
				(width 0.1)
				(type default)
			)
			(layer "F.Fab")
		)
		(pad "1" smd circle
			(at -0.40005 0 270)
			(size 0 0)
			(layers "F.Cu" "F.Mask" "F.Paste")
			(net "PEX3_MODE_SEL1")
		)
		(pad "2" smd circle
			(at 0.40005 0 270)
			(size 0 0)
			(layers "F.Cu" "F.Mask" "F.Paste")
			(net "P1V8_PEX")
		)
	)
	(footprint ""
		(layer "F.Cu")
		(at 98.674936 -56.977534 180)
		(property "Reference" "PC354"
			(at 0 0 180)
			(layer "F.SilkS")
			(hide yes)
			(effects
				(font
					(size 1.27 1.27)
				)
			)
		)
		(property "Value" ""
			(at 0 0 180)
			(layer "F.Fab")
			(effects
				(font
					(size 1.27 1.27)
				)
			)
		)
		(duplicate_pad_numbers_are_jumpers no)
		(fp_line
			(start 0.7874 0.4064)
			(end -0.7874 0.4064)
			(stroke
				(width 0.1524)
				(type default)
			)
			(layer "F.SilkS")
		)
		(fp_line
			(start 0.7874 -0.4064)
			(end 0.7874 0.4064)
			(stroke
				(width 0.1524)
				(type default)
			)
			(layer "F.SilkS")
		)
		(fp_line
			(start -0.7874 0.4064)
			(end -0.7874 -0.4064)
			(stroke
				(width 0.1524)
				(type default)
			)
			(layer "F.SilkS")
		)
		(fp_line
			(start -0.7874 -0.4064)
			(end 0.7874 -0.4064)
			(stroke
				(width 0.1524)
				(type default)
			)
			(layer "F.SilkS")
		)
		(fp_line
			(start 0.67945 0.3048)
			(end 0.120396 0.3048)
			(stroke
				(width 0.1)
				(type default)
			)
			(layer "F.Fab")
		)
		(fp_line
			(start 0.67945 -0.3048)
			(end 0.67945 0.3048)
			(stroke
				(width 0.1)
				(type default)
			)
			(layer "F.Fab")
		)
		(fp_line
			(start 0.12065 -0.2794)
			(end 0.12065 -0.3048)
			(stroke
				(width 0.1)
				(type default)
			)
			(layer "F.Fab")
		)
		(fp_line
			(start 0.12065 -0.3048)
			(end 0.67945 -0.3048)
			(stroke
				(width 0.1)
				(type default)
			)
			(layer "F.Fab")
		)
		(fp_line
			(start 0.120396 0.3048)
			(end 0.120396 0.2794)
			(stroke
				(width 0.1)
				(type default)
			)
			(layer "F.Fab")
		)
		(fp_line
			(start 0.120396 0.2794)
			(end -0.12065 0.2794)
			(stroke
				(width 0.1)
				(type default)
			)
			(layer "F.Fab")
		)
		(fp_line
			(start -0.12065 0.3048)
			(end -0.67945 0.3048)
			(stroke
				(width 0.1)
				(type default)
			)
			(layer "F.Fab")
		)
		(fp_line
			(start -0.12065 0.2794)
			(end -0.12065 0.3048)
			(stroke
				(width 0.1)
				(type default)
			)
			(layer "F.Fab")
		)
		(fp_line
			(start -0.12065 -0.2794)
			(end 0.12065 -0.2794)
			(stroke
				(width 0.1)
				(type default)
			)
			(layer "F.Fab")
		)
		(fp_line
			(start -0.12065 -0.305054)
			(end -0.12065 -0.2794)
			(stroke
				(width 0.1)
				(type default)
			)
			(layer "F.Fab")
		)
		(fp_line
			(start -0.67945 0.3048)
			(end -0.67945 -0.305054)
			(stroke
				(width 0.1)
				(type default)
			)
			(layer "F.Fab")
		)
		(fp_line
			(start -0.67945 -0.305054)
			(end -0.12065 -0.305054)
			(stroke
				(width 0.1)
				(type default)
			)
			(layer "F.Fab")
		)
		(pad "1" smd circle
			(at -0.40005 0 180)
			(size 0 0)
			(layers "F.Cu" "F.Mask" "F.Paste")
			(net "P12V_AUX")
		)
		(pad "2" smd circle
			(at 0.40005 0 180)
			(size 0 0)
			(layers "F.Cu" "F.Mask" "F.Paste")
			(net "GND")
		)
	)
	(footprint ""
		(layer "F.Cu")
		(at 143.85163 -260.840982)
		(property "Reference" "R4577"
			(at 0 0 0)
			(layer "F.SilkS")
			(hide yes)
			(effects
				(font
					(size 1.27 1.27)
				)
			)
		)
		(property "Value" ""
			(at 0 0 0)
			(layer "F.Fab")
			(effects
				(font
					(size 1.27 1.27)
				)
			)
		)
		(duplicate_pad_numbers_are_jumpers no)
		(fp_line
			(start -0.7874 -0.4064)
			(end 0.7874 -0.4064)
			(stroke
				(width 0.1524)
				(type default)
			)
			(layer "F.SilkS")
		)
		(fp_line
			(start -0.7874 0.4064)
			(end -0.7874 -0.4064)
			(stroke
				(width 0.1524)
				(type default)
			)
			(layer "F.SilkS")
		)
		(fp_line
			(start 0.7874 -0.4064)
			(end 0.7874 0.4064)
			(stroke
				(width 0.1524)
				(type default)
			)
			(layer "F.SilkS")
		)
		(fp_line
			(start 0.7874 0.4064)
			(end -0.7874 0.4064)
			(stroke
				(width 0.1524)
				(type default)
			)
			(layer "F.SilkS")
		)
		(fp_line
			(start -0.67945 -0.305054)
			(end -0.12065 -0.305054)
			(stroke
				(width 0.1)
				(type default)
			)
			(layer "F.Fab")
		)
		(fp_line
			(start -0.67945 0.3048)
			(end -0.67945 -0.305054)
			(stroke
				(width 0.1)
				(type default)
			)
			(layer "F.Fab")
		)
		(fp_line
			(start -0.12065 -0.305054)
			(end -0.12065 -0.2794)
			(stroke
				(width 0.1)
				(type default)
			)
			(layer "F.Fab")
		)
		(fp_line
			(start -0.12065 -0.2794)
			(end 0.12065 -0.2794)
			(stroke
				(width 0.1)
				(type default)
			)
			(layer "F.Fab")
		)
		(fp_line
			(start -0.12065 0.2794)
			(end -0.12065 0.3048)
			(stroke
				(width 0.1)
				(type default)
			)
			(layer "F.Fab")
		)
		(fp_line
			(start -0.12065 0.3048)
			(end -0.67945 0.3048)
			(stroke
				(width 0.1)
				(type default)
			)
			(layer "F.Fab")
		)
		(fp_line
			(start 0.120396 0.2794)
			(end -0.12065 0.2794)
			(stroke
				(width 0.1)
				(type default)
			)
			(layer "F.Fab")
		)
		(fp_line
			(start 0.120396 0.3048)
			(end 0.120396 0.2794)
			(stroke
				(width 0.1)
				(type default)
			)
			(layer "F.Fab")
		)
		(fp_line
			(start 0.12065 -0.3048)
			(end 0.67945 -0.3048)
			(stroke
				(width 0.1)
				(type default)
			)
			(layer "F.Fab")
		)
		(fp_line
			(start 0.12065 -0.2794)
			(end 0.12065 -0.3048)
			(stroke
				(width 0.1)
				(type default)
			)
			(layer "F.Fab")
		)
		(fp_line
			(start 0.67945 -0.3048)
			(end 0.67945 0.3048)
			(stroke
				(width 0.1)
				(type default)
			)
			(layer "F.Fab")
		)
		(fp_line
			(start 0.67945 0.3048)
			(end 0.120396 0.3048)
			(stroke
				(width 0.1)
				(type default)
			)
			(layer "F.Fab")
		)
		(pad "1" smd circle
			(at -0.40005 0)
			(size 0 0)
			(layers "F.Cu" "F.Mask" "F.Paste")
			(net "P1V8_VDDA_PEX1")
		)
		(pad "2" smd circle
			(at 0.40005 0)
			(size 0 0)
			(layers "F.Cu" "F.Mask" "F.Paste")
			(net "P1V8_VDDA_PEX1_R")
		)
	)
	(footprint ""
		(layer "F.Cu")
		(at 328.699368 -112.903508 90)
		(property "Reference" "PC804"
			(at 0 0 90)
			(layer "F.SilkS")
			(hide yes)
			(effects
				(font
					(size 1.27 1.27)
				)
			)
		)
		(property "Value" ""
			(at 0 0 90)
			(layer "F.Fab")
			(effects
				(font
					(size 1.27 1.27)
				)
			)
		)
		(duplicate_pad_numbers_are_jumpers no)
		(fp_line
			(start 1.524 -0.762)
			(end 1.524 0.762)
			(stroke
				(width 0.1524)
				(type default)
			)
			(layer "F.SilkS")
		)
		(fp_line
			(start -1.524 -0.762)
			(end 1.524 -0.762)
			(stroke
				(width 0.1524)
				(type default)
			)
			(layer "F.SilkS")
		)
		(fp_line
			(start 1.524 0.762)
			(end -1.524 0.762)
			(stroke
				(width 0.1524)
				(type default)
			)
			(layer "F.SilkS")
		)
		(fp_line
			(start -1.524 0.762)
			(end -1.524 -0.762)
			(stroke
				(width 0.1524)
				(type default)
			)
			(layer "F.SilkS")
		)
		(fp_line
			(start 1.1049 -0.724916)
			(end -1.1049 -0.724916)
			(stroke
				(width 0.1)
				(type default)
			)
			(layer "F.Fab")
		)
		(fp_line
			(start -1.1049 -0.724916)
			(end -1.1049 0.724916)
			(stroke
				(width 0.1)
				(type default)
			)
			(layer "F.Fab")
		)
		(fp_line
			(start 1.1049 0.724916)
			(end 1.1049 -0.724916)
			(stroke
				(width 0.1)
				(type default)
			)
			(layer "F.Fab")
		)
		(fp_line
			(start -1.1049 0.724916)
			(end 1.1049 0.724916)
			(stroke
				(width 0.1)
				(type default)
			)
			(layer "F.Fab")
		)
		(pad "1" smd rect
			(at -0.889 0 270)
			(size 1.016 1.27)
			(layers "F.Cu" "F.Mask" "F.Paste")
			(net "P12V_NIC5_R")
		)
		(pad "2" smd rect
			(at 0.889 0 270)
			(size 1.016 1.27)
			(layers "F.Cu" "F.Mask" "F.Paste")
			(net "GND")
		)
	)
	(footprint ""
		(layer "F.Cu")
		(at 26.267918 -56.353456)
		(property "Reference" "C2861"
			(at 0 0 0)
			(layer "F.SilkS")
			(hide yes)
			(effects
				(font
					(size 1.27 1.27)
				)
			)
		)
		(property "Value" ""
			(at 0 0 0)
			(layer "F.Fab")
			(effects
				(font
					(size 1.27 1.27)
				)
			)
		)
		(duplicate_pad_numbers_are_jumpers no)
		(fp_line
			(start -0.7874 -0.4064)
			(end 0.7874 -0.4064)
			(stroke
				(width 0.1524)
				(type default)
			)
			(layer "F.SilkS")
		)
		(fp_line
			(start -0.7874 0.4064)
			(end -0.7874 -0.4064)
			(stroke
				(width 0.1524)
				(type default)
			)
			(layer "F.SilkS")
		)
		(fp_line
			(start 0.7874 -0.4064)
			(end 0.7874 0.4064)
			(stroke
				(width 0.1524)
				(type default)
			)
			(layer "F.SilkS")
		)
		(fp_line
			(start 0.7874 0.4064)
			(end -0.7874 0.4064)
			(stroke
				(width 0.1524)
				(type default)
			)
			(layer "F.SilkS")
		)
		(fp_line
			(start -0.67945 -0.305054)
			(end -0.12065 -0.305054)
			(stroke
				(width 0.1)
				(type default)
			)
			(layer "F.Fab")
		)
		(fp_line
			(start -0.67945 0.3048)
			(end -0.67945 -0.305054)
			(stroke
				(width 0.1)
				(type default)
			)
			(layer "F.Fab")
		)
		(fp_line
			(start -0.12065 -0.305054)
			(end -0.12065 -0.2794)
			(stroke
				(width 0.1)
				(type default)
			)
			(layer "F.Fab")
		)
		(fp_line
			(start -0.12065 -0.2794)
			(end 0.12065 -0.2794)
			(stroke
				(width 0.1)
				(type default)
			)
			(layer "F.Fab")
		)
		(fp_line
			(start -0.12065 0.2794)
			(end -0.12065 0.3048)
			(stroke
				(width 0.1)
				(type default)
			)
			(layer "F.Fab")
		)
		(fp_line
			(start -0.12065 0.3048)
			(end -0.67945 0.3048)
			(stroke
				(width 0.1)
				(type default)
			)
			(layer "F.Fab")
		)
		(fp_line
			(start 0.120396 0.2794)
			(end -0.12065 0.2794)
			(stroke
				(width 0.1)
				(type default)
			)
			(layer "F.Fab")
		)
		(fp_line
			(start 0.120396 0.3048)
			(end 0.120396 0.2794)
			(stroke
				(width 0.1)
				(type default)
			)
			(layer "F.Fab")
		)
		(fp_line
			(start 0.12065 -0.3048)
			(end 0.67945 -0.3048)
			(stroke
				(width 0.1)
				(type default)
			)
			(layer "F.Fab")
		)
		(fp_line
			(start 0.12065 -0.2794)
			(end 0.12065 -0.3048)
			(stroke
				(width 0.1)
				(type default)
			)
			(layer "F.Fab")
		)
		(fp_line
			(start 0.67945 -0.3048)
			(end 0.67945 0.3048)
			(stroke
				(width 0.1)
				(type default)
			)
			(layer "F.Fab")
		)
		(fp_line
			(start 0.67945 0.3048)
			(end 0.120396 0.3048)
			(stroke
				(width 0.1)
				(type default)
			)
			(layer "F.Fab")
		)
		(pad "1" smd circle
			(at -0.40005 0)
			(size 0 0)
			(layers "F.Cu" "F.Mask" "F.Paste")
			(net "SSD0_PWR_EN_R")
		)
		(pad "2" smd circle
			(at 0.40005 0)
			(size 0 0)
			(layers "F.Cu" "F.Mask" "F.Paste")
			(net "GND")
		)
	)
	(footprint ""
		(layer "F.Cu")
		(at 300.60519 -210.094068 -90)
		(property "Reference" "R3365"
			(at 0 0 270)
			(layer "F.SilkS")
			(hide yes)
			(effects
				(font
					(size 1.27 1.27)
				)
			)
		)
		(property "Value" ""
			(at 0 0 270)
			(layer "F.Fab")
			(effects
				(font
					(size 1.27 1.27)
				)
			)
		)
		(duplicate_pad_numbers_are_jumpers no)
		(fp_line
			(start -0.7874 0.4064)
			(end -0.7874 -0.4064)
			(stroke
				(width 0.1524)
				(type default)
			)
			(layer "F.SilkS")
		)
		(fp_line
			(start 0.7874 0.4064)
			(end -0.7874 0.4064)
			(stroke
				(width 0.1524)
				(type default)
			)
			(layer "F.SilkS")
		)
		(fp_line
			(start -0.7874 -0.4064)
			(end 0.7874 -0.4064)
			(stroke
				(width 0.1524)
				(type default)
			)
			(layer "F.SilkS")
		)
		(fp_line
			(start 0.7874 -0.4064)
			(end 0.7874 0.4064)
			(stroke
				(width 0.1524)
				(type default)
			)
			(layer "F.SilkS")
		)
		(fp_line
			(start -0.67945 0.3048)
			(end -0.67945 -0.305054)
			(stroke
				(width 0.1)
				(type default)
			)
			(layer "F.Fab")
		)
		(fp_line
			(start -0.12065 0.3048)
			(end -0.67945 0.3048)
			(stroke
				(width 0.1)
				(type default)
			)
			(layer "F.Fab")
		)
		(fp_line
			(start 0.120396 0.3048)
			(end 0.120396 0.2794)
			(stroke
				(width 0.1)
				(type default)
			)
			(layer "F.Fab")
		)
		(fp_line
			(start 0.67945 0.3048)
			(end 0.120396 0.3048)
			(stroke
				(width 0.1)
				(type default)
			)
			(layer "F.Fab")
		)
		(fp_line
			(start -0.12065 0.2794)
			(end -0.12065 0.3048)
			(stroke
				(width 0.1)
				(type default)
			)
			(layer "F.Fab")
		)
		(fp_line
			(start 0.120396 0.2794)
			(end -0.12065 0.2794)
			(stroke
				(width 0.1)
				(type default)
			)
			(layer "F.Fab")
		)
		(fp_line
			(start -0.12065 -0.2794)
			(end 0.12065 -0.2794)
			(stroke
				(width 0.1)
				(type default)
			)
			(layer "F.Fab")
		)
		(fp_line
			(start 0.12065 -0.2794)
			(end 0.12065 -0.3048)
			(stroke
				(width 0.1)
				(type default)
			)
			(layer "F.Fab")
		)
		(fp_line
			(start 0.12065 -0.3048)
			(end 0.67945 -0.3048)
			(stroke
				(width 0.1)
				(type default)
			)
			(layer "F.Fab")
		)
		(fp_line
			(start 0.67945 -0.3048)
			(end 0.67945 0.3048)
			(stroke
				(width 0.1)
				(type default)
			)
			(layer "F.Fab")
		)
		(fp_line
			(start -0.67945 -0.305054)
			(end -0.12065 -0.305054)
			(stroke
				(width 0.1)
				(type default)
			)
			(layer "F.Fab")
		)
		(fp_line
			(start -0.12065 -0.305054)
			(end -0.12065 -0.2794)
			(stroke
				(width 0.1)
				(type default)
			)
			(layer "F.Fab")
		)
		(pad "1" smd circle
			(at -0.40005 0 270)
			(size 0 0)
			(layers "F.Cu" "F.Mask" "F.Paste")
			(net "SPI_BIC1_CS0_LS23_R_N")
		)
		(pad "2" smd circle
			(at 0.40005 0 270)
			(size 0 0)
			(layers "F.Cu" "F.Mask" "F.Paste")
			(net "SPI_BIC1_CS0_LS23_N")
		)
	)
	(footprint ""
		(layer "F.Cu")
		(at 314.86602 -77.889608 180)
		(property "Reference" "C930"
			(at 0 0 180)
			(layer "F.SilkS")
			(hide yes)
			(effects
				(font
					(size 1.27 1.27)
				)
			)
		)
		(property "Value" ""
			(at 0 0 180)
			(layer "F.Fab")
			(effects
				(font
					(size 1.27 1.27)
				)
			)
		)
		(duplicate_pad_numbers_are_jumpers no)
		(fp_line
			(start 0.7874 0.4064)
			(end -0.7874 0.4064)
			(stroke
				(width 0.1524)
				(type default)
			)
			(layer "F.SilkS")
		)
		(fp_line
			(start 0.7874 -0.4064)
			(end 0.7874 0.4064)
			(stroke
				(width 0.1524)
				(type default)
			)
			(layer "F.SilkS")
		)
		(fp_line
			(start -0.7874 0.4064)
			(end -0.7874 -0.4064)
			(stroke
				(width 0.1524)
				(type default)
			)
			(layer "F.SilkS")
		)
		(fp_line
			(start -0.7874 -0.4064)
			(end 0.7874 -0.4064)
			(stroke
				(width 0.1524)
				(type default)
			)
			(layer "F.SilkS")
		)
		(fp_line
			(start 0.67945 0.3048)
			(end 0.120396 0.3048)
			(stroke
				(width 0.1)
				(type default)
			)
			(layer "F.Fab")
		)
		(fp_line
			(start 0.67945 -0.3048)
			(end 0.67945 0.3048)
			(stroke
				(width 0.1)
				(type default)
			)
			(layer "F.Fab")
		)
		(fp_line
			(start 0.12065 -0.2794)
			(end 0.12065 -0.3048)
			(stroke
				(width 0.1)
				(type default)
			)
			(layer "F.Fab")
		)
		(fp_line
			(start 0.12065 -0.3048)
			(end 0.67945 -0.3048)
			(stroke
				(width 0.1)
				(type default)
			)
			(layer "F.Fab")
		)
		(fp_line
			(start 0.120396 0.3048)
			(end 0.120396 0.2794)
			(stroke
				(width 0.1)
				(type default)
			)
			(layer "F.Fab")
		)
		(fp_line
			(start 0.120396 0.2794)
			(end -0.12065 0.2794)
			(stroke
				(width 0.1)
				(type default)
			)
			(layer "F.Fab")
		)
		(fp_line
			(start -0.12065 0.3048)
			(end -0.67945 0.3048)
			(stroke
				(width 0.1)
				(type default)
			)
			(layer "F.Fab")
		)
		(fp_line
			(start -0.12065 0.2794)
			(end -0.12065 0.3048)
			(stroke
				(width 0.1)
				(type default)
			)
			(layer "F.Fab")
		)
		(fp_line
			(start -0.12065 -0.2794)
			(end 0.12065 -0.2794)
			(stroke
				(width 0.1)
				(type default)
			)
			(layer "F.Fab")
		)
		(fp_line
			(start -0.12065 -0.305054)
			(end -0.12065 -0.2794)
			(stroke
				(width 0.1)
				(type default)
			)
			(layer "F.Fab")
		)
		(fp_line
			(start -0.67945 0.3048)
			(end -0.67945 -0.305054)
			(stroke
				(width 0.1)
				(type default)
			)
			(layer "F.Fab")
		)
		(fp_line
			(start -0.67945 -0.305054)
			(end -0.12065 -0.305054)
			(stroke
				(width 0.1)
				(type default)
			)
			(layer "F.Fab")
		)
		(pad "1" smd circle
			(at -0.40005 0 180)
			(size 0 0)
			(layers "F.Cu" "F.Mask" "F.Paste")
			(net "P3V3_NIC5")
		)
		(pad "2" smd circle
			(at 0.40005 0 180)
			(size 0 0)
			(layers "F.Cu" "F.Mask" "F.Paste")
			(net "GND")
		)
	)
	(footprint ""
		(layer "F.Cu")
		(at 29.88818 -257.64871 -90)
		(property "Reference" "C3019"
			(at 0 0 270)
			(layer "F.SilkS")
			(hide yes)
			(effects
				(font
					(size 1.27 1.27)
				)
			)
		)
		(property "Value" ""
			(at 0 0 270)
			(layer "F.Fab")
			(effects
				(font
					(size 1.27 1.27)
				)
			)
		)
		(duplicate_pad_numbers_are_jumpers no)
		(fp_line
			(start -1.2954 0.5842)
			(end -1.2954 -0.5842)
			(stroke
				(width 0.1524)
				(type default)
			)
			(layer "F.SilkS")
		)
		(fp_line
			(start 1.2954 0.5842)
			(end -1.2954 0.5842)
			(stroke
				(width 0.1524)
				(type default)
			)
			(layer "F.SilkS")
		)
		(fp_line
			(start -1.2954 -0.5842)
			(end 1.2954 -0.5842)
			(stroke
				(width 0.1524)
				(type default)
			)
			(layer "F.SilkS")
		)
		(fp_line
			(start 1.2954 -0.5842)
			(end 1.2954 0.5842)
			(stroke
				(width 0.1524)
				(type default)
			)
			(layer "F.SilkS")
		)
		(fp_line
			(start -0.8636 0.4572)
			(end -0.8636 0.4064)
			(stroke
				(width 0.1)
				(type default)
			)
			(layer "F.Fab")
		)
		(fp_line
			(start 0.8636 0.4572)
			(end -0.8636 0.4572)
			(stroke
				(width 0.1)
				(type default)
			)
			(layer "F.Fab")
		)
		(fp_line
			(start -1.1938 0.4064)
			(end -1.1938 -0.4064)
			(stroke
				(width 0.1)
				(type default)
			)
			(layer "F.Fab")
		)
		(fp_line
			(start -0.8636 0.4064)
			(end -1.1938 0.4064)
			(stroke
				(width 0.1)
				(type default)
			)
			(layer "F.Fab")
		)
		(fp_line
			(start 0.8636 0.4064)
			(end 0.8636 0.4572)
			(stroke
				(width 0.1)
				(type default)
			)
			(layer "F.Fab")
		)
		(fp_line
			(start 1.1938 0.4064)
			(end 0.8636 0.4064)
			(stroke
				(width 0.1)
				(type default)
			)
			(layer "F.Fab")
		)
		(fp_line
			(start -1.1938 -0.4064)
			(end -0.8636 -0.4064)
			(stroke
				(width 0.1)
				(type default)
			)
			(layer "F.Fab")
		)
		(fp_line
			(start -0.8636 -0.4064)
			(end -0.8636 -0.4572)
			(stroke
				(width 0.1)
				(type default)
			)
			(layer "F.Fab")
		)
		(fp_line
			(start 0.8636 -0.4064)
			(end 1.1938 -0.4064)
			(stroke
				(width 0.1)
				(type default)
			)
			(layer "F.Fab")
		)
		(fp_line
			(start 1.1938 -0.4064)
			(end 1.1938 0.4064)
			(stroke
				(width 0.1)
				(type default)
			)
			(layer "F.Fab")
		)
		(fp_line
			(start -0.8636 -0.4572)
			(end 0.8636 -0.4572)
			(stroke
				(width 0.1)
				(type default)
			)
			(layer "F.Fab")
		)
		(fp_line
			(start 0.8636 -0.4572)
			(end 0.8636 -0.4064)
			(stroke
				(width 0.1)
				(type default)
			)
			(layer "F.Fab")
		)
		(pad "1" smd rect
			(at -0.7366 0 180)
			(size 0.7112 0.8128)
			(layers "F.Cu" "F.Mask" "F.Paste")
			(net "P1V8_PLL0_PEX0")
		)
		(pad "2" smd rect
			(at 0.7366 0 180)
			(size 0.7112 0.8128)
			(layers "F.Cu" "F.Mask" "F.Paste")
			(net "GND")
		)
	)
	(footprint ""
		(layer "F.Cu")
		(at 30.153356 -288.190432)
		(property "Reference" "L94"
			(at 0 0 0)
			(layer "F.SilkS")
			(hide yes)
			(effects
				(font
					(size 1.27 1.27)
				)
			)
		)
		(property "Value" ""
			(at 0 0 0)
			(layer "F.Fab")
			(effects
				(font
					(size 1.27 1.27)
				)
			)
		)
		(duplicate_pad_numbers_are_jumpers no)
		(fp_line
			(start -1.63576 -0.8128)
			(end -1.63576 0.8128)
			(stroke
				(width 0.1524)
				(type default)
			)
			(layer "F.SilkS")
		)
		(fp_line
			(start -1.63576 -0.8128)
			(end 1.63576 -0.8128)
			(stroke
				(width 0.1524)
				(type default)
			)
			(layer "F.SilkS")
		)
		(fp_line
			(start 1.63576 -0.8128)
			(end 1.63576 0.8128)
			(stroke
				(width 0.1524)
				(type default)
			)
			(layer "F.SilkS")
		)
		(fp_line
			(start 1.63576 0.8128)
			(end -1.63576 0.8128)
			(stroke
				(width 0.1524)
				(type default)
			)
			(layer "F.SilkS")
		)
		(fp_line
			(start -1.56083 -0.738632)
			(end -1.56083 0.7366)
			(stroke
				(width 0.1)
				(type default)
			)
			(layer "F.Fab")
		)
		(fp_line
			(start -1.56083 0.7366)
			(end -1.524 0.7366)
			(stroke
				(width 0.1)
				(type default)
			)
			(layer "F.Fab")
		)
		(fp_line
			(start -1.524 0.7366)
			(end 1.524 0.7366)
			(stroke
				(width 0.1)
				(type default)
			)
			(layer "F.Fab")
		)
		(fp_line
			(start 1.524 0.7366)
			(end 1.560576 0.7366)
			(stroke
				(width 0.1)
				(type default)
			)
			(layer "F.Fab")
		)
		(fp_line
			(start 1.560576 -0.738632)
			(end -1.56083 -0.738632)
			(stroke
				(width 0.1)
				(type default)
			)
			(layer "F.Fab")
		)
		(fp_line
			(start 1.560576 0.7366)
			(end 1.560576 -0.738632)
			(stroke
				(width 0.1)
				(type default)
			)
			(layer "F.Fab")
		)
		(pad "1" smd rect
			(at -0.94996 0 180)
			(size 1.1176 1.3716)
			(layers "F.Cu" "F.Mask" "F.Paste")
			(net "P1V8_PLL0_PEX0")
		)
		(pad "2" smd rect
			(at 0.94996 0 180)
			(size 1.1176 1.3716)
			(layers "F.Cu" "F.Mask" "F.Paste")
			(net "PCEPLL6_VDDA18_PEX0")
		)
	)
	(footprint ""
		(layer "F.Cu")
		(at 279.14727 -20.35556)
		(property "Reference" "C3939"
			(at 0 0 0)
			(layer "F.SilkS")
			(hide yes)
			(effects
				(font
					(size 1.27 1.27)
				)
			)
		)
		(property "Value" ""
			(at 0 0 0)
			(layer "F.Fab")
			(effects
				(font
					(size 1.27 1.27)
				)
			)
		)
		(duplicate_pad_numbers_are_jumpers no)
		(fp_line
			(start -0.7874 -0.4064)
			(end 0.7874 -0.4064)
			(stroke
				(width 0.1524)
				(type default)
			)
			(layer "F.SilkS")
		)
		(fp_line
			(start -0.7874 0.4064)
			(end -0.7874 -0.4064)
			(stroke
				(width 0.1524)
				(type default)
			)
			(layer "F.SilkS")
		)
		(fp_line
			(start 0.7874 -0.4064)
			(end 0.7874 0.4064)
			(stroke
				(width 0.1524)
				(type default)
			)
			(layer "F.SilkS")
		)
		(fp_line
			(start 0.7874 0.4064)
			(end -0.7874 0.4064)
			(stroke
				(width 0.1524)
				(type default)
			)
			(layer "F.SilkS")
		)
		(fp_line
			(start -0.67945 -0.305054)
			(end -0.12065 -0.305054)
			(stroke
				(width 0.1)
				(type default)
			)
			(layer "F.Fab")
		)
		(fp_line
			(start -0.67945 0.3048)
			(end -0.67945 -0.305054)
			(stroke
				(width 0.1)
				(type default)
			)
			(layer "F.Fab")
		)
		(fp_line
			(start -0.12065 -0.305054)
			(end -0.12065 -0.2794)
			(stroke
				(width 0.1)
				(type default)
			)
			(layer "F.Fab")
		)
		(fp_line
			(start -0.12065 -0.2794)
			(end 0.12065 -0.2794)
			(stroke
				(width 0.1)
				(type default)
			)
			(layer "F.Fab")
		)
		(fp_line
			(start -0.12065 0.2794)
			(end -0.12065 0.3048)
			(stroke
				(width 0.1)
				(type default)
			)
			(layer "F.Fab")
		)
		(fp_line
			(start -0.12065 0.3048)
			(end -0.67945 0.3048)
			(stroke
				(width 0.1)
				(type default)
			)
			(layer "F.Fab")
		)
		(fp_line
			(start 0.120396 0.2794)
			(end -0.12065 0.2794)
			(stroke
				(width 0.1)
				(type default)
			)
			(layer "F.Fab")
		)
		(fp_line
			(start 0.120396 0.3048)
			(end 0.120396 0.2794)
			(stroke
				(width 0.1)
				(type default)
			)
			(layer "F.Fab")
		)
		(fp_line
			(start 0.12065 -0.3048)
			(end 0.67945 -0.3048)
			(stroke
				(width 0.1)
				(type default)
			)
			(layer "F.Fab")
		)
		(fp_line
			(start 0.12065 -0.2794)
			(end 0.12065 -0.3048)
			(stroke
				(width 0.1)
				(type default)
			)
			(layer "F.Fab")
		)
		(fp_line
			(start 0.67945 -0.3048)
			(end 0.67945 0.3048)
			(stroke
				(width 0.1)
				(type default)
			)
			(layer "F.Fab")
		)
		(fp_line
			(start 0.67945 0.3048)
			(end 0.120396 0.3048)
			(stroke
				(width 0.1)
				(type default)
			)
			(layer "F.Fab")
		)
		(pad "1" smd circle
			(at -0.40005 0)
			(size 0 0)
			(layers "F.Cu" "F.Mask" "F.Paste")
			(net "P12V_SSD9")
		)
		(pad "2" smd circle
			(at 0.40005 0)
			(size 0 0)
			(layers "F.Cu" "F.Mask" "F.Paste")
			(net "GND")
		)
	)
	(footprint ""
		(layer "F.Cu")
		(at 240.139474 -257.975862 -90)
		(property "Reference" "R6524"
			(at 0 0 270)
			(layer "F.SilkS")
			(hide yes)
			(effects
				(font
					(size 1.27 1.27)
				)
			)
		)
		(property "Value" ""
			(at 0 0 270)
			(layer "F.Fab")
			(effects
				(font
					(size 1.27 1.27)
				)
			)
		)
		(duplicate_pad_numbers_are_jumpers no)
		(fp_line
			(start -0.7874 0.4064)
			(end -0.7874 -0.4064)
			(stroke
				(width 0.1524)
				(type default)
			)
			(layer "F.SilkS")
		)
		(fp_line
			(start 0.7874 0.4064)
			(end -0.7874 0.4064)
			(stroke
				(width 0.1524)
				(type default)
			)
			(layer "F.SilkS")
		)
		(fp_line
			(start -0.7874 -0.4064)
			(end 0.7874 -0.4064)
			(stroke
				(width 0.1524)
				(type default)
			)
			(layer "F.SilkS")
		)
		(fp_line
			(start 0.7874 -0.4064)
			(end 0.7874 0.4064)
			(stroke
				(width 0.1524)
				(type default)
			)
			(layer "F.SilkS")
		)
		(fp_line
			(start -0.67945 0.3048)
			(end -0.67945 -0.305054)
			(stroke
				(width 0.1)
				(type default)
			)
			(layer "F.Fab")
		)
		(fp_line
			(start -0.12065 0.3048)
			(end -0.67945 0.3048)
			(stroke
				(width 0.1)
				(type default)
			)
			(layer "F.Fab")
		)
		(fp_line
			(start 0.120396 0.3048)
			(end 0.120396 0.2794)
			(stroke
				(width 0.1)
				(type default)
			)
			(layer "F.Fab")
		)
		(fp_line
			(start 0.67945 0.3048)
			(end 0.120396 0.3048)
			(stroke
				(width 0.1)
				(type default)
			)
			(layer "F.Fab")
		)
		(fp_line
			(start -0.12065 0.2794)
			(end -0.12065 0.3048)
			(stroke
				(width 0.1)
				(type default)
			)
			(layer "F.Fab")
		)
		(fp_line
			(start 0.120396 0.2794)
			(end -0.12065 0.2794)
			(stroke
				(width 0.1)
				(type default)
			)
			(layer "F.Fab")
		)
		(fp_line
			(start -0.12065 -0.2794)
			(end 0.12065 -0.2794)
			(stroke
				(width 0.1)
				(type default)
			)
			(layer "F.Fab")
		)
		(fp_line
			(start 0.12065 -0.2794)
			(end 0.12065 -0.3048)
			(stroke
				(width 0.1)
				(type default)
			)
			(layer "F.Fab")
		)
		(fp_line
			(start 0.12065 -0.3048)
			(end 0.67945 -0.3048)
			(stroke
				(width 0.1)
				(type default)
			)
			(layer "F.Fab")
		)
		(fp_line
			(start 0.67945 -0.3048)
			(end 0.67945 0.3048)
			(stroke
				(width 0.1)
				(type default)
			)
			(layer "F.Fab")
		)
		(fp_line
			(start -0.67945 -0.305054)
			(end -0.12065 -0.305054)
			(stroke
				(width 0.1)
				(type default)
			)
			(layer "F.Fab")
		)
		(fp_line
			(start -0.12065 -0.305054)
			(end -0.12065 -0.2794)
			(stroke
				(width 0.1)
				(type default)
			)
			(layer "F.Fab")
		)
		(pad "1" smd circle
			(at -0.40005 0 270)
			(size 0 0)
			(layers "F.Cu" "F.Mask" "F.Paste")
			(net "P1V25_SERDES_VDDPLL_PEX2")
		)
		(pad "2" smd circle
			(at 0.40005 0 270)
			(size 0 0)
			(layers "F.Cu" "F.Mask" "F.Paste")
			(net "P1V25_SERDES_VDDPLL_PEX2_C3")
		)
	)
	(footprint ""
		(layer "F.Cu")
		(at 174.164244 -141.6558 180)
		(property "Reference" "R137"
			(at 0 0 180)
			(layer "F.SilkS")
			(hide yes)
			(effects
				(font
					(size 1.27 1.27)
				)
			)
		)
		(property "Value" ""
			(at 0 0 180)
			(layer "F.Fab")
			(effects
				(font
					(size 1.27 1.27)
				)
			)
		)
		(duplicate_pad_numbers_are_jumpers no)
		(fp_line
			(start 0.7874 0.4064)
			(end -0.7874 0.4064)
			(stroke
				(width 0.1524)
				(type default)
			)
			(layer "F.SilkS")
		)
		(fp_line
			(start 0.7874 -0.4064)
			(end 0.7874 0.4064)
			(stroke
				(width 0.1524)
				(type default)
			)
			(layer "F.SilkS")
		)
		(fp_line
			(start -0.7874 0.4064)
			(end -0.7874 -0.4064)
			(stroke
				(width 0.1524)
				(type default)
			)
			(layer "F.SilkS")
		)
		(fp_line
			(start -0.7874 -0.4064)
			(end 0.7874 -0.4064)
			(stroke
				(width 0.1524)
				(type default)
			)
			(layer "F.SilkS")
		)
		(fp_line
			(start 0.67945 0.3048)
			(end 0.120396 0.3048)
			(stroke
				(width 0.1)
				(type default)
			)
			(layer "F.Fab")
		)
		(fp_line
			(start 0.67945 -0.3048)
			(end 0.67945 0.3048)
			(stroke
				(width 0.1)
				(type default)
			)
			(layer "F.Fab")
		)
		(fp_line
			(start 0.12065 -0.2794)
			(end 0.12065 -0.3048)
			(stroke
				(width 0.1)
				(type default)
			)
			(layer "F.Fab")
		)
		(fp_line
			(start 0.12065 -0.3048)
			(end 0.67945 -0.3048)
			(stroke
				(width 0.1)
				(type default)
			)
			(layer "F.Fab")
		)
		(fp_line
			(start 0.120396 0.3048)
			(end 0.120396 0.2794)
			(stroke
				(width 0.1)
				(type default)
			)
			(layer "F.Fab")
		)
		(fp_line
			(start 0.120396 0.2794)
			(end -0.12065 0.2794)
			(stroke
				(width 0.1)
				(type default)
			)
			(layer "F.Fab")
		)
		(fp_line
			(start -0.12065 0.3048)
			(end -0.67945 0.3048)
			(stroke
				(width 0.1)
				(type default)
			)
			(layer "F.Fab")
		)
		(fp_line
			(start -0.12065 0.2794)
			(end -0.12065 0.3048)
			(stroke
				(width 0.1)
				(type default)
			)
			(layer "F.Fab")
		)
		(fp_line
			(start -0.12065 -0.2794)
			(end 0.12065 -0.2794)
			(stroke
				(width 0.1)
				(type default)
			)
			(layer "F.Fab")
		)
		(fp_line
			(start -0.12065 -0.305054)
			(end -0.12065 -0.2794)
			(stroke
				(width 0.1)
				(type default)
			)
			(layer "F.Fab")
		)
		(fp_line
			(start -0.67945 0.3048)
			(end -0.67945 -0.305054)
			(stroke
				(width 0.1)
				(type default)
			)
			(layer "F.Fab")
		)
		(fp_line
			(start -0.67945 -0.305054)
			(end -0.12065 -0.305054)
			(stroke
				(width 0.1)
				(type default)
			)
			(layer "F.Fab")
		)
		(pad "1" smd circle
			(at -0.40005 0 180)
			(size 0 0)
			(layers "F.Cu" "F.Mask" "F.Paste")
			(net "RST_SMB_NIC2_MUX_ISO_N")
		)
		(pad "2" smd circle
			(at 0.40005 0 180)
			(size 0 0)
			(layers "F.Cu" "F.Mask" "F.Paste")
			(net "P3V3_NIC2")
		)
	)
	(footprint ""
		(layer "F.Cu")
		(at 80.019398 -133.480302 180)
		(property "Reference" "C20"
			(at 0 0 180)
			(layer "F.SilkS")
			(hide yes)
			(effects
				(font
					(size 1.27 1.27)
				)
			)
		)
		(property "Value" ""
			(at 0 0 180)
			(layer "F.Fab")
			(effects
				(font
					(size 1.27 1.27)
				)
			)
		)
		(duplicate_pad_numbers_are_jumpers no)
		(fp_line
			(start 0.299974 0.150114)
			(end -0.299974 0.150114)
			(stroke
				(width 0.1)
				(type default)
			)
			(layer "F.Fab")
		)
		(fp_line
			(start 0.299974 -0.150114)
			(end 0.299974 0.150114)
			(stroke
				(width 0.1)
				(type default)
			)
			(layer "F.Fab")
		)
		(fp_line
			(start -0.299974 0.150114)
			(end -0.299974 -0.150114)
			(stroke
				(width 0.1)
				(type default)
			)
			(layer "F.Fab")
		)
		(fp_line
			(start -0.299974 -0.150114)
			(end 0.299974 -0.150114)
			(stroke
				(width 0.1)
				(type default)
			)
			(layer "F.Fab")
		)
		(pad "1" smd rect
			(at -0.2667 0 180)
			(size 0.3048 0.381)
			(layers "F.Cu" "F.Mask" "F.Paste")
			(net "P5E_PEX0_STN0_TX_DN<6>")
		)
		(pad "2" smd rect
			(at 0.2667 0 180)
			(size 0.3048 0.381)
			(layers "F.Cu" "F.Mask" "F.Paste")
			(net "P5E_PEX0_STN0_TX_C_DN<6>")
		)
	)
	(footprint ""
		(layer "F.Cu")
		(at 338.074 -148.971 180)
		(property "Reference" "R4843"
			(at 0 0 180)
			(layer "F.SilkS")
			(hide yes)
			(effects
				(font
					(size 1.27 1.27)
				)
			)
		)
		(property "Value" ""
			(at 0 0 180)
			(layer "F.Fab")
			(effects
				(font
					(size 1.27 1.27)
				)
			)
		)
		(duplicate_pad_numbers_are_jumpers no)
		(fp_line
			(start 0.7874 0.4064)
			(end -0.7874 0.4064)
			(stroke
				(width 0.1524)
				(type default)
			)
			(layer "F.SilkS")
		)
		(fp_line
			(start 0.7874 -0.4064)
			(end 0.7874 0.4064)
			(stroke
				(width 0.1524)
				(type default)
			)
			(layer "F.SilkS")
		)
		(fp_line
			(start -0.7874 0.4064)
			(end -0.7874 -0.4064)
			(stroke
				(width 0.1524)
				(type default)
			)
			(layer "F.SilkS")
		)
		(fp_line
			(start -0.7874 -0.4064)
			(end 0.7874 -0.4064)
			(stroke
				(width 0.1524)
				(type default)
			)
			(layer "F.SilkS")
		)
		(fp_line
			(start 0.67945 0.3048)
			(end 0.120396 0.3048)
			(stroke
				(width 0.1)
				(type default)
			)
			(layer "F.Fab")
		)
		(fp_line
			(start 0.67945 -0.3048)
			(end 0.67945 0.3048)
			(stroke
				(width 0.1)
				(type default)
			)
			(layer "F.Fab")
		)
		(fp_line
			(start 0.12065 -0.2794)
			(end 0.12065 -0.3048)
			(stroke
				(width 0.1)
				(type default)
			)
			(layer "F.Fab")
		)
		(fp_line
			(start 0.12065 -0.3048)
			(end 0.67945 -0.3048)
			(stroke
				(width 0.1)
				(type default)
			)
			(layer "F.Fab")
		)
		(fp_line
			(start 0.120396 0.3048)
			(end 0.120396 0.2794)
			(stroke
				(width 0.1)
				(type default)
			)
			(layer "F.Fab")
		)
		(fp_line
			(start 0.120396 0.2794)
			(end -0.12065 0.2794)
			(stroke
				(width 0.1)
				(type default)
			)
			(layer "F.Fab")
		)
		(fp_line
			(start -0.12065 0.3048)
			(end -0.67945 0.3048)
			(stroke
				(width 0.1)
				(type default)
			)
			(layer "F.Fab")
		)
		(fp_line
			(start -0.12065 0.2794)
			(end -0.12065 0.3048)
			(stroke
				(width 0.1)
				(type default)
			)
			(layer "F.Fab")
		)
		(fp_line
			(start -0.12065 -0.2794)
			(end 0.12065 -0.2794)
			(stroke
				(width 0.1)
				(type default)
			)
			(layer "F.Fab")
		)
		(fp_line
			(start -0.12065 -0.305054)
			(end -0.12065 -0.2794)
			(stroke
				(width 0.1)
				(type default)
			)
			(layer "F.Fab")
		)
		(fp_line
			(start -0.67945 0.3048)
			(end -0.67945 -0.305054)
			(stroke
				(width 0.1)
				(type default)
			)
			(layer "F.Fab")
		)
		(fp_line
			(start -0.67945 -0.305054)
			(end -0.12065 -0.305054)
			(stroke
				(width 0.1)
				(type default)
			)
			(layer "F.Fab")
		)
		(pad "1" smd circle
			(at -0.40005 0 180)
			(size 0 0)
			(layers "F.Cu" "F.Mask" "F.Paste")
			(net "GND")
		)
		(pad "2" smd circle
			(at 0.40005 0 180)
			(size 0 0)
			(layers "F.Cu" "F.Mask" "F.Paste")
			(net "PCA9555_1_PEX3_A2")
		)
	)
	(footprint ""
		(layer "F.Cu")
		(at 233.316018 -78.99019)
		(property "Reference" "R1003"
			(at 0 0 0)
			(layer "F.SilkS")
			(hide yes)
			(effects
				(font
					(size 1.27 1.27)
				)
			)
		)
		(property "Value" ""
			(at 0 0 0)
			(layer "F.Fab")
			(effects
				(font
					(size 1.27 1.27)
				)
			)
		)
		(duplicate_pad_numbers_are_jumpers no)
		(fp_line
			(start -0.7874 -0.4064)
			(end 0.7874 -0.4064)
			(stroke
				(width 0.1524)
				(type default)
			)
			(layer "F.SilkS")
		)
		(fp_line
			(start -0.7874 0.4064)
			(end -0.7874 -0.4064)
			(stroke
				(width 0.1524)
				(type default)
			)
			(layer "F.SilkS")
		)
		(fp_line
			(start 0.7874 -0.4064)
			(end 0.7874 0.4064)
			(stroke
				(width 0.1524)
				(type default)
			)
			(layer "F.SilkS")
		)
		(fp_line
			(start 0.7874 0.4064)
			(end -0.7874 0.4064)
			(stroke
				(width 0.1524)
				(type default)
			)
			(layer "F.SilkS")
		)
		(fp_line
			(start -0.67945 -0.305054)
			(end -0.12065 -0.305054)
			(stroke
				(width 0.1)
				(type default)
			)
			(layer "F.Fab")
		)
		(fp_line
			(start -0.67945 0.3048)
			(end -0.67945 -0.305054)
			(stroke
				(width 0.1)
				(type default)
			)
			(layer "F.Fab")
		)
		(fp_line
			(start -0.12065 -0.305054)
			(end -0.12065 -0.2794)
			(stroke
				(width 0.1)
				(type default)
			)
			(layer "F.Fab")
		)
		(fp_line
			(start -0.12065 -0.2794)
			(end 0.12065 -0.2794)
			(stroke
				(width 0.1)
				(type default)
			)
			(layer "F.Fab")
		)
		(fp_line
			(start -0.12065 0.2794)
			(end -0.12065 0.3048)
			(stroke
				(width 0.1)
				(type default)
			)
			(layer "F.Fab")
		)
		(fp_line
			(start -0.12065 0.3048)
			(end -0.67945 0.3048)
			(stroke
				(width 0.1)
				(type default)
			)
			(layer "F.Fab")
		)
		(fp_line
			(start 0.120396 0.2794)
			(end -0.12065 0.2794)
			(stroke
				(width 0.1)
				(type default)
			)
			(layer "F.Fab")
		)
		(fp_line
			(start 0.120396 0.3048)
			(end 0.120396 0.2794)
			(stroke
				(width 0.1)
				(type default)
			)
			(layer "F.Fab")
		)
		(fp_line
			(start 0.12065 -0.3048)
			(end 0.67945 -0.3048)
			(stroke
				(width 0.1)
				(type default)
			)
			(layer "F.Fab")
		)
		(fp_line
			(start 0.12065 -0.2794)
			(end 0.12065 -0.3048)
			(stroke
				(width 0.1)
				(type default)
			)
			(layer "F.Fab")
		)
		(fp_line
			(start 0.67945 -0.3048)
			(end 0.67945 0.3048)
			(stroke
				(width 0.1)
				(type default)
			)
			(layer "F.Fab")
		)
		(fp_line
			(start 0.67945 0.3048)
			(end 0.120396 0.3048)
			(stroke
				(width 0.1)
				(type default)
			)
			(layer "F.Fab")
		)
		(pad "1" smd circle
			(at -0.40005 0)
			(size 0 0)
			(layers "F.Cu" "F.Mask" "F.Paste")
			(net "PEX_USB2_SEL")
		)
		(pad "2" smd circle
			(at 0.40005 0)
			(size 0 0)
			(layers "F.Cu" "F.Mask" "F.Paste")
			(net "GND")
		)
	)
	(footprint ""
		(layer "F.Cu")
		(at 220.812868 -104.912668 90)
		(property "Reference" "C903"
			(at 0 0 90)
			(layer "F.SilkS")
			(hide yes)
			(effects
				(font
					(size 1.27 1.27)
				)
			)
		)
		(property "Value" ""
			(at 0 0 90)
			(layer "F.Fab")
			(effects
				(font
					(size 1.27 1.27)
				)
			)
		)
		(duplicate_pad_numbers_are_jumpers no)
		(fp_line
			(start 0.7874 -0.4064)
			(end 0.7874 0.4064)
			(stroke
				(width 0.1524)
				(type default)
			)
			(layer "F.SilkS")
		)
		(fp_line
			(start -0.7874 -0.4064)
			(end 0.7874 -0.4064)
			(stroke
				(width 0.1524)
				(type default)
			)
			(layer "F.SilkS")
		)
		(fp_line
			(start 0.7874 0.4064)
			(end -0.7874 0.4064)
			(stroke
				(width 0.1524)
				(type default)
			)
			(layer "F.SilkS")
		)
		(fp_line
			(start -0.7874 0.4064)
			(end -0.7874 -0.4064)
			(stroke
				(width 0.1524)
				(type default)
			)
			(layer "F.SilkS")
		)
		(fp_line
			(start -0.12065 -0.305054)
			(end -0.12065 -0.2794)
			(stroke
				(width 0.1)
				(type default)
			)
			(layer "F.Fab")
		)
		(fp_line
			(start -0.67945 -0.305054)
			(end -0.12065 -0.305054)
			(stroke
				(width 0.1)
				(type default)
			)
			(layer "F.Fab")
		)
		(fp_line
			(start 0.67945 -0.3048)
			(end 0.67945 0.3048)
			(stroke
				(width 0.1)
				(type default)
			)
			(layer "F.Fab")
		)
		(fp_line
			(start 0.12065 -0.3048)
			(end 0.67945 -0.3048)
			(stroke
				(width 0.1)
				(type default)
			)
			(layer "F.Fab")
		)
		(fp_line
			(start 0.12065 -0.2794)
			(end 0.12065 -0.3048)
			(stroke
				(width 0.1)
				(type default)
			)
			(layer "F.Fab")
		)
		(fp_line
			(start -0.12065 -0.2794)
			(end 0.12065 -0.2794)
			(stroke
				(width 0.1)
				(type default)
			)
			(layer "F.Fab")
		)
		(fp_line
			(start 0.120396 0.2794)
			(end -0.12065 0.2794)
			(stroke
				(width 0.1)
				(type default)
			)
			(layer "F.Fab")
		)
		(fp_line
			(start -0.12065 0.2794)
			(end -0.12065 0.3048)
			(stroke
				(width 0.1)
				(type default)
			)
			(layer "F.Fab")
		)
		(fp_line
			(start 0.67945 0.3048)
			(end 0.120396 0.3048)
			(stroke
				(width 0.1)
				(type default)
			)
			(layer "F.Fab")
		)
		(fp_line
			(start 0.120396 0.3048)
			(end 0.120396 0.2794)
			(stroke
				(width 0.1)
				(type default)
			)
			(layer "F.Fab")
		)
		(fp_line
			(start -0.12065 0.3048)
			(end -0.67945 0.3048)
			(stroke
				(width 0.1)
				(type default)
			)
			(layer "F.Fab")
		)
		(fp_line
			(start -0.67945 0.3048)
			(end -0.67945 -0.305054)
			(stroke
				(width 0.1)
				(type default)
			)
			(layer "F.Fab")
		)
		(pad "1" smd circle
			(at -0.40005 0 90)
			(size 0 0)
			(layers "F.Cu" "F.Mask" "F.Paste")
			(net "P3V3_AUX")
		)
		(pad "2" smd circle
			(at 0.40005 0 90)
			(size 0 0)
			(layers "F.Cu" "F.Mask" "F.Paste")
			(net "GND")
		)
	)
	(footprint ""
		(layer "F.Cu")
		(at 365.506 -196.723 180)
		(property "Reference" "R4690"
			(at 0 0 180)
			(layer "F.SilkS")
			(hide yes)
			(effects
				(font
					(size 1.27 1.27)
				)
			)
		)
		(property "Value" ""
			(at 0 0 180)
			(layer "F.Fab")
			(effects
				(font
					(size 1.27 1.27)
				)
			)
		)
		(duplicate_pad_numbers_are_jumpers no)
		(fp_line
			(start 0.7874 0.4064)
			(end -0.7874 0.4064)
			(stroke
				(width 0.1524)
				(type default)
			)
			(layer "F.SilkS")
		)
		(fp_line
			(start 0.7874 -0.4064)
			(end 0.7874 0.4064)
			(stroke
				(width 0.1524)
				(type default)
			)
			(layer "F.SilkS")
		)
		(fp_line
			(start -0.7874 0.4064)
			(end -0.7874 -0.4064)
			(stroke
				(width 0.1524)
				(type default)
			)
			(layer "F.SilkS")
		)
		(fp_line
			(start -0.7874 -0.4064)
			(end 0.7874 -0.4064)
			(stroke
				(width 0.1524)
				(type default)
			)
			(layer "F.SilkS")
		)
		(fp_line
			(start 0.67945 0.3048)
			(end 0.120396 0.3048)
			(stroke
				(width 0.1)
				(type default)
			)
			(layer "F.Fab")
		)
		(fp_line
			(start 0.67945 -0.3048)
			(end 0.67945 0.3048)
			(stroke
				(width 0.1)
				(type default)
			)
			(layer "F.Fab")
		)
		(fp_line
			(start 0.12065 -0.2794)
			(end 0.12065 -0.3048)
			(stroke
				(width 0.1)
				(type default)
			)
			(layer "F.Fab")
		)
		(fp_line
			(start 0.12065 -0.3048)
			(end 0.67945 -0.3048)
			(stroke
				(width 0.1)
				(type default)
			)
			(layer "F.Fab")
		)
		(fp_line
			(start 0.120396 0.3048)
			(end 0.120396 0.2794)
			(stroke
				(width 0.1)
				(type default)
			)
			(layer "F.Fab")
		)
		(fp_line
			(start 0.120396 0.2794)
			(end -0.12065 0.2794)
			(stroke
				(width 0.1)
				(type default)
			)
			(layer "F.Fab")
		)
		(fp_line
			(start -0.12065 0.3048)
			(end -0.67945 0.3048)
			(stroke
				(width 0.1)
				(type default)
			)
			(layer "F.Fab")
		)
		(fp_line
			(start -0.12065 0.2794)
			(end -0.12065 0.3048)
			(stroke
				(width 0.1)
				(type default)
			)
			(layer "F.Fab")
		)
		(fp_line
			(start -0.12065 -0.2794)
			(end 0.12065 -0.2794)
			(stroke
				(width 0.1)
				(type default)
			)
			(layer "F.Fab")
		)
		(fp_line
			(start -0.12065 -0.305054)
			(end -0.12065 -0.2794)
			(stroke
				(width 0.1)
				(type default)
			)
			(layer "F.Fab")
		)
		(fp_line
			(start -0.67945 0.3048)
			(end -0.67945 -0.305054)
			(stroke
				(width 0.1)
				(type default)
			)
			(layer "F.Fab")
		)
		(fp_line
			(start -0.67945 -0.305054)
			(end -0.12065 -0.305054)
			(stroke
				(width 0.1)
				(type default)
			)
			(layer "F.Fab")
		)
		(pad "1" smd circle
			(at -0.40005 0 180)
			(size 0 0)
			(layers "F.Cu" "F.Mask" "F.Paste")
			(net "PRSNT_SSD5_FPGA_PCA9555_N")
		)
		(pad "2" smd circle
			(at 0.40005 0 180)
			(size 0 0)
			(layers "F.Cu" "F.Mask" "F.Paste")
			(net "PRSNT_SSD5_FPGA_R_N")
		)
	)
	(footprint ""
		(layer "F.Cu")
		(at 336.042 -178.943 180)
		(property "Reference" "R4740"
			(at 0 0 180)
			(layer "F.SilkS")
			(hide yes)
			(effects
				(font
					(size 1.27 1.27)
				)
			)
		)
		(property "Value" ""
			(at 0 0 180)
			(layer "F.Fab")
			(effects
				(font
					(size 1.27 1.27)
				)
			)
		)
		(duplicate_pad_numbers_are_jumpers no)
		(fp_line
			(start 0.7874 0.4064)
			(end -0.7874 0.4064)
			(stroke
				(width 0.1524)
				(type default)
			)
			(layer "F.SilkS")
		)
		(fp_line
			(start 0.7874 -0.4064)
			(end 0.7874 0.4064)
			(stroke
				(width 0.1524)
				(type default)
			)
			(layer "F.SilkS")
		)
		(fp_line
			(start -0.7874 0.4064)
			(end -0.7874 -0.4064)
			(stroke
				(width 0.1524)
				(type default)
			)
			(layer "F.SilkS")
		)
		(fp_line
			(start -0.7874 -0.4064)
			(end 0.7874 -0.4064)
			(stroke
				(width 0.1524)
				(type default)
			)
			(layer "F.SilkS")
		)
		(fp_line
			(start 0.67945 0.3048)
			(end 0.120396 0.3048)
			(stroke
				(width 0.1)
				(type default)
			)
			(layer "F.Fab")
		)
		(fp_line
			(start 0.67945 -0.3048)
			(end 0.67945 0.3048)
			(stroke
				(width 0.1)
				(type default)
			)
			(layer "F.Fab")
		)
		(fp_line
			(start 0.12065 -0.2794)
			(end 0.12065 -0.3048)
			(stroke
				(width 0.1)
				(type default)
			)
			(layer "F.Fab")
		)
		(fp_line
			(start 0.12065 -0.3048)
			(end 0.67945 -0.3048)
			(stroke
				(width 0.1)
				(type default)
			)
			(layer "F.Fab")
		)
		(fp_line
			(start 0.120396 0.3048)
			(end 0.120396 0.2794)
			(stroke
				(width 0.1)
				(type default)
			)
			(layer "F.Fab")
		)
		(fp_line
			(start 0.120396 0.2794)
			(end -0.12065 0.2794)
			(stroke
				(width 0.1)
				(type default)
			)
			(layer "F.Fab")
		)
		(fp_line
			(start -0.12065 0.3048)
			(end -0.67945 0.3048)
			(stroke
				(width 0.1)
				(type default)
			)
			(layer "F.Fab")
		)
		(fp_line
			(start -0.12065 0.2794)
			(end -0.12065 0.3048)
			(stroke
				(width 0.1)
				(type default)
			)
			(layer "F.Fab")
		)
		(fp_line
			(start -0.12065 -0.2794)
			(end 0.12065 -0.2794)
			(stroke
				(width 0.1)
				(type default)
			)
			(layer "F.Fab")
		)
		(fp_line
			(start -0.12065 -0.305054)
			(end -0.12065 -0.2794)
			(stroke
				(width 0.1)
				(type default)
			)
			(layer "F.Fab")
		)
		(fp_line
			(start -0.67945 0.3048)
			(end -0.67945 -0.305054)
			(stroke
				(width 0.1)
				(type default)
			)
			(layer "F.Fab")
		)
		(fp_line
			(start -0.67945 -0.305054)
			(end -0.12065 -0.305054)
			(stroke
				(width 0.1)
				(type default)
			)
			(layer "F.Fab")
		)
		(pad "1" smd circle
			(at -0.40005 0 180)
			(size 0 0)
			(layers "F.Cu" "F.Mask" "F.Paste")
			(net "SSD9_PEX_PWR_EN_R")
		)
		(pad "2" smd circle
			(at 0.40005 0 180)
			(size 0 0)
			(layers "F.Cu" "F.Mask" "F.Paste")
			(net "GND")
		)
	)
	(footprint ""
		(layer "F.Cu")
		(at 43.926506 -25.432004 -90)
		(property "Reference" "C966"
			(at 0 0 270)
			(layer "F.SilkS")
			(hide yes)
			(effects
				(font
					(size 1.27 1.27)
				)
			)
		)
		(property "Value" ""
			(at 0 0 270)
			(layer "F.Fab")
			(effects
				(font
					(size 1.27 1.27)
				)
			)
		)
		(duplicate_pad_numbers_are_jumpers no)
		(fp_line
			(start -0.7874 0.4064)
			(end -0.7874 -0.4064)
			(stroke
				(width 0.1524)
				(type default)
			)
			(layer "F.SilkS")
		)
		(fp_line
			(start 0.7874 0.4064)
			(end -0.7874 0.4064)
			(stroke
				(width 0.1524)
				(type default)
			)
			(layer "F.SilkS")
		)
		(fp_line
			(start -0.7874 -0.4064)
			(end 0.7874 -0.4064)
			(stroke
				(width 0.1524)
				(type default)
			)
			(layer "F.SilkS")
		)
		(fp_line
			(start 0.7874 -0.4064)
			(end 0.7874 0.4064)
			(stroke
				(width 0.1524)
				(type default)
			)
			(layer "F.SilkS")
		)
		(fp_line
			(start -0.67945 0.3048)
			(end -0.67945 -0.305054)
			(stroke
				(width 0.1)
				(type default)
			)
			(layer "F.Fab")
		)
		(fp_line
			(start -0.12065 0.3048)
			(end -0.67945 0.3048)
			(stroke
				(width 0.1)
				(type default)
			)
			(layer "F.Fab")
		)
		(fp_line
			(start 0.120396 0.3048)
			(end 0.120396 0.2794)
			(stroke
				(width 0.1)
				(type default)
			)
			(layer "F.Fab")
		)
		(fp_line
			(start 0.67945 0.3048)
			(end 0.120396 0.3048)
			(stroke
				(width 0.1)
				(type default)
			)
			(layer "F.Fab")
		)
		(fp_line
			(start -0.12065 0.2794)
			(end -0.12065 0.3048)
			(stroke
				(width 0.1)
				(type default)
			)
			(layer "F.Fab")
		)
		(fp_line
			(start 0.120396 0.2794)
			(end -0.12065 0.2794)
			(stroke
				(width 0.1)
				(type default)
			)
			(layer "F.Fab")
		)
		(fp_line
			(start -0.12065 -0.2794)
			(end 0.12065 -0.2794)
			(stroke
				(width 0.1)
				(type default)
			)
			(layer "F.Fab")
		)
		(fp_line
			(start 0.12065 -0.2794)
			(end 0.12065 -0.3048)
			(stroke
				(width 0.1)
				(type default)
			)
			(layer "F.Fab")
		)
		(fp_line
			(start 0.12065 -0.3048)
			(end 0.67945 -0.3048)
			(stroke
				(width 0.1)
				(type default)
			)
			(layer "F.Fab")
		)
		(fp_line
			(start 0.67945 -0.3048)
			(end 0.67945 0.3048)
			(stroke
				(width 0.1)
				(type default)
			)
			(layer "F.Fab")
		)
		(fp_line
			(start -0.67945 -0.305054)
			(end -0.12065 -0.305054)
			(stroke
				(width 0.1)
				(type default)
			)
			(layer "F.Fab")
		)
		(fp_line
			(start -0.12065 -0.305054)
			(end -0.12065 -0.2794)
			(stroke
				(width 0.1)
				(type default)
			)
			(layer "F.Fab")
		)
		(pad "1" smd circle
			(at -0.40005 0 270)
			(size 0 0)
			(layers "F.Cu" "F.Mask" "F.Paste")
			(net "GND")
		)
		(pad "2" smd circle
			(at 0.40005 0 270)
			(size 0 0)
			(layers "F.Cu" "F.Mask" "F.Paste")
			(net "P3V3_SSD1")
		)
	)
	(footprint ""
		(layer "F.Cu")
		(at 307.045868 -46.4439 180)
		(property "Reference" "U73"
			(at 0.467868 -2.45237 0)
			(unlocked yes)
			(layer "F.SilkS")
			(effects
				(font
					(size 0.7874 0.5842)
					(thickness 0.1524)
				)
			)
		)
		(property "Value" ""
			(at 0 0 180)
			(layer "F.Fab")
			(effects
				(font
					(size 1.27 1.27)
				)
			)
		)
		(duplicate_pad_numbers_are_jumpers no)
		(fp_line
			(start 1.500124 1.500124)
			(end 1.004062 1.500124)
			(stroke
				(width 0.1524)
				(type default)
			)
			(layer "F.SilkS")
		)
		(fp_line
			(start 1.500124 1.004062)
			(end 1.500124 1.500124)
			(stroke
				(width 0.1524)
				(type default)
			)
			(layer "F.SilkS")
		)
		(fp_line
			(start 1.500124 -1.500124)
			(end 1.500124 -1.004062)
			(stroke
				(width 0.1524)
				(type default)
			)
			(layer "F.SilkS")
		)
		(fp_line
			(start 1.004062 -1.500124)
			(end 1.500124 -1.500124)
			(stroke
				(width 0.1524)
				(type default)
			)
			(layer "F.SilkS")
		)
		(fp_line
			(start -1.004062 1.500124)
			(end -1.500124 1.500124)
			(stroke
				(width 0.1524)
				(type default)
			)
			(layer "F.SilkS")
		)
		(fp_line
			(start -1.500124 1.500124)
			(end -1.500124 1.004062)
			(stroke
				(width 0.1524)
				(type default)
			)
			(layer "F.SilkS")
		)
		(fp_line
			(start -1.500124 -1.004062)
			(end -1.500124 -1.500124)
			(stroke
				(width 0.1524)
				(type default)
			)
			(layer "F.SilkS")
		)
		(fp_line
			(start -1.500124 -1.500124)
			(end -1.004062 -1.500124)
			(stroke
				(width 0.1524)
				(type default)
			)
			(layer "F.SilkS")
		)
		(fp_poly
			(pts
				(xy -1.96977 -2.297684) (xy -2.688336 -1.579118) (xy -1.610614 -1.219962)
			)
			(stroke
				(width 0)
				(type default)
			)
			(fill yes)
			(layer "F.SilkS")
		)
		(fp_line
			(start 1.500124 1.500124)
			(end -1.500124 1.500124)
			(stroke
				(width 0.1)
				(type default)
			)
			(layer "F.Fab")
		)
		(fp_line
			(start 1.500124 -1.500124)
			(end 1.500124 1.500124)
			(stroke
				(width 0.1)
				(type default)
			)
			(layer "F.Fab")
		)
		(fp_line
			(start -1.500124 1.500124)
			(end -1.500124 -1.500124)
			(stroke
				(width 0.1)
				(type default)
			)
			(layer "F.Fab")
		)
		(fp_line
			(start -1.500124 -1.500124)
			(end 1.500124 -1.500124)
			(stroke
				(width 0.1)
				(type default)
			)
			(layer "F.Fab")
		)
		(fp_poly
			(pts
				(xy -2.847848 -1.258062) (xy -2.847848 -0.242062) (xy -1.831848 -0.750062)
			)
			(stroke
				(width 0)
				(type default)
			)
			(fill yes)
			(layer "F.Fab")
		)
		(pad "1" smd rect
			(at -1.400048 -0.750062 90)
			(size 0.2286 0.6096)
			(layers "F.Cu" "F.Mask" "F.Paste")
			(net "SSD10_ADC_A1")
		)
		(pad "2" smd rect
			(at -1.400048 -0.249936 90)
			(size 0.2286 0.6096)
			(layers "F.Cu" "F.Mask" "F.Paste")
			(net "SSD10_ADC_A0")
		)
		(pad "3" smd rect
			(at -1.400048 0.249936 90)
			(size 0.2286 0.6096)
			(layers "F.Cu" "F.Mask" "F.Paste")
			(net "SSD10_ADC_ALERT_N")
		)
		(pad "4" smd rect
			(at -1.400048 0.750062 90)
			(size 0.2286 0.6096)
			(layers "F.Cu" "F.Mask" "F.Paste")
			(net "SMB_SSD10_ADC_SDA")
		)
		(pad "5" smd rect
			(at -0.750062 1.400048 180)
			(size 0.2286 0.6096)
			(layers "F.Cu" "F.Mask" "F.Paste")
			(net "SMB_SSD10_ADC_SCL")
		)
		(pad "6" smd rect
			(at -0.249936 1.400048 180)
			(size 0.2286 0.6096)
			(layers "F.Cu" "F.Mask" "F.Paste")
			(net "Net_8702")
		)
		(pad "7" smd rect
			(at 0.249936 1.400048 180)
			(size 0.2286 0.6096)
			(layers "F.Cu" "F.Mask" "F.Paste")
			(net "Net_8701")
		)
		(pad "8" smd rect
			(at 0.750062 1.400048 180)
			(size 0.2286 0.6096)
			(layers "F.Cu" "F.Mask" "F.Paste")
			(net "Net_8700")
		)
		(pad "9" smd rect
			(at 1.400048 0.750062 90)
			(size 0.2286 0.6096)
			(layers "F.Cu" "F.Mask" "F.Paste")
			(net "P3V3_AUX")
		)
		(pad "10" smd rect
			(at 1.400048 0.249936 90)
			(size 0.2286 0.6096)
			(layers "F.Cu" "F.Mask" "F.Paste")
			(net "GND")
		)
		(pad "11" smd rect
			(at 1.400048 -0.249936 90)
			(size 0.2286 0.6096)
			(layers "F.Cu" "F.Mask" "F.Paste")
			(net "P12V_SSD10_R")
		)
		(pad "12" smd rect
			(at 1.400048 -0.750062 90)
			(size 0.2286 0.6096)
			(layers "F.Cu" "F.Mask" "F.Paste")
			(net "P12V_SSD10_VIN_N")
		)
		(pad "13" smd rect
			(at 0.750062 -1.400048 180)
			(size 0.2286 0.6096)
			(layers "F.Cu" "F.Mask" "F.Paste")
			(net "P12V_SSD10_VIN_P")
		)
		(pad "14" smd rect
			(at 0.249936 -1.400048 180)
			(size 0.2286 0.6096)
			(layers "F.Cu" "F.Mask" "F.Paste")
			(net "Net_8699")
		)
		(pad "15" smd rect
			(at -0.249936 -1.400048 180)
			(size 0.2286 0.6096)
			(layers "F.Cu" "F.Mask" "F.Paste")
			(net "Net_8698")
		)
		(pad "16" smd rect
			(at -0.750062 -1.400048 180)
			(size 0.2286 0.6096)
			(layers "F.Cu" "F.Mask" "F.Paste")
			(net "Net_8697")
		)
		(pad "TH" smd rect
			(at 0 0 180)
			(size 1.7018 1.7018)
			(layers "F.Cu" "F.Mask" "F.Paste")
			(net "GND")
		)
		(zone
			(layer "F.Cu")
			(hatch none 0.5)
			(connect_pads
				(clearance 0)
			)
			(min_thickness 0.25)
			(keepout
				(tracks not_allowed)
				(vias allowed)
				(pads allowed)
				(copperpour not_allowed)
				(footprints allowed)
			)
			(placement
				(enabled no)
				(sheetname "")
			)
			(fill
				(thermal_gap 0.5)
				(thermal_bridge_width 0.5)
				(island_removal_mode 0)
			)
			(polygon
				(pts
					(xy 308.090316 -46.4185) (xy 308.090316 -45.399452) (xy 306.00142 -45.399452) (xy 306.00142 -47.488348)
					(xy 308.090316 -47.488348) (xy 308.090316 -46.4439) (xy 307.947568 -46.4439) (xy 307.947568 -47.3456)
					(xy 306.144168 -47.3456) (xy 306.144168 -45.5422) (xy 307.947568 -45.5422) (xy 307.947568 -46.4185)
				)
			)
		)
	)
	(footprint ""
		(layer "F.Cu")
		(at 356.349808 -159.844994 180)
		(property "Reference" "PR7052"
			(at 0 0 180)
			(layer "F.SilkS")
			(hide yes)
			(effects
				(font
					(size 1.27 1.27)
				)
			)
		)
		(property "Value" ""
			(at 0 0 180)
			(layer "F.Fab")
			(effects
				(font
					(size 1.27 1.27)
				)
			)
		)
		(duplicate_pad_numbers_are_jumpers no)
		(fp_line
			(start 0.7874 0.4064)
			(end -0.7874 0.4064)
			(stroke
				(width 0.1524)
				(type default)
			)
			(layer "F.SilkS")
		)
		(fp_line
			(start 0.7874 -0.4064)
			(end 0.7874 0.4064)
			(stroke
				(width 0.1524)
				(type default)
			)
			(layer "F.SilkS")
		)
		(fp_line
			(start -0.7874 0.4064)
			(end -0.7874 -0.4064)
			(stroke
				(width 0.1524)
				(type default)
			)
			(layer "F.SilkS")
		)
		(fp_line
			(start -0.7874 -0.4064)
			(end 0.7874 -0.4064)
			(stroke
				(width 0.1524)
				(type default)
			)
			(layer "F.SilkS")
		)
		(fp_line
			(start 0.67945 0.3048)
			(end 0.120396 0.3048)
			(stroke
				(width 0.1)
				(type default)
			)
			(layer "F.Fab")
		)
		(fp_line
			(start 0.67945 -0.3048)
			(end 0.67945 0.3048)
			(stroke
				(width 0.1)
				(type default)
			)
			(layer "F.Fab")
		)
		(fp_line
			(start 0.12065 -0.2794)
			(end 0.12065 -0.3048)
			(stroke
				(width 0.1)
				(type default)
			)
			(layer "F.Fab")
		)
		(fp_line
			(start 0.12065 -0.3048)
			(end 0.67945 -0.3048)
			(stroke
				(width 0.1)
				(type default)
			)
			(layer "F.Fab")
		)
		(fp_line
			(start 0.120396 0.3048)
			(end 0.120396 0.2794)
			(stroke
				(width 0.1)
				(type default)
			)
			(layer "F.Fab")
		)
		(fp_line
			(start 0.120396 0.2794)
			(end -0.12065 0.2794)
			(stroke
				(width 0.1)
				(type default)
			)
			(layer "F.Fab")
		)
		(fp_line
			(start -0.12065 0.3048)
			(end -0.67945 0.3048)
			(stroke
				(width 0.1)
				(type default)
			)
			(layer "F.Fab")
		)
		(fp_line
			(start -0.12065 0.2794)
			(end -0.12065 0.3048)
			(stroke
				(width 0.1)
				(type default)
			)
			(layer "F.Fab")
		)
		(fp_line
			(start -0.12065 -0.2794)
			(end 0.12065 -0.2794)
			(stroke
				(width 0.1)
				(type default)
			)
			(layer "F.Fab")
		)
		(fp_line
			(start -0.12065 -0.305054)
			(end -0.12065 -0.2794)
			(stroke
				(width 0.1)
				(type default)
			)
			(layer "F.Fab")
		)
		(fp_line
			(start -0.67945 0.3048)
			(end -0.67945 -0.305054)
			(stroke
				(width 0.1)
				(type default)
			)
			(layer "F.Fab")
		)
		(fp_line
			(start -0.67945 -0.305054)
			(end -0.12065 -0.305054)
			(stroke
				(width 0.1)
				(type default)
			)
			(layer "F.Fab")
		)
		(pad "1" smd circle
			(at -0.40005 0 180)
			(size 0 0)
			(layers "F.Cu" "F.Mask" "F.Paste")
			(net "P12V_NIC6_CO_FLTB")
		)
		(pad "2" smd circle
			(at 0.40005 0 180)
			(size 0 0)
			(layers "F.Cu" "F.Mask" "F.Paste")
			(net "P3V3_AUX")
		)
	)
	(footprint ""
		(layer "F.Cu")
		(at 338.074 -169.037 180)
		(property "Reference" "R4770"
			(at 0 0 180)
			(layer "F.SilkS")
			(hide yes)
			(effects
				(font
					(size 1.27 1.27)
				)
			)
		)
		(property "Value" ""
			(at 0 0 180)
			(layer "F.Fab")
			(effects
				(font
					(size 1.27 1.27)
				)
			)
		)
		(duplicate_pad_numbers_are_jumpers no)
		(fp_line
			(start 0.7874 0.4064)
			(end -0.7874 0.4064)
			(stroke
				(width 0.1524)
				(type default)
			)
			(layer "F.SilkS")
		)
		(fp_line
			(start 0.7874 -0.4064)
			(end 0.7874 0.4064)
			(stroke
				(width 0.1524)
				(type default)
			)
			(layer "F.SilkS")
		)
		(fp_line
			(start -0.7874 0.4064)
			(end -0.7874 -0.4064)
			(stroke
				(width 0.1524)
				(type default)
			)
			(layer "F.SilkS")
		)
		(fp_line
			(start -0.7874 -0.4064)
			(end 0.7874 -0.4064)
			(stroke
				(width 0.1524)
				(type default)
			)
			(layer "F.SilkS")
		)
		(fp_line
			(start 0.67945 0.3048)
			(end 0.120396 0.3048)
			(stroke
				(width 0.1)
				(type default)
			)
			(layer "F.Fab")
		)
		(fp_line
			(start 0.67945 -0.3048)
			(end 0.67945 0.3048)
			(stroke
				(width 0.1)
				(type default)
			)
			(layer "F.Fab")
		)
		(fp_line
			(start 0.12065 -0.2794)
			(end 0.12065 -0.3048)
			(stroke
				(width 0.1)
				(type default)
			)
			(layer "F.Fab")
		)
		(fp_line
			(start 0.12065 -0.3048)
			(end 0.67945 -0.3048)
			(stroke
				(width 0.1)
				(type default)
			)
			(layer "F.Fab")
		)
		(fp_line
			(start 0.120396 0.3048)
			(end 0.120396 0.2794)
			(stroke
				(width 0.1)
				(type default)
			)
			(layer "F.Fab")
		)
		(fp_line
			(start 0.120396 0.2794)
			(end -0.12065 0.2794)
			(stroke
				(width 0.1)
				(type default)
			)
			(layer "F.Fab")
		)
		(fp_line
			(start -0.12065 0.3048)
			(end -0.67945 0.3048)
			(stroke
				(width 0.1)
				(type default)
			)
			(layer "F.Fab")
		)
		(fp_line
			(start -0.12065 0.2794)
			(end -0.12065 0.3048)
			(stroke
				(width 0.1)
				(type default)
			)
			(layer "F.Fab")
		)
		(fp_line
			(start -0.12065 -0.2794)
			(end 0.12065 -0.2794)
			(stroke
				(width 0.1)
				(type default)
			)
			(layer "F.Fab")
		)
		(fp_line
			(start -0.12065 -0.305054)
			(end -0.12065 -0.2794)
			(stroke
				(width 0.1)
				(type default)
			)
			(layer "F.Fab")
		)
		(fp_line
			(start -0.67945 0.3048)
			(end -0.67945 -0.305054)
			(stroke
				(width 0.1)
				(type default)
			)
			(layer "F.Fab")
		)
		(fp_line
			(start -0.67945 -0.305054)
			(end -0.12065 -0.305054)
			(stroke
				(width 0.1)
				(type default)
			)
			(layer "F.Fab")
		)
		(pad "1" smd circle
			(at -0.40005 0 180)
			(size 0 0)
			(layers "F.Cu" "F.Mask" "F.Paste")
			(net "RST_PEX_SSD10_PERST_N")
		)
		(pad "2" smd circle
			(at 0.40005 0 180)
			(size 0 0)
			(layers "F.Cu" "F.Mask" "F.Paste")
			(net "RST_PEX_SSD10_PERST_R_N")
		)
	)
	(footprint ""
		(layer "F.Cu")
		(at 152.634442 -252.356874 -90)
		(property "Reference" "R1295"
			(at 0 0 270)
			(layer "F.SilkS")
			(hide yes)
			(effects
				(font
					(size 1.27 1.27)
				)
			)
		)
		(property "Value" ""
			(at 0 0 270)
			(layer "F.Fab")
			(effects
				(font
					(size 1.27 1.27)
				)
			)
		)
		(duplicate_pad_numbers_are_jumpers no)
		(fp_line
			(start -0.7874 0.4064)
			(end -0.7874 -0.4064)
			(stroke
				(width 0.1524)
				(type default)
			)
			(layer "F.SilkS")
		)
		(fp_line
			(start 0.7874 0.4064)
			(end -0.7874 0.4064)
			(stroke
				(width 0.1524)
				(type default)
			)
			(layer "F.SilkS")
		)
		(fp_line
			(start -0.7874 -0.4064)
			(end 0.7874 -0.4064)
			(stroke
				(width 0.1524)
				(type default)
			)
			(layer "F.SilkS")
		)
		(fp_line
			(start 0.7874 -0.4064)
			(end 0.7874 0.4064)
			(stroke
				(width 0.1524)
				(type default)
			)
			(layer "F.SilkS")
		)
		(fp_line
			(start -0.67945 0.3048)
			(end -0.67945 -0.305054)
			(stroke
				(width 0.1)
				(type default)
			)
			(layer "F.Fab")
		)
		(fp_line
			(start -0.12065 0.3048)
			(end -0.67945 0.3048)
			(stroke
				(width 0.1)
				(type default)
			)
			(layer "F.Fab")
		)
		(fp_line
			(start 0.120396 0.3048)
			(end 0.120396 0.2794)
			(stroke
				(width 0.1)
				(type default)
			)
			(layer "F.Fab")
		)
		(fp_line
			(start 0.67945 0.3048)
			(end 0.120396 0.3048)
			(stroke
				(width 0.1)
				(type default)
			)
			(layer "F.Fab")
		)
		(fp_line
			(start -0.12065 0.2794)
			(end -0.12065 0.3048)
			(stroke
				(width 0.1)
				(type default)
			)
			(layer "F.Fab")
		)
		(fp_line
			(start 0.120396 0.2794)
			(end -0.12065 0.2794)
			(stroke
				(width 0.1)
				(type default)
			)
			(layer "F.Fab")
		)
		(fp_line
			(start -0.12065 -0.2794)
			(end 0.12065 -0.2794)
			(stroke
				(width 0.1)
				(type default)
			)
			(layer "F.Fab")
		)
		(fp_line
			(start 0.12065 -0.2794)
			(end 0.12065 -0.3048)
			(stroke
				(width 0.1)
				(type default)
			)
			(layer "F.Fab")
		)
		(fp_line
			(start 0.12065 -0.3048)
			(end 0.67945 -0.3048)
			(stroke
				(width 0.1)
				(type default)
			)
			(layer "F.Fab")
		)
		(fp_line
			(start 0.67945 -0.3048)
			(end 0.67945 0.3048)
			(stroke
				(width 0.1)
				(type default)
			)
			(layer "F.Fab")
		)
		(fp_line
			(start -0.67945 -0.305054)
			(end -0.12065 -0.305054)
			(stroke
				(width 0.1)
				(type default)
			)
			(layer "F.Fab")
		)
		(fp_line
			(start -0.12065 -0.305054)
			(end -0.12065 -0.2794)
			(stroke
				(width 0.1)
				(type default)
			)
			(layer "F.Fab")
		)
		(pad "1" smd circle
			(at -0.40005 0 270)
			(size 0 0)
			(layers "F.Cu" "F.Mask" "F.Paste")
			(net "GND")
		)
		(pad "2" smd circle
			(at 0.40005 0 270)
			(size 0 0)
			(layers "F.Cu" "F.Mask" "F.Paste")
			(net "PEX1_MODE_SEL6")
		)
	)
	(footprint ""
		(layer "F.Cu")
		(at 361.188 -190.246 180)
		(property "Reference" "R4642"
			(at 0 0 180)
			(layer "F.SilkS")
			(hide yes)
			(effects
				(font
					(size 1.27 1.27)
				)
			)
		)
		(property "Value" ""
			(at 0 0 180)
			(layer "F.Fab")
			(effects
				(font
					(size 1.27 1.27)
				)
			)
		)
		(duplicate_pad_numbers_are_jumpers no)
		(fp_line
			(start 0.7874 0.4064)
			(end -0.7874 0.4064)
			(stroke
				(width 0.1524)
				(type default)
			)
			(layer "F.SilkS")
		)
		(fp_line
			(start 0.7874 -0.4064)
			(end 0.7874 0.4064)
			(stroke
				(width 0.1524)
				(type default)
			)
			(layer "F.SilkS")
		)
		(fp_line
			(start -0.7874 0.4064)
			(end -0.7874 -0.4064)
			(stroke
				(width 0.1524)
				(type default)
			)
			(layer "F.SilkS")
		)
		(fp_line
			(start -0.7874 -0.4064)
			(end 0.7874 -0.4064)
			(stroke
				(width 0.1524)
				(type default)
			)
			(layer "F.SilkS")
		)
		(fp_line
			(start 0.67945 0.3048)
			(end 0.120396 0.3048)
			(stroke
				(width 0.1)
				(type default)
			)
			(layer "F.Fab")
		)
		(fp_line
			(start 0.67945 -0.3048)
			(end 0.67945 0.3048)
			(stroke
				(width 0.1)
				(type default)
			)
			(layer "F.Fab")
		)
		(fp_line
			(start 0.12065 -0.2794)
			(end 0.12065 -0.3048)
			(stroke
				(width 0.1)
				(type default)
			)
			(layer "F.Fab")
		)
		(fp_line
			(start 0.12065 -0.3048)
			(end 0.67945 -0.3048)
			(stroke
				(width 0.1)
				(type default)
			)
			(layer "F.Fab")
		)
		(fp_line
			(start 0.120396 0.3048)
			(end 0.120396 0.2794)
			(stroke
				(width 0.1)
				(type default)
			)
			(layer "F.Fab")
		)
		(fp_line
			(start 0.120396 0.2794)
			(end -0.12065 0.2794)
			(stroke
				(width 0.1)
				(type default)
			)
			(layer "F.Fab")
		)
		(fp_line
			(start -0.12065 0.3048)
			(end -0.67945 0.3048)
			(stroke
				(width 0.1)
				(type default)
			)
			(layer "F.Fab")
		)
		(fp_line
			(start -0.12065 0.2794)
			(end -0.12065 0.3048)
			(stroke
				(width 0.1)
				(type default)
			)
			(layer "F.Fab")
		)
		(fp_line
			(start -0.12065 -0.2794)
			(end 0.12065 -0.2794)
			(stroke
				(width 0.1)
				(type default)
			)
			(layer "F.Fab")
		)
		(fp_line
			(start -0.12065 -0.305054)
			(end -0.12065 -0.2794)
			(stroke
				(width 0.1)
				(type default)
			)
			(layer "F.Fab")
		)
		(fp_line
			(start -0.67945 0.3048)
			(end -0.67945 -0.305054)
			(stroke
				(width 0.1)
				(type default)
			)
			(layer "F.Fab")
		)
		(fp_line
			(start -0.67945 -0.305054)
			(end -0.12065 -0.305054)
			(stroke
				(width 0.1)
				(type default)
			)
			(layer "F.Fab")
		)
		(pad "1" smd circle
			(at -0.40005 0 180)
			(size 0 0)
			(layers "F.Cu" "F.Mask" "F.Paste")
			(net "PRSNT_SSD2_FPGA_PCA9555_N")
		)
		(pad "2" smd circle
			(at 0.40005 0 180)
			(size 0 0)
			(layers "F.Cu" "F.Mask" "F.Paste")
			(net "PRSNT_SSD2_FPGA_R_N")
		)
	)
	(footprint ""
		(layer "F.Cu")
		(at 52.243736 -45.88891)
		(property "Reference" "R519"
			(at 0 0 0)
			(layer "F.SilkS")
			(hide yes)
			(effects
				(font
					(size 1.27 1.27)
				)
			)
		)
		(property "Value" ""
			(at 0 0 0)
			(layer "F.Fab")
			(effects
				(font
					(size 1.27 1.27)
				)
			)
		)
		(duplicate_pad_numbers_are_jumpers no)
		(fp_line
			(start -0.7874 -0.4064)
			(end 0.7874 -0.4064)
			(stroke
				(width 0.1524)
				(type default)
			)
			(layer "F.SilkS")
		)
		(fp_line
			(start -0.7874 0.4064)
			(end -0.7874 -0.4064)
			(stroke
				(width 0.1524)
				(type default)
			)
			(layer "F.SilkS")
		)
		(fp_line
			(start 0.7874 -0.4064)
			(end 0.7874 0.4064)
			(stroke
				(width 0.1524)
				(type default)
			)
			(layer "F.SilkS")
		)
		(fp_line
			(start 0.7874 0.4064)
			(end -0.7874 0.4064)
			(stroke
				(width 0.1524)
				(type default)
			)
			(layer "F.SilkS")
		)
		(fp_line
			(start -0.67945 -0.305054)
			(end -0.12065 -0.305054)
			(stroke
				(width 0.1)
				(type default)
			)
			(layer "F.Fab")
		)
		(fp_line
			(start -0.67945 0.3048)
			(end -0.67945 -0.305054)
			(stroke
				(width 0.1)
				(type default)
			)
			(layer "F.Fab")
		)
		(fp_line
			(start -0.12065 -0.305054)
			(end -0.12065 -0.2794)
			(stroke
				(width 0.1)
				(type default)
			)
			(layer "F.Fab")
		)
		(fp_line
			(start -0.12065 -0.2794)
			(end 0.12065 -0.2794)
			(stroke
				(width 0.1)
				(type default)
			)
			(layer "F.Fab")
		)
		(fp_line
			(start -0.12065 0.2794)
			(end -0.12065 0.3048)
			(stroke
				(width 0.1)
				(type default)
			)
			(layer "F.Fab")
		)
		(fp_line
			(start -0.12065 0.3048)
			(end -0.67945 0.3048)
			(stroke
				(width 0.1)
				(type default)
			)
			(layer "F.Fab")
		)
		(fp_line
			(start 0.120396 0.2794)
			(end -0.12065 0.2794)
			(stroke
				(width 0.1)
				(type default)
			)
			(layer "F.Fab")
		)
		(fp_line
			(start 0.120396 0.3048)
			(end 0.120396 0.2794)
			(stroke
				(width 0.1)
				(type default)
			)
			(layer "F.Fab")
		)
		(fp_line
			(start 0.12065 -0.3048)
			(end 0.67945 -0.3048)
			(stroke
				(width 0.1)
				(type default)
			)
			(layer "F.Fab")
		)
		(fp_line
			(start 0.12065 -0.2794)
			(end 0.12065 -0.3048)
			(stroke
				(width 0.1)
				(type default)
			)
			(layer "F.Fab")
		)
		(fp_line
			(start 0.67945 -0.3048)
			(end 0.67945 0.3048)
			(stroke
				(width 0.1)
				(type default)
			)
			(layer "F.Fab")
		)
		(fp_line
			(start 0.67945 0.3048)
			(end 0.120396 0.3048)
			(stroke
				(width 0.1)
				(type default)
			)
			(layer "F.Fab")
		)
		(pad "1" smd circle
			(at -0.40005 0)
			(size 0 0)
			(layers "F.Cu" "F.Mask" "F.Paste")
			(net "SSD1_ADC_A0")
		)
		(pad "2" smd circle
			(at 0.40005 0)
			(size 0 0)
			(layers "F.Cu" "F.Mask" "F.Paste")
			(net "GND")
		)
	)
	(footprint ""
		(layer "F.Cu")
		(at 443.922658 -22.867366 90)
		(property "Reference" "C3979"
			(at 0 0 90)
			(layer "F.SilkS")
			(hide yes)
			(effects
				(font
					(size 1.27 1.27)
				)
			)
		)
		(property "Value" ""
			(at 0 0 90)
			(layer "F.Fab")
			(effects
				(font
					(size 1.27 1.27)
				)
			)
		)
		(duplicate_pad_numbers_are_jumpers no)
		(fp_line
			(start 0.7874 -0.4064)
			(end 0.7874 0.4064)
			(stroke
				(width 0.1524)
				(type default)
			)
			(layer "F.SilkS")
		)
		(fp_line
			(start -0.7874 -0.4064)
			(end 0.7874 -0.4064)
			(stroke
				(width 0.1524)
				(type default)
			)
			(layer "F.SilkS")
		)
		(fp_line
			(start 0.7874 0.4064)
			(end -0.7874 0.4064)
			(stroke
				(width 0.1524)
				(type default)
			)
			(layer "F.SilkS")
		)
		(fp_line
			(start -0.7874 0.4064)
			(end -0.7874 -0.4064)
			(stroke
				(width 0.1524)
				(type default)
			)
			(layer "F.SilkS")
		)
		(fp_line
			(start -0.12065 -0.305054)
			(end -0.12065 -0.2794)
			(stroke
				(width 0.1)
				(type default)
			)
			(layer "F.Fab")
		)
		(fp_line
			(start -0.67945 -0.305054)
			(end -0.12065 -0.305054)
			(stroke
				(width 0.1)
				(type default)
			)
			(layer "F.Fab")
		)
		(fp_line
			(start 0.67945 -0.3048)
			(end 0.67945 0.3048)
			(stroke
				(width 0.1)
				(type default)
			)
			(layer "F.Fab")
		)
		(fp_line
			(start 0.12065 -0.3048)
			(end 0.67945 -0.3048)
			(stroke
				(width 0.1)
				(type default)
			)
			(layer "F.Fab")
		)
		(fp_line
			(start 0.12065 -0.2794)
			(end 0.12065 -0.3048)
			(stroke
				(width 0.1)
				(type default)
			)
			(layer "F.Fab")
		)
		(fp_line
			(start -0.12065 -0.2794)
			(end 0.12065 -0.2794)
			(stroke
				(width 0.1)
				(type default)
			)
			(layer "F.Fab")
		)
		(fp_line
			(start 0.120396 0.2794)
			(end -0.12065 0.2794)
			(stroke
				(width 0.1)
				(type default)
			)
			(layer "F.Fab")
		)
		(fp_line
			(start -0.12065 0.2794)
			(end -0.12065 0.3048)
			(stroke
				(width 0.1)
				(type default)
			)
			(layer "F.Fab")
		)
		(fp_line
			(start 0.67945 0.3048)
			(end 0.120396 0.3048)
			(stroke
				(width 0.1)
				(type default)
			)
			(layer "F.Fab")
		)
		(fp_line
			(start 0.120396 0.3048)
			(end 0.120396 0.2794)
			(stroke
				(width 0.1)
				(type default)
			)
			(layer "F.Fab")
		)
		(fp_line
			(start -0.12065 0.3048)
			(end -0.67945 0.3048)
			(stroke
				(width 0.1)
				(type default)
			)
			(layer "F.Fab")
		)
		(fp_line
			(start -0.67945 0.3048)
			(end -0.67945 -0.305054)
			(stroke
				(width 0.1)
				(type default)
			)
			(layer "F.Fab")
		)
		(pad "1" smd circle
			(at -0.40005 0 90)
			(size 0 0)
			(layers "F.Cu" "F.Mask" "F.Paste")
			(net "P12V_SSD15")
		)
		(pad "2" smd circle
			(at 0.40005 0 90)
			(size 0 0)
			(layers "F.Cu" "F.Mask" "F.Paste")
			(net "GND")
		)
	)
	(footprint ""
		(layer "F.Cu")
		(at 86.120478 -26.666444 -90)
		(property "Reference" "R4059"
			(at 0 0 270)
			(layer "F.SilkS")
			(hide yes)
			(effects
				(font
					(size 1.27 1.27)
				)
			)
		)
		(property "Value" ""
			(at 0 0 270)
			(layer "F.Fab")
			(effects
				(font
					(size 1.27 1.27)
				)
			)
		)
		(duplicate_pad_numbers_are_jumpers no)
		(fp_line
			(start -0.7874 0.4064)
			(end -0.7874 -0.4064)
			(stroke
				(width 0.1524)
				(type default)
			)
			(layer "F.SilkS")
		)
		(fp_line
			(start 0.7874 0.4064)
			(end -0.7874 0.4064)
			(stroke
				(width 0.1524)
				(type default)
			)
			(layer "F.SilkS")
		)
		(fp_line
			(start -0.7874 -0.4064)
			(end 0.7874 -0.4064)
			(stroke
				(width 0.1524)
				(type default)
			)
			(layer "F.SilkS")
		)
		(fp_line
			(start 0.7874 -0.4064)
			(end 0.7874 0.4064)
			(stroke
				(width 0.1524)
				(type default)
			)
			(layer "F.SilkS")
		)
		(fp_line
			(start -0.67945 0.3048)
			(end -0.67945 -0.305054)
			(stroke
				(width 0.1)
				(type default)
			)
			(layer "F.Fab")
		)
		(fp_line
			(start -0.12065 0.3048)
			(end -0.67945 0.3048)
			(stroke
				(width 0.1)
				(type default)
			)
			(layer "F.Fab")
		)
		(fp_line
			(start 0.120396 0.3048)
			(end 0.120396 0.2794)
			(stroke
				(width 0.1)
				(type default)
			)
			(layer "F.Fab")
		)
		(fp_line
			(start 0.67945 0.3048)
			(end 0.120396 0.3048)
			(stroke
				(width 0.1)
				(type default)
			)
			(layer "F.Fab")
		)
		(fp_line
			(start -0.12065 0.2794)
			(end -0.12065 0.3048)
			(stroke
				(width 0.1)
				(type default)
			)
			(layer "F.Fab")
		)
		(fp_line
			(start 0.120396 0.2794)
			(end -0.12065 0.2794)
			(stroke
				(width 0.1)
				(type default)
			)
			(layer "F.Fab")
		)
		(fp_line
			(start -0.12065 -0.2794)
			(end 0.12065 -0.2794)
			(stroke
				(width 0.1)
				(type default)
			)
			(layer "F.Fab")
		)
		(fp_line
			(start 0.12065 -0.2794)
			(end 0.12065 -0.3048)
			(stroke
				(width 0.1)
				(type default)
			)
			(layer "F.Fab")
		)
		(fp_line
			(start 0.12065 -0.3048)
			(end 0.67945 -0.3048)
			(stroke
				(width 0.1)
				(type default)
			)
			(layer "F.Fab")
		)
		(fp_line
			(start 0.67945 -0.3048)
			(end 0.67945 0.3048)
			(stroke
				(width 0.1)
				(type default)
			)
			(layer "F.Fab")
		)
		(fp_line
			(start -0.67945 -0.305054)
			(end -0.12065 -0.305054)
			(stroke
				(width 0.1)
				(type default)
			)
			(layer "F.Fab")
		)
		(fp_line
			(start -0.12065 -0.305054)
			(end -0.12065 -0.2794)
			(stroke
				(width 0.1)
				(type default)
			)
			(layer "F.Fab")
		)
		(pad "1" smd circle
			(at -0.40005 0 270)
			(size 0 0)
			(layers "F.Cu" "F.Mask" "F.Paste")
			(net "PRSNT_SSD3_R_N")
		)
		(pad "2" smd circle
			(at 0.40005 0 270)
			(size 0 0)
			(layers "F.Cu" "F.Mask" "F.Paste")
			(net "PRSNT_SSD3_N")
		)
	)
	(footprint ""
		(layer "F.Cu")
		(at 236.018324 -202.760834)
		(property "Reference" "R4857"
			(at 0 0 0)
			(layer "F.SilkS")
			(hide yes)
			(effects
				(font
					(size 1.27 1.27)
				)
			)
		)
		(property "Value" ""
			(at 0 0 0)
			(layer "F.Fab")
			(effects
				(font
					(size 1.27 1.27)
				)
			)
		)
		(duplicate_pad_numbers_are_jumpers no)
		(fp_line
			(start -0.7874 -0.4064)
			(end 0.7874 -0.4064)
			(stroke
				(width 0.1524)
				(type default)
			)
			(layer "F.SilkS")
		)
		(fp_line
			(start -0.7874 0.4064)
			(end -0.7874 -0.4064)
			(stroke
				(width 0.1524)
				(type default)
			)
			(layer "F.SilkS")
		)
		(fp_line
			(start 0.7874 -0.4064)
			(end 0.7874 0.4064)
			(stroke
				(width 0.1524)
				(type default)
			)
			(layer "F.SilkS")
		)
		(fp_line
			(start 0.7874 0.4064)
			(end -0.7874 0.4064)
			(stroke
				(width 0.1524)
				(type default)
			)
			(layer "F.SilkS")
		)
		(fp_line
			(start -0.67945 -0.305054)
			(end -0.12065 -0.305054)
			(stroke
				(width 0.1)
				(type default)
			)
			(layer "F.Fab")
		)
		(fp_line
			(start -0.67945 0.3048)
			(end -0.67945 -0.305054)
			(stroke
				(width 0.1)
				(type default)
			)
			(layer "F.Fab")
		)
		(fp_line
			(start -0.12065 -0.305054)
			(end -0.12065 -0.2794)
			(stroke
				(width 0.1)
				(type default)
			)
			(layer "F.Fab")
		)
		(fp_line
			(start -0.12065 -0.2794)
			(end 0.12065 -0.2794)
			(stroke
				(width 0.1)
				(type default)
			)
			(layer "F.Fab")
		)
		(fp_line
			(start -0.12065 0.2794)
			(end -0.12065 0.3048)
			(stroke
				(width 0.1)
				(type default)
			)
			(layer "F.Fab")
		)
		(fp_line
			(start -0.12065 0.3048)
			(end -0.67945 0.3048)
			(stroke
				(width 0.1)
				(type default)
			)
			(layer "F.Fab")
		)
		(fp_line
			(start 0.120396 0.2794)
			(end -0.12065 0.2794)
			(stroke
				(width 0.1)
				(type default)
			)
			(layer "F.Fab")
		)
		(fp_line
			(start 0.120396 0.3048)
			(end 0.120396 0.2794)
			(stroke
				(width 0.1)
				(type default)
			)
			(layer "F.Fab")
		)
		(fp_line
			(start 0.12065 -0.3048)
			(end 0.67945 -0.3048)
			(stroke
				(width 0.1)
				(type default)
			)
			(layer "F.Fab")
		)
		(fp_line
			(start 0.12065 -0.2794)
			(end 0.12065 -0.3048)
			(stroke
				(width 0.1)
				(type default)
			)
			(layer "F.Fab")
		)
		(fp_line
			(start 0.67945 -0.3048)
			(end 0.67945 0.3048)
			(stroke
				(width 0.1)
				(type default)
			)
			(layer "F.Fab")
		)
		(fp_line
			(start 0.67945 0.3048)
			(end 0.120396 0.3048)
			(stroke
				(width 0.1)
				(type default)
			)
			(layer "F.Fab")
		)
		(pad "1" smd circle
			(at -0.40005 0)
			(size 0 0)
			(layers "F.Cu" "F.Mask" "F.Paste")
			(net "P3V3_LED")
		)
		(pad "2" smd circle
			(at 0.40005 0)
			(size 0 0)
			(layers "F.Cu" "F.Mask" "F.Paste")
			(net "BMC_HEARTBEAT_N_D")
		)
	)
	(footprint ""
		(layer "F.Cu")
		(at 311.326022 -39.73576 -90)
		(property "Reference" "R5581"
			(at 0 0 270)
			(layer "F.SilkS")
			(hide yes)
			(effects
				(font
					(size 1.27 1.27)
				)
			)
		)
		(property "Value" ""
			(at 0 0 270)
			(layer "F.Fab")
			(effects
				(font
					(size 1.27 1.27)
				)
			)
		)
		(duplicate_pad_numbers_are_jumpers no)
		(fp_line
			(start -0.7874 0.4064)
			(end -0.7874 -0.4064)
			(stroke
				(width 0.1524)
				(type default)
			)
			(layer "F.SilkS")
		)
		(fp_line
			(start 0.7874 0.4064)
			(end -0.7874 0.4064)
			(stroke
				(width 0.1524)
				(type default)
			)
			(layer "F.SilkS")
		)
		(fp_line
			(start -0.7874 -0.4064)
			(end 0.7874 -0.4064)
			(stroke
				(width 0.1524)
				(type default)
			)
			(layer "F.SilkS")
		)
		(fp_line
			(start 0.7874 -0.4064)
			(end 0.7874 0.4064)
			(stroke
				(width 0.1524)
				(type default)
			)
			(layer "F.SilkS")
		)
		(fp_line
			(start -0.67945 0.3048)
			(end -0.67945 -0.305054)
			(stroke
				(width 0.1)
				(type default)
			)
			(layer "F.Fab")
		)
		(fp_line
			(start -0.12065 0.3048)
			(end -0.67945 0.3048)
			(stroke
				(width 0.1)
				(type default)
			)
			(layer "F.Fab")
		)
		(fp_line
			(start 0.120396 0.3048)
			(end 0.120396 0.2794)
			(stroke
				(width 0.1)
				(type default)
			)
			(layer "F.Fab")
		)
		(fp_line
			(start 0.67945 0.3048)
			(end 0.120396 0.3048)
			(stroke
				(width 0.1)
				(type default)
			)
			(layer "F.Fab")
		)
		(fp_line
			(start -0.12065 0.2794)
			(end -0.12065 0.3048)
			(stroke
				(width 0.1)
				(type default)
			)
			(layer "F.Fab")
		)
		(fp_line
			(start 0.120396 0.2794)
			(end -0.12065 0.2794)
			(stroke
				(width 0.1)
				(type default)
			)
			(layer "F.Fab")
		)
		(fp_line
			(start -0.12065 -0.2794)
			(end 0.12065 -0.2794)
			(stroke
				(width 0.1)
				(type default)
			)
			(layer "F.Fab")
		)
		(fp_line
			(start 0.12065 -0.2794)
			(end 0.12065 -0.3048)
			(stroke
				(width 0.1)
				(type default)
			)
			(layer "F.Fab")
		)
		(fp_line
			(start 0.12065 -0.3048)
			(end 0.67945 -0.3048)
			(stroke
				(width 0.1)
				(type default)
			)
			(layer "F.Fab")
		)
		(fp_line
			(start 0.67945 -0.3048)
			(end 0.67945 0.3048)
			(stroke
				(width 0.1)
				(type default)
			)
			(layer "F.Fab")
		)
		(fp_line
			(start -0.67945 -0.305054)
			(end -0.12065 -0.305054)
			(stroke
				(width 0.1)
				(type default)
			)
			(layer "F.Fab")
		)
		(fp_line
			(start -0.12065 -0.305054)
			(end -0.12065 -0.2794)
			(stroke
				(width 0.1)
				(type default)
			)
			(layer "F.Fab")
		)
		(pad "1" smd circle
			(at -0.40005 0 270)
			(size 0 0)
			(layers "F.Cu" "F.Mask" "F.Paste")
			(net "P3V3_AUX")
		)
		(pad "2" smd circle
			(at 0.40005 0 270)
			(size 0 0)
			(layers "F.Cu" "F.Mask" "F.Paste")
			(net "SSD11_AUX_P3V3_EN")
		)
	)
	(footprint ""
		(layer "F.Cu")
		(at 148.260562 -237.923578 180)
		(property "Reference" "C4421"
			(at 0 0 180)
			(layer "F.SilkS")
			(hide yes)
			(effects
				(font
					(size 1.27 1.27)
				)
			)
		)
		(property "Value" ""
			(at 0 0 180)
			(layer "F.Fab")
			(effects
				(font
					(size 1.27 1.27)
				)
			)
		)
		(duplicate_pad_numbers_are_jumpers no)
		(fp_line
			(start 1.524 0.762)
			(end -1.524 0.762)
			(stroke
				(width 0.1524)
				(type default)
			)
			(layer "F.SilkS")
		)
		(fp_line
			(start 1.524 -0.762)
			(end 1.524 0.762)
			(stroke
				(width 0.1524)
				(type default)
			)
			(layer "F.SilkS")
		)
		(fp_line
			(start -1.524 0.762)
			(end -1.524 -0.762)
			(stroke
				(width 0.1524)
				(type default)
			)
			(layer "F.SilkS")
		)
		(fp_line
			(start -1.524 -0.762)
			(end 1.524 -0.762)
			(stroke
				(width 0.1524)
				(type default)
			)
			(layer "F.SilkS")
		)
		(fp_line
			(start 1.1049 0.724916)
			(end 1.1049 -0.724916)
			(stroke
				(width 0.1)
				(type default)
			)
			(layer "F.Fab")
		)
		(fp_line
			(start 1.1049 -0.724916)
			(end -1.1049 -0.724916)
			(stroke
				(width 0.1)
				(type default)
			)
			(layer "F.Fab")
		)
		(fp_line
			(start -1.1049 0.724916)
			(end 1.1049 0.724916)
			(stroke
				(width 0.1)
				(type default)
			)
			(layer "F.Fab")
		)
		(fp_line
			(start -1.1049 -0.724916)
			(end -1.1049 0.724916)
			(stroke
				(width 0.1)
				(type default)
			)
			(layer "F.Fab")
		)
		(pad "1" smd rect
			(at -0.889 0)
			(size 1.016 1.27)
			(layers "F.Cu" "F.Mask" "F.Paste")
			(net "P1V8_PLL0_PEX1")
		)
		(pad "2" smd rect
			(at 0.889 0)
			(size 1.016 1.27)
			(layers "F.Cu" "F.Mask" "F.Paste")
			(net "GND")
		)
	)
	(footprint ""
		(layer "F.Cu")
		(at 15.934182 -135.77697 -90)
		(property "Reference" "PC311"
			(at 0 0 270)
			(layer "F.SilkS")
			(hide yes)
			(effects
				(font
					(size 1.27 1.27)
				)
			)
		)
		(property "Value" ""
			(at 0 0 270)
			(layer "F.Fab")
			(effects
				(font
					(size 1.27 1.27)
				)
			)
		)
		(duplicate_pad_numbers_are_jumpers no)
		(fp_line
			(start -1.524 0.762)
			(end -1.524 -0.762)
			(stroke
				(width 0.1524)
				(type default)
			)
			(layer "F.SilkS")
		)
		(fp_line
			(start 1.524 0.762)
			(end -1.524 0.762)
			(stroke
				(width 0.1524)
				(type default)
			)
			(layer "F.SilkS")
		)
		(fp_line
			(start -1.524 -0.762)
			(end 1.524 -0.762)
			(stroke
				(width 0.1524)
				(type default)
			)
			(layer "F.SilkS")
		)
		(fp_line
			(start 1.524 -0.762)
			(end 1.524 0.762)
			(stroke
				(width 0.1524)
				(type default)
			)
			(layer "F.SilkS")
		)
		(fp_line
			(start -1.1049 0.724916)
			(end 1.1049 0.724916)
			(stroke
				(width 0.1)
				(type default)
			)
			(layer "F.Fab")
		)
		(fp_line
			(start 1.1049 0.724916)
			(end 1.1049 -0.724916)
			(stroke
				(width 0.1)
				(type default)
			)
			(layer "F.Fab")
		)
		(fp_line
			(start -1.1049 -0.724916)
			(end -1.1049 0.724916)
			(stroke
				(width 0.1)
				(type default)
			)
			(layer "F.Fab")
		)
		(fp_line
			(start 1.1049 -0.724916)
			(end -1.1049 -0.724916)
			(stroke
				(width 0.1)
				(type default)
			)
			(layer "F.Fab")
		)
		(pad "1" smd rect
			(at -0.889 0 90)
			(size 1.016 1.27)
			(layers "F.Cu" "F.Mask" "F.Paste")
			(net "P12V_NIC0_R")
		)
		(pad "2" smd rect
			(at 0.889 0 90)
			(size 1.016 1.27)
			(layers "F.Cu" "F.Mask" "F.Paste")
			(net "GND")
		)
	)
	(footprint ""
		(layer "F.Cu")
		(at 236.757718 -204.30236 90)
		(property "Reference" "D7"
			(at 0 0 90)
			(layer "F.SilkS")
			(hide yes)
			(effects
				(font
					(size 1.27 1.27)
				)
			)
		)
		(property "Value" ""
			(at 0 0 90)
			(layer "F.Fab")
			(effects
				(font
					(size 1.27 1.27)
				)
			)
		)
		(duplicate_pad_numbers_are_jumpers no)
		(fp_line
			(start 1.16078 -0.4826)
			(end 1.16078 0.4826)
			(stroke
				(width 0.1524)
				(type default)
			)
			(layer "F.SilkS")
		)
		(fp_line
			(start 1.03378 -0.4826)
			(end 1.03378 0.4826)
			(stroke
				(width 0.1524)
				(type default)
			)
			(layer "F.SilkS")
		)
		(fp_line
			(start 0.90678 -0.4826)
			(end 0.90678 0.4826)
			(stroke
				(width 0.1524)
				(type default)
			)
			(layer "F.SilkS")
		)
		(fp_line
			(start -0.64008 -0.4826)
			(end 1.16078 -0.4826)
			(stroke
				(width 0.1524)
				(type default)
			)
			(layer "F.SilkS")
		)
		(fp_line
			(start -0.79248 -0.4826)
			(end 1.03378 -0.4826)
			(stroke
				(width 0.1524)
				(type default)
			)
			(layer "F.SilkS")
		)
		(fp_line
			(start -0.89408 -0.4826)
			(end 0.90678 -0.4826)
			(stroke
				(width 0.1524)
				(type default)
			)
			(layer "F.SilkS")
		)
		(fp_line
			(start 1.16078 0.4826)
			(end -0.64008 0.4826)
			(stroke
				(width 0.1524)
				(type default)
			)
			(layer "F.SilkS")
		)
		(fp_line
			(start 1.03378 0.4826)
			(end -0.79248 0.4826)
			(stroke
				(width 0.1524)
				(type default)
			)
			(layer "F.SilkS")
		)
		(fp_line
			(start 0.90678 0.4826)
			(end -0.90678 0.4826)
			(stroke
				(width 0.1524)
				(type default)
			)
			(layer "F.SilkS")
		)
		(fp_line
			(start -0.90678 0.4826)
			(end -0.90678 -0.4699)
			(stroke
				(width 0.1524)
				(type default)
			)
			(layer "F.SilkS")
		)
		(fp_line
			(start 0.499872 -0.249936)
			(end 0.499872 0.249936)
			(stroke
				(width 0.1)
				(type default)
			)
			(layer "F.Fab")
		)
		(fp_line
			(start -0.499872 -0.249936)
			(end 0.499872 -0.249936)
			(stroke
				(width 0.1)
				(type default)
			)
			(layer "F.Fab")
		)
		(fp_line
			(start 0.499872 0.249936)
			(end -0.499872 0.249936)
			(stroke
				(width 0.1)
				(type default)
			)
			(layer "F.Fab")
		)
		(fp_line
			(start -0.499872 0.249936)
			(end -0.499872 -0.249936)
			(stroke
				(width 0.1)
				(type default)
			)
			(layer "F.Fab")
		)
		(pad "A" smd rect
			(at -0.47498 0 90)
			(size 0.6096 0.7112)
			(layers "F.Cu" "F.Mask" "F.Paste")
			(net "BMC_HEARTBEAT_N_D")
		)
		(pad "C" smd rect
			(at 0.47498 0 90)
			(size 0.6096 0.7112)
			(layers "F.Cu" "F.Mask" "F.Paste")
			(net "BIC_HEARTBEAT_N")
		)
	)
	(footprint ""
		(layer "F.Cu")
		(at 228.79304 -95.089726)
		(property "Reference" "R5440"
			(at 0 0 0)
			(layer "F.SilkS")
			(hide yes)
			(effects
				(font
					(size 1.27 1.27)
				)
			)
		)
		(property "Value" ""
			(at 0 0 0)
			(layer "F.Fab")
			(effects
				(font
					(size 1.27 1.27)
				)
			)
		)
		(duplicate_pad_numbers_are_jumpers no)
		(fp_line
			(start -0.7874 -0.4064)
			(end 0.7874 -0.4064)
			(stroke
				(width 0.1524)
				(type default)
			)
			(layer "F.SilkS")
		)
		(fp_line
			(start -0.7874 0.4064)
			(end -0.7874 -0.4064)
			(stroke
				(width 0.1524)
				(type default)
			)
			(layer "F.SilkS")
		)
		(fp_line
			(start 0.7874 -0.4064)
			(end 0.7874 0.4064)
			(stroke
				(width 0.1524)
				(type default)
			)
			(layer "F.SilkS")
		)
		(fp_line
			(start 0.7874 0.4064)
			(end -0.7874 0.4064)
			(stroke
				(width 0.1524)
				(type default)
			)
			(layer "F.SilkS")
		)
		(fp_line
			(start -0.67945 -0.305054)
			(end -0.12065 -0.305054)
			(stroke
				(width 0.1)
				(type default)
			)
			(layer "F.Fab")
		)
		(fp_line
			(start -0.67945 0.3048)
			(end -0.67945 -0.305054)
			(stroke
				(width 0.1)
				(type default)
			)
			(layer "F.Fab")
		)
		(fp_line
			(start -0.12065 -0.305054)
			(end -0.12065 -0.2794)
			(stroke
				(width 0.1)
				(type default)
			)
			(layer "F.Fab")
		)
		(fp_line
			(start -0.12065 -0.2794)
			(end 0.12065 -0.2794)
			(stroke
				(width 0.1)
				(type default)
			)
			(layer "F.Fab")
		)
		(fp_line
			(start -0.12065 0.2794)
			(end -0.12065 0.3048)
			(stroke
				(width 0.1)
				(type default)
			)
			(layer "F.Fab")
		)
		(fp_line
			(start -0.12065 0.3048)
			(end -0.67945 0.3048)
			(stroke
				(width 0.1)
				(type default)
			)
			(layer "F.Fab")
		)
		(fp_line
			(start 0.120396 0.2794)
			(end -0.12065 0.2794)
			(stroke
				(width 0.1)
				(type default)
			)
			(layer "F.Fab")
		)
		(fp_line
			(start 0.120396 0.3048)
			(end 0.120396 0.2794)
			(stroke
				(width 0.1)
				(type default)
			)
			(layer "F.Fab")
		)
		(fp_line
			(start 0.12065 -0.3048)
			(end 0.67945 -0.3048)
			(stroke
				(width 0.1)
				(type default)
			)
			(layer "F.Fab")
		)
		(fp_line
			(start 0.12065 -0.2794)
			(end 0.12065 -0.3048)
			(stroke
				(width 0.1)
				(type default)
			)
			(layer "F.Fab")
		)
		(fp_line
			(start 0.67945 -0.3048)
			(end 0.67945 0.3048)
			(stroke
				(width 0.1)
				(type default)
			)
			(layer "F.Fab")
		)
		(fp_line
			(start 0.67945 0.3048)
			(end 0.120396 0.3048)
			(stroke
				(width 0.1)
				(type default)
			)
			(layer "F.Fab")
		)
		(pad "1" smd circle
			(at -0.40005 0)
			(size 0 0)
			(layers "F.Cu" "F.Mask" "F.Paste")
			(net "P3V3_AUX")
		)
		(pad "2" smd circle
			(at 0.40005 0)
			(size 0 0)
			(layers "F.Cu" "F.Mask" "F.Paste")
			(net "PEX_USB_HUB_PSELF")
		)
	)
	(footprint ""
		(layer "F.Cu")
		(at 269.595854 -228.839522)
		(property "Reference" "ME9"
			(at 0 0 0)
			(layer "F.SilkS")
			(hide yes)
			(effects
				(font
					(size 1.27 1.27)
				)
			)
		)
		(property "Value" ""
			(at 0 0 0)
			(layer "F.Fab")
			(effects
				(font
					(size 1.27 1.27)
				)
			)
		)
		(duplicate_pad_numbers_are_jumpers no)
		(fp_line
			(start 0 -5.999988)
			(end 0 -4.475988)
			(stroke
				(width 0.1524)
				(type default)
			)
			(layer "F.SilkS")
		)
		(fp_line
			(start 0 -1.524)
			(end 0 0)
			(stroke
				(width 0.1524)
				(type default)
			)
			(layer "F.SilkS")
		)
		(fp_line
			(start 0 0)
			(end 1.524 0)
			(stroke
				(width 0.1524)
				(type default)
			)
			(layer "F.SilkS")
		)
		(fp_line
			(start 1.524 -5.999988)
			(end 0 -5.999988)
			(stroke
				(width 0.1524)
				(type default)
			)
			(layer "F.SilkS")
		)
		(fp_line
			(start 25.475946 -5.999988)
			(end 26.999946 -5.999988)
			(stroke
				(width 0.1524)
				(type default)
			)
			(layer "F.SilkS")
		)
		(fp_line
			(start 26.999946 -5.999988)
			(end 26.999946 -4.475988)
			(stroke
				(width 0.1524)
				(type default)
			)
			(layer "F.SilkS")
		)
		(fp_line
			(start 26.999946 -1.524)
			(end 26.999946 0)
			(stroke
				(width 0.1524)
				(type default)
			)
			(layer "F.SilkS")
		)
		(fp_line
			(start 26.999946 0)
			(end 25.475946 0)
			(stroke
				(width 0.1524)
				(type default)
			)
			(layer "F.SilkS")
		)
		(fp_text user "S/N"
			(at 0.2032 -4.59105 0)
			(unlocked yes)
			(layer "F.SilkS")
			(effects
				(font
					(size 1.905 1.4224)
					(thickness 0.1524)
				)
				(justify left)
			)
		)
	)
	(footprint ""
		(layer "F.Cu")
		(at 366.920018 -15.649956 180)
		(property "Reference" "H126"
			(at -3.65379 -2.645664 0)
			(unlocked yes)
			(layer "B.SilkS")
			(effects
				(font
					(size 0.7874 0.5842)
					(thickness 0.1524)
				)
				(justify left mirror)
			)
		)
		(property "Value" ""
			(at 0 0 180)
			(layer "F.Fab")
			(effects
				(font
					(size 1.27 1.27)
				)
			)
		)
		(duplicate_pad_numbers_are_jumpers no)
		(pad "1" thru_hole rect
			(at 0 0 180)
			(size 4.2164 5.0038)
			(drill 2.0066
				(offset 0.099822 0)
			)
			(layers "*.Cu" "*.Mask")
			(remove_unused_layers no)
			(net "Net_8537")
			(clearance -0.8509)
			(padstack
				(mode front_inner_back)
				(layer "Inner"
					(shape circle)
					(size 4.0132 4.0132)
					(clearance -0.7493)
				)
				(layer "B.Cu"
					(shape circle)
					(size 4.0132 4.0132)
					(clearance -0.7493)
				)
			)
		)
	)
	(footprint ""
		(layer "F.Cu")
		(at 380.711456 -299.645832 -90)
		(property "Reference" "R4589"
			(at 0 0 270)
			(layer "F.SilkS")
			(hide yes)
			(effects
				(font
					(size 1.27 1.27)
				)
			)
		)
		(property "Value" ""
			(at 0 0 270)
			(layer "F.Fab")
			(effects
				(font
					(size 1.27 1.27)
				)
			)
		)
		(duplicate_pad_numbers_are_jumpers no)
		(fp_line
			(start -0.7874 0.4064)
			(end -0.7874 -0.4064)
			(stroke
				(width 0.1524)
				(type default)
			)
			(layer "F.SilkS")
		)
		(fp_line
			(start 0.7874 0.4064)
			(end -0.7874 0.4064)
			(stroke
				(width 0.1524)
				(type default)
			)
			(layer "F.SilkS")
		)
		(fp_line
			(start -0.7874 -0.4064)
			(end 0.7874 -0.4064)
			(stroke
				(width 0.1524)
				(type default)
			)
			(layer "F.SilkS")
		)
		(fp_line
			(start 0.7874 -0.4064)
			(end 0.7874 0.4064)
			(stroke
				(width 0.1524)
				(type default)
			)
			(layer "F.SilkS")
		)
		(fp_line
			(start -0.67945 0.3048)
			(end -0.67945 -0.305054)
			(stroke
				(width 0.1)
				(type default)
			)
			(layer "F.Fab")
		)
		(fp_line
			(start -0.12065 0.3048)
			(end -0.67945 0.3048)
			(stroke
				(width 0.1)
				(type default)
			)
			(layer "F.Fab")
		)
		(fp_line
			(start 0.120396 0.3048)
			(end 0.120396 0.2794)
			(stroke
				(width 0.1)
				(type default)
			)
			(layer "F.Fab")
		)
		(fp_line
			(start 0.67945 0.3048)
			(end 0.120396 0.3048)
			(stroke
				(width 0.1)
				(type default)
			)
			(layer "F.Fab")
		)
		(fp_line
			(start -0.12065 0.2794)
			(end -0.12065 0.3048)
			(stroke
				(width 0.1)
				(type default)
			)
			(layer "F.Fab")
		)
		(fp_line
			(start 0.120396 0.2794)
			(end -0.12065 0.2794)
			(stroke
				(width 0.1)
				(type default)
			)
			(layer "F.Fab")
		)
		(fp_line
			(start -0.12065 -0.2794)
			(end 0.12065 -0.2794)
			(stroke
				(width 0.1)
				(type default)
			)
			(layer "F.Fab")
		)
		(fp_line
			(start 0.12065 -0.2794)
			(end 0.12065 -0.3048)
			(stroke
				(width 0.1)
				(type default)
			)
			(layer "F.Fab")
		)
		(fp_line
			(start 0.12065 -0.3048)
			(end 0.67945 -0.3048)
			(stroke
				(width 0.1)
				(type default)
			)
			(layer "F.Fab")
		)
		(fp_line
			(start 0.67945 -0.3048)
			(end 0.67945 0.3048)
			(stroke
				(width 0.1)
				(type default)
			)
			(layer "F.Fab")
		)
		(fp_line
			(start -0.67945 -0.305054)
			(end -0.12065 -0.305054)
			(stroke
				(width 0.1)
				(type default)
			)
			(layer "F.Fab")
		)
		(fp_line
			(start -0.12065 -0.305054)
			(end -0.12065 -0.2794)
			(stroke
				(width 0.1)
				(type default)
			)
			(layer "F.Fab")
		)
		(pad "1" smd circle
			(at -0.40005 0 270)
			(size 0 0)
			(layers "F.Cu" "F.Mask" "F.Paste")
			(net "PCEPLL1_VDDA18_PEX3")
		)
		(pad "2" smd circle
			(at 0.40005 0 270)
			(size 0 0)
			(layers "F.Cu" "F.Mask" "F.Paste")
			(net "PCEPLL1_VDDA18_PEX3_R")
		)
	)
	(footprint ""
		(layer "F.Cu")
		(at 161.59861 -66.32194 -90)
		(property "Reference" "PC843"
			(at 0 0 270)
			(layer "F.SilkS")
			(hide yes)
			(effects
				(font
					(size 1.27 1.27)
				)
			)
		)
		(property "Value" ""
			(at 0 0 270)
			(layer "F.Fab")
			(effects
				(font
					(size 1.27 1.27)
				)
			)
		)
		(duplicate_pad_numbers_are_jumpers no)
		(fp_line
			(start -0.7874 0.4064)
			(end -0.7874 -0.4064)
			(stroke
				(width 0.1524)
				(type default)
			)
			(layer "F.SilkS")
		)
		(fp_line
			(start 0.7874 0.4064)
			(end -0.7874 0.4064)
			(stroke
				(width 0.1524)
				(type default)
			)
			(layer "F.SilkS")
		)
		(fp_line
			(start -0.7874 -0.4064)
			(end 0.7874 -0.4064)
			(stroke
				(width 0.1524)
				(type default)
			)
			(layer "F.SilkS")
		)
		(fp_line
			(start 0.7874 -0.4064)
			(end 0.7874 0.4064)
			(stroke
				(width 0.1524)
				(type default)
			)
			(layer "F.SilkS")
		)
		(fp_line
			(start -0.67945 0.3048)
			(end -0.67945 -0.305054)
			(stroke
				(width 0.1)
				(type default)
			)
			(layer "F.Fab")
		)
		(fp_line
			(start -0.12065 0.3048)
			(end -0.67945 0.3048)
			(stroke
				(width 0.1)
				(type default)
			)
			(layer "F.Fab")
		)
		(fp_line
			(start 0.120396 0.3048)
			(end 0.120396 0.2794)
			(stroke
				(width 0.1)
				(type default)
			)
			(layer "F.Fab")
		)
		(fp_line
			(start 0.67945 0.3048)
			(end 0.120396 0.3048)
			(stroke
				(width 0.1)
				(type default)
			)
			(layer "F.Fab")
		)
		(fp_line
			(start -0.12065 0.2794)
			(end -0.12065 0.3048)
			(stroke
				(width 0.1)
				(type default)
			)
			(layer "F.Fab")
		)
		(fp_line
			(start 0.120396 0.2794)
			(end -0.12065 0.2794)
			(stroke
				(width 0.1)
				(type default)
			)
			(layer "F.Fab")
		)
		(fp_line
			(start -0.12065 -0.2794)
			(end 0.12065 -0.2794)
			(stroke
				(width 0.1)
				(type default)
			)
			(layer "F.Fab")
		)
		(fp_line
			(start 0.12065 -0.2794)
			(end 0.12065 -0.3048)
			(stroke
				(width 0.1)
				(type default)
			)
			(layer "F.Fab")
		)
		(fp_line
			(start 0.12065 -0.3048)
			(end 0.67945 -0.3048)
			(stroke
				(width 0.1)
				(type default)
			)
			(layer "F.Fab")
		)
		(fp_line
			(start 0.67945 -0.3048)
			(end 0.67945 0.3048)
			(stroke
				(width 0.1)
				(type default)
			)
			(layer "F.Fab")
		)
		(fp_line
			(start -0.67945 -0.305054)
			(end -0.12065 -0.305054)
			(stroke
				(width 0.1)
				(type default)
			)
			(layer "F.Fab")
		)
		(fp_line
			(start -0.12065 -0.305054)
			(end -0.12065 -0.2794)
			(stroke
				(width 0.1)
				(type default)
			)
			(layer "F.Fab")
		)
		(pad "1" smd circle
			(at -0.40005 0 270)
			(size 0 0)
			(layers "F.Cu" "F.Mask" "F.Paste")
			(net "P12V_SSD5_CO_GATE")
		)
		(pad "2" smd circle
			(at 0.40005 0 270)
			(size 0 0)
			(layers "F.Cu" "F.Mask" "F.Paste")
			(net "GND")
		)
	)
	(footprint ""
		(layer "F.Cu")
		(at 150.22068 -26.666444 -90)
		(property "Reference" "R4063"
			(at 0 0 270)
			(layer "F.SilkS")
			(hide yes)
			(effects
				(font
					(size 1.27 1.27)
				)
			)
		)
		(property "Value" ""
			(at 0 0 270)
			(layer "F.Fab")
			(effects
				(font
					(size 1.27 1.27)
				)
			)
		)
		(duplicate_pad_numbers_are_jumpers no)
		(fp_line
			(start -0.7874 0.4064)
			(end -0.7874 -0.4064)
			(stroke
				(width 0.1524)
				(type default)
			)
			(layer "F.SilkS")
		)
		(fp_line
			(start 0.7874 0.4064)
			(end -0.7874 0.4064)
			(stroke
				(width 0.1524)
				(type default)
			)
			(layer "F.SilkS")
		)
		(fp_line
			(start -0.7874 -0.4064)
			(end 0.7874 -0.4064)
			(stroke
				(width 0.1524)
				(type default)
			)
			(layer "F.SilkS")
		)
		(fp_line
			(start 0.7874 -0.4064)
			(end 0.7874 0.4064)
			(stroke
				(width 0.1524)
				(type default)
			)
			(layer "F.SilkS")
		)
		(fp_line
			(start -0.67945 0.3048)
			(end -0.67945 -0.305054)
			(stroke
				(width 0.1)
				(type default)
			)
			(layer "F.Fab")
		)
		(fp_line
			(start -0.12065 0.3048)
			(end -0.67945 0.3048)
			(stroke
				(width 0.1)
				(type default)
			)
			(layer "F.Fab")
		)
		(fp_line
			(start 0.120396 0.3048)
			(end 0.120396 0.2794)
			(stroke
				(width 0.1)
				(type default)
			)
			(layer "F.Fab")
		)
		(fp_line
			(start 0.67945 0.3048)
			(end 0.120396 0.3048)
			(stroke
				(width 0.1)
				(type default)
			)
			(layer "F.Fab")
		)
		(fp_line
			(start -0.12065 0.2794)
			(end -0.12065 0.3048)
			(stroke
				(width 0.1)
				(type default)
			)
			(layer "F.Fab")
		)
		(fp_line
			(start 0.120396 0.2794)
			(end -0.12065 0.2794)
			(stroke
				(width 0.1)
				(type default)
			)
			(layer "F.Fab")
		)
		(fp_line
			(start -0.12065 -0.2794)
			(end 0.12065 -0.2794)
			(stroke
				(width 0.1)
				(type default)
			)
			(layer "F.Fab")
		)
		(fp_line
			(start 0.12065 -0.2794)
			(end 0.12065 -0.3048)
			(stroke
				(width 0.1)
				(type default)
			)
			(layer "F.Fab")
		)
		(fp_line
			(start 0.12065 -0.3048)
			(end 0.67945 -0.3048)
			(stroke
				(width 0.1)
				(type default)
			)
			(layer "F.Fab")
		)
		(fp_line
			(start 0.67945 -0.3048)
			(end 0.67945 0.3048)
			(stroke
				(width 0.1)
				(type default)
			)
			(layer "F.Fab")
		)
		(fp_line
			(start -0.67945 -0.305054)
			(end -0.12065 -0.305054)
			(stroke
				(width 0.1)
				(type default)
			)
			(layer "F.Fab")
		)
		(fp_line
			(start -0.12065 -0.305054)
			(end -0.12065 -0.2794)
			(stroke
				(width 0.1)
				(type default)
			)
			(layer "F.Fab")
		)
		(pad "1" smd circle
			(at -0.40005 0 270)
			(size 0 0)
			(layers "F.Cu" "F.Mask" "F.Paste")
			(net "PRSNT_SSD5_R_N")
		)
		(pad "2" smd circle
			(at 0.40005 0 270)
			(size 0 0)
			(layers "F.Cu" "F.Mask" "F.Paste")
			(net "PRSNT_SSD5_N")
		)
	)
	(footprint ""
		(layer "F.Cu")
		(at 345.059 -234.061 -90)
		(property "Reference" "R3552"
			(at 0 0 270)
			(layer "F.SilkS")
			(hide yes)
			(effects
				(font
					(size 1.27 1.27)
				)
			)
		)
		(property "Value" ""
			(at 0 0 270)
			(layer "F.Fab")
			(effects
				(font
					(size 1.27 1.27)
				)
			)
		)
		(duplicate_pad_numbers_are_jumpers no)
		(fp_line
			(start -0.7874 0.4064)
			(end -0.7874 -0.4064)
			(stroke
				(width 0.1524)
				(type default)
			)
			(layer "F.SilkS")
		)
		(fp_line
			(start 0.7874 0.4064)
			(end -0.7874 0.4064)
			(stroke
				(width 0.1524)
				(type default)
			)
			(layer "F.SilkS")
		)
		(fp_line
			(start -0.7874 -0.4064)
			(end 0.7874 -0.4064)
			(stroke
				(width 0.1524)
				(type default)
			)
			(layer "F.SilkS")
		)
		(fp_line
			(start 0.7874 -0.4064)
			(end 0.7874 0.4064)
			(stroke
				(width 0.1524)
				(type default)
			)
			(layer "F.SilkS")
		)
		(fp_line
			(start -0.67945 0.3048)
			(end -0.67945 -0.305054)
			(stroke
				(width 0.1)
				(type default)
			)
			(layer "F.Fab")
		)
		(fp_line
			(start -0.12065 0.3048)
			(end -0.67945 0.3048)
			(stroke
				(width 0.1)
				(type default)
			)
			(layer "F.Fab")
		)
		(fp_line
			(start 0.120396 0.3048)
			(end 0.120396 0.2794)
			(stroke
				(width 0.1)
				(type default)
			)
			(layer "F.Fab")
		)
		(fp_line
			(start 0.67945 0.3048)
			(end 0.120396 0.3048)
			(stroke
				(width 0.1)
				(type default)
			)
			(layer "F.Fab")
		)
		(fp_line
			(start -0.12065 0.2794)
			(end -0.12065 0.3048)
			(stroke
				(width 0.1)
				(type default)
			)
			(layer "F.Fab")
		)
		(fp_line
			(start 0.120396 0.2794)
			(end -0.12065 0.2794)
			(stroke
				(width 0.1)
				(type default)
			)
			(layer "F.Fab")
		)
		(fp_line
			(start -0.12065 -0.2794)
			(end 0.12065 -0.2794)
			(stroke
				(width 0.1)
				(type default)
			)
			(layer "F.Fab")
		)
		(fp_line
			(start 0.12065 -0.2794)
			(end 0.12065 -0.3048)
			(stroke
				(width 0.1)
				(type default)
			)
			(layer "F.Fab")
		)
		(fp_line
			(start 0.12065 -0.3048)
			(end 0.67945 -0.3048)
			(stroke
				(width 0.1)
				(type default)
			)
			(layer "F.Fab")
		)
		(fp_line
			(start 0.67945 -0.3048)
			(end 0.67945 0.3048)
			(stroke
				(width 0.1)
				(type default)
			)
			(layer "F.Fab")
		)
		(fp_line
			(start -0.67945 -0.305054)
			(end -0.12065 -0.305054)
			(stroke
				(width 0.1)
				(type default)
			)
			(layer "F.Fab")
		)
		(fp_line
			(start -0.12065 -0.305054)
			(end -0.12065 -0.2794)
			(stroke
				(width 0.1)
				(type default)
			)
			(layer "F.Fab")
		)
		(pad "1" smd circle
			(at -0.40005 0 270)
			(size 0 0)
			(layers "F.Cu" "F.Mask" "F.Paste")
			(net "SSD4_PWRDIS_R")
		)
		(pad "2" smd circle
			(at 0.40005 0 270)
			(size 0 0)
			(layers "F.Cu" "F.Mask" "F.Paste")
			(net "SSD4_PWRDIS")
		)
	)
	(footprint ""
		(layer "F.Cu")
		(at 148.287486 -390.398254 90)
		(property "Reference" "R1843"
			(at 0 0 90)
			(layer "F.SilkS")
			(hide yes)
			(effects
				(font
					(size 1.27 1.27)
				)
			)
		)
		(property "Value" ""
			(at 0 0 90)
			(layer "F.Fab")
			(effects
				(font
					(size 1.27 1.27)
				)
			)
		)
		(duplicate_pad_numbers_are_jumpers no)
		(fp_line
			(start 0.7874 -0.4064)
			(end 0.7874 0.4064)
			(stroke
				(width 0.1524)
				(type default)
			)
			(layer "F.SilkS")
		)
		(fp_line
			(start -0.7874 -0.4064)
			(end 0.7874 -0.4064)
			(stroke
				(width 0.1524)
				(type default)
			)
			(layer "F.SilkS")
		)
		(fp_line
			(start 0.7874 0.4064)
			(end -0.7874 0.4064)
			(stroke
				(width 0.1524)
				(type default)
			)
			(layer "F.SilkS")
		)
		(fp_line
			(start -0.7874 0.4064)
			(end -0.7874 -0.4064)
			(stroke
				(width 0.1524)
				(type default)
			)
			(layer "F.SilkS")
		)
		(fp_line
			(start -0.12065 -0.305054)
			(end -0.12065 -0.2794)
			(stroke
				(width 0.1)
				(type default)
			)
			(layer "F.Fab")
		)
		(fp_line
			(start -0.67945 -0.305054)
			(end -0.12065 -0.305054)
			(stroke
				(width 0.1)
				(type default)
			)
			(layer "F.Fab")
		)
		(fp_line
			(start 0.67945 -0.3048)
			(end 0.67945 0.3048)
			(stroke
				(width 0.1)
				(type default)
			)
			(layer "F.Fab")
		)
		(fp_line
			(start 0.12065 -0.3048)
			(end 0.67945 -0.3048)
			(stroke
				(width 0.1)
				(type default)
			)
			(layer "F.Fab")
		)
		(fp_line
			(start 0.12065 -0.2794)
			(end 0.12065 -0.3048)
			(stroke
				(width 0.1)
				(type default)
			)
			(layer "F.Fab")
		)
		(fp_line
			(start -0.12065 -0.2794)
			(end 0.12065 -0.2794)
			(stroke
				(width 0.1)
				(type default)
			)
			(layer "F.Fab")
		)
		(fp_line
			(start 0.120396 0.2794)
			(end -0.12065 0.2794)
			(stroke
				(width 0.1)
				(type default)
			)
			(layer "F.Fab")
		)
		(fp_line
			(start -0.12065 0.2794)
			(end -0.12065 0.3048)
			(stroke
				(width 0.1)
				(type default)
			)
			(layer "F.Fab")
		)
		(fp_line
			(start 0.67945 0.3048)
			(end 0.120396 0.3048)
			(stroke
				(width 0.1)
				(type default)
			)
			(layer "F.Fab")
		)
		(fp_line
			(start 0.120396 0.3048)
			(end 0.120396 0.2794)
			(stroke
				(width 0.1)
				(type default)
			)
			(layer "F.Fab")
		)
		(fp_line
			(start -0.12065 0.3048)
			(end -0.67945 0.3048)
			(stroke
				(width 0.1)
				(type default)
			)
			(layer "F.Fab")
		)
		(fp_line
			(start -0.67945 0.3048)
			(end -0.67945 -0.305054)
			(stroke
				(width 0.1)
				(type default)
			)
			(layer "F.Fab")
		)
		(pad "1" smd circle
			(at -0.40005 0 90)
			(size 0 0)
			(layers "F.Cu" "F.Mask" "F.Paste")
			(net "GPU_BASE_STBY_EN_R")
		)
		(pad "2" smd circle
			(at 0.40005 0 90)
			(size 0 0)
			(layers "F.Cu" "F.Mask" "F.Paste")
			(net "GPU_BASE_STBY_EN")
		)
	)
	(footprint ""
		(layer "F.Cu")
		(at 24.792686 -257.148838 -90)
		(property "Reference" "R1260"
			(at 0 0 270)
			(layer "F.SilkS")
			(hide yes)
			(effects
				(font
					(size 1.27 1.27)
				)
			)
		)
		(property "Value" ""
			(at 0 0 270)
			(layer "F.Fab")
			(effects
				(font
					(size 1.27 1.27)
				)
			)
		)
		(duplicate_pad_numbers_are_jumpers no)
		(fp_line
			(start -0.7874 0.4064)
			(end -0.7874 -0.4064)
			(stroke
				(width 0.1524)
				(type default)
			)
			(layer "F.SilkS")
		)
		(fp_line
			(start 0.7874 0.4064)
			(end -0.7874 0.4064)
			(stroke
				(width 0.1524)
				(type default)
			)
			(layer "F.SilkS")
		)
		(fp_line
			(start -0.7874 -0.4064)
			(end 0.7874 -0.4064)
			(stroke
				(width 0.1524)
				(type default)
			)
			(layer "F.SilkS")
		)
		(fp_line
			(start 0.7874 -0.4064)
			(end 0.7874 0.4064)
			(stroke
				(width 0.1524)
				(type default)
			)
			(layer "F.SilkS")
		)
		(fp_line
			(start -0.67945 0.3048)
			(end -0.67945 -0.305054)
			(stroke
				(width 0.1)
				(type default)
			)
			(layer "F.Fab")
		)
		(fp_line
			(start -0.12065 0.3048)
			(end -0.67945 0.3048)
			(stroke
				(width 0.1)
				(type default)
			)
			(layer "F.Fab")
		)
		(fp_line
			(start 0.120396 0.3048)
			(end 0.120396 0.2794)
			(stroke
				(width 0.1)
				(type default)
			)
			(layer "F.Fab")
		)
		(fp_line
			(start 0.67945 0.3048)
			(end 0.120396 0.3048)
			(stroke
				(width 0.1)
				(type default)
			)
			(layer "F.Fab")
		)
		(fp_line
			(start -0.12065 0.2794)
			(end -0.12065 0.3048)
			(stroke
				(width 0.1)
				(type default)
			)
			(layer "F.Fab")
		)
		(fp_line
			(start 0.120396 0.2794)
			(end -0.12065 0.2794)
			(stroke
				(width 0.1)
				(type default)
			)
			(layer "F.Fab")
		)
		(fp_line
			(start -0.12065 -0.2794)
			(end 0.12065 -0.2794)
			(stroke
				(width 0.1)
				(type default)
			)
			(layer "F.Fab")
		)
		(fp_line
			(start 0.12065 -0.2794)
			(end 0.12065 -0.3048)
			(stroke
				(width 0.1)
				(type default)
			)
			(layer "F.Fab")
		)
		(fp_line
			(start 0.12065 -0.3048)
			(end 0.67945 -0.3048)
			(stroke
				(width 0.1)
				(type default)
			)
			(layer "F.Fab")
		)
		(fp_line
			(start 0.67945 -0.3048)
			(end 0.67945 0.3048)
			(stroke
				(width 0.1)
				(type default)
			)
			(layer "F.Fab")
		)
		(fp_line
			(start -0.67945 -0.305054)
			(end -0.12065 -0.305054)
			(stroke
				(width 0.1)
				(type default)
			)
			(layer "F.Fab")
		)
		(fp_line
			(start -0.12065 -0.305054)
			(end -0.12065 -0.2794)
			(stroke
				(width 0.1)
				(type default)
			)
			(layer "F.Fab")
		)
		(pad "1" smd circle
			(at -0.40005 0 270)
			(size 0 0)
			(layers "F.Cu" "F.Mask" "F.Paste")
			(net "P3V3_LED")
		)
		(pad "2" smd circle
			(at 0.40005 0 270)
			(size 0 0)
			(layers "F.Cu" "F.Mask" "F.Paste")
			(net "LED_PEX0_SYS_ERR_N")
		)
	)
	(footprint ""
		(layer "F.Cu")
		(at 204.57541 -121.661682 -90)
		(property "Reference" "PD58"
			(at 4.161282 2.18694 90)
			(unlocked yes)
			(layer "F.SilkS")
			(effects
				(font
					(size 0.7874 0.5842)
					(thickness 0.1524)
				)
				(justify left)
			)
		)
		(property "Value" ""
			(at 0 0 270)
			(layer "F.Fab")
			(effects
				(font
					(size 1.27 1.27)
				)
			)
		)
		(duplicate_pad_numbers_are_jumpers no)
		(fp_line
			(start -3.400044 1.459992)
			(end -3.400044 -1.459992)
			(stroke
				(width 0.1524)
				(type default)
			)
			(layer "F.SilkS")
		)
		(fp_line
			(start 4.107942 1.459992)
			(end -3.400044 1.459992)
			(stroke
				(width 0.1524)
				(type default)
			)
			(layer "F.SilkS")
		)
		(fp_line
			(start -3.400044 -1.459992)
			(end 4.107942 -1.459992)
			(stroke
				(width 0.1524)
				(type default)
			)
			(layer "F.SilkS")
		)
		(fp_line
			(start 4.107942 -1.459992)
			(end 4.107942 1.459992)
			(stroke
				(width 0.1524)
				(type default)
			)
			(layer "F.SilkS")
		)
		(fp_poly
			(pts
				(xy 4.107942 -1.459992) (xy 4.107942 1.459992) (xy 3.308096 1.459992) (xy 3.308096 -1.459992)
			)
			(stroke
				(width 0)
				(type default)
			)
			(fill yes)
			(layer "F.SilkS")
		)
		(fp_line
			(start -2.29997 1.459992)
			(end -2.29997 -1.459992)
			(stroke
				(width 0.1)
				(type default)
			)
			(layer "F.Fab")
		)
		(fp_line
			(start 2.29997 1.459992)
			(end -2.29997 1.459992)
			(stroke
				(width 0.1)
				(type default)
			)
			(layer "F.Fab")
		)
		(fp_line
			(start -2.29997 -1.459992)
			(end 2.29997 -1.459992)
			(stroke
				(width 0.1)
				(type default)
			)
			(layer "F.Fab")
		)
		(fp_line
			(start 2.29997 -1.459992)
			(end 2.29997 1.459992)
			(stroke
				(width 0.1)
				(type default)
			)
			(layer "F.Fab")
		)
		(fp_text user "-"
			(at 5.4102 0.29845 90)
			(unlocked yes)
			(layer "F.SilkS")
			(effects
				(font
					(size 1.905 1.4224)
					(thickness 0.1524)
				)
				(justify left)
			)
		)
		(fp_text user "+"
			(at -4.7752 -0.12065 270)
			(unlocked yes)
			(layer "F.SilkS")
			(effects
				(font
					(size 1.905 1.4224)
					(thickness 0.1524)
				)
				(justify left)
			)
		)
		(fp_text user "-"
			(at 5.4102 0.29845 90)
			(unlocked yes)
			(layer "F.Fab")
			(effects
				(font
					(size 1.905 1.4224)
					(thickness 0.1524)
				)
				(justify left)
			)
		)
		(fp_text user "+"
			(at -4.7752 -0.12065 270)
			(unlocked yes)
			(layer "F.Fab")
			(effects
				(font
					(size 1.905 1.4224)
					(thickness 0.1524)
				)
				(justify left)
			)
		)
		(pad "A" smd rect
			(at -1.999996 0)
			(size 1.7018 2.5146)
			(layers "F.Cu" "F.Mask" "F.Paste")
			(net "GND")
		)
		(pad "C" smd rect
			(at 1.999996 0)
			(size 1.7018 2.5146)
			(layers "F.Cu" "F.Mask" "F.Paste")
			(net "P3V3_NIC3")
		)
	)
	(footprint ""
		(layer "F.Cu")
		(at 288.072068 -32.848042 90)
		(property "Reference" "PC950"
			(at 0 0 90)
			(layer "F.SilkS")
			(hide yes)
			(effects
				(font
					(size 1.27 1.27)
				)
			)
		)
		(property "Value" ""
			(at 0 0 90)
			(layer "F.Fab")
			(effects
				(font
					(size 1.27 1.27)
				)
			)
		)
		(duplicate_pad_numbers_are_jumpers no)
		(fp_line
			(start 0.7874 -0.4064)
			(end 0.7874 0.4064)
			(stroke
				(width 0.1524)
				(type default)
			)
			(layer "F.SilkS")
		)
		(fp_line
			(start -0.7874 -0.4064)
			(end 0.7874 -0.4064)
			(stroke
				(width 0.1524)
				(type default)
			)
			(layer "F.SilkS")
		)
		(fp_line
			(start 0.7874 0.4064)
			(end -0.7874 0.4064)
			(stroke
				(width 0.1524)
				(type default)
			)
			(layer "F.SilkS")
		)
		(fp_line
			(start -0.7874 0.4064)
			(end -0.7874 -0.4064)
			(stroke
				(width 0.1524)
				(type default)
			)
			(layer "F.SilkS")
		)
		(fp_line
			(start -0.12065 -0.305054)
			(end -0.12065 -0.2794)
			(stroke
				(width 0.1)
				(type default)
			)
			(layer "F.Fab")
		)
		(fp_line
			(start -0.67945 -0.305054)
			(end -0.12065 -0.305054)
			(stroke
				(width 0.1)
				(type default)
			)
			(layer "F.Fab")
		)
		(fp_line
			(start 0.67945 -0.3048)
			(end 0.67945 0.3048)
			(stroke
				(width 0.1)
				(type default)
			)
			(layer "F.Fab")
		)
		(fp_line
			(start 0.12065 -0.3048)
			(end 0.67945 -0.3048)
			(stroke
				(width 0.1)
				(type default)
			)
			(layer "F.Fab")
		)
		(fp_line
			(start 0.12065 -0.2794)
			(end 0.12065 -0.3048)
			(stroke
				(width 0.1)
				(type default)
			)
			(layer "F.Fab")
		)
		(fp_line
			(start -0.12065 -0.2794)
			(end 0.12065 -0.2794)
			(stroke
				(width 0.1)
				(type default)
			)
			(layer "F.Fab")
		)
		(fp_line
			(start 0.120396 0.2794)
			(end -0.12065 0.2794)
			(stroke
				(width 0.1)
				(type default)
			)
			(layer "F.Fab")
		)
		(fp_line
			(start -0.12065 0.2794)
			(end -0.12065 0.3048)
			(stroke
				(width 0.1)
				(type default)
			)
			(layer "F.Fab")
		)
		(fp_line
			(start 0.67945 0.3048)
			(end 0.120396 0.3048)
			(stroke
				(width 0.1)
				(type default)
			)
			(layer "F.Fab")
		)
		(fp_line
			(start 0.120396 0.3048)
			(end 0.120396 0.2794)
			(stroke
				(width 0.1)
				(type default)
			)
			(layer "F.Fab")
		)
		(fp_line
			(start -0.12065 0.3048)
			(end -0.67945 0.3048)
			(stroke
				(width 0.1)
				(type default)
			)
			(layer "F.Fab")
		)
		(fp_line
			(start -0.67945 0.3048)
			(end -0.67945 -0.305054)
			(stroke
				(width 0.1)
				(type default)
			)
			(layer "F.Fab")
		)
		(pad "1" smd circle
			(at -0.40005 0 90)
			(size 0 0)
			(layers "F.Cu" "F.Mask" "F.Paste")
			(net "P3V3_SSD10_CO_GATE")
		)
		(pad "2" smd circle
			(at 0.40005 0 90)
			(size 0 0)
			(layers "F.Cu" "F.Mask" "F.Paste")
			(net "GND")
		)
	)
	(footprint ""
		(layer "F.Cu")
		(at 439.215784 -309.760366 135)
		(property "Reference" "R1454"
			(at 0 0 135)
			(layer "F.SilkS")
			(hide yes)
			(effects
				(font
					(size 1.27 1.27)
				)
			)
		)
		(property "Value" ""
			(at 0 0 135)
			(layer "F.Fab")
			(effects
				(font
					(size 1.27 1.27)
				)
			)
		)
		(duplicate_pad_numbers_are_jumpers no)
		(fp_line
			(start 0.787389 -0.406267)
			(end 0.787389 0.406267)
			(stroke
				(width 0.1524)
				(type default)
			)
			(layer "F.SilkS")
		)
		(fp_line
			(start 0.787389 0.406267)
			(end -0.787389 0.406267)
			(stroke
				(width 0.1524)
				(type default)
			)
			(layer "F.SilkS")
		)
		(fp_line
			(start -0.787389 -0.406267)
			(end 0.787389 -0.406267)
			(stroke
				(width 0.1524)
				(type default)
			)
			(layer "F.SilkS")
		)
		(fp_line
			(start -0.787389 0.406267)
			(end -0.787389 -0.406267)
			(stroke
				(width 0.1524)
				(type default)
			)
			(layer "F.SilkS")
		)
		(fp_line
			(start 0.679446 -0.30479)
			(end 0.679446 0.30479)
			(stroke
				(width 0.1)
				(type default)
			)
			(layer "F.Fab")
		)
		(fp_line
			(start 0.120515 -0.30479)
			(end 0.679446 -0.30479)
			(stroke
				(width 0.1)
				(type default)
			)
			(layer "F.Fab")
		)
		(fp_line
			(start 0.120695 -0.279466)
			(end 0.120515 -0.30479)
			(stroke
				(width 0.1)
				(type default)
			)
			(layer "F.Fab")
		)
		(fp_line
			(start 0.679446 0.30479)
			(end 0.120515 0.30479)
			(stroke
				(width 0.1)
				(type default)
			)
			(layer "F.Fab")
		)
		(fp_line
			(start -0.120695 -0.304969)
			(end -0.120695 -0.279466)
			(stroke
				(width 0.1)
				(type default)
			)
			(layer "F.Fab")
		)
		(fp_line
			(start -0.120695 -0.279466)
			(end 0.120695 -0.279466)
			(stroke
				(width 0.1)
				(type default)
			)
			(layer "F.Fab")
		)
		(fp_line
			(start 0.120335 0.279466)
			(end -0.120695 0.279466)
			(stroke
				(width 0.1)
				(type default)
			)
			(layer "F.Fab")
		)
		(fp_line
			(start 0.120515 0.30479)
			(end 0.120335 0.279466)
			(stroke
				(width 0.1)
				(type default)
			)
			(layer "F.Fab")
		)
		(fp_line
			(start -0.679446 -0.305149)
			(end -0.120695 -0.304969)
			(stroke
				(width 0.1)
				(type default)
			)
			(layer "F.Fab")
		)
		(fp_line
			(start -0.120695 0.279466)
			(end -0.120515 0.30479)
			(stroke
				(width 0.1)
				(type default)
			)
			(layer "F.Fab")
		)
		(fp_line
			(start -0.120515 0.30479)
			(end -0.679446 0.30479)
			(stroke
				(width 0.1)
				(type default)
			)
			(layer "F.Fab")
		)
		(fp_line
			(start -0.679446 0.30479)
			(end -0.679446 -0.305149)
			(stroke
				(width 0.1)
				(type default)
			)
			(layer "F.Fab")
		)
		(pad "1" smd circle
			(at -0.40005 0 135)
			(size 0 0)
			(layers "F.Cu" "F.Mask" "F.Paste")
			(net "GND")
		)
		(pad "2" smd circle
			(at 0.40005 0 135)
			(size 0 0)
			(layers "F.Cu" "F.Mask" "F.Paste")
			(net "PEX3_SPARE0")
		)
	)
	(footprint ""
		(layer "F.Cu")
		(at 432.054254 -48.21809)
		(property "Reference" "PD74"
			(at -3.353054 2.24536 0)
			(unlocked yes)
			(layer "F.SilkS")
			(effects
				(font
					(size 0.7874 0.5842)
					(thickness 0.1524)
				)
				(justify left)
			)
		)
		(property "Value" ""
			(at 0 0 0)
			(layer "F.Fab")
			(effects
				(font
					(size 1.27 1.27)
				)
			)
		)
		(duplicate_pad_numbers_are_jumpers no)
		(fp_line
			(start -3.400044 -1.459992)
			(end 4.107942 -1.459992)
			(stroke
				(width 0.1524)
				(type default)
			)
			(layer "F.SilkS")
		)
		(fp_line
			(start -3.400044 1.459992)
			(end -3.400044 -1.459992)
			(stroke
				(width 0.1524)
				(type default)
			)
			(layer "F.SilkS")
		)
		(fp_line
			(start 4.107942 -1.459992)
			(end 4.107942 1.459992)
			(stroke
				(width 0.1524)
				(type default)
			)
			(layer "F.SilkS")
		)
		(fp_line
			(start 4.107942 1.459992)
			(end -3.400044 1.459992)
			(stroke
				(width 0.1524)
				(type default)
			)
			(layer "F.SilkS")
		)
		(fp_poly
			(pts
				(xy 4.107942 -1.459992) (xy 4.107942 1.459992) (xy 3.308096 1.459992) (xy 3.308096 -1.459992)
			)
			(stroke
				(width 0)
				(type default)
			)
			(fill yes)
			(layer "F.SilkS")
		)
		(fp_line
			(start -2.29997 -1.459992)
			(end 2.29997 -1.459992)
			(stroke
				(width 0.1)
				(type default)
			)
			(layer "F.Fab")
		)
		(fp_line
			(start -2.29997 1.459992)
			(end -2.29997 -1.459992)
			(stroke
				(width 0.1)
				(type default)
			)
			(layer "F.Fab")
		)
		(fp_line
			(start 2.29997 -1.459992)
			(end 2.29997 1.459992)
			(stroke
				(width 0.1)
				(type default)
			)
			(layer "F.Fab")
		)
		(fp_line
			(start 2.29997 1.459992)
			(end -2.29997 1.459992)
			(stroke
				(width 0.1)
				(type default)
			)
			(layer "F.Fab")
		)
		(fp_text user "+"
			(at -4.7752 -0.12065 0)
			(unlocked yes)
			(layer "F.SilkS")
			(effects
				(font
					(size 1.905 1.4224)
					(thickness 0.1524)
				)
				(justify left)
			)
		)
		(fp_text user "-"
			(at 5.4102 0.29845 180)
			(unlocked yes)
			(layer "F.SilkS")
			(effects
				(font
					(size 1.905 1.4224)
					(thickness 0.1524)
				)
				(justify left)
			)
		)
		(fp_text user "+"
			(at -4.7752 -0.12065 0)
			(unlocked yes)
			(layer "F.Fab")
			(effects
				(font
					(size 1.905 1.4224)
					(thickness 0.1524)
				)
				(justify left)
			)
		)
		(fp_text user "-"
			(at 5.4102 0.29845 180)
			(unlocked yes)
			(layer "F.Fab")
			(effects
				(font
					(size 1.905 1.4224)
					(thickness 0.1524)
				)
				(justify left)
			)
		)
		(pad "A" smd rect
			(at -1.999996 0 90)
			(size 1.7018 2.5146)
			(layers "F.Cu" "F.Mask" "F.Paste")
			(net "GND")
		)
		(pad "C" smd rect
			(at 1.999996 0 90)
			(size 1.7018 2.5146)
			(layers "F.Cu" "F.Mask" "F.Paste")
			(net "P3V3_SSD15")
		)
	)
	(footprint ""
		(layer "F.Cu")
		(at 104.267762 -51.019456)
		(property "Reference" "PC398"
			(at 0 0 0)
			(layer "F.SilkS")
			(hide yes)
			(effects
				(font
					(size 1.27 1.27)
				)
			)
		)
		(property "Value" ""
			(at 0 0 0)
			(layer "F.Fab")
			(effects
				(font
					(size 1.27 1.27)
				)
			)
		)
		(duplicate_pad_numbers_are_jumpers no)
		(fp_line
			(start -0.7874 -0.4064)
			(end 0.7874 -0.4064)
			(stroke
				(width 0.1524)
				(type default)
			)
			(layer "F.SilkS")
		)
		(fp_line
			(start -0.7874 0.4064)
			(end -0.7874 -0.4064)
			(stroke
				(width 0.1524)
				(type default)
			)
			(layer "F.SilkS")
		)
		(fp_line
			(start 0.7874 -0.4064)
			(end 0.7874 0.4064)
			(stroke
				(width 0.1524)
				(type default)
			)
			(layer "F.SilkS")
		)
		(fp_line
			(start 0.7874 0.4064)
			(end -0.7874 0.4064)
			(stroke
				(width 0.1524)
				(type default)
			)
			(layer "F.SilkS")
		)
		(fp_line
			(start -0.6858 -0.3048)
			(end -0.1016 -0.3048)
			(stroke
				(width 0.1)
				(type default)
			)
			(layer "F.Fab")
		)
		(fp_line
			(start -0.6858 0.3048)
			(end -0.6858 -0.3048)
			(stroke
				(width 0.1)
				(type default)
			)
			(layer "F.Fab")
		)
		(fp_line
			(start -0.1016 -0.3048)
			(end -0.1016 -0.2794)
			(stroke
				(width 0.1)
				(type default)
			)
			(layer "F.Fab")
		)
		(fp_line
			(start -0.1016 -0.2794)
			(end 0.1016 -0.2794)
			(stroke
				(width 0.1)
				(type default)
			)
			(layer "F.Fab")
		)
		(fp_line
			(start -0.1016 0.2794)
			(end -0.1016 0.3048)
			(stroke
				(width 0.1)
				(type default)
			)
			(layer "F.Fab")
		)
		(fp_line
			(start -0.1016 0.3048)
			(end -0.6858 0.3048)
			(stroke
				(width 0.1)
				(type default)
			)
			(layer "F.Fab")
		)
		(fp_line
			(start 0.1016 -0.3048)
			(end 0.6858 -0.3048)
			(stroke
				(width 0.1)
				(type default)
			)
			(layer "F.Fab")
		)
		(fp_line
			(start 0.1016 -0.2794)
			(end 0.1016 -0.3048)
			(stroke
				(width 0.1)
				(type default)
			)
			(layer "F.Fab")
		)
		(fp_line
			(start 0.1016 0.2794)
			(end -0.1016 0.2794)
			(stroke
				(width 0.1)
				(type default)
			)
			(layer "F.Fab")
		)
		(fp_line
			(start 0.1016 0.3048)
			(end 0.1016 0.2794)
			(stroke
				(width 0.1)
				(type default)
			)
			(layer "F.Fab")
		)
		(fp_line
			(start 0.6858 -0.3048)
			(end 0.6858 0.3048)
			(stroke
				(width 0.1)
				(type default)
			)
			(layer "F.Fab")
		)
		(fp_line
			(start 0.6858 0.3048)
			(end 0.1016 0.3048)
			(stroke
				(width 0.1)
				(type default)
			)
			(layer "F.Fab")
		)
		(pad "1" smd rect
			(at -0.40005 0 180)
			(size 0.4572 0.508)
			(layers "F.Cu" "F.Mask" "F.Paste")
			(net "P12V_SSD3_SS")
		)
		(pad "2" smd rect
			(at 0.40005 0 180)
			(size 0.4572 0.508)
			(layers "F.Cu" "F.Mask" "F.Paste")
			(net "GND")
		)
	)
	(footprint ""
		(layer "F.Cu")
		(at 229.630478 -238.534702 -90)
		(property "Reference" "R6216"
			(at 0 0 270)
			(layer "F.SilkS")
			(hide yes)
			(effects
				(font
					(size 1.27 1.27)
				)
			)
		)
		(property "Value" ""
			(at 0 0 270)
			(layer "F.Fab")
			(effects
				(font
					(size 1.27 1.27)
				)
			)
		)
		(duplicate_pad_numbers_are_jumpers no)
		(fp_line
			(start -0.7874 0.4064)
			(end -0.7874 -0.4064)
			(stroke
				(width 0.1524)
				(type default)
			)
			(layer "F.SilkS")
		)
		(fp_line
			(start 0.7874 0.4064)
			(end -0.7874 0.4064)
			(stroke
				(width 0.1524)
				(type default)
			)
			(layer "F.SilkS")
		)
		(fp_line
			(start -0.7874 -0.4064)
			(end 0.7874 -0.4064)
			(stroke
				(width 0.1524)
				(type default)
			)
			(layer "F.SilkS")
		)
		(fp_line
			(start 0.7874 -0.4064)
			(end 0.7874 0.4064)
			(stroke
				(width 0.1524)
				(type default)
			)
			(layer "F.SilkS")
		)
		(fp_line
			(start -0.67945 0.3048)
			(end -0.67945 -0.305054)
			(stroke
				(width 0.1)
				(type default)
			)
			(layer "F.Fab")
		)
		(fp_line
			(start -0.12065 0.3048)
			(end -0.67945 0.3048)
			(stroke
				(width 0.1)
				(type default)
			)
			(layer "F.Fab")
		)
		(fp_line
			(start 0.120396 0.3048)
			(end 0.120396 0.2794)
			(stroke
				(width 0.1)
				(type default)
			)
			(layer "F.Fab")
		)
		(fp_line
			(start 0.67945 0.3048)
			(end 0.120396 0.3048)
			(stroke
				(width 0.1)
				(type default)
			)
			(layer "F.Fab")
		)
		(fp_line
			(start -0.12065 0.2794)
			(end -0.12065 0.3048)
			(stroke
				(width 0.1)
				(type default)
			)
			(layer "F.Fab")
		)
		(fp_line
			(start 0.120396 0.2794)
			(end -0.12065 0.2794)
			(stroke
				(width 0.1)
				(type default)
			)
			(layer "F.Fab")
		)
		(fp_line
			(start -0.12065 -0.2794)
			(end 0.12065 -0.2794)
			(stroke
				(width 0.1)
				(type default)
			)
			(layer "F.Fab")
		)
		(fp_line
			(start 0.12065 -0.2794)
			(end 0.12065 -0.3048)
			(stroke
				(width 0.1)
				(type default)
			)
			(layer "F.Fab")
		)
		(fp_line
			(start 0.12065 -0.3048)
			(end 0.67945 -0.3048)
			(stroke
				(width 0.1)
				(type default)
			)
			(layer "F.Fab")
		)
		(fp_line
			(start 0.67945 -0.3048)
			(end 0.67945 0.3048)
			(stroke
				(width 0.1)
				(type default)
			)
			(layer "F.Fab")
		)
		(fp_line
			(start -0.67945 -0.305054)
			(end -0.12065 -0.305054)
			(stroke
				(width 0.1)
				(type default)
			)
			(layer "F.Fab")
		)
		(fp_line
			(start -0.12065 -0.305054)
			(end -0.12065 -0.2794)
			(stroke
				(width 0.1)
				(type default)
			)
			(layer "F.Fab")
		)
		(pad "1" smd circle
			(at -0.40005 0 270)
			(size 0 0)
			(layers "F.Cu" "F.Mask" "F.Paste")
			(net "BIC_UART_SW_SEL1")
		)
		(pad "2" smd circle
			(at 0.40005 0 270)
			(size 0 0)
			(layers "F.Cu" "F.Mask" "F.Paste")
			(net "BIC_UART_SW_SEL1_R")
		)
	)
	(footprint ""
		(layer "F.Cu")
		(at 451.79996 -194.360038)
		(property "Reference" "H56"
			(at -4.134612 -5.646166 0)
			(unlocked yes)
			(layer "F.SilkS")
			(effects
				(font
					(size 0.7874 0.5842)
					(thickness 0.1524)
				)
				(justify left)
			)
		)
		(property "Value" ""
			(at 0 0 0)
			(layer "F.Fab")
			(effects
				(font
					(size 1.27 1.27)
				)
			)
		)
		(duplicate_pad_numbers_are_jumpers no)
		(pad "1" thru_hole circle
			(at 0 0)
			(size 10.0076 10.0076)
			(drill 5.6134)
			(layers "*.Cu" "*.Mask")
			(remove_unused_layers no)
			(net "GND")
			(clearance -1.9431)
		)
	)
	(footprint ""
		(layer "F.Cu")
		(at 170.882564 -29.875734)
		(property "Reference" "PU125"
			(at -3.248914 -2.166112 90)
			(unlocked yes)
			(layer "F.SilkS")
			(effects
				(font
					(size 0.7874 0.5842)
					(thickness 0.1524)
				)
			)
		)
		(property "Value" ""
			(at 0 0 0)
			(layer "F.Fab")
			(effects
				(font
					(size 1.27 1.27)
				)
			)
		)
		(duplicate_pad_numbers_are_jumpers no)
		(fp_line
			(start -1.239774 -1.495298)
			(end 1.239774 -1.495298)
			(stroke
				(width 0.1524)
				(type default)
			)
			(layer "F.SilkS")
		)
		(fp_line
			(start -1.239774 1.495298)
			(end -1.239774 -1.495298)
			(stroke
				(width 0.1524)
				(type default)
			)
			(layer "F.SilkS")
		)
		(fp_line
			(start 1.239774 -1.495298)
			(end 1.239774 1.495298)
			(stroke
				(width 0.1524)
				(type default)
			)
			(layer "F.SilkS")
		)
		(fp_line
			(start 1.239774 1.495298)
			(end -1.239774 1.495298)
			(stroke
				(width 0.1524)
				(type default)
			)
			(layer "F.SilkS")
		)
		(fp_poly
			(pts
				(xy -2.173224 -1.829562) (xy -2.89179 -1.11125) (xy -1.814068 -0.75184)
			)
			(stroke
				(width 0)
				(type default)
			)
			(fill yes)
			(layer "F.SilkS")
		)
		(fp_line
			(start -0.8001 -1.050036)
			(end 0.8001 -1.050036)
			(stroke
				(width 0.1)
				(type default)
			)
			(layer "F.Fab")
		)
		(fp_line
			(start -0.8001 1.050036)
			(end -0.8001 -1.050036)
			(stroke
				(width 0.1)
				(type default)
			)
			(layer "F.Fab")
		)
		(fp_line
			(start 0.8001 -1.050036)
			(end 0.8001 1.050036)
			(stroke
				(width 0.1)
				(type default)
			)
			(layer "F.Fab")
		)
		(fp_line
			(start 0.8001 1.050036)
			(end -0.8001 1.050036)
			(stroke
				(width 0.1)
				(type default)
			)
			(layer "F.Fab")
		)
		(fp_poly
			(pts
				(xy -2.458974 -0.508) (xy -2.458974 0.508) (xy -1.442974 0)
			)
			(stroke
				(width 0)
				(type default)
			)
			(fill yes)
			(layer "F.Fab")
		)
		(pad "1_2" smd circle
			(at -0.374904 0 90)
			(size 0 0)
			(layers "F.Cu" "F.Mask" "F.Paste")
			(net "P3V3_AUX")
		)
		(pad "3" smd rect
			(at -0.499872 0.999998)
			(size 0.254 0.7112)
			(layers "F.Cu" "F.Mask" "F.Paste")
			(net "GND")
		)
		(pad "4" smd rect
			(at 0 0.999998)
			(size 0.254 0.7112)
			(layers "F.Cu" "F.Mask" "F.Paste")
			(net "P3V3_SSD6_CO_ILIMIT")
		)
		(pad "5" smd rect
			(at 0.499872 0.999998)
			(size 0.254 0.7112)
			(layers "F.Cu" "F.Mask" "F.Paste")
			(net "P3V3_SSD6_CO_MODE")
		)
		(pad "6_7" smd circle
			(at 0.374904 0 270)
			(size 0 0)
			(layers "F.Cu" "F.Mask" "F.Paste")
			(net "P3V3_SSD6")
		)
		(pad "8" smd rect
			(at 0.499872 -0.999998)
			(size 0.254 0.7112)
			(layers "F.Cu" "F.Mask" "F.Paste")
			(net "P3V3_SSD6_CO_GATE")
		)
		(pad "9" smd rect
			(at 0 -0.999998)
			(size 0.254 0.7112)
			(layers "F.Cu" "F.Mask" "F.Paste")
			(net "P3V3_SSD6_CO_EN")
		)
		(pad "10" smd rect
			(at -0.499872 -0.999998)
			(size 0.254 0.7112)
			(layers "F.Cu" "F.Mask" "F.Paste")
			(net "P3V3_SSD6_CO_DV_DT")
		)
	)
	(footprint ""
		(layer "F.Cu")
		(at 205.101698 -304.036476 90)
		(property "Reference" "R1314"
			(at 0 0 90)
			(layer "F.SilkS")
			(hide yes)
			(effects
				(font
					(size 1.27 1.27)
				)
			)
		)
		(property "Value" ""
			(at 0 0 90)
			(layer "F.Fab")
			(effects
				(font
					(size 1.27 1.27)
				)
			)
		)
		(duplicate_pad_numbers_are_jumpers no)
		(fp_line
			(start 0.7874 -0.4064)
			(end 0.7874 0.4064)
			(stroke
				(width 0.1524)
				(type default)
			)
			(layer "F.SilkS")
		)
		(fp_line
			(start -0.7874 -0.4064)
			(end 0.7874 -0.4064)
			(stroke
				(width 0.1524)
				(type default)
			)
			(layer "F.SilkS")
		)
		(fp_line
			(start 0.7874 0.4064)
			(end -0.7874 0.4064)
			(stroke
				(width 0.1524)
				(type default)
			)
			(layer "F.SilkS")
		)
		(fp_line
			(start -0.7874 0.4064)
			(end -0.7874 -0.4064)
			(stroke
				(width 0.1524)
				(type default)
			)
			(layer "F.SilkS")
		)
		(fp_line
			(start -0.12065 -0.305054)
			(end -0.12065 -0.2794)
			(stroke
				(width 0.1)
				(type default)
			)
			(layer "F.Fab")
		)
		(fp_line
			(start -0.67945 -0.305054)
			(end -0.12065 -0.305054)
			(stroke
				(width 0.1)
				(type default)
			)
			(layer "F.Fab")
		)
		(fp_line
			(start 0.67945 -0.3048)
			(end 0.67945 0.3048)
			(stroke
				(width 0.1)
				(type default)
			)
			(layer "F.Fab")
		)
		(fp_line
			(start 0.12065 -0.3048)
			(end 0.67945 -0.3048)
			(stroke
				(width 0.1)
				(type default)
			)
			(layer "F.Fab")
		)
		(fp_line
			(start 0.12065 -0.2794)
			(end 0.12065 -0.3048)
			(stroke
				(width 0.1)
				(type default)
			)
			(layer "F.Fab")
		)
		(fp_line
			(start -0.12065 -0.2794)
			(end 0.12065 -0.2794)
			(stroke
				(width 0.1)
				(type default)
			)
			(layer "F.Fab")
		)
		(fp_line
			(start 0.120396 0.2794)
			(end -0.12065 0.2794)
			(stroke
				(width 0.1)
				(type default)
			)
			(layer "F.Fab")
		)
		(fp_line
			(start -0.12065 0.2794)
			(end -0.12065 0.3048)
			(stroke
				(width 0.1)
				(type default)
			)
			(layer "F.Fab")
		)
		(fp_line
			(start 0.67945 0.3048)
			(end 0.120396 0.3048)
			(stroke
				(width 0.1)
				(type default)
			)
			(layer "F.Fab")
		)
		(fp_line
			(start 0.120396 0.3048)
			(end 0.120396 0.2794)
			(stroke
				(width 0.1)
				(type default)
			)
			(layer "F.Fab")
		)
		(fp_line
			(start -0.12065 0.3048)
			(end -0.67945 0.3048)
			(stroke
				(width 0.1)
				(type default)
			)
			(layer "F.Fab")
		)
		(fp_line
			(start -0.67945 0.3048)
			(end -0.67945 -0.305054)
			(stroke
				(width 0.1)
				(type default)
			)
			(layer "F.Fab")
		)
		(pad "1" smd circle
			(at -0.40005 0 90)
			(size 0 0)
			(layers "F.Cu" "F.Mask" "F.Paste")
			(net "GND")
		)
		(pad "2" smd circle
			(at 0.40005 0 90)
			(size 0 0)
			(layers "F.Cu" "F.Mask" "F.Paste")
			(net "PEX1_SPARE4")
		)
	)
	(footprint ""
		(layer "F.Cu")
		(at 107.323128 -279.486868 -90)
		(property "Reference" "PR102"
			(at 0 0 270)
			(layer "F.SilkS")
			(hide yes)
			(effects
				(font
					(size 1.27 1.27)
				)
			)
		)
		(property "Value" ""
			(at 0 0 270)
			(layer "F.Fab")
			(effects
				(font
					(size 1.27 1.27)
				)
			)
		)
		(duplicate_pad_numbers_are_jumpers no)
		(fp_line
			(start -0.7874 0.4064)
			(end -0.7874 -0.4064)
			(stroke
				(width 0.1524)
				(type default)
			)
			(layer "F.SilkS")
		)
		(fp_line
			(start 0.7874 0.4064)
			(end -0.7874 0.4064)
			(stroke
				(width 0.1524)
				(type default)
			)
			(layer "F.SilkS")
		)
		(fp_line
			(start -0.7874 -0.4064)
			(end 0.7874 -0.4064)
			(stroke
				(width 0.1524)
				(type default)
			)
			(layer "F.SilkS")
		)
		(fp_line
			(start 0.7874 -0.4064)
			(end 0.7874 0.4064)
			(stroke
				(width 0.1524)
				(type default)
			)
			(layer "F.SilkS")
		)
		(fp_line
			(start -0.67945 0.3048)
			(end -0.67945 -0.305054)
			(stroke
				(width 0.1)
				(type default)
			)
			(layer "F.Fab")
		)
		(fp_line
			(start -0.12065 0.3048)
			(end -0.67945 0.3048)
			(stroke
				(width 0.1)
				(type default)
			)
			(layer "F.Fab")
		)
		(fp_line
			(start 0.120396 0.3048)
			(end 0.120396 0.2794)
			(stroke
				(width 0.1)
				(type default)
			)
			(layer "F.Fab")
		)
		(fp_line
			(start 0.67945 0.3048)
			(end 0.120396 0.3048)
			(stroke
				(width 0.1)
				(type default)
			)
			(layer "F.Fab")
		)
		(fp_line
			(start -0.12065 0.2794)
			(end -0.12065 0.3048)
			(stroke
				(width 0.1)
				(type default)
			)
			(layer "F.Fab")
		)
		(fp_line
			(start 0.120396 0.2794)
			(end -0.12065 0.2794)
			(stroke
				(width 0.1)
				(type default)
			)
			(layer "F.Fab")
		)
		(fp_line
			(start -0.12065 -0.2794)
			(end 0.12065 -0.2794)
			(stroke
				(width 0.1)
				(type default)
			)
			(layer "F.Fab")
		)
		(fp_line
			(start 0.12065 -0.2794)
			(end 0.12065 -0.3048)
			(stroke
				(width 0.1)
				(type default)
			)
			(layer "F.Fab")
		)
		(fp_line
			(start 0.12065 -0.3048)
			(end 0.67945 -0.3048)
			(stroke
				(width 0.1)
				(type default)
			)
			(layer "F.Fab")
		)
		(fp_line
			(start 0.67945 -0.3048)
			(end 0.67945 0.3048)
			(stroke
				(width 0.1)
				(type default)
			)
			(layer "F.Fab")
		)
		(fp_line
			(start -0.67945 -0.305054)
			(end -0.12065 -0.305054)
			(stroke
				(width 0.1)
				(type default)
			)
			(layer "F.Fab")
		)
		(fp_line
			(start -0.12065 -0.305054)
			(end -0.12065 -0.2794)
			(stroke
				(width 0.1)
				(type default)
			)
			(layer "F.Fab")
		)
		(pad "1" smd circle
			(at -0.40005 0 270)
			(size 0 0)
			(layers "F.Cu" "F.Mask" "F.Paste")
			(net "P0V8_PEX0_LSET1")
		)
		(pad "2" smd circle
			(at 0.40005 0 270)
			(size 0 0)
			(layers "F.Cu" "F.Mask" "F.Paste")
			(net "GND")
		)
	)
	(footprint ""
		(layer "F.Cu")
		(at 30.901894 -32.849312 90)
		(property "Reference" "R5650"
			(at 0 0 90)
			(layer "F.SilkS")
			(hide yes)
			(effects
				(font
					(size 1.27 1.27)
				)
			)
		)
		(property "Value" ""
			(at 0 0 90)
			(layer "F.Fab")
			(effects
				(font
					(size 1.27 1.27)
				)
			)
		)
		(duplicate_pad_numbers_are_jumpers no)
		(fp_line
			(start 0.7874 -0.4064)
			(end 0.7874 0.4064)
			(stroke
				(width 0.1524)
				(type default)
			)
			(layer "F.SilkS")
		)
		(fp_line
			(start -0.7874 -0.4064)
			(end 0.7874 -0.4064)
			(stroke
				(width 0.1524)
				(type default)
			)
			(layer "F.SilkS")
		)
		(fp_line
			(start 0.7874 0.4064)
			(end -0.7874 0.4064)
			(stroke
				(width 0.1524)
				(type default)
			)
			(layer "F.SilkS")
		)
		(fp_line
			(start -0.7874 0.4064)
			(end -0.7874 -0.4064)
			(stroke
				(width 0.1524)
				(type default)
			)
			(layer "F.SilkS")
		)
		(fp_line
			(start -0.12065 -0.305054)
			(end -0.12065 -0.2794)
			(stroke
				(width 0.1)
				(type default)
			)
			(layer "F.Fab")
		)
		(fp_line
			(start -0.67945 -0.305054)
			(end -0.12065 -0.305054)
			(stroke
				(width 0.1)
				(type default)
			)
			(layer "F.Fab")
		)
		(fp_line
			(start 0.67945 -0.3048)
			(end 0.67945 0.3048)
			(stroke
				(width 0.1)
				(type default)
			)
			(layer "F.Fab")
		)
		(fp_line
			(start 0.12065 -0.3048)
			(end 0.67945 -0.3048)
			(stroke
				(width 0.1)
				(type default)
			)
			(layer "F.Fab")
		)
		(fp_line
			(start 0.12065 -0.2794)
			(end 0.12065 -0.3048)
			(stroke
				(width 0.1)
				(type default)
			)
			(layer "F.Fab")
		)
		(fp_line
			(start -0.12065 -0.2794)
			(end 0.12065 -0.2794)
			(stroke
				(width 0.1)
				(type default)
			)
			(layer "F.Fab")
		)
		(fp_line
			(start 0.120396 0.2794)
			(end -0.12065 0.2794)
			(stroke
				(width 0.1)
				(type default)
			)
			(layer "F.Fab")
		)
		(fp_line
			(start -0.12065 0.2794)
			(end -0.12065 0.3048)
			(stroke
				(width 0.1)
				(type default)
			)
			(layer "F.Fab")
		)
		(fp_line
			(start 0.67945 0.3048)
			(end 0.120396 0.3048)
			(stroke
				(width 0.1)
				(type default)
			)
			(layer "F.Fab")
		)
		(fp_line
			(start 0.120396 0.3048)
			(end 0.120396 0.2794)
			(stroke
				(width 0.1)
				(type default)
			)
			(layer "F.Fab")
		)
		(fp_line
			(start -0.12065 0.3048)
			(end -0.67945 0.3048)
			(stroke
				(width 0.1)
				(type default)
			)
			(layer "F.Fab")
		)
		(fp_line
			(start -0.67945 0.3048)
			(end -0.67945 -0.305054)
			(stroke
				(width 0.1)
				(type default)
			)
			(layer "F.Fab")
		)
		(pad "1" smd circle
			(at -0.40005 0 90)
			(size 0 0)
			(layers "F.Cu" "F.Mask" "F.Paste")
			(net "RST_SMB_SSD1_ISO_R_N")
		)
		(pad "2" smd circle
			(at 0.40005 0 90)
			(size 0 0)
			(layers "F.Cu" "F.Mask" "F.Paste")
			(net "RST_SMB_SSD1_ISO_N")
		)
	)
	(footprint ""
		(layer "F.Cu")
		(at 196.119242 -142.590266 180)
		(property "Reference" "C227"
			(at 0 0 180)
			(layer "F.SilkS")
			(hide yes)
			(effects
				(font
					(size 1.27 1.27)
				)
			)
		)
		(property "Value" ""
			(at 0 0 180)
			(layer "F.Fab")
			(effects
				(font
					(size 1.27 1.27)
				)
			)
		)
		(duplicate_pad_numbers_are_jumpers no)
		(fp_line
			(start 0.299974 0.150114)
			(end -0.299974 0.150114)
			(stroke
				(width 0.1)
				(type default)
			)
			(layer "F.Fab")
		)
		(fp_line
			(start 0.299974 -0.150114)
			(end 0.299974 0.150114)
			(stroke
				(width 0.1)
				(type default)
			)
			(layer "F.Fab")
		)
		(fp_line
			(start -0.299974 0.150114)
			(end -0.299974 -0.150114)
			(stroke
				(width 0.1)
				(type default)
			)
			(layer "F.Fab")
		)
		(fp_line
			(start -0.299974 -0.150114)
			(end 0.299974 -0.150114)
			(stroke
				(width 0.1)
				(type default)
			)
			(layer "F.Fab")
		)
		(pad "1" smd rect
			(at -0.2667 0 180)
			(size 0.3048 0.381)
			(layers "F.Cu" "F.Mask" "F.Paste")
			(net "P5E_PEX1_STN0_TX_DN<8>")
		)
		(pad "2" smd rect
			(at 0.2667 0 180)
			(size 0.3048 0.381)
			(layers "F.Cu" "F.Mask" "F.Paste")
			(net "P5E_PEX1_STN0_TX_C_DN<8>")
		)
	)
	(footprint ""
		(layer "F.Cu")
		(at 332.33614 -95.264224 -90)
		(property "Reference" "C2856"
			(at 0 0 270)
			(layer "F.SilkS")
			(hide yes)
			(effects
				(font
					(size 1.27 1.27)
				)
			)
		)
		(property "Value" ""
			(at 0 0 270)
			(layer "F.Fab")
			(effects
				(font
					(size 1.27 1.27)
				)
			)
		)
		(duplicate_pad_numbers_are_jumpers no)
		(fp_line
			(start -0.7874 0.4064)
			(end -0.7874 -0.4064)
			(stroke
				(width 0.1524)
				(type default)
			)
			(layer "F.SilkS")
		)
		(fp_line
			(start 0.7874 0.4064)
			(end -0.7874 0.4064)
			(stroke
				(width 0.1524)
				(type default)
			)
			(layer "F.SilkS")
		)
		(fp_line
			(start -0.7874 -0.4064)
			(end 0.7874 -0.4064)
			(stroke
				(width 0.1524)
				(type default)
			)
			(layer "F.SilkS")
		)
		(fp_line
			(start 0.7874 -0.4064)
			(end 0.7874 0.4064)
			(stroke
				(width 0.1524)
				(type default)
			)
			(layer "F.SilkS")
		)
		(fp_line
			(start -0.67945 0.3048)
			(end -0.67945 -0.305054)
			(stroke
				(width 0.1)
				(type default)
			)
			(layer "F.Fab")
		)
		(fp_line
			(start -0.12065 0.3048)
			(end -0.67945 0.3048)
			(stroke
				(width 0.1)
				(type default)
			)
			(layer "F.Fab")
		)
		(fp_line
			(start 0.120396 0.3048)
			(end 0.120396 0.2794)
			(stroke
				(width 0.1)
				(type default)
			)
			(layer "F.Fab")
		)
		(fp_line
			(start 0.67945 0.3048)
			(end 0.120396 0.3048)
			(stroke
				(width 0.1)
				(type default)
			)
			(layer "F.Fab")
		)
		(fp_line
			(start -0.12065 0.2794)
			(end -0.12065 0.3048)
			(stroke
				(width 0.1)
				(type default)
			)
			(layer "F.Fab")
		)
		(fp_line
			(start 0.120396 0.2794)
			(end -0.12065 0.2794)
			(stroke
				(width 0.1)
				(type default)
			)
			(layer "F.Fab")
		)
		(fp_line
			(start -0.12065 -0.2794)
			(end 0.12065 -0.2794)
			(stroke
				(width 0.1)
				(type default)
			)
			(layer "F.Fab")
		)
		(fp_line
			(start 0.12065 -0.2794)
			(end 0.12065 -0.3048)
			(stroke
				(width 0.1)
				(type default)
			)
			(layer "F.Fab")
		)
		(fp_line
			(start 0.12065 -0.3048)
			(end 0.67945 -0.3048)
			(stroke
				(width 0.1)
				(type default)
			)
			(layer "F.Fab")
		)
		(fp_line
			(start 0.67945 -0.3048)
			(end 0.67945 0.3048)
			(stroke
				(width 0.1)
				(type default)
			)
			(layer "F.Fab")
		)
		(fp_line
			(start -0.67945 -0.305054)
			(end -0.12065 -0.305054)
			(stroke
				(width 0.1)
				(type default)
			)
			(layer "F.Fab")
		)
		(fp_line
			(start -0.12065 -0.305054)
			(end -0.12065 -0.2794)
			(stroke
				(width 0.1)
				(type default)
			)
			(layer "F.Fab")
		)
		(pad "1" smd circle
			(at -0.40005 0 270)
			(size 0 0)
			(layers "F.Cu" "F.Mask" "F.Paste")
			(net "P12V_NIC5_EN_R")
		)
		(pad "2" smd circle
			(at 0.40005 0 270)
			(size 0 0)
			(layers "F.Cu" "F.Mask" "F.Paste")
			(net "GND")
		)
	)
	(footprint ""
		(layer "F.Cu")
		(at 20.771104 -145.189956 180)
		(property "Reference" "R690"
			(at 0 0 180)
			(layer "F.SilkS")
			(hide yes)
			(effects
				(font
					(size 1.27 1.27)
				)
			)
		)
		(property "Value" ""
			(at 0 0 180)
			(layer "F.Fab")
			(effects
				(font
					(size 1.27 1.27)
				)
			)
		)
		(duplicate_pad_numbers_are_jumpers no)
		(fp_line
			(start 0.7874 0.4064)
			(end -0.7874 0.4064)
			(stroke
				(width 0.1524)
				(type default)
			)
			(layer "F.SilkS")
		)
		(fp_line
			(start 0.7874 -0.4064)
			(end 0.7874 0.4064)
			(stroke
				(width 0.1524)
				(type default)
			)
			(layer "F.SilkS")
		)
		(fp_line
			(start -0.7874 0.4064)
			(end -0.7874 -0.4064)
			(stroke
				(width 0.1524)
				(type default)
			)
			(layer "F.SilkS")
		)
		(fp_line
			(start -0.7874 -0.4064)
			(end 0.7874 -0.4064)
			(stroke
				(width 0.1524)
				(type default)
			)
			(layer "F.SilkS")
		)
		(fp_line
			(start 0.67945 0.3048)
			(end 0.120396 0.3048)
			(stroke
				(width 0.1)
				(type default)
			)
			(layer "F.Fab")
		)
		(fp_line
			(start 0.67945 -0.3048)
			(end 0.67945 0.3048)
			(stroke
				(width 0.1)
				(type default)
			)
			(layer "F.Fab")
		)
		(fp_line
			(start 0.12065 -0.2794)
			(end 0.12065 -0.3048)
			(stroke
				(width 0.1)
				(type default)
			)
			(layer "F.Fab")
		)
		(fp_line
			(start 0.12065 -0.3048)
			(end 0.67945 -0.3048)
			(stroke
				(width 0.1)
				(type default)
			)
			(layer "F.Fab")
		)
		(fp_line
			(start 0.120396 0.3048)
			(end 0.120396 0.2794)
			(stroke
				(width 0.1)
				(type default)
			)
			(layer "F.Fab")
		)
		(fp_line
			(start 0.120396 0.2794)
			(end -0.12065 0.2794)
			(stroke
				(width 0.1)
				(type default)
			)
			(layer "F.Fab")
		)
		(fp_line
			(start -0.12065 0.3048)
			(end -0.67945 0.3048)
			(stroke
				(width 0.1)
				(type default)
			)
			(layer "F.Fab")
		)
		(fp_line
			(start -0.12065 0.2794)
			(end -0.12065 0.3048)
			(stroke
				(width 0.1)
				(type default)
			)
			(layer "F.Fab")
		)
		(fp_line
			(start -0.12065 -0.2794)
			(end 0.12065 -0.2794)
			(stroke
				(width 0.1)
				(type default)
			)
			(layer "F.Fab")
		)
		(fp_line
			(start -0.12065 -0.305054)
			(end -0.12065 -0.2794)
			(stroke
				(width 0.1)
				(type default)
			)
			(layer "F.Fab")
		)
		(fp_line
			(start -0.67945 0.3048)
			(end -0.67945 -0.305054)
			(stroke
				(width 0.1)
				(type default)
			)
			(layer "F.Fab")
		)
		(fp_line
			(start -0.67945 -0.305054)
			(end -0.12065 -0.305054)
			(stroke
				(width 0.1)
				(type default)
			)
			(layer "F.Fab")
		)
		(pad "1" smd circle
			(at -0.40005 0 180)
			(size 0 0)
			(layers "F.Cu" "F.Mask" "F.Paste")
			(net "P12V_NIC0")
		)
		(pad "2" smd circle
			(at 0.40005 0 180)
			(size 0 0)
			(layers "F.Cu" "F.Mask" "F.Paste")
			(net "P12V_NIC0_VIN_N")
		)
	)
	(footprint ""
		(layer "F.Cu")
		(at 106.964734 -237.306612 90)
		(property "Reference" "PC292"
			(at 0 0 90)
			(layer "F.SilkS")
			(hide yes)
			(effects
				(font
					(size 1.27 1.27)
				)
			)
		)
		(property "Value" ""
			(at 0 0 90)
			(layer "F.Fab")
			(effects
				(font
					(size 1.27 1.27)
				)
			)
		)
		(duplicate_pad_numbers_are_jumpers no)
		(fp_line
			(start 1.524 -0.762)
			(end 1.524 0.762)
			(stroke
				(width 0.1524)
				(type default)
			)
			(layer "F.SilkS")
		)
		(fp_line
			(start -1.524 -0.762)
			(end 1.524 -0.762)
			(stroke
				(width 0.1524)
				(type default)
			)
			(layer "F.SilkS")
		)
		(fp_line
			(start 1.524 0.762)
			(end -1.524 0.762)
			(stroke
				(width 0.1524)
				(type default)
			)
			(layer "F.SilkS")
		)
		(fp_line
			(start -1.524 0.762)
			(end -1.524 -0.762)
			(stroke
				(width 0.1524)
				(type default)
			)
			(layer "F.SilkS")
		)
		(fp_line
			(start 1.1049 -0.724916)
			(end -1.1049 -0.724916)
			(stroke
				(width 0.1)
				(type default)
			)
			(layer "F.Fab")
		)
		(fp_line
			(start -1.1049 -0.724916)
			(end -1.1049 0.724916)
			(stroke
				(width 0.1)
				(type default)
			)
			(layer "F.Fab")
		)
		(fp_line
			(start 1.1049 0.724916)
			(end 1.1049 -0.724916)
			(stroke
				(width 0.1)
				(type default)
			)
			(layer "F.Fab")
		)
		(fp_line
			(start -1.1049 0.724916)
			(end 1.1049 0.724916)
			(stroke
				(width 0.1)
				(type default)
			)
			(layer "F.Fab")
		)
		(pad "1" smd rect
			(at -0.889 0 270)
			(size 1.016 1.27)
			(layers "F.Cu" "F.Mask" "F.Paste")
			(net "P1V8_PEX_R")
		)
		(pad "2" smd rect
			(at 0.889 0 270)
			(size 1.016 1.27)
			(layers "F.Cu" "F.Mask" "F.Paste")
			(net "GND")
		)
	)
	(footprint ""
		(layer "F.Cu")
		(at 46.434502 -30.94609 180)
		(property "Reference" "C77"
			(at 0 0 180)
			(layer "F.SilkS")
			(hide yes)
			(effects
				(font
					(size 1.27 1.27)
				)
			)
		)
		(property "Value" ""
			(at 0 0 180)
			(layer "F.Fab")
			(effects
				(font
					(size 1.27 1.27)
				)
			)
		)
		(duplicate_pad_numbers_are_jumpers no)
		(fp_line
			(start 0.299974 0.150114)
			(end -0.299974 0.150114)
			(stroke
				(width 0.1)
				(type default)
			)
			(layer "F.Fab")
		)
		(fp_line
			(start 0.299974 -0.150114)
			(end 0.299974 0.150114)
			(stroke
				(width 0.1)
				(type default)
			)
			(layer "F.Fab")
		)
		(fp_line
			(start -0.299974 0.150114)
			(end -0.299974 -0.150114)
			(stroke
				(width 0.1)
				(type default)
			)
			(layer "F.Fab")
		)
		(fp_line
			(start -0.299974 -0.150114)
			(end 0.299974 -0.150114)
			(stroke
				(width 0.1)
				(type default)
			)
			(layer "F.Fab")
		)
		(pad "1" smd rect
			(at -0.2667 0 180)
			(size 0.3048 0.381)
			(layers "F.Cu" "F.Mask" "F.Paste")
			(net "P5E_PEX0_STN2_TX_DP<41>")
		)
		(pad "2" smd rect
			(at 0.2667 0 180)
			(size 0.3048 0.381)
			(layers "F.Cu" "F.Mask" "F.Paste")
			(net "P5E_PEX0_STN2_TX_C_DP<41>")
		)
	)
	(footprint ""
		(layer "F.Cu")
		(at 45.7962 -47.20082 90)
		(property "Reference" "C205"
			(at 0 0 90)
			(layer "F.SilkS")
			(hide yes)
			(effects
				(font
					(size 1.27 1.27)
				)
			)
		)
		(property "Value" ""
			(at 0 0 90)
			(layer "F.Fab")
			(effects
				(font
					(size 1.27 1.27)
				)
			)
		)
		(duplicate_pad_numbers_are_jumpers no)
		(fp_line
			(start 0.7874 -0.4064)
			(end 0.7874 0.4064)
			(stroke
				(width 0.1524)
				(type default)
			)
			(layer "F.SilkS")
		)
		(fp_line
			(start -0.7874 -0.4064)
			(end 0.7874 -0.4064)
			(stroke
				(width 0.1524)
				(type default)
			)
			(layer "F.SilkS")
		)
		(fp_line
			(start 0.7874 0.4064)
			(end -0.7874 0.4064)
			(stroke
				(width 0.1524)
				(type default)
			)
			(layer "F.SilkS")
		)
		(fp_line
			(start -0.7874 0.4064)
			(end -0.7874 -0.4064)
			(stroke
				(width 0.1524)
				(type default)
			)
			(layer "F.SilkS")
		)
		(fp_line
			(start -0.12065 -0.305054)
			(end -0.12065 -0.2794)
			(stroke
				(width 0.1)
				(type default)
			)
			(layer "F.Fab")
		)
		(fp_line
			(start -0.67945 -0.305054)
			(end -0.12065 -0.305054)
			(stroke
				(width 0.1)
				(type default)
			)
			(layer "F.Fab")
		)
		(fp_line
			(start 0.67945 -0.3048)
			(end 0.67945 0.3048)
			(stroke
				(width 0.1)
				(type default)
			)
			(layer "F.Fab")
		)
		(fp_line
			(start 0.12065 -0.3048)
			(end 0.67945 -0.3048)
			(stroke
				(width 0.1)
				(type default)
			)
			(layer "F.Fab")
		)
		(fp_line
			(start 0.12065 -0.2794)
			(end 0.12065 -0.3048)
			(stroke
				(width 0.1)
				(type default)
			)
			(layer "F.Fab")
		)
		(fp_line
			(start -0.12065 -0.2794)
			(end 0.12065 -0.2794)
			(stroke
				(width 0.1)
				(type default)
			)
			(layer "F.Fab")
		)
		(fp_line
			(start 0.120396 0.2794)
			(end -0.12065 0.2794)
			(stroke
				(width 0.1)
				(type default)
			)
			(layer "F.Fab")
		)
		(fp_line
			(start -0.12065 0.2794)
			(end -0.12065 0.3048)
			(stroke
				(width 0.1)
				(type default)
			)
			(layer "F.Fab")
		)
		(fp_line
			(start 0.67945 0.3048)
			(end 0.120396 0.3048)
			(stroke
				(width 0.1)
				(type default)
			)
			(layer "F.Fab")
		)
		(fp_line
			(start 0.120396 0.3048)
			(end 0.120396 0.2794)
			(stroke
				(width 0.1)
				(type default)
			)
			(layer "F.Fab")
		)
		(fp_line
			(start -0.12065 0.3048)
			(end -0.67945 0.3048)
			(stroke
				(width 0.1)
				(type default)
			)
			(layer "F.Fab")
		)
		(fp_line
			(start -0.67945 0.3048)
			(end -0.67945 -0.305054)
			(stroke
				(width 0.1)
				(type default)
			)
			(layer "F.Fab")
		)
		(pad "1" smd circle
			(at -0.40005 0 90)
			(size 0 0)
			(layers "F.Cu" "F.Mask" "F.Paste")
			(net "P12V_SSD1_R")
		)
		(pad "2" smd circle
			(at 0.40005 0 90)
			(size 0 0)
			(layers "F.Cu" "F.Mask" "F.Paste")
			(net "GND")
		)
	)
	(footprint ""
		(layer "F.Cu")
		(at 8.633968 -156.288994 -90)
		(property "Reference" "PR6871"
			(at 0 0 270)
			(layer "F.SilkS")
			(hide yes)
			(effects
				(font
					(size 1.27 1.27)
				)
			)
		)
		(property "Value" ""
			(at 0 0 270)
			(layer "F.Fab")
			(effects
				(font
					(size 1.27 1.27)
				)
			)
		)
		(duplicate_pad_numbers_are_jumpers no)
		(fp_line
			(start -0.7874 0.4064)
			(end -0.7874 -0.4064)
			(stroke
				(width 0.1524)
				(type default)
			)
			(layer "F.SilkS")
		)
		(fp_line
			(start 0.7874 0.4064)
			(end -0.7874 0.4064)
			(stroke
				(width 0.1524)
				(type default)
			)
			(layer "F.SilkS")
		)
		(fp_line
			(start -0.7874 -0.4064)
			(end 0.7874 -0.4064)
			(stroke
				(width 0.1524)
				(type default)
			)
			(layer "F.SilkS")
		)
		(fp_line
			(start 0.7874 -0.4064)
			(end 0.7874 0.4064)
			(stroke
				(width 0.1524)
				(type default)
			)
			(layer "F.SilkS")
		)
		(fp_line
			(start -0.67945 0.3048)
			(end -0.67945 -0.305054)
			(stroke
				(width 0.1)
				(type default)
			)
			(layer "F.Fab")
		)
		(fp_line
			(start -0.12065 0.3048)
			(end -0.67945 0.3048)
			(stroke
				(width 0.1)
				(type default)
			)
			(layer "F.Fab")
		)
		(fp_line
			(start 0.120396 0.3048)
			(end 0.120396 0.2794)
			(stroke
				(width 0.1)
				(type default)
			)
			(layer "F.Fab")
		)
		(fp_line
			(start 0.67945 0.3048)
			(end 0.120396 0.3048)
			(stroke
				(width 0.1)
				(type default)
			)
			(layer "F.Fab")
		)
		(fp_line
			(start -0.12065 0.2794)
			(end -0.12065 0.3048)
			(stroke
				(width 0.1)
				(type default)
			)
			(layer "F.Fab")
		)
		(fp_line
			(start 0.120396 0.2794)
			(end -0.12065 0.2794)
			(stroke
				(width 0.1)
				(type default)
			)
			(layer "F.Fab")
		)
		(fp_line
			(start -0.12065 -0.2794)
			(end 0.12065 -0.2794)
			(stroke
				(width 0.1)
				(type default)
			)
			(layer "F.Fab")
		)
		(fp_line
			(start 0.12065 -0.2794)
			(end 0.12065 -0.3048)
			(stroke
				(width 0.1)
				(type default)
			)
			(layer "F.Fab")
		)
		(fp_line
			(start 0.12065 -0.3048)
			(end 0.67945 -0.3048)
			(stroke
				(width 0.1)
				(type default)
			)
			(layer "F.Fab")
		)
		(fp_line
			(start 0.67945 -0.3048)
			(end 0.67945 0.3048)
			(stroke
				(width 0.1)
				(type default)
			)
			(layer "F.Fab")
		)
		(fp_line
			(start -0.67945 -0.305054)
			(end -0.12065 -0.305054)
			(stroke
				(width 0.1)
				(type default)
			)
			(layer "F.Fab")
		)
		(fp_line
			(start -0.12065 -0.305054)
			(end -0.12065 -0.2794)
			(stroke
				(width 0.1)
				(type default)
			)
			(layer "F.Fab")
		)
		(pad "1" smd circle
			(at -0.40005 0 270)
			(size 0 0)
			(layers "F.Cu" "F.Mask" "F.Paste")
			(net "P12V_NIC0_CO_OV_FB")
		)
		(pad "2" smd circle
			(at 0.40005 0 270)
			(size 0 0)
			(layers "F.Cu" "F.Mask" "F.Paste")
			(net "GND")
		)
	)
	(footprint ""
		(layer "F.Cu")
		(at 450.415406 -42.853102 180)
		(property "Reference" "R5908"
			(at 0 0 180)
			(layer "F.SilkS")
			(hide yes)
			(effects
				(font
					(size 1.27 1.27)
				)
			)
		)
		(property "Value" ""
			(at 0 0 180)
			(layer "F.Fab")
			(effects
				(font
					(size 1.27 1.27)
				)
			)
		)
		(duplicate_pad_numbers_are_jumpers no)
		(fp_line
			(start 0.7874 0.4064)
			(end -0.7874 0.4064)
			(stroke
				(width 0.1524)
				(type default)
			)
			(layer "F.SilkS")
		)
		(fp_line
			(start 0.7874 -0.4064)
			(end 0.7874 0.4064)
			(stroke
				(width 0.1524)
				(type default)
			)
			(layer "F.SilkS")
		)
		(fp_line
			(start -0.7874 0.4064)
			(end -0.7874 -0.4064)
			(stroke
				(width 0.1524)
				(type default)
			)
			(layer "F.SilkS")
		)
		(fp_line
			(start -0.7874 -0.4064)
			(end 0.7874 -0.4064)
			(stroke
				(width 0.1524)
				(type default)
			)
			(layer "F.SilkS")
		)
		(fp_line
			(start 0.67945 0.3048)
			(end 0.120396 0.3048)
			(stroke
				(width 0.1)
				(type default)
			)
			(layer "F.Fab")
		)
		(fp_line
			(start 0.67945 -0.3048)
			(end 0.67945 0.3048)
			(stroke
				(width 0.1)
				(type default)
			)
			(layer "F.Fab")
		)
		(fp_line
			(start 0.12065 -0.2794)
			(end 0.12065 -0.3048)
			(stroke
				(width 0.1)
				(type default)
			)
			(layer "F.Fab")
		)
		(fp_line
			(start 0.12065 -0.3048)
			(end 0.67945 -0.3048)
			(stroke
				(width 0.1)
				(type default)
			)
			(layer "F.Fab")
		)
		(fp_line
			(start 0.120396 0.3048)
			(end 0.120396 0.2794)
			(stroke
				(width 0.1)
				(type default)
			)
			(layer "F.Fab")
		)
		(fp_line
			(start 0.120396 0.2794)
			(end -0.12065 0.2794)
			(stroke
				(width 0.1)
				(type default)
			)
			(layer "F.Fab")
		)
		(fp_line
			(start -0.12065 0.3048)
			(end -0.67945 0.3048)
			(stroke
				(width 0.1)
				(type default)
			)
			(layer "F.Fab")
		)
		(fp_line
			(start -0.12065 0.2794)
			(end -0.12065 0.3048)
			(stroke
				(width 0.1)
				(type default)
			)
			(layer "F.Fab")
		)
		(fp_line
			(start -0.12065 -0.2794)
			(end 0.12065 -0.2794)
			(stroke
				(width 0.1)
				(type default)
			)
			(layer "F.Fab")
		)
		(fp_line
			(start -0.12065 -0.305054)
			(end -0.12065 -0.2794)
			(stroke
				(width 0.1)
				(type default)
			)
			(layer "F.Fab")
		)
		(fp_line
			(start -0.67945 0.3048)
			(end -0.67945 -0.305054)
			(stroke
				(width 0.1)
				(type default)
			)
			(layer "F.Fab")
		)
		(fp_line
			(start -0.67945 -0.305054)
			(end -0.12065 -0.305054)
			(stroke
				(width 0.1)
				(type default)
			)
			(layer "F.Fab")
		)
		(pad "1" smd circle
			(at -0.40005 0 180)
			(size 0 0)
			(layers "F.Cu" "F.Mask" "F.Paste")
			(net "SSD15_ADC_A1")
		)
		(pad "2" smd circle
			(at 0.40005 0 180)
			(size 0 0)
			(layers "F.Cu" "F.Mask" "F.Paste")
			(net "SMB_SSD15_ADC_SCL")
		)
	)
	(footprint ""
		(layer "F.Cu")
		(at 248.094754 -274.487386)
		(property "Reference" "R794"
			(at 0 0 0)
			(layer "F.SilkS")
			(hide yes)
			(effects
				(font
					(size 1.27 1.27)
				)
			)
		)
		(property "Value" ""
			(at 0 0 0)
			(layer "F.Fab")
			(effects
				(font
					(size 1.27 1.27)
				)
			)
		)
		(duplicate_pad_numbers_are_jumpers no)
		(fp_line
			(start -0.7874 -0.4064)
			(end 0.7874 -0.4064)
			(stroke
				(width 0.1524)
				(type default)
			)
			(layer "F.SilkS")
		)
		(fp_line
			(start -0.7874 0.4064)
			(end -0.7874 -0.4064)
			(stroke
				(width 0.1524)
				(type default)
			)
			(layer "F.SilkS")
		)
		(fp_line
			(start 0.7874 -0.4064)
			(end 0.7874 0.4064)
			(stroke
				(width 0.1524)
				(type default)
			)
			(layer "F.SilkS")
		)
		(fp_line
			(start 0.7874 0.4064)
			(end -0.7874 0.4064)
			(stroke
				(width 0.1524)
				(type default)
			)
			(layer "F.SilkS")
		)
		(fp_line
			(start -0.67945 -0.305054)
			(end -0.12065 -0.305054)
			(stroke
				(width 0.1)
				(type default)
			)
			(layer "F.Fab")
		)
		(fp_line
			(start -0.67945 0.3048)
			(end -0.67945 -0.305054)
			(stroke
				(width 0.1)
				(type default)
			)
			(layer "F.Fab")
		)
		(fp_line
			(start -0.12065 -0.305054)
			(end -0.12065 -0.2794)
			(stroke
				(width 0.1)
				(type default)
			)
			(layer "F.Fab")
		)
		(fp_line
			(start -0.12065 -0.2794)
			(end 0.12065 -0.2794)
			(stroke
				(width 0.1)
				(type default)
			)
			(layer "F.Fab")
		)
		(fp_line
			(start -0.12065 0.2794)
			(end -0.12065 0.3048)
			(stroke
				(width 0.1)
				(type default)
			)
			(layer "F.Fab")
		)
		(fp_line
			(start -0.12065 0.3048)
			(end -0.67945 0.3048)
			(stroke
				(width 0.1)
				(type default)
			)
			(layer "F.Fab")
		)
		(fp_line
			(start 0.120396 0.2794)
			(end -0.12065 0.2794)
			(stroke
				(width 0.1)
				(type default)
			)
			(layer "F.Fab")
		)
		(fp_line
			(start 0.120396 0.3048)
			(end 0.120396 0.2794)
			(stroke
				(width 0.1)
				(type default)
			)
			(layer "F.Fab")
		)
		(fp_line
			(start 0.12065 -0.3048)
			(end 0.67945 -0.3048)
			(stroke
				(width 0.1)
				(type default)
			)
			(layer "F.Fab")
		)
		(fp_line
			(start 0.12065 -0.2794)
			(end 0.12065 -0.3048)
			(stroke
				(width 0.1)
				(type default)
			)
			(layer "F.Fab")
		)
		(fp_line
			(start 0.67945 -0.3048)
			(end 0.67945 0.3048)
			(stroke
				(width 0.1)
				(type default)
			)
			(layer "F.Fab")
		)
		(fp_line
			(start 0.67945 0.3048)
			(end 0.120396 0.3048)
			(stroke
				(width 0.1)
				(type default)
			)
			(layer "F.Fab")
		)
		(pad "1" smd circle
			(at -0.40005 0)
			(size 0 0)
			(layers "F.Cu" "F.Mask" "F.Paste")
			(net "PEX2_P1V25_ADC_A1")
		)
		(pad "2" smd circle
			(at 0.40005 0)
			(size 0 0)
			(layers "F.Cu" "F.Mask" "F.Paste")
			(net "GND")
		)
	)
	(footprint ""
		(layer "F.Cu")
		(at 137.390124 -72.766682 90)
		(property "Reference" "PR7064"
			(at 0 0 90)
			(layer "F.SilkS")
			(hide yes)
			(effects
				(font
					(size 1.27 1.27)
				)
			)
		)
		(property "Value" ""
			(at 0 0 90)
			(layer "F.Fab")
			(effects
				(font
					(size 1.27 1.27)
				)
			)
		)
		(duplicate_pad_numbers_are_jumpers no)
		(fp_line
			(start 0.7874 -0.4064)
			(end 0.7874 0.4064)
			(stroke
				(width 0.1524)
				(type default)
			)
			(layer "F.SilkS")
		)
		(fp_line
			(start -0.7874 -0.4064)
			(end 0.7874 -0.4064)
			(stroke
				(width 0.1524)
				(type default)
			)
			(layer "F.SilkS")
		)
		(fp_line
			(start 0.7874 0.4064)
			(end -0.7874 0.4064)
			(stroke
				(width 0.1524)
				(type default)
			)
			(layer "F.SilkS")
		)
		(fp_line
			(start -0.7874 0.4064)
			(end -0.7874 -0.4064)
			(stroke
				(width 0.1524)
				(type default)
			)
			(layer "F.SilkS")
		)
		(fp_line
			(start -0.12065 -0.305054)
			(end -0.12065 -0.2794)
			(stroke
				(width 0.1)
				(type default)
			)
			(layer "F.Fab")
		)
		(fp_line
			(start -0.67945 -0.305054)
			(end -0.12065 -0.305054)
			(stroke
				(width 0.1)
				(type default)
			)
			(layer "F.Fab")
		)
		(fp_line
			(start 0.67945 -0.3048)
			(end 0.67945 0.3048)
			(stroke
				(width 0.1)
				(type default)
			)
			(layer "F.Fab")
		)
		(fp_line
			(start 0.12065 -0.3048)
			(end 0.67945 -0.3048)
			(stroke
				(width 0.1)
				(type default)
			)
			(layer "F.Fab")
		)
		(fp_line
			(start 0.12065 -0.2794)
			(end 0.12065 -0.3048)
			(stroke
				(width 0.1)
				(type default)
			)
			(layer "F.Fab")
		)
		(fp_line
			(start -0.12065 -0.2794)
			(end 0.12065 -0.2794)
			(stroke
				(width 0.1)
				(type default)
			)
			(layer "F.Fab")
		)
		(fp_line
			(start 0.120396 0.2794)
			(end -0.12065 0.2794)
			(stroke
				(width 0.1)
				(type default)
			)
			(layer "F.Fab")
		)
		(fp_line
			(start -0.12065 0.2794)
			(end -0.12065 0.3048)
			(stroke
				(width 0.1)
				(type default)
			)
			(layer "F.Fab")
		)
		(fp_line
			(start 0.67945 0.3048)
			(end 0.120396 0.3048)
			(stroke
				(width 0.1)
				(type default)
			)
			(layer "F.Fab")
		)
		(fp_line
			(start 0.120396 0.3048)
			(end 0.120396 0.2794)
			(stroke
				(width 0.1)
				(type default)
			)
			(layer "F.Fab")
		)
		(fp_line
			(start -0.12065 0.3048)
			(end -0.67945 0.3048)
			(stroke
				(width 0.1)
				(type default)
			)
			(layer "F.Fab")
		)
		(fp_line
			(start -0.67945 0.3048)
			(end -0.67945 -0.305054)
			(stroke
				(width 0.1)
				(type default)
			)
			(layer "F.Fab")
		)
		(pad "1" smd circle
			(at -0.40005 0 90)
			(size 0 0)
			(layers "F.Cu" "F.Mask" "F.Paste")
			(net "P12V_SSD4_CO_ILIMIT")
		)
		(pad "2" smd circle
			(at 0.40005 0 90)
			(size 0 0)
			(layers "F.Cu" "F.Mask" "F.Paste")
			(net "GND")
		)
	)
	(footprint ""
		(layer "F.Cu")
		(at 29.548328 -356.244906 90)
		(property "Reference" "C182"
			(at 0 0 90)
			(layer "F.SilkS")
			(hide yes)
			(effects
				(font
					(size 1.27 1.27)
				)
			)
		)
		(property "Value" ""
			(at 0 0 90)
			(layer "F.Fab")
			(effects
				(font
					(size 1.27 1.27)
				)
			)
		)
		(duplicate_pad_numbers_are_jumpers no)
		(fp_line
			(start 0.299974 -0.150114)
			(end 0.299974 0.150114)
			(stroke
				(width 0.1)
				(type default)
			)
			(layer "F.Fab")
		)
		(fp_line
			(start -0.299974 -0.150114)
			(end 0.299974 -0.150114)
			(stroke
				(width 0.1)
				(type default)
			)
			(layer "F.Fab")
		)
		(fp_line
			(start 0.299974 0.150114)
			(end -0.299974 0.150114)
			(stroke
				(width 0.1)
				(type default)
			)
			(layer "F.Fab")
		)
		(fp_line
			(start -0.299974 0.150114)
			(end -0.299974 -0.150114)
			(stroke
				(width 0.1)
				(type default)
			)
			(layer "F.Fab")
		)
		(pad "1" smd rect
			(at -0.2667 0 90)
			(size 0.3048 0.381)
			(layers "F.Cu" "F.Mask" "F.Paste")
			(net "P5E_PEX0_STN7_TX_DN<117>")
		)
		(pad "2" smd rect
			(at 0.2667 0 90)
			(size 0.3048 0.381)
			(layers "F.Cu" "F.Mask" "F.Paste")
			(net "P5E_PEX0_STN7_TX_C_DN<117>")
		)
	)
	(footprint ""
		(layer "F.Cu")
		(at 85.757766 -299.04055 -90)
		(property "Reference" "C4185"
			(at 0 0 270)
			(layer "F.SilkS")
			(hide yes)
			(effects
				(font
					(size 1.27 1.27)
				)
			)
		)
		(property "Value" ""
			(at 0 0 270)
			(layer "F.Fab")
			(effects
				(font
					(size 1.27 1.27)
				)
			)
		)
		(duplicate_pad_numbers_are_jumpers no)
		(fp_line
			(start -0.7874 0.4064)
			(end -0.7874 -0.4064)
			(stroke
				(width 0.1524)
				(type default)
			)
			(layer "F.SilkS")
		)
		(fp_line
			(start 0.7874 0.4064)
			(end -0.7874 0.4064)
			(stroke
				(width 0.1524)
				(type default)
			)
			(layer "F.SilkS")
		)
		(fp_line
			(start -0.7874 -0.4064)
			(end 0.7874 -0.4064)
			(stroke
				(width 0.1524)
				(type default)
			)
			(layer "F.SilkS")
		)
		(fp_line
			(start 0.7874 -0.4064)
			(end 0.7874 0.4064)
			(stroke
				(width 0.1524)
				(type default)
			)
			(layer "F.SilkS")
		)
		(fp_line
			(start -0.67945 0.3048)
			(end -0.67945 -0.305054)
			(stroke
				(width 0.1)
				(type default)
			)
			(layer "F.Fab")
		)
		(fp_line
			(start -0.12065 0.3048)
			(end -0.67945 0.3048)
			(stroke
				(width 0.1)
				(type default)
			)
			(layer "F.Fab")
		)
		(fp_line
			(start 0.120396 0.3048)
			(end 0.120396 0.2794)
			(stroke
				(width 0.1)
				(type default)
			)
			(layer "F.Fab")
		)
		(fp_line
			(start 0.67945 0.3048)
			(end 0.120396 0.3048)
			(stroke
				(width 0.1)
				(type default)
			)
			(layer "F.Fab")
		)
		(fp_line
			(start -0.12065 0.2794)
			(end -0.12065 0.3048)
			(stroke
				(width 0.1)
				(type default)
			)
			(layer "F.Fab")
		)
		(fp_line
			(start 0.120396 0.2794)
			(end -0.12065 0.2794)
			(stroke
				(width 0.1)
				(type default)
			)
			(layer "F.Fab")
		)
		(fp_line
			(start -0.12065 -0.2794)
			(end 0.12065 -0.2794)
			(stroke
				(width 0.1)
				(type default)
			)
			(layer "F.Fab")
		)
		(fp_line
			(start 0.12065 -0.2794)
			(end 0.12065 -0.3048)
			(stroke
				(width 0.1)
				(type default)
			)
			(layer "F.Fab")
		)
		(fp_line
			(start 0.12065 -0.3048)
			(end 0.67945 -0.3048)
			(stroke
				(width 0.1)
				(type default)
			)
			(layer "F.Fab")
		)
		(fp_line
			(start 0.67945 -0.3048)
			(end 0.67945 0.3048)
			(stroke
				(width 0.1)
				(type default)
			)
			(layer "F.Fab")
		)
		(fp_line
			(start -0.67945 -0.305054)
			(end -0.12065 -0.305054)
			(stroke
				(width 0.1)
				(type default)
			)
			(layer "F.Fab")
		)
		(fp_line
			(start -0.12065 -0.305054)
			(end -0.12065 -0.2794)
			(stroke
				(width 0.1)
				(type default)
			)
			(layer "F.Fab")
		)
		(pad "1" smd circle
			(at -0.40005 0 270)
			(size 0 0)
			(layers "F.Cu" "F.Mask" "F.Paste")
			(net "GND")
		)
		(pad "2" smd circle
			(at 0.40005 0 270)
			(size 0 0)
			(layers "F.Cu" "F.Mask" "F.Paste")
			(net "P1V8_PEX")
		)
	)
	(footprint ""
		(layer "F.Cu")
		(at 259.130038 -284.404308 -90)
		(property "Reference" "C3385"
			(at 0 0 270)
			(layer "F.SilkS")
			(hide yes)
			(effects
				(font
					(size 1.27 1.27)
				)
			)
		)
		(property "Value" ""
			(at 0 0 270)
			(layer "F.Fab")
			(effects
				(font
					(size 1.27 1.27)
				)
			)
		)
		(duplicate_pad_numbers_are_jumpers no)
		(fp_line
			(start -1.2954 0.5842)
			(end -1.2954 -0.5842)
			(stroke
				(width 0.1524)
				(type default)
			)
			(layer "F.SilkS")
		)
		(fp_line
			(start 1.2954 0.5842)
			(end -1.2954 0.5842)
			(stroke
				(width 0.1524)
				(type default)
			)
			(layer "F.SilkS")
		)
		(fp_line
			(start -1.2954 -0.5842)
			(end 1.2954 -0.5842)
			(stroke
				(width 0.1524)
				(type default)
			)
			(layer "F.SilkS")
		)
		(fp_line
			(start 1.2954 -0.5842)
			(end 1.2954 0.5842)
			(stroke
				(width 0.1524)
				(type default)
			)
			(layer "F.SilkS")
		)
		(fp_line
			(start -0.8636 0.4572)
			(end -0.8636 0.4064)
			(stroke
				(width 0.1)
				(type default)
			)
			(layer "F.Fab")
		)
		(fp_line
			(start 0.8636 0.4572)
			(end -0.8636 0.4572)
			(stroke
				(width 0.1)
				(type default)
			)
			(layer "F.Fab")
		)
		(fp_line
			(start -1.1938 0.4064)
			(end -1.1938 -0.4064)
			(stroke
				(width 0.1)
				(type default)
			)
			(layer "F.Fab")
		)
		(fp_line
			(start -0.8636 0.4064)
			(end -1.1938 0.4064)
			(stroke
				(width 0.1)
				(type default)
			)
			(layer "F.Fab")
		)
		(fp_line
			(start 0.8636 0.4064)
			(end 0.8636 0.4572)
			(stroke
				(width 0.1)
				(type default)
			)
			(layer "F.Fab")
		)
		(fp_line
			(start 1.1938 0.4064)
			(end 0.8636 0.4064)
			(stroke
				(width 0.1)
				(type default)
			)
			(layer "F.Fab")
		)
		(fp_line
			(start -1.1938 -0.4064)
			(end -0.8636 -0.4064)
			(stroke
				(width 0.1)
				(type default)
			)
			(layer "F.Fab")
		)
		(fp_line
			(start -0.8636 -0.4064)
			(end -0.8636 -0.4572)
			(stroke
				(width 0.1)
				(type default)
			)
			(layer "F.Fab")
		)
		(fp_line
			(start 0.8636 -0.4064)
			(end 1.1938 -0.4064)
			(stroke
				(width 0.1)
				(type default)
			)
			(layer "F.Fab")
		)
		(fp_line
			(start 1.1938 -0.4064)
			(end 1.1938 0.4064)
			(stroke
				(width 0.1)
				(type default)
			)
			(layer "F.Fab")
		)
		(fp_line
			(start -0.8636 -0.4572)
			(end 0.8636 -0.4572)
			(stroke
				(width 0.1)
				(type default)
			)
			(layer "F.Fab")
		)
		(fp_line
			(start 0.8636 -0.4572)
			(end 0.8636 -0.4064)
			(stroke
				(width 0.1)
				(type default)
			)
			(layer "F.Fab")
		)
		(pad "1" smd rect
			(at -0.7366 0 180)
			(size 0.7112 0.8128)
			(layers "F.Cu" "F.Mask" "F.Paste")
			(net "P1V8_PLL0_PEX2")
		)
		(pad "2" smd rect
			(at 0.7366 0 180)
			(size 0.7112 0.8128)
			(layers "F.Cu" "F.Mask" "F.Paste")
			(net "GND")
		)
	)
	(footprint ""
		(layer "F.Cu")
		(at 39.280592 -103.803196)
		(property "Reference" "C60"
			(at 0 0 0)
			(layer "F.SilkS")
			(hide yes)
			(effects
				(font
					(size 1.27 1.27)
				)
			)
		)
		(property "Value" ""
			(at 0 0 0)
			(layer "F.Fab")
			(effects
				(font
					(size 1.27 1.27)
				)
			)
		)
		(duplicate_pad_numbers_are_jumpers no)
		(fp_line
			(start -0.299974 -0.150114)
			(end 0.299974 -0.150114)
			(stroke
				(width 0.1)
				(type default)
			)
			(layer "F.Fab")
		)
		(fp_line
			(start -0.299974 0.150114)
			(end -0.299974 -0.150114)
			(stroke
				(width 0.1)
				(type default)
			)
			(layer "F.Fab")
		)
		(fp_line
			(start 0.299974 -0.150114)
			(end 0.299974 0.150114)
			(stroke
				(width 0.1)
				(type default)
			)
			(layer "F.Fab")
		)
		(fp_line
			(start 0.299974 0.150114)
			(end -0.299974 0.150114)
			(stroke
				(width 0.1)
				(type default)
			)
			(layer "F.Fab")
		)
		(pad "1" smd rect
			(at -0.2667 0)
			(size 0.3048 0.381)
			(layers "F.Cu" "F.Mask" "F.Paste")
			(net "P5E_PEX0_STN1_TX_DN<18>")
		)
		(pad "2" smd rect
			(at 0.2667 0)
			(size 0.3048 0.381)
			(layers "F.Cu" "F.Mask" "F.Paste")
			(net "P5E_PEX0_STN1_TX_C_DN<18>")
		)
	)
	(footprint ""
		(layer "F.Cu")
		(at 199.047354 -36.686998 90)
		(property "Reference" "C3666"
			(at 0 0 90)
			(layer "F.SilkS")
			(hide yes)
			(effects
				(font
					(size 1.27 1.27)
				)
			)
		)
		(property "Value" ""
			(at 0 0 90)
			(layer "F.Fab")
			(effects
				(font
					(size 1.27 1.27)
				)
			)
		)
		(duplicate_pad_numbers_are_jumpers no)
		(fp_line
			(start 0.7874 -0.4064)
			(end 0.7874 0.4064)
			(stroke
				(width 0.1524)
				(type default)
			)
			(layer "F.SilkS")
		)
		(fp_line
			(start -0.7874 -0.4064)
			(end 0.7874 -0.4064)
			(stroke
				(width 0.1524)
				(type default)
			)
			(layer "F.SilkS")
		)
		(fp_line
			(start 0.7874 0.4064)
			(end -0.7874 0.4064)
			(stroke
				(width 0.1524)
				(type default)
			)
			(layer "F.SilkS")
		)
		(fp_line
			(start -0.7874 0.4064)
			(end -0.7874 -0.4064)
			(stroke
				(width 0.1524)
				(type default)
			)
			(layer "F.SilkS")
		)
		(fp_line
			(start -0.12065 -0.305054)
			(end -0.12065 -0.2794)
			(stroke
				(width 0.1)
				(type default)
			)
			(layer "F.Fab")
		)
		(fp_line
			(start -0.67945 -0.305054)
			(end -0.12065 -0.305054)
			(stroke
				(width 0.1)
				(type default)
			)
			(layer "F.Fab")
		)
		(fp_line
			(start 0.67945 -0.3048)
			(end 0.67945 0.3048)
			(stroke
				(width 0.1)
				(type default)
			)
			(layer "F.Fab")
		)
		(fp_line
			(start 0.12065 -0.3048)
			(end 0.67945 -0.3048)
			(stroke
				(width 0.1)
				(type default)
			)
			(layer "F.Fab")
		)
		(fp_line
			(start 0.12065 -0.2794)
			(end 0.12065 -0.3048)
			(stroke
				(width 0.1)
				(type default)
			)
			(layer "F.Fab")
		)
		(fp_line
			(start -0.12065 -0.2794)
			(end 0.12065 -0.2794)
			(stroke
				(width 0.1)
				(type default)
			)
			(layer "F.Fab")
		)
		(fp_line
			(start 0.120396 0.2794)
			(end -0.12065 0.2794)
			(stroke
				(width 0.1)
				(type default)
			)
			(layer "F.Fab")
		)
		(fp_line
			(start -0.12065 0.2794)
			(end -0.12065 0.3048)
			(stroke
				(width 0.1)
				(type default)
			)
			(layer "F.Fab")
		)
		(fp_line
			(start 0.67945 0.3048)
			(end 0.120396 0.3048)
			(stroke
				(width 0.1)
				(type default)
			)
			(layer "F.Fab")
		)
		(fp_line
			(start 0.120396 0.3048)
			(end 0.120396 0.2794)
			(stroke
				(width 0.1)
				(type default)
			)
			(layer "F.Fab")
		)
		(fp_line
			(start -0.12065 0.3048)
			(end -0.67945 0.3048)
			(stroke
				(width 0.1)
				(type default)
			)
			(layer "F.Fab")
		)
		(fp_line
			(start -0.67945 0.3048)
			(end -0.67945 -0.305054)
			(stroke
				(width 0.1)
				(type default)
			)
			(layer "F.Fab")
		)
		(pad "1" smd circle
			(at -0.40005 0 90)
			(size 0 0)
			(layers "F.Cu" "F.Mask" "F.Paste")
			(net "P3V3_AUX")
		)
		(pad "2" smd circle
			(at 0.40005 0 90)
			(size 0 0)
			(layers "F.Cu" "F.Mask" "F.Paste")
			(net "GND")
		)
	)
	(footprint ""
		(layer "F.Cu")
		(at 229.48265 -310.571642 180)
		(property "Reference" "PR171"
			(at 0 0 180)
			(layer "F.SilkS")
			(hide yes)
			(effects
				(font
					(size 1.27 1.27)
				)
			)
		)
		(property "Value" ""
			(at 0 0 180)
			(layer "F.Fab")
			(effects
				(font
					(size 1.27 1.27)
				)
			)
		)
		(duplicate_pad_numbers_are_jumpers no)
		(fp_line
			(start 0.7874 0.4064)
			(end -0.7874 0.4064)
			(stroke
				(width 0.1524)
				(type default)
			)
			(layer "F.SilkS")
		)
		(fp_line
			(start 0.7874 -0.4064)
			(end 0.7874 0.4064)
			(stroke
				(width 0.1524)
				(type default)
			)
			(layer "F.SilkS")
		)
		(fp_line
			(start -0.7874 0.4064)
			(end -0.7874 -0.4064)
			(stroke
				(width 0.1524)
				(type default)
			)
			(layer "F.SilkS")
		)
		(fp_line
			(start -0.7874 -0.4064)
			(end 0.7874 -0.4064)
			(stroke
				(width 0.1524)
				(type default)
			)
			(layer "F.SilkS")
		)
		(fp_line
			(start 0.67945 0.3048)
			(end 0.120396 0.3048)
			(stroke
				(width 0.1)
				(type default)
			)
			(layer "F.Fab")
		)
		(fp_line
			(start 0.67945 -0.3048)
			(end 0.67945 0.3048)
			(stroke
				(width 0.1)
				(type default)
			)
			(layer "F.Fab")
		)
		(fp_line
			(start 0.12065 -0.2794)
			(end 0.12065 -0.3048)
			(stroke
				(width 0.1)
				(type default)
			)
			(layer "F.Fab")
		)
		(fp_line
			(start 0.12065 -0.3048)
			(end 0.67945 -0.3048)
			(stroke
				(width 0.1)
				(type default)
			)
			(layer "F.Fab")
		)
		(fp_line
			(start 0.120396 0.3048)
			(end 0.120396 0.2794)
			(stroke
				(width 0.1)
				(type default)
			)
			(layer "F.Fab")
		)
		(fp_line
			(start 0.120396 0.2794)
			(end -0.12065 0.2794)
			(stroke
				(width 0.1)
				(type default)
			)
			(layer "F.Fab")
		)
		(fp_line
			(start -0.12065 0.3048)
			(end -0.67945 0.3048)
			(stroke
				(width 0.1)
				(type default)
			)
			(layer "F.Fab")
		)
		(fp_line
			(start -0.12065 0.2794)
			(end -0.12065 0.3048)
			(stroke
				(width 0.1)
				(type default)
			)
			(layer "F.Fab")
		)
		(fp_line
			(start -0.12065 -0.2794)
			(end 0.12065 -0.2794)
			(stroke
				(width 0.1)
				(type default)
			)
			(layer "F.Fab")
		)
		(fp_line
			(start -0.12065 -0.305054)
			(end -0.12065 -0.2794)
			(stroke
				(width 0.1)
				(type default)
			)
			(layer "F.Fab")
		)
		(fp_line
			(start -0.67945 0.3048)
			(end -0.67945 -0.305054)
			(stroke
				(width 0.1)
				(type default)
			)
			(layer "F.Fab")
		)
		(fp_line
			(start -0.67945 -0.305054)
			(end -0.12065 -0.305054)
			(stroke
				(width 0.1)
				(type default)
			)
			(layer "F.Fab")
		)
		(pad "1" smd circle
			(at -0.40005 0 180)
			(size 0 0)
			(layers "F.Cu" "F.Mask" "F.Paste")
			(net "SH_P1V25_PEX1_FB_P")
		)
		(pad "2" smd circle
			(at 0.40005 0 180)
			(size 0 0)
			(layers "F.Cu" "F.Mask" "F.Paste")
			(net "P1V25_PEX1_FB")
		)
	)
	(footprint ""
		(layer "F.Cu")
		(at 130.26263 -111.377476 -90)
		(property "Reference" "PR7013"
			(at 0 0 270)
			(layer "F.SilkS")
			(hide yes)
			(effects
				(font
					(size 1.27 1.27)
				)
			)
		)
		(property "Value" ""
			(at 0 0 270)
			(layer "F.Fab")
			(effects
				(font
					(size 1.27 1.27)
				)
			)
		)
		(duplicate_pad_numbers_are_jumpers no)
		(fp_line
			(start -0.7874 0.4064)
			(end -0.7874 -0.4064)
			(stroke
				(width 0.1524)
				(type default)
			)
			(layer "F.SilkS")
		)
		(fp_line
			(start 0.7874 0.4064)
			(end -0.7874 0.4064)
			(stroke
				(width 0.1524)
				(type default)
			)
			(layer "F.SilkS")
		)
		(fp_line
			(start -0.7874 -0.4064)
			(end 0.7874 -0.4064)
			(stroke
				(width 0.1524)
				(type default)
			)
			(layer "F.SilkS")
		)
		(fp_line
			(start 0.7874 -0.4064)
			(end 0.7874 0.4064)
			(stroke
				(width 0.1524)
				(type default)
			)
			(layer "F.SilkS")
		)
		(fp_line
			(start -0.67945 0.3048)
			(end -0.67945 -0.305054)
			(stroke
				(width 0.1)
				(type default)
			)
			(layer "F.Fab")
		)
		(fp_line
			(start -0.12065 0.3048)
			(end -0.67945 0.3048)
			(stroke
				(width 0.1)
				(type default)
			)
			(layer "F.Fab")
		)
		(fp_line
			(start 0.120396 0.3048)
			(end 0.120396 0.2794)
			(stroke
				(width 0.1)
				(type default)
			)
			(layer "F.Fab")
		)
		(fp_line
			(start 0.67945 0.3048)
			(end 0.120396 0.3048)
			(stroke
				(width 0.1)
				(type default)
			)
			(layer "F.Fab")
		)
		(fp_line
			(start -0.12065 0.2794)
			(end -0.12065 0.3048)
			(stroke
				(width 0.1)
				(type default)
			)
			(layer "F.Fab")
		)
		(fp_line
			(start 0.120396 0.2794)
			(end -0.12065 0.2794)
			(stroke
				(width 0.1)
				(type default)
			)
			(layer "F.Fab")
		)
		(fp_line
			(start -0.12065 -0.2794)
			(end 0.12065 -0.2794)
			(stroke
				(width 0.1)
				(type default)
			)
			(layer "F.Fab")
		)
		(fp_line
			(start 0.12065 -0.2794)
			(end 0.12065 -0.3048)
			(stroke
				(width 0.1)
				(type default)
			)
			(layer "F.Fab")
		)
		(fp_line
			(start 0.12065 -0.3048)
			(end 0.67945 -0.3048)
			(stroke
				(width 0.1)
				(type default)
			)
			(layer "F.Fab")
		)
		(fp_line
			(start 0.67945 -0.3048)
			(end 0.67945 0.3048)
			(stroke
				(width 0.1)
				(type default)
			)
			(layer "F.Fab")
		)
		(fp_line
			(start -0.67945 -0.305054)
			(end -0.12065 -0.305054)
			(stroke
				(width 0.1)
				(type default)
			)
			(layer "F.Fab")
		)
		(fp_line
			(start -0.12065 -0.305054)
			(end -0.12065 -0.2794)
			(stroke
				(width 0.1)
				(type default)
			)
			(layer "F.Fab")
		)
		(pad "1" smd circle
			(at -0.40005 0 270)
			(size 0 0)
			(layers "F.Cu" "F.Mask" "F.Paste")
			(net "P3V3_NIC2_CO_ILIMIT")
		)
		(pad "2" smd circle
			(at 0.40005 0 270)
			(size 0 0)
			(layers "F.Cu" "F.Mask" "F.Paste")
			(net "GND")
		)
	)
	(footprint ""
		(layer "F.Cu")
		(at 369.08359 -7.719822)
		(property "Reference" "R5818"
			(at 0 0 0)
			(layer "F.SilkS")
			(hide yes)
			(effects
				(font
					(size 1.27 1.27)
				)
			)
		)
		(property "Value" ""
			(at 0 0 0)
			(layer "F.Fab")
			(effects
				(font
					(size 1.27 1.27)
				)
			)
		)
		(duplicate_pad_numbers_are_jumpers no)
		(fp_line
			(start -0.7874 -0.4064)
			(end 0.7874 -0.4064)
			(stroke
				(width 0.1524)
				(type default)
			)
			(layer "F.SilkS")
		)
		(fp_line
			(start -0.7874 0.4064)
			(end -0.7874 -0.4064)
			(stroke
				(width 0.1524)
				(type default)
			)
			(layer "F.SilkS")
		)
		(fp_line
			(start 0.7874 -0.4064)
			(end 0.7874 0.4064)
			(stroke
				(width 0.1524)
				(type default)
			)
			(layer "F.SilkS")
		)
		(fp_line
			(start 0.7874 0.4064)
			(end -0.7874 0.4064)
			(stroke
				(width 0.1524)
				(type default)
			)
			(layer "F.SilkS")
		)
		(fp_line
			(start -0.67945 -0.305054)
			(end -0.12065 -0.305054)
			(stroke
				(width 0.1)
				(type default)
			)
			(layer "F.Fab")
		)
		(fp_line
			(start -0.67945 0.3048)
			(end -0.67945 -0.305054)
			(stroke
				(width 0.1)
				(type default)
			)
			(layer "F.Fab")
		)
		(fp_line
			(start -0.12065 -0.305054)
			(end -0.12065 -0.2794)
			(stroke
				(width 0.1)
				(type default)
			)
			(layer "F.Fab")
		)
		(fp_line
			(start -0.12065 -0.2794)
			(end 0.12065 -0.2794)
			(stroke
				(width 0.1)
				(type default)
			)
			(layer "F.Fab")
		)
		(fp_line
			(start -0.12065 0.2794)
			(end -0.12065 0.3048)
			(stroke
				(width 0.1)
				(type default)
			)
			(layer "F.Fab")
		)
		(fp_line
			(start -0.12065 0.3048)
			(end -0.67945 0.3048)
			(stroke
				(width 0.1)
				(type default)
			)
			(layer "F.Fab")
		)
		(fp_line
			(start 0.120396 0.2794)
			(end -0.12065 0.2794)
			(stroke
				(width 0.1)
				(type default)
			)
			(layer "F.Fab")
		)
		(fp_line
			(start 0.120396 0.3048)
			(end 0.120396 0.2794)
			(stroke
				(width 0.1)
				(type default)
			)
			(layer "F.Fab")
		)
		(fp_line
			(start 0.12065 -0.3048)
			(end 0.67945 -0.3048)
			(stroke
				(width 0.1)
				(type default)
			)
			(layer "F.Fab")
		)
		(fp_line
			(start 0.12065 -0.2794)
			(end 0.12065 -0.3048)
			(stroke
				(width 0.1)
				(type default)
			)
			(layer "F.Fab")
		)
		(fp_line
			(start 0.67945 -0.3048)
			(end 0.67945 0.3048)
			(stroke
				(width 0.1)
				(type default)
			)
			(layer "F.Fab")
		)
		(fp_line
			(start 0.67945 0.3048)
			(end 0.120396 0.3048)
			(stroke
				(width 0.1)
				(type default)
			)
			(layer "F.Fab")
		)
		(pad "1" smd circle
			(at -0.40005 0)
			(size 0 0)
			(layers "F.Cu" "F.Mask" "F.Paste")
			(net "SMB_BIC_I2C6_MUX_THERMAL_R_SDA")
		)
		(pad "2" smd circle
			(at 0.40005 0)
			(size 0 0)
			(layers "F.Cu" "F.Mask" "F.Paste")
			(net "SMB_LM75_3_SDA")
		)
	)
	(footprint ""
		(layer "F.Cu")
		(at 399.348452 -166.302944 90)
		(property "Reference" "R351"
			(at 0 0 90)
			(layer "F.SilkS")
			(hide yes)
			(effects
				(font
					(size 1.27 1.27)
				)
			)
		)
		(property "Value" ""
			(at 0 0 90)
			(layer "F.Fab")
			(effects
				(font
					(size 1.27 1.27)
				)
			)
		)
		(duplicate_pad_numbers_are_jumpers no)
		(fp_line
			(start 0.7874 -0.4064)
			(end 0.7874 0.4064)
			(stroke
				(width 0.1524)
				(type default)
			)
			(layer "F.SilkS")
		)
		(fp_line
			(start -0.7874 -0.4064)
			(end 0.7874 -0.4064)
			(stroke
				(width 0.1524)
				(type default)
			)
			(layer "F.SilkS")
		)
		(fp_line
			(start 0.7874 0.4064)
			(end -0.7874 0.4064)
			(stroke
				(width 0.1524)
				(type default)
			)
			(layer "F.SilkS")
		)
		(fp_line
			(start -0.7874 0.4064)
			(end -0.7874 -0.4064)
			(stroke
				(width 0.1524)
				(type default)
			)
			(layer "F.SilkS")
		)
		(fp_line
			(start -0.12065 -0.305054)
			(end -0.12065 -0.2794)
			(stroke
				(width 0.1)
				(type default)
			)
			(layer "F.Fab")
		)
		(fp_line
			(start -0.67945 -0.305054)
			(end -0.12065 -0.305054)
			(stroke
				(width 0.1)
				(type default)
			)
			(layer "F.Fab")
		)
		(fp_line
			(start 0.67945 -0.3048)
			(end 0.67945 0.3048)
			(stroke
				(width 0.1)
				(type default)
			)
			(layer "F.Fab")
		)
		(fp_line
			(start 0.12065 -0.3048)
			(end 0.67945 -0.3048)
			(stroke
				(width 0.1)
				(type default)
			)
			(layer "F.Fab")
		)
		(fp_line
			(start 0.12065 -0.2794)
			(end 0.12065 -0.3048)
			(stroke
				(width 0.1)
				(type default)
			)
			(layer "F.Fab")
		)
		(fp_line
			(start -0.12065 -0.2794)
			(end 0.12065 -0.2794)
			(stroke
				(width 0.1)
				(type default)
			)
			(layer "F.Fab")
		)
		(fp_line
			(start 0.120396 0.2794)
			(end -0.12065 0.2794)
			(stroke
				(width 0.1)
				(type default)
			)
			(layer "F.Fab")
		)
		(fp_line
			(start -0.12065 0.2794)
			(end -0.12065 0.3048)
			(stroke
				(width 0.1)
				(type default)
			)
			(layer "F.Fab")
		)
		(fp_line
			(start 0.67945 0.3048)
			(end 0.120396 0.3048)
			(stroke
				(width 0.1)
				(type default)
			)
			(layer "F.Fab")
		)
		(fp_line
			(start 0.120396 0.3048)
			(end 0.120396 0.2794)
			(stroke
				(width 0.1)
				(type default)
			)
			(layer "F.Fab")
		)
		(fp_line
			(start -0.12065 0.3048)
			(end -0.67945 0.3048)
			(stroke
				(width 0.1)
				(type default)
			)
			(layer "F.Fab")
		)
		(fp_line
			(start -0.67945 0.3048)
			(end -0.67945 -0.305054)
			(stroke
				(width 0.1)
				(type default)
			)
			(layer "F.Fab")
		)
		(pad "1" smd circle
			(at -0.40005 0 90)
			(size 0 0)
			(layers "F.Cu" "F.Mask" "F.Paste")
			(net "RST_NIC6_PERST0_R_N")
		)
		(pad "2" smd circle
			(at 0.40005 0 90)
			(size 0 0)
			(layers "F.Cu" "F.Mask" "F.Paste")
			(net "RST_HP_NIC6_BUF_N")
		)
	)
	(footprint ""
		(layer "F.Cu")
		(at 397.967962 -18.437098)
		(property "Reference" "R1722"
			(at 0 0 0)
			(layer "F.SilkS")
			(hide yes)
			(effects
				(font
					(size 1.27 1.27)
				)
			)
		)
		(property "Value" ""
			(at 0 0 0)
			(layer "F.Fab")
			(effects
				(font
					(size 1.27 1.27)
				)
			)
		)
		(duplicate_pad_numbers_are_jumpers no)
		(fp_line
			(start -0.7874 -0.4064)
			(end 0.7874 -0.4064)
			(stroke
				(width 0.1524)
				(type default)
			)
			(layer "F.SilkS")
		)
		(fp_line
			(start -0.7874 0.4064)
			(end -0.7874 -0.4064)
			(stroke
				(width 0.1524)
				(type default)
			)
			(layer "F.SilkS")
		)
		(fp_line
			(start 0.7874 -0.4064)
			(end 0.7874 0.4064)
			(stroke
				(width 0.1524)
				(type default)
			)
			(layer "F.SilkS")
		)
		(fp_line
			(start 0.7874 0.4064)
			(end -0.7874 0.4064)
			(stroke
				(width 0.1524)
				(type default)
			)
			(layer "F.SilkS")
		)
		(fp_line
			(start -0.67945 -0.305054)
			(end -0.12065 -0.305054)
			(stroke
				(width 0.1)
				(type default)
			)
			(layer "F.Fab")
		)
		(fp_line
			(start -0.67945 0.3048)
			(end -0.67945 -0.305054)
			(stroke
				(width 0.1)
				(type default)
			)
			(layer "F.Fab")
		)
		(fp_line
			(start -0.12065 -0.305054)
			(end -0.12065 -0.2794)
			(stroke
				(width 0.1)
				(type default)
			)
			(layer "F.Fab")
		)
		(fp_line
			(start -0.12065 -0.2794)
			(end 0.12065 -0.2794)
			(stroke
				(width 0.1)
				(type default)
			)
			(layer "F.Fab")
		)
		(fp_line
			(start -0.12065 0.2794)
			(end -0.12065 0.3048)
			(stroke
				(width 0.1)
				(type default)
			)
			(layer "F.Fab")
		)
		(fp_line
			(start -0.12065 0.3048)
			(end -0.67945 0.3048)
			(stroke
				(width 0.1)
				(type default)
			)
			(layer "F.Fab")
		)
		(fp_line
			(start 0.120396 0.2794)
			(end -0.12065 0.2794)
			(stroke
				(width 0.1)
				(type default)
			)
			(layer "F.Fab")
		)
		(fp_line
			(start 0.120396 0.3048)
			(end 0.120396 0.2794)
			(stroke
				(width 0.1)
				(type default)
			)
			(layer "F.Fab")
		)
		(fp_line
			(start 0.12065 -0.3048)
			(end 0.67945 -0.3048)
			(stroke
				(width 0.1)
				(type default)
			)
			(layer "F.Fab")
		)
		(fp_line
			(start 0.12065 -0.2794)
			(end 0.12065 -0.3048)
			(stroke
				(width 0.1)
				(type default)
			)
			(layer "F.Fab")
		)
		(fp_line
			(start 0.67945 -0.3048)
			(end 0.67945 0.3048)
			(stroke
				(width 0.1)
				(type default)
			)
			(layer "F.Fab")
		)
		(fp_line
			(start 0.67945 0.3048)
			(end 0.120396 0.3048)
			(stroke
				(width 0.1)
				(type default)
			)
			(layer "F.Fab")
		)
		(pad "1" smd circle
			(at -0.40005 0)
			(size 0 0)
			(layers "F.Cu" "F.Mask" "F.Paste")
			(net "SMB_ISO_SSD13_R_SCL")
		)
		(pad "2" smd circle
			(at 0.40005 0)
			(size 0 0)
			(layers "F.Cu" "F.Mask" "F.Paste")
			(net "SMB_ISO_SSD13_SCL")
		)
	)
	(footprint ""
		(layer "F.Cu")
		(at 392.092434 -31.825184 180)
		(property "Reference" "C709"
			(at 0 0 180)
			(layer "F.SilkS")
			(hide yes)
			(effects
				(font
					(size 1.27 1.27)
				)
			)
		)
		(property "Value" ""
			(at 0 0 180)
			(layer "F.Fab")
			(effects
				(font
					(size 1.27 1.27)
				)
			)
		)
		(duplicate_pad_numbers_are_jumpers no)
		(fp_line
			(start 0.299974 0.150114)
			(end -0.299974 0.150114)
			(stroke
				(width 0.1)
				(type default)
			)
			(layer "F.Fab")
		)
		(fp_line
			(start 0.299974 -0.150114)
			(end 0.299974 0.150114)
			(stroke
				(width 0.1)
				(type default)
			)
			(layer "F.Fab")
		)
		(fp_line
			(start -0.299974 0.150114)
			(end -0.299974 -0.150114)
			(stroke
				(width 0.1)
				(type default)
			)
			(layer "F.Fab")
		)
		(fp_line
			(start -0.299974 -0.150114)
			(end 0.299974 -0.150114)
			(stroke
				(width 0.1)
				(type default)
			)
			(layer "F.Fab")
		)
		(pad "1" smd rect
			(at -0.2667 0 180)
			(size 0.3048 0.381)
			(layers "F.Cu" "F.Mask" "F.Paste")
			(net "P5E_PEX3_STN2_TX_DN<42>")
		)
		(pad "2" smd rect
			(at 0.2667 0 180)
			(size 0.3048 0.381)
			(layers "F.Cu" "F.Mask" "F.Paste")
			(net "P5E_PEX3_STN2_TX_C_DN<42>")
		)
	)
	(footprint ""
		(layer "F.Cu")
		(at 169.293032 -356.244906 90)
		(property "Reference" "C395"
			(at 0 0 90)
			(layer "F.SilkS")
			(hide yes)
			(effects
				(font
					(size 1.27 1.27)
				)
			)
		)
		(property "Value" ""
			(at 0 0 90)
			(layer "F.Fab")
			(effects
				(font
					(size 1.27 1.27)
				)
			)
		)
		(duplicate_pad_numbers_are_jumpers no)
		(fp_line
			(start 0.299974 -0.150114)
			(end 0.299974 0.150114)
			(stroke
				(width 0.1)
				(type default)
			)
			(layer "F.Fab")
		)
		(fp_line
			(start -0.299974 -0.150114)
			(end 0.299974 -0.150114)
			(stroke
				(width 0.1)
				(type default)
			)
			(layer "F.Fab")
		)
		(fp_line
			(start 0.299974 0.150114)
			(end -0.299974 0.150114)
			(stroke
				(width 0.1)
				(type default)
			)
			(layer "F.Fab")
		)
		(fp_line
			(start -0.299974 0.150114)
			(end -0.299974 -0.150114)
			(stroke
				(width 0.1)
				(type default)
			)
			(layer "F.Fab")
		)
		(pad "1" smd rect
			(at -0.2667 0 90)
			(size 0.3048 0.381)
			(layers "F.Cu" "F.Mask" "F.Paste")
			(net "P5E_PEX1_STN7_TX_DN<116>")
		)
		(pad "2" smd rect
			(at 0.2667 0 90)
			(size 0.3048 0.381)
			(layers "F.Cu" "F.Mask" "F.Paste")
			(net "P5E_PEX1_STN7_TX_C_DN<116>")
		)
	)
	(footprint ""
		(layer "F.Cu")
		(at 103.011224 -85.239606 180)
		(property "Reference" "R1469"
			(at 0 0 180)
			(layer "F.SilkS")
			(hide yes)
			(effects
				(font
					(size 1.27 1.27)
				)
			)
		)
		(property "Value" ""
			(at 0 0 180)
			(layer "F.Fab")
			(effects
				(font
					(size 1.27 1.27)
				)
			)
		)
		(duplicate_pad_numbers_are_jumpers no)
		(fp_line
			(start 0.7874 0.4064)
			(end -0.7874 0.4064)
			(stroke
				(width 0.1524)
				(type default)
			)
			(layer "F.SilkS")
		)
		(fp_line
			(start 0.7874 -0.4064)
			(end 0.7874 0.4064)
			(stroke
				(width 0.1524)
				(type default)
			)
			(layer "F.SilkS")
		)
		(fp_line
			(start -0.7874 0.4064)
			(end -0.7874 -0.4064)
			(stroke
				(width 0.1524)
				(type default)
			)
			(layer "F.SilkS")
		)
		(fp_line
			(start -0.7874 -0.4064)
			(end 0.7874 -0.4064)
			(stroke
				(width 0.1524)
				(type default)
			)
			(layer "F.SilkS")
		)
		(fp_line
			(start 0.67945 0.3048)
			(end 0.120396 0.3048)
			(stroke
				(width 0.1)
				(type default)
			)
			(layer "F.Fab")
		)
		(fp_line
			(start 0.67945 -0.3048)
			(end 0.67945 0.3048)
			(stroke
				(width 0.1)
				(type default)
			)
			(layer "F.Fab")
		)
		(fp_line
			(start 0.12065 -0.2794)
			(end 0.12065 -0.3048)
			(stroke
				(width 0.1)
				(type default)
			)
			(layer "F.Fab")
		)
		(fp_line
			(start 0.12065 -0.3048)
			(end 0.67945 -0.3048)
			(stroke
				(width 0.1)
				(type default)
			)
			(layer "F.Fab")
		)
		(fp_line
			(start 0.120396 0.3048)
			(end 0.120396 0.2794)
			(stroke
				(width 0.1)
				(type default)
			)
			(layer "F.Fab")
		)
		(fp_line
			(start 0.120396 0.2794)
			(end -0.12065 0.2794)
			(stroke
				(width 0.1)
				(type default)
			)
			(layer "F.Fab")
		)
		(fp_line
			(start -0.12065 0.3048)
			(end -0.67945 0.3048)
			(stroke
				(width 0.1)
				(type default)
			)
			(layer "F.Fab")
		)
		(fp_line
			(start -0.12065 0.2794)
			(end -0.12065 0.3048)
			(stroke
				(width 0.1)
				(type default)
			)
			(layer "F.Fab")
		)
		(fp_line
			(start -0.12065 -0.2794)
			(end 0.12065 -0.2794)
			(stroke
				(width 0.1)
				(type default)
			)
			(layer "F.Fab")
		)
		(fp_line
			(start -0.12065 -0.305054)
			(end -0.12065 -0.2794)
			(stroke
				(width 0.1)
				(type default)
			)
			(layer "F.Fab")
		)
		(fp_line
			(start -0.67945 0.3048)
			(end -0.67945 -0.305054)
			(stroke
				(width 0.1)
				(type default)
			)
			(layer "F.Fab")
		)
		(fp_line
			(start -0.67945 -0.305054)
			(end -0.12065 -0.305054)
			(stroke
				(width 0.1)
				(type default)
			)
			(layer "F.Fab")
		)
		(pad "1" smd circle
			(at -0.40005 0 180)
			(size 0 0)
			(layers "F.Cu" "F.Mask" "F.Paste")
			(net "SMB_BMC_9ZXL0851_0_7_SDA")
		)
		(pad "2" smd circle
			(at 0.40005 0 180)
			(size 0 0)
			(layers "F.Cu" "F.Mask" "F.Paste")
			(net "SMB_CLK_ISO_R_SDA")
		)
	)
	(footprint ""
		(layer "F.Cu")
		(at 80.019398 -130.794506 180)
		(property "Reference" "C23"
			(at 0 0 180)
			(layer "F.SilkS")
			(hide yes)
			(effects
				(font
					(size 1.27 1.27)
				)
			)
		)
		(property "Value" ""
			(at 0 0 180)
			(layer "F.Fab")
			(effects
				(font
					(size 1.27 1.27)
				)
			)
		)
		(duplicate_pad_numbers_are_jumpers no)
		(fp_line
			(start 0.299974 0.150114)
			(end -0.299974 0.150114)
			(stroke
				(width 0.1)
				(type default)
			)
			(layer "F.Fab")
		)
		(fp_line
			(start 0.299974 -0.150114)
			(end 0.299974 0.150114)
			(stroke
				(width 0.1)
				(type default)
			)
			(layer "F.Fab")
		)
		(fp_line
			(start -0.299974 0.150114)
			(end -0.299974 -0.150114)
			(stroke
				(width 0.1)
				(type default)
			)
			(layer "F.Fab")
		)
		(fp_line
			(start -0.299974 -0.150114)
			(end 0.299974 -0.150114)
			(stroke
				(width 0.1)
				(type default)
			)
			(layer "F.Fab")
		)
		(pad "1" smd rect
			(at -0.2667 0 180)
			(size 0.3048 0.381)
			(layers "F.Cu" "F.Mask" "F.Paste")
			(net "P5E_PEX0_STN0_TX_DP<4>")
		)
		(pad "2" smd rect
			(at 0.2667 0 180)
			(size 0.3048 0.381)
			(layers "F.Cu" "F.Mask" "F.Paste")
			(net "P5E_PEX0_STN0_TX_C_DP<4>")
		)
	)
	(footprint ""
		(layer "F.Cu")
		(at 372.782084 -38.041072 180)
		(property "Reference" "R6109"
			(at 0 0 180)
			(layer "F.SilkS")
			(hide yes)
			(effects
				(font
					(size 1.27 1.27)
				)
			)
		)
		(property "Value" ""
			(at 0 0 180)
			(layer "F.Fab")
			(effects
				(font
					(size 1.27 1.27)
				)
			)
		)
		(duplicate_pad_numbers_are_jumpers no)
		(fp_line
			(start 0.7874 0.4064)
			(end -0.7874 0.4064)
			(stroke
				(width 0.1524)
				(type default)
			)
			(layer "F.SilkS")
		)
		(fp_line
			(start 0.7874 -0.4064)
			(end 0.7874 0.4064)
			(stroke
				(width 0.1524)
				(type default)
			)
			(layer "F.SilkS")
		)
		(fp_line
			(start -0.7874 0.4064)
			(end -0.7874 -0.4064)
			(stroke
				(width 0.1524)
				(type default)
			)
			(layer "F.SilkS")
		)
		(fp_line
			(start -0.7874 -0.4064)
			(end 0.7874 -0.4064)
			(stroke
				(width 0.1524)
				(type default)
			)
			(layer "F.SilkS")
		)
		(fp_line
			(start 0.67945 0.3048)
			(end 0.120396 0.3048)
			(stroke
				(width 0.1)
				(type default)
			)
			(layer "F.Fab")
		)
		(fp_line
			(start 0.67945 -0.3048)
			(end 0.67945 0.3048)
			(stroke
				(width 0.1)
				(type default)
			)
			(layer "F.Fab")
		)
		(fp_line
			(start 0.12065 -0.2794)
			(end 0.12065 -0.3048)
			(stroke
				(width 0.1)
				(type default)
			)
			(layer "F.Fab")
		)
		(fp_line
			(start 0.12065 -0.3048)
			(end 0.67945 -0.3048)
			(stroke
				(width 0.1)
				(type default)
			)
			(layer "F.Fab")
		)
		(fp_line
			(start 0.120396 0.3048)
			(end 0.120396 0.2794)
			(stroke
				(width 0.1)
				(type default)
			)
			(layer "F.Fab")
		)
		(fp_line
			(start 0.120396 0.2794)
			(end -0.12065 0.2794)
			(stroke
				(width 0.1)
				(type default)
			)
			(layer "F.Fab")
		)
		(fp_line
			(start -0.12065 0.3048)
			(end -0.67945 0.3048)
			(stroke
				(width 0.1)
				(type default)
			)
			(layer "F.Fab")
		)
		(fp_line
			(start -0.12065 0.2794)
			(end -0.12065 0.3048)
			(stroke
				(width 0.1)
				(type default)
			)
			(layer "F.Fab")
		)
		(fp_line
			(start -0.12065 -0.2794)
			(end 0.12065 -0.2794)
			(stroke
				(width 0.1)
				(type default)
			)
			(layer "F.Fab")
		)
		(fp_line
			(start -0.12065 -0.305054)
			(end -0.12065 -0.2794)
			(stroke
				(width 0.1)
				(type default)
			)
			(layer "F.Fab")
		)
		(fp_line
			(start -0.67945 0.3048)
			(end -0.67945 -0.305054)
			(stroke
				(width 0.1)
				(type default)
			)
			(layer "F.Fab")
		)
		(fp_line
			(start -0.67945 -0.305054)
			(end -0.12065 -0.305054)
			(stroke
				(width 0.1)
				(type default)
			)
			(layer "F.Fab")
		)
		(pad "1" smd circle
			(at -0.40005 0 180)
			(size 0 0)
			(layers "F.Cu" "F.Mask" "F.Paste")
			(net "P5V_AUX")
		)
		(pad "2" smd circle
			(at 0.40005 0 180)
			(size 0 0)
			(layers "F.Cu" "F.Mask" "F.Paste")
			(net "P3V3_SSD13_PG_G2")
		)
	)
	(footprint ""
		(layer "F.Cu")
		(at 444.09233 -28.225242 180)
		(property "Reference" "C729"
			(at 0 0 180)
			(layer "F.SilkS")
			(hide yes)
			(effects
				(font
					(size 1.27 1.27)
				)
			)
		)
		(property "Value" ""
			(at 0 0 180)
			(layer "F.Fab")
			(effects
				(font
					(size 1.27 1.27)
				)
			)
		)
		(duplicate_pad_numbers_are_jumpers no)
		(fp_line
			(start 0.299974 0.150114)
			(end -0.299974 0.150114)
			(stroke
				(width 0.1)
				(type default)
			)
			(layer "F.Fab")
		)
		(fp_line
			(start 0.299974 -0.150114)
			(end 0.299974 0.150114)
			(stroke
				(width 0.1)
				(type default)
			)
			(layer "F.Fab")
		)
		(fp_line
			(start -0.299974 0.150114)
			(end -0.299974 -0.150114)
			(stroke
				(width 0.1)
				(type default)
			)
			(layer "F.Fab")
		)
		(fp_line
			(start -0.299974 -0.150114)
			(end 0.299974 -0.150114)
			(stroke
				(width 0.1)
				(type default)
			)
			(layer "F.Fab")
		)
		(pad "1" smd rect
			(at -0.2667 0 180)
			(size 0.3048 0.381)
			(layers "F.Cu" "F.Mask" "F.Paste")
			(net "P5E_PEX3_STN2_TX_DN<32>")
		)
		(pad "2" smd rect
			(at 0.2667 0 180)
			(size 0.3048 0.381)
			(layers "F.Cu" "F.Mask" "F.Paste")
			(net "P5E_PEX3_STN2_TX_C_DN<32>")
		)
	)
	(footprint ""
		(layer "F.Cu")
		(at 257.176016 -344.916252)
		(property "Reference" "R6824"
			(at 0 0 0)
			(layer "F.SilkS")
			(hide yes)
			(effects
				(font
					(size 1.27 1.27)
				)
			)
		)
		(property "Value" ""
			(at 0 0 0)
			(layer "F.Fab")
			(effects
				(font
					(size 1.27 1.27)
				)
			)
		)
		(duplicate_pad_numbers_are_jumpers no)
		(fp_line
			(start -0.7874 -0.4064)
			(end 0.7874 -0.4064)
			(stroke
				(width 0.1524)
				(type default)
			)
			(layer "F.SilkS")
		)
		(fp_line
			(start -0.7874 0.4064)
			(end -0.7874 -0.4064)
			(stroke
				(width 0.1524)
				(type default)
			)
			(layer "F.SilkS")
		)
		(fp_line
			(start 0.7874 -0.4064)
			(end 0.7874 0.4064)
			(stroke
				(width 0.1524)
				(type default)
			)
			(layer "F.SilkS")
		)
		(fp_line
			(start 0.7874 0.4064)
			(end -0.7874 0.4064)
			(stroke
				(width 0.1524)
				(type default)
			)
			(layer "F.SilkS")
		)
		(fp_line
			(start -0.67945 -0.305054)
			(end -0.12065 -0.305054)
			(stroke
				(width 0.1)
				(type default)
			)
			(layer "F.Fab")
		)
		(fp_line
			(start -0.67945 0.3048)
			(end -0.67945 -0.305054)
			(stroke
				(width 0.1)
				(type default)
			)
			(layer "F.Fab")
		)
		(fp_line
			(start -0.12065 -0.305054)
			(end -0.12065 -0.2794)
			(stroke
				(width 0.1)
				(type default)
			)
			(layer "F.Fab")
		)
		(fp_line
			(start -0.12065 -0.2794)
			(end 0.12065 -0.2794)
			(stroke
				(width 0.1)
				(type default)
			)
			(layer "F.Fab")
		)
		(fp_line
			(start -0.12065 0.2794)
			(end -0.12065 0.3048)
			(stroke
				(width 0.1)
				(type default)
			)
			(layer "F.Fab")
		)
		(fp_line
			(start -0.12065 0.3048)
			(end -0.67945 0.3048)
			(stroke
				(width 0.1)
				(type default)
			)
			(layer "F.Fab")
		)
		(fp_line
			(start 0.120396 0.2794)
			(end -0.12065 0.2794)
			(stroke
				(width 0.1)
				(type default)
			)
			(layer "F.Fab")
		)
		(fp_line
			(start 0.120396 0.3048)
			(end 0.120396 0.2794)
			(stroke
				(width 0.1)
				(type default)
			)
			(layer "F.Fab")
		)
		(fp_line
			(start 0.12065 -0.3048)
			(end 0.67945 -0.3048)
			(stroke
				(width 0.1)
				(type default)
			)
			(layer "F.Fab")
		)
		(fp_line
			(start 0.12065 -0.2794)
			(end 0.12065 -0.3048)
			(stroke
				(width 0.1)
				(type default)
			)
			(layer "F.Fab")
		)
		(fp_line
			(start 0.67945 -0.3048)
			(end 0.67945 0.3048)
			(stroke
				(width 0.1)
				(type default)
			)
			(layer "F.Fab")
		)
		(fp_line
			(start 0.67945 0.3048)
			(end 0.120396 0.3048)
			(stroke
				(width 0.1)
				(type default)
			)
			(layer "F.Fab")
		)
		(pad "1" smd circle
			(at -0.40005 0)
			(size 0 0)
			(layers "F.Cu" "F.Mask" "F.Paste")
			(net "P3V3_AUX")
		)
		(pad "2" smd circle
			(at 0.40005 0)
			(size 0 0)
			(layers "F.Cu" "F.Mask" "F.Paste")
			(net "HSC_OC_LT6700_VS")
		)
	)
	(footprint ""
		(layer "F.Cu")
		(at 18.722594 -44.341542 90)
		(property "Reference" "R514"
			(at 0 0 90)
			(layer "F.SilkS")
			(hide yes)
			(effects
				(font
					(size 1.27 1.27)
				)
			)
		)
		(property "Value" ""
			(at 0 0 90)
			(layer "F.Fab")
			(effects
				(font
					(size 1.27 1.27)
				)
			)
		)
		(duplicate_pad_numbers_are_jumpers no)
		(fp_line
			(start 0.7874 -0.4064)
			(end 0.7874 0.4064)
			(stroke
				(width 0.1524)
				(type default)
			)
			(layer "F.SilkS")
		)
		(fp_line
			(start -0.7874 -0.4064)
			(end 0.7874 -0.4064)
			(stroke
				(width 0.1524)
				(type default)
			)
			(layer "F.SilkS")
		)
		(fp_line
			(start 0.7874 0.4064)
			(end -0.7874 0.4064)
			(stroke
				(width 0.1524)
				(type default)
			)
			(layer "F.SilkS")
		)
		(fp_line
			(start -0.7874 0.4064)
			(end -0.7874 -0.4064)
			(stroke
				(width 0.1524)
				(type default)
			)
			(layer "F.SilkS")
		)
		(fp_line
			(start -0.12065 -0.305054)
			(end -0.12065 -0.2794)
			(stroke
				(width 0.1)
				(type default)
			)
			(layer "F.Fab")
		)
		(fp_line
			(start -0.67945 -0.305054)
			(end -0.12065 -0.305054)
			(stroke
				(width 0.1)
				(type default)
			)
			(layer "F.Fab")
		)
		(fp_line
			(start 0.67945 -0.3048)
			(end 0.67945 0.3048)
			(stroke
				(width 0.1)
				(type default)
			)
			(layer "F.Fab")
		)
		(fp_line
			(start 0.12065 -0.3048)
			(end 0.67945 -0.3048)
			(stroke
				(width 0.1)
				(type default)
			)
			(layer "F.Fab")
		)
		(fp_line
			(start 0.12065 -0.2794)
			(end 0.12065 -0.3048)
			(stroke
				(width 0.1)
				(type default)
			)
			(layer "F.Fab")
		)
		(fp_line
			(start -0.12065 -0.2794)
			(end 0.12065 -0.2794)
			(stroke
				(width 0.1)
				(type default)
			)
			(layer "F.Fab")
		)
		(fp_line
			(start 0.120396 0.2794)
			(end -0.12065 0.2794)
			(stroke
				(width 0.1)
				(type default)
			)
			(layer "F.Fab")
		)
		(fp_line
			(start -0.12065 0.2794)
			(end -0.12065 0.3048)
			(stroke
				(width 0.1)
				(type default)
			)
			(layer "F.Fab")
		)
		(fp_line
			(start 0.67945 0.3048)
			(end 0.120396 0.3048)
			(stroke
				(width 0.1)
				(type default)
			)
			(layer "F.Fab")
		)
		(fp_line
			(start 0.120396 0.3048)
			(end 0.120396 0.2794)
			(stroke
				(width 0.1)
				(type default)
			)
			(layer "F.Fab")
		)
		(fp_line
			(start -0.12065 0.3048)
			(end -0.67945 0.3048)
			(stroke
				(width 0.1)
				(type default)
			)
			(layer "F.Fab")
		)
		(fp_line
			(start -0.67945 0.3048)
			(end -0.67945 -0.305054)
			(stroke
				(width 0.1)
				(type default)
			)
			(layer "F.Fab")
		)
		(pad "1" smd circle
			(at -0.40005 0 90)
			(size 0 0)
			(layers "F.Cu" "F.Mask" "F.Paste")
			(net "P12V_SSD0")
		)
		(pad "2" smd circle
			(at 0.40005 0 90)
			(size 0 0)
			(layers "F.Cu" "F.Mask" "F.Paste")
			(net "P12V_SSD0_VIN_N")
		)
	)
	(footprint ""
		(layer "F.Cu")
		(at 479.221546 -554.52518 180)
		(property "Reference" "J56_12"
			(at -2.8448 -1.402334 0)
			(unlocked yes)
			(layer "B.SilkS")
			(effects
				(font
					(size 0.7874 0.5842)
					(thickness 0.1524)
				)
				(justify mirror)
			)
		)
		(property "Value" ""
			(at 0 0 180)
			(layer "F.Fab")
			(effects
				(font
					(size 1.27 1.27)
				)
			)
		)
		(duplicate_pad_numbers_are_jumpers no)
		(pad "1" thru_hole circle
			(at 0 0 180)
			(size 0.4572 0.4572)
			(drill 0.2032)
			(layers "*.Cu" "*.Mask")
			(remove_unused_layers no)
			(net "Net_2679")
			(clearance 0.127)
			(thermal_gap 0.127)
			(padstack
				(mode front_inner_back)
				(layer "Inner"
					(shape circle)
					(size 0.4572 0.4572)
					(clearance 0.127)
				)
				(layer "B.Cu"
					(shape circle)
					(size 0.508 0.508)
					(clearance 0.1016)
				)
			)
		)
	)
	(footprint ""
		(layer "F.Cu")
		(at 224.022158 -86.700868)
		(property "Reference" "R4264"
			(at 0 0 0)
			(layer "F.SilkS")
			(hide yes)
			(effects
				(font
					(size 1.27 1.27)
				)
			)
		)
		(property "Value" ""
			(at 0 0 0)
			(layer "F.Fab")
			(effects
				(font
					(size 1.27 1.27)
				)
			)
		)
		(duplicate_pad_numbers_are_jumpers no)
		(fp_line
			(start -0.7874 -0.4064)
			(end 0.7874 -0.4064)
			(stroke
				(width 0.1524)
				(type default)
			)
			(layer "F.SilkS")
		)
		(fp_line
			(start -0.7874 0.4064)
			(end -0.7874 -0.4064)
			(stroke
				(width 0.1524)
				(type default)
			)
			(layer "F.SilkS")
		)
		(fp_line
			(start 0.7874 -0.4064)
			(end 0.7874 0.4064)
			(stroke
				(width 0.1524)
				(type default)
			)
			(layer "F.SilkS")
		)
		(fp_line
			(start 0.7874 0.4064)
			(end -0.7874 0.4064)
			(stroke
				(width 0.1524)
				(type default)
			)
			(layer "F.SilkS")
		)
		(fp_line
			(start -0.67945 -0.305054)
			(end -0.12065 -0.305054)
			(stroke
				(width 0.1)
				(type default)
			)
			(layer "F.Fab")
		)
		(fp_line
			(start -0.67945 0.3048)
			(end -0.67945 -0.305054)
			(stroke
				(width 0.1)
				(type default)
			)
			(layer "F.Fab")
		)
		(fp_line
			(start -0.12065 -0.305054)
			(end -0.12065 -0.2794)
			(stroke
				(width 0.1)
				(type default)
			)
			(layer "F.Fab")
		)
		(fp_line
			(start -0.12065 -0.2794)
			(end 0.12065 -0.2794)
			(stroke
				(width 0.1)
				(type default)
			)
			(layer "F.Fab")
		)
		(fp_line
			(start -0.12065 0.2794)
			(end -0.12065 0.3048)
			(stroke
				(width 0.1)
				(type default)
			)
			(layer "F.Fab")
		)
		(fp_line
			(start -0.12065 0.3048)
			(end -0.67945 0.3048)
			(stroke
				(width 0.1)
				(type default)
			)
			(layer "F.Fab")
		)
		(fp_line
			(start 0.120396 0.2794)
			(end -0.12065 0.2794)
			(stroke
				(width 0.1)
				(type default)
			)
			(layer "F.Fab")
		)
		(fp_line
			(start 0.120396 0.3048)
			(end 0.120396 0.2794)
			(stroke
				(width 0.1)
				(type default)
			)
			(layer "F.Fab")
		)
		(fp_line
			(start 0.12065 -0.3048)
			(end 0.67945 -0.3048)
			(stroke
				(width 0.1)
				(type default)
			)
			(layer "F.Fab")
		)
		(fp_line
			(start 0.12065 -0.2794)
			(end 0.12065 -0.3048)
			(stroke
				(width 0.1)
				(type default)
			)
			(layer "F.Fab")
		)
		(fp_line
			(start 0.67945 -0.3048)
			(end 0.67945 0.3048)
			(stroke
				(width 0.1)
				(type default)
			)
			(layer "F.Fab")
		)
		(fp_line
			(start 0.67945 0.3048)
			(end 0.120396 0.3048)
			(stroke
				(width 0.1)
				(type default)
			)
			(layer "F.Fab")
		)
		(pad "1" smd circle
			(at -0.40005 0)
			(size 0 0)
			(layers "F.Cu" "F.Mask" "F.Paste")
			(net "SMB_SSD_LED_IOEXP_SCL")
		)
		(pad "2" smd circle
			(at 0.40005 0)
			(size 0 0)
			(layers "F.Cu" "F.Mask" "F.Paste")
			(net "SMB_BIC_I2C6_R_SCL")
		)
	)
	(footprint ""
		(layer "F.Cu")
		(at 444.09233 -29.139642 180)
		(property "Reference" "C728"
			(at 0 0 180)
			(layer "F.SilkS")
			(hide yes)
			(effects
				(font
					(size 1.27 1.27)
				)
			)
		)
		(property "Value" ""
			(at 0 0 180)
			(layer "F.Fab")
			(effects
				(font
					(size 1.27 1.27)
				)
			)
		)
		(duplicate_pad_numbers_are_jumpers no)
		(fp_line
			(start 0.299974 0.150114)
			(end -0.299974 0.150114)
			(stroke
				(width 0.1)
				(type default)
			)
			(layer "F.Fab")
		)
		(fp_line
			(start 0.299974 -0.150114)
			(end 0.299974 0.150114)
			(stroke
				(width 0.1)
				(type default)
			)
			(layer "F.Fab")
		)
		(fp_line
			(start -0.299974 0.150114)
			(end -0.299974 -0.150114)
			(stroke
				(width 0.1)
				(type default)
			)
			(layer "F.Fab")
		)
		(fp_line
			(start -0.299974 -0.150114)
			(end 0.299974 -0.150114)
			(stroke
				(width 0.1)
				(type default)
			)
			(layer "F.Fab")
		)
		(pad "1" smd rect
			(at -0.2667 0 180)
			(size 0.3048 0.381)
			(layers "F.Cu" "F.Mask" "F.Paste")
			(net "P5E_PEX3_STN2_TX_DP<32>")
		)
		(pad "2" smd rect
			(at 0.2667 0 180)
			(size 0.3048 0.381)
			(layers "F.Cu" "F.Mask" "F.Paste")
			(net "P5E_PEX3_STN2_TX_C_DP<32>")
		)
	)
	(footprint ""
		(layer "F.Cu")
		(at 335.367884 -114.833654 90)
		(property "Reference" "PR7030"
			(at 0 0 90)
			(layer "F.SilkS")
			(hide yes)
			(effects
				(font
					(size 1.27 1.27)
				)
			)
		)
		(property "Value" ""
			(at 0 0 90)
			(layer "F.Fab")
			(effects
				(font
					(size 1.27 1.27)
				)
			)
		)
		(duplicate_pad_numbers_are_jumpers no)
		(fp_line
			(start 1.2954 -0.5842)
			(end 1.2954 0.5842)
			(stroke
				(width 0.1524)
				(type default)
			)
			(layer "F.SilkS")
		)
		(fp_line
			(start -1.2954 -0.5842)
			(end 1.2954 -0.5842)
			(stroke
				(width 0.1524)
				(type default)
			)
			(layer "F.SilkS")
		)
		(fp_line
			(start 1.2954 0.5842)
			(end -1.2954 0.5842)
			(stroke
				(width 0.1524)
				(type default)
			)
			(layer "F.SilkS")
		)
		(fp_line
			(start -1.2954 0.5842)
			(end -1.2954 -0.5842)
			(stroke
				(width 0.1524)
				(type default)
			)
			(layer "F.SilkS")
		)
		(fp_line
			(start 0.8636 -0.4572)
			(end 0.8636 -0.406654)
			(stroke
				(width 0.1)
				(type default)
			)
			(layer "F.Fab")
		)
		(fp_line
			(start -0.8636 -0.4572)
			(end 0.8636 -0.4572)
			(stroke
				(width 0.1)
				(type default)
			)
			(layer "F.Fab")
		)
		(fp_line
			(start 1.1938 -0.406654)
			(end 1.1938 0.4064)
			(stroke
				(width 0.1)
				(type default)
			)
			(layer "F.Fab")
		)
		(fp_line
			(start 0.8636 -0.406654)
			(end 1.1938 -0.406654)
			(stroke
				(width 0.1)
				(type default)
			)
			(layer "F.Fab")
		)
		(fp_line
			(start -0.8636 -0.406654)
			(end -0.8636 -0.4572)
			(stroke
				(width 0.1)
				(type default)
			)
			(layer "F.Fab")
		)
		(fp_line
			(start -1.1938 -0.406654)
			(end -0.8636 -0.406654)
			(stroke
				(width 0.1)
				(type default)
			)
			(layer "F.Fab")
		)
		(fp_line
			(start 1.1938 0.4064)
			(end 0.8636 0.4064)
			(stroke
				(width 0.1)
				(type default)
			)
			(layer "F.Fab")
		)
		(fp_line
			(start 0.8636 0.4064)
			(end 0.8636 0.4572)
			(stroke
				(width 0.1)
				(type default)
			)
			(layer "F.Fab")
		)
		(fp_line
			(start -0.8636 0.4064)
			(end -1.1938 0.4064)
			(stroke
				(width 0.1)
				(type default)
			)
			(layer "F.Fab")
		)
		(fp_line
			(start -1.1938 0.4064)
			(end -1.1938 -0.406654)
			(stroke
				(width 0.1)
				(type default)
			)
			(layer "F.Fab")
		)
		(fp_line
			(start -0.8636 0.4318)
			(end -0.8636 0.4064)
			(stroke
				(width 0.1)
				(type default)
			)
			(layer "F.Fab")
		)
		(fp_line
			(start 0.8636 0.4572)
			(end -0.8636 0.4572)
			(stroke
				(width 0.1)
				(type default)
			)
			(layer "F.Fab")
		)
		(fp_line
			(start -0.8636 0.4572)
			(end -0.8636 0.4318)
			(stroke
				(width 0.1)
				(type default)
			)
			(layer "F.Fab")
		)
		(pad "1" smd rect
			(at -0.7366 0)
			(size 0.7112 0.8128)
			(layers "F.Cu" "F.Mask" "F.Paste")
			(net "P12V_NIC5_CO_AVIN_PD")
		)
		(pad "2" smd rect
			(at 0.7366 0)
			(size 0.7112 0.8128)
			(layers "F.Cu" "F.Mask" "F.Paste")
			(net "P12V_AUX")
		)
	)
	(footprint ""
		(layer "F.Cu")
		(at 31.650178 -50.96383 180)
		(property "Reference" "PC513"
			(at 0 0 180)
			(layer "F.SilkS")
			(hide yes)
			(effects
				(font
					(size 1.27 1.27)
				)
			)
		)
		(property "Value" ""
			(at 0 0 180)
			(layer "F.Fab")
			(effects
				(font
					(size 1.27 1.27)
				)
			)
		)
		(duplicate_pad_numbers_are_jumpers no)
		(fp_line
			(start 1.524 0.762)
			(end -1.524 0.762)
			(stroke
				(width 0.1524)
				(type default)
			)
			(layer "F.SilkS")
		)
		(fp_line
			(start 1.524 -0.762)
			(end 1.524 0.762)
			(stroke
				(width 0.1524)
				(type default)
			)
			(layer "F.SilkS")
		)
		(fp_line
			(start -1.524 0.762)
			(end -1.524 -0.762)
			(stroke
				(width 0.1524)
				(type default)
			)
			(layer "F.SilkS")
		)
		(fp_line
			(start -1.524 -0.762)
			(end 1.524 -0.762)
			(stroke
				(width 0.1524)
				(type default)
			)
			(layer "F.SilkS")
		)
		(fp_line
			(start 1.1049 0.724916)
			(end 1.1049 -0.724916)
			(stroke
				(width 0.1)
				(type default)
			)
			(layer "F.Fab")
		)
		(fp_line
			(start 1.1049 -0.724916)
			(end -1.1049 -0.724916)
			(stroke
				(width 0.1)
				(type default)
			)
			(layer "F.Fab")
		)
		(fp_line
			(start -1.1049 0.724916)
			(end 1.1049 0.724916)
			(stroke
				(width 0.1)
				(type default)
			)
			(layer "F.Fab")
		)
		(fp_line
			(start -1.1049 -0.724916)
			(end -1.1049 0.724916)
			(stroke
				(width 0.1)
				(type default)
			)
			(layer "F.Fab")
		)
		(pad "1" smd rect
			(at -0.889 0)
			(size 1.016 1.27)
			(layers "F.Cu" "F.Mask" "F.Paste")
			(net "P3V3_SSD1")
		)
		(pad "2" smd rect
			(at 0.889 0)
			(size 1.016 1.27)
			(layers "F.Cu" "F.Mask" "F.Paste")
			(net "GND")
		)
	)
	(footprint ""
		(layer "F.Cu")
		(at 188.534548 -30.03169 180)
		(property "Reference" "C297"
			(at 0 0 180)
			(layer "F.SilkS")
			(hide yes)
			(effects
				(font
					(size 1.27 1.27)
				)
			)
		)
		(property "Value" ""
			(at 0 0 180)
			(layer "F.Fab")
			(effects
				(font
					(size 1.27 1.27)
				)
			)
		)
		(duplicate_pad_numbers_are_jumpers no)
		(fp_line
			(start 0.299974 0.150114)
			(end -0.299974 0.150114)
			(stroke
				(width 0.1)
				(type default)
			)
			(layer "F.Fab")
		)
		(fp_line
			(start 0.299974 -0.150114)
			(end 0.299974 0.150114)
			(stroke
				(width 0.1)
				(type default)
			)
			(layer "F.Fab")
		)
		(fp_line
			(start -0.299974 0.150114)
			(end -0.299974 -0.150114)
			(stroke
				(width 0.1)
				(type default)
			)
			(layer "F.Fab")
		)
		(fp_line
			(start -0.299974 -0.150114)
			(end 0.299974 -0.150114)
			(stroke
				(width 0.1)
				(type default)
			)
			(layer "F.Fab")
		)
		(pad "1" smd rect
			(at -0.2667 0 180)
			(size 0.3048 0.381)
			(layers "F.Cu" "F.Mask" "F.Paste")
			(net "P5E_PEX1_STN2_TX_DN<37>")
		)
		(pad "2" smd rect
			(at 0.2667 0 180)
			(size 0.3048 0.381)
			(layers "F.Cu" "F.Mask" "F.Paste")
			(net "P5E_PEX1_STN2_TX_C_DN<37>")
		)
	)
	(footprint ""
		(layer "F.Cu")
		(at 259.326126 -39.73576 -90)
		(property "Reference" "R5569"
			(at 0 0 270)
			(layer "F.SilkS")
			(hide yes)
			(effects
				(font
					(size 1.27 1.27)
				)
			)
		)
		(property "Value" ""
			(at 0 0 270)
			(layer "F.Fab")
			(effects
				(font
					(size 1.27 1.27)
				)
			)
		)
		(duplicate_pad_numbers_are_jumpers no)
		(fp_line
			(start -0.7874 0.4064)
			(end -0.7874 -0.4064)
			(stroke
				(width 0.1524)
				(type default)
			)
			(layer "F.SilkS")
		)
		(fp_line
			(start 0.7874 0.4064)
			(end -0.7874 0.4064)
			(stroke
				(width 0.1524)
				(type default)
			)
			(layer "F.SilkS")
		)
		(fp_line
			(start -0.7874 -0.4064)
			(end 0.7874 -0.4064)
			(stroke
				(width 0.1524)
				(type default)
			)
			(layer "F.SilkS")
		)
		(fp_line
			(start 0.7874 -0.4064)
			(end 0.7874 0.4064)
			(stroke
				(width 0.1524)
				(type default)
			)
			(layer "F.SilkS")
		)
		(fp_line
			(start -0.67945 0.3048)
			(end -0.67945 -0.305054)
			(stroke
				(width 0.1)
				(type default)
			)
			(layer "F.Fab")
		)
		(fp_line
			(start -0.12065 0.3048)
			(end -0.67945 0.3048)
			(stroke
				(width 0.1)
				(type default)
			)
			(layer "F.Fab")
		)
		(fp_line
			(start 0.120396 0.3048)
			(end 0.120396 0.2794)
			(stroke
				(width 0.1)
				(type default)
			)
			(layer "F.Fab")
		)
		(fp_line
			(start 0.67945 0.3048)
			(end 0.120396 0.3048)
			(stroke
				(width 0.1)
				(type default)
			)
			(layer "F.Fab")
		)
		(fp_line
			(start -0.12065 0.2794)
			(end -0.12065 0.3048)
			(stroke
				(width 0.1)
				(type default)
			)
			(layer "F.Fab")
		)
		(fp_line
			(start 0.120396 0.2794)
			(end -0.12065 0.2794)
			(stroke
				(width 0.1)
				(type default)
			)
			(layer "F.Fab")
		)
		(fp_line
			(start -0.12065 -0.2794)
			(end 0.12065 -0.2794)
			(stroke
				(width 0.1)
				(type default)
			)
			(layer "F.Fab")
		)
		(fp_line
			(start 0.12065 -0.2794)
			(end 0.12065 -0.3048)
			(stroke
				(width 0.1)
				(type default)
			)
			(layer "F.Fab")
		)
		(fp_line
			(start 0.12065 -0.3048)
			(end 0.67945 -0.3048)
			(stroke
				(width 0.1)
				(type default)
			)
			(layer "F.Fab")
		)
		(fp_line
			(start 0.67945 -0.3048)
			(end 0.67945 0.3048)
			(stroke
				(width 0.1)
				(type default)
			)
			(layer "F.Fab")
		)
		(fp_line
			(start -0.67945 -0.305054)
			(end -0.12065 -0.305054)
			(stroke
				(width 0.1)
				(type default)
			)
			(layer "F.Fab")
		)
		(fp_line
			(start -0.12065 -0.305054)
			(end -0.12065 -0.2794)
			(stroke
				(width 0.1)
				(type default)
			)
			(layer "F.Fab")
		)
		(pad "1" smd circle
			(at -0.40005 0 270)
			(size 0 0)
			(layers "F.Cu" "F.Mask" "F.Paste")
			(net "P3V3_AUX")
		)
		(pad "2" smd circle
			(at 0.40005 0 270)
			(size 0 0)
			(layers "F.Cu" "F.Mask" "F.Paste")
			(net "SSD9_AUX_P3V3_EN")
		)
	)
	(footprint ""
		(layer "F.Cu")
		(at 381.009144 -27.04973 180)
		(property "Reference" "C2776"
			(at 0 0 180)
			(layer "F.SilkS")
			(hide yes)
			(effects
				(font
					(size 1.27 1.27)
				)
			)
		)
		(property "Value" ""
			(at 0 0 180)
			(layer "F.Fab")
			(effects
				(font
					(size 1.27 1.27)
				)
			)
		)
		(duplicate_pad_numbers_are_jumpers no)
		(fp_line
			(start 0.7874 0.4064)
			(end -0.7874 0.4064)
			(stroke
				(width 0.1524)
				(type default)
			)
			(layer "F.SilkS")
		)
		(fp_line
			(start 0.7874 -0.4064)
			(end 0.7874 0.4064)
			(stroke
				(width 0.1524)
				(type default)
			)
			(layer "F.SilkS")
		)
		(fp_line
			(start -0.7874 0.4064)
			(end -0.7874 -0.4064)
			(stroke
				(width 0.1524)
				(type default)
			)
			(layer "F.SilkS")
		)
		(fp_line
			(start -0.7874 -0.4064)
			(end 0.7874 -0.4064)
			(stroke
				(width 0.1524)
				(type default)
			)
			(layer "F.SilkS")
		)
		(fp_line
			(start 0.67945 0.3048)
			(end 0.120396 0.3048)
			(stroke
				(width 0.1)
				(type default)
			)
			(layer "F.Fab")
		)
		(fp_line
			(start 0.67945 -0.3048)
			(end 0.67945 0.3048)
			(stroke
				(width 0.1)
				(type default)
			)
			(layer "F.Fab")
		)
		(fp_line
			(start 0.12065 -0.2794)
			(end 0.12065 -0.3048)
			(stroke
				(width 0.1)
				(type default)
			)
			(layer "F.Fab")
		)
		(fp_line
			(start 0.12065 -0.3048)
			(end 0.67945 -0.3048)
			(stroke
				(width 0.1)
				(type default)
			)
			(layer "F.Fab")
		)
		(fp_line
			(start 0.120396 0.3048)
			(end 0.120396 0.2794)
			(stroke
				(width 0.1)
				(type default)
			)
			(layer "F.Fab")
		)
		(fp_line
			(start 0.120396 0.2794)
			(end -0.12065 0.2794)
			(stroke
				(width 0.1)
				(type default)
			)
			(layer "F.Fab")
		)
		(fp_line
			(start -0.12065 0.3048)
			(end -0.67945 0.3048)
			(stroke
				(width 0.1)
				(type default)
			)
			(layer "F.Fab")
		)
		(fp_line
			(start -0.12065 0.2794)
			(end -0.12065 0.3048)
			(stroke
				(width 0.1)
				(type default)
			)
			(layer "F.Fab")
		)
		(fp_line
			(start -0.12065 -0.2794)
			(end 0.12065 -0.2794)
			(stroke
				(width 0.1)
				(type default)
			)
			(layer "F.Fab")
		)
		(fp_line
			(start -0.12065 -0.305054)
			(end -0.12065 -0.2794)
			(stroke
				(width 0.1)
				(type default)
			)
			(layer "F.Fab")
		)
		(fp_line
			(start -0.67945 0.3048)
			(end -0.67945 -0.305054)
			(stroke
				(width 0.1)
				(type default)
			)
			(layer "F.Fab")
		)
		(fp_line
			(start -0.67945 -0.305054)
			(end -0.12065 -0.305054)
			(stroke
				(width 0.1)
				(type default)
			)
			(layer "F.Fab")
		)
		(pad "1" smd circle
			(at -0.40005 0 180)
			(size 0 0)
			(layers "F.Cu" "F.Mask" "F.Paste")
			(net "PRSNT_SSD13_R_N")
		)
		(pad "2" smd circle
			(at 0.40005 0 180)
			(size 0 0)
			(layers "F.Cu" "F.Mask" "F.Paste")
			(net "GND")
		)
	)
	(footprint ""
		(layer "F.Cu")
		(at 236.895894 -49.930558 -90)
		(property "Reference" "PC568"
			(at 0 0 270)
			(layer "F.SilkS")
			(hide yes)
			(effects
				(font
					(size 1.27 1.27)
				)
			)
		)
		(property "Value" ""
			(at 0 0 270)
			(layer "F.Fab")
			(effects
				(font
					(size 1.27 1.27)
				)
			)
		)
		(duplicate_pad_numbers_are_jumpers no)
		(fp_line
			(start -0.7874 0.4064)
			(end -0.7874 -0.4064)
			(stroke
				(width 0.1524)
				(type default)
			)
			(layer "F.SilkS")
		)
		(fp_line
			(start 0.7874 0.4064)
			(end -0.7874 0.4064)
			(stroke
				(width 0.1524)
				(type default)
			)
			(layer "F.SilkS")
		)
		(fp_line
			(start -0.7874 -0.4064)
			(end 0.7874 -0.4064)
			(stroke
				(width 0.1524)
				(type default)
			)
			(layer "F.SilkS")
		)
		(fp_line
			(start 0.7874 -0.4064)
			(end 0.7874 0.4064)
			(stroke
				(width 0.1524)
				(type default)
			)
			(layer "F.SilkS")
		)
		(fp_line
			(start -0.67945 0.3048)
			(end -0.67945 -0.305054)
			(stroke
				(width 0.1)
				(type default)
			)
			(layer "F.Fab")
		)
		(fp_line
			(start -0.12065 0.3048)
			(end -0.67945 0.3048)
			(stroke
				(width 0.1)
				(type default)
			)
			(layer "F.Fab")
		)
		(fp_line
			(start 0.120396 0.3048)
			(end 0.120396 0.2794)
			(stroke
				(width 0.1)
				(type default)
			)
			(layer "F.Fab")
		)
		(fp_line
			(start 0.67945 0.3048)
			(end 0.120396 0.3048)
			(stroke
				(width 0.1)
				(type default)
			)
			(layer "F.Fab")
		)
		(fp_line
			(start -0.12065 0.2794)
			(end -0.12065 0.3048)
			(stroke
				(width 0.1)
				(type default)
			)
			(layer "F.Fab")
		)
		(fp_line
			(start 0.120396 0.2794)
			(end -0.12065 0.2794)
			(stroke
				(width 0.1)
				(type default)
			)
			(layer "F.Fab")
		)
		(fp_line
			(start -0.12065 -0.2794)
			(end 0.12065 -0.2794)
			(stroke
				(width 0.1)
				(type default)
			)
			(layer "F.Fab")
		)
		(fp_line
			(start 0.12065 -0.2794)
			(end 0.12065 -0.3048)
			(stroke
				(width 0.1)
				(type default)
			)
			(layer "F.Fab")
		)
		(fp_line
			(start 0.12065 -0.3048)
			(end 0.67945 -0.3048)
			(stroke
				(width 0.1)
				(type default)
			)
			(layer "F.Fab")
		)
		(fp_line
			(start 0.67945 -0.3048)
			(end 0.67945 0.3048)
			(stroke
				(width 0.1)
				(type default)
			)
			(layer "F.Fab")
		)
		(fp_line
			(start -0.67945 -0.305054)
			(end -0.12065 -0.305054)
			(stroke
				(width 0.1)
				(type default)
			)
			(layer "F.Fab")
		)
		(fp_line
			(start -0.12065 -0.305054)
			(end -0.12065 -0.2794)
			(stroke
				(width 0.1)
				(type default)
			)
			(layer "F.Fab")
		)
		(pad "1" smd circle
			(at -0.40005 0 270)
			(size 0 0)
			(layers "F.Cu" "F.Mask" "F.Paste")
			(net "P3V3_AUX")
		)
		(pad "2" smd circle
			(at 0.40005 0 270)
			(size 0 0)
			(layers "F.Cu" "F.Mask" "F.Paste")
			(net "GND")
		)
	)
	(footprint ""
		(layer "F.Cu")
		(at 356.349808 -157.812994)
		(property "Reference" "R957"
			(at 0 0 0)
			(layer "F.SilkS")
			(hide yes)
			(effects
				(font
					(size 1.27 1.27)
				)
			)
		)
		(property "Value" ""
			(at 0 0 0)
			(layer "F.Fab")
			(effects
				(font
					(size 1.27 1.27)
				)
			)
		)
		(duplicate_pad_numbers_are_jumpers no)
		(fp_line
			(start -0.7874 -0.4064)
			(end 0.7874 -0.4064)
			(stroke
				(width 0.1524)
				(type default)
			)
			(layer "F.SilkS")
		)
		(fp_line
			(start -0.7874 0.4064)
			(end -0.7874 -0.4064)
			(stroke
				(width 0.1524)
				(type default)
			)
			(layer "F.SilkS")
		)
		(fp_line
			(start 0.7874 -0.4064)
			(end 0.7874 0.4064)
			(stroke
				(width 0.1524)
				(type default)
			)
			(layer "F.SilkS")
		)
		(fp_line
			(start 0.7874 0.4064)
			(end -0.7874 0.4064)
			(stroke
				(width 0.1524)
				(type default)
			)
			(layer "F.SilkS")
		)
		(fp_line
			(start -0.67945 -0.305054)
			(end -0.12065 -0.305054)
			(stroke
				(width 0.1)
				(type default)
			)
			(layer "F.Fab")
		)
		(fp_line
			(start -0.67945 0.3048)
			(end -0.67945 -0.305054)
			(stroke
				(width 0.1)
				(type default)
			)
			(layer "F.Fab")
		)
		(fp_line
			(start -0.12065 -0.305054)
			(end -0.12065 -0.2794)
			(stroke
				(width 0.1)
				(type default)
			)
			(layer "F.Fab")
		)
		(fp_line
			(start -0.12065 -0.2794)
			(end 0.12065 -0.2794)
			(stroke
				(width 0.1)
				(type default)
			)
			(layer "F.Fab")
		)
		(fp_line
			(start -0.12065 0.2794)
			(end -0.12065 0.3048)
			(stroke
				(width 0.1)
				(type default)
			)
			(layer "F.Fab")
		)
		(fp_line
			(start -0.12065 0.3048)
			(end -0.67945 0.3048)
			(stroke
				(width 0.1)
				(type default)
			)
			(layer "F.Fab")
		)
		(fp_line
			(start 0.120396 0.2794)
			(end -0.12065 0.2794)
			(stroke
				(width 0.1)
				(type default)
			)
			(layer "F.Fab")
		)
		(fp_line
			(start 0.120396 0.3048)
			(end 0.120396 0.2794)
			(stroke
				(width 0.1)
				(type default)
			)
			(layer "F.Fab")
		)
		(fp_line
			(start 0.12065 -0.3048)
			(end 0.67945 -0.3048)
			(stroke
				(width 0.1)
				(type default)
			)
			(layer "F.Fab")
		)
		(fp_line
			(start 0.12065 -0.2794)
			(end 0.12065 -0.3048)
			(stroke
				(width 0.1)
				(type default)
			)
			(layer "F.Fab")
		)
		(fp_line
			(start 0.67945 -0.3048)
			(end 0.67945 0.3048)
			(stroke
				(width 0.1)
				(type default)
			)
			(layer "F.Fab")
		)
		(fp_line
			(start 0.67945 0.3048)
			(end 0.120396 0.3048)
			(stroke
				(width 0.1)
				(type default)
			)
			(layer "F.Fab")
		)
		(pad "1" smd circle
			(at -0.40005 0)
			(size 0 0)
			(layers "F.Cu" "F.Mask" "F.Paste")
			(net "P3V3_AUX")
		)
		(pad "2" smd circle
			(at 0.40005 0)
			(size 0 0)
			(layers "F.Cu" "F.Mask" "F.Paste")
			(net "PWRGD_P12V_NIC6_CO")
		)
	)
	(footprint ""
		(layer "F.Cu")
		(at 45.246798 -37.47516)
		(property "Reference" "R5886"
			(at 0 0 0)
			(layer "F.SilkS")
			(hide yes)
			(effects
				(font
					(size 1.27 1.27)
				)
			)
		)
		(property "Value" ""
			(at 0 0 0)
			(layer "F.Fab")
			(effects
				(font
					(size 1.27 1.27)
				)
			)
		)
		(duplicate_pad_numbers_are_jumpers no)
		(fp_line
			(start -0.7874 -0.4064)
			(end 0.7874 -0.4064)
			(stroke
				(width 0.1524)
				(type default)
			)
			(layer "F.SilkS")
		)
		(fp_line
			(start -0.7874 0.4064)
			(end -0.7874 -0.4064)
			(stroke
				(width 0.1524)
				(type default)
			)
			(layer "F.SilkS")
		)
		(fp_line
			(start 0.7874 -0.4064)
			(end 0.7874 0.4064)
			(stroke
				(width 0.1524)
				(type default)
			)
			(layer "F.SilkS")
		)
		(fp_line
			(start 0.7874 0.4064)
			(end -0.7874 0.4064)
			(stroke
				(width 0.1524)
				(type default)
			)
			(layer "F.SilkS")
		)
		(fp_line
			(start -0.67945 -0.305054)
			(end -0.12065 -0.305054)
			(stroke
				(width 0.1)
				(type default)
			)
			(layer "F.Fab")
		)
		(fp_line
			(start -0.67945 0.3048)
			(end -0.67945 -0.305054)
			(stroke
				(width 0.1)
				(type default)
			)
			(layer "F.Fab")
		)
		(fp_line
			(start -0.12065 -0.305054)
			(end -0.12065 -0.2794)
			(stroke
				(width 0.1)
				(type default)
			)
			(layer "F.Fab")
		)
		(fp_line
			(start -0.12065 -0.2794)
			(end 0.12065 -0.2794)
			(stroke
				(width 0.1)
				(type default)
			)
			(layer "F.Fab")
		)
		(fp_line
			(start -0.12065 0.2794)
			(end -0.12065 0.3048)
			(stroke
				(width 0.1)
				(type default)
			)
			(layer "F.Fab")
		)
		(fp_line
			(start -0.12065 0.3048)
			(end -0.67945 0.3048)
			(stroke
				(width 0.1)
				(type default)
			)
			(layer "F.Fab")
		)
		(fp_line
			(start 0.120396 0.2794)
			(end -0.12065 0.2794)
			(stroke
				(width 0.1)
				(type default)
			)
			(layer "F.Fab")
		)
		(fp_line
			(start 0.120396 0.3048)
			(end 0.120396 0.2794)
			(stroke
				(width 0.1)
				(type default)
			)
			(layer "F.Fab")
		)
		(fp_line
			(start 0.12065 -0.3048)
			(end 0.67945 -0.3048)
			(stroke
				(width 0.1)
				(type default)
			)
			(layer "F.Fab")
		)
		(fp_line
			(start 0.12065 -0.2794)
			(end 0.12065 -0.3048)
			(stroke
				(width 0.1)
				(type default)
			)
			(layer "F.Fab")
		)
		(fp_line
			(start 0.67945 -0.3048)
			(end 0.67945 0.3048)
			(stroke
				(width 0.1)
				(type default)
			)
			(layer "F.Fab")
		)
		(fp_line
			(start 0.67945 0.3048)
			(end 0.120396 0.3048)
			(stroke
				(width 0.1)
				(type default)
			)
			(layer "F.Fab")
		)
		(pad "1" smd circle
			(at -0.40005 0)
			(size 0 0)
			(layers "F.Cu" "F.Mask" "F.Paste")
			(net "P3V3_SSD2")
		)
		(pad "2" smd circle
			(at 0.40005 0)
			(size 0 0)
			(layers "F.Cu" "F.Mask" "F.Paste")
			(net "P3V3_SSD2_PG_G1")
		)
	)
	(footprint ""
		(layer "F.Cu")
		(at 411.530292 -197.556882)
		(property "Reference" "Q233"
			(at -3.08991 1.494282 0)
			(unlocked yes)
			(layer "F.SilkS")
			(effects
				(font
					(size 0.7874 0.5842)
					(thickness 0.1524)
				)
			)
		)
		(property "Value" ""
			(at 0 0 0)
			(layer "F.Fab")
			(effects
				(font
					(size 1.27 1.27)
				)
			)
		)
		(duplicate_pad_numbers_are_jumpers no)
		(fp_line
			(start -1.376172 -1.199896)
			(end -0.508 -1.199896)
			(stroke
				(width 0.1524)
				(type default)
			)
			(layer "F.SilkS")
		)
		(fp_line
			(start -1.376172 1.199896)
			(end -1.376172 -1.199896)
			(stroke
				(width 0.1524)
				(type default)
			)
			(layer "F.SilkS")
		)
		(fp_line
			(start -0.508 -1.199896)
			(end 0 -0.762)
			(stroke
				(width 0.1524)
				(type default)
			)
			(layer "F.SilkS")
		)
		(fp_line
			(start 0 -0.762)
			(end 0.508 -1.199896)
			(stroke
				(width 0.1524)
				(type default)
			)
			(layer "F.SilkS")
		)
		(fp_line
			(start 0.508 -1.199896)
			(end 1.376172 -1.199896)
			(stroke
				(width 0.1524)
				(type default)
			)
			(layer "F.SilkS")
		)
		(fp_line
			(start 1.376172 -1.199896)
			(end 1.376172 1.199896)
			(stroke
				(width 0.1524)
				(type default)
			)
			(layer "F.SilkS")
		)
		(fp_line
			(start 1.376172 1.199896)
			(end -1.376172 1.199896)
			(stroke
				(width 0.1524)
				(type default)
			)
			(layer "F.SilkS")
		)
		(fp_poly
			(pts
				(xy -1.4605 -0.7493) (xy -2.2225 -1.1303) (xy -2.2225 -0.3683)
			)
			(stroke
				(width 0)
				(type default)
			)
			(fill yes)
			(layer "F.SilkS")
		)
		(fp_line
			(start -0.674878 -1.100074)
			(end 0.674878 -1.100074)
			(stroke
				(width 0.1)
				(type default)
			)
			(layer "F.Fab")
		)
		(fp_line
			(start -0.674878 1.100074)
			(end -0.674878 -1.100074)
			(stroke
				(width 0.1)
				(type default)
			)
			(layer "F.Fab")
		)
		(fp_line
			(start 0.674878 -1.100074)
			(end 0.674878 1.100074)
			(stroke
				(width 0.1)
				(type default)
			)
			(layer "F.Fab")
		)
		(fp_line
			(start 0.674878 1.100074)
			(end -0.674878 1.100074)
			(stroke
				(width 0.1)
				(type default)
			)
			(layer "F.Fab")
		)
		(fp_poly
			(pts
				(xy -1.4605 -0.7493) (xy -2.2225 -1.1303) (xy -2.2225 -0.3683)
			)
			(stroke
				(width 0)
				(type default)
			)
			(fill yes)
			(layer "F.Fab")
		)
		(pad "1" smd rect
			(at -0.899922 -0.750062 270)
			(size 0.6096 0.6096)
			(layers "F.Cu" "F.Mask" "F.Paste")
			(net "GND")
		)
		(pad "2" smd rect
			(at -0.899922 0 270)
			(size 0.4064 0.6096)
			(layers "F.Cu" "F.Mask" "F.Paste")
			(net "FPGA_PEX0_MODE_SEL1_R")
		)
		(pad "3" smd rect
			(at -0.899922 0.750062 270)
			(size 0.6096 0.6096)
			(layers "F.Cu" "F.Mask" "F.Paste")
			(net "FPGA_PEX0_MODE_SEL1_ISO")
		)
		(pad "4" smd rect
			(at 0.899922 0.750062 270)
			(size 0.6096 0.6096)
			(layers "F.Cu" "F.Mask" "F.Paste")
			(net "GND")
		)
		(pad "5" smd rect
			(at 0.899922 0 270)
			(size 0.4064 0.6096)
			(layers "F.Cu" "F.Mask" "F.Paste")
			(net "FPGA_PEX0_MODE_SEL1_D_N")
		)
		(pad "6" smd rect
			(at 0.899922 -0.750062 270)
			(size 0.6096 0.6096)
			(layers "F.Cu" "F.Mask" "F.Paste")
			(net "FPGA_PEX0_MODE_SEL1_D_N")
		)
	)
	(footprint ""
		(layer "F.Cu")
		(at 268.445742 -261.663434)
		(property "Reference" "C3387"
			(at 0 0 0)
			(layer "F.SilkS")
			(hide yes)
			(effects
				(font
					(size 1.27 1.27)
				)
			)
		)
		(property "Value" ""
			(at 0 0 0)
			(layer "F.Fab")
			(effects
				(font
					(size 1.27 1.27)
				)
			)
		)
		(duplicate_pad_numbers_are_jumpers no)
		(fp_line
			(start -1.2954 -0.5842)
			(end 1.2954 -0.5842)
			(stroke
				(width 0.1524)
				(type default)
			)
			(layer "F.SilkS")
		)
		(fp_line
			(start -1.2954 0.5842)
			(end -1.2954 -0.5842)
			(stroke
				(width 0.1524)
				(type default)
			)
			(layer "F.SilkS")
		)
		(fp_line
			(start 1.2954 -0.5842)
			(end 1.2954 0.5842)
			(stroke
				(width 0.1524)
				(type default)
			)
			(layer "F.SilkS")
		)
		(fp_line
			(start 1.2954 0.5842)
			(end -1.2954 0.5842)
			(stroke
				(width 0.1524)
				(type default)
			)
			(layer "F.SilkS")
		)
		(fp_line
			(start -1.1938 -0.4064)
			(end -0.8636 -0.4064)
			(stroke
				(width 0.1)
				(type default)
			)
			(layer "F.Fab")
		)
		(fp_line
			(start -1.1938 0.4064)
			(end -1.1938 -0.4064)
			(stroke
				(width 0.1)
				(type default)
			)
			(layer "F.Fab")
		)
		(fp_line
			(start -0.8636 -0.4572)
			(end 0.8636 -0.4572)
			(stroke
				(width 0.1)
				(type default)
			)
			(layer "F.Fab")
		)
		(fp_line
			(start -0.8636 -0.4064)
			(end -0.8636 -0.4572)
			(stroke
				(width 0.1)
				(type default)
			)
			(layer "F.Fab")
		)
		(fp_line
			(start -0.8636 0.4064)
			(end -1.1938 0.4064)
			(stroke
				(width 0.1)
				(type default)
			)
			(layer "F.Fab")
		)
		(fp_line
			(start -0.8636 0.4572)
			(end -0.8636 0.4064)
			(stroke
				(width 0.1)
				(type default)
			)
			(layer "F.Fab")
		)
		(fp_line
			(start 0.8636 -0.4572)
			(end 0.8636 -0.4064)
			(stroke
				(width 0.1)
				(type default)
			)
			(layer "F.Fab")
		)
		(fp_line
			(start 0.8636 -0.4064)
			(end 1.1938 -0.4064)
			(stroke
				(width 0.1)
				(type default)
			)
			(layer "F.Fab")
		)
		(fp_line
			(start 0.8636 0.4064)
			(end 0.8636 0.4572)
			(stroke
				(width 0.1)
				(type default)
			)
			(layer "F.Fab")
		)
		(fp_line
			(start 0.8636 0.4572)
			(end -0.8636 0.4572)
			(stroke
				(width 0.1)
				(type default)
			)
			(layer "F.Fab")
		)
		(fp_line
			(start 1.1938 -0.4064)
			(end 1.1938 0.4064)
			(stroke
				(width 0.1)
				(type default)
			)
			(layer "F.Fab")
		)
		(fp_line
			(start 1.1938 0.4064)
			(end 0.8636 0.4064)
			(stroke
				(width 0.1)
				(type default)
			)
			(layer "F.Fab")
		)
		(pad "1" smd rect
			(at -0.7366 0 270)
			(size 0.7112 0.8128)
			(layers "F.Cu" "F.Mask" "F.Paste")
			(net "PCEPLL3_VDDA18_PEX2")
		)
		(pad "2" smd rect
			(at 0.7366 0 270)
			(size 0.7112 0.8128)
			(layers "F.Cu" "F.Mask" "F.Paste")
			(net "GND")
		)
	)
	(footprint ""
		(layer "F.Cu")
		(at 497.694712 -546.502082 180)
		(property "Reference" "SCREW_6"
			(at -3.2385 -1.402334 0)
			(unlocked yes)
			(layer "B.SilkS")
			(effects
				(font
					(size 0.7874 0.5842)
					(thickness 0.1524)
				)
				(justify mirror)
			)
		)
		(property "Value" ""
			(at 0 0 180)
			(layer "F.Fab")
			(effects
				(font
					(size 1.27 1.27)
				)
			)
		)
		(duplicate_pad_numbers_are_jumpers no)
		(pad "1" thru_hole circle
			(at 0 0 180)
			(size 0.4572 0.4572)
			(drill 0.2032)
			(layers "*.Cu" "*.Mask")
			(remove_unused_layers no)
			(net "Net_9158")
			(clearance 0.127)
			(thermal_gap 0.127)
			(padstack
				(mode front_inner_back)
				(layer "Inner"
					(shape circle)
					(size 0.4572 0.4572)
					(clearance 0.127)
				)
				(layer "B.Cu"
					(shape circle)
					(size 0.508 0.508)
					(clearance 0.1016)
				)
			)
		)
	)
	(footprint ""
		(layer "F.Cu")
		(at 465.746846 -522.606778 180)
		(property "Reference" "SCREW_SSD7_1"
			(at -5.207 -1.402334 0)
			(unlocked yes)
			(layer "B.SilkS")
			(effects
				(font
					(size 0.7874 0.5842)
					(thickness 0.1524)
				)
				(justify mirror)
			)
		)
		(property "Value" ""
			(at 0 0 180)
			(layer "F.Fab")
			(effects
				(font
					(size 1.27 1.27)
				)
			)
		)
		(duplicate_pad_numbers_are_jumpers no)
		(pad "1" thru_hole circle
			(at 0 0 180)
			(size 0.4572 0.4572)
			(drill 0.2032)
			(layers "*.Cu" "*.Mask")
			(remove_unused_layers no)
			(net "Net_9130")
			(clearance 0.127)
			(thermal_gap 0.127)
			(padstack
				(mode front_inner_back)
				(layer "Inner"
					(shape circle)
					(size 0.4572 0.4572)
					(clearance 0.127)
				)
				(layer "B.Cu"
					(shape circle)
					(size 0.508 0.508)
					(clearance 0.1016)
				)
			)
		)
	)
	(footprint ""
		(layer "F.Cu")
		(at 158.088076 -45.704252 90)
		(property "Reference" "R562"
			(at 0 0 90)
			(layer "F.SilkS")
			(hide yes)
			(effects
				(font
					(size 1.27 1.27)
				)
			)
		)
		(property "Value" ""
			(at 0 0 90)
			(layer "F.Fab")
			(effects
				(font
					(size 1.27 1.27)
				)
			)
		)
		(duplicate_pad_numbers_are_jumpers no)
		(fp_line
			(start 3.937508 -1.8796)
			(end -3.937508 -1.8796)
			(stroke
				(width 0.1524)
				(type default)
			)
			(layer "F.SilkS")
		)
		(fp_line
			(start -3.937508 -1.8796)
			(end -3.937508 1.8796)
			(stroke
				(width 0.1524)
				(type default)
			)
			(layer "F.SilkS")
		)
		(fp_line
			(start 3.937508 1.8796)
			(end 3.937508 -1.8796)
			(stroke
				(width 0.1524)
				(type default)
			)
			(layer "F.SilkS")
		)
		(fp_line
			(start -3.937508 1.8796)
			(end 3.937508 1.8796)
			(stroke
				(width 0.1524)
				(type default)
			)
			(layer "F.SilkS")
		)
		(fp_line
			(start 3.275076 -1.674876)
			(end -3.275076 -1.674876)
			(stroke
				(width 0.1)
				(type default)
			)
			(layer "F.Fab")
		)
		(fp_line
			(start -3.275076 -1.674876)
			(end -3.275076 1.674876)
			(stroke
				(width 0.1)
				(type default)
			)
			(layer "F.Fab")
		)
		(fp_line
			(start 3.275076 1.674876)
			(end 3.275076 -1.674876)
			(stroke
				(width 0.1)
				(type default)
			)
			(layer "F.Fab")
		)
		(fp_line
			(start -3.275076 1.674876)
			(end 3.275076 1.674876)
			(stroke
				(width 0.1)
				(type default)
			)
			(layer "F.Fab")
		)
		(pad "1" smd rect
			(at -2.350008 0 90)
			(size 2.921 3.5052)
			(layers "F.Cu" "F.Mask" "F.Paste")
			(net "P12V_SSD5")
		)
		(pad "2" smd rect
			(at 2.350008 0 90)
			(size 2.921 3.5052)
			(layers "F.Cu" "F.Mask" "F.Paste")
			(net "P12V_SSD5_R")
		)
	)
	(footprint ""
		(layer "F.Cu")
		(at 80.124554 -84.476336 180)
		(property "Reference" "U16"
			(at -2.782316 -0.402336 90)
			(unlocked yes)
			(layer "F.SilkS")
			(effects
				(font
					(size 0.7874 0.5842)
					(thickness 0.1524)
				)
				(justify left)
			)
		)
		(property "Value" ""
			(at 0 0 180)
			(layer "F.Fab")
			(effects
				(font
					(size 1.27 1.27)
				)
			)
		)
		(duplicate_pad_numbers_are_jumpers no)
		(fp_line
			(start 2.0574 1.651)
			(end -2.0574 1.651)
			(stroke
				(width 0.1524)
				(type default)
			)
			(layer "F.SilkS")
		)
		(fp_line
			(start 2.0574 -1.651)
			(end 2.0574 1.651)
			(stroke
				(width 0.1524)
				(type default)
			)
			(layer "F.SilkS")
		)
		(fp_line
			(start 0.381 -1.651)
			(end 2.0574 -1.651)
			(stroke
				(width 0.1524)
				(type default)
			)
			(layer "F.SilkS")
		)
		(fp_line
			(start 0 -1.016)
			(end 0.381 -1.651)
			(stroke
				(width 0.1524)
				(type default)
			)
			(layer "F.SilkS")
		)
		(fp_line
			(start -0.381 -1.651)
			(end 0 -1.016)
			(stroke
				(width 0.1524)
				(type default)
			)
			(layer "F.SilkS")
		)
		(fp_line
			(start -2.0574 1.651)
			(end -2.0574 -1.651)
			(stroke
				(width 0.1524)
				(type default)
			)
			(layer "F.SilkS")
		)
		(fp_line
			(start -2.0574 -1.651)
			(end -0.381 -1.651)
			(stroke
				(width 0.1524)
				(type default)
			)
			(layer "F.SilkS")
		)
		(fp_poly
			(pts
				(xy -2.71272 -0.719328) (xy -2.71272 -1.344168) (xy -2.159 -1.016)
			)
			(stroke
				(width 0)
				(type default)
			)
			(fill yes)
			(layer "F.SilkS")
		)
		(fp_line
			(start 1.599946 1.199896)
			(end 0.899922 1.199896)
			(stroke
				(width 0.1)
				(type default)
			)
			(layer "F.Fab")
		)
		(fp_line
			(start 1.599946 -1.199896)
			(end 1.599946 1.199896)
			(stroke
				(width 0.1)
				(type default)
			)
			(layer "F.Fab")
		)
		(fp_line
			(start 0.899922 1.549908)
			(end -0.899922 1.549908)
			(stroke
				(width 0.1)
				(type default)
			)
			(layer "F.Fab")
		)
		(fp_line
			(start 0.899922 1.199896)
			(end 0.899922 1.549908)
			(stroke
				(width 0.1)
				(type default)
			)
			(layer "F.Fab")
		)
		(fp_line
			(start 0.899922 -1.199896)
			(end 1.599946 -1.199896)
			(stroke
				(width 0.1)
				(type default)
			)
			(layer "F.Fab")
		)
		(fp_line
			(start 0.899922 -1.549908)
			(end 0.899922 -1.199896)
			(stroke
				(width 0.1)
				(type default)
			)
			(layer "F.Fab")
		)
		(fp_line
			(start -0.899922 1.549908)
			(end -0.899922 1.199896)
			(stroke
				(width 0.1)
				(type default)
			)
			(layer "F.Fab")
		)
		(fp_line
			(start -0.899922 1.199896)
			(end -1.599946 1.199896)
			(stroke
				(width 0.1)
				(type default)
			)
			(layer "F.Fab")
		)
		(fp_line
			(start -0.899922 -1.199896)
			(end -0.899922 -1.549908)
			(stroke
				(width 0.1)
				(type default)
			)
			(layer "F.Fab")
		)
		(fp_line
			(start -0.899922 -1.549908)
			(end 0.899922 -1.549908)
			(stroke
				(width 0.1)
				(type default)
			)
			(layer "F.Fab")
		)
		(fp_line
			(start -1.599946 1.199896)
			(end -1.599946 -1.199896)
			(stroke
				(width 0.1)
				(type default)
			)
			(layer "F.Fab")
		)
		(fp_line
			(start -1.599946 -1.199896)
			(end -0.899922 -1.199896)
			(stroke
				(width 0.1)
				(type default)
			)
			(layer "F.Fab")
		)
		(fp_poly
			(pts
				(xy -2.71272 -0.719328) (xy -2.71272 -1.344168) (xy -2.159 -1.016)
			)
			(stroke
				(width 0)
				(type default)
			)
			(fill yes)
			(layer "F.Fab")
		)
		(pad "1" smd rect
			(at -1.225042 -0.94996 90)
			(size 0.5588 1.3462)
			(layers "F.Cu" "F.Mask" "F.Paste")
			(net "HP_NIC1_PWRGD_R")
		)
		(pad "2" smd rect
			(at -1.225042 0 90)
			(size 0.5588 1.3462)
			(layers "F.Cu" "F.Mask" "F.Paste")
			(net "RST_NIC1_PERST_R_N")
		)
		(pad "3" smd rect
			(at -1.225042 0.94996 90)
			(size 0.5588 1.3462)
			(layers "F.Cu" "F.Mask" "F.Paste")
			(net "GND")
		)
		(pad "4" smd rect
			(at 1.225042 0.94996 90)
			(size 0.5588 1.3462)
			(layers "F.Cu" "F.Mask" "F.Paste")
			(net "RST_HP_NIC1_N")
		)
		(pad "5" smd rect
			(at 1.225042 -0.94996 90)
			(size 0.5588 1.3462)
			(layers "F.Cu" "F.Mask" "F.Paste")
			(net "P3V3_AUX")
		)
	)
	(footprint ""
		(layer "F.Cu")
		(at 280.307542 -343.952322 90)
		(property "Reference" "C2351"
			(at 0 0 90)
			(layer "F.SilkS")
			(hide yes)
			(effects
				(font
					(size 1.27 1.27)
				)
			)
		)
		(property "Value" ""
			(at 0 0 90)
			(layer "F.Fab")
			(effects
				(font
					(size 1.27 1.27)
				)
			)
		)
		(duplicate_pad_numbers_are_jumpers no)
		(fp_line
			(start 0.299974 -0.150114)
			(end 0.299974 0.150114)
			(stroke
				(width 0.1)
				(type default)
			)
			(layer "F.Fab")
		)
		(fp_line
			(start -0.299974 -0.150114)
			(end 0.299974 -0.150114)
			(stroke
				(width 0.1)
				(type default)
			)
			(layer "F.Fab")
		)
		(fp_line
			(start 0.299974 0.150114)
			(end -0.299974 0.150114)
			(stroke
				(width 0.1)
				(type default)
			)
			(layer "F.Fab")
		)
		(fp_line
			(start -0.299974 0.150114)
			(end -0.299974 -0.150114)
			(stroke
				(width 0.1)
				(type default)
			)
			(layer "F.Fab")
		)
		(pad "1" smd rect
			(at -0.2667 0 90)
			(size 0.3048 0.381)
			(layers "F.Cu" "F.Mask" "F.Paste")
			(net "P5E_PEX2_STN4_TX_DP<74>")
		)
		(pad "2" smd rect
			(at 0.2667 0 90)
			(size 0.3048 0.381)
			(layers "F.Cu" "F.Mask" "F.Paste")
			(net "P5E_PEX2_STN4_TX_C_DP<74>")
		)
	)
	(footprint ""
		(layer "F.Cu")
		(at 154.666442 -252.356874 -90)
		(property "Reference" "R1288"
			(at 0 0 270)
			(layer "F.SilkS")
			(hide yes)
			(effects
				(font
					(size 1.27 1.27)
				)
			)
		)
		(property "Value" ""
			(at 0 0 270)
			(layer "F.Fab")
			(effects
				(font
					(size 1.27 1.27)
				)
			)
		)
		(duplicate_pad_numbers_are_jumpers no)
		(fp_line
			(start -0.7874 0.4064)
			(end -0.7874 -0.4064)
			(stroke
				(width 0.1524)
				(type default)
			)
			(layer "F.SilkS")
		)
		(fp_line
			(start 0.7874 0.4064)
			(end -0.7874 0.4064)
			(stroke
				(width 0.1524)
				(type default)
			)
			(layer "F.SilkS")
		)
		(fp_line
			(start -0.7874 -0.4064)
			(end 0.7874 -0.4064)
			(stroke
				(width 0.1524)
				(type default)
			)
			(layer "F.SilkS")
		)
		(fp_line
			(start 0.7874 -0.4064)
			(end 0.7874 0.4064)
			(stroke
				(width 0.1524)
				(type default)
			)
			(layer "F.SilkS")
		)
		(fp_line
			(start -0.67945 0.3048)
			(end -0.67945 -0.305054)
			(stroke
				(width 0.1)
				(type default)
			)
			(layer "F.Fab")
		)
		(fp_line
			(start -0.12065 0.3048)
			(end -0.67945 0.3048)
			(stroke
				(width 0.1)
				(type default)
			)
			(layer "F.Fab")
		)
		(fp_line
			(start 0.120396 0.3048)
			(end 0.120396 0.2794)
			(stroke
				(width 0.1)
				(type default)
			)
			(layer "F.Fab")
		)
		(fp_line
			(start 0.67945 0.3048)
			(end 0.120396 0.3048)
			(stroke
				(width 0.1)
				(type default)
			)
			(layer "F.Fab")
		)
		(fp_line
			(start -0.12065 0.2794)
			(end -0.12065 0.3048)
			(stroke
				(width 0.1)
				(type default)
			)
			(layer "F.Fab")
		)
		(fp_line
			(start 0.120396 0.2794)
			(end -0.12065 0.2794)
			(stroke
				(width 0.1)
				(type default)
			)
			(layer "F.Fab")
		)
		(fp_line
			(start -0.12065 -0.2794)
			(end 0.12065 -0.2794)
			(stroke
				(width 0.1)
				(type default)
			)
			(layer "F.Fab")
		)
		(fp_line
			(start 0.12065 -0.2794)
			(end 0.12065 -0.3048)
			(stroke
				(width 0.1)
				(type default)
			)
			(layer "F.Fab")
		)
		(fp_line
			(start 0.12065 -0.3048)
			(end 0.67945 -0.3048)
			(stroke
				(width 0.1)
				(type default)
			)
			(layer "F.Fab")
		)
		(fp_line
			(start 0.67945 -0.3048)
			(end 0.67945 0.3048)
			(stroke
				(width 0.1)
				(type default)
			)
			(layer "F.Fab")
		)
		(fp_line
			(start -0.67945 -0.305054)
			(end -0.12065 -0.305054)
			(stroke
				(width 0.1)
				(type default)
			)
			(layer "F.Fab")
		)
		(fp_line
			(start -0.12065 -0.305054)
			(end -0.12065 -0.2794)
			(stroke
				(width 0.1)
				(type default)
			)
			(layer "F.Fab")
		)
		(pad "1" smd circle
			(at -0.40005 0 270)
			(size 0 0)
			(layers "F.Cu" "F.Mask" "F.Paste")
			(net "GND")
		)
		(pad "2" smd circle
			(at 0.40005 0 270)
			(size 0 0)
			(layers "F.Cu" "F.Mask" "F.Paste")
			(net "PEX1_DBG_MODE4")
		)
	)
	(footprint ""
		(layer "F.Cu")
		(at 318.695324 -356.244906 90)
		(property "Reference" "C557"
			(at 0 0 90)
			(layer "F.SilkS")
			(hide yes)
			(effects
				(font
					(size 1.27 1.27)
				)
			)
		)
		(property "Value" ""
			(at 0 0 90)
			(layer "F.Fab")
			(effects
				(font
					(size 1.27 1.27)
				)
			)
		)
		(duplicate_pad_numbers_are_jumpers no)
		(fp_line
			(start 0.299974 -0.150114)
			(end 0.299974 0.150114)
			(stroke
				(width 0.1)
				(type default)
			)
			(layer "F.Fab")
		)
		(fp_line
			(start -0.299974 -0.150114)
			(end 0.299974 -0.150114)
			(stroke
				(width 0.1)
				(type default)
			)
			(layer "F.Fab")
		)
		(fp_line
			(start 0.299974 0.150114)
			(end -0.299974 0.150114)
			(stroke
				(width 0.1)
				(type default)
			)
			(layer "F.Fab")
		)
		(fp_line
			(start -0.299974 0.150114)
			(end -0.299974 -0.150114)
			(stroke
				(width 0.1)
				(type default)
			)
			(layer "F.Fab")
		)
		(pad "1" smd rect
			(at -0.2667 0 90)
			(size 0.3048 0.381)
			(layers "F.Cu" "F.Mask" "F.Paste")
			(net "P5E_PEX2_STN6_TX_DP<108>")
		)
		(pad "2" smd rect
			(at 0.2667 0 90)
			(size 0.3048 0.381)
			(layers "F.Cu" "F.Mask" "F.Paste")
			(net "P5E_PEX2_STN6_TX_C_DP<108>")
		)
	)
	(footprint ""
		(layer "F.Cu")
		(at 373.507 -199.009)
		(property "Reference" "U345"
			(at -1.3462 -4.613148 0)
			(unlocked yes)
			(layer "F.SilkS")
			(effects
				(font
					(size 0.7874 0.5842)
					(thickness 0.1524)
				)
				(justify left)
			)
		)
		(property "Value" ""
			(at 0 0 0)
			(layer "F.Fab")
			(effects
				(font
					(size 1.27 1.27)
				)
			)
		)
		(duplicate_pad_numbers_are_jumpers no)
		(fp_line
			(start -2.097532 -3.949954)
			(end -2.097532 3.949954)
			(stroke
				(width 0.1524)
				(type default)
			)
			(layer "F.SilkS")
		)
		(fp_line
			(start -2.097532 3.949954)
			(end 2.097532 3.949954)
			(stroke
				(width 0.1524)
				(type default)
			)
			(layer "F.SilkS")
		)
		(fp_line
			(start -1.409954 -3.949954)
			(end -2.097532 -3.949954)
			(stroke
				(width 0.1524)
				(type default)
			)
			(layer "F.SilkS")
		)
		(fp_line
			(start 0 -2.54)
			(end -1.409954 -3.949954)
			(stroke
				(width 0.1524)
				(type default)
			)
			(layer "F.SilkS")
		)
		(fp_line
			(start 1.409954 -3.949954)
			(end 0 -2.54)
			(stroke
				(width 0.1524)
				(type default)
			)
			(layer "F.SilkS")
		)
		(fp_line
			(start 2.097532 -3.949954)
			(end 1.409954 -3.949954)
			(stroke
				(width 0.1524)
				(type default)
			)
			(layer "F.SilkS")
		)
		(fp_line
			(start 2.097532 3.949954)
			(end 2.097532 -3.949954)
			(stroke
				(width 0.1524)
				(type default)
			)
			(layer "F.SilkS")
		)
		(fp_poly
			(pts
				(xy -4.7498 -4.182872) (xy -4.7498 -3.166872) (xy -3.7338 -3.674872)
			)
			(stroke
				(width 0)
				(type default)
			)
			(fill yes)
			(layer "F.SilkS")
		)
		(fp_line
			(start -2.249932 -3.949954)
			(end -2.249932 3.949954)
			(stroke
				(width 0.1)
				(type default)
			)
			(layer "F.Fab")
		)
		(fp_line
			(start -2.249932 3.949954)
			(end 2.249932 3.949954)
			(stroke
				(width 0.1)
				(type default)
			)
			(layer "F.Fab")
		)
		(fp_line
			(start 2.249932 -3.949954)
			(end -2.249932 -3.949954)
			(stroke
				(width 0.1)
				(type default)
			)
			(layer "F.Fab")
		)
		(fp_line
			(start 2.249932 3.949954)
			(end 2.249932 -3.949954)
			(stroke
				(width 0.1)
				(type default)
			)
			(layer "F.Fab")
		)
		(fp_poly
			(pts
				(xy -4.7498 -4.182872) (xy -4.7498 -3.166872) (xy -3.7338 -3.674872)
			)
			(stroke
				(width 0)
				(type default)
			)
			(fill yes)
			(layer "F.Fab")
		)
		(pad "1" smd rect
			(at -2.925064 -3.674872 270)
			(size 0.6096 1.3716)
			(layers "F.Cu" "F.Mask" "F.Paste")
			(net "PEX1_PCA9555_0_INT_N")
		)
		(pad "2" smd rect
			(at -2.925064 -2.925064 270)
			(size 0.4064 1.3716)
			(layers "F.Cu" "F.Mask" "F.Paste")
			(net "PCA9555_0_PEX1_A1")
		)
		(pad "3" smd rect
			(at -2.925064 -2.275078 270)
			(size 0.4064 1.3716)
			(layers "F.Cu" "F.Mask" "F.Paste")
			(net "PCA9555_0_PEX1_A2")
		)
		(pad "4" smd rect
			(at -2.925064 -1.625092 270)
			(size 0.4064 1.3716)
			(layers "F.Cu" "F.Mask" "F.Paste")
			(net "PRSNT_SSD4_FPGA_PCA9555_N")
		)
		(pad "5" smd rect
			(at -2.925064 -0.975106 270)
			(size 0.4064 1.3716)
			(layers "F.Cu" "F.Mask" "F.Paste")
			(net "SSD4_PEX_PWR_EN")
		)
		(pad "6" smd rect
			(at -2.925064 -0.32512 270)
			(size 0.4064 1.3716)
			(layers "F.Cu" "F.Mask" "F.Paste")
			(net "RST_PEX_SSD4_PERST_N")
		)
		(pad "7" smd rect
			(at -2.925064 0.32512 270)
			(size 0.4064 1.3716)
			(layers "F.Cu" "F.Mask" "F.Paste")
			(net "Net_1169")
		)
		(pad "8" smd rect
			(at -2.925064 0.975106 270)
			(size 0.4064 1.3716)
			(layers "F.Cu" "F.Mask" "F.Paste")
			(net "PRSNT_SSD5_FPGA_PCA9555_N")
		)
		(pad "9" smd rect
			(at -2.925064 1.625092 270)
			(size 0.4064 1.3716)
			(layers "F.Cu" "F.Mask" "F.Paste")
			(net "SSD5_PEX_PWR_EN")
		)
		(pad "10" smd rect
			(at -2.925064 2.275078 270)
			(size 0.4064 1.3716)
			(layers "F.Cu" "F.Mask" "F.Paste")
			(net "RST_PEX_SSD5_PERST_N")
		)
		(pad "11" smd rect
			(at -2.925064 2.925064 270)
			(size 0.4064 1.3716)
			(layers "F.Cu" "F.Mask" "F.Paste")
			(net "Net_1170")
		)
		(pad "12" smd rect
			(at -2.925064 3.674872 270)
			(size 0.6096 1.3716)
			(layers "F.Cu" "F.Mask" "F.Paste")
			(net "GND")
		)
		(pad "13" smd rect
			(at 2.925064 3.674872 270)
			(size 0.6096 1.3716)
			(layers "F.Cu" "F.Mask" "F.Paste")
			(net "PRSNT_NIC2_FPGA_PCA9555_N")
		)
		(pad "14" smd rect
			(at 2.925064 2.925064 270)
			(size 0.4064 1.3716)
			(layers "F.Cu" "F.Mask" "F.Paste")
			(net "NIC2_PEX_PWR_EN")
		)
		(pad "15" smd rect
			(at 2.925064 2.275078 270)
			(size 0.4064 1.3716)
			(layers "F.Cu" "F.Mask" "F.Paste")
			(net "RST_PEX_NIC2_PERST_N")
		)
		(pad "16" smd rect
			(at 2.925064 1.625092 270)
			(size 0.4064 1.3716)
			(layers "F.Cu" "F.Mask" "F.Paste")
			(net "Net_1171")
		)
		(pad "17" smd rect
			(at 2.925064 0.975106 270)
			(size 0.4064 1.3716)
			(layers "F.Cu" "F.Mask" "F.Paste")
			(net "Net_8984")
		)
		(pad "18" smd rect
			(at 2.925064 0.32512 270)
			(size 0.4064 1.3716)
			(layers "F.Cu" "F.Mask" "F.Paste")
			(net "Net_8983")
		)
		(pad "19" smd rect
			(at 2.925064 -0.32512 270)
			(size 0.4064 1.3716)
			(layers "F.Cu" "F.Mask" "F.Paste")
			(net "Net_8982")
		)
		(pad "20" smd rect
			(at 2.925064 -0.975106 270)
			(size 0.4064 1.3716)
			(layers "F.Cu" "F.Mask" "F.Paste")
			(net "Net_8981")
		)
		(pad "21" smd rect
			(at 2.925064 -1.625092 270)
			(size 0.4064 1.3716)
			(layers "F.Cu" "F.Mask" "F.Paste")
			(net "PCA9555_0_PEX1_A0")
		)
		(pad "22" smd rect
			(at 2.925064 -2.275078 270)
			(size 0.4064 1.3716)
			(layers "F.Cu" "F.Mask" "F.Paste")
			(net "SMB_PEX1_PCA9555_SCL")
		)
		(pad "23" smd rect
			(at 2.925064 -2.925064 270)
			(size 0.4064 1.3716)
			(layers "F.Cu" "F.Mask" "F.Paste")
			(net "SMB_PEX1_PCA9555_SDA")
		)
		(pad "24" smd rect
			(at 2.925064 -3.674872 270)
			(size 0.6096 1.3716)
			(layers "F.Cu" "F.Mask" "F.Paste")
			(net "P3V3_AUX")
		)
	)
	(footprint ""
		(layer "F.Cu")
		(at 378.841 -179.451)
		(property "Reference" "R4702"
			(at 0 0 0)
			(layer "F.SilkS")
			(hide yes)
			(effects
				(font
					(size 1.27 1.27)
				)
			)
		)
		(property "Value" ""
			(at 0 0 0)
			(layer "F.Fab")
			(effects
				(font
					(size 1.27 1.27)
				)
			)
		)
		(duplicate_pad_numbers_are_jumpers no)
		(fp_line
			(start -0.7874 -0.4064)
			(end 0.7874 -0.4064)
			(stroke
				(width 0.1524)
				(type default)
			)
			(layer "F.SilkS")
		)
		(fp_line
			(start -0.7874 0.4064)
			(end -0.7874 -0.4064)
			(stroke
				(width 0.1524)
				(type default)
			)
			(layer "F.SilkS")
		)
		(fp_line
			(start 0.7874 -0.4064)
			(end 0.7874 0.4064)
			(stroke
				(width 0.1524)
				(type default)
			)
			(layer "F.SilkS")
		)
		(fp_line
			(start 0.7874 0.4064)
			(end -0.7874 0.4064)
			(stroke
				(width 0.1524)
				(type default)
			)
			(layer "F.SilkS")
		)
		(fp_line
			(start -0.67945 -0.305054)
			(end -0.12065 -0.305054)
			(stroke
				(width 0.1)
				(type default)
			)
			(layer "F.Fab")
		)
		(fp_line
			(start -0.67945 0.3048)
			(end -0.67945 -0.305054)
			(stroke
				(width 0.1)
				(type default)
			)
			(layer "F.Fab")
		)
		(fp_line
			(start -0.12065 -0.305054)
			(end -0.12065 -0.2794)
			(stroke
				(width 0.1)
				(type default)
			)
			(layer "F.Fab")
		)
		(fp_line
			(start -0.12065 -0.2794)
			(end 0.12065 -0.2794)
			(stroke
				(width 0.1)
				(type default)
			)
			(layer "F.Fab")
		)
		(fp_line
			(start -0.12065 0.2794)
			(end -0.12065 0.3048)
			(stroke
				(width 0.1)
				(type default)
			)
			(layer "F.Fab")
		)
		(fp_line
			(start -0.12065 0.3048)
			(end -0.67945 0.3048)
			(stroke
				(width 0.1)
				(type default)
			)
			(layer "F.Fab")
		)
		(fp_line
			(start 0.120396 0.2794)
			(end -0.12065 0.2794)
			(stroke
				(width 0.1)
				(type default)
			)
			(layer "F.Fab")
		)
		(fp_line
			(start 0.120396 0.3048)
			(end 0.120396 0.2794)
			(stroke
				(width 0.1)
				(type default)
			)
			(layer "F.Fab")
		)
		(fp_line
			(start 0.12065 -0.3048)
			(end 0.67945 -0.3048)
			(stroke
				(width 0.1)
				(type default)
			)
			(layer "F.Fab")
		)
		(fp_line
			(start 0.12065 -0.2794)
			(end 0.12065 -0.3048)
			(stroke
				(width 0.1)
				(type default)
			)
			(layer "F.Fab")
		)
		(fp_line
			(start 0.67945 -0.3048)
			(end 0.67945 0.3048)
			(stroke
				(width 0.1)
				(type default)
			)
			(layer "F.Fab")
		)
		(fp_line
			(start 0.67945 0.3048)
			(end 0.120396 0.3048)
			(stroke
				(width 0.1)
				(type default)
			)
			(layer "F.Fab")
		)
		(pad "1" smd circle
			(at -0.40005 0)
			(size 0 0)
			(layers "F.Cu" "F.Mask" "F.Paste")
			(net "PCA9555_1_PEX1_A0")
		)
		(pad "2" smd circle
			(at 0.40005 0)
			(size 0 0)
			(layers "F.Cu" "F.Mask" "F.Paste")
			(net "P3V3_AUX")
		)
	)
	(footprint ""
		(layer "F.Cu")
		(at 348.477586 -254.55372 180)
		(property "Reference" "PC128"
			(at 0 0 180)
			(layer "F.SilkS")
			(hide yes)
			(effects
				(font
					(size 1.27 1.27)
				)
			)
		)
		(property "Value" ""
			(at 0 0 180)
			(layer "F.Fab")
			(effects
				(font
					(size 1.27 1.27)
				)
			)
		)
		(duplicate_pad_numbers_are_jumpers no)
		(fp_line
			(start 0.7874 0.4064)
			(end -0.7874 0.4064)
			(stroke
				(width 0.1524)
				(type default)
			)
			(layer "F.SilkS")
		)
		(fp_line
			(start 0.7874 -0.4064)
			(end 0.7874 0.4064)
			(stroke
				(width 0.1524)
				(type default)
			)
			(layer "F.SilkS")
		)
		(fp_line
			(start -0.7874 0.4064)
			(end -0.7874 -0.4064)
			(stroke
				(width 0.1524)
				(type default)
			)
			(layer "F.SilkS")
		)
		(fp_line
			(start -0.7874 -0.4064)
			(end 0.7874 -0.4064)
			(stroke
				(width 0.1524)
				(type default)
			)
			(layer "F.SilkS")
		)
		(fp_line
			(start 0.67945 0.3048)
			(end 0.120396 0.3048)
			(stroke
				(width 0.1)
				(type default)
			)
			(layer "F.Fab")
		)
		(fp_line
			(start 0.67945 -0.3048)
			(end 0.67945 0.3048)
			(stroke
				(width 0.1)
				(type default)
			)
			(layer "F.Fab")
		)
		(fp_line
			(start 0.12065 -0.2794)
			(end 0.12065 -0.3048)
			(stroke
				(width 0.1)
				(type default)
			)
			(layer "F.Fab")
		)
		(fp_line
			(start 0.12065 -0.3048)
			(end 0.67945 -0.3048)
			(stroke
				(width 0.1)
				(type default)
			)
			(layer "F.Fab")
		)
		(fp_line
			(start 0.120396 0.3048)
			(end 0.120396 0.2794)
			(stroke
				(width 0.1)
				(type default)
			)
			(layer "F.Fab")
		)
		(fp_line
			(start 0.120396 0.2794)
			(end -0.12065 0.2794)
			(stroke
				(width 0.1)
				(type default)
			)
			(layer "F.Fab")
		)
		(fp_line
			(start -0.12065 0.3048)
			(end -0.67945 0.3048)
			(stroke
				(width 0.1)
				(type default)
			)
			(layer "F.Fab")
		)
		(fp_line
			(start -0.12065 0.2794)
			(end -0.12065 0.3048)
			(stroke
				(width 0.1)
				(type default)
			)
			(layer "F.Fab")
		)
		(fp_line
			(start -0.12065 -0.2794)
			(end 0.12065 -0.2794)
			(stroke
				(width 0.1)
				(type default)
			)
			(layer "F.Fab")
		)
		(fp_line
			(start -0.12065 -0.305054)
			(end -0.12065 -0.2794)
			(stroke
				(width 0.1)
				(type default)
			)
			(layer "F.Fab")
		)
		(fp_line
			(start -0.67945 0.3048)
			(end -0.67945 -0.305054)
			(stroke
				(width 0.1)
				(type default)
			)
			(layer "F.Fab")
		)
		(fp_line
			(start -0.67945 -0.305054)
			(end -0.12065 -0.305054)
			(stroke
				(width 0.1)
				(type default)
			)
			(layer "F.Fab")
		)
		(pad "1" smd circle
			(at -0.40005 0 180)
			(size 0 0)
			(layers "F.Cu" "F.Mask" "F.Paste")
			(net "P0V8_PEX2_VREF")
		)
		(pad "2" smd circle
			(at 0.40005 0 180)
			(size 0 0)
			(layers "F.Cu" "F.Mask" "F.Paste")
			(net "GND")
		)
	)
	(footprint ""
		(layer "F.Cu")
		(at 35.766248 -343.952322 90)
		(property "Reference" "C178"
			(at 0 0 90)
			(layer "F.SilkS")
			(hide yes)
			(effects
				(font
					(size 1.27 1.27)
				)
			)
		)
		(property "Value" ""
			(at 0 0 90)
			(layer "F.Fab")
			(effects
				(font
					(size 1.27 1.27)
				)
			)
		)
		(duplicate_pad_numbers_are_jumpers no)
		(fp_line
			(start 0.299974 -0.150114)
			(end 0.299974 0.150114)
			(stroke
				(width 0.1)
				(type default)
			)
			(layer "F.Fab")
		)
		(fp_line
			(start -0.299974 -0.150114)
			(end 0.299974 -0.150114)
			(stroke
				(width 0.1)
				(type default)
			)
			(layer "F.Fab")
		)
		(fp_line
			(start 0.299974 0.150114)
			(end -0.299974 0.150114)
			(stroke
				(width 0.1)
				(type default)
			)
			(layer "F.Fab")
		)
		(fp_line
			(start -0.299974 0.150114)
			(end -0.299974 -0.150114)
			(stroke
				(width 0.1)
				(type default)
			)
			(layer "F.Fab")
		)
		(pad "1" smd rect
			(at -0.2667 0 90)
			(size 0.3048 0.381)
			(layers "F.Cu" "F.Mask" "F.Paste")
			(net "P5E_PEX0_STN7_TX_DN<119>")
		)
		(pad "2" smd rect
			(at 0.2667 0 90)
			(size 0.3048 0.381)
			(layers "F.Cu" "F.Mask" "F.Paste")
			(net "P5E_PEX0_STN7_TX_C_DN<119>")
		)
	)
	(footprint ""
		(layer "F.Cu")
		(at 252.325378 -42.849038 180)
		(property "Reference" "R601"
			(at 0 0 180)
			(layer "F.SilkS")
			(hide yes)
			(effects
				(font
					(size 1.27 1.27)
				)
			)
		)
		(property "Value" ""
			(at 0 0 180)
			(layer "F.Fab")
			(effects
				(font
					(size 1.27 1.27)
				)
			)
		)
		(duplicate_pad_numbers_are_jumpers no)
		(fp_line
			(start 0.7874 0.4064)
			(end -0.7874 0.4064)
			(stroke
				(width 0.1524)
				(type default)
			)
			(layer "F.SilkS")
		)
		(fp_line
			(start 0.7874 -0.4064)
			(end 0.7874 0.4064)
			(stroke
				(width 0.1524)
				(type default)
			)
			(layer "F.SilkS")
		)
		(fp_line
			(start -0.7874 0.4064)
			(end -0.7874 -0.4064)
			(stroke
				(width 0.1524)
				(type default)
			)
			(layer "F.SilkS")
		)
		(fp_line
			(start -0.7874 -0.4064)
			(end 0.7874 -0.4064)
			(stroke
				(width 0.1524)
				(type default)
			)
			(layer "F.SilkS")
		)
		(fp_line
			(start 0.67945 0.3048)
			(end 0.120396 0.3048)
			(stroke
				(width 0.1)
				(type default)
			)
			(layer "F.Fab")
		)
		(fp_line
			(start 0.67945 -0.3048)
			(end 0.67945 0.3048)
			(stroke
				(width 0.1)
				(type default)
			)
			(layer "F.Fab")
		)
		(fp_line
			(start 0.12065 -0.2794)
			(end 0.12065 -0.3048)
			(stroke
				(width 0.1)
				(type default)
			)
			(layer "F.Fab")
		)
		(fp_line
			(start 0.12065 -0.3048)
			(end 0.67945 -0.3048)
			(stroke
				(width 0.1)
				(type default)
			)
			(layer "F.Fab")
		)
		(fp_line
			(start 0.120396 0.3048)
			(end 0.120396 0.2794)
			(stroke
				(width 0.1)
				(type default)
			)
			(layer "F.Fab")
		)
		(fp_line
			(start 0.120396 0.2794)
			(end -0.12065 0.2794)
			(stroke
				(width 0.1)
				(type default)
			)
			(layer "F.Fab")
		)
		(fp_line
			(start -0.12065 0.3048)
			(end -0.67945 0.3048)
			(stroke
				(width 0.1)
				(type default)
			)
			(layer "F.Fab")
		)
		(fp_line
			(start -0.12065 0.2794)
			(end -0.12065 0.3048)
			(stroke
				(width 0.1)
				(type default)
			)
			(layer "F.Fab")
		)
		(fp_line
			(start -0.12065 -0.2794)
			(end 0.12065 -0.2794)
			(stroke
				(width 0.1)
				(type default)
			)
			(layer "F.Fab")
		)
		(fp_line
			(start -0.12065 -0.305054)
			(end -0.12065 -0.2794)
			(stroke
				(width 0.1)
				(type default)
			)
			(layer "F.Fab")
		)
		(fp_line
			(start -0.67945 0.3048)
			(end -0.67945 -0.305054)
			(stroke
				(width 0.1)
				(type default)
			)
			(layer "F.Fab")
		)
		(fp_line
			(start -0.67945 -0.305054)
			(end -0.12065 -0.305054)
			(stroke
				(width 0.1)
				(type default)
			)
			(layer "F.Fab")
		)
		(pad "1" smd circle
			(at -0.40005 0 180)
			(size 0 0)
			(layers "F.Cu" "F.Mask" "F.Paste")
			(net "P12V_SSD8_R")
		)
		(pad "2" smd circle
			(at 0.40005 0 180)
			(size 0 0)
			(layers "F.Cu" "F.Mask" "F.Paste")
			(net "P12V_SSD8_VIN_P")
		)
	)
	(footprint ""
		(layer "F.Cu")
		(at 197.273672 -343.952322 90)
		(property "Reference" "C2543"
			(at 0 0 90)
			(layer "F.SilkS")
			(hide yes)
			(effects
				(font
					(size 1.27 1.27)
				)
			)
		)
		(property "Value" ""
			(at 0 0 90)
			(layer "F.Fab")
			(effects
				(font
					(size 1.27 1.27)
				)
			)
		)
		(duplicate_pad_numbers_are_jumpers no)
		(fp_line
			(start 0.299974 -0.150114)
			(end 0.299974 0.150114)
			(stroke
				(width 0.1)
				(type default)
			)
			(layer "F.Fab")
		)
		(fp_line
			(start -0.299974 -0.150114)
			(end 0.299974 -0.150114)
			(stroke
				(width 0.1)
				(type default)
			)
			(layer "F.Fab")
		)
		(fp_line
			(start 0.299974 0.150114)
			(end -0.299974 0.150114)
			(stroke
				(width 0.1)
				(type default)
			)
			(layer "F.Fab")
		)
		(fp_line
			(start -0.299974 0.150114)
			(end -0.299974 -0.150114)
			(stroke
				(width 0.1)
				(type default)
			)
			(layer "F.Fab")
		)
		(pad "1" smd rect
			(at -0.2667 0 90)
			(size 0.3048 0.381)
			(layers "F.Cu" "F.Mask" "F.Paste")
			(net "P5E_PEX1_STN4_TX_DN<64>")
		)
		(pad "2" smd rect
			(at 0.2667 0 90)
			(size 0.3048 0.381)
			(layers "F.Cu" "F.Mask" "F.Paste")
			(net "P5E_PEX1_STN4_TX_C_DN<64>")
		)
	)
	(footprint ""
		(layer "F.Cu")
		(at 320.852292 -115.400836)
		(property "Reference" "R6031"
			(at 0 0 0)
			(layer "F.SilkS")
			(hide yes)
			(effects
				(font
					(size 1.27 1.27)
				)
			)
		)
		(property "Value" ""
			(at 0 0 0)
			(layer "F.Fab")
			(effects
				(font
					(size 1.27 1.27)
				)
			)
		)
		(duplicate_pad_numbers_are_jumpers no)
		(fp_line
			(start -0.7874 -0.4064)
			(end 0.7874 -0.4064)
			(stroke
				(width 0.1524)
				(type default)
			)
			(layer "F.SilkS")
		)
		(fp_line
			(start -0.7874 0.4064)
			(end -0.7874 -0.4064)
			(stroke
				(width 0.1524)
				(type default)
			)
			(layer "F.SilkS")
		)
		(fp_line
			(start 0.7874 -0.4064)
			(end 0.7874 0.4064)
			(stroke
				(width 0.1524)
				(type default)
			)
			(layer "F.SilkS")
		)
		(fp_line
			(start 0.7874 0.4064)
			(end -0.7874 0.4064)
			(stroke
				(width 0.1524)
				(type default)
			)
			(layer "F.SilkS")
		)
		(fp_line
			(start -0.67945 -0.305054)
			(end -0.12065 -0.305054)
			(stroke
				(width 0.1)
				(type default)
			)
			(layer "F.Fab")
		)
		(fp_line
			(start -0.67945 0.3048)
			(end -0.67945 -0.305054)
			(stroke
				(width 0.1)
				(type default)
			)
			(layer "F.Fab")
		)
		(fp_line
			(start -0.12065 -0.305054)
			(end -0.12065 -0.2794)
			(stroke
				(width 0.1)
				(type default)
			)
			(layer "F.Fab")
		)
		(fp_line
			(start -0.12065 -0.2794)
			(end 0.12065 -0.2794)
			(stroke
				(width 0.1)
				(type default)
			)
			(layer "F.Fab")
		)
		(fp_line
			(start -0.12065 0.2794)
			(end -0.12065 0.3048)
			(stroke
				(width 0.1)
				(type default)
			)
			(layer "F.Fab")
		)
		(fp_line
			(start -0.12065 0.3048)
			(end -0.67945 0.3048)
			(stroke
				(width 0.1)
				(type default)
			)
			(layer "F.Fab")
		)
		(fp_line
			(start 0.120396 0.2794)
			(end -0.12065 0.2794)
			(stroke
				(width 0.1)
				(type default)
			)
			(layer "F.Fab")
		)
		(fp_line
			(start 0.120396 0.3048)
			(end 0.120396 0.2794)
			(stroke
				(width 0.1)
				(type default)
			)
			(layer "F.Fab")
		)
		(fp_line
			(start 0.12065 -0.3048)
			(end 0.67945 -0.3048)
			(stroke
				(width 0.1)
				(type default)
			)
			(layer "F.Fab")
		)
		(fp_line
			(start 0.12065 -0.2794)
			(end 0.12065 -0.3048)
			(stroke
				(width 0.1)
				(type default)
			)
			(layer "F.Fab")
		)
		(fp_line
			(start 0.67945 -0.3048)
			(end 0.67945 0.3048)
			(stroke
				(width 0.1)
				(type default)
			)
			(layer "F.Fab")
		)
		(fp_line
			(start 0.67945 0.3048)
			(end 0.120396 0.3048)
			(stroke
				(width 0.1)
				(type default)
			)
			(layer "F.Fab")
		)
		(pad "1" smd circle
			(at -0.40005 0)
			(size 0 0)
			(layers "F.Cu" "F.Mask" "F.Paste")
			(net "HP_NIC5_EN")
		)
		(pad "2" smd circle
			(at 0.40005 0)
			(size 0 0)
			(layers "F.Cu" "F.Mask" "F.Paste")
			(net "P3V3_NIC5_CO_EN")
		)
	)
	(footprint ""
		(layer "F.Cu")
		(at 138.985244 -87.813642 180)
		(property "Reference" "R1562"
			(at 0 0 180)
			(layer "F.SilkS")
			(hide yes)
			(effects
				(font
					(size 1.27 1.27)
				)
			)
		)
		(property "Value" ""
			(at 0 0 180)
			(layer "F.Fab")
			(effects
				(font
					(size 1.27 1.27)
				)
			)
		)
		(duplicate_pad_numbers_are_jumpers no)
		(fp_line
			(start 0.7874 0.4064)
			(end -0.7874 0.4064)
			(stroke
				(width 0.1524)
				(type default)
			)
			(layer "F.SilkS")
		)
		(fp_line
			(start 0.7874 -0.4064)
			(end 0.7874 0.4064)
			(stroke
				(width 0.1524)
				(type default)
			)
			(layer "F.SilkS")
		)
		(fp_line
			(start -0.7874 0.4064)
			(end -0.7874 -0.4064)
			(stroke
				(width 0.1524)
				(type default)
			)
			(layer "F.SilkS")
		)
		(fp_line
			(start -0.7874 -0.4064)
			(end 0.7874 -0.4064)
			(stroke
				(width 0.1524)
				(type default)
			)
			(layer "F.SilkS")
		)
		(fp_line
			(start 0.67945 0.3048)
			(end 0.120396 0.3048)
			(stroke
				(width 0.1)
				(type default)
			)
			(layer "F.Fab")
		)
		(fp_line
			(start 0.67945 -0.3048)
			(end 0.67945 0.3048)
			(stroke
				(width 0.1)
				(type default)
			)
			(layer "F.Fab")
		)
		(fp_line
			(start 0.12065 -0.2794)
			(end 0.12065 -0.3048)
			(stroke
				(width 0.1)
				(type default)
			)
			(layer "F.Fab")
		)
		(fp_line
			(start 0.12065 -0.3048)
			(end 0.67945 -0.3048)
			(stroke
				(width 0.1)
				(type default)
			)
			(layer "F.Fab")
		)
		(fp_line
			(start 0.120396 0.3048)
			(end 0.120396 0.2794)
			(stroke
				(width 0.1)
				(type default)
			)
			(layer "F.Fab")
		)
		(fp_line
			(start 0.120396 0.2794)
			(end -0.12065 0.2794)
			(stroke
				(width 0.1)
				(type default)
			)
			(layer "F.Fab")
		)
		(fp_line
			(start -0.12065 0.3048)
			(end -0.67945 0.3048)
			(stroke
				(width 0.1)
				(type default)
			)
			(layer "F.Fab")
		)
		(fp_line
			(start -0.12065 0.2794)
			(end -0.12065 0.3048)
			(stroke
				(width 0.1)
				(type default)
			)
			(layer "F.Fab")
		)
		(fp_line
			(start -0.12065 -0.2794)
			(end 0.12065 -0.2794)
			(stroke
				(width 0.1)
				(type default)
			)
			(layer "F.Fab")
		)
		(fp_line
			(start -0.12065 -0.305054)
			(end -0.12065 -0.2794)
			(stroke
				(width 0.1)
				(type default)
			)
			(layer "F.Fab")
		)
		(fp_line
			(start -0.67945 0.3048)
			(end -0.67945 -0.305054)
			(stroke
				(width 0.1)
				(type default)
			)
			(layer "F.Fab")
		)
		(fp_line
			(start -0.67945 -0.305054)
			(end -0.12065 -0.305054)
			(stroke
				(width 0.1)
				(type default)
			)
			(layer "F.Fab")
		)
		(pad "1" smd circle
			(at -0.40005 0 180)
			(size 0 0)
			(layers "F.Cu" "F.Mask" "F.Paste")
			(net "P3V3_AUX")
		)
		(pad "2" smd circle
			(at 0.40005 0 180)
			(size 0 0)
			(layers "F.Cu" "F.Mask" "F.Paste")
			(net "SMB_BIC_I2C9_MUX0_SSD4_R_SDA")
		)
	)
	(footprint ""
		(layer "F.Cu")
		(at 100.42906 -222.06458 90)
		(property "Reference" "PC297"
			(at 0 0 90)
			(layer "F.SilkS")
			(hide yes)
			(effects
				(font
					(size 1.27 1.27)
				)
			)
		)
		(property "Value" ""
			(at 0 0 90)
			(layer "F.Fab")
			(effects
				(font
					(size 1.27 1.27)
				)
			)
		)
		(duplicate_pad_numbers_are_jumpers no)
		(fp_line
			(start 0.7874 -0.4064)
			(end 0.7874 0.4064)
			(stroke
				(width 0.1524)
				(type default)
			)
			(layer "F.SilkS")
		)
		(fp_line
			(start -0.7874 -0.4064)
			(end 0.7874 -0.4064)
			(stroke
				(width 0.1524)
				(type default)
			)
			(layer "F.SilkS")
		)
		(fp_line
			(start 0.7874 0.4064)
			(end -0.7874 0.4064)
			(stroke
				(width 0.1524)
				(type default)
			)
			(layer "F.SilkS")
		)
		(fp_line
			(start -0.7874 0.4064)
			(end -0.7874 -0.4064)
			(stroke
				(width 0.1524)
				(type default)
			)
			(layer "F.SilkS")
		)
		(fp_line
			(start -0.12065 -0.305054)
			(end -0.12065 -0.2794)
			(stroke
				(width 0.1)
				(type default)
			)
			(layer "F.Fab")
		)
		(fp_line
			(start -0.67945 -0.305054)
			(end -0.12065 -0.305054)
			(stroke
				(width 0.1)
				(type default)
			)
			(layer "F.Fab")
		)
		(fp_line
			(start 0.67945 -0.3048)
			(end 0.67945 0.3048)
			(stroke
				(width 0.1)
				(type default)
			)
			(layer "F.Fab")
		)
		(fp_line
			(start 0.12065 -0.3048)
			(end 0.67945 -0.3048)
			(stroke
				(width 0.1)
				(type default)
			)
			(layer "F.Fab")
		)
		(fp_line
			(start 0.12065 -0.2794)
			(end 0.12065 -0.3048)
			(stroke
				(width 0.1)
				(type default)
			)
			(layer "F.Fab")
		)
		(fp_line
			(start -0.12065 -0.2794)
			(end 0.12065 -0.2794)
			(stroke
				(width 0.1)
				(type default)
			)
			(layer "F.Fab")
		)
		(fp_line
			(start 0.120396 0.2794)
			(end -0.12065 0.2794)
			(stroke
				(width 0.1)
				(type default)
			)
			(layer "F.Fab")
		)
		(fp_line
			(start -0.12065 0.2794)
			(end -0.12065 0.3048)
			(stroke
				(width 0.1)
				(type default)
			)
			(layer "F.Fab")
		)
		(fp_line
			(start 0.67945 0.3048)
			(end 0.120396 0.3048)
			(stroke
				(width 0.1)
				(type default)
			)
			(layer "F.Fab")
		)
		(fp_line
			(start 0.120396 0.3048)
			(end 0.120396 0.2794)
			(stroke
				(width 0.1)
				(type default)
			)
			(layer "F.Fab")
		)
		(fp_line
			(start -0.12065 0.3048)
			(end -0.67945 0.3048)
			(stroke
				(width 0.1)
				(type default)
			)
			(layer "F.Fab")
		)
		(fp_line
			(start -0.67945 0.3048)
			(end -0.67945 -0.305054)
			(stroke
				(width 0.1)
				(type default)
			)
			(layer "F.Fab")
		)
		(pad "1" smd circle
			(at -0.40005 0 90)
			(size 0 0)
			(layers "F.Cu" "F.Mask" "F.Paste")
			(net "P1V8_PEX_FB")
		)
		(pad "2" smd circle
			(at 0.40005 0 90)
			(size 0 0)
			(layers "F.Cu" "F.Mask" "F.Paste")
			(net "SH_P1V8_PEX_FB")
		)
	)
	(footprint ""
		(layer "F.Cu")
		(at 437.305196 -298.87291 -90)
		(property "Reference" "R3990"
			(at 0 0 270)
			(layer "F.SilkS")
			(hide yes)
			(effects
				(font
					(size 1.27 1.27)
				)
			)
		)
		(property "Value" ""
			(at 0 0 270)
			(layer "F.Fab")
			(effects
				(font
					(size 1.27 1.27)
				)
			)
		)
		(duplicate_pad_numbers_are_jumpers no)
		(fp_line
			(start -0.7874 0.4064)
			(end -0.7874 -0.4064)
			(stroke
				(width 0.1524)
				(type default)
			)
			(layer "F.SilkS")
		)
		(fp_line
			(start 0.7874 0.4064)
			(end -0.7874 0.4064)
			(stroke
				(width 0.1524)
				(type default)
			)
			(layer "F.SilkS")
		)
		(fp_line
			(start -0.7874 -0.4064)
			(end 0.7874 -0.4064)
			(stroke
				(width 0.1524)
				(type default)
			)
			(layer "F.SilkS")
		)
		(fp_line
			(start 0.7874 -0.4064)
			(end 0.7874 0.4064)
			(stroke
				(width 0.1524)
				(type default)
			)
			(layer "F.SilkS")
		)
		(fp_line
			(start -0.67945 0.3048)
			(end -0.67945 -0.305054)
			(stroke
				(width 0.1)
				(type default)
			)
			(layer "F.Fab")
		)
		(fp_line
			(start -0.12065 0.3048)
			(end -0.67945 0.3048)
			(stroke
				(width 0.1)
				(type default)
			)
			(layer "F.Fab")
		)
		(fp_line
			(start 0.120396 0.3048)
			(end 0.120396 0.2794)
			(stroke
				(width 0.1)
				(type default)
			)
			(layer "F.Fab")
		)
		(fp_line
			(start 0.67945 0.3048)
			(end 0.120396 0.3048)
			(stroke
				(width 0.1)
				(type default)
			)
			(layer "F.Fab")
		)
		(fp_line
			(start -0.12065 0.2794)
			(end -0.12065 0.3048)
			(stroke
				(width 0.1)
				(type default)
			)
			(layer "F.Fab")
		)
		(fp_line
			(start 0.120396 0.2794)
			(end -0.12065 0.2794)
			(stroke
				(width 0.1)
				(type default)
			)
			(layer "F.Fab")
		)
		(fp_line
			(start -0.12065 -0.2794)
			(end 0.12065 -0.2794)
			(stroke
				(width 0.1)
				(type default)
			)
			(layer "F.Fab")
		)
		(fp_line
			(start 0.12065 -0.2794)
			(end 0.12065 -0.3048)
			(stroke
				(width 0.1)
				(type default)
			)
			(layer "F.Fab")
		)
		(fp_line
			(start 0.12065 -0.3048)
			(end 0.67945 -0.3048)
			(stroke
				(width 0.1)
				(type default)
			)
			(layer "F.Fab")
		)
		(fp_line
			(start 0.67945 -0.3048)
			(end 0.67945 0.3048)
			(stroke
				(width 0.1)
				(type default)
			)
			(layer "F.Fab")
		)
		(fp_line
			(start -0.67945 -0.305054)
			(end -0.12065 -0.305054)
			(stroke
				(width 0.1)
				(type default)
			)
			(layer "F.Fab")
		)
		(fp_line
			(start -0.12065 -0.305054)
			(end -0.12065 -0.2794)
			(stroke
				(width 0.1)
				(type default)
			)
			(layer "F.Fab")
		)
		(pad "1" smd circle
			(at -0.40005 0 270)
			(size 0 0)
			(layers "F.Cu" "F.Mask" "F.Paste")
			(net "I2C_PEX3_HOST_SDA")
		)
		(pad "2" smd circle
			(at 0.40005 0 270)
			(size 0 0)
			(layers "F.Cu" "F.Mask" "F.Paste")
			(net "I2C_PEX3_HOST_R_SDA")
		)
	)
	(footprint ""
		(layer "F.Cu")
		(at 187.38342 -411.99181)
		(property "Reference" "R4420"
			(at 0 0 0)
			(layer "F.SilkS")
			(hide yes)
			(effects
				(font
					(size 1.27 1.27)
				)
			)
		)
		(property "Value" ""
			(at 0 0 0)
			(layer "F.Fab")
			(effects
				(font
					(size 1.27 1.27)
				)
			)
		)
		(duplicate_pad_numbers_are_jumpers no)
		(fp_line
			(start -0.7874 -0.4064)
			(end 0.7874 -0.4064)
			(stroke
				(width 0.1524)
				(type default)
			)
			(layer "F.SilkS")
		)
		(fp_line
			(start -0.7874 0.4064)
			(end -0.7874 -0.4064)
			(stroke
				(width 0.1524)
				(type default)
			)
			(layer "F.SilkS")
		)
		(fp_line
			(start 0.7874 -0.4064)
			(end 0.7874 0.4064)
			(stroke
				(width 0.1524)
				(type default)
			)
			(layer "F.SilkS")
		)
		(fp_line
			(start 0.7874 0.4064)
			(end -0.7874 0.4064)
			(stroke
				(width 0.1524)
				(type default)
			)
			(layer "F.SilkS")
		)
		(fp_line
			(start -0.67945 -0.305054)
			(end -0.12065 -0.305054)
			(stroke
				(width 0.1)
				(type default)
			)
			(layer "F.Fab")
		)
		(fp_line
			(start -0.67945 0.3048)
			(end -0.67945 -0.305054)
			(stroke
				(width 0.1)
				(type default)
			)
			(layer "F.Fab")
		)
		(fp_line
			(start -0.12065 -0.305054)
			(end -0.12065 -0.2794)
			(stroke
				(width 0.1)
				(type default)
			)
			(layer "F.Fab")
		)
		(fp_line
			(start -0.12065 -0.2794)
			(end 0.12065 -0.2794)
			(stroke
				(width 0.1)
				(type default)
			)
			(layer "F.Fab")
		)
		(fp_line
			(start -0.12065 0.2794)
			(end -0.12065 0.3048)
			(stroke
				(width 0.1)
				(type default)
			)
			(layer "F.Fab")
		)
		(fp_line
			(start -0.12065 0.3048)
			(end -0.67945 0.3048)
			(stroke
				(width 0.1)
				(type default)
			)
			(layer "F.Fab")
		)
		(fp_line
			(start 0.120396 0.2794)
			(end -0.12065 0.2794)
			(stroke
				(width 0.1)
				(type default)
			)
			(layer "F.Fab")
		)
		(fp_line
			(start 0.120396 0.3048)
			(end 0.120396 0.2794)
			(stroke
				(width 0.1)
				(type default)
			)
			(layer "F.Fab")
		)
		(fp_line
			(start 0.12065 -0.3048)
			(end 0.67945 -0.3048)
			(stroke
				(width 0.1)
				(type default)
			)
			(layer "F.Fab")
		)
		(fp_line
			(start 0.12065 -0.2794)
			(end 0.12065 -0.3048)
			(stroke
				(width 0.1)
				(type default)
			)
			(layer "F.Fab")
		)
		(fp_line
			(start 0.67945 -0.3048)
			(end 0.67945 0.3048)
			(stroke
				(width 0.1)
				(type default)
			)
			(layer "F.Fab")
		)
		(fp_line
			(start 0.67945 0.3048)
			(end 0.120396 0.3048)
			(stroke
				(width 0.1)
				(type default)
			)
			(layer "F.Fab")
		)
		(pad "1" smd circle
			(at -0.40005 0)
			(size 0 0)
			(layers "F.Cu" "F.Mask" "F.Paste")
			(net "HSC_UV_N")
		)
		(pad "2" smd circle
			(at 0.40005 0)
			(size 0 0)
			(layers "F.Cu" "F.Mask" "F.Paste")
			(net "P3V3_AUX")
		)
	)
	(footprint ""
		(layer "F.Cu")
		(at 355.854 -179.578 180)
		(property "Reference" "R4734"
			(at 0 0 180)
			(layer "F.SilkS")
			(hide yes)
			(effects
				(font
					(size 1.27 1.27)
				)
			)
		)
		(property "Value" ""
			(at 0 0 180)
			(layer "F.Fab")
			(effects
				(font
					(size 1.27 1.27)
				)
			)
		)
		(duplicate_pad_numbers_are_jumpers no)
		(fp_line
			(start 0.7874 0.4064)
			(end -0.7874 0.4064)
			(stroke
				(width 0.1524)
				(type default)
			)
			(layer "F.SilkS")
		)
		(fp_line
			(start 0.7874 -0.4064)
			(end 0.7874 0.4064)
			(stroke
				(width 0.1524)
				(type default)
			)
			(layer "F.SilkS")
		)
		(fp_line
			(start -0.7874 0.4064)
			(end -0.7874 -0.4064)
			(stroke
				(width 0.1524)
				(type default)
			)
			(layer "F.SilkS")
		)
		(fp_line
			(start -0.7874 -0.4064)
			(end 0.7874 -0.4064)
			(stroke
				(width 0.1524)
				(type default)
			)
			(layer "F.SilkS")
		)
		(fp_line
			(start 0.67945 0.3048)
			(end 0.120396 0.3048)
			(stroke
				(width 0.1)
				(type default)
			)
			(layer "F.Fab")
		)
		(fp_line
			(start 0.67945 -0.3048)
			(end 0.67945 0.3048)
			(stroke
				(width 0.1)
				(type default)
			)
			(layer "F.Fab")
		)
		(fp_line
			(start 0.12065 -0.2794)
			(end 0.12065 -0.3048)
			(stroke
				(width 0.1)
				(type default)
			)
			(layer "F.Fab")
		)
		(fp_line
			(start 0.12065 -0.3048)
			(end 0.67945 -0.3048)
			(stroke
				(width 0.1)
				(type default)
			)
			(layer "F.Fab")
		)
		(fp_line
			(start 0.120396 0.3048)
			(end 0.120396 0.2794)
			(stroke
				(width 0.1)
				(type default)
			)
			(layer "F.Fab")
		)
		(fp_line
			(start 0.120396 0.2794)
			(end -0.12065 0.2794)
			(stroke
				(width 0.1)
				(type default)
			)
			(layer "F.Fab")
		)
		(fp_line
			(start -0.12065 0.3048)
			(end -0.67945 0.3048)
			(stroke
				(width 0.1)
				(type default)
			)
			(layer "F.Fab")
		)
		(fp_line
			(start -0.12065 0.2794)
			(end -0.12065 0.3048)
			(stroke
				(width 0.1)
				(type default)
			)
			(layer "F.Fab")
		)
		(fp_line
			(start -0.12065 -0.2794)
			(end 0.12065 -0.2794)
			(stroke
				(width 0.1)
				(type default)
			)
			(layer "F.Fab")
		)
		(fp_line
			(start -0.12065 -0.305054)
			(end -0.12065 -0.2794)
			(stroke
				(width 0.1)
				(type default)
			)
			(layer "F.Fab")
		)
		(fp_line
			(start -0.67945 0.3048)
			(end -0.67945 -0.305054)
			(stroke
				(width 0.1)
				(type default)
			)
			(layer "F.Fab")
		)
		(fp_line
			(start -0.67945 -0.305054)
			(end -0.12065 -0.305054)
			(stroke
				(width 0.1)
				(type default)
			)
			(layer "F.Fab")
		)
		(pad "1" smd circle
			(at -0.40005 0 180)
			(size 0 0)
			(layers "F.Cu" "F.Mask" "F.Paste")
			(net "P3V3_AUX")
		)
		(pad "2" smd circle
			(at 0.40005 0 180)
			(size 0 0)
			(layers "F.Cu" "F.Mask" "F.Paste")
			(net "RST_PEX_NIC4_PERST_R_N")
		)
	)
	(footprint ""
		(layer "F.Cu")
		(at 95.839788 -70.52437 90)
		(property "Reference" "PC655"
			(at 0 0 90)
			(layer "F.SilkS")
			(hide yes)
			(effects
				(font
					(size 1.27 1.27)
				)
			)
		)
		(property "Value" ""
			(at 0 0 90)
			(layer "F.Fab")
			(effects
				(font
					(size 1.27 1.27)
				)
			)
		)
		(duplicate_pad_numbers_are_jumpers no)
		(fp_line
			(start 1.524 -0.762)
			(end 1.524 0.762)
			(stroke
				(width 0.1524)
				(type default)
			)
			(layer "F.SilkS")
		)
		(fp_line
			(start -1.524 -0.762)
			(end 1.524 -0.762)
			(stroke
				(width 0.1524)
				(type default)
			)
			(layer "F.SilkS")
		)
		(fp_line
			(start 1.524 0.762)
			(end -1.524 0.762)
			(stroke
				(width 0.1524)
				(type default)
			)
			(layer "F.SilkS")
		)
		(fp_line
			(start -1.524 0.762)
			(end -1.524 -0.762)
			(stroke
				(width 0.1524)
				(type default)
			)
			(layer "F.SilkS")
		)
		(fp_line
			(start 1.1049 -0.724916)
			(end -1.1049 -0.724916)
			(stroke
				(width 0.1)
				(type default)
			)
			(layer "F.Fab")
		)
		(fp_line
			(start -1.1049 -0.724916)
			(end -1.1049 0.724916)
			(stroke
				(width 0.1)
				(type default)
			)
			(layer "F.Fab")
		)
		(fp_line
			(start 1.1049 0.724916)
			(end 1.1049 -0.724916)
			(stroke
				(width 0.1)
				(type default)
			)
			(layer "F.Fab")
		)
		(fp_line
			(start -1.1049 0.724916)
			(end 1.1049 0.724916)
			(stroke
				(width 0.1)
				(type default)
			)
			(layer "F.Fab")
		)
		(pad "1" smd rect
			(at -0.889 0 270)
			(size 1.016 1.27)
			(layers "F.Cu" "F.Mask" "F.Paste")
			(net "P12V_SSD3_R")
		)
		(pad "2" smd rect
			(at 0.889 0 270)
			(size 1.016 1.27)
			(layers "F.Cu" "F.Mask" "F.Paste")
			(net "GND")
		)
	)
	(footprint ""
		(layer "F.Cu")
		(at 331.490066 -412.090108)
		(property "Reference" "J13"
			(at -5.874512 6.282436 90)
			(unlocked yes)
			(layer "F.SilkS")
			(effects
				(font
					(size 2.032 1.524)
					(thickness 0.1524)
				)
				(justify left)
			)
		)
		(property "Value" ""
			(at 0 0 0)
			(layer "F.Fab")
			(effects
				(font
					(size 1.27 1.27)
				)
			)
		)
		(duplicate_pad_numbers_are_jumpers no)
		(fp_line
			(start -4.249928 -16.999966)
			(end 24.45004 -16.999966)
			(stroke
				(width 0.1524)
				(type default)
			)
			(layer "F.SilkS")
		)
		(fp_line
			(start -4.249928 50.099976)
			(end -4.249928 -16.999966)
			(stroke
				(width 0.1524)
				(type default)
			)
			(layer "F.SilkS")
		)
		(fp_line
			(start -1.249934 -13.999972)
			(end -1.249934 47.099982)
			(stroke
				(width 0.1524)
				(type default)
			)
			(layer "F.SilkS")
		)
		(fp_line
			(start -1.249934 -6.500114)
			(end 21.450046 -6.500114)
			(stroke
				(width 0.1524)
				(type default)
			)
			(layer "F.SilkS")
		)
		(fp_line
			(start -1.249934 47.099982)
			(end 21.450046 47.099982)
			(stroke
				(width 0.1524)
				(type default)
			)
			(layer "F.SilkS")
		)
		(fp_line
			(start 21.450046 -13.999972)
			(end -1.249934 -13.999972)
			(stroke
				(width 0.1524)
				(type default)
			)
			(layer "F.SilkS")
		)
		(fp_line
			(start 21.450046 47.099982)
			(end 21.450046 -13.999972)
			(stroke
				(width 0.1524)
				(type default)
			)
			(layer "F.SilkS")
		)
		(fp_line
			(start 24.45004 -16.999966)
			(end 24.45004 50.099976)
			(stroke
				(width 0.1524)
				(type default)
			)
			(layer "F.SilkS")
		)
		(fp_line
			(start 24.45004 50.099976)
			(end -4.249928 50.099976)
			(stroke
				(width 0.1524)
				(type default)
			)
			(layer "F.SilkS")
		)
		(fp_poly
			(pts
				(xy -2.413 -0.508) (xy -2.413 0.508) (xy -1.397 0)
			)
			(stroke
				(width 0)
				(type default)
			)
			(fill yes)
			(layer "F.SilkS")
		)
		(fp_line
			(start -4.249928 -16.999966)
			(end 24.45004 -16.999966)
			(stroke
				(width 0.1524)
				(type default)
			)
			(layer "B.SilkS")
		)
		(fp_line
			(start -4.249928 50.099976)
			(end -4.249928 -16.999966)
			(stroke
				(width 0.1524)
				(type default)
			)
			(layer "B.SilkS")
		)
		(fp_line
			(start 24.45004 -16.999966)
			(end 24.45004 50.099976)
			(stroke
				(width 0.1524)
				(type default)
			)
			(layer "B.SilkS")
		)
		(fp_line
			(start 24.45004 50.099976)
			(end -4.249928 50.099976)
			(stroke
				(width 0.1524)
				(type default)
			)
			(layer "B.SilkS")
		)
		(fp_line
			(start -4.249928 -16.999966)
			(end 24.45004 -16.999966)
			(stroke
				(width 0.1)
				(type default)
			)
			(layer "B.Fab")
		)
		(fp_line
			(start -4.249928 50.099976)
			(end -4.249928 -16.999966)
			(stroke
				(width 0.1)
				(type default)
			)
			(layer "B.Fab")
		)
		(fp_line
			(start 24.45004 -16.999966)
			(end 24.45004 50.099976)
			(stroke
				(width 0.1)
				(type default)
			)
			(layer "B.Fab")
		)
		(fp_line
			(start 24.45004 50.099976)
			(end -4.249928 50.099976)
			(stroke
				(width 0.1)
				(type default)
			)
			(layer "B.Fab")
		)
		(fp_line
			(start -1.249934 -13.999972)
			(end -1.249934 47.099982)
			(stroke
				(width 0.1)
				(type default)
			)
			(layer "F.Fab")
		)
		(fp_line
			(start -1.249934 47.099982)
			(end 21.450046 47.099982)
			(stroke
				(width 0.1)
				(type default)
			)
			(layer "F.Fab")
		)
		(fp_line
			(start 21.450046 -13.999972)
			(end -1.249934 -13.999972)
			(stroke
				(width 0.1)
				(type default)
			)
			(layer "F.Fab")
		)
		(fp_line
			(start 21.450046 47.099982)
			(end 21.450046 -13.999972)
			(stroke
				(width 0.1)
				(type default)
			)
			(layer "F.Fab")
		)
		(fp_poly
			(pts
				(xy -2.413 -0.508) (xy -2.413 0.508) (xy -1.397 0)
			)
			(stroke
				(width 0)
				(type default)
			)
			(fill yes)
			(layer "F.Fab")
		)
		(fp_text user "PRESS-FIT"
			(at 23.217124 39.95928 90)
			(unlocked yes)
			(layer "F.SilkS")
			(effects
				(font
					(size 1.905 1.4224)
					(thickness 0.1524)
				)
				(justify left)
			)
		)
		(fp_text user "PRESS-FIT"
			(at -6.201918 31.739332 90)
			(unlocked yes)
			(layer "B.SilkS")
			(effects
				(font
					(size 1.905 1.4224)
					(thickness 0.1524)
				)
				(justify left mirror)
			)
		)
		(fp_text user "PRESS-FIT"
			(at 18.326862 48.74895 0)
			(unlocked yes)
			(layer "B.Fab")
			(effects
				(font
					(size 1.905 1.4224)
					(thickness 0.1524)
				)
				(justify left mirror)
			)
		)
		(fp_text user "PRESS-FIT"
			(at 1.5875 48.73625 0)
			(unlocked yes)
			(layer "F.Fab")
			(effects
				(font
					(size 1.905 1.4224)
					(thickness 0.1524)
				)
				(justify left)
			)
		)
		(pad "A1" thru_hole rect
			(at 0 0 180)
			(size 0.71628 0.71628)
			(drill 0.30988)
			(layers "*.Cu" "*.Mask")
			(remove_unused_layers no)
			(net "GPU_3V3IO_RSVD3_FFU_R")
			(clearance 0.0508)
			(thermal_gap 0.0508)
			(padstack
				(mode front_inner_back)
				(layer "Inner"
					(shape circle)
					(size 0.71628 0.71628)
					(clearance 0.0508)
				)
				(layer "B.Cu"
					(shape rect)
					(size 0.71628 0.71628)
					(clearance 0.0508)
				)
			)
		)
		(pad "A2" thru_hole circle
			(at 2.199894 0.199898 180)
			(size 0.906272 0.906272)
			(drill 0.499872)
			(layers "*.Cu" "*.Mask")
			(remove_unused_layers no)
			(net "GND")
			(clearance 0.0508)
			(thermal_gap 0.0508)
		)
		(pad "A3" thru_hole circle
			(at 4.400042 0 180)
			(size 0.71628 0.71628)
			(drill 0.30988)
			(layers "*.Cu" "*.Mask")
			(remove_unused_layers no)
			(net "PRSNT_GPU_A2_R_N")
			(clearance 0.0508)
			(thermal_gap 0.0508)
		)
		(pad "A4" thru_hole circle
			(at 6.599936 0.199898 180)
			(size 0.906272 0.906272)
			(drill 0.499872)
			(layers "*.Cu" "*.Mask")
			(remove_unused_layers no)
			(net "GND")
			(clearance 0.0508)
			(thermal_gap 0.0508)
		)
		(pad "A5" thru_hole circle
			(at 8.800084 0 180)
			(size 0.71628 0.71628)
			(drill 0.30988)
			(layers "*.Cu" "*.Mask")
			(remove_unused_layers no)
			(net "GPU_3V3IO_RSVD5_FFU_R")
			(clearance 0.0508)
			(thermal_gap 0.0508)
		)
		(pad "A6" thru_hole circle
			(at 10.999978 0.199898 180)
			(size 0.906272 0.906272)
			(drill 0.499872)
			(layers "*.Cu" "*.Mask")
			(remove_unused_layers no)
			(net "GND")
			(clearance 0.0508)
			(thermal_gap 0.0508)
		)
		(pad "A7" thru_hole circle
			(at 13.199872 0 180)
			(size 0.71628 0.71628)
			(drill 0.30988)
			(layers "*.Cu" "*.Mask")
			(remove_unused_layers no)
			(net "GPU_FPGA_OVERT_R_N")
			(clearance 0.0508)
			(thermal_gap 0.0508)
		)
		(pad "A8" thru_hole circle
			(at 15.40002 0.199898 180)
			(size 0.906272 0.906272)
			(drill 0.499872)
			(layers "*.Cu" "*.Mask")
			(remove_unused_layers no)
			(net "GND")
			(clearance 0.0508)
			(thermal_gap 0.0508)
		)
		(pad "A9" thru_hole circle
			(at 17.599914 0 180)
			(size 0.71628 0.71628)
			(drill 0.30988)
			(layers "*.Cu" "*.Mask")
			(remove_unused_layers no)
			(net "SWB_HSC_PWRGD")
			(clearance 0.0508)
			(thermal_gap 0.0508)
		)
		(pad "A10" thru_hole circle
			(at 19.800062 0.199898 180)
			(size 0.906272 0.906272)
			(drill 0.499872)
			(layers "*.Cu" "*.Mask")
			(remove_unused_layers no)
			(net "GND")
			(clearance 0.0508)
			(thermal_gap 0.0508)
		)
		(pad "B1" thru_hole circle
			(at 0 1.299972 180)
			(size 0.906272 0.906272)
			(drill 0.499872)
			(layers "*.Cu" "*.Mask")
			(remove_unused_layers no)
			(net "GND")
			(clearance 0.0508)
			(thermal_gap 0.0508)
		)
		(pad "B3" thru_hole circle
			(at 4.400042 1.299972 180)
			(size 0.906272 0.906272)
			(drill 0.499872)
			(layers "*.Cu" "*.Mask")
			(remove_unused_layers no)
			(net "GND")
			(clearance 0.0508)
			(thermal_gap 0.0508)
		)
		(pad "B5" thru_hole circle
			(at 8.800084 1.299972 180)
			(size 0.906272 0.906272)
			(drill 0.499872)
			(layers "*.Cu" "*.Mask")
			(remove_unused_layers no)
			(net "GND")
			(clearance 0.0508)
			(thermal_gap 0.0508)
		)
		(pad "B7" thru_hole circle
			(at 13.199872 1.299972 180)
			(size 0.906272 0.906272)
			(drill 0.499872)
			(layers "*.Cu" "*.Mask")
			(remove_unused_layers no)
			(net "GND")
			(clearance 0.0508)
			(thermal_gap 0.0508)
		)
		(pad "B9" thru_hole circle
			(at 17.599914 1.299972 180)
			(size 0.906272 0.906272)
			(drill 0.499872)
			(layers "*.Cu" "*.Mask")
			(remove_unused_layers no)
			(net "GND")
			(clearance 0.0508)
			(thermal_gap 0.0508)
		)
		(pad "B10" thru_hole circle
			(at 19.800062 1.500124 180)
			(size 0.71628 0.71628)
			(drill 0.30988)
			(layers "*.Cu" "*.Mask")
			(remove_unused_layers no)
			(net "Net_8904")
			(clearance 0.0508)
			(thermal_gap 0.0508)
		)
		(pad "C9" thru_hole circle
			(at 17.599914 2.599944 180)
			(size 0.71628 0.71628)
			(drill 0.30988)
			(layers "*.Cu" "*.Mask")
			(remove_unused_layers no)
			(net "Net_8902")
			(clearance 0.0508)
			(thermal_gap 0.0508)
		)
		(pad "C10" thru_hole circle
			(at 19.800062 2.800096 180)
			(size 0.71628 0.71628)
			(drill 0.30988)
			(layers "*.Cu" "*.Mask")
			(remove_unused_layers no)
			(net "Net_8903")
			(clearance 0.0508)
			(thermal_gap 0.0508)
		)
		(pad "D2" thru_hole circle
			(at 2.199894 4.100068 180)
			(size 0.906272 0.906272)
			(drill 0.499872)
			(layers "*.Cu" "*.Mask")
			(remove_unused_layers no)
			(net "GND")
			(clearance 0.0508)
			(thermal_gap 0.0508)
		)
		(pad "D4" thru_hole circle
			(at 6.599936 4.100068 180)
			(size 0.906272 0.906272)
			(drill 0.499872)
			(layers "*.Cu" "*.Mask")
			(remove_unused_layers no)
			(net "GND")
			(clearance 0.0508)
			(thermal_gap 0.0508)
		)
		(pad "D6" thru_hole circle
			(at 10.999978 4.100068 180)
			(size 0.906272 0.906272)
			(drill 0.499872)
			(layers "*.Cu" "*.Mask")
			(remove_unused_layers no)
			(net "GND")
			(clearance 0.0508)
			(thermal_gap 0.0508)
		)
		(pad "D8" thru_hole circle
			(at 15.40002 4.100068 180)
			(size 0.906272 0.906272)
			(drill 0.499872)
			(layers "*.Cu" "*.Mask")
			(remove_unused_layers no)
			(net "GND")
			(clearance 0.0508)
			(thermal_gap 0.0508)
		)
		(pad "D9" thru_hole circle
			(at 17.599914 3.899916 180)
			(size 0.71628 0.71628)
			(drill 0.30988)
			(layers "*.Cu" "*.Mask")
			(remove_unused_layers no)
			(net "Net_8901")
			(clearance 0.0508)
			(thermal_gap 0.0508)
		)
		(pad "D10" thru_hole circle
			(at 19.800062 4.100068 180)
			(size 0.906272 0.906272)
			(drill 0.499872)
			(layers "*.Cu" "*.Mask")
			(remove_unused_layers no)
			(net "GND")
			(clearance 0.0508)
			(thermal_gap 0.0508)
		)
		(pad "E1" thru_hole circle
			(at 0 5.199888 180)
			(size 0.906272 0.906272)
			(drill 0.499872)
			(layers "*.Cu" "*.Mask")
			(remove_unused_layers no)
			(net "GND")
			(clearance 0.0508)
			(thermal_gap 0.0508)
		)
		(pad "E3" thru_hole circle
			(at 4.400042 5.199888 180)
			(size 0.906272 0.906272)
			(drill 0.499872)
			(layers "*.Cu" "*.Mask")
			(remove_unused_layers no)
			(net "GND")
			(clearance 0.0508)
			(thermal_gap 0.0508)
		)
		(pad "E5" thru_hole circle
			(at 8.800084 5.199888 180)
			(size 0.906272 0.906272)
			(drill 0.499872)
			(layers "*.Cu" "*.Mask")
			(remove_unused_layers no)
			(net "GND")
			(clearance 0.0508)
			(thermal_gap 0.0508)
		)
		(pad "E7" thru_hole circle
			(at 13.199872 5.199888 180)
			(size 0.906272 0.906272)
			(drill 0.499872)
			(layers "*.Cu" "*.Mask")
			(remove_unused_layers no)
			(net "GND")
			(clearance 0.0508)
			(thermal_gap 0.0508)
		)
		(pad "E9" thru_hole circle
			(at 17.599914 5.199888 180)
			(size 0.906272 0.906272)
			(drill 0.499872)
			(layers "*.Cu" "*.Mask")
			(remove_unused_layers no)
			(net "GND")
			(clearance 0.0508)
			(thermal_gap 0.0508)
		)
		(pad "E10" thru_hole circle
			(at 19.800062 5.40004 180)
			(size 0.71628 0.71628)
			(drill 0.30988)
			(layers "*.Cu" "*.Mask")
			(remove_unused_layers no)
			(net "Net_8900")
			(clearance 0.0508)
			(thermal_gap 0.0508)
		)
		(pad "F9" thru_hole circle
			(at 17.599914 6.500114 180)
			(size 0.71628 0.71628)
			(drill 0.30988)
			(layers "*.Cu" "*.Mask")
			(remove_unused_layers no)
			(net "Net_8898")
			(clearance 0.0508)
			(thermal_gap 0.0508)
		)
		(pad "F10" thru_hole circle
			(at 19.800062 6.700012 180)
			(size 0.71628 0.71628)
			(drill 0.30988)
			(layers "*.Cu" "*.Mask")
			(remove_unused_layers no)
			(net "Net_8899")
			(clearance 0.0508)
			(thermal_gap 0.0508)
		)
		(pad "G2" thru_hole circle
			(at 2.199894 7.999984 180)
			(size 0.906272 0.906272)
			(drill 0.499872)
			(layers "*.Cu" "*.Mask")
			(remove_unused_layers no)
			(net "GND")
			(clearance 0.0508)
			(thermal_gap 0.0508)
		)
		(pad "G4" thru_hole circle
			(at 6.599936 7.999984 180)
			(size 0.906272 0.906272)
			(drill 0.499872)
			(layers "*.Cu" "*.Mask")
			(remove_unused_layers no)
			(net "GND")
			(clearance 0.0508)
			(thermal_gap 0.0508)
		)
		(pad "G6" thru_hole circle
			(at 10.999978 7.999984 180)
			(size 0.906272 0.906272)
			(drill 0.499872)
			(layers "*.Cu" "*.Mask")
			(remove_unused_layers no)
			(net "GND")
			(clearance 0.0508)
			(thermal_gap 0.0508)
		)
		(pad "G8" thru_hole circle
			(at 15.40002 7.999984 180)
			(size 0.906272 0.906272)
			(drill 0.499872)
			(layers "*.Cu" "*.Mask")
			(remove_unused_layers no)
			(net "GND")
			(clearance 0.0508)
			(thermal_gap 0.0508)
		)
		(pad "G9" thru_hole circle
			(at 17.599914 7.800086 180)
			(size 0.71628 0.71628)
			(drill 0.30988)
			(layers "*.Cu" "*.Mask")
			(remove_unused_layers no)
			(net "Net_8897")
			(clearance 0.0508)
			(thermal_gap 0.0508)
		)
		(pad "G10" thru_hole circle
			(at 19.800062 7.999984 180)
			(size 0.906272 0.906272)
			(drill 0.499872)
			(layers "*.Cu" "*.Mask")
			(remove_unused_layers no)
			(net "GND")
			(clearance 0.0508)
			(thermal_gap 0.0508)
		)
		(pad "H1" thru_hole circle
			(at 0 9.100058 180)
			(size 0.906272 0.906272)
			(drill 0.499872)
			(layers "*.Cu" "*.Mask")
			(remove_unused_layers no)
			(net "GND")
			(clearance 0.0508)
			(thermal_gap 0.0508)
		)
		(pad "H3" thru_hole circle
			(at 4.400042 9.100058 180)
			(size 0.906272 0.906272)
			(drill 0.499872)
			(layers "*.Cu" "*.Mask")
			(remove_unused_layers no)
			(net "GND")
			(clearance 0.0508)
			(thermal_gap 0.0508)
		)
		(pad "H5" thru_hole circle
			(at 8.800084 9.100058 180)
			(size 0.906272 0.906272)
			(drill 0.499872)
			(layers "*.Cu" "*.Mask")
			(remove_unused_layers no)
			(net "GND")
			(clearance 0.0508)
			(thermal_gap 0.0508)
		)
		(pad "H7" thru_hole circle
			(at 13.199872 9.100058 180)
			(size 0.906272 0.906272)
			(drill 0.499872)
			(layers "*.Cu" "*.Mask")
			(remove_unused_layers no)
			(net "GND")
			(clearance 0.0508)
			(thermal_gap 0.0508)
		)
		(pad "H9" thru_hole circle
			(at 17.599914 9.100058 180)
			(size 0.906272 0.906272)
			(drill 0.499872)
			(layers "*.Cu" "*.Mask")
			(remove_unused_layers no)
			(net "GND")
			(clearance 0.0508)
			(thermal_gap 0.0508)
		)
		(pad "H10" thru_hole circle
			(at 19.800062 9.299956 180)
			(size 0.71628 0.71628)
			(drill 0.30988)
			(layers "*.Cu" "*.Mask")
			(remove_unused_layers no)
			(net "Net_8896")
			(clearance 0.0508)
			(thermal_gap 0.0508)
		)
		(pad "I9" thru_hole circle
			(at 17.599914 10.40003 180)
			(size 0.71628 0.71628)
			(drill 0.30988)
			(layers "*.Cu" "*.Mask")
			(remove_unused_layers no)
			(net "Net_8894")
			(clearance 0.0508)
			(thermal_gap 0.0508)
		)
		(pad "I10" thru_hole circle
			(at 19.800062 10.599928 180)
			(size 0.71628 0.71628)
			(drill 0.30988)
			(layers "*.Cu" "*.Mask")
			(remove_unused_layers no)
			(net "Net_8895")
			(clearance 0.0508)
			(thermal_gap 0.0508)
		)
		(pad "J2" thru_hole circle
			(at 2.199894 11.8999 180)
			(size 0.906272 0.906272)
			(drill 0.499872)
			(layers "*.Cu" "*.Mask")
			(remove_unused_layers no)
			(net "GND")
			(clearance 0.0508)
			(thermal_gap 0.0508)
		)
		(pad "J4" thru_hole circle
			(at 6.599936 11.8999 180)
			(size 0.906272 0.906272)
			(drill 0.499872)
			(layers "*.Cu" "*.Mask")
			(remove_unused_layers no)
			(net "GND")
			(clearance 0.0508)
			(thermal_gap 0.0508)
		)
		(pad "J6" thru_hole circle
			(at 10.999978 11.8999 180)
			(size 0.906272 0.906272)
			(drill 0.499872)
			(layers "*.Cu" "*.Mask")
			(remove_unused_layers no)
			(net "GND")
			(clearance 0.0508)
			(thermal_gap 0.0508)
		)
		(pad "J8" thru_hole circle
			(at 15.40002 11.8999 180)
			(size 0.906272 0.906272)
			(drill 0.499872)
			(layers "*.Cu" "*.Mask")
			(remove_unused_layers no)
			(net "GND")
			(clearance 0.0508)
			(thermal_gap 0.0508)
		)
		(pad "J9" thru_hole circle
			(at 17.599914 11.700002 180)
			(size 0.71628 0.71628)
			(drill 0.30988)
			(layers "*.Cu" "*.Mask")
			(remove_unused_layers no)
			(net "Net_8893")
			(clearance 0.0508)
			(thermal_gap 0.0508)
		)
		(pad "J10" thru_hole circle
			(at 19.800062 11.8999 180)
			(size 0.906272 0.906272)
			(drill 0.499872)
			(layers "*.Cu" "*.Mask")
			(remove_unused_layers no)
			(net "GND")
			(clearance 0.0508)
			(thermal_gap 0.0508)
		)
		(pad "K1" thru_hole circle
			(at 0 12.999974 180)
			(size 0.906272 0.906272)
			(drill 0.499872)
			(layers "*.Cu" "*.Mask")
			(remove_unused_layers no)
			(net "GND")
			(clearance 0.0508)
			(thermal_gap 0.0508)
		)
		(pad "K3" thru_hole circle
			(at 4.400042 12.999974 180)
			(size 0.906272 0.906272)
			(drill 0.499872)
			(layers "*.Cu" "*.Mask")
			(remove_unused_layers no)
			(net "GND")
			(clearance 0.0508)
			(thermal_gap 0.0508)
		)
		(pad "K5" thru_hole circle
			(at 8.800084 12.999974 180)
			(size 0.906272 0.906272)
			(drill 0.499872)
			(layers "*.Cu" "*.Mask")
			(remove_unused_layers no)
			(net "GND")
			(clearance 0.0508)
			(thermal_gap 0.0508)
		)
		(pad "K7" thru_hole circle
			(at 13.199872 12.999974 180)
			(size 0.906272 0.906272)
			(drill 0.499872)
			(layers "*.Cu" "*.Mask")
			(remove_unused_layers no)
			(net "GND")
			(clearance 0.0508)
			(thermal_gap 0.0508)
		)
		(pad "K9" thru_hole circle
			(at 17.599914 12.999974 180)
			(size 0.906272 0.906272)
			(drill 0.499872)
			(layers "*.Cu" "*.Mask")
			(remove_unused_layers no)
			(net "GND")
			(clearance 0.0508)
			(thermal_gap 0.0508)
		)
		(pad "K10" thru_hole circle
			(at 19.800062 13.199872 180)
			(size 0.71628 0.71628)
			(drill 0.30988)
			(layers "*.Cu" "*.Mask")
			(remove_unused_layers no)
			(net "Net_8892")
			(clearance 0.0508)
			(thermal_gap 0.0508)
		)
		(pad "L9" thru_hole circle
			(at 17.599914 14.299946 180)
			(size 0.71628 0.71628)
			(drill 0.30988)
			(layers "*.Cu" "*.Mask")
			(remove_unused_layers no)
			(net "Net_8890")
			(clearance 0.0508)
			(thermal_gap 0.0508)
		)
		(pad "L10" thru_hole circle
			(at 19.800062 14.500098 180)
			(size 0.71628 0.71628)
			(drill 0.30988)
			(layers "*.Cu" "*.Mask")
			(remove_unused_layers no)
			(net "Net_8891")
			(clearance 0.0508)
			(thermal_gap 0.0508)
		)
		(pad "M1_2" thru_hole circle
			(at 2.199894 15.80007 180)
			(size 0.906272 0.906272)
			(drill 0.499872)
			(layers "*.Cu" "*.Mask")
			(remove_unused_layers no)
			(net "GND")
			(clearance 0.0508)
			(thermal_gap 0.0508)
		)
		(pad "M1_4" thru_hole circle
			(at 6.599936 15.80007 180)
			(size 0.906272 0.906272)
			(drill 0.499872)
			(layers "*.Cu" "*.Mask")
			(remove_unused_layers no)
			(net "GND")
			(clearance 0.0508)
			(thermal_gap 0.0508)
		)
		(pad "M1_6" thru_hole circle
			(at 10.999978 15.80007 180)
			(size 0.906272 0.906272)
			(drill 0.499872)
			(layers "*.Cu" "*.Mask")
			(remove_unused_layers no)
			(net "GND")
			(clearance 0.0508)
			(thermal_gap 0.0508)
		)
		(pad "M1_8" thru_hole circle
			(at 15.40002 15.80007 180)
			(size 0.906272 0.906272)
			(drill 0.499872)
			(layers "*.Cu" "*.Mask")
			(remove_unused_layers no)
			(net "GND")
			(clearance 0.0508)
			(thermal_gap 0.0508)
		)
		(pad "M1_10" thru_hole circle
			(at 19.800062 15.80007 180)
			(size 0.906272 0.906272)
			(drill 0.499872)
			(layers "*.Cu" "*.Mask")
			(remove_unused_layers no)
			(net "GND")
			(clearance 0.0508)
			(thermal_gap 0.0508)
		)
		(pad "M2_2" thru_hole circle
			(at 2.199894 26.2001 180)
			(size 0.906272 0.906272)
			(drill 0.499872)
			(layers "*.Cu" "*.Mask")
			(remove_unused_layers no)
			(net "GND")
			(clearance 0.0508)
			(thermal_gap 0.0508)
		)
		(pad "M2_4" thru_hole circle
			(at 6.599936 26.2001 180)
			(size 0.906272 0.906272)
			(drill 0.499872)
			(layers "*.Cu" "*.Mask")
			(remove_unused_layers no)
			(net "GND")
			(clearance 0.0508)
			(thermal_gap 0.0508)
		)
		(pad "M2_6" thru_hole circle
			(at 10.999978 26.2001 180)
			(size 0.906272 0.906272)
			(drill 0.499872)
			(layers "*.Cu" "*.Mask")
			(remove_unused_layers no)
			(net "GND")
			(clearance 0.0508)
			(thermal_gap 0.0508)
		)
		(pad "M2_8" thru_hole circle
			(at 15.40002 26.2001 180)
			(size 0.906272 0.906272)
			(drill 0.499872)
			(layers "*.Cu" "*.Mask")
			(remove_unused_layers no)
			(net "GND")
			(clearance 0.0508)
			(thermal_gap 0.0508)
		)
		(pad "M2_10" thru_hole circle
			(at 19.800062 26.2001 180)
			(size 0.906272 0.906272)
			(drill 0.499872)
			(layers "*.Cu" "*.Mask")
			(remove_unused_layers no)
			(net "GND")
			(clearance 0.0508)
			(thermal_gap 0.0508)
		)
		(pad "M9" thru_hole circle
			(at 17.599914 15.599918 180)
			(size 0.71628 0.71628)
			(drill 0.30988)
			(layers "*.Cu" "*.Mask")
			(remove_unused_layers no)
			(net "Net_8889")
			(clearance 0.0508)
			(thermal_gap 0.0508)
		)
		(pad "N1_1" thru_hole circle
			(at 0 16.89989 180)
			(size 0.906272 0.906272)
			(drill 0.499872)
			(layers "*.Cu" "*.Mask")
			(remove_unused_layers no)
			(net "GND")
			(clearance 0.0508)
			(thermal_gap 0.0508)
		)
		(pad "N1_3" thru_hole circle
			(at 4.400042 16.89989 180)
			(size 0.906272 0.906272)
			(drill 0.499872)
			(layers "*.Cu" "*.Mask")
			(remove_unused_layers no)
			(net "GND")
			(clearance 0.0508)
			(thermal_gap 0.0508)
		)
		(pad "N1_5" thru_hole circle
			(at 8.800084 16.89989 180)
			(size 0.906272 0.906272)
			(drill 0.499872)
			(layers "*.Cu" "*.Mask")
			(remove_unused_layers no)
			(net "GND")
			(clearance 0.0508)
			(thermal_gap 0.0508)
		)
		(pad "N1_7" thru_hole circle
			(at 13.199872 16.89989 180)
			(size 0.906272 0.906272)
			(drill 0.499872)
			(layers "*.Cu" "*.Mask")
			(remove_unused_layers no)
			(net "GND")
			(clearance 0.0508)
			(thermal_gap 0.0508)
		)
		(pad "N1_9" thru_hole circle
			(at 17.599914 16.89989 180)
			(size 0.906272 0.906272)
			(drill 0.499872)
			(layers "*.Cu" "*.Mask")
			(remove_unused_layers no)
			(net "GND")
			(clearance 0.0508)
			(thermal_gap 0.0508)
		)
		(pad "N2_1" thru_hole circle
			(at 0 27.29992 180)
			(size 0.906272 0.906272)
			(drill 0.499872)
			(layers "*.Cu" "*.Mask")
			(remove_unused_layers no)
			(net "GND")
			(clearance 0.0508)
			(thermal_gap 0.0508)
		)
		(pad "N2_3" thru_hole circle
			(at 4.400042 27.29992 180)
			(size 0.906272 0.906272)
			(drill 0.499872)
			(layers "*.Cu" "*.Mask")
			(remove_unused_layers no)
			(net "GND")
			(clearance 0.0508)
			(thermal_gap 0.0508)
		)
		(pad "N2_5" thru_hole circle
			(at 8.800084 27.29992 180)
			(size 0.906272 0.906272)
			(drill 0.499872)
			(layers "*.Cu" "*.Mask")
			(remove_unused_layers no)
			(net "GND")
			(clearance 0.0508)
			(thermal_gap 0.0508)
		)
		(pad "N2_7" thru_hole circle
			(at 13.199872 27.29992 180)
			(size 0.906272 0.906272)
			(drill 0.499872)
			(layers "*.Cu" "*.Mask")
			(remove_unused_layers no)
			(net "GND")
			(clearance 0.0508)
			(thermal_gap 0.0508)
		)
		(pad "N2_9" thru_hole circle
			(at 17.599914 27.29992 180)
			(size 0.906272 0.906272)
			(drill 0.499872)
			(layers "*.Cu" "*.Mask")
			(remove_unused_layers no)
			(net "GND")
			(clearance 0.0508)
			(thermal_gap 0.0508)
		)
		(pad "N10" thru_hole circle
			(at 19.800062 27.500072 180)
			(size 0.71628 0.71628)
			(drill 0.30988)
			(layers "*.Cu" "*.Mask")
			(remove_unused_layers no)
			(net "Net_8888")
			(clearance 0.0508)
			(thermal_gap 0.0508)
		)
		(pad "O9" thru_hole circle
			(at 17.599914 28.599892 180)
			(size 0.71628 0.71628)
			(drill 0.30988)
			(layers "*.Cu" "*.Mask")
			(remove_unused_layers no)
			(net "Net_8886")
			(clearance 0.0508)
			(thermal_gap 0.0508)
		)
		(pad "O10" thru_hole circle
			(at 19.800062 28.800044 180)
			(size 0.71628 0.71628)
			(drill 0.30988)
			(layers "*.Cu" "*.Mask")
			(remove_unused_layers no)
			(net "Net_8887")
			(clearance 0.0508)
			(thermal_gap 0.0508)
		)
		(pad "P2" thru_hole circle
			(at 2.199894 30.100016 180)
			(size 0.906272 0.906272)
			(drill 0.499872)
			(layers "*.Cu" "*.Mask")
			(remove_unused_layers no)
			(net "GND")
			(clearance 0.0508)
			(thermal_gap 0.0508)
		)
		(pad "P4" thru_hole circle
			(at 6.599936 30.100016 180)
			(size 0.906272 0.906272)
			(drill 0.499872)
			(layers "*.Cu" "*.Mask")
			(remove_unused_layers no)
			(net "GND")
			(clearance 0.0508)
			(thermal_gap 0.0508)
		)
		(pad "P6" thru_hole circle
			(at 10.999978 30.100016 180)
			(size 0.906272 0.906272)
			(drill 0.499872)
			(layers "*.Cu" "*.Mask")
			(remove_unused_layers no)
			(net "GND")
			(clearance 0.0508)
			(thermal_gap 0.0508)
		)
		(pad "P8" thru_hole circle
			(at 15.40002 30.100016 180)
			(size 0.906272 0.906272)
			(drill 0.499872)
			(layers "*.Cu" "*.Mask")
			(remove_unused_layers no)
			(net "GND")
			(clearance 0.0508)
			(thermal_gap 0.0508)
		)
		(pad "P9" thru_hole circle
			(at 17.599914 29.900118 180)
			(size 0.71628 0.71628)
			(drill 0.30988)
			(layers "*.Cu" "*.Mask")
			(remove_unused_layers no)
			(net "Net_8885")
			(clearance 0.0508)
			(thermal_gap 0.0508)
		)
		(pad "P10" thru_hole circle
			(at 19.800062 30.100016 180)
			(size 0.906272 0.906272)
			(drill 0.499872)
			(layers "*.Cu" "*.Mask")
			(remove_unused_layers no)
			(net "GND")
			(clearance 0.0508)
			(thermal_gap 0.0508)
		)
		(pad "Q1" thru_hole circle
			(at 0 31.20009 180)
			(size 0.906272 0.906272)
			(drill 0.499872)
			(layers "*.Cu" "*.Mask")
			(remove_unused_layers no)
			(net "GND")
			(clearance 0.0508)
			(thermal_gap 0.0508)
		)
		(pad "Q3" thru_hole circle
			(at 4.400042 31.20009 180)
			(size 0.906272 0.906272)
			(drill 0.499872)
			(layers "*.Cu" "*.Mask")
			(remove_unused_layers no)
			(net "GND")
			(clearance 0.0508)
			(thermal_gap 0.0508)
		)
		(pad "Q5" thru_hole circle
			(at 8.800084 31.20009 180)
			(size 0.906272 0.906272)
			(drill 0.499872)
			(layers "*.Cu" "*.Mask")
			(remove_unused_layers no)
			(net "GND")
			(clearance 0.0508)
			(thermal_gap 0.0508)
		)
		(pad "Q7" thru_hole circle
			(at 13.199872 31.20009 180)
			(size 0.906272 0.906272)
			(drill 0.499872)
			(layers "*.Cu" "*.Mask")
			(remove_unused_layers no)
			(net "GND")
			(clearance 0.0508)
			(thermal_gap 0.0508)
		)
		(pad "Q9" thru_hole circle
			(at 17.599914 31.20009 180)
			(size 0.906272 0.906272)
			(drill 0.499872)
			(layers "*.Cu" "*.Mask")
			(remove_unused_layers no)
			(net "GND")
			(clearance 0.0508)
			(thermal_gap 0.0508)
		)
		(pad "Q10" thru_hole circle
			(at 19.800062 31.399988 180)
			(size 0.71628 0.71628)
			(drill 0.30988)
			(layers "*.Cu" "*.Mask")
			(remove_unused_layers no)
			(net "Net_8884")
			(clearance 0.0508)
			(thermal_gap 0.0508)
		)
		(pad "R9" thru_hole circle
			(at 17.599914 32.500062 180)
			(size 0.71628 0.71628)
			(drill 0.30988)
			(layers "*.Cu" "*.Mask")
			(remove_unused_layers no)
			(net "Net_8882")
			(clearance 0.0508)
			(thermal_gap 0.0508)
		)
		(pad "R10" thru_hole circle
			(at 19.800062 32.69996 180)
			(size 0.71628 0.71628)
			(drill 0.30988)
			(layers "*.Cu" "*.Mask")
			(remove_unused_layers no)
			(net "Net_8883")
			(clearance 0.0508)
			(thermal_gap 0.0508)
		)
		(pad "S2" thru_hole circle
			(at 2.199894 33.999932 180)
			(size 0.906272 0.906272)
			(drill 0.499872)
			(layers "*.Cu" "*.Mask")
			(remove_unused_layers no)
			(net "GND")
			(clearance 0.0508)
			(thermal_gap 0.0508)
		)
		(pad "S4" thru_hole circle
			(at 6.599936 33.999932 180)
			(size 0.906272 0.906272)
			(drill 0.499872)
			(layers "*.Cu" "*.Mask")
			(remove_unused_layers no)
			(net "GND")
			(clearance 0.0508)
			(thermal_gap 0.0508)
		)
		(pad "S6" thru_hole circle
			(at 10.999978 33.999932 180)
			(size 0.906272 0.906272)
			(drill 0.499872)
			(layers "*.Cu" "*.Mask")
			(remove_unused_layers no)
			(net "GND")
			(clearance 0.0508)
			(thermal_gap 0.0508)
		)
		(pad "S8" thru_hole circle
			(at 15.40002 33.999932 180)
			(size 0.906272 0.906272)
			(drill 0.499872)
			(layers "*.Cu" "*.Mask")
			(remove_unused_layers no)
			(net "GND")
			(clearance 0.0508)
			(thermal_gap 0.0508)
		)
		(pad "S9" thru_hole circle
			(at 17.599914 33.800034 180)
			(size 0.71628 0.71628)
			(drill 0.30988)
			(layers "*.Cu" "*.Mask")
			(remove_unused_layers no)
			(net "Net_8881")
			(clearance 0.0508)
			(thermal_gap 0.0508)
		)
		(pad "S10" thru_hole circle
			(at 19.800062 33.999932 180)
			(size 0.906272 0.906272)
			(drill 0.499872)
			(layers "*.Cu" "*.Mask")
			(remove_unused_layers no)
			(net "GND")
			(clearance 0.0508)
			(thermal_gap 0.0508)
		)
		(pad "T1" thru_hole circle
			(at 0 35.100006 180)
			(size 0.906272 0.906272)
			(drill 0.499872)
			(layers "*.Cu" "*.Mask")
			(remove_unused_layers no)
			(net "GND")
			(clearance 0.0508)
			(thermal_gap 0.0508)
		)
		(pad "T3" thru_hole circle
			(at 4.400042 35.100006 180)
			(size 0.906272 0.906272)
			(drill 0.499872)
			(layers "*.Cu" "*.Mask")
			(remove_unused_layers no)
			(net "GND")
			(clearance 0.0508)
			(thermal_gap 0.0508)
		)
		(pad "T5" thru_hole circle
			(at 8.800084 35.100006 180)
			(size 0.906272 0.906272)
			(drill 0.499872)
			(layers "*.Cu" "*.Mask")
			(remove_unused_layers no)
			(net "GND")
			(clearance 0.0508)
			(thermal_gap 0.0508)
		)
		(pad "T7" thru_hole circle
			(at 13.199872 35.100006 180)
			(size 0.906272 0.906272)
			(drill 0.499872)
			(layers "*.Cu" "*.Mask")
			(remove_unused_layers no)
			(net "GND")
			(clearance 0.0508)
			(thermal_gap 0.0508)
		)
		(pad "T9" thru_hole circle
			(at 17.599914 35.100006 180)
			(size 0.906272 0.906272)
			(drill 0.499872)
			(layers "*.Cu" "*.Mask")
			(remove_unused_layers no)
			(net "GND")
			(clearance 0.0508)
			(thermal_gap 0.0508)
		)
		(pad "T10" thru_hole circle
			(at 19.800062 35.299904 180)
			(size 0.71628 0.71628)
			(drill 0.30988)
			(layers "*.Cu" "*.Mask")
			(remove_unused_layers no)
			(net "Net_8880")
			(clearance 0.0508)
			(thermal_gap 0.0508)
		)
		(pad "U9" thru_hole circle
			(at 17.599914 36.399978 180)
			(size 0.71628 0.71628)
			(drill 0.30988)
			(layers "*.Cu" "*.Mask")
			(remove_unused_layers no)
			(net "Net_8878")
			(clearance 0.0508)
			(thermal_gap 0.0508)
		)
		(pad "U10" thru_hole circle
			(at 19.800062 36.599876 180)
			(size 0.71628 0.71628)
			(drill 0.30988)
			(layers "*.Cu" "*.Mask")
			(remove_unused_layers no)
			(net "Net_8879")
			(clearance 0.0508)
			(thermal_gap 0.0508)
		)
		(pad "V2" thru_hole circle
			(at 2.199894 37.900102 180)
			(size 0.906272 0.906272)
			(drill 0.499872)
			(layers "*.Cu" "*.Mask")
			(remove_unused_layers no)
			(net "GND")
			(clearance 0.0508)
			(thermal_gap 0.0508)
		)
		(pad "V4" thru_hole circle
			(at 6.599936 37.900102 180)
			(size 0.906272 0.906272)
			(drill 0.499872)
			(layers "*.Cu" "*.Mask")
			(remove_unused_layers no)
			(net "GND")
			(clearance 0.0508)
			(thermal_gap 0.0508)
		)
		(pad "V6" thru_hole circle
			(at 10.999978 37.900102 180)
			(size 0.906272 0.906272)
			(drill 0.499872)
			(layers "*.Cu" "*.Mask")
			(remove_unused_layers no)
			(net "GND")
			(clearance 0.0508)
			(thermal_gap 0.0508)
		)
		(pad "V8" thru_hole circle
			(at 15.40002 37.900102 180)
			(size 0.906272 0.906272)
			(drill 0.499872)
			(layers "*.Cu" "*.Mask")
			(remove_unused_layers no)
			(net "GND")
			(clearance 0.0508)
			(thermal_gap 0.0508)
		)
		(pad "V9" thru_hole circle
			(at 17.599914 37.69995 180)
			(size 0.71628 0.71628)
			(drill 0.30988)
			(layers "*.Cu" "*.Mask")
			(remove_unused_layers no)
			(net "Net_8877")
			(clearance 0.0508)
			(thermal_gap 0.0508)
		)
		(pad "V10" thru_hole circle
			(at 19.800062 37.900102 180)
			(size 0.906272 0.906272)
			(drill 0.499872)
			(layers "*.Cu" "*.Mask")
			(remove_unused_layers no)
			(net "GND")
			(clearance 0.0508)
			(thermal_gap 0.0508)
		)
		(pad "W1" thru_hole circle
			(at 0 38.999922 180)
			(size 0.906272 0.906272)
			(drill 0.499872)
			(layers "*.Cu" "*.Mask")
			(remove_unused_layers no)
			(net "GND")
			(clearance 0.0508)
			(thermal_gap 0.0508)
		)
		(pad "W3" thru_hole circle
			(at 4.400042 38.999922 180)
			(size 0.906272 0.906272)
			(drill 0.499872)
			(layers "*.Cu" "*.Mask")
			(remove_unused_layers no)
			(net "GND")
			(clearance 0.0508)
			(thermal_gap 0.0508)
		)
		(pad "W5" thru_hole circle
			(at 8.800084 38.999922 180)
			(size 0.906272 0.906272)
			(drill 0.499872)
			(layers "*.Cu" "*.Mask")
			(remove_unused_layers no)
			(net "GND")
			(clearance 0.0508)
			(thermal_gap 0.0508)
		)
		(pad "W7" thru_hole circle
			(at 13.199872 38.999922 180)
			(size 0.906272 0.906272)
			(drill 0.499872)
			(layers "*.Cu" "*.Mask")
			(remove_unused_layers no)
			(net "GND")
			(clearance 0.0508)
			(thermal_gap 0.0508)
		)
		(pad "W9" thru_hole circle
			(at 17.599914 38.999922 180)
			(size 0.906272 0.906272)
			(drill 0.499872)
			(layers "*.Cu" "*.Mask")
			(remove_unused_layers no)
			(net "GND")
			(clearance 0.0508)
			(thermal_gap 0.0508)
		)
		(pad "W10" thru_hole circle
			(at 19.800062 39.200074 180)
			(size 0.71628 0.71628)
			(drill 0.30988)
			(layers "*.Cu" "*.Mask")
			(remove_unused_layers no)
			(net "Net_8876")
			(clearance 0.0508)
			(thermal_gap 0.0508)
		)
		(pad "X9" thru_hole circle
			(at 17.599914 40.299894 180)
			(size 0.71628 0.71628)
			(drill 0.30988)
			(layers "*.Cu" "*.Mask")
			(remove_unused_layers no)
			(net "Net_8874")
			(clearance 0.0508)
			(thermal_gap 0.0508)
		)
		(pad "X10" thru_hole circle
			(at 19.800062 40.500046 180)
			(size 0.71628 0.71628)
			(drill 0.30988)
			(layers "*.Cu" "*.Mask")
			(remove_unused_layers no)
			(net "Net_8875")
			(clearance 0.0508)
			(thermal_gap 0.0508)
		)
		(pad "Y2" thru_hole circle
			(at 2.199894 41.800018 180)
			(size 0.906272 0.906272)
			(drill 0.499872)
			(layers "*.Cu" "*.Mask")
			(remove_unused_layers no)
			(net "GND")
			(clearance 0.0508)
			(thermal_gap 0.0508)
		)
		(pad "Y4" thru_hole circle
			(at 6.599936 41.800018 180)
			(size 0.906272 0.906272)
			(drill 0.499872)
			(layers "*.Cu" "*.Mask")
			(remove_unused_layers no)
			(net "GND")
			(clearance 0.0508)
			(thermal_gap 0.0508)
		)
		(pad "Y6" thru_hole circle
			(at 10.999978 41.800018 180)
			(size 0.906272 0.906272)
			(drill 0.499872)
			(layers "*.Cu" "*.Mask")
			(remove_unused_layers no)
			(net "GND")
			(clearance 0.0508)
			(thermal_gap 0.0508)
		)
		(pad "Y8" thru_hole circle
			(at 15.40002 41.800018 180)
			(size 0.906272 0.906272)
			(drill 0.499872)
			(layers "*.Cu" "*.Mask")
			(remove_unused_layers no)
			(net "GND")
			(clearance 0.0508)
			(thermal_gap 0.0508)
		)
		(pad "Y9" thru_hole circle
			(at 17.599914 41.60012 180)
			(size 0.71628 0.71628)
			(drill 0.30988)
			(layers "*.Cu" "*.Mask")
			(remove_unused_layers no)
			(net "Net_8873")
			(clearance 0.0508)
			(thermal_gap 0.0508)
		)
		(pad "Y10" thru_hole circle
			(at 19.800062 41.800018 180)
			(size 0.906272 0.906272)
			(drill 0.499872)
			(layers "*.Cu" "*.Mask")
			(remove_unused_layers no)
			(net "GND")
			(clearance 0.0508)
			(thermal_gap 0.0508)
		)
		(pad "Z1" thru_hole circle
			(at 0 42.900092 180)
			(size 0.906272 0.906272)
			(drill 0.499872)
			(layers "*.Cu" "*.Mask")
			(remove_unused_layers no)
			(net "GND")
			(clearance 0.0508)
			(thermal_gap 0.0508)
		)
		(pad "Z2" thru_hole circle
			(at 2.199894 43.09999 180)
			(size 0.71628 0.71628)
			(drill 0.30988)
			(layers "*.Cu" "*.Mask")
			(remove_unused_layers no)
			(net "PRSNT_SWB_B2_N")
			(clearance 0.0508)
			(thermal_gap 0.0508)
		)
		(pad "Z3" thru_hole circle
			(at 4.400042 42.900092 180)
			(size 0.906272 0.906272)
			(drill 0.499872)
			(layers "*.Cu" "*.Mask")
			(remove_unused_layers no)
			(net "GND")
			(clearance 0.0508)
			(thermal_gap 0.0508)
		)
		(pad "Z4" thru_hole circle
			(at 6.599936 43.09999 180)
			(size 0.71628 0.71628)
			(drill 0.30988)
			(layers "*.Cu" "*.Mask")
			(remove_unused_layers no)
			(net "Net_8906")
			(clearance 0.0508)
			(thermal_gap 0.0508)
		)
		(pad "Z5" thru_hole circle
			(at 8.800084 42.900092 180)
			(size 0.906272 0.906272)
			(drill 0.499872)
			(layers "*.Cu" "*.Mask")
			(remove_unused_layers no)
			(net "GND")
			(clearance 0.0508)
			(thermal_gap 0.0508)
		)
		(pad "Z6" thru_hole circle
			(at 10.999978 43.09999 180)
			(size 0.71628 0.71628)
			(drill 0.30988)
			(layers "*.Cu" "*.Mask")
			(remove_unused_layers no)
			(net "Net_8905")
			(clearance 0.0508)
			(thermal_gap 0.0508)
		)
		(pad "Z7" thru_hole circle
			(at 13.199872 42.900092 180)
			(size 0.906272 0.906272)
			(drill 0.499872)
			(layers "*.Cu" "*.Mask")
			(remove_unused_layers no)
			(net "GND")
			(clearance 0.0508)
			(thermal_gap 0.0508)
		)
		(pad "Z8" thru_hole circle
			(at 15.40002 43.09999 180)
			(size 0.71628 0.71628)
			(drill 0.30988)
			(layers "*.Cu" "*.Mask")
			(remove_unused_layers no)
			(net "MB_HSC_EN")
			(clearance 0.0508)
			(thermal_gap 0.0508)
		)
		(pad "Z9" thru_hole circle
			(at 17.599914 42.900092 180)
			(size 0.906272 0.906272)
			(drill 0.499872)
			(layers "*.Cu" "*.Mask")
			(remove_unused_layers no)
			(net "GND")
			(clearance 0.0508)
			(thermal_gap 0.0508)
		)
		(pad "Z10" thru_hole circle
			(at 19.800062 43.09999 180)
			(size 0.71628 0.71628)
			(drill 0.30988)
			(layers "*.Cu" "*.Mask")
			(remove_unused_layers no)
			(net "PRSNT_GPU_A3_R_N")
			(clearance 0.0508)
			(thermal_gap 0.0508)
		)
		(zone
			(layer "B.Cu")
			(hatch none 0.5)
			(connect_pads
				(clearance 0)
			)
			(min_thickness 0.25)
			(keepout
				(tracks allowed)
				(vias not_allowed)
				(pads allowed)
				(copperpour not_allowed)
				(footprints allowed)
			)
			(placement
				(enabled no)
				(sheetname "")
			)
			(fill
				(thermal_gap 0.5)
				(thermal_bridge_width 0.5)
				(island_removal_mode 0)
			)
			(polygon
				(pts
					(xy 330.972922 -394.665708) (xy 351.800922 -394.665708) (xy 351.800922 -412.50743) (xy 330.972922 -412.50743)
				)
			)
		)
		(zone
			(layer "B.Cu")
			(hatch none 0.5)
			(connect_pads
				(clearance 0)
			)
			(min_thickness 0.25)
			(keepout
				(tracks allowed)
				(vias not_allowed)
				(pads allowed)
				(copperpour not_allowed)
				(footprints allowed)
			)
			(placement
				(enabled no)
				(sheetname "")
			)
			(fill
				(thermal_gap 0.5)
				(thermal_bridge_width 0.5)
				(island_removal_mode 0)
			)
			(polygon
				(pts
					(xy 330.972922 -368.572796) (xy 351.800922 -368.572796) (xy 351.800922 -386.414518) (xy 330.972922 -386.414518)
				)
			)
		)
	)
	(footprint ""
		(layer "F.Cu")
		(at 385.304792 -140.85697 180)
		(property "Reference" "R339"
			(at 0 0 180)
			(layer "F.SilkS")
			(hide yes)
			(effects
				(font
					(size 1.27 1.27)
				)
			)
		)
		(property "Value" ""
			(at 0 0 180)
			(layer "F.Fab")
			(effects
				(font
					(size 1.27 1.27)
				)
			)
		)
		(duplicate_pad_numbers_are_jumpers no)
		(fp_line
			(start 0.7874 0.4064)
			(end -0.7874 0.4064)
			(stroke
				(width 0.1524)
				(type default)
			)
			(layer "F.SilkS")
		)
		(fp_line
			(start 0.7874 -0.4064)
			(end 0.7874 0.4064)
			(stroke
				(width 0.1524)
				(type default)
			)
			(layer "F.SilkS")
		)
		(fp_line
			(start -0.7874 0.4064)
			(end -0.7874 -0.4064)
			(stroke
				(width 0.1524)
				(type default)
			)
			(layer "F.SilkS")
		)
		(fp_line
			(start -0.7874 -0.4064)
			(end 0.7874 -0.4064)
			(stroke
				(width 0.1524)
				(type default)
			)
			(layer "F.SilkS")
		)
		(fp_line
			(start 0.67945 0.3048)
			(end 0.120396 0.3048)
			(stroke
				(width 0.1)
				(type default)
			)
			(layer "F.Fab")
		)
		(fp_line
			(start 0.67945 -0.3048)
			(end 0.67945 0.3048)
			(stroke
				(width 0.1)
				(type default)
			)
			(layer "F.Fab")
		)
		(fp_line
			(start 0.12065 -0.2794)
			(end 0.12065 -0.3048)
			(stroke
				(width 0.1)
				(type default)
			)
			(layer "F.Fab")
		)
		(fp_line
			(start 0.12065 -0.3048)
			(end 0.67945 -0.3048)
			(stroke
				(width 0.1)
				(type default)
			)
			(layer "F.Fab")
		)
		(fp_line
			(start 0.120396 0.3048)
			(end 0.120396 0.2794)
			(stroke
				(width 0.1)
				(type default)
			)
			(layer "F.Fab")
		)
		(fp_line
			(start 0.120396 0.2794)
			(end -0.12065 0.2794)
			(stroke
				(width 0.1)
				(type default)
			)
			(layer "F.Fab")
		)
		(fp_line
			(start -0.12065 0.3048)
			(end -0.67945 0.3048)
			(stroke
				(width 0.1)
				(type default)
			)
			(layer "F.Fab")
		)
		(fp_line
			(start -0.12065 0.2794)
			(end -0.12065 0.3048)
			(stroke
				(width 0.1)
				(type default)
			)
			(layer "F.Fab")
		)
		(fp_line
			(start -0.12065 -0.2794)
			(end 0.12065 -0.2794)
			(stroke
				(width 0.1)
				(type default)
			)
			(layer "F.Fab")
		)
		(fp_line
			(start -0.12065 -0.305054)
			(end -0.12065 -0.2794)
			(stroke
				(width 0.1)
				(type default)
			)
			(layer "F.Fab")
		)
		(fp_line
			(start -0.67945 0.3048)
			(end -0.67945 -0.305054)
			(stroke
				(width 0.1)
				(type default)
			)
			(layer "F.Fab")
		)
		(fp_line
			(start -0.67945 -0.305054)
			(end -0.12065 -0.305054)
			(stroke
				(width 0.1)
				(type default)
			)
			(layer "F.Fab")
		)
		(pad "1" smd circle
			(at -0.40005 0 180)
			(size 0 0)
			(layers "F.Cu" "F.Mask" "F.Paste")
			(net "NIC6_BIF2_N")
		)
		(pad "2" smd circle
			(at 0.40005 0 180)
			(size 0 0)
			(layers "F.Cu" "F.Mask" "F.Paste")
			(net "P3V3_AUX")
		)
	)
	(footprint ""
		(layer "F.Cu")
		(at 94.467426 -112.903508 90)
		(property "Reference" "PC606"
			(at 0 0 90)
			(layer "F.SilkS")
			(hide yes)
			(effects
				(font
					(size 1.27 1.27)
				)
			)
		)
		(property "Value" ""
			(at 0 0 90)
			(layer "F.Fab")
			(effects
				(font
					(size 1.27 1.27)
				)
			)
		)
		(duplicate_pad_numbers_are_jumpers no)
		(fp_line
			(start 1.524 -0.762)
			(end 1.524 0.762)
			(stroke
				(width 0.1524)
				(type default)
			)
			(layer "F.SilkS")
		)
		(fp_line
			(start -1.524 -0.762)
			(end 1.524 -0.762)
			(stroke
				(width 0.1524)
				(type default)
			)
			(layer "F.SilkS")
		)
		(fp_line
			(start 1.524 0.762)
			(end -1.524 0.762)
			(stroke
				(width 0.1524)
				(type default)
			)
			(layer "F.SilkS")
		)
		(fp_line
			(start -1.524 0.762)
			(end -1.524 -0.762)
			(stroke
				(width 0.1524)
				(type default)
			)
			(layer "F.SilkS")
		)
		(fp_line
			(start 1.1049 -0.724916)
			(end -1.1049 -0.724916)
			(stroke
				(width 0.1)
				(type default)
			)
			(layer "F.Fab")
		)
		(fp_line
			(start -1.1049 -0.724916)
			(end -1.1049 0.724916)
			(stroke
				(width 0.1)
				(type default)
			)
			(layer "F.Fab")
		)
		(fp_line
			(start 1.1049 0.724916)
			(end 1.1049 -0.724916)
			(stroke
				(width 0.1)
				(type default)
			)
			(layer "F.Fab")
		)
		(fp_line
			(start -1.1049 0.724916)
			(end 1.1049 0.724916)
			(stroke
				(width 0.1)
				(type default)
			)
			(layer "F.Fab")
		)
		(pad "1" smd rect
			(at -0.889 0 270)
			(size 1.016 1.27)
			(layers "F.Cu" "F.Mask" "F.Paste")
			(net "P12V_NIC1_R")
		)
		(pad "2" smd rect
			(at 0.889 0 270)
			(size 1.016 1.27)
			(layers "F.Cu" "F.Mask" "F.Paste")
			(net "GND")
		)
	)
	(footprint ""
		(layer "F.Cu")
		(at 161.75482 -22.867366 90)
		(property "Reference" "C3913"
			(at 0 0 90)
			(layer "F.SilkS")
			(hide yes)
			(effects
				(font
					(size 1.27 1.27)
				)
			)
		)
		(property "Value" ""
			(at 0 0 90)
			(layer "F.Fab")
			(effects
				(font
					(size 1.27 1.27)
				)
			)
		)
		(duplicate_pad_numbers_are_jumpers no)
		(fp_line
			(start 0.7874 -0.4064)
			(end 0.7874 0.4064)
			(stroke
				(width 0.1524)
				(type default)
			)
			(layer "F.SilkS")
		)
		(fp_line
			(start -0.7874 -0.4064)
			(end 0.7874 -0.4064)
			(stroke
				(width 0.1524)
				(type default)
			)
			(layer "F.SilkS")
		)
		(fp_line
			(start 0.7874 0.4064)
			(end -0.7874 0.4064)
			(stroke
				(width 0.1524)
				(type default)
			)
			(layer "F.SilkS")
		)
		(fp_line
			(start -0.7874 0.4064)
			(end -0.7874 -0.4064)
			(stroke
				(width 0.1524)
				(type default)
			)
			(layer "F.SilkS")
		)
		(fp_line
			(start -0.12065 -0.305054)
			(end -0.12065 -0.2794)
			(stroke
				(width 0.1)
				(type default)
			)
			(layer "F.Fab")
		)
		(fp_line
			(start -0.67945 -0.305054)
			(end -0.12065 -0.305054)
			(stroke
				(width 0.1)
				(type default)
			)
			(layer "F.Fab")
		)
		(fp_line
			(start 0.67945 -0.3048)
			(end 0.67945 0.3048)
			(stroke
				(width 0.1)
				(type default)
			)
			(layer "F.Fab")
		)
		(fp_line
			(start 0.12065 -0.3048)
			(end 0.67945 -0.3048)
			(stroke
				(width 0.1)
				(type default)
			)
			(layer "F.Fab")
		)
		(fp_line
			(start 0.12065 -0.2794)
			(end 0.12065 -0.3048)
			(stroke
				(width 0.1)
				(type default)
			)
			(layer "F.Fab")
		)
		(fp_line
			(start -0.12065 -0.2794)
			(end 0.12065 -0.2794)
			(stroke
				(width 0.1)
				(type default)
			)
			(layer "F.Fab")
		)
		(fp_line
			(start 0.120396 0.2794)
			(end -0.12065 0.2794)
			(stroke
				(width 0.1)
				(type default)
			)
			(layer "F.Fab")
		)
		(fp_line
			(start -0.12065 0.2794)
			(end -0.12065 0.3048)
			(stroke
				(width 0.1)
				(type default)
			)
			(layer "F.Fab")
		)
		(fp_line
			(start 0.67945 0.3048)
			(end 0.120396 0.3048)
			(stroke
				(width 0.1)
				(type default)
			)
			(layer "F.Fab")
		)
		(fp_line
			(start 0.120396 0.3048)
			(end 0.120396 0.2794)
			(stroke
				(width 0.1)
				(type default)
			)
			(layer "F.Fab")
		)
		(fp_line
			(start -0.12065 0.3048)
			(end -0.67945 0.3048)
			(stroke
				(width 0.1)
				(type default)
			)
			(layer "F.Fab")
		)
		(fp_line
			(start -0.67945 0.3048)
			(end -0.67945 -0.305054)
			(stroke
				(width 0.1)
				(type default)
			)
			(layer "F.Fab")
		)
		(pad "1" smd circle
			(at -0.40005 0 90)
			(size 0 0)
			(layers "F.Cu" "F.Mask" "F.Paste")
			(net "P12V_SSD5")
		)
		(pad "2" smd circle
			(at 0.40005 0 90)
			(size 0 0)
			(layers "F.Cu" "F.Mask" "F.Paste")
			(net "GND")
		)
	)
	(footprint ""
		(layer "F.Cu")
		(at 56.84774 -40.037258 90)
		(property "Reference" "U365"
			(at 0.094742 2.38633 90)
			(unlocked yes)
			(layer "F.SilkS")
			(effects
				(font
					(size 0.7874 0.5842)
					(thickness 0.1524)
				)
			)
		)
		(property "Value" ""
			(at 0 0 90)
			(layer "F.Fab")
			(effects
				(font
					(size 1.27 1.27)
				)
			)
		)
		(duplicate_pad_numbers_are_jumpers no)
		(fp_line
			(start -1.949958 -1.610106)
			(end 1.949958 -1.610106)
			(stroke
				(width 0.1524)
				(type default)
			)
			(layer "F.SilkS")
		)
		(fp_line
			(start 1.949958 -1.560068)
			(end 1.949958 1.610106)
			(stroke
				(width 0.1524)
				(type default)
			)
			(layer "F.SilkS")
		)
		(fp_line
			(start 1.949958 1.610106)
			(end -1.949958 1.610106)
			(stroke
				(width 0.1524)
				(type default)
			)
			(layer "F.SilkS")
		)
		(fp_line
			(start -1.949958 1.610106)
			(end -1.949958 -1.610106)
			(stroke
				(width 0.1524)
				(type default)
			)
			(layer "F.SilkS")
		)
		(fp_line
			(start 0.750062 -1.560068)
			(end 0.750062 1.560068)
			(stroke
				(width 0.1)
				(type default)
			)
			(layer "F.Fab")
		)
		(fp_line
			(start -0.750062 -1.560068)
			(end 0.750062 -1.560068)
			(stroke
				(width 0.1)
				(type default)
			)
			(layer "F.Fab")
		)
		(fp_line
			(start 0.750062 1.560068)
			(end -0.750062 1.560068)
			(stroke
				(width 0.1)
				(type default)
			)
			(layer "F.Fab")
		)
		(fp_line
			(start -0.750062 1.560068)
			(end -0.750062 -1.560068)
			(stroke
				(width 0.1)
				(type default)
			)
			(layer "F.Fab")
		)
		(pad "D" smd rect
			(at 1.100074 0)
			(size 1.016 1.4224)
			(layers "F.Cu" "F.Mask" "F.Paste")
			(net "SSD2_AUX_P3V3_EN")
		)
		(pad "G" smd rect
			(at -1.100074 -0.94996)
			(size 1.016 1.4224)
			(layers "F.Cu" "F.Mask" "F.Paste")
			(net "PRSNT_SSD2_R1_N")
		)
		(pad "S" smd rect
			(at -1.100074 0.94996)
			(size 1.016 1.4224)
			(layers "F.Cu" "F.Mask" "F.Paste")
			(net "GND")
		)
	)
	(footprint ""
		(layer "F.Cu")
		(at 104.243632 -47.92091)
		(property "Reference" "R537"
			(at 0 0 0)
			(layer "F.SilkS")
			(hide yes)
			(effects
				(font
					(size 1.27 1.27)
				)
			)
		)
		(property "Value" ""
			(at 0 0 0)
			(layer "F.Fab")
			(effects
				(font
					(size 1.27 1.27)
				)
			)
		)
		(duplicate_pad_numbers_are_jumpers no)
		(fp_line
			(start -0.7874 -0.4064)
			(end 0.7874 -0.4064)
			(stroke
				(width 0.1524)
				(type default)
			)
			(layer "F.SilkS")
		)
		(fp_line
			(start -0.7874 0.4064)
			(end -0.7874 -0.4064)
			(stroke
				(width 0.1524)
				(type default)
			)
			(layer "F.SilkS")
		)
		(fp_line
			(start 0.7874 -0.4064)
			(end 0.7874 0.4064)
			(stroke
				(width 0.1524)
				(type default)
			)
			(layer "F.SilkS")
		)
		(fp_line
			(start 0.7874 0.4064)
			(end -0.7874 0.4064)
			(stroke
				(width 0.1524)
				(type default)
			)
			(layer "F.SilkS")
		)
		(fp_line
			(start -0.67945 -0.305054)
			(end -0.12065 -0.305054)
			(stroke
				(width 0.1)
				(type default)
			)
			(layer "F.Fab")
		)
		(fp_line
			(start -0.67945 0.3048)
			(end -0.67945 -0.305054)
			(stroke
				(width 0.1)
				(type default)
			)
			(layer "F.Fab")
		)
		(fp_line
			(start -0.12065 -0.305054)
			(end -0.12065 -0.2794)
			(stroke
				(width 0.1)
				(type default)
			)
			(layer "F.Fab")
		)
		(fp_line
			(start -0.12065 -0.2794)
			(end 0.12065 -0.2794)
			(stroke
				(width 0.1)
				(type default)
			)
			(layer "F.Fab")
		)
		(fp_line
			(start -0.12065 0.2794)
			(end -0.12065 0.3048)
			(stroke
				(width 0.1)
				(type default)
			)
			(layer "F.Fab")
		)
		(fp_line
			(start -0.12065 0.3048)
			(end -0.67945 0.3048)
			(stroke
				(width 0.1)
				(type default)
			)
			(layer "F.Fab")
		)
		(fp_line
			(start 0.120396 0.2794)
			(end -0.12065 0.2794)
			(stroke
				(width 0.1)
				(type default)
			)
			(layer "F.Fab")
		)
		(fp_line
			(start 0.120396 0.3048)
			(end 0.120396 0.2794)
			(stroke
				(width 0.1)
				(type default)
			)
			(layer "F.Fab")
		)
		(fp_line
			(start 0.12065 -0.3048)
			(end 0.67945 -0.3048)
			(stroke
				(width 0.1)
				(type default)
			)
			(layer "F.Fab")
		)
		(fp_line
			(start 0.12065 -0.2794)
			(end 0.12065 -0.3048)
			(stroke
				(width 0.1)
				(type default)
			)
			(layer "F.Fab")
		)
		(fp_line
			(start 0.67945 -0.3048)
			(end 0.67945 0.3048)
			(stroke
				(width 0.1)
				(type default)
			)
			(layer "F.Fab")
		)
		(fp_line
			(start 0.67945 0.3048)
			(end 0.120396 0.3048)
			(stroke
				(width 0.1)
				(type default)
			)
			(layer "F.Fab")
		)
		(pad "1" smd circle
			(at -0.40005 0)
			(size 0 0)
			(layers "F.Cu" "F.Mask" "F.Paste")
			(net "P3V3_AUX")
		)
		(pad "2" smd circle
			(at 0.40005 0)
			(size 0 0)
			(layers "F.Cu" "F.Mask" "F.Paste")
			(net "SSD_0_7_ADC_ALERT_N")
		)
	)
	(footprint ""
		(layer "F.Cu")
		(at 329.922886 -207.541368 -90)
		(property "Reference" "R4405"
			(at 0 0 270)
			(layer "F.SilkS")
			(hide yes)
			(effects
				(font
					(size 1.27 1.27)
				)
			)
		)
		(property "Value" ""
			(at 0 0 270)
			(layer "F.Fab")
			(effects
				(font
					(size 1.27 1.27)
				)
			)
		)
		(duplicate_pad_numbers_are_jumpers no)
		(fp_line
			(start -0.7874 0.4064)
			(end -0.7874 -0.4064)
			(stroke
				(width 0.1524)
				(type default)
			)
			(layer "F.SilkS")
		)
		(fp_line
			(start 0.7874 0.4064)
			(end -0.7874 0.4064)
			(stroke
				(width 0.1524)
				(type default)
			)
			(layer "F.SilkS")
		)
		(fp_line
			(start -0.7874 -0.4064)
			(end 0.7874 -0.4064)
			(stroke
				(width 0.1524)
				(type default)
			)
			(layer "F.SilkS")
		)
		(fp_line
			(start 0.7874 -0.4064)
			(end 0.7874 0.4064)
			(stroke
				(width 0.1524)
				(type default)
			)
			(layer "F.SilkS")
		)
		(fp_line
			(start -0.67945 0.3048)
			(end -0.67945 -0.305054)
			(stroke
				(width 0.1)
				(type default)
			)
			(layer "F.Fab")
		)
		(fp_line
			(start -0.12065 0.3048)
			(end -0.67945 0.3048)
			(stroke
				(width 0.1)
				(type default)
			)
			(layer "F.Fab")
		)
		(fp_line
			(start 0.120396 0.3048)
			(end 0.120396 0.2794)
			(stroke
				(width 0.1)
				(type default)
			)
			(layer "F.Fab")
		)
		(fp_line
			(start 0.67945 0.3048)
			(end 0.120396 0.3048)
			(stroke
				(width 0.1)
				(type default)
			)
			(layer "F.Fab")
		)
		(fp_line
			(start -0.12065 0.2794)
			(end -0.12065 0.3048)
			(stroke
				(width 0.1)
				(type default)
			)
			(layer "F.Fab")
		)
		(fp_line
			(start 0.120396 0.2794)
			(end -0.12065 0.2794)
			(stroke
				(width 0.1)
				(type default)
			)
			(layer "F.Fab")
		)
		(fp_line
			(start -0.12065 -0.2794)
			(end 0.12065 -0.2794)
			(stroke
				(width 0.1)
				(type default)
			)
			(layer "F.Fab")
		)
		(fp_line
			(start 0.12065 -0.2794)
			(end 0.12065 -0.3048)
			(stroke
				(width 0.1)
				(type default)
			)
			(layer "F.Fab")
		)
		(fp_line
			(start 0.12065 -0.3048)
			(end 0.67945 -0.3048)
			(stroke
				(width 0.1)
				(type default)
			)
			(layer "F.Fab")
		)
		(fp_line
			(start 0.67945 -0.3048)
			(end 0.67945 0.3048)
			(stroke
				(width 0.1)
				(type default)
			)
			(layer "F.Fab")
		)
		(fp_line
			(start -0.67945 -0.305054)
			(end -0.12065 -0.305054)
			(stroke
				(width 0.1)
				(type default)
			)
			(layer "F.Fab")
		)
		(fp_line
			(start -0.12065 -0.305054)
			(end -0.12065 -0.2794)
			(stroke
				(width 0.1)
				(type default)
			)
			(layer "F.Fab")
		)
		(pad "1" smd circle
			(at -0.40005 0 270)
			(size 0 0)
			(layers "F.Cu" "F.Mask" "F.Paste")
			(net "CLK_25M_FPGA_R")
		)
		(pad "2" smd circle
			(at 0.40005 0 270)
			(size 0 0)
			(layers "F.Cu" "F.Mask" "F.Paste")
			(net "CLK_25M_FPGA")
		)
	)
	(footprint ""
		(layer "F.Cu")
		(at 195.414646 -79.58201 90)
		(property "Reference" "R202"
			(at 0 0 90)
			(layer "F.SilkS")
			(hide yes)
			(effects
				(font
					(size 1.27 1.27)
				)
			)
		)
		(property "Value" ""
			(at 0 0 90)
			(layer "F.Fab")
			(effects
				(font
					(size 1.27 1.27)
				)
			)
		)
		(duplicate_pad_numbers_are_jumpers no)
		(fp_line
			(start 0.7874 -0.4064)
			(end 0.7874 0.4064)
			(stroke
				(width 0.1524)
				(type default)
			)
			(layer "F.SilkS")
		)
		(fp_line
			(start -0.7874 -0.4064)
			(end 0.7874 -0.4064)
			(stroke
				(width 0.1524)
				(type default)
			)
			(layer "F.SilkS")
		)
		(fp_line
			(start 0.7874 0.4064)
			(end -0.7874 0.4064)
			(stroke
				(width 0.1524)
				(type default)
			)
			(layer "F.SilkS")
		)
		(fp_line
			(start -0.7874 0.4064)
			(end -0.7874 -0.4064)
			(stroke
				(width 0.1524)
				(type default)
			)
			(layer "F.SilkS")
		)
		(fp_line
			(start -0.12065 -0.305054)
			(end -0.12065 -0.2794)
			(stroke
				(width 0.1)
				(type default)
			)
			(layer "F.Fab")
		)
		(fp_line
			(start -0.67945 -0.305054)
			(end -0.12065 -0.305054)
			(stroke
				(width 0.1)
				(type default)
			)
			(layer "F.Fab")
		)
		(fp_line
			(start 0.67945 -0.3048)
			(end 0.67945 0.3048)
			(stroke
				(width 0.1)
				(type default)
			)
			(layer "F.Fab")
		)
		(fp_line
			(start 0.12065 -0.3048)
			(end 0.67945 -0.3048)
			(stroke
				(width 0.1)
				(type default)
			)
			(layer "F.Fab")
		)
		(fp_line
			(start 0.12065 -0.2794)
			(end 0.12065 -0.3048)
			(stroke
				(width 0.1)
				(type default)
			)
			(layer "F.Fab")
		)
		(fp_line
			(start -0.12065 -0.2794)
			(end 0.12065 -0.2794)
			(stroke
				(width 0.1)
				(type default)
			)
			(layer "F.Fab")
		)
		(fp_line
			(start 0.120396 0.2794)
			(end -0.12065 0.2794)
			(stroke
				(width 0.1)
				(type default)
			)
			(layer "F.Fab")
		)
		(fp_line
			(start -0.12065 0.2794)
			(end -0.12065 0.3048)
			(stroke
				(width 0.1)
				(type default)
			)
			(layer "F.Fab")
		)
		(fp_line
			(start 0.67945 0.3048)
			(end 0.120396 0.3048)
			(stroke
				(width 0.1)
				(type default)
			)
			(layer "F.Fab")
		)
		(fp_line
			(start 0.120396 0.3048)
			(end 0.120396 0.2794)
			(stroke
				(width 0.1)
				(type default)
			)
			(layer "F.Fab")
		)
		(fp_line
			(start -0.12065 0.3048)
			(end -0.67945 0.3048)
			(stroke
				(width 0.1)
				(type default)
			)
			(layer "F.Fab")
		)
		(fp_line
			(start -0.67945 0.3048)
			(end -0.67945 -0.305054)
			(stroke
				(width 0.1)
				(type default)
			)
			(layer "F.Fab")
		)
		(pad "1" smd circle
			(at -0.40005 0 90)
			(size 0 0)
			(layers "F.Cu" "F.Mask" "F.Paste")
			(net "P3V3_NIC3")
		)
		(pad "2" smd circle
			(at 0.40005 0 90)
			(size 0 0)
			(layers "F.Cu" "F.Mask" "F.Paste")
			(net "HP_NIC3_PWRGD")
		)
	)
	(footprint ""
		(layer "F.Cu")
		(at 338.074 -183.007 180)
		(property "Reference" "R4749"
			(at 0 0 180)
			(layer "F.SilkS")
			(hide yes)
			(effects
				(font
					(size 1.27 1.27)
				)
			)
		)
		(property "Value" ""
			(at 0 0 180)
			(layer "F.Fab")
			(effects
				(font
					(size 1.27 1.27)
				)
			)
		)
		(duplicate_pad_numbers_are_jumpers no)
		(fp_line
			(start 0.7874 0.4064)
			(end -0.7874 0.4064)
			(stroke
				(width 0.1524)
				(type default)
			)
			(layer "F.SilkS")
		)
		(fp_line
			(start 0.7874 -0.4064)
			(end 0.7874 0.4064)
			(stroke
				(width 0.1524)
				(type default)
			)
			(layer "F.SilkS")
		)
		(fp_line
			(start -0.7874 0.4064)
			(end -0.7874 -0.4064)
			(stroke
				(width 0.1524)
				(type default)
			)
			(layer "F.SilkS")
		)
		(fp_line
			(start -0.7874 -0.4064)
			(end 0.7874 -0.4064)
			(stroke
				(width 0.1524)
				(type default)
			)
			(layer "F.SilkS")
		)
		(fp_line
			(start 0.67945 0.3048)
			(end 0.120396 0.3048)
			(stroke
				(width 0.1)
				(type default)
			)
			(layer "F.Fab")
		)
		(fp_line
			(start 0.67945 -0.3048)
			(end 0.67945 0.3048)
			(stroke
				(width 0.1)
				(type default)
			)
			(layer "F.Fab")
		)
		(fp_line
			(start 0.12065 -0.2794)
			(end 0.12065 -0.3048)
			(stroke
				(width 0.1)
				(type default)
			)
			(layer "F.Fab")
		)
		(fp_line
			(start 0.12065 -0.3048)
			(end 0.67945 -0.3048)
			(stroke
				(width 0.1)
				(type default)
			)
			(layer "F.Fab")
		)
		(fp_line
			(start 0.120396 0.3048)
			(end 0.120396 0.2794)
			(stroke
				(width 0.1)
				(type default)
			)
			(layer "F.Fab")
		)
		(fp_line
			(start 0.120396 0.2794)
			(end -0.12065 0.2794)
			(stroke
				(width 0.1)
				(type default)
			)
			(layer "F.Fab")
		)
		(fp_line
			(start -0.12065 0.3048)
			(end -0.67945 0.3048)
			(stroke
				(width 0.1)
				(type default)
			)
			(layer "F.Fab")
		)
		(fp_line
			(start -0.12065 0.2794)
			(end -0.12065 0.3048)
			(stroke
				(width 0.1)
				(type default)
			)
			(layer "F.Fab")
		)
		(fp_line
			(start -0.12065 -0.2794)
			(end 0.12065 -0.2794)
			(stroke
				(width 0.1)
				(type default)
			)
			(layer "F.Fab")
		)
		(fp_line
			(start -0.12065 -0.305054)
			(end -0.12065 -0.2794)
			(stroke
				(width 0.1)
				(type default)
			)
			(layer "F.Fab")
		)
		(fp_line
			(start -0.67945 0.3048)
			(end -0.67945 -0.305054)
			(stroke
				(width 0.1)
				(type default)
			)
			(layer "F.Fab")
		)
		(fp_line
			(start -0.67945 -0.305054)
			(end -0.12065 -0.305054)
			(stroke
				(width 0.1)
				(type default)
			)
			(layer "F.Fab")
		)
		(pad "1" smd circle
			(at -0.40005 0 180)
			(size 0 0)
			(layers "F.Cu" "F.Mask" "F.Paste")
			(net "PRSNT_SSD8_FPGA_PCA9555_N")
		)
		(pad "2" smd circle
			(at 0.40005 0 180)
			(size 0 0)
			(layers "F.Cu" "F.Mask" "F.Paste")
			(net "PRSNT_SSD8_FPGA_R_N")
		)
	)
	(footprint ""
		(layer "F.Cu")
		(at 284.16504 -5.999988)
		(property "Reference" "H62"
			(at -5.272024 -5.20573 0)
			(unlocked yes)
			(layer "F.SilkS")
			(effects
				(font
					(size 0.7874 0.5842)
					(thickness 0.1524)
				)
				(justify left)
			)
		)
		(property "Value" ""
			(at 0 0 0)
			(layer "F.Fab")
			(effects
				(font
					(size 1.27 1.27)
				)
			)
		)
		(duplicate_pad_numbers_are_jumpers no)
		(pad "1" thru_hole circle
			(at 0 0)
			(size 10.0076 10.0076)
			(drill 5.6134)
			(layers "*.Cu" "*.Mask")
			(remove_unused_layers no)
			(net "GND")
			(clearance -1.9431)
		)
	)
	(footprint ""
		(layer "F.Cu")
		(at 426.567854 -54.067456)
		(property "Reference" "PR234"
			(at 0 0 0)
			(layer "F.SilkS")
			(hide yes)
			(effects
				(font
					(size 1.27 1.27)
				)
			)
		)
		(property "Value" ""
			(at 0 0 0)
			(layer "F.Fab")
			(effects
				(font
					(size 1.27 1.27)
				)
			)
		)
		(duplicate_pad_numbers_are_jumpers no)
		(fp_line
			(start -0.7874 -0.4064)
			(end 0.7874 -0.4064)
			(stroke
				(width 0.1524)
				(type default)
			)
			(layer "F.SilkS")
		)
		(fp_line
			(start -0.7874 0.4064)
			(end -0.7874 -0.4064)
			(stroke
				(width 0.1524)
				(type default)
			)
			(layer "F.SilkS")
		)
		(fp_line
			(start 0.7874 -0.4064)
			(end 0.7874 0.4064)
			(stroke
				(width 0.1524)
				(type default)
			)
			(layer "F.SilkS")
		)
		(fp_line
			(start 0.7874 0.4064)
			(end -0.7874 0.4064)
			(stroke
				(width 0.1524)
				(type default)
			)
			(layer "F.SilkS")
		)
		(fp_line
			(start -0.67945 -0.305054)
			(end -0.12065 -0.305054)
			(stroke
				(width 0.1)
				(type default)
			)
			(layer "F.Fab")
		)
		(fp_line
			(start -0.67945 0.3048)
			(end -0.67945 -0.305054)
			(stroke
				(width 0.1)
				(type default)
			)
			(layer "F.Fab")
		)
		(fp_line
			(start -0.12065 -0.305054)
			(end -0.12065 -0.2794)
			(stroke
				(width 0.1)
				(type default)
			)
			(layer "F.Fab")
		)
		(fp_line
			(start -0.12065 -0.2794)
			(end 0.12065 -0.2794)
			(stroke
				(width 0.1)
				(type default)
			)
			(layer "F.Fab")
		)
		(fp_line
			(start -0.12065 0.2794)
			(end -0.12065 0.3048)
			(stroke
				(width 0.1)
				(type default)
			)
			(layer "F.Fab")
		)
		(fp_line
			(start -0.12065 0.3048)
			(end -0.67945 0.3048)
			(stroke
				(width 0.1)
				(type default)
			)
			(layer "F.Fab")
		)
		(fp_line
			(start 0.120396 0.2794)
			(end -0.12065 0.2794)
			(stroke
				(width 0.1)
				(type default)
			)
			(layer "F.Fab")
		)
		(fp_line
			(start 0.120396 0.3048)
			(end 0.120396 0.2794)
			(stroke
				(width 0.1)
				(type default)
			)
			(layer "F.Fab")
		)
		(fp_line
			(start 0.12065 -0.3048)
			(end 0.67945 -0.3048)
			(stroke
				(width 0.1)
				(type default)
			)
			(layer "F.Fab")
		)
		(fp_line
			(start 0.12065 -0.2794)
			(end 0.12065 -0.3048)
			(stroke
				(width 0.1)
				(type default)
			)
			(layer "F.Fab")
		)
		(fp_line
			(start 0.67945 -0.3048)
			(end 0.67945 0.3048)
			(stroke
				(width 0.1)
				(type default)
			)
			(layer "F.Fab")
		)
		(fp_line
			(start 0.67945 0.3048)
			(end 0.120396 0.3048)
			(stroke
				(width 0.1)
				(type default)
			)
			(layer "F.Fab")
		)
		(pad "1" smd circle
			(at -0.40005 0)
			(size 0 0)
			(layers "F.Cu" "F.Mask" "F.Paste")
			(net "P12V_SSD14_OCP")
		)
		(pad "2" smd circle
			(at 0.40005 0)
			(size 0 0)
			(layers "F.Cu" "F.Mask" "F.Paste")
			(net "GND")
		)
	)
	(footprint ""
		(layer "F.Cu")
		(at 365.506 -203.835)
		(property "Reference" "R4685"
			(at 0 0 0)
			(layer "F.SilkS")
			(hide yes)
			(effects
				(font
					(size 1.27 1.27)
				)
			)
		)
		(property "Value" ""
			(at 0 0 0)
			(layer "F.Fab")
			(effects
				(font
					(size 1.27 1.27)
				)
			)
		)
		(duplicate_pad_numbers_are_jumpers no)
		(fp_line
			(start -0.7874 -0.4064)
			(end 0.7874 -0.4064)
			(stroke
				(width 0.1524)
				(type default)
			)
			(layer "F.SilkS")
		)
		(fp_line
			(start -0.7874 0.4064)
			(end -0.7874 -0.4064)
			(stroke
				(width 0.1524)
				(type default)
			)
			(layer "F.SilkS")
		)
		(fp_line
			(start 0.7874 -0.4064)
			(end 0.7874 0.4064)
			(stroke
				(width 0.1524)
				(type default)
			)
			(layer "F.SilkS")
		)
		(fp_line
			(start 0.7874 0.4064)
			(end -0.7874 0.4064)
			(stroke
				(width 0.1524)
				(type default)
			)
			(layer "F.SilkS")
		)
		(fp_line
			(start -0.67945 -0.305054)
			(end -0.12065 -0.305054)
			(stroke
				(width 0.1)
				(type default)
			)
			(layer "F.Fab")
		)
		(fp_line
			(start -0.67945 0.3048)
			(end -0.67945 -0.305054)
			(stroke
				(width 0.1)
				(type default)
			)
			(layer "F.Fab")
		)
		(fp_line
			(start -0.12065 -0.305054)
			(end -0.12065 -0.2794)
			(stroke
				(width 0.1)
				(type default)
			)
			(layer "F.Fab")
		)
		(fp_line
			(start -0.12065 -0.2794)
			(end 0.12065 -0.2794)
			(stroke
				(width 0.1)
				(type default)
			)
			(layer "F.Fab")
		)
		(fp_line
			(start -0.12065 0.2794)
			(end -0.12065 0.3048)
			(stroke
				(width 0.1)
				(type default)
			)
			(layer "F.Fab")
		)
		(fp_line
			(start -0.12065 0.3048)
			(end -0.67945 0.3048)
			(stroke
				(width 0.1)
				(type default)
			)
			(layer "F.Fab")
		)
		(fp_line
			(start 0.120396 0.2794)
			(end -0.12065 0.2794)
			(stroke
				(width 0.1)
				(type default)
			)
			(layer "F.Fab")
		)
		(fp_line
			(start 0.120396 0.3048)
			(end 0.120396 0.2794)
			(stroke
				(width 0.1)
				(type default)
			)
			(layer "F.Fab")
		)
		(fp_line
			(start 0.12065 -0.3048)
			(end 0.67945 -0.3048)
			(stroke
				(width 0.1)
				(type default)
			)
			(layer "F.Fab")
		)
		(fp_line
			(start 0.12065 -0.2794)
			(end 0.12065 -0.3048)
			(stroke
				(width 0.1)
				(type default)
			)
			(layer "F.Fab")
		)
		(fp_line
			(start 0.67945 -0.3048)
			(end 0.67945 0.3048)
			(stroke
				(width 0.1)
				(type default)
			)
			(layer "F.Fab")
		)
		(fp_line
			(start 0.67945 0.3048)
			(end 0.120396 0.3048)
			(stroke
				(width 0.1)
				(type default)
			)
			(layer "F.Fab")
		)
		(pad "1" smd circle
			(at -0.40005 0)
			(size 0 0)
			(layers "F.Cu" "F.Mask" "F.Paste")
			(net "PEX1_PCA9555_0_INT_N")
		)
		(pad "2" smd circle
			(at 0.40005 0)
			(size 0 0)
			(layers "F.Cu" "F.Mask" "F.Paste")
			(net "P1V8_PEX")
		)
	)
	(footprint ""
		(layer "F.Cu")
		(at 329.311 -245.237 90)
		(property "Reference" "R4047"
			(at 0 0 90)
			(layer "F.SilkS")
			(hide yes)
			(effects
				(font
					(size 1.27 1.27)
				)
			)
		)
		(property "Value" ""
			(at 0 0 90)
			(layer "F.Fab")
			(effects
				(font
					(size 1.27 1.27)
				)
			)
		)
		(duplicate_pad_numbers_are_jumpers no)
		(fp_line
			(start 0.7874 -0.4064)
			(end 0.7874 0.4064)
			(stroke
				(width 0.1524)
				(type default)
			)
			(layer "F.SilkS")
		)
		(fp_line
			(start -0.7874 -0.4064)
			(end 0.7874 -0.4064)
			(stroke
				(width 0.1524)
				(type default)
			)
			(layer "F.SilkS")
		)
		(fp_line
			(start 0.7874 0.4064)
			(end -0.7874 0.4064)
			(stroke
				(width 0.1524)
				(type default)
			)
			(layer "F.SilkS")
		)
		(fp_line
			(start -0.7874 0.4064)
			(end -0.7874 -0.4064)
			(stroke
				(width 0.1524)
				(type default)
			)
			(layer "F.SilkS")
		)
		(fp_line
			(start -0.12065 -0.305054)
			(end -0.12065 -0.2794)
			(stroke
				(width 0.1)
				(type default)
			)
			(layer "F.Fab")
		)
		(fp_line
			(start -0.67945 -0.305054)
			(end -0.12065 -0.305054)
			(stroke
				(width 0.1)
				(type default)
			)
			(layer "F.Fab")
		)
		(fp_line
			(start 0.67945 -0.3048)
			(end 0.67945 0.3048)
			(stroke
				(width 0.1)
				(type default)
			)
			(layer "F.Fab")
		)
		(fp_line
			(start 0.12065 -0.3048)
			(end 0.67945 -0.3048)
			(stroke
				(width 0.1)
				(type default)
			)
			(layer "F.Fab")
		)
		(fp_line
			(start 0.12065 -0.2794)
			(end 0.12065 -0.3048)
			(stroke
				(width 0.1)
				(type default)
			)
			(layer "F.Fab")
		)
		(fp_line
			(start -0.12065 -0.2794)
			(end 0.12065 -0.2794)
			(stroke
				(width 0.1)
				(type default)
			)
			(layer "F.Fab")
		)
		(fp_line
			(start 0.120396 0.2794)
			(end -0.12065 0.2794)
			(stroke
				(width 0.1)
				(type default)
			)
			(layer "F.Fab")
		)
		(fp_line
			(start -0.12065 0.2794)
			(end -0.12065 0.3048)
			(stroke
				(width 0.1)
				(type default)
			)
			(layer "F.Fab")
		)
		(fp_line
			(start 0.67945 0.3048)
			(end 0.120396 0.3048)
			(stroke
				(width 0.1)
				(type default)
			)
			(layer "F.Fab")
		)
		(fp_line
			(start 0.120396 0.3048)
			(end 0.120396 0.2794)
			(stroke
				(width 0.1)
				(type default)
			)
			(layer "F.Fab")
		)
		(fp_line
			(start -0.12065 0.3048)
			(end -0.67945 0.3048)
			(stroke
				(width 0.1)
				(type default)
			)
			(layer "F.Fab")
		)
		(fp_line
			(start -0.67945 0.3048)
			(end -0.67945 -0.305054)
			(stroke
				(width 0.1)
				(type default)
			)
			(layer "F.Fab")
		)
		(pad "1" smd circle
			(at -0.40005 0 90)
			(size 0 0)
			(layers "F.Cu" "F.Mask" "F.Paste")
			(net "P3V3_AUX")
		)
		(pad "2" smd circle
			(at 0.40005 0 90)
			(size 0 0)
			(layers "F.Cu" "F.Mask" "F.Paste")
			(net "JP_FPGA_FRC_PWRON_N")
		)
	)
	(footprint ""
		(layer "F.Cu")
		(at 363.478826 -111.377476 -90)
		(property "Reference" "PR7103"
			(at 0 0 270)
			(layer "F.SilkS")
			(hide yes)
			(effects
				(font
					(size 1.27 1.27)
				)
			)
		)
		(property "Value" ""
			(at 0 0 270)
			(layer "F.Fab")
			(effects
				(font
					(size 1.27 1.27)
				)
			)
		)
		(duplicate_pad_numbers_are_jumpers no)
		(fp_line
			(start -0.7874 0.4064)
			(end -0.7874 -0.4064)
			(stroke
				(width 0.1524)
				(type default)
			)
			(layer "F.SilkS")
		)
		(fp_line
			(start 0.7874 0.4064)
			(end -0.7874 0.4064)
			(stroke
				(width 0.1524)
				(type default)
			)
			(layer "F.SilkS")
		)
		(fp_line
			(start -0.7874 -0.4064)
			(end 0.7874 -0.4064)
			(stroke
				(width 0.1524)
				(type default)
			)
			(layer "F.SilkS")
		)
		(fp_line
			(start 0.7874 -0.4064)
			(end 0.7874 0.4064)
			(stroke
				(width 0.1524)
				(type default)
			)
			(layer "F.SilkS")
		)
		(fp_line
			(start -0.67945 0.3048)
			(end -0.67945 -0.305054)
			(stroke
				(width 0.1)
				(type default)
			)
			(layer "F.Fab")
		)
		(fp_line
			(start -0.12065 0.3048)
			(end -0.67945 0.3048)
			(stroke
				(width 0.1)
				(type default)
			)
			(layer "F.Fab")
		)
		(fp_line
			(start 0.120396 0.3048)
			(end 0.120396 0.2794)
			(stroke
				(width 0.1)
				(type default)
			)
			(layer "F.Fab")
		)
		(fp_line
			(start 0.67945 0.3048)
			(end 0.120396 0.3048)
			(stroke
				(width 0.1)
				(type default)
			)
			(layer "F.Fab")
		)
		(fp_line
			(start -0.12065 0.2794)
			(end -0.12065 0.3048)
			(stroke
				(width 0.1)
				(type default)
			)
			(layer "F.Fab")
		)
		(fp_line
			(start 0.120396 0.2794)
			(end -0.12065 0.2794)
			(stroke
				(width 0.1)
				(type default)
			)
			(layer "F.Fab")
		)
		(fp_line
			(start -0.12065 -0.2794)
			(end 0.12065 -0.2794)
			(stroke
				(width 0.1)
				(type default)
			)
			(layer "F.Fab")
		)
		(fp_line
			(start 0.12065 -0.2794)
			(end 0.12065 -0.3048)
			(stroke
				(width 0.1)
				(type default)
			)
			(layer "F.Fab")
		)
		(fp_line
			(start 0.12065 -0.3048)
			(end 0.67945 -0.3048)
			(stroke
				(width 0.1)
				(type default)
			)
			(layer "F.Fab")
		)
		(fp_line
			(start 0.67945 -0.3048)
			(end 0.67945 0.3048)
			(stroke
				(width 0.1)
				(type default)
			)
			(layer "F.Fab")
		)
		(fp_line
			(start -0.67945 -0.305054)
			(end -0.12065 -0.305054)
			(stroke
				(width 0.1)
				(type default)
			)
			(layer "F.Fab")
		)
		(fp_line
			(start -0.12065 -0.305054)
			(end -0.12065 -0.2794)
			(stroke
				(width 0.1)
				(type default)
			)
			(layer "F.Fab")
		)
		(pad "1" smd circle
			(at -0.40005 0 270)
			(size 0 0)
			(layers "F.Cu" "F.Mask" "F.Paste")
			(net "P3V3_NIC6_CO_MODE")
		)
		(pad "2" smd circle
			(at 0.40005 0 270)
			(size 0 0)
			(layers "F.Cu" "F.Mask" "F.Paste")
			(net "GND")
		)
	)
	(footprint ""
		(layer "F.Cu")
		(at 177.593752 -165.670484 -90)
		(property "Reference" "R2465"
			(at 0 0 270)
			(layer "F.SilkS")
			(hide yes)
			(effects
				(font
					(size 1.27 1.27)
				)
			)
		)
		(property "Value" ""
			(at 0 0 270)
			(layer "F.Fab")
			(effects
				(font
					(size 1.27 1.27)
				)
			)
		)
		(duplicate_pad_numbers_are_jumpers no)
		(fp_line
			(start -0.7874 0.4064)
			(end -0.7874 -0.4064)
			(stroke
				(width 0.1524)
				(type default)
			)
			(layer "F.SilkS")
		)
		(fp_line
			(start 0.7874 0.4064)
			(end -0.7874 0.4064)
			(stroke
				(width 0.1524)
				(type default)
			)
			(layer "F.SilkS")
		)
		(fp_line
			(start -0.7874 -0.4064)
			(end 0.7874 -0.4064)
			(stroke
				(width 0.1524)
				(type default)
			)
			(layer "F.SilkS")
		)
		(fp_line
			(start 0.7874 -0.4064)
			(end 0.7874 0.4064)
			(stroke
				(width 0.1524)
				(type default)
			)
			(layer "F.SilkS")
		)
		(fp_line
			(start -0.67945 0.3048)
			(end -0.67945 -0.305054)
			(stroke
				(width 0.1)
				(type default)
			)
			(layer "F.Fab")
		)
		(fp_line
			(start -0.12065 0.3048)
			(end -0.67945 0.3048)
			(stroke
				(width 0.1)
				(type default)
			)
			(layer "F.Fab")
		)
		(fp_line
			(start 0.120396 0.3048)
			(end 0.120396 0.2794)
			(stroke
				(width 0.1)
				(type default)
			)
			(layer "F.Fab")
		)
		(fp_line
			(start 0.67945 0.3048)
			(end 0.120396 0.3048)
			(stroke
				(width 0.1)
				(type default)
			)
			(layer "F.Fab")
		)
		(fp_line
			(start -0.12065 0.2794)
			(end -0.12065 0.3048)
			(stroke
				(width 0.1)
				(type default)
			)
			(layer "F.Fab")
		)
		(fp_line
			(start 0.120396 0.2794)
			(end -0.12065 0.2794)
			(stroke
				(width 0.1)
				(type default)
			)
			(layer "F.Fab")
		)
		(fp_line
			(start -0.12065 -0.2794)
			(end 0.12065 -0.2794)
			(stroke
				(width 0.1)
				(type default)
			)
			(layer "F.Fab")
		)
		(fp_line
			(start 0.12065 -0.2794)
			(end 0.12065 -0.3048)
			(stroke
				(width 0.1)
				(type default)
			)
			(layer "F.Fab")
		)
		(fp_line
			(start 0.12065 -0.3048)
			(end 0.67945 -0.3048)
			(stroke
				(width 0.1)
				(type default)
			)
			(layer "F.Fab")
		)
		(fp_line
			(start 0.67945 -0.3048)
			(end 0.67945 0.3048)
			(stroke
				(width 0.1)
				(type default)
			)
			(layer "F.Fab")
		)
		(fp_line
			(start -0.67945 -0.305054)
			(end -0.12065 -0.305054)
			(stroke
				(width 0.1)
				(type default)
			)
			(layer "F.Fab")
		)
		(fp_line
			(start -0.12065 -0.305054)
			(end -0.12065 -0.2794)
			(stroke
				(width 0.1)
				(type default)
			)
			(layer "F.Fab")
		)
		(pad "1" smd circle
			(at -0.40005 0 270)
			(size 0 0)
			(layers "F.Cu" "F.Mask" "F.Paste")
			(net "P3V3_NIC2")
		)
		(pad "2" smd circle
			(at 0.40005 0 270)
			(size 0 0)
			(layers "F.Cu" "F.Mask" "F.Paste")
			(net "NIC2_PWRBRK_N")
		)
	)
	(footprint ""
		(layer "F.Cu")
		(at 427.632114 -32.848042 90)
		(property "Reference" "PC977"
			(at 0 0 90)
			(layer "F.SilkS")
			(hide yes)
			(effects
				(font
					(size 1.27 1.27)
				)
			)
		)
		(property "Value" ""
			(at 0 0 90)
			(layer "F.Fab")
			(effects
				(font
					(size 1.27 1.27)
				)
			)
		)
		(duplicate_pad_numbers_are_jumpers no)
		(fp_line
			(start 0.7874 -0.4064)
			(end 0.7874 0.4064)
			(stroke
				(width 0.1524)
				(type default)
			)
			(layer "F.SilkS")
		)
		(fp_line
			(start -0.7874 -0.4064)
			(end 0.7874 -0.4064)
			(stroke
				(width 0.1524)
				(type default)
			)
			(layer "F.SilkS")
		)
		(fp_line
			(start 0.7874 0.4064)
			(end -0.7874 0.4064)
			(stroke
				(width 0.1524)
				(type default)
			)
			(layer "F.SilkS")
		)
		(fp_line
			(start -0.7874 0.4064)
			(end -0.7874 -0.4064)
			(stroke
				(width 0.1524)
				(type default)
			)
			(layer "F.SilkS")
		)
		(fp_line
			(start -0.12065 -0.305054)
			(end -0.12065 -0.2794)
			(stroke
				(width 0.1)
				(type default)
			)
			(layer "F.Fab")
		)
		(fp_line
			(start -0.67945 -0.305054)
			(end -0.12065 -0.305054)
			(stroke
				(width 0.1)
				(type default)
			)
			(layer "F.Fab")
		)
		(fp_line
			(start 0.67945 -0.3048)
			(end 0.67945 0.3048)
			(stroke
				(width 0.1)
				(type default)
			)
			(layer "F.Fab")
		)
		(fp_line
			(start 0.12065 -0.3048)
			(end 0.67945 -0.3048)
			(stroke
				(width 0.1)
				(type default)
			)
			(layer "F.Fab")
		)
		(fp_line
			(start 0.12065 -0.2794)
			(end 0.12065 -0.3048)
			(stroke
				(width 0.1)
				(type default)
			)
			(layer "F.Fab")
		)
		(fp_line
			(start -0.12065 -0.2794)
			(end 0.12065 -0.2794)
			(stroke
				(width 0.1)
				(type default)
			)
			(layer "F.Fab")
		)
		(fp_line
			(start 0.120396 0.2794)
			(end -0.12065 0.2794)
			(stroke
				(width 0.1)
				(type default)
			)
			(layer "F.Fab")
		)
		(fp_line
			(start -0.12065 0.2794)
			(end -0.12065 0.3048)
			(stroke
				(width 0.1)
				(type default)
			)
			(layer "F.Fab")
		)
		(fp_line
			(start 0.67945 0.3048)
			(end 0.120396 0.3048)
			(stroke
				(width 0.1)
				(type default)
			)
			(layer "F.Fab")
		)
		(fp_line
			(start 0.120396 0.3048)
			(end 0.120396 0.2794)
			(stroke
				(width 0.1)
				(type default)
			)
			(layer "F.Fab")
		)
		(fp_line
			(start -0.12065 0.3048)
			(end -0.67945 0.3048)
			(stroke
				(width 0.1)
				(type default)
			)
			(layer "F.Fab")
		)
		(fp_line
			(start -0.67945 0.3048)
			(end -0.67945 -0.305054)
			(stroke
				(width 0.1)
				(type default)
			)
			(layer "F.Fab")
		)
		(pad "1" smd circle
			(at -0.40005 0 90)
			(size 0 0)
			(layers "F.Cu" "F.Mask" "F.Paste")
			(net "P3V3_SSD15_CO_DV_DT")
		)
		(pad "2" smd circle
			(at 0.40005 0 90)
			(size 0 0)
			(layers "F.Cu" "F.Mask" "F.Paste")
			(net "GND")
		)
	)
	(footprint ""
		(layer "F.Cu")
		(at 188.614558 -66.32194 90)
		(property "Reference" "R5980"
			(at 0 0 90)
			(layer "F.SilkS")
			(hide yes)
			(effects
				(font
					(size 1.27 1.27)
				)
			)
		)
		(property "Value" ""
			(at 0 0 90)
			(layer "F.Fab")
			(effects
				(font
					(size 1.27 1.27)
				)
			)
		)
		(duplicate_pad_numbers_are_jumpers no)
		(fp_line
			(start 0.7874 -0.4064)
			(end 0.7874 0.4064)
			(stroke
				(width 0.1524)
				(type default)
			)
			(layer "F.SilkS")
		)
		(fp_line
			(start -0.7874 -0.4064)
			(end 0.7874 -0.4064)
			(stroke
				(width 0.1524)
				(type default)
			)
			(layer "F.SilkS")
		)
		(fp_line
			(start 0.7874 0.4064)
			(end -0.7874 0.4064)
			(stroke
				(width 0.1524)
				(type default)
			)
			(layer "F.SilkS")
		)
		(fp_line
			(start -0.7874 0.4064)
			(end -0.7874 -0.4064)
			(stroke
				(width 0.1524)
				(type default)
			)
			(layer "F.SilkS")
		)
		(fp_line
			(start -0.12065 -0.305054)
			(end -0.12065 -0.2794)
			(stroke
				(width 0.1)
				(type default)
			)
			(layer "F.Fab")
		)
		(fp_line
			(start -0.67945 -0.305054)
			(end -0.12065 -0.305054)
			(stroke
				(width 0.1)
				(type default)
			)
			(layer "F.Fab")
		)
		(fp_line
			(start 0.67945 -0.3048)
			(end 0.67945 0.3048)
			(stroke
				(width 0.1)
				(type default)
			)
			(layer "F.Fab")
		)
		(fp_line
			(start 0.12065 -0.3048)
			(end 0.67945 -0.3048)
			(stroke
				(width 0.1)
				(type default)
			)
			(layer "F.Fab")
		)
		(fp_line
			(start 0.12065 -0.2794)
			(end 0.12065 -0.3048)
			(stroke
				(width 0.1)
				(type default)
			)
			(layer "F.Fab")
		)
		(fp_line
			(start -0.12065 -0.2794)
			(end 0.12065 -0.2794)
			(stroke
				(width 0.1)
				(type default)
			)
			(layer "F.Fab")
		)
		(fp_line
			(start 0.120396 0.2794)
			(end -0.12065 0.2794)
			(stroke
				(width 0.1)
				(type default)
			)
			(layer "F.Fab")
		)
		(fp_line
			(start -0.12065 0.2794)
			(end -0.12065 0.3048)
			(stroke
				(width 0.1)
				(type default)
			)
			(layer "F.Fab")
		)
		(fp_line
			(start 0.67945 0.3048)
			(end 0.120396 0.3048)
			(stroke
				(width 0.1)
				(type default)
			)
			(layer "F.Fab")
		)
		(fp_line
			(start 0.120396 0.3048)
			(end 0.120396 0.2794)
			(stroke
				(width 0.1)
				(type default)
			)
			(layer "F.Fab")
		)
		(fp_line
			(start -0.12065 0.3048)
			(end -0.67945 0.3048)
			(stroke
				(width 0.1)
				(type default)
			)
			(layer "F.Fab")
		)
		(fp_line
			(start -0.67945 0.3048)
			(end -0.67945 -0.305054)
			(stroke
				(width 0.1)
				(type default)
			)
			(layer "F.Fab")
		)
		(pad "1" smd circle
			(at -0.40005 0 90)
			(size 0 0)
			(layers "F.Cu" "F.Mask" "F.Paste")
			(net "SSD6_PWR_EN_R")
		)
		(pad "2" smd circle
			(at 0.40005 0 90)
			(size 0 0)
			(layers "F.Cu" "F.Mask" "F.Paste")
			(net "P12V_SSD6_CO_EN")
		)
	)
	(footprint ""
		(layer "F.Cu")
		(at 198.230236 -107.552998 -90)
		(property "Reference" "C890"
			(at 0 0 270)
			(layer "F.SilkS")
			(hide yes)
			(effects
				(font
					(size 1.27 1.27)
				)
			)
		)
		(property "Value" ""
			(at 0 0 270)
			(layer "F.Fab")
			(effects
				(font
					(size 1.27 1.27)
				)
			)
		)
		(duplicate_pad_numbers_are_jumpers no)
		(fp_line
			(start -1.524 0.762)
			(end -1.524 -0.762)
			(stroke
				(width 0.1524)
				(type default)
			)
			(layer "F.SilkS")
		)
		(fp_line
			(start 1.524 0.762)
			(end -1.524 0.762)
			(stroke
				(width 0.1524)
				(type default)
			)
			(layer "F.SilkS")
		)
		(fp_line
			(start -1.524 -0.762)
			(end 1.524 -0.762)
			(stroke
				(width 0.1524)
				(type default)
			)
			(layer "F.SilkS")
		)
		(fp_line
			(start 1.524 -0.762)
			(end 1.524 0.762)
			(stroke
				(width 0.1524)
				(type default)
			)
			(layer "F.SilkS")
		)
		(fp_line
			(start -1.1049 0.724916)
			(end 1.1049 0.724916)
			(stroke
				(width 0.1)
				(type default)
			)
			(layer "F.Fab")
		)
		(fp_line
			(start 1.1049 0.724916)
			(end 1.1049 -0.724916)
			(stroke
				(width 0.1)
				(type default)
			)
			(layer "F.Fab")
		)
		(fp_line
			(start -1.1049 -0.724916)
			(end -1.1049 0.724916)
			(stroke
				(width 0.1)
				(type default)
			)
			(layer "F.Fab")
		)
		(fp_line
			(start 1.1049 -0.724916)
			(end -1.1049 -0.724916)
			(stroke
				(width 0.1)
				(type default)
			)
			(layer "F.Fab")
		)
		(pad "1" smd rect
			(at -0.889 0 90)
			(size 1.016 1.27)
			(layers "F.Cu" "F.Mask" "F.Paste")
			(net "P12V_NIC3")
		)
		(pad "2" smd rect
			(at 0.889 0 90)
			(size 1.016 1.27)
			(layers "F.Cu" "F.Mask" "F.Paste")
			(net "GND")
		)
	)
	(footprint ""
		(layer "F.Cu")
		(at 373.362474 -22.955504 -90)
		(property "Reference" "C2731"
			(at 0 0 270)
			(layer "F.SilkS")
			(hide yes)
			(effects
				(font
					(size 1.27 1.27)
				)
			)
		)
		(property "Value" ""
			(at 0 0 270)
			(layer "F.Fab")
			(effects
				(font
					(size 1.27 1.27)
				)
			)
		)
		(duplicate_pad_numbers_are_jumpers no)
		(fp_line
			(start -0.7874 0.4064)
			(end -0.7874 -0.4064)
			(stroke
				(width 0.1524)
				(type default)
			)
			(layer "F.SilkS")
		)
		(fp_line
			(start 0.7874 0.4064)
			(end -0.7874 0.4064)
			(stroke
				(width 0.1524)
				(type default)
			)
			(layer "F.SilkS")
		)
		(fp_line
			(start -0.7874 -0.4064)
			(end 0.7874 -0.4064)
			(stroke
				(width 0.1524)
				(type default)
			)
			(layer "F.SilkS")
		)
		(fp_line
			(start 0.7874 -0.4064)
			(end 0.7874 0.4064)
			(stroke
				(width 0.1524)
				(type default)
			)
			(layer "F.SilkS")
		)
		(fp_line
			(start -0.67945 0.3048)
			(end -0.67945 -0.305054)
			(stroke
				(width 0.1)
				(type default)
			)
			(layer "F.Fab")
		)
		(fp_line
			(start -0.12065 0.3048)
			(end -0.67945 0.3048)
			(stroke
				(width 0.1)
				(type default)
			)
			(layer "F.Fab")
		)
		(fp_line
			(start 0.120396 0.3048)
			(end 0.120396 0.2794)
			(stroke
				(width 0.1)
				(type default)
			)
			(layer "F.Fab")
		)
		(fp_line
			(start 0.67945 0.3048)
			(end 0.120396 0.3048)
			(stroke
				(width 0.1)
				(type default)
			)
			(layer "F.Fab")
		)
		(fp_line
			(start -0.12065 0.2794)
			(end -0.12065 0.3048)
			(stroke
				(width 0.1)
				(type default)
			)
			(layer "F.Fab")
		)
		(fp_line
			(start 0.120396 0.2794)
			(end -0.12065 0.2794)
			(stroke
				(width 0.1)
				(type default)
			)
			(layer "F.Fab")
		)
		(fp_line
			(start -0.12065 -0.2794)
			(end 0.12065 -0.2794)
			(stroke
				(width 0.1)
				(type default)
			)
			(layer "F.Fab")
		)
		(fp_line
			(start 0.12065 -0.2794)
			(end 0.12065 -0.3048)
			(stroke
				(width 0.1)
				(type default)
			)
			(layer "F.Fab")
		)
		(fp_line
			(start 0.12065 -0.3048)
			(end 0.67945 -0.3048)
			(stroke
				(width 0.1)
				(type default)
			)
			(layer "F.Fab")
		)
		(fp_line
			(start 0.67945 -0.3048)
			(end 0.67945 0.3048)
			(stroke
				(width 0.1)
				(type default)
			)
			(layer "F.Fab")
		)
		(fp_line
			(start -0.67945 -0.305054)
			(end -0.12065 -0.305054)
			(stroke
				(width 0.1)
				(type default)
			)
			(layer "F.Fab")
		)
		(fp_line
			(start -0.12065 -0.305054)
			(end -0.12065 -0.2794)
			(stroke
				(width 0.1)
				(type default)
			)
			(layer "F.Fab")
		)
		(pad "1" smd circle
			(at -0.40005 0 270)
			(size 0 0)
			(layers "F.Cu" "F.Mask" "F.Paste")
			(net "GND")
		)
		(pad "2" smd circle
			(at 0.40005 0 270)
			(size 0 0)
			(layers "F.Cu" "F.Mask" "F.Paste")
			(net "P3V3_AUX")
		)
	)
	(footprint ""
		(layer "F.Cu")
		(at 140.074142 -183.009286 180)
		(property "Reference" "R1108"
			(at 0 0 180)
			(layer "F.SilkS")
			(hide yes)
			(effects
				(font
					(size 1.27 1.27)
				)
			)
		)
		(property "Value" ""
			(at 0 0 180)
			(layer "F.Fab")
			(effects
				(font
					(size 1.27 1.27)
				)
			)
		)
		(duplicate_pad_numbers_are_jumpers no)
		(fp_line
			(start 0.7874 0.4064)
			(end -0.7874 0.4064)
			(stroke
				(width 0.1524)
				(type default)
			)
			(layer "F.SilkS")
		)
		(fp_line
			(start 0.67945 0.3048)
			(end 0.120396 0.3048)
			(stroke
				(width 0.1)
				(type default)
			)
			(layer "F.Fab")
		)
		(fp_line
			(start 0.67945 -0.3048)
			(end 0.67945 0.3048)
			(stroke
				(width 0.1)
				(type default)
			)
			(layer "F.Fab")
		)
		(fp_line
			(start 0.12065 -0.2794)
			(end 0.12065 -0.3048)
			(stroke
				(width 0.1)
				(type default)
			)
			(layer "F.Fab")
		)
		(fp_line
			(start 0.12065 -0.3048)
			(end 0.67945 -0.3048)
			(stroke
				(width 0.1)
				(type default)
			)
			(layer "F.Fab")
		)
		(fp_line
			(start 0.120396 0.3048)
			(end 0.120396 0.2794)
			(stroke
				(width 0.1)
				(type default)
			)
			(layer "F.Fab")
		)
		(fp_line
			(start 0.120396 0.2794)
			(end -0.12065 0.2794)
			(stroke
				(width 0.1)
				(type default)
			)
			(layer "F.Fab")
		)
		(fp_line
			(start -0.12065 0.3048)
			(end -0.67945 0.3048)
			(stroke
				(width 0.1)
				(type default)
			)
			(layer "F.Fab")
		)
		(fp_line
			(start -0.12065 0.2794)
			(end -0.12065 0.3048)
			(stroke
				(width 0.1)
				(type default)
			)
			(layer "F.Fab")
		)
		(fp_line
			(start -0.12065 -0.2794)
			(end 0.12065 -0.2794)
			(stroke
				(width 0.1)
				(type default)
			)
			(layer "F.Fab")
		)
		(fp_line
			(start -0.12065 -0.305054)
			(end -0.12065 -0.2794)
			(stroke
				(width 0.1)
				(type default)
			)
			(layer "F.Fab")
		)
		(fp_line
			(start -0.67945 0.3048)
			(end -0.67945 -0.305054)
			(stroke
				(width 0.1)
				(type default)
			)
			(layer "F.Fab")
		)
		(fp_line
			(start -0.67945 -0.305054)
			(end -0.12065 -0.305054)
			(stroke
				(width 0.1)
				(type default)
			)
			(layer "F.Fab")
		)
		(pad "1" smd circle
			(at -0.40005 0 180)
			(size 0 0)
			(layers "F.Cu" "F.Mask" "F.Paste")
			(net "CLK_100M_DB2000QL_NIC6_R_DN")
		)
		(pad "2" smd circle
			(at 0.40005 0 180)
			(size 0 0)
			(layers "F.Cu" "F.Mask" "F.Paste")
			(net "CLK_100M_DB2000QL_NIC6_DN")
		)
	)
	(footprint ""
		(layer "F.Cu")
		(at 381.254 -199.39)
		(property "Reference" "R4671"
			(at 0 0 0)
			(layer "F.SilkS")
			(hide yes)
			(effects
				(font
					(size 1.27 1.27)
				)
			)
		)
		(property "Value" ""
			(at 0 0 0)
			(layer "F.Fab")
			(effects
				(font
					(size 1.27 1.27)
				)
			)
		)
		(duplicate_pad_numbers_are_jumpers no)
		(fp_line
			(start -0.7874 -0.4064)
			(end 0.7874 -0.4064)
			(stroke
				(width 0.1524)
				(type default)
			)
			(layer "F.SilkS")
		)
		(fp_line
			(start -0.7874 0.4064)
			(end -0.7874 -0.4064)
			(stroke
				(width 0.1524)
				(type default)
			)
			(layer "F.SilkS")
		)
		(fp_line
			(start 0.7874 -0.4064)
			(end 0.7874 0.4064)
			(stroke
				(width 0.1524)
				(type default)
			)
			(layer "F.SilkS")
		)
		(fp_line
			(start 0.7874 0.4064)
			(end -0.7874 0.4064)
			(stroke
				(width 0.1524)
				(type default)
			)
			(layer "F.SilkS")
		)
		(fp_line
			(start -0.67945 -0.305054)
			(end -0.12065 -0.305054)
			(stroke
				(width 0.1)
				(type default)
			)
			(layer "F.Fab")
		)
		(fp_line
			(start -0.67945 0.3048)
			(end -0.67945 -0.305054)
			(stroke
				(width 0.1)
				(type default)
			)
			(layer "F.Fab")
		)
		(fp_line
			(start -0.12065 -0.305054)
			(end -0.12065 -0.2794)
			(stroke
				(width 0.1)
				(type default)
			)
			(layer "F.Fab")
		)
		(fp_line
			(start -0.12065 -0.2794)
			(end 0.12065 -0.2794)
			(stroke
				(width 0.1)
				(type default)
			)
			(layer "F.Fab")
		)
		(fp_line
			(start -0.12065 0.2794)
			(end -0.12065 0.3048)
			(stroke
				(width 0.1)
				(type default)
			)
			(layer "F.Fab")
		)
		(fp_line
			(start -0.12065 0.3048)
			(end -0.67945 0.3048)
			(stroke
				(width 0.1)
				(type default)
			)
			(layer "F.Fab")
		)
		(fp_line
			(start 0.120396 0.2794)
			(end -0.12065 0.2794)
			(stroke
				(width 0.1)
				(type default)
			)
			(layer "F.Fab")
		)
		(fp_line
			(start 0.120396 0.3048)
			(end 0.120396 0.2794)
			(stroke
				(width 0.1)
				(type default)
			)
			(layer "F.Fab")
		)
		(fp_line
			(start 0.12065 -0.3048)
			(end 0.67945 -0.3048)
			(stroke
				(width 0.1)
				(type default)
			)
			(layer "F.Fab")
		)
		(fp_line
			(start 0.12065 -0.2794)
			(end 0.12065 -0.3048)
			(stroke
				(width 0.1)
				(type default)
			)
			(layer "F.Fab")
		)
		(fp_line
			(start 0.67945 -0.3048)
			(end 0.67945 0.3048)
			(stroke
				(width 0.1)
				(type default)
			)
			(layer "F.Fab")
		)
		(fp_line
			(start 0.67945 0.3048)
			(end 0.120396 0.3048)
			(stroke
				(width 0.1)
				(type default)
			)
			(layer "F.Fab")
		)
		(pad "1" smd circle
			(at -0.40005 0)
			(size 0 0)
			(layers "F.Cu" "F.Mask" "F.Paste")
			(net "P3V3_AUX")
		)
		(pad "2" smd circle
			(at 0.40005 0)
			(size 0 0)
			(layers "F.Cu" "F.Mask" "F.Paste")
			(net "RST_PEX_NIC2_PERST_R_N")
		)
	)
	(footprint ""
		(layer "F.Cu")
		(at 198.40194 -404.113238 -90)
		(property "Reference" "R5714"
			(at 0 0 270)
			(layer "F.SilkS")
			(hide yes)
			(effects
				(font
					(size 1.27 1.27)
				)
			)
		)
		(property "Value" ""
			(at 0 0 270)
			(layer "F.Fab")
			(effects
				(font
					(size 1.27 1.27)
				)
			)
		)
		(duplicate_pad_numbers_are_jumpers no)
		(fp_line
			(start -0.7874 0.4064)
			(end -0.7874 -0.4064)
			(stroke
				(width 0.1524)
				(type default)
			)
			(layer "F.SilkS")
		)
		(fp_line
			(start 0.7874 0.4064)
			(end -0.7874 0.4064)
			(stroke
				(width 0.1524)
				(type default)
			)
			(layer "F.SilkS")
		)
		(fp_line
			(start -0.7874 -0.4064)
			(end 0.7874 -0.4064)
			(stroke
				(width 0.1524)
				(type default)
			)
			(layer "F.SilkS")
		)
		(fp_line
			(start 0.7874 -0.4064)
			(end 0.7874 0.4064)
			(stroke
				(width 0.1524)
				(type default)
			)
			(layer "F.SilkS")
		)
		(fp_line
			(start -0.67945 0.3048)
			(end -0.67945 -0.305054)
			(stroke
				(width 0.1)
				(type default)
			)
			(layer "F.Fab")
		)
		(fp_line
			(start -0.12065 0.3048)
			(end -0.67945 0.3048)
			(stroke
				(width 0.1)
				(type default)
			)
			(layer "F.Fab")
		)
		(fp_line
			(start 0.120396 0.3048)
			(end 0.120396 0.2794)
			(stroke
				(width 0.1)
				(type default)
			)
			(layer "F.Fab")
		)
		(fp_line
			(start 0.67945 0.3048)
			(end 0.120396 0.3048)
			(stroke
				(width 0.1)
				(type default)
			)
			(layer "F.Fab")
		)
		(fp_line
			(start -0.12065 0.2794)
			(end -0.12065 0.3048)
			(stroke
				(width 0.1)
				(type default)
			)
			(layer "F.Fab")
		)
		(fp_line
			(start 0.120396 0.2794)
			(end -0.12065 0.2794)
			(stroke
				(width 0.1)
				(type default)
			)
			(layer "F.Fab")
		)
		(fp_line
			(start -0.12065 -0.2794)
			(end 0.12065 -0.2794)
			(stroke
				(width 0.1)
				(type default)
			)
			(layer "F.Fab")
		)
		(fp_line
			(start 0.12065 -0.2794)
			(end 0.12065 -0.3048)
			(stroke
				(width 0.1)
				(type default)
			)
			(layer "F.Fab")
		)
		(fp_line
			(start 0.12065 -0.3048)
			(end 0.67945 -0.3048)
			(stroke
				(width 0.1)
				(type default)
			)
			(layer "F.Fab")
		)
		(fp_line
			(start 0.67945 -0.3048)
			(end 0.67945 0.3048)
			(stroke
				(width 0.1)
				(type default)
			)
			(layer "F.Fab")
		)
		(fp_line
			(start -0.67945 -0.305054)
			(end -0.12065 -0.305054)
			(stroke
				(width 0.1)
				(type default)
			)
			(layer "F.Fab")
		)
		(fp_line
			(start -0.12065 -0.305054)
			(end -0.12065 -0.2794)
			(stroke
				(width 0.1)
				(type default)
			)
			(layer "F.Fab")
		)
		(pad "1" smd circle
			(at -0.40005 0 270)
			(size 0 0)
			(layers "F.Cu" "F.Mask" "F.Paste")
			(net "MB_HSC_ISO_D2_EN")
		)
		(pad "2" smd circle
			(at 0.40005 0 270)
			(size 0 0)
			(layers "F.Cu" "F.Mask" "F.Paste")
			(net "HSC_P12V_EN")
		)
	)
	(footprint ""
		(layer "F.Cu")
		(at 235.623608 -142.640812 180)
		(property "Reference" "R4208"
			(at 0 0 180)
			(layer "F.SilkS")
			(hide yes)
			(effects
				(font
					(size 1.27 1.27)
				)
			)
		)
		(property "Value" ""
			(at 0 0 180)
			(layer "F.Fab")
			(effects
				(font
					(size 1.27 1.27)
				)
			)
		)
		(duplicate_pad_numbers_are_jumpers no)
		(fp_line
			(start 0.7874 0.4064)
			(end -0.7874 0.4064)
			(stroke
				(width 0.1524)
				(type default)
			)
			(layer "F.SilkS")
		)
		(fp_line
			(start 0.7874 -0.4064)
			(end 0.7874 0.4064)
			(stroke
				(width 0.1524)
				(type default)
			)
			(layer "F.SilkS")
		)
		(fp_line
			(start -0.7874 0.4064)
			(end -0.7874 -0.4064)
			(stroke
				(width 0.1524)
				(type default)
			)
			(layer "F.SilkS")
		)
		(fp_line
			(start -0.7874 -0.4064)
			(end 0.7874 -0.4064)
			(stroke
				(width 0.1524)
				(type default)
			)
			(layer "F.SilkS")
		)
		(fp_line
			(start 0.67945 0.3048)
			(end 0.120396 0.3048)
			(stroke
				(width 0.1)
				(type default)
			)
			(layer "F.Fab")
		)
		(fp_line
			(start 0.67945 -0.3048)
			(end 0.67945 0.3048)
			(stroke
				(width 0.1)
				(type default)
			)
			(layer "F.Fab")
		)
		(fp_line
			(start 0.12065 -0.2794)
			(end 0.12065 -0.3048)
			(stroke
				(width 0.1)
				(type default)
			)
			(layer "F.Fab")
		)
		(fp_line
			(start 0.12065 -0.3048)
			(end 0.67945 -0.3048)
			(stroke
				(width 0.1)
				(type default)
			)
			(layer "F.Fab")
		)
		(fp_line
			(start 0.120396 0.3048)
			(end 0.120396 0.2794)
			(stroke
				(width 0.1)
				(type default)
			)
			(layer "F.Fab")
		)
		(fp_line
			(start 0.120396 0.2794)
			(end -0.12065 0.2794)
			(stroke
				(width 0.1)
				(type default)
			)
			(layer "F.Fab")
		)
		(fp_line
			(start -0.12065 0.3048)
			(end -0.67945 0.3048)
			(stroke
				(width 0.1)
				(type default)
			)
			(layer "F.Fab")
		)
		(fp_line
			(start -0.12065 0.2794)
			(end -0.12065 0.3048)
			(stroke
				(width 0.1)
				(type default)
			)
			(layer "F.Fab")
		)
		(fp_line
			(start -0.12065 -0.2794)
			(end 0.12065 -0.2794)
			(stroke
				(width 0.1)
				(type default)
			)
			(layer "F.Fab")
		)
		(fp_line
			(start -0.12065 -0.305054)
			(end -0.12065 -0.2794)
			(stroke
				(width 0.1)
				(type default)
			)
			(layer "F.Fab")
		)
		(fp_line
			(start -0.67945 0.3048)
			(end -0.67945 -0.305054)
			(stroke
				(width 0.1)
				(type default)
			)
			(layer "F.Fab")
		)
		(fp_line
			(start -0.67945 -0.305054)
			(end -0.12065 -0.305054)
			(stroke
				(width 0.1)
				(type default)
			)
			(layer "F.Fab")
		)
		(pad "1" smd circle
			(at -0.40005 0 180)
			(size 0 0)
			(layers "F.Cu" "F.Mask" "F.Paste")
			(net "GND")
		)
		(pad "2" smd circle
			(at 0.40005 0 180)
			(size 0 0)
			(layers "F.Cu" "F.Mask" "F.Paste")
			(net "CK440_PEX_SS_EN")
		)
	)
	(footprint ""
		(layer "F.Cu")
		(at 95.105728 -239.728248)
		(property "Reference" "R819"
			(at 0 0 0)
			(layer "F.SilkS")
			(hide yes)
			(effects
				(font
					(size 1.27 1.27)
				)
			)
		)
		(property "Value" ""
			(at 0 0 0)
			(layer "F.Fab")
			(effects
				(font
					(size 1.27 1.27)
				)
			)
		)
		(duplicate_pad_numbers_are_jumpers no)
		(fp_line
			(start -0.7874 -0.4064)
			(end 0.7874 -0.4064)
			(stroke
				(width 0.1524)
				(type default)
			)
			(layer "F.SilkS")
		)
		(fp_line
			(start -0.7874 0.4064)
			(end -0.7874 -0.4064)
			(stroke
				(width 0.1524)
				(type default)
			)
			(layer "F.SilkS")
		)
		(fp_line
			(start 0.7874 -0.4064)
			(end 0.7874 0.4064)
			(stroke
				(width 0.1524)
				(type default)
			)
			(layer "F.SilkS")
		)
		(fp_line
			(start 0.7874 0.4064)
			(end -0.7874 0.4064)
			(stroke
				(width 0.1524)
				(type default)
			)
			(layer "F.SilkS")
		)
		(fp_line
			(start -0.67945 -0.305054)
			(end -0.12065 -0.305054)
			(stroke
				(width 0.1)
				(type default)
			)
			(layer "F.Fab")
		)
		(fp_line
			(start -0.67945 0.3048)
			(end -0.67945 -0.305054)
			(stroke
				(width 0.1)
				(type default)
			)
			(layer "F.Fab")
		)
		(fp_line
			(start -0.12065 -0.305054)
			(end -0.12065 -0.2794)
			(stroke
				(width 0.1)
				(type default)
			)
			(layer "F.Fab")
		)
		(fp_line
			(start -0.12065 -0.2794)
			(end 0.12065 -0.2794)
			(stroke
				(width 0.1)
				(type default)
			)
			(layer "F.Fab")
		)
		(fp_line
			(start -0.12065 0.2794)
			(end -0.12065 0.3048)
			(stroke
				(width 0.1)
				(type default)
			)
			(layer "F.Fab")
		)
		(fp_line
			(start -0.12065 0.3048)
			(end -0.67945 0.3048)
			(stroke
				(width 0.1)
				(type default)
			)
			(layer "F.Fab")
		)
		(fp_line
			(start 0.120396 0.2794)
			(end -0.12065 0.2794)
			(stroke
				(width 0.1)
				(type default)
			)
			(layer "F.Fab")
		)
		(fp_line
			(start 0.120396 0.3048)
			(end 0.120396 0.2794)
			(stroke
				(width 0.1)
				(type default)
			)
			(layer "F.Fab")
		)
		(fp_line
			(start 0.12065 -0.3048)
			(end 0.67945 -0.3048)
			(stroke
				(width 0.1)
				(type default)
			)
			(layer "F.Fab")
		)
		(fp_line
			(start 0.12065 -0.2794)
			(end 0.12065 -0.3048)
			(stroke
				(width 0.1)
				(type default)
			)
			(layer "F.Fab")
		)
		(fp_line
			(start 0.67945 -0.3048)
			(end 0.67945 0.3048)
			(stroke
				(width 0.1)
				(type default)
			)
			(layer "F.Fab")
		)
		(fp_line
			(start 0.67945 0.3048)
			(end 0.120396 0.3048)
			(stroke
				(width 0.1)
				(type default)
			)
			(layer "F.Fab")
		)
		(pad "1" smd circle
			(at -0.40005 0)
			(size 0 0)
			(layers "F.Cu" "F.Mask" "F.Paste")
			(net "SMB_BIC_I2C6_MUX_PEX_ADC_R_SCL")
		)
		(pad "2" smd circle
			(at 0.40005 0)
			(size 0 0)
			(layers "F.Cu" "F.Mask" "F.Paste")
			(net "SMB_PEX_P1V8_ADC_SCL")
		)
	)
	(footprint ""
		(layer "F.Cu")
		(at 28.875228 -64.102234 180)
		(property "Reference" "PR6908"
			(at 0 0 180)
			(layer "F.SilkS")
			(hide yes)
			(effects
				(font
					(size 1.27 1.27)
				)
			)
		)
		(property "Value" ""
			(at 0 0 180)
			(layer "F.Fab")
			(effects
				(font
					(size 1.27 1.27)
				)
			)
		)
		(duplicate_pad_numbers_are_jumpers no)
		(fp_line
			(start 0.7874 0.4064)
			(end -0.7874 0.4064)
			(stroke
				(width 0.1524)
				(type default)
			)
			(layer "F.SilkS")
		)
		(fp_line
			(start 0.7874 -0.4064)
			(end 0.7874 0.4064)
			(stroke
				(width 0.1524)
				(type default)
			)
			(layer "F.SilkS")
		)
		(fp_line
			(start -0.7874 0.4064)
			(end -0.7874 -0.4064)
			(stroke
				(width 0.1524)
				(type default)
			)
			(layer "F.SilkS")
		)
		(fp_line
			(start -0.7874 -0.4064)
			(end 0.7874 -0.4064)
			(stroke
				(width 0.1524)
				(type default)
			)
			(layer "F.SilkS")
		)
		(fp_line
			(start 0.67945 0.3048)
			(end 0.120396 0.3048)
			(stroke
				(width 0.1)
				(type default)
			)
			(layer "F.Fab")
		)
		(fp_line
			(start 0.67945 -0.3048)
			(end 0.67945 0.3048)
			(stroke
				(width 0.1)
				(type default)
			)
			(layer "F.Fab")
		)
		(fp_line
			(start 0.12065 -0.2794)
			(end 0.12065 -0.3048)
			(stroke
				(width 0.1)
				(type default)
			)
			(layer "F.Fab")
		)
		(fp_line
			(start 0.12065 -0.3048)
			(end 0.67945 -0.3048)
			(stroke
				(width 0.1)
				(type default)
			)
			(layer "F.Fab")
		)
		(fp_line
			(start 0.120396 0.3048)
			(end 0.120396 0.2794)
			(stroke
				(width 0.1)
				(type default)
			)
			(layer "F.Fab")
		)
		(fp_line
			(start 0.120396 0.2794)
			(end -0.12065 0.2794)
			(stroke
				(width 0.1)
				(type default)
			)
			(layer "F.Fab")
		)
		(fp_line
			(start -0.12065 0.3048)
			(end -0.67945 0.3048)
			(stroke
				(width 0.1)
				(type default)
			)
			(layer "F.Fab")
		)
		(fp_line
			(start -0.12065 0.2794)
			(end -0.12065 0.3048)
			(stroke
				(width 0.1)
				(type default)
			)
			(layer "F.Fab")
		)
		(fp_line
			(start -0.12065 -0.2794)
			(end 0.12065 -0.2794)
			(stroke
				(width 0.1)
				(type default)
			)
			(layer "F.Fab")
		)
		(fp_line
			(start -0.12065 -0.305054)
			(end -0.12065 -0.2794)
			(stroke
				(width 0.1)
				(type default)
			)
			(layer "F.Fab")
		)
		(fp_line
			(start -0.67945 0.3048)
			(end -0.67945 -0.305054)
			(stroke
				(width 0.1)
				(type default)
			)
			(layer "F.Fab")
		)
		(fp_line
			(start -0.67945 -0.305054)
			(end -0.12065 -0.305054)
			(stroke
				(width 0.1)
				(type default)
			)
			(layer "F.Fab")
		)
		(pad "1" smd circle
			(at -0.40005 0 180)
			(size 0 0)
			(layers "F.Cu" "F.Mask" "F.Paste")
			(net "P12V_SSD1_PG_G1")
		)
		(pad "2" smd circle
			(at 0.40005 0 180)
			(size 0 0)
			(layers "F.Cu" "F.Mask" "F.Paste")
			(net "GND")
		)
	)
	(footprint ""
		(layer "F.Cu")
		(at 12.04595 -316.361826 -90)
		(property "Reference" "PL17"
			(at -0.509016 -1.910334 90)
			(unlocked yes)
			(layer "F.SilkS")
			(effects
				(font
					(size 0.7874 0.5842)
					(thickness 0.1524)
				)
			)
		)
		(property "Value" ""
			(at 0 0 270)
			(layer "F.Fab")
			(effects
				(font
					(size 1.27 1.27)
				)
			)
		)
		(duplicate_pad_numbers_are_jumpers no)
		(fp_line
			(start -1.27 0.5842)
			(end -1.27 -0.5842)
			(stroke
				(width 0.1524)
				(type default)
			)
			(layer "F.SilkS")
		)
		(fp_line
			(start 1.27 0.5842)
			(end -1.27 0.5842)
			(stroke
				(width 0.1524)
				(type default)
			)
			(layer "F.SilkS")
		)
		(fp_line
			(start 1.27 0.5842)
			(end 1.27 -0.5842)
			(stroke
				(width 0.1524)
				(type default)
			)
			(layer "F.SilkS")
		)
		(fp_line
			(start -1.27 -0.5588)
			(end -1.27 -0.5842)
			(stroke
				(width 0.1524)
				(type default)
			)
			(layer "F.SilkS")
		)
		(fp_line
			(start -1.27 -0.5842)
			(end 1.27 -0.5842)
			(stroke
				(width 0.1524)
				(type default)
			)
			(layer "F.SilkS")
		)
		(fp_line
			(start -0.9144 0.508)
			(end -0.9144 0.406654)
			(stroke
				(width 0.1)
				(type default)
			)
			(layer "F.Fab")
		)
		(fp_line
			(start 0.9144 0.508)
			(end -0.9144 0.508)
			(stroke
				(width 0.1)
				(type default)
			)
			(layer "F.Fab")
		)
		(fp_line
			(start -1.194308 0.406654)
			(end -1.194308 -0.406654)
			(stroke
				(width 0.1)
				(type default)
			)
			(layer "F.Fab")
		)
		(fp_line
			(start -0.9144 0.406654)
			(end -1.194308 0.406654)
			(stroke
				(width 0.1)
				(type default)
			)
			(layer "F.Fab")
		)
		(fp_line
			(start 0.9144 0.4064)
			(end 0.9144 0.508)
			(stroke
				(width 0.1)
				(type default)
			)
			(layer "F.Fab")
		)
		(fp_line
			(start 1.1938 0.4064)
			(end 0.9144 0.4064)
			(stroke
				(width 0.1)
				(type default)
			)
			(layer "F.Fab")
		)
		(fp_line
			(start -1.194308 -0.406654)
			(end -0.9144 -0.406654)
			(stroke
				(width 0.1)
				(type default)
			)
			(layer "F.Fab")
		)
		(fp_line
			(start -0.9144 -0.406654)
			(end -0.9144 -0.508)
			(stroke
				(width 0.1)
				(type default)
			)
			(layer "F.Fab")
		)
		(fp_line
			(start 0.9144 -0.406654)
			(end 1.1938 -0.406654)
			(stroke
				(width 0.1)
				(type default)
			)
			(layer "F.Fab")
		)
		(fp_line
			(start 1.1938 -0.406654)
			(end 1.1938 0.4064)
			(stroke
				(width 0.1)
				(type default)
			)
			(layer "F.Fab")
		)
		(fp_line
			(start -0.9144 -0.508)
			(end 0.9144 -0.508)
			(stroke
				(width 0.1)
				(type default)
			)
			(layer "F.Fab")
		)
		(fp_line
			(start 0.9144 -0.508)
			(end 0.9144 -0.406654)
			(stroke
				(width 0.1)
				(type default)
			)
			(layer "F.Fab")
		)
		(pad "1" smd rect
			(at -0.7366 0 180)
			(size 0.7112 0.8128)
			(layers "F.Cu" "F.Mask" "F.Paste")
			(net "P12V_AUX")
		)
		(pad "2" smd rect
			(at 0.7366 0 180)
			(size 0.7112 0.8128)
			(layers "F.Cu" "F.Mask" "F.Paste")
			(net "SW_P12V_P1V25_PEX0_FLT")
		)
	)
	(footprint ""
		(layer "F.Cu")
		(at 1.650746 -34.890456 -90)
		(property "Reference" "C2711"
			(at 0 0 270)
			(layer "F.SilkS")
			(hide yes)
			(effects
				(font
					(size 1.27 1.27)
				)
			)
		)
		(property "Value" ""
			(at 0 0 270)
			(layer "F.Fab")
			(effects
				(font
					(size 1.27 1.27)
				)
			)
		)
		(duplicate_pad_numbers_are_jumpers no)
		(fp_line
			(start -0.7874 0.4064)
			(end -0.7874 -0.4064)
			(stroke
				(width 0.1524)
				(type default)
			)
			(layer "F.SilkS")
		)
		(fp_line
			(start 0.7874 0.4064)
			(end -0.7874 0.4064)
			(stroke
				(width 0.1524)
				(type default)
			)
			(layer "F.SilkS")
		)
		(fp_line
			(start -0.7874 -0.4064)
			(end 0.7874 -0.4064)
			(stroke
				(width 0.1524)
				(type default)
			)
			(layer "F.SilkS")
		)
		(fp_line
			(start 0.7874 -0.4064)
			(end 0.7874 0.4064)
			(stroke
				(width 0.1524)
				(type default)
			)
			(layer "F.SilkS")
		)
		(fp_line
			(start -0.67945 0.3048)
			(end -0.67945 -0.305054)
			(stroke
				(width 0.1)
				(type default)
			)
			(layer "F.Fab")
		)
		(fp_line
			(start -0.12065 0.3048)
			(end -0.67945 0.3048)
			(stroke
				(width 0.1)
				(type default)
			)
			(layer "F.Fab")
		)
		(fp_line
			(start 0.120396 0.3048)
			(end 0.120396 0.2794)
			(stroke
				(width 0.1)
				(type default)
			)
			(layer "F.Fab")
		)
		(fp_line
			(start 0.67945 0.3048)
			(end 0.120396 0.3048)
			(stroke
				(width 0.1)
				(type default)
			)
			(layer "F.Fab")
		)
		(fp_line
			(start -0.12065 0.2794)
			(end -0.12065 0.3048)
			(stroke
				(width 0.1)
				(type default)
			)
			(layer "F.Fab")
		)
		(fp_line
			(start 0.120396 0.2794)
			(end -0.12065 0.2794)
			(stroke
				(width 0.1)
				(type default)
			)
			(layer "F.Fab")
		)
		(fp_line
			(start -0.12065 -0.2794)
			(end 0.12065 -0.2794)
			(stroke
				(width 0.1)
				(type default)
			)
			(layer "F.Fab")
		)
		(fp_line
			(start 0.12065 -0.2794)
			(end 0.12065 -0.3048)
			(stroke
				(width 0.1)
				(type default)
			)
			(layer "F.Fab")
		)
		(fp_line
			(start 0.12065 -0.3048)
			(end 0.67945 -0.3048)
			(stroke
				(width 0.1)
				(type default)
			)
			(layer "F.Fab")
		)
		(fp_line
			(start 0.67945 -0.3048)
			(end 0.67945 0.3048)
			(stroke
				(width 0.1)
				(type default)
			)
			(layer "F.Fab")
		)
		(fp_line
			(start -0.67945 -0.305054)
			(end -0.12065 -0.305054)
			(stroke
				(width 0.1)
				(type default)
			)
			(layer "F.Fab")
		)
		(fp_line
			(start -0.12065 -0.305054)
			(end -0.12065 -0.2794)
			(stroke
				(width 0.1)
				(type default)
			)
			(layer "F.Fab")
		)
		(pad "1" smd circle
			(at -0.40005 0 270)
			(size 0 0)
			(layers "F.Cu" "F.Mask" "F.Paste")
			(net "GND")
		)
		(pad "2" smd circle
			(at 0.40005 0 270)
			(size 0 0)
			(layers "F.Cu" "F.Mask" "F.Paste")
			(net "P3V3_AUX")
		)
	)
	(footprint ""
		(layer "F.Cu")
		(at 207.270858 -220.79077 90)
		(property "Reference" "R5473"
			(at 0 0 90)
			(layer "F.SilkS")
			(hide yes)
			(effects
				(font
					(size 1.27 1.27)
				)
			)
		)
		(property "Value" ""
			(at 0 0 90)
			(layer "F.Fab")
			(effects
				(font
					(size 1.27 1.27)
				)
			)
		)
		(duplicate_pad_numbers_are_jumpers no)
		(fp_line
			(start 0.7874 -0.4064)
			(end 0.7874 0.4064)
			(stroke
				(width 0.1524)
				(type default)
			)
			(layer "F.SilkS")
		)
		(fp_line
			(start -0.7874 -0.4064)
			(end 0.7874 -0.4064)
			(stroke
				(width 0.1524)
				(type default)
			)
			(layer "F.SilkS")
		)
		(fp_line
			(start 0.7874 0.4064)
			(end -0.7874 0.4064)
			(stroke
				(width 0.1524)
				(type default)
			)
			(layer "F.SilkS")
		)
		(fp_line
			(start -0.7874 0.4064)
			(end -0.7874 -0.4064)
			(stroke
				(width 0.1524)
				(type default)
			)
			(layer "F.SilkS")
		)
		(fp_line
			(start -0.12065 -0.305054)
			(end -0.12065 -0.2794)
			(stroke
				(width 0.1)
				(type default)
			)
			(layer "F.Fab")
		)
		(fp_line
			(start -0.67945 -0.305054)
			(end -0.12065 -0.305054)
			(stroke
				(width 0.1)
				(type default)
			)
			(layer "F.Fab")
		)
		(fp_line
			(start 0.67945 -0.3048)
			(end 0.67945 0.3048)
			(stroke
				(width 0.1)
				(type default)
			)
			(layer "F.Fab")
		)
		(fp_line
			(start 0.12065 -0.3048)
			(end 0.67945 -0.3048)
			(stroke
				(width 0.1)
				(type default)
			)
			(layer "F.Fab")
		)
		(fp_line
			(start 0.12065 -0.2794)
			(end 0.12065 -0.3048)
			(stroke
				(width 0.1)
				(type default)
			)
			(layer "F.Fab")
		)
		(fp_line
			(start -0.12065 -0.2794)
			(end 0.12065 -0.2794)
			(stroke
				(width 0.1)
				(type default)
			)
			(layer "F.Fab")
		)
		(fp_line
			(start 0.120396 0.2794)
			(end -0.12065 0.2794)
			(stroke
				(width 0.1)
				(type default)
			)
			(layer "F.Fab")
		)
		(fp_line
			(start -0.12065 0.2794)
			(end -0.12065 0.3048)
			(stroke
				(width 0.1)
				(type default)
			)
			(layer "F.Fab")
		)
		(fp_line
			(start 0.67945 0.3048)
			(end 0.120396 0.3048)
			(stroke
				(width 0.1)
				(type default)
			)
			(layer "F.Fab")
		)
		(fp_line
			(start 0.120396 0.3048)
			(end 0.120396 0.2794)
			(stroke
				(width 0.1)
				(type default)
			)
			(layer "F.Fab")
		)
		(fp_line
			(start -0.12065 0.3048)
			(end -0.67945 0.3048)
			(stroke
				(width 0.1)
				(type default)
			)
			(layer "F.Fab")
		)
		(fp_line
			(start -0.67945 0.3048)
			(end -0.67945 -0.305054)
			(stroke
				(width 0.1)
				(type default)
			)
			(layer "F.Fab")
		)
		(pad "1" smd circle
			(at -0.40005 0 90)
			(size 0 0)
			(layers "F.Cu" "F.Mask" "F.Paste")
			(net "UART_MB_BIC_RX_BUF_R")
		)
		(pad "2" smd circle
			(at 0.40005 0 90)
			(size 0 0)
			(layers "F.Cu" "F.Mask" "F.Paste")
			(net "UART_MB_BIC_RX_BUF")
		)
	)
	(footprint ""
		(layer "F.Cu")
		(at 350.380554 -89.502234)
		(property "Reference" "R1591"
			(at 0 0 0)
			(layer "F.SilkS")
			(hide yes)
			(effects
				(font
					(size 1.27 1.27)
				)
			)
		)
		(property "Value" ""
			(at 0 0 0)
			(layer "F.Fab")
			(effects
				(font
					(size 1.27 1.27)
				)
			)
		)
		(duplicate_pad_numbers_are_jumpers no)
		(fp_line
			(start -0.7874 -0.4064)
			(end 0.7874 -0.4064)
			(stroke
				(width 0.1524)
				(type default)
			)
			(layer "F.SilkS")
		)
		(fp_line
			(start -0.7874 0.4064)
			(end -0.7874 -0.4064)
			(stroke
				(width 0.1524)
				(type default)
			)
			(layer "F.SilkS")
		)
		(fp_line
			(start 0.7874 -0.4064)
			(end 0.7874 0.4064)
			(stroke
				(width 0.1524)
				(type default)
			)
			(layer "F.SilkS")
		)
		(fp_line
			(start 0.7874 0.4064)
			(end -0.7874 0.4064)
			(stroke
				(width 0.1524)
				(type default)
			)
			(layer "F.SilkS")
		)
		(fp_line
			(start -0.67945 -0.305054)
			(end -0.12065 -0.305054)
			(stroke
				(width 0.1)
				(type default)
			)
			(layer "F.Fab")
		)
		(fp_line
			(start -0.67945 0.3048)
			(end -0.67945 -0.305054)
			(stroke
				(width 0.1)
				(type default)
			)
			(layer "F.Fab")
		)
		(fp_line
			(start -0.12065 -0.305054)
			(end -0.12065 -0.2794)
			(stroke
				(width 0.1)
				(type default)
			)
			(layer "F.Fab")
		)
		(fp_line
			(start -0.12065 -0.2794)
			(end 0.12065 -0.2794)
			(stroke
				(width 0.1)
				(type default)
			)
			(layer "F.Fab")
		)
		(fp_line
			(start -0.12065 0.2794)
			(end -0.12065 0.3048)
			(stroke
				(width 0.1)
				(type default)
			)
			(layer "F.Fab")
		)
		(fp_line
			(start -0.12065 0.3048)
			(end -0.67945 0.3048)
			(stroke
				(width 0.1)
				(type default)
			)
			(layer "F.Fab")
		)
		(fp_line
			(start 0.120396 0.2794)
			(end -0.12065 0.2794)
			(stroke
				(width 0.1)
				(type default)
			)
			(layer "F.Fab")
		)
		(fp_line
			(start 0.120396 0.3048)
			(end 0.120396 0.2794)
			(stroke
				(width 0.1)
				(type default)
			)
			(layer "F.Fab")
		)
		(fp_line
			(start 0.12065 -0.3048)
			(end 0.67945 -0.3048)
			(stroke
				(width 0.1)
				(type default)
			)
			(layer "F.Fab")
		)
		(fp_line
			(start 0.12065 -0.2794)
			(end 0.12065 -0.3048)
			(stroke
				(width 0.1)
				(type default)
			)
			(layer "F.Fab")
		)
		(fp_line
			(start 0.67945 -0.3048)
			(end 0.67945 0.3048)
			(stroke
				(width 0.1)
				(type default)
			)
			(layer "F.Fab")
		)
		(fp_line
			(start 0.67945 0.3048)
			(end 0.120396 0.3048)
			(stroke
				(width 0.1)
				(type default)
			)
			(layer "F.Fab")
		)
		(pad "1" smd circle
			(at -0.40005 0)
			(size 0 0)
			(layers "F.Cu" "F.Mask" "F.Paste")
			(net "P3V3_AUX")
		)
		(pad "2" smd circle
			(at 0.40005 0)
			(size 0 0)
			(layers "F.Cu" "F.Mask" "F.Paste")
			(net "SMB_BIC_I2C9_MUX1_SSD8_R_SDA")
		)
	)
	(footprint ""
		(layer "F.Cu")
		(at 323.511926 -100.20935 90)
		(property "Reference" "U84"
			(at 0.42545 2.371344 90)
			(unlocked yes)
			(layer "F.SilkS")
			(effects
				(font
					(size 0.7874 0.5842)
					(thickness 0.1524)
				)
			)
		)
		(property "Value" ""
			(at 0 0 90)
			(layer "F.Fab")
			(effects
				(font
					(size 1.27 1.27)
				)
			)
		)
		(duplicate_pad_numbers_are_jumpers no)
		(fp_line
			(start 1.500124 -1.500124)
			(end 1.500124 -1.004062)
			(stroke
				(width 0.1524)
				(type default)
			)
			(layer "F.SilkS")
		)
		(fp_line
			(start 1.004062 -1.500124)
			(end 1.500124 -1.500124)
			(stroke
				(width 0.1524)
				(type default)
			)
			(layer "F.SilkS")
		)
		(fp_line
			(start -1.500124 -1.500124)
			(end -1.004062 -1.500124)
			(stroke
				(width 0.1524)
				(type default)
			)
			(layer "F.SilkS")
		)
		(fp_line
			(start -1.500124 -1.004062)
			(end -1.500124 -1.500124)
			(stroke
				(width 0.1524)
				(type default)
			)
			(layer "F.SilkS")
		)
		(fp_line
			(start 1.500124 1.004062)
			(end 1.500124 1.500124)
			(stroke
				(width 0.1524)
				(type default)
			)
			(layer "F.SilkS")
		)
		(fp_line
			(start 1.500124 1.500124)
			(end 1.004062 1.500124)
			(stroke
				(width 0.1524)
				(type default)
			)
			(layer "F.SilkS")
		)
		(fp_line
			(start -1.004062 1.500124)
			(end -1.500124 1.500124)
			(stroke
				(width 0.1524)
				(type default)
			)
			(layer "F.SilkS")
		)
		(fp_line
			(start -1.500124 1.500124)
			(end -1.500124 1.004062)
			(stroke
				(width 0.1524)
				(type default)
			)
			(layer "F.SilkS")
		)
		(fp_poly
			(pts
				(xy -1.968246 -2.281936) (xy -2.686812 -1.563624) (xy -1.60909 -1.204468)
			)
			(stroke
				(width 0)
				(type default)
			)
			(fill yes)
			(layer "F.SilkS")
		)
		(fp_line
			(start 1.500124 -1.500124)
			(end 1.500124 1.500124)
			(stroke
				(width 0.1)
				(type default)
			)
			(layer "F.Fab")
		)
		(fp_line
			(start -1.500124 -1.500124)
			(end 1.500124 -1.500124)
			(stroke
				(width 0.1)
				(type default)
			)
			(layer "F.Fab")
		)
		(fp_line
			(start 1.500124 1.500124)
			(end -1.500124 1.500124)
			(stroke
				(width 0.1)
				(type default)
			)
			(layer "F.Fab")
		)
		(fp_line
			(start -1.500124 1.500124)
			(end -1.500124 -1.500124)
			(stroke
				(width 0.1)
				(type default)
			)
			(layer "F.Fab")
		)
		(fp_poly
			(pts
				(xy -2.847848 -1.258062) (xy -2.847848 -0.242062) (xy -1.831848 -0.750062)
			)
			(stroke
				(width 0)
				(type default)
			)
			(fill yes)
			(layer "F.Fab")
		)
		(pad "1" smd rect
			(at -1.400048 -0.750062)
			(size 0.2286 0.6096)
			(layers "F.Cu" "F.Mask" "F.Paste")
			(net "NIC5_ADC_A1")
		)
		(pad "2" smd rect
			(at -1.400048 -0.249936)
			(size 0.2286 0.6096)
			(layers "F.Cu" "F.Mask" "F.Paste")
			(net "NIC5_ADC_A0")
		)
		(pad "3" smd rect
			(at -1.400048 0.249936)
			(size 0.2286 0.6096)
			(layers "F.Cu" "F.Mask" "F.Paste")
			(net "NIC5_ADC_ALERT_N")
		)
		(pad "4" smd rect
			(at -1.400048 0.750062)
			(size 0.2286 0.6096)
			(layers "F.Cu" "F.Mask" "F.Paste")
			(net "SMB_NIC5_ADC_SDA")
		)
		(pad "5" smd rect
			(at -0.750062 1.400048 90)
			(size 0.2286 0.6096)
			(layers "F.Cu" "F.Mask" "F.Paste")
			(net "SMB_NIC5_ADC_SCL")
		)
		(pad "6" smd rect
			(at -0.249936 1.400048 90)
			(size 0.2286 0.6096)
			(layers "F.Cu" "F.Mask" "F.Paste")
			(net "Net_8636")
		)
		(pad "7" smd rect
			(at 0.249936 1.400048 90)
			(size 0.2286 0.6096)
			(layers "F.Cu" "F.Mask" "F.Paste")
			(net "Net_8635")
		)
		(pad "8" smd rect
			(at 0.750062 1.400048 90)
			(size 0.2286 0.6096)
			(layers "F.Cu" "F.Mask" "F.Paste")
			(net "Net_8634")
		)
		(pad "9" smd rect
			(at 1.400048 0.750062)
			(size 0.2286 0.6096)
			(layers "F.Cu" "F.Mask" "F.Paste")
			(net "P3V3_AUX")
		)
		(pad "10" smd rect
			(at 1.400048 0.249936)
			(size 0.2286 0.6096)
			(layers "F.Cu" "F.Mask" "F.Paste")
			(net "GND")
		)
		(pad "11" smd rect
			(at 1.400048 -0.249936)
			(size 0.2286 0.6096)
			(layers "F.Cu" "F.Mask" "F.Paste")
			(net "P12V_NIC5_R")
		)
		(pad "12" smd rect
			(at 1.400048 -0.750062)
			(size 0.2286 0.6096)
			(layers "F.Cu" "F.Mask" "F.Paste")
			(net "P12V_NIC5_VIN_N")
		)
		(pad "13" smd rect
			(at 0.750062 -1.400048 90)
			(size 0.2286 0.6096)
			(layers "F.Cu" "F.Mask" "F.Paste")
			(net "P12V_NIC5_VIN_P")
		)
		(pad "14" smd rect
			(at 0.249936 -1.400048 90)
			(size 0.2286 0.6096)
			(layers "F.Cu" "F.Mask" "F.Paste")
			(net "Net_8633")
		)
		(pad "15" smd rect
			(at -0.249936 -1.400048 90)
			(size 0.2286 0.6096)
			(layers "F.Cu" "F.Mask" "F.Paste")
			(net "Net_8632")
		)
		(pad "16" smd rect
			(at -0.750062 -1.400048 90)
			(size 0.2286 0.6096)
			(layers "F.Cu" "F.Mask" "F.Paste")
			(net "Net_8631")
		)
		(pad "TH" smd rect
			(at 0 0 90)
			(size 1.7018 1.7018)
			(layers "F.Cu" "F.Mask" "F.Paste")
			(net "GND")
		)
		(zone
			(layer "F.Cu")
			(hatch none 0.5)
			(connect_pads
				(clearance 0)
			)
			(min_thickness 0.25)
			(keepout
				(tracks not_allowed)
				(vias allowed)
				(pads allowed)
				(copperpour not_allowed)
				(footprints allowed)
			)
			(placement
				(enabled no)
				(sheetname "")
			)
			(fill
				(thermal_gap 0.5)
				(thermal_bridge_width 0.5)
				(island_removal_mode 0)
			)
			(polygon
				(pts
					(xy 323.486526 -99.164902) (xy 322.467478 -99.164902) (xy 322.467478 -101.253798) (xy 324.556374 -101.253798)
					(xy 324.556374 -99.164902) (xy 323.511926 -99.164902) (xy 323.511926 -99.30765) (xy 324.413626 -99.30765)
					(xy 324.413626 -101.11105) (xy 322.610226 -101.11105) (xy 322.610226 -99.30765) (xy 323.486526 -99.30765)
				)
			)
		)
	)
	(footprint ""
		(layer "F.Cu")
		(at 436.795926 -310.509412 135)
		(property "Reference" "R1441"
			(at 0 0 135)
			(layer "F.SilkS")
			(hide yes)
			(effects
				(font
					(size 1.27 1.27)
				)
			)
		)
		(property "Value" ""
			(at 0 0 135)
			(layer "F.Fab")
			(effects
				(font
					(size 1.27 1.27)
				)
			)
		)
		(duplicate_pad_numbers_are_jumpers no)
		(fp_line
			(start 0.787389 -0.406267)
			(end 0.787389 0.406267)
			(stroke
				(width 0.1524)
				(type default)
			)
			(layer "F.SilkS")
		)
		(fp_line
			(start 0.787389 0.406267)
			(end -0.787389 0.406267)
			(stroke
				(width 0.1524)
				(type default)
			)
			(layer "F.SilkS")
		)
		(fp_line
			(start -0.787389 -0.406267)
			(end 0.787389 -0.406267)
			(stroke
				(width 0.1524)
				(type default)
			)
			(layer "F.SilkS")
		)
		(fp_line
			(start -0.787389 0.406267)
			(end -0.787389 -0.406267)
			(stroke
				(width 0.1524)
				(type default)
			)
			(layer "F.SilkS")
		)
		(fp_line
			(start 0.679446 -0.30479)
			(end 0.679446 0.30479)
			(stroke
				(width 0.1)
				(type default)
			)
			(layer "F.Fab")
		)
		(fp_line
			(start 0.120515 -0.30479)
			(end 0.679446 -0.30479)
			(stroke
				(width 0.1)
				(type default)
			)
			(layer "F.Fab")
		)
		(fp_line
			(start 0.120695 -0.279466)
			(end 0.120515 -0.30479)
			(stroke
				(width 0.1)
				(type default)
			)
			(layer "F.Fab")
		)
		(fp_line
			(start 0.679446 0.30479)
			(end 0.120515 0.30479)
			(stroke
				(width 0.1)
				(type default)
			)
			(layer "F.Fab")
		)
		(fp_line
			(start -0.120695 -0.304969)
			(end -0.120695 -0.279466)
			(stroke
				(width 0.1)
				(type default)
			)
			(layer "F.Fab")
		)
		(fp_line
			(start -0.120695 -0.279466)
			(end 0.120695 -0.279466)
			(stroke
				(width 0.1)
				(type default)
			)
			(layer "F.Fab")
		)
		(fp_line
			(start 0.120335 0.279466)
			(end -0.120695 0.279466)
			(stroke
				(width 0.1)
				(type default)
			)
			(layer "F.Fab")
		)
		(fp_line
			(start 0.120515 0.30479)
			(end 0.120335 0.279466)
			(stroke
				(width 0.1)
				(type default)
			)
			(layer "F.Fab")
		)
		(fp_line
			(start -0.679446 -0.305149)
			(end -0.120695 -0.304969)
			(stroke
				(width 0.1)
				(type default)
			)
			(layer "F.Fab")
		)
		(fp_line
			(start -0.120695 0.279466)
			(end -0.120515 0.30479)
			(stroke
				(width 0.1)
				(type default)
			)
			(layer "F.Fab")
		)
		(fp_line
			(start -0.120515 0.30479)
			(end -0.679446 0.30479)
			(stroke
				(width 0.1)
				(type default)
			)
			(layer "F.Fab")
		)
		(fp_line
			(start -0.679446 0.30479)
			(end -0.679446 -0.305149)
			(stroke
				(width 0.1)
				(type default)
			)
			(layer "F.Fab")
		)
		(pad "1" smd circle
			(at -0.40005 0 135)
			(size 0 0)
			(layers "F.Cu" "F.Mask" "F.Paste")
			(net "PEX3_SPARE2")
		)
		(pad "2" smd circle
			(at 0.40005 0 135)
			(size 0 0)
			(layers "F.Cu" "F.Mask" "F.Paste")
			(net "P1V8_PEX")
		)
	)
	(footprint ""
		(layer "F.Cu")
		(at 157.242764 -70.844918 -90)
		(property "Reference" "PD103"
			(at 3.890518 2.098294 90)
			(unlocked yes)
			(layer "F.SilkS")
			(effects
				(font
					(size 0.7874 0.5842)
					(thickness 0.1524)
				)
				(justify left)
			)
		)
		(property "Value" ""
			(at 0 0 270)
			(layer "F.Fab")
			(effects
				(font
					(size 1.27 1.27)
				)
			)
		)
		(duplicate_pad_numbers_are_jumpers no)
		(fp_line
			(start -3.400044 1.459992)
			(end -3.400044 -1.459992)
			(stroke
				(width 0.1524)
				(type default)
			)
			(layer "F.SilkS")
		)
		(fp_line
			(start 4.107942 1.459992)
			(end -3.400044 1.459992)
			(stroke
				(width 0.1524)
				(type default)
			)
			(layer "F.SilkS")
		)
		(fp_line
			(start -3.400044 -1.459992)
			(end 4.107942 -1.459992)
			(stroke
				(width 0.1524)
				(type default)
			)
			(layer "F.SilkS")
		)
		(fp_line
			(start 4.107942 -1.459992)
			(end 4.107942 1.459992)
			(stroke
				(width 0.1524)
				(type default)
			)
			(layer "F.SilkS")
		)
		(fp_poly
			(pts
				(xy 4.107942 -1.459992) (xy 4.107942 1.459992) (xy 3.308096 1.459992) (xy 3.308096 -1.459992)
			)
			(stroke
				(width 0)
				(type default)
			)
			(fill yes)
			(layer "F.SilkS")
		)
		(fp_line
			(start -2.29997 1.459992)
			(end -2.29997 -1.459992)
			(stroke
				(width 0.1)
				(type default)
			)
			(layer "F.Fab")
		)
		(fp_line
			(start 2.29997 1.459992)
			(end -2.29997 1.459992)
			(stroke
				(width 0.1)
				(type default)
			)
			(layer "F.Fab")
		)
		(fp_line
			(start -2.29997 -1.459992)
			(end 2.29997 -1.459992)
			(stroke
				(width 0.1)
				(type default)
			)
			(layer "F.Fab")
		)
		(fp_line
			(start 2.29997 -1.459992)
			(end 2.29997 1.459992)
			(stroke
				(width 0.1)
				(type default)
			)
			(layer "F.Fab")
		)
		(fp_text user "-"
			(at 5.4102 0.29845 90)
			(unlocked yes)
			(layer "F.SilkS")
			(effects
				(font
					(size 1.905 1.4224)
					(thickness 0.1524)
				)
				(justify left)
			)
		)
		(fp_text user "+"
			(at -4.838954 -1.230884 270)
			(unlocked yes)
			(layer "F.SilkS")
			(effects
				(font
					(size 1.905 1.4224)
					(thickness 0.1524)
				)
				(justify left)
			)
		)
		(fp_text user "-"
			(at 5.4102 0.29845 90)
			(unlocked yes)
			(layer "F.Fab")
			(effects
				(font
					(size 1.905 1.4224)
					(thickness 0.1524)
				)
				(justify left)
			)
		)
		(fp_text user "+"
			(at -4.7752 -0.12065 270)
			(unlocked yes)
			(layer "F.Fab")
			(effects
				(font
					(size 1.905 1.4224)
					(thickness 0.1524)
				)
				(justify left)
			)
		)
		(pad "A" smd rect
			(at -1.999996 0)
			(size 1.7018 2.5146)
			(layers "F.Cu" "F.Mask" "F.Paste")
			(net "GND")
		)
		(pad "C" smd rect
			(at 1.999996 0)
			(size 1.7018 2.5146)
			(layers "F.Cu" "F.Mask" "F.Paste")
			(net "P12V_SSD5_R")
		)
	)
	(footprint ""
		(layer "F.Cu")
		(at 314.861448 -152.511252 180)
		(property "Reference" "C427"
			(at 0 0 180)
			(layer "F.SilkS")
			(hide yes)
			(effects
				(font
					(size 1.27 1.27)
				)
			)
		)
		(property "Value" ""
			(at 0 0 180)
			(layer "F.Fab")
			(effects
				(font
					(size 1.27 1.27)
				)
			)
		)
		(duplicate_pad_numbers_are_jumpers no)
		(fp_line
			(start 0.299974 0.150114)
			(end -0.299974 0.150114)
			(stroke
				(width 0.1)
				(type default)
			)
			(layer "F.Fab")
		)
		(fp_line
			(start 0.299974 -0.150114)
			(end 0.299974 0.150114)
			(stroke
				(width 0.1)
				(type default)
			)
			(layer "F.Fab")
		)
		(fp_line
			(start -0.299974 0.150114)
			(end -0.299974 -0.150114)
			(stroke
				(width 0.1)
				(type default)
			)
			(layer "F.Fab")
		)
		(fp_line
			(start -0.299974 -0.150114)
			(end 0.299974 -0.150114)
			(stroke
				(width 0.1)
				(type default)
			)
			(layer "F.Fab")
		)
		(pad "1" smd rect
			(at -0.2667 0 180)
			(size 0.3048 0.381)
			(layers "F.Cu" "F.Mask" "F.Paste")
			(net "P5E_PEX2_STN0_TX_DP<13>")
		)
		(pad "2" smd rect
			(at 0.2667 0 180)
			(size 0.3048 0.381)
			(layers "F.Cu" "F.Mask" "F.Paste")
			(net "P5E_PEX2_STN0_TX_C_DP<13>")
		)
	)
	(footprint ""
		(layer "F.Cu")
		(at 369.495578 -82.641694 180)
		(property "Reference" "R1603"
			(at 0 0 180)
			(layer "F.SilkS")
			(hide yes)
			(effects
				(font
					(size 1.27 1.27)
				)
			)
		)
		(property "Value" ""
			(at 0 0 180)
			(layer "F.Fab")
			(effects
				(font
					(size 1.27 1.27)
				)
			)
		)
		(duplicate_pad_numbers_are_jumpers no)
		(fp_line
			(start 0.7874 0.4064)
			(end -0.7874 0.4064)
			(stroke
				(width 0.1524)
				(type default)
			)
			(layer "F.SilkS")
		)
		(fp_line
			(start 0.7874 -0.4064)
			(end 0.7874 0.4064)
			(stroke
				(width 0.1524)
				(type default)
			)
			(layer "F.SilkS")
		)
		(fp_line
			(start -0.7874 0.4064)
			(end -0.7874 -0.4064)
			(stroke
				(width 0.1524)
				(type default)
			)
			(layer "F.SilkS")
		)
		(fp_line
			(start -0.7874 -0.4064)
			(end 0.7874 -0.4064)
			(stroke
				(width 0.1524)
				(type default)
			)
			(layer "F.SilkS")
		)
		(fp_line
			(start 0.67945 0.3048)
			(end 0.120396 0.3048)
			(stroke
				(width 0.1)
				(type default)
			)
			(layer "F.Fab")
		)
		(fp_line
			(start 0.67945 -0.3048)
			(end 0.67945 0.3048)
			(stroke
				(width 0.1)
				(type default)
			)
			(layer "F.Fab")
		)
		(fp_line
			(start 0.12065 -0.2794)
			(end 0.12065 -0.3048)
			(stroke
				(width 0.1)
				(type default)
			)
			(layer "F.Fab")
		)
		(fp_line
			(start 0.12065 -0.3048)
			(end 0.67945 -0.3048)
			(stroke
				(width 0.1)
				(type default)
			)
			(layer "F.Fab")
		)
		(fp_line
			(start 0.120396 0.3048)
			(end 0.120396 0.2794)
			(stroke
				(width 0.1)
				(type default)
			)
			(layer "F.Fab")
		)
		(fp_line
			(start 0.120396 0.2794)
			(end -0.12065 0.2794)
			(stroke
				(width 0.1)
				(type default)
			)
			(layer "F.Fab")
		)
		(fp_line
			(start -0.12065 0.3048)
			(end -0.67945 0.3048)
			(stroke
				(width 0.1)
				(type default)
			)
			(layer "F.Fab")
		)
		(fp_line
			(start -0.12065 0.2794)
			(end -0.12065 0.3048)
			(stroke
				(width 0.1)
				(type default)
			)
			(layer "F.Fab")
		)
		(fp_line
			(start -0.12065 -0.2794)
			(end 0.12065 -0.2794)
			(stroke
				(width 0.1)
				(type default)
			)
			(layer "F.Fab")
		)
		(fp_line
			(start -0.12065 -0.305054)
			(end -0.12065 -0.2794)
			(stroke
				(width 0.1)
				(type default)
			)
			(layer "F.Fab")
		)
		(fp_line
			(start -0.67945 0.3048)
			(end -0.67945 -0.305054)
			(stroke
				(width 0.1)
				(type default)
			)
			(layer "F.Fab")
		)
		(fp_line
			(start -0.67945 -0.305054)
			(end -0.12065 -0.305054)
			(stroke
				(width 0.1)
				(type default)
			)
			(layer "F.Fab")
		)
		(pad "1" smd circle
			(at -0.40005 0 180)
			(size 0 0)
			(layers "F.Cu" "F.Mask" "F.Paste")
			(net "P3V3_AUX")
		)
		(pad "2" smd circle
			(at 0.40005 0 180)
			(size 0 0)
			(layers "F.Cu" "F.Mask" "F.Paste")
			(net "SMB_BIC_I2C9_MUX1_SSD12_R_SCL")
		)
	)
	(footprint ""
		(layer "F.Cu")
		(at 358.013 -210.312 180)
		(property "Reference" "R4097"
			(at 0 0 180)
			(layer "F.SilkS")
			(hide yes)
			(effects
				(font
					(size 1.27 1.27)
				)
			)
		)
		(property "Value" ""
			(at 0 0 180)
			(layer "F.Fab")
			(effects
				(font
					(size 1.27 1.27)
				)
			)
		)
		(duplicate_pad_numbers_are_jumpers no)
		(fp_line
			(start 0.7874 0.4064)
			(end -0.7874 0.4064)
			(stroke
				(width 0.1524)
				(type default)
			)
			(layer "F.SilkS")
		)
		(fp_line
			(start 0.7874 -0.4064)
			(end 0.7874 0.4064)
			(stroke
				(width 0.1524)
				(type default)
			)
			(layer "F.SilkS")
		)
		(fp_line
			(start -0.7874 0.4064)
			(end -0.7874 -0.4064)
			(stroke
				(width 0.1524)
				(type default)
			)
			(layer "F.SilkS")
		)
		(fp_line
			(start -0.7874 -0.4064)
			(end 0.7874 -0.4064)
			(stroke
				(width 0.1524)
				(type default)
			)
			(layer "F.SilkS")
		)
		(fp_line
			(start 0.67945 0.3048)
			(end 0.120396 0.3048)
			(stroke
				(width 0.1)
				(type default)
			)
			(layer "F.Fab")
		)
		(fp_line
			(start 0.67945 -0.3048)
			(end 0.67945 0.3048)
			(stroke
				(width 0.1)
				(type default)
			)
			(layer "F.Fab")
		)
		(fp_line
			(start 0.12065 -0.2794)
			(end 0.12065 -0.3048)
			(stroke
				(width 0.1)
				(type default)
			)
			(layer "F.Fab")
		)
		(fp_line
			(start 0.12065 -0.3048)
			(end 0.67945 -0.3048)
			(stroke
				(width 0.1)
				(type default)
			)
			(layer "F.Fab")
		)
		(fp_line
			(start 0.120396 0.3048)
			(end 0.120396 0.2794)
			(stroke
				(width 0.1)
				(type default)
			)
			(layer "F.Fab")
		)
		(fp_line
			(start 0.120396 0.2794)
			(end -0.12065 0.2794)
			(stroke
				(width 0.1)
				(type default)
			)
			(layer "F.Fab")
		)
		(fp_line
			(start -0.12065 0.3048)
			(end -0.67945 0.3048)
			(stroke
				(width 0.1)
				(type default)
			)
			(layer "F.Fab")
		)
		(fp_line
			(start -0.12065 0.2794)
			(end -0.12065 0.3048)
			(stroke
				(width 0.1)
				(type default)
			)
			(layer "F.Fab")
		)
		(fp_line
			(start -0.12065 -0.2794)
			(end 0.12065 -0.2794)
			(stroke
				(width 0.1)
				(type default)
			)
			(layer "F.Fab")
		)
		(fp_line
			(start -0.12065 -0.305054)
			(end -0.12065 -0.2794)
			(stroke
				(width 0.1)
				(type default)
			)
			(layer "F.Fab")
		)
		(fp_line
			(start -0.67945 0.3048)
			(end -0.67945 -0.305054)
			(stroke
				(width 0.1)
				(type default)
			)
			(layer "F.Fab")
		)
		(fp_line
			(start -0.67945 -0.305054)
			(end -0.12065 -0.305054)
			(stroke
				(width 0.1)
				(type default)
			)
			(layer "F.Fab")
		)
		(pad "1" smd circle
			(at -0.40005 0 180)
			(size 0 0)
			(layers "F.Cu" "F.Mask" "F.Paste")
			(net "PRSNT_NIC5_FPGA_R_N")
		)
		(pad "2" smd circle
			(at 0.40005 0 180)
			(size 0 0)
			(layers "F.Cu" "F.Mask" "F.Paste")
			(net "PRSNT_NIC5_FPGA_N")
		)
	)
	(footprint ""
		(layer "F.Cu")
		(at 424.78198 -38.041072 180)
		(property "Reference" "R6121"
			(at 0 0 180)
			(layer "F.SilkS")
			(hide yes)
			(effects
				(font
					(size 1.27 1.27)
				)
			)
		)
		(property "Value" ""
			(at 0 0 180)
			(layer "F.Fab")
			(effects
				(font
					(size 1.27 1.27)
				)
			)
		)
		(duplicate_pad_numbers_are_jumpers no)
		(fp_line
			(start 0.7874 0.4064)
			(end -0.7874 0.4064)
			(stroke
				(width 0.1524)
				(type default)
			)
			(layer "F.SilkS")
		)
		(fp_line
			(start 0.7874 -0.4064)
			(end 0.7874 0.4064)
			(stroke
				(width 0.1524)
				(type default)
			)
			(layer "F.SilkS")
		)
		(fp_line
			(start -0.7874 0.4064)
			(end -0.7874 -0.4064)
			(stroke
				(width 0.1524)
				(type default)
			)
			(layer "F.SilkS")
		)
		(fp_line
			(start -0.7874 -0.4064)
			(end 0.7874 -0.4064)
			(stroke
				(width 0.1524)
				(type default)
			)
			(layer "F.SilkS")
		)
		(fp_line
			(start 0.67945 0.3048)
			(end 0.120396 0.3048)
			(stroke
				(width 0.1)
				(type default)
			)
			(layer "F.Fab")
		)
		(fp_line
			(start 0.67945 -0.3048)
			(end 0.67945 0.3048)
			(stroke
				(width 0.1)
				(type default)
			)
			(layer "F.Fab")
		)
		(fp_line
			(start 0.12065 -0.2794)
			(end 0.12065 -0.3048)
			(stroke
				(width 0.1)
				(type default)
			)
			(layer "F.Fab")
		)
		(fp_line
			(start 0.12065 -0.3048)
			(end 0.67945 -0.3048)
			(stroke
				(width 0.1)
				(type default)
			)
			(layer "F.Fab")
		)
		(fp_line
			(start 0.120396 0.3048)
			(end 0.120396 0.2794)
			(stroke
				(width 0.1)
				(type default)
			)
			(layer "F.Fab")
		)
		(fp_line
			(start 0.120396 0.2794)
			(end -0.12065 0.2794)
			(stroke
				(width 0.1)
				(type default)
			)
			(layer "F.Fab")
		)
		(fp_line
			(start -0.12065 0.3048)
			(end -0.67945 0.3048)
			(stroke
				(width 0.1)
				(type default)
			)
			(layer "F.Fab")
		)
		(fp_line
			(start -0.12065 0.2794)
			(end -0.12065 0.3048)
			(stroke
				(width 0.1)
				(type default)
			)
			(layer "F.Fab")
		)
		(fp_line
			(start -0.12065 -0.2794)
			(end 0.12065 -0.2794)
			(stroke
				(width 0.1)
				(type default)
			)
			(layer "F.Fab")
		)
		(fp_line
			(start -0.12065 -0.305054)
			(end -0.12065 -0.2794)
			(stroke
				(width 0.1)
				(type default)
			)
			(layer "F.Fab")
		)
		(fp_line
			(start -0.67945 0.3048)
			(end -0.67945 -0.305054)
			(stroke
				(width 0.1)
				(type default)
			)
			(layer "F.Fab")
		)
		(fp_line
			(start -0.67945 -0.305054)
			(end -0.12065 -0.305054)
			(stroke
				(width 0.1)
				(type default)
			)
			(layer "F.Fab")
		)
		(pad "1" smd circle
			(at -0.40005 0 180)
			(size 0 0)
			(layers "F.Cu" "F.Mask" "F.Paste")
			(net "P5V_AUX")
		)
		(pad "2" smd circle
			(at 0.40005 0 180)
			(size 0 0)
			(layers "F.Cu" "F.Mask" "F.Paste")
			(net "P3V3_SSD15_PG_G2")
		)
	)
	(footprint ""
		(layer "F.Cu")
		(at 86.218522 -350.098614 90)
		(property "Reference" "C103"
			(at 0 0 90)
			(layer "F.SilkS")
			(hide yes)
			(effects
				(font
					(size 1.27 1.27)
				)
			)
		)
		(property "Value" ""
			(at 0 0 90)
			(layer "F.Fab")
			(effects
				(font
					(size 1.27 1.27)
				)
			)
		)
		(duplicate_pad_numbers_are_jumpers no)
		(fp_line
			(start 0.299974 -0.150114)
			(end 0.299974 0.150114)
			(stroke
				(width 0.1)
				(type default)
			)
			(layer "F.Fab")
		)
		(fp_line
			(start -0.299974 -0.150114)
			(end 0.299974 -0.150114)
			(stroke
				(width 0.1)
				(type default)
			)
			(layer "F.Fab")
		)
		(fp_line
			(start 0.299974 0.150114)
			(end -0.299974 0.150114)
			(stroke
				(width 0.1)
				(type default)
			)
			(layer "F.Fab")
		)
		(fp_line
			(start -0.299974 0.150114)
			(end -0.299974 -0.150114)
			(stroke
				(width 0.1)
				(type default)
			)
			(layer "F.Fab")
		)
		(pad "1" smd rect
			(at -0.2667 0 90)
			(size 0.3048 0.381)
			(layers "F.Cu" "F.Mask" "F.Paste")
			(net "P5E_PEX0_STN5_TX_DP<92>")
		)
		(pad "2" smd rect
			(at 0.2667 0 90)
			(size 0.3048 0.381)
			(layers "F.Cu" "F.Mask" "F.Paste")
			(net "P5E_PEX0_STN5_TX_C_DP<92>")
		)
	)
	(footprint ""
		(layer "F.Cu")
		(at 87.749634 -300.60265 90)
		(property "Reference" "R6387"
			(at 0 0 90)
			(layer "F.SilkS")
			(hide yes)
			(effects
				(font
					(size 1.27 1.27)
				)
			)
		)
		(property "Value" ""
			(at 0 0 90)
			(layer "F.Fab")
			(effects
				(font
					(size 1.27 1.27)
				)
			)
		)
		(duplicate_pad_numbers_are_jumpers no)
		(fp_line
			(start 0.7874 -0.4064)
			(end 0.7874 0.4064)
			(stroke
				(width 0.1524)
				(type default)
			)
			(layer "F.SilkS")
		)
		(fp_line
			(start -0.7874 -0.4064)
			(end 0.7874 -0.4064)
			(stroke
				(width 0.1524)
				(type default)
			)
			(layer "F.SilkS")
		)
		(fp_line
			(start 0.7874 0.4064)
			(end -0.7874 0.4064)
			(stroke
				(width 0.1524)
				(type default)
			)
			(layer "F.SilkS")
		)
		(fp_line
			(start -0.7874 0.4064)
			(end -0.7874 -0.4064)
			(stroke
				(width 0.1524)
				(type default)
			)
			(layer "F.SilkS")
		)
		(fp_line
			(start -0.12065 -0.305054)
			(end -0.12065 -0.2794)
			(stroke
				(width 0.1)
				(type default)
			)
			(layer "F.Fab")
		)
		(fp_line
			(start -0.67945 -0.305054)
			(end -0.12065 -0.305054)
			(stroke
				(width 0.1)
				(type default)
			)
			(layer "F.Fab")
		)
		(fp_line
			(start 0.67945 -0.3048)
			(end 0.67945 0.3048)
			(stroke
				(width 0.1)
				(type default)
			)
			(layer "F.Fab")
		)
		(fp_line
			(start 0.12065 -0.3048)
			(end 0.67945 -0.3048)
			(stroke
				(width 0.1)
				(type default)
			)
			(layer "F.Fab")
		)
		(fp_line
			(start 0.12065 -0.2794)
			(end 0.12065 -0.3048)
			(stroke
				(width 0.1)
				(type default)
			)
			(layer "F.Fab")
		)
		(fp_line
			(start -0.12065 -0.2794)
			(end 0.12065 -0.2794)
			(stroke
				(width 0.1)
				(type default)
			)
			(layer "F.Fab")
		)
		(fp_line
			(start 0.120396 0.2794)
			(end -0.12065 0.2794)
			(stroke
				(width 0.1)
				(type default)
			)
			(layer "F.Fab")
		)
		(fp_line
			(start -0.12065 0.2794)
			(end -0.12065 0.3048)
			(stroke
				(width 0.1)
				(type default)
			)
			(layer "F.Fab")
		)
		(fp_line
			(start 0.67945 0.3048)
			(end 0.120396 0.3048)
			(stroke
				(width 0.1)
				(type default)
			)
			(layer "F.Fab")
		)
		(fp_line
			(start 0.120396 0.3048)
			(end 0.120396 0.2794)
			(stroke
				(width 0.1)
				(type default)
			)
			(layer "F.Fab")
		)
		(fp_line
			(start -0.12065 0.3048)
			(end -0.67945 0.3048)
			(stroke
				(width 0.1)
				(type default)
			)
			(layer "F.Fab")
		)
		(fp_line
			(start -0.67945 0.3048)
			(end -0.67945 -0.305054)
			(stroke
				(width 0.1)
				(type default)
			)
			(layer "F.Fab")
		)
		(pad "1" smd circle
			(at -0.40005 0 90)
			(size 0 0)
			(layers "F.Cu" "F.Mask" "F.Paste")
			(net "RST_PEX0_S1_PERST_N")
		)
		(pad "2" smd circle
			(at 0.40005 0 90)
			(size 0 0)
			(layers "F.Cu" "F.Mask" "F.Paste")
			(net "RST_PEX0_S1_PERST_R_N")
		)
	)
	(footprint ""
		(layer "F.Cu")
		(at 281.856434 -17.419574 180)
		(property "Reference" "R1691"
			(at 0 0 180)
			(layer "F.SilkS")
			(hide yes)
			(effects
				(font
					(size 1.27 1.27)
				)
			)
		)
		(property "Value" ""
			(at 0 0 180)
			(layer "F.Fab")
			(effects
				(font
					(size 1.27 1.27)
				)
			)
		)
		(duplicate_pad_numbers_are_jumpers no)
		(fp_line
			(start 0.7874 0.4064)
			(end -0.7874 0.4064)
			(stroke
				(width 0.1524)
				(type default)
			)
			(layer "F.SilkS")
		)
		(fp_line
			(start 0.7874 -0.4064)
			(end 0.7874 0.4064)
			(stroke
				(width 0.1524)
				(type default)
			)
			(layer "F.SilkS")
		)
		(fp_line
			(start -0.7874 0.4064)
			(end -0.7874 -0.4064)
			(stroke
				(width 0.1524)
				(type default)
			)
			(layer "F.SilkS")
		)
		(fp_line
			(start -0.7874 -0.4064)
			(end 0.7874 -0.4064)
			(stroke
				(width 0.1524)
				(type default)
			)
			(layer "F.SilkS")
		)
		(fp_line
			(start 0.67945 0.3048)
			(end 0.120396 0.3048)
			(stroke
				(width 0.1)
				(type default)
			)
			(layer "F.Fab")
		)
		(fp_line
			(start 0.67945 -0.3048)
			(end 0.67945 0.3048)
			(stroke
				(width 0.1)
				(type default)
			)
			(layer "F.Fab")
		)
		(fp_line
			(start 0.12065 -0.2794)
			(end 0.12065 -0.3048)
			(stroke
				(width 0.1)
				(type default)
			)
			(layer "F.Fab")
		)
		(fp_line
			(start 0.12065 -0.3048)
			(end 0.67945 -0.3048)
			(stroke
				(width 0.1)
				(type default)
			)
			(layer "F.Fab")
		)
		(fp_line
			(start 0.120396 0.3048)
			(end 0.120396 0.2794)
			(stroke
				(width 0.1)
				(type default)
			)
			(layer "F.Fab")
		)
		(fp_line
			(start 0.120396 0.2794)
			(end -0.12065 0.2794)
			(stroke
				(width 0.1)
				(type default)
			)
			(layer "F.Fab")
		)
		(fp_line
			(start -0.12065 0.3048)
			(end -0.67945 0.3048)
			(stroke
				(width 0.1)
				(type default)
			)
			(layer "F.Fab")
		)
		(fp_line
			(start -0.12065 0.2794)
			(end -0.12065 0.3048)
			(stroke
				(width 0.1)
				(type default)
			)
			(layer "F.Fab")
		)
		(fp_line
			(start -0.12065 -0.2794)
			(end 0.12065 -0.2794)
			(stroke
				(width 0.1)
				(type default)
			)
			(layer "F.Fab")
		)
		(fp_line
			(start -0.12065 -0.305054)
			(end -0.12065 -0.2794)
			(stroke
				(width 0.1)
				(type default)
			)
			(layer "F.Fab")
		)
		(fp_line
			(start -0.67945 0.3048)
			(end -0.67945 -0.305054)
			(stroke
				(width 0.1)
				(type default)
			)
			(layer "F.Fab")
		)
		(fp_line
			(start -0.67945 -0.305054)
			(end -0.12065 -0.305054)
			(stroke
				(width 0.1)
				(type default)
			)
			(layer "F.Fab")
		)
		(pad "1" smd circle
			(at -0.40005 0 180)
			(size 0 0)
			(layers "F.Cu" "F.Mask" "F.Paste")
			(net "P3V3_SSD9")
		)
		(pad "2" smd circle
			(at 0.40005 0 180)
			(size 0 0)
			(layers "F.Cu" "F.Mask" "F.Paste")
			(net "SMB_ISO_SSD9_SCL")
		)
	)
	(footprint ""
		(layer "F.Cu")
		(at 423.96791 -19.453098)
		(property "Reference" "R1737"
			(at 0 0 0)
			(layer "F.SilkS")
			(hide yes)
			(effects
				(font
					(size 1.27 1.27)
				)
			)
		)
		(property "Value" ""
			(at 0 0 0)
			(layer "F.Fab")
			(effects
				(font
					(size 1.27 1.27)
				)
			)
		)
		(duplicate_pad_numbers_are_jumpers no)
		(fp_line
			(start -0.7874 -0.4064)
			(end 0.7874 -0.4064)
			(stroke
				(width 0.1524)
				(type default)
			)
			(layer "F.SilkS")
		)
		(fp_line
			(start -0.7874 0.4064)
			(end -0.7874 -0.4064)
			(stroke
				(width 0.1524)
				(type default)
			)
			(layer "F.SilkS")
		)
		(fp_line
			(start 0.7874 -0.4064)
			(end 0.7874 0.4064)
			(stroke
				(width 0.1524)
				(type default)
			)
			(layer "F.SilkS")
		)
		(fp_line
			(start 0.7874 0.4064)
			(end -0.7874 0.4064)
			(stroke
				(width 0.1524)
				(type default)
			)
			(layer "F.SilkS")
		)
		(fp_line
			(start -0.67945 -0.305054)
			(end -0.12065 -0.305054)
			(stroke
				(width 0.1)
				(type default)
			)
			(layer "F.Fab")
		)
		(fp_line
			(start -0.67945 0.3048)
			(end -0.67945 -0.305054)
			(stroke
				(width 0.1)
				(type default)
			)
			(layer "F.Fab")
		)
		(fp_line
			(start -0.12065 -0.305054)
			(end -0.12065 -0.2794)
			(stroke
				(width 0.1)
				(type default)
			)
			(layer "F.Fab")
		)
		(fp_line
			(start -0.12065 -0.2794)
			(end 0.12065 -0.2794)
			(stroke
				(width 0.1)
				(type default)
			)
			(layer "F.Fab")
		)
		(fp_line
			(start -0.12065 0.2794)
			(end -0.12065 0.3048)
			(stroke
				(width 0.1)
				(type default)
			)
			(layer "F.Fab")
		)
		(fp_line
			(start -0.12065 0.3048)
			(end -0.67945 0.3048)
			(stroke
				(width 0.1)
				(type default)
			)
			(layer "F.Fab")
		)
		(fp_line
			(start 0.120396 0.2794)
			(end -0.12065 0.2794)
			(stroke
				(width 0.1)
				(type default)
			)
			(layer "F.Fab")
		)
		(fp_line
			(start 0.120396 0.3048)
			(end 0.120396 0.2794)
			(stroke
				(width 0.1)
				(type default)
			)
			(layer "F.Fab")
		)
		(fp_line
			(start 0.12065 -0.3048)
			(end 0.67945 -0.3048)
			(stroke
				(width 0.1)
				(type default)
			)
			(layer "F.Fab")
		)
		(fp_line
			(start 0.12065 -0.2794)
			(end 0.12065 -0.3048)
			(stroke
				(width 0.1)
				(type default)
			)
			(layer "F.Fab")
		)
		(fp_line
			(start 0.67945 -0.3048)
			(end 0.67945 0.3048)
			(stroke
				(width 0.1)
				(type default)
			)
			(layer "F.Fab")
		)
		(fp_line
			(start 0.67945 0.3048)
			(end 0.120396 0.3048)
			(stroke
				(width 0.1)
				(type default)
			)
			(layer "F.Fab")
		)
		(pad "1" smd circle
			(at -0.40005 0)
			(size 0 0)
			(layers "F.Cu" "F.Mask" "F.Paste")
			(net "SMB_ISO_SSD14_R_SDA")
		)
		(pad "2" smd circle
			(at 0.40005 0)
			(size 0 0)
			(layers "F.Cu" "F.Mask" "F.Paste")
			(net "SMB_ISO_SSD14_SDA")
		)
	)
	(footprint ""
		(layer "F.Cu")
		(at 123.87199 -24.807418)
		(property "Reference" "R422"
			(at 0 0 0)
			(layer "F.SilkS")
			(hide yes)
			(effects
				(font
					(size 1.27 1.27)
				)
			)
		)
		(property "Value" ""
			(at 0 0 0)
			(layer "F.Fab")
			(effects
				(font
					(size 1.27 1.27)
				)
			)
		)
		(duplicate_pad_numbers_are_jumpers no)
		(fp_line
			(start -0.7874 -0.4064)
			(end 0.7874 -0.4064)
			(stroke
				(width 0.1524)
				(type default)
			)
			(layer "F.SilkS")
		)
		(fp_line
			(start -0.7874 0.4064)
			(end -0.7874 -0.4064)
			(stroke
				(width 0.1524)
				(type default)
			)
			(layer "F.SilkS")
		)
		(fp_line
			(start 0.7874 -0.4064)
			(end 0.7874 0.4064)
			(stroke
				(width 0.1524)
				(type default)
			)
			(layer "F.SilkS")
		)
		(fp_line
			(start 0.7874 0.4064)
			(end -0.7874 0.4064)
			(stroke
				(width 0.1524)
				(type default)
			)
			(layer "F.SilkS")
		)
		(fp_line
			(start -0.67945 -0.305054)
			(end -0.12065 -0.305054)
			(stroke
				(width 0.1)
				(type default)
			)
			(layer "F.Fab")
		)
		(fp_line
			(start -0.67945 0.3048)
			(end -0.67945 -0.305054)
			(stroke
				(width 0.1)
				(type default)
			)
			(layer "F.Fab")
		)
		(fp_line
			(start -0.12065 -0.305054)
			(end -0.12065 -0.2794)
			(stroke
				(width 0.1)
				(type default)
			)
			(layer "F.Fab")
		)
		(fp_line
			(start -0.12065 -0.2794)
			(end 0.12065 -0.2794)
			(stroke
				(width 0.1)
				(type default)
			)
			(layer "F.Fab")
		)
		(fp_line
			(start -0.12065 0.2794)
			(end -0.12065 0.3048)
			(stroke
				(width 0.1)
				(type default)
			)
			(layer "F.Fab")
		)
		(fp_line
			(start -0.12065 0.3048)
			(end -0.67945 0.3048)
			(stroke
				(width 0.1)
				(type default)
			)
			(layer "F.Fab")
		)
		(fp_line
			(start 0.120396 0.2794)
			(end -0.12065 0.2794)
			(stroke
				(width 0.1)
				(type default)
			)
			(layer "F.Fab")
		)
		(fp_line
			(start 0.120396 0.3048)
			(end 0.120396 0.2794)
			(stroke
				(width 0.1)
				(type default)
			)
			(layer "F.Fab")
		)
		(fp_line
			(start 0.12065 -0.3048)
			(end 0.67945 -0.3048)
			(stroke
				(width 0.1)
				(type default)
			)
			(layer "F.Fab")
		)
		(fp_line
			(start 0.12065 -0.2794)
			(end 0.12065 -0.3048)
			(stroke
				(width 0.1)
				(type default)
			)
			(layer "F.Fab")
		)
		(fp_line
			(start 0.67945 -0.3048)
			(end 0.67945 0.3048)
			(stroke
				(width 0.1)
				(type default)
			)
			(layer "F.Fab")
		)
		(fp_line
			(start 0.67945 0.3048)
			(end 0.120396 0.3048)
			(stroke
				(width 0.1)
				(type default)
			)
			(layer "F.Fab")
		)
		(pad "1" smd circle
			(at -0.40005 0)
			(size 0 0)
			(layers "F.Cu" "F.Mask" "F.Paste")
			(net "P3V3_SSD4")
		)
		(pad "2" smd circle
			(at 0.40005 0)
			(size 0 0)
			(layers "F.Cu" "F.Mask" "F.Paste")
			(net "PU_CLKREQ4")
		)
	)
	(footprint ""
		(layer "F.Cu")
		(at 334.229456 -277.639272 180)
		(property "Reference" "PC158"
			(at 0 0 180)
			(layer "F.SilkS")
			(hide yes)
			(effects
				(font
					(size 1.27 1.27)
				)
			)
		)
		(property "Value" ""
			(at 0 0 180)
			(layer "F.Fab")
			(effects
				(font
					(size 1.27 1.27)
				)
			)
		)
		(duplicate_pad_numbers_are_jumpers no)
		(fp_line
			(start 1.524 0.762)
			(end -1.524 0.762)
			(stroke
				(width 0.1524)
				(type default)
			)
			(layer "F.SilkS")
		)
		(fp_line
			(start 1.524 -0.762)
			(end 1.524 0.762)
			(stroke
				(width 0.1524)
				(type default)
			)
			(layer "F.SilkS")
		)
		(fp_line
			(start -1.524 0.762)
			(end -1.524 -0.762)
			(stroke
				(width 0.1524)
				(type default)
			)
			(layer "F.SilkS")
		)
		(fp_line
			(start -1.524 -0.762)
			(end 1.524 -0.762)
			(stroke
				(width 0.1524)
				(type default)
			)
			(layer "F.SilkS")
		)
		(fp_line
			(start 1.1049 0.724916)
			(end 1.1049 -0.724916)
			(stroke
				(width 0.1)
				(type default)
			)
			(layer "F.Fab")
		)
		(fp_line
			(start 1.1049 -0.724916)
			(end -1.1049 -0.724916)
			(stroke
				(width 0.1)
				(type default)
			)
			(layer "F.Fab")
		)
		(fp_line
			(start -1.1049 0.724916)
			(end 1.1049 0.724916)
			(stroke
				(width 0.1)
				(type default)
			)
			(layer "F.Fab")
		)
		(fp_line
			(start -1.1049 -0.724916)
			(end -1.1049 0.724916)
			(stroke
				(width 0.1)
				(type default)
			)
			(layer "F.Fab")
		)
		(pad "1" smd rect
			(at -0.889 0)
			(size 1.016 1.27)
			(layers "F.Cu" "F.Mask" "F.Paste")
			(net "SW_P12V_P0V8_PEX2_FLT")
		)
		(pad "2" smd rect
			(at 0.889 0)
			(size 1.016 1.27)
			(layers "F.Cu" "F.Mask" "F.Paste")
			(net "GND")
		)
	)
	(footprint ""
		(layer "F.Cu")
		(at 486.08234 -546.564566 180)
		(property "Reference" "SCREW_SSD9_2"
			(at -5.207 -1.402334 0)
			(unlocked yes)
			(layer "B.SilkS")
			(effects
				(font
					(size 0.7874 0.5842)
					(thickness 0.1524)
				)
				(justify mirror)
			)
		)
		(property "Value" ""
			(at 0 0 180)
			(layer "F.Fab")
			(effects
				(font
					(size 1.27 1.27)
				)
			)
		)
		(duplicate_pad_numbers_are_jumpers no)
		(pad "1" thru_hole circle
			(at 0 0 180)
			(size 0.4572 0.4572)
			(drill 0.2032)
			(layers "*.Cu" "*.Mask")
			(remove_unused_layers no)
			(net "Net_9125")
			(clearance 0.127)
			(thermal_gap 0.127)
			(padstack
				(mode front_inner_back)
				(layer "Inner"
					(shape circle)
					(size 0.4572 0.4572)
					(clearance 0.127)
				)
				(layer "B.Cu"
					(shape circle)
					(size 0.508 0.508)
					(clearance 0.1016)
				)
			)
		)
	)
	(footprint ""
		(layer "F.Cu")
		(at 86.218522 -343.952322 90)
		(property "Reference" "C151"
			(at 0 0 90)
			(layer "F.SilkS")
			(hide yes)
			(effects
				(font
					(size 1.27 1.27)
				)
			)
		)
		(property "Value" ""
			(at 0 0 90)
			(layer "F.Fab")
			(effects
				(font
					(size 1.27 1.27)
				)
			)
		)
		(duplicate_pad_numbers_are_jumpers no)
		(fp_line
			(start 0.299974 -0.150114)
			(end 0.299974 0.150114)
			(stroke
				(width 0.1)
				(type default)
			)
			(layer "F.Fab")
		)
		(fp_line
			(start -0.299974 -0.150114)
			(end 0.299974 -0.150114)
			(stroke
				(width 0.1)
				(type default)
			)
			(layer "F.Fab")
		)
		(fp_line
			(start 0.299974 0.150114)
			(end -0.299974 0.150114)
			(stroke
				(width 0.1)
				(type default)
			)
			(layer "F.Fab")
		)
		(fp_line
			(start -0.299974 0.150114)
			(end -0.299974 -0.150114)
			(stroke
				(width 0.1)
				(type default)
			)
			(layer "F.Fab")
		)
		(pad "1" smd rect
			(at -0.2667 0 90)
			(size 0.3048 0.381)
			(layers "F.Cu" "F.Mask" "F.Paste")
			(net "P5E_PEX0_STN6_TX_DP<100>")
		)
		(pad "2" smd rect
			(at 0.2667 0 90)
			(size 0.3048 0.381)
			(layers "F.Cu" "F.Mask" "F.Paste")
			(net "P5E_PEX0_STN6_TX_C_DP<100>")
		)
	)
	(footprint ""
		(layer "F.Cu")
		(at 129.690114 -258.131564 180)
		(property "Reference" "R831"
			(at 0 0 180)
			(layer "F.SilkS")
			(hide yes)
			(effects
				(font
					(size 1.27 1.27)
				)
			)
		)
		(property "Value" ""
			(at 0 0 180)
			(layer "F.Fab")
			(effects
				(font
					(size 1.27 1.27)
				)
			)
		)
		(duplicate_pad_numbers_are_jumpers no)
		(fp_line
			(start 0.7874 0.4064)
			(end -0.7874 0.4064)
			(stroke
				(width 0.1524)
				(type default)
			)
			(layer "F.SilkS")
		)
		(fp_line
			(start 0.7874 -0.4064)
			(end 0.7874 0.4064)
			(stroke
				(width 0.1524)
				(type default)
			)
			(layer "F.SilkS")
		)
		(fp_line
			(start -0.7874 0.4064)
			(end -0.7874 -0.4064)
			(stroke
				(width 0.1524)
				(type default)
			)
			(layer "F.SilkS")
		)
		(fp_line
			(start -0.7874 -0.4064)
			(end 0.7874 -0.4064)
			(stroke
				(width 0.1524)
				(type default)
			)
			(layer "F.SilkS")
		)
		(fp_line
			(start 0.67945 0.3048)
			(end 0.120396 0.3048)
			(stroke
				(width 0.1)
				(type default)
			)
			(layer "F.Fab")
		)
		(fp_line
			(start 0.67945 -0.3048)
			(end 0.67945 0.3048)
			(stroke
				(width 0.1)
				(type default)
			)
			(layer "F.Fab")
		)
		(fp_line
			(start 0.12065 -0.2794)
			(end 0.12065 -0.3048)
			(stroke
				(width 0.1)
				(type default)
			)
			(layer "F.Fab")
		)
		(fp_line
			(start 0.12065 -0.3048)
			(end 0.67945 -0.3048)
			(stroke
				(width 0.1)
				(type default)
			)
			(layer "F.Fab")
		)
		(fp_line
			(start 0.120396 0.3048)
			(end 0.120396 0.2794)
			(stroke
				(width 0.1)
				(type default)
			)
			(layer "F.Fab")
		)
		(fp_line
			(start 0.120396 0.2794)
			(end -0.12065 0.2794)
			(stroke
				(width 0.1)
				(type default)
			)
			(layer "F.Fab")
		)
		(fp_line
			(start -0.12065 0.3048)
			(end -0.67945 0.3048)
			(stroke
				(width 0.1)
				(type default)
			)
			(layer "F.Fab")
		)
		(fp_line
			(start -0.12065 0.2794)
			(end -0.12065 0.3048)
			(stroke
				(width 0.1)
				(type default)
			)
			(layer "F.Fab")
		)
		(fp_line
			(start -0.12065 -0.2794)
			(end 0.12065 -0.2794)
			(stroke
				(width 0.1)
				(type default)
			)
			(layer "F.Fab")
		)
		(fp_line
			(start -0.12065 -0.305054)
			(end -0.12065 -0.2794)
			(stroke
				(width 0.1)
				(type default)
			)
			(layer "F.Fab")
		)
		(fp_line
			(start -0.67945 0.3048)
			(end -0.67945 -0.305054)
			(stroke
				(width 0.1)
				(type default)
			)
			(layer "F.Fab")
		)
		(fp_line
			(start -0.67945 -0.305054)
			(end -0.12065 -0.305054)
			(stroke
				(width 0.1)
				(type default)
			)
			(layer "F.Fab")
		)
		(pad "1" smd circle
			(at -0.40005 0 180)
			(size 0 0)
			(layers "F.Cu" "F.Mask" "F.Paste")
			(net "P3V3_AUX")
		)
		(pad "2" smd circle
			(at 0.40005 0 180)
			(size 0 0)
			(layers "F.Cu" "F.Mask" "F.Paste")
			(net "P0V8_PEX1_BVRRDY")
		)
	)
	(footprint ""
		(layer "F.Cu")
		(at 362.459016 -319.545462 90)
		(property "Reference" "L75"
			(at 0 0 90)
			(layer "F.SilkS")
			(hide yes)
			(effects
				(font
					(size 1.27 1.27)
				)
			)
		)
		(property "Value" ""
			(at 0 0 90)
			(layer "F.Fab")
			(effects
				(font
					(size 1.27 1.27)
				)
			)
		)
		(duplicate_pad_numbers_are_jumpers no)
		(fp_line
			(start 2.248154 -4.9911)
			(end -2.248154 -4.9911)
			(stroke
				(width 0.1524)
				(type default)
			)
			(layer "F.SilkS")
		)
		(fp_line
			(start -2.248154 -4.9911)
			(end -2.248154 -1.682496)
			(stroke
				(width 0.1524)
				(type default)
			)
			(layer "F.SilkS")
		)
		(fp_line
			(start 2.248154 -1.748536)
			(end 2.248154 -4.9911)
			(stroke
				(width 0.1524)
				(type default)
			)
			(layer "F.SilkS")
		)
		(fp_line
			(start -2.248154 1.787144)
			(end -2.248154 4.9911)
			(stroke
				(width 0.1524)
				(type default)
			)
			(layer "F.SilkS")
		)
		(fp_line
			(start 2.248154 4.9911)
			(end 2.248154 1.743202)
			(stroke
				(width 0.1524)
				(type default)
			)
			(layer "F.SilkS")
		)
		(fp_line
			(start -2.248154 4.9911)
			(end 2.248154 4.9911)
			(stroke
				(width 0.1524)
				(type default)
			)
			(layer "F.SilkS")
		)
		(fp_line
			(start 1.700022 -0.899922)
			(end -1.700022 -0.899922)
			(stroke
				(width 0.1)
				(type default)
			)
			(layer "F.Fab")
		)
		(fp_line
			(start -1.700022 -0.899922)
			(end -1.700022 0.899922)
			(stroke
				(width 0.1)
				(type default)
			)
			(layer "F.Fab")
		)
		(fp_line
			(start 1.700022 0.899922)
			(end 1.700022 -0.899922)
			(stroke
				(width 0.1)
				(type default)
			)
			(layer "F.Fab")
		)
		(fp_line
			(start -1.700022 0.899922)
			(end 1.700022 0.899922)
			(stroke
				(width 0.1)
				(type default)
			)
			(layer "F.Fab")
		)
		(pad "1" smd rect
			(at -1.575054 0 90)
			(size 1.1684 9.8044)
			(layers "F.Cu" "F.Mask" "F.Paste")
			(net "P0V8_PEX3")
		)
		(pad "2" smd rect
			(at 1.575054 0 90)
			(size 1.1684 9.8044)
			(layers "F.Cu" "F.Mask" "F.Paste")
			(net "P0V8_SERDES_VDDA_PEX3")
		)
	)
	(footprint ""
		(layer "F.Cu")
		(at 117.958362 -125.899926 180)
		(property "Reference" "R852"
			(at 0 0 180)
			(layer "F.SilkS")
			(hide yes)
			(effects
				(font
					(size 1.27 1.27)
				)
			)
		)
		(property "Value" ""
			(at 0 0 180)
			(layer "F.Fab")
			(effects
				(font
					(size 1.27 1.27)
				)
			)
		)
		(duplicate_pad_numbers_are_jumpers no)
		(fp_line
			(start 0.7874 0.4064)
			(end -0.7874 0.4064)
			(stroke
				(width 0.1524)
				(type default)
			)
			(layer "F.SilkS")
		)
		(fp_line
			(start 0.7874 -0.4064)
			(end 0.7874 0.4064)
			(stroke
				(width 0.1524)
				(type default)
			)
			(layer "F.SilkS")
		)
		(fp_line
			(start -0.7874 0.4064)
			(end -0.7874 -0.4064)
			(stroke
				(width 0.1524)
				(type default)
			)
			(layer "F.SilkS")
		)
		(fp_line
			(start -0.7874 -0.4064)
			(end 0.7874 -0.4064)
			(stroke
				(width 0.1524)
				(type default)
			)
			(layer "F.SilkS")
		)
		(fp_line
			(start 0.67945 0.3048)
			(end 0.120396 0.3048)
			(stroke
				(width 0.1)
				(type default)
			)
			(layer "F.Fab")
		)
		(fp_line
			(start 0.67945 -0.3048)
			(end 0.67945 0.3048)
			(stroke
				(width 0.1)
				(type default)
			)
			(layer "F.Fab")
		)
		(fp_line
			(start 0.12065 -0.2794)
			(end 0.12065 -0.3048)
			(stroke
				(width 0.1)
				(type default)
			)
			(layer "F.Fab")
		)
		(fp_line
			(start 0.12065 -0.3048)
			(end 0.67945 -0.3048)
			(stroke
				(width 0.1)
				(type default)
			)
			(layer "F.Fab")
		)
		(fp_line
			(start 0.120396 0.3048)
			(end 0.120396 0.2794)
			(stroke
				(width 0.1)
				(type default)
			)
			(layer "F.Fab")
		)
		(fp_line
			(start 0.120396 0.2794)
			(end -0.12065 0.2794)
			(stroke
				(width 0.1)
				(type default)
			)
			(layer "F.Fab")
		)
		(fp_line
			(start -0.12065 0.3048)
			(end -0.67945 0.3048)
			(stroke
				(width 0.1)
				(type default)
			)
			(layer "F.Fab")
		)
		(fp_line
			(start -0.12065 0.2794)
			(end -0.12065 0.3048)
			(stroke
				(width 0.1)
				(type default)
			)
			(layer "F.Fab")
		)
		(fp_line
			(start -0.12065 -0.2794)
			(end 0.12065 -0.2794)
			(stroke
				(width 0.1)
				(type default)
			)
			(layer "F.Fab")
		)
		(fp_line
			(start -0.12065 -0.305054)
			(end -0.12065 -0.2794)
			(stroke
				(width 0.1)
				(type default)
			)
			(layer "F.Fab")
		)
		(fp_line
			(start -0.67945 0.3048)
			(end -0.67945 -0.305054)
			(stroke
				(width 0.1)
				(type default)
			)
			(layer "F.Fab")
		)
		(fp_line
			(start -0.67945 -0.305054)
			(end -0.12065 -0.305054)
			(stroke
				(width 0.1)
				(type default)
			)
			(layer "F.Fab")
		)
		(pad "1" smd circle
			(at -0.40005 0 180)
			(size 0 0)
			(layers "F.Cu" "F.Mask" "F.Paste")
			(net "P3V3")
		)
		(pad "2" smd circle
			(at 0.40005 0 180)
			(size 0 0)
			(layers "F.Cu" "F.Mask" "F.Paste")
			(net "PWRGD_P3V3")
		)
	)
	(footprint ""
		(layer "F.Cu")
		(at 199.750172 -50.96383 180)
		(property "Reference" "PC537"
			(at 0 0 180)
			(layer "F.SilkS")
			(hide yes)
			(effects
				(font
					(size 1.27 1.27)
				)
			)
		)
		(property "Value" ""
			(at 0 0 180)
			(layer "F.Fab")
			(effects
				(font
					(size 1.27 1.27)
				)
			)
		)
		(duplicate_pad_numbers_are_jumpers no)
		(fp_line
			(start 1.524 0.762)
			(end -1.524 0.762)
			(stroke
				(width 0.1524)
				(type default)
			)
			(layer "F.SilkS")
		)
		(fp_line
			(start 1.524 -0.762)
			(end 1.524 0.762)
			(stroke
				(width 0.1524)
				(type default)
			)
			(layer "F.SilkS")
		)
		(fp_line
			(start -1.524 0.762)
			(end -1.524 -0.762)
			(stroke
				(width 0.1524)
				(type default)
			)
			(layer "F.SilkS")
		)
		(fp_line
			(start -1.524 -0.762)
			(end 1.524 -0.762)
			(stroke
				(width 0.1524)
				(type default)
			)
			(layer "F.SilkS")
		)
		(fp_line
			(start 1.1049 0.724916)
			(end 1.1049 -0.724916)
			(stroke
				(width 0.1)
				(type default)
			)
			(layer "F.Fab")
		)
		(fp_line
			(start 1.1049 -0.724916)
			(end -1.1049 -0.724916)
			(stroke
				(width 0.1)
				(type default)
			)
			(layer "F.Fab")
		)
		(fp_line
			(start -1.1049 0.724916)
			(end 1.1049 0.724916)
			(stroke
				(width 0.1)
				(type default)
			)
			(layer "F.Fab")
		)
		(fp_line
			(start -1.1049 -0.724916)
			(end -1.1049 0.724916)
			(stroke
				(width 0.1)
				(type default)
			)
			(layer "F.Fab")
		)
		(pad "1" smd rect
			(at -0.889 0)
			(size 1.016 1.27)
			(layers "F.Cu" "F.Mask" "F.Paste")
			(net "P3V3_SSD7")
		)
		(pad "2" smd rect
			(at 0.889 0)
			(size 1.016 1.27)
			(layers "F.Cu" "F.Mask" "F.Paste")
			(net "GND")
		)
	)
	(footprint ""
		(layer "F.Cu")
		(at 122.689366 -313.620404 180)
		(property "Reference" "R5789"
			(at 0 0 180)
			(layer "F.SilkS")
			(hide yes)
			(effects
				(font
					(size 1.27 1.27)
				)
			)
		)
		(property "Value" ""
			(at 0 0 180)
			(layer "F.Fab")
			(effects
				(font
					(size 1.27 1.27)
				)
			)
		)
		(duplicate_pad_numbers_are_jumpers no)
		(fp_line
			(start 2.576322 1.1303)
			(end -2.576322 1.1303)
			(stroke
				(width 0.1524)
				(type default)
			)
			(layer "F.SilkS")
		)
		(fp_line
			(start 2.576322 -1.1303)
			(end 2.576322 1.1303)
			(stroke
				(width 0.1524)
				(type default)
			)
			(layer "F.SilkS")
		)
		(fp_line
			(start -2.576322 1.1303)
			(end -2.576322 -1.1303)
			(stroke
				(width 0.1524)
				(type default)
			)
			(layer "F.SilkS")
		)
		(fp_line
			(start -2.576322 -1.1303)
			(end 2.576322 -1.1303)
			(stroke
				(width 0.1524)
				(type default)
			)
			(layer "F.SilkS")
		)
		(fp_line
			(start 1.649984 0.899922)
			(end 1.649984 -0.899922)
			(stroke
				(width 0.1)
				(type default)
			)
			(layer "F.Fab")
		)
		(fp_line
			(start 1.649984 -0.899922)
			(end -1.649984 -0.899922)
			(stroke
				(width 0.1)
				(type default)
			)
			(layer "F.Fab")
		)
		(fp_line
			(start -1.649984 0.899922)
			(end 1.649984 0.899922)
			(stroke
				(width 0.1)
				(type default)
			)
			(layer "F.Fab")
		)
		(fp_line
			(start -1.649984 -0.899922)
			(end -1.649984 0.899922)
			(stroke
				(width 0.1)
				(type default)
			)
			(layer "F.Fab")
		)
		(pad "1A" smd rect
			(at -1.700022 0 180)
			(size 1.4986 2.0066)
			(layers "F.Cu" "F.Mask" "F.Paste")
			(net "P0V8_PEX1")
		)
		(pad "1B" smd rect
			(at -1.077722 0 180)
			(size 0.254 0.508)
			(layers "F.Cu" "F.Mask" "F.Paste")
			(net "P0V8_PEX1")
		)
		(pad "2A" smd rect
			(at 1.700022 0 180)
			(size 1.4986 2.0066)
			(layers "F.Cu" "F.Mask" "F.Paste")
			(net "P0V8_SERDES_VDDA_PEX1")
		)
		(pad "2B" smd rect
			(at 1.077722 0 180)
			(size 0.254 0.508)
			(layers "F.Cu" "F.Mask" "F.Paste")
			(net "P0V8_SERDES_VDDA_PEX1")
		)
	)
	(footprint ""
		(layer "F.Cu")
		(at 312.21934 -154.304746 180)
		(property "Reference" "C425"
			(at 0 0 180)
			(layer "F.SilkS")
			(hide yes)
			(effects
				(font
					(size 1.27 1.27)
				)
			)
		)
		(property "Value" ""
			(at 0 0 180)
			(layer "F.Fab")
			(effects
				(font
					(size 1.27 1.27)
				)
			)
		)
		(duplicate_pad_numbers_are_jumpers no)
		(fp_line
			(start 0.299974 0.150114)
			(end -0.299974 0.150114)
			(stroke
				(width 0.1)
				(type default)
			)
			(layer "F.Fab")
		)
		(fp_line
			(start 0.299974 -0.150114)
			(end 0.299974 0.150114)
			(stroke
				(width 0.1)
				(type default)
			)
			(layer "F.Fab")
		)
		(fp_line
			(start -0.299974 0.150114)
			(end -0.299974 -0.150114)
			(stroke
				(width 0.1)
				(type default)
			)
			(layer "F.Fab")
		)
		(fp_line
			(start -0.299974 -0.150114)
			(end 0.299974 -0.150114)
			(stroke
				(width 0.1)
				(type default)
			)
			(layer "F.Fab")
		)
		(pad "1" smd rect
			(at -0.2667 0 180)
			(size 0.3048 0.381)
			(layers "F.Cu" "F.Mask" "F.Paste")
			(net "P5E_PEX2_STN0_TX_DN<14>")
		)
		(pad "2" smd rect
			(at 0.2667 0 180)
			(size 0.3048 0.381)
			(layers "F.Cu" "F.Mask" "F.Paste")
			(net "P5E_PEX2_STN0_TX_C_DN<14>")
		)
	)
	(footprint ""
		(layer "F.Cu")
		(at 130.753612 -162.003994 -90)
		(property "Reference" "R948"
			(at 0 0 270)
			(layer "F.SilkS")
			(hide yes)
			(effects
				(font
					(size 1.27 1.27)
				)
			)
		)
		(property "Value" ""
			(at 0 0 270)
			(layer "F.Fab")
			(effects
				(font
					(size 1.27 1.27)
				)
			)
		)
		(duplicate_pad_numbers_are_jumpers no)
		(fp_line
			(start -0.7874 0.4064)
			(end -0.7874 -0.4064)
			(stroke
				(width 0.1524)
				(type default)
			)
			(layer "F.SilkS")
		)
		(fp_line
			(start 0.7874 0.4064)
			(end -0.7874 0.4064)
			(stroke
				(width 0.1524)
				(type default)
			)
			(layer "F.SilkS")
		)
		(fp_line
			(start -0.7874 -0.4064)
			(end 0.7874 -0.4064)
			(stroke
				(width 0.1524)
				(type default)
			)
			(layer "F.SilkS")
		)
		(fp_line
			(start 0.7874 -0.4064)
			(end 0.7874 0.4064)
			(stroke
				(width 0.1524)
				(type default)
			)
			(layer "F.SilkS")
		)
		(fp_line
			(start -0.67945 0.3048)
			(end -0.67945 -0.305054)
			(stroke
				(width 0.1)
				(type default)
			)
			(layer "F.Fab")
		)
		(fp_line
			(start -0.12065 0.3048)
			(end -0.67945 0.3048)
			(stroke
				(width 0.1)
				(type default)
			)
			(layer "F.Fab")
		)
		(fp_line
			(start 0.120396 0.3048)
			(end 0.120396 0.2794)
			(stroke
				(width 0.1)
				(type default)
			)
			(layer "F.Fab")
		)
		(fp_line
			(start 0.67945 0.3048)
			(end 0.120396 0.3048)
			(stroke
				(width 0.1)
				(type default)
			)
			(layer "F.Fab")
		)
		(fp_line
			(start -0.12065 0.2794)
			(end -0.12065 0.3048)
			(stroke
				(width 0.1)
				(type default)
			)
			(layer "F.Fab")
		)
		(fp_line
			(start 0.120396 0.2794)
			(end -0.12065 0.2794)
			(stroke
				(width 0.1)
				(type default)
			)
			(layer "F.Fab")
		)
		(fp_line
			(start -0.12065 -0.2794)
			(end 0.12065 -0.2794)
			(stroke
				(width 0.1)
				(type default)
			)
			(layer "F.Fab")
		)
		(fp_line
			(start 0.12065 -0.2794)
			(end 0.12065 -0.3048)
			(stroke
				(width 0.1)
				(type default)
			)
			(layer "F.Fab")
		)
		(fp_line
			(start 0.12065 -0.3048)
			(end 0.67945 -0.3048)
			(stroke
				(width 0.1)
				(type default)
			)
			(layer "F.Fab")
		)
		(fp_line
			(start 0.67945 -0.3048)
			(end 0.67945 0.3048)
			(stroke
				(width 0.1)
				(type default)
			)
			(layer "F.Fab")
		)
		(fp_line
			(start -0.67945 -0.305054)
			(end -0.12065 -0.305054)
			(stroke
				(width 0.1)
				(type default)
			)
			(layer "F.Fab")
		)
		(fp_line
			(start -0.12065 -0.305054)
			(end -0.12065 -0.2794)
			(stroke
				(width 0.1)
				(type default)
			)
			(layer "F.Fab")
		)
		(pad "1" smd circle
			(at -0.40005 0 270)
			(size 0 0)
			(layers "F.Cu" "F.Mask" "F.Paste")
			(net "GND")
		)
		(pad "2" smd circle
			(at 0.40005 0 270)
			(size 0 0)
			(layers "F.Cu" "F.Mask" "F.Paste")
			(net "P12V_NIC2_CO_EN")
		)
	)
	(footprint ""
		(layer "F.Cu")
		(at 273.401282 -55.78475 -90)
		(property "Reference" "PD42"
			(at 4.07035 2.128012 90)
			(unlocked yes)
			(layer "F.SilkS")
			(effects
				(font
					(size 0.7874 0.5842)
					(thickness 0.1524)
				)
				(justify left)
			)
		)
		(property "Value" ""
			(at 0 0 270)
			(layer "F.Fab")
			(effects
				(font
					(size 1.27 1.27)
				)
			)
		)
		(duplicate_pad_numbers_are_jumpers no)
		(fp_line
			(start -3.400044 1.459992)
			(end -3.400044 -1.459992)
			(stroke
				(width 0.1524)
				(type default)
			)
			(layer "F.SilkS")
		)
		(fp_line
			(start 4.107942 1.459992)
			(end -3.400044 1.459992)
			(stroke
				(width 0.1524)
				(type default)
			)
			(layer "F.SilkS")
		)
		(fp_line
			(start -3.400044 -1.459992)
			(end 4.107942 -1.459992)
			(stroke
				(width 0.1524)
				(type default)
			)
			(layer "F.SilkS")
		)
		(fp_line
			(start 4.107942 -1.459992)
			(end 4.107942 1.459992)
			(stroke
				(width 0.1524)
				(type default)
			)
			(layer "F.SilkS")
		)
		(fp_poly
			(pts
				(xy 4.107942 -1.459992) (xy 4.107942 1.459992) (xy 3.308096 1.459992) (xy 3.308096 -1.459992)
			)
			(stroke
				(width 0)
				(type default)
			)
			(fill yes)
			(layer "F.SilkS")
		)
		(fp_line
			(start -2.29997 1.459992)
			(end -2.29997 -1.459992)
			(stroke
				(width 0.1)
				(type default)
			)
			(layer "F.Fab")
		)
		(fp_line
			(start 2.29997 1.459992)
			(end -2.29997 1.459992)
			(stroke
				(width 0.1)
				(type default)
			)
			(layer "F.Fab")
		)
		(fp_line
			(start -2.29997 -1.459992)
			(end 2.29997 -1.459992)
			(stroke
				(width 0.1)
				(type default)
			)
			(layer "F.Fab")
		)
		(fp_line
			(start 2.29997 -1.459992)
			(end 2.29997 1.459992)
			(stroke
				(width 0.1)
				(type default)
			)
			(layer "F.Fab")
		)
		(fp_text user "-"
			(at 5.4102 0.29845 90)
			(unlocked yes)
			(layer "F.SilkS")
			(effects
				(font
					(size 1.905 1.4224)
					(thickness 0.1524)
				)
				(justify left)
			)
		)
		(fp_text user "+"
			(at -4.7752 -0.12065 270)
			(unlocked yes)
			(layer "F.SilkS")
			(effects
				(font
					(size 1.905 1.4224)
					(thickness 0.1524)
				)
				(justify left)
			)
		)
		(fp_text user "-"
			(at 5.4102 0.29845 90)
			(unlocked yes)
			(layer "F.Fab")
			(effects
				(font
					(size 1.905 1.4224)
					(thickness 0.1524)
				)
				(justify left)
			)
		)
		(fp_text user "+"
			(at -4.7752 -0.12065 270)
			(unlocked yes)
			(layer "F.Fab")
			(effects
				(font
					(size 1.905 1.4224)
					(thickness 0.1524)
				)
				(justify left)
			)
		)
		(pad "A" smd rect
			(at -1.999996 0)
			(size 1.7018 2.5146)
			(layers "F.Cu" "F.Mask" "F.Paste")
			(net "GND")
		)
		(pad "C" smd rect
			(at 1.999996 0)
			(size 1.7018 2.5146)
			(layers "F.Cu" "F.Mask" "F.Paste")
			(net "P12V_SSD9_R")
		)
	)
	(footprint ""
		(layer "F.Cu")
		(at 260.249162 -290.595812 -90)
		(property "Reference" "C3382"
			(at 0 0 270)
			(layer "F.SilkS")
			(hide yes)
			(effects
				(font
					(size 1.27 1.27)
				)
			)
		)
		(property "Value" ""
			(at 0 0 270)
			(layer "F.Fab")
			(effects
				(font
					(size 1.27 1.27)
				)
			)
		)
		(duplicate_pad_numbers_are_jumpers no)
		(fp_line
			(start -0.299974 0.150114)
			(end -0.299974 -0.150114)
			(stroke
				(width 0.1)
				(type default)
			)
			(layer "F.Fab")
		)
		(fp_line
			(start 0.299974 0.150114)
			(end -0.299974 0.150114)
			(stroke
				(width 0.1)
				(type default)
			)
			(layer "F.Fab")
		)
		(fp_line
			(start -0.299974 -0.150114)
			(end 0.299974 -0.150114)
			(stroke
				(width 0.1)
				(type default)
			)
			(layer "F.Fab")
		)
		(fp_line
			(start 0.299974 -0.150114)
			(end 0.299974 0.150114)
			(stroke
				(width 0.1)
				(type default)
			)
			(layer "F.Fab")
		)
		(pad "1" smd rect
			(at -0.2667 0 270)
			(size 0.3048 0.381)
			(layers "F.Cu" "F.Mask" "F.Paste")
			(net "P1V8_PLL0_PEX2")
		)
		(pad "2" smd rect
			(at 0.2667 0 270)
			(size 0.3048 0.381)
			(layers "F.Cu" "F.Mask" "F.Paste")
			(net "GND")
		)
	)
	(footprint ""
		(layer "F.Cu")
		(at 3.88366 -61.487812 180)
		(property "Reference" "R5838"
			(at 0 0 180)
			(layer "F.SilkS")
			(hide yes)
			(effects
				(font
					(size 1.27 1.27)
				)
			)
		)
		(property "Value" ""
			(at 0 0 180)
			(layer "F.Fab")
			(effects
				(font
					(size 1.27 1.27)
				)
			)
		)
		(duplicate_pad_numbers_are_jumpers no)
		(fp_line
			(start 0.7874 0.4064)
			(end -0.7874 0.4064)
			(stroke
				(width 0.1524)
				(type default)
			)
			(layer "F.SilkS")
		)
		(fp_line
			(start 0.7874 -0.4064)
			(end 0.7874 0.4064)
			(stroke
				(width 0.1524)
				(type default)
			)
			(layer "F.SilkS")
		)
		(fp_line
			(start -0.7874 0.4064)
			(end -0.7874 -0.4064)
			(stroke
				(width 0.1524)
				(type default)
			)
			(layer "F.SilkS")
		)
		(fp_line
			(start -0.7874 -0.4064)
			(end 0.7874 -0.4064)
			(stroke
				(width 0.1524)
				(type default)
			)
			(layer "F.SilkS")
		)
		(fp_line
			(start 0.67945 0.3048)
			(end 0.120396 0.3048)
			(stroke
				(width 0.1)
				(type default)
			)
			(layer "F.Fab")
		)
		(fp_line
			(start 0.67945 -0.3048)
			(end 0.67945 0.3048)
			(stroke
				(width 0.1)
				(type default)
			)
			(layer "F.Fab")
		)
		(fp_line
			(start 0.12065 -0.2794)
			(end 0.12065 -0.3048)
			(stroke
				(width 0.1)
				(type default)
			)
			(layer "F.Fab")
		)
		(fp_line
			(start 0.12065 -0.3048)
			(end 0.67945 -0.3048)
			(stroke
				(width 0.1)
				(type default)
			)
			(layer "F.Fab")
		)
		(fp_line
			(start 0.120396 0.3048)
			(end 0.120396 0.2794)
			(stroke
				(width 0.1)
				(type default)
			)
			(layer "F.Fab")
		)
		(fp_line
			(start 0.120396 0.2794)
			(end -0.12065 0.2794)
			(stroke
				(width 0.1)
				(type default)
			)
			(layer "F.Fab")
		)
		(fp_line
			(start -0.12065 0.3048)
			(end -0.67945 0.3048)
			(stroke
				(width 0.1)
				(type default)
			)
			(layer "F.Fab")
		)
		(fp_line
			(start -0.12065 0.2794)
			(end -0.12065 0.3048)
			(stroke
				(width 0.1)
				(type default)
			)
			(layer "F.Fab")
		)
		(fp_line
			(start -0.12065 -0.2794)
			(end 0.12065 -0.2794)
			(stroke
				(width 0.1)
				(type default)
			)
			(layer "F.Fab")
		)
		(fp_line
			(start -0.12065 -0.305054)
			(end -0.12065 -0.2794)
			(stroke
				(width 0.1)
				(type default)
			)
			(layer "F.Fab")
		)
		(fp_line
			(start -0.67945 0.3048)
			(end -0.67945 -0.305054)
			(stroke
				(width 0.1)
				(type default)
			)
			(layer "F.Fab")
		)
		(fp_line
			(start -0.67945 -0.305054)
			(end -0.12065 -0.305054)
			(stroke
				(width 0.1)
				(type default)
			)
			(layer "F.Fab")
		)
		(pad "1" smd circle
			(at -0.40005 0 180)
			(size 0 0)
			(layers "F.Cu" "F.Mask" "F.Paste")
			(net "PWRGD_P12V_SSD0_D")
		)
		(pad "2" smd circle
			(at 0.40005 0 180)
			(size 0 0)
			(layers "F.Cu" "F.Mask" "F.Paste")
			(net "PWRGD_P12V_SSD0_R")
		)
	)
	(footprint ""
		(layer "F.Cu")
		(at 419.7985 -66.32194 -90)
		(property "Reference" "PC891"
			(at 0 0 270)
			(layer "F.SilkS")
			(hide yes)
			(effects
				(font
					(size 1.27 1.27)
				)
			)
		)
		(property "Value" ""
			(at 0 0 270)
			(layer "F.Fab")
			(effects
				(font
					(size 1.27 1.27)
				)
			)
		)
		(duplicate_pad_numbers_are_jumpers no)
		(fp_line
			(start -0.7874 0.4064)
			(end -0.7874 -0.4064)
			(stroke
				(width 0.1524)
				(type default)
			)
			(layer "F.SilkS")
		)
		(fp_line
			(start 0.7874 0.4064)
			(end -0.7874 0.4064)
			(stroke
				(width 0.1524)
				(type default)
			)
			(layer "F.SilkS")
		)
		(fp_line
			(start -0.7874 -0.4064)
			(end 0.7874 -0.4064)
			(stroke
				(width 0.1524)
				(type default)
			)
			(layer "F.SilkS")
		)
		(fp_line
			(start 0.7874 -0.4064)
			(end 0.7874 0.4064)
			(stroke
				(width 0.1524)
				(type default)
			)
			(layer "F.SilkS")
		)
		(fp_line
			(start -0.67945 0.3048)
			(end -0.67945 -0.305054)
			(stroke
				(width 0.1)
				(type default)
			)
			(layer "F.Fab")
		)
		(fp_line
			(start -0.12065 0.3048)
			(end -0.67945 0.3048)
			(stroke
				(width 0.1)
				(type default)
			)
			(layer "F.Fab")
		)
		(fp_line
			(start 0.120396 0.3048)
			(end 0.120396 0.2794)
			(stroke
				(width 0.1)
				(type default)
			)
			(layer "F.Fab")
		)
		(fp_line
			(start 0.67945 0.3048)
			(end 0.120396 0.3048)
			(stroke
				(width 0.1)
				(type default)
			)
			(layer "F.Fab")
		)
		(fp_line
			(start -0.12065 0.2794)
			(end -0.12065 0.3048)
			(stroke
				(width 0.1)
				(type default)
			)
			(layer "F.Fab")
		)
		(fp_line
			(start 0.120396 0.2794)
			(end -0.12065 0.2794)
			(stroke
				(width 0.1)
				(type default)
			)
			(layer "F.Fab")
		)
		(fp_line
			(start -0.12065 -0.2794)
			(end 0.12065 -0.2794)
			(stroke
				(width 0.1)
				(type default)
			)
			(layer "F.Fab")
		)
		(fp_line
			(start 0.12065 -0.2794)
			(end 0.12065 -0.3048)
			(stroke
				(width 0.1)
				(type default)
			)
			(layer "F.Fab")
		)
		(fp_line
			(start 0.12065 -0.3048)
			(end 0.67945 -0.3048)
			(stroke
				(width 0.1)
				(type default)
			)
			(layer "F.Fab")
		)
		(fp_line
			(start 0.67945 -0.3048)
			(end 0.67945 0.3048)
			(stroke
				(width 0.1)
				(type default)
			)
			(layer "F.Fab")
		)
		(fp_line
			(start -0.67945 -0.305054)
			(end -0.12065 -0.305054)
			(stroke
				(width 0.1)
				(type default)
			)
			(layer "F.Fab")
		)
		(fp_line
			(start -0.12065 -0.305054)
			(end -0.12065 -0.2794)
			(stroke
				(width 0.1)
				(type default)
			)
			(layer "F.Fab")
		)
		(pad "1" smd circle
			(at -0.40005 0 270)
			(size 0 0)
			(layers "F.Cu" "F.Mask" "F.Paste")
			(net "P12V_SSD14_CO_GATE")
		)
		(pad "2" smd circle
			(at 0.40005 0 270)
			(size 0 0)
			(layers "F.Cu" "F.Mask" "F.Paste")
			(net "GND")
		)
	)
	(footprint ""
		(layer "F.Cu")
		(at 365.113824 -241.783108)
		(property "Reference" "R5891"
			(at 0 0 0)
			(layer "F.SilkS")
			(hide yes)
			(effects
				(font
					(size 1.27 1.27)
				)
			)
		)
		(property "Value" ""
			(at 0 0 0)
			(layer "F.Fab")
			(effects
				(font
					(size 1.27 1.27)
				)
			)
		)
		(duplicate_pad_numbers_are_jumpers no)
		(fp_line
			(start -0.7874 -0.4064)
			(end 0.7874 -0.4064)
			(stroke
				(width 0.1524)
				(type default)
			)
			(layer "F.SilkS")
		)
		(fp_line
			(start -0.7874 0.4064)
			(end -0.7874 -0.4064)
			(stroke
				(width 0.1524)
				(type default)
			)
			(layer "F.SilkS")
		)
		(fp_line
			(start 0.7874 -0.4064)
			(end 0.7874 0.4064)
			(stroke
				(width 0.1524)
				(type default)
			)
			(layer "F.SilkS")
		)
		(fp_line
			(start 0.7874 0.4064)
			(end -0.7874 0.4064)
			(stroke
				(width 0.1524)
				(type default)
			)
			(layer "F.SilkS")
		)
		(fp_line
			(start -0.67945 -0.305054)
			(end -0.12065 -0.305054)
			(stroke
				(width 0.1)
				(type default)
			)
			(layer "F.Fab")
		)
		(fp_line
			(start -0.67945 0.3048)
			(end -0.67945 -0.305054)
			(stroke
				(width 0.1)
				(type default)
			)
			(layer "F.Fab")
		)
		(fp_line
			(start -0.12065 -0.305054)
			(end -0.12065 -0.2794)
			(stroke
				(width 0.1)
				(type default)
			)
			(layer "F.Fab")
		)
		(fp_line
			(start -0.12065 -0.2794)
			(end 0.12065 -0.2794)
			(stroke
				(width 0.1)
				(type default)
			)
			(layer "F.Fab")
		)
		(fp_line
			(start -0.12065 0.2794)
			(end -0.12065 0.3048)
			(stroke
				(width 0.1)
				(type default)
			)
			(layer "F.Fab")
		)
		(fp_line
			(start -0.12065 0.3048)
			(end -0.67945 0.3048)
			(stroke
				(width 0.1)
				(type default)
			)
			(layer "F.Fab")
		)
		(fp_line
			(start 0.120396 0.2794)
			(end -0.12065 0.2794)
			(stroke
				(width 0.1)
				(type default)
			)
			(layer "F.Fab")
		)
		(fp_line
			(start 0.120396 0.3048)
			(end 0.120396 0.2794)
			(stroke
				(width 0.1)
				(type default)
			)
			(layer "F.Fab")
		)
		(fp_line
			(start 0.12065 -0.3048)
			(end 0.67945 -0.3048)
			(stroke
				(width 0.1)
				(type default)
			)
			(layer "F.Fab")
		)
		(fp_line
			(start 0.12065 -0.2794)
			(end 0.12065 -0.3048)
			(stroke
				(width 0.1)
				(type default)
			)
			(layer "F.Fab")
		)
		(fp_line
			(start 0.67945 -0.3048)
			(end 0.67945 0.3048)
			(stroke
				(width 0.1)
				(type default)
			)
			(layer "F.Fab")
		)
		(fp_line
			(start 0.67945 0.3048)
			(end 0.120396 0.3048)
			(stroke
				(width 0.1)
				(type default)
			)
			(layer "F.Fab")
		)
		(pad "1" smd circle
			(at -0.40005 0)
			(size 0 0)
			(layers "F.Cu" "F.Mask" "F.Paste")
			(net "JP_FPGA_LED")
		)
		(pad "2" smd circle
			(at 0.40005 0)
			(size 0 0)
			(layers "F.Cu" "F.Mask" "F.Paste")
			(net "P3V3_LED")
		)
	)
	(footprint ""
		(layer "F.Cu")
		(at 107.817666 -92.368878 90)
		(property "Reference" "R1134"
			(at 0 0 90)
			(layer "F.SilkS")
			(hide yes)
			(effects
				(font
					(size 1.27 1.27)
				)
			)
		)
		(property "Value" ""
			(at 0 0 90)
			(layer "F.Fab")
			(effects
				(font
					(size 1.27 1.27)
				)
			)
		)
		(duplicate_pad_numbers_are_jumpers no)
		(fp_line
			(start 0.7874 -0.4064)
			(end 0.7874 0.4064)
			(stroke
				(width 0.1524)
				(type default)
			)
			(layer "F.SilkS")
		)
		(fp_line
			(start -0.7874 -0.4064)
			(end 0.7874 -0.4064)
			(stroke
				(width 0.1524)
				(type default)
			)
			(layer "F.SilkS")
		)
		(fp_line
			(start 0.7874 0.4064)
			(end -0.7874 0.4064)
			(stroke
				(width 0.1524)
				(type default)
			)
			(layer "F.SilkS")
		)
		(fp_line
			(start -0.7874 0.4064)
			(end -0.7874 -0.4064)
			(stroke
				(width 0.1524)
				(type default)
			)
			(layer "F.SilkS")
		)
		(fp_line
			(start -0.12065 -0.305054)
			(end -0.12065 -0.2794)
			(stroke
				(width 0.1)
				(type default)
			)
			(layer "F.Fab")
		)
		(fp_line
			(start -0.67945 -0.305054)
			(end -0.12065 -0.305054)
			(stroke
				(width 0.1)
				(type default)
			)
			(layer "F.Fab")
		)
		(fp_line
			(start 0.67945 -0.3048)
			(end 0.67945 0.3048)
			(stroke
				(width 0.1)
				(type default)
			)
			(layer "F.Fab")
		)
		(fp_line
			(start 0.12065 -0.3048)
			(end 0.67945 -0.3048)
			(stroke
				(width 0.1)
				(type default)
			)
			(layer "F.Fab")
		)
		(fp_line
			(start 0.12065 -0.2794)
			(end 0.12065 -0.3048)
			(stroke
				(width 0.1)
				(type default)
			)
			(layer "F.Fab")
		)
		(fp_line
			(start -0.12065 -0.2794)
			(end 0.12065 -0.2794)
			(stroke
				(width 0.1)
				(type default)
			)
			(layer "F.Fab")
		)
		(fp_line
			(start 0.120396 0.2794)
			(end -0.12065 0.2794)
			(stroke
				(width 0.1)
				(type default)
			)
			(layer "F.Fab")
		)
		(fp_line
			(start -0.12065 0.2794)
			(end -0.12065 0.3048)
			(stroke
				(width 0.1)
				(type default)
			)
			(layer "F.Fab")
		)
		(fp_line
			(start 0.67945 0.3048)
			(end 0.120396 0.3048)
			(stroke
				(width 0.1)
				(type default)
			)
			(layer "F.Fab")
		)
		(fp_line
			(start 0.120396 0.3048)
			(end 0.120396 0.2794)
			(stroke
				(width 0.1)
				(type default)
			)
			(layer "F.Fab")
		)
		(fp_line
			(start -0.12065 0.3048)
			(end -0.67945 0.3048)
			(stroke
				(width 0.1)
				(type default)
			)
			(layer "F.Fab")
		)
		(fp_line
			(start -0.67945 0.3048)
			(end -0.67945 -0.305054)
			(stroke
				(width 0.1)
				(type default)
			)
			(layer "F.Fab")
		)
		(pad "1" smd circle
			(at -0.40005 0 90)
			(size 0 0)
			(layers "F.Cu" "F.Mask" "F.Paste")
			(net "PU_9ZXL0851_0_7_100M")
		)
		(pad "2" smd circle
			(at 0.40005 0 90)
			(size 0 0)
			(layers "F.Cu" "F.Mask" "F.Paste")
			(net "GND")
		)
	)
	(footprint ""
		(layer "F.Cu")
		(at 366.07496 -303.649634 90)
		(property "Reference" "PC198"
			(at 0 0 90)
			(layer "F.SilkS")
			(hide yes)
			(effects
				(font
					(size 1.27 1.27)
				)
			)
		)
		(property "Value" ""
			(at 0 0 90)
			(layer "F.Fab")
			(effects
				(font
					(size 1.27 1.27)
				)
			)
		)
		(duplicate_pad_numbers_are_jumpers no)
		(fp_line
			(start 1.524 -0.762)
			(end 1.524 0.762)
			(stroke
				(width 0.1524)
				(type default)
			)
			(layer "F.SilkS")
		)
		(fp_line
			(start -1.524 -0.762)
			(end 1.524 -0.762)
			(stroke
				(width 0.1524)
				(type default)
			)
			(layer "F.SilkS")
		)
		(fp_line
			(start 1.524 0.762)
			(end -1.524 0.762)
			(stroke
				(width 0.1524)
				(type default)
			)
			(layer "F.SilkS")
		)
		(fp_line
			(start -1.524 0.762)
			(end -1.524 -0.762)
			(stroke
				(width 0.1524)
				(type default)
			)
			(layer "F.SilkS")
		)
		(fp_line
			(start 1.1049 -0.724916)
			(end -1.1049 -0.724916)
			(stroke
				(width 0.1)
				(type default)
			)
			(layer "F.Fab")
		)
		(fp_line
			(start -1.1049 -0.724916)
			(end -1.1049 0.724916)
			(stroke
				(width 0.1)
				(type default)
			)
			(layer "F.Fab")
		)
		(fp_line
			(start 1.1049 0.724916)
			(end 1.1049 -0.724916)
			(stroke
				(width 0.1)
				(type default)
			)
			(layer "F.Fab")
		)
		(fp_line
			(start -1.1049 0.724916)
			(end 1.1049 0.724916)
			(stroke
				(width 0.1)
				(type default)
			)
			(layer "F.Fab")
		)
		(pad "1" smd rect
			(at -0.889 0 270)
			(size 1.016 1.27)
			(layers "F.Cu" "F.Mask" "F.Paste")
			(net "P0V8_PEX3")
		)
		(pad "2" smd rect
			(at 0.889 0 270)
			(size 1.016 1.27)
			(layers "F.Cu" "F.Mask" "F.Paste")
			(net "GND")
		)
	)
	(footprint ""
		(layer "F.Cu")
		(at 58.175398 -379.567694)
		(property "Reference" "C4037"
			(at 0 0 0)
			(layer "F.SilkS")
			(hide yes)
			(effects
				(font
					(size 1.27 1.27)
				)
			)
		)
		(property "Value" ""
			(at 0 0 0)
			(layer "F.Fab")
			(effects
				(font
					(size 1.27 1.27)
				)
			)
		)
		(duplicate_pad_numbers_are_jumpers no)
		(fp_line
			(start -0.7874 -0.4064)
			(end 0.7874 -0.4064)
			(stroke
				(width 0.1524)
				(type default)
			)
			(layer "F.SilkS")
		)
		(fp_line
			(start -0.7874 0.4064)
			(end -0.7874 -0.4064)
			(stroke
				(width 0.1524)
				(type default)
			)
			(layer "F.SilkS")
		)
		(fp_line
			(start 0.7874 -0.4064)
			(end 0.7874 0.4064)
			(stroke
				(width 0.1524)
				(type default)
			)
			(layer "F.SilkS")
		)
		(fp_line
			(start 0.7874 0.4064)
			(end -0.7874 0.4064)
			(stroke
				(width 0.1524)
				(type default)
			)
			(layer "F.SilkS")
		)
		(fp_line
			(start -0.67945 -0.305054)
			(end -0.12065 -0.305054)
			(stroke
				(width 0.1)
				(type default)
			)
			(layer "F.Fab")
		)
		(fp_line
			(start -0.67945 0.3048)
			(end -0.67945 -0.305054)
			(stroke
				(width 0.1)
				(type default)
			)
			(layer "F.Fab")
		)
		(fp_line
			(start -0.12065 -0.305054)
			(end -0.12065 -0.2794)
			(stroke
				(width 0.1)
				(type default)
			)
			(layer "F.Fab")
		)
		(fp_line
			(start -0.12065 -0.2794)
			(end 0.12065 -0.2794)
			(stroke
				(width 0.1)
				(type default)
			)
			(layer "F.Fab")
		)
		(fp_line
			(start -0.12065 0.2794)
			(end -0.12065 0.3048)
			(stroke
				(width 0.1)
				(type default)
			)
			(layer "F.Fab")
		)
		(fp_line
			(start -0.12065 0.3048)
			(end -0.67945 0.3048)
			(stroke
				(width 0.1)
				(type default)
			)
			(layer "F.Fab")
		)
		(fp_line
			(start 0.120396 0.2794)
			(end -0.12065 0.2794)
			(stroke
				(width 0.1)
				(type default)
			)
			(layer "F.Fab")
		)
		(fp_line
			(start 0.120396 0.3048)
			(end 0.120396 0.2794)
			(stroke
				(width 0.1)
				(type default)
			)
			(layer "F.Fab")
		)
		(fp_line
			(start 0.12065 -0.3048)
			(end 0.67945 -0.3048)
			(stroke
				(width 0.1)
				(type default)
			)
			(layer "F.Fab")
		)
		(fp_line
			(start 0.12065 -0.2794)
			(end 0.12065 -0.3048)
			(stroke
				(width 0.1)
				(type default)
			)
			(layer "F.Fab")
		)
		(fp_line
			(start 0.67945 -0.3048)
			(end 0.67945 0.3048)
			(stroke
				(width 0.1)
				(type default)
			)
			(layer "F.Fab")
		)
		(fp_line
			(start 0.67945 0.3048)
			(end 0.120396 0.3048)
			(stroke
				(width 0.1)
				(type default)
			)
			(layer "F.Fab")
		)
		(pad "1" smd circle
			(at -0.40005 0)
			(size 0 0)
			(layers "F.Cu" "F.Mask" "F.Paste")
			(net "GND")
		)
		(pad "2" smd circle
			(at 0.40005 0)
			(size 0 0)
			(layers "F.Cu" "F.Mask" "F.Paste")
			(net "GPU_BASE_ID1")
		)
	)
	(footprint ""
		(layer "F.Cu")
		(at 146.815302 -59.546236 90)
		(property "Reference" "C2888"
			(at 0 0 90)
			(layer "F.SilkS")
			(hide yes)
			(effects
				(font
					(size 1.27 1.27)
				)
			)
		)
		(property "Value" ""
			(at 0 0 90)
			(layer "F.Fab")
			(effects
				(font
					(size 1.27 1.27)
				)
			)
		)
		(duplicate_pad_numbers_are_jumpers no)
		(fp_line
			(start 0.7874 -0.4064)
			(end 0.7874 0.4064)
			(stroke
				(width 0.1524)
				(type default)
			)
			(layer "F.SilkS")
		)
		(fp_line
			(start -0.7874 -0.4064)
			(end 0.7874 -0.4064)
			(stroke
				(width 0.1524)
				(type default)
			)
			(layer "F.SilkS")
		)
		(fp_line
			(start 0.7874 0.4064)
			(end -0.7874 0.4064)
			(stroke
				(width 0.1524)
				(type default)
			)
			(layer "F.SilkS")
		)
		(fp_line
			(start -0.7874 0.4064)
			(end -0.7874 -0.4064)
			(stroke
				(width 0.1524)
				(type default)
			)
			(layer "F.SilkS")
		)
		(fp_line
			(start -0.12065 -0.305054)
			(end -0.12065 -0.2794)
			(stroke
				(width 0.1)
				(type default)
			)
			(layer "F.Fab")
		)
		(fp_line
			(start -0.67945 -0.305054)
			(end -0.12065 -0.305054)
			(stroke
				(width 0.1)
				(type default)
			)
			(layer "F.Fab")
		)
		(fp_line
			(start 0.67945 -0.3048)
			(end 0.67945 0.3048)
			(stroke
				(width 0.1)
				(type default)
			)
			(layer "F.Fab")
		)
		(fp_line
			(start 0.12065 -0.3048)
			(end 0.67945 -0.3048)
			(stroke
				(width 0.1)
				(type default)
			)
			(layer "F.Fab")
		)
		(fp_line
			(start 0.12065 -0.2794)
			(end 0.12065 -0.3048)
			(stroke
				(width 0.1)
				(type default)
			)
			(layer "F.Fab")
		)
		(fp_line
			(start -0.12065 -0.2794)
			(end 0.12065 -0.2794)
			(stroke
				(width 0.1)
				(type default)
			)
			(layer "F.Fab")
		)
		(fp_line
			(start 0.120396 0.2794)
			(end -0.12065 0.2794)
			(stroke
				(width 0.1)
				(type default)
			)
			(layer "F.Fab")
		)
		(fp_line
			(start -0.12065 0.2794)
			(end -0.12065 0.3048)
			(stroke
				(width 0.1)
				(type default)
			)
			(layer "F.Fab")
		)
		(fp_line
			(start 0.67945 0.3048)
			(end 0.120396 0.3048)
			(stroke
				(width 0.1)
				(type default)
			)
			(layer "F.Fab")
		)
		(fp_line
			(start 0.120396 0.3048)
			(end 0.120396 0.2794)
			(stroke
				(width 0.1)
				(type default)
			)
			(layer "F.Fab")
		)
		(fp_line
			(start -0.12065 0.3048)
			(end -0.67945 0.3048)
			(stroke
				(width 0.1)
				(type default)
			)
			(layer "F.Fab")
		)
		(fp_line
			(start -0.67945 0.3048)
			(end -0.67945 -0.305054)
			(stroke
				(width 0.1)
				(type default)
			)
			(layer "F.Fab")
		)
		(pad "1" smd circle
			(at -0.40005 0 90)
			(size 0 0)
			(layers "F.Cu" "F.Mask" "F.Paste")
			(net "SSD5_AUX_P3V3_EN_R")
		)
		(pad "2" smd circle
			(at 0.40005 0 90)
			(size 0 0)
			(layers "F.Cu" "F.Mask" "F.Paste")
			(net "GND")
		)
	)
	(footprint ""
		(layer "F.Cu")
		(at 394.425424 -42.849038 180)
		(property "Reference" "R656"
			(at 0 0 180)
			(layer "F.SilkS")
			(hide yes)
			(effects
				(font
					(size 1.27 1.27)
				)
			)
		)
		(property "Value" ""
			(at 0 0 180)
			(layer "F.Fab")
			(effects
				(font
					(size 1.27 1.27)
				)
			)
		)
		(duplicate_pad_numbers_are_jumpers no)
		(fp_line
			(start 0.7874 0.4064)
			(end -0.7874 0.4064)
			(stroke
				(width 0.1524)
				(type default)
			)
			(layer "F.SilkS")
		)
		(fp_line
			(start 0.7874 -0.4064)
			(end 0.7874 0.4064)
			(stroke
				(width 0.1524)
				(type default)
			)
			(layer "F.SilkS")
		)
		(fp_line
			(start -0.7874 0.4064)
			(end -0.7874 -0.4064)
			(stroke
				(width 0.1524)
				(type default)
			)
			(layer "F.SilkS")
		)
		(fp_line
			(start -0.7874 -0.4064)
			(end 0.7874 -0.4064)
			(stroke
				(width 0.1524)
				(type default)
			)
			(layer "F.SilkS")
		)
		(fp_line
			(start 0.67945 0.3048)
			(end 0.120396 0.3048)
			(stroke
				(width 0.1)
				(type default)
			)
			(layer "F.Fab")
		)
		(fp_line
			(start 0.67945 -0.3048)
			(end 0.67945 0.3048)
			(stroke
				(width 0.1)
				(type default)
			)
			(layer "F.Fab")
		)
		(fp_line
			(start 0.12065 -0.2794)
			(end 0.12065 -0.3048)
			(stroke
				(width 0.1)
				(type default)
			)
			(layer "F.Fab")
		)
		(fp_line
			(start 0.12065 -0.3048)
			(end 0.67945 -0.3048)
			(stroke
				(width 0.1)
				(type default)
			)
			(layer "F.Fab")
		)
		(fp_line
			(start 0.120396 0.3048)
			(end 0.120396 0.2794)
			(stroke
				(width 0.1)
				(type default)
			)
			(layer "F.Fab")
		)
		(fp_line
			(start 0.120396 0.2794)
			(end -0.12065 0.2794)
			(stroke
				(width 0.1)
				(type default)
			)
			(layer "F.Fab")
		)
		(fp_line
			(start -0.12065 0.3048)
			(end -0.67945 0.3048)
			(stroke
				(width 0.1)
				(type default)
			)
			(layer "F.Fab")
		)
		(fp_line
			(start -0.12065 0.2794)
			(end -0.12065 0.3048)
			(stroke
				(width 0.1)
				(type default)
			)
			(layer "F.Fab")
		)
		(fp_line
			(start -0.12065 -0.2794)
			(end 0.12065 -0.2794)
			(stroke
				(width 0.1)
				(type default)
			)
			(layer "F.Fab")
		)
		(fp_line
			(start -0.12065 -0.305054)
			(end -0.12065 -0.2794)
			(stroke
				(width 0.1)
				(type default)
			)
			(layer "F.Fab")
		)
		(fp_line
			(start -0.67945 0.3048)
			(end -0.67945 -0.305054)
			(stroke
				(width 0.1)
				(type default)
			)
			(layer "F.Fab")
		)
		(fp_line
			(start -0.67945 -0.305054)
			(end -0.12065 -0.305054)
			(stroke
				(width 0.1)
				(type default)
			)
			(layer "F.Fab")
		)
		(pad "1" smd circle
			(at -0.40005 0 180)
			(size 0 0)
			(layers "F.Cu" "F.Mask" "F.Paste")
			(net "P12V_SSD13_R")
		)
		(pad "2" smd circle
			(at 0.40005 0 180)
			(size 0 0)
			(layers "F.Cu" "F.Mask" "F.Paste")
			(net "P12V_SSD13_VIN_P")
		)
	)
	(footprint ""
		(layer "F.Cu")
		(at 446.875408 -69.47916 180)
		(property "Reference" "PU118"
			(at -1.943862 4.07924 90)
			(unlocked yes)
			(layer "F.SilkS")
			(effects
				(font
					(size 0.7874 0.5842)
					(thickness 0.1524)
				)
			)
		)
		(property "Value" ""
			(at 0 0 180)
			(layer "F.Fab")
			(effects
				(font
					(size 1.27 1.27)
				)
			)
		)
		(duplicate_pad_numbers_are_jumpers no)
		(fp_line
			(start 1.239774 1.495298)
			(end -1.239774 1.495298)
			(stroke
				(width 0.1524)
				(type default)
			)
			(layer "F.SilkS")
		)
		(fp_line
			(start 1.239774 -1.495298)
			(end 1.239774 1.495298)
			(stroke
				(width 0.1524)
				(type default)
			)
			(layer "F.SilkS")
		)
		(fp_line
			(start -1.239774 1.495298)
			(end -1.239774 -1.495298)
			(stroke
				(width 0.1524)
				(type default)
			)
			(layer "F.SilkS")
		)
		(fp_line
			(start -1.239774 -1.495298)
			(end 1.239774 -1.495298)
			(stroke
				(width 0.1524)
				(type default)
			)
			(layer "F.SilkS")
		)
		(fp_poly
			(pts
				(xy -1.739392 -1.187958) (xy -2.457704 -0.469392) (xy -1.380236 -0.110236)
			)
			(stroke
				(width 0)
				(type default)
			)
			(fill yes)
			(layer "F.SilkS")
		)
		(fp_line
			(start 0.8001 1.050036)
			(end -0.8001 1.050036)
			(stroke
				(width 0.1)
				(type default)
			)
			(layer "F.Fab")
		)
		(fp_line
			(start 0.8001 -1.050036)
			(end 0.8001 1.050036)
			(stroke
				(width 0.1)
				(type default)
			)
			(layer "F.Fab")
		)
		(fp_line
			(start -0.8001 1.050036)
			(end -0.8001 -1.050036)
			(stroke
				(width 0.1)
				(type default)
			)
			(layer "F.Fab")
		)
		(fp_line
			(start -0.8001 -1.050036)
			(end 0.8001 -1.050036)
			(stroke
				(width 0.1)
				(type default)
			)
			(layer "F.Fab")
		)
		(fp_poly
			(pts
				(xy -2.458974 -0.508) (xy -2.458974 0.508) (xy -1.442974 0)
			)
			(stroke
				(width 0)
				(type default)
			)
			(fill yes)
			(layer "F.Fab")
		)
		(pad "1_2" smd circle
			(at -0.374904 0 270)
			(size 0 0)
			(layers "F.Cu" "F.Mask" "F.Paste")
			(net "P12V_AUX")
		)
		(pad "3" smd rect
			(at -0.499872 0.999998 180)
			(size 0.254 0.7112)
			(layers "F.Cu" "F.Mask" "F.Paste")
			(net "GND")
		)
		(pad "4" smd rect
			(at 0 0.999998 180)
			(size 0.254 0.7112)
			(layers "F.Cu" "F.Mask" "F.Paste")
			(net "P12V_SSD15_CO_ILIMIT")
		)
		(pad "5" smd rect
			(at 0.499872 0.999998 180)
			(size 0.254 0.7112)
			(layers "F.Cu" "F.Mask" "F.Paste")
			(net "P12V_SSD15_CO_MODE")
		)
		(pad "6_7" smd circle
			(at 0.374904 0 90)
			(size 0 0)
			(layers "F.Cu" "F.Mask" "F.Paste")
			(net "P12V_SSD15_R")
		)
		(pad "8" smd rect
			(at 0.499872 -0.999998 180)
			(size 0.254 0.7112)
			(layers "F.Cu" "F.Mask" "F.Paste")
			(net "P12V_SSD15_CO_GATE")
		)
		(pad "9" smd rect
			(at 0 -0.999998 180)
			(size 0.254 0.7112)
			(layers "F.Cu" "F.Mask" "F.Paste")
			(net "P12V_SSD15_CO_EN")
		)
		(pad "10" smd rect
			(at -0.499872 -0.999998 180)
			(size 0.254 0.7112)
			(layers "F.Cu" "F.Mask" "F.Paste")
			(net "P12V_SSD15_CO_DV_DT")
		)
	)
	(footprint ""
		(layer "F.Cu")
		(at 89.602818 -302.666146 180)
		(property "Reference" "R6659"
			(at 0 0 180)
			(layer "F.SilkS")
			(hide yes)
			(effects
				(font
					(size 1.27 1.27)
				)
			)
		)
		(property "Value" ""
			(at 0 0 180)
			(layer "F.Fab")
			(effects
				(font
					(size 1.27 1.27)
				)
			)
		)
		(duplicate_pad_numbers_are_jumpers no)
		(fp_line
			(start 0.7874 0.4064)
			(end -0.7874 0.4064)
			(stroke
				(width 0.1524)
				(type default)
			)
			(layer "F.SilkS")
		)
		(fp_line
			(start 0.7874 -0.4064)
			(end 0.7874 0.4064)
			(stroke
				(width 0.1524)
				(type default)
			)
			(layer "F.SilkS")
		)
		(fp_line
			(start -0.7874 0.4064)
			(end -0.7874 -0.4064)
			(stroke
				(width 0.1524)
				(type default)
			)
			(layer "F.SilkS")
		)
		(fp_line
			(start -0.7874 -0.4064)
			(end 0.7874 -0.4064)
			(stroke
				(width 0.1524)
				(type default)
			)
			(layer "F.SilkS")
		)
		(fp_line
			(start 0.67945 0.3048)
			(end 0.120396 0.3048)
			(stroke
				(width 0.1)
				(type default)
			)
			(layer "F.Fab")
		)
		(fp_line
			(start 0.67945 -0.3048)
			(end 0.67945 0.3048)
			(stroke
				(width 0.1)
				(type default)
			)
			(layer "F.Fab")
		)
		(fp_line
			(start 0.12065 -0.2794)
			(end 0.12065 -0.3048)
			(stroke
				(width 0.1)
				(type default)
			)
			(layer "F.Fab")
		)
		(fp_line
			(start 0.12065 -0.3048)
			(end 0.67945 -0.3048)
			(stroke
				(width 0.1)
				(type default)
			)
			(layer "F.Fab")
		)
		(fp_line
			(start 0.120396 0.3048)
			(end 0.120396 0.2794)
			(stroke
				(width 0.1)
				(type default)
			)
			(layer "F.Fab")
		)
		(fp_line
			(start 0.120396 0.2794)
			(end -0.12065 0.2794)
			(stroke
				(width 0.1)
				(type default)
			)
			(layer "F.Fab")
		)
		(fp_line
			(start -0.12065 0.3048)
			(end -0.67945 0.3048)
			(stroke
				(width 0.1)
				(type default)
			)
			(layer "F.Fab")
		)
		(fp_line
			(start -0.12065 0.2794)
			(end -0.12065 0.3048)
			(stroke
				(width 0.1)
				(type default)
			)
			(layer "F.Fab")
		)
		(fp_line
			(start -0.12065 -0.2794)
			(end 0.12065 -0.2794)
			(stroke
				(width 0.1)
				(type default)
			)
			(layer "F.Fab")
		)
		(fp_line
			(start -0.12065 -0.305054)
			(end -0.12065 -0.2794)
			(stroke
				(width 0.1)
				(type default)
			)
			(layer "F.Fab")
		)
		(fp_line
			(start -0.67945 0.3048)
			(end -0.67945 -0.305054)
			(stroke
				(width 0.1)
				(type default)
			)
			(layer "F.Fab")
		)
		(fp_line
			(start -0.67945 -0.305054)
			(end -0.12065 -0.305054)
			(stroke
				(width 0.1)
				(type default)
			)
			(layer "F.Fab")
		)
		(pad "1" smd circle
			(at -0.40005 0 180)
			(size 0 0)
			(layers "F.Cu" "F.Mask" "F.Paste")
			(net "SMB_PEX0_SLAVE1_SDA")
		)
		(pad "2" smd circle
			(at 0.40005 0 180)
			(size 0 0)
			(layers "F.Cu" "F.Mask" "F.Paste")
			(net "SMB_PEX0_R_SDA")
		)
	)
	(footprint ""
		(layer "F.Cu")
		(at 263.594088 -29.507688 -90)
		(property "Reference" "PC943"
			(at 0 0 270)
			(layer "F.SilkS")
			(hide yes)
			(effects
				(font
					(size 1.27 1.27)
				)
			)
		)
		(property "Value" ""
			(at 0 0 270)
			(layer "F.Fab")
			(effects
				(font
					(size 1.27 1.27)
				)
			)
		)
		(duplicate_pad_numbers_are_jumpers no)
		(fp_line
			(start -1.524 0.762)
			(end -1.524 -0.762)
			(stroke
				(width 0.1524)
				(type default)
			)
			(layer "F.SilkS")
		)
		(fp_line
			(start 1.524 0.762)
			(end -1.524 0.762)
			(stroke
				(width 0.1524)
				(type default)
			)
			(layer "F.SilkS")
		)
		(fp_line
			(start -1.524 -0.762)
			(end 1.524 -0.762)
			(stroke
				(width 0.1524)
				(type default)
			)
			(layer "F.SilkS")
		)
		(fp_line
			(start 1.524 -0.762)
			(end 1.524 0.762)
			(stroke
				(width 0.1524)
				(type default)
			)
			(layer "F.SilkS")
		)
		(fp_line
			(start -1.1049 0.724916)
			(end 1.1049 0.724916)
			(stroke
				(width 0.1)
				(type default)
			)
			(layer "F.Fab")
		)
		(fp_line
			(start 1.1049 0.724916)
			(end 1.1049 -0.724916)
			(stroke
				(width 0.1)
				(type default)
			)
			(layer "F.Fab")
		)
		(fp_line
			(start -1.1049 -0.724916)
			(end -1.1049 0.724916)
			(stroke
				(width 0.1)
				(type default)
			)
			(layer "F.Fab")
		)
		(fp_line
			(start 1.1049 -0.724916)
			(end -1.1049 -0.724916)
			(stroke
				(width 0.1)
				(type default)
			)
			(layer "F.Fab")
		)
		(pad "1" smd rect
			(at -0.889 0 90)
			(size 1.016 1.27)
			(layers "F.Cu" "F.Mask" "F.Paste")
			(net "P3V3_SSD9")
		)
		(pad "2" smd rect
			(at 0.889 0 90)
			(size 1.016 1.27)
			(layers "F.Cu" "F.Mask" "F.Paste")
			(net "GND")
		)
	)
	(footprint ""
		(layer "F.Cu")
		(at 455.14006 -308.692042 180)
		(property "Reference" "PU19"
			(at 3.652012 -4.026662 0)
			(unlocked yes)
			(layer "F.SilkS")
			(effects
				(font
					(size 0.7874 0.5842)
					(thickness 0.1524)
				)
				(justify left)
			)
		)
		(property "Value" ""
			(at 0 0 180)
			(layer "F.Fab")
			(effects
				(font
					(size 1.27 1.27)
				)
			)
		)
		(duplicate_pad_numbers_are_jumpers no)
		(fp_line
			(start 1.549908 2.050034)
			(end 1.549908 1.9304)
			(stroke
				(width 0.1524)
				(type default)
			)
			(layer "F.SilkS")
		)
		(fp_line
			(start 1.549908 -1.9812)
			(end 1.549908 -2.050034)
			(stroke
				(width 0.1524)
				(type default)
			)
			(layer "F.SilkS")
		)
		(fp_line
			(start 1.549908 -2.050034)
			(end 0.5842 -2.050034)
			(stroke
				(width 0.1524)
				(type default)
			)
			(layer "F.SilkS")
		)
		(fp_line
			(start 0.3048 -2.4638)
			(end 0.3048 -3.2258)
			(stroke
				(width 0.1524)
				(type default)
			)
			(layer "F.SilkS")
		)
		(fp_line
			(start 0 2.050034)
			(end 1.549908 2.050034)
			(stroke
				(width 0.1524)
				(type default)
			)
			(layer "F.SilkS")
		)
		(fp_line
			(start -0.3048 2.4638)
			(end -0.3048 3.2258)
			(stroke
				(width 0.1524)
				(type default)
			)
			(layer "F.SilkS")
		)
		(fp_line
			(start -0.5842 -2.050034)
			(end -1.549908 -2.050034)
			(stroke
				(width 0.1524)
				(type default)
			)
			(layer "F.SilkS")
		)
		(fp_line
			(start -1.549908 2.050034)
			(end -0.5842 2.050034)
			(stroke
				(width 0.1524)
				(type default)
			)
			(layer "F.SilkS")
		)
		(fp_line
			(start -1.549908 1.9812)
			(end -1.549908 2.050034)
			(stroke
				(width 0.1524)
				(type default)
			)
			(layer "F.SilkS")
		)
		(fp_line
			(start -1.549908 -2.050034)
			(end -1.549908 -1.9812)
			(stroke
				(width 0.1524)
				(type default)
			)
			(layer "F.SilkS")
		)
		(fp_line
			(start -1.9812 0)
			(end -2.3622 0)
			(stroke
				(width 0.1524)
				(type default)
			)
			(layer "F.SilkS")
		)
		(fp_poly
			(pts
				(xy -2.9464 -2.208022) (xy -2.9464 -1.192022) (xy -1.9304 -1.700022)
			)
			(stroke
				(width 0)
				(type default)
			)
			(fill yes)
			(layer "F.SilkS")
		)
		(fp_line
			(start 1.549908 2.050034)
			(end 1.549908 -2.050034)
			(stroke
				(width 0.1)
				(type default)
			)
			(layer "F.Fab")
		)
		(fp_line
			(start 1.549908 -2.050034)
			(end -1.549908 -2.050034)
			(stroke
				(width 0.1)
				(type default)
			)
			(layer "F.Fab")
		)
		(fp_line
			(start 0.3048 -2.4638)
			(end 0.3048 -3.2258)
			(stroke
				(width 0.1)
				(type default)
			)
			(layer "F.Fab")
		)
		(fp_line
			(start -0.3048 2.4638)
			(end -0.3048 3.2258)
			(stroke
				(width 0.1)
				(type default)
			)
			(layer "F.Fab")
		)
		(fp_line
			(start -1.549908 2.050034)
			(end 1.549908 2.050034)
			(stroke
				(width 0.1)
				(type default)
			)
			(layer "F.Fab")
		)
		(fp_line
			(start -1.549908 -2.050034)
			(end -1.549908 2.050034)
			(stroke
				(width 0.1)
				(type default)
			)
			(layer "F.Fab")
		)
		(fp_line
			(start -1.9812 0)
			(end -2.3622 0)
			(stroke
				(width 0.1)
				(type default)
			)
			(layer "F.Fab")
		)
		(fp_poly
			(pts
				(xy -2.9464 -2.208022) (xy -2.9464 -1.192022) (xy -1.9304 -1.700022)
			)
			(stroke
				(width 0)
				(type default)
			)
			(fill yes)
			(layer "F.Fab")
		)
		(fp_text user "11_18"
			(at 2.512568 0.9906 90)
			(unlocked yes)
			(layer "F.SilkS")
			(effects
				(font
					(size 0.635 0.4064)
					(thickness 0.1524)
				)
			)
		)
		(fp_text user "19"
			(at 1.952498 -2.562606 90)
			(unlocked yes)
			(layer "F.SilkS")
			(effects
				(font
					(size 0.635 0.4064)
					(thickness 0.1524)
				)
			)
		)
		(fp_text user "9"
			(at -2.338832 2.0574 90)
			(unlocked yes)
			(layer "F.SilkS")
			(effects
				(font
					(size 0.635 0.4064)
					(thickness 0.1524)
				)
			)
		)
		(fp_text user "11_18"
			(at 2.512568 0.9906 90)
			(unlocked yes)
			(layer "F.Fab")
			(effects
				(font
					(size 0.635 0.4064)
					(thickness 0.1524)
				)
			)
		)
		(fp_text user "19"
			(at 2.410968 -2.159 90)
			(unlocked yes)
			(layer "F.Fab")
			(effects
				(font
					(size 0.635 0.4064)
					(thickness 0.1524)
				)
			)
		)
		(fp_text user "9"
			(at -2.338832 2.0574 90)
			(unlocked yes)
			(layer "F.Fab")
			(effects
				(font
					(size 0.635 0.4064)
					(thickness 0.1524)
				)
			)
		)
		(pad "1" smd rect
			(at -1.35001 -1.700022 270)
			(size 0.3048 0.9144)
			(layers "F.Cu" "F.Mask" "F.Paste")
			(net "SW_P1V25_PEX3_BT")
		)
		(pad "2" smd rect
			(at -1.400048 -1.199896 270)
			(size 0.1778 0.8128)
			(layers "F.Cu" "F.Mask" "F.Paste")
			(net "GND")
		)
		(pad "3" smd rect
			(at -1.400048 -0.8001 270)
			(size 0.1778 0.8128)
			(layers "F.Cu" "F.Mask" "F.Paste")
			(net "P1V25_PEX3_CS")
		)
		(pad "4" smd rect
			(at -1.400048 -0.40005 270)
			(size 0.1778 0.8128)
			(layers "F.Cu" "F.Mask" "F.Paste")
			(net "GND")
		)
		(pad "5" smd rect
			(at -1.400048 0 270)
			(size 0.1778 0.8128)
			(layers "F.Cu" "F.Mask" "F.Paste")
			(net "P1V25_PEX3_REF")
		)
		(pad "6" smd rect
			(at -1.400048 0.40005 270)
			(size 0.1778 0.8128)
			(layers "F.Cu" "F.Mask" "F.Paste")
			(net "SH_P1V25_PEX3_FB_N")
		)
		(pad "7" smd rect
			(at -1.400048 0.8001 270)
			(size 0.1778 0.8128)
			(layers "F.Cu" "F.Mask" "F.Paste")
			(net "P1V25_PEX3_FB")
		)
		(pad "8" smd rect
			(at -1.400048 1.199896 270)
			(size 0.1778 0.8128)
			(layers "F.Cu" "F.Mask" "F.Paste")
			(net "P1V25_PEX3_EN")
		)
		(pad "9" smd rect
			(at -1.400048 1.700022 270)
			(size 0.3048 0.8128)
			(layers "F.Cu" "F.Mask" "F.Paste")
			(net "PWRGD_P1V25_PEX3")
		)
		(pad "10" smd rect
			(at -0.299974 1.299972 180)
			(size 0.3048 2.0066)
			(layers "F.Cu" "F.Mask" "F.Paste")
			(net "SW_P12V_P1V25_PEX3_FLT")
		)
		(pad "11_18" smd circle
			(at 1.175004 0.275082 180)
			(size 0 0)
			(layers "F.Cu" "F.Mask" "F.Paste")
			(net "GND")
		)
		(pad "19" smd rect
			(at 1.400048 -1.700022 90)
			(size 0.3048 0.8128)
			(layers "F.Cu" "F.Mask" "F.Paste")
			(net "P1V25_PEX3_VCC")
		)
		(pad "20" smd rect
			(at 0.299974 -1.299972 180)
			(size 0.3048 2.0066)
			(layers "F.Cu" "F.Mask" "F.Paste")
			(net "SW_P1V25_PEX3_PH")
		)
		(pad "21" smd rect
			(at -0.299974 -1.299972 180)
			(size 0.3048 2.0066)
			(layers "F.Cu" "F.Mask" "F.Paste")
			(net "SW_P12V_P1V25_PEX3_FLT")
		)
	)
	(footprint ""
		(layer "F.Cu")
		(at 37.550344 -250.070874 -90)
		(property "Reference" "R1164"
			(at 0 0 270)
			(layer "F.SilkS")
			(hide yes)
			(effects
				(font
					(size 1.27 1.27)
				)
			)
		)
		(property "Value" ""
			(at 0 0 270)
			(layer "F.Fab")
			(effects
				(font
					(size 1.27 1.27)
				)
			)
		)
		(duplicate_pad_numbers_are_jumpers no)
		(fp_line
			(start -0.7874 0.4064)
			(end -0.7874 -0.4064)
			(stroke
				(width 0.1524)
				(type default)
			)
			(layer "F.SilkS")
		)
		(fp_line
			(start 0.7874 0.4064)
			(end -0.7874 0.4064)
			(stroke
				(width 0.1524)
				(type default)
			)
			(layer "F.SilkS")
		)
		(fp_line
			(start -0.7874 -0.4064)
			(end 0.7874 -0.4064)
			(stroke
				(width 0.1524)
				(type default)
			)
			(layer "F.SilkS")
		)
		(fp_line
			(start 0.7874 -0.4064)
			(end 0.7874 0.4064)
			(stroke
				(width 0.1524)
				(type default)
			)
			(layer "F.SilkS")
		)
		(fp_line
			(start -0.67945 0.3048)
			(end -0.67945 -0.305054)
			(stroke
				(width 0.1)
				(type default)
			)
			(layer "F.Fab")
		)
		(fp_line
			(start -0.12065 0.3048)
			(end -0.67945 0.3048)
			(stroke
				(width 0.1)
				(type default)
			)
			(layer "F.Fab")
		)
		(fp_line
			(start 0.120396 0.3048)
			(end 0.120396 0.2794)
			(stroke
				(width 0.1)
				(type default)
			)
			(layer "F.Fab")
		)
		(fp_line
			(start 0.67945 0.3048)
			(end 0.120396 0.3048)
			(stroke
				(width 0.1)
				(type default)
			)
			(layer "F.Fab")
		)
		(fp_line
			(start -0.12065 0.2794)
			(end -0.12065 0.3048)
			(stroke
				(width 0.1)
				(type default)
			)
			(layer "F.Fab")
		)
		(fp_line
			(start 0.120396 0.2794)
			(end -0.12065 0.2794)
			(stroke
				(width 0.1)
				(type default)
			)
			(layer "F.Fab")
		)
		(fp_line
			(start -0.12065 -0.2794)
			(end 0.12065 -0.2794)
			(stroke
				(width 0.1)
				(type default)
			)
			(layer "F.Fab")
		)
		(fp_line
			(start 0.12065 -0.2794)
			(end 0.12065 -0.3048)
			(stroke
				(width 0.1)
				(type default)
			)
			(layer "F.Fab")
		)
		(fp_line
			(start 0.12065 -0.3048)
			(end 0.67945 -0.3048)
			(stroke
				(width 0.1)
				(type default)
			)
			(layer "F.Fab")
		)
		(fp_line
			(start 0.67945 -0.3048)
			(end 0.67945 0.3048)
			(stroke
				(width 0.1)
				(type default)
			)
			(layer "F.Fab")
		)
		(fp_line
			(start -0.67945 -0.305054)
			(end -0.12065 -0.305054)
			(stroke
				(width 0.1)
				(type default)
			)
			(layer "F.Fab")
		)
		(fp_line
			(start -0.12065 -0.305054)
			(end -0.12065 -0.2794)
			(stroke
				(width 0.1)
				(type default)
			)
			(layer "F.Fab")
		)
		(pad "1" smd circle
			(at -0.40005 0 270)
			(size 0 0)
			(layers "F.Cu" "F.Mask" "F.Paste")
			(net "PEX0_MODE_SEL10")
		)
		(pad "2" smd circle
			(at 0.40005 0 270)
			(size 0 0)
			(layers "F.Cu" "F.Mask" "F.Paste")
			(net "P1V8_PEX")
		)
	)
	(footprint ""
		(layer "F.Cu")
		(at 382.802384 -250.070874 -90)
		(property "Reference" "R1416"
			(at 0 0 270)
			(layer "F.SilkS")
			(hide yes)
			(effects
				(font
					(size 1.27 1.27)
				)
			)
		)
		(property "Value" ""
			(at 0 0 270)
			(layer "F.Fab")
			(effects
				(font
					(size 1.27 1.27)
				)
			)
		)
		(duplicate_pad_numbers_are_jumpers no)
		(fp_line
			(start -0.7874 0.4064)
			(end -0.7874 -0.4064)
			(stroke
				(width 0.1524)
				(type default)
			)
			(layer "F.SilkS")
		)
		(fp_line
			(start 0.7874 0.4064)
			(end -0.7874 0.4064)
			(stroke
				(width 0.1524)
				(type default)
			)
			(layer "F.SilkS")
		)
		(fp_line
			(start -0.7874 -0.4064)
			(end 0.7874 -0.4064)
			(stroke
				(width 0.1524)
				(type default)
			)
			(layer "F.SilkS")
		)
		(fp_line
			(start 0.7874 -0.4064)
			(end 0.7874 0.4064)
			(stroke
				(width 0.1524)
				(type default)
			)
			(layer "F.SilkS")
		)
		(fp_line
			(start -0.67945 0.3048)
			(end -0.67945 -0.305054)
			(stroke
				(width 0.1)
				(type default)
			)
			(layer "F.Fab")
		)
		(fp_line
			(start -0.12065 0.3048)
			(end -0.67945 0.3048)
			(stroke
				(width 0.1)
				(type default)
			)
			(layer "F.Fab")
		)
		(fp_line
			(start 0.120396 0.3048)
			(end 0.120396 0.2794)
			(stroke
				(width 0.1)
				(type default)
			)
			(layer "F.Fab")
		)
		(fp_line
			(start 0.67945 0.3048)
			(end 0.120396 0.3048)
			(stroke
				(width 0.1)
				(type default)
			)
			(layer "F.Fab")
		)
		(fp_line
			(start -0.12065 0.2794)
			(end -0.12065 0.3048)
			(stroke
				(width 0.1)
				(type default)
			)
			(layer "F.Fab")
		)
		(fp_line
			(start 0.120396 0.2794)
			(end -0.12065 0.2794)
			(stroke
				(width 0.1)
				(type default)
			)
			(layer "F.Fab")
		)
		(fp_line
			(start -0.12065 -0.2794)
			(end 0.12065 -0.2794)
			(stroke
				(width 0.1)
				(type default)
			)
			(layer "F.Fab")
		)
		(fp_line
			(start 0.12065 -0.2794)
			(end 0.12065 -0.3048)
			(stroke
				(width 0.1)
				(type default)
			)
			(layer "F.Fab")
		)
		(fp_line
			(start 0.12065 -0.3048)
			(end 0.67945 -0.3048)
			(stroke
				(width 0.1)
				(type default)
			)
			(layer "F.Fab")
		)
		(fp_line
			(start 0.67945 -0.3048)
			(end 0.67945 0.3048)
			(stroke
				(width 0.1)
				(type default)
			)
			(layer "F.Fab")
		)
		(fp_line
			(start -0.67945 -0.305054)
			(end -0.12065 -0.305054)
			(stroke
				(width 0.1)
				(type default)
			)
			(layer "F.Fab")
		)
		(fp_line
			(start -0.12065 -0.305054)
			(end -0.12065 -0.2794)
			(stroke
				(width 0.1)
				(type default)
			)
			(layer "F.Fab")
		)
		(pad "1" smd circle
			(at -0.40005 0 270)
			(size 0 0)
			(layers "F.Cu" "F.Mask" "F.Paste")
			(net "PEX3_MODE_SEL11")
		)
		(pad "2" smd circle
			(at 0.40005 0 270)
			(size 0 0)
			(layers "F.Cu" "F.Mask" "F.Paste")
			(net "P1V8_PEX")
		)
	)
	(footprint ""
		(layer "F.Cu")
		(at 357.495094 -59.577986 90)
		(property "Reference" "PC555"
			(at 0 0 90)
			(layer "F.SilkS")
			(hide yes)
			(effects
				(font
					(size 1.27 1.27)
				)
			)
		)
		(property "Value" ""
			(at 0 0 90)
			(layer "F.Fab")
			(effects
				(font
					(size 1.27 1.27)
				)
			)
		)
		(duplicate_pad_numbers_are_jumpers no)
		(fp_line
			(start 0.7874 -0.4064)
			(end 0.7874 0.4064)
			(stroke
				(width 0.1524)
				(type default)
			)
			(layer "F.SilkS")
		)
		(fp_line
			(start -0.7874 -0.4064)
			(end 0.7874 -0.4064)
			(stroke
				(width 0.1524)
				(type default)
			)
			(layer "F.SilkS")
		)
		(fp_line
			(start 0.7874 0.4064)
			(end -0.7874 0.4064)
			(stroke
				(width 0.1524)
				(type default)
			)
			(layer "F.SilkS")
		)
		(fp_line
			(start -0.7874 0.4064)
			(end -0.7874 -0.4064)
			(stroke
				(width 0.1524)
				(type default)
			)
			(layer "F.SilkS")
		)
		(fp_line
			(start -0.12065 -0.305054)
			(end -0.12065 -0.2794)
			(stroke
				(width 0.1)
				(type default)
			)
			(layer "F.Fab")
		)
		(fp_line
			(start -0.67945 -0.305054)
			(end -0.12065 -0.305054)
			(stroke
				(width 0.1)
				(type default)
			)
			(layer "F.Fab")
		)
		(fp_line
			(start 0.67945 -0.3048)
			(end 0.67945 0.3048)
			(stroke
				(width 0.1)
				(type default)
			)
			(layer "F.Fab")
		)
		(fp_line
			(start 0.12065 -0.3048)
			(end 0.67945 -0.3048)
			(stroke
				(width 0.1)
				(type default)
			)
			(layer "F.Fab")
		)
		(fp_line
			(start 0.12065 -0.2794)
			(end 0.12065 -0.3048)
			(stroke
				(width 0.1)
				(type default)
			)
			(layer "F.Fab")
		)
		(fp_line
			(start -0.12065 -0.2794)
			(end 0.12065 -0.2794)
			(stroke
				(width 0.1)
				(type default)
			)
			(layer "F.Fab")
		)
		(fp_line
			(start 0.120396 0.2794)
			(end -0.12065 0.2794)
			(stroke
				(width 0.1)
				(type default)
			)
			(layer "F.Fab")
		)
		(fp_line
			(start -0.12065 0.2794)
			(end -0.12065 0.3048)
			(stroke
				(width 0.1)
				(type default)
			)
			(layer "F.Fab")
		)
		(fp_line
			(start 0.67945 0.3048)
			(end 0.120396 0.3048)
			(stroke
				(width 0.1)
				(type default)
			)
			(layer "F.Fab")
		)
		(fp_line
			(start 0.120396 0.3048)
			(end 0.120396 0.2794)
			(stroke
				(width 0.1)
				(type default)
			)
			(layer "F.Fab")
		)
		(fp_line
			(start -0.12065 0.3048)
			(end -0.67945 0.3048)
			(stroke
				(width 0.1)
				(type default)
			)
			(layer "F.Fab")
		)
		(fp_line
			(start -0.67945 0.3048)
			(end -0.67945 -0.305054)
			(stroke
				(width 0.1)
				(type default)
			)
			(layer "F.Fab")
		)
		(pad "1" smd circle
			(at -0.40005 0 90)
			(size 0 0)
			(layers "F.Cu" "F.Mask" "F.Paste")
			(net "P3V3_SSD12_SS")
		)
		(pad "2" smd circle
			(at 0.40005 0 90)
			(size 0 0)
			(layers "F.Cu" "F.Mask" "F.Paste")
			(net "GND")
		)
	)
	(footprint ""
		(layer "F.Cu")
		(at 321.322192 -102.319328 45)
		(property "Reference" "C618"
			(at 0 0 45)
			(layer "F.SilkS")
			(hide yes)
			(effects
				(font
					(size 1.27 1.27)
				)
			)
		)
		(property "Value" ""
			(at 0 0 45)
			(layer "F.Fab")
			(effects
				(font
					(size 1.27 1.27)
				)
			)
		)
		(duplicate_pad_numbers_are_jumpers no)
		(fp_line
			(start -0.787389 -0.406267)
			(end 0.787389 -0.406267)
			(stroke
				(width 0.1524)
				(type default)
			)
			(layer "F.SilkS")
		)
		(fp_line
			(start -0.787389 0.406267)
			(end -0.787389 -0.406267)
			(stroke
				(width 0.1524)
				(type default)
			)
			(layer "F.SilkS")
		)
		(fp_line
			(start 0.787389 -0.406267)
			(end 0.787389 0.406267)
			(stroke
				(width 0.1524)
				(type default)
			)
			(layer "F.SilkS")
		)
		(fp_line
			(start 0.787389 0.406267)
			(end -0.787389 0.406267)
			(stroke
				(width 0.1524)
				(type default)
			)
			(layer "F.SilkS")
		)
		(fp_line
			(start -0.679446 -0.305149)
			(end -0.120695 -0.304969)
			(stroke
				(width 0.1)
				(type default)
			)
			(layer "F.Fab")
		)
		(fp_line
			(start -0.120695 -0.304969)
			(end -0.120695 -0.279466)
			(stroke
				(width 0.1)
				(type default)
			)
			(layer "F.Fab")
		)
		(fp_line
			(start -0.120695 -0.279466)
			(end 0.120695 -0.279466)
			(stroke
				(width 0.1)
				(type default)
			)
			(layer "F.Fab")
		)
		(fp_line
			(start -0.679446 0.30479)
			(end -0.679446 -0.305149)
			(stroke
				(width 0.1)
				(type default)
			)
			(layer "F.Fab")
		)
		(fp_line
			(start 0.120515 -0.30479)
			(end 0.679446 -0.30479)
			(stroke
				(width 0.1)
				(type default)
			)
			(layer "F.Fab")
		)
		(fp_line
			(start 0.120695 -0.279466)
			(end 0.120515 -0.30479)
			(stroke
				(width 0.1)
				(type default)
			)
			(layer "F.Fab")
		)
		(fp_line
			(start -0.120695 0.279466)
			(end -0.120515 0.30479)
			(stroke
				(width 0.1)
				(type default)
			)
			(layer "F.Fab")
		)
		(fp_line
			(start -0.120515 0.30479)
			(end -0.679446 0.30479)
			(stroke
				(width 0.1)
				(type default)
			)
			(layer "F.Fab")
		)
		(fp_line
			(start 0.679446 -0.30479)
			(end 0.679446 0.30479)
			(stroke
				(width 0.1)
				(type default)
			)
			(layer "F.Fab")
		)
		(fp_line
			(start 0.120335 0.279466)
			(end -0.120695 0.279466)
			(stroke
				(width 0.1)
				(type default)
			)
			(layer "F.Fab")
		)
		(fp_line
			(start 0.120515 0.30479)
			(end 0.120335 0.279466)
			(stroke
				(width 0.1)
				(type default)
			)
			(layer "F.Fab")
		)
		(fp_line
			(start 0.679446 0.30479)
			(end 0.120515 0.30479)
			(stroke
				(width 0.1)
				(type default)
			)
			(layer "F.Fab")
		)
		(pad "1" smd circle
			(at -0.40005 0 45)
			(size 0 0)
			(layers "F.Cu" "F.Mask" "F.Paste")
			(net "P12V_NIC5_VIN_P")
		)
		(pad "2" smd circle
			(at 0.40005 0 45)
			(size 0 0)
			(layers "F.Cu" "F.Mask" "F.Paste")
			(net "P12V_NIC5_VIN_N")
		)
	)
	(footprint ""
		(layer "F.Cu")
		(at 198.76135 -156.111194 180)
		(property "Reference" "C212"
			(at 0 0 180)
			(layer "F.SilkS")
			(hide yes)
			(effects
				(font
					(size 1.27 1.27)
				)
			)
		)
		(property "Value" ""
			(at 0 0 180)
			(layer "F.Fab")
			(effects
				(font
					(size 1.27 1.27)
				)
			)
		)
		(duplicate_pad_numbers_are_jumpers no)
		(fp_line
			(start 0.299974 0.150114)
			(end -0.299974 0.150114)
			(stroke
				(width 0.1)
				(type default)
			)
			(layer "F.Fab")
		)
		(fp_line
			(start 0.299974 -0.150114)
			(end 0.299974 0.150114)
			(stroke
				(width 0.1)
				(type default)
			)
			(layer "F.Fab")
		)
		(fp_line
			(start -0.299974 0.150114)
			(end -0.299974 -0.150114)
			(stroke
				(width 0.1)
				(type default)
			)
			(layer "F.Fab")
		)
		(fp_line
			(start -0.299974 -0.150114)
			(end 0.299974 -0.150114)
			(stroke
				(width 0.1)
				(type default)
			)
			(layer "F.Fab")
		)
		(pad "1" smd rect
			(at -0.2667 0 180)
			(size 0.3048 0.381)
			(layers "F.Cu" "F.Mask" "F.Paste")
			(net "P5E_PEX1_STN0_TX_DP<15>")
		)
		(pad "2" smd rect
			(at 0.2667 0 180)
			(size 0.3048 0.381)
			(layers "F.Cu" "F.Mask" "F.Paste")
			(net "P5E_PEX1_STN0_TX_C_DP<15>")
		)
	)
	(footprint ""
		(layer "F.Cu")
		(at 456.818238 -266.996672)
		(property "Reference" "R6141"
			(at 0 0 0)
			(layer "F.SilkS")
			(hide yes)
			(effects
				(font
					(size 1.27 1.27)
				)
			)
		)
		(property "Value" ""
			(at 0 0 0)
			(layer "F.Fab")
			(effects
				(font
					(size 1.27 1.27)
				)
			)
		)
		(duplicate_pad_numbers_are_jumpers no)
		(fp_line
			(start -2.576322 -1.1303)
			(end 2.576322 -1.1303)
			(stroke
				(width 0.1524)
				(type default)
			)
			(layer "F.SilkS")
		)
		(fp_line
			(start -2.576322 1.1303)
			(end -2.576322 -1.1303)
			(stroke
				(width 0.1524)
				(type default)
			)
			(layer "F.SilkS")
		)
		(fp_line
			(start 2.576322 -1.1303)
			(end 2.576322 1.1303)
			(stroke
				(width 0.1524)
				(type default)
			)
			(layer "F.SilkS")
		)
		(fp_line
			(start 2.576322 1.1303)
			(end -2.576322 1.1303)
			(stroke
				(width 0.1524)
				(type default)
			)
			(layer "F.SilkS")
		)
		(fp_line
			(start -1.649984 -0.899922)
			(end -1.649984 0.899922)
			(stroke
				(width 0.1)
				(type default)
			)
			(layer "F.Fab")
		)
		(fp_line
			(start -1.649984 0.899922)
			(end 1.649984 0.899922)
			(stroke
				(width 0.1)
				(type default)
			)
			(layer "F.Fab")
		)
		(fp_line
			(start 1.649984 -0.899922)
			(end -1.649984 -0.899922)
			(stroke
				(width 0.1)
				(type default)
			)
			(layer "F.Fab")
		)
		(fp_line
			(start 1.649984 0.899922)
			(end 1.649984 -0.899922)
			(stroke
				(width 0.1)
				(type default)
			)
			(layer "F.Fab")
		)
		(pad "1A" smd rect
			(at -1.700022 0)
			(size 1.4986 2.0066)
			(layers "F.Cu" "F.Mask" "F.Paste")
			(net "P1V25_PEX3")
		)
		(pad "1B" smd rect
			(at -1.077722 0)
			(size 0.254 0.508)
			(layers "F.Cu" "F.Mask" "F.Paste")
			(net "P1V25_PEX3")
		)
		(pad "2A" smd rect
			(at 1.700022 0)
			(size 1.4986 2.0066)
			(layers "F.Cu" "F.Mask" "F.Paste")
			(net "P1V25_SERDES_VDDPLL_PEX3")
		)
		(pad "2B" smd rect
			(at 1.077722 0)
			(size 0.254 0.508)
			(layers "F.Cu" "F.Mask" "F.Paste")
			(net "P1V25_SERDES_VDDPLL_PEX3")
		)
	)
	(footprint ""
		(layer "F.Cu")
		(at 67.564762 -343.952322 90)
		(property "Reference" "C133"
			(at 0 0 90)
			(layer "F.SilkS")
			(hide yes)
			(effects
				(font
					(size 1.27 1.27)
				)
			)
		)
		(property "Value" ""
			(at 0 0 90)
			(layer "F.Fab")
			(effects
				(font
					(size 1.27 1.27)
				)
			)
		)
		(duplicate_pad_numbers_are_jumpers no)
		(fp_line
			(start 0.299974 -0.150114)
			(end 0.299974 0.150114)
			(stroke
				(width 0.1)
				(type default)
			)
			(layer "F.Fab")
		)
		(fp_line
			(start -0.299974 -0.150114)
			(end 0.299974 -0.150114)
			(stroke
				(width 0.1)
				(type default)
			)
			(layer "F.Fab")
		)
		(fp_line
			(start 0.299974 0.150114)
			(end -0.299974 0.150114)
			(stroke
				(width 0.1)
				(type default)
			)
			(layer "F.Fab")
		)
		(fp_line
			(start -0.299974 0.150114)
			(end -0.299974 -0.150114)
			(stroke
				(width 0.1)
				(type default)
			)
			(layer "F.Fab")
		)
		(pad "1" smd rect
			(at -0.2667 0 90)
			(size 0.3048 0.381)
			(layers "F.Cu" "F.Mask" "F.Paste")
			(net "P5E_PEX0_STN6_TX_DP<109>")
		)
		(pad "2" smd rect
			(at 0.2667 0 90)
			(size 0.3048 0.381)
			(layers "F.Cu" "F.Mask" "F.Paste")
			(net "P5E_PEX0_STN6_TX_C_DP<109>")
		)
	)
	(footprint ""
		(layer "F.Cu")
		(at 19.258026 -72.766682 90)
		(property "Reference" "PC641"
			(at 0 0 90)
			(layer "F.SilkS")
			(hide yes)
			(effects
				(font
					(size 1.27 1.27)
				)
			)
		)
		(property "Value" ""
			(at 0 0 90)
			(layer "F.Fab")
			(effects
				(font
					(size 1.27 1.27)
				)
			)
		)
		(duplicate_pad_numbers_are_jumpers no)
		(fp_line
			(start 0.7874 -0.4064)
			(end 0.7874 0.4064)
			(stroke
				(width 0.1524)
				(type default)
			)
			(layer "F.SilkS")
		)
		(fp_line
			(start -0.7874 -0.4064)
			(end 0.7874 -0.4064)
			(stroke
				(width 0.1524)
				(type default)
			)
			(layer "F.SilkS")
		)
		(fp_line
			(start 0.7874 0.4064)
			(end -0.7874 0.4064)
			(stroke
				(width 0.1524)
				(type default)
			)
			(layer "F.SilkS")
		)
		(fp_line
			(start -0.7874 0.4064)
			(end -0.7874 -0.4064)
			(stroke
				(width 0.1524)
				(type default)
			)
			(layer "F.SilkS")
		)
		(fp_line
			(start -0.12065 -0.305054)
			(end -0.12065 -0.2794)
			(stroke
				(width 0.1)
				(type default)
			)
			(layer "F.Fab")
		)
		(fp_line
			(start -0.67945 -0.305054)
			(end -0.12065 -0.305054)
			(stroke
				(width 0.1)
				(type default)
			)
			(layer "F.Fab")
		)
		(fp_line
			(start 0.67945 -0.3048)
			(end 0.67945 0.3048)
			(stroke
				(width 0.1)
				(type default)
			)
			(layer "F.Fab")
		)
		(fp_line
			(start 0.12065 -0.3048)
			(end 0.67945 -0.3048)
			(stroke
				(width 0.1)
				(type default)
			)
			(layer "F.Fab")
		)
		(fp_line
			(start 0.12065 -0.2794)
			(end 0.12065 -0.3048)
			(stroke
				(width 0.1)
				(type default)
			)
			(layer "F.Fab")
		)
		(fp_line
			(start -0.12065 -0.2794)
			(end 0.12065 -0.2794)
			(stroke
				(width 0.1)
				(type default)
			)
			(layer "F.Fab")
		)
		(fp_line
			(start 0.120396 0.2794)
			(end -0.12065 0.2794)
			(stroke
				(width 0.1)
				(type default)
			)
			(layer "F.Fab")
		)
		(fp_line
			(start -0.12065 0.2794)
			(end -0.12065 0.3048)
			(stroke
				(width 0.1)
				(type default)
			)
			(layer "F.Fab")
		)
		(fp_line
			(start 0.67945 0.3048)
			(end 0.120396 0.3048)
			(stroke
				(width 0.1)
				(type default)
			)
			(layer "F.Fab")
		)
		(fp_line
			(start 0.120396 0.3048)
			(end 0.120396 0.2794)
			(stroke
				(width 0.1)
				(type default)
			)
			(layer "F.Fab")
		)
		(fp_line
			(start -0.12065 0.3048)
			(end -0.67945 0.3048)
			(stroke
				(width 0.1)
				(type default)
			)
			(layer "F.Fab")
		)
		(fp_line
			(start -0.67945 0.3048)
			(end -0.67945 -0.305054)
			(stroke
				(width 0.1)
				(type default)
			)
			(layer "F.Fab")
		)
		(pad "1" smd circle
			(at -0.40005 0 90)
			(size 0 0)
			(layers "F.Cu" "F.Mask" "F.Paste")
			(net "P12V_SSD0_CO_MODE")
		)
		(pad "2" smd circle
			(at 0.40005 0 90)
			(size 0 0)
			(layers "F.Cu" "F.Mask" "F.Paste")
			(net "GND")
		)
	)
	(footprint ""
		(layer "F.Cu")
		(at 142.367254 -57.332626)
		(property "Reference" "R6837"
			(at 0 0 0)
			(layer "F.SilkS")
			(hide yes)
			(effects
				(font
					(size 1.27 1.27)
				)
			)
		)
		(property "Value" ""
			(at 0 0 0)
			(layer "F.Fab")
			(effects
				(font
					(size 1.27 1.27)
				)
			)
		)
		(duplicate_pad_numbers_are_jumpers no)
		(fp_line
			(start -0.7874 -0.4064)
			(end 0.7874 -0.4064)
			(stroke
				(width 0.1524)
				(type default)
			)
			(layer "F.SilkS")
		)
		(fp_line
			(start -0.7874 0.4064)
			(end -0.7874 -0.4064)
			(stroke
				(width 0.1524)
				(type default)
			)
			(layer "F.SilkS")
		)
		(fp_line
			(start 0.7874 -0.4064)
			(end 0.7874 0.4064)
			(stroke
				(width 0.1524)
				(type default)
			)
			(layer "F.SilkS")
		)
		(fp_line
			(start 0.7874 0.4064)
			(end -0.7874 0.4064)
			(stroke
				(width 0.1524)
				(type default)
			)
			(layer "F.SilkS")
		)
		(fp_line
			(start -0.67945 -0.305054)
			(end -0.12065 -0.305054)
			(stroke
				(width 0.1)
				(type default)
			)
			(layer "F.Fab")
		)
		(fp_line
			(start -0.67945 0.3048)
			(end -0.67945 -0.305054)
			(stroke
				(width 0.1)
				(type default)
			)
			(layer "F.Fab")
		)
		(fp_line
			(start -0.12065 -0.305054)
			(end -0.12065 -0.2794)
			(stroke
				(width 0.1)
				(type default)
			)
			(layer "F.Fab")
		)
		(fp_line
			(start -0.12065 -0.2794)
			(end 0.12065 -0.2794)
			(stroke
				(width 0.1)
				(type default)
			)
			(layer "F.Fab")
		)
		(fp_line
			(start -0.12065 0.2794)
			(end -0.12065 0.3048)
			(stroke
				(width 0.1)
				(type default)
			)
			(layer "F.Fab")
		)
		(fp_line
			(start -0.12065 0.3048)
			(end -0.67945 0.3048)
			(stroke
				(width 0.1)
				(type default)
			)
			(layer "F.Fab")
		)
		(fp_line
			(start 0.120396 0.2794)
			(end -0.12065 0.2794)
			(stroke
				(width 0.1)
				(type default)
			)
			(layer "F.Fab")
		)
		(fp_line
			(start 0.120396 0.3048)
			(end 0.120396 0.2794)
			(stroke
				(width 0.1)
				(type default)
			)
			(layer "F.Fab")
		)
		(fp_line
			(start 0.12065 -0.3048)
			(end 0.67945 -0.3048)
			(stroke
				(width 0.1)
				(type default)
			)
			(layer "F.Fab")
		)
		(fp_line
			(start 0.12065 -0.2794)
			(end 0.12065 -0.3048)
			(stroke
				(width 0.1)
				(type default)
			)
			(layer "F.Fab")
		)
		(fp_line
			(start 0.67945 -0.3048)
			(end 0.67945 0.3048)
			(stroke
				(width 0.1)
				(type default)
			)
			(layer "F.Fab")
		)
		(fp_line
			(start 0.67945 0.3048)
			(end 0.120396 0.3048)
			(stroke
				(width 0.1)
				(type default)
			)
			(layer "F.Fab")
		)
		(pad "1" smd circle
			(at -0.40005 0)
			(size 0 0)
			(layers "F.Cu" "F.Mask" "F.Paste")
			(net "SSD4_PWR_EN_R")
		)
		(pad "2" smd circle
			(at 0.40005 0)
			(size 0 0)
			(layers "F.Cu" "F.Mask" "F.Paste")
			(net "GND")
		)
	)
	(footprint ""
		(layer "F.Cu")
		(at 305.147218 -21.37156)
		(property "Reference" "C3946"
			(at 0 0 0)
			(layer "F.SilkS")
			(hide yes)
			(effects
				(font
					(size 1.27 1.27)
				)
			)
		)
		(property "Value" ""
			(at 0 0 0)
			(layer "F.Fab")
			(effects
				(font
					(size 1.27 1.27)
				)
			)
		)
		(duplicate_pad_numbers_are_jumpers no)
		(fp_line
			(start -0.7874 -0.4064)
			(end 0.7874 -0.4064)
			(stroke
				(width 0.1524)
				(type default)
			)
			(layer "F.SilkS")
		)
		(fp_line
			(start -0.7874 0.4064)
			(end -0.7874 -0.4064)
			(stroke
				(width 0.1524)
				(type default)
			)
			(layer "F.SilkS")
		)
		(fp_line
			(start 0.7874 -0.4064)
			(end 0.7874 0.4064)
			(stroke
				(width 0.1524)
				(type default)
			)
			(layer "F.SilkS")
		)
		(fp_line
			(start 0.7874 0.4064)
			(end -0.7874 0.4064)
			(stroke
				(width 0.1524)
				(type default)
			)
			(layer "F.SilkS")
		)
		(fp_line
			(start -0.67945 -0.305054)
			(end -0.12065 -0.305054)
			(stroke
				(width 0.1)
				(type default)
			)
			(layer "F.Fab")
		)
		(fp_line
			(start -0.67945 0.3048)
			(end -0.67945 -0.305054)
			(stroke
				(width 0.1)
				(type default)
			)
			(layer "F.Fab")
		)
		(fp_line
			(start -0.12065 -0.305054)
			(end -0.12065 -0.2794)
			(stroke
				(width 0.1)
				(type default)
			)
			(layer "F.Fab")
		)
		(fp_line
			(start -0.12065 -0.2794)
			(end 0.12065 -0.2794)
			(stroke
				(width 0.1)
				(type default)
			)
			(layer "F.Fab")
		)
		(fp_line
			(start -0.12065 0.2794)
			(end -0.12065 0.3048)
			(stroke
				(width 0.1)
				(type default)
			)
			(layer "F.Fab")
		)
		(fp_line
			(start -0.12065 0.3048)
			(end -0.67945 0.3048)
			(stroke
				(width 0.1)
				(type default)
			)
			(layer "F.Fab")
		)
		(fp_line
			(start 0.120396 0.2794)
			(end -0.12065 0.2794)
			(stroke
				(width 0.1)
				(type default)
			)
			(layer "F.Fab")
		)
		(fp_line
			(start 0.120396 0.3048)
			(end 0.120396 0.2794)
			(stroke
				(width 0.1)
				(type default)
			)
			(layer "F.Fab")
		)
		(fp_line
			(start 0.12065 -0.3048)
			(end 0.67945 -0.3048)
			(stroke
				(width 0.1)
				(type default)
			)
			(layer "F.Fab")
		)
		(fp_line
			(start 0.12065 -0.2794)
			(end 0.12065 -0.3048)
			(stroke
				(width 0.1)
				(type default)
			)
			(layer "F.Fab")
		)
		(fp_line
			(start 0.67945 -0.3048)
			(end 0.67945 0.3048)
			(stroke
				(width 0.1)
				(type default)
			)
			(layer "F.Fab")
		)
		(fp_line
			(start 0.67945 0.3048)
			(end 0.120396 0.3048)
			(stroke
				(width 0.1)
				(type default)
			)
			(layer "F.Fab")
		)
		(pad "1" smd circle
			(at -0.40005 0)
			(size 0 0)
			(layers "F.Cu" "F.Mask" "F.Paste")
			(net "P12V_SSD10")
		)
		(pad "2" smd circle
			(at 0.40005 0)
			(size 0 0)
			(layers "F.Cu" "F.Mask" "F.Paste")
			(net "GND")
		)
	)
	(footprint ""
		(layer "F.Cu")
		(at 55.155084 -53.468524 90)
		(property "Reference" "PC523"
			(at 0 0 90)
			(layer "F.SilkS")
			(hide yes)
			(effects
				(font
					(size 1.27 1.27)
				)
			)
		)
		(property "Value" ""
			(at 0 0 90)
			(layer "F.Fab")
			(effects
				(font
					(size 1.27 1.27)
				)
			)
		)
		(duplicate_pad_numbers_are_jumpers no)
		(fp_line
			(start 1.524 -0.762)
			(end 1.524 0.762)
			(stroke
				(width 0.1524)
				(type default)
			)
			(layer "F.SilkS")
		)
		(fp_line
			(start -1.524 -0.762)
			(end 1.524 -0.762)
			(stroke
				(width 0.1524)
				(type default)
			)
			(layer "F.SilkS")
		)
		(fp_line
			(start 1.524 0.762)
			(end -1.524 0.762)
			(stroke
				(width 0.1524)
				(type default)
			)
			(layer "F.SilkS")
		)
		(fp_line
			(start -1.524 0.762)
			(end -1.524 -0.762)
			(stroke
				(width 0.1524)
				(type default)
			)
			(layer "F.SilkS")
		)
		(fp_line
			(start 1.1049 -0.724916)
			(end -1.1049 -0.724916)
			(stroke
				(width 0.1)
				(type default)
			)
			(layer "F.Fab")
		)
		(fp_line
			(start -1.1049 -0.724916)
			(end -1.1049 0.724916)
			(stroke
				(width 0.1)
				(type default)
			)
			(layer "F.Fab")
		)
		(fp_line
			(start 1.1049 0.724916)
			(end 1.1049 -0.724916)
			(stroke
				(width 0.1)
				(type default)
			)
			(layer "F.Fab")
		)
		(fp_line
			(start -1.1049 0.724916)
			(end 1.1049 0.724916)
			(stroke
				(width 0.1)
				(type default)
			)
			(layer "F.Fab")
		)
		(pad "1" smd rect
			(at -0.889 0 270)
			(size 1.016 1.27)
			(layers "F.Cu" "F.Mask" "F.Paste")
			(net "GND")
		)
		(pad "2" smd rect
			(at 0.889 0 270)
			(size 1.016 1.27)
			(layers "F.Cu" "F.Mask" "F.Paste")
			(net "P3V3_AUX")
		)
	)
	(footprint ""
		(layer "F.Cu")
		(at 448.18554 -27.092148 -90)
		(property "Reference" "R5749"
			(at 0 0 270)
			(layer "F.SilkS")
			(hide yes)
			(effects
				(font
					(size 1.27 1.27)
				)
			)
		)
		(property "Value" ""
			(at 0 0 270)
			(layer "F.Fab")
			(effects
				(font
					(size 1.27 1.27)
				)
			)
		)
		(duplicate_pad_numbers_are_jumpers no)
		(fp_line
			(start -0.7874 0.4064)
			(end -0.7874 -0.4064)
			(stroke
				(width 0.1524)
				(type default)
			)
			(layer "F.SilkS")
		)
		(fp_line
			(start 0.7874 0.4064)
			(end -0.7874 0.4064)
			(stroke
				(width 0.1524)
				(type default)
			)
			(layer "F.SilkS")
		)
		(fp_line
			(start -0.7874 -0.4064)
			(end 0.7874 -0.4064)
			(stroke
				(width 0.1524)
				(type default)
			)
			(layer "F.SilkS")
		)
		(fp_line
			(start 0.7874 -0.4064)
			(end 0.7874 0.4064)
			(stroke
				(width 0.1524)
				(type default)
			)
			(layer "F.SilkS")
		)
		(fp_line
			(start -0.67945 0.3048)
			(end -0.67945 -0.305054)
			(stroke
				(width 0.1)
				(type default)
			)
			(layer "F.Fab")
		)
		(fp_line
			(start -0.12065 0.3048)
			(end -0.67945 0.3048)
			(stroke
				(width 0.1)
				(type default)
			)
			(layer "F.Fab")
		)
		(fp_line
			(start 0.120396 0.3048)
			(end 0.120396 0.2794)
			(stroke
				(width 0.1)
				(type default)
			)
			(layer "F.Fab")
		)
		(fp_line
			(start 0.67945 0.3048)
			(end 0.120396 0.3048)
			(stroke
				(width 0.1)
				(type default)
			)
			(layer "F.Fab")
		)
		(fp_line
			(start -0.12065 0.2794)
			(end -0.12065 0.3048)
			(stroke
				(width 0.1)
				(type default)
			)
			(layer "F.Fab")
		)
		(fp_line
			(start 0.120396 0.2794)
			(end -0.12065 0.2794)
			(stroke
				(width 0.1)
				(type default)
			)
			(layer "F.Fab")
		)
		(fp_line
			(start -0.12065 -0.2794)
			(end 0.12065 -0.2794)
			(stroke
				(width 0.1)
				(type default)
			)
			(layer "F.Fab")
		)
		(fp_line
			(start 0.12065 -0.2794)
			(end 0.12065 -0.3048)
			(stroke
				(width 0.1)
				(type default)
			)
			(layer "F.Fab")
		)
		(fp_line
			(start 0.12065 -0.3048)
			(end 0.67945 -0.3048)
			(stroke
				(width 0.1)
				(type default)
			)
			(layer "F.Fab")
		)
		(fp_line
			(start 0.67945 -0.3048)
			(end 0.67945 0.3048)
			(stroke
				(width 0.1)
				(type default)
			)
			(layer "F.Fab")
		)
		(fp_line
			(start -0.67945 -0.305054)
			(end -0.12065 -0.305054)
			(stroke
				(width 0.1)
				(type default)
			)
			(layer "F.Fab")
		)
		(fp_line
			(start -0.12065 -0.305054)
			(end -0.12065 -0.2794)
			(stroke
				(width 0.1)
				(type default)
			)
			(layer "F.Fab")
		)
		(pad "1" smd circle
			(at -0.40005 0 270)
			(size 0 0)
			(layers "F.Cu" "F.Mask" "F.Paste")
			(net "P3V3_SSD15")
		)
		(pad "2" smd circle
			(at 0.40005 0 270)
			(size 0 0)
			(layers "F.Cu" "F.Mask" "F.Paste")
			(net "SSD15_LED_ISO_N")
		)
	)
	(footprint ""
		(layer "F.Cu")
		(at 247.817386 -258.04495 -90)
		(property "Reference" "R6534"
			(at 0 0 270)
			(layer "F.SilkS")
			(hide yes)
			(effects
				(font
					(size 1.27 1.27)
				)
			)
		)
		(property "Value" ""
			(at 0 0 270)
			(layer "F.Fab")
			(effects
				(font
					(size 1.27 1.27)
				)
			)
		)
		(duplicate_pad_numbers_are_jumpers no)
		(fp_line
			(start -0.7874 0.4064)
			(end -0.7874 -0.4064)
			(stroke
				(width 0.1524)
				(type default)
			)
			(layer "F.SilkS")
		)
		(fp_line
			(start 0.7874 0.4064)
			(end -0.7874 0.4064)
			(stroke
				(width 0.1524)
				(type default)
			)
			(layer "F.SilkS")
		)
		(fp_line
			(start -0.7874 -0.4064)
			(end 0.7874 -0.4064)
			(stroke
				(width 0.1524)
				(type default)
			)
			(layer "F.SilkS")
		)
		(fp_line
			(start 0.7874 -0.4064)
			(end 0.7874 0.4064)
			(stroke
				(width 0.1524)
				(type default)
			)
			(layer "F.SilkS")
		)
		(fp_line
			(start -0.67945 0.3048)
			(end -0.67945 -0.305054)
			(stroke
				(width 0.1)
				(type default)
			)
			(layer "F.Fab")
		)
		(fp_line
			(start -0.12065 0.3048)
			(end -0.67945 0.3048)
			(stroke
				(width 0.1)
				(type default)
			)
			(layer "F.Fab")
		)
		(fp_line
			(start 0.120396 0.3048)
			(end 0.120396 0.2794)
			(stroke
				(width 0.1)
				(type default)
			)
			(layer "F.Fab")
		)
		(fp_line
			(start 0.67945 0.3048)
			(end 0.120396 0.3048)
			(stroke
				(width 0.1)
				(type default)
			)
			(layer "F.Fab")
		)
		(fp_line
			(start -0.12065 0.2794)
			(end -0.12065 0.3048)
			(stroke
				(width 0.1)
				(type default)
			)
			(layer "F.Fab")
		)
		(fp_line
			(start 0.120396 0.2794)
			(end -0.12065 0.2794)
			(stroke
				(width 0.1)
				(type default)
			)
			(layer "F.Fab")
		)
		(fp_line
			(start -0.12065 -0.2794)
			(end 0.12065 -0.2794)
			(stroke
				(width 0.1)
				(type default)
			)
			(layer "F.Fab")
		)
		(fp_line
			(start 0.12065 -0.2794)
			(end 0.12065 -0.3048)
			(stroke
				(width 0.1)
				(type default)
			)
			(layer "F.Fab")
		)
		(fp_line
			(start 0.12065 -0.3048)
			(end 0.67945 -0.3048)
			(stroke
				(width 0.1)
				(type default)
			)
			(layer "F.Fab")
		)
		(fp_line
			(start 0.67945 -0.3048)
			(end 0.67945 0.3048)
			(stroke
				(width 0.1)
				(type default)
			)
			(layer "F.Fab")
		)
		(fp_line
			(start -0.67945 -0.305054)
			(end -0.12065 -0.305054)
			(stroke
				(width 0.1)
				(type default)
			)
			(layer "F.Fab")
		)
		(fp_line
			(start -0.12065 -0.305054)
			(end -0.12065 -0.2794)
			(stroke
				(width 0.1)
				(type default)
			)
			(layer "F.Fab")
		)
		(pad "1" smd circle
			(at -0.40005 0 270)
			(size 0 0)
			(layers "F.Cu" "F.Mask" "F.Paste")
			(net "P1V25_SERDES_VDDPLL_PEX2")
		)
		(pad "2" smd circle
			(at 0.40005 0 270)
			(size 0 0)
			(layers "F.Cu" "F.Mask" "F.Paste")
			(net "P1V25_SERDES_VDDPLL_PEX2_C11")
		)
	)
	(footprint ""
		(layer "F.Cu")
		(at 147.494244 -29.507688 -90)
		(property "Reference" "PC923"
			(at 0 0 270)
			(layer "F.SilkS")
			(hide yes)
			(effects
				(font
					(size 1.27 1.27)
				)
			)
		)
		(property "Value" ""
			(at 0 0 270)
			(layer "F.Fab")
			(effects
				(font
					(size 1.27 1.27)
				)
			)
		)
		(duplicate_pad_numbers_are_jumpers no)
		(fp_line
			(start -1.524 0.762)
			(end -1.524 -0.762)
			(stroke
				(width 0.1524)
				(type default)
			)
			(layer "F.SilkS")
		)
		(fp_line
			(start 1.524 0.762)
			(end -1.524 0.762)
			(stroke
				(width 0.1524)
				(type default)
			)
			(layer "F.SilkS")
		)
		(fp_line
			(start -1.524 -0.762)
			(end 1.524 -0.762)
			(stroke
				(width 0.1524)
				(type default)
			)
			(layer "F.SilkS")
		)
		(fp_line
			(start 1.524 -0.762)
			(end 1.524 0.762)
			(stroke
				(width 0.1524)
				(type default)
			)
			(layer "F.SilkS")
		)
		(fp_line
			(start -1.1049 0.724916)
			(end 1.1049 0.724916)
			(stroke
				(width 0.1)
				(type default)
			)
			(layer "F.Fab")
		)
		(fp_line
			(start 1.1049 0.724916)
			(end 1.1049 -0.724916)
			(stroke
				(width 0.1)
				(type default)
			)
			(layer "F.Fab")
		)
		(fp_line
			(start -1.1049 -0.724916)
			(end -1.1049 0.724916)
			(stroke
				(width 0.1)
				(type default)
			)
			(layer "F.Fab")
		)
		(fp_line
			(start 1.1049 -0.724916)
			(end -1.1049 -0.724916)
			(stroke
				(width 0.1)
				(type default)
			)
			(layer "F.Fab")
		)
		(pad "1" smd rect
			(at -0.889 0 90)
			(size 1.016 1.27)
			(layers "F.Cu" "F.Mask" "F.Paste")
			(net "P3V3_SSD5")
		)
		(pad "2" smd rect
			(at 0.889 0 90)
			(size 1.016 1.27)
			(layers "F.Cu" "F.Mask" "F.Paste")
			(net "GND")
		)
	)
	(footprint ""
		(layer "F.Cu")
		(at 46.174914 -48.753014 180)
		(property "Reference" "C210"
			(at 0 0 180)
			(layer "F.SilkS")
			(hide yes)
			(effects
				(font
					(size 1.27 1.27)
				)
			)
		)
		(property "Value" ""
			(at 0 0 180)
			(layer "F.Fab")
			(effects
				(font
					(size 1.27 1.27)
				)
			)
		)
		(duplicate_pad_numbers_are_jumpers no)
		(fp_line
			(start 0.7874 0.4064)
			(end -0.7874 0.4064)
			(stroke
				(width 0.1524)
				(type default)
			)
			(layer "F.SilkS")
		)
		(fp_line
			(start 0.7874 -0.4064)
			(end 0.7874 0.4064)
			(stroke
				(width 0.1524)
				(type default)
			)
			(layer "F.SilkS")
		)
		(fp_line
			(start -0.7874 0.4064)
			(end -0.7874 -0.4064)
			(stroke
				(width 0.1524)
				(type default)
			)
			(layer "F.SilkS")
		)
		(fp_line
			(start -0.7874 -0.4064)
			(end 0.7874 -0.4064)
			(stroke
				(width 0.1524)
				(type default)
			)
			(layer "F.SilkS")
		)
		(fp_line
			(start 0.67945 0.3048)
			(end 0.120396 0.3048)
			(stroke
				(width 0.1)
				(type default)
			)
			(layer "F.Fab")
		)
		(fp_line
			(start 0.67945 -0.3048)
			(end 0.67945 0.3048)
			(stroke
				(width 0.1)
				(type default)
			)
			(layer "F.Fab")
		)
		(fp_line
			(start 0.12065 -0.2794)
			(end 0.12065 -0.3048)
			(stroke
				(width 0.1)
				(type default)
			)
			(layer "F.Fab")
		)
		(fp_line
			(start 0.12065 -0.3048)
			(end 0.67945 -0.3048)
			(stroke
				(width 0.1)
				(type default)
			)
			(layer "F.Fab")
		)
		(fp_line
			(start 0.120396 0.3048)
			(end 0.120396 0.2794)
			(stroke
				(width 0.1)
				(type default)
			)
			(layer "F.Fab")
		)
		(fp_line
			(start 0.120396 0.2794)
			(end -0.12065 0.2794)
			(stroke
				(width 0.1)
				(type default)
			)
			(layer "F.Fab")
		)
		(fp_line
			(start -0.12065 0.3048)
			(end -0.67945 0.3048)
			(stroke
				(width 0.1)
				(type default)
			)
			(layer "F.Fab")
		)
		(fp_line
			(start -0.12065 0.2794)
			(end -0.12065 0.3048)
			(stroke
				(width 0.1)
				(type default)
			)
			(layer "F.Fab")
		)
		(fp_line
			(start -0.12065 -0.2794)
			(end 0.12065 -0.2794)
			(stroke
				(width 0.1)
				(type default)
			)
			(layer "F.Fab")
		)
		(fp_line
			(start -0.12065 -0.305054)
			(end -0.12065 -0.2794)
			(stroke
				(width 0.1)
				(type default)
			)
			(layer "F.Fab")
		)
		(fp_line
			(start -0.67945 0.3048)
			(end -0.67945 -0.305054)
			(stroke
				(width 0.1)
				(type default)
			)
			(layer "F.Fab")
		)
		(fp_line
			(start -0.67945 -0.305054)
			(end -0.12065 -0.305054)
			(stroke
				(width 0.1)
				(type default)
			)
			(layer "F.Fab")
		)
		(pad "1" smd circle
			(at -0.40005 0 180)
			(size 0 0)
			(layers "F.Cu" "F.Mask" "F.Paste")
			(net "P3V3_AUX")
		)
		(pad "2" smd circle
			(at 0.40005 0 180)
			(size 0 0)
			(layers "F.Cu" "F.Mask" "F.Paste")
			(net "GND")
		)
	)
	(footprint ""
		(layer "F.Cu")
		(at 281.02052 -70.307454 90)
		(property "Reference" "PC869"
			(at 0 0 90)
			(layer "F.SilkS")
			(hide yes)
			(effects
				(font
					(size 1.27 1.27)
				)
			)
		)
		(property "Value" ""
			(at 0 0 90)
			(layer "F.Fab")
			(effects
				(font
					(size 1.27 1.27)
				)
			)
		)
		(duplicate_pad_numbers_are_jumpers no)
		(fp_line
			(start 0.7874 -0.4064)
			(end 0.7874 0.4064)
			(stroke
				(width 0.1524)
				(type default)
			)
			(layer "F.SilkS")
		)
		(fp_line
			(start -0.7874 -0.4064)
			(end 0.7874 -0.4064)
			(stroke
				(width 0.1524)
				(type default)
			)
			(layer "F.SilkS")
		)
		(fp_line
			(start 0.7874 0.4064)
			(end -0.7874 0.4064)
			(stroke
				(width 0.1524)
				(type default)
			)
			(layer "F.SilkS")
		)
		(fp_line
			(start -0.7874 0.4064)
			(end -0.7874 -0.4064)
			(stroke
				(width 0.1524)
				(type default)
			)
			(layer "F.SilkS")
		)
		(fp_line
			(start -0.12065 -0.305054)
			(end -0.12065 -0.2794)
			(stroke
				(width 0.1)
				(type default)
			)
			(layer "F.Fab")
		)
		(fp_line
			(start -0.67945 -0.305054)
			(end -0.12065 -0.305054)
			(stroke
				(width 0.1)
				(type default)
			)
			(layer "F.Fab")
		)
		(fp_line
			(start 0.67945 -0.3048)
			(end 0.67945 0.3048)
			(stroke
				(width 0.1)
				(type default)
			)
			(layer "F.Fab")
		)
		(fp_line
			(start 0.12065 -0.3048)
			(end 0.67945 -0.3048)
			(stroke
				(width 0.1)
				(type default)
			)
			(layer "F.Fab")
		)
		(fp_line
			(start 0.12065 -0.2794)
			(end 0.12065 -0.3048)
			(stroke
				(width 0.1)
				(type default)
			)
			(layer "F.Fab")
		)
		(fp_line
			(start -0.12065 -0.2794)
			(end 0.12065 -0.2794)
			(stroke
				(width 0.1)
				(type default)
			)
			(layer "F.Fab")
		)
		(fp_line
			(start 0.120396 0.2794)
			(end -0.12065 0.2794)
			(stroke
				(width 0.1)
				(type default)
			)
			(layer "F.Fab")
		)
		(fp_line
			(start -0.12065 0.2794)
			(end -0.12065 0.3048)
			(stroke
				(width 0.1)
				(type default)
			)
			(layer "F.Fab")
		)
		(fp_line
			(start 0.67945 0.3048)
			(end 0.120396 0.3048)
			(stroke
				(width 0.1)
				(type default)
			)
			(layer "F.Fab")
		)
		(fp_line
			(start 0.120396 0.3048)
			(end 0.120396 0.2794)
			(stroke
				(width 0.1)
				(type default)
			)
			(layer "F.Fab")
		)
		(fp_line
			(start -0.12065 0.3048)
			(end -0.67945 0.3048)
			(stroke
				(width 0.1)
				(type default)
			)
			(layer "F.Fab")
		)
		(fp_line
			(start -0.67945 0.3048)
			(end -0.67945 -0.305054)
			(stroke
				(width 0.1)
				(type default)
			)
			(layer "F.Fab")
		)
		(pad "1" smd circle
			(at -0.40005 0 90)
			(size 0 0)
			(layers "F.Cu" "F.Mask" "F.Paste")
			(net "P12V_AUX")
		)
		(pad "2" smd circle
			(at 0.40005 0 90)
			(size 0 0)
			(layers "F.Cu" "F.Mask" "F.Paste")
			(net "GND")
		)
	)
	(footprint ""
		(layer "F.Cu")
		(at 304.64633 -58.323734)
		(property "Reference" "PC427"
			(at 0 0 0)
			(layer "F.SilkS")
			(hide yes)
			(effects
				(font
					(size 1.27 1.27)
				)
			)
		)
		(property "Value" ""
			(at 0 0 0)
			(layer "F.Fab")
			(effects
				(font
					(size 1.27 1.27)
				)
			)
		)
		(duplicate_pad_numbers_are_jumpers no)
		(fp_line
			(start -1.524 -0.762)
			(end 1.524 -0.762)
			(stroke
				(width 0.1524)
				(type default)
			)
			(layer "F.SilkS")
		)
		(fp_line
			(start -1.524 0.762)
			(end -1.524 -0.762)
			(stroke
				(width 0.1524)
				(type default)
			)
			(layer "F.SilkS")
		)
		(fp_line
			(start 1.524 -0.762)
			(end 1.524 0.762)
			(stroke
				(width 0.1524)
				(type default)
			)
			(layer "F.SilkS")
		)
		(fp_line
			(start 1.524 0.762)
			(end -1.524 0.762)
			(stroke
				(width 0.1524)
				(type default)
			)
			(layer "F.SilkS")
		)
		(fp_line
			(start -1.1049 -0.724916)
			(end -1.1049 0.724916)
			(stroke
				(width 0.1)
				(type default)
			)
			(layer "F.Fab")
		)
		(fp_line
			(start -1.1049 0.724916)
			(end 1.1049 0.724916)
			(stroke
				(width 0.1)
				(type default)
			)
			(layer "F.Fab")
		)
		(fp_line
			(start 1.1049 -0.724916)
			(end -1.1049 -0.724916)
			(stroke
				(width 0.1)
				(type default)
			)
			(layer "F.Fab")
		)
		(fp_line
			(start 1.1049 0.724916)
			(end 1.1049 -0.724916)
			(stroke
				(width 0.1)
				(type default)
			)
			(layer "F.Fab")
		)
		(pad "1" smd rect
			(at -0.889 0 180)
			(size 1.016 1.27)
			(layers "F.Cu" "F.Mask" "F.Paste")
			(net "GND")
		)
		(pad "2" smd rect
			(at 0.889 0 180)
			(size 1.016 1.27)
			(layers "F.Cu" "F.Mask" "F.Paste")
			(net "P12V_AUX")
		)
	)
	(footprint ""
		(layer "F.Cu")
		(at 273.342608 -70.844918 -90)
		(property "Reference" "PD110"
			(at 4.093718 2.221738 90)
			(unlocked yes)
			(layer "F.SilkS")
			(effects
				(font
					(size 0.7874 0.5842)
					(thickness 0.1524)
				)
				(justify left)
			)
		)
		(property "Value" ""
			(at 0 0 270)
			(layer "F.Fab")
			(effects
				(font
					(size 1.27 1.27)
				)
			)
		)
		(duplicate_pad_numbers_are_jumpers no)
		(fp_line
			(start -3.400044 1.459992)
			(end -3.400044 -1.459992)
			(stroke
				(width 0.1524)
				(type default)
			)
			(layer "F.SilkS")
		)
		(fp_line
			(start 4.107942 1.459992)
			(end -3.400044 1.459992)
			(stroke
				(width 0.1524)
				(type default)
			)
			(layer "F.SilkS")
		)
		(fp_line
			(start -3.400044 -1.459992)
			(end 4.107942 -1.459992)
			(stroke
				(width 0.1524)
				(type default)
			)
			(layer "F.SilkS")
		)
		(fp_line
			(start 4.107942 -1.459992)
			(end 4.107942 1.459992)
			(stroke
				(width 0.1524)
				(type default)
			)
			(layer "F.SilkS")
		)
		(fp_poly
			(pts
				(xy 4.107942 -1.459992) (xy 4.107942 1.459992) (xy 3.308096 1.459992) (xy 3.308096 -1.459992)
			)
			(stroke
				(width 0)
				(type default)
			)
			(fill yes)
			(layer "F.SilkS")
		)
		(fp_line
			(start -2.29997 1.459992)
			(end -2.29997 -1.459992)
			(stroke
				(width 0.1)
				(type default)
			)
			(layer "F.Fab")
		)
		(fp_line
			(start 2.29997 1.459992)
			(end -2.29997 1.459992)
			(stroke
				(width 0.1)
				(type default)
			)
			(layer "F.Fab")
		)
		(fp_line
			(start -2.29997 -1.459992)
			(end 2.29997 -1.459992)
			(stroke
				(width 0.1)
				(type default)
			)
			(layer "F.Fab")
		)
		(fp_line
			(start 2.29997 -1.459992)
			(end 2.29997 1.459992)
			(stroke
				(width 0.1)
				(type default)
			)
			(layer "F.Fab")
		)
		(fp_text user "-"
			(at 5.4102 0.29845 90)
			(unlocked yes)
			(layer "F.SilkS")
			(effects
				(font
					(size 1.905 1.4224)
					(thickness 0.1524)
				)
				(justify left)
			)
		)
		(fp_text user "+"
			(at -5.093716 -1.278128 270)
			(unlocked yes)
			(layer "F.SilkS")
			(effects
				(font
					(size 1.905 1.4224)
					(thickness 0.1524)
				)
				(justify left)
			)
		)
		(fp_text user "-"
			(at 5.4102 0.29845 90)
			(unlocked yes)
			(layer "F.Fab")
			(effects
				(font
					(size 1.905 1.4224)
					(thickness 0.1524)
				)
				(justify left)
			)
		)
		(fp_text user "+"
			(at -4.7752 -0.12065 270)
			(unlocked yes)
			(layer "F.Fab")
			(effects
				(font
					(size 1.905 1.4224)
					(thickness 0.1524)
				)
				(justify left)
			)
		)
		(pad "A" smd rect
			(at -1.999996 0)
			(size 1.7018 2.5146)
			(layers "F.Cu" "F.Mask" "F.Paste")
			(net "GND")
		)
		(pad "C" smd rect
			(at 1.999996 0)
			(size 1.7018 2.5146)
			(layers "F.Cu" "F.Mask" "F.Paste")
			(net "P12V_SSD9_R")
		)
	)
	(footprint ""
		(layer "F.Cu")
		(at 284.330902 -343.952322 90)
		(property "Reference" "C600"
			(at 0 0 90)
			(layer "F.SilkS")
			(hide yes)
			(effects
				(font
					(size 1.27 1.27)
				)
			)
		)
		(property "Value" ""
			(at 0 0 90)
			(layer "F.Fab")
			(effects
				(font
					(size 1.27 1.27)
				)
			)
		)
		(duplicate_pad_numbers_are_jumpers no)
		(fp_line
			(start 0.299974 -0.150114)
			(end 0.299974 0.150114)
			(stroke
				(width 0.1)
				(type default)
			)
			(layer "F.Fab")
		)
		(fp_line
			(start -0.299974 -0.150114)
			(end 0.299974 -0.150114)
			(stroke
				(width 0.1)
				(type default)
			)
			(layer "F.Fab")
		)
		(fp_line
			(start 0.299974 0.150114)
			(end -0.299974 0.150114)
			(stroke
				(width 0.1)
				(type default)
			)
			(layer "F.Fab")
		)
		(fp_line
			(start -0.299974 0.150114)
			(end -0.299974 -0.150114)
			(stroke
				(width 0.1)
				(type default)
			)
			(layer "F.Fab")
		)
		(pad "1" smd rect
			(at -0.2667 0 90)
			(size 0.3048 0.381)
			(layers "F.Cu" "F.Mask" "F.Paste")
			(net "P5E_PEX2_STN7_TX_DN<119>")
		)
		(pad "2" smd rect
			(at 0.2667 0 90)
			(size 0.3048 0.381)
			(layers "F.Cu" "F.Mask" "F.Paste")
			(net "P5E_PEX2_STN7_TX_C_DN<119>")
		)
	)
	(footprint ""
		(layer "F.Cu")
		(at 340.561422 -191.43345 180)
		(property "Reference" "R4241"
			(at 0 0 180)
			(layer "F.SilkS")
			(hide yes)
			(effects
				(font
					(size 1.27 1.27)
				)
			)
		)
		(property "Value" ""
			(at 0 0 180)
			(layer "F.Fab")
			(effects
				(font
					(size 1.27 1.27)
				)
			)
		)
		(duplicate_pad_numbers_are_jumpers no)
		(fp_line
			(start 0.7874 0.4064)
			(end -0.7874 0.4064)
			(stroke
				(width 0.1524)
				(type default)
			)
			(layer "F.SilkS")
		)
		(fp_line
			(start 0.7874 -0.4064)
			(end 0.7874 0.4064)
			(stroke
				(width 0.1524)
				(type default)
			)
			(layer "F.SilkS")
		)
		(fp_line
			(start -0.7874 0.4064)
			(end -0.7874 -0.4064)
			(stroke
				(width 0.1524)
				(type default)
			)
			(layer "F.SilkS")
		)
		(fp_line
			(start -0.7874 -0.4064)
			(end 0.7874 -0.4064)
			(stroke
				(width 0.1524)
				(type default)
			)
			(layer "F.SilkS")
		)
		(fp_line
			(start 0.67945 0.3048)
			(end 0.120396 0.3048)
			(stroke
				(width 0.1)
				(type default)
			)
			(layer "F.Fab")
		)
		(fp_line
			(start 0.67945 -0.3048)
			(end 0.67945 0.3048)
			(stroke
				(width 0.1)
				(type default)
			)
			(layer "F.Fab")
		)
		(fp_line
			(start 0.12065 -0.2794)
			(end 0.12065 -0.3048)
			(stroke
				(width 0.1)
				(type default)
			)
			(layer "F.Fab")
		)
		(fp_line
			(start 0.12065 -0.3048)
			(end 0.67945 -0.3048)
			(stroke
				(width 0.1)
				(type default)
			)
			(layer "F.Fab")
		)
		(fp_line
			(start 0.120396 0.3048)
			(end 0.120396 0.2794)
			(stroke
				(width 0.1)
				(type default)
			)
			(layer "F.Fab")
		)
		(fp_line
			(start 0.120396 0.2794)
			(end -0.12065 0.2794)
			(stroke
				(width 0.1)
				(type default)
			)
			(layer "F.Fab")
		)
		(fp_line
			(start -0.12065 0.3048)
			(end -0.67945 0.3048)
			(stroke
				(width 0.1)
				(type default)
			)
			(layer "F.Fab")
		)
		(fp_line
			(start -0.12065 0.2794)
			(end -0.12065 0.3048)
			(stroke
				(width 0.1)
				(type default)
			)
			(layer "F.Fab")
		)
		(fp_line
			(start -0.12065 -0.2794)
			(end 0.12065 -0.2794)
			(stroke
				(width 0.1)
				(type default)
			)
			(layer "F.Fab")
		)
		(fp_line
			(start -0.12065 -0.305054)
			(end -0.12065 -0.2794)
			(stroke
				(width 0.1)
				(type default)
			)
			(layer "F.Fab")
		)
		(fp_line
			(start -0.67945 0.3048)
			(end -0.67945 -0.305054)
			(stroke
				(width 0.1)
				(type default)
			)
			(layer "F.Fab")
		)
		(fp_line
			(start -0.67945 -0.305054)
			(end -0.12065 -0.305054)
			(stroke
				(width 0.1)
				(type default)
			)
			(layer "F.Fab")
		)
		(pad "1" smd circle
			(at -0.40005 0 180)
			(size 0 0)
			(layers "F.Cu" "F.Mask" "F.Paste")
			(net "P3V3_AUX")
		)
		(pad "2" smd circle
			(at 0.40005 0 180)
			(size 0 0)
			(layers "F.Cu" "F.Mask" "F.Paste")
			(net "PWRGD_DSW_PWROK")
		)
	)
	(footprint ""
		(layer "F.Cu")
		(at 124.149612 -157.812994)
		(property "Reference" "R945"
			(at 0 0 0)
			(layer "F.SilkS")
			(hide yes)
			(effects
				(font
					(size 1.27 1.27)
				)
			)
		)
		(property "Value" ""
			(at 0 0 0)
			(layer "F.Fab")
			(effects
				(font
					(size 1.27 1.27)
				)
			)
		)
		(duplicate_pad_numbers_are_jumpers no)
		(fp_line
			(start -0.7874 -0.4064)
			(end 0.7874 -0.4064)
			(stroke
				(width 0.1524)
				(type default)
			)
			(layer "F.SilkS")
		)
		(fp_line
			(start -0.7874 0.4064)
			(end -0.7874 -0.4064)
			(stroke
				(width 0.1524)
				(type default)
			)
			(layer "F.SilkS")
		)
		(fp_line
			(start 0.7874 -0.4064)
			(end 0.7874 0.4064)
			(stroke
				(width 0.1524)
				(type default)
			)
			(layer "F.SilkS")
		)
		(fp_line
			(start 0.7874 0.4064)
			(end -0.7874 0.4064)
			(stroke
				(width 0.1524)
				(type default)
			)
			(layer "F.SilkS")
		)
		(fp_line
			(start -0.67945 -0.305054)
			(end -0.12065 -0.305054)
			(stroke
				(width 0.1)
				(type default)
			)
			(layer "F.Fab")
		)
		(fp_line
			(start -0.67945 0.3048)
			(end -0.67945 -0.305054)
			(stroke
				(width 0.1)
				(type default)
			)
			(layer "F.Fab")
		)
		(fp_line
			(start -0.12065 -0.305054)
			(end -0.12065 -0.2794)
			(stroke
				(width 0.1)
				(type default)
			)
			(layer "F.Fab")
		)
		(fp_line
			(start -0.12065 -0.2794)
			(end 0.12065 -0.2794)
			(stroke
				(width 0.1)
				(type default)
			)
			(layer "F.Fab")
		)
		(fp_line
			(start -0.12065 0.2794)
			(end -0.12065 0.3048)
			(stroke
				(width 0.1)
				(type default)
			)
			(layer "F.Fab")
		)
		(fp_line
			(start -0.12065 0.3048)
			(end -0.67945 0.3048)
			(stroke
				(width 0.1)
				(type default)
			)
			(layer "F.Fab")
		)
		(fp_line
			(start 0.120396 0.2794)
			(end -0.12065 0.2794)
			(stroke
				(width 0.1)
				(type default)
			)
			(layer "F.Fab")
		)
		(fp_line
			(start 0.120396 0.3048)
			(end 0.120396 0.2794)
			(stroke
				(width 0.1)
				(type default)
			)
			(layer "F.Fab")
		)
		(fp_line
			(start 0.12065 -0.3048)
			(end 0.67945 -0.3048)
			(stroke
				(width 0.1)
				(type default)
			)
			(layer "F.Fab")
		)
		(fp_line
			(start 0.12065 -0.2794)
			(end 0.12065 -0.3048)
			(stroke
				(width 0.1)
				(type default)
			)
			(layer "F.Fab")
		)
		(fp_line
			(start 0.67945 -0.3048)
			(end 0.67945 0.3048)
			(stroke
				(width 0.1)
				(type default)
			)
			(layer "F.Fab")
		)
		(fp_line
			(start 0.67945 0.3048)
			(end 0.120396 0.3048)
			(stroke
				(width 0.1)
				(type default)
			)
			(layer "F.Fab")
		)
		(pad "1" smd circle
			(at -0.40005 0)
			(size 0 0)
			(layers "F.Cu" "F.Mask" "F.Paste")
			(net "P3V3_AUX")
		)
		(pad "2" smd circle
			(at 0.40005 0)
			(size 0 0)
			(layers "F.Cu" "F.Mask" "F.Paste")
			(net "PWRGD_P12V_NIC2_CO")
		)
	)
	(footprint ""
		(layer "F.Cu")
		(at 351.17024 -237.698534 90)
		(property "Reference" "R6834"
			(at 0 0 90)
			(layer "F.SilkS")
			(hide yes)
			(effects
				(font
					(size 1.27 1.27)
				)
			)
		)
		(property "Value" ""
			(at 0 0 90)
			(layer "F.Fab")
			(effects
				(font
					(size 1.27 1.27)
				)
			)
		)
		(duplicate_pad_numbers_are_jumpers no)
		(fp_line
			(start 0.7874 -0.4064)
			(end 0.7874 0.4064)
			(stroke
				(width 0.1524)
				(type default)
			)
			(layer "F.SilkS")
		)
		(fp_line
			(start -0.7874 -0.4064)
			(end 0.7874 -0.4064)
			(stroke
				(width 0.1524)
				(type default)
			)
			(layer "F.SilkS")
		)
		(fp_line
			(start 0.7874 0.4064)
			(end -0.7874 0.4064)
			(stroke
				(width 0.1524)
				(type default)
			)
			(layer "F.SilkS")
		)
		(fp_line
			(start -0.7874 0.4064)
			(end -0.7874 -0.4064)
			(stroke
				(width 0.1524)
				(type default)
			)
			(layer "F.SilkS")
		)
		(fp_line
			(start -0.12065 -0.305054)
			(end -0.12065 -0.2794)
			(stroke
				(width 0.1)
				(type default)
			)
			(layer "F.Fab")
		)
		(fp_line
			(start -0.67945 -0.305054)
			(end -0.12065 -0.305054)
			(stroke
				(width 0.1)
				(type default)
			)
			(layer "F.Fab")
		)
		(fp_line
			(start 0.67945 -0.3048)
			(end 0.67945 0.3048)
			(stroke
				(width 0.1)
				(type default)
			)
			(layer "F.Fab")
		)
		(fp_line
			(start 0.12065 -0.3048)
			(end 0.67945 -0.3048)
			(stroke
				(width 0.1)
				(type default)
			)
			(layer "F.Fab")
		)
		(fp_line
			(start 0.12065 -0.2794)
			(end 0.12065 -0.3048)
			(stroke
				(width 0.1)
				(type default)
			)
			(layer "F.Fab")
		)
		(fp_line
			(start -0.12065 -0.2794)
			(end 0.12065 -0.2794)
			(stroke
				(width 0.1)
				(type default)
			)
			(layer "F.Fab")
		)
		(fp_line
			(start 0.120396 0.2794)
			(end -0.12065 0.2794)
			(stroke
				(width 0.1)
				(type default)
			)
			(layer "F.Fab")
		)
		(fp_line
			(start -0.12065 0.2794)
			(end -0.12065 0.3048)
			(stroke
				(width 0.1)
				(type default)
			)
			(layer "F.Fab")
		)
		(fp_line
			(start 0.67945 0.3048)
			(end 0.120396 0.3048)
			(stroke
				(width 0.1)
				(type default)
			)
			(layer "F.Fab")
		)
		(fp_line
			(start 0.120396 0.3048)
			(end 0.120396 0.2794)
			(stroke
				(width 0.1)
				(type default)
			)
			(layer "F.Fab")
		)
		(fp_line
			(start -0.12065 0.3048)
			(end -0.67945 0.3048)
			(stroke
				(width 0.1)
				(type default)
			)
			(layer "F.Fab")
		)
		(fp_line
			(start -0.67945 0.3048)
			(end -0.67945 -0.305054)
			(stroke
				(width 0.1)
				(type default)
			)
			(layer "F.Fab")
		)
		(pad "1" smd circle
			(at -0.40005 0 90)
			(size 0 0)
			(layers "F.Cu" "F.Mask" "F.Paste")
			(net "SSD7_PWR_EN_R")
		)
		(pad "2" smd circle
			(at 0.40005 0 90)
			(size 0 0)
			(layers "F.Cu" "F.Mask" "F.Paste")
			(net "GND")
		)
	)
	(footprint ""
		(layer "F.Cu")
		(at 359.85831 -256.226564 180)
		(property "Reference" "PR134"
			(at 0 0 180)
			(layer "F.SilkS")
			(hide yes)
			(effects
				(font
					(size 1.27 1.27)
				)
			)
		)
		(property "Value" ""
			(at 0 0 180)
			(layer "F.Fab")
			(effects
				(font
					(size 1.27 1.27)
				)
			)
		)
		(duplicate_pad_numbers_are_jumpers no)
		(fp_line
			(start 0.7874 0.4064)
			(end -0.7874 0.4064)
			(stroke
				(width 0.1524)
				(type default)
			)
			(layer "F.SilkS")
		)
		(fp_line
			(start 0.7874 -0.4064)
			(end 0.7874 0.4064)
			(stroke
				(width 0.1524)
				(type default)
			)
			(layer "F.SilkS")
		)
		(fp_line
			(start -0.7874 0.4064)
			(end -0.7874 -0.4064)
			(stroke
				(width 0.1524)
				(type default)
			)
			(layer "F.SilkS")
		)
		(fp_line
			(start -0.7874 -0.4064)
			(end 0.7874 -0.4064)
			(stroke
				(width 0.1524)
				(type default)
			)
			(layer "F.SilkS")
		)
		(fp_line
			(start 0.67945 0.3048)
			(end 0.120396 0.3048)
			(stroke
				(width 0.1)
				(type default)
			)
			(layer "F.Fab")
		)
		(fp_line
			(start 0.67945 -0.3048)
			(end 0.67945 0.3048)
			(stroke
				(width 0.1)
				(type default)
			)
			(layer "F.Fab")
		)
		(fp_line
			(start 0.12065 -0.2794)
			(end 0.12065 -0.3048)
			(stroke
				(width 0.1)
				(type default)
			)
			(layer "F.Fab")
		)
		(fp_line
			(start 0.12065 -0.3048)
			(end 0.67945 -0.3048)
			(stroke
				(width 0.1)
				(type default)
			)
			(layer "F.Fab")
		)
		(fp_line
			(start 0.120396 0.3048)
			(end 0.120396 0.2794)
			(stroke
				(width 0.1)
				(type default)
			)
			(layer "F.Fab")
		)
		(fp_line
			(start 0.120396 0.2794)
			(end -0.12065 0.2794)
			(stroke
				(width 0.1)
				(type default)
			)
			(layer "F.Fab")
		)
		(fp_line
			(start -0.12065 0.3048)
			(end -0.67945 0.3048)
			(stroke
				(width 0.1)
				(type default)
			)
			(layer "F.Fab")
		)
		(fp_line
			(start -0.12065 0.2794)
			(end -0.12065 0.3048)
			(stroke
				(width 0.1)
				(type default)
			)
			(layer "F.Fab")
		)
		(fp_line
			(start -0.12065 -0.2794)
			(end 0.12065 -0.2794)
			(stroke
				(width 0.1)
				(type default)
			)
			(layer "F.Fab")
		)
		(fp_line
			(start -0.12065 -0.305054)
			(end -0.12065 -0.2794)
			(stroke
				(width 0.1)
				(type default)
			)
			(layer "F.Fab")
		)
		(fp_line
			(start -0.67945 0.3048)
			(end -0.67945 -0.305054)
			(stroke
				(width 0.1)
				(type default)
			)
			(layer "F.Fab")
		)
		(fp_line
			(start -0.67945 -0.305054)
			(end -0.12065 -0.305054)
			(stroke
				(width 0.1)
				(type default)
			)
			(layer "F.Fab")
		)
		(pad "1" smd circle
			(at -0.40005 0 180)
			(size 0 0)
			(layers "F.Cu" "F.Mask" "F.Paste")
			(net "P3V3_AUX")
		)
		(pad "2" smd circle
			(at 0.40005 0 180)
			(size 0 0)
			(layers "F.Cu" "F.Mask" "F.Paste")
			(net "P0V8_PEX2_VRHOT_R")
		)
	)
	(footprint ""
		(layer "F.Cu")
		(at 384.938524 -131.323334)
		(property "Reference" "C673"
			(at 0 0 0)
			(layer "F.SilkS")
			(hide yes)
			(effects
				(font
					(size 1.27 1.27)
				)
			)
		)
		(property "Value" ""
			(at 0 0 0)
			(layer "F.Fab")
			(effects
				(font
					(size 1.27 1.27)
				)
			)
		)
		(duplicate_pad_numbers_are_jumpers no)
		(fp_line
			(start -0.299974 -0.150114)
			(end 0.299974 -0.150114)
			(stroke
				(width 0.1)
				(type default)
			)
			(layer "F.Fab")
		)
		(fp_line
			(start -0.299974 0.150114)
			(end -0.299974 -0.150114)
			(stroke
				(width 0.1)
				(type default)
			)
			(layer "F.Fab")
		)
		(fp_line
			(start 0.299974 -0.150114)
			(end 0.299974 0.150114)
			(stroke
				(width 0.1)
				(type default)
			)
			(layer "F.Fab")
		)
		(fp_line
			(start 0.299974 0.150114)
			(end -0.299974 0.150114)
			(stroke
				(width 0.1)
				(type default)
			)
			(layer "F.Fab")
		)
		(pad "1" smd rect
			(at -0.2667 0)
			(size 0.3048 0.381)
			(layers "F.Cu" "F.Mask" "F.Paste")
			(net "P5E_PEX3_STN1_TX_DN<28>")
		)
		(pad "2" smd rect
			(at 0.2667 0)
			(size 0.3048 0.381)
			(layers "F.Cu" "F.Mask" "F.Paste")
			(net "P5E_PEX3_STN1_TX_C_DN<28>")
		)
	)
	(footprint ""
		(layer "F.Cu")
		(at 258.46786 -55.083456)
		(property "Reference" "PC408"
			(at 0 0 0)
			(layer "F.SilkS")
			(hide yes)
			(effects
				(font
					(size 1.27 1.27)
				)
			)
		)
		(property "Value" ""
			(at 0 0 0)
			(layer "F.Fab")
			(effects
				(font
					(size 1.27 1.27)
				)
			)
		)
		(duplicate_pad_numbers_are_jumpers no)
		(fp_line
			(start -0.7874 -0.4064)
			(end 0.7874 -0.4064)
			(stroke
				(width 0.1524)
				(type default)
			)
			(layer "F.SilkS")
		)
		(fp_line
			(start -0.7874 0.4064)
			(end -0.7874 -0.4064)
			(stroke
				(width 0.1524)
				(type default)
			)
			(layer "F.SilkS")
		)
		(fp_line
			(start 0.7874 -0.4064)
			(end 0.7874 0.4064)
			(stroke
				(width 0.1524)
				(type default)
			)
			(layer "F.SilkS")
		)
		(fp_line
			(start 0.7874 0.4064)
			(end -0.7874 0.4064)
			(stroke
				(width 0.1524)
				(type default)
			)
			(layer "F.SilkS")
		)
		(fp_line
			(start -0.67945 -0.305054)
			(end -0.12065 -0.305054)
			(stroke
				(width 0.1)
				(type default)
			)
			(layer "F.Fab")
		)
		(fp_line
			(start -0.67945 0.3048)
			(end -0.67945 -0.305054)
			(stroke
				(width 0.1)
				(type default)
			)
			(layer "F.Fab")
		)
		(fp_line
			(start -0.12065 -0.305054)
			(end -0.12065 -0.2794)
			(stroke
				(width 0.1)
				(type default)
			)
			(layer "F.Fab")
		)
		(fp_line
			(start -0.12065 -0.2794)
			(end 0.12065 -0.2794)
			(stroke
				(width 0.1)
				(type default)
			)
			(layer "F.Fab")
		)
		(fp_line
			(start -0.12065 0.2794)
			(end -0.12065 0.3048)
			(stroke
				(width 0.1)
				(type default)
			)
			(layer "F.Fab")
		)
		(fp_line
			(start -0.12065 0.3048)
			(end -0.67945 0.3048)
			(stroke
				(width 0.1)
				(type default)
			)
			(layer "F.Fab")
		)
		(fp_line
			(start 0.120396 0.2794)
			(end -0.12065 0.2794)
			(stroke
				(width 0.1)
				(type default)
			)
			(layer "F.Fab")
		)
		(fp_line
			(start 0.120396 0.3048)
			(end 0.120396 0.2794)
			(stroke
				(width 0.1)
				(type default)
			)
			(layer "F.Fab")
		)
		(fp_line
			(start 0.12065 -0.3048)
			(end 0.67945 -0.3048)
			(stroke
				(width 0.1)
				(type default)
			)
			(layer "F.Fab")
		)
		(fp_line
			(start 0.12065 -0.2794)
			(end 0.12065 -0.3048)
			(stroke
				(width 0.1)
				(type default)
			)
			(layer "F.Fab")
		)
		(fp_line
			(start 0.67945 -0.3048)
			(end 0.67945 0.3048)
			(stroke
				(width 0.1)
				(type default)
			)
			(layer "F.Fab")
		)
		(fp_line
			(start 0.67945 0.3048)
			(end 0.120396 0.3048)
			(stroke
				(width 0.1)
				(type default)
			)
			(layer "F.Fab")
		)
		(pad "1" smd circle
			(at -0.40005 0)
			(size 0 0)
			(layers "F.Cu" "F.Mask" "F.Paste")
			(net "P5V_AUX")
		)
		(pad "2" smd circle
			(at 0.40005 0)
			(size 0 0)
			(layers "F.Cu" "F.Mask" "F.Paste")
			(net "GND")
		)
	)
	(footprint ""
		(layer "F.Cu")
		(at 413.867854 -223.863662)
		(property "Reference" "J68"
			(at -7.126986 0.264668 0)
			(unlocked yes)
			(layer "F.SilkS")
			(effects
				(font
					(size 0.7874 0.5842)
					(thickness 0.1524)
				)
				(justify left)
			)
		)
		(property "Value" ""
			(at 0 0 0)
			(layer "F.Fab")
			(effects
				(font
					(size 1.27 1.27)
				)
			)
		)
		(duplicate_pad_numbers_are_jumpers no)
		(fp_line
			(start -1.27 -3.81)
			(end 1.27 -3.81)
			(stroke
				(width 0.1524)
				(type default)
			)
			(layer "F.SilkS")
		)
		(fp_line
			(start -1.27 -0.7747)
			(end -1.27 -3.81)
			(stroke
				(width 0.1524)
				(type default)
			)
			(layer "F.SilkS")
		)
		(fp_line
			(start -1.27 3.81)
			(end -1.27 0.7747)
			(stroke
				(width 0.1524)
				(type default)
			)
			(layer "F.SilkS")
		)
		(fp_line
			(start 1.27 -3.81)
			(end 1.27 -3.3147)
			(stroke
				(width 0.1524)
				(type default)
			)
			(layer "F.SilkS")
		)
		(fp_line
			(start 1.27 -1.7653)
			(end 1.27 1.7653)
			(stroke
				(width 0.1524)
				(type default)
			)
			(layer "F.SilkS")
		)
		(fp_line
			(start 1.27 3.3147)
			(end 1.27 3.81)
			(stroke
				(width 0.1524)
				(type default)
			)
			(layer "F.SilkS")
		)
		(fp_line
			(start 1.27 3.81)
			(end -1.27 3.81)
			(stroke
				(width 0.1524)
				(type default)
			)
			(layer "F.SilkS")
		)
		(fp_poly
			(pts
				(xy 4.3942 -3.048) (xy 4.3942 -2.032) (xy 3.3782 -2.54)
			)
			(stroke
				(width 0)
				(type default)
			)
			(fill yes)
			(layer "F.SilkS")
		)
		(fp_line
			(start -1.27 -3.81)
			(end -1.27 3.81)
			(stroke
				(width 0.1)
				(type default)
			)
			(layer "F.Fab")
		)
		(fp_line
			(start -1.27 3.81)
			(end 1.27 3.81)
			(stroke
				(width 0.1)
				(type default)
			)
			(layer "F.Fab")
		)
		(fp_line
			(start 1.27 -3.81)
			(end -1.27 -3.81)
			(stroke
				(width 0.1)
				(type default)
			)
			(layer "F.Fab")
		)
		(fp_line
			(start 1.27 3.81)
			(end 1.27 -3.81)
			(stroke
				(width 0.1)
				(type default)
			)
			(layer "F.Fab")
		)
		(fp_poly
			(pts
				(xy 4.3942 -3.048) (xy 4.3942 -2.032) (xy 3.3782 -2.54)
			)
			(stroke
				(width 0)
				(type default)
			)
			(fill yes)
			(layer "F.Fab")
		)
		(fp_text user "3"
			(at 3.921252 2.54 90)
			(unlocked yes)
			(layer "F.SilkS")
			(effects
				(font
					(size 0.7874 0.5842)
					(thickness 0.1524)
				)
			)
		)
		(fp_text user "3"
			(at 3.921252 2.54 90)
			(unlocked yes)
			(layer "F.Fab")
			(effects
				(font
					(size 0.7874 0.5842)
					(thickness 0.1524)
				)
			)
		)
		(pad "1" smd rect
			(at 1.459992 -2.54 90)
			(size 1.27 3.429)
			(layers "F.Cu" "F.Mask" "F.Paste")
			(net "GND")
		)
		(pad "2" smd rect
			(at -1.459992 0 90)
			(size 1.27 3.429)
			(layers "F.Cu" "F.Mask" "F.Paste")
			(net "UART_PEX0_SDB_BUF_R1_TX")
		)
		(pad "3" smd rect
			(at 1.459992 2.54 90)
			(size 1.27 3.429)
			(layers "F.Cu" "F.Mask" "F.Paste")
			(net "UART_PEX0_SDB_R1_RX")
		)
	)
	(footprint ""
		(layer "F.Cu")
		(at 145.999962 -243.130578)
		(property "Reference" "C4423"
			(at 0 0 0)
			(layer "F.SilkS")
			(hide yes)
			(effects
				(font
					(size 1.27 1.27)
				)
			)
		)
		(property "Value" ""
			(at 0 0 0)
			(layer "F.Fab")
			(effects
				(font
					(size 1.27 1.27)
				)
			)
		)
		(duplicate_pad_numbers_are_jumpers no)
		(fp_line
			(start -0.7874 -0.4064)
			(end 0.7874 -0.4064)
			(stroke
				(width 0.1524)
				(type default)
			)
			(layer "F.SilkS")
		)
		(fp_line
			(start -0.7874 0.4064)
			(end -0.7874 -0.4064)
			(stroke
				(width 0.1524)
				(type default)
			)
			(layer "F.SilkS")
		)
		(fp_line
			(start 0.7874 -0.4064)
			(end 0.7874 0.4064)
			(stroke
				(width 0.1524)
				(type default)
			)
			(layer "F.SilkS")
		)
		(fp_line
			(start 0.7874 0.4064)
			(end -0.7874 0.4064)
			(stroke
				(width 0.1524)
				(type default)
			)
			(layer "F.SilkS")
		)
		(fp_line
			(start -0.67945 -0.305054)
			(end -0.12065 -0.305054)
			(stroke
				(width 0.1)
				(type default)
			)
			(layer "F.Fab")
		)
		(fp_line
			(start -0.67945 0.3048)
			(end -0.67945 -0.305054)
			(stroke
				(width 0.1)
				(type default)
			)
			(layer "F.Fab")
		)
		(fp_line
			(start -0.12065 -0.305054)
			(end -0.12065 -0.2794)
			(stroke
				(width 0.1)
				(type default)
			)
			(layer "F.Fab")
		)
		(fp_line
			(start -0.12065 -0.2794)
			(end 0.12065 -0.2794)
			(stroke
				(width 0.1)
				(type default)
			)
			(layer "F.Fab")
		)
		(fp_line
			(start -0.12065 0.2794)
			(end -0.12065 0.3048)
			(stroke
				(width 0.1)
				(type default)
			)
			(layer "F.Fab")
		)
		(fp_line
			(start -0.12065 0.3048)
			(end -0.67945 0.3048)
			(stroke
				(width 0.1)
				(type default)
			)
			(layer "F.Fab")
		)
		(fp_line
			(start 0.120396 0.2794)
			(end -0.12065 0.2794)
			(stroke
				(width 0.1)
				(type default)
			)
			(layer "F.Fab")
		)
		(fp_line
			(start 0.120396 0.3048)
			(end 0.120396 0.2794)
			(stroke
				(width 0.1)
				(type default)
			)
			(layer "F.Fab")
		)
		(fp_line
			(start 0.12065 -0.3048)
			(end 0.67945 -0.3048)
			(stroke
				(width 0.1)
				(type default)
			)
			(layer "F.Fab")
		)
		(fp_line
			(start 0.12065 -0.2794)
			(end 0.12065 -0.3048)
			(stroke
				(width 0.1)
				(type default)
			)
			(layer "F.Fab")
		)
		(fp_line
			(start 0.67945 -0.3048)
			(end 0.67945 0.3048)
			(stroke
				(width 0.1)
				(type default)
			)
			(layer "F.Fab")
		)
		(fp_line
			(start 0.67945 0.3048)
			(end 0.120396 0.3048)
			(stroke
				(width 0.1)
				(type default)
			)
			(layer "F.Fab")
		)
		(pad "1" smd circle
			(at -0.40005 0)
			(size 0 0)
			(layers "F.Cu" "F.Mask" "F.Paste")
			(net "PEX1_P1V8_PLL_EN")
		)
		(pad "2" smd circle
			(at 0.40005 0)
			(size 0 0)
			(layers "F.Cu" "F.Mask" "F.Paste")
			(net "GND")
		)
	)
	(footprint ""
		(layer "F.Cu")
		(at 422.26103 -37.951156)
		(property "Reference" "Q231"
			(at 2.020062 -1.787398 0)
			(unlocked yes)
			(layer "F.SilkS")
			(effects
				(font
					(size 0.7874 0.5842)
					(thickness 0.1524)
				)
			)
		)
		(property "Value" ""
			(at 0 0 0)
			(layer "F.Fab")
			(effects
				(font
					(size 1.27 1.27)
				)
			)
		)
		(duplicate_pad_numbers_are_jumpers no)
		(fp_line
			(start -1.376172 -1.199896)
			(end -0.508 -1.199896)
			(stroke
				(width 0.1524)
				(type default)
			)
			(layer "F.SilkS")
		)
		(fp_line
			(start -1.376172 1.199896)
			(end -1.376172 -1.199896)
			(stroke
				(width 0.1524)
				(type default)
			)
			(layer "F.SilkS")
		)
		(fp_line
			(start -0.508 -1.199896)
			(end 0 -0.762)
			(stroke
				(width 0.1524)
				(type default)
			)
			(layer "F.SilkS")
		)
		(fp_line
			(start 0 -0.762)
			(end 0.508 -1.199896)
			(stroke
				(width 0.1524)
				(type default)
			)
			(layer "F.SilkS")
		)
		(fp_line
			(start 0.508 -1.199896)
			(end 1.376172 -1.199896)
			(stroke
				(width 0.1524)
				(type default)
			)
			(layer "F.SilkS")
		)
		(fp_line
			(start 1.376172 -1.199896)
			(end 1.376172 1.199896)
			(stroke
				(width 0.1524)
				(type default)
			)
			(layer "F.SilkS")
		)
		(fp_line
			(start 1.376172 1.199896)
			(end -1.376172 1.199896)
			(stroke
				(width 0.1524)
				(type default)
			)
			(layer "F.SilkS")
		)
		(fp_poly
			(pts
				(xy -1.743456 -1.124966) (xy -2.01295 -1.933194) (xy -2.551684 -1.39446)
			)
			(stroke
				(width 0)
				(type default)
			)
			(fill yes)
			(layer "F.SilkS")
		)
		(fp_line
			(start -0.674878 -1.100074)
			(end 0.674878 -1.100074)
			(stroke
				(width 0.1)
				(type default)
			)
			(layer "F.Fab")
		)
		(fp_line
			(start -0.674878 1.100074)
			(end -0.674878 -1.100074)
			(stroke
				(width 0.1)
				(type default)
			)
			(layer "F.Fab")
		)
		(fp_line
			(start 0.674878 -1.100074)
			(end 0.674878 1.100074)
			(stroke
				(width 0.1)
				(type default)
			)
			(layer "F.Fab")
		)
		(fp_line
			(start 0.674878 1.100074)
			(end -0.674878 1.100074)
			(stroke
				(width 0.1)
				(type default)
			)
			(layer "F.Fab")
		)
		(fp_poly
			(pts
				(xy -1.4605 -0.7493) (xy -2.2225 -1.1303) (xy -2.2225 -0.3683)
			)
			(stroke
				(width 0)
				(type default)
			)
			(fill yes)
			(layer "F.Fab")
		)
		(pad "1" smd rect
			(at -0.899922 -0.750062 270)
			(size 0.6096 0.6096)
			(layers "F.Cu" "F.Mask" "F.Paste")
			(net "GND")
		)
		(pad "2" smd rect
			(at -0.899922 0 270)
			(size 0.4064 0.6096)
			(layers "F.Cu" "F.Mask" "F.Paste")
			(net "P3V3_SSD15_PG_G1")
		)
		(pad "3" smd rect
			(at -0.899922 0.750062 270)
			(size 0.6096 0.6096)
			(layers "F.Cu" "F.Mask" "F.Paste")
			(net "PWRGD_P3V3_SSD15_D")
		)
		(pad "4" smd rect
			(at 0.899922 0.750062 270)
			(size 0.6096 0.6096)
			(layers "F.Cu" "F.Mask" "F.Paste")
			(net "GND")
		)
		(pad "5" smd rect
			(at 0.899922 0 270)
			(size 0.4064 0.6096)
			(layers "F.Cu" "F.Mask" "F.Paste")
			(net "P3V3_SSD15_PG_G2")
		)
		(pad "6" smd rect
			(at 0.899922 -0.750062 270)
			(size 0.6096 0.6096)
			(layers "F.Cu" "F.Mask" "F.Paste")
			(net "P3V3_SSD15_PG_G2")
		)
	)
	(footprint ""
		(layer "F.Cu")
		(at 271.480534 -133.129782)
		(property "Reference" "C460"
			(at 0 0 0)
			(layer "F.SilkS")
			(hide yes)
			(effects
				(font
					(size 1.27 1.27)
				)
			)
		)
		(property "Value" ""
			(at 0 0 0)
			(layer "F.Fab")
			(effects
				(font
					(size 1.27 1.27)
				)
			)
		)
		(duplicate_pad_numbers_are_jumpers no)
		(fp_line
			(start -0.299974 -0.150114)
			(end 0.299974 -0.150114)
			(stroke
				(width 0.1)
				(type default)
			)
			(layer "F.Fab")
		)
		(fp_line
			(start -0.299974 0.150114)
			(end -0.299974 -0.150114)
			(stroke
				(width 0.1)
				(type default)
			)
			(layer "F.Fab")
		)
		(fp_line
			(start 0.299974 -0.150114)
			(end 0.299974 0.150114)
			(stroke
				(width 0.1)
				(type default)
			)
			(layer "F.Fab")
		)
		(fp_line
			(start 0.299974 0.150114)
			(end -0.299974 0.150114)
			(stroke
				(width 0.1)
				(type default)
			)
			(layer "F.Fab")
		)
		(pad "1" smd rect
			(at -0.2667 0)
			(size 0.3048 0.381)
			(layers "F.Cu" "F.Mask" "F.Paste")
			(net "P5E_PEX2_STN1_TX_DP<29>")
		)
		(pad "2" smd rect
			(at 0.2667 0)
			(size 0.3048 0.381)
			(layers "F.Cu" "F.Mask" "F.Paste")
			(net "P5E_PEX2_STN1_TX_C_DP<29>")
		)
	)
	(footprint ""
		(layer "F.Cu")
		(at 309.553864 -83.932268 90)
		(property "Reference" "C931"
			(at 0 0 90)
			(layer "F.SilkS")
			(hide yes)
			(effects
				(font
					(size 1.27 1.27)
				)
			)
		)
		(property "Value" ""
			(at 0 0 90)
			(layer "F.Fab")
			(effects
				(font
					(size 1.27 1.27)
				)
			)
		)
		(duplicate_pad_numbers_are_jumpers no)
		(fp_line
			(start 0.7874 -0.4064)
			(end 0.7874 0.4064)
			(stroke
				(width 0.1524)
				(type default)
			)
			(layer "F.SilkS")
		)
		(fp_line
			(start -0.7874 -0.4064)
			(end 0.7874 -0.4064)
			(stroke
				(width 0.1524)
				(type default)
			)
			(layer "F.SilkS")
		)
		(fp_line
			(start 0.7874 0.4064)
			(end -0.7874 0.4064)
			(stroke
				(width 0.1524)
				(type default)
			)
			(layer "F.SilkS")
		)
		(fp_line
			(start -0.7874 0.4064)
			(end -0.7874 -0.4064)
			(stroke
				(width 0.1524)
				(type default)
			)
			(layer "F.SilkS")
		)
		(fp_line
			(start -0.12065 -0.305054)
			(end -0.12065 -0.2794)
			(stroke
				(width 0.1)
				(type default)
			)
			(layer "F.Fab")
		)
		(fp_line
			(start -0.67945 -0.305054)
			(end -0.12065 -0.305054)
			(stroke
				(width 0.1)
				(type default)
			)
			(layer "F.Fab")
		)
		(fp_line
			(start 0.67945 -0.3048)
			(end 0.67945 0.3048)
			(stroke
				(width 0.1)
				(type default)
			)
			(layer "F.Fab")
		)
		(fp_line
			(start 0.12065 -0.3048)
			(end 0.67945 -0.3048)
			(stroke
				(width 0.1)
				(type default)
			)
			(layer "F.Fab")
		)
		(fp_line
			(start 0.12065 -0.2794)
			(end 0.12065 -0.3048)
			(stroke
				(width 0.1)
				(type default)
			)
			(layer "F.Fab")
		)
		(fp_line
			(start -0.12065 -0.2794)
			(end 0.12065 -0.2794)
			(stroke
				(width 0.1)
				(type default)
			)
			(layer "F.Fab")
		)
		(fp_line
			(start 0.120396 0.2794)
			(end -0.12065 0.2794)
			(stroke
				(width 0.1)
				(type default)
			)
			(layer "F.Fab")
		)
		(fp_line
			(start -0.12065 0.2794)
			(end -0.12065 0.3048)
			(stroke
				(width 0.1)
				(type default)
			)
			(layer "F.Fab")
		)
		(fp_line
			(start 0.67945 0.3048)
			(end 0.120396 0.3048)
			(stroke
				(width 0.1)
				(type default)
			)
			(layer "F.Fab")
		)
		(fp_line
			(start 0.120396 0.3048)
			(end 0.120396 0.2794)
			(stroke
				(width 0.1)
				(type default)
			)
			(layer "F.Fab")
		)
		(fp_line
			(start -0.12065 0.3048)
			(end -0.67945 0.3048)
			(stroke
				(width 0.1)
				(type default)
			)
			(layer "F.Fab")
		)
		(fp_line
			(start -0.67945 0.3048)
			(end -0.67945 -0.305054)
			(stroke
				(width 0.1)
				(type default)
			)
			(layer "F.Fab")
		)
		(pad "1" smd circle
			(at -0.40005 0 90)
			(size 0 0)
			(layers "F.Cu" "F.Mask" "F.Paste")
			(net "P3V3_AUX")
		)
		(pad "2" smd circle
			(at 0.40005 0 90)
			(size 0 0)
			(layers "F.Cu" "F.Mask" "F.Paste")
			(net "GND")
		)
	)
	(footprint ""
		(layer "F.Cu")
		(at 126.770892 -272.15846 -90)
		(property "Reference" "PL8"
			(at 4.70789 0.448056 0)
			(unlocked yes)
			(layer "F.SilkS")
			(effects
				(font
					(size 0.7874 0.5842)
					(thickness 0.1524)
				)
			)
		)
		(property "Value" ""
			(at 0 0 270)
			(layer "F.Fab")
			(effects
				(font
					(size 1.27 1.27)
				)
			)
		)
		(duplicate_pad_numbers_are_jumpers no)
		(fp_line
			(start -2.249932 2.249932)
			(end -2.249932 1.3843)
			(stroke
				(width 0.1524)
				(type default)
			)
			(layer "F.SilkS")
		)
		(fp_line
			(start 2.249932 2.249932)
			(end -2.249932 2.249932)
			(stroke
				(width 0.1524)
				(type default)
			)
			(layer "F.SilkS")
		)
		(fp_line
			(start 2.249932 1.3843)
			(end 2.249932 2.249932)
			(stroke
				(width 0.1524)
				(type default)
			)
			(layer "F.SilkS")
		)
		(fp_line
			(start -2.249932 -1.3843)
			(end -2.249932 -2.249932)
			(stroke
				(width 0.1524)
				(type default)
			)
			(layer "F.SilkS")
		)
		(fp_line
			(start -2.249932 -2.249932)
			(end 2.249932 -2.249932)
			(stroke
				(width 0.1524)
				(type default)
			)
			(layer "F.SilkS")
		)
		(fp_line
			(start 2.249932 -2.249932)
			(end 2.249932 -1.3843)
			(stroke
				(width 0.1524)
				(type default)
			)
			(layer "F.SilkS")
		)
		(fp_line
			(start -2.249932 2.249932)
			(end -2.249932 -2.249932)
			(stroke
				(width 0.1)
				(type default)
			)
			(layer "F.Fab")
		)
		(fp_line
			(start 2.249932 2.249932)
			(end -2.249932 2.249932)
			(stroke
				(width 0.1)
				(type default)
			)
			(layer "F.Fab")
		)
		(fp_line
			(start -2.249932 -2.249932)
			(end 2.249932 -2.249932)
			(stroke
				(width 0.1)
				(type default)
			)
			(layer "F.Fab")
		)
		(fp_line
			(start 2.249932 -2.249932)
			(end 2.249932 2.249932)
			(stroke
				(width 0.1)
				(type default)
			)
			(layer "F.Fab")
		)
		(pad "1" smd rect
			(at -1.82499 0 270)
			(size 1.0668 2.5146)
			(layers "F.Cu" "F.Mask" "F.Paste")
			(net "SW_P12V_P0V8_PEX1_FLT")
		)
		(pad "2" smd rect
			(at 1.82499 0 270)
			(size 1.0668 2.5146)
			(layers "F.Cu" "F.Mask" "F.Paste")
			(net "P12V_AUX")
		)
	)
	(footprint ""
		(layer "F.Cu")
		(at 230.991664 -207.02016 -90)
		(property "Reference" "R1507"
			(at 0 0 270)
			(layer "F.SilkS")
			(hide yes)
			(effects
				(font
					(size 1.27 1.27)
				)
			)
		)
		(property "Value" ""
			(at 0 0 270)
			(layer "F.Fab")
			(effects
				(font
					(size 1.27 1.27)
				)
			)
		)
		(duplicate_pad_numbers_are_jumpers no)
		(fp_line
			(start -0.7874 0.4064)
			(end -0.7874 -0.4064)
			(stroke
				(width 0.1524)
				(type default)
			)
			(layer "F.SilkS")
		)
		(fp_line
			(start 0.7874 0.4064)
			(end -0.7874 0.4064)
			(stroke
				(width 0.1524)
				(type default)
			)
			(layer "F.SilkS")
		)
		(fp_line
			(start -0.7874 -0.4064)
			(end 0.7874 -0.4064)
			(stroke
				(width 0.1524)
				(type default)
			)
			(layer "F.SilkS")
		)
		(fp_line
			(start 0.7874 -0.4064)
			(end 0.7874 0.4064)
			(stroke
				(width 0.1524)
				(type default)
			)
			(layer "F.SilkS")
		)
		(fp_line
			(start -0.67945 0.3048)
			(end -0.67945 -0.305054)
			(stroke
				(width 0.1)
				(type default)
			)
			(layer "F.Fab")
		)
		(fp_line
			(start -0.12065 0.3048)
			(end -0.67945 0.3048)
			(stroke
				(width 0.1)
				(type default)
			)
			(layer "F.Fab")
		)
		(fp_line
			(start 0.120396 0.3048)
			(end 0.120396 0.2794)
			(stroke
				(width 0.1)
				(type default)
			)
			(layer "F.Fab")
		)
		(fp_line
			(start 0.67945 0.3048)
			(end 0.120396 0.3048)
			(stroke
				(width 0.1)
				(type default)
			)
			(layer "F.Fab")
		)
		(fp_line
			(start -0.12065 0.2794)
			(end -0.12065 0.3048)
			(stroke
				(width 0.1)
				(type default)
			)
			(layer "F.Fab")
		)
		(fp_line
			(start 0.120396 0.2794)
			(end -0.12065 0.2794)
			(stroke
				(width 0.1)
				(type default)
			)
			(layer "F.Fab")
		)
		(fp_line
			(start -0.12065 -0.2794)
			(end 0.12065 -0.2794)
			(stroke
				(width 0.1)
				(type default)
			)
			(layer "F.Fab")
		)
		(fp_line
			(start 0.12065 -0.2794)
			(end 0.12065 -0.3048)
			(stroke
				(width 0.1)
				(type default)
			)
			(layer "F.Fab")
		)
		(fp_line
			(start 0.12065 -0.3048)
			(end 0.67945 -0.3048)
			(stroke
				(width 0.1)
				(type default)
			)
			(layer "F.Fab")
		)
		(fp_line
			(start 0.67945 -0.3048)
			(end 0.67945 0.3048)
			(stroke
				(width 0.1)
				(type default)
			)
			(layer "F.Fab")
		)
		(fp_line
			(start -0.67945 -0.305054)
			(end -0.12065 -0.305054)
			(stroke
				(width 0.1)
				(type default)
			)
			(layer "F.Fab")
		)
		(fp_line
			(start -0.12065 -0.305054)
			(end -0.12065 -0.2794)
			(stroke
				(width 0.1)
				(type default)
			)
			(layer "F.Fab")
		)
		(pad "1" smd circle
			(at -0.40005 0 270)
			(size 0 0)
			(layers "F.Cu" "F.Mask" "F.Paste")
			(net "SPI_BIC1_CS1_N")
		)
		(pad "2" smd circle
			(at 0.40005 0 270)
			(size 0 0)
			(layers "F.Cu" "F.Mask" "F.Paste")
			(net "P3V3_AUX")
		)
	)
	(footprint ""
		(layer "F.Cu")
		(at 249.992388 -28.225242 180)
		(property "Reference" "C494"
			(at 0 0 180)
			(layer "F.SilkS")
			(hide yes)
			(effects
				(font
					(size 1.27 1.27)
				)
			)
		)
		(property "Value" ""
			(at 0 0 180)
			(layer "F.Fab")
			(effects
				(font
					(size 1.27 1.27)
				)
			)
		)
		(duplicate_pad_numbers_are_jumpers no)
		(fp_line
			(start 0.299974 0.150114)
			(end -0.299974 0.150114)
			(stroke
				(width 0.1)
				(type default)
			)
			(layer "F.Fab")
		)
		(fp_line
			(start 0.299974 -0.150114)
			(end 0.299974 0.150114)
			(stroke
				(width 0.1)
				(type default)
			)
			(layer "F.Fab")
		)
		(fp_line
			(start -0.299974 0.150114)
			(end -0.299974 -0.150114)
			(stroke
				(width 0.1)
				(type default)
			)
			(layer "F.Fab")
		)
		(fp_line
			(start -0.299974 -0.150114)
			(end 0.299974 -0.150114)
			(stroke
				(width 0.1)
				(type default)
			)
			(layer "F.Fab")
		)
		(pad "1" smd rect
			(at -0.2667 0 180)
			(size 0.3048 0.381)
			(layers "F.Cu" "F.Mask" "F.Paste")
			(net "P5E_PEX2_STN2_TX_DN<44>")
		)
		(pad "2" smd rect
			(at 0.2667 0 180)
			(size 0.3048 0.381)
			(layers "F.Cu" "F.Mask" "F.Paste")
			(net "P5E_PEX2_STN2_TX_C_DN<44>")
		)
	)
	(footprint ""
		(layer "F.Cu")
		(at 454.523602 -245.0465 -90)
		(property "Reference" "C4429"
			(at 0 0 270)
			(layer "F.SilkS")
			(hide yes)
			(effects
				(font
					(size 1.27 1.27)
				)
			)
		)
		(property "Value" ""
			(at 0 0 270)
			(layer "F.Fab")
			(effects
				(font
					(size 1.27 1.27)
				)
			)
		)
		(duplicate_pad_numbers_are_jumpers no)
		(fp_line
			(start -0.7874 0.4064)
			(end -0.7874 -0.4064)
			(stroke
				(width 0.1524)
				(type default)
			)
			(layer "F.SilkS")
		)
		(fp_line
			(start 0.7874 0.4064)
			(end -0.7874 0.4064)
			(stroke
				(width 0.1524)
				(type default)
			)
			(layer "F.SilkS")
		)
		(fp_line
			(start -0.7874 -0.4064)
			(end 0.7874 -0.4064)
			(stroke
				(width 0.1524)
				(type default)
			)
			(layer "F.SilkS")
		)
		(fp_line
			(start 0.7874 -0.4064)
			(end 0.7874 0.4064)
			(stroke
				(width 0.1524)
				(type default)
			)
			(layer "F.SilkS")
		)
		(fp_line
			(start -0.67945 0.3048)
			(end -0.67945 -0.305054)
			(stroke
				(width 0.1)
				(type default)
			)
			(layer "F.Fab")
		)
		(fp_line
			(start -0.12065 0.3048)
			(end -0.67945 0.3048)
			(stroke
				(width 0.1)
				(type default)
			)
			(layer "F.Fab")
		)
		(fp_line
			(start 0.120396 0.3048)
			(end 0.120396 0.2794)
			(stroke
				(width 0.1)
				(type default)
			)
			(layer "F.Fab")
		)
		(fp_line
			(start 0.67945 0.3048)
			(end 0.120396 0.3048)
			(stroke
				(width 0.1)
				(type default)
			)
			(layer "F.Fab")
		)
		(fp_line
			(start -0.12065 0.2794)
			(end -0.12065 0.3048)
			(stroke
				(width 0.1)
				(type default)
			)
			(layer "F.Fab")
		)
		(fp_line
			(start 0.120396 0.2794)
			(end -0.12065 0.2794)
			(stroke
				(width 0.1)
				(type default)
			)
			(layer "F.Fab")
		)
		(fp_line
			(start -0.12065 -0.2794)
			(end 0.12065 -0.2794)
			(stroke
				(width 0.1)
				(type default)
			)
			(layer "F.Fab")
		)
		(fp_line
			(start 0.12065 -0.2794)
			(end 0.12065 -0.3048)
			(stroke
				(width 0.1)
				(type default)
			)
			(layer "F.Fab")
		)
		(fp_line
			(start 0.12065 -0.3048)
			(end 0.67945 -0.3048)
			(stroke
				(width 0.1)
				(type default)
			)
			(layer "F.Fab")
		)
		(fp_line
			(start 0.67945 -0.3048)
			(end 0.67945 0.3048)
			(stroke
				(width 0.1)
				(type default)
			)
			(layer "F.Fab")
		)
		(fp_line
			(start -0.67945 -0.305054)
			(end -0.12065 -0.305054)
			(stroke
				(width 0.1)
				(type default)
			)
			(layer "F.Fab")
		)
		(fp_line
			(start -0.12065 -0.305054)
			(end -0.12065 -0.2794)
			(stroke
				(width 0.1)
				(type default)
			)
			(layer "F.Fab")
		)
		(pad "1" smd circle
			(at -0.40005 0 270)
			(size 0 0)
			(layers "F.Cu" "F.Mask" "F.Paste")
			(net "P5V_AUX")
		)
		(pad "2" smd circle
			(at 0.40005 0 270)
			(size 0 0)
			(layers "F.Cu" "F.Mask" "F.Paste")
			(net "GND")
		)
	)
	(footprint ""
		(layer "F.Cu")
		(at 89.478866 -308.323488 135)
		(property "Reference" "R1254"
			(at 0 0 135)
			(layer "F.SilkS")
			(hide yes)
			(effects
				(font
					(size 1.27 1.27)
				)
			)
		)
		(property "Value" ""
			(at 0 0 135)
			(layer "F.Fab")
			(effects
				(font
					(size 1.27 1.27)
				)
			)
		)
		(duplicate_pad_numbers_are_jumpers no)
		(fp_line
			(start 0.787389 -0.406267)
			(end 0.787389 0.406267)
			(stroke
				(width 0.1524)
				(type default)
			)
			(layer "F.SilkS")
		)
		(fp_line
			(start 0.787389 0.406267)
			(end -0.787389 0.406267)
			(stroke
				(width 0.1524)
				(type default)
			)
			(layer "F.SilkS")
		)
		(fp_line
			(start -0.787389 -0.406267)
			(end 0.787389 -0.406267)
			(stroke
				(width 0.1524)
				(type default)
			)
			(layer "F.SilkS")
		)
		(fp_line
			(start -0.787389 0.406267)
			(end -0.787389 -0.406267)
			(stroke
				(width 0.1524)
				(type default)
			)
			(layer "F.SilkS")
		)
		(fp_line
			(start 0.679446 -0.30479)
			(end 0.679446 0.30479)
			(stroke
				(width 0.1)
				(type default)
			)
			(layer "F.Fab")
		)
		(fp_line
			(start 0.120515 -0.30479)
			(end 0.679446 -0.30479)
			(stroke
				(width 0.1)
				(type default)
			)
			(layer "F.Fab")
		)
		(fp_line
			(start 0.120695 -0.279466)
			(end 0.120515 -0.30479)
			(stroke
				(width 0.1)
				(type default)
			)
			(layer "F.Fab")
		)
		(fp_line
			(start 0.679446 0.30479)
			(end 0.120515 0.30479)
			(stroke
				(width 0.1)
				(type default)
			)
			(layer "F.Fab")
		)
		(fp_line
			(start -0.120695 -0.304969)
			(end -0.120695 -0.279466)
			(stroke
				(width 0.1)
				(type default)
			)
			(layer "F.Fab")
		)
		(fp_line
			(start -0.120695 -0.279466)
			(end 0.120695 -0.279466)
			(stroke
				(width 0.1)
				(type default)
			)
			(layer "F.Fab")
		)
		(fp_line
			(start 0.120335 0.279466)
			(end -0.120695 0.279466)
			(stroke
				(width 0.1)
				(type default)
			)
			(layer "F.Fab")
		)
		(fp_line
			(start 0.120515 0.30479)
			(end 0.120335 0.279466)
			(stroke
				(width 0.1)
				(type default)
			)
			(layer "F.Fab")
		)
		(fp_line
			(start -0.679446 -0.305149)
			(end -0.120695 -0.304969)
			(stroke
				(width 0.1)
				(type default)
			)
			(layer "F.Fab")
		)
		(fp_line
			(start -0.120695 0.279466)
			(end -0.120515 0.30479)
			(stroke
				(width 0.1)
				(type default)
			)
			(layer "F.Fab")
		)
		(fp_line
			(start -0.120515 0.30479)
			(end -0.679446 0.30479)
			(stroke
				(width 0.1)
				(type default)
			)
			(layer "F.Fab")
		)
		(fp_line
			(start -0.679446 0.30479)
			(end -0.679446 -0.305149)
			(stroke
				(width 0.1)
				(type default)
			)
			(layer "F.Fab")
		)
		(pad "1" smd circle
			(at -0.40005 0 135)
			(size 0 0)
			(layers "F.Cu" "F.Mask" "F.Paste")
			(net "GND")
		)
		(pad "2" smd circle
			(at 0.40005 0 135)
			(size 0 0)
			(layers "F.Cu" "F.Mask" "F.Paste")
			(net "PEX0_SPARE7")
		)
	)
	(footprint ""
		(layer "F.Cu")
		(at 428.83963 -137.645648)
		(property "Reference" "R363"
			(at 0 0 0)
			(layer "F.SilkS")
			(hide yes)
			(effects
				(font
					(size 1.27 1.27)
				)
			)
		)
		(property "Value" ""
			(at 0 0 0)
			(layer "F.Fab")
			(effects
				(font
					(size 1.27 1.27)
				)
			)
		)
		(duplicate_pad_numbers_are_jumpers no)
		(fp_line
			(start -0.7874 -0.4064)
			(end 0.7874 -0.4064)
			(stroke
				(width 0.1524)
				(type default)
			)
			(layer "F.SilkS")
		)
		(fp_line
			(start -0.7874 0.4064)
			(end -0.7874 -0.4064)
			(stroke
				(width 0.1524)
				(type default)
			)
			(layer "F.SilkS")
		)
		(fp_line
			(start 0.7874 -0.4064)
			(end 0.7874 0.4064)
			(stroke
				(width 0.1524)
				(type default)
			)
			(layer "F.SilkS")
		)
		(fp_line
			(start 0.7874 0.4064)
			(end -0.7874 0.4064)
			(stroke
				(width 0.1524)
				(type default)
			)
			(layer "F.SilkS")
		)
		(fp_line
			(start -0.67945 -0.305054)
			(end -0.12065 -0.305054)
			(stroke
				(width 0.1)
				(type default)
			)
			(layer "F.Fab")
		)
		(fp_line
			(start -0.67945 0.3048)
			(end -0.67945 -0.305054)
			(stroke
				(width 0.1)
				(type default)
			)
			(layer "F.Fab")
		)
		(fp_line
			(start -0.12065 -0.305054)
			(end -0.12065 -0.2794)
			(stroke
				(width 0.1)
				(type default)
			)
			(layer "F.Fab")
		)
		(fp_line
			(start -0.12065 -0.2794)
			(end 0.12065 -0.2794)
			(stroke
				(width 0.1)
				(type default)
			)
			(layer "F.Fab")
		)
		(fp_line
			(start -0.12065 0.2794)
			(end -0.12065 0.3048)
			(stroke
				(width 0.1)
				(type default)
			)
			(layer "F.Fab")
		)
		(fp_line
			(start -0.12065 0.3048)
			(end -0.67945 0.3048)
			(stroke
				(width 0.1)
				(type default)
			)
			(layer "F.Fab")
		)
		(fp_line
			(start 0.120396 0.2794)
			(end -0.12065 0.2794)
			(stroke
				(width 0.1)
				(type default)
			)
			(layer "F.Fab")
		)
		(fp_line
			(start 0.120396 0.3048)
			(end 0.120396 0.2794)
			(stroke
				(width 0.1)
				(type default)
			)
			(layer "F.Fab")
		)
		(fp_line
			(start 0.12065 -0.3048)
			(end 0.67945 -0.3048)
			(stroke
				(width 0.1)
				(type default)
			)
			(layer "F.Fab")
		)
		(fp_line
			(start 0.12065 -0.2794)
			(end 0.12065 -0.3048)
			(stroke
				(width 0.1)
				(type default)
			)
			(layer "F.Fab")
		)
		(fp_line
			(start 0.67945 -0.3048)
			(end 0.67945 0.3048)
			(stroke
				(width 0.1)
				(type default)
			)
			(layer "F.Fab")
		)
		(fp_line
			(start 0.67945 0.3048)
			(end 0.120396 0.3048)
			(stroke
				(width 0.1)
				(type default)
			)
			(layer "F.Fab")
		)
		(pad "1" smd circle
			(at -0.40005 0)
			(size 0 0)
			(layers "F.Cu" "F.Mask" "F.Paste")
			(net "PRSNTB0_NIC7_N")
		)
		(pad "2" smd circle
			(at 0.40005 0)
			(size 0 0)
			(layers "F.Cu" "F.Mask" "F.Paste")
			(net "P3V3_AUX")
		)
	)
	(footprint ""
		(layer "F.Cu")
		(at 350.647 -173.482 90)
		(property "Reference" "C3602"
			(at 0 0 90)
			(layer "F.SilkS")
			(hide yes)
			(effects
				(font
					(size 1.27 1.27)
				)
			)
		)
		(property "Value" ""
			(at 0 0 90)
			(layer "F.Fab")
			(effects
				(font
					(size 1.27 1.27)
				)
			)
		)
		(duplicate_pad_numbers_are_jumpers no)
		(fp_line
			(start 0.7874 -0.4064)
			(end 0.7874 0.4064)
			(stroke
				(width 0.1524)
				(type default)
			)
			(layer "F.SilkS")
		)
		(fp_line
			(start -0.7874 -0.4064)
			(end 0.7874 -0.4064)
			(stroke
				(width 0.1524)
				(type default)
			)
			(layer "F.SilkS")
		)
		(fp_line
			(start 0.7874 0.4064)
			(end -0.7874 0.4064)
			(stroke
				(width 0.1524)
				(type default)
			)
			(layer "F.SilkS")
		)
		(fp_line
			(start -0.7874 0.4064)
			(end -0.7874 -0.4064)
			(stroke
				(width 0.1524)
				(type default)
			)
			(layer "F.SilkS")
		)
		(fp_line
			(start -0.12065 -0.305054)
			(end -0.12065 -0.2794)
			(stroke
				(width 0.1)
				(type default)
			)
			(layer "F.Fab")
		)
		(fp_line
			(start -0.67945 -0.305054)
			(end -0.12065 -0.305054)
			(stroke
				(width 0.1)
				(type default)
			)
			(layer "F.Fab")
		)
		(fp_line
			(start 0.67945 -0.3048)
			(end 0.67945 0.3048)
			(stroke
				(width 0.1)
				(type default)
			)
			(layer "F.Fab")
		)
		(fp_line
			(start 0.12065 -0.3048)
			(end 0.67945 -0.3048)
			(stroke
				(width 0.1)
				(type default)
			)
			(layer "F.Fab")
		)
		(fp_line
			(start 0.12065 -0.2794)
			(end 0.12065 -0.3048)
			(stroke
				(width 0.1)
				(type default)
			)
			(layer "F.Fab")
		)
		(fp_line
			(start -0.12065 -0.2794)
			(end 0.12065 -0.2794)
			(stroke
				(width 0.1)
				(type default)
			)
			(layer "F.Fab")
		)
		(fp_line
			(start 0.120396 0.2794)
			(end -0.12065 0.2794)
			(stroke
				(width 0.1)
				(type default)
			)
			(layer "F.Fab")
		)
		(fp_line
			(start -0.12065 0.2794)
			(end -0.12065 0.3048)
			(stroke
				(width 0.1)
				(type default)
			)
			(layer "F.Fab")
		)
		(fp_line
			(start 0.67945 0.3048)
			(end 0.120396 0.3048)
			(stroke
				(width 0.1)
				(type default)
			)
			(layer "F.Fab")
		)
		(fp_line
			(start 0.120396 0.3048)
			(end 0.120396 0.2794)
			(stroke
				(width 0.1)
				(type default)
			)
			(layer "F.Fab")
		)
		(fp_line
			(start -0.12065 0.3048)
			(end -0.67945 0.3048)
			(stroke
				(width 0.1)
				(type default)
			)
			(layer "F.Fab")
		)
		(fp_line
			(start -0.67945 0.3048)
			(end -0.67945 -0.305054)
			(stroke
				(width 0.1)
				(type default)
			)
			(layer "F.Fab")
		)
		(pad "1" smd circle
			(at -0.40005 0 90)
			(size 0 0)
			(layers "F.Cu" "F.Mask" "F.Paste")
			(net "P3V3_AUX")
		)
		(pad "2" smd circle
			(at 0.40005 0 90)
			(size 0 0)
			(layers "F.Cu" "F.Mask" "F.Paste")
			(net "GND")
		)
	)
	(footprint ""
		(layer "F.Cu")
		(at 450.230494 -118.76024)
		(property "Reference" "R6045"
			(at 0 0 0)
			(layer "F.SilkS")
			(hide yes)
			(effects
				(font
					(size 1.27 1.27)
				)
			)
		)
		(property "Value" ""
			(at 0 0 0)
			(layer "F.Fab")
			(effects
				(font
					(size 1.27 1.27)
				)
			)
		)
		(duplicate_pad_numbers_are_jumpers no)
		(fp_line
			(start -0.7874 -0.4064)
			(end 0.7874 -0.4064)
			(stroke
				(width 0.1524)
				(type default)
			)
			(layer "F.SilkS")
		)
		(fp_line
			(start -0.7874 0.4064)
			(end -0.7874 -0.4064)
			(stroke
				(width 0.1524)
				(type default)
			)
			(layer "F.SilkS")
		)
		(fp_line
			(start 0.7874 -0.4064)
			(end 0.7874 0.4064)
			(stroke
				(width 0.1524)
				(type default)
			)
			(layer "F.SilkS")
		)
		(fp_line
			(start 0.7874 0.4064)
			(end -0.7874 0.4064)
			(stroke
				(width 0.1524)
				(type default)
			)
			(layer "F.SilkS")
		)
		(fp_line
			(start -0.67945 -0.305054)
			(end -0.12065 -0.305054)
			(stroke
				(width 0.1)
				(type default)
			)
			(layer "F.Fab")
		)
		(fp_line
			(start -0.67945 0.3048)
			(end -0.67945 -0.305054)
			(stroke
				(width 0.1)
				(type default)
			)
			(layer "F.Fab")
		)
		(fp_line
			(start -0.12065 -0.305054)
			(end -0.12065 -0.2794)
			(stroke
				(width 0.1)
				(type default)
			)
			(layer "F.Fab")
		)
		(fp_line
			(start -0.12065 -0.2794)
			(end 0.12065 -0.2794)
			(stroke
				(width 0.1)
				(type default)
			)
			(layer "F.Fab")
		)
		(fp_line
			(start -0.12065 0.2794)
			(end -0.12065 0.3048)
			(stroke
				(width 0.1)
				(type default)
			)
			(layer "F.Fab")
		)
		(fp_line
			(start -0.12065 0.3048)
			(end -0.67945 0.3048)
			(stroke
				(width 0.1)
				(type default)
			)
			(layer "F.Fab")
		)
		(fp_line
			(start 0.120396 0.2794)
			(end -0.12065 0.2794)
			(stroke
				(width 0.1)
				(type default)
			)
			(layer "F.Fab")
		)
		(fp_line
			(start 0.120396 0.3048)
			(end 0.120396 0.2794)
			(stroke
				(width 0.1)
				(type default)
			)
			(layer "F.Fab")
		)
		(fp_line
			(start 0.12065 -0.3048)
			(end 0.67945 -0.3048)
			(stroke
				(width 0.1)
				(type default)
			)
			(layer "F.Fab")
		)
		(fp_line
			(start 0.12065 -0.2794)
			(end 0.12065 -0.3048)
			(stroke
				(width 0.1)
				(type default)
			)
			(layer "F.Fab")
		)
		(fp_line
			(start 0.67945 -0.3048)
			(end 0.67945 0.3048)
			(stroke
				(width 0.1)
				(type default)
			)
			(layer "F.Fab")
		)
		(fp_line
			(start 0.67945 0.3048)
			(end 0.120396 0.3048)
			(stroke
				(width 0.1)
				(type default)
			)
			(layer "F.Fab")
		)
		(pad "1" smd circle
			(at -0.40005 0)
			(size 0 0)
			(layers "F.Cu" "F.Mask" "F.Paste")
			(net "P3V3_AUX")
		)
		(pad "2" smd circle
			(at 0.40005 0)
			(size 0 0)
			(layers "F.Cu" "F.Mask" "F.Paste")
			(net "PWRGD_P3V3_NIC7_D")
		)
	)
	(footprint ""
		(layer "F.Cu")
		(at 446.57391 -72.766682 90)
		(property "Reference" "PR7095"
			(at 0 0 90)
			(layer "F.SilkS")
			(hide yes)
			(effects
				(font
					(size 1.27 1.27)
				)
			)
		)
		(property "Value" ""
			(at 0 0 90)
			(layer "F.Fab")
			(effects
				(font
					(size 1.27 1.27)
				)
			)
		)
		(duplicate_pad_numbers_are_jumpers no)
		(fp_line
			(start 0.7874 -0.4064)
			(end 0.7874 0.4064)
			(stroke
				(width 0.1524)
				(type default)
			)
			(layer "F.SilkS")
		)
		(fp_line
			(start -0.7874 -0.4064)
			(end 0.7874 -0.4064)
			(stroke
				(width 0.1524)
				(type default)
			)
			(layer "F.SilkS")
		)
		(fp_line
			(start 0.7874 0.4064)
			(end -0.7874 0.4064)
			(stroke
				(width 0.1524)
				(type default)
			)
			(layer "F.SilkS")
		)
		(fp_line
			(start -0.7874 0.4064)
			(end -0.7874 -0.4064)
			(stroke
				(width 0.1524)
				(type default)
			)
			(layer "F.SilkS")
		)
		(fp_line
			(start -0.12065 -0.305054)
			(end -0.12065 -0.2794)
			(stroke
				(width 0.1)
				(type default)
			)
			(layer "F.Fab")
		)
		(fp_line
			(start -0.67945 -0.305054)
			(end -0.12065 -0.305054)
			(stroke
				(width 0.1)
				(type default)
			)
			(layer "F.Fab")
		)
		(fp_line
			(start 0.67945 -0.3048)
			(end 0.67945 0.3048)
			(stroke
				(width 0.1)
				(type default)
			)
			(layer "F.Fab")
		)
		(fp_line
			(start 0.12065 -0.3048)
			(end 0.67945 -0.3048)
			(stroke
				(width 0.1)
				(type default)
			)
			(layer "F.Fab")
		)
		(fp_line
			(start 0.12065 -0.2794)
			(end 0.12065 -0.3048)
			(stroke
				(width 0.1)
				(type default)
			)
			(layer "F.Fab")
		)
		(fp_line
			(start -0.12065 -0.2794)
			(end 0.12065 -0.2794)
			(stroke
				(width 0.1)
				(type default)
			)
			(layer "F.Fab")
		)
		(fp_line
			(start 0.120396 0.2794)
			(end -0.12065 0.2794)
			(stroke
				(width 0.1)
				(type default)
			)
			(layer "F.Fab")
		)
		(fp_line
			(start -0.12065 0.2794)
			(end -0.12065 0.3048)
			(stroke
				(width 0.1)
				(type default)
			)
			(layer "F.Fab")
		)
		(fp_line
			(start 0.67945 0.3048)
			(end 0.120396 0.3048)
			(stroke
				(width 0.1)
				(type default)
			)
			(layer "F.Fab")
		)
		(fp_line
			(start 0.120396 0.3048)
			(end 0.120396 0.2794)
			(stroke
				(width 0.1)
				(type default)
			)
			(layer "F.Fab")
		)
		(fp_line
			(start -0.12065 0.3048)
			(end -0.67945 0.3048)
			(stroke
				(width 0.1)
				(type default)
			)
			(layer "F.Fab")
		)
		(fp_line
			(start -0.67945 0.3048)
			(end -0.67945 -0.305054)
			(stroke
				(width 0.1)
				(type default)
			)
			(layer "F.Fab")
		)
		(pad "1" smd circle
			(at -0.40005 0 90)
			(size 0 0)
			(layers "F.Cu" "F.Mask" "F.Paste")
			(net "P12V_SSD15_CO_MODE")
		)
		(pad "2" smd circle
			(at 0.40005 0 90)
			(size 0 0)
			(layers "F.Cu" "F.Mask" "F.Paste")
			(net "GND")
		)
	)
	(footprint ""
		(layer "F.Cu")
		(at 113.032032 -162.782504)
		(property "Reference" "R824"
			(at 0 0 0)
			(layer "F.SilkS")
			(hide yes)
			(effects
				(font
					(size 1.27 1.27)
				)
			)
		)
		(property "Value" ""
			(at 0 0 0)
			(layer "F.Fab")
			(effects
				(font
					(size 1.27 1.27)
				)
			)
		)
		(duplicate_pad_numbers_are_jumpers no)
		(fp_line
			(start -0.7874 -0.4064)
			(end 0.7874 -0.4064)
			(stroke
				(width 0.1524)
				(type default)
			)
			(layer "F.SilkS")
		)
		(fp_line
			(start -0.7874 0.4064)
			(end -0.7874 -0.4064)
			(stroke
				(width 0.1524)
				(type default)
			)
			(layer "F.SilkS")
		)
		(fp_line
			(start 0.7874 -0.4064)
			(end 0.7874 0.4064)
			(stroke
				(width 0.1524)
				(type default)
			)
			(layer "F.SilkS")
		)
		(fp_line
			(start 0.7874 0.4064)
			(end -0.7874 0.4064)
			(stroke
				(width 0.1524)
				(type default)
			)
			(layer "F.SilkS")
		)
		(fp_line
			(start -0.67945 -0.305054)
			(end -0.12065 -0.305054)
			(stroke
				(width 0.1)
				(type default)
			)
			(layer "F.Fab")
		)
		(fp_line
			(start -0.67945 0.3048)
			(end -0.67945 -0.305054)
			(stroke
				(width 0.1)
				(type default)
			)
			(layer "F.Fab")
		)
		(fp_line
			(start -0.12065 -0.305054)
			(end -0.12065 -0.2794)
			(stroke
				(width 0.1)
				(type default)
			)
			(layer "F.Fab")
		)
		(fp_line
			(start -0.12065 -0.2794)
			(end 0.12065 -0.2794)
			(stroke
				(width 0.1)
				(type default)
			)
			(layer "F.Fab")
		)
		(fp_line
			(start -0.12065 0.2794)
			(end -0.12065 0.3048)
			(stroke
				(width 0.1)
				(type default)
			)
			(layer "F.Fab")
		)
		(fp_line
			(start -0.12065 0.3048)
			(end -0.67945 0.3048)
			(stroke
				(width 0.1)
				(type default)
			)
			(layer "F.Fab")
		)
		(fp_line
			(start 0.120396 0.2794)
			(end -0.12065 0.2794)
			(stroke
				(width 0.1)
				(type default)
			)
			(layer "F.Fab")
		)
		(fp_line
			(start 0.120396 0.3048)
			(end 0.120396 0.2794)
			(stroke
				(width 0.1)
				(type default)
			)
			(layer "F.Fab")
		)
		(fp_line
			(start 0.12065 -0.3048)
			(end 0.67945 -0.3048)
			(stroke
				(width 0.1)
				(type default)
			)
			(layer "F.Fab")
		)
		(fp_line
			(start 0.12065 -0.2794)
			(end 0.12065 -0.3048)
			(stroke
				(width 0.1)
				(type default)
			)
			(layer "F.Fab")
		)
		(fp_line
			(start 0.67945 -0.3048)
			(end 0.67945 0.3048)
			(stroke
				(width 0.1)
				(type default)
			)
			(layer "F.Fab")
		)
		(fp_line
			(start 0.67945 0.3048)
			(end 0.120396 0.3048)
			(stroke
				(width 0.1)
				(type default)
			)
			(layer "F.Fab")
		)
		(pad "1" smd circle
			(at -0.40005 0)
			(size 0 0)
			(layers "F.Cu" "F.Mask" "F.Paste")
			(net "P3V3_AUX_EN")
		)
		(pad "2" smd circle
			(at 0.40005 0)
			(size 0 0)
			(layers "F.Cu" "F.Mask" "F.Paste")
			(net "PWRGD_P5V_AUX_R")
		)
	)
	(footprint ""
		(layer "F.Cu")
		(at 320.852292 -114.384836 180)
		(property "Reference" "PC907"
			(at 0 0 180)
			(layer "F.SilkS")
			(hide yes)
			(effects
				(font
					(size 1.27 1.27)
				)
			)
		)
		(property "Value" ""
			(at 0 0 180)
			(layer "F.Fab")
			(effects
				(font
					(size 1.27 1.27)
				)
			)
		)
		(duplicate_pad_numbers_are_jumpers no)
		(fp_line
			(start 0.7874 0.4064)
			(end -0.7874 0.4064)
			(stroke
				(width 0.1524)
				(type default)
			)
			(layer "F.SilkS")
		)
		(fp_line
			(start 0.7874 -0.4064)
			(end 0.7874 0.4064)
			(stroke
				(width 0.1524)
				(type default)
			)
			(layer "F.SilkS")
		)
		(fp_line
			(start -0.7874 0.4064)
			(end -0.7874 -0.4064)
			(stroke
				(width 0.1524)
				(type default)
			)
			(layer "F.SilkS")
		)
		(fp_line
			(start -0.7874 -0.4064)
			(end 0.7874 -0.4064)
			(stroke
				(width 0.1524)
				(type default)
			)
			(layer "F.SilkS")
		)
		(fp_line
			(start 0.67945 0.3048)
			(end 0.120396 0.3048)
			(stroke
				(width 0.1)
				(type default)
			)
			(layer "F.Fab")
		)
		(fp_line
			(start 0.67945 -0.3048)
			(end 0.67945 0.3048)
			(stroke
				(width 0.1)
				(type default)
			)
			(layer "F.Fab")
		)
		(fp_line
			(start 0.12065 -0.2794)
			(end 0.12065 -0.3048)
			(stroke
				(width 0.1)
				(type default)
			)
			(layer "F.Fab")
		)
		(fp_line
			(start 0.12065 -0.3048)
			(end 0.67945 -0.3048)
			(stroke
				(width 0.1)
				(type default)
			)
			(layer "F.Fab")
		)
		(fp_line
			(start 0.120396 0.3048)
			(end 0.120396 0.2794)
			(stroke
				(width 0.1)
				(type default)
			)
			(layer "F.Fab")
		)
		(fp_line
			(start 0.120396 0.2794)
			(end -0.12065 0.2794)
			(stroke
				(width 0.1)
				(type default)
			)
			(layer "F.Fab")
		)
		(fp_line
			(start -0.12065 0.3048)
			(end -0.67945 0.3048)
			(stroke
				(width 0.1)
				(type default)
			)
			(layer "F.Fab")
		)
		(fp_line
			(start -0.12065 0.2794)
			(end -0.12065 0.3048)
			(stroke
				(width 0.1)
				(type default)
			)
			(layer "F.Fab")
		)
		(fp_line
			(start -0.12065 -0.2794)
			(end 0.12065 -0.2794)
			(stroke
				(width 0.1)
				(type default)
			)
			(layer "F.Fab")
		)
		(fp_line
			(start -0.12065 -0.305054)
			(end -0.12065 -0.2794)
			(stroke
				(width 0.1)
				(type default)
			)
			(layer "F.Fab")
		)
		(fp_line
			(start -0.67945 0.3048)
			(end -0.67945 -0.305054)
			(stroke
				(width 0.1)
				(type default)
			)
			(layer "F.Fab")
		)
		(fp_line
			(start -0.67945 -0.305054)
			(end -0.12065 -0.305054)
			(stroke
				(width 0.1)
				(type default)
			)
			(layer "F.Fab")
		)
		(pad "1" smd circle
			(at -0.40005 0 180)
			(size 0 0)
			(layers "F.Cu" "F.Mask" "F.Paste")
			(net "P3V3_NIC5_CO_DV_DT")
		)
		(pad "2" smd circle
			(at 0.40005 0 180)
			(size 0 0)
			(layers "F.Cu" "F.Mask" "F.Paste")
			(net "GND")
		)
	)
	(footprint ""
		(layer "F.Cu")
		(at 251.56287 -81.2165 90)
		(property "Reference" "C2637"
			(at 0 0 90)
			(layer "F.SilkS")
			(hide yes)
			(effects
				(font
					(size 1.27 1.27)
				)
			)
		)
		(property "Value" ""
			(at 0 0 90)
			(layer "F.Fab")
			(effects
				(font
					(size 1.27 1.27)
				)
			)
		)
		(duplicate_pad_numbers_are_jumpers no)
		(fp_line
			(start 0.7874 -0.4064)
			(end 0.7874 0.4064)
			(stroke
				(width 0.1524)
				(type default)
			)
			(layer "F.SilkS")
		)
		(fp_line
			(start -0.7874 -0.4064)
			(end 0.7874 -0.4064)
			(stroke
				(width 0.1524)
				(type default)
			)
			(layer "F.SilkS")
		)
		(fp_line
			(start 0.7874 0.4064)
			(end -0.7874 0.4064)
			(stroke
				(width 0.1524)
				(type default)
			)
			(layer "F.SilkS")
		)
		(fp_line
			(start -0.7874 0.4064)
			(end -0.7874 -0.4064)
			(stroke
				(width 0.1524)
				(type default)
			)
			(layer "F.SilkS")
		)
		(fp_line
			(start -0.12065 -0.305054)
			(end -0.12065 -0.2794)
			(stroke
				(width 0.1)
				(type default)
			)
			(layer "F.Fab")
		)
		(fp_line
			(start -0.67945 -0.305054)
			(end -0.12065 -0.305054)
			(stroke
				(width 0.1)
				(type default)
			)
			(layer "F.Fab")
		)
		(fp_line
			(start 0.67945 -0.3048)
			(end 0.67945 0.3048)
			(stroke
				(width 0.1)
				(type default)
			)
			(layer "F.Fab")
		)
		(fp_line
			(start 0.12065 -0.3048)
			(end 0.67945 -0.3048)
			(stroke
				(width 0.1)
				(type default)
			)
			(layer "F.Fab")
		)
		(fp_line
			(start 0.12065 -0.2794)
			(end 0.12065 -0.3048)
			(stroke
				(width 0.1)
				(type default)
			)
			(layer "F.Fab")
		)
		(fp_line
			(start -0.12065 -0.2794)
			(end 0.12065 -0.2794)
			(stroke
				(width 0.1)
				(type default)
			)
			(layer "F.Fab")
		)
		(fp_line
			(start 0.120396 0.2794)
			(end -0.12065 0.2794)
			(stroke
				(width 0.1)
				(type default)
			)
			(layer "F.Fab")
		)
		(fp_line
			(start -0.12065 0.2794)
			(end -0.12065 0.3048)
			(stroke
				(width 0.1)
				(type default)
			)
			(layer "F.Fab")
		)
		(fp_line
			(start 0.67945 0.3048)
			(end 0.120396 0.3048)
			(stroke
				(width 0.1)
				(type default)
			)
			(layer "F.Fab")
		)
		(fp_line
			(start 0.120396 0.3048)
			(end 0.120396 0.2794)
			(stroke
				(width 0.1)
				(type default)
			)
			(layer "F.Fab")
		)
		(fp_line
			(start -0.12065 0.3048)
			(end -0.67945 0.3048)
			(stroke
				(width 0.1)
				(type default)
			)
			(layer "F.Fab")
		)
		(fp_line
			(start -0.67945 0.3048)
			(end -0.67945 -0.305054)
			(stroke
				(width 0.1)
				(type default)
			)
			(layer "F.Fab")
		)
		(pad "1" smd circle
			(at -0.40005 0 90)
			(size 0 0)
			(layers "F.Cu" "F.Mask" "F.Paste")
			(net "XTAL_CK440_25M_XOUT")
		)
		(pad "2" smd circle
			(at 0.40005 0 90)
			(size 0 0)
			(layers "F.Cu" "F.Mask" "F.Paste")
			(net "GND")
		)
	)
	(footprint ""
		(layer "F.Cu")
		(at 418.919914 -15.649956 180)
		(property "Reference" "H114"
			(at -5.614416 0.421894 0)
			(unlocked yes)
			(layer "B.SilkS")
			(effects
				(font
					(size 0.7874 0.5842)
					(thickness 0.1524)
				)
				(justify left mirror)
			)
		)
		(property "Value" ""
			(at 0 0 180)
			(layer "F.Fab")
			(effects
				(font
					(size 1.27 1.27)
				)
			)
		)
		(duplicate_pad_numbers_are_jumpers no)
		(pad "1" thru_hole rect
			(at 0 0 180)
			(size 4.2164 5.0038)
			(drill 2.0066
				(offset 0.099822 0)
			)
			(layers "*.Cu" "*.Mask")
			(remove_unused_layers no)
			(net "Net_8549")
			(clearance -0.8509)
			(padstack
				(mode front_inner_back)
				(layer "Inner"
					(shape circle)
					(size 4.0132 4.0132)
					(clearance -0.7493)
				)
				(layer "B.Cu"
					(shape circle)
					(size 4.0132 4.0132)
					(clearance -0.7493)
				)
			)
		)
	)
	(footprint ""
		(layer "F.Cu")
		(at 101.930454 -118.76024 180)
		(property "Reference" "R5859"
			(at 0 0 180)
			(layer "F.SilkS")
			(hide yes)
			(effects
				(font
					(size 1.27 1.27)
				)
			)
		)
		(property "Value" ""
			(at 0 0 180)
			(layer "F.Fab")
			(effects
				(font
					(size 1.27 1.27)
				)
			)
		)
		(duplicate_pad_numbers_are_jumpers no)
		(fp_line
			(start 0.7874 0.4064)
			(end -0.7874 0.4064)
			(stroke
				(width 0.1524)
				(type default)
			)
			(layer "F.SilkS")
		)
		(fp_line
			(start 0.7874 -0.4064)
			(end 0.7874 0.4064)
			(stroke
				(width 0.1524)
				(type default)
			)
			(layer "F.SilkS")
		)
		(fp_line
			(start -0.7874 0.4064)
			(end -0.7874 -0.4064)
			(stroke
				(width 0.1524)
				(type default)
			)
			(layer "F.SilkS")
		)
		(fp_line
			(start -0.7874 -0.4064)
			(end 0.7874 -0.4064)
			(stroke
				(width 0.1524)
				(type default)
			)
			(layer "F.SilkS")
		)
		(fp_line
			(start 0.67945 0.3048)
			(end 0.120396 0.3048)
			(stroke
				(width 0.1)
				(type default)
			)
			(layer "F.Fab")
		)
		(fp_line
			(start 0.67945 -0.3048)
			(end 0.67945 0.3048)
			(stroke
				(width 0.1)
				(type default)
			)
			(layer "F.Fab")
		)
		(fp_line
			(start 0.12065 -0.2794)
			(end 0.12065 -0.3048)
			(stroke
				(width 0.1)
				(type default)
			)
			(layer "F.Fab")
		)
		(fp_line
			(start 0.12065 -0.3048)
			(end 0.67945 -0.3048)
			(stroke
				(width 0.1)
				(type default)
			)
			(layer "F.Fab")
		)
		(fp_line
			(start 0.120396 0.3048)
			(end 0.120396 0.2794)
			(stroke
				(width 0.1)
				(type default)
			)
			(layer "F.Fab")
		)
		(fp_line
			(start 0.120396 0.2794)
			(end -0.12065 0.2794)
			(stroke
				(width 0.1)
				(type default)
			)
			(layer "F.Fab")
		)
		(fp_line
			(start -0.12065 0.3048)
			(end -0.67945 0.3048)
			(stroke
				(width 0.1)
				(type default)
			)
			(layer "F.Fab")
		)
		(fp_line
			(start -0.12065 0.2794)
			(end -0.12065 0.3048)
			(stroke
				(width 0.1)
				(type default)
			)
			(layer "F.Fab")
		)
		(fp_line
			(start -0.12065 -0.2794)
			(end 0.12065 -0.2794)
			(stroke
				(width 0.1)
				(type default)
			)
			(layer "F.Fab")
		)
		(fp_line
			(start -0.12065 -0.305054)
			(end -0.12065 -0.2794)
			(stroke
				(width 0.1)
				(type default)
			)
			(layer "F.Fab")
		)
		(fp_line
			(start -0.67945 0.3048)
			(end -0.67945 -0.305054)
			(stroke
				(width 0.1)
				(type default)
			)
			(layer "F.Fab")
		)
		(fp_line
			(start -0.67945 -0.305054)
			(end -0.12065 -0.305054)
			(stroke
				(width 0.1)
				(type default)
			)
			(layer "F.Fab")
		)
		(pad "1" smd circle
			(at -0.40005 0 180)
			(size 0 0)
			(layers "F.Cu" "F.Mask" "F.Paste")
			(net "PWRGD_P3V3_NIC1_D")
		)
		(pad "2" smd circle
			(at 0.40005 0 180)
			(size 0 0)
			(layers "F.Cu" "F.Mask" "F.Paste")
			(net "PWRGD_P3V3_NIC1_R")
		)
	)
	(footprint ""
		(layer "F.Cu")
		(at 139.228576 -260.807708 90)
		(property "Reference" "R5800"
			(at 0 0 90)
			(layer "F.SilkS")
			(hide yes)
			(effects
				(font
					(size 1.27 1.27)
				)
			)
		)
		(property "Value" ""
			(at 0 0 90)
			(layer "F.Fab")
			(effects
				(font
					(size 1.27 1.27)
				)
			)
		)
		(duplicate_pad_numbers_are_jumpers no)
		(fp_line
			(start 0.7874 -0.4064)
			(end 0.7874 0.4064)
			(stroke
				(width 0.1524)
				(type default)
			)
			(layer "F.SilkS")
		)
		(fp_line
			(start -0.7874 -0.4064)
			(end 0.7874 -0.4064)
			(stroke
				(width 0.1524)
				(type default)
			)
			(layer "F.SilkS")
		)
		(fp_line
			(start 0.7874 0.4064)
			(end -0.7874 0.4064)
			(stroke
				(width 0.1524)
				(type default)
			)
			(layer "F.SilkS")
		)
		(fp_line
			(start -0.7874 0.4064)
			(end -0.7874 -0.4064)
			(stroke
				(width 0.1524)
				(type default)
			)
			(layer "F.SilkS")
		)
		(fp_line
			(start -0.12065 -0.305054)
			(end -0.12065 -0.2794)
			(stroke
				(width 0.1)
				(type default)
			)
			(layer "F.Fab")
		)
		(fp_line
			(start -0.67945 -0.305054)
			(end -0.12065 -0.305054)
			(stroke
				(width 0.1)
				(type default)
			)
			(layer "F.Fab")
		)
		(fp_line
			(start 0.67945 -0.3048)
			(end 0.67945 0.3048)
			(stroke
				(width 0.1)
				(type default)
			)
			(layer "F.Fab")
		)
		(fp_line
			(start 0.12065 -0.3048)
			(end 0.67945 -0.3048)
			(stroke
				(width 0.1)
				(type default)
			)
			(layer "F.Fab")
		)
		(fp_line
			(start 0.12065 -0.2794)
			(end 0.12065 -0.3048)
			(stroke
				(width 0.1)
				(type default)
			)
			(layer "F.Fab")
		)
		(fp_line
			(start -0.12065 -0.2794)
			(end 0.12065 -0.2794)
			(stroke
				(width 0.1)
				(type default)
			)
			(layer "F.Fab")
		)
		(fp_line
			(start 0.120396 0.2794)
			(end -0.12065 0.2794)
			(stroke
				(width 0.1)
				(type default)
			)
			(layer "F.Fab")
		)
		(fp_line
			(start -0.12065 0.2794)
			(end -0.12065 0.3048)
			(stroke
				(width 0.1)
				(type default)
			)
			(layer "F.Fab")
		)
		(fp_line
			(start 0.67945 0.3048)
			(end 0.120396 0.3048)
			(stroke
				(width 0.1)
				(type default)
			)
			(layer "F.Fab")
		)
		(fp_line
			(start 0.120396 0.3048)
			(end 0.120396 0.2794)
			(stroke
				(width 0.1)
				(type default)
			)
			(layer "F.Fab")
		)
		(fp_line
			(start -0.12065 0.3048)
			(end -0.67945 0.3048)
			(stroke
				(width 0.1)
				(type default)
			)
			(layer "F.Fab")
		)
		(fp_line
			(start -0.67945 0.3048)
			(end -0.67945 -0.305054)
			(stroke
				(width 0.1)
				(type default)
			)
			(layer "F.Fab")
		)
		(pad "1" smd circle
			(at -0.40005 0 90)
			(size 0 0)
			(layers "F.Cu" "F.Mask" "F.Paste")
			(net "PEX1_SYS_ERR_N_G")
		)
		(pad "2" smd circle
			(at 0.40005 0 90)
			(size 0 0)
			(layers "F.Cu" "F.Mask" "F.Paste")
			(net "PEX1_SYS_ERR_FPGA")
		)
	)
	(footprint ""
		(layer "F.Cu")
		(at 312.857388 -107.552998 -90)
		(property "Reference" "C920"
			(at 0 0 270)
			(layer "F.SilkS")
			(hide yes)
			(effects
				(font
					(size 1.27 1.27)
				)
			)
		)
		(property "Value" ""
			(at 0 0 270)
			(layer "F.Fab")
			(effects
				(font
					(size 1.27 1.27)
				)
			)
		)
		(duplicate_pad_numbers_are_jumpers no)
		(fp_line
			(start -1.524 0.762)
			(end -1.524 -0.762)
			(stroke
				(width 0.1524)
				(type default)
			)
			(layer "F.SilkS")
		)
		(fp_line
			(start 1.524 0.762)
			(end -1.524 0.762)
			(stroke
				(width 0.1524)
				(type default)
			)
			(layer "F.SilkS")
		)
		(fp_line
			(start -1.524 -0.762)
			(end 1.524 -0.762)
			(stroke
				(width 0.1524)
				(type default)
			)
			(layer "F.SilkS")
		)
		(fp_line
			(start 1.524 -0.762)
			(end 1.524 0.762)
			(stroke
				(width 0.1524)
				(type default)
			)
			(layer "F.SilkS")
		)
		(fp_line
			(start -1.1049 0.724916)
			(end 1.1049 0.724916)
			(stroke
				(width 0.1)
				(type default)
			)
			(layer "F.Fab")
		)
		(fp_line
			(start 1.1049 0.724916)
			(end 1.1049 -0.724916)
			(stroke
				(width 0.1)
				(type default)
			)
			(layer "F.Fab")
		)
		(fp_line
			(start -1.1049 -0.724916)
			(end -1.1049 0.724916)
			(stroke
				(width 0.1)
				(type default)
			)
			(layer "F.Fab")
		)
		(fp_line
			(start 1.1049 -0.724916)
			(end -1.1049 -0.724916)
			(stroke
				(width 0.1)
				(type default)
			)
			(layer "F.Fab")
		)
		(pad "1" smd rect
			(at -0.889 0 90)
			(size 1.016 1.27)
			(layers "F.Cu" "F.Mask" "F.Paste")
			(net "P12V_NIC5")
		)
		(pad "2" smd rect
			(at 0.889 0 90)
			(size 1.016 1.27)
			(layers "F.Cu" "F.Mask" "F.Paste")
			(net "GND")
		)
	)
	(footprint ""
		(layer "F.Cu")
		(at 387.580632 -124.605542)
		(property "Reference" "C674"
			(at 0 0 0)
			(layer "F.SilkS")
			(hide yes)
			(effects
				(font
					(size 1.27 1.27)
				)
			)
		)
		(property "Value" ""
			(at 0 0 0)
			(layer "F.Fab")
			(effects
				(font
					(size 1.27 1.27)
				)
			)
		)
		(duplicate_pad_numbers_are_jumpers no)
		(fp_line
			(start -0.299974 -0.150114)
			(end 0.299974 -0.150114)
			(stroke
				(width 0.1)
				(type default)
			)
			(layer "F.Fab")
		)
		(fp_line
			(start -0.299974 0.150114)
			(end -0.299974 -0.150114)
			(stroke
				(width 0.1)
				(type default)
			)
			(layer "F.Fab")
		)
		(fp_line
			(start 0.299974 -0.150114)
			(end 0.299974 0.150114)
			(stroke
				(width 0.1)
				(type default)
			)
			(layer "F.Fab")
		)
		(fp_line
			(start 0.299974 0.150114)
			(end -0.299974 0.150114)
			(stroke
				(width 0.1)
				(type default)
			)
			(layer "F.Fab")
		)
		(pad "1" smd rect
			(at -0.2667 0)
			(size 0.3048 0.381)
			(layers "F.Cu" "F.Mask" "F.Paste")
			(net "P5E_PEX3_STN1_TX_DN<27>")
		)
		(pad "2" smd rect
			(at 0.2667 0)
			(size 0.3048 0.381)
			(layers "F.Cu" "F.Mask" "F.Paste")
			(net "P5E_PEX3_STN1_TX_C_DN<27>")
		)
	)
	(footprint ""
		(layer "F.Cu")
		(at 383.66954 -260.088634 -90)
		(property "Reference" "R4591"
			(at 0 0 270)
			(layer "F.SilkS")
			(hide yes)
			(effects
				(font
					(size 1.27 1.27)
				)
			)
		)
		(property "Value" ""
			(at 0 0 270)
			(layer "F.Fab")
			(effects
				(font
					(size 1.27 1.27)
				)
			)
		)
		(duplicate_pad_numbers_are_jumpers no)
		(fp_line
			(start -0.7874 0.4064)
			(end -0.7874 -0.4064)
			(stroke
				(width 0.1524)
				(type default)
			)
			(layer "F.SilkS")
		)
		(fp_line
			(start 0.7874 0.4064)
			(end -0.7874 0.4064)
			(stroke
				(width 0.1524)
				(type default)
			)
			(layer "F.SilkS")
		)
		(fp_line
			(start -0.7874 -0.4064)
			(end 0.7874 -0.4064)
			(stroke
				(width 0.1524)
				(type default)
			)
			(layer "F.SilkS")
		)
		(fp_line
			(start 0.7874 -0.4064)
			(end 0.7874 0.4064)
			(stroke
				(width 0.1524)
				(type default)
			)
			(layer "F.SilkS")
		)
		(fp_line
			(start -0.67945 0.3048)
			(end -0.67945 -0.305054)
			(stroke
				(width 0.1)
				(type default)
			)
			(layer "F.Fab")
		)
		(fp_line
			(start -0.12065 0.3048)
			(end -0.67945 0.3048)
			(stroke
				(width 0.1)
				(type default)
			)
			(layer "F.Fab")
		)
		(fp_line
			(start 0.120396 0.3048)
			(end 0.120396 0.2794)
			(stroke
				(width 0.1)
				(type default)
			)
			(layer "F.Fab")
		)
		(fp_line
			(start 0.67945 0.3048)
			(end 0.120396 0.3048)
			(stroke
				(width 0.1)
				(type default)
			)
			(layer "F.Fab")
		)
		(fp_line
			(start -0.12065 0.2794)
			(end -0.12065 0.3048)
			(stroke
				(width 0.1)
				(type default)
			)
			(layer "F.Fab")
		)
		(fp_line
			(start 0.120396 0.2794)
			(end -0.12065 0.2794)
			(stroke
				(width 0.1)
				(type default)
			)
			(layer "F.Fab")
		)
		(fp_line
			(start -0.12065 -0.2794)
			(end 0.12065 -0.2794)
			(stroke
				(width 0.1)
				(type default)
			)
			(layer "F.Fab")
		)
		(fp_line
			(start 0.12065 -0.2794)
			(end 0.12065 -0.3048)
			(stroke
				(width 0.1)
				(type default)
			)
			(layer "F.Fab")
		)
		(fp_line
			(start 0.12065 -0.3048)
			(end 0.67945 -0.3048)
			(stroke
				(width 0.1)
				(type default)
			)
			(layer "F.Fab")
		)
		(fp_line
			(start 0.67945 -0.3048)
			(end 0.67945 0.3048)
			(stroke
				(width 0.1)
				(type default)
			)
			(layer "F.Fab")
		)
		(fp_line
			(start -0.67945 -0.305054)
			(end -0.12065 -0.305054)
			(stroke
				(width 0.1)
				(type default)
			)
			(layer "F.Fab")
		)
		(fp_line
			(start -0.12065 -0.305054)
			(end -0.12065 -0.2794)
			(stroke
				(width 0.1)
				(type default)
			)
			(layer "F.Fab")
		)
		(pad "1" smd circle
			(at -0.40005 0 270)
			(size 0 0)
			(layers "F.Cu" "F.Mask" "F.Paste")
			(net "PCEPLL3_VDDA18_PEX3")
		)
		(pad "2" smd circle
			(at 0.40005 0 270)
			(size 0 0)
			(layers "F.Cu" "F.Mask" "F.Paste")
			(net "PCEPLL3_VDDA18_PEX3_R")
		)
	)
	(footprint ""
		(layer "F.Cu")
		(at 289.850068 -50.96383 180)
		(property "Reference" "PC573"
			(at 0 0 180)
			(layer "F.SilkS")
			(hide yes)
			(effects
				(font
					(size 1.27 1.27)
				)
			)
		)
		(property "Value" ""
			(at 0 0 180)
			(layer "F.Fab")
			(effects
				(font
					(size 1.27 1.27)
				)
			)
		)
		(duplicate_pad_numbers_are_jumpers no)
		(fp_line
			(start 1.524 0.762)
			(end -1.524 0.762)
			(stroke
				(width 0.1524)
				(type default)
			)
			(layer "F.SilkS")
		)
		(fp_line
			(start 1.524 -0.762)
			(end 1.524 0.762)
			(stroke
				(width 0.1524)
				(type default)
			)
			(layer "F.SilkS")
		)
		(fp_line
			(start -1.524 0.762)
			(end -1.524 -0.762)
			(stroke
				(width 0.1524)
				(type default)
			)
			(layer "F.SilkS")
		)
		(fp_line
			(start -1.524 -0.762)
			(end 1.524 -0.762)
			(stroke
				(width 0.1524)
				(type default)
			)
			(layer "F.SilkS")
		)
		(fp_line
			(start 1.1049 0.724916)
			(end 1.1049 -0.724916)
			(stroke
				(width 0.1)
				(type default)
			)
			(layer "F.Fab")
		)
		(fp_line
			(start 1.1049 -0.724916)
			(end -1.1049 -0.724916)
			(stroke
				(width 0.1)
				(type default)
			)
			(layer "F.Fab")
		)
		(fp_line
			(start -1.1049 0.724916)
			(end 1.1049 0.724916)
			(stroke
				(width 0.1)
				(type default)
			)
			(layer "F.Fab")
		)
		(fp_line
			(start -1.1049 -0.724916)
			(end -1.1049 0.724916)
			(stroke
				(width 0.1)
				(type default)
			)
			(layer "F.Fab")
		)
		(pad "1" smd rect
			(at -0.889 0)
			(size 1.016 1.27)
			(layers "F.Cu" "F.Mask" "F.Paste")
			(net "P3V3_SSD10")
		)
		(pad "2" smd rect
			(at 0.889 0)
			(size 1.016 1.27)
			(layers "F.Cu" "F.Mask" "F.Paste")
			(net "GND")
		)
	)
	(footprint ""
		(layer "F.Cu")
		(at 270.807942 -155.3464 180)
		(property "Reference" "R218"
			(at 0 0 180)
			(layer "F.SilkS")
			(hide yes)
			(effects
				(font
					(size 1.27 1.27)
				)
			)
		)
		(property "Value" ""
			(at 0 0 180)
			(layer "F.Fab")
			(effects
				(font
					(size 1.27 1.27)
				)
			)
		)
		(duplicate_pad_numbers_are_jumpers no)
		(fp_line
			(start 0.7874 0.4064)
			(end -0.7874 0.4064)
			(stroke
				(width 0.1524)
				(type default)
			)
			(layer "F.SilkS")
		)
		(fp_line
			(start 0.7874 -0.4064)
			(end 0.7874 0.4064)
			(stroke
				(width 0.1524)
				(type default)
			)
			(layer "F.SilkS")
		)
		(fp_line
			(start -0.7874 0.4064)
			(end -0.7874 -0.4064)
			(stroke
				(width 0.1524)
				(type default)
			)
			(layer "F.SilkS")
		)
		(fp_line
			(start -0.7874 -0.4064)
			(end 0.7874 -0.4064)
			(stroke
				(width 0.1524)
				(type default)
			)
			(layer "F.SilkS")
		)
		(fp_line
			(start 0.67945 0.3048)
			(end 0.120396 0.3048)
			(stroke
				(width 0.1)
				(type default)
			)
			(layer "F.Fab")
		)
		(fp_line
			(start 0.67945 -0.3048)
			(end 0.67945 0.3048)
			(stroke
				(width 0.1)
				(type default)
			)
			(layer "F.Fab")
		)
		(fp_line
			(start 0.12065 -0.2794)
			(end 0.12065 -0.3048)
			(stroke
				(width 0.1)
				(type default)
			)
			(layer "F.Fab")
		)
		(fp_line
			(start 0.12065 -0.3048)
			(end 0.67945 -0.3048)
			(stroke
				(width 0.1)
				(type default)
			)
			(layer "F.Fab")
		)
		(fp_line
			(start 0.120396 0.3048)
			(end 0.120396 0.2794)
			(stroke
				(width 0.1)
				(type default)
			)
			(layer "F.Fab")
		)
		(fp_line
			(start 0.120396 0.2794)
			(end -0.12065 0.2794)
			(stroke
				(width 0.1)
				(type default)
			)
			(layer "F.Fab")
		)
		(fp_line
			(start -0.12065 0.3048)
			(end -0.67945 0.3048)
			(stroke
				(width 0.1)
				(type default)
			)
			(layer "F.Fab")
		)
		(fp_line
			(start -0.12065 0.2794)
			(end -0.12065 0.3048)
			(stroke
				(width 0.1)
				(type default)
			)
			(layer "F.Fab")
		)
		(fp_line
			(start -0.12065 -0.2794)
			(end 0.12065 -0.2794)
			(stroke
				(width 0.1)
				(type default)
			)
			(layer "F.Fab")
		)
		(fp_line
			(start -0.12065 -0.305054)
			(end -0.12065 -0.2794)
			(stroke
				(width 0.1)
				(type default)
			)
			(layer "F.Fab")
		)
		(fp_line
			(start -0.67945 0.3048)
			(end -0.67945 -0.305054)
			(stroke
				(width 0.1)
				(type default)
			)
			(layer "F.Fab")
		)
		(fp_line
			(start -0.67945 -0.305054)
			(end -0.12065 -0.305054)
			(stroke
				(width 0.1)
				(type default)
			)
			(layer "F.Fab")
		)
		(pad "1" smd circle
			(at -0.40005 0 180)
			(size 0 0)
			(layers "F.Cu" "F.Mask" "F.Paste")
			(net "NIC4_CLK")
		)
		(pad "2" smd circle
			(at 0.40005 0 180)
			(size 0 0)
			(layers "F.Cu" "F.Mask" "F.Paste")
			(net "GND")
		)
	)
	(footprint ""
		(layer "F.Cu")
		(at 262.353298 -291.390832)
		(property "Reference" "L124"
			(at 0 0 0)
			(layer "F.SilkS")
			(hide yes)
			(effects
				(font
					(size 1.27 1.27)
				)
			)
		)
		(property "Value" ""
			(at 0 0 0)
			(layer "F.Fab")
			(effects
				(font
					(size 1.27 1.27)
				)
			)
		)
		(duplicate_pad_numbers_are_jumpers no)
		(fp_line
			(start -1.63576 -0.8128)
			(end -1.63576 0.8128)
			(stroke
				(width 0.1524)
				(type default)
			)
			(layer "F.SilkS")
		)
		(fp_line
			(start -1.63576 -0.8128)
			(end 1.63576 -0.8128)
			(stroke
				(width 0.1524)
				(type default)
			)
			(layer "F.SilkS")
		)
		(fp_line
			(start 1.63576 -0.8128)
			(end 1.63576 0.8128)
			(stroke
				(width 0.1524)
				(type default)
			)
			(layer "F.SilkS")
		)
		(fp_line
			(start 1.63576 0.8128)
			(end -1.63576 0.8128)
			(stroke
				(width 0.1524)
				(type default)
			)
			(layer "F.SilkS")
		)
		(fp_line
			(start -1.56083 -0.738632)
			(end -1.56083 0.7366)
			(stroke
				(width 0.1)
				(type default)
			)
			(layer "F.Fab")
		)
		(fp_line
			(start -1.56083 0.7366)
			(end -1.524 0.7366)
			(stroke
				(width 0.1)
				(type default)
			)
			(layer "F.Fab")
		)
		(fp_line
			(start -1.524 0.7366)
			(end 1.524 0.7366)
			(stroke
				(width 0.1)
				(type default)
			)
			(layer "F.Fab")
		)
		(fp_line
			(start 1.524 0.7366)
			(end 1.560576 0.7366)
			(stroke
				(width 0.1)
				(type default)
			)
			(layer "F.Fab")
		)
		(fp_line
			(start 1.560576 -0.738632)
			(end -1.56083 -0.738632)
			(stroke
				(width 0.1)
				(type default)
			)
			(layer "F.Fab")
		)
		(fp_line
			(start 1.560576 0.7366)
			(end 1.560576 -0.738632)
			(stroke
				(width 0.1)
				(type default)
			)
			(layer "F.Fab")
		)
		(pad "1" smd rect
			(at -0.94996 0 180)
			(size 1.1176 1.3716)
			(layers "F.Cu" "F.Mask" "F.Paste")
			(net "P1V8_PLL0_PEX2")
		)
		(pad "2" smd rect
			(at 0.94996 0 180)
			(size 1.1176 1.3716)
			(layers "F.Cu" "F.Mask" "F.Paste")
			(net "PCEPLL4_VDDA18_PEX2")
		)
	)
	(footprint ""
		(layer "F.Cu")
		(at 374.543828 -49.95291 180)
		(property "Reference" "R643"
			(at 0 0 180)
			(layer "F.SilkS")
			(hide yes)
			(effects
				(font
					(size 1.27 1.27)
				)
			)
		)
		(property "Value" ""
			(at 0 0 180)
			(layer "F.Fab")
			(effects
				(font
					(size 1.27 1.27)
				)
			)
		)
		(duplicate_pad_numbers_are_jumpers no)
		(fp_line
			(start 0.7874 0.4064)
			(end -0.7874 0.4064)
			(stroke
				(width 0.1524)
				(type default)
			)
			(layer "F.SilkS")
		)
		(fp_line
			(start 0.7874 -0.4064)
			(end 0.7874 0.4064)
			(stroke
				(width 0.1524)
				(type default)
			)
			(layer "F.SilkS")
		)
		(fp_line
			(start -0.7874 0.4064)
			(end -0.7874 -0.4064)
			(stroke
				(width 0.1524)
				(type default)
			)
			(layer "F.SilkS")
		)
		(fp_line
			(start -0.7874 -0.4064)
			(end 0.7874 -0.4064)
			(stroke
				(width 0.1524)
				(type default)
			)
			(layer "F.SilkS")
		)
		(fp_line
			(start 0.67945 0.3048)
			(end 0.120396 0.3048)
			(stroke
				(width 0.1)
				(type default)
			)
			(layer "F.Fab")
		)
		(fp_line
			(start 0.67945 -0.3048)
			(end 0.67945 0.3048)
			(stroke
				(width 0.1)
				(type default)
			)
			(layer "F.Fab")
		)
		(fp_line
			(start 0.12065 -0.2794)
			(end 0.12065 -0.3048)
			(stroke
				(width 0.1)
				(type default)
			)
			(layer "F.Fab")
		)
		(fp_line
			(start 0.12065 -0.3048)
			(end 0.67945 -0.3048)
			(stroke
				(width 0.1)
				(type default)
			)
			(layer "F.Fab")
		)
		(fp_line
			(start 0.120396 0.3048)
			(end 0.120396 0.2794)
			(stroke
				(width 0.1)
				(type default)
			)
			(layer "F.Fab")
		)
		(fp_line
			(start 0.120396 0.2794)
			(end -0.12065 0.2794)
			(stroke
				(width 0.1)
				(type default)
			)
			(layer "F.Fab")
		)
		(fp_line
			(start -0.12065 0.3048)
			(end -0.67945 0.3048)
			(stroke
				(width 0.1)
				(type default)
			)
			(layer "F.Fab")
		)
		(fp_line
			(start -0.12065 0.2794)
			(end -0.12065 0.3048)
			(stroke
				(width 0.1)
				(type default)
			)
			(layer "F.Fab")
		)
		(fp_line
			(start -0.12065 -0.2794)
			(end 0.12065 -0.2794)
			(stroke
				(width 0.1)
				(type default)
			)
			(layer "F.Fab")
		)
		(fp_line
			(start -0.12065 -0.305054)
			(end -0.12065 -0.2794)
			(stroke
				(width 0.1)
				(type default)
			)
			(layer "F.Fab")
		)
		(fp_line
			(start -0.67945 0.3048)
			(end -0.67945 -0.305054)
			(stroke
				(width 0.1)
				(type default)
			)
			(layer "F.Fab")
		)
		(fp_line
			(start -0.67945 -0.305054)
			(end -0.12065 -0.305054)
			(stroke
				(width 0.1)
				(type default)
			)
			(layer "F.Fab")
		)
		(pad "1" smd circle
			(at -0.40005 0 180)
			(size 0 0)
			(layers "F.Cu" "F.Mask" "F.Paste")
			(net "SMB_BIC_I2C6_MUX_SSD_8_15_ADC_R_SCL")
		)
		(pad "2" smd circle
			(at 0.40005 0 180)
			(size 0 0)
			(layers "F.Cu" "F.Mask" "F.Paste")
			(net "SMB_SSD12_ADC_SCL")
		)
	)
	(footprint ""
		(layer "F.Cu")
		(at 148.417534 -115.336574 90)
		(property "Reference" "R145"
			(at 0 0 90)
			(layer "F.SilkS")
			(hide yes)
			(effects
				(font
					(size 1.27 1.27)
				)
			)
		)
		(property "Value" ""
			(at 0 0 90)
			(layer "F.Fab")
			(effects
				(font
					(size 1.27 1.27)
				)
			)
		)
		(duplicate_pad_numbers_are_jumpers no)
		(fp_line
			(start 0.7874 -0.4064)
			(end 0.7874 0.4064)
			(stroke
				(width 0.1524)
				(type default)
			)
			(layer "F.SilkS")
		)
		(fp_line
			(start -0.7874 -0.4064)
			(end 0.7874 -0.4064)
			(stroke
				(width 0.1524)
				(type default)
			)
			(layer "F.SilkS")
		)
		(fp_line
			(start 0.7874 0.4064)
			(end -0.7874 0.4064)
			(stroke
				(width 0.1524)
				(type default)
			)
			(layer "F.SilkS")
		)
		(fp_line
			(start -0.7874 0.4064)
			(end -0.7874 -0.4064)
			(stroke
				(width 0.1524)
				(type default)
			)
			(layer "F.SilkS")
		)
		(fp_line
			(start -0.12065 -0.305054)
			(end -0.12065 -0.2794)
			(stroke
				(width 0.1)
				(type default)
			)
			(layer "F.Fab")
		)
		(fp_line
			(start -0.67945 -0.305054)
			(end -0.12065 -0.305054)
			(stroke
				(width 0.1)
				(type default)
			)
			(layer "F.Fab")
		)
		(fp_line
			(start 0.67945 -0.3048)
			(end 0.67945 0.3048)
			(stroke
				(width 0.1)
				(type default)
			)
			(layer "F.Fab")
		)
		(fp_line
			(start 0.12065 -0.3048)
			(end 0.67945 -0.3048)
			(stroke
				(width 0.1)
				(type default)
			)
			(layer "F.Fab")
		)
		(fp_line
			(start 0.12065 -0.2794)
			(end 0.12065 -0.3048)
			(stroke
				(width 0.1)
				(type default)
			)
			(layer "F.Fab")
		)
		(fp_line
			(start -0.12065 -0.2794)
			(end 0.12065 -0.2794)
			(stroke
				(width 0.1)
				(type default)
			)
			(layer "F.Fab")
		)
		(fp_line
			(start 0.120396 0.2794)
			(end -0.12065 0.2794)
			(stroke
				(width 0.1)
				(type default)
			)
			(layer "F.Fab")
		)
		(fp_line
			(start -0.12065 0.2794)
			(end -0.12065 0.3048)
			(stroke
				(width 0.1)
				(type default)
			)
			(layer "F.Fab")
		)
		(fp_line
			(start 0.67945 0.3048)
			(end 0.120396 0.3048)
			(stroke
				(width 0.1)
				(type default)
			)
			(layer "F.Fab")
		)
		(fp_line
			(start 0.120396 0.3048)
			(end 0.120396 0.2794)
			(stroke
				(width 0.1)
				(type default)
			)
			(layer "F.Fab")
		)
		(fp_line
			(start -0.12065 0.3048)
			(end -0.67945 0.3048)
			(stroke
				(width 0.1)
				(type default)
			)
			(layer "F.Fab")
		)
		(fp_line
			(start -0.67945 0.3048)
			(end -0.67945 -0.305054)
			(stroke
				(width 0.1)
				(type default)
			)
			(layer "F.Fab")
		)
		(pad "1" smd circle
			(at -0.40005 0 90)
			(size 0 0)
			(layers "F.Cu" "F.Mask" "F.Paste")
			(net "PRSNT_NIC2_R_N")
		)
		(pad "2" smd circle
			(at 0.40005 0 90)
			(size 0 0)
			(layers "F.Cu" "F.Mask" "F.Paste")
			(net "PRSNT_NIC2_N")
		)
	)
	(footprint ""
		(layer "F.Cu")
		(at 414.273492 -191.410082)
		(property "Reference" "Q236"
			(at -0.3683 -3.474466 0)
			(unlocked yes)
			(layer "F.SilkS")
			(effects
				(font
					(size 0.7874 0.5842)
					(thickness 0.1524)
				)
			)
		)
		(property "Value" ""
			(at 0 0 0)
			(layer "F.Fab")
			(effects
				(font
					(size 1.27 1.27)
				)
			)
		)
		(duplicate_pad_numbers_are_jumpers no)
		(fp_line
			(start -1.376172 -1.199896)
			(end -0.508 -1.199896)
			(stroke
				(width 0.1524)
				(type default)
			)
			(layer "F.SilkS")
		)
		(fp_line
			(start -1.376172 1.199896)
			(end -1.376172 -1.199896)
			(stroke
				(width 0.1524)
				(type default)
			)
			(layer "F.SilkS")
		)
		(fp_line
			(start -0.508 -1.199896)
			(end 0 -0.762)
			(stroke
				(width 0.1524)
				(type default)
			)
			(layer "F.SilkS")
		)
		(fp_line
			(start 0 -0.762)
			(end 0.508 -1.199896)
			(stroke
				(width 0.1524)
				(type default)
			)
			(layer "F.SilkS")
		)
		(fp_line
			(start 0.508 -1.199896)
			(end 1.376172 -1.199896)
			(stroke
				(width 0.1524)
				(type default)
			)
			(layer "F.SilkS")
		)
		(fp_line
			(start 1.376172 -1.199896)
			(end 1.376172 1.199896)
			(stroke
				(width 0.1524)
				(type default)
			)
			(layer "F.SilkS")
		)
		(fp_line
			(start 1.376172 1.199896)
			(end -1.376172 1.199896)
			(stroke
				(width 0.1524)
				(type default)
			)
			(layer "F.SilkS")
		)
		(fp_poly
			(pts
				(xy -1.4605 -0.7493) (xy -2.2225 -1.1303) (xy -2.2225 -0.3683)
			)
			(stroke
				(width 0)
				(type default)
			)
			(fill yes)
			(layer "F.SilkS")
		)
		(fp_line
			(start -0.674878 -1.100074)
			(end 0.674878 -1.100074)
			(stroke
				(width 0.1)
				(type default)
			)
			(layer "F.Fab")
		)
		(fp_line
			(start -0.674878 1.100074)
			(end -0.674878 -1.100074)
			(stroke
				(width 0.1)
				(type default)
			)
			(layer "F.Fab")
		)
		(fp_line
			(start 0.674878 -1.100074)
			(end 0.674878 1.100074)
			(stroke
				(width 0.1)
				(type default)
			)
			(layer "F.Fab")
		)
		(fp_line
			(start 0.674878 1.100074)
			(end -0.674878 1.100074)
			(stroke
				(width 0.1)
				(type default)
			)
			(layer "F.Fab")
		)
		(fp_poly
			(pts
				(xy -1.4605 -0.7493) (xy -2.2225 -1.1303) (xy -2.2225 -0.3683)
			)
			(stroke
				(width 0)
				(type default)
			)
			(fill yes)
			(layer "F.Fab")
		)
		(pad "1" smd rect
			(at -0.899922 -0.750062 270)
			(size 0.6096 0.6096)
			(layers "F.Cu" "F.Mask" "F.Paste")
			(net "GND")
		)
		(pad "2" smd rect
			(at -0.899922 0 270)
			(size 0.4064 0.6096)
			(layers "F.Cu" "F.Mask" "F.Paste")
			(net "FPGA_PEX2_MODE_SEL1_R")
		)
		(pad "3" smd rect
			(at -0.899922 0.750062 270)
			(size 0.6096 0.6096)
			(layers "F.Cu" "F.Mask" "F.Paste")
			(net "FPGA_PEX2_MODE_SEL1_ISO")
		)
		(pad "4" smd rect
			(at 0.899922 0.750062 270)
			(size 0.6096 0.6096)
			(layers "F.Cu" "F.Mask" "F.Paste")
			(net "GND")
		)
		(pad "5" smd rect
			(at 0.899922 0 270)
			(size 0.4064 0.6096)
			(layers "F.Cu" "F.Mask" "F.Paste")
			(net "FPGA_PEX2_MODE_SEL1_D_N")
		)
		(pad "6" smd rect
			(at 0.899922 -0.750062 270)
			(size 0.6096 0.6096)
			(layers "F.Cu" "F.Mask" "F.Paste")
			(net "FPGA_PEX2_MODE_SEL1_D_N")
		)
	)
	(footprint ""
		(layer "F.Cu")
		(at 147.107402 -260.639814 -90)
		(property "Reference" "C3210"
			(at 0 0 270)
			(layer "F.SilkS")
			(hide yes)
			(effects
				(font
					(size 1.27 1.27)
				)
			)
		)
		(property "Value" ""
			(at 0 0 270)
			(layer "F.Fab")
			(effects
				(font
					(size 1.27 1.27)
				)
			)
		)
		(duplicate_pad_numbers_are_jumpers no)
		(fp_line
			(start -0.299974 0.150114)
			(end -0.299974 -0.150114)
			(stroke
				(width 0.1)
				(type default)
			)
			(layer "F.Fab")
		)
		(fp_line
			(start 0.299974 0.150114)
			(end -0.299974 0.150114)
			(stroke
				(width 0.1)
				(type default)
			)
			(layer "F.Fab")
		)
		(fp_line
			(start -0.299974 -0.150114)
			(end 0.299974 -0.150114)
			(stroke
				(width 0.1)
				(type default)
			)
			(layer "F.Fab")
		)
		(fp_line
			(start 0.299974 -0.150114)
			(end 0.299974 0.150114)
			(stroke
				(width 0.1)
				(type default)
			)
			(layer "F.Fab")
		)
		(pad "1" smd rect
			(at -0.2667 0 270)
			(size 0.3048 0.381)
			(layers "F.Cu" "F.Mask" "F.Paste")
			(net "P1V8_PLL0_PEX1")
		)
		(pad "2" smd rect
			(at 0.2667 0 270)
			(size 0.3048 0.381)
			(layers "F.Cu" "F.Mask" "F.Paste")
			(net "GND")
		)
	)
	(footprint ""
		(layer "F.Cu")
		(at 368.734594 -30.03169 180)
		(property "Reference" "C703"
			(at 0 0 180)
			(layer "F.SilkS")
			(hide yes)
			(effects
				(font
					(size 1.27 1.27)
				)
			)
		)
		(property "Value" ""
			(at 0 0 180)
			(layer "F.Fab")
			(effects
				(font
					(size 1.27 1.27)
				)
			)
		)
		(duplicate_pad_numbers_are_jumpers no)
		(fp_line
			(start 0.299974 0.150114)
			(end -0.299974 0.150114)
			(stroke
				(width 0.1)
				(type default)
			)
			(layer "F.Fab")
		)
		(fp_line
			(start 0.299974 -0.150114)
			(end 0.299974 0.150114)
			(stroke
				(width 0.1)
				(type default)
			)
			(layer "F.Fab")
		)
		(fp_line
			(start -0.299974 0.150114)
			(end -0.299974 -0.150114)
			(stroke
				(width 0.1)
				(type default)
			)
			(layer "F.Fab")
		)
		(fp_line
			(start -0.299974 -0.150114)
			(end 0.299974 -0.150114)
			(stroke
				(width 0.1)
				(type default)
			)
			(layer "F.Fab")
		)
		(pad "1" smd rect
			(at -0.2667 0 180)
			(size 0.3048 0.381)
			(layers "F.Cu" "F.Mask" "F.Paste")
			(net "P5E_PEX3_STN2_TX_DN<45>")
		)
		(pad "2" smd rect
			(at 0.2667 0 180)
			(size 0.3048 0.381)
			(layers "F.Cu" "F.Mask" "F.Paste")
			(net "P5E_PEX3_STN2_TX_C_DN<45>")
		)
	)
	(footprint ""
		(layer "F.Cu")
		(at 343.567004 -343.952322 90)
		(property "Reference" "C579"
			(at 0 0 90)
			(layer "F.SilkS")
			(hide yes)
			(effects
				(font
					(size 1.27 1.27)
				)
			)
		)
		(property "Value" ""
			(at 0 0 90)
			(layer "F.Fab")
			(effects
				(font
					(size 1.27 1.27)
				)
			)
		)
		(duplicate_pad_numbers_are_jumpers no)
		(fp_line
			(start 0.299974 -0.150114)
			(end 0.299974 0.150114)
			(stroke
				(width 0.1)
				(type default)
			)
			(layer "F.Fab")
		)
		(fp_line
			(start -0.299974 -0.150114)
			(end 0.299974 -0.150114)
			(stroke
				(width 0.1)
				(type default)
			)
			(layer "F.Fab")
		)
		(fp_line
			(start 0.299974 0.150114)
			(end -0.299974 0.150114)
			(stroke
				(width 0.1)
				(type default)
			)
			(layer "F.Fab")
		)
		(fp_line
			(start -0.299974 0.150114)
			(end -0.299974 -0.150114)
			(stroke
				(width 0.1)
				(type default)
			)
			(layer "F.Fab")
		)
		(pad "1" smd rect
			(at -0.2667 0 90)
			(size 0.3048 0.381)
			(layers "F.Cu" "F.Mask" "F.Paste")
			(net "P5E_PEX2_STN6_TX_DP<97>")
		)
		(pad "2" smd rect
			(at 0.2667 0 90)
			(size 0.3048 0.381)
			(layers "F.Cu" "F.Mask" "F.Paste")
			(net "P5E_PEX2_STN6_TX_C_DP<97>")
		)
	)
	(footprint ""
		(layer "F.Cu")
		(at 74.647044 -54.3941)
		(property "Reference" "PU34"
			(at -1.744218 2.865628 0)
			(unlocked yes)
			(layer "F.SilkS")
			(effects
				(font
					(size 0.7874 0.5842)
					(thickness 0.1524)
				)
				(justify left)
			)
		)
		(property "Value" ""
			(at 0 0 0)
			(layer "F.Fab")
			(effects
				(font
					(size 1.27 1.27)
				)
			)
		)
		(duplicate_pad_numbers_are_jumpers no)
		(fp_line
			(start -1.943608 -1.549908)
			(end 1.943608 -1.549908)
			(stroke
				(width 0.1524)
				(type default)
			)
			(layer "F.SilkS")
		)
		(fp_line
			(start -1.943608 1.549908)
			(end -1.943608 -1.549908)
			(stroke
				(width 0.1524)
				(type default)
			)
			(layer "F.SilkS")
		)
		(fp_line
			(start 1.943608 -1.549908)
			(end 1.943608 1.549908)
			(stroke
				(width 0.1524)
				(type default)
			)
			(layer "F.SilkS")
		)
		(fp_line
			(start 1.943608 1.549908)
			(end -1.943608 1.549908)
			(stroke
				(width 0.1524)
				(type default)
			)
			(layer "F.SilkS")
		)
		(fp_poly
			(pts
				(xy -2.019808 -1.549908) (xy -1.257808 -1.549908) (xy -1.257808 -1.880108) (xy -2.019808 -1.880108)
			)
			(stroke
				(width 0)
				(type default)
			)
			(fill yes)
			(layer "F.SilkS")
		)
		(fp_line
			(start -1.549908 -1.549908)
			(end 1.549908 -1.549908)
			(stroke
				(width 0.1)
				(type default)
			)
			(layer "F.Fab")
		)
		(fp_line
			(start -1.549908 1.549908)
			(end -1.549908 -1.549908)
			(stroke
				(width 0.1)
				(type default)
			)
			(layer "F.Fab")
		)
		(fp_line
			(start 1.549908 -1.549908)
			(end 1.549908 1.549908)
			(stroke
				(width 0.1)
				(type default)
			)
			(layer "F.Fab")
		)
		(fp_line
			(start 1.549908 1.549908)
			(end -1.549908 1.549908)
			(stroke
				(width 0.1)
				(type default)
			)
			(layer "F.Fab")
		)
		(fp_poly
			(pts
				(xy -2.019808 -1.549908) (xy -1.257808 -1.549908) (xy -1.257808 -1.880108) (xy -2.019808 -1.880108)
			)
			(stroke
				(width 0)
				(type default)
			)
			(fill yes)
			(layer "F.Fab")
		)
		(pad "1" smd rect
			(at -1.500124 -1.249934 270)
			(size 0.2794 0.6096)
			(layers "F.Cu" "F.Mask" "F.Paste")
			(net "P12V_SSD2_R")
		)
		(pad "2" smd rect
			(at -1.500124 -0.750062 270)
			(size 0.2794 0.6096)
			(layers "F.Cu" "F.Mask" "F.Paste")
			(net "P12V_SSD2_R")
		)
		(pad "3" smd rect
			(at -1.500124 -0.249936 270)
			(size 0.2794 0.6096)
			(layers "F.Cu" "F.Mask" "F.Paste")
			(net "P12V_SSD2_R")
		)
		(pad "4" smd rect
			(at -1.500124 0.249936 270)
			(size 0.2794 0.6096)
			(layers "F.Cu" "F.Mask" "F.Paste")
			(net "P12V_SSD2_R")
		)
		(pad "5" smd rect
			(at -1.500124 0.750062 270)
			(size 0.2794 0.6096)
			(layers "F.Cu" "F.Mask" "F.Paste")
			(net "P12V_SSD2_R")
		)
		(pad "6" smd rect
			(at -1.500124 1.249934 270)
			(size 0.2794 0.6096)
			(layers "F.Cu" "F.Mask" "F.Paste")
			(net "GND")
		)
		(pad "7" smd rect
			(at 1.500124 1.249934 270)
			(size 0.2794 0.6096)
			(layers "F.Cu" "F.Mask" "F.Paste")
			(net "P12V_SSD2_SS")
		)
		(pad "8" smd rect
			(at 1.500124 0.750062 270)
			(size 0.2794 0.6096)
			(layers "F.Cu" "F.Mask" "F.Paste")
			(net "PWRGD_P12V_SSD2")
		)
		(pad "9" smd rect
			(at 1.500124 0.249936 270)
			(size 0.2794 0.6096)
			(layers "F.Cu" "F.Mask" "F.Paste")
			(net "P12V_SSD2_OCP")
		)
		(pad "10" smd rect
			(at 1.500124 -0.249936 270)
			(size 0.2794 0.6096)
			(layers "F.Cu" "F.Mask" "F.Paste")
			(net "P5V_AUX")
		)
		(pad "11" smd rect
			(at 1.500124 -0.750062 270)
			(size 0.2794 0.6096)
			(layers "F.Cu" "F.Mask" "F.Paste")
			(net "SSD2_PWR_EN_R")
		)
		(pad "12" smd rect
			(at 1.500124 -1.249934 270)
			(size 0.2794 0.6096)
			(layers "F.Cu" "F.Mask" "F.Paste")
			(net "P12V_AUX")
		)
		(pad "13" smd rect
			(at 0 0)
			(size 1.9812 2.7178)
			(layers "F.Cu" "F.Mask" "F.Paste")
			(net "P12V_AUX")
		)
		(zone
			(layer "F.Cu")
			(hatch none 0.5)
			(connect_pads
				(clearance 0)
			)
			(min_thickness 0.25)
			(keepout
				(tracks not_allowed)
				(vias allowed)
				(pads allowed)
				(copperpour not_allowed)
				(footprints allowed)
			)
			(placement
				(enabled no)
				(sheetname "")
			)
			(fill
				(thermal_gap 0.5)
				(thermal_bridge_width 0.5)
				(island_removal_mode 0)
			)
			(polygon
				(pts
					(xy 75.790044 -55.9435) (xy 75.790044 -55.8165) (xy 75.790044 -52.8447) (xy 75.790044 -52.844192)
					(xy 73.504044 -52.844192) (xy 73.504044 -52.8447) (xy 73.504044 -52.9717) (xy 73.504044 -54.3941)
					(xy 73.605644 -54.3941) (xy 73.605644 -52.9717) (xy 75.688444 -52.9717) (xy 75.688444 -55.8165)
					(xy 73.605644 -55.8165) (xy 73.605644 -54.4195) (xy 73.504044 -54.4195) (xy 73.504044 -55.8165)
					(xy 73.504044 -55.9435) (xy 73.504044 -55.944008) (xy 75.790044 -55.944008)
				)
			)
		)
	)
	(footprint ""
		(layer "F.Cu")
		(at 117.226334 -39.73576 -90)
		(property "Reference" "R5551"
			(at 0 0 270)
			(layer "F.SilkS")
			(hide yes)
			(effects
				(font
					(size 1.27 1.27)
				)
			)
		)
		(property "Value" ""
			(at 0 0 270)
			(layer "F.Fab")
			(effects
				(font
					(size 1.27 1.27)
				)
			)
		)
		(duplicate_pad_numbers_are_jumpers no)
		(fp_line
			(start -0.7874 0.4064)
			(end -0.7874 -0.4064)
			(stroke
				(width 0.1524)
				(type default)
			)
			(layer "F.SilkS")
		)
		(fp_line
			(start 0.7874 0.4064)
			(end -0.7874 0.4064)
			(stroke
				(width 0.1524)
				(type default)
			)
			(layer "F.SilkS")
		)
		(fp_line
			(start -0.7874 -0.4064)
			(end 0.7874 -0.4064)
			(stroke
				(width 0.1524)
				(type default)
			)
			(layer "F.SilkS")
		)
		(fp_line
			(start 0.7874 -0.4064)
			(end 0.7874 0.4064)
			(stroke
				(width 0.1524)
				(type default)
			)
			(layer "F.SilkS")
		)
		(fp_line
			(start -0.67945 0.3048)
			(end -0.67945 -0.305054)
			(stroke
				(width 0.1)
				(type default)
			)
			(layer "F.Fab")
		)
		(fp_line
			(start -0.12065 0.3048)
			(end -0.67945 0.3048)
			(stroke
				(width 0.1)
				(type default)
			)
			(layer "F.Fab")
		)
		(fp_line
			(start 0.120396 0.3048)
			(end 0.120396 0.2794)
			(stroke
				(width 0.1)
				(type default)
			)
			(layer "F.Fab")
		)
		(fp_line
			(start 0.67945 0.3048)
			(end 0.120396 0.3048)
			(stroke
				(width 0.1)
				(type default)
			)
			(layer "F.Fab")
		)
		(fp_line
			(start -0.12065 0.2794)
			(end -0.12065 0.3048)
			(stroke
				(width 0.1)
				(type default)
			)
			(layer "F.Fab")
		)
		(fp_line
			(start 0.120396 0.2794)
			(end -0.12065 0.2794)
			(stroke
				(width 0.1)
				(type default)
			)
			(layer "F.Fab")
		)
		(fp_line
			(start -0.12065 -0.2794)
			(end 0.12065 -0.2794)
			(stroke
				(width 0.1)
				(type default)
			)
			(layer "F.Fab")
		)
		(fp_line
			(start 0.12065 -0.2794)
			(end 0.12065 -0.3048)
			(stroke
				(width 0.1)
				(type default)
			)
			(layer "F.Fab")
		)
		(fp_line
			(start 0.12065 -0.3048)
			(end 0.67945 -0.3048)
			(stroke
				(width 0.1)
				(type default)
			)
			(layer "F.Fab")
		)
		(fp_line
			(start 0.67945 -0.3048)
			(end 0.67945 0.3048)
			(stroke
				(width 0.1)
				(type default)
			)
			(layer "F.Fab")
		)
		(fp_line
			(start -0.67945 -0.305054)
			(end -0.12065 -0.305054)
			(stroke
				(width 0.1)
				(type default)
			)
			(layer "F.Fab")
		)
		(fp_line
			(start -0.12065 -0.305054)
			(end -0.12065 -0.2794)
			(stroke
				(width 0.1)
				(type default)
			)
			(layer "F.Fab")
		)
		(pad "1" smd circle
			(at -0.40005 0 270)
			(size 0 0)
			(layers "F.Cu" "F.Mask" "F.Paste")
			(net "P3V3_AUX")
		)
		(pad "2" smd circle
			(at 0.40005 0 270)
			(size 0 0)
			(layers "F.Cu" "F.Mask" "F.Paste")
			(net "SSD4_AUX_P3V3_EN")
		)
	)
	(footprint ""
		(layer "F.Cu")
		(at 52.243736 -47.92091)
		(property "Reference" "R515"
			(at 0 0 0)
			(layer "F.SilkS")
			(hide yes)
			(effects
				(font
					(size 1.27 1.27)
				)
			)
		)
		(property "Value" ""
			(at 0 0 0)
			(layer "F.Fab")
			(effects
				(font
					(size 1.27 1.27)
				)
			)
		)
		(duplicate_pad_numbers_are_jumpers no)
		(fp_line
			(start -0.7874 -0.4064)
			(end 0.7874 -0.4064)
			(stroke
				(width 0.1524)
				(type default)
			)
			(layer "F.SilkS")
		)
		(fp_line
			(start -0.7874 0.4064)
			(end -0.7874 -0.4064)
			(stroke
				(width 0.1524)
				(type default)
			)
			(layer "F.SilkS")
		)
		(fp_line
			(start 0.7874 -0.4064)
			(end 0.7874 0.4064)
			(stroke
				(width 0.1524)
				(type default)
			)
			(layer "F.SilkS")
		)
		(fp_line
			(start 0.7874 0.4064)
			(end -0.7874 0.4064)
			(stroke
				(width 0.1524)
				(type default)
			)
			(layer "F.SilkS")
		)
		(fp_line
			(start -0.67945 -0.305054)
			(end -0.12065 -0.305054)
			(stroke
				(width 0.1)
				(type default)
			)
			(layer "F.Fab")
		)
		(fp_line
			(start -0.67945 0.3048)
			(end -0.67945 -0.305054)
			(stroke
				(width 0.1)
				(type default)
			)
			(layer "F.Fab")
		)
		(fp_line
			(start -0.12065 -0.305054)
			(end -0.12065 -0.2794)
			(stroke
				(width 0.1)
				(type default)
			)
			(layer "F.Fab")
		)
		(fp_line
			(start -0.12065 -0.2794)
			(end 0.12065 -0.2794)
			(stroke
				(width 0.1)
				(type default)
			)
			(layer "F.Fab")
		)
		(fp_line
			(start -0.12065 0.2794)
			(end -0.12065 0.3048)
			(stroke
				(width 0.1)
				(type default)
			)
			(layer "F.Fab")
		)
		(fp_line
			(start -0.12065 0.3048)
			(end -0.67945 0.3048)
			(stroke
				(width 0.1)
				(type default)
			)
			(layer "F.Fab")
		)
		(fp_line
			(start 0.120396 0.2794)
			(end -0.12065 0.2794)
			(stroke
				(width 0.1)
				(type default)
			)
			(layer "F.Fab")
		)
		(fp_line
			(start 0.120396 0.3048)
			(end 0.120396 0.2794)
			(stroke
				(width 0.1)
				(type default)
			)
			(layer "F.Fab")
		)
		(fp_line
			(start 0.12065 -0.3048)
			(end 0.67945 -0.3048)
			(stroke
				(width 0.1)
				(type default)
			)
			(layer "F.Fab")
		)
		(fp_line
			(start 0.12065 -0.2794)
			(end 0.12065 -0.3048)
			(stroke
				(width 0.1)
				(type default)
			)
			(layer "F.Fab")
		)
		(fp_line
			(start 0.67945 -0.3048)
			(end 0.67945 0.3048)
			(stroke
				(width 0.1)
				(type default)
			)
			(layer "F.Fab")
		)
		(fp_line
			(start 0.67945 0.3048)
			(end 0.120396 0.3048)
			(stroke
				(width 0.1)
				(type default)
			)
			(layer "F.Fab")
		)
		(pad "1" smd circle
			(at -0.40005 0)
			(size 0 0)
			(layers "F.Cu" "F.Mask" "F.Paste")
			(net "P3V3_AUX")
		)
		(pad "2" smd circle
			(at 0.40005 0)
			(size 0 0)
			(layers "F.Cu" "F.Mask" "F.Paste")
			(net "SSD_0_7_ADC_ALERT_N")
		)
	)
	(footprint ""
		(layer "F.Cu")
		(at 241.216434 -250.759722 -90)
		(property "Reference" "R6227"
			(at 0 0 270)
			(layer "F.SilkS")
			(hide yes)
			(effects
				(font
					(size 1.27 1.27)
				)
			)
		)
		(property "Value" ""
			(at 0 0 270)
			(layer "F.Fab")
			(effects
				(font
					(size 1.27 1.27)
				)
			)
		)
		(duplicate_pad_numbers_are_jumpers no)
		(fp_line
			(start -0.7874 0.4064)
			(end -0.7874 -0.4064)
			(stroke
				(width 0.1524)
				(type default)
			)
			(layer "F.SilkS")
		)
		(fp_line
			(start 0.7874 0.4064)
			(end -0.7874 0.4064)
			(stroke
				(width 0.1524)
				(type default)
			)
			(layer "F.SilkS")
		)
		(fp_line
			(start -0.7874 -0.4064)
			(end 0.7874 -0.4064)
			(stroke
				(width 0.1524)
				(type default)
			)
			(layer "F.SilkS")
		)
		(fp_line
			(start 0.7874 -0.4064)
			(end 0.7874 0.4064)
			(stroke
				(width 0.1524)
				(type default)
			)
			(layer "F.SilkS")
		)
		(fp_line
			(start -0.67945 0.3048)
			(end -0.67945 -0.305054)
			(stroke
				(width 0.1)
				(type default)
			)
			(layer "F.Fab")
		)
		(fp_line
			(start -0.12065 0.3048)
			(end -0.67945 0.3048)
			(stroke
				(width 0.1)
				(type default)
			)
			(layer "F.Fab")
		)
		(fp_line
			(start 0.120396 0.3048)
			(end 0.120396 0.2794)
			(stroke
				(width 0.1)
				(type default)
			)
			(layer "F.Fab")
		)
		(fp_line
			(start 0.67945 0.3048)
			(end 0.120396 0.3048)
			(stroke
				(width 0.1)
				(type default)
			)
			(layer "F.Fab")
		)
		(fp_line
			(start -0.12065 0.2794)
			(end -0.12065 0.3048)
			(stroke
				(width 0.1)
				(type default)
			)
			(layer "F.Fab")
		)
		(fp_line
			(start 0.120396 0.2794)
			(end -0.12065 0.2794)
			(stroke
				(width 0.1)
				(type default)
			)
			(layer "F.Fab")
		)
		(fp_line
			(start -0.12065 -0.2794)
			(end 0.12065 -0.2794)
			(stroke
				(width 0.1)
				(type default)
			)
			(layer "F.Fab")
		)
		(fp_line
			(start 0.12065 -0.2794)
			(end 0.12065 -0.3048)
			(stroke
				(width 0.1)
				(type default)
			)
			(layer "F.Fab")
		)
		(fp_line
			(start 0.12065 -0.3048)
			(end 0.67945 -0.3048)
			(stroke
				(width 0.1)
				(type default)
			)
			(layer "F.Fab")
		)
		(fp_line
			(start 0.67945 -0.3048)
			(end 0.67945 0.3048)
			(stroke
				(width 0.1)
				(type default)
			)
			(layer "F.Fab")
		)
		(fp_line
			(start -0.67945 -0.305054)
			(end -0.12065 -0.305054)
			(stroke
				(width 0.1)
				(type default)
			)
			(layer "F.Fab")
		)
		(fp_line
			(start -0.12065 -0.305054)
			(end -0.12065 -0.2794)
			(stroke
				(width 0.1)
				(type default)
			)
			(layer "F.Fab")
		)
		(pad "1" smd circle
			(at -0.40005 0 270)
			(size 0 0)
			(layers "F.Cu" "F.Mask" "F.Paste")
			(net "BIC_FWSPICK")
		)
		(pad "2" smd circle
			(at 0.40005 0 270)
			(size 0 0)
			(layers "F.Cu" "F.Mask" "F.Paste")
			(net "BIC_FWSPICK_IOEXP")
		)
	)
	(footprint ""
		(layer "F.Cu")
		(at 355.19106 -55.663846 90)
		(property "Reference" "PU63"
			(at -0.900176 2.939034 90)
			(unlocked yes)
			(layer "F.SilkS")
			(effects
				(font
					(size 0.7874 0.5842)
					(thickness 0.1524)
				)
				(justify left)
			)
		)
		(property "Value" ""
			(at 0 0 90)
			(layer "F.Fab")
			(effects
				(font
					(size 1.27 1.27)
				)
			)
		)
		(duplicate_pad_numbers_are_jumpers no)
		(fp_line
			(start 1.943608 -1.549908)
			(end 1.943608 1.549908)
			(stroke
				(width 0.1524)
				(type default)
			)
			(layer "F.SilkS")
		)
		(fp_line
			(start -1.943608 -1.549908)
			(end 1.943608 -1.549908)
			(stroke
				(width 0.1524)
				(type default)
			)
			(layer "F.SilkS")
		)
		(fp_line
			(start 1.943608 1.549908)
			(end -1.943608 1.549908)
			(stroke
				(width 0.1524)
				(type default)
			)
			(layer "F.SilkS")
		)
		(fp_line
			(start -1.943608 1.549908)
			(end -1.943608 -1.549908)
			(stroke
				(width 0.1524)
				(type default)
			)
			(layer "F.SilkS")
		)
		(fp_poly
			(pts
				(xy -2.019808 -1.549908) (xy -1.257808 -1.549908) (xy -1.257808 -1.880108) (xy -2.019808 -1.880108)
			)
			(stroke
				(width 0)
				(type default)
			)
			(fill yes)
			(layer "F.SilkS")
		)
		(fp_line
			(start 1.549908 -1.549908)
			(end 1.549908 1.549908)
			(stroke
				(width 0.1)
				(type default)
			)
			(layer "F.Fab")
		)
		(fp_line
			(start -1.549908 -1.549908)
			(end 1.549908 -1.549908)
			(stroke
				(width 0.1)
				(type default)
			)
			(layer "F.Fab")
		)
		(fp_line
			(start 1.549908 1.549908)
			(end -1.549908 1.549908)
			(stroke
				(width 0.1)
				(type default)
			)
			(layer "F.Fab")
		)
		(fp_line
			(start -1.549908 1.549908)
			(end -1.549908 -1.549908)
			(stroke
				(width 0.1)
				(type default)
			)
			(layer "F.Fab")
		)
		(fp_poly
			(pts
				(xy -2.019808 -1.549908) (xy -1.257808 -1.549908) (xy -1.257808 -1.880108) (xy -2.019808 -1.880108)
			)
			(stroke
				(width 0)
				(type default)
			)
			(fill yes)
			(layer "F.Fab")
		)
		(pad "1" smd rect
			(at -1.500124 -1.249934)
			(size 0.2794 0.6096)
			(layers "F.Cu" "F.Mask" "F.Paste")
			(net "P3V3_SSD12")
		)
		(pad "2" smd rect
			(at -1.500124 -0.750062)
			(size 0.2794 0.6096)
			(layers "F.Cu" "F.Mask" "F.Paste")
			(net "P3V3_SSD12")
		)
		(pad "3" smd rect
			(at -1.500124 -0.249936)
			(size 0.2794 0.6096)
			(layers "F.Cu" "F.Mask" "F.Paste")
			(net "P3V3_SSD12")
		)
		(pad "4" smd rect
			(at -1.500124 0.249936)
			(size 0.2794 0.6096)
			(layers "F.Cu" "F.Mask" "F.Paste")
			(net "P3V3_SSD12")
		)
		(pad "5" smd rect
			(at -1.500124 0.750062)
			(size 0.2794 0.6096)
			(layers "F.Cu" "F.Mask" "F.Paste")
			(net "P3V3_SSD12")
		)
		(pad "6" smd rect
			(at -1.500124 1.249934)
			(size 0.2794 0.6096)
			(layers "F.Cu" "F.Mask" "F.Paste")
			(net "GND")
		)
		(pad "7" smd rect
			(at 1.500124 1.249934)
			(size 0.2794 0.6096)
			(layers "F.Cu" "F.Mask" "F.Paste")
			(net "P3V3_SSD12_SS")
		)
		(pad "8" smd rect
			(at 1.500124 0.750062)
			(size 0.2794 0.6096)
			(layers "F.Cu" "F.Mask" "F.Paste")
			(net "PWRGD_P3V3_SSD12")
		)
		(pad "9" smd rect
			(at 1.500124 0.249936)
			(size 0.2794 0.6096)
			(layers "F.Cu" "F.Mask" "F.Paste")
			(net "P3V3_SSD12_OCP")
		)
		(pad "10" smd rect
			(at 1.500124 -0.249936)
			(size 0.2794 0.6096)
			(layers "F.Cu" "F.Mask" "F.Paste")
			(net "P5V_AUX")
		)
		(pad "11" smd rect
			(at 1.500124 -0.750062)
			(size 0.2794 0.6096)
			(layers "F.Cu" "F.Mask" "F.Paste")
			(net "SSD12_AUX_P3V3_EN_R")
		)
		(pad "12" smd rect
			(at 1.500124 -1.249934)
			(size 0.2794 0.6096)
			(layers "F.Cu" "F.Mask" "F.Paste")
			(net "P3V3_AUX")
		)
		(pad "13" smd rect
			(at 0 0 90)
			(size 1.9812 2.7178)
			(layers "F.Cu" "F.Mask" "F.Paste")
			(net "P3V3_AUX")
		)
		(zone
			(layer "F.Cu")
			(hatch none 0.5)
			(connect_pads
				(clearance 0)
			)
			(min_thickness 0.25)
			(keepout
				(tracks not_allowed)
				(vias allowed)
				(pads allowed)
				(copperpour not_allowed)
				(footprints allowed)
			)
			(placement
				(enabled no)
				(sheetname "")
			)
			(fill
				(thermal_gap 0.5)
				(thermal_bridge_width 0.5)
				(island_removal_mode 0)
			)
			(polygon
				(pts
					(xy 353.64166 -56.806846) (xy 353.76866 -56.806846) (xy 356.74046 -56.806846) (xy 356.740968 -56.806846)
					(xy 356.740968 -54.520846) (xy 356.74046 -54.520846) (xy 356.61346 -54.520846) (xy 355.19106 -54.520846)
					(xy 355.19106 -54.622446) (xy 356.61346 -54.622446) (xy 356.61346 -56.705246) (xy 353.76866 -56.705246)
					(xy 353.76866 -54.622446) (xy 355.16566 -54.622446) (xy 355.16566 -54.520846) (xy 353.76866 -54.520846)
					(xy 353.64166 -54.520846) (xy 353.641152 -54.520846) (xy 353.641152 -56.806846)
				)
			)
		)
	)
	(footprint ""
		(layer "F.Cu")
		(at 254.085598 -25.1587 -90)
		(property "Reference" "R5760"
			(at 0 0 270)
			(layer "F.SilkS")
			(hide yes)
			(effects
				(font
					(size 1.27 1.27)
				)
			)
		)
		(property "Value" ""
			(at 0 0 270)
			(layer "F.Fab")
			(effects
				(font
					(size 1.27 1.27)
				)
			)
		)
		(duplicate_pad_numbers_are_jumpers no)
		(fp_line
			(start -0.7874 0.4064)
			(end -0.7874 -0.4064)
			(stroke
				(width 0.1524)
				(type default)
			)
			(layer "F.SilkS")
		)
		(fp_line
			(start 0.7874 0.4064)
			(end -0.7874 0.4064)
			(stroke
				(width 0.1524)
				(type default)
			)
			(layer "F.SilkS")
		)
		(fp_line
			(start -0.7874 -0.4064)
			(end 0.7874 -0.4064)
			(stroke
				(width 0.1524)
				(type default)
			)
			(layer "F.SilkS")
		)
		(fp_line
			(start 0.7874 -0.4064)
			(end 0.7874 0.4064)
			(stroke
				(width 0.1524)
				(type default)
			)
			(layer "F.SilkS")
		)
		(fp_line
			(start -0.67945 0.3048)
			(end -0.67945 -0.305054)
			(stroke
				(width 0.1)
				(type default)
			)
			(layer "F.Fab")
		)
		(fp_line
			(start -0.12065 0.3048)
			(end -0.67945 0.3048)
			(stroke
				(width 0.1)
				(type default)
			)
			(layer "F.Fab")
		)
		(fp_line
			(start 0.120396 0.3048)
			(end 0.120396 0.2794)
			(stroke
				(width 0.1)
				(type default)
			)
			(layer "F.Fab")
		)
		(fp_line
			(start 0.67945 0.3048)
			(end 0.120396 0.3048)
			(stroke
				(width 0.1)
				(type default)
			)
			(layer "F.Fab")
		)
		(fp_line
			(start -0.12065 0.2794)
			(end -0.12065 0.3048)
			(stroke
				(width 0.1)
				(type default)
			)
			(layer "F.Fab")
		)
		(fp_line
			(start 0.120396 0.2794)
			(end -0.12065 0.2794)
			(stroke
				(width 0.1)
				(type default)
			)
			(layer "F.Fab")
		)
		(fp_line
			(start -0.12065 -0.2794)
			(end 0.12065 -0.2794)
			(stroke
				(width 0.1)
				(type default)
			)
			(layer "F.Fab")
		)
		(fp_line
			(start 0.12065 -0.2794)
			(end 0.12065 -0.3048)
			(stroke
				(width 0.1)
				(type default)
			)
			(layer "F.Fab")
		)
		(fp_line
			(start 0.12065 -0.3048)
			(end 0.67945 -0.3048)
			(stroke
				(width 0.1)
				(type default)
			)
			(layer "F.Fab")
		)
		(fp_line
			(start 0.67945 -0.3048)
			(end 0.67945 0.3048)
			(stroke
				(width 0.1)
				(type default)
			)
			(layer "F.Fab")
		)
		(fp_line
			(start -0.67945 -0.305054)
			(end -0.12065 -0.305054)
			(stroke
				(width 0.1)
				(type default)
			)
			(layer "F.Fab")
		)
		(fp_line
			(start -0.12065 -0.305054)
			(end -0.12065 -0.2794)
			(stroke
				(width 0.1)
				(type default)
			)
			(layer "F.Fab")
		)
		(pad "1" smd circle
			(at -0.40005 0 270)
			(size 0 0)
			(layers "F.Cu" "F.Mask" "F.Paste")
			(net "SSD8_LED_ISO_N")
		)
		(pad "2" smd circle
			(at 0.40005 0 270)
			(size 0 0)
			(layers "F.Cu" "F.Mask" "F.Paste")
			(net "SSD8_LED_ISO_R_N")
		)
	)
	(footprint ""
		(layer "F.Cu")
		(at 322.239386 -96.811592 -90)
		(property "Reference" "R739"
			(at 0 0 270)
			(layer "F.SilkS")
			(hide yes)
			(effects
				(font
					(size 1.27 1.27)
				)
			)
		)
		(property "Value" ""
			(at 0 0 270)
			(layer "F.Fab")
			(effects
				(font
					(size 1.27 1.27)
				)
			)
		)
		(duplicate_pad_numbers_are_jumpers no)
		(fp_line
			(start -0.7874 0.4064)
			(end -0.7874 -0.4064)
			(stroke
				(width 0.1524)
				(type default)
			)
			(layer "F.SilkS")
		)
		(fp_line
			(start 0.7874 0.4064)
			(end -0.7874 0.4064)
			(stroke
				(width 0.1524)
				(type default)
			)
			(layer "F.SilkS")
		)
		(fp_line
			(start -0.7874 -0.4064)
			(end 0.7874 -0.4064)
			(stroke
				(width 0.1524)
				(type default)
			)
			(layer "F.SilkS")
		)
		(fp_line
			(start 0.7874 -0.4064)
			(end 0.7874 0.4064)
			(stroke
				(width 0.1524)
				(type default)
			)
			(layer "F.SilkS")
		)
		(fp_line
			(start -0.67945 0.3048)
			(end -0.67945 -0.305054)
			(stroke
				(width 0.1)
				(type default)
			)
			(layer "F.Fab")
		)
		(fp_line
			(start -0.12065 0.3048)
			(end -0.67945 0.3048)
			(stroke
				(width 0.1)
				(type default)
			)
			(layer "F.Fab")
		)
		(fp_line
			(start 0.120396 0.3048)
			(end 0.120396 0.2794)
			(stroke
				(width 0.1)
				(type default)
			)
			(layer "F.Fab")
		)
		(fp_line
			(start 0.67945 0.3048)
			(end 0.120396 0.3048)
			(stroke
				(width 0.1)
				(type default)
			)
			(layer "F.Fab")
		)
		(fp_line
			(start -0.12065 0.2794)
			(end -0.12065 0.3048)
			(stroke
				(width 0.1)
				(type default)
			)
			(layer "F.Fab")
		)
		(fp_line
			(start 0.120396 0.2794)
			(end -0.12065 0.2794)
			(stroke
				(width 0.1)
				(type default)
			)
			(layer "F.Fab")
		)
		(fp_line
			(start -0.12065 -0.2794)
			(end 0.12065 -0.2794)
			(stroke
				(width 0.1)
				(type default)
			)
			(layer "F.Fab")
		)
		(fp_line
			(start 0.12065 -0.2794)
			(end 0.12065 -0.3048)
			(stroke
				(width 0.1)
				(type default)
			)
			(layer "F.Fab")
		)
		(fp_line
			(start 0.12065 -0.3048)
			(end 0.67945 -0.3048)
			(stroke
				(width 0.1)
				(type default)
			)
			(layer "F.Fab")
		)
		(fp_line
			(start 0.67945 -0.3048)
			(end 0.67945 0.3048)
			(stroke
				(width 0.1)
				(type default)
			)
			(layer "F.Fab")
		)
		(fp_line
			(start -0.67945 -0.305054)
			(end -0.12065 -0.305054)
			(stroke
				(width 0.1)
				(type default)
			)
			(layer "F.Fab")
		)
		(fp_line
			(start -0.12065 -0.305054)
			(end -0.12065 -0.2794)
			(stroke
				(width 0.1)
				(type default)
			)
			(layer "F.Fab")
		)
		(pad "1" smd circle
			(at -0.40005 0 270)
			(size 0 0)
			(layers "F.Cu" "F.Mask" "F.Paste")
			(net "NIC5_ADC_A0")
		)
		(pad "2" smd circle
			(at 0.40005 0 270)
			(size 0 0)
			(layers "F.Cu" "F.Mask" "F.Paste")
			(net "GND")
		)
	)
	(footprint ""
		(layer "F.Cu")
		(at 458.18679 -365.54156 -90)
		(property "Reference" "R6689"
			(at 0 0 270)
			(layer "F.SilkS")
			(hide yes)
			(effects
				(font
					(size 1.27 1.27)
				)
			)
		)
		(property "Value" ""
			(at 0 0 270)
			(layer "F.Fab")
			(effects
				(font
					(size 1.27 1.27)
				)
			)
		)
		(duplicate_pad_numbers_are_jumpers no)
		(fp_line
			(start -0.7874 0.4064)
			(end -0.7874 -0.4064)
			(stroke
				(width 0.1524)
				(type default)
			)
			(layer "F.SilkS")
		)
		(fp_line
			(start 0.7874 0.4064)
			(end -0.7874 0.4064)
			(stroke
				(width 0.1524)
				(type default)
			)
			(layer "F.SilkS")
		)
		(fp_line
			(start -0.7874 -0.4064)
			(end 0.7874 -0.4064)
			(stroke
				(width 0.1524)
				(type default)
			)
			(layer "F.SilkS")
		)
		(fp_line
			(start 0.7874 -0.4064)
			(end 0.7874 0.4064)
			(stroke
				(width 0.1524)
				(type default)
			)
			(layer "F.SilkS")
		)
		(fp_line
			(start -0.67945 0.3048)
			(end -0.67945 -0.305054)
			(stroke
				(width 0.1)
				(type default)
			)
			(layer "F.Fab")
		)
		(fp_line
			(start -0.12065 0.3048)
			(end -0.67945 0.3048)
			(stroke
				(width 0.1)
				(type default)
			)
			(layer "F.Fab")
		)
		(fp_line
			(start 0.120396 0.3048)
			(end 0.120396 0.2794)
			(stroke
				(width 0.1)
				(type default)
			)
			(layer "F.Fab")
		)
		(fp_line
			(start 0.67945 0.3048)
			(end 0.120396 0.3048)
			(stroke
				(width 0.1)
				(type default)
			)
			(layer "F.Fab")
		)
		(fp_line
			(start -0.12065 0.2794)
			(end -0.12065 0.3048)
			(stroke
				(width 0.1)
				(type default)
			)
			(layer "F.Fab")
		)
		(fp_line
			(start 0.120396 0.2794)
			(end -0.12065 0.2794)
			(stroke
				(width 0.1)
				(type default)
			)
			(layer "F.Fab")
		)
		(fp_line
			(start -0.12065 -0.2794)
			(end 0.12065 -0.2794)
			(stroke
				(width 0.1)
				(type default)
			)
			(layer "F.Fab")
		)
		(fp_line
			(start 0.12065 -0.2794)
			(end 0.12065 -0.3048)
			(stroke
				(width 0.1)
				(type default)
			)
			(layer "F.Fab")
		)
		(fp_line
			(start 0.12065 -0.3048)
			(end 0.67945 -0.3048)
			(stroke
				(width 0.1)
				(type default)
			)
			(layer "F.Fab")
		)
		(fp_line
			(start 0.67945 -0.3048)
			(end 0.67945 0.3048)
			(stroke
				(width 0.1)
				(type default)
			)
			(layer "F.Fab")
		)
		(fp_line
			(start -0.67945 -0.305054)
			(end -0.12065 -0.305054)
			(stroke
				(width 0.1)
				(type default)
			)
			(layer "F.Fab")
		)
		(fp_line
			(start -0.12065 -0.305054)
			(end -0.12065 -0.2794)
			(stroke
				(width 0.1)
				(type default)
			)
			(layer "F.Fab")
		)
		(pad "1" smd circle
			(at -0.40005 0 270)
			(size 0 0)
			(layers "F.Cu" "F.Mask" "F.Paste")
			(net "GPU_3V3IO_RSVD4_ISO")
		)
		(pad "2" smd circle
			(at 0.40005 0 270)
			(size 0 0)
			(layers "F.Cu" "F.Mask" "F.Paste")
			(net "P3V3_AUX")
		)
	)
	(footprint ""
		(layer "F.Cu")
		(at 436.07736 -309.791354 135)
		(property "Reference" "R1446"
			(at 0 0 135)
			(layer "F.SilkS")
			(hide yes)
			(effects
				(font
					(size 1.27 1.27)
				)
			)
		)
		(property "Value" ""
			(at 0 0 135)
			(layer "F.Fab")
			(effects
				(font
					(size 1.27 1.27)
				)
			)
		)
		(duplicate_pad_numbers_are_jumpers no)
		(fp_line
			(start 0.787389 -0.406267)
			(end 0.787389 0.406267)
			(stroke
				(width 0.1524)
				(type default)
			)
			(layer "F.SilkS")
		)
		(fp_line
			(start 0.787389 0.406267)
			(end -0.787389 0.406267)
			(stroke
				(width 0.1524)
				(type default)
			)
			(layer "F.SilkS")
		)
		(fp_line
			(start -0.787389 -0.406267)
			(end 0.787389 -0.406267)
			(stroke
				(width 0.1524)
				(type default)
			)
			(layer "F.SilkS")
		)
		(fp_line
			(start -0.787389 0.406267)
			(end -0.787389 -0.406267)
			(stroke
				(width 0.1524)
				(type default)
			)
			(layer "F.SilkS")
		)
		(fp_line
			(start 0.679446 -0.30479)
			(end 0.679446 0.30479)
			(stroke
				(width 0.1)
				(type default)
			)
			(layer "F.Fab")
		)
		(fp_line
			(start 0.120515 -0.30479)
			(end 0.679446 -0.30479)
			(stroke
				(width 0.1)
				(type default)
			)
			(layer "F.Fab")
		)
		(fp_line
			(start 0.120695 -0.279466)
			(end 0.120515 -0.30479)
			(stroke
				(width 0.1)
				(type default)
			)
			(layer "F.Fab")
		)
		(fp_line
			(start 0.679446 0.30479)
			(end 0.120515 0.30479)
			(stroke
				(width 0.1)
				(type default)
			)
			(layer "F.Fab")
		)
		(fp_line
			(start -0.120695 -0.304969)
			(end -0.120695 -0.279466)
			(stroke
				(width 0.1)
				(type default)
			)
			(layer "F.Fab")
		)
		(fp_line
			(start -0.120695 -0.279466)
			(end 0.120695 -0.279466)
			(stroke
				(width 0.1)
				(type default)
			)
			(layer "F.Fab")
		)
		(fp_line
			(start 0.120335 0.279466)
			(end -0.120695 0.279466)
			(stroke
				(width 0.1)
				(type default)
			)
			(layer "F.Fab")
		)
		(fp_line
			(start 0.120515 0.30479)
			(end 0.120335 0.279466)
			(stroke
				(width 0.1)
				(type default)
			)
			(layer "F.Fab")
		)
		(fp_line
			(start -0.679446 -0.305149)
			(end -0.120695 -0.304969)
			(stroke
				(width 0.1)
				(type default)
			)
			(layer "F.Fab")
		)
		(fp_line
			(start -0.120695 0.279466)
			(end -0.120515 0.30479)
			(stroke
				(width 0.1)
				(type default)
			)
			(layer "F.Fab")
		)
		(fp_line
			(start -0.120515 0.30479)
			(end -0.679446 0.30479)
			(stroke
				(width 0.1)
				(type default)
			)
			(layer "F.Fab")
		)
		(fp_line
			(start -0.679446 0.30479)
			(end -0.679446 -0.305149)
			(stroke
				(width 0.1)
				(type default)
			)
			(layer "F.Fab")
		)
		(pad "1" smd circle
			(at -0.40005 0 135)
			(size 0 0)
			(layers "F.Cu" "F.Mask" "F.Paste")
			(net "PEX3_SPARE7")
		)
		(pad "2" smd circle
			(at 0.40005 0 135)
			(size 0 0)
			(layers "F.Cu" "F.Mask" "F.Paste")
			(net "P1V8_PEX")
		)
	)
	(footprint ""
		(layer "F.Cu")
		(at 380.770384 -252.356874 -90)
		(property "Reference" "R1433"
			(at 0 0 270)
			(layer "F.SilkS")
			(hide yes)
			(effects
				(font
					(size 1.27 1.27)
				)
			)
		)
		(property "Value" ""
			(at 0 0 270)
			(layer "F.Fab")
			(effects
				(font
					(size 1.27 1.27)
				)
			)
		)
		(duplicate_pad_numbers_are_jumpers no)
		(fp_line
			(start -0.7874 0.4064)
			(end -0.7874 -0.4064)
			(stroke
				(width 0.1524)
				(type default)
			)
			(layer "F.SilkS")
		)
		(fp_line
			(start 0.7874 0.4064)
			(end -0.7874 0.4064)
			(stroke
				(width 0.1524)
				(type default)
			)
			(layer "F.SilkS")
		)
		(fp_line
			(start -0.7874 -0.4064)
			(end 0.7874 -0.4064)
			(stroke
				(width 0.1524)
				(type default)
			)
			(layer "F.SilkS")
		)
		(fp_line
			(start 0.7874 -0.4064)
			(end 0.7874 0.4064)
			(stroke
				(width 0.1524)
				(type default)
			)
			(layer "F.SilkS")
		)
		(fp_line
			(start -0.67945 0.3048)
			(end -0.67945 -0.305054)
			(stroke
				(width 0.1)
				(type default)
			)
			(layer "F.Fab")
		)
		(fp_line
			(start -0.12065 0.3048)
			(end -0.67945 0.3048)
			(stroke
				(width 0.1)
				(type default)
			)
			(layer "F.Fab")
		)
		(fp_line
			(start 0.120396 0.3048)
			(end 0.120396 0.2794)
			(stroke
				(width 0.1)
				(type default)
			)
			(layer "F.Fab")
		)
		(fp_line
			(start 0.67945 0.3048)
			(end 0.120396 0.3048)
			(stroke
				(width 0.1)
				(type default)
			)
			(layer "F.Fab")
		)
		(fp_line
			(start -0.12065 0.2794)
			(end -0.12065 0.3048)
			(stroke
				(width 0.1)
				(type default)
			)
			(layer "F.Fab")
		)
		(fp_line
			(start 0.120396 0.2794)
			(end -0.12065 0.2794)
			(stroke
				(width 0.1)
				(type default)
			)
			(layer "F.Fab")
		)
		(fp_line
			(start -0.12065 -0.2794)
			(end 0.12065 -0.2794)
			(stroke
				(width 0.1)
				(type default)
			)
			(layer "F.Fab")
		)
		(fp_line
			(start 0.12065 -0.2794)
			(end 0.12065 -0.3048)
			(stroke
				(width 0.1)
				(type default)
			)
			(layer "F.Fab")
		)
		(fp_line
			(start 0.12065 -0.3048)
			(end 0.67945 -0.3048)
			(stroke
				(width 0.1)
				(type default)
			)
			(layer "F.Fab")
		)
		(fp_line
			(start 0.67945 -0.3048)
			(end 0.67945 0.3048)
			(stroke
				(width 0.1)
				(type default)
			)
			(layer "F.Fab")
		)
		(fp_line
			(start -0.67945 -0.305054)
			(end -0.12065 -0.305054)
			(stroke
				(width 0.1)
				(type default)
			)
			(layer "F.Fab")
		)
		(fp_line
			(start -0.12065 -0.305054)
			(end -0.12065 -0.2794)
			(stroke
				(width 0.1)
				(type default)
			)
			(layer "F.Fab")
		)
		(pad "1" smd circle
			(at -0.40005 0 270)
			(size 0 0)
			(layers "F.Cu" "F.Mask" "F.Paste")
			(net "GND")
		)
		(pad "2" smd circle
			(at 0.40005 0 270)
			(size 0 0)
			(layers "F.Cu" "F.Mask" "F.Paste")
			(net "PEX3_MODE_SEL8")
		)
	)
	(footprint ""
		(layer "F.Cu")
		(at 447.449956 -308.61)
		(property "Reference" "H134"
			(at -2.435098 -4.410964 0)
			(unlocked yes)
			(layer "F.SilkS")
			(effects
				(font
					(size 0.7874 0.5842)
					(thickness 0.1524)
				)
				(justify left)
			)
		)
		(property "Value" ""
			(at 0 0 0)
			(layer "F.Fab")
			(effects
				(font
					(size 1.27 1.27)
				)
			)
		)
		(duplicate_pad_numbers_are_jumpers no)
		(pad "1" thru_hole circle
			(at 0 0)
			(size 6.5024 6.5024)
			(drill 3.2004)
			(layers "*.Cu" "*.Mask")
			(remove_unused_layers no)
			(net "GND")
			(clearance -1.397)
		)
	)
	(footprint ""
		(layer "F.Cu")
		(at 106.596942 -116.611654 180)
		(property "Reference" "PR6868"
			(at 0 0 180)
			(layer "F.SilkS")
			(hide yes)
			(effects
				(font
					(size 1.27 1.27)
				)
			)
		)
		(property "Value" ""
			(at 0 0 180)
			(layer "F.Fab")
			(effects
				(font
					(size 1.27 1.27)
				)
			)
		)
		(duplicate_pad_numbers_are_jumpers no)
		(fp_line
			(start 0.7874 0.4064)
			(end -0.7874 0.4064)
			(stroke
				(width 0.1524)
				(type default)
			)
			(layer "F.SilkS")
		)
		(fp_line
			(start 0.7874 -0.4064)
			(end 0.7874 0.4064)
			(stroke
				(width 0.1524)
				(type default)
			)
			(layer "F.SilkS")
		)
		(fp_line
			(start -0.7874 0.4064)
			(end -0.7874 -0.4064)
			(stroke
				(width 0.1524)
				(type default)
			)
			(layer "F.SilkS")
		)
		(fp_line
			(start -0.7874 -0.4064)
			(end 0.7874 -0.4064)
			(stroke
				(width 0.1524)
				(type default)
			)
			(layer "F.SilkS")
		)
		(fp_line
			(start 0.67945 0.3048)
			(end 0.120396 0.3048)
			(stroke
				(width 0.1)
				(type default)
			)
			(layer "F.Fab")
		)
		(fp_line
			(start 0.67945 -0.3048)
			(end 0.67945 0.3048)
			(stroke
				(width 0.1)
				(type default)
			)
			(layer "F.Fab")
		)
		(fp_line
			(start 0.12065 -0.2794)
			(end 0.12065 -0.3048)
			(stroke
				(width 0.1)
				(type default)
			)
			(layer "F.Fab")
		)
		(fp_line
			(start 0.12065 -0.3048)
			(end 0.67945 -0.3048)
			(stroke
				(width 0.1)
				(type default)
			)
			(layer "F.Fab")
		)
		(fp_line
			(start 0.120396 0.3048)
			(end 0.120396 0.2794)
			(stroke
				(width 0.1)
				(type default)
			)
			(layer "F.Fab")
		)
		(fp_line
			(start 0.120396 0.2794)
			(end -0.12065 0.2794)
			(stroke
				(width 0.1)
				(type default)
			)
			(layer "F.Fab")
		)
		(fp_line
			(start -0.12065 0.3048)
			(end -0.67945 0.3048)
			(stroke
				(width 0.1)
				(type default)
			)
			(layer "F.Fab")
		)
		(fp_line
			(start -0.12065 0.2794)
			(end -0.12065 0.3048)
			(stroke
				(width 0.1)
				(type default)
			)
			(layer "F.Fab")
		)
		(fp_line
			(start -0.12065 -0.2794)
			(end 0.12065 -0.2794)
			(stroke
				(width 0.1)
				(type default)
			)
			(layer "F.Fab")
		)
		(fp_line
			(start -0.12065 -0.305054)
			(end -0.12065 -0.2794)
			(stroke
				(width 0.1)
				(type default)
			)
			(layer "F.Fab")
		)
		(fp_line
			(start -0.67945 0.3048)
			(end -0.67945 -0.305054)
			(stroke
				(width 0.1)
				(type default)
			)
			(layer "F.Fab")
		)
		(fp_line
			(start -0.67945 -0.305054)
			(end -0.12065 -0.305054)
			(stroke
				(width 0.1)
				(type default)
			)
			(layer "F.Fab")
		)
		(pad "1" smd circle
			(at -0.40005 0 180)
			(size 0 0)
			(layers "F.Cu" "F.Mask" "F.Paste")
			(net "P12V_NIC1_CO_OV_FB")
		)
		(pad "2" smd circle
			(at 0.40005 0 180)
			(size 0 0)
			(layers "F.Cu" "F.Mask" "F.Paste")
			(net "P12V_AUX")
		)
	)
	(footprint ""
		(layer "F.Cu")
		(at 327.992232 -29.139642 180)
		(property "Reference" "C517"
			(at 0 0 180)
			(layer "F.SilkS")
			(hide yes)
			(effects
				(font
					(size 1.27 1.27)
				)
			)
		)
		(property "Value" ""
			(at 0 0 180)
			(layer "F.Fab")
			(effects
				(font
					(size 1.27 1.27)
				)
			)
		)
		(duplicate_pad_numbers_are_jumpers no)
		(fp_line
			(start 0.299974 0.150114)
			(end -0.299974 0.150114)
			(stroke
				(width 0.1)
				(type default)
			)
			(layer "F.Fab")
		)
		(fp_line
			(start 0.299974 -0.150114)
			(end 0.299974 0.150114)
			(stroke
				(width 0.1)
				(type default)
			)
			(layer "F.Fab")
		)
		(fp_line
			(start -0.299974 0.150114)
			(end -0.299974 -0.150114)
			(stroke
				(width 0.1)
				(type default)
			)
			(layer "F.Fab")
		)
		(fp_line
			(start -0.299974 -0.150114)
			(end 0.299974 -0.150114)
			(stroke
				(width 0.1)
				(type default)
			)
			(layer "F.Fab")
		)
		(pad "1" smd rect
			(at -0.2667 0 180)
			(size 0.3048 0.381)
			(layers "F.Cu" "F.Mask" "F.Paste")
			(net "P5E_PEX2_STN2_TX_DP<32>")
		)
		(pad "2" smd rect
			(at 0.2667 0 180)
			(size 0.3048 0.381)
			(layers "F.Cu" "F.Mask" "F.Paste")
			(net "P5E_PEX2_STN2_TX_C_DP<32>")
		)
	)
	(footprint ""
		(layer "F.Cu")
		(at 196.956172 -32.848042 -90)
		(property "Reference" "R6067"
			(at 0 0 270)
			(layer "F.SilkS")
			(hide yes)
			(effects
				(font
					(size 1.27 1.27)
				)
			)
		)
		(property "Value" ""
			(at 0 0 270)
			(layer "F.Fab")
			(effects
				(font
					(size 1.27 1.27)
				)
			)
		)
		(duplicate_pad_numbers_are_jumpers no)
		(fp_line
			(start -0.7874 0.4064)
			(end -0.7874 -0.4064)
			(stroke
				(width 0.1524)
				(type default)
			)
			(layer "F.SilkS")
		)
		(fp_line
			(start 0.7874 0.4064)
			(end -0.7874 0.4064)
			(stroke
				(width 0.1524)
				(type default)
			)
			(layer "F.SilkS")
		)
		(fp_line
			(start -0.7874 -0.4064)
			(end 0.7874 -0.4064)
			(stroke
				(width 0.1524)
				(type default)
			)
			(layer "F.SilkS")
		)
		(fp_line
			(start 0.7874 -0.4064)
			(end 0.7874 0.4064)
			(stroke
				(width 0.1524)
				(type default)
			)
			(layer "F.SilkS")
		)
		(fp_line
			(start -0.67945 0.3048)
			(end -0.67945 -0.305054)
			(stroke
				(width 0.1)
				(type default)
			)
			(layer "F.Fab")
		)
		(fp_line
			(start -0.12065 0.3048)
			(end -0.67945 0.3048)
			(stroke
				(width 0.1)
				(type default)
			)
			(layer "F.Fab")
		)
		(fp_line
			(start 0.120396 0.3048)
			(end 0.120396 0.2794)
			(stroke
				(width 0.1)
				(type default)
			)
			(layer "F.Fab")
		)
		(fp_line
			(start 0.67945 0.3048)
			(end 0.120396 0.3048)
			(stroke
				(width 0.1)
				(type default)
			)
			(layer "F.Fab")
		)
		(fp_line
			(start -0.12065 0.2794)
			(end -0.12065 0.3048)
			(stroke
				(width 0.1)
				(type default)
			)
			(layer "F.Fab")
		)
		(fp_line
			(start 0.120396 0.2794)
			(end -0.12065 0.2794)
			(stroke
				(width 0.1)
				(type default)
			)
			(layer "F.Fab")
		)
		(fp_line
			(start -0.12065 -0.2794)
			(end 0.12065 -0.2794)
			(stroke
				(width 0.1)
				(type default)
			)
			(layer "F.Fab")
		)
		(fp_line
			(start 0.12065 -0.2794)
			(end 0.12065 -0.3048)
			(stroke
				(width 0.1)
				(type default)
			)
			(layer "F.Fab")
		)
		(fp_line
			(start 0.12065 -0.3048)
			(end 0.67945 -0.3048)
			(stroke
				(width 0.1)
				(type default)
			)
			(layer "F.Fab")
		)
		(fp_line
			(start 0.67945 -0.3048)
			(end 0.67945 0.3048)
			(stroke
				(width 0.1)
				(type default)
			)
			(layer "F.Fab")
		)
		(fp_line
			(start -0.67945 -0.305054)
			(end -0.12065 -0.305054)
			(stroke
				(width 0.1)
				(type default)
			)
			(layer "F.Fab")
		)
		(fp_line
			(start -0.12065 -0.305054)
			(end -0.12065 -0.2794)
			(stroke
				(width 0.1)
				(type default)
			)
			(layer "F.Fab")
		)
		(pad "1" smd circle
			(at -0.40005 0 270)
			(size 0 0)
			(layers "F.Cu" "F.Mask" "F.Paste")
			(net "SSD7_AUX_P3V3_EN_R")
		)
		(pad "2" smd circle
			(at 0.40005 0 270)
			(size 0 0)
			(layers "F.Cu" "F.Mask" "F.Paste")
			(net "P3V3_SSD7_CO_EN")
		)
	)
	(footprint ""
		(layer "F.Cu")
		(at 283.264356 -29.079952 180)
		(property "Reference" "R6207"
			(at 0 0 180)
			(layer "F.SilkS")
			(hide yes)
			(effects
				(font
					(size 1.27 1.27)
				)
			)
		)
		(property "Value" ""
			(at 0 0 180)
			(layer "F.Fab")
			(effects
				(font
					(size 1.27 1.27)
				)
			)
		)
		(duplicate_pad_numbers_are_jumpers no)
		(fp_line
			(start 0.7874 0.4064)
			(end -0.7874 0.4064)
			(stroke
				(width 0.1524)
				(type default)
			)
			(layer "F.SilkS")
		)
		(fp_line
			(start 0.7874 -0.4064)
			(end 0.7874 0.4064)
			(stroke
				(width 0.1524)
				(type default)
			)
			(layer "F.SilkS")
		)
		(fp_line
			(start -0.7874 0.4064)
			(end -0.7874 -0.4064)
			(stroke
				(width 0.1524)
				(type default)
			)
			(layer "F.SilkS")
		)
		(fp_line
			(start -0.7874 -0.4064)
			(end 0.7874 -0.4064)
			(stroke
				(width 0.1524)
				(type default)
			)
			(layer "F.SilkS")
		)
		(fp_line
			(start 0.67945 0.3048)
			(end 0.120396 0.3048)
			(stroke
				(width 0.1)
				(type default)
			)
			(layer "F.Fab")
		)
		(fp_line
			(start 0.67945 -0.3048)
			(end 0.67945 0.3048)
			(stroke
				(width 0.1)
				(type default)
			)
			(layer "F.Fab")
		)
		(fp_line
			(start 0.12065 -0.2794)
			(end 0.12065 -0.3048)
			(stroke
				(width 0.1)
				(type default)
			)
			(layer "F.Fab")
		)
		(fp_line
			(start 0.12065 -0.3048)
			(end 0.67945 -0.3048)
			(stroke
				(width 0.1)
				(type default)
			)
			(layer "F.Fab")
		)
		(fp_line
			(start 0.120396 0.3048)
			(end 0.120396 0.2794)
			(stroke
				(width 0.1)
				(type default)
			)
			(layer "F.Fab")
		)
		(fp_line
			(start 0.120396 0.2794)
			(end -0.12065 0.2794)
			(stroke
				(width 0.1)
				(type default)
			)
			(layer "F.Fab")
		)
		(fp_line
			(start -0.12065 0.3048)
			(end -0.67945 0.3048)
			(stroke
				(width 0.1)
				(type default)
			)
			(layer "F.Fab")
		)
		(fp_line
			(start -0.12065 0.2794)
			(end -0.12065 0.3048)
			(stroke
				(width 0.1)
				(type default)
			)
			(layer "F.Fab")
		)
		(fp_line
			(start -0.12065 -0.2794)
			(end 0.12065 -0.2794)
			(stroke
				(width 0.1)
				(type default)
			)
			(layer "F.Fab")
		)
		(fp_line
			(start -0.12065 -0.305054)
			(end -0.12065 -0.2794)
			(stroke
				(width 0.1)
				(type default)
			)
			(layer "F.Fab")
		)
		(fp_line
			(start -0.67945 0.3048)
			(end -0.67945 -0.305054)
			(stroke
				(width 0.1)
				(type default)
			)
			(layer "F.Fab")
		)
		(fp_line
			(start -0.67945 -0.305054)
			(end -0.12065 -0.305054)
			(stroke
				(width 0.1)
				(type default)
			)
			(layer "F.Fab")
		)
		(pad "1" smd circle
			(at -0.40005 0 180)
			(size 0 0)
			(layers "F.Cu" "F.Mask" "F.Paste")
			(net "GND")
		)
		(pad "2" smd circle
			(at 0.40005 0 180)
			(size 0 0)
			(layers "F.Cu" "F.Mask" "F.Paste")
			(net "SSD9_PWRDIS_R")
		)
	)
	(footprint ""
		(layer "F.Cu")
		(at 110.35538 -35.876738)
		(property "Reference" "R6056"
			(at 0 0 0)
			(layer "F.SilkS")
			(hide yes)
			(effects
				(font
					(size 1.27 1.27)
				)
			)
		)
		(property "Value" ""
			(at 0 0 0)
			(layer "F.Fab")
			(effects
				(font
					(size 1.27 1.27)
				)
			)
		)
		(duplicate_pad_numbers_are_jumpers no)
		(fp_line
			(start -0.7874 -0.4064)
			(end 0.7874 -0.4064)
			(stroke
				(width 0.1524)
				(type default)
			)
			(layer "F.SilkS")
		)
		(fp_line
			(start -0.7874 0.4064)
			(end -0.7874 -0.4064)
			(stroke
				(width 0.1524)
				(type default)
			)
			(layer "F.SilkS")
		)
		(fp_line
			(start 0.7874 -0.4064)
			(end 0.7874 0.4064)
			(stroke
				(width 0.1524)
				(type default)
			)
			(layer "F.SilkS")
		)
		(fp_line
			(start 0.7874 0.4064)
			(end -0.7874 0.4064)
			(stroke
				(width 0.1524)
				(type default)
			)
			(layer "F.SilkS")
		)
		(fp_line
			(start -0.67945 -0.305054)
			(end -0.12065 -0.305054)
			(stroke
				(width 0.1)
				(type default)
			)
			(layer "F.Fab")
		)
		(fp_line
			(start -0.67945 0.3048)
			(end -0.67945 -0.305054)
			(stroke
				(width 0.1)
				(type default)
			)
			(layer "F.Fab")
		)
		(fp_line
			(start -0.12065 -0.305054)
			(end -0.12065 -0.2794)
			(stroke
				(width 0.1)
				(type default)
			)
			(layer "F.Fab")
		)
		(fp_line
			(start -0.12065 -0.2794)
			(end 0.12065 -0.2794)
			(stroke
				(width 0.1)
				(type default)
			)
			(layer "F.Fab")
		)
		(fp_line
			(start -0.12065 0.2794)
			(end -0.12065 0.3048)
			(stroke
				(width 0.1)
				(type default)
			)
			(layer "F.Fab")
		)
		(fp_line
			(start -0.12065 0.3048)
			(end -0.67945 0.3048)
			(stroke
				(width 0.1)
				(type default)
			)
			(layer "F.Fab")
		)
		(fp_line
			(start 0.120396 0.2794)
			(end -0.12065 0.2794)
			(stroke
				(width 0.1)
				(type default)
			)
			(layer "F.Fab")
		)
		(fp_line
			(start 0.120396 0.3048)
			(end 0.120396 0.2794)
			(stroke
				(width 0.1)
				(type default)
			)
			(layer "F.Fab")
		)
		(fp_line
			(start 0.12065 -0.3048)
			(end 0.67945 -0.3048)
			(stroke
				(width 0.1)
				(type default)
			)
			(layer "F.Fab")
		)
		(fp_line
			(start 0.12065 -0.2794)
			(end 0.12065 -0.3048)
			(stroke
				(width 0.1)
				(type default)
			)
			(layer "F.Fab")
		)
		(fp_line
			(start 0.67945 -0.3048)
			(end 0.67945 0.3048)
			(stroke
				(width 0.1)
				(type default)
			)
			(layer "F.Fab")
		)
		(fp_line
			(start 0.67945 0.3048)
			(end 0.120396 0.3048)
			(stroke
				(width 0.1)
				(type default)
			)
			(layer "F.Fab")
		)
		(pad "1" smd circle
			(at -0.40005 0)
			(size 0 0)
			(layers "F.Cu" "F.Mask" "F.Paste")
			(net "P3V3_AUX")
		)
		(pad "2" smd circle
			(at 0.40005 0)
			(size 0 0)
			(layers "F.Cu" "F.Mask" "F.Paste")
			(net "PWRGD_P3V3_SSD4_D")
		)
	)
	(footprint ""
		(layer "F.Cu")
		(at 396.03426 -343.952322 90)
		(property "Reference" "C738"
			(at 0 0 90)
			(layer "F.SilkS")
			(hide yes)
			(effects
				(font
					(size 1.27 1.27)
				)
			)
		)
		(property "Value" ""
			(at 0 0 90)
			(layer "F.Fab")
			(effects
				(font
					(size 1.27 1.27)
				)
			)
		)
		(duplicate_pad_numbers_are_jumpers no)
		(fp_line
			(start 0.299974 -0.150114)
			(end 0.299974 0.150114)
			(stroke
				(width 0.1)
				(type default)
			)
			(layer "F.Fab")
		)
		(fp_line
			(start -0.299974 -0.150114)
			(end 0.299974 -0.150114)
			(stroke
				(width 0.1)
				(type default)
			)
			(layer "F.Fab")
		)
		(fp_line
			(start 0.299974 0.150114)
			(end -0.299974 0.150114)
			(stroke
				(width 0.1)
				(type default)
			)
			(layer "F.Fab")
		)
		(fp_line
			(start -0.299974 0.150114)
			(end -0.299974 -0.150114)
			(stroke
				(width 0.1)
				(type default)
			)
			(layer "F.Fab")
		)
		(pad "1" smd rect
			(at -0.2667 0 90)
			(size 0.3048 0.381)
			(layers "F.Cu" "F.Mask" "F.Paste")
			(net "P5E_PEX3_STN5_TX_DP<91>")
		)
		(pad "2" smd rect
			(at 0.2667 0 90)
			(size 0.3048 0.381)
			(layers "F.Cu" "F.Mask" "F.Paste")
			(net "P5E_PEX3_STN5_TX_C_DP<91>")
		)
	)
	(footprint ""
		(layer "F.Cu")
		(at 124.733812 -156.288994 -90)
		(property "Reference" "PR6894"
			(at 0 0 270)
			(layer "F.SilkS")
			(hide yes)
			(effects
				(font
					(size 1.27 1.27)
				)
			)
		)
		(property "Value" ""
			(at 0 0 270)
			(layer "F.Fab")
			(effects
				(font
					(size 1.27 1.27)
				)
			)
		)
		(duplicate_pad_numbers_are_jumpers no)
		(fp_line
			(start -0.7874 0.4064)
			(end -0.7874 -0.4064)
			(stroke
				(width 0.1524)
				(type default)
			)
			(layer "F.SilkS")
		)
		(fp_line
			(start 0.7874 0.4064)
			(end -0.7874 0.4064)
			(stroke
				(width 0.1524)
				(type default)
			)
			(layer "F.SilkS")
		)
		(fp_line
			(start -0.7874 -0.4064)
			(end 0.7874 -0.4064)
			(stroke
				(width 0.1524)
				(type default)
			)
			(layer "F.SilkS")
		)
		(fp_line
			(start 0.7874 -0.4064)
			(end 0.7874 0.4064)
			(stroke
				(width 0.1524)
				(type default)
			)
			(layer "F.SilkS")
		)
		(fp_line
			(start -0.67945 0.3048)
			(end -0.67945 -0.305054)
			(stroke
				(width 0.1)
				(type default)
			)
			(layer "F.Fab")
		)
		(fp_line
			(start -0.12065 0.3048)
			(end -0.67945 0.3048)
			(stroke
				(width 0.1)
				(type default)
			)
			(layer "F.Fab")
		)
		(fp_line
			(start 0.120396 0.3048)
			(end 0.120396 0.2794)
			(stroke
				(width 0.1)
				(type default)
			)
			(layer "F.Fab")
		)
		(fp_line
			(start 0.67945 0.3048)
			(end 0.120396 0.3048)
			(stroke
				(width 0.1)
				(type default)
			)
			(layer "F.Fab")
		)
		(fp_line
			(start -0.12065 0.2794)
			(end -0.12065 0.3048)
			(stroke
				(width 0.1)
				(type default)
			)
			(layer "F.Fab")
		)
		(fp_line
			(start 0.120396 0.2794)
			(end -0.12065 0.2794)
			(stroke
				(width 0.1)
				(type default)
			)
			(layer "F.Fab")
		)
		(fp_line
			(start -0.12065 -0.2794)
			(end 0.12065 -0.2794)
			(stroke
				(width 0.1)
				(type default)
			)
			(layer "F.Fab")
		)
		(fp_line
			(start 0.12065 -0.2794)
			(end 0.12065 -0.3048)
			(stroke
				(width 0.1)
				(type default)
			)
			(layer "F.Fab")
		)
		(fp_line
			(start 0.12065 -0.3048)
			(end 0.67945 -0.3048)
			(stroke
				(width 0.1)
				(type default)
			)
			(layer "F.Fab")
		)
		(fp_line
			(start 0.67945 -0.3048)
			(end 0.67945 0.3048)
			(stroke
				(width 0.1)
				(type default)
			)
			(layer "F.Fab")
		)
		(fp_line
			(start -0.67945 -0.305054)
			(end -0.12065 -0.305054)
			(stroke
				(width 0.1)
				(type default)
			)
			(layer "F.Fab")
		)
		(fp_line
			(start -0.12065 -0.305054)
			(end -0.12065 -0.2794)
			(stroke
				(width 0.1)
				(type default)
			)
			(layer "F.Fab")
		)
		(pad "1" smd circle
			(at -0.40005 0 270)
			(size 0 0)
			(layers "F.Cu" "F.Mask" "F.Paste")
			(net "P12V_NIC2_CO_OV_FB")
		)
		(pad "2" smd circle
			(at 0.40005 0 270)
			(size 0 0)
			(layers "F.Cu" "F.Mask" "F.Paste")
			(net "GND")
		)
	)
	(footprint ""
		(layer "F.Cu")
		(at 434.410358 -63.652146 180)
		(property "Reference" "R6027"
			(at 0 0 180)
			(layer "F.SilkS")
			(hide yes)
			(effects
				(font
					(size 1.27 1.27)
				)
			)
		)
		(property "Value" ""
			(at 0 0 180)
			(layer "F.Fab")
			(effects
				(font
					(size 1.27 1.27)
				)
			)
		)
		(duplicate_pad_numbers_are_jumpers no)
		(fp_line
			(start 0.7874 0.4064)
			(end -0.7874 0.4064)
			(stroke
				(width 0.1524)
				(type default)
			)
			(layer "F.SilkS")
		)
		(fp_line
			(start 0.7874 -0.4064)
			(end 0.7874 0.4064)
			(stroke
				(width 0.1524)
				(type default)
			)
			(layer "F.SilkS")
		)
		(fp_line
			(start -0.7874 0.4064)
			(end -0.7874 -0.4064)
			(stroke
				(width 0.1524)
				(type default)
			)
			(layer "F.SilkS")
		)
		(fp_line
			(start -0.7874 -0.4064)
			(end 0.7874 -0.4064)
			(stroke
				(width 0.1524)
				(type default)
			)
			(layer "F.SilkS")
		)
		(fp_line
			(start 0.67945 0.3048)
			(end 0.120396 0.3048)
			(stroke
				(width 0.1)
				(type default)
			)
			(layer "F.Fab")
		)
		(fp_line
			(start 0.67945 -0.3048)
			(end 0.67945 0.3048)
			(stroke
				(width 0.1)
				(type default)
			)
			(layer "F.Fab")
		)
		(fp_line
			(start 0.12065 -0.2794)
			(end 0.12065 -0.3048)
			(stroke
				(width 0.1)
				(type default)
			)
			(layer "F.Fab")
		)
		(fp_line
			(start 0.12065 -0.3048)
			(end 0.67945 -0.3048)
			(stroke
				(width 0.1)
				(type default)
			)
			(layer "F.Fab")
		)
		(fp_line
			(start 0.120396 0.3048)
			(end 0.120396 0.2794)
			(stroke
				(width 0.1)
				(type default)
			)
			(layer "F.Fab")
		)
		(fp_line
			(start 0.120396 0.2794)
			(end -0.12065 0.2794)
			(stroke
				(width 0.1)
				(type default)
			)
			(layer "F.Fab")
		)
		(fp_line
			(start -0.12065 0.3048)
			(end -0.67945 0.3048)
			(stroke
				(width 0.1)
				(type default)
			)
			(layer "F.Fab")
		)
		(fp_line
			(start -0.12065 0.2794)
			(end -0.12065 0.3048)
			(stroke
				(width 0.1)
				(type default)
			)
			(layer "F.Fab")
		)
		(fp_line
			(start -0.12065 -0.2794)
			(end 0.12065 -0.2794)
			(stroke
				(width 0.1)
				(type default)
			)
			(layer "F.Fab")
		)
		(fp_line
			(start -0.12065 -0.305054)
			(end -0.12065 -0.2794)
			(stroke
				(width 0.1)
				(type default)
			)
			(layer "F.Fab")
		)
		(fp_line
			(start -0.67945 0.3048)
			(end -0.67945 -0.305054)
			(stroke
				(width 0.1)
				(type default)
			)
			(layer "F.Fab")
		)
		(fp_line
			(start -0.67945 -0.305054)
			(end -0.12065 -0.305054)
			(stroke
				(width 0.1)
				(type default)
			)
			(layer "F.Fab")
		)
		(pad "1" smd circle
			(at -0.40005 0 180)
			(size 0 0)
			(layers "F.Cu" "F.Mask" "F.Paste")
			(net "P5V_AUX")
		)
		(pad "2" smd circle
			(at 0.40005 0 180)
			(size 0 0)
			(layers "F.Cu" "F.Mask" "F.Paste")
			(net "P12V_SSD15_PG_G2")
		)
	)
	(footprint ""
		(layer "F.Cu")
		(at 393.558014 -72.766682 90)
		(property "Reference" "PC885"
			(at 0 0 90)
			(layer "F.SilkS")
			(hide yes)
			(effects
				(font
					(size 1.27 1.27)
				)
			)
		)
		(property "Value" ""
			(at 0 0 90)
			(layer "F.Fab")
			(effects
				(font
					(size 1.27 1.27)
				)
			)
		)
		(duplicate_pad_numbers_are_jumpers no)
		(fp_line
			(start 0.7874 -0.4064)
			(end 0.7874 0.4064)
			(stroke
				(width 0.1524)
				(type default)
			)
			(layer "F.SilkS")
		)
		(fp_line
			(start -0.7874 -0.4064)
			(end 0.7874 -0.4064)
			(stroke
				(width 0.1524)
				(type default)
			)
			(layer "F.SilkS")
		)
		(fp_line
			(start 0.7874 0.4064)
			(end -0.7874 0.4064)
			(stroke
				(width 0.1524)
				(type default)
			)
			(layer "F.SilkS")
		)
		(fp_line
			(start -0.7874 0.4064)
			(end -0.7874 -0.4064)
			(stroke
				(width 0.1524)
				(type default)
			)
			(layer "F.SilkS")
		)
		(fp_line
			(start -0.12065 -0.305054)
			(end -0.12065 -0.2794)
			(stroke
				(width 0.1)
				(type default)
			)
			(layer "F.Fab")
		)
		(fp_line
			(start -0.67945 -0.305054)
			(end -0.12065 -0.305054)
			(stroke
				(width 0.1)
				(type default)
			)
			(layer "F.Fab")
		)
		(fp_line
			(start 0.67945 -0.3048)
			(end 0.67945 0.3048)
			(stroke
				(width 0.1)
				(type default)
			)
			(layer "F.Fab")
		)
		(fp_line
			(start 0.12065 -0.3048)
			(end 0.67945 -0.3048)
			(stroke
				(width 0.1)
				(type default)
			)
			(layer "F.Fab")
		)
		(fp_line
			(start 0.12065 -0.2794)
			(end 0.12065 -0.3048)
			(stroke
				(width 0.1)
				(type default)
			)
			(layer "F.Fab")
		)
		(fp_line
			(start -0.12065 -0.2794)
			(end 0.12065 -0.2794)
			(stroke
				(width 0.1)
				(type default)
			)
			(layer "F.Fab")
		)
		(fp_line
			(start 0.120396 0.2794)
			(end -0.12065 0.2794)
			(stroke
				(width 0.1)
				(type default)
			)
			(layer "F.Fab")
		)
		(fp_line
			(start -0.12065 0.2794)
			(end -0.12065 0.3048)
			(stroke
				(width 0.1)
				(type default)
			)
			(layer "F.Fab")
		)
		(fp_line
			(start 0.67945 0.3048)
			(end 0.120396 0.3048)
			(stroke
				(width 0.1)
				(type default)
			)
			(layer "F.Fab")
		)
		(fp_line
			(start 0.120396 0.3048)
			(end 0.120396 0.2794)
			(stroke
				(width 0.1)
				(type default)
			)
			(layer "F.Fab")
		)
		(fp_line
			(start -0.12065 0.3048)
			(end -0.67945 0.3048)
			(stroke
				(width 0.1)
				(type default)
			)
			(layer "F.Fab")
		)
		(fp_line
			(start -0.67945 0.3048)
			(end -0.67945 -0.305054)
			(stroke
				(width 0.1)
				(type default)
			)
			(layer "F.Fab")
		)
		(pad "1" smd circle
			(at -0.40005 0 90)
			(size 0 0)
			(layers "F.Cu" "F.Mask" "F.Paste")
			(net "P12V_SSD13_CO_MODE")
		)
		(pad "2" smd circle
			(at 0.40005 0 90)
			(size 0 0)
			(layers "F.Cu" "F.Mask" "F.Paste")
			(net "GND")
		)
	)
	(footprint ""
		(layer "F.Cu")
		(at 115.600226 -118.061486 180)
		(property "Reference" "PC597"
			(at 0 0 180)
			(layer "F.SilkS")
			(hide yes)
			(effects
				(font
					(size 1.27 1.27)
				)
			)
		)
		(property "Value" ""
			(at 0 0 180)
			(layer "F.Fab")
			(effects
				(font
					(size 1.27 1.27)
				)
			)
		)
		(duplicate_pad_numbers_are_jumpers no)
		(fp_line
			(start 0.7874 0.4064)
			(end -0.7874 0.4064)
			(stroke
				(width 0.1524)
				(type default)
			)
			(layer "F.SilkS")
		)
		(fp_line
			(start 0.7874 -0.4064)
			(end 0.7874 0.4064)
			(stroke
				(width 0.1524)
				(type default)
			)
			(layer "F.SilkS")
		)
		(fp_line
			(start -0.7874 0.4064)
			(end -0.7874 -0.4064)
			(stroke
				(width 0.1524)
				(type default)
			)
			(layer "F.SilkS")
		)
		(fp_line
			(start -0.7874 -0.4064)
			(end 0.7874 -0.4064)
			(stroke
				(width 0.1524)
				(type default)
			)
			(layer "F.SilkS")
		)
		(fp_line
			(start 0.67945 0.3048)
			(end 0.120396 0.3048)
			(stroke
				(width 0.1)
				(type default)
			)
			(layer "F.Fab")
		)
		(fp_line
			(start 0.67945 -0.3048)
			(end 0.67945 0.3048)
			(stroke
				(width 0.1)
				(type default)
			)
			(layer "F.Fab")
		)
		(fp_line
			(start 0.12065 -0.2794)
			(end 0.12065 -0.3048)
			(stroke
				(width 0.1)
				(type default)
			)
			(layer "F.Fab")
		)
		(fp_line
			(start 0.12065 -0.3048)
			(end 0.67945 -0.3048)
			(stroke
				(width 0.1)
				(type default)
			)
			(layer "F.Fab")
		)
		(fp_line
			(start 0.120396 0.3048)
			(end 0.120396 0.2794)
			(stroke
				(width 0.1)
				(type default)
			)
			(layer "F.Fab")
		)
		(fp_line
			(start 0.120396 0.2794)
			(end -0.12065 0.2794)
			(stroke
				(width 0.1)
				(type default)
			)
			(layer "F.Fab")
		)
		(fp_line
			(start -0.12065 0.3048)
			(end -0.67945 0.3048)
			(stroke
				(width 0.1)
				(type default)
			)
			(layer "F.Fab")
		)
		(fp_line
			(start -0.12065 0.2794)
			(end -0.12065 0.3048)
			(stroke
				(width 0.1)
				(type default)
			)
			(layer "F.Fab")
		)
		(fp_line
			(start -0.12065 -0.2794)
			(end 0.12065 -0.2794)
			(stroke
				(width 0.1)
				(type default)
			)
			(layer "F.Fab")
		)
		(fp_line
			(start -0.12065 -0.305054)
			(end -0.12065 -0.2794)
			(stroke
				(width 0.1)
				(type default)
			)
			(layer "F.Fab")
		)
		(fp_line
			(start -0.67945 0.3048)
			(end -0.67945 -0.305054)
			(stroke
				(width 0.1)
				(type default)
			)
			(layer "F.Fab")
		)
		(fp_line
			(start -0.67945 -0.305054)
			(end -0.12065 -0.305054)
			(stroke
				(width 0.1)
				(type default)
			)
			(layer "F.Fab")
		)
		(pad "1" smd circle
			(at -0.40005 0 180)
			(size 0 0)
			(layers "F.Cu" "F.Mask" "F.Paste")
			(net "P3V3_CO_DV_DT")
		)
		(pad "2" smd circle
			(at 0.40005 0 180)
			(size 0 0)
			(layers "F.Cu" "F.Mask" "F.Paste")
			(net "GND")
		)
	)
	(footprint ""
		(layer "F.Cu")
		(at 118.882668 -29.875734)
		(property "Reference" "PU123"
			(at -3.226054 -0.215646 90)
			(unlocked yes)
			(layer "F.SilkS")
			(effects
				(font
					(size 0.7874 0.5842)
					(thickness 0.1524)
				)
			)
		)
		(property "Value" ""
			(at 0 0 0)
			(layer "F.Fab")
			(effects
				(font
					(size 1.27 1.27)
				)
			)
		)
		(duplicate_pad_numbers_are_jumpers no)
		(fp_line
			(start -1.239774 -1.495298)
			(end 1.239774 -1.495298)
			(stroke
				(width 0.1524)
				(type default)
			)
			(layer "F.SilkS")
		)
		(fp_line
			(start -1.239774 1.495298)
			(end -1.239774 -1.495298)
			(stroke
				(width 0.1524)
				(type default)
			)
			(layer "F.SilkS")
		)
		(fp_line
			(start 1.239774 -1.495298)
			(end 1.239774 1.495298)
			(stroke
				(width 0.1524)
				(type default)
			)
			(layer "F.SilkS")
		)
		(fp_line
			(start 1.239774 1.495298)
			(end -1.239774 1.495298)
			(stroke
				(width 0.1524)
				(type default)
			)
			(layer "F.SilkS")
		)
		(fp_poly
			(pts
				(xy -2.141474 -1.380744) (xy -2.859786 -0.662432) (xy -1.782064 -0.303276)
			)
			(stroke
				(width 0)
				(type default)
			)
			(fill yes)
			(layer "F.SilkS")
		)
		(fp_line
			(start -0.8001 -1.050036)
			(end 0.8001 -1.050036)
			(stroke
				(width 0.1)
				(type default)
			)
			(layer "F.Fab")
		)
		(fp_line
			(start -0.8001 1.050036)
			(end -0.8001 -1.050036)
			(stroke
				(width 0.1)
				(type default)
			)
			(layer "F.Fab")
		)
		(fp_line
			(start 0.8001 -1.050036)
			(end 0.8001 1.050036)
			(stroke
				(width 0.1)
				(type default)
			)
			(layer "F.Fab")
		)
		(fp_line
			(start 0.8001 1.050036)
			(end -0.8001 1.050036)
			(stroke
				(width 0.1)
				(type default)
			)
			(layer "F.Fab")
		)
		(fp_poly
			(pts
				(xy -2.458974 -0.508) (xy -2.458974 0.508) (xy -1.442974 0)
			)
			(stroke
				(width 0)
				(type default)
			)
			(fill yes)
			(layer "F.Fab")
		)
		(pad "1_2" smd circle
			(at -0.374904 0 90)
			(size 0 0)
			(layers "F.Cu" "F.Mask" "F.Paste")
			(net "P3V3_AUX")
		)
		(pad "3" smd rect
			(at -0.499872 0.999998)
			(size 0.254 0.7112)
			(layers "F.Cu" "F.Mask" "F.Paste")
			(net "GND")
		)
		(pad "4" smd rect
			(at 0 0.999998)
			(size 0.254 0.7112)
			(layers "F.Cu" "F.Mask" "F.Paste")
			(net "P3V3_SSD4_CO_ILIMIT")
		)
		(pad "5" smd rect
			(at 0.499872 0.999998)
			(size 0.254 0.7112)
			(layers "F.Cu" "F.Mask" "F.Paste")
			(net "P3V3_SSD4_CO_MODE")
		)
		(pad "6_7" smd circle
			(at 0.374904 0 270)
			(size 0 0)
			(layers "F.Cu" "F.Mask" "F.Paste")
			(net "P3V3_SSD4")
		)
		(pad "8" smd rect
			(at 0.499872 -0.999998)
			(size 0.254 0.7112)
			(layers "F.Cu" "F.Mask" "F.Paste")
			(net "P3V3_SSD4_CO_GATE")
		)
		(pad "9" smd rect
			(at 0 -0.999998)
			(size 0.254 0.7112)
			(layers "F.Cu" "F.Mask" "F.Paste")
			(net "P3V3_SSD4_CO_EN")
		)
		(pad "10" smd rect
			(at -0.499872 -0.999998)
			(size 0.254 0.7112)
			(layers "F.Cu" "F.Mask" "F.Paste")
			(net "P3V3_SSD4_CO_DV_DT")
		)
	)
	(footprint ""
		(layer "F.Cu")
		(at 403.287484 -370.619528 90)
		(property "Reference" "R6680"
			(at 0 0 90)
			(layer "F.SilkS")
			(hide yes)
			(effects
				(font
					(size 1.27 1.27)
				)
			)
		)
		(property "Value" ""
			(at 0 0 90)
			(layer "F.Fab")
			(effects
				(font
					(size 1.27 1.27)
				)
			)
		)
		(duplicate_pad_numbers_are_jumpers no)
		(fp_line
			(start 0.7874 -0.4064)
			(end 0.7874 0.4064)
			(stroke
				(width 0.1524)
				(type default)
			)
			(layer "F.SilkS")
		)
		(fp_line
			(start -0.7874 -0.4064)
			(end 0.7874 -0.4064)
			(stroke
				(width 0.1524)
				(type default)
			)
			(layer "F.SilkS")
		)
		(fp_line
			(start 0.7874 0.4064)
			(end -0.7874 0.4064)
			(stroke
				(width 0.1524)
				(type default)
			)
			(layer "F.SilkS")
		)
		(fp_line
			(start -0.7874 0.4064)
			(end -0.7874 -0.4064)
			(stroke
				(width 0.1524)
				(type default)
			)
			(layer "F.SilkS")
		)
		(fp_line
			(start -0.12065 -0.305054)
			(end -0.12065 -0.2794)
			(stroke
				(width 0.1)
				(type default)
			)
			(layer "F.Fab")
		)
		(fp_line
			(start -0.67945 -0.305054)
			(end -0.12065 -0.305054)
			(stroke
				(width 0.1)
				(type default)
			)
			(layer "F.Fab")
		)
		(fp_line
			(start 0.67945 -0.3048)
			(end 0.67945 0.3048)
			(stroke
				(width 0.1)
				(type default)
			)
			(layer "F.Fab")
		)
		(fp_line
			(start 0.12065 -0.3048)
			(end 0.67945 -0.3048)
			(stroke
				(width 0.1)
				(type default)
			)
			(layer "F.Fab")
		)
		(fp_line
			(start 0.12065 -0.2794)
			(end 0.12065 -0.3048)
			(stroke
				(width 0.1)
				(type default)
			)
			(layer "F.Fab")
		)
		(fp_line
			(start -0.12065 -0.2794)
			(end 0.12065 -0.2794)
			(stroke
				(width 0.1)
				(type default)
			)
			(layer "F.Fab")
		)
		(fp_line
			(start 0.120396 0.2794)
			(end -0.12065 0.2794)
			(stroke
				(width 0.1)
				(type default)
			)
			(layer "F.Fab")
		)
		(fp_line
			(start -0.12065 0.2794)
			(end -0.12065 0.3048)
			(stroke
				(width 0.1)
				(type default)
			)
			(layer "F.Fab")
		)
		(fp_line
			(start 0.67945 0.3048)
			(end 0.120396 0.3048)
			(stroke
				(width 0.1)
				(type default)
			)
			(layer "F.Fab")
		)
		(fp_line
			(start 0.120396 0.3048)
			(end 0.120396 0.2794)
			(stroke
				(width 0.1)
				(type default)
			)
			(layer "F.Fab")
		)
		(fp_line
			(start -0.12065 0.3048)
			(end -0.67945 0.3048)
			(stroke
				(width 0.1)
				(type default)
			)
			(layer "F.Fab")
		)
		(fp_line
			(start -0.67945 0.3048)
			(end -0.67945 -0.305054)
			(stroke
				(width 0.1)
				(type default)
			)
			(layer "F.Fab")
		)
		(pad "1" smd circle
			(at -0.40005 0 90)
			(size 0 0)
			(layers "F.Cu" "F.Mask" "F.Paste")
			(net "GPU_3V3IO_RSVD1_ISO")
		)
		(pad "2" smd circle
			(at 0.40005 0 90)
			(size 0 0)
			(layers "F.Cu" "F.Mask" "F.Paste")
			(net "GPU_3V3IO_RSVD1")
		)
	)
	(footprint ""
		(layer "F.Cu")
		(at 268.838426 -130.408934)
		(property "Reference" "C461"
			(at 0 0 0)
			(layer "F.SilkS")
			(hide yes)
			(effects
				(font
					(size 1.27 1.27)
				)
			)
		)
		(property "Value" ""
			(at 0 0 0)
			(layer "F.Fab")
			(effects
				(font
					(size 1.27 1.27)
				)
			)
		)
		(duplicate_pad_numbers_are_jumpers no)
		(fp_line
			(start -0.299974 -0.150114)
			(end 0.299974 -0.150114)
			(stroke
				(width 0.1)
				(type default)
			)
			(layer "F.Fab")
		)
		(fp_line
			(start -0.299974 0.150114)
			(end -0.299974 -0.150114)
			(stroke
				(width 0.1)
				(type default)
			)
			(layer "F.Fab")
		)
		(fp_line
			(start 0.299974 -0.150114)
			(end 0.299974 0.150114)
			(stroke
				(width 0.1)
				(type default)
			)
			(layer "F.Fab")
		)
		(fp_line
			(start 0.299974 0.150114)
			(end -0.299974 0.150114)
			(stroke
				(width 0.1)
				(type default)
			)
			(layer "F.Fab")
		)
		(pad "1" smd rect
			(at -0.2667 0)
			(size 0.3048 0.381)
			(layers "F.Cu" "F.Mask" "F.Paste")
			(net "P5E_PEX2_STN1_TX_DP<28>")
		)
		(pad "2" smd rect
			(at 0.2667 0)
			(size 0.3048 0.381)
			(layers "F.Cu" "F.Mask" "F.Paste")
			(net "P5E_PEX2_STN1_TX_C_DP<28>")
		)
	)
	(footprint ""
		(layer "F.Cu")
		(at 214.546434 -58.323734)
		(property "Reference" "PC365"
			(at 0 0 0)
			(layer "F.SilkS")
			(hide yes)
			(effects
				(font
					(size 1.27 1.27)
				)
			)
		)
		(property "Value" ""
			(at 0 0 0)
			(layer "F.Fab")
			(effects
				(font
					(size 1.27 1.27)
				)
			)
		)
		(duplicate_pad_numbers_are_jumpers no)
		(fp_line
			(start -1.524 -0.762)
			(end 1.524 -0.762)
			(stroke
				(width 0.1524)
				(type default)
			)
			(layer "F.SilkS")
		)
		(fp_line
			(start -1.524 0.762)
			(end -1.524 -0.762)
			(stroke
				(width 0.1524)
				(type default)
			)
			(layer "F.SilkS")
		)
		(fp_line
			(start 1.524 -0.762)
			(end 1.524 0.762)
			(stroke
				(width 0.1524)
				(type default)
			)
			(layer "F.SilkS")
		)
		(fp_line
			(start 1.524 0.762)
			(end -1.524 0.762)
			(stroke
				(width 0.1524)
				(type default)
			)
			(layer "F.SilkS")
		)
		(fp_line
			(start -1.1049 -0.724916)
			(end -1.1049 0.724916)
			(stroke
				(width 0.1)
				(type default)
			)
			(layer "F.Fab")
		)
		(fp_line
			(start -1.1049 0.724916)
			(end 1.1049 0.724916)
			(stroke
				(width 0.1)
				(type default)
			)
			(layer "F.Fab")
		)
		(fp_line
			(start 1.1049 -0.724916)
			(end -1.1049 -0.724916)
			(stroke
				(width 0.1)
				(type default)
			)
			(layer "F.Fab")
		)
		(fp_line
			(start 1.1049 0.724916)
			(end 1.1049 -0.724916)
			(stroke
				(width 0.1)
				(type default)
			)
			(layer "F.Fab")
		)
		(pad "1" smd rect
			(at -0.889 0 180)
			(size 1.016 1.27)
			(layers "F.Cu" "F.Mask" "F.Paste")
			(net "GND")
		)
		(pad "2" smd rect
			(at 0.889 0 180)
			(size 1.016 1.27)
			(layers "F.Cu" "F.Mask" "F.Paste")
			(net "P12V_AUX")
		)
	)
	(footprint ""
		(layer "F.Cu")
		(at 291.303202 -59.571636 90)
		(property "Reference" "PR281"
			(at 0 0 90)
			(layer "F.SilkS")
			(hide yes)
			(effects
				(font
					(size 1.27 1.27)
				)
			)
		)
		(property "Value" ""
			(at 0 0 90)
			(layer "F.Fab")
			(effects
				(font
					(size 1.27 1.27)
				)
			)
		)
		(duplicate_pad_numbers_are_jumpers no)
		(fp_line
			(start 0.7874 -0.4064)
			(end 0.7874 0.4064)
			(stroke
				(width 0.1524)
				(type default)
			)
			(layer "F.SilkS")
		)
		(fp_line
			(start -0.7874 -0.4064)
			(end 0.7874 -0.4064)
			(stroke
				(width 0.1524)
				(type default)
			)
			(layer "F.SilkS")
		)
		(fp_line
			(start 0.7874 0.4064)
			(end -0.7874 0.4064)
			(stroke
				(width 0.1524)
				(type default)
			)
			(layer "F.SilkS")
		)
		(fp_line
			(start -0.7874 0.4064)
			(end -0.7874 -0.4064)
			(stroke
				(width 0.1524)
				(type default)
			)
			(layer "F.SilkS")
		)
		(fp_line
			(start -0.12065 -0.305054)
			(end -0.12065 -0.2794)
			(stroke
				(width 0.1)
				(type default)
			)
			(layer "F.Fab")
		)
		(fp_line
			(start -0.67945 -0.305054)
			(end -0.12065 -0.305054)
			(stroke
				(width 0.1)
				(type default)
			)
			(layer "F.Fab")
		)
		(fp_line
			(start 0.67945 -0.3048)
			(end 0.67945 0.3048)
			(stroke
				(width 0.1)
				(type default)
			)
			(layer "F.Fab")
		)
		(fp_line
			(start 0.12065 -0.3048)
			(end 0.67945 -0.3048)
			(stroke
				(width 0.1)
				(type default)
			)
			(layer "F.Fab")
		)
		(fp_line
			(start 0.12065 -0.2794)
			(end 0.12065 -0.3048)
			(stroke
				(width 0.1)
				(type default)
			)
			(layer "F.Fab")
		)
		(fp_line
			(start -0.12065 -0.2794)
			(end 0.12065 -0.2794)
			(stroke
				(width 0.1)
				(type default)
			)
			(layer "F.Fab")
		)
		(fp_line
			(start 0.120396 0.2794)
			(end -0.12065 0.2794)
			(stroke
				(width 0.1)
				(type default)
			)
			(layer "F.Fab")
		)
		(fp_line
			(start -0.12065 0.2794)
			(end -0.12065 0.3048)
			(stroke
				(width 0.1)
				(type default)
			)
			(layer "F.Fab")
		)
		(fp_line
			(start 0.67945 0.3048)
			(end 0.120396 0.3048)
			(stroke
				(width 0.1)
				(type default)
			)
			(layer "F.Fab")
		)
		(fp_line
			(start 0.120396 0.3048)
			(end 0.120396 0.2794)
			(stroke
				(width 0.1)
				(type default)
			)
			(layer "F.Fab")
		)
		(fp_line
			(start -0.12065 0.3048)
			(end -0.67945 0.3048)
			(stroke
				(width 0.1)
				(type default)
			)
			(layer "F.Fab")
		)
		(fp_line
			(start -0.67945 0.3048)
			(end -0.67945 -0.305054)
			(stroke
				(width 0.1)
				(type default)
			)
			(layer "F.Fab")
		)
		(pad "1" smd circle
			(at -0.40005 0 90)
			(size 0 0)
			(layers "F.Cu" "F.Mask" "F.Paste")
			(net "P3V3_SSD10_OCP")
		)
		(pad "2" smd circle
			(at 0.40005 0 90)
			(size 0 0)
			(layers "F.Cu" "F.Mask" "F.Paste")
			(net "GND")
		)
	)
	(footprint ""
		(layer "F.Cu")
		(at 387.06044 -116.7384)
		(property "Reference" "R345"
			(at 0 0 0)
			(layer "F.SilkS")
			(hide yes)
			(effects
				(font
					(size 1.27 1.27)
				)
			)
		)
		(property "Value" ""
			(at 0 0 0)
			(layer "F.Fab")
			(effects
				(font
					(size 1.27 1.27)
				)
			)
		)
		(duplicate_pad_numbers_are_jumpers no)
		(fp_line
			(start -0.7874 -0.4064)
			(end 0.7874 -0.4064)
			(stroke
				(width 0.1524)
				(type default)
			)
			(layer "F.SilkS")
		)
		(fp_line
			(start -0.7874 0.4064)
			(end -0.7874 -0.4064)
			(stroke
				(width 0.1524)
				(type default)
			)
			(layer "F.SilkS")
		)
		(fp_line
			(start 0.7874 -0.4064)
			(end 0.7874 0.4064)
			(stroke
				(width 0.1524)
				(type default)
			)
			(layer "F.SilkS")
		)
		(fp_line
			(start 0.7874 0.4064)
			(end -0.7874 0.4064)
			(stroke
				(width 0.1524)
				(type default)
			)
			(layer "F.SilkS")
		)
		(fp_line
			(start -0.67945 -0.305054)
			(end -0.12065 -0.305054)
			(stroke
				(width 0.1)
				(type default)
			)
			(layer "F.Fab")
		)
		(fp_line
			(start -0.67945 0.3048)
			(end -0.67945 -0.305054)
			(stroke
				(width 0.1)
				(type default)
			)
			(layer "F.Fab")
		)
		(fp_line
			(start -0.12065 -0.305054)
			(end -0.12065 -0.2794)
			(stroke
				(width 0.1)
				(type default)
			)
			(layer "F.Fab")
		)
		(fp_line
			(start -0.12065 -0.2794)
			(end 0.12065 -0.2794)
			(stroke
				(width 0.1)
				(type default)
			)
			(layer "F.Fab")
		)
		(fp_line
			(start -0.12065 0.2794)
			(end -0.12065 0.3048)
			(stroke
				(width 0.1)
				(type default)
			)
			(layer "F.Fab")
		)
		(fp_line
			(start -0.12065 0.3048)
			(end -0.67945 0.3048)
			(stroke
				(width 0.1)
				(type default)
			)
			(layer "F.Fab")
		)
		(fp_line
			(start 0.120396 0.2794)
			(end -0.12065 0.2794)
			(stroke
				(width 0.1)
				(type default)
			)
			(layer "F.Fab")
		)
		(fp_line
			(start 0.120396 0.3048)
			(end 0.120396 0.2794)
			(stroke
				(width 0.1)
				(type default)
			)
			(layer "F.Fab")
		)
		(fp_line
			(start 0.12065 -0.3048)
			(end 0.67945 -0.3048)
			(stroke
				(width 0.1)
				(type default)
			)
			(layer "F.Fab")
		)
		(fp_line
			(start 0.12065 -0.2794)
			(end 0.12065 -0.3048)
			(stroke
				(width 0.1)
				(type default)
			)
			(layer "F.Fab")
		)
		(fp_line
			(start 0.67945 -0.3048)
			(end 0.67945 0.3048)
			(stroke
				(width 0.1)
				(type default)
			)
			(layer "F.Fab")
		)
		(fp_line
			(start 0.67945 0.3048)
			(end 0.120396 0.3048)
			(stroke
				(width 0.1)
				(type default)
			)
			(layer "F.Fab")
		)
		(pad "1" smd circle
			(at -0.40005 0)
			(size 0 0)
			(layers "F.Cu" "F.Mask" "F.Paste")
			(net "PRSNT_NIC6_N")
		)
		(pad "2" smd circle
			(at 0.40005 0)
			(size 0 0)
			(layers "F.Cu" "F.Mask" "F.Paste")
			(net "PRSNTB0_NIC6_N")
		)
	)
	(footprint ""
		(layer "F.Cu")
		(at 146.253454 -297.791632)
		(property "Reference" "L104"
			(at 0 0 0)
			(layer "F.SilkS")
			(hide yes)
			(effects
				(font
					(size 1.27 1.27)
				)
			)
		)
		(property "Value" ""
			(at 0 0 0)
			(layer "F.Fab")
			(effects
				(font
					(size 1.27 1.27)
				)
			)
		)
		(duplicate_pad_numbers_are_jumpers no)
		(fp_line
			(start -1.63576 -0.8128)
			(end -1.63576 0.8128)
			(stroke
				(width 0.1524)
				(type default)
			)
			(layer "F.SilkS")
		)
		(fp_line
			(start -1.63576 -0.8128)
			(end 1.63576 -0.8128)
			(stroke
				(width 0.1524)
				(type default)
			)
			(layer "F.SilkS")
		)
		(fp_line
			(start 1.63576 -0.8128)
			(end 1.63576 0.8128)
			(stroke
				(width 0.1524)
				(type default)
			)
			(layer "F.SilkS")
		)
		(fp_line
			(start 1.63576 0.8128)
			(end -1.63576 0.8128)
			(stroke
				(width 0.1524)
				(type default)
			)
			(layer "F.SilkS")
		)
		(fp_line
			(start -1.56083 -0.738632)
			(end -1.56083 0.7366)
			(stroke
				(width 0.1)
				(type default)
			)
			(layer "F.Fab")
		)
		(fp_line
			(start -1.56083 0.7366)
			(end -1.524 0.7366)
			(stroke
				(width 0.1)
				(type default)
			)
			(layer "F.Fab")
		)
		(fp_line
			(start -1.524 0.7366)
			(end 1.524 0.7366)
			(stroke
				(width 0.1)
				(type default)
			)
			(layer "F.Fab")
		)
		(fp_line
			(start 1.524 0.7366)
			(end 1.560576 0.7366)
			(stroke
				(width 0.1)
				(type default)
			)
			(layer "F.Fab")
		)
		(fp_line
			(start 1.560576 -0.738632)
			(end -1.56083 -0.738632)
			(stroke
				(width 0.1)
				(type default)
			)
			(layer "F.Fab")
		)
		(fp_line
			(start 1.560576 0.7366)
			(end 1.560576 -0.738632)
			(stroke
				(width 0.1)
				(type default)
			)
			(layer "F.Fab")
		)
		(pad "1" smd rect
			(at -0.94996 0 180)
			(size 1.1176 1.3716)
			(layers "F.Cu" "F.Mask" "F.Paste")
			(net "P1V8_PLL0_PEX1")
		)
		(pad "2" smd rect
			(at 0.94996 0 180)
			(size 1.1176 1.3716)
			(layers "F.Cu" "F.Mask" "F.Paste")
			(net "PCEPLL0_VDDA18_PEX1")
		)
	)
	(footprint ""
		(layer "F.Cu")
		(at 243.217954 -178.519328 -90)
		(property "Reference" "R4251"
			(at 0 0 270)
			(layer "F.SilkS")
			(hide yes)
			(effects
				(font
					(size 1.27 1.27)
				)
			)
		)
		(property "Value" ""
			(at 0 0 270)
			(layer "F.Fab")
			(effects
				(font
					(size 1.27 1.27)
				)
			)
		)
		(duplicate_pad_numbers_are_jumpers no)
		(fp_line
			(start -0.7874 0.4064)
			(end -0.7874 -0.4064)
			(stroke
				(width 0.1524)
				(type default)
			)
			(layer "F.SilkS")
		)
		(fp_line
			(start 0.7874 0.4064)
			(end -0.7874 0.4064)
			(stroke
				(width 0.1524)
				(type default)
			)
			(layer "F.SilkS")
		)
		(fp_line
			(start -0.7874 -0.4064)
			(end 0.7874 -0.4064)
			(stroke
				(width 0.1524)
				(type default)
			)
			(layer "F.SilkS")
		)
		(fp_line
			(start 0.7874 -0.4064)
			(end 0.7874 0.4064)
			(stroke
				(width 0.1524)
				(type default)
			)
			(layer "F.SilkS")
		)
		(fp_line
			(start -0.67945 0.3048)
			(end -0.67945 -0.305054)
			(stroke
				(width 0.1)
				(type default)
			)
			(layer "F.Fab")
		)
		(fp_line
			(start -0.12065 0.3048)
			(end -0.67945 0.3048)
			(stroke
				(width 0.1)
				(type default)
			)
			(layer "F.Fab")
		)
		(fp_line
			(start 0.120396 0.3048)
			(end 0.120396 0.2794)
			(stroke
				(width 0.1)
				(type default)
			)
			(layer "F.Fab")
		)
		(fp_line
			(start 0.67945 0.3048)
			(end 0.120396 0.3048)
			(stroke
				(width 0.1)
				(type default)
			)
			(layer "F.Fab")
		)
		(fp_line
			(start -0.12065 0.2794)
			(end -0.12065 0.3048)
			(stroke
				(width 0.1)
				(type default)
			)
			(layer "F.Fab")
		)
		(fp_line
			(start 0.120396 0.2794)
			(end -0.12065 0.2794)
			(stroke
				(width 0.1)
				(type default)
			)
			(layer "F.Fab")
		)
		(fp_line
			(start -0.12065 -0.2794)
			(end 0.12065 -0.2794)
			(stroke
				(width 0.1)
				(type default)
			)
			(layer "F.Fab")
		)
		(fp_line
			(start 0.12065 -0.2794)
			(end 0.12065 -0.3048)
			(stroke
				(width 0.1)
				(type default)
			)
			(layer "F.Fab")
		)
		(fp_line
			(start 0.12065 -0.3048)
			(end 0.67945 -0.3048)
			(stroke
				(width 0.1)
				(type default)
			)
			(layer "F.Fab")
		)
		(fp_line
			(start 0.67945 -0.3048)
			(end 0.67945 0.3048)
			(stroke
				(width 0.1)
				(type default)
			)
			(layer "F.Fab")
		)
		(fp_line
			(start -0.67945 -0.305054)
			(end -0.12065 -0.305054)
			(stroke
				(width 0.1)
				(type default)
			)
			(layer "F.Fab")
		)
		(fp_line
			(start -0.12065 -0.305054)
			(end -0.12065 -0.2794)
			(stroke
				(width 0.1)
				(type default)
			)
			(layer "F.Fab")
		)
		(pad "1" smd circle
			(at -0.40005 0 270)
			(size 0 0)
			(layers "F.Cu" "F.Mask" "F.Paste")
			(net "BIC_RST_PWRGD_RSMRST_R")
		)
		(pad "2" smd circle
			(at 0.40005 0 270)
			(size 0 0)
			(layers "F.Cu" "F.Mask" "F.Paste")
			(net "GND")
		)
	)
	(footprint ""
		(layer "F.Cu")
		(at 270.807942 -162.044126 180)
		(property "Reference" "R226"
			(at 0 0 180)
			(layer "F.SilkS")
			(hide yes)
			(effects
				(font
					(size 1.27 1.27)
				)
			)
		)
		(property "Value" ""
			(at 0 0 180)
			(layer "F.Fab")
			(effects
				(font
					(size 1.27 1.27)
				)
			)
		)
		(duplicate_pad_numbers_are_jumpers no)
		(fp_line
			(start 0.7874 0.4064)
			(end -0.7874 0.4064)
			(stroke
				(width 0.1524)
				(type default)
			)
			(layer "F.SilkS")
		)
		(fp_line
			(start 0.7874 -0.4064)
			(end 0.7874 0.4064)
			(stroke
				(width 0.1524)
				(type default)
			)
			(layer "F.SilkS")
		)
		(fp_line
			(start -0.7874 0.4064)
			(end -0.7874 -0.4064)
			(stroke
				(width 0.1524)
				(type default)
			)
			(layer "F.SilkS")
		)
		(fp_line
			(start -0.7874 -0.4064)
			(end 0.7874 -0.4064)
			(stroke
				(width 0.1524)
				(type default)
			)
			(layer "F.SilkS")
		)
		(fp_line
			(start 0.67945 0.3048)
			(end 0.120396 0.3048)
			(stroke
				(width 0.1)
				(type default)
			)
			(layer "F.Fab")
		)
		(fp_line
			(start 0.67945 -0.3048)
			(end 0.67945 0.3048)
			(stroke
				(width 0.1)
				(type default)
			)
			(layer "F.Fab")
		)
		(fp_line
			(start 0.12065 -0.2794)
			(end 0.12065 -0.3048)
			(stroke
				(width 0.1)
				(type default)
			)
			(layer "F.Fab")
		)
		(fp_line
			(start 0.12065 -0.3048)
			(end 0.67945 -0.3048)
			(stroke
				(width 0.1)
				(type default)
			)
			(layer "F.Fab")
		)
		(fp_line
			(start 0.120396 0.3048)
			(end 0.120396 0.2794)
			(stroke
				(width 0.1)
				(type default)
			)
			(layer "F.Fab")
		)
		(fp_line
			(start 0.120396 0.2794)
			(end -0.12065 0.2794)
			(stroke
				(width 0.1)
				(type default)
			)
			(layer "F.Fab")
		)
		(fp_line
			(start -0.12065 0.3048)
			(end -0.67945 0.3048)
			(stroke
				(width 0.1)
				(type default)
			)
			(layer "F.Fab")
		)
		(fp_line
			(start -0.12065 0.2794)
			(end -0.12065 0.3048)
			(stroke
				(width 0.1)
				(type default)
			)
			(layer "F.Fab")
		)
		(fp_line
			(start -0.12065 -0.2794)
			(end 0.12065 -0.2794)
			(stroke
				(width 0.1)
				(type default)
			)
			(layer "F.Fab")
		)
		(fp_line
			(start -0.12065 -0.305054)
			(end -0.12065 -0.2794)
			(stroke
				(width 0.1)
				(type default)
			)
			(layer "F.Fab")
		)
		(fp_line
			(start -0.67945 0.3048)
			(end -0.67945 -0.305054)
			(stroke
				(width 0.1)
				(type default)
			)
			(layer "F.Fab")
		)
		(fp_line
			(start -0.67945 -0.305054)
			(end -0.12065 -0.305054)
			(stroke
				(width 0.1)
				(type default)
			)
			(layer "F.Fab")
		)
		(pad "1" smd circle
			(at -0.40005 0 180)
			(size 0 0)
			(layers "F.Cu" "F.Mask" "F.Paste")
			(net "PWRGD_NIC4_PWR_GOOD")
		)
		(pad "2" smd circle
			(at 0.40005 0 180)
			(size 0 0)
			(layers "F.Cu" "F.Mask" "F.Paste")
			(net "GND")
		)
	)
	(footprint ""
		(layer "F.Cu")
		(at 458.567536 -306.805076 -90)
		(property "Reference" "PR182"
			(at 0 0 270)
			(layer "F.SilkS")
			(hide yes)
			(effects
				(font
					(size 1.27 1.27)
				)
			)
		)
		(property "Value" ""
			(at 0 0 270)
			(layer "F.Fab")
			(effects
				(font
					(size 1.27 1.27)
				)
			)
		)
		(duplicate_pad_numbers_are_jumpers no)
		(fp_line
			(start -0.7874 0.4064)
			(end -0.7874 -0.4064)
			(stroke
				(width 0.1524)
				(type default)
			)
			(layer "F.SilkS")
		)
		(fp_line
			(start 0.7874 0.4064)
			(end -0.7874 0.4064)
			(stroke
				(width 0.1524)
				(type default)
			)
			(layer "F.SilkS")
		)
		(fp_line
			(start -0.7874 -0.4064)
			(end 0.7874 -0.4064)
			(stroke
				(width 0.1524)
				(type default)
			)
			(layer "F.SilkS")
		)
		(fp_line
			(start 0.7874 -0.4064)
			(end 0.7874 0.4064)
			(stroke
				(width 0.1524)
				(type default)
			)
			(layer "F.SilkS")
		)
		(fp_line
			(start -0.67945 0.3048)
			(end -0.67945 -0.305054)
			(stroke
				(width 0.1)
				(type default)
			)
			(layer "F.Fab")
		)
		(fp_line
			(start -0.12065 0.3048)
			(end -0.67945 0.3048)
			(stroke
				(width 0.1)
				(type default)
			)
			(layer "F.Fab")
		)
		(fp_line
			(start 0.120396 0.3048)
			(end 0.120396 0.2794)
			(stroke
				(width 0.1)
				(type default)
			)
			(layer "F.Fab")
		)
		(fp_line
			(start 0.67945 0.3048)
			(end 0.120396 0.3048)
			(stroke
				(width 0.1)
				(type default)
			)
			(layer "F.Fab")
		)
		(fp_line
			(start -0.12065 0.2794)
			(end -0.12065 0.3048)
			(stroke
				(width 0.1)
				(type default)
			)
			(layer "F.Fab")
		)
		(fp_line
			(start 0.120396 0.2794)
			(end -0.12065 0.2794)
			(stroke
				(width 0.1)
				(type default)
			)
			(layer "F.Fab")
		)
		(fp_line
			(start -0.12065 -0.2794)
			(end 0.12065 -0.2794)
			(stroke
				(width 0.1)
				(type default)
			)
			(layer "F.Fab")
		)
		(fp_line
			(start 0.12065 -0.2794)
			(end 0.12065 -0.3048)
			(stroke
				(width 0.1)
				(type default)
			)
			(layer "F.Fab")
		)
		(fp_line
			(start 0.12065 -0.3048)
			(end 0.67945 -0.3048)
			(stroke
				(width 0.1)
				(type default)
			)
			(layer "F.Fab")
		)
		(fp_line
			(start 0.67945 -0.3048)
			(end 0.67945 0.3048)
			(stroke
				(width 0.1)
				(type default)
			)
			(layer "F.Fab")
		)
		(fp_line
			(start -0.67945 -0.305054)
			(end -0.12065 -0.305054)
			(stroke
				(width 0.1)
				(type default)
			)
			(layer "F.Fab")
		)
		(fp_line
			(start -0.12065 -0.305054)
			(end -0.12065 -0.2794)
			(stroke
				(width 0.1)
				(type default)
			)
			(layer "F.Fab")
		)
		(pad "1" smd circle
			(at -0.40005 0 270)
			(size 0 0)
			(layers "F.Cu" "F.Mask" "F.Paste")
			(net "P1V25_PEX3_CS")
		)
		(pad "2" smd circle
			(at 0.40005 0 270)
			(size 0 0)
			(layers "F.Cu" "F.Mask" "F.Paste")
			(net "GND")
		)
	)
	(footprint ""
		(layer "F.Cu")
		(at 46.487588 -25.342342 -90)
		(property "Reference" "R414"
			(at 0 0 270)
			(layer "F.SilkS")
			(hide yes)
			(effects
				(font
					(size 1.27 1.27)
				)
			)
		)
		(property "Value" ""
			(at 0 0 270)
			(layer "F.Fab")
			(effects
				(font
					(size 1.27 1.27)
				)
			)
		)
		(duplicate_pad_numbers_are_jumpers no)
		(fp_line
			(start -0.7874 0.4064)
			(end -0.7874 -0.4064)
			(stroke
				(width 0.1524)
				(type default)
			)
			(layer "F.SilkS")
		)
		(fp_line
			(start 0.7874 0.4064)
			(end -0.7874 0.4064)
			(stroke
				(width 0.1524)
				(type default)
			)
			(layer "F.SilkS")
		)
		(fp_line
			(start -0.7874 -0.4064)
			(end 0.7874 -0.4064)
			(stroke
				(width 0.1524)
				(type default)
			)
			(layer "F.SilkS")
		)
		(fp_line
			(start 0.7874 -0.4064)
			(end 0.7874 0.4064)
			(stroke
				(width 0.1524)
				(type default)
			)
			(layer "F.SilkS")
		)
		(fp_line
			(start -0.67945 0.3048)
			(end -0.67945 -0.305054)
			(stroke
				(width 0.1)
				(type default)
			)
			(layer "F.Fab")
		)
		(fp_line
			(start -0.12065 0.3048)
			(end -0.67945 0.3048)
			(stroke
				(width 0.1)
				(type default)
			)
			(layer "F.Fab")
		)
		(fp_line
			(start 0.120396 0.3048)
			(end 0.120396 0.2794)
			(stroke
				(width 0.1)
				(type default)
			)
			(layer "F.Fab")
		)
		(fp_line
			(start 0.67945 0.3048)
			(end 0.120396 0.3048)
			(stroke
				(width 0.1)
				(type default)
			)
			(layer "F.Fab")
		)
		(fp_line
			(start -0.12065 0.2794)
			(end -0.12065 0.3048)
			(stroke
				(width 0.1)
				(type default)
			)
			(layer "F.Fab")
		)
		(fp_line
			(start 0.120396 0.2794)
			(end -0.12065 0.2794)
			(stroke
				(width 0.1)
				(type default)
			)
			(layer "F.Fab")
		)
		(fp_line
			(start -0.12065 -0.2794)
			(end 0.12065 -0.2794)
			(stroke
				(width 0.1)
				(type default)
			)
			(layer "F.Fab")
		)
		(fp_line
			(start 0.12065 -0.2794)
			(end 0.12065 -0.3048)
			(stroke
				(width 0.1)
				(type default)
			)
			(layer "F.Fab")
		)
		(fp_line
			(start 0.12065 -0.3048)
			(end 0.67945 -0.3048)
			(stroke
				(width 0.1)
				(type default)
			)
			(layer "F.Fab")
		)
		(fp_line
			(start 0.67945 -0.3048)
			(end 0.67945 0.3048)
			(stroke
				(width 0.1)
				(type default)
			)
			(layer "F.Fab")
		)
		(fp_line
			(start -0.67945 -0.305054)
			(end -0.12065 -0.305054)
			(stroke
				(width 0.1)
				(type default)
			)
			(layer "F.Fab")
		)
		(fp_line
			(start -0.12065 -0.305054)
			(end -0.12065 -0.2794)
			(stroke
				(width 0.1)
				(type default)
			)
			(layer "F.Fab")
		)
		(pad "1" smd circle
			(at -0.40005 0 270)
			(size 0 0)
			(layers "F.Cu" "F.Mask" "F.Paste")
			(net "GND")
		)
		(pad "2" smd circle
			(at 0.40005 0 270)
			(size 0 0)
			(layers "F.Cu" "F.Mask" "F.Paste")
			(net "DUALPORT_N_SSD1")
		)
	)
	(footprint ""
		(layer "F.Cu")
		(at 387.06044 -117.7544 180)
		(property "Reference" "R313"
			(at 0 0 180)
			(layer "F.SilkS")
			(hide yes)
			(effects
				(font
					(size 1.27 1.27)
				)
			)
		)
		(property "Value" ""
			(at 0 0 180)
			(layer "F.Fab")
			(effects
				(font
					(size 1.27 1.27)
				)
			)
		)
		(duplicate_pad_numbers_are_jumpers no)
		(fp_line
			(start 0.7874 0.4064)
			(end -0.7874 0.4064)
			(stroke
				(width 0.1524)
				(type default)
			)
			(layer "F.SilkS")
		)
		(fp_line
			(start 0.7874 -0.4064)
			(end 0.7874 0.4064)
			(stroke
				(width 0.1524)
				(type default)
			)
			(layer "F.SilkS")
		)
		(fp_line
			(start -0.7874 0.4064)
			(end -0.7874 -0.4064)
			(stroke
				(width 0.1524)
				(type default)
			)
			(layer "F.SilkS")
		)
		(fp_line
			(start -0.7874 -0.4064)
			(end 0.7874 -0.4064)
			(stroke
				(width 0.1524)
				(type default)
			)
			(layer "F.SilkS")
		)
		(fp_line
			(start 0.67945 0.3048)
			(end 0.120396 0.3048)
			(stroke
				(width 0.1)
				(type default)
			)
			(layer "F.Fab")
		)
		(fp_line
			(start 0.67945 -0.3048)
			(end 0.67945 0.3048)
			(stroke
				(width 0.1)
				(type default)
			)
			(layer "F.Fab")
		)
		(fp_line
			(start 0.12065 -0.2794)
			(end 0.12065 -0.3048)
			(stroke
				(width 0.1)
				(type default)
			)
			(layer "F.Fab")
		)
		(fp_line
			(start 0.12065 -0.3048)
			(end 0.67945 -0.3048)
			(stroke
				(width 0.1)
				(type default)
			)
			(layer "F.Fab")
		)
		(fp_line
			(start 0.120396 0.3048)
			(end 0.120396 0.2794)
			(stroke
				(width 0.1)
				(type default)
			)
			(layer "F.Fab")
		)
		(fp_line
			(start 0.120396 0.2794)
			(end -0.12065 0.2794)
			(stroke
				(width 0.1)
				(type default)
			)
			(layer "F.Fab")
		)
		(fp_line
			(start -0.12065 0.3048)
			(end -0.67945 0.3048)
			(stroke
				(width 0.1)
				(type default)
			)
			(layer "F.Fab")
		)
		(fp_line
			(start -0.12065 0.2794)
			(end -0.12065 0.3048)
			(stroke
				(width 0.1)
				(type default)
			)
			(layer "F.Fab")
		)
		(fp_line
			(start -0.12065 -0.2794)
			(end 0.12065 -0.2794)
			(stroke
				(width 0.1)
				(type default)
			)
			(layer "F.Fab")
		)
		(fp_line
			(start -0.12065 -0.305054)
			(end -0.12065 -0.2794)
			(stroke
				(width 0.1)
				(type default)
			)
			(layer "F.Fab")
		)
		(fp_line
			(start -0.67945 0.3048)
			(end -0.67945 -0.305054)
			(stroke
				(width 0.1)
				(type default)
			)
			(layer "F.Fab")
		)
		(fp_line
			(start -0.67945 -0.305054)
			(end -0.12065 -0.305054)
			(stroke
				(width 0.1)
				(type default)
			)
			(layer "F.Fab")
		)
		(pad "1" smd circle
			(at -0.40005 0 180)
			(size 0 0)
			(layers "F.Cu" "F.Mask" "F.Paste")
			(net "PRSNTB0_NIC6_N")
		)
		(pad "2" smd circle
			(at 0.40005 0 180)
			(size 0 0)
			(layers "F.Cu" "F.Mask" "F.Paste")
			(net "P3V3_AUX")
		)
	)
	(footprint ""
		(layer "F.Cu")
		(at 238.909098 -26.03373)
		(property "Reference" "R4068"
			(at 0 0 0)
			(layer "F.SilkS")
			(hide yes)
			(effects
				(font
					(size 1.27 1.27)
				)
			)
		)
		(property "Value" ""
			(at 0 0 0)
			(layer "F.Fab")
			(effects
				(font
					(size 1.27 1.27)
				)
			)
		)
		(duplicate_pad_numbers_are_jumpers no)
		(fp_line
			(start -0.7874 -0.4064)
			(end 0.7874 -0.4064)
			(stroke
				(width 0.1524)
				(type default)
			)
			(layer "F.SilkS")
		)
		(fp_line
			(start -0.7874 0.4064)
			(end -0.7874 -0.4064)
			(stroke
				(width 0.1524)
				(type default)
			)
			(layer "F.SilkS")
		)
		(fp_line
			(start 0.7874 -0.4064)
			(end 0.7874 0.4064)
			(stroke
				(width 0.1524)
				(type default)
			)
			(layer "F.SilkS")
		)
		(fp_line
			(start 0.7874 0.4064)
			(end -0.7874 0.4064)
			(stroke
				(width 0.1524)
				(type default)
			)
			(layer "F.SilkS")
		)
		(fp_line
			(start -0.67945 -0.305054)
			(end -0.12065 -0.305054)
			(stroke
				(width 0.1)
				(type default)
			)
			(layer "F.Fab")
		)
		(fp_line
			(start -0.67945 0.3048)
			(end -0.67945 -0.305054)
			(stroke
				(width 0.1)
				(type default)
			)
			(layer "F.Fab")
		)
		(fp_line
			(start -0.12065 -0.305054)
			(end -0.12065 -0.2794)
			(stroke
				(width 0.1)
				(type default)
			)
			(layer "F.Fab")
		)
		(fp_line
			(start -0.12065 -0.2794)
			(end 0.12065 -0.2794)
			(stroke
				(width 0.1)
				(type default)
			)
			(layer "F.Fab")
		)
		(fp_line
			(start -0.12065 0.2794)
			(end -0.12065 0.3048)
			(stroke
				(width 0.1)
				(type default)
			)
			(layer "F.Fab")
		)
		(fp_line
			(start -0.12065 0.3048)
			(end -0.67945 0.3048)
			(stroke
				(width 0.1)
				(type default)
			)
			(layer "F.Fab")
		)
		(fp_line
			(start 0.120396 0.2794)
			(end -0.12065 0.2794)
			(stroke
				(width 0.1)
				(type default)
			)
			(layer "F.Fab")
		)
		(fp_line
			(start 0.120396 0.3048)
			(end 0.120396 0.2794)
			(stroke
				(width 0.1)
				(type default)
			)
			(layer "F.Fab")
		)
		(fp_line
			(start 0.12065 -0.3048)
			(end 0.67945 -0.3048)
			(stroke
				(width 0.1)
				(type default)
			)
			(layer "F.Fab")
		)
		(fp_line
			(start 0.12065 -0.2794)
			(end 0.12065 -0.3048)
			(stroke
				(width 0.1)
				(type default)
			)
			(layer "F.Fab")
		)
		(fp_line
			(start 0.67945 -0.3048)
			(end 0.67945 0.3048)
			(stroke
				(width 0.1)
				(type default)
			)
			(layer "F.Fab")
		)
		(fp_line
			(start 0.67945 0.3048)
			(end 0.120396 0.3048)
			(stroke
				(width 0.1)
				(type default)
			)
			(layer "F.Fab")
		)
		(pad "1" smd circle
			(at -0.40005 0)
			(size 0 0)
			(layers "F.Cu" "F.Mask" "F.Paste")
			(net "P3V3_AUX")
		)
		(pad "2" smd circle
			(at 0.40005 0)
			(size 0 0)
			(layers "F.Cu" "F.Mask" "F.Paste")
			(net "PRSNT_SSD8_R_N")
		)
	)
	(footprint ""
		(layer "F.Cu")
		(at 276.073616 -405.074374 90)
		(property "Reference" "R1821"
			(at 0 0 90)
			(layer "F.SilkS")
			(hide yes)
			(effects
				(font
					(size 1.27 1.27)
				)
			)
		)
		(property "Value" ""
			(at 0 0 90)
			(layer "F.Fab")
			(effects
				(font
					(size 1.27 1.27)
				)
			)
		)
		(duplicate_pad_numbers_are_jumpers no)
		(fp_line
			(start 0.7874 -0.4064)
			(end 0.7874 0.4064)
			(stroke
				(width 0.1524)
				(type default)
			)
			(layer "F.SilkS")
		)
		(fp_line
			(start -0.7874 -0.4064)
			(end 0.7874 -0.4064)
			(stroke
				(width 0.1524)
				(type default)
			)
			(layer "F.SilkS")
		)
		(fp_line
			(start 0.7874 0.4064)
			(end -0.7874 0.4064)
			(stroke
				(width 0.1524)
				(type default)
			)
			(layer "F.SilkS")
		)
		(fp_line
			(start -0.7874 0.4064)
			(end -0.7874 -0.4064)
			(stroke
				(width 0.1524)
				(type default)
			)
			(layer "F.SilkS")
		)
		(fp_line
			(start -0.12065 -0.305054)
			(end -0.12065 -0.2794)
			(stroke
				(width 0.1)
				(type default)
			)
			(layer "F.Fab")
		)
		(fp_line
			(start -0.67945 -0.305054)
			(end -0.12065 -0.305054)
			(stroke
				(width 0.1)
				(type default)
			)
			(layer "F.Fab")
		)
		(fp_line
			(start 0.67945 -0.3048)
			(end 0.67945 0.3048)
			(stroke
				(width 0.1)
				(type default)
			)
			(layer "F.Fab")
		)
		(fp_line
			(start 0.12065 -0.3048)
			(end 0.67945 -0.3048)
			(stroke
				(width 0.1)
				(type default)
			)
			(layer "F.Fab")
		)
		(fp_line
			(start 0.12065 -0.2794)
			(end 0.12065 -0.3048)
			(stroke
				(width 0.1)
				(type default)
			)
			(layer "F.Fab")
		)
		(fp_line
			(start -0.12065 -0.2794)
			(end 0.12065 -0.2794)
			(stroke
				(width 0.1)
				(type default)
			)
			(layer "F.Fab")
		)
		(fp_line
			(start 0.120396 0.2794)
			(end -0.12065 0.2794)
			(stroke
				(width 0.1)
				(type default)
			)
			(layer "F.Fab")
		)
		(fp_line
			(start -0.12065 0.2794)
			(end -0.12065 0.3048)
			(stroke
				(width 0.1)
				(type default)
			)
			(layer "F.Fab")
		)
		(fp_line
			(start 0.67945 0.3048)
			(end 0.120396 0.3048)
			(stroke
				(width 0.1)
				(type default)
			)
			(layer "F.Fab")
		)
		(fp_line
			(start 0.120396 0.3048)
			(end 0.120396 0.2794)
			(stroke
				(width 0.1)
				(type default)
			)
			(layer "F.Fab")
		)
		(fp_line
			(start -0.12065 0.3048)
			(end -0.67945 0.3048)
			(stroke
				(width 0.1)
				(type default)
			)
			(layer "F.Fab")
		)
		(fp_line
			(start -0.67945 0.3048)
			(end -0.67945 -0.305054)
			(stroke
				(width 0.1)
				(type default)
			)
			(layer "F.Fab")
		)
		(pad "1" smd circle
			(at -0.40005 0 90)
			(size 0 0)
			(layers "F.Cu" "F.Mask" "F.Paste")
			(net "BIC_SYS_READY_R_N")
		)
		(pad "2" smd circle
			(at 0.40005 0 90)
			(size 0 0)
			(layers "F.Cu" "F.Mask" "F.Paste")
			(net "BIC_SYS_READY_R2_N")
		)
	)
	(footprint ""
		(layer "F.Cu")
		(at 101.930454 -119.77624)
		(property "Reference" "R5857"
			(at 0 0 0)
			(layer "F.SilkS")
			(hide yes)
			(effects
				(font
					(size 1.27 1.27)
				)
			)
		)
		(property "Value" ""
			(at 0 0 0)
			(layer "F.Fab")
			(effects
				(font
					(size 1.27 1.27)
				)
			)
		)
		(duplicate_pad_numbers_are_jumpers no)
		(fp_line
			(start -0.7874 -0.4064)
			(end 0.7874 -0.4064)
			(stroke
				(width 0.1524)
				(type default)
			)
			(layer "F.SilkS")
		)
		(fp_line
			(start -0.7874 0.4064)
			(end -0.7874 -0.4064)
			(stroke
				(width 0.1524)
				(type default)
			)
			(layer "F.SilkS")
		)
		(fp_line
			(start 0.7874 -0.4064)
			(end 0.7874 0.4064)
			(stroke
				(width 0.1524)
				(type default)
			)
			(layer "F.SilkS")
		)
		(fp_line
			(start 0.7874 0.4064)
			(end -0.7874 0.4064)
			(stroke
				(width 0.1524)
				(type default)
			)
			(layer "F.SilkS")
		)
		(fp_line
			(start -0.67945 -0.305054)
			(end -0.12065 -0.305054)
			(stroke
				(width 0.1)
				(type default)
			)
			(layer "F.Fab")
		)
		(fp_line
			(start -0.67945 0.3048)
			(end -0.67945 -0.305054)
			(stroke
				(width 0.1)
				(type default)
			)
			(layer "F.Fab")
		)
		(fp_line
			(start -0.12065 -0.305054)
			(end -0.12065 -0.2794)
			(stroke
				(width 0.1)
				(type default)
			)
			(layer "F.Fab")
		)
		(fp_line
			(start -0.12065 -0.2794)
			(end 0.12065 -0.2794)
			(stroke
				(width 0.1)
				(type default)
			)
			(layer "F.Fab")
		)
		(fp_line
			(start -0.12065 0.2794)
			(end -0.12065 0.3048)
			(stroke
				(width 0.1)
				(type default)
			)
			(layer "F.Fab")
		)
		(fp_line
			(start -0.12065 0.3048)
			(end -0.67945 0.3048)
			(stroke
				(width 0.1)
				(type default)
			)
			(layer "F.Fab")
		)
		(fp_line
			(start 0.120396 0.2794)
			(end -0.12065 0.2794)
			(stroke
				(width 0.1)
				(type default)
			)
			(layer "F.Fab")
		)
		(fp_line
			(start 0.120396 0.3048)
			(end 0.120396 0.2794)
			(stroke
				(width 0.1)
				(type default)
			)
			(layer "F.Fab")
		)
		(fp_line
			(start 0.12065 -0.3048)
			(end 0.67945 -0.3048)
			(stroke
				(width 0.1)
				(type default)
			)
			(layer "F.Fab")
		)
		(fp_line
			(start 0.12065 -0.2794)
			(end 0.12065 -0.3048)
			(stroke
				(width 0.1)
				(type default)
			)
			(layer "F.Fab")
		)
		(fp_line
			(start 0.67945 -0.3048)
			(end 0.67945 0.3048)
			(stroke
				(width 0.1)
				(type default)
			)
			(layer "F.Fab")
		)
		(fp_line
			(start 0.67945 0.3048)
			(end 0.120396 0.3048)
			(stroke
				(width 0.1)
				(type default)
			)
			(layer "F.Fab")
		)
		(pad "1" smd circle
			(at -0.40005 0)
			(size 0 0)
			(layers "F.Cu" "F.Mask" "F.Paste")
			(net "P3V3_AUX")
		)
		(pad "2" smd circle
			(at 0.40005 0)
			(size 0 0)
			(layers "F.Cu" "F.Mask" "F.Paste")
			(net "PWRGD_P3V3_NIC1_D")
		)
	)
	(footprint ""
		(layer "F.Cu")
		(at 136.445244 -95.814642 180)
		(property "Reference" "R1590"
			(at 0 0 180)
			(layer "F.SilkS")
			(hide yes)
			(effects
				(font
					(size 1.27 1.27)
				)
			)
		)
		(property "Value" ""
			(at 0 0 180)
			(layer "F.Fab")
			(effects
				(font
					(size 1.27 1.27)
				)
			)
		)
		(duplicate_pad_numbers_are_jumpers no)
		(fp_line
			(start 0.7874 0.4064)
			(end -0.7874 0.4064)
			(stroke
				(width 0.1524)
				(type default)
			)
			(layer "F.SilkS")
		)
		(fp_line
			(start 0.7874 -0.4064)
			(end 0.7874 0.4064)
			(stroke
				(width 0.1524)
				(type default)
			)
			(layer "F.SilkS")
		)
		(fp_line
			(start -0.7874 0.4064)
			(end -0.7874 -0.4064)
			(stroke
				(width 0.1524)
				(type default)
			)
			(layer "F.SilkS")
		)
		(fp_line
			(start -0.7874 -0.4064)
			(end 0.7874 -0.4064)
			(stroke
				(width 0.1524)
				(type default)
			)
			(layer "F.SilkS")
		)
		(fp_line
			(start 0.67945 0.3048)
			(end 0.120396 0.3048)
			(stroke
				(width 0.1)
				(type default)
			)
			(layer "F.Fab")
		)
		(fp_line
			(start 0.67945 -0.3048)
			(end 0.67945 0.3048)
			(stroke
				(width 0.1)
				(type default)
			)
			(layer "F.Fab")
		)
		(fp_line
			(start 0.12065 -0.2794)
			(end 0.12065 -0.3048)
			(stroke
				(width 0.1)
				(type default)
			)
			(layer "F.Fab")
		)
		(fp_line
			(start 0.12065 -0.3048)
			(end 0.67945 -0.3048)
			(stroke
				(width 0.1)
				(type default)
			)
			(layer "F.Fab")
		)
		(fp_line
			(start 0.120396 0.3048)
			(end 0.120396 0.2794)
			(stroke
				(width 0.1)
				(type default)
			)
			(layer "F.Fab")
		)
		(fp_line
			(start 0.120396 0.2794)
			(end -0.12065 0.2794)
			(stroke
				(width 0.1)
				(type default)
			)
			(layer "F.Fab")
		)
		(fp_line
			(start -0.12065 0.3048)
			(end -0.67945 0.3048)
			(stroke
				(width 0.1)
				(type default)
			)
			(layer "F.Fab")
		)
		(fp_line
			(start -0.12065 0.2794)
			(end -0.12065 0.3048)
			(stroke
				(width 0.1)
				(type default)
			)
			(layer "F.Fab")
		)
		(fp_line
			(start -0.12065 -0.2794)
			(end 0.12065 -0.2794)
			(stroke
				(width 0.1)
				(type default)
			)
			(layer "F.Fab")
		)
		(fp_line
			(start -0.12065 -0.305054)
			(end -0.12065 -0.2794)
			(stroke
				(width 0.1)
				(type default)
			)
			(layer "F.Fab")
		)
		(fp_line
			(start -0.67945 0.3048)
			(end -0.67945 -0.305054)
			(stroke
				(width 0.1)
				(type default)
			)
			(layer "F.Fab")
		)
		(fp_line
			(start -0.67945 -0.305054)
			(end -0.12065 -0.305054)
			(stroke
				(width 0.1)
				(type default)
			)
			(layer "F.Fab")
		)
		(pad "1" smd circle
			(at -0.40005 0 180)
			(size 0 0)
			(layers "F.Cu" "F.Mask" "F.Paste")
			(net "SMB_BIC_I2C9_MUX0_SSD7_R_SCL")
		)
		(pad "2" smd circle
			(at 0.40005 0 180)
			(size 0 0)
			(layers "F.Cu" "F.Mask" "F.Paste")
			(net "SMB_BIC_I2C9_MUX0_SSD7_SCL")
		)
	)
	(footprint ""
		(layer "F.Cu")
		(at 25.341834 -261.026402 180)
		(property "Reference" "C3070"
			(at 0 0 180)
			(layer "F.SilkS")
			(hide yes)
			(effects
				(font
					(size 1.27 1.27)
				)
			)
		)
		(property "Value" ""
			(at 0 0 180)
			(layer "F.Fab")
			(effects
				(font
					(size 1.27 1.27)
				)
			)
		)
		(duplicate_pad_numbers_are_jumpers no)
		(fp_line
			(start 1.2954 0.5842)
			(end -1.2954 0.5842)
			(stroke
				(width 0.1524)
				(type default)
			)
			(layer "F.SilkS")
		)
		(fp_line
			(start 1.2954 -0.5842)
			(end 1.2954 0.5842)
			(stroke
				(width 0.1524)
				(type default)
			)
			(layer "F.SilkS")
		)
		(fp_line
			(start -1.2954 0.5842)
			(end -1.2954 -0.5842)
			(stroke
				(width 0.1524)
				(type default)
			)
			(layer "F.SilkS")
		)
		(fp_line
			(start -1.2954 -0.5842)
			(end 1.2954 -0.5842)
			(stroke
				(width 0.1524)
				(type default)
			)
			(layer "F.SilkS")
		)
		(fp_line
			(start 1.1938 0.4064)
			(end 0.8636 0.4064)
			(stroke
				(width 0.1)
				(type default)
			)
			(layer "F.Fab")
		)
		(fp_line
			(start 1.1938 -0.4064)
			(end 1.1938 0.4064)
			(stroke
				(width 0.1)
				(type default)
			)
			(layer "F.Fab")
		)
		(fp_line
			(start 0.8636 0.4572)
			(end -0.8636 0.4572)
			(stroke
				(width 0.1)
				(type default)
			)
			(layer "F.Fab")
		)
		(fp_line
			(start 0.8636 0.4064)
			(end 0.8636 0.4572)
			(stroke
				(width 0.1)
				(type default)
			)
			(layer "F.Fab")
		)
		(fp_line
			(start 0.8636 -0.4064)
			(end 1.1938 -0.4064)
			(stroke
				(width 0.1)
				(type default)
			)
			(layer "F.Fab")
		)
		(fp_line
			(start 0.8636 -0.4572)
			(end 0.8636 -0.4064)
			(stroke
				(width 0.1)
				(type default)
			)
			(layer "F.Fab")
		)
		(fp_line
			(start -0.8636 0.4572)
			(end -0.8636 0.4064)
			(stroke
				(width 0.1)
				(type default)
			)
			(layer "F.Fab")
		)
		(fp_line
			(start -0.8636 0.4064)
			(end -1.1938 0.4064)
			(stroke
				(width 0.1)
				(type default)
			)
			(layer "F.Fab")
		)
		(fp_line
			(start -0.8636 -0.4064)
			(end -0.8636 -0.4572)
			(stroke
				(width 0.1)
				(type default)
			)
			(layer "F.Fab")
		)
		(fp_line
			(start -0.8636 -0.4572)
			(end 0.8636 -0.4572)
			(stroke
				(width 0.1)
				(type default)
			)
			(layer "F.Fab")
		)
		(fp_line
			(start -1.1938 0.4064)
			(end -1.1938 -0.4064)
			(stroke
				(width 0.1)
				(type default)
			)
			(layer "F.Fab")
		)
		(fp_line
			(start -1.1938 -0.4064)
			(end -0.8636 -0.4064)
			(stroke
				(width 0.1)
				(type default)
			)
			(layer "F.Fab")
		)
		(pad "1" smd rect
			(at -0.7366 0 90)
			(size 0.7112 0.8128)
			(layers "F.Cu" "F.Mask" "F.Paste")
			(net "P1V8_VDDA_PEX0")
		)
		(pad "2" smd rect
			(at 0.7366 0 90)
			(size 0.7112 0.8128)
			(layers "F.Cu" "F.Mask" "F.Paste")
			(net "GND")
		)
	)
	(footprint ""
		(layer "F.Cu")
		(at 110.745016 -149.428454 -90)
		(property "Reference" "PL4"
			(at 7.442454 7.060946 90)
			(unlocked yes)
			(layer "F.SilkS")
			(effects
				(font
					(size 0.7874 0.5842)
					(thickness 0.1524)
				)
				(justify left)
			)
		)
		(property "Value" ""
			(at 0 0 270)
			(layer "F.Fab")
			(effects
				(font
					(size 1.27 1.27)
				)
			)
		)
		(duplicate_pad_numbers_are_jumpers no)
		(fp_line
			(start -7.4422 6.400038)
			(end -7.4422 -6.400038)
			(stroke
				(width 0.1524)
				(type default)
			)
			(layer "F.SilkS")
		)
		(fp_line
			(start 7.4422 6.400038)
			(end -7.4422 6.400038)
			(stroke
				(width 0.1524)
				(type default)
			)
			(layer "F.SilkS")
		)
		(fp_line
			(start -7.4422 -6.400038)
			(end 7.4422 -6.400038)
			(stroke
				(width 0.1524)
				(type default)
			)
			(layer "F.SilkS")
		)
		(fp_line
			(start 7.4422 -6.400038)
			(end 7.4422 6.400038)
			(stroke
				(width 0.1524)
				(type default)
			)
			(layer "F.SilkS")
		)
		(fp_line
			(start -6.862064 6.400038)
			(end 6.938264 6.400038)
			(stroke
				(width 0.1)
				(type default)
			)
			(layer "F.Fab")
		)
		(fp_line
			(start 6.938264 6.400038)
			(end 6.938264 -6.400038)
			(stroke
				(width 0.1)
				(type default)
			)
			(layer "F.Fab")
		)
		(fp_line
			(start -6.862064 -6.400038)
			(end -6.862064 6.400038)
			(stroke
				(width 0.1)
				(type default)
			)
			(layer "F.Fab")
		)
		(fp_line
			(start 6.938264 -6.400038)
			(end -6.862064 -6.400038)
			(stroke
				(width 0.1)
				(type default)
			)
			(layer "F.Fab")
		)
		(pad "1" smd rect
			(at -5.650484 0 270)
			(size 3.302 4.29768)
			(layers "F.Cu" "F.Mask" "F.Paste")
			(net "SW_P3V3_AUX_PH")
		)
		(pad "2" smd rect
			(at 5.650484 0 270)
			(size 3.302 4.29768)
			(layers "F.Cu" "F.Mask" "F.Paste")
			(net "P3V3_AUX")
		)
	)
	(footprint ""
		(layer "F.Cu")
		(at 363.474 -201.803 180)
		(property "Reference" "R4682"
			(at 0 0 180)
			(layer "F.SilkS")
			(hide yes)
			(effects
				(font
					(size 1.27 1.27)
				)
			)
		)
		(property "Value" ""
			(at 0 0 180)
			(layer "F.Fab")
			(effects
				(font
					(size 1.27 1.27)
				)
			)
		)
		(duplicate_pad_numbers_are_jumpers no)
		(fp_line
			(start 0.7874 0.4064)
			(end -0.7874 0.4064)
			(stroke
				(width 0.1524)
				(type default)
			)
			(layer "F.SilkS")
		)
		(fp_line
			(start 0.7874 -0.4064)
			(end 0.7874 0.4064)
			(stroke
				(width 0.1524)
				(type default)
			)
			(layer "F.SilkS")
		)
		(fp_line
			(start -0.7874 0.4064)
			(end -0.7874 -0.4064)
			(stroke
				(width 0.1524)
				(type default)
			)
			(layer "F.SilkS")
		)
		(fp_line
			(start -0.7874 -0.4064)
			(end 0.7874 -0.4064)
			(stroke
				(width 0.1524)
				(type default)
			)
			(layer "F.SilkS")
		)
		(fp_line
			(start 0.67945 0.3048)
			(end 0.120396 0.3048)
			(stroke
				(width 0.1)
				(type default)
			)
			(layer "F.Fab")
		)
		(fp_line
			(start 0.67945 -0.3048)
			(end 0.67945 0.3048)
			(stroke
				(width 0.1)
				(type default)
			)
			(layer "F.Fab")
		)
		(fp_line
			(start 0.12065 -0.2794)
			(end 0.12065 -0.3048)
			(stroke
				(width 0.1)
				(type default)
			)
			(layer "F.Fab")
		)
		(fp_line
			(start 0.12065 -0.3048)
			(end 0.67945 -0.3048)
			(stroke
				(width 0.1)
				(type default)
			)
			(layer "F.Fab")
		)
		(fp_line
			(start 0.120396 0.3048)
			(end 0.120396 0.2794)
			(stroke
				(width 0.1)
				(type default)
			)
			(layer "F.Fab")
		)
		(fp_line
			(start 0.120396 0.2794)
			(end -0.12065 0.2794)
			(stroke
				(width 0.1)
				(type default)
			)
			(layer "F.Fab")
		)
		(fp_line
			(start -0.12065 0.3048)
			(end -0.67945 0.3048)
			(stroke
				(width 0.1)
				(type default)
			)
			(layer "F.Fab")
		)
		(fp_line
			(start -0.12065 0.2794)
			(end -0.12065 0.3048)
			(stroke
				(width 0.1)
				(type default)
			)
			(layer "F.Fab")
		)
		(fp_line
			(start -0.12065 -0.2794)
			(end 0.12065 -0.2794)
			(stroke
				(width 0.1)
				(type default)
			)
			(layer "F.Fab")
		)
		(fp_line
			(start -0.12065 -0.305054)
			(end -0.12065 -0.2794)
			(stroke
				(width 0.1)
				(type default)
			)
			(layer "F.Fab")
		)
		(fp_line
			(start -0.67945 0.3048)
			(end -0.67945 -0.305054)
			(stroke
				(width 0.1)
				(type default)
			)
			(layer "F.Fab")
		)
		(fp_line
			(start -0.67945 -0.305054)
			(end -0.12065 -0.305054)
			(stroke
				(width 0.1)
				(type default)
			)
			(layer "F.Fab")
		)
		(pad "1" smd circle
			(at -0.40005 0 180)
			(size 0 0)
			(layers "F.Cu" "F.Mask" "F.Paste")
			(net "PCA9555_0_PEX1_A2")
		)
		(pad "2" smd circle
			(at 0.40005 0 180)
			(size 0 0)
			(layers "F.Cu" "F.Mask" "F.Paste")
			(net "P3V3_AUX")
		)
	)
	(footprint ""
		(layer "F.Cu")
		(at 46.434502 -34.546286 180)
		(property "Reference" "C73"
			(at 0 0 180)
			(layer "F.SilkS")
			(hide yes)
			(effects
				(font
					(size 1.27 1.27)
				)
			)
		)
		(property "Value" ""
			(at 0 0 180)
			(layer "F.Fab")
			(effects
				(font
					(size 1.27 1.27)
				)
			)
		)
		(duplicate_pad_numbers_are_jumpers no)
		(fp_line
			(start 0.299974 0.150114)
			(end -0.299974 0.150114)
			(stroke
				(width 0.1)
				(type default)
			)
			(layer "F.Fab")
		)
		(fp_line
			(start 0.299974 -0.150114)
			(end 0.299974 0.150114)
			(stroke
				(width 0.1)
				(type default)
			)
			(layer "F.Fab")
		)
		(fp_line
			(start -0.299974 0.150114)
			(end -0.299974 -0.150114)
			(stroke
				(width 0.1)
				(type default)
			)
			(layer "F.Fab")
		)
		(fp_line
			(start -0.299974 -0.150114)
			(end 0.299974 -0.150114)
			(stroke
				(width 0.1)
				(type default)
			)
			(layer "F.Fab")
		)
		(pad "1" smd rect
			(at -0.2667 0 180)
			(size 0.3048 0.381)
			(layers "F.Cu" "F.Mask" "F.Paste")
			(net "P5E_PEX0_STN2_TX_DP<43>")
		)
		(pad "2" smd rect
			(at 0.2667 0 180)
			(size 0.3048 0.381)
			(layers "F.Cu" "F.Mask" "F.Paste")
			(net "P5E_PEX0_STN2_TX_C_DP<43>")
		)
	)
	(footprint ""
		(layer "F.Cu")
		(at 239.813338 -137.344404 180)
		(property "Reference" "PR194"
			(at 0 0 180)
			(layer "F.SilkS")
			(hide yes)
			(effects
				(font
					(size 1.27 1.27)
				)
			)
		)
		(property "Value" ""
			(at 0 0 180)
			(layer "F.Fab")
			(effects
				(font
					(size 1.27 1.27)
				)
			)
		)
		(duplicate_pad_numbers_are_jumpers no)
		(fp_line
			(start 0.7874 0.4064)
			(end -0.7874 0.4064)
			(stroke
				(width 0.1524)
				(type default)
			)
			(layer "F.SilkS")
		)
		(fp_line
			(start 0.7874 -0.4064)
			(end 0.7874 0.4064)
			(stroke
				(width 0.1524)
				(type default)
			)
			(layer "F.SilkS")
		)
		(fp_line
			(start -0.7874 0.4064)
			(end -0.7874 -0.4064)
			(stroke
				(width 0.1524)
				(type default)
			)
			(layer "F.SilkS")
		)
		(fp_line
			(start -0.7874 -0.4064)
			(end 0.7874 -0.4064)
			(stroke
				(width 0.1524)
				(type default)
			)
			(layer "F.SilkS")
		)
		(fp_line
			(start 0.67945 0.3048)
			(end 0.120396 0.3048)
			(stroke
				(width 0.1)
				(type default)
			)
			(layer "F.Fab")
		)
		(fp_line
			(start 0.67945 -0.3048)
			(end 0.67945 0.3048)
			(stroke
				(width 0.1)
				(type default)
			)
			(layer "F.Fab")
		)
		(fp_line
			(start 0.12065 -0.2794)
			(end 0.12065 -0.3048)
			(stroke
				(width 0.1)
				(type default)
			)
			(layer "F.Fab")
		)
		(fp_line
			(start 0.12065 -0.3048)
			(end 0.67945 -0.3048)
			(stroke
				(width 0.1)
				(type default)
			)
			(layer "F.Fab")
		)
		(fp_line
			(start 0.120396 0.3048)
			(end 0.120396 0.2794)
			(stroke
				(width 0.1)
				(type default)
			)
			(layer "F.Fab")
		)
		(fp_line
			(start 0.120396 0.2794)
			(end -0.12065 0.2794)
			(stroke
				(width 0.1)
				(type default)
			)
			(layer "F.Fab")
		)
		(fp_line
			(start -0.12065 0.3048)
			(end -0.67945 0.3048)
			(stroke
				(width 0.1)
				(type default)
			)
			(layer "F.Fab")
		)
		(fp_line
			(start -0.12065 0.2794)
			(end -0.12065 0.3048)
			(stroke
				(width 0.1)
				(type default)
			)
			(layer "F.Fab")
		)
		(fp_line
			(start -0.12065 -0.2794)
			(end 0.12065 -0.2794)
			(stroke
				(width 0.1)
				(type default)
			)
			(layer "F.Fab")
		)
		(fp_line
			(start -0.12065 -0.305054)
			(end -0.12065 -0.2794)
			(stroke
				(width 0.1)
				(type default)
			)
			(layer "F.Fab")
		)
		(fp_line
			(start -0.67945 0.3048)
			(end -0.67945 -0.305054)
			(stroke
				(width 0.1)
				(type default)
			)
			(layer "F.Fab")
		)
		(fp_line
			(start -0.67945 -0.305054)
			(end -0.12065 -0.305054)
			(stroke
				(width 0.1)
				(type default)
			)
			(layer "F.Fab")
		)
		(pad "1" smd circle
			(at -0.40005 0 180)
			(size 0 0)
			(layers "F.Cu" "F.Mask" "F.Paste")
			(net "P12V_NIC4_OCP")
		)
		(pad "2" smd circle
			(at 0.40005 0 180)
			(size 0 0)
			(layers "F.Cu" "F.Mask" "F.Paste")
			(net "GND")
		)
	)
	(footprint ""
		(layer "F.Cu")
		(at 30.373828 -27.006296 -90)
		(property "Reference" "PC676"
			(at 0 0 270)
			(layer "F.SilkS")
			(hide yes)
			(effects
				(font
					(size 1.27 1.27)
				)
			)
		)
		(property "Value" ""
			(at 0 0 270)
			(layer "F.Fab")
			(effects
				(font
					(size 1.27 1.27)
				)
			)
		)
		(duplicate_pad_numbers_are_jumpers no)
		(fp_line
			(start -0.7874 0.4064)
			(end -0.7874 -0.4064)
			(stroke
				(width 0.1524)
				(type default)
			)
			(layer "F.SilkS")
		)
		(fp_line
			(start 0.7874 0.4064)
			(end -0.7874 0.4064)
			(stroke
				(width 0.1524)
				(type default)
			)
			(layer "F.SilkS")
		)
		(fp_line
			(start -0.7874 -0.4064)
			(end 0.7874 -0.4064)
			(stroke
				(width 0.1524)
				(type default)
			)
			(layer "F.SilkS")
		)
		(fp_line
			(start 0.7874 -0.4064)
			(end 0.7874 0.4064)
			(stroke
				(width 0.1524)
				(type default)
			)
			(layer "F.SilkS")
		)
		(fp_line
			(start -0.67945 0.3048)
			(end -0.67945 -0.305054)
			(stroke
				(width 0.1)
				(type default)
			)
			(layer "F.Fab")
		)
		(fp_line
			(start -0.12065 0.3048)
			(end -0.67945 0.3048)
			(stroke
				(width 0.1)
				(type default)
			)
			(layer "F.Fab")
		)
		(fp_line
			(start 0.120396 0.3048)
			(end 0.120396 0.2794)
			(stroke
				(width 0.1)
				(type default)
			)
			(layer "F.Fab")
		)
		(fp_line
			(start 0.67945 0.3048)
			(end 0.120396 0.3048)
			(stroke
				(width 0.1)
				(type default)
			)
			(layer "F.Fab")
		)
		(fp_line
			(start -0.12065 0.2794)
			(end -0.12065 0.3048)
			(stroke
				(width 0.1)
				(type default)
			)
			(layer "F.Fab")
		)
		(fp_line
			(start 0.120396 0.2794)
			(end -0.12065 0.2794)
			(stroke
				(width 0.1)
				(type default)
			)
			(layer "F.Fab")
		)
		(fp_line
			(start -0.12065 -0.2794)
			(end 0.12065 -0.2794)
			(stroke
				(width 0.1)
				(type default)
			)
			(layer "F.Fab")
		)
		(fp_line
			(start 0.12065 -0.2794)
			(end 0.12065 -0.3048)
			(stroke
				(width 0.1)
				(type default)
			)
			(layer "F.Fab")
		)
		(fp_line
			(start 0.12065 -0.3048)
			(end 0.67945 -0.3048)
			(stroke
				(width 0.1)
				(type default)
			)
			(layer "F.Fab")
		)
		(fp_line
			(start 0.67945 -0.3048)
			(end 0.67945 0.3048)
			(stroke
				(width 0.1)
				(type default)
			)
			(layer "F.Fab")
		)
		(fp_line
			(start -0.67945 -0.305054)
			(end -0.12065 -0.305054)
			(stroke
				(width 0.1)
				(type default)
			)
			(layer "F.Fab")
		)
		(fp_line
			(start -0.12065 -0.305054)
			(end -0.12065 -0.2794)
			(stroke
				(width 0.1)
				(type default)
			)
			(layer "F.Fab")
		)
		(pad "1" smd circle
			(at -0.40005 0 270)
			(size 0 0)
			(layers "F.Cu" "F.Mask" "F.Paste")
			(net "P3V3_SSD1_CO_MODE")
		)
		(pad "2" smd circle
			(at 0.40005 0 270)
			(size 0 0)
			(layers "F.Cu" "F.Mask" "F.Paste")
			(net "GND")
		)
	)
	(footprint ""
		(layer "F.Cu")
		(at 13.802106 -378.325888 90)
		(property "Reference" "R6751"
			(at 0 0 90)
			(layer "F.SilkS")
			(hide yes)
			(effects
				(font
					(size 1.27 1.27)
				)
			)
		)
		(property "Value" ""
			(at 0 0 90)
			(layer "F.Fab")
			(effects
				(font
					(size 1.27 1.27)
				)
			)
		)
		(duplicate_pad_numbers_are_jumpers no)
		(fp_line
			(start 0.7874 -0.4064)
			(end 0.7874 0.4064)
			(stroke
				(width 0.1524)
				(type default)
			)
			(layer "F.SilkS")
		)
		(fp_line
			(start -0.395986 -0.4064)
			(end 0.7874 -0.4064)
			(stroke
				(width 0.1524)
				(type default)
			)
			(layer "F.SilkS")
		)
		(fp_line
			(start 0.7874 0.4064)
			(end -0.358902 0.4064)
			(stroke
				(width 0.1524)
				(type default)
			)
			(layer "F.SilkS")
		)
		(fp_line
			(start -0.12065 -0.305054)
			(end -0.12065 -0.2794)
			(stroke
				(width 0.1)
				(type default)
			)
			(layer "F.Fab")
		)
		(fp_line
			(start -0.67945 -0.305054)
			(end -0.12065 -0.305054)
			(stroke
				(width 0.1)
				(type default)
			)
			(layer "F.Fab")
		)
		(fp_line
			(start 0.67945 -0.3048)
			(end 0.67945 0.3048)
			(stroke
				(width 0.1)
				(type default)
			)
			(layer "F.Fab")
		)
		(fp_line
			(start 0.12065 -0.3048)
			(end 0.67945 -0.3048)
			(stroke
				(width 0.1)
				(type default)
			)
			(layer "F.Fab")
		)
		(fp_line
			(start 0.12065 -0.2794)
			(end 0.12065 -0.3048)
			(stroke
				(width 0.1)
				(type default)
			)
			(layer "F.Fab")
		)
		(fp_line
			(start -0.12065 -0.2794)
			(end 0.12065 -0.2794)
			(stroke
				(width 0.1)
				(type default)
			)
			(layer "F.Fab")
		)
		(fp_line
			(start 0.120396 0.2794)
			(end -0.12065 0.2794)
			(stroke
				(width 0.1)
				(type default)
			)
			(layer "F.Fab")
		)
		(fp_line
			(start -0.12065 0.2794)
			(end -0.12065 0.3048)
			(stroke
				(width 0.1)
				(type default)
			)
			(layer "F.Fab")
		)
		(fp_line
			(start 0.67945 0.3048)
			(end 0.120396 0.3048)
			(stroke
				(width 0.1)
				(type default)
			)
			(layer "F.Fab")
		)
		(fp_line
			(start 0.120396 0.3048)
			(end 0.120396 0.2794)
			(stroke
				(width 0.1)
				(type default)
			)
			(layer "F.Fab")
		)
		(fp_line
			(start -0.12065 0.3048)
			(end -0.67945 0.3048)
			(stroke
				(width 0.1)
				(type default)
			)
			(layer "F.Fab")
		)
		(fp_line
			(start -0.67945 0.3048)
			(end -0.67945 -0.305054)
			(stroke
				(width 0.1)
				(type default)
			)
			(layer "F.Fab")
		)
		(pad "1" smd circle
			(at -0.40005 0 90)
			(size 0 0)
			(layers "F.Cu" "F.Mask" "F.Paste")
			(net "USB2_GPU_HMC_USB8042_DN")
		)
		(pad "2" smd circle
			(at 0.40005 0 90)
			(size 0 0)
			(layers "F.Cu" "F.Mask" "F.Paste")
			(net "GND")
		)
	)
	(footprint ""
		(layer "F.Cu")
		(at 357.567738 -392.41984 90)
		(property "Reference" "R6695"
			(at 0 0 90)
			(layer "F.SilkS")
			(hide yes)
			(effects
				(font
					(size 1.27 1.27)
				)
			)
		)
		(property "Value" ""
			(at 0 0 90)
			(layer "F.Fab")
			(effects
				(font
					(size 1.27 1.27)
				)
			)
		)
		(duplicate_pad_numbers_are_jumpers no)
		(fp_line
			(start 0.7874 -0.4064)
			(end 0.7874 0.4064)
			(stroke
				(width 0.1524)
				(type default)
			)
			(layer "F.SilkS")
		)
		(fp_line
			(start -0.7874 -0.4064)
			(end 0.7874 -0.4064)
			(stroke
				(width 0.1524)
				(type default)
			)
			(layer "F.SilkS")
		)
		(fp_line
			(start 0.7874 0.4064)
			(end -0.7874 0.4064)
			(stroke
				(width 0.1524)
				(type default)
			)
			(layer "F.SilkS")
		)
		(fp_line
			(start -0.7874 0.4064)
			(end -0.7874 -0.4064)
			(stroke
				(width 0.1524)
				(type default)
			)
			(layer "F.SilkS")
		)
		(fp_line
			(start -0.12065 -0.305054)
			(end -0.12065 -0.2794)
			(stroke
				(width 0.1)
				(type default)
			)
			(layer "F.Fab")
		)
		(fp_line
			(start -0.67945 -0.305054)
			(end -0.12065 -0.305054)
			(stroke
				(width 0.1)
				(type default)
			)
			(layer "F.Fab")
		)
		(fp_line
			(start 0.67945 -0.3048)
			(end 0.67945 0.3048)
			(stroke
				(width 0.1)
				(type default)
			)
			(layer "F.Fab")
		)
		(fp_line
			(start 0.12065 -0.3048)
			(end 0.67945 -0.3048)
			(stroke
				(width 0.1)
				(type default)
			)
			(layer "F.Fab")
		)
		(fp_line
			(start 0.12065 -0.2794)
			(end 0.12065 -0.3048)
			(stroke
				(width 0.1)
				(type default)
			)
			(layer "F.Fab")
		)
		(fp_line
			(start -0.12065 -0.2794)
			(end 0.12065 -0.2794)
			(stroke
				(width 0.1)
				(type default)
			)
			(layer "F.Fab")
		)
		(fp_line
			(start 0.120396 0.2794)
			(end -0.12065 0.2794)
			(stroke
				(width 0.1)
				(type default)
			)
			(layer "F.Fab")
		)
		(fp_line
			(start -0.12065 0.2794)
			(end -0.12065 0.3048)
			(stroke
				(width 0.1)
				(type default)
			)
			(layer "F.Fab")
		)
		(fp_line
			(start 0.67945 0.3048)
			(end 0.120396 0.3048)
			(stroke
				(width 0.1)
				(type default)
			)
			(layer "F.Fab")
		)
		(fp_line
			(start 0.120396 0.3048)
			(end 0.120396 0.2794)
			(stroke
				(width 0.1)
				(type default)
			)
			(layer "F.Fab")
		)
		(fp_line
			(start -0.12065 0.3048)
			(end -0.67945 0.3048)
			(stroke
				(width 0.1)
				(type default)
			)
			(layer "F.Fab")
		)
		(fp_line
			(start -0.67945 0.3048)
			(end -0.67945 -0.305054)
			(stroke
				(width 0.1)
				(type default)
			)
			(layer "F.Fab")
		)
		(pad "1" smd circle
			(at -0.40005 0 90)
			(size 0 0)
			(layers "F.Cu" "F.Mask" "F.Paste")
			(net "MB_3V3IO_RSVD1_ISO")
		)
		(pad "2" smd circle
			(at 0.40005 0 90)
			(size 0 0)
			(layers "F.Cu" "F.Mask" "F.Paste")
			(net "P3V3_AUX")
		)
	)
	(footprint ""
		(layer "F.Cu")
		(at 293.992554 -158.080202 90)
		(property "Reference" "R3308"
			(at 0 0 90)
			(layer "F.SilkS")
			(hide yes)
			(effects
				(font
					(size 1.27 1.27)
				)
			)
		)
		(property "Value" ""
			(at 0 0 90)
			(layer "F.Fab")
			(effects
				(font
					(size 1.27 1.27)
				)
			)
		)
		(duplicate_pad_numbers_are_jumpers no)
		(fp_line
			(start 0.7874 -0.4064)
			(end 0.7874 0.4064)
			(stroke
				(width 0.1524)
				(type default)
			)
			(layer "F.SilkS")
		)
		(fp_line
			(start -0.7874 -0.4064)
			(end 0.7874 -0.4064)
			(stroke
				(width 0.1524)
				(type default)
			)
			(layer "F.SilkS")
		)
		(fp_line
			(start 0.7874 0.4064)
			(end -0.7874 0.4064)
			(stroke
				(width 0.1524)
				(type default)
			)
			(layer "F.SilkS")
		)
		(fp_line
			(start -0.7874 0.4064)
			(end -0.7874 -0.4064)
			(stroke
				(width 0.1524)
				(type default)
			)
			(layer "F.SilkS")
		)
		(fp_line
			(start -0.12065 -0.305054)
			(end -0.12065 -0.2794)
			(stroke
				(width 0.1)
				(type default)
			)
			(layer "F.Fab")
		)
		(fp_line
			(start -0.67945 -0.305054)
			(end -0.12065 -0.305054)
			(stroke
				(width 0.1)
				(type default)
			)
			(layer "F.Fab")
		)
		(fp_line
			(start 0.67945 -0.3048)
			(end 0.67945 0.3048)
			(stroke
				(width 0.1)
				(type default)
			)
			(layer "F.Fab")
		)
		(fp_line
			(start 0.12065 -0.3048)
			(end 0.67945 -0.3048)
			(stroke
				(width 0.1)
				(type default)
			)
			(layer "F.Fab")
		)
		(fp_line
			(start 0.12065 -0.2794)
			(end 0.12065 -0.3048)
			(stroke
				(width 0.1)
				(type default)
			)
			(layer "F.Fab")
		)
		(fp_line
			(start -0.12065 -0.2794)
			(end 0.12065 -0.2794)
			(stroke
				(width 0.1)
				(type default)
			)
			(layer "F.Fab")
		)
		(fp_line
			(start 0.120396 0.2794)
			(end -0.12065 0.2794)
			(stroke
				(width 0.1)
				(type default)
			)
			(layer "F.Fab")
		)
		(fp_line
			(start -0.12065 0.2794)
			(end -0.12065 0.3048)
			(stroke
				(width 0.1)
				(type default)
			)
			(layer "F.Fab")
		)
		(fp_line
			(start 0.67945 0.3048)
			(end 0.120396 0.3048)
			(stroke
				(width 0.1)
				(type default)
			)
			(layer "F.Fab")
		)
		(fp_line
			(start 0.120396 0.3048)
			(end 0.120396 0.2794)
			(stroke
				(width 0.1)
				(type default)
			)
			(layer "F.Fab")
		)
		(fp_line
			(start -0.12065 0.3048)
			(end -0.67945 0.3048)
			(stroke
				(width 0.1)
				(type default)
			)
			(layer "F.Fab")
		)
		(fp_line
			(start -0.67945 0.3048)
			(end -0.67945 -0.305054)
			(stroke
				(width 0.1)
				(type default)
			)
			(layer "F.Fab")
		)
		(pad "1" smd circle
			(at -0.40005 0 90)
			(size 0 0)
			(layers "F.Cu" "F.Mask" "F.Paste")
			(net "FM_SYS_THROTTLE_R")
		)
		(pad "2" smd circle
			(at 0.40005 0 90)
			(size 0 0)
			(layers "F.Cu" "F.Mask" "F.Paste")
			(net "FM_SYS_THROTTLE_NIC4")
		)
	)
	(footprint ""
		(layer "F.Cu")
		(at 171.983654 -61.487812 180)
		(property "Reference" "R5984"
			(at 0 0 180)
			(layer "F.SilkS")
			(hide yes)
			(effects
				(font
					(size 1.27 1.27)
				)
			)
		)
		(property "Value" ""
			(at 0 0 180)
			(layer "F.Fab")
			(effects
				(font
					(size 1.27 1.27)
				)
			)
		)
		(duplicate_pad_numbers_are_jumpers no)
		(fp_line
			(start 0.7874 0.4064)
			(end -0.7874 0.4064)
			(stroke
				(width 0.1524)
				(type default)
			)
			(layer "F.SilkS")
		)
		(fp_line
			(start 0.7874 -0.4064)
			(end 0.7874 0.4064)
			(stroke
				(width 0.1524)
				(type default)
			)
			(layer "F.SilkS")
		)
		(fp_line
			(start -0.7874 0.4064)
			(end -0.7874 -0.4064)
			(stroke
				(width 0.1524)
				(type default)
			)
			(layer "F.SilkS")
		)
		(fp_line
			(start -0.7874 -0.4064)
			(end 0.7874 -0.4064)
			(stroke
				(width 0.1524)
				(type default)
			)
			(layer "F.SilkS")
		)
		(fp_line
			(start 0.67945 0.3048)
			(end 0.120396 0.3048)
			(stroke
				(width 0.1)
				(type default)
			)
			(layer "F.Fab")
		)
		(fp_line
			(start 0.67945 -0.3048)
			(end 0.67945 0.3048)
			(stroke
				(width 0.1)
				(type default)
			)
			(layer "F.Fab")
		)
		(fp_line
			(start 0.12065 -0.2794)
			(end 0.12065 -0.3048)
			(stroke
				(width 0.1)
				(type default)
			)
			(layer "F.Fab")
		)
		(fp_line
			(start 0.12065 -0.3048)
			(end 0.67945 -0.3048)
			(stroke
				(width 0.1)
				(type default)
			)
			(layer "F.Fab")
		)
		(fp_line
			(start 0.120396 0.3048)
			(end 0.120396 0.2794)
			(stroke
				(width 0.1)
				(type default)
			)
			(layer "F.Fab")
		)
		(fp_line
			(start 0.120396 0.2794)
			(end -0.12065 0.2794)
			(stroke
				(width 0.1)
				(type default)
			)
			(layer "F.Fab")
		)
		(fp_line
			(start -0.12065 0.3048)
			(end -0.67945 0.3048)
			(stroke
				(width 0.1)
				(type default)
			)
			(layer "F.Fab")
		)
		(fp_line
			(start -0.12065 0.2794)
			(end -0.12065 0.3048)
			(stroke
				(width 0.1)
				(type default)
			)
			(layer "F.Fab")
		)
		(fp_line
			(start -0.12065 -0.2794)
			(end 0.12065 -0.2794)
			(stroke
				(width 0.1)
				(type default)
			)
			(layer "F.Fab")
		)
		(fp_line
			(start -0.12065 -0.305054)
			(end -0.12065 -0.2794)
			(stroke
				(width 0.1)
				(type default)
			)
			(layer "F.Fab")
		)
		(fp_line
			(start -0.67945 0.3048)
			(end -0.67945 -0.305054)
			(stroke
				(width 0.1)
				(type default)
			)
			(layer "F.Fab")
		)
		(fp_line
			(start -0.67945 -0.305054)
			(end -0.12065 -0.305054)
			(stroke
				(width 0.1)
				(type default)
			)
			(layer "F.Fab")
		)
		(pad "1" smd circle
			(at -0.40005 0 180)
			(size 0 0)
			(layers "F.Cu" "F.Mask" "F.Paste")
			(net "PWRGD_P12V_SSD6_D")
		)
		(pad "2" smd circle
			(at 0.40005 0 180)
			(size 0 0)
			(layers "F.Cu" "F.Mask" "F.Paste")
			(net "PWRGD_P12V_SSD6_R")
		)
	)
	(footprint ""
		(layer "F.Cu")
		(at 116.27739 -255.82372 180)
		(property "Reference" "PC45"
			(at 0 0 180)
			(layer "F.SilkS")
			(hide yes)
			(effects
				(font
					(size 1.27 1.27)
				)
			)
		)
		(property "Value" ""
			(at 0 0 180)
			(layer "F.Fab")
			(effects
				(font
					(size 1.27 1.27)
				)
			)
		)
		(duplicate_pad_numbers_are_jumpers no)
		(fp_line
			(start 0.7874 0.4064)
			(end -0.7874 0.4064)
			(stroke
				(width 0.1524)
				(type default)
			)
			(layer "F.SilkS")
		)
		(fp_line
			(start 0.7874 -0.4064)
			(end 0.7874 0.4064)
			(stroke
				(width 0.1524)
				(type default)
			)
			(layer "F.SilkS")
		)
		(fp_line
			(start -0.7874 0.4064)
			(end -0.7874 -0.4064)
			(stroke
				(width 0.1524)
				(type default)
			)
			(layer "F.SilkS")
		)
		(fp_line
			(start -0.7874 -0.4064)
			(end 0.7874 -0.4064)
			(stroke
				(width 0.1524)
				(type default)
			)
			(layer "F.SilkS")
		)
		(fp_line
			(start 0.67945 0.3048)
			(end 0.120396 0.3048)
			(stroke
				(width 0.1)
				(type default)
			)
			(layer "F.Fab")
		)
		(fp_line
			(start 0.67945 -0.3048)
			(end 0.67945 0.3048)
			(stroke
				(width 0.1)
				(type default)
			)
			(layer "F.Fab")
		)
		(fp_line
			(start 0.12065 -0.2794)
			(end 0.12065 -0.3048)
			(stroke
				(width 0.1)
				(type default)
			)
			(layer "F.Fab")
		)
		(fp_line
			(start 0.12065 -0.3048)
			(end 0.67945 -0.3048)
			(stroke
				(width 0.1)
				(type default)
			)
			(layer "F.Fab")
		)
		(fp_line
			(start 0.120396 0.3048)
			(end 0.120396 0.2794)
			(stroke
				(width 0.1)
				(type default)
			)
			(layer "F.Fab")
		)
		(fp_line
			(start 0.120396 0.2794)
			(end -0.12065 0.2794)
			(stroke
				(width 0.1)
				(type default)
			)
			(layer "F.Fab")
		)
		(fp_line
			(start -0.12065 0.3048)
			(end -0.67945 0.3048)
			(stroke
				(width 0.1)
				(type default)
			)
			(layer "F.Fab")
		)
		(fp_line
			(start -0.12065 0.2794)
			(end -0.12065 0.3048)
			(stroke
				(width 0.1)
				(type default)
			)
			(layer "F.Fab")
		)
		(fp_line
			(start -0.12065 -0.2794)
			(end 0.12065 -0.2794)
			(stroke
				(width 0.1)
				(type default)
			)
			(layer "F.Fab")
		)
		(fp_line
			(start -0.12065 -0.305054)
			(end -0.12065 -0.2794)
			(stroke
				(width 0.1)
				(type default)
			)
			(layer "F.Fab")
		)
		(fp_line
			(start -0.67945 0.3048)
			(end -0.67945 -0.305054)
			(stroke
				(width 0.1)
				(type default)
			)
			(layer "F.Fab")
		)
		(fp_line
			(start -0.67945 -0.305054)
			(end -0.12065 -0.305054)
			(stroke
				(width 0.1)
				(type default)
			)
			(layer "F.Fab")
		)
		(pad "1" smd circle
			(at -0.40005 0 180)
			(size 0 0)
			(layers "F.Cu" "F.Mask" "F.Paste")
			(net "P0V8_PEX0_VDD")
		)
		(pad "2" smd circle
			(at 0.40005 0 180)
			(size 0 0)
			(layers "F.Cu" "F.Mask" "F.Paste")
			(net "GND")
		)
	)
	(footprint ""
		(layer "F.Cu")
		(at 20.675092 -56.977534 180)
		(property "Reference" "PC390"
			(at 0 0 180)
			(layer "F.SilkS")
			(hide yes)
			(effects
				(font
					(size 1.27 1.27)
				)
			)
		)
		(property "Value" ""
			(at 0 0 180)
			(layer "F.Fab")
			(effects
				(font
					(size 1.27 1.27)
				)
			)
		)
		(duplicate_pad_numbers_are_jumpers no)
		(fp_line
			(start 0.7874 0.4064)
			(end -0.7874 0.4064)
			(stroke
				(width 0.1524)
				(type default)
			)
			(layer "F.SilkS")
		)
		(fp_line
			(start 0.7874 -0.4064)
			(end 0.7874 0.4064)
			(stroke
				(width 0.1524)
				(type default)
			)
			(layer "F.SilkS")
		)
		(fp_line
			(start -0.7874 0.4064)
			(end -0.7874 -0.4064)
			(stroke
				(width 0.1524)
				(type default)
			)
			(layer "F.SilkS")
		)
		(fp_line
			(start -0.7874 -0.4064)
			(end 0.7874 -0.4064)
			(stroke
				(width 0.1524)
				(type default)
			)
			(layer "F.SilkS")
		)
		(fp_line
			(start 0.67945 0.3048)
			(end 0.120396 0.3048)
			(stroke
				(width 0.1)
				(type default)
			)
			(layer "F.Fab")
		)
		(fp_line
			(start 0.67945 -0.3048)
			(end 0.67945 0.3048)
			(stroke
				(width 0.1)
				(type default)
			)
			(layer "F.Fab")
		)
		(fp_line
			(start 0.12065 -0.2794)
			(end 0.12065 -0.3048)
			(stroke
				(width 0.1)
				(type default)
			)
			(layer "F.Fab")
		)
		(fp_line
			(start 0.12065 -0.3048)
			(end 0.67945 -0.3048)
			(stroke
				(width 0.1)
				(type default)
			)
			(layer "F.Fab")
		)
		(fp_line
			(start 0.120396 0.3048)
			(end 0.120396 0.2794)
			(stroke
				(width 0.1)
				(type default)
			)
			(layer "F.Fab")
		)
		(fp_line
			(start 0.120396 0.2794)
			(end -0.12065 0.2794)
			(stroke
				(width 0.1)
				(type default)
			)
			(layer "F.Fab")
		)
		(fp_line
			(start -0.12065 0.3048)
			(end -0.67945 0.3048)
			(stroke
				(width 0.1)
				(type default)
			)
			(layer "F.Fab")
		)
		(fp_line
			(start -0.12065 0.2794)
			(end -0.12065 0.3048)
			(stroke
				(width 0.1)
				(type default)
			)
			(layer "F.Fab")
		)
		(fp_line
			(start -0.12065 -0.2794)
			(end 0.12065 -0.2794)
			(stroke
				(width 0.1)
				(type default)
			)
			(layer "F.Fab")
		)
		(fp_line
			(start -0.12065 -0.305054)
			(end -0.12065 -0.2794)
			(stroke
				(width 0.1)
				(type default)
			)
			(layer "F.Fab")
		)
		(fp_line
			(start -0.67945 0.3048)
			(end -0.67945 -0.305054)
			(stroke
				(width 0.1)
				(type default)
			)
			(layer "F.Fab")
		)
		(fp_line
			(start -0.67945 -0.305054)
			(end -0.12065 -0.305054)
			(stroke
				(width 0.1)
				(type default)
			)
			(layer "F.Fab")
		)
		(pad "1" smd circle
			(at -0.40005 0 180)
			(size 0 0)
			(layers "F.Cu" "F.Mask" "F.Paste")
			(net "P12V_AUX")
		)
		(pad "2" smd circle
			(at 0.40005 0 180)
			(size 0 0)
			(layers "F.Cu" "F.Mask" "F.Paste")
			(net "GND")
		)
	)
	(footprint ""
		(layer "F.Cu")
		(at 336.042 -145.923)
		(property "Reference" "R4795"
			(at 0 0 0)
			(layer "F.SilkS")
			(hide yes)
			(effects
				(font
					(size 1.27 1.27)
				)
			)
		)
		(property "Value" ""
			(at 0 0 0)
			(layer "F.Fab")
			(effects
				(font
					(size 1.27 1.27)
				)
			)
		)
		(duplicate_pad_numbers_are_jumpers no)
		(fp_line
			(start -0.7874 -0.4064)
			(end 0.7874 -0.4064)
			(stroke
				(width 0.1524)
				(type default)
			)
			(layer "F.SilkS")
		)
		(fp_line
			(start -0.7874 0.4064)
			(end -0.7874 -0.4064)
			(stroke
				(width 0.1524)
				(type default)
			)
			(layer "F.SilkS")
		)
		(fp_line
			(start 0.7874 -0.4064)
			(end 0.7874 0.4064)
			(stroke
				(width 0.1524)
				(type default)
			)
			(layer "F.SilkS")
		)
		(fp_line
			(start 0.7874 0.4064)
			(end -0.7874 0.4064)
			(stroke
				(width 0.1524)
				(type default)
			)
			(layer "F.SilkS")
		)
		(fp_line
			(start -0.67945 -0.305054)
			(end -0.12065 -0.305054)
			(stroke
				(width 0.1)
				(type default)
			)
			(layer "F.Fab")
		)
		(fp_line
			(start -0.67945 0.3048)
			(end -0.67945 -0.305054)
			(stroke
				(width 0.1)
				(type default)
			)
			(layer "F.Fab")
		)
		(fp_line
			(start -0.12065 -0.305054)
			(end -0.12065 -0.2794)
			(stroke
				(width 0.1)
				(type default)
			)
			(layer "F.Fab")
		)
		(fp_line
			(start -0.12065 -0.2794)
			(end 0.12065 -0.2794)
			(stroke
				(width 0.1)
				(type default)
			)
			(layer "F.Fab")
		)
		(fp_line
			(start -0.12065 0.2794)
			(end -0.12065 0.3048)
			(stroke
				(width 0.1)
				(type default)
			)
			(layer "F.Fab")
		)
		(fp_line
			(start -0.12065 0.3048)
			(end -0.67945 0.3048)
			(stroke
				(width 0.1)
				(type default)
			)
			(layer "F.Fab")
		)
		(fp_line
			(start 0.120396 0.2794)
			(end -0.12065 0.2794)
			(stroke
				(width 0.1)
				(type default)
			)
			(layer "F.Fab")
		)
		(fp_line
			(start 0.120396 0.3048)
			(end 0.120396 0.2794)
			(stroke
				(width 0.1)
				(type default)
			)
			(layer "F.Fab")
		)
		(fp_line
			(start 0.12065 -0.3048)
			(end 0.67945 -0.3048)
			(stroke
				(width 0.1)
				(type default)
			)
			(layer "F.Fab")
		)
		(fp_line
			(start 0.12065 -0.2794)
			(end 0.12065 -0.3048)
			(stroke
				(width 0.1)
				(type default)
			)
			(layer "F.Fab")
		)
		(fp_line
			(start 0.67945 -0.3048)
			(end 0.67945 0.3048)
			(stroke
				(width 0.1)
				(type default)
			)
			(layer "F.Fab")
		)
		(fp_line
			(start 0.67945 0.3048)
			(end 0.120396 0.3048)
			(stroke
				(width 0.1)
				(type default)
			)
			(layer "F.Fab")
		)
		(pad "1" smd circle
			(at -0.40005 0)
			(size 0 0)
			(layers "F.Cu" "F.Mask" "F.Paste")
			(net "P3V3_AUX")
		)
		(pad "2" smd circle
			(at 0.40005 0)
			(size 0 0)
			(layers "F.Cu" "F.Mask" "F.Paste")
			(net "RST_PEX_SSD14_PERST_R_N")
		)
	)
	(footprint ""
		(layer "F.Cu")
		(at 237.722664 -206.51216 -90)
		(property "Reference" "C3609"
			(at 0 0 270)
			(layer "F.SilkS")
			(hide yes)
			(effects
				(font
					(size 1.27 1.27)
				)
			)
		)
		(property "Value" ""
			(at 0 0 270)
			(layer "F.Fab")
			(effects
				(font
					(size 1.27 1.27)
				)
			)
		)
		(duplicate_pad_numbers_are_jumpers no)
		(fp_line
			(start -0.7874 0.4064)
			(end -0.7874 -0.4064)
			(stroke
				(width 0.1524)
				(type default)
			)
			(layer "F.SilkS")
		)
		(fp_line
			(start 0.7874 0.4064)
			(end -0.7874 0.4064)
			(stroke
				(width 0.1524)
				(type default)
			)
			(layer "F.SilkS")
		)
		(fp_line
			(start -0.7874 -0.4064)
			(end 0.7874 -0.4064)
			(stroke
				(width 0.1524)
				(type default)
			)
			(layer "F.SilkS")
		)
		(fp_line
			(start 0.7874 -0.4064)
			(end 0.7874 0.4064)
			(stroke
				(width 0.1524)
				(type default)
			)
			(layer "F.SilkS")
		)
		(fp_line
			(start -0.67945 0.3048)
			(end -0.67945 -0.305054)
			(stroke
				(width 0.1)
				(type default)
			)
			(layer "F.Fab")
		)
		(fp_line
			(start -0.12065 0.3048)
			(end -0.67945 0.3048)
			(stroke
				(width 0.1)
				(type default)
			)
			(layer "F.Fab")
		)
		(fp_line
			(start 0.120396 0.3048)
			(end 0.120396 0.2794)
			(stroke
				(width 0.1)
				(type default)
			)
			(layer "F.Fab")
		)
		(fp_line
			(start 0.67945 0.3048)
			(end 0.120396 0.3048)
			(stroke
				(width 0.1)
				(type default)
			)
			(layer "F.Fab")
		)
		(fp_line
			(start -0.12065 0.2794)
			(end -0.12065 0.3048)
			(stroke
				(width 0.1)
				(type default)
			)
			(layer "F.Fab")
		)
		(fp_line
			(start 0.120396 0.2794)
			(end -0.12065 0.2794)
			(stroke
				(width 0.1)
				(type default)
			)
			(layer "F.Fab")
		)
		(fp_line
			(start -0.12065 -0.2794)
			(end 0.12065 -0.2794)
			(stroke
				(width 0.1)
				(type default)
			)
			(layer "F.Fab")
		)
		(fp_line
			(start 0.12065 -0.2794)
			(end 0.12065 -0.3048)
			(stroke
				(width 0.1)
				(type default)
			)
			(layer "F.Fab")
		)
		(fp_line
			(start 0.12065 -0.3048)
			(end 0.67945 -0.3048)
			(stroke
				(width 0.1)
				(type default)
			)
			(layer "F.Fab")
		)
		(fp_line
			(start 0.67945 -0.3048)
			(end 0.67945 0.3048)
			(stroke
				(width 0.1)
				(type default)
			)
			(layer "F.Fab")
		)
		(fp_line
			(start -0.67945 -0.305054)
			(end -0.12065 -0.305054)
			(stroke
				(width 0.1)
				(type default)
			)
			(layer "F.Fab")
		)
		(fp_line
			(start -0.12065 -0.305054)
			(end -0.12065 -0.2794)
			(stroke
				(width 0.1)
				(type default)
			)
			(layer "F.Fab")
		)
		(pad "1" smd circle
			(at -0.40005 0 270)
			(size 0 0)
			(layers "F.Cu" "F.Mask" "F.Paste")
			(net "P12V_AUX_SCALED")
		)
		(pad "2" smd circle
			(at 0.40005 0 270)
			(size 0 0)
			(layers "F.Cu" "F.Mask" "F.Paste")
			(net "GND")
		)
	)
	(footprint ""
		(layer "F.Cu")
		(at 437.514492 -311.227978 135)
		(property "Reference" "R1443"
			(at 0 0 135)
			(layer "F.SilkS")
			(hide yes)
			(effects
				(font
					(size 1.27 1.27)
				)
			)
		)
		(property "Value" ""
			(at 0 0 135)
			(layer "F.Fab")
			(effects
				(font
					(size 1.27 1.27)
				)
			)
		)
		(duplicate_pad_numbers_are_jumpers no)
		(fp_line
			(start 0.787389 -0.406267)
			(end 0.787389 0.406267)
			(stroke
				(width 0.1524)
				(type default)
			)
			(layer "F.SilkS")
		)
		(fp_line
			(start 0.787389 0.406267)
			(end -0.787389 0.406267)
			(stroke
				(width 0.1524)
				(type default)
			)
			(layer "F.SilkS")
		)
		(fp_line
			(start -0.787389 -0.406267)
			(end 0.787389 -0.406267)
			(stroke
				(width 0.1524)
				(type default)
			)
			(layer "F.SilkS")
		)
		(fp_line
			(start -0.787389 0.406267)
			(end -0.787389 -0.406267)
			(stroke
				(width 0.1524)
				(type default)
			)
			(layer "F.SilkS")
		)
		(fp_line
			(start 0.679446 -0.30479)
			(end 0.679446 0.30479)
			(stroke
				(width 0.1)
				(type default)
			)
			(layer "F.Fab")
		)
		(fp_line
			(start 0.120515 -0.30479)
			(end 0.679446 -0.30479)
			(stroke
				(width 0.1)
				(type default)
			)
			(layer "F.Fab")
		)
		(fp_line
			(start 0.120695 -0.279466)
			(end 0.120515 -0.30479)
			(stroke
				(width 0.1)
				(type default)
			)
			(layer "F.Fab")
		)
		(fp_line
			(start 0.679446 0.30479)
			(end 0.120515 0.30479)
			(stroke
				(width 0.1)
				(type default)
			)
			(layer "F.Fab")
		)
		(fp_line
			(start -0.120695 -0.304969)
			(end -0.120695 -0.279466)
			(stroke
				(width 0.1)
				(type default)
			)
			(layer "F.Fab")
		)
		(fp_line
			(start -0.120695 -0.279466)
			(end 0.120695 -0.279466)
			(stroke
				(width 0.1)
				(type default)
			)
			(layer "F.Fab")
		)
		(fp_line
			(start 0.120335 0.279466)
			(end -0.120695 0.279466)
			(stroke
				(width 0.1)
				(type default)
			)
			(layer "F.Fab")
		)
		(fp_line
			(start 0.120515 0.30479)
			(end 0.120335 0.279466)
			(stroke
				(width 0.1)
				(type default)
			)
			(layer "F.Fab")
		)
		(fp_line
			(start -0.679446 -0.305149)
			(end -0.120695 -0.304969)
			(stroke
				(width 0.1)
				(type default)
			)
			(layer "F.Fab")
		)
		(fp_line
			(start -0.120695 0.279466)
			(end -0.120515 0.30479)
			(stroke
				(width 0.1)
				(type default)
			)
			(layer "F.Fab")
		)
		(fp_line
			(start -0.120515 0.30479)
			(end -0.679446 0.30479)
			(stroke
				(width 0.1)
				(type default)
			)
			(layer "F.Fab")
		)
		(fp_line
			(start -0.679446 0.30479)
			(end -0.679446 -0.305149)
			(stroke
				(width 0.1)
				(type default)
			)
			(layer "F.Fab")
		)
		(pad "1" smd circle
			(at -0.40005 0 135)
			(size 0 0)
			(layers "F.Cu" "F.Mask" "F.Paste")
			(net "PEX3_SPARE0")
		)
		(pad "2" smd circle
			(at 0.40005 0 135)
			(size 0 0)
			(layers "F.Cu" "F.Mask" "F.Paste")
			(net "P1V8_PEX")
		)
	)
	(footprint ""
		(layer "F.Cu")
		(at 405.928068 -388.33679 -90)
		(property "Reference" "C4175"
			(at 0 0 270)
			(layer "F.SilkS")
			(hide yes)
			(effects
				(font
					(size 1.27 1.27)
				)
			)
		)
		(property "Value" ""
			(at 0 0 270)
			(layer "F.Fab")
			(effects
				(font
					(size 1.27 1.27)
				)
			)
		)
		(duplicate_pad_numbers_are_jumpers no)
		(fp_line
			(start -0.7874 0.4064)
			(end -0.7874 -0.4064)
			(stroke
				(width 0.1524)
				(type default)
			)
			(layer "F.SilkS")
		)
		(fp_line
			(start 0.7874 0.4064)
			(end -0.7874 0.4064)
			(stroke
				(width 0.1524)
				(type default)
			)
			(layer "F.SilkS")
		)
		(fp_line
			(start -0.7874 -0.4064)
			(end 0.7874 -0.4064)
			(stroke
				(width 0.1524)
				(type default)
			)
			(layer "F.SilkS")
		)
		(fp_line
			(start 0.7874 -0.4064)
			(end 0.7874 0.4064)
			(stroke
				(width 0.1524)
				(type default)
			)
			(layer "F.SilkS")
		)
		(fp_line
			(start -0.67945 0.3048)
			(end -0.67945 -0.305054)
			(stroke
				(width 0.1)
				(type default)
			)
			(layer "F.Fab")
		)
		(fp_line
			(start -0.12065 0.3048)
			(end -0.67945 0.3048)
			(stroke
				(width 0.1)
				(type default)
			)
			(layer "F.Fab")
		)
		(fp_line
			(start 0.120396 0.3048)
			(end 0.120396 0.2794)
			(stroke
				(width 0.1)
				(type default)
			)
			(layer "F.Fab")
		)
		(fp_line
			(start 0.67945 0.3048)
			(end 0.120396 0.3048)
			(stroke
				(width 0.1)
				(type default)
			)
			(layer "F.Fab")
		)
		(fp_line
			(start -0.12065 0.2794)
			(end -0.12065 0.3048)
			(stroke
				(width 0.1)
				(type default)
			)
			(layer "F.Fab")
		)
		(fp_line
			(start 0.120396 0.2794)
			(end -0.12065 0.2794)
			(stroke
				(width 0.1)
				(type default)
			)
			(layer "F.Fab")
		)
		(fp_line
			(start -0.12065 -0.2794)
			(end 0.12065 -0.2794)
			(stroke
				(width 0.1)
				(type default)
			)
			(layer "F.Fab")
		)
		(fp_line
			(start 0.12065 -0.2794)
			(end 0.12065 -0.3048)
			(stroke
				(width 0.1)
				(type default)
			)
			(layer "F.Fab")
		)
		(fp_line
			(start 0.12065 -0.3048)
			(end 0.67945 -0.3048)
			(stroke
				(width 0.1)
				(type default)
			)
			(layer "F.Fab")
		)
		(fp_line
			(start 0.67945 -0.3048)
			(end 0.67945 0.3048)
			(stroke
				(width 0.1)
				(type default)
			)
			(layer "F.Fab")
		)
		(fp_line
			(start -0.67945 -0.305054)
			(end -0.12065 -0.305054)
			(stroke
				(width 0.1)
				(type default)
			)
			(layer "F.Fab")
		)
		(fp_line
			(start -0.12065 -0.305054)
			(end -0.12065 -0.2794)
			(stroke
				(width 0.1)
				(type default)
			)
			(layer "F.Fab")
		)
		(pad "1" smd circle
			(at -0.40005 0 270)
			(size 0 0)
			(layers "F.Cu" "F.Mask" "F.Paste")
			(net "GND")
		)
		(pad "2" smd circle
			(at 0.40005 0 270)
			(size 0 0)
			(layers "F.Cu" "F.Mask" "F.Paste")
			(net "GPU_WP_HW_CTRL_N")
		)
	)
	(footprint ""
		(layer "F.Cu")
		(at 164.659056 -166.55288)
		(property "Reference" "U20"
			(at -4.740656 0.469646 0)
			(unlocked yes)
			(layer "F.SilkS")
			(effects
				(font
					(size 0.7874 0.5842)
					(thickness 0.1524)
				)
				(justify left)
			)
		)
		(property "Value" ""
			(at 0 0 0)
			(layer "F.Fab")
			(effects
				(font
					(size 1.27 1.27)
				)
			)
		)
		(duplicate_pad_numbers_are_jumpers no)
		(fp_line
			(start -1.684274 -1.074928)
			(end -0.381 -1.074928)
			(stroke
				(width 0.1524)
				(type default)
			)
			(layer "F.SilkS")
		)
		(fp_line
			(start -1.684274 1.074928)
			(end -1.684274 -1.074928)
			(stroke
				(width 0.1524)
				(type default)
			)
			(layer "F.SilkS")
		)
		(fp_line
			(start -0.381 -1.074928)
			(end 0 -0.625094)
			(stroke
				(width 0.1524)
				(type default)
			)
			(layer "F.SilkS")
		)
		(fp_line
			(start 0 -0.625094)
			(end 0.381 -1.074928)
			(stroke
				(width 0.1524)
				(type default)
			)
			(layer "F.SilkS")
		)
		(fp_line
			(start 0.381 -1.074928)
			(end 1.684274 -1.074928)
			(stroke
				(width 0.1524)
				(type default)
			)
			(layer "F.SilkS")
		)
		(fp_line
			(start 1.684274 -1.074928)
			(end 1.684274 1.074928)
			(stroke
				(width 0.1524)
				(type default)
			)
			(layer "F.SilkS")
		)
		(fp_line
			(start 1.684274 1.074928)
			(end -1.684274 1.074928)
			(stroke
				(width 0.1524)
				(type default)
			)
			(layer "F.SilkS")
		)
		(fp_poly
			(pts
				(xy -2.637282 -0.903986) (xy -2.637282 -0.395986) (xy -1.875282 -0.649986)
			)
			(stroke
				(width 0)
				(type default)
			)
			(fill yes)
			(layer "F.SilkS")
		)
		(fp_line
			(start -0.700024 -1.074928)
			(end -0.700024 1.074928)
			(stroke
				(width 0.1)
				(type default)
			)
			(layer "F.Fab")
		)
		(fp_line
			(start -0.700024 1.074928)
			(end 0.700024 1.074928)
			(stroke
				(width 0.1)
				(type default)
			)
			(layer "F.Fab")
		)
		(fp_line
			(start 0.700024 -1.074928)
			(end -0.700024 -1.074928)
			(stroke
				(width 0.1)
				(type default)
			)
			(layer "F.Fab")
		)
		(fp_line
			(start 0.700024 1.074928)
			(end 0.700024 -1.074928)
			(stroke
				(width 0.1)
				(type default)
			)
			(layer "F.Fab")
		)
		(fp_poly
			(pts
				(xy -2.637282 -0.903986) (xy -2.637282 -0.395986) (xy -1.875282 -0.649986)
			)
			(stroke
				(width 0)
				(type default)
			)
			(fill yes)
			(layer "F.Fab")
		)
		(pad "1" smd rect
			(at -1.100074 -0.649986 270)
			(size 0.4064 0.9144)
			(layers "F.Cu" "F.Mask" "F.Paste")
			(net "Net_8454")
		)
		(pad "2" smd rect
			(at -1.100074 0 270)
			(size 0.4064 0.9144)
			(layers "F.Cu" "F.Mask" "F.Paste")
			(net "RST_HP_NIC2_N")
		)
		(pad "3" smd rect
			(at -1.100074 0.649986 270)
			(size 0.4064 0.9144)
			(layers "F.Cu" "F.Mask" "F.Paste")
			(net "GND")
		)
		(pad "4" smd rect
			(at 1.100074 0.649986 270)
			(size 0.4064 0.9144)
			(layers "F.Cu" "F.Mask" "F.Paste")
			(net "RST_HP_NIC2_BUF_N")
		)
		(pad "5" smd rect
			(at 1.100074 -0.649986 270)
			(size 0.4064 0.9144)
			(layers "F.Cu" "F.Mask" "F.Paste")
			(net "P3V3_AUX")
		)
	)
	(footprint ""
		(layer "F.Cu")
		(at 258.467098 -57.332626)
		(property "Reference" "R6833"
			(at 0 0 0)
			(layer "F.SilkS")
			(hide yes)
			(effects
				(font
					(size 1.27 1.27)
				)
			)
		)
		(property "Value" ""
			(at 0 0 0)
			(layer "F.Fab")
			(effects
				(font
					(size 1.27 1.27)
				)
			)
		)
		(duplicate_pad_numbers_are_jumpers no)
		(fp_line
			(start -0.7874 -0.4064)
			(end 0.7874 -0.4064)
			(stroke
				(width 0.1524)
				(type default)
			)
			(layer "F.SilkS")
		)
		(fp_line
			(start -0.7874 0.4064)
			(end -0.7874 -0.4064)
			(stroke
				(width 0.1524)
				(type default)
			)
			(layer "F.SilkS")
		)
		(fp_line
			(start 0.7874 -0.4064)
			(end 0.7874 0.4064)
			(stroke
				(width 0.1524)
				(type default)
			)
			(layer "F.SilkS")
		)
		(fp_line
			(start 0.7874 0.4064)
			(end -0.7874 0.4064)
			(stroke
				(width 0.1524)
				(type default)
			)
			(layer "F.SilkS")
		)
		(fp_line
			(start -0.67945 -0.305054)
			(end -0.12065 -0.305054)
			(stroke
				(width 0.1)
				(type default)
			)
			(layer "F.Fab")
		)
		(fp_line
			(start -0.67945 0.3048)
			(end -0.67945 -0.305054)
			(stroke
				(width 0.1)
				(type default)
			)
			(layer "F.Fab")
		)
		(fp_line
			(start -0.12065 -0.305054)
			(end -0.12065 -0.2794)
			(stroke
				(width 0.1)
				(type default)
			)
			(layer "F.Fab")
		)
		(fp_line
			(start -0.12065 -0.2794)
			(end 0.12065 -0.2794)
			(stroke
				(width 0.1)
				(type default)
			)
			(layer "F.Fab")
		)
		(fp_line
			(start -0.12065 0.2794)
			(end -0.12065 0.3048)
			(stroke
				(width 0.1)
				(type default)
			)
			(layer "F.Fab")
		)
		(fp_line
			(start -0.12065 0.3048)
			(end -0.67945 0.3048)
			(stroke
				(width 0.1)
				(type default)
			)
			(layer "F.Fab")
		)
		(fp_line
			(start 0.120396 0.2794)
			(end -0.12065 0.2794)
			(stroke
				(width 0.1)
				(type default)
			)
			(layer "F.Fab")
		)
		(fp_line
			(start 0.120396 0.3048)
			(end 0.120396 0.2794)
			(stroke
				(width 0.1)
				(type default)
			)
			(layer "F.Fab")
		)
		(fp_line
			(start 0.12065 -0.3048)
			(end 0.67945 -0.3048)
			(stroke
				(width 0.1)
				(type default)
			)
			(layer "F.Fab")
		)
		(fp_line
			(start 0.12065 -0.2794)
			(end 0.12065 -0.3048)
			(stroke
				(width 0.1)
				(type default)
			)
			(layer "F.Fab")
		)
		(fp_line
			(start 0.67945 -0.3048)
			(end 0.67945 0.3048)
			(stroke
				(width 0.1)
				(type default)
			)
			(layer "F.Fab")
		)
		(fp_line
			(start 0.67945 0.3048)
			(end 0.120396 0.3048)
			(stroke
				(width 0.1)
				(type default)
			)
			(layer "F.Fab")
		)
		(pad "1" smd circle
			(at -0.40005 0)
			(size 0 0)
			(layers "F.Cu" "F.Mask" "F.Paste")
			(net "SSD8_PWR_EN_R")
		)
		(pad "2" smd circle
			(at 0.40005 0)
			(size 0 0)
			(layers "F.Cu" "F.Mask" "F.Paste")
			(net "GND")
		)
	)
	(footprint ""
		(layer "F.Cu")
		(at 123.67514 -98.320606 180)
		(property "Reference" "R1567"
			(at 0 0 180)
			(layer "F.SilkS")
			(hide yes)
			(effects
				(font
					(size 1.27 1.27)
				)
			)
		)
		(property "Value" ""
			(at 0 0 180)
			(layer "F.Fab")
			(effects
				(font
					(size 1.27 1.27)
				)
			)
		)
		(duplicate_pad_numbers_are_jumpers no)
		(fp_line
			(start 0.7874 0.4064)
			(end -0.7874 0.4064)
			(stroke
				(width 0.1524)
				(type default)
			)
			(layer "F.SilkS")
		)
		(fp_line
			(start 0.7874 -0.4064)
			(end 0.7874 0.4064)
			(stroke
				(width 0.1524)
				(type default)
			)
			(layer "F.SilkS")
		)
		(fp_line
			(start -0.7874 0.4064)
			(end -0.7874 -0.4064)
			(stroke
				(width 0.1524)
				(type default)
			)
			(layer "F.SilkS")
		)
		(fp_line
			(start -0.7874 -0.4064)
			(end 0.7874 -0.4064)
			(stroke
				(width 0.1524)
				(type default)
			)
			(layer "F.SilkS")
		)
		(fp_line
			(start 0.67945 0.3048)
			(end 0.120396 0.3048)
			(stroke
				(width 0.1)
				(type default)
			)
			(layer "F.Fab")
		)
		(fp_line
			(start 0.67945 -0.3048)
			(end 0.67945 0.3048)
			(stroke
				(width 0.1)
				(type default)
			)
			(layer "F.Fab")
		)
		(fp_line
			(start 0.12065 -0.2794)
			(end 0.12065 -0.3048)
			(stroke
				(width 0.1)
				(type default)
			)
			(layer "F.Fab")
		)
		(fp_line
			(start 0.12065 -0.3048)
			(end 0.67945 -0.3048)
			(stroke
				(width 0.1)
				(type default)
			)
			(layer "F.Fab")
		)
		(fp_line
			(start 0.120396 0.3048)
			(end 0.120396 0.2794)
			(stroke
				(width 0.1)
				(type default)
			)
			(layer "F.Fab")
		)
		(fp_line
			(start 0.120396 0.2794)
			(end -0.12065 0.2794)
			(stroke
				(width 0.1)
				(type default)
			)
			(layer "F.Fab")
		)
		(fp_line
			(start -0.12065 0.3048)
			(end -0.67945 0.3048)
			(stroke
				(width 0.1)
				(type default)
			)
			(layer "F.Fab")
		)
		(fp_line
			(start -0.12065 0.2794)
			(end -0.12065 0.3048)
			(stroke
				(width 0.1)
				(type default)
			)
			(layer "F.Fab")
		)
		(fp_line
			(start -0.12065 -0.2794)
			(end 0.12065 -0.2794)
			(stroke
				(width 0.1)
				(type default)
			)
			(layer "F.Fab")
		)
		(fp_line
			(start -0.12065 -0.305054)
			(end -0.12065 -0.2794)
			(stroke
				(width 0.1)
				(type default)
			)
			(layer "F.Fab")
		)
		(fp_line
			(start -0.67945 0.3048)
			(end -0.67945 -0.305054)
			(stroke
				(width 0.1)
				(type default)
			)
			(layer "F.Fab")
		)
		(fp_line
			(start -0.67945 -0.305054)
			(end -0.12065 -0.305054)
			(stroke
				(width 0.1)
				(type default)
			)
			(layer "F.Fab")
		)
		(pad "1" smd circle
			(at -0.40005 0 180)
			(size 0 0)
			(layers "F.Cu" "F.Mask" "F.Paste")
			(net "BIC_I2C9_SSD_MUX0_A1")
		)
		(pad "2" smd circle
			(at 0.40005 0 180)
			(size 0 0)
			(layers "F.Cu" "F.Mask" "F.Paste")
			(net "GND")
		)
	)
	(footprint ""
		(layer "F.Cu")
		(at 404.446232 -366.409478 180)
		(property "Reference" "R6679"
			(at 0 0 180)
			(layer "F.SilkS")
			(hide yes)
			(effects
				(font
					(size 1.27 1.27)
				)
			)
		)
		(property "Value" ""
			(at 0 0 180)
			(layer "F.Fab")
			(effects
				(font
					(size 1.27 1.27)
				)
			)
		)
		(duplicate_pad_numbers_are_jumpers no)
		(fp_line
			(start 0.7874 0.4064)
			(end -0.7874 0.4064)
			(stroke
				(width 0.1524)
				(type default)
			)
			(layer "F.SilkS")
		)
		(fp_line
			(start 0.7874 -0.4064)
			(end 0.7874 0.4064)
			(stroke
				(width 0.1524)
				(type default)
			)
			(layer "F.SilkS")
		)
		(fp_line
			(start -0.7874 0.4064)
			(end -0.7874 -0.4064)
			(stroke
				(width 0.1524)
				(type default)
			)
			(layer "F.SilkS")
		)
		(fp_line
			(start -0.7874 -0.4064)
			(end 0.7874 -0.4064)
			(stroke
				(width 0.1524)
				(type default)
			)
			(layer "F.SilkS")
		)
		(fp_line
			(start 0.67945 0.3048)
			(end 0.120396 0.3048)
			(stroke
				(width 0.1)
				(type default)
			)
			(layer "F.Fab")
		)
		(fp_line
			(start 0.67945 -0.3048)
			(end 0.67945 0.3048)
			(stroke
				(width 0.1)
				(type default)
			)
			(layer "F.Fab")
		)
		(fp_line
			(start 0.12065 -0.2794)
			(end 0.12065 -0.3048)
			(stroke
				(width 0.1)
				(type default)
			)
			(layer "F.Fab")
		)
		(fp_line
			(start 0.12065 -0.3048)
			(end 0.67945 -0.3048)
			(stroke
				(width 0.1)
				(type default)
			)
			(layer "F.Fab")
		)
		(fp_line
			(start 0.120396 0.3048)
			(end 0.120396 0.2794)
			(stroke
				(width 0.1)
				(type default)
			)
			(layer "F.Fab")
		)
		(fp_line
			(start 0.120396 0.2794)
			(end -0.12065 0.2794)
			(stroke
				(width 0.1)
				(type default)
			)
			(layer "F.Fab")
		)
		(fp_line
			(start -0.12065 0.3048)
			(end -0.67945 0.3048)
			(stroke
				(width 0.1)
				(type default)
			)
			(layer "F.Fab")
		)
		(fp_line
			(start -0.12065 0.2794)
			(end -0.12065 0.3048)
			(stroke
				(width 0.1)
				(type default)
			)
			(layer "F.Fab")
		)
		(fp_line
			(start -0.12065 -0.2794)
			(end 0.12065 -0.2794)
			(stroke
				(width 0.1)
				(type default)
			)
			(layer "F.Fab")
		)
		(fp_line
			(start -0.12065 -0.305054)
			(end -0.12065 -0.2794)
			(stroke
				(width 0.1)
				(type default)
			)
			(layer "F.Fab")
		)
		(fp_line
			(start -0.67945 0.3048)
			(end -0.67945 -0.305054)
			(stroke
				(width 0.1)
				(type default)
			)
			(layer "F.Fab")
		)
		(fp_line
			(start -0.67945 -0.305054)
			(end -0.12065 -0.305054)
			(stroke
				(width 0.1)
				(type default)
			)
			(layer "F.Fab")
		)
		(pad "1" smd circle
			(at -0.40005 0 180)
			(size 0 0)
			(layers "F.Cu" "F.Mask" "F.Paste")
			(net "GPU_3V3IO_RSVD1_ISO_R")
		)
		(pad "2" smd circle
			(at 0.40005 0 180)
			(size 0 0)
			(layers "F.Cu" "F.Mask" "F.Paste")
			(net "GPU_3V3IO_RSVD1_ISO")
		)
	)
	(footprint ""
		(layer "F.Cu")
		(at 392.938762 -22.867366 90)
		(property "Reference" "C3966"
			(at 0 0 90)
			(layer "F.SilkS")
			(hide yes)
			(effects
				(font
					(size 1.27 1.27)
				)
			)
		)
		(property "Value" ""
			(at 0 0 90)
			(layer "F.Fab")
			(effects
				(font
					(size 1.27 1.27)
				)
			)
		)
		(duplicate_pad_numbers_are_jumpers no)
		(fp_line
			(start 0.7874 -0.4064)
			(end 0.7874 0.4064)
			(stroke
				(width 0.1524)
				(type default)
			)
			(layer "F.SilkS")
		)
		(fp_line
			(start -0.7874 -0.4064)
			(end 0.7874 -0.4064)
			(stroke
				(width 0.1524)
				(type default)
			)
			(layer "F.SilkS")
		)
		(fp_line
			(start 0.7874 0.4064)
			(end -0.7874 0.4064)
			(stroke
				(width 0.1524)
				(type default)
			)
			(layer "F.SilkS")
		)
		(fp_line
			(start -0.7874 0.4064)
			(end -0.7874 -0.4064)
			(stroke
				(width 0.1524)
				(type default)
			)
			(layer "F.SilkS")
		)
		(fp_line
			(start -0.12065 -0.305054)
			(end -0.12065 -0.2794)
			(stroke
				(width 0.1)
				(type default)
			)
			(layer "F.Fab")
		)
		(fp_line
			(start -0.67945 -0.305054)
			(end -0.12065 -0.305054)
			(stroke
				(width 0.1)
				(type default)
			)
			(layer "F.Fab")
		)
		(fp_line
			(start 0.67945 -0.3048)
			(end 0.67945 0.3048)
			(stroke
				(width 0.1)
				(type default)
			)
			(layer "F.Fab")
		)
		(fp_line
			(start 0.12065 -0.3048)
			(end 0.67945 -0.3048)
			(stroke
				(width 0.1)
				(type default)
			)
			(layer "F.Fab")
		)
		(fp_line
			(start 0.12065 -0.2794)
			(end 0.12065 -0.3048)
			(stroke
				(width 0.1)
				(type default)
			)
			(layer "F.Fab")
		)
		(fp_line
			(start -0.12065 -0.2794)
			(end 0.12065 -0.2794)
			(stroke
				(width 0.1)
				(type default)
			)
			(layer "F.Fab")
		)
		(fp_line
			(start 0.120396 0.2794)
			(end -0.12065 0.2794)
			(stroke
				(width 0.1)
				(type default)
			)
			(layer "F.Fab")
		)
		(fp_line
			(start -0.12065 0.2794)
			(end -0.12065 0.3048)
			(stroke
				(width 0.1)
				(type default)
			)
			(layer "F.Fab")
		)
		(fp_line
			(start 0.67945 0.3048)
			(end 0.120396 0.3048)
			(stroke
				(width 0.1)
				(type default)
			)
			(layer "F.Fab")
		)
		(fp_line
			(start 0.120396 0.3048)
			(end 0.120396 0.2794)
			(stroke
				(width 0.1)
				(type default)
			)
			(layer "F.Fab")
		)
		(fp_line
			(start -0.12065 0.3048)
			(end -0.67945 0.3048)
			(stroke
				(width 0.1)
				(type default)
			)
			(layer "F.Fab")
		)
		(fp_line
			(start -0.67945 0.3048)
			(end -0.67945 -0.305054)
			(stroke
				(width 0.1)
				(type default)
			)
			(layer "F.Fab")
		)
		(pad "1" smd circle
			(at -0.40005 0 90)
			(size 0 0)
			(layers "F.Cu" "F.Mask" "F.Paste")
			(net "P12V_SSD13")
		)
		(pad "2" smd circle
			(at 0.40005 0 90)
			(size 0 0)
			(layers "F.Cu" "F.Mask" "F.Paste")
			(net "GND")
		)
	)
	(footprint ""
		(layer "F.Cu")
		(at 146.253454 -284.990032)
		(property "Reference" "L111"
			(at 0 0 0)
			(layer "F.SilkS")
			(hide yes)
			(effects
				(font
					(size 1.27 1.27)
				)
			)
		)
		(property "Value" ""
			(at 0 0 0)
			(layer "F.Fab")
			(effects
				(font
					(size 1.27 1.27)
				)
			)
		)
		(duplicate_pad_numbers_are_jumpers no)
		(fp_line
			(start -1.63576 -0.8128)
			(end -1.63576 0.8128)
			(stroke
				(width 0.1524)
				(type default)
			)
			(layer "F.SilkS")
		)
		(fp_line
			(start -1.63576 -0.8128)
			(end 1.63576 -0.8128)
			(stroke
				(width 0.1524)
				(type default)
			)
			(layer "F.SilkS")
		)
		(fp_line
			(start 1.63576 -0.8128)
			(end 1.63576 0.8128)
			(stroke
				(width 0.1524)
				(type default)
			)
			(layer "F.SilkS")
		)
		(fp_line
			(start 1.63576 0.8128)
			(end -1.63576 0.8128)
			(stroke
				(width 0.1524)
				(type default)
			)
			(layer "F.SilkS")
		)
		(fp_line
			(start -1.56083 -0.738632)
			(end -1.56083 0.7366)
			(stroke
				(width 0.1)
				(type default)
			)
			(layer "F.Fab")
		)
		(fp_line
			(start -1.56083 0.7366)
			(end -1.524 0.7366)
			(stroke
				(width 0.1)
				(type default)
			)
			(layer "F.Fab")
		)
		(fp_line
			(start -1.524 0.7366)
			(end 1.524 0.7366)
			(stroke
				(width 0.1)
				(type default)
			)
			(layer "F.Fab")
		)
		(fp_line
			(start 1.524 0.7366)
			(end 1.560576 0.7366)
			(stroke
				(width 0.1)
				(type default)
			)
			(layer "F.Fab")
		)
		(fp_line
			(start 1.560576 -0.738632)
			(end -1.56083 -0.738632)
			(stroke
				(width 0.1)
				(type default)
			)
			(layer "F.Fab")
		)
		(fp_line
			(start 1.560576 0.7366)
			(end 1.560576 -0.738632)
			(stroke
				(width 0.1)
				(type default)
			)
			(layer "F.Fab")
		)
		(pad "1" smd rect
			(at -0.94996 0 180)
			(size 1.1176 1.3716)
			(layers "F.Cu" "F.Mask" "F.Paste")
			(net "P1V8_PLL0_PEX1")
		)
		(pad "2" smd rect
			(at 0.94996 0 180)
			(size 1.1176 1.3716)
			(layers "F.Cu" "F.Mask" "F.Paste")
			(net "PCEPLL7_VDDA18_PEX1")
		)
	)
	(footprint ""
		(layer "F.Cu")
		(at 216.937844 -96.139 -90)
		(property "Reference" "R714"
			(at 0 0 270)
			(layer "F.SilkS")
			(hide yes)
			(effects
				(font
					(size 1.27 1.27)
				)
			)
		)
		(property "Value" ""
			(at 0 0 270)
			(layer "F.Fab")
			(effects
				(font
					(size 1.27 1.27)
				)
			)
		)
		(duplicate_pad_numbers_are_jumpers no)
		(fp_line
			(start -0.7874 0.4064)
			(end -0.7874 -0.4064)
			(stroke
				(width 0.1524)
				(type default)
			)
			(layer "F.SilkS")
		)
		(fp_line
			(start 0.7874 0.4064)
			(end -0.7874 0.4064)
			(stroke
				(width 0.1524)
				(type default)
			)
			(layer "F.SilkS")
		)
		(fp_line
			(start -0.7874 -0.4064)
			(end 0.7874 -0.4064)
			(stroke
				(width 0.1524)
				(type default)
			)
			(layer "F.SilkS")
		)
		(fp_line
			(start 0.7874 -0.4064)
			(end 0.7874 0.4064)
			(stroke
				(width 0.1524)
				(type default)
			)
			(layer "F.SilkS")
		)
		(fp_line
			(start -0.67945 0.3048)
			(end -0.67945 -0.305054)
			(stroke
				(width 0.1)
				(type default)
			)
			(layer "F.Fab")
		)
		(fp_line
			(start -0.12065 0.3048)
			(end -0.67945 0.3048)
			(stroke
				(width 0.1)
				(type default)
			)
			(layer "F.Fab")
		)
		(fp_line
			(start 0.120396 0.3048)
			(end 0.120396 0.2794)
			(stroke
				(width 0.1)
				(type default)
			)
			(layer "F.Fab")
		)
		(fp_line
			(start 0.67945 0.3048)
			(end 0.120396 0.3048)
			(stroke
				(width 0.1)
				(type default)
			)
			(layer "F.Fab")
		)
		(fp_line
			(start -0.12065 0.2794)
			(end -0.12065 0.3048)
			(stroke
				(width 0.1)
				(type default)
			)
			(layer "F.Fab")
		)
		(fp_line
			(start 0.120396 0.2794)
			(end -0.12065 0.2794)
			(stroke
				(width 0.1)
				(type default)
			)
			(layer "F.Fab")
		)
		(fp_line
			(start -0.12065 -0.2794)
			(end 0.12065 -0.2794)
			(stroke
				(width 0.1)
				(type default)
			)
			(layer "F.Fab")
		)
		(fp_line
			(start 0.12065 -0.2794)
			(end 0.12065 -0.3048)
			(stroke
				(width 0.1)
				(type default)
			)
			(layer "F.Fab")
		)
		(fp_line
			(start 0.12065 -0.3048)
			(end 0.67945 -0.3048)
			(stroke
				(width 0.1)
				(type default)
			)
			(layer "F.Fab")
		)
		(fp_line
			(start 0.67945 -0.3048)
			(end 0.67945 0.3048)
			(stroke
				(width 0.1)
				(type default)
			)
			(layer "F.Fab")
		)
		(fp_line
			(start -0.67945 -0.305054)
			(end -0.12065 -0.305054)
			(stroke
				(width 0.1)
				(type default)
			)
			(layer "F.Fab")
		)
		(fp_line
			(start -0.12065 -0.305054)
			(end -0.12065 -0.2794)
			(stroke
				(width 0.1)
				(type default)
			)
			(layer "F.Fab")
		)
		(pad "1" smd circle
			(at -0.40005 0 270)
			(size 0 0)
			(layers "F.Cu" "F.Mask" "F.Paste")
			(net "NIC3_ADC_A1")
		)
		(pad "2" smd circle
			(at 0.40005 0 270)
			(size 0 0)
			(layers "F.Cu" "F.Mask" "F.Paste")
			(net "P3V3_AUX")
		)
	)
	(footprint ""
		(layer "F.Cu")
		(at 330.687426 -25.342342 -90)
		(property "Reference" "R443"
			(at 0 0 270)
			(layer "F.SilkS")
			(hide yes)
			(effects
				(font
					(size 1.27 1.27)
				)
			)
		)
		(property "Value" ""
			(at 0 0 270)
			(layer "F.Fab")
			(effects
				(font
					(size 1.27 1.27)
				)
			)
		)
		(duplicate_pad_numbers_are_jumpers no)
		(fp_line
			(start -0.7874 0.4064)
			(end -0.7874 -0.4064)
			(stroke
				(width 0.1524)
				(type default)
			)
			(layer "F.SilkS")
		)
		(fp_line
			(start 0.7874 0.4064)
			(end -0.7874 0.4064)
			(stroke
				(width 0.1524)
				(type default)
			)
			(layer "F.SilkS")
		)
		(fp_line
			(start -0.7874 -0.4064)
			(end 0.7874 -0.4064)
			(stroke
				(width 0.1524)
				(type default)
			)
			(layer "F.SilkS")
		)
		(fp_line
			(start 0.7874 -0.4064)
			(end 0.7874 0.4064)
			(stroke
				(width 0.1524)
				(type default)
			)
			(layer "F.SilkS")
		)
		(fp_line
			(start -0.67945 0.3048)
			(end -0.67945 -0.305054)
			(stroke
				(width 0.1)
				(type default)
			)
			(layer "F.Fab")
		)
		(fp_line
			(start -0.12065 0.3048)
			(end -0.67945 0.3048)
			(stroke
				(width 0.1)
				(type default)
			)
			(layer "F.Fab")
		)
		(fp_line
			(start 0.120396 0.3048)
			(end 0.120396 0.2794)
			(stroke
				(width 0.1)
				(type default)
			)
			(layer "F.Fab")
		)
		(fp_line
			(start 0.67945 0.3048)
			(end 0.120396 0.3048)
			(stroke
				(width 0.1)
				(type default)
			)
			(layer "F.Fab")
		)
		(fp_line
			(start -0.12065 0.2794)
			(end -0.12065 0.3048)
			(stroke
				(width 0.1)
				(type default)
			)
			(layer "F.Fab")
		)
		(fp_line
			(start 0.120396 0.2794)
			(end -0.12065 0.2794)
			(stroke
				(width 0.1)
				(type default)
			)
			(layer "F.Fab")
		)
		(fp_line
			(start -0.12065 -0.2794)
			(end 0.12065 -0.2794)
			(stroke
				(width 0.1)
				(type default)
			)
			(layer "F.Fab")
		)
		(fp_line
			(start 0.12065 -0.2794)
			(end 0.12065 -0.3048)
			(stroke
				(width 0.1)
				(type default)
			)
			(layer "F.Fab")
		)
		(fp_line
			(start 0.12065 -0.3048)
			(end 0.67945 -0.3048)
			(stroke
				(width 0.1)
				(type default)
			)
			(layer "F.Fab")
		)
		(fp_line
			(start 0.67945 -0.3048)
			(end 0.67945 0.3048)
			(stroke
				(width 0.1)
				(type default)
			)
			(layer "F.Fab")
		)
		(fp_line
			(start -0.67945 -0.305054)
			(end -0.12065 -0.305054)
			(stroke
				(width 0.1)
				(type default)
			)
			(layer "F.Fab")
		)
		(fp_line
			(start -0.12065 -0.305054)
			(end -0.12065 -0.2794)
			(stroke
				(width 0.1)
				(type default)
			)
			(layer "F.Fab")
		)
		(pad "1" smd circle
			(at -0.40005 0 270)
			(size 0 0)
			(layers "F.Cu" "F.Mask" "F.Paste")
			(net "GND")
		)
		(pad "2" smd circle
			(at 0.40005 0 270)
			(size 0 0)
			(layers "F.Cu" "F.Mask" "F.Paste")
			(net "DUALPORT_N_SSD11")
		)
	)
	(footprint ""
		(layer "F.Cu")
		(at 381.127 -212.344)
		(property "Reference" "R4637"
			(at 0 0 0)
			(layer "F.SilkS")
			(hide yes)
			(effects
				(font
					(size 1.27 1.27)
				)
			)
		)
		(property "Value" ""
			(at 0 0 0)
			(layer "F.Fab")
			(effects
				(font
					(size 1.27 1.27)
				)
			)
		)
		(duplicate_pad_numbers_are_jumpers no)
		(fp_line
			(start -0.7874 -0.4064)
			(end 0.7874 -0.4064)
			(stroke
				(width 0.1524)
				(type default)
			)
			(layer "F.SilkS")
		)
		(fp_line
			(start -0.7874 0.4064)
			(end -0.7874 -0.4064)
			(stroke
				(width 0.1524)
				(type default)
			)
			(layer "F.SilkS")
		)
		(fp_line
			(start 0.7874 -0.4064)
			(end 0.7874 0.4064)
			(stroke
				(width 0.1524)
				(type default)
			)
			(layer "F.SilkS")
		)
		(fp_line
			(start 0.7874 0.4064)
			(end -0.7874 0.4064)
			(stroke
				(width 0.1524)
				(type default)
			)
			(layer "F.SilkS")
		)
		(fp_line
			(start -0.67945 -0.305054)
			(end -0.12065 -0.305054)
			(stroke
				(width 0.1)
				(type default)
			)
			(layer "F.Fab")
		)
		(fp_line
			(start -0.67945 0.3048)
			(end -0.67945 -0.305054)
			(stroke
				(width 0.1)
				(type default)
			)
			(layer "F.Fab")
		)
		(fp_line
			(start -0.12065 -0.305054)
			(end -0.12065 -0.2794)
			(stroke
				(width 0.1)
				(type default)
			)
			(layer "F.Fab")
		)
		(fp_line
			(start -0.12065 -0.2794)
			(end 0.12065 -0.2794)
			(stroke
				(width 0.1)
				(type default)
			)
			(layer "F.Fab")
		)
		(fp_line
			(start -0.12065 0.2794)
			(end -0.12065 0.3048)
			(stroke
				(width 0.1)
				(type default)
			)
			(layer "F.Fab")
		)
		(fp_line
			(start -0.12065 0.3048)
			(end -0.67945 0.3048)
			(stroke
				(width 0.1)
				(type default)
			)
			(layer "F.Fab")
		)
		(fp_line
			(start 0.120396 0.2794)
			(end -0.12065 0.2794)
			(stroke
				(width 0.1)
				(type default)
			)
			(layer "F.Fab")
		)
		(fp_line
			(start 0.120396 0.3048)
			(end 0.120396 0.2794)
			(stroke
				(width 0.1)
				(type default)
			)
			(layer "F.Fab")
		)
		(fp_line
			(start 0.12065 -0.3048)
			(end 0.67945 -0.3048)
			(stroke
				(width 0.1)
				(type default)
			)
			(layer "F.Fab")
		)
		(fp_line
			(start 0.12065 -0.2794)
			(end 0.12065 -0.3048)
			(stroke
				(width 0.1)
				(type default)
			)
			(layer "F.Fab")
		)
		(fp_line
			(start 0.67945 -0.3048)
			(end 0.67945 0.3048)
			(stroke
				(width 0.1)
				(type default)
			)
			(layer "F.Fab")
		)
		(fp_line
			(start 0.67945 0.3048)
			(end 0.120396 0.3048)
			(stroke
				(width 0.1)
				(type default)
			)
			(layer "F.Fab")
		)
		(pad "1" smd circle
			(at -0.40005 0)
			(size 0 0)
			(layers "F.Cu" "F.Mask" "F.Paste")
			(net "GND")
		)
		(pad "2" smd circle
			(at 0.40005 0)
			(size 0 0)
			(layers "F.Cu" "F.Mask" "F.Paste")
			(net "PCA9555_0_PEX0_A0")
		)
	)
	(footprint ""
		(layer "F.Cu")
		(at 361.188 -191.262 180)
		(property "Reference" "R4654"
			(at 0 0 180)
			(layer "F.SilkS")
			(hide yes)
			(effects
				(font
					(size 1.27 1.27)
				)
			)
		)
		(property "Value" ""
			(at 0 0 180)
			(layer "F.Fab")
			(effects
				(font
					(size 1.27 1.27)
				)
			)
		)
		(duplicate_pad_numbers_are_jumpers no)
		(fp_line
			(start 0.7874 0.4064)
			(end -0.7874 0.4064)
			(stroke
				(width 0.1524)
				(type default)
			)
			(layer "F.SilkS")
		)
		(fp_line
			(start 0.7874 -0.4064)
			(end 0.7874 0.4064)
			(stroke
				(width 0.1524)
				(type default)
			)
			(layer "F.SilkS")
		)
		(fp_line
			(start -0.7874 0.4064)
			(end -0.7874 -0.4064)
			(stroke
				(width 0.1524)
				(type default)
			)
			(layer "F.SilkS")
		)
		(fp_line
			(start -0.7874 -0.4064)
			(end 0.7874 -0.4064)
			(stroke
				(width 0.1524)
				(type default)
			)
			(layer "F.SilkS")
		)
		(fp_line
			(start 0.67945 0.3048)
			(end 0.120396 0.3048)
			(stroke
				(width 0.1)
				(type default)
			)
			(layer "F.Fab")
		)
		(fp_line
			(start 0.67945 -0.3048)
			(end 0.67945 0.3048)
			(stroke
				(width 0.1)
				(type default)
			)
			(layer "F.Fab")
		)
		(fp_line
			(start 0.12065 -0.2794)
			(end 0.12065 -0.3048)
			(stroke
				(width 0.1)
				(type default)
			)
			(layer "F.Fab")
		)
		(fp_line
			(start 0.12065 -0.3048)
			(end 0.67945 -0.3048)
			(stroke
				(width 0.1)
				(type default)
			)
			(layer "F.Fab")
		)
		(fp_line
			(start 0.120396 0.3048)
			(end 0.120396 0.2794)
			(stroke
				(width 0.1)
				(type default)
			)
			(layer "F.Fab")
		)
		(fp_line
			(start 0.120396 0.2794)
			(end -0.12065 0.2794)
			(stroke
				(width 0.1)
				(type default)
			)
			(layer "F.Fab")
		)
		(fp_line
			(start -0.12065 0.3048)
			(end -0.67945 0.3048)
			(stroke
				(width 0.1)
				(type default)
			)
			(layer "F.Fab")
		)
		(fp_line
			(start -0.12065 0.2794)
			(end -0.12065 0.3048)
			(stroke
				(width 0.1)
				(type default)
			)
			(layer "F.Fab")
		)
		(fp_line
			(start -0.12065 -0.2794)
			(end 0.12065 -0.2794)
			(stroke
				(width 0.1)
				(type default)
			)
			(layer "F.Fab")
		)
		(fp_line
			(start -0.12065 -0.305054)
			(end -0.12065 -0.2794)
			(stroke
				(width 0.1)
				(type default)
			)
			(layer "F.Fab")
		)
		(fp_line
			(start -0.67945 0.3048)
			(end -0.67945 -0.305054)
			(stroke
				(width 0.1)
				(type default)
			)
			(layer "F.Fab")
		)
		(fp_line
			(start -0.67945 -0.305054)
			(end -0.12065 -0.305054)
			(stroke
				(width 0.1)
				(type default)
			)
			(layer "F.Fab")
		)
		(pad "1" smd circle
			(at -0.40005 0 180)
			(size 0 0)
			(layers "F.Cu" "F.Mask" "F.Paste")
			(net "GND")
		)
		(pad "2" smd circle
			(at 0.40005 0 180)
			(size 0 0)
			(layers "F.Cu" "F.Mask" "F.Paste")
			(net "PCA9555_1_PEX0_A2")
		)
	)
	(footprint ""
		(layer "F.Cu")
		(at 278.112982 -356.244906 90)
		(property "Reference" "C604"
			(at 0 0 90)
			(layer "F.SilkS")
			(hide yes)
			(effects
				(font
					(size 1.27 1.27)
				)
			)
		)
		(property "Value" ""
			(at 0 0 90)
			(layer "F.Fab")
			(effects
				(font
					(size 1.27 1.27)
				)
			)
		)
		(duplicate_pad_numbers_are_jumpers no)
		(fp_line
			(start 0.299974 -0.150114)
			(end 0.299974 0.150114)
			(stroke
				(width 0.1)
				(type default)
			)
			(layer "F.Fab")
		)
		(fp_line
			(start -0.299974 -0.150114)
			(end 0.299974 -0.150114)
			(stroke
				(width 0.1)
				(type default)
			)
			(layer "F.Fab")
		)
		(fp_line
			(start 0.299974 0.150114)
			(end -0.299974 0.150114)
			(stroke
				(width 0.1)
				(type default)
			)
			(layer "F.Fab")
		)
		(fp_line
			(start -0.299974 0.150114)
			(end -0.299974 -0.150114)
			(stroke
				(width 0.1)
				(type default)
			)
			(layer "F.Fab")
		)
		(pad "1" smd rect
			(at -0.2667 0 90)
			(size 0.3048 0.381)
			(layers "F.Cu" "F.Mask" "F.Paste")
			(net "P5E_PEX2_STN7_TX_DN<117>")
		)
		(pad "2" smd rect
			(at 0.2667 0 90)
			(size 0.3048 0.381)
			(layers "F.Cu" "F.Mask" "F.Paste")
			(net "P5E_PEX2_STN7_TX_C_DN<117>")
		)
	)
	(footprint ""
		(layer "F.Cu")
		(at 254.339598 -213.934294)
		(property "Reference" "U342"
			(at -1.152398 2.810764 0)
			(unlocked yes)
			(layer "F.SilkS")
			(effects
				(font
					(size 0.7874 0.5842)
					(thickness 0.1524)
				)
				(justify left)
			)
		)
		(property "Value" ""
			(at 0 0 0)
			(layer "F.Fab")
			(effects
				(font
					(size 1.27 1.27)
				)
			)
		)
		(duplicate_pad_numbers_are_jumpers no)
		(fp_line
			(start -1.525016 -1.525016)
			(end -1.525016 -1.3208)
			(stroke
				(width 0.1524)
				(type default)
			)
			(layer "F.SilkS")
		)
		(fp_line
			(start -1.525016 1.3208)
			(end -1.525016 1.525016)
			(stroke
				(width 0.1524)
				(type default)
			)
			(layer "F.SilkS")
		)
		(fp_line
			(start -1.525016 1.525016)
			(end -0.889 1.525016)
			(stroke
				(width 0.1524)
				(type default)
			)
			(layer "F.SilkS")
		)
		(fp_line
			(start -0.8636 -1.525016)
			(end -1.525016 -1.525016)
			(stroke
				(width 0.1524)
				(type default)
			)
			(layer "F.SilkS")
		)
		(fp_line
			(start 0.9906 1.525016)
			(end 1.525016 1.525016)
			(stroke
				(width 0.1524)
				(type default)
			)
			(layer "F.SilkS")
		)
		(fp_line
			(start 1.525016 -1.525016)
			(end -1.525016 -1.525016)
			(stroke
				(width 0.1524)
				(type default)
			)
			(layer "F.SilkS")
		)
		(fp_line
			(start 1.525016 -1.525016)
			(end 0.9398 -1.525016)
			(stroke
				(width 0.1524)
				(type default)
			)
			(layer "F.SilkS")
		)
		(fp_line
			(start 1.525016 -1.3208)
			(end 1.525016 -1.525016)
			(stroke
				(width 0.1524)
				(type default)
			)
			(layer "F.SilkS")
		)
		(fp_line
			(start 1.525016 1.525016)
			(end -1.525016 1.525016)
			(stroke
				(width 0.1524)
				(type default)
			)
			(layer "F.SilkS")
		)
		(fp_line
			(start 1.525016 1.525016)
			(end 1.525016 1.3208)
			(stroke
				(width 0.1524)
				(type default)
			)
			(layer "F.SilkS")
		)
		(fp_poly
			(pts
				(xy -1.522222 -1.738122) (xy -1.222248 -2.638298) (xy -1.822196 -2.638298)
			)
			(stroke
				(width 0)
				(type default)
			)
			(fill yes)
			(layer "F.SilkS")
		)
		(fp_line
			(start -1.525016 -1.525016)
			(end 1.525016 -1.525016)
			(stroke
				(width 0.1)
				(type default)
			)
			(layer "F.Fab")
		)
		(fp_line
			(start -1.525016 1.525016)
			(end -1.525016 -1.525016)
			(stroke
				(width 0.1)
				(type default)
			)
			(layer "F.Fab")
		)
		(fp_line
			(start 1.525016 -1.525016)
			(end 1.525016 1.525016)
			(stroke
				(width 0.1)
				(type default)
			)
			(layer "F.Fab")
		)
		(fp_line
			(start 1.525016 1.525016)
			(end -1.525016 1.525016)
			(stroke
				(width 0.1)
				(type default)
			)
			(layer "F.Fab")
		)
		(fp_poly
			(pts
				(xy -2.0701 -0.999998) (xy -2.977896 -1.302512) (xy -2.977896 -0.697484)
			)
			(stroke
				(width 0)
				(type default)
			)
			(fill yes)
			(layer "F.Fab")
		)
		(pad "1" smd rect
			(at -1.550162 -0.999998 270)
			(size 0.2794 0.9144)
			(layers "F.Cu" "F.Mask" "F.Paste")
			(net "P1V2_AUX")
		)
		(pad "2" smd rect
			(at -1.550162 -0.500126 270)
			(size 0.2794 0.9144)
			(layers "F.Cu" "F.Mask" "F.Paste")
			(net "P1V2_AUX")
		)
		(pad "3" smd rect
			(at -1.550162 0 270)
			(size 0.2794 0.9144)
			(layers "F.Cu" "F.Mask" "F.Paste")
			(net "P1V2_AUX")
		)
		(pad "4" smd rect
			(at -1.550162 0.500126 270)
			(size 0.2794 0.9144)
			(layers "F.Cu" "F.Mask" "F.Paste")
			(net "P1V2_AUX_ADJ")
		)
		(pad "5" smd rect
			(at -1.550162 0.999998 90)
			(size 0.2794 0.9144)
			(layers "F.Cu" "F.Mask" "F.Paste")
			(net "PWRGD_P1V2_AUX")
		)
		(pad "6" smd rect
			(at 1.550162 0.999998 90)
			(size 0.2794 0.9144)
			(layers "F.Cu" "F.Mask" "F.Paste")
			(net "PWR_EN_P1V2_AUX_R")
		)
		(pad "7" smd rect
			(at 1.550162 0.500126 270)
			(size 0.2794 0.9144)
			(layers "F.Cu" "F.Mask" "F.Paste")
			(net "P3V3_AUX")
		)
		(pad "8" smd rect
			(at 1.550162 0 270)
			(size 0.2794 0.9144)
			(layers "F.Cu" "F.Mask" "F.Paste")
			(net "P3V3_AUX")
		)
		(pad "9" smd rect
			(at 1.550162 -0.500126 270)
			(size 0.2794 0.9144)
			(layers "F.Cu" "F.Mask" "F.Paste")
			(net "P3V3_AUX")
		)
		(pad "10" smd rect
			(at 1.550162 -0.999998 270)
			(size 0.2794 0.9144)
			(layers "F.Cu" "F.Mask" "F.Paste")
			(net "P5V_AUX")
		)
		(pad "TH" smd rect
			(at 0 0)
			(size 1.7526 2.667)
			(layers "F.Cu" "F.Mask" "F.Paste")
			(net "GND")
		)
	)
	(footprint ""
		(layer "F.Cu")
		(at 338.492592 -7.742682)
		(property "Reference" "R1714"
			(at 0 0 0)
			(layer "F.SilkS")
			(hide yes)
			(effects
				(font
					(size 1.27 1.27)
				)
			)
		)
		(property "Value" ""
			(at 0 0 0)
			(layer "F.Fab")
			(effects
				(font
					(size 1.27 1.27)
				)
			)
		)
		(duplicate_pad_numbers_are_jumpers no)
		(fp_line
			(start -0.7874 -0.4064)
			(end 0.7874 -0.4064)
			(stroke
				(width 0.1524)
				(type default)
			)
			(layer "F.SilkS")
		)
		(fp_line
			(start -0.7874 0.4064)
			(end -0.7874 -0.4064)
			(stroke
				(width 0.1524)
				(type default)
			)
			(layer "F.SilkS")
		)
		(fp_line
			(start 0.7874 -0.4064)
			(end 0.7874 0.4064)
			(stroke
				(width 0.1524)
				(type default)
			)
			(layer "F.SilkS")
		)
		(fp_line
			(start 0.7874 0.4064)
			(end -0.7874 0.4064)
			(stroke
				(width 0.1524)
				(type default)
			)
			(layer "F.SilkS")
		)
		(fp_line
			(start -0.67945 -0.305054)
			(end -0.12065 -0.305054)
			(stroke
				(width 0.1)
				(type default)
			)
			(layer "F.Fab")
		)
		(fp_line
			(start -0.67945 0.3048)
			(end -0.67945 -0.305054)
			(stroke
				(width 0.1)
				(type default)
			)
			(layer "F.Fab")
		)
		(fp_line
			(start -0.12065 -0.305054)
			(end -0.12065 -0.2794)
			(stroke
				(width 0.1)
				(type default)
			)
			(layer "F.Fab")
		)
		(fp_line
			(start -0.12065 -0.2794)
			(end 0.12065 -0.2794)
			(stroke
				(width 0.1)
				(type default)
			)
			(layer "F.Fab")
		)
		(fp_line
			(start -0.12065 0.2794)
			(end -0.12065 0.3048)
			(stroke
				(width 0.1)
				(type default)
			)
			(layer "F.Fab")
		)
		(fp_line
			(start -0.12065 0.3048)
			(end -0.67945 0.3048)
			(stroke
				(width 0.1)
				(type default)
			)
			(layer "F.Fab")
		)
		(fp_line
			(start 0.120396 0.2794)
			(end -0.12065 0.2794)
			(stroke
				(width 0.1)
				(type default)
			)
			(layer "F.Fab")
		)
		(fp_line
			(start 0.120396 0.3048)
			(end 0.120396 0.2794)
			(stroke
				(width 0.1)
				(type default)
			)
			(layer "F.Fab")
		)
		(fp_line
			(start 0.12065 -0.3048)
			(end 0.67945 -0.3048)
			(stroke
				(width 0.1)
				(type default)
			)
			(layer "F.Fab")
		)
		(fp_line
			(start 0.12065 -0.2794)
			(end 0.12065 -0.3048)
			(stroke
				(width 0.1)
				(type default)
			)
			(layer "F.Fab")
		)
		(fp_line
			(start 0.67945 -0.3048)
			(end 0.67945 0.3048)
			(stroke
				(width 0.1)
				(type default)
			)
			(layer "F.Fab")
		)
		(fp_line
			(start 0.67945 0.3048)
			(end 0.120396 0.3048)
			(stroke
				(width 0.1)
				(type default)
			)
			(layer "F.Fab")
		)
		(pad "1" smd circle
			(at -0.40005 0)
			(size 0 0)
			(layers "F.Cu" "F.Mask" "F.Paste")
			(net "SMB_BIC_I2C9_MUX1_SSD11_R_SCL")
		)
		(pad "2" smd circle
			(at 0.40005 0)
			(size 0 0)
			(layers "F.Cu" "F.Mask" "F.Paste")
			(net "SMB_ISO_SSD11_SCL")
		)
	)
	(footprint ""
		(layer "F.Cu")
		(at 284.443678 -48.93691 180)
		(property "Reference" "R611"
			(at 0 0 180)
			(layer "F.SilkS")
			(hide yes)
			(effects
				(font
					(size 1.27 1.27)
				)
			)
		)
		(property "Value" ""
			(at 0 0 180)
			(layer "F.Fab")
			(effects
				(font
					(size 1.27 1.27)
				)
			)
		)
		(duplicate_pad_numbers_are_jumpers no)
		(fp_line
			(start 0.7874 0.4064)
			(end -0.7874 0.4064)
			(stroke
				(width 0.1524)
				(type default)
			)
			(layer "F.SilkS")
		)
		(fp_line
			(start 0.7874 -0.4064)
			(end 0.7874 0.4064)
			(stroke
				(width 0.1524)
				(type default)
			)
			(layer "F.SilkS")
		)
		(fp_line
			(start -0.7874 0.4064)
			(end -0.7874 -0.4064)
			(stroke
				(width 0.1524)
				(type default)
			)
			(layer "F.SilkS")
		)
		(fp_line
			(start -0.7874 -0.4064)
			(end 0.7874 -0.4064)
			(stroke
				(width 0.1524)
				(type default)
			)
			(layer "F.SilkS")
		)
		(fp_line
			(start 0.67945 0.3048)
			(end 0.120396 0.3048)
			(stroke
				(width 0.1)
				(type default)
			)
			(layer "F.Fab")
		)
		(fp_line
			(start 0.67945 -0.3048)
			(end 0.67945 0.3048)
			(stroke
				(width 0.1)
				(type default)
			)
			(layer "F.Fab")
		)
		(fp_line
			(start 0.12065 -0.2794)
			(end 0.12065 -0.3048)
			(stroke
				(width 0.1)
				(type default)
			)
			(layer "F.Fab")
		)
		(fp_line
			(start 0.12065 -0.3048)
			(end 0.67945 -0.3048)
			(stroke
				(width 0.1)
				(type default)
			)
			(layer "F.Fab")
		)
		(fp_line
			(start 0.120396 0.3048)
			(end 0.120396 0.2794)
			(stroke
				(width 0.1)
				(type default)
			)
			(layer "F.Fab")
		)
		(fp_line
			(start 0.120396 0.2794)
			(end -0.12065 0.2794)
			(stroke
				(width 0.1)
				(type default)
			)
			(layer "F.Fab")
		)
		(fp_line
			(start -0.12065 0.3048)
			(end -0.67945 0.3048)
			(stroke
				(width 0.1)
				(type default)
			)
			(layer "F.Fab")
		)
		(fp_line
			(start -0.12065 0.2794)
			(end -0.12065 0.3048)
			(stroke
				(width 0.1)
				(type default)
			)
			(layer "F.Fab")
		)
		(fp_line
			(start -0.12065 -0.2794)
			(end 0.12065 -0.2794)
			(stroke
				(width 0.1)
				(type default)
			)
			(layer "F.Fab")
		)
		(fp_line
			(start -0.12065 -0.305054)
			(end -0.12065 -0.2794)
			(stroke
				(width 0.1)
				(type default)
			)
			(layer "F.Fab")
		)
		(fp_line
			(start -0.67945 0.3048)
			(end -0.67945 -0.305054)
			(stroke
				(width 0.1)
				(type default)
			)
			(layer "F.Fab")
		)
		(fp_line
			(start -0.67945 -0.305054)
			(end -0.12065 -0.305054)
			(stroke
				(width 0.1)
				(type default)
			)
			(layer "F.Fab")
		)
		(pad "1" smd circle
			(at -0.40005 0 180)
			(size 0 0)
			(layers "F.Cu" "F.Mask" "F.Paste")
			(net "SMB_BIC_I2C6_MUX_SSD_8_15_ADC_R_SDA")
		)
		(pad "2" smd circle
			(at 0.40005 0 180)
			(size 0 0)
			(layers "F.Cu" "F.Mask" "F.Paste")
			(net "SMB_SSD9_ADC_SDA")
		)
	)
	(footprint ""
		(layer "F.Cu")
		(at 260.249162 -284.195012 -90)
		(property "Reference" "C3384"
			(at 0 0 270)
			(layer "F.SilkS")
			(hide yes)
			(effects
				(font
					(size 1.27 1.27)
				)
			)
		)
		(property "Value" ""
			(at 0 0 270)
			(layer "F.Fab")
			(effects
				(font
					(size 1.27 1.27)
				)
			)
		)
		(duplicate_pad_numbers_are_jumpers no)
		(fp_line
			(start -0.299974 0.150114)
			(end -0.299974 -0.150114)
			(stroke
				(width 0.1)
				(type default)
			)
			(layer "F.Fab")
		)
		(fp_line
			(start 0.299974 0.150114)
			(end -0.299974 0.150114)
			(stroke
				(width 0.1)
				(type default)
			)
			(layer "F.Fab")
		)
		(fp_line
			(start -0.299974 -0.150114)
			(end 0.299974 -0.150114)
			(stroke
				(width 0.1)
				(type default)
			)
			(layer "F.Fab")
		)
		(fp_line
			(start 0.299974 -0.150114)
			(end 0.299974 0.150114)
			(stroke
				(width 0.1)
				(type default)
			)
			(layer "F.Fab")
		)
		(pad "1" smd rect
			(at -0.2667 0 270)
			(size 0.3048 0.381)
			(layers "F.Cu" "F.Mask" "F.Paste")
			(net "P1V8_PLL0_PEX2")
		)
		(pad "2" smd rect
			(at 0.2667 0 270)
			(size 0.3048 0.381)
			(layers "F.Cu" "F.Mask" "F.Paste")
			(net "GND")
		)
	)
	(footprint ""
		(layer "F.Cu")
		(at 350.774 -205.232 90)
		(property "Reference" "R4153"
			(at 0 0 90)
			(layer "F.SilkS")
			(hide yes)
			(effects
				(font
					(size 1.27 1.27)
				)
			)
		)
		(property "Value" ""
			(at 0 0 90)
			(layer "F.Fab")
			(effects
				(font
					(size 1.27 1.27)
				)
			)
		)
		(duplicate_pad_numbers_are_jumpers no)
		(fp_line
			(start 0.7874 -0.4064)
			(end 0.7874 0.4064)
			(stroke
				(width 0.1524)
				(type default)
			)
			(layer "F.SilkS")
		)
		(fp_line
			(start -0.7874 -0.4064)
			(end 0.7874 -0.4064)
			(stroke
				(width 0.1524)
				(type default)
			)
			(layer "F.SilkS")
		)
		(fp_line
			(start 0.7874 0.4064)
			(end -0.7874 0.4064)
			(stroke
				(width 0.1524)
				(type default)
			)
			(layer "F.SilkS")
		)
		(fp_line
			(start -0.7874 0.4064)
			(end -0.7874 -0.4064)
			(stroke
				(width 0.1524)
				(type default)
			)
			(layer "F.SilkS")
		)
		(fp_line
			(start -0.12065 -0.305054)
			(end -0.12065 -0.2794)
			(stroke
				(width 0.1)
				(type default)
			)
			(layer "F.Fab")
		)
		(fp_line
			(start -0.67945 -0.305054)
			(end -0.12065 -0.305054)
			(stroke
				(width 0.1)
				(type default)
			)
			(layer "F.Fab")
		)
		(fp_line
			(start 0.67945 -0.3048)
			(end 0.67945 0.3048)
			(stroke
				(width 0.1)
				(type default)
			)
			(layer "F.Fab")
		)
		(fp_line
			(start 0.12065 -0.3048)
			(end 0.67945 -0.3048)
			(stroke
				(width 0.1)
				(type default)
			)
			(layer "F.Fab")
		)
		(fp_line
			(start 0.12065 -0.2794)
			(end 0.12065 -0.3048)
			(stroke
				(width 0.1)
				(type default)
			)
			(layer "F.Fab")
		)
		(fp_line
			(start -0.12065 -0.2794)
			(end 0.12065 -0.2794)
			(stroke
				(width 0.1)
				(type default)
			)
			(layer "F.Fab")
		)
		(fp_line
			(start 0.120396 0.2794)
			(end -0.12065 0.2794)
			(stroke
				(width 0.1)
				(type default)
			)
			(layer "F.Fab")
		)
		(fp_line
			(start -0.12065 0.2794)
			(end -0.12065 0.3048)
			(stroke
				(width 0.1)
				(type default)
			)
			(layer "F.Fab")
		)
		(fp_line
			(start 0.67945 0.3048)
			(end 0.120396 0.3048)
			(stroke
				(width 0.1)
				(type default)
			)
			(layer "F.Fab")
		)
		(fp_line
			(start 0.120396 0.3048)
			(end 0.120396 0.2794)
			(stroke
				(width 0.1)
				(type default)
			)
			(layer "F.Fab")
		)
		(fp_line
			(start -0.12065 0.3048)
			(end -0.67945 0.3048)
			(stroke
				(width 0.1)
				(type default)
			)
			(layer "F.Fab")
		)
		(fp_line
			(start -0.67945 0.3048)
			(end -0.67945 -0.305054)
			(stroke
				(width 0.1)
				(type default)
			)
			(layer "F.Fab")
		)
		(pad "1" smd circle
			(at -0.40005 0 90)
			(size 0 0)
			(layers "F.Cu" "F.Mask" "F.Paste")
			(net "PRSNT_SSD6_FPGA_R_N")
		)
		(pad "2" smd circle
			(at 0.40005 0 90)
			(size 0 0)
			(layers "F.Cu" "F.Mask" "F.Paste")
			(net "PRSNT_SSD6_FPGA_N")
		)
	)
	(footprint ""
		(layer "F.Cu")
		(at 394.973048 -22.867366 90)
		(property "Reference" "C3963"
			(at 0 0 90)
			(layer "F.SilkS")
			(hide yes)
			(effects
				(font
					(size 1.27 1.27)
				)
			)
		)
		(property "Value" ""
			(at 0 0 90)
			(layer "F.Fab")
			(effects
				(font
					(size 1.27 1.27)
				)
			)
		)
		(duplicate_pad_numbers_are_jumpers no)
		(fp_line
			(start 0.7874 -0.4064)
			(end 0.7874 0.4064)
			(stroke
				(width 0.1524)
				(type default)
			)
			(layer "F.SilkS")
		)
		(fp_line
			(start -0.7874 -0.4064)
			(end 0.7874 -0.4064)
			(stroke
				(width 0.1524)
				(type default)
			)
			(layer "F.SilkS")
		)
		(fp_line
			(start 0.7874 0.4064)
			(end -0.7874 0.4064)
			(stroke
				(width 0.1524)
				(type default)
			)
			(layer "F.SilkS")
		)
		(fp_line
			(start -0.7874 0.4064)
			(end -0.7874 -0.4064)
			(stroke
				(width 0.1524)
				(type default)
			)
			(layer "F.SilkS")
		)
		(fp_line
			(start -0.12065 -0.305054)
			(end -0.12065 -0.2794)
			(stroke
				(width 0.1)
				(type default)
			)
			(layer "F.Fab")
		)
		(fp_line
			(start -0.67945 -0.305054)
			(end -0.12065 -0.305054)
			(stroke
				(width 0.1)
				(type default)
			)
			(layer "F.Fab")
		)
		(fp_line
			(start 0.67945 -0.3048)
			(end 0.67945 0.3048)
			(stroke
				(width 0.1)
				(type default)
			)
			(layer "F.Fab")
		)
		(fp_line
			(start 0.12065 -0.3048)
			(end 0.67945 -0.3048)
			(stroke
				(width 0.1)
				(type default)
			)
			(layer "F.Fab")
		)
		(fp_line
			(start 0.12065 -0.2794)
			(end 0.12065 -0.3048)
			(stroke
				(width 0.1)
				(type default)
			)
			(layer "F.Fab")
		)
		(fp_line
			(start -0.12065 -0.2794)
			(end 0.12065 -0.2794)
			(stroke
				(width 0.1)
				(type default)
			)
			(layer "F.Fab")
		)
		(fp_line
			(start 0.120396 0.2794)
			(end -0.12065 0.2794)
			(stroke
				(width 0.1)
				(type default)
			)
			(layer "F.Fab")
		)
		(fp_line
			(start -0.12065 0.2794)
			(end -0.12065 0.3048)
			(stroke
				(width 0.1)
				(type default)
			)
			(layer "F.Fab")
		)
		(fp_line
			(start 0.67945 0.3048)
			(end 0.120396 0.3048)
			(stroke
				(width 0.1)
				(type default)
			)
			(layer "F.Fab")
		)
		(fp_line
			(start 0.120396 0.3048)
			(end 0.120396 0.2794)
			(stroke
				(width 0.1)
				(type default)
			)
			(layer "F.Fab")
		)
		(fp_line
			(start -0.12065 0.3048)
			(end -0.67945 0.3048)
			(stroke
				(width 0.1)
				(type default)
			)
			(layer "F.Fab")
		)
		(fp_line
			(start -0.67945 0.3048)
			(end -0.67945 -0.305054)
			(stroke
				(width 0.1)
				(type default)
			)
			(layer "F.Fab")
		)
		(pad "1" smd circle
			(at -0.40005 0 90)
			(size 0 0)
			(layers "F.Cu" "F.Mask" "F.Paste")
			(net "P12V_SSD13")
		)
		(pad "2" smd circle
			(at 0.40005 0 90)
			(size 0 0)
			(layers "F.Cu" "F.Mask" "F.Paste")
			(net "GND")
		)
	)
	(footprint ""
		(layer "F.Cu")
		(at 237.903512 -231.416606 90)
		(property "Reference" "R4519"
			(at 0 0 90)
			(layer "F.SilkS")
			(hide yes)
			(effects
				(font
					(size 1.27 1.27)
				)
			)
		)
		(property "Value" ""
			(at 0 0 90)
			(layer "F.Fab")
			(effects
				(font
					(size 1.27 1.27)
				)
			)
		)
		(duplicate_pad_numbers_are_jumpers no)
		(fp_line
			(start 0.7874 -0.4064)
			(end 0.7874 0.4064)
			(stroke
				(width 0.1524)
				(type default)
			)
			(layer "F.SilkS")
		)
		(fp_line
			(start -0.7874 -0.4064)
			(end 0.7874 -0.4064)
			(stroke
				(width 0.1524)
				(type default)
			)
			(layer "F.SilkS")
		)
		(fp_line
			(start 0.7874 0.4064)
			(end -0.7874 0.4064)
			(stroke
				(width 0.1524)
				(type default)
			)
			(layer "F.SilkS")
		)
		(fp_line
			(start -0.7874 0.4064)
			(end -0.7874 -0.4064)
			(stroke
				(width 0.1524)
				(type default)
			)
			(layer "F.SilkS")
		)
		(fp_line
			(start -0.12065 -0.305054)
			(end -0.12065 -0.2794)
			(stroke
				(width 0.1)
				(type default)
			)
			(layer "F.Fab")
		)
		(fp_line
			(start -0.67945 -0.305054)
			(end -0.12065 -0.305054)
			(stroke
				(width 0.1)
				(type default)
			)
			(layer "F.Fab")
		)
		(fp_line
			(start 0.67945 -0.3048)
			(end 0.67945 0.3048)
			(stroke
				(width 0.1)
				(type default)
			)
			(layer "F.Fab")
		)
		(fp_line
			(start 0.12065 -0.3048)
			(end 0.67945 -0.3048)
			(stroke
				(width 0.1)
				(type default)
			)
			(layer "F.Fab")
		)
		(fp_line
			(start 0.12065 -0.2794)
			(end 0.12065 -0.3048)
			(stroke
				(width 0.1)
				(type default)
			)
			(layer "F.Fab")
		)
		(fp_line
			(start -0.12065 -0.2794)
			(end 0.12065 -0.2794)
			(stroke
				(width 0.1)
				(type default)
			)
			(layer "F.Fab")
		)
		(fp_line
			(start 0.120396 0.2794)
			(end -0.12065 0.2794)
			(stroke
				(width 0.1)
				(type default)
			)
			(layer "F.Fab")
		)
		(fp_line
			(start -0.12065 0.2794)
			(end -0.12065 0.3048)
			(stroke
				(width 0.1)
				(type default)
			)
			(layer "F.Fab")
		)
		(fp_line
			(start 0.67945 0.3048)
			(end 0.120396 0.3048)
			(stroke
				(width 0.1)
				(type default)
			)
			(layer "F.Fab")
		)
		(fp_line
			(start 0.120396 0.3048)
			(end 0.120396 0.2794)
			(stroke
				(width 0.1)
				(type default)
			)
			(layer "F.Fab")
		)
		(fp_line
			(start -0.12065 0.3048)
			(end -0.67945 0.3048)
			(stroke
				(width 0.1)
				(type default)
			)
			(layer "F.Fab")
		)
		(fp_line
			(start -0.67945 0.3048)
			(end -0.67945 -0.305054)
			(stroke
				(width 0.1)
				(type default)
			)
			(layer "F.Fab")
		)
		(pad "1" smd circle
			(at -0.40005 0 90)
			(size 0 0)
			(layers "F.Cu" "F.Mask" "F.Paste")
			(net "SSD5_PWRDIS_BIC")
		)
		(pad "2" smd circle
			(at 0.40005 0 90)
			(size 0 0)
			(layers "F.Cu" "F.Mask" "F.Paste")
			(net "SSD5_PWRDIS_BIC_R")
		)
	)
	(footprint ""
		(layer "F.Cu")
		(at 317.30315 -59.571636 90)
		(property "Reference" "PR286"
			(at 0 0 90)
			(layer "F.SilkS")
			(hide yes)
			(effects
				(font
					(size 1.27 1.27)
				)
			)
		)
		(property "Value" ""
			(at 0 0 90)
			(layer "F.Fab")
			(effects
				(font
					(size 1.27 1.27)
				)
			)
		)
		(duplicate_pad_numbers_are_jumpers no)
		(fp_line
			(start 0.7874 -0.4064)
			(end 0.7874 0.4064)
			(stroke
				(width 0.1524)
				(type default)
			)
			(layer "F.SilkS")
		)
		(fp_line
			(start -0.7874 -0.4064)
			(end 0.7874 -0.4064)
			(stroke
				(width 0.1524)
				(type default)
			)
			(layer "F.SilkS")
		)
		(fp_line
			(start 0.7874 0.4064)
			(end -0.7874 0.4064)
			(stroke
				(width 0.1524)
				(type default)
			)
			(layer "F.SilkS")
		)
		(fp_line
			(start -0.7874 0.4064)
			(end -0.7874 -0.4064)
			(stroke
				(width 0.1524)
				(type default)
			)
			(layer "F.SilkS")
		)
		(fp_line
			(start -0.12065 -0.305054)
			(end -0.12065 -0.2794)
			(stroke
				(width 0.1)
				(type default)
			)
			(layer "F.Fab")
		)
		(fp_line
			(start -0.67945 -0.305054)
			(end -0.12065 -0.305054)
			(stroke
				(width 0.1)
				(type default)
			)
			(layer "F.Fab")
		)
		(fp_line
			(start 0.67945 -0.3048)
			(end 0.67945 0.3048)
			(stroke
				(width 0.1)
				(type default)
			)
			(layer "F.Fab")
		)
		(fp_line
			(start 0.12065 -0.3048)
			(end 0.67945 -0.3048)
			(stroke
				(width 0.1)
				(type default)
			)
			(layer "F.Fab")
		)
		(fp_line
			(start 0.12065 -0.2794)
			(end 0.12065 -0.3048)
			(stroke
				(width 0.1)
				(type default)
			)
			(layer "F.Fab")
		)
		(fp_line
			(start -0.12065 -0.2794)
			(end 0.12065 -0.2794)
			(stroke
				(width 0.1)
				(type default)
			)
			(layer "F.Fab")
		)
		(fp_line
			(start 0.120396 0.2794)
			(end -0.12065 0.2794)
			(stroke
				(width 0.1)
				(type default)
			)
			(layer "F.Fab")
		)
		(fp_line
			(start -0.12065 0.2794)
			(end -0.12065 0.3048)
			(stroke
				(width 0.1)
				(type default)
			)
			(layer "F.Fab")
		)
		(fp_line
			(start 0.67945 0.3048)
			(end 0.120396 0.3048)
			(stroke
				(width 0.1)
				(type default)
			)
			(layer "F.Fab")
		)
		(fp_line
			(start 0.120396 0.3048)
			(end 0.120396 0.2794)
			(stroke
				(width 0.1)
				(type default)
			)
			(layer "F.Fab")
		)
		(fp_line
			(start -0.12065 0.3048)
			(end -0.67945 0.3048)
			(stroke
				(width 0.1)
				(type default)
			)
			(layer "F.Fab")
		)
		(fp_line
			(start -0.67945 0.3048)
			(end -0.67945 -0.305054)
			(stroke
				(width 0.1)
				(type default)
			)
			(layer "F.Fab")
		)
		(pad "1" smd circle
			(at -0.40005 0 90)
			(size 0 0)
			(layers "F.Cu" "F.Mask" "F.Paste")
			(net "P3V3_SSD11_OCP")
		)
		(pad "2" smd circle
			(at 0.40005 0 90)
			(size 0 0)
			(layers "F.Cu" "F.Mask" "F.Paste")
			(net "GND")
		)
	)
	(footprint ""
		(layer "F.Cu")
		(at 356.420674 -26.666444 -90)
		(property "Reference" "R4077"
			(at 0 0 270)
			(layer "F.SilkS")
			(hide yes)
			(effects
				(font
					(size 1.27 1.27)
				)
			)
		)
		(property "Value" ""
			(at 0 0 270)
			(layer "F.Fab")
			(effects
				(font
					(size 1.27 1.27)
				)
			)
		)
		(duplicate_pad_numbers_are_jumpers no)
		(fp_line
			(start -0.7874 0.4064)
			(end -0.7874 -0.4064)
			(stroke
				(width 0.1524)
				(type default)
			)
			(layer "F.SilkS")
		)
		(fp_line
			(start 0.7874 0.4064)
			(end -0.7874 0.4064)
			(stroke
				(width 0.1524)
				(type default)
			)
			(layer "F.SilkS")
		)
		(fp_line
			(start -0.7874 -0.4064)
			(end 0.7874 -0.4064)
			(stroke
				(width 0.1524)
				(type default)
			)
			(layer "F.SilkS")
		)
		(fp_line
			(start 0.7874 -0.4064)
			(end 0.7874 0.4064)
			(stroke
				(width 0.1524)
				(type default)
			)
			(layer "F.SilkS")
		)
		(fp_line
			(start -0.67945 0.3048)
			(end -0.67945 -0.305054)
			(stroke
				(width 0.1)
				(type default)
			)
			(layer "F.Fab")
		)
		(fp_line
			(start -0.12065 0.3048)
			(end -0.67945 0.3048)
			(stroke
				(width 0.1)
				(type default)
			)
			(layer "F.Fab")
		)
		(fp_line
			(start 0.120396 0.3048)
			(end 0.120396 0.2794)
			(stroke
				(width 0.1)
				(type default)
			)
			(layer "F.Fab")
		)
		(fp_line
			(start 0.67945 0.3048)
			(end 0.120396 0.3048)
			(stroke
				(width 0.1)
				(type default)
			)
			(layer "F.Fab")
		)
		(fp_line
			(start -0.12065 0.2794)
			(end -0.12065 0.3048)
			(stroke
				(width 0.1)
				(type default)
			)
			(layer "F.Fab")
		)
		(fp_line
			(start 0.120396 0.2794)
			(end -0.12065 0.2794)
			(stroke
				(width 0.1)
				(type default)
			)
			(layer "F.Fab")
		)
		(fp_line
			(start -0.12065 -0.2794)
			(end 0.12065 -0.2794)
			(stroke
				(width 0.1)
				(type default)
			)
			(layer "F.Fab")
		)
		(fp_line
			(start 0.12065 -0.2794)
			(end 0.12065 -0.3048)
			(stroke
				(width 0.1)
				(type default)
			)
			(layer "F.Fab")
		)
		(fp_line
			(start 0.12065 -0.3048)
			(end 0.67945 -0.3048)
			(stroke
				(width 0.1)
				(type default)
			)
			(layer "F.Fab")
		)
		(fp_line
			(start 0.67945 -0.3048)
			(end 0.67945 0.3048)
			(stroke
				(width 0.1)
				(type default)
			)
			(layer "F.Fab")
		)
		(fp_line
			(start -0.67945 -0.305054)
			(end -0.12065 -0.305054)
			(stroke
				(width 0.1)
				(type default)
			)
			(layer "F.Fab")
		)
		(fp_line
			(start -0.12065 -0.305054)
			(end -0.12065 -0.2794)
			(stroke
				(width 0.1)
				(type default)
			)
			(layer "F.Fab")
		)
		(pad "1" smd circle
			(at -0.40005 0 270)
			(size 0 0)
			(layers "F.Cu" "F.Mask" "F.Paste")
			(net "PRSNT_SSD12_R_N")
		)
		(pad "2" smd circle
			(at 0.40005 0 270)
			(size 0 0)
			(layers "F.Cu" "F.Mask" "F.Paste")
			(net "PRSNT_SSD12_N")
		)
	)
	(footprint ""
		(layer "F.Cu")
		(at 395.830552 -66.32194 -90)
		(property "Reference" "PC887"
			(at 0 0 270)
			(layer "F.SilkS")
			(hide yes)
			(effects
				(font
					(size 1.27 1.27)
				)
			)
		)
		(property "Value" ""
			(at 0 0 270)
			(layer "F.Fab")
			(effects
				(font
					(size 1.27 1.27)
				)
			)
		)
		(duplicate_pad_numbers_are_jumpers no)
		(fp_line
			(start -0.7874 0.4064)
			(end -0.7874 -0.4064)
			(stroke
				(width 0.1524)
				(type default)
			)
			(layer "F.SilkS")
		)
		(fp_line
			(start 0.7874 0.4064)
			(end -0.7874 0.4064)
			(stroke
				(width 0.1524)
				(type default)
			)
			(layer "F.SilkS")
		)
		(fp_line
			(start -0.7874 -0.4064)
			(end 0.7874 -0.4064)
			(stroke
				(width 0.1524)
				(type default)
			)
			(layer "F.SilkS")
		)
		(fp_line
			(start 0.7874 -0.4064)
			(end 0.7874 0.4064)
			(stroke
				(width 0.1524)
				(type default)
			)
			(layer "F.SilkS")
		)
		(fp_line
			(start -0.67945 0.3048)
			(end -0.67945 -0.305054)
			(stroke
				(width 0.1)
				(type default)
			)
			(layer "F.Fab")
		)
		(fp_line
			(start -0.12065 0.3048)
			(end -0.67945 0.3048)
			(stroke
				(width 0.1)
				(type default)
			)
			(layer "F.Fab")
		)
		(fp_line
			(start 0.120396 0.3048)
			(end 0.120396 0.2794)
			(stroke
				(width 0.1)
				(type default)
			)
			(layer "F.Fab")
		)
		(fp_line
			(start 0.67945 0.3048)
			(end 0.120396 0.3048)
			(stroke
				(width 0.1)
				(type default)
			)
			(layer "F.Fab")
		)
		(fp_line
			(start -0.12065 0.2794)
			(end -0.12065 0.3048)
			(stroke
				(width 0.1)
				(type default)
			)
			(layer "F.Fab")
		)
		(fp_line
			(start 0.120396 0.2794)
			(end -0.12065 0.2794)
			(stroke
				(width 0.1)
				(type default)
			)
			(layer "F.Fab")
		)
		(fp_line
			(start -0.12065 -0.2794)
			(end 0.12065 -0.2794)
			(stroke
				(width 0.1)
				(type default)
			)
			(layer "F.Fab")
		)
		(fp_line
			(start 0.12065 -0.2794)
			(end 0.12065 -0.3048)
			(stroke
				(width 0.1)
				(type default)
			)
			(layer "F.Fab")
		)
		(fp_line
			(start 0.12065 -0.3048)
			(end 0.67945 -0.3048)
			(stroke
				(width 0.1)
				(type default)
			)
			(layer "F.Fab")
		)
		(fp_line
			(start 0.67945 -0.3048)
			(end 0.67945 0.3048)
			(stroke
				(width 0.1)
				(type default)
			)
			(layer "F.Fab")
		)
		(fp_line
			(start -0.67945 -0.305054)
			(end -0.12065 -0.305054)
			(stroke
				(width 0.1)
				(type default)
			)
			(layer "F.Fab")
		)
		(fp_line
			(start -0.12065 -0.305054)
			(end -0.12065 -0.2794)
			(stroke
				(width 0.1)
				(type default)
			)
			(layer "F.Fab")
		)
		(pad "1" smd circle
			(at -0.40005 0 270)
			(size 0 0)
			(layers "F.Cu" "F.Mask" "F.Paste")
			(net "P12V_SSD13_CO_DV_DT")
		)
		(pad "2" smd circle
			(at 0.40005 0 270)
			(size 0 0)
			(layers "F.Cu" "F.Mask" "F.Paste")
			(net "GND")
		)
	)
	(footprint ""
		(layer "F.Cu")
		(at 266.378944 -59.577986 -90)
		(property "Reference" "R896"
			(at 0 0 270)
			(layer "F.SilkS")
			(hide yes)
			(effects
				(font
					(size 1.27 1.27)
				)
			)
		)
		(property "Value" ""
			(at 0 0 270)
			(layer "F.Fab")
			(effects
				(font
					(size 1.27 1.27)
				)
			)
		)
		(duplicate_pad_numbers_are_jumpers no)
		(fp_line
			(start -0.7874 0.4064)
			(end -0.7874 -0.4064)
			(stroke
				(width 0.1524)
				(type default)
			)
			(layer "F.SilkS")
		)
		(fp_line
			(start 0.7874 0.4064)
			(end -0.7874 0.4064)
			(stroke
				(width 0.1524)
				(type default)
			)
			(layer "F.SilkS")
		)
		(fp_line
			(start -0.7874 -0.4064)
			(end 0.7874 -0.4064)
			(stroke
				(width 0.1524)
				(type default)
			)
			(layer "F.SilkS")
		)
		(fp_line
			(start 0.7874 -0.4064)
			(end 0.7874 0.4064)
			(stroke
				(width 0.1524)
				(type default)
			)
			(layer "F.SilkS")
		)
		(fp_line
			(start -0.67945 0.3048)
			(end -0.67945 -0.305054)
			(stroke
				(width 0.1)
				(type default)
			)
			(layer "F.Fab")
		)
		(fp_line
			(start -0.12065 0.3048)
			(end -0.67945 0.3048)
			(stroke
				(width 0.1)
				(type default)
			)
			(layer "F.Fab")
		)
		(fp_line
			(start 0.120396 0.3048)
			(end 0.120396 0.2794)
			(stroke
				(width 0.1)
				(type default)
			)
			(layer "F.Fab")
		)
		(fp_line
			(start 0.67945 0.3048)
			(end 0.120396 0.3048)
			(stroke
				(width 0.1)
				(type default)
			)
			(layer "F.Fab")
		)
		(fp_line
			(start -0.12065 0.2794)
			(end -0.12065 0.3048)
			(stroke
				(width 0.1)
				(type default)
			)
			(layer "F.Fab")
		)
		(fp_line
			(start 0.120396 0.2794)
			(end -0.12065 0.2794)
			(stroke
				(width 0.1)
				(type default)
			)
			(layer "F.Fab")
		)
		(fp_line
			(start -0.12065 -0.2794)
			(end 0.12065 -0.2794)
			(stroke
				(width 0.1)
				(type default)
			)
			(layer "F.Fab")
		)
		(fp_line
			(start 0.12065 -0.2794)
			(end 0.12065 -0.3048)
			(stroke
				(width 0.1)
				(type default)
			)
			(layer "F.Fab")
		)
		(fp_line
			(start 0.12065 -0.3048)
			(end 0.67945 -0.3048)
			(stroke
				(width 0.1)
				(type default)
			)
			(layer "F.Fab")
		)
		(fp_line
			(start 0.67945 -0.3048)
			(end 0.67945 0.3048)
			(stroke
				(width 0.1)
				(type default)
			)
			(layer "F.Fab")
		)
		(fp_line
			(start -0.67945 -0.305054)
			(end -0.12065 -0.305054)
			(stroke
				(width 0.1)
				(type default)
			)
			(layer "F.Fab")
		)
		(fp_line
			(start -0.12065 -0.305054)
			(end -0.12065 -0.2794)
			(stroke
				(width 0.1)
				(type default)
			)
			(layer "F.Fab")
		)
		(pad "1" smd circle
			(at -0.40005 0 270)
			(size 0 0)
			(layers "F.Cu" "F.Mask" "F.Paste")
			(net "P3V3_SSD9")
		)
		(pad "2" smd circle
			(at 0.40005 0 270)
			(size 0 0)
			(layers "F.Cu" "F.Mask" "F.Paste")
			(net "PWRGD_P3V3_SSD9")
		)
	)
	(footprint ""
		(layer "F.Cu")
		(at 344.481404 -350.098614 90)
		(property "Reference" "C520"
			(at 0 0 90)
			(layer "F.SilkS")
			(hide yes)
			(effects
				(font
					(size 1.27 1.27)
				)
			)
		)
		(property "Value" ""
			(at 0 0 90)
			(layer "F.Fab")
			(effects
				(font
					(size 1.27 1.27)
				)
			)
		)
		(duplicate_pad_numbers_are_jumpers no)
		(fp_line
			(start 0.299974 -0.150114)
			(end 0.299974 0.150114)
			(stroke
				(width 0.1)
				(type default)
			)
			(layer "F.Fab")
		)
		(fp_line
			(start -0.299974 -0.150114)
			(end 0.299974 -0.150114)
			(stroke
				(width 0.1)
				(type default)
			)
			(layer "F.Fab")
		)
		(fp_line
			(start 0.299974 0.150114)
			(end -0.299974 0.150114)
			(stroke
				(width 0.1)
				(type default)
			)
			(layer "F.Fab")
		)
		(fp_line
			(start -0.299974 0.150114)
			(end -0.299974 -0.150114)
			(stroke
				(width 0.1)
				(type default)
			)
			(layer "F.Fab")
		)
		(pad "1" smd rect
			(at -0.2667 0 90)
			(size 0.3048 0.381)
			(layers "F.Cu" "F.Mask" "F.Paste")
			(net "P5E_PEX2_STN5_TX_DN<95>")
		)
		(pad "2" smd rect
			(at 0.2667 0 90)
			(size 0.3048 0.381)
			(layers "F.Cu" "F.Mask" "F.Paste")
			(net "P5E_PEX2_STN5_TX_C_DN<95>")
		)
	)
	(footprint ""
		(layer "F.Cu")
		(at 245.634764 -133.088126 180)
		(property "Reference" "PC343"
			(at 0 0 180)
			(layer "F.SilkS")
			(hide yes)
			(effects
				(font
					(size 1.27 1.27)
				)
			)
		)
		(property "Value" ""
			(at 0 0 180)
			(layer "F.Fab")
			(effects
				(font
					(size 1.27 1.27)
				)
			)
		)
		(duplicate_pad_numbers_are_jumpers no)
		(fp_line
			(start 1.524 0.762)
			(end -1.524 0.762)
			(stroke
				(width 0.1524)
				(type default)
			)
			(layer "F.SilkS")
		)
		(fp_line
			(start 1.524 -0.762)
			(end 1.524 0.762)
			(stroke
				(width 0.1524)
				(type default)
			)
			(layer "F.SilkS")
		)
		(fp_line
			(start -1.524 0.762)
			(end -1.524 -0.762)
			(stroke
				(width 0.1524)
				(type default)
			)
			(layer "F.SilkS")
		)
		(fp_line
			(start -1.524 -0.762)
			(end 1.524 -0.762)
			(stroke
				(width 0.1524)
				(type default)
			)
			(layer "F.SilkS")
		)
		(fp_line
			(start 1.1049 0.724916)
			(end 1.1049 -0.724916)
			(stroke
				(width 0.1)
				(type default)
			)
			(layer "F.Fab")
		)
		(fp_line
			(start 1.1049 -0.724916)
			(end -1.1049 -0.724916)
			(stroke
				(width 0.1)
				(type default)
			)
			(layer "F.Fab")
		)
		(fp_line
			(start -1.1049 0.724916)
			(end 1.1049 0.724916)
			(stroke
				(width 0.1)
				(type default)
			)
			(layer "F.Fab")
		)
		(fp_line
			(start -1.1049 -0.724916)
			(end -1.1049 0.724916)
			(stroke
				(width 0.1)
				(type default)
			)
			(layer "F.Fab")
		)
		(pad "1" smd rect
			(at -0.889 0)
			(size 1.016 1.27)
			(layers "F.Cu" "F.Mask" "F.Paste")
			(net "GND")
		)
		(pad "2" smd rect
			(at 0.889 0)
			(size 1.016 1.27)
			(layers "F.Cu" "F.Mask" "F.Paste")
			(net "P12V_AUX")
		)
	)
	(footprint ""
		(layer "F.Cu")
		(at 26.267918 -51.019456)
		(property "Reference" "PC362"
			(at 0 0 0)
			(layer "F.SilkS")
			(hide yes)
			(effects
				(font
					(size 1.27 1.27)
				)
			)
		)
		(property "Value" ""
			(at 0 0 0)
			(layer "F.Fab")
			(effects
				(font
					(size 1.27 1.27)
				)
			)
		)
		(duplicate_pad_numbers_are_jumpers no)
		(fp_line
			(start -0.7874 -0.4064)
			(end 0.7874 -0.4064)
			(stroke
				(width 0.1524)
				(type default)
			)
			(layer "F.SilkS")
		)
		(fp_line
			(start -0.7874 0.4064)
			(end -0.7874 -0.4064)
			(stroke
				(width 0.1524)
				(type default)
			)
			(layer "F.SilkS")
		)
		(fp_line
			(start 0.7874 -0.4064)
			(end 0.7874 0.4064)
			(stroke
				(width 0.1524)
				(type default)
			)
			(layer "F.SilkS")
		)
		(fp_line
			(start 0.7874 0.4064)
			(end -0.7874 0.4064)
			(stroke
				(width 0.1524)
				(type default)
			)
			(layer "F.SilkS")
		)
		(fp_line
			(start -0.67945 -0.305054)
			(end -0.12065 -0.305054)
			(stroke
				(width 0.1)
				(type default)
			)
			(layer "F.Fab")
		)
		(fp_line
			(start -0.67945 0.3048)
			(end -0.67945 -0.305054)
			(stroke
				(width 0.1)
				(type default)
			)
			(layer "F.Fab")
		)
		(fp_line
			(start -0.12065 -0.305054)
			(end -0.12065 -0.2794)
			(stroke
				(width 0.1)
				(type default)
			)
			(layer "F.Fab")
		)
		(fp_line
			(start -0.12065 -0.2794)
			(end 0.12065 -0.2794)
			(stroke
				(width 0.1)
				(type default)
			)
			(layer "F.Fab")
		)
		(fp_line
			(start -0.12065 0.2794)
			(end -0.12065 0.3048)
			(stroke
				(width 0.1)
				(type default)
			)
			(layer "F.Fab")
		)
		(fp_line
			(start -0.12065 0.3048)
			(end -0.67945 0.3048)
			(stroke
				(width 0.1)
				(type default)
			)
			(layer "F.Fab")
		)
		(fp_line
			(start 0.120396 0.2794)
			(end -0.12065 0.2794)
			(stroke
				(width 0.1)
				(type default)
			)
			(layer "F.Fab")
		)
		(fp_line
			(start 0.120396 0.3048)
			(end 0.120396 0.2794)
			(stroke
				(width 0.1)
				(type default)
			)
			(layer "F.Fab")
		)
		(fp_line
			(start 0.12065 -0.3048)
			(end 0.67945 -0.3048)
			(stroke
				(width 0.1)
				(type default)
			)
			(layer "F.Fab")
		)
		(fp_line
			(start 0.12065 -0.2794)
			(end 0.12065 -0.3048)
			(stroke
				(width 0.1)
				(type default)
			)
			(layer "F.Fab")
		)
		(fp_line
			(start 0.67945 -0.3048)
			(end 0.67945 0.3048)
			(stroke
				(width 0.1)
				(type default)
			)
			(layer "F.Fab")
		)
		(fp_line
			(start 0.67945 0.3048)
			(end 0.120396 0.3048)
			(stroke
				(width 0.1)
				(type default)
			)
			(layer "F.Fab")
		)
		(pad "1" smd circle
			(at -0.40005 0)
			(size 0 0)
			(layers "F.Cu" "F.Mask" "F.Paste")
			(net "P12V_SSD0_SS")
		)
		(pad "2" smd circle
			(at 0.40005 0)
			(size 0 0)
			(layers "F.Cu" "F.Mask" "F.Paste")
			(net "GND")
		)
	)
	(footprint ""
		(layer "F.Cu")
		(at 430.966118 -77.889608 180)
		(property "Reference" "C957"
			(at 0 0 180)
			(layer "F.SilkS")
			(hide yes)
			(effects
				(font
					(size 1.27 1.27)
				)
			)
		)
		(property "Value" ""
			(at 0 0 180)
			(layer "F.Fab")
			(effects
				(font
					(size 1.27 1.27)
				)
			)
		)
		(duplicate_pad_numbers_are_jumpers no)
		(fp_line
			(start 0.7874 0.4064)
			(end -0.7874 0.4064)
			(stroke
				(width 0.1524)
				(type default)
			)
			(layer "F.SilkS")
		)
		(fp_line
			(start 0.7874 -0.4064)
			(end 0.7874 0.4064)
			(stroke
				(width 0.1524)
				(type default)
			)
			(layer "F.SilkS")
		)
		(fp_line
			(start -0.7874 0.4064)
			(end -0.7874 -0.4064)
			(stroke
				(width 0.1524)
				(type default)
			)
			(layer "F.SilkS")
		)
		(fp_line
			(start -0.7874 -0.4064)
			(end 0.7874 -0.4064)
			(stroke
				(width 0.1524)
				(type default)
			)
			(layer "F.SilkS")
		)
		(fp_line
			(start 0.67945 0.3048)
			(end 0.120396 0.3048)
			(stroke
				(width 0.1)
				(type default)
			)
			(layer "F.Fab")
		)
		(fp_line
			(start 0.67945 -0.3048)
			(end 0.67945 0.3048)
			(stroke
				(width 0.1)
				(type default)
			)
			(layer "F.Fab")
		)
		(fp_line
			(start 0.12065 -0.2794)
			(end 0.12065 -0.3048)
			(stroke
				(width 0.1)
				(type default)
			)
			(layer "F.Fab")
		)
		(fp_line
			(start 0.12065 -0.3048)
			(end 0.67945 -0.3048)
			(stroke
				(width 0.1)
				(type default)
			)
			(layer "F.Fab")
		)
		(fp_line
			(start 0.120396 0.3048)
			(end 0.120396 0.2794)
			(stroke
				(width 0.1)
				(type default)
			)
			(layer "F.Fab")
		)
		(fp_line
			(start 0.120396 0.2794)
			(end -0.12065 0.2794)
			(stroke
				(width 0.1)
				(type default)
			)
			(layer "F.Fab")
		)
		(fp_line
			(start -0.12065 0.3048)
			(end -0.67945 0.3048)
			(stroke
				(width 0.1)
				(type default)
			)
			(layer "F.Fab")
		)
		(fp_line
			(start -0.12065 0.2794)
			(end -0.12065 0.3048)
			(stroke
				(width 0.1)
				(type default)
			)
			(layer "F.Fab")
		)
		(fp_line
			(start -0.12065 -0.2794)
			(end 0.12065 -0.2794)
			(stroke
				(width 0.1)
				(type default)
			)
			(layer "F.Fab")
		)
		(fp_line
			(start -0.12065 -0.305054)
			(end -0.12065 -0.2794)
			(stroke
				(width 0.1)
				(type default)
			)
			(layer "F.Fab")
		)
		(fp_line
			(start -0.67945 0.3048)
			(end -0.67945 -0.305054)
			(stroke
				(width 0.1)
				(type default)
			)
			(layer "F.Fab")
		)
		(fp_line
			(start -0.67945 -0.305054)
			(end -0.12065 -0.305054)
			(stroke
				(width 0.1)
				(type default)
			)
			(layer "F.Fab")
		)
		(pad "1" smd circle
			(at -0.40005 0 180)
			(size 0 0)
			(layers "F.Cu" "F.Mask" "F.Paste")
			(net "P3V3_NIC7")
		)
		(pad "2" smd circle
			(at 0.40005 0 180)
			(size 0 0)
			(layers "F.Cu" "F.Mask" "F.Paste")
			(net "GND")
		)
	)
	(footprint ""
		(layer "F.Cu")
		(at 89.214452 -311.227978 135)
		(property "Reference" "R1240"
			(at 0 0 135)
			(layer "F.SilkS")
			(hide yes)
			(effects
				(font
					(size 1.27 1.27)
				)
			)
		)
		(property "Value" ""
			(at 0 0 135)
			(layer "F.Fab")
			(effects
				(font
					(size 1.27 1.27)
				)
			)
		)
		(duplicate_pad_numbers_are_jumpers no)
		(fp_line
			(start 0.787389 -0.406267)
			(end 0.787389 0.406267)
			(stroke
				(width 0.1524)
				(type default)
			)
			(layer "F.SilkS")
		)
		(fp_line
			(start 0.787389 0.406267)
			(end -0.787389 0.406267)
			(stroke
				(width 0.1524)
				(type default)
			)
			(layer "F.SilkS")
		)
		(fp_line
			(start -0.787389 -0.406267)
			(end 0.787389 -0.406267)
			(stroke
				(width 0.1524)
				(type default)
			)
			(layer "F.SilkS")
		)
		(fp_line
			(start -0.787389 0.406267)
			(end -0.787389 -0.406267)
			(stroke
				(width 0.1524)
				(type default)
			)
			(layer "F.SilkS")
		)
		(fp_line
			(start 0.679446 -0.30479)
			(end 0.679446 0.30479)
			(stroke
				(width 0.1)
				(type default)
			)
			(layer "F.Fab")
		)
		(fp_line
			(start 0.120515 -0.30479)
			(end 0.679446 -0.30479)
			(stroke
				(width 0.1)
				(type default)
			)
			(layer "F.Fab")
		)
		(fp_line
			(start 0.120695 -0.279466)
			(end 0.120515 -0.30479)
			(stroke
				(width 0.1)
				(type default)
			)
			(layer "F.Fab")
		)
		(fp_line
			(start 0.679446 0.30479)
			(end 0.120515 0.30479)
			(stroke
				(width 0.1)
				(type default)
			)
			(layer "F.Fab")
		)
		(fp_line
			(start -0.120695 -0.304969)
			(end -0.120695 -0.279466)
			(stroke
				(width 0.1)
				(type default)
			)
			(layer "F.Fab")
		)
		(fp_line
			(start -0.120695 -0.279466)
			(end 0.120695 -0.279466)
			(stroke
				(width 0.1)
				(type default)
			)
			(layer "F.Fab")
		)
		(fp_line
			(start 0.120335 0.279466)
			(end -0.120695 0.279466)
			(stroke
				(width 0.1)
				(type default)
			)
			(layer "F.Fab")
		)
		(fp_line
			(start 0.120515 0.30479)
			(end 0.120335 0.279466)
			(stroke
				(width 0.1)
				(type default)
			)
			(layer "F.Fab")
		)
		(fp_line
			(start -0.679446 -0.305149)
			(end -0.120695 -0.304969)
			(stroke
				(width 0.1)
				(type default)
			)
			(layer "F.Fab")
		)
		(fp_line
			(start -0.120695 0.279466)
			(end -0.120515 0.30479)
			(stroke
				(width 0.1)
				(type default)
			)
			(layer "F.Fab")
		)
		(fp_line
			(start -0.120515 0.30479)
			(end -0.679446 0.30479)
			(stroke
				(width 0.1)
				(type default)
			)
			(layer "F.Fab")
		)
		(fp_line
			(start -0.679446 0.30479)
			(end -0.679446 -0.305149)
			(stroke
				(width 0.1)
				(type default)
			)
			(layer "F.Fab")
		)
		(pad "1" smd circle
			(at -0.40005 0 135)
			(size 0 0)
			(layers "F.Cu" "F.Mask" "F.Paste")
			(net "PEX0_SPARE0")
		)
		(pad "2" smd circle
			(at 0.40005 0 135)
			(size 0 0)
			(layers "F.Cu" "F.Mask" "F.Paste")
			(net "P1V8_PEX")
		)
	)
	(footprint ""
		(layer "F.Cu")
		(at 145.983706 -61.487812 180)
		(property "Reference" "R5975"
			(at 0 0 180)
			(layer "F.SilkS")
			(hide yes)
			(effects
				(font
					(size 1.27 1.27)
				)
			)
		)
		(property "Value" ""
			(at 0 0 180)
			(layer "F.Fab")
			(effects
				(font
					(size 1.27 1.27)
				)
			)
		)
		(duplicate_pad_numbers_are_jumpers no)
		(fp_line
			(start 0.7874 0.4064)
			(end -0.7874 0.4064)
			(stroke
				(width 0.1524)
				(type default)
			)
			(layer "F.SilkS")
		)
		(fp_line
			(start 0.7874 -0.4064)
			(end 0.7874 0.4064)
			(stroke
				(width 0.1524)
				(type default)
			)
			(layer "F.SilkS")
		)
		(fp_line
			(start -0.7874 0.4064)
			(end -0.7874 -0.4064)
			(stroke
				(width 0.1524)
				(type default)
			)
			(layer "F.SilkS")
		)
		(fp_line
			(start -0.7874 -0.4064)
			(end 0.7874 -0.4064)
			(stroke
				(width 0.1524)
				(type default)
			)
			(layer "F.SilkS")
		)
		(fp_line
			(start 0.67945 0.3048)
			(end 0.120396 0.3048)
			(stroke
				(width 0.1)
				(type default)
			)
			(layer "F.Fab")
		)
		(fp_line
			(start 0.67945 -0.3048)
			(end 0.67945 0.3048)
			(stroke
				(width 0.1)
				(type default)
			)
			(layer "F.Fab")
		)
		(fp_line
			(start 0.12065 -0.2794)
			(end 0.12065 -0.3048)
			(stroke
				(width 0.1)
				(type default)
			)
			(layer "F.Fab")
		)
		(fp_line
			(start 0.12065 -0.3048)
			(end 0.67945 -0.3048)
			(stroke
				(width 0.1)
				(type default)
			)
			(layer "F.Fab")
		)
		(fp_line
			(start 0.120396 0.3048)
			(end 0.120396 0.2794)
			(stroke
				(width 0.1)
				(type default)
			)
			(layer "F.Fab")
		)
		(fp_line
			(start 0.120396 0.2794)
			(end -0.12065 0.2794)
			(stroke
				(width 0.1)
				(type default)
			)
			(layer "F.Fab")
		)
		(fp_line
			(start -0.12065 0.3048)
			(end -0.67945 0.3048)
			(stroke
				(width 0.1)
				(type default)
			)
			(layer "F.Fab")
		)
		(fp_line
			(start -0.12065 0.2794)
			(end -0.12065 0.3048)
			(stroke
				(width 0.1)
				(type default)
			)
			(layer "F.Fab")
		)
		(fp_line
			(start -0.12065 -0.2794)
			(end 0.12065 -0.2794)
			(stroke
				(width 0.1)
				(type default)
			)
			(layer "F.Fab")
		)
		(fp_line
			(start -0.12065 -0.305054)
			(end -0.12065 -0.2794)
			(stroke
				(width 0.1)
				(type default)
			)
			(layer "F.Fab")
		)
		(fp_line
			(start -0.67945 0.3048)
			(end -0.67945 -0.305054)
			(stroke
				(width 0.1)
				(type default)
			)
			(layer "F.Fab")
		)
		(fp_line
			(start -0.67945 -0.305054)
			(end -0.12065 -0.305054)
			(stroke
				(width 0.1)
				(type default)
			)
			(layer "F.Fab")
		)
		(pad "1" smd circle
			(at -0.40005 0 180)
			(size 0 0)
			(layers "F.Cu" "F.Mask" "F.Paste")
			(net "PWRGD_P12V_SSD5_D")
		)
		(pad "2" smd circle
			(at 0.40005 0 180)
			(size 0 0)
			(layers "F.Cu" "F.Mask" "F.Paste")
			(net "PWRGD_P12V_SSD5_R")
		)
	)
	(footprint ""
		(layer "F.Cu")
		(at 71.49846 -66.32194 -90)
		(property "Reference" "PC652"
			(at 0 0 270)
			(layer "F.SilkS")
			(hide yes)
			(effects
				(font
					(size 1.27 1.27)
				)
			)
		)
		(property "Value" ""
			(at 0 0 270)
			(layer "F.Fab")
			(effects
				(font
					(size 1.27 1.27)
				)
			)
		)
		(duplicate_pad_numbers_are_jumpers no)
		(fp_line
			(start -0.7874 0.4064)
			(end -0.7874 -0.4064)
			(stroke
				(width 0.1524)
				(type default)
			)
			(layer "F.SilkS")
		)
		(fp_line
			(start 0.7874 0.4064)
			(end -0.7874 0.4064)
			(stroke
				(width 0.1524)
				(type default)
			)
			(layer "F.SilkS")
		)
		(fp_line
			(start -0.7874 -0.4064)
			(end 0.7874 -0.4064)
			(stroke
				(width 0.1524)
				(type default)
			)
			(layer "F.SilkS")
		)
		(fp_line
			(start 0.7874 -0.4064)
			(end 0.7874 0.4064)
			(stroke
				(width 0.1524)
				(type default)
			)
			(layer "F.SilkS")
		)
		(fp_line
			(start -0.67945 0.3048)
			(end -0.67945 -0.305054)
			(stroke
				(width 0.1)
				(type default)
			)
			(layer "F.Fab")
		)
		(fp_line
			(start -0.12065 0.3048)
			(end -0.67945 0.3048)
			(stroke
				(width 0.1)
				(type default)
			)
			(layer "F.Fab")
		)
		(fp_line
			(start 0.120396 0.3048)
			(end 0.120396 0.2794)
			(stroke
				(width 0.1)
				(type default)
			)
			(layer "F.Fab")
		)
		(fp_line
			(start 0.67945 0.3048)
			(end 0.120396 0.3048)
			(stroke
				(width 0.1)
				(type default)
			)
			(layer "F.Fab")
		)
		(fp_line
			(start -0.12065 0.2794)
			(end -0.12065 0.3048)
			(stroke
				(width 0.1)
				(type default)
			)
			(layer "F.Fab")
		)
		(fp_line
			(start 0.120396 0.2794)
			(end -0.12065 0.2794)
			(stroke
				(width 0.1)
				(type default)
			)
			(layer "F.Fab")
		)
		(fp_line
			(start -0.12065 -0.2794)
			(end 0.12065 -0.2794)
			(stroke
				(width 0.1)
				(type default)
			)
			(layer "F.Fab")
		)
		(fp_line
			(start 0.12065 -0.2794)
			(end 0.12065 -0.3048)
			(stroke
				(width 0.1)
				(type default)
			)
			(layer "F.Fab")
		)
		(fp_line
			(start 0.12065 -0.3048)
			(end 0.67945 -0.3048)
			(stroke
				(width 0.1)
				(type default)
			)
			(layer "F.Fab")
		)
		(fp_line
			(start 0.67945 -0.3048)
			(end 0.67945 0.3048)
			(stroke
				(width 0.1)
				(type default)
			)
			(layer "F.Fab")
		)
		(fp_line
			(start -0.67945 -0.305054)
			(end -0.12065 -0.305054)
			(stroke
				(width 0.1)
				(type default)
			)
			(layer "F.Fab")
		)
		(fp_line
			(start -0.12065 -0.305054)
			(end -0.12065 -0.2794)
			(stroke
				(width 0.1)
				(type default)
			)
			(layer "F.Fab")
		)
		(pad "1" smd circle
			(at -0.40005 0 270)
			(size 0 0)
			(layers "F.Cu" "F.Mask" "F.Paste")
			(net "P12V_SSD2_CO_GATE")
		)
		(pad "2" smd circle
			(at 0.40005 0 270)
			(size 0 0)
			(layers "F.Cu" "F.Mask" "F.Paste")
			(net "GND")
		)
	)
	(footprint ""
		(layer "F.Cu")
		(at 227.693474 -136.669272 90)
		(property "Reference" "R4201"
			(at 0 0 90)
			(layer "F.SilkS")
			(hide yes)
			(effects
				(font
					(size 1.27 1.27)
				)
			)
		)
		(property "Value" ""
			(at 0 0 90)
			(layer "F.Fab")
			(effects
				(font
					(size 1.27 1.27)
				)
			)
		)
		(duplicate_pad_numbers_are_jumpers no)
		(fp_line
			(start 0.7874 -0.4064)
			(end 0.7874 0.4064)
			(stroke
				(width 0.1524)
				(type default)
			)
			(layer "F.SilkS")
		)
		(fp_line
			(start -0.7874 -0.4064)
			(end 0.7874 -0.4064)
			(stroke
				(width 0.1524)
				(type default)
			)
			(layer "F.SilkS")
		)
		(fp_line
			(start 0.7874 0.4064)
			(end -0.7874 0.4064)
			(stroke
				(width 0.1524)
				(type default)
			)
			(layer "F.SilkS")
		)
		(fp_line
			(start -0.7874 0.4064)
			(end -0.7874 -0.4064)
			(stroke
				(width 0.1524)
				(type default)
			)
			(layer "F.SilkS")
		)
		(fp_line
			(start -0.12065 -0.305054)
			(end -0.12065 -0.2794)
			(stroke
				(width 0.1)
				(type default)
			)
			(layer "F.Fab")
		)
		(fp_line
			(start -0.67945 -0.305054)
			(end -0.12065 -0.305054)
			(stroke
				(width 0.1)
				(type default)
			)
			(layer "F.Fab")
		)
		(fp_line
			(start 0.67945 -0.3048)
			(end 0.67945 0.3048)
			(stroke
				(width 0.1)
				(type default)
			)
			(layer "F.Fab")
		)
		(fp_line
			(start 0.12065 -0.3048)
			(end 0.67945 -0.3048)
			(stroke
				(width 0.1)
				(type default)
			)
			(layer "F.Fab")
		)
		(fp_line
			(start 0.12065 -0.2794)
			(end 0.12065 -0.3048)
			(stroke
				(width 0.1)
				(type default)
			)
			(layer "F.Fab")
		)
		(fp_line
			(start -0.12065 -0.2794)
			(end 0.12065 -0.2794)
			(stroke
				(width 0.1)
				(type default)
			)
			(layer "F.Fab")
		)
		(fp_line
			(start 0.120396 0.2794)
			(end -0.12065 0.2794)
			(stroke
				(width 0.1)
				(type default)
			)
			(layer "F.Fab")
		)
		(fp_line
			(start -0.12065 0.2794)
			(end -0.12065 0.3048)
			(stroke
				(width 0.1)
				(type default)
			)
			(layer "F.Fab")
		)
		(fp_line
			(start 0.67945 0.3048)
			(end 0.120396 0.3048)
			(stroke
				(width 0.1)
				(type default)
			)
			(layer "F.Fab")
		)
		(fp_line
			(start 0.120396 0.3048)
			(end 0.120396 0.2794)
			(stroke
				(width 0.1)
				(type default)
			)
			(layer "F.Fab")
		)
		(fp_line
			(start -0.12065 0.3048)
			(end -0.67945 0.3048)
			(stroke
				(width 0.1)
				(type default)
			)
			(layer "F.Fab")
		)
		(fp_line
			(start -0.67945 0.3048)
			(end -0.67945 -0.305054)
			(stroke
				(width 0.1)
				(type default)
			)
			(layer "F.Fab")
		)
		(pad "1" smd circle
			(at -0.40005 0 90)
			(size 0 0)
			(layers "F.Cu" "F.Mask" "F.Paste")
			(net "GND")
		)
		(pad "2" smd circle
			(at 0.40005 0 90)
			(size 0 0)
			(layers "F.Cu" "F.Mask" "F.Paste")
			(net "CLK_CK440_PEX_SMB_ADDR1")
		)
	)
	(footprint ""
		(layer "F.Cu")
		(at 13.73124 -125.144784 180)
		(property "Reference" "PU46"
			(at 2.615692 -3.35788 0)
			(unlocked yes)
			(layer "F.SilkS")
			(effects
				(font
					(size 0.7874 0.5842)
					(thickness 0.1524)
				)
				(justify left)
			)
		)
		(property "Value" ""
			(at 0 0 180)
			(layer "F.Fab")
			(effects
				(font
					(size 1.27 1.27)
				)
			)
		)
		(duplicate_pad_numbers_are_jumpers no)
		(fp_line
			(start 1.943608 1.549908)
			(end -1.943608 1.549908)
			(stroke
				(width 0.1524)
				(type default)
			)
			(layer "F.SilkS")
		)
		(fp_line
			(start 1.943608 -1.549908)
			(end 1.943608 1.549908)
			(stroke
				(width 0.1524)
				(type default)
			)
			(layer "F.SilkS")
		)
		(fp_line
			(start -1.943608 1.549908)
			(end -1.943608 -1.549908)
			(stroke
				(width 0.1524)
				(type default)
			)
			(layer "F.SilkS")
		)
		(fp_line
			(start -1.943608 -1.549908)
			(end 1.943608 -1.549908)
			(stroke
				(width 0.1524)
				(type default)
			)
			(layer "F.SilkS")
		)
		(fp_poly
			(pts
				(xy -2.019808 -1.549908) (xy -1.257808 -1.549908) (xy -1.257808 -1.880108) (xy -2.019808 -1.880108)
			)
			(stroke
				(width 0)
				(type default)
			)
			(fill yes)
			(layer "F.SilkS")
		)
		(fp_line
			(start 1.549908 1.549908)
			(end -1.549908 1.549908)
			(stroke
				(width 0.1)
				(type default)
			)
			(layer "F.Fab")
		)
		(fp_line
			(start 1.549908 -1.549908)
			(end 1.549908 1.549908)
			(stroke
				(width 0.1)
				(type default)
			)
			(layer "F.Fab")
		)
		(fp_line
			(start -1.549908 1.549908)
			(end -1.549908 -1.549908)
			(stroke
				(width 0.1)
				(type default)
			)
			(layer "F.Fab")
		)
		(fp_line
			(start -1.549908 -1.549908)
			(end 1.549908 -1.549908)
			(stroke
				(width 0.1)
				(type default)
			)
			(layer "F.Fab")
		)
		(fp_poly
			(pts
				(xy -2.019808 -1.549908) (xy -1.257808 -1.549908) (xy -1.257808 -1.880108) (xy -2.019808 -1.880108)
			)
			(stroke
				(width 0)
				(type default)
			)
			(fill yes)
			(layer "F.Fab")
		)
		(pad "1" smd rect
			(at -1.500124 -1.249934 90)
			(size 0.2794 0.6096)
			(layers "F.Cu" "F.Mask" "F.Paste")
			(net "P3V3_NIC0")
		)
		(pad "2" smd rect
			(at -1.500124 -0.750062 90)
			(size 0.2794 0.6096)
			(layers "F.Cu" "F.Mask" "F.Paste")
			(net "P3V3_NIC0")
		)
		(pad "3" smd rect
			(at -1.500124 -0.249936 90)
			(size 0.2794 0.6096)
			(layers "F.Cu" "F.Mask" "F.Paste")
			(net "P3V3_NIC0")
		)
		(pad "4" smd rect
			(at -1.500124 0.249936 90)
			(size 0.2794 0.6096)
			(layers "F.Cu" "F.Mask" "F.Paste")
			(net "P3V3_NIC0")
		)
		(pad "5" smd rect
			(at -1.500124 0.750062 90)
			(size 0.2794 0.6096)
			(layers "F.Cu" "F.Mask" "F.Paste")
			(net "P3V3_NIC0")
		)
		(pad "6" smd rect
			(at -1.500124 1.249934 90)
			(size 0.2794 0.6096)
			(layers "F.Cu" "F.Mask" "F.Paste")
			(net "GND")
		)
		(pad "7" smd rect
			(at 1.500124 1.249934 90)
			(size 0.2794 0.6096)
			(layers "F.Cu" "F.Mask" "F.Paste")
			(net "P3V3_NIC0_SS")
		)
		(pad "8" smd rect
			(at 1.500124 0.750062 90)
			(size 0.2794 0.6096)
			(layers "F.Cu" "F.Mask" "F.Paste")
			(net "PWRGD_P3V3_NIC0")
		)
		(pad "9" smd rect
			(at 1.500124 0.249936 90)
			(size 0.2794 0.6096)
			(layers "F.Cu" "F.Mask" "F.Paste")
			(net "P3V3_NIC0_OCP")
		)
		(pad "10" smd rect
			(at 1.500124 -0.249936 90)
			(size 0.2794 0.6096)
			(layers "F.Cu" "F.Mask" "F.Paste")
			(net "P5V_AUX")
		)
		(pad "11" smd rect
			(at 1.500124 -0.750062 90)
			(size 0.2794 0.6096)
			(layers "F.Cu" "F.Mask" "F.Paste")
			(net "HP_NIC0_EN")
		)
		(pad "12" smd rect
			(at 1.500124 -1.249934 90)
			(size 0.2794 0.6096)
			(layers "F.Cu" "F.Mask" "F.Paste")
			(net "P3V3_AUX")
		)
		(pad "13" smd rect
			(at 0 0 180)
			(size 1.9812 2.7178)
			(layers "F.Cu" "F.Mask" "F.Paste")
			(net "P3V3_AUX")
		)
		(zone
			(layer "F.Cu")
			(hatch none 0.5)
			(connect_pads
				(clearance 0)
			)
			(min_thickness 0.25)
			(keepout
				(tracks not_allowed)
				(vias allowed)
				(pads allowed)
				(copperpour not_allowed)
				(footprints allowed)
			)
			(placement
				(enabled no)
				(sheetname "")
			)
			(fill
				(thermal_gap 0.5)
				(thermal_bridge_width 0.5)
				(island_removal_mode 0)
			)
			(polygon
				(pts
					(xy 12.58824 -123.595384) (xy 12.58824 -123.722384) (xy 12.58824 -126.694184) (xy 12.58824 -126.694692)
					(xy 14.87424 -126.694692) (xy 14.87424 -126.694184) (xy 14.87424 -126.567184) (xy 14.87424 -125.144784)
					(xy 14.77264 -125.144784) (xy 14.77264 -126.567184) (xy 12.68984 -126.567184) (xy 12.68984 -123.722384)
					(xy 14.77264 -123.722384) (xy 14.77264 -125.119384) (xy 14.87424 -125.119384) (xy 14.87424 -123.722384)
					(xy 14.87424 -123.595384) (xy 14.87424 -123.594876) (xy 12.58824 -123.594876)
				)
			)
		)
	)
	(footprint ""
		(layer "F.Cu")
		(at 271.480534 -106.488738)
		(property "Reference" "C477"
			(at 0 0 0)
			(layer "F.SilkS")
			(hide yes)
			(effects
				(font
					(size 1.27 1.27)
				)
			)
		)
		(property "Value" ""
			(at 0 0 0)
			(layer "F.Fab")
			(effects
				(font
					(size 1.27 1.27)
				)
			)
		)
		(duplicate_pad_numbers_are_jumpers no)
		(fp_line
			(start -0.299974 -0.150114)
			(end 0.299974 -0.150114)
			(stroke
				(width 0.1)
				(type default)
			)
			(layer "F.Fab")
		)
		(fp_line
			(start -0.299974 0.150114)
			(end -0.299974 -0.150114)
			(stroke
				(width 0.1)
				(type default)
			)
			(layer "F.Fab")
		)
		(fp_line
			(start 0.299974 -0.150114)
			(end 0.299974 0.150114)
			(stroke
				(width 0.1)
				(type default)
			)
			(layer "F.Fab")
		)
		(fp_line
			(start 0.299974 0.150114)
			(end -0.299974 0.150114)
			(stroke
				(width 0.1)
				(type default)
			)
			(layer "F.Fab")
		)
		(pad "1" smd rect
			(at -0.2667 0)
			(size 0.3048 0.381)
			(layers "F.Cu" "F.Mask" "F.Paste")
			(net "P5E_PEX2_STN1_TX_DP<20>")
		)
		(pad "2" smd rect
			(at 0.2667 0)
			(size 0.3048 0.381)
			(layers "F.Cu" "F.Mask" "F.Paste")
			(net "P5E_PEX2_STN1_TX_C_DP<20>")
		)
	)
	(footprint ""
		(layer "F.Cu")
		(at 375.76252 -22.937216 90)
		(property "Reference" "R1725"
			(at 0 0 90)
			(layer "F.SilkS")
			(hide yes)
			(effects
				(font
					(size 1.27 1.27)
				)
			)
		)
		(property "Value" ""
			(at 0 0 90)
			(layer "F.Fab")
			(effects
				(font
					(size 1.27 1.27)
				)
			)
		)
		(duplicate_pad_numbers_are_jumpers no)
		(fp_line
			(start 0.7874 -0.4064)
			(end 0.7874 0.4064)
			(stroke
				(width 0.1524)
				(type default)
			)
			(layer "F.SilkS")
		)
		(fp_line
			(start -0.7874 -0.4064)
			(end 0.7874 -0.4064)
			(stroke
				(width 0.1524)
				(type default)
			)
			(layer "F.SilkS")
		)
		(fp_line
			(start 0.7874 0.4064)
			(end -0.7874 0.4064)
			(stroke
				(width 0.1524)
				(type default)
			)
			(layer "F.SilkS")
		)
		(fp_line
			(start -0.7874 0.4064)
			(end -0.7874 -0.4064)
			(stroke
				(width 0.1524)
				(type default)
			)
			(layer "F.SilkS")
		)
		(fp_line
			(start -0.12065 -0.305054)
			(end -0.12065 -0.2794)
			(stroke
				(width 0.1)
				(type default)
			)
			(layer "F.Fab")
		)
		(fp_line
			(start -0.67945 -0.305054)
			(end -0.12065 -0.305054)
			(stroke
				(width 0.1)
				(type default)
			)
			(layer "F.Fab")
		)
		(fp_line
			(start 0.67945 -0.3048)
			(end 0.67945 0.3048)
			(stroke
				(width 0.1)
				(type default)
			)
			(layer "F.Fab")
		)
		(fp_line
			(start 0.12065 -0.3048)
			(end 0.67945 -0.3048)
			(stroke
				(width 0.1)
				(type default)
			)
			(layer "F.Fab")
		)
		(fp_line
			(start 0.12065 -0.2794)
			(end 0.12065 -0.3048)
			(stroke
				(width 0.1)
				(type default)
			)
			(layer "F.Fab")
		)
		(fp_line
			(start -0.12065 -0.2794)
			(end 0.12065 -0.2794)
			(stroke
				(width 0.1)
				(type default)
			)
			(layer "F.Fab")
		)
		(fp_line
			(start 0.120396 0.2794)
			(end -0.12065 0.2794)
			(stroke
				(width 0.1)
				(type default)
			)
			(layer "F.Fab")
		)
		(fp_line
			(start -0.12065 0.2794)
			(end -0.12065 0.3048)
			(stroke
				(width 0.1)
				(type default)
			)
			(layer "F.Fab")
		)
		(fp_line
			(start 0.67945 0.3048)
			(end 0.120396 0.3048)
			(stroke
				(width 0.1)
				(type default)
			)
			(layer "F.Fab")
		)
		(fp_line
			(start 0.120396 0.3048)
			(end 0.120396 0.2794)
			(stroke
				(width 0.1)
				(type default)
			)
			(layer "F.Fab")
		)
		(fp_line
			(start -0.12065 0.3048)
			(end -0.67945 0.3048)
			(stroke
				(width 0.1)
				(type default)
			)
			(layer "F.Fab")
		)
		(fp_line
			(start -0.67945 0.3048)
			(end -0.67945 -0.305054)
			(stroke
				(width 0.1)
				(type default)
			)
			(layer "F.Fab")
		)
		(pad "1" smd circle
			(at -0.40005 0 90)
			(size 0 0)
			(layers "F.Cu" "F.Mask" "F.Paste")
			(net "SMB_BIC_I2C9_MUX1_SSD12_R_SDA")
		)
		(pad "2" smd circle
			(at 0.40005 0 90)
			(size 0 0)
			(layers "F.Cu" "F.Mask" "F.Paste")
			(net "SMB_ISO_SSD12_SDA")
		)
	)
	(footprint ""
		(layer "F.Cu")
		(at 241.075464 -217.78976)
		(property "Reference" "C3614"
			(at 0 0 0)
			(layer "F.SilkS")
			(hide yes)
			(effects
				(font
					(size 1.27 1.27)
				)
			)
		)
		(property "Value" ""
			(at 0 0 0)
			(layer "F.Fab")
			(effects
				(font
					(size 1.27 1.27)
				)
			)
		)
		(duplicate_pad_numbers_are_jumpers no)
		(fp_line
			(start -0.69215 -0.2921)
			(end 0.69215 -0.2921)
			(stroke
				(width 0.1524)
				(type default)
			)
			(layer "F.SilkS")
		)
		(fp_line
			(start -0.69215 0.2921)
			(end -0.69215 -0.2921)
			(stroke
				(width 0.1524)
				(type default)
			)
			(layer "F.SilkS")
		)
		(fp_line
			(start 0.69215 -0.2921)
			(end 0.69215 0.2921)
			(stroke
				(width 0.1524)
				(type default)
			)
			(layer "F.SilkS")
		)
		(fp_line
			(start 0.69215 0.2921)
			(end -0.69215 0.2921)
			(stroke
				(width 0.1524)
				(type default)
			)
			(layer "F.SilkS")
		)
		(fp_line
			(start -0.51435 -0.2794)
			(end 0.51435 -0.2794)
			(stroke
				(width 0.1)
				(type default)
			)
			(layer "F.Fab")
		)
		(fp_line
			(start -0.51435 0.2794)
			(end -0.51435 -0.2794)
			(stroke
				(width 0.1)
				(type default)
			)
			(layer "F.Fab")
		)
		(fp_line
			(start 0.51435 -0.2794)
			(end 0.51435 0.2794)
			(stroke
				(width 0.1)
				(type default)
			)
			(layer "F.Fab")
		)
		(fp_line
			(start 0.51435 0.2794)
			(end -0.51435 0.2794)
			(stroke
				(width 0.1)
				(type default)
			)
			(layer "F.Fab")
		)
		(pad "1" smd circle
			(at -0.40005 0)
			(size 0 0)
			(layers "F.Cu" "F.Mask" "F.Paste")
			(net "BIC_ADCVREFP0")
		)
		(pad "2" smd circle
			(at 0.40005 0)
			(size 0 0)
			(layers "F.Cu" "F.Mask" "F.Paste")
			(net "GND")
		)
		(zone
			(layer "F.Cu")
			(hatch none 0.5)
			(connect_pads
				(clearance 0)
			)
			(min_thickness 0.25)
			(keepout
				(tracks not_allowed)
				(vias allowed)
				(pads allowed)
				(copperpour not_allowed)
				(footprints allowed)
			)
			(placement
				(enabled no)
				(sheetname "")
			)
			(fill
				(thermal_gap 0.5)
				(thermal_bridge_width 0.5)
				(island_removal_mode 0)
			)
			(polygon
				(pts
					(xy 240.884964 -217.70213) (xy 240.976404 -217.643964) (xy 241.175794 -217.643964) (xy 241.265964 -217.70213)
					(xy 241.265964 -217.87739) (xy 241.175794 -217.93581) (xy 240.976404 -217.93581) (xy 240.884964 -217.877644)
				)
			)
		)
	)
	(footprint ""
		(layer "F.Cu")
		(at 368.9731 -22.867366 90)
		(property "Reference" "C3956"
			(at 0 0 90)
			(layer "F.SilkS")
			(hide yes)
			(effects
				(font
					(size 1.27 1.27)
				)
			)
		)
		(property "Value" ""
			(at 0 0 90)
			(layer "F.Fab")
			(effects
				(font
					(size 1.27 1.27)
				)
			)
		)
		(duplicate_pad_numbers_are_jumpers no)
		(fp_line
			(start 0.7874 -0.4064)
			(end 0.7874 0.4064)
			(stroke
				(width 0.1524)
				(type default)
			)
			(layer "F.SilkS")
		)
		(fp_line
			(start -0.7874 -0.4064)
			(end 0.7874 -0.4064)
			(stroke
				(width 0.1524)
				(type default)
			)
			(layer "F.SilkS")
		)
		(fp_line
			(start 0.7874 0.4064)
			(end -0.7874 0.4064)
			(stroke
				(width 0.1524)
				(type default)
			)
			(layer "F.SilkS")
		)
		(fp_line
			(start -0.7874 0.4064)
			(end -0.7874 -0.4064)
			(stroke
				(width 0.1524)
				(type default)
			)
			(layer "F.SilkS")
		)
		(fp_line
			(start -0.12065 -0.305054)
			(end -0.12065 -0.2794)
			(stroke
				(width 0.1)
				(type default)
			)
			(layer "F.Fab")
		)
		(fp_line
			(start -0.67945 -0.305054)
			(end -0.12065 -0.305054)
			(stroke
				(width 0.1)
				(type default)
			)
			(layer "F.Fab")
		)
		(fp_line
			(start 0.67945 -0.3048)
			(end 0.67945 0.3048)
			(stroke
				(width 0.1)
				(type default)
			)
			(layer "F.Fab")
		)
		(fp_line
			(start 0.12065 -0.3048)
			(end 0.67945 -0.3048)
			(stroke
				(width 0.1)
				(type default)
			)
			(layer "F.Fab")
		)
		(fp_line
			(start 0.12065 -0.2794)
			(end 0.12065 -0.3048)
			(stroke
				(width 0.1)
				(type default)
			)
			(layer "F.Fab")
		)
		(fp_line
			(start -0.12065 -0.2794)
			(end 0.12065 -0.2794)
			(stroke
				(width 0.1)
				(type default)
			)
			(layer "F.Fab")
		)
		(fp_line
			(start 0.120396 0.2794)
			(end -0.12065 0.2794)
			(stroke
				(width 0.1)
				(type default)
			)
			(layer "F.Fab")
		)
		(fp_line
			(start -0.12065 0.2794)
			(end -0.12065 0.3048)
			(stroke
				(width 0.1)
				(type default)
			)
			(layer "F.Fab")
		)
		(fp_line
			(start 0.67945 0.3048)
			(end 0.120396 0.3048)
			(stroke
				(width 0.1)
				(type default)
			)
			(layer "F.Fab")
		)
		(fp_line
			(start 0.120396 0.3048)
			(end 0.120396 0.2794)
			(stroke
				(width 0.1)
				(type default)
			)
			(layer "F.Fab")
		)
		(fp_line
			(start -0.12065 0.3048)
			(end -0.67945 0.3048)
			(stroke
				(width 0.1)
				(type default)
			)
			(layer "F.Fab")
		)
		(fp_line
			(start -0.67945 0.3048)
			(end -0.67945 -0.305054)
			(stroke
				(width 0.1)
				(type default)
			)
			(layer "F.Fab")
		)
		(pad "1" smd circle
			(at -0.40005 0 90)
			(size 0 0)
			(layers "F.Cu" "F.Mask" "F.Paste")
			(net "P12V_SSD12")
		)
		(pad "2" smd circle
			(at 0.40005 0 90)
			(size 0 0)
			(layers "F.Cu" "F.Mask" "F.Paste")
			(net "GND")
		)
	)
	(footprint ""
		(layer "F.Cu")
		(at 255.701546 -207.1116 -90)
		(property "Reference" "R5067"
			(at 0 0 270)
			(layer "F.SilkS")
			(hide yes)
			(effects
				(font
					(size 1.27 1.27)
				)
			)
		)
		(property "Value" ""
			(at 0 0 270)
			(layer "F.Fab")
			(effects
				(font
					(size 1.27 1.27)
				)
			)
		)
		(duplicate_pad_numbers_are_jumpers no)
		(fp_line
			(start -0.7874 0.4064)
			(end -0.7874 -0.4064)
			(stroke
				(width 0.1524)
				(type default)
			)
			(layer "F.SilkS")
		)
		(fp_line
			(start 0.7874 0.4064)
			(end -0.7874 0.4064)
			(stroke
				(width 0.1524)
				(type default)
			)
			(layer "F.SilkS")
		)
		(fp_line
			(start -0.7874 -0.4064)
			(end 0.7874 -0.4064)
			(stroke
				(width 0.1524)
				(type default)
			)
			(layer "F.SilkS")
		)
		(fp_line
			(start 0.7874 -0.4064)
			(end 0.7874 0.4064)
			(stroke
				(width 0.1524)
				(type default)
			)
			(layer "F.SilkS")
		)
		(fp_line
			(start -0.67945 0.3048)
			(end -0.67945 -0.305054)
			(stroke
				(width 0.1)
				(type default)
			)
			(layer "F.Fab")
		)
		(fp_line
			(start -0.12065 0.3048)
			(end -0.67945 0.3048)
			(stroke
				(width 0.1)
				(type default)
			)
			(layer "F.Fab")
		)
		(fp_line
			(start 0.120396 0.3048)
			(end 0.120396 0.2794)
			(stroke
				(width 0.1)
				(type default)
			)
			(layer "F.Fab")
		)
		(fp_line
			(start 0.67945 0.3048)
			(end 0.120396 0.3048)
			(stroke
				(width 0.1)
				(type default)
			)
			(layer "F.Fab")
		)
		(fp_line
			(start -0.12065 0.2794)
			(end -0.12065 0.3048)
			(stroke
				(width 0.1)
				(type default)
			)
			(layer "F.Fab")
		)
		(fp_line
			(start 0.120396 0.2794)
			(end -0.12065 0.2794)
			(stroke
				(width 0.1)
				(type default)
			)
			(layer "F.Fab")
		)
		(fp_line
			(start -0.12065 -0.2794)
			(end 0.12065 -0.2794)
			(stroke
				(width 0.1)
				(type default)
			)
			(layer "F.Fab")
		)
		(fp_line
			(start 0.12065 -0.2794)
			(end 0.12065 -0.3048)
			(stroke
				(width 0.1)
				(type default)
			)
			(layer "F.Fab")
		)
		(fp_line
			(start 0.12065 -0.3048)
			(end 0.67945 -0.3048)
			(stroke
				(width 0.1)
				(type default)
			)
			(layer "F.Fab")
		)
		(fp_line
			(start 0.67945 -0.3048)
			(end 0.67945 0.3048)
			(stroke
				(width 0.1)
				(type default)
			)
			(layer "F.Fab")
		)
		(fp_line
			(start -0.67945 -0.305054)
			(end -0.12065 -0.305054)
			(stroke
				(width 0.1)
				(type default)
			)
			(layer "F.Fab")
		)
		(fp_line
			(start -0.12065 -0.305054)
			(end -0.12065 -0.2794)
			(stroke
				(width 0.1)
				(type default)
			)
			(layer "F.Fab")
		)
		(pad "1" smd circle
			(at -0.40005 0 270)
			(size 0 0)
			(layers "F.Cu" "F.Mask" "F.Paste")
			(net "P3V3_AUX")
		)
		(pad "2" smd circle
			(at 0.40005 0 270)
			(size 0 0)
			(layers "F.Cu" "F.Mask" "F.Paste")
			(net "JTAG_BIC_TDI_R")
		)
	)
	(footprint ""
		(layer "F.Cu")
		(at 379.015244 -59.546236 90)
		(property "Reference" "C2896"
			(at 0 0 90)
			(layer "F.SilkS")
			(hide yes)
			(effects
				(font
					(size 1.27 1.27)
				)
			)
		)
		(property "Value" ""
			(at 0 0 90)
			(layer "F.Fab")
			(effects
				(font
					(size 1.27 1.27)
				)
			)
		)
		(duplicate_pad_numbers_are_jumpers no)
		(fp_line
			(start 0.7874 -0.4064)
			(end 0.7874 0.4064)
			(stroke
				(width 0.1524)
				(type default)
			)
			(layer "F.SilkS")
		)
		(fp_line
			(start -0.7874 -0.4064)
			(end 0.7874 -0.4064)
			(stroke
				(width 0.1524)
				(type default)
			)
			(layer "F.SilkS")
		)
		(fp_line
			(start 0.7874 0.4064)
			(end -0.7874 0.4064)
			(stroke
				(width 0.1524)
				(type default)
			)
			(layer "F.SilkS")
		)
		(fp_line
			(start -0.7874 0.4064)
			(end -0.7874 -0.4064)
			(stroke
				(width 0.1524)
				(type default)
			)
			(layer "F.SilkS")
		)
		(fp_line
			(start -0.12065 -0.305054)
			(end -0.12065 -0.2794)
			(stroke
				(width 0.1)
				(type default)
			)
			(layer "F.Fab")
		)
		(fp_line
			(start -0.67945 -0.305054)
			(end -0.12065 -0.305054)
			(stroke
				(width 0.1)
				(type default)
			)
			(layer "F.Fab")
		)
		(fp_line
			(start 0.67945 -0.3048)
			(end 0.67945 0.3048)
			(stroke
				(width 0.1)
				(type default)
			)
			(layer "F.Fab")
		)
		(fp_line
			(start 0.12065 -0.3048)
			(end 0.67945 -0.3048)
			(stroke
				(width 0.1)
				(type default)
			)
			(layer "F.Fab")
		)
		(fp_line
			(start 0.12065 -0.2794)
			(end 0.12065 -0.3048)
			(stroke
				(width 0.1)
				(type default)
			)
			(layer "F.Fab")
		)
		(fp_line
			(start -0.12065 -0.2794)
			(end 0.12065 -0.2794)
			(stroke
				(width 0.1)
				(type default)
			)
			(layer "F.Fab")
		)
		(fp_line
			(start 0.120396 0.2794)
			(end -0.12065 0.2794)
			(stroke
				(width 0.1)
				(type default)
			)
			(layer "F.Fab")
		)
		(fp_line
			(start -0.12065 0.2794)
			(end -0.12065 0.3048)
			(stroke
				(width 0.1)
				(type default)
			)
			(layer "F.Fab")
		)
		(fp_line
			(start 0.67945 0.3048)
			(end 0.120396 0.3048)
			(stroke
				(width 0.1)
				(type default)
			)
			(layer "F.Fab")
		)
		(fp_line
			(start 0.120396 0.3048)
			(end 0.120396 0.2794)
			(stroke
				(width 0.1)
				(type default)
			)
			(layer "F.Fab")
		)
		(fp_line
			(start -0.12065 0.3048)
			(end -0.67945 0.3048)
			(stroke
				(width 0.1)
				(type default)
			)
			(layer "F.Fab")
		)
		(fp_line
			(start -0.67945 0.3048)
			(end -0.67945 -0.305054)
			(stroke
				(width 0.1)
				(type default)
			)
			(layer "F.Fab")
		)
		(pad "1" smd circle
			(at -0.40005 0 90)
			(size 0 0)
			(layers "F.Cu" "F.Mask" "F.Paste")
			(net "SSD13_AUX_P3V3_EN_R")
		)
		(pad "2" smd circle
			(at 0.40005 0 90)
			(size 0 0)
			(layers "F.Cu" "F.Mask" "F.Paste")
			(net "GND")
		)
	)
	(footprint ""
		(layer "F.Cu")
		(at 326.012556 -196.234304)
		(property "Reference" "R4244"
			(at 0 0 0)
			(layer "F.SilkS")
			(hide yes)
			(effects
				(font
					(size 1.27 1.27)
				)
			)
		)
		(property "Value" ""
			(at 0 0 0)
			(layer "F.Fab")
			(effects
				(font
					(size 1.27 1.27)
				)
			)
		)
		(duplicate_pad_numbers_are_jumpers no)
		(fp_line
			(start -0.7874 -0.4064)
			(end 0.7874 -0.4064)
			(stroke
				(width 0.1524)
				(type default)
			)
			(layer "F.SilkS")
		)
		(fp_line
			(start -0.7874 0.4064)
			(end -0.7874 -0.4064)
			(stroke
				(width 0.1524)
				(type default)
			)
			(layer "F.SilkS")
		)
		(fp_line
			(start 0.7874 -0.4064)
			(end 0.7874 0.4064)
			(stroke
				(width 0.1524)
				(type default)
			)
			(layer "F.SilkS")
		)
		(fp_line
			(start 0.7874 0.4064)
			(end -0.7874 0.4064)
			(stroke
				(width 0.1524)
				(type default)
			)
			(layer "F.SilkS")
		)
		(fp_line
			(start -0.67945 -0.305054)
			(end -0.12065 -0.305054)
			(stroke
				(width 0.1)
				(type default)
			)
			(layer "F.Fab")
		)
		(fp_line
			(start -0.67945 0.3048)
			(end -0.67945 -0.305054)
			(stroke
				(width 0.1)
				(type default)
			)
			(layer "F.Fab")
		)
		(fp_line
			(start -0.12065 -0.305054)
			(end -0.12065 -0.2794)
			(stroke
				(width 0.1)
				(type default)
			)
			(layer "F.Fab")
		)
		(fp_line
			(start -0.12065 -0.2794)
			(end 0.12065 -0.2794)
			(stroke
				(width 0.1)
				(type default)
			)
			(layer "F.Fab")
		)
		(fp_line
			(start -0.12065 0.2794)
			(end -0.12065 0.3048)
			(stroke
				(width 0.1)
				(type default)
			)
			(layer "F.Fab")
		)
		(fp_line
			(start -0.12065 0.3048)
			(end -0.67945 0.3048)
			(stroke
				(width 0.1)
				(type default)
			)
			(layer "F.Fab")
		)
		(fp_line
			(start 0.120396 0.2794)
			(end -0.12065 0.2794)
			(stroke
				(width 0.1)
				(type default)
			)
			(layer "F.Fab")
		)
		(fp_line
			(start 0.120396 0.3048)
			(end 0.120396 0.2794)
			(stroke
				(width 0.1)
				(type default)
			)
			(layer "F.Fab")
		)
		(fp_line
			(start 0.12065 -0.3048)
			(end 0.67945 -0.3048)
			(stroke
				(width 0.1)
				(type default)
			)
			(layer "F.Fab")
		)
		(fp_line
			(start 0.12065 -0.2794)
			(end 0.12065 -0.3048)
			(stroke
				(width 0.1)
				(type default)
			)
			(layer "F.Fab")
		)
		(fp_line
			(start 0.67945 -0.3048)
			(end 0.67945 0.3048)
			(stroke
				(width 0.1)
				(type default)
			)
			(layer "F.Fab")
		)
		(fp_line
			(start 0.67945 0.3048)
			(end 0.120396 0.3048)
			(stroke
				(width 0.1)
				(type default)
			)
			(layer "F.Fab")
		)
		(pad "1" smd circle
			(at -0.40005 0)
			(size 0 0)
			(layers "F.Cu" "F.Mask" "F.Paste")
			(net "GND")
		)
		(pad "2" smd circle
			(at 0.40005 0)
			(size 0 0)
			(layers "F.Cu" "F.Mask" "F.Paste")
			(net "IOEXP_DBV2_A2")
		)
	)
	(footprint ""
		(layer "F.Cu")
		(at 295.877742 -113.251742)
		(property "Reference" "R290"
			(at 0 0 0)
			(layer "F.SilkS")
			(hide yes)
			(effects
				(font
					(size 1.27 1.27)
				)
			)
		)
		(property "Value" ""
			(at 0 0 0)
			(layer "F.Fab")
			(effects
				(font
					(size 1.27 1.27)
				)
			)
		)
		(duplicate_pad_numbers_are_jumpers no)
		(fp_line
			(start -0.7874 -0.4064)
			(end 0.7874 -0.4064)
			(stroke
				(width 0.1524)
				(type default)
			)
			(layer "F.SilkS")
		)
		(fp_line
			(start -0.7874 0.4064)
			(end -0.7874 -0.4064)
			(stroke
				(width 0.1524)
				(type default)
			)
			(layer "F.SilkS")
		)
		(fp_line
			(start 0.7874 -0.4064)
			(end 0.7874 0.4064)
			(stroke
				(width 0.1524)
				(type default)
			)
			(layer "F.SilkS")
		)
		(fp_line
			(start 0.7874 0.4064)
			(end -0.7874 0.4064)
			(stroke
				(width 0.1524)
				(type default)
			)
			(layer "F.SilkS")
		)
		(fp_line
			(start -0.67945 -0.305054)
			(end -0.12065 -0.305054)
			(stroke
				(width 0.1)
				(type default)
			)
			(layer "F.Fab")
		)
		(fp_line
			(start -0.67945 0.3048)
			(end -0.67945 -0.305054)
			(stroke
				(width 0.1)
				(type default)
			)
			(layer "F.Fab")
		)
		(fp_line
			(start -0.12065 -0.305054)
			(end -0.12065 -0.2794)
			(stroke
				(width 0.1)
				(type default)
			)
			(layer "F.Fab")
		)
		(fp_line
			(start -0.12065 -0.2794)
			(end 0.12065 -0.2794)
			(stroke
				(width 0.1)
				(type default)
			)
			(layer "F.Fab")
		)
		(fp_line
			(start -0.12065 0.2794)
			(end -0.12065 0.3048)
			(stroke
				(width 0.1)
				(type default)
			)
			(layer "F.Fab")
		)
		(fp_line
			(start -0.12065 0.3048)
			(end -0.67945 0.3048)
			(stroke
				(width 0.1)
				(type default)
			)
			(layer "F.Fab")
		)
		(fp_line
			(start 0.120396 0.2794)
			(end -0.12065 0.2794)
			(stroke
				(width 0.1)
				(type default)
			)
			(layer "F.Fab")
		)
		(fp_line
			(start 0.120396 0.3048)
			(end 0.120396 0.2794)
			(stroke
				(width 0.1)
				(type default)
			)
			(layer "F.Fab")
		)
		(fp_line
			(start 0.12065 -0.3048)
			(end 0.67945 -0.3048)
			(stroke
				(width 0.1)
				(type default)
			)
			(layer "F.Fab")
		)
		(fp_line
			(start 0.12065 -0.2794)
			(end 0.12065 -0.3048)
			(stroke
				(width 0.1)
				(type default)
			)
			(layer "F.Fab")
		)
		(fp_line
			(start 0.67945 -0.3048)
			(end 0.67945 0.3048)
			(stroke
				(width 0.1)
				(type default)
			)
			(layer "F.Fab")
		)
		(fp_line
			(start 0.67945 0.3048)
			(end 0.120396 0.3048)
			(stroke
				(width 0.1)
				(type default)
			)
			(layer "F.Fab")
		)
		(pad "1" smd circle
			(at -0.40005 0)
			(size 0 0)
			(layers "F.Cu" "F.Mask" "F.Paste")
			(net "RST_SMB_NIC5_MUX_ISO_N")
		)
		(pad "2" smd circle
			(at 0.40005 0)
			(size 0 0)
			(layers "F.Cu" "F.Mask" "F.Paste")
			(net "P3V3_NIC5")
		)
	)
	(footprint ""
		(layer "F.Cu")
		(at 22.416008 -350.098614 90)
		(property "Reference" "C2154"
			(at 0 0 90)
			(layer "F.SilkS")
			(hide yes)
			(effects
				(font
					(size 1.27 1.27)
				)
			)
		)
		(property "Value" ""
			(at 0 0 90)
			(layer "F.Fab")
			(effects
				(font
					(size 1.27 1.27)
				)
			)
		)
		(duplicate_pad_numbers_are_jumpers no)
		(fp_line
			(start 0.299974 -0.150114)
			(end 0.299974 0.150114)
			(stroke
				(width 0.1)
				(type default)
			)
			(layer "F.Fab")
		)
		(fp_line
			(start -0.299974 -0.150114)
			(end 0.299974 -0.150114)
			(stroke
				(width 0.1)
				(type default)
			)
			(layer "F.Fab")
		)
		(fp_line
			(start 0.299974 0.150114)
			(end -0.299974 0.150114)
			(stroke
				(width 0.1)
				(type default)
			)
			(layer "F.Fab")
		)
		(fp_line
			(start -0.299974 0.150114)
			(end -0.299974 -0.150114)
			(stroke
				(width 0.1)
				(type default)
			)
			(layer "F.Fab")
		)
		(pad "1" smd rect
			(at -0.2667 0 90)
			(size 0.3048 0.381)
			(layers "F.Cu" "F.Mask" "F.Paste")
			(net "P5E_PEX0_STN4_TX_DP<78>")
		)
		(pad "2" smd rect
			(at 0.2667 0 90)
			(size 0.3048 0.381)
			(layers "F.Cu" "F.Mask" "F.Paste")
			(net "P5E_PEX0_STN4_TX_C_DP<78>")
		)
	)
	(footprint ""
		(layer "F.Cu")
		(at 129.207006 -275.81606)
		(property "Reference" "PC6614"
			(at 0 0 0)
			(layer "F.SilkS")
			(hide yes)
			(effects
				(font
					(size 1.27 1.27)
				)
			)
		)
		(property "Value" ""
			(at 0 0 0)
			(layer "F.Fab")
			(effects
				(font
					(size 1.27 1.27)
				)
			)
		)
		(duplicate_pad_numbers_are_jumpers no)
		(fp_line
			(start -1.524 -0.762)
			(end 1.524 -0.762)
			(stroke
				(width 0.1524)
				(type default)
			)
			(layer "F.SilkS")
		)
		(fp_line
			(start -1.524 0.762)
			(end -1.524 -0.762)
			(stroke
				(width 0.1524)
				(type default)
			)
			(layer "F.SilkS")
		)
		(fp_line
			(start 1.524 -0.762)
			(end 1.524 0.762)
			(stroke
				(width 0.1524)
				(type default)
			)
			(layer "F.SilkS")
		)
		(fp_line
			(start 1.524 0.762)
			(end -1.524 0.762)
			(stroke
				(width 0.1524)
				(type default)
			)
			(layer "F.SilkS")
		)
		(fp_line
			(start -1.1049 -0.724916)
			(end -1.1049 0.724916)
			(stroke
				(width 0.1)
				(type default)
			)
			(layer "F.Fab")
		)
		(fp_line
			(start -1.1049 0.724916)
			(end 1.1049 0.724916)
			(stroke
				(width 0.1)
				(type default)
			)
			(layer "F.Fab")
		)
		(fp_line
			(start 1.1049 -0.724916)
			(end -1.1049 -0.724916)
			(stroke
				(width 0.1)
				(type default)
			)
			(layer "F.Fab")
		)
		(fp_line
			(start 1.1049 0.724916)
			(end 1.1049 -0.724916)
			(stroke
				(width 0.1)
				(type default)
			)
			(layer "F.Fab")
		)
		(pad "1" smd rect
			(at -0.889 0 180)
			(size 1.016 1.27)
			(layers "F.Cu" "F.Mask" "F.Paste")
			(net "SW_P12V_P0V8_PEX1_FLT")
		)
		(pad "2" smd rect
			(at 0.889 0 180)
			(size 1.016 1.27)
			(layers "F.Cu" "F.Mask" "F.Paste")
			(net "GND")
		)
	)
	(footprint ""
		(layer "F.Cu")
		(at 109.58195 -79.822294 90)
		(property "Reference" "R1140"
			(at 0 0 90)
			(layer "F.SilkS")
			(hide yes)
			(effects
				(font
					(size 1.27 1.27)
				)
			)
		)
		(property "Value" ""
			(at 0 0 90)
			(layer "F.Fab")
			(effects
				(font
					(size 1.27 1.27)
				)
			)
		)
		(duplicate_pad_numbers_are_jumpers no)
		(fp_line
			(start -0.7874 -0.4064)
			(end 0.7874 -0.4064)
			(stroke
				(width 0.1524)
				(type default)
			)
			(layer "F.SilkS")
		)
		(fp_line
			(start -0.12065 -0.305054)
			(end -0.12065 -0.2794)
			(stroke
				(width 0.1)
				(type default)
			)
			(layer "F.Fab")
		)
		(fp_line
			(start -0.67945 -0.305054)
			(end -0.12065 -0.305054)
			(stroke
				(width 0.1)
				(type default)
			)
			(layer "F.Fab")
		)
		(fp_line
			(start 0.67945 -0.3048)
			(end 0.67945 0.3048)
			(stroke
				(width 0.1)
				(type default)
			)
			(layer "F.Fab")
		)
		(fp_line
			(start 0.12065 -0.3048)
			(end 0.67945 -0.3048)
			(stroke
				(width 0.1)
				(type default)
			)
			(layer "F.Fab")
		)
		(fp_line
			(start 0.12065 -0.2794)
			(end 0.12065 -0.3048)
			(stroke
				(width 0.1)
				(type default)
			)
			(layer "F.Fab")
		)
		(fp_line
			(start -0.12065 -0.2794)
			(end 0.12065 -0.2794)
			(stroke
				(width 0.1)
				(type default)
			)
			(layer "F.Fab")
		)
		(fp_line
			(start 0.120396 0.2794)
			(end -0.12065 0.2794)
			(stroke
				(width 0.1)
				(type default)
			)
			(layer "F.Fab")
		)
		(fp_line
			(start -0.12065 0.2794)
			(end -0.12065 0.3048)
			(stroke
				(width 0.1)
				(type default)
			)
			(layer "F.Fab")
		)
		(fp_line
			(start 0.67945 0.3048)
			(end 0.120396 0.3048)
			(stroke
				(width 0.1)
				(type default)
			)
			(layer "F.Fab")
		)
		(fp_line
			(start 0.120396 0.3048)
			(end 0.120396 0.2794)
			(stroke
				(width 0.1)
				(type default)
			)
			(layer "F.Fab")
		)
		(fp_line
			(start -0.12065 0.3048)
			(end -0.67945 0.3048)
			(stroke
				(width 0.1)
				(type default)
			)
			(layer "F.Fab")
		)
		(fp_line
			(start -0.67945 0.3048)
			(end -0.67945 -0.305054)
			(stroke
				(width 0.1)
				(type default)
			)
			(layer "F.Fab")
		)
		(pad "1" smd circle
			(at -0.40005 0 90)
			(size 0 0)
			(layers "F.Cu" "F.Mask" "F.Paste")
			(net "CLK_100M_DB800ZL_SSD2_R_DP")
		)
		(pad "2" smd circle
			(at 0.40005 0 90)
			(size 0 0)
			(layers "F.Cu" "F.Mask" "F.Paste")
			(net "CLK_100M_DB800ZL_SSD2_DP")
		)
	)
	(footprint ""
		(layer "F.Cu")
		(at 146.361912 -311.007252 -135)
		(property "Reference" "R1324"
			(at 0 0 225)
			(layer "F.SilkS")
			(hide yes)
			(effects
				(font
					(size 1.27 1.27)
				)
			)
		)
		(property "Value" ""
			(at 0 0 225)
			(layer "F.Fab")
			(effects
				(font
					(size 1.27 1.27)
				)
			)
		)
		(duplicate_pad_numbers_are_jumpers no)
		(fp_line
			(start 0.787389 0.406267)
			(end -0.787389 0.406267)
			(stroke
				(width 0.1524)
				(type default)
			)
			(layer "F.SilkS")
		)
		(fp_line
			(start 0.787389 -0.406267)
			(end 0.787389 0.406267)
			(stroke
				(width 0.1524)
				(type default)
			)
			(layer "F.SilkS")
		)
		(fp_line
			(start -0.787389 0.406267)
			(end -0.787389 -0.406267)
			(stroke
				(width 0.1524)
				(type default)
			)
			(layer "F.SilkS")
		)
		(fp_line
			(start -0.787389 -0.406267)
			(end 0.787389 -0.406267)
			(stroke
				(width 0.1524)
				(type default)
			)
			(layer "F.SilkS")
		)
		(fp_line
			(start 0.679446 0.30479)
			(end 0.120515 0.30479)
			(stroke
				(width 0.1)
				(type default)
			)
			(layer "F.Fab")
		)
		(fp_line
			(start 0.120515 0.30479)
			(end 0.120335 0.279466)
			(stroke
				(width 0.1)
				(type default)
			)
			(layer "F.Fab")
		)
		(fp_line
			(start 0.120335 0.279466)
			(end -0.120695 0.279466)
			(stroke
				(width 0.1)
				(type default)
			)
			(layer "F.Fab")
		)
		(fp_line
			(start 0.679446 -0.30479)
			(end 0.679446 0.30479)
			(stroke
				(width 0.1)
				(type default)
			)
			(layer "F.Fab")
		)
		(fp_line
			(start -0.120515 0.30479)
			(end -0.679446 0.30479)
			(stroke
				(width 0.1)
				(type default)
			)
			(layer "F.Fab")
		)
		(fp_line
			(start -0.120695 0.279466)
			(end -0.120515 0.30479)
			(stroke
				(width 0.1)
				(type default)
			)
			(layer "F.Fab")
		)
		(fp_line
			(start 0.120695 -0.279466)
			(end 0.120515 -0.30479)
			(stroke
				(width 0.1)
				(type default)
			)
			(layer "F.Fab")
		)
		(fp_line
			(start 0.120515 -0.30479)
			(end 0.679446 -0.30479)
			(stroke
				(width 0.1)
				(type default)
			)
			(layer "F.Fab")
		)
		(fp_line
			(start -0.679446 0.30479)
			(end -0.679446 -0.305149)
			(stroke
				(width 0.1)
				(type default)
			)
			(layer "F.Fab")
		)
		(fp_line
			(start -0.120695 -0.279466)
			(end 0.120695 -0.279466)
			(stroke
				(width 0.1)
				(type default)
			)
			(layer "F.Fab")
		)
		(fp_line
			(start -0.120695 -0.304969)
			(end -0.120695 -0.279466)
			(stroke
				(width 0.1)
				(type default)
			)
			(layer "F.Fab")
		)
		(fp_line
			(start -0.679446 -0.305149)
			(end -0.120695 -0.304969)
			(stroke
				(width 0.1)
				(type default)
			)
			(layer "F.Fab")
		)
		(pad "1" smd circle
			(at -0.40005 0 225)
			(size 0 0)
			(layers "F.Cu" "F.Mask" "F.Paste")
			(net "PU_PEX1_PAD_TRI_L")
		)
		(pad "2" smd circle
			(at 0.40005 0 225)
			(size 0 0)
			(layers "F.Cu" "F.Mask" "F.Paste")
			(net "P1V8_PEX")
		)
	)
	(footprint ""
		(layer "F.Cu")
		(at 250.039886 -70.52437 90)
		(property "Reference" "PC405"
			(at 0 0 90)
			(layer "F.SilkS")
			(hide yes)
			(effects
				(font
					(size 1.27 1.27)
				)
			)
		)
		(property "Value" ""
			(at 0 0 90)
			(layer "F.Fab")
			(effects
				(font
					(size 1.27 1.27)
				)
			)
		)
		(duplicate_pad_numbers_are_jumpers no)
		(fp_line
			(start 1.524 -0.762)
			(end 1.524 0.762)
			(stroke
				(width 0.1524)
				(type default)
			)
			(layer "F.SilkS")
		)
		(fp_line
			(start -1.524 -0.762)
			(end 1.524 -0.762)
			(stroke
				(width 0.1524)
				(type default)
			)
			(layer "F.SilkS")
		)
		(fp_line
			(start 1.524 0.762)
			(end -1.524 0.762)
			(stroke
				(width 0.1524)
				(type default)
			)
			(layer "F.SilkS")
		)
		(fp_line
			(start -1.524 0.762)
			(end -1.524 -0.762)
			(stroke
				(width 0.1524)
				(type default)
			)
			(layer "F.SilkS")
		)
		(fp_line
			(start 1.1049 -0.724916)
			(end -1.1049 -0.724916)
			(stroke
				(width 0.1)
				(type default)
			)
			(layer "F.Fab")
		)
		(fp_line
			(start -1.1049 -0.724916)
			(end -1.1049 0.724916)
			(stroke
				(width 0.1)
				(type default)
			)
			(layer "F.Fab")
		)
		(fp_line
			(start 1.1049 0.724916)
			(end 1.1049 -0.724916)
			(stroke
				(width 0.1)
				(type default)
			)
			(layer "F.Fab")
		)
		(fp_line
			(start -1.1049 0.724916)
			(end 1.1049 0.724916)
			(stroke
				(width 0.1)
				(type default)
			)
			(layer "F.Fab")
		)
		(pad "1" smd rect
			(at -0.889 0 270)
			(size 1.016 1.27)
			(layers "F.Cu" "F.Mask" "F.Paste")
			(net "P12V_SSD8_R")
		)
		(pad "2" smd rect
			(at 0.889 0 270)
			(size 1.016 1.27)
			(layers "F.Cu" "F.Mask" "F.Paste")
			(net "GND")
		)
	)
	(footprint ""
		(layer "F.Cu")
		(at 444.09233 -32.739584 180)
		(property "Reference" "C724"
			(at 0 0 180)
			(layer "F.SilkS")
			(hide yes)
			(effects
				(font
					(size 1.27 1.27)
				)
			)
		)
		(property "Value" ""
			(at 0 0 180)
			(layer "F.Fab")
			(effects
				(font
					(size 1.27 1.27)
				)
			)
		)
		(duplicate_pad_numbers_are_jumpers no)
		(fp_line
			(start 0.299974 0.150114)
			(end -0.299974 0.150114)
			(stroke
				(width 0.1)
				(type default)
			)
			(layer "F.Fab")
		)
		(fp_line
			(start 0.299974 -0.150114)
			(end 0.299974 0.150114)
			(stroke
				(width 0.1)
				(type default)
			)
			(layer "F.Fab")
		)
		(fp_line
			(start -0.299974 0.150114)
			(end -0.299974 -0.150114)
			(stroke
				(width 0.1)
				(type default)
			)
			(layer "F.Fab")
		)
		(fp_line
			(start -0.299974 -0.150114)
			(end 0.299974 -0.150114)
			(stroke
				(width 0.1)
				(type default)
			)
			(layer "F.Fab")
		)
		(pad "1" smd rect
			(at -0.2667 0 180)
			(size 0.3048 0.381)
			(layers "F.Cu" "F.Mask" "F.Paste")
			(net "P5E_PEX3_STN2_TX_DP<34>")
		)
		(pad "2" smd rect
			(at 0.2667 0 180)
			(size 0.3048 0.381)
			(layers "F.Cu" "F.Mask" "F.Paste")
			(net "P5E_PEX3_STN2_TX_C_DP<34>")
		)
	)
	(footprint ""
		(layer "F.Cu")
		(at 440.184032 -289.230816 90)
		(property "Reference" "R4001"
			(at 0 0 90)
			(layer "F.SilkS")
			(hide yes)
			(effects
				(font
					(size 1.27 1.27)
				)
			)
		)
		(property "Value" ""
			(at 0 0 90)
			(layer "F.Fab")
			(effects
				(font
					(size 1.27 1.27)
				)
			)
		)
		(duplicate_pad_numbers_are_jumpers no)
		(fp_line
			(start 0.7874 -0.4064)
			(end 0.7874 0.4064)
			(stroke
				(width 0.1524)
				(type default)
			)
			(layer "F.SilkS")
		)
		(fp_line
			(start -0.7874 -0.4064)
			(end 0.7874 -0.4064)
			(stroke
				(width 0.1524)
				(type default)
			)
			(layer "F.SilkS")
		)
		(fp_line
			(start 0.7874 0.4064)
			(end -0.7874 0.4064)
			(stroke
				(width 0.1524)
				(type default)
			)
			(layer "F.SilkS")
		)
		(fp_line
			(start -0.7874 0.4064)
			(end -0.7874 -0.4064)
			(stroke
				(width 0.1524)
				(type default)
			)
			(layer "F.SilkS")
		)
		(fp_line
			(start -0.12065 -0.305054)
			(end -0.12065 -0.2794)
			(stroke
				(width 0.1)
				(type default)
			)
			(layer "F.Fab")
		)
		(fp_line
			(start -0.67945 -0.305054)
			(end -0.12065 -0.305054)
			(stroke
				(width 0.1)
				(type default)
			)
			(layer "F.Fab")
		)
		(fp_line
			(start 0.67945 -0.3048)
			(end 0.67945 0.3048)
			(stroke
				(width 0.1)
				(type default)
			)
			(layer "F.Fab")
		)
		(fp_line
			(start 0.12065 -0.3048)
			(end 0.67945 -0.3048)
			(stroke
				(width 0.1)
				(type default)
			)
			(layer "F.Fab")
		)
		(fp_line
			(start 0.12065 -0.2794)
			(end 0.12065 -0.3048)
			(stroke
				(width 0.1)
				(type default)
			)
			(layer "F.Fab")
		)
		(fp_line
			(start -0.12065 -0.2794)
			(end 0.12065 -0.2794)
			(stroke
				(width 0.1)
				(type default)
			)
			(layer "F.Fab")
		)
		(fp_line
			(start 0.120396 0.2794)
			(end -0.12065 0.2794)
			(stroke
				(width 0.1)
				(type default)
			)
			(layer "F.Fab")
		)
		(fp_line
			(start -0.12065 0.2794)
			(end -0.12065 0.3048)
			(stroke
				(width 0.1)
				(type default)
			)
			(layer "F.Fab")
		)
		(fp_line
			(start 0.67945 0.3048)
			(end 0.120396 0.3048)
			(stroke
				(width 0.1)
				(type default)
			)
			(layer "F.Fab")
		)
		(fp_line
			(start 0.120396 0.3048)
			(end 0.120396 0.2794)
			(stroke
				(width 0.1)
				(type default)
			)
			(layer "F.Fab")
		)
		(fp_line
			(start -0.12065 0.3048)
			(end -0.67945 0.3048)
			(stroke
				(width 0.1)
				(type default)
			)
			(layer "F.Fab")
		)
		(fp_line
			(start -0.67945 0.3048)
			(end -0.67945 -0.305054)
			(stroke
				(width 0.1)
				(type default)
			)
			(layer "F.Fab")
		)
		(pad "1" smd circle
			(at -0.40005 0 90)
			(size 0 0)
			(layers "F.Cu" "F.Mask" "F.Paste")
			(net "SMB_PEX3_PCA9555_SCL")
		)
		(pad "2" smd circle
			(at 0.40005 0 90)
			(size 0 0)
			(layers "F.Cu" "F.Mask" "F.Paste")
			(net "SMB_PEX3_HOST_LS_SCL")
		)
	)
	(footprint ""
		(layer "F.Cu")
		(at 242.535964 -257.975862 -90)
		(property "Reference" "R6533"
			(at 0 0 270)
			(layer "F.SilkS")
			(hide yes)
			(effects
				(font
					(size 1.27 1.27)
				)
			)
		)
		(property "Value" ""
			(at 0 0 270)
			(layer "F.Fab")
			(effects
				(font
					(size 1.27 1.27)
				)
			)
		)
		(duplicate_pad_numbers_are_jumpers no)
		(fp_line
			(start -0.7874 0.4064)
			(end -0.7874 -0.4064)
			(stroke
				(width 0.1524)
				(type default)
			)
			(layer "F.SilkS")
		)
		(fp_line
			(start 0.7874 0.4064)
			(end -0.7874 0.4064)
			(stroke
				(width 0.1524)
				(type default)
			)
			(layer "F.SilkS")
		)
		(fp_line
			(start -0.7874 -0.4064)
			(end 0.7874 -0.4064)
			(stroke
				(width 0.1524)
				(type default)
			)
			(layer "F.SilkS")
		)
		(fp_line
			(start 0.7874 -0.4064)
			(end 0.7874 0.4064)
			(stroke
				(width 0.1524)
				(type default)
			)
			(layer "F.SilkS")
		)
		(fp_line
			(start -0.67945 0.3048)
			(end -0.67945 -0.305054)
			(stroke
				(width 0.1)
				(type default)
			)
			(layer "F.Fab")
		)
		(fp_line
			(start -0.12065 0.3048)
			(end -0.67945 0.3048)
			(stroke
				(width 0.1)
				(type default)
			)
			(layer "F.Fab")
		)
		(fp_line
			(start 0.120396 0.3048)
			(end 0.120396 0.2794)
			(stroke
				(width 0.1)
				(type default)
			)
			(layer "F.Fab")
		)
		(fp_line
			(start 0.67945 0.3048)
			(end 0.120396 0.3048)
			(stroke
				(width 0.1)
				(type default)
			)
			(layer "F.Fab")
		)
		(fp_line
			(start -0.12065 0.2794)
			(end -0.12065 0.3048)
			(stroke
				(width 0.1)
				(type default)
			)
			(layer "F.Fab")
		)
		(fp_line
			(start 0.120396 0.2794)
			(end -0.12065 0.2794)
			(stroke
				(width 0.1)
				(type default)
			)
			(layer "F.Fab")
		)
		(fp_line
			(start -0.12065 -0.2794)
			(end 0.12065 -0.2794)
			(stroke
				(width 0.1)
				(type default)
			)
			(layer "F.Fab")
		)
		(fp_line
			(start 0.12065 -0.2794)
			(end 0.12065 -0.3048)
			(stroke
				(width 0.1)
				(type default)
			)
			(layer "F.Fab")
		)
		(fp_line
			(start 0.12065 -0.3048)
			(end 0.67945 -0.3048)
			(stroke
				(width 0.1)
				(type default)
			)
			(layer "F.Fab")
		)
		(fp_line
			(start 0.67945 -0.3048)
			(end 0.67945 0.3048)
			(stroke
				(width 0.1)
				(type default)
			)
			(layer "F.Fab")
		)
		(fp_line
			(start -0.67945 -0.305054)
			(end -0.12065 -0.305054)
			(stroke
				(width 0.1)
				(type default)
			)
			(layer "F.Fab")
		)
		(fp_line
			(start -0.12065 -0.305054)
			(end -0.12065 -0.2794)
			(stroke
				(width 0.1)
				(type default)
			)
			(layer "F.Fab")
		)
		(pad "1" smd circle
			(at -0.40005 0 270)
			(size 0 0)
			(layers "F.Cu" "F.Mask" "F.Paste")
			(net "P1V25_SERDES_VDDPLL_PEX2")
		)
		(pad "2" smd circle
			(at 0.40005 0 270)
			(size 0 0)
			(layers "F.Cu" "F.Mask" "F.Paste")
			(net "P1V25_SERDES_VDDPLL_PEX2_C10")
		)
	)
	(footprint ""
		(layer "F.Cu")
		(at 12.609322 -119.105426 -90)
		(property "Reference" "R5862"
			(at 0 0 270)
			(layer "F.SilkS")
			(hide yes)
			(effects
				(font
					(size 1.27 1.27)
				)
			)
		)
		(property "Value" ""
			(at 0 0 270)
			(layer "F.Fab")
			(effects
				(font
					(size 1.27 1.27)
				)
			)
		)
		(duplicate_pad_numbers_are_jumpers no)
		(fp_line
			(start -0.7874 0.4064)
			(end -0.7874 -0.4064)
			(stroke
				(width 0.1524)
				(type default)
			)
			(layer "F.SilkS")
		)
		(fp_line
			(start 0.7874 0.4064)
			(end -0.7874 0.4064)
			(stroke
				(width 0.1524)
				(type default)
			)
			(layer "F.SilkS")
		)
		(fp_line
			(start -0.7874 -0.4064)
			(end 0.7874 -0.4064)
			(stroke
				(width 0.1524)
				(type default)
			)
			(layer "F.SilkS")
		)
		(fp_line
			(start 0.7874 -0.4064)
			(end 0.7874 0.4064)
			(stroke
				(width 0.1524)
				(type default)
			)
			(layer "F.SilkS")
		)
		(fp_line
			(start -0.67945 0.3048)
			(end -0.67945 -0.305054)
			(stroke
				(width 0.1)
				(type default)
			)
			(layer "F.Fab")
		)
		(fp_line
			(start -0.12065 0.3048)
			(end -0.67945 0.3048)
			(stroke
				(width 0.1)
				(type default)
			)
			(layer "F.Fab")
		)
		(fp_line
			(start 0.120396 0.3048)
			(end 0.120396 0.2794)
			(stroke
				(width 0.1)
				(type default)
			)
			(layer "F.Fab")
		)
		(fp_line
			(start 0.67945 0.3048)
			(end 0.120396 0.3048)
			(stroke
				(width 0.1)
				(type default)
			)
			(layer "F.Fab")
		)
		(fp_line
			(start -0.12065 0.2794)
			(end -0.12065 0.3048)
			(stroke
				(width 0.1)
				(type default)
			)
			(layer "F.Fab")
		)
		(fp_line
			(start 0.120396 0.2794)
			(end -0.12065 0.2794)
			(stroke
				(width 0.1)
				(type default)
			)
			(layer "F.Fab")
		)
		(fp_line
			(start -0.12065 -0.2794)
			(end 0.12065 -0.2794)
			(stroke
				(width 0.1)
				(type default)
			)
			(layer "F.Fab")
		)
		(fp_line
			(start 0.12065 -0.2794)
			(end 0.12065 -0.3048)
			(stroke
				(width 0.1)
				(type default)
			)
			(layer "F.Fab")
		)
		(fp_line
			(start 0.12065 -0.3048)
			(end 0.67945 -0.3048)
			(stroke
				(width 0.1)
				(type default)
			)
			(layer "F.Fab")
		)
		(fp_line
			(start 0.67945 -0.3048)
			(end 0.67945 0.3048)
			(stroke
				(width 0.1)
				(type default)
			)
			(layer "F.Fab")
		)
		(fp_line
			(start -0.67945 -0.305054)
			(end -0.12065 -0.305054)
			(stroke
				(width 0.1)
				(type default)
			)
			(layer "F.Fab")
		)
		(fp_line
			(start -0.12065 -0.305054)
			(end -0.12065 -0.2794)
			(stroke
				(width 0.1)
				(type default)
			)
			(layer "F.Fab")
		)
		(pad "1" smd circle
			(at -0.40005 0 270)
			(size 0 0)
			(layers "F.Cu" "F.Mask" "F.Paste")
			(net "P3V3_NIC0")
		)
		(pad "2" smd circle
			(at 0.40005 0 270)
			(size 0 0)
			(layers "F.Cu" "F.Mask" "F.Paste")
			(net "P3V3_NIC0_PG_G1")
		)
	)
	(footprint ""
		(layer "F.Cu")
		(at 113.509806 -293.5351 90)
		(property "Reference" "PL7"
			(at -4.260596 23.43277 90)
			(unlocked yes)
			(layer "F.SilkS")
			(effects
				(font
					(size 0.7874 0.5842)
					(thickness 0.1524)
				)
				(justify left)
			)
		)
		(property "Value" ""
			(at 0 0 90)
			(layer "F.Fab")
			(effects
				(font
					(size 1.27 1.27)
				)
			)
		)
		(duplicate_pad_numbers_are_jumpers no)
		(fp_line
			(start 4.800092 -3.199892)
			(end 4.800092 -1.6764)
			(stroke
				(width 0.1524)
				(type default)
			)
			(layer "F.SilkS")
		)
		(fp_line
			(start -4.800092 -3.199892)
			(end 4.800092 -3.199892)
			(stroke
				(width 0.1524)
				(type default)
			)
			(layer "F.SilkS")
		)
		(fp_line
			(start -4.800092 -1.6764)
			(end -4.800092 -3.199892)
			(stroke
				(width 0.1524)
				(type default)
			)
			(layer "F.SilkS")
		)
		(fp_line
			(start 4.800092 1.6764)
			(end 4.800092 3.199892)
			(stroke
				(width 0.1524)
				(type default)
			)
			(layer "F.SilkS")
		)
		(fp_line
			(start 4.800092 3.199892)
			(end -4.800092 3.199892)
			(stroke
				(width 0.1524)
				(type default)
			)
			(layer "F.SilkS")
		)
		(fp_line
			(start -4.800092 3.199892)
			(end -4.800092 1.6764)
			(stroke
				(width 0.1524)
				(type default)
			)
			(layer "F.SilkS")
		)
		(fp_line
			(start 4.800092 -3.199892)
			(end 4.800092 3.199892)
			(stroke
				(width 0.1)
				(type default)
			)
			(layer "F.Fab")
		)
		(fp_line
			(start -4.800092 -3.199892)
			(end 4.800092 -3.199892)
			(stroke
				(width 0.1)
				(type default)
			)
			(layer "F.Fab")
		)
		(fp_line
			(start 4.800092 3.199892)
			(end -4.800092 3.199892)
			(stroke
				(width 0.1)
				(type default)
			)
			(layer "F.Fab")
		)
		(fp_line
			(start -4.800092 3.199892)
			(end -4.800092 -3.199892)
			(stroke
				(width 0.1)
				(type default)
			)
			(layer "F.Fab")
		)
		(pad "1" smd rect
			(at -3.074924 0 180)
			(size 3.0988 3.3528)
			(layers "F.Cu" "F.Mask" "F.Paste")
			(net "SW_P0V8_PEX0_PH2")
		)
		(pad "2" smd rect
			(at 3.074924 0 180)
			(size 3.0988 3.3528)
			(layers "F.Cu" "F.Mask" "F.Paste")
			(net "P0V8_PEX0")
		)
	)
	(footprint ""
		(layer "F.Cu")
		(at 146.253454 -300.992032)
		(property "Reference" "L105"
			(at 0 0 0)
			(layer "F.SilkS")
			(hide yes)
			(effects
				(font
					(size 1.27 1.27)
				)
			)
		)
		(property "Value" ""
			(at 0 0 0)
			(layer "F.Fab")
			(effects
				(font
					(size 1.27 1.27)
				)
			)
		)
		(duplicate_pad_numbers_are_jumpers no)
		(fp_line
			(start -1.63576 -0.8128)
			(end -1.63576 0.8128)
			(stroke
				(width 0.1524)
				(type default)
			)
			(layer "F.SilkS")
		)
		(fp_line
			(start -1.63576 -0.8128)
			(end 1.63576 -0.8128)
			(stroke
				(width 0.1524)
				(type default)
			)
			(layer "F.SilkS")
		)
		(fp_line
			(start 1.63576 -0.8128)
			(end 1.63576 0.8128)
			(stroke
				(width 0.1524)
				(type default)
			)
			(layer "F.SilkS")
		)
		(fp_line
			(start 1.63576 0.8128)
			(end -1.63576 0.8128)
			(stroke
				(width 0.1524)
				(type default)
			)
			(layer "F.SilkS")
		)
		(fp_line
			(start -1.56083 -0.738632)
			(end -1.56083 0.7366)
			(stroke
				(width 0.1)
				(type default)
			)
			(layer "F.Fab")
		)
		(fp_line
			(start -1.56083 0.7366)
			(end -1.524 0.7366)
			(stroke
				(width 0.1)
				(type default)
			)
			(layer "F.Fab")
		)
		(fp_line
			(start -1.524 0.7366)
			(end 1.524 0.7366)
			(stroke
				(width 0.1)
				(type default)
			)
			(layer "F.Fab")
		)
		(fp_line
			(start 1.524 0.7366)
			(end 1.560576 0.7366)
			(stroke
				(width 0.1)
				(type default)
			)
			(layer "F.Fab")
		)
		(fp_line
			(start 1.560576 -0.738632)
			(end -1.56083 -0.738632)
			(stroke
				(width 0.1)
				(type default)
			)
			(layer "F.Fab")
		)
		(fp_line
			(start 1.560576 0.7366)
			(end 1.560576 -0.738632)
			(stroke
				(width 0.1)
				(type default)
			)
			(layer "F.Fab")
		)
		(pad "1" smd rect
			(at -0.94996 0 180)
			(size 1.1176 1.3716)
			(layers "F.Cu" "F.Mask" "F.Paste")
			(net "P1V8_PLL0_PEX1")
		)
		(pad "2" smd rect
			(at 0.94996 0 180)
			(size 1.1176 1.3716)
			(layers "F.Cu" "F.Mask" "F.Paste")
			(net "PCEPLL1_VDDA18_PEX1")
		)
	)
	(footprint ""
		(layer "F.Cu")
		(at 56.271922 -363.356144 -90)
		(property "Reference" "R5451"
			(at 0 0 270)
			(layer "F.SilkS")
			(hide yes)
			(effects
				(font
					(size 1.27 1.27)
				)
			)
		)
		(property "Value" ""
			(at 0 0 270)
			(layer "F.Fab")
			(effects
				(font
					(size 1.27 1.27)
				)
			)
		)
		(duplicate_pad_numbers_are_jumpers no)
		(fp_line
			(start 0.028448 0.4064)
			(end -0.7874 0.4064)
			(stroke
				(width 0.1524)
				(type default)
			)
			(layer "F.SilkS")
		)
		(fp_line
			(start -0.7874 -0.4064)
			(end 0.7874 -0.4064)
			(stroke
				(width 0.1524)
				(type default)
			)
			(layer "F.SilkS")
		)
		(fp_line
			(start 0.7874 -0.4064)
			(end 0.7874 0.4064)
			(stroke
				(width 0.1524)
				(type default)
			)
			(layer "F.SilkS")
		)
		(fp_line
			(start -0.67945 0.3048)
			(end -0.67945 -0.305054)
			(stroke
				(width 0.1)
				(type default)
			)
			(layer "F.Fab")
		)
		(fp_line
			(start -0.12065 0.3048)
			(end -0.67945 0.3048)
			(stroke
				(width 0.1)
				(type default)
			)
			(layer "F.Fab")
		)
		(fp_line
			(start 0.120396 0.3048)
			(end 0.120396 0.2794)
			(stroke
				(width 0.1)
				(type default)
			)
			(layer "F.Fab")
		)
		(fp_line
			(start 0.67945 0.3048)
			(end 0.120396 0.3048)
			(stroke
				(width 0.1)
				(type default)
			)
			(layer "F.Fab")
		)
		(fp_line
			(start -0.12065 0.2794)
			(end -0.12065 0.3048)
			(stroke
				(width 0.1)
				(type default)
			)
			(layer "F.Fab")
		)
		(fp_line
			(start 0.120396 0.2794)
			(end -0.12065 0.2794)
			(stroke
				(width 0.1)
				(type default)
			)
			(layer "F.Fab")
		)
		(fp_line
			(start -0.12065 -0.2794)
			(end 0.12065 -0.2794)
			(stroke
				(width 0.1)
				(type default)
			)
			(layer "F.Fab")
		)
		(fp_line
			(start 0.12065 -0.2794)
			(end 0.12065 -0.3048)
			(stroke
				(width 0.1)
				(type default)
			)
			(layer "F.Fab")
		)
		(fp_line
			(start 0.12065 -0.3048)
			(end 0.67945 -0.3048)
			(stroke
				(width 0.1)
				(type default)
			)
			(layer "F.Fab")
		)
		(fp_line
			(start 0.67945 -0.3048)
			(end 0.67945 0.3048)
			(stroke
				(width 0.1)
				(type default)
			)
			(layer "F.Fab")
		)
		(fp_line
			(start -0.67945 -0.305054)
			(end -0.12065 -0.305054)
			(stroke
				(width 0.1)
				(type default)
			)
			(layer "F.Fab")
		)
		(fp_line
			(start -0.12065 -0.305054)
			(end -0.12065 -0.2794)
			(stroke
				(width 0.1)
				(type default)
			)
			(layer "F.Fab")
		)
		(pad "1" smd rect
			(at -0.40005 0 90)
			(size 0.4572 0.508)
			(layers "F.Cu" "F.Mask" "F.Paste")
			(net "USB2_GPU_HMC_R_DP")
		)
		(pad "2" smd rect
			(at 0.40005 0 90)
			(size 0.4572 0.508)
			(layers "F.Cu" "F.Mask" "F.Paste")
			(net "USB2_GPU_HMC_DP")
		)
	)
	(footprint ""
		(layer "F.Cu")
		(at 321.804284 -343.952322 90)
		(property "Reference" "C541"
			(at 0 0 90)
			(layer "F.SilkS")
			(hide yes)
			(effects
				(font
					(size 1.27 1.27)
				)
			)
		)
		(property "Value" ""
			(at 0 0 90)
			(layer "F.Fab")
			(effects
				(font
					(size 1.27 1.27)
				)
			)
		)
		(duplicate_pad_numbers_are_jumpers no)
		(fp_line
			(start 0.299974 -0.150114)
			(end 0.299974 0.150114)
			(stroke
				(width 0.1)
				(type default)
			)
			(layer "F.Fab")
		)
		(fp_line
			(start -0.299974 -0.150114)
			(end 0.299974 -0.150114)
			(stroke
				(width 0.1)
				(type default)
			)
			(layer "F.Fab")
		)
		(fp_line
			(start 0.299974 0.150114)
			(end -0.299974 0.150114)
			(stroke
				(width 0.1)
				(type default)
			)
			(layer "F.Fab")
		)
		(fp_line
			(start -0.299974 0.150114)
			(end -0.299974 -0.150114)
			(stroke
				(width 0.1)
				(type default)
			)
			(layer "F.Fab")
		)
		(pad "1" smd rect
			(at -0.2667 0 90)
			(size 0.3048 0.381)
			(layers "F.Cu" "F.Mask" "F.Paste")
			(net "P5E_PEX2_STN5_TX_DP<84>")
		)
		(pad "2" smd rect
			(at 0.2667 0 90)
			(size 0.3048 0.381)
			(layers "F.Cu" "F.Mask" "F.Paste")
			(net "P5E_PEX2_STN5_TX_C_DP<84>")
		)
	)
	(footprint ""
		(layer "F.Cu")
		(at 454.754742 -22.961346 90)
		(property "Reference" "R1732"
			(at 0 0 90)
			(layer "F.SilkS")
			(hide yes)
			(effects
				(font
					(size 1.27 1.27)
				)
			)
		)
		(property "Value" ""
			(at 0 0 90)
			(layer "F.Fab")
			(effects
				(font
					(size 1.27 1.27)
				)
			)
		)
		(duplicate_pad_numbers_are_jumpers no)
		(fp_line
			(start 0.7874 -0.4064)
			(end 0.7874 0.4064)
			(stroke
				(width 0.1524)
				(type default)
			)
			(layer "F.SilkS")
		)
		(fp_line
			(start -0.7874 -0.4064)
			(end 0.7874 -0.4064)
			(stroke
				(width 0.1524)
				(type default)
			)
			(layer "F.SilkS")
		)
		(fp_line
			(start 0.7874 0.4064)
			(end -0.7874 0.4064)
			(stroke
				(width 0.1524)
				(type default)
			)
			(layer "F.SilkS")
		)
		(fp_line
			(start -0.7874 0.4064)
			(end -0.7874 -0.4064)
			(stroke
				(width 0.1524)
				(type default)
			)
			(layer "F.SilkS")
		)
		(fp_line
			(start -0.12065 -0.305054)
			(end -0.12065 -0.2794)
			(stroke
				(width 0.1)
				(type default)
			)
			(layer "F.Fab")
		)
		(fp_line
			(start -0.67945 -0.305054)
			(end -0.12065 -0.305054)
			(stroke
				(width 0.1)
				(type default)
			)
			(layer "F.Fab")
		)
		(fp_line
			(start 0.67945 -0.3048)
			(end 0.67945 0.3048)
			(stroke
				(width 0.1)
				(type default)
			)
			(layer "F.Fab")
		)
		(fp_line
			(start 0.12065 -0.3048)
			(end 0.67945 -0.3048)
			(stroke
				(width 0.1)
				(type default)
			)
			(layer "F.Fab")
		)
		(fp_line
			(start 0.12065 -0.2794)
			(end 0.12065 -0.3048)
			(stroke
				(width 0.1)
				(type default)
			)
			(layer "F.Fab")
		)
		(fp_line
			(start -0.12065 -0.2794)
			(end 0.12065 -0.2794)
			(stroke
				(width 0.1)
				(type default)
			)
			(layer "F.Fab")
		)
		(fp_line
			(start 0.120396 0.2794)
			(end -0.12065 0.2794)
			(stroke
				(width 0.1)
				(type default)
			)
			(layer "F.Fab")
		)
		(fp_line
			(start -0.12065 0.2794)
			(end -0.12065 0.3048)
			(stroke
				(width 0.1)
				(type default)
			)
			(layer "F.Fab")
		)
		(fp_line
			(start 0.67945 0.3048)
			(end 0.120396 0.3048)
			(stroke
				(width 0.1)
				(type default)
			)
			(layer "F.Fab")
		)
		(fp_line
			(start 0.120396 0.3048)
			(end 0.120396 0.2794)
			(stroke
				(width 0.1)
				(type default)
			)
			(layer "F.Fab")
		)
		(fp_line
			(start -0.12065 0.3048)
			(end -0.67945 0.3048)
			(stroke
				(width 0.1)
				(type default)
			)
			(layer "F.Fab")
		)
		(fp_line
			(start -0.67945 0.3048)
			(end -0.67945 -0.305054)
			(stroke
				(width 0.1)
				(type default)
			)
			(layer "F.Fab")
		)
		(pad "1" smd circle
			(at -0.40005 0 90)
			(size 0 0)
			(layers "F.Cu" "F.Mask" "F.Paste")
			(net "SMB_SSD15_ISO_EN")
		)
		(pad "2" smd circle
			(at 0.40005 0 90)
			(size 0 0)
			(layers "F.Cu" "F.Mask" "F.Paste")
			(net "P3V3_AUX")
		)
	)
	(footprint ""
		(layer "F.Cu")
		(at 277.198582 -356.244906 90)
		(property "Reference" "C603"
			(at 0 0 90)
			(layer "F.SilkS")
			(hide yes)
			(effects
				(font
					(size 1.27 1.27)
				)
			)
		)
		(property "Value" ""
			(at 0 0 90)
			(layer "F.Fab")
			(effects
				(font
					(size 1.27 1.27)
				)
			)
		)
		(duplicate_pad_numbers_are_jumpers no)
		(fp_line
			(start 0.299974 -0.150114)
			(end 0.299974 0.150114)
			(stroke
				(width 0.1)
				(type default)
			)
			(layer "F.Fab")
		)
		(fp_line
			(start -0.299974 -0.150114)
			(end 0.299974 -0.150114)
			(stroke
				(width 0.1)
				(type default)
			)
			(layer "F.Fab")
		)
		(fp_line
			(start 0.299974 0.150114)
			(end -0.299974 0.150114)
			(stroke
				(width 0.1)
				(type default)
			)
			(layer "F.Fab")
		)
		(fp_line
			(start -0.299974 0.150114)
			(end -0.299974 -0.150114)
			(stroke
				(width 0.1)
				(type default)
			)
			(layer "F.Fab")
		)
		(pad "1" smd rect
			(at -0.2667 0 90)
			(size 0.3048 0.381)
			(layers "F.Cu" "F.Mask" "F.Paste")
			(net "P5E_PEX2_STN7_TX_DP<117>")
		)
		(pad "2" smd rect
			(at 0.2667 0 90)
			(size 0.3048 0.381)
			(layers "F.Cu" "F.Mask" "F.Paste")
			(net "P5E_PEX2_STN7_TX_C_DP<117>")
		)
	)
	(footprint ""
		(layer "F.Cu")
		(at 336.924396 -119.77624)
		(property "Reference" "Q217"
			(at -0.051816 -2.817622 0)
			(unlocked yes)
			(layer "F.SilkS")
			(effects
				(font
					(size 0.7874 0.5842)
					(thickness 0.1524)
				)
			)
		)
		(property "Value" ""
			(at 0 0 0)
			(layer "F.Fab")
			(effects
				(font
					(size 1.27 1.27)
				)
			)
		)
		(duplicate_pad_numbers_are_jumpers no)
		(fp_line
			(start -1.376172 -1.199896)
			(end -0.508 -1.199896)
			(stroke
				(width 0.1524)
				(type default)
			)
			(layer "F.SilkS")
		)
		(fp_line
			(start -1.376172 1.199896)
			(end -1.376172 -1.199896)
			(stroke
				(width 0.1524)
				(type default)
			)
			(layer "F.SilkS")
		)
		(fp_line
			(start -0.508 -1.199896)
			(end 0 -0.762)
			(stroke
				(width 0.1524)
				(type default)
			)
			(layer "F.SilkS")
		)
		(fp_line
			(start 0 -0.762)
			(end 0.508 -1.199896)
			(stroke
				(width 0.1524)
				(type default)
			)
			(layer "F.SilkS")
		)
		(fp_line
			(start 0.508 -1.199896)
			(end 1.376172 -1.199896)
			(stroke
				(width 0.1524)
				(type default)
			)
			(layer "F.SilkS")
		)
		(fp_line
			(start 1.376172 -1.199896)
			(end 1.376172 1.199896)
			(stroke
				(width 0.1524)
				(type default)
			)
			(layer "F.SilkS")
		)
		(fp_line
			(start 1.376172 1.199896)
			(end -1.376172 1.199896)
			(stroke
				(width 0.1524)
				(type default)
			)
			(layer "F.SilkS")
		)
		(fp_poly
			(pts
				(xy -0.9652 -1.325118) (xy -1.234694 -2.133346) (xy -1.773428 -1.594612)
			)
			(stroke
				(width 0)
				(type default)
			)
			(fill yes)
			(layer "F.SilkS")
		)
		(fp_line
			(start -0.674878 -1.100074)
			(end 0.674878 -1.100074)
			(stroke
				(width 0.1)
				(type default)
			)
			(layer "F.Fab")
		)
		(fp_line
			(start -0.674878 1.100074)
			(end -0.674878 -1.100074)
			(stroke
				(width 0.1)
				(type default)
			)
			(layer "F.Fab")
		)
		(fp_line
			(start 0.674878 -1.100074)
			(end 0.674878 1.100074)
			(stroke
				(width 0.1)
				(type default)
			)
			(layer "F.Fab")
		)
		(fp_line
			(start 0.674878 1.100074)
			(end -0.674878 1.100074)
			(stroke
				(width 0.1)
				(type default)
			)
			(layer "F.Fab")
		)
		(fp_poly
			(pts
				(xy -1.4605 -0.7493) (xy -2.2225 -1.1303) (xy -2.2225 -0.3683)
			)
			(stroke
				(width 0)
				(type default)
			)
			(fill yes)
			(layer "F.Fab")
		)
		(pad "1" smd rect
			(at -0.899922 -0.750062 270)
			(size 0.6096 0.6096)
			(layers "F.Cu" "F.Mask" "F.Paste")
			(net "GND")
		)
		(pad "2" smd rect
			(at -0.899922 0 270)
			(size 0.4064 0.6096)
			(layers "F.Cu" "F.Mask" "F.Paste")
			(net "P3V3_NIC5_PG_G1")
		)
		(pad "3" smd rect
			(at -0.899922 0.750062 270)
			(size 0.6096 0.6096)
			(layers "F.Cu" "F.Mask" "F.Paste")
			(net "PWRGD_P3V3_NIC5_D")
		)
		(pad "4" smd rect
			(at 0.899922 0.750062 270)
			(size 0.6096 0.6096)
			(layers "F.Cu" "F.Mask" "F.Paste")
			(net "GND")
		)
		(pad "5" smd rect
			(at 0.899922 0 270)
			(size 0.4064 0.6096)
			(layers "F.Cu" "F.Mask" "F.Paste")
			(net "P3V3_NIC5_PG_G2")
		)
		(pad "6" smd rect
			(at 0.899922 -0.750062 270)
			(size 0.6096 0.6096)
			(layers "F.Cu" "F.Mask" "F.Paste")
			(net "P3V3_NIC5_PG_G2")
		)
	)
	(footprint ""
		(layer "F.Cu")
		(at 379.307344 -260.639814 -90)
		(property "Reference" "C3556"
			(at 0 0 270)
			(layer "F.SilkS")
			(hide yes)
			(effects
				(font
					(size 1.27 1.27)
				)
			)
		)
		(property "Value" ""
			(at 0 0 270)
			(layer "F.Fab")
			(effects
				(font
					(size 1.27 1.27)
				)
			)
		)
		(duplicate_pad_numbers_are_jumpers no)
		(fp_line
			(start -0.299974 0.150114)
			(end -0.299974 -0.150114)
			(stroke
				(width 0.1)
				(type default)
			)
			(layer "F.Fab")
		)
		(fp_line
			(start 0.299974 0.150114)
			(end -0.299974 0.150114)
			(stroke
				(width 0.1)
				(type default)
			)
			(layer "F.Fab")
		)
		(fp_line
			(start -0.299974 -0.150114)
			(end 0.299974 -0.150114)
			(stroke
				(width 0.1)
				(type default)
			)
			(layer "F.Fab")
		)
		(fp_line
			(start 0.299974 -0.150114)
			(end 0.299974 0.150114)
			(stroke
				(width 0.1)
				(type default)
			)
			(layer "F.Fab")
		)
		(pad "1" smd rect
			(at -0.2667 0 270)
			(size 0.3048 0.381)
			(layers "F.Cu" "F.Mask" "F.Paste")
			(net "P1V8_PLL0_PEX3")
		)
		(pad "2" smd rect
			(at 0.2667 0 270)
			(size 0.3048 0.381)
			(layers "F.Cu" "F.Mask" "F.Paste")
			(net "GND")
		)
	)
	(footprint ""
		(layer "F.Cu")
		(at 122.752612 -156.288994 -90)
		(property "Reference" "PR6886"
			(at 0 0 270)
			(layer "F.SilkS")
			(hide yes)
			(effects
				(font
					(size 1.27 1.27)
				)
			)
		)
		(property "Value" ""
			(at 0 0 270)
			(layer "F.Fab")
			(effects
				(font
					(size 1.27 1.27)
				)
			)
		)
		(duplicate_pad_numbers_are_jumpers no)
		(fp_line
			(start -0.7874 0.4064)
			(end -0.7874 -0.4064)
			(stroke
				(width 0.1524)
				(type default)
			)
			(layer "F.SilkS")
		)
		(fp_line
			(start 0.7874 0.4064)
			(end -0.7874 0.4064)
			(stroke
				(width 0.1524)
				(type default)
			)
			(layer "F.SilkS")
		)
		(fp_line
			(start -0.7874 -0.4064)
			(end 0.7874 -0.4064)
			(stroke
				(width 0.1524)
				(type default)
			)
			(layer "F.SilkS")
		)
		(fp_line
			(start 0.7874 -0.4064)
			(end 0.7874 0.4064)
			(stroke
				(width 0.1524)
				(type default)
			)
			(layer "F.SilkS")
		)
		(fp_line
			(start -0.67945 0.3048)
			(end -0.67945 -0.305054)
			(stroke
				(width 0.1)
				(type default)
			)
			(layer "F.Fab")
		)
		(fp_line
			(start -0.12065 0.3048)
			(end -0.67945 0.3048)
			(stroke
				(width 0.1)
				(type default)
			)
			(layer "F.Fab")
		)
		(fp_line
			(start 0.120396 0.3048)
			(end 0.120396 0.2794)
			(stroke
				(width 0.1)
				(type default)
			)
			(layer "F.Fab")
		)
		(fp_line
			(start 0.67945 0.3048)
			(end 0.120396 0.3048)
			(stroke
				(width 0.1)
				(type default)
			)
			(layer "F.Fab")
		)
		(fp_line
			(start -0.12065 0.2794)
			(end -0.12065 0.3048)
			(stroke
				(width 0.1)
				(type default)
			)
			(layer "F.Fab")
		)
		(fp_line
			(start 0.120396 0.2794)
			(end -0.12065 0.2794)
			(stroke
				(width 0.1)
				(type default)
			)
			(layer "F.Fab")
		)
		(fp_line
			(start -0.12065 -0.2794)
			(end 0.12065 -0.2794)
			(stroke
				(width 0.1)
				(type default)
			)
			(layer "F.Fab")
		)
		(fp_line
			(start 0.12065 -0.2794)
			(end 0.12065 -0.3048)
			(stroke
				(width 0.1)
				(type default)
			)
			(layer "F.Fab")
		)
		(fp_line
			(start 0.12065 -0.3048)
			(end 0.67945 -0.3048)
			(stroke
				(width 0.1)
				(type default)
			)
			(layer "F.Fab")
		)
		(fp_line
			(start 0.67945 -0.3048)
			(end 0.67945 0.3048)
			(stroke
				(width 0.1)
				(type default)
			)
			(layer "F.Fab")
		)
		(fp_line
			(start -0.67945 -0.305054)
			(end -0.12065 -0.305054)
			(stroke
				(width 0.1)
				(type default)
			)
			(layer "F.Fab")
		)
		(fp_line
			(start -0.12065 -0.305054)
			(end -0.12065 -0.2794)
			(stroke
				(width 0.1)
				(type default)
			)
			(layer "F.Fab")
		)
		(pad "1" smd circle
			(at -0.40005 0 270)
			(size 0 0)
			(layers "F.Cu" "F.Mask" "F.Paste")
			(net "P12V_NIC2_CO_OV_FB")
		)
		(pad "2" smd circle
			(at 0.40005 0 270)
			(size 0 0)
			(layers "F.Cu" "F.Mask" "F.Paste")
			(net "P12V_NIC2_R")
		)
	)
	(footprint ""
		(layer "F.Cu")
		(at 279.519888 -127.700024)
		(property "Reference" "J24"
			(at -5.198618 34.837624 90)
			(unlocked yes)
			(layer "F.SilkS")
			(effects
				(font
					(size 0.7874 0.5842)
					(thickness 0.1524)
				)
				(justify left)
			)
		)
		(property "Value" ""
			(at 0 0 0)
			(layer "F.Fab")
			(effects
				(font
					(size 1.27 1.27)
				)
			)
		)
		(duplicate_pad_numbers_are_jumpers no)
		(fp_line
			(start -4.507484 34.720022)
			(end -0.5588 34.720022)
			(stroke
				(width 0.1524)
				(type default)
			)
			(layer "F.SilkS")
		)
		(fp_line
			(start -0.57658 -34.720022)
			(end -4.507484 -34.720022)
			(stroke
				(width 0.1524)
				(type default)
			)
			(layer "F.SilkS")
		)
		(fp_line
			(start 2.6035 34.720022)
			(end 4.507484 34.720022)
			(stroke
				(width 0.1524)
				(type default)
			)
			(layer "F.SilkS")
		)
		(fp_line
			(start 4.507484 -34.720022)
			(end 2.6162 -34.720022)
			(stroke
				(width 0.1524)
				(type default)
			)
			(layer "F.SilkS")
		)
		(fp_line
			(start 4.507484 -21.5265)
			(end 4.507484 -34.720022)
			(stroke
				(width 0.1524)
				(type default)
			)
			(layer "F.SilkS")
		)
		(fp_poly
			(pts
				(xy 5.735574 -17.957038) (xy 5.735574 -18.973038) (xy 4.719574 -18.465038)
			)
			(stroke
				(width 0)
				(type default)
			)
			(fill yes)
			(layer "F.SilkS")
		)
		(fp_line
			(start -4.507484 -34.720022)
			(end -4.507484 34.720022)
			(stroke
				(width 0.1)
				(type default)
			)
			(layer "F.Fab")
		)
		(fp_line
			(start -4.507484 34.720022)
			(end 4.507484 34.720022)
			(stroke
				(width 0.1)
				(type default)
			)
			(layer "F.Fab")
		)
		(fp_line
			(start 4.507484 -34.720022)
			(end -4.507484 -34.720022)
			(stroke
				(width 0.1)
				(type default)
			)
			(layer "F.Fab")
		)
		(fp_line
			(start 4.507484 34.720022)
			(end 4.507484 -34.720022)
			(stroke
				(width 0.1)
				(type default)
			)
			(layer "F.Fab")
		)
		(fp_poly
			(pts
				(xy 5.735574 -17.957038) (xy 5.735574 -18.973038) (xy 4.719574 -18.465038)
			)
			(stroke
				(width 0)
				(type default)
			)
			(fill yes)
			(layer "F.Fab")
		)
		(pad "" np_thru_hole circle
			(at -0.727456 -32.485076)
			(size 1.1176 1.1176)
			(drill 1.1176)
			(layers "*.Cu" "*.Mask")
			(clearance 0.381)
			(thermal_gap 0.381)
		)
		(pad "" np_thru_hole circle
			(at 1.022604 32.485076)
			(size 1.1176 1.1176)
			(drill 1.1176)
			(layers "*.Cu" "*.Mask")
			(clearance 0.381)
			(thermal_gap 0.381)
		)
		(pad "A1" smd rect
			(at 3.322574 -18.465038 270)
			(size 0.3556 1.2192)
			(layers "F.Cu" "F.Mask" "F.Paste")
			(net "GND")
		)
		(pad "A2" smd rect
			(at 3.322574 -17.86509 270)
			(size 0.3556 1.2192)
			(layers "F.Cu" "F.Mask" "F.Paste")
			(net "GND")
		)
		(pad "A3" smd rect
			(at 3.322574 -17.264888 270)
			(size 0.3556 1.2192)
			(layers "F.Cu" "F.Mask" "F.Paste")
			(net "GND")
		)
		(pad "A4" smd rect
			(at 3.322574 -16.66494 270)
			(size 0.3556 1.2192)
			(layers "F.Cu" "F.Mask" "F.Paste")
			(net "GND")
		)
		(pad "A5" smd rect
			(at 3.322574 -16.064992 270)
			(size 0.3556 1.2192)
			(layers "F.Cu" "F.Mask" "F.Paste")
			(net "GND")
		)
		(pad "A6" smd rect
			(at 3.322574 -15.465044 270)
			(size 0.3556 1.2192)
			(layers "F.Cu" "F.Mask" "F.Paste")
			(net "GND")
		)
		(pad "A7" smd rect
			(at 3.322574 -14.865096 270)
			(size 0.3556 1.2192)
			(layers "F.Cu" "F.Mask" "F.Paste")
			(net "SMB_NIC4_LS_SCL")
		)
		(pad "A8" smd rect
			(at 3.322574 -14.264894 270)
			(size 0.3556 1.2192)
			(layers "F.Cu" "F.Mask" "F.Paste")
			(net "SMB_NIC4_LS_SDA")
		)
		(pad "A9" smd rect
			(at 3.322574 -13.664946 270)
			(size 0.3556 1.2192)
			(layers "F.Cu" "F.Mask" "F.Paste")
			(net "RST_SMB_NIC4_MUX_ISO_R_N")
		)
		(pad "A10" smd rect
			(at 3.322574 -13.064998 270)
			(size 0.3556 1.2192)
			(layers "F.Cu" "F.Mask" "F.Paste")
			(net "GND")
		)
		(pad "A11" smd rect
			(at 3.322574 -12.46505 270)
			(size 0.3556 1.2192)
			(layers "F.Cu" "F.Mask" "F.Paste")
			(net "RST_NIC4_PERST1_R_N")
		)
		(pad "A12" smd rect
			(at 3.322574 -11.865102 270)
			(size 0.3556 1.2192)
			(layers "F.Cu" "F.Mask" "F.Paste")
			(net "PRSNTB2_NIC4_N")
		)
		(pad "A13" smd rect
			(at 3.322574 -11.2649 270)
			(size 0.3556 1.2192)
			(layers "F.Cu" "F.Mask" "F.Paste")
			(net "GND")
		)
		(pad "A14" smd rect
			(at 3.322574 -10.664952 270)
			(size 0.3556 1.2192)
			(layers "F.Cu" "F.Mask" "F.Paste")
			(net "Net_2627")
		)
		(pad "A15" smd rect
			(at 3.322574 -10.065004 270)
			(size 0.3556 1.2192)
			(layers "F.Cu" "F.Mask" "F.Paste")
			(net "Net_2630")
		)
		(pad "A16" smd rect
			(at 3.322574 -9.465056 270)
			(size 0.3556 1.2192)
			(layers "F.Cu" "F.Mask" "F.Paste")
			(net "GND")
		)
		(pad "A17" smd rect
			(at 3.322574 -8.865108 270)
			(size 0.3556 1.2192)
			(layers "F.Cu" "F.Mask" "F.Paste")
			(net "P5E_PEX2_STN1_RX_DN<31>")
		)
		(pad "A18" smd rect
			(at 3.322574 -8.264906 270)
			(size 0.3556 1.2192)
			(layers "F.Cu" "F.Mask" "F.Paste")
			(net "P5E_PEX2_STN1_RX_DP<31>")
		)
		(pad "A19" smd rect
			(at 3.322574 -7.664958 270)
			(size 0.3556 1.2192)
			(layers "F.Cu" "F.Mask" "F.Paste")
			(net "GND")
		)
		(pad "A20" smd rect
			(at 3.322574 -7.06501 270)
			(size 0.3556 1.2192)
			(layers "F.Cu" "F.Mask" "F.Paste")
			(net "P5E_PEX2_STN1_RX_DN<30>")
		)
		(pad "A21" smd rect
			(at 3.322574 -6.465062 270)
			(size 0.3556 1.2192)
			(layers "F.Cu" "F.Mask" "F.Paste")
			(net "P5E_PEX2_STN1_RX_DP<30>")
		)
		(pad "A22" smd rect
			(at 3.322574 -5.865114 270)
			(size 0.3556 1.2192)
			(layers "F.Cu" "F.Mask" "F.Paste")
			(net "GND")
		)
		(pad "A23" smd rect
			(at 3.322574 -5.264912 270)
			(size 0.3556 1.2192)
			(layers "F.Cu" "F.Mask" "F.Paste")
			(net "P5E_PEX2_STN1_RX_DN<29>")
		)
		(pad "A24" smd rect
			(at 3.322574 -4.664964 270)
			(size 0.3556 1.2192)
			(layers "F.Cu" "F.Mask" "F.Paste")
			(net "P5E_PEX2_STN1_RX_DP<29>")
		)
		(pad "A25" smd rect
			(at 3.322574 -4.065016 270)
			(size 0.3556 1.2192)
			(layers "F.Cu" "F.Mask" "F.Paste")
			(net "GND")
		)
		(pad "A26" smd rect
			(at 3.322574 -3.465068 270)
			(size 0.3556 1.2192)
			(layers "F.Cu" "F.Mask" "F.Paste")
			(net "P5E_PEX2_STN1_RX_DN<28>")
		)
		(pad "A27" smd rect
			(at 3.322574 -2.86512 270)
			(size 0.3556 1.2192)
			(layers "F.Cu" "F.Mask" "F.Paste")
			(net "P5E_PEX2_STN1_RX_DP<28>")
		)
		(pad "A28" smd rect
			(at 3.322574 -2.264918 270)
			(size 0.3556 1.2192)
			(layers "F.Cu" "F.Mask" "F.Paste")
			(net "GND")
		)
		(pad "A29" smd rect
			(at 3.322574 1.74498 270)
			(size 0.3556 1.2192)
			(layers "F.Cu" "F.Mask" "F.Paste")
			(net "GND")
		)
		(pad "A30" smd rect
			(at 3.322574 2.344928 270)
			(size 0.3556 1.2192)
			(layers "F.Cu" "F.Mask" "F.Paste")
			(net "P5E_PEX2_STN1_RX_DN<27>")
		)
		(pad "A31" smd rect
			(at 3.322574 2.944876 270)
			(size 0.3556 1.2192)
			(layers "F.Cu" "F.Mask" "F.Paste")
			(net "P5E_PEX2_STN1_RX_DP<27>")
		)
		(pad "A32" smd rect
			(at 3.322574 3.545078 270)
			(size 0.3556 1.2192)
			(layers "F.Cu" "F.Mask" "F.Paste")
			(net "GND")
		)
		(pad "A33" smd rect
			(at 3.322574 4.145026 270)
			(size 0.3556 1.2192)
			(layers "F.Cu" "F.Mask" "F.Paste")
			(net "P5E_PEX2_STN1_RX_DN<26>")
		)
		(pad "A34" smd rect
			(at 3.322574 4.744974 270)
			(size 0.3556 1.2192)
			(layers "F.Cu" "F.Mask" "F.Paste")
			(net "P5E_PEX2_STN1_RX_DP<26>")
		)
		(pad "A35" smd rect
			(at 3.322574 5.344922 270)
			(size 0.3556 1.2192)
			(layers "F.Cu" "F.Mask" "F.Paste")
			(net "GND")
		)
		(pad "A36" smd rect
			(at 3.322574 5.945124 270)
			(size 0.3556 1.2192)
			(layers "F.Cu" "F.Mask" "F.Paste")
			(net "P5E_PEX2_STN1_RX_DN<25>")
		)
		(pad "A37" smd rect
			(at 3.322574 6.545072 270)
			(size 0.3556 1.2192)
			(layers "F.Cu" "F.Mask" "F.Paste")
			(net "P5E_PEX2_STN1_RX_DP<25>")
		)
		(pad "A38" smd rect
			(at 3.322574 7.14502 270)
			(size 0.3556 1.2192)
			(layers "F.Cu" "F.Mask" "F.Paste")
			(net "GND")
		)
		(pad "A39" smd rect
			(at 3.322574 7.744968 270)
			(size 0.3556 1.2192)
			(layers "F.Cu" "F.Mask" "F.Paste")
			(net "P5E_PEX2_STN1_RX_DN<24>")
		)
		(pad "A40" smd rect
			(at 3.322574 8.344916 270)
			(size 0.3556 1.2192)
			(layers "F.Cu" "F.Mask" "F.Paste")
			(net "P5E_PEX2_STN1_RX_DP<24>")
		)
		(pad "A41" smd rect
			(at 3.322574 8.945118 270)
			(size 0.3556 1.2192)
			(layers "F.Cu" "F.Mask" "F.Paste")
			(net "GND")
		)
		(pad "A42" smd rect
			(at 3.322574 9.545066 270)
			(size 0.3556 1.2192)
			(layers "F.Cu" "F.Mask" "F.Paste")
			(net "PRSNTB1_NIC4_N")
		)
		(pad "A43" smd rect
			(at 3.322574 14.454886 270)
			(size 0.3556 1.2192)
			(layers "F.Cu" "F.Mask" "F.Paste")
			(net "GND")
		)
		(pad "A44" smd rect
			(at 3.322574 15.055088 270)
			(size 0.3556 1.2192)
			(layers "F.Cu" "F.Mask" "F.Paste")
			(net "P5E_PEX2_STN1_RX_DN<23>")
		)
		(pad "A45" smd rect
			(at 3.322574 15.655036 270)
			(size 0.3556 1.2192)
			(layers "F.Cu" "F.Mask" "F.Paste")
			(net "P5E_PEX2_STN1_RX_DP<23>")
		)
		(pad "A46" smd rect
			(at 3.322574 16.254984 270)
			(size 0.3556 1.2192)
			(layers "F.Cu" "F.Mask" "F.Paste")
			(net "GND")
		)
		(pad "A47" smd rect
			(at 3.322574 16.854932 270)
			(size 0.3556 1.2192)
			(layers "F.Cu" "F.Mask" "F.Paste")
			(net "P5E_PEX2_STN1_RX_DN<22>")
		)
		(pad "A48" smd rect
			(at 3.322574 17.45488 270)
			(size 0.3556 1.2192)
			(layers "F.Cu" "F.Mask" "F.Paste")
			(net "P5E_PEX2_STN1_RX_DP<22>")
		)
		(pad "A49" smd rect
			(at 3.322574 18.055082 270)
			(size 0.3556 1.2192)
			(layers "F.Cu" "F.Mask" "F.Paste")
			(net "GND")
		)
		(pad "A50" smd rect
			(at 3.322574 18.65503 270)
			(size 0.3556 1.2192)
			(layers "F.Cu" "F.Mask" "F.Paste")
			(net "P5E_PEX2_STN1_RX_DN<21>")
		)
		(pad "A51" smd rect
			(at 3.322574 19.254978 270)
			(size 0.3556 1.2192)
			(layers "F.Cu" "F.Mask" "F.Paste")
			(net "P5E_PEX2_STN1_RX_DP<21>")
		)
		(pad "A52" smd rect
			(at 3.322574 19.854926 270)
			(size 0.3556 1.2192)
			(layers "F.Cu" "F.Mask" "F.Paste")
			(net "GND")
		)
		(pad "A53" smd rect
			(at 3.322574 20.455128 270)
			(size 0.3556 1.2192)
			(layers "F.Cu" "F.Mask" "F.Paste")
			(net "P5E_PEX2_STN1_RX_DN<20>")
		)
		(pad "A54" smd rect
			(at 3.322574 21.055076 270)
			(size 0.3556 1.2192)
			(layers "F.Cu" "F.Mask" "F.Paste")
			(net "P5E_PEX2_STN1_RX_DP<20>")
		)
		(pad "A55" smd rect
			(at 3.322574 21.655024 270)
			(size 0.3556 1.2192)
			(layers "F.Cu" "F.Mask" "F.Paste")
			(net "GND")
		)
		(pad "A56" smd rect
			(at 3.322574 22.254972 270)
			(size 0.3556 1.2192)
			(layers "F.Cu" "F.Mask" "F.Paste")
			(net "P5E_PEX2_STN1_RX_DN<19>")
		)
		(pad "A57" smd rect
			(at 3.322574 22.85492 270)
			(size 0.3556 1.2192)
			(layers "F.Cu" "F.Mask" "F.Paste")
			(net "P5E_PEX2_STN1_RX_DP<19>")
		)
		(pad "A58" smd rect
			(at 3.322574 23.455122 270)
			(size 0.3556 1.2192)
			(layers "F.Cu" "F.Mask" "F.Paste")
			(net "GND")
		)
		(pad "A59" smd rect
			(at 3.322574 24.05507 270)
			(size 0.3556 1.2192)
			(layers "F.Cu" "F.Mask" "F.Paste")
			(net "P5E_PEX2_STN1_RX_DN<18>")
		)
		(pad "A60" smd rect
			(at 3.322574 24.655018 270)
			(size 0.3556 1.2192)
			(layers "F.Cu" "F.Mask" "F.Paste")
			(net "P5E_PEX2_STN1_RX_DP<18>")
		)
		(pad "A61" smd rect
			(at 3.322574 25.254966 270)
			(size 0.3556 1.2192)
			(layers "F.Cu" "F.Mask" "F.Paste")
			(net "GND")
		)
		(pad "A62" smd rect
			(at 3.322574 25.854914 270)
			(size 0.3556 1.2192)
			(layers "F.Cu" "F.Mask" "F.Paste")
			(net "P5E_PEX2_STN1_RX_DN<17>")
		)
		(pad "A63" smd rect
			(at 3.322574 26.455116 270)
			(size 0.3556 1.2192)
			(layers "F.Cu" "F.Mask" "F.Paste")
			(net "P5E_PEX2_STN1_RX_DP<17>")
		)
		(pad "A64" smd rect
			(at 3.322574 27.055064 270)
			(size 0.3556 1.2192)
			(layers "F.Cu" "F.Mask" "F.Paste")
			(net "GND")
		)
		(pad "A65" smd rect
			(at 3.322574 27.655012 270)
			(size 0.3556 1.2192)
			(layers "F.Cu" "F.Mask" "F.Paste")
			(net "P5E_PEX2_STN1_RX_DN<16>")
		)
		(pad "A66" smd rect
			(at 3.322574 28.25496 270)
			(size 0.3556 1.2192)
			(layers "F.Cu" "F.Mask" "F.Paste")
			(net "P5E_PEX2_STN1_RX_DP<16>")
		)
		(pad "A67" smd rect
			(at 3.322574 28.854908 270)
			(size 0.3556 1.2192)
			(layers "F.Cu" "F.Mask" "F.Paste")
			(net "GND")
		)
		(pad "A68" smd rect
			(at 3.322574 29.45511 270)
			(size 0.3556 1.2192)
			(layers "F.Cu" "F.Mask" "F.Paste")
			(net "Net_2635")
		)
		(pad "A69" smd rect
			(at 3.322574 30.055058 270)
			(size 0.3556 1.2192)
			(layers "F.Cu" "F.Mask" "F.Paste")
			(net "Net_2636")
		)
		(pad "A70" smd rect
			(at 3.322574 30.655006 270)
			(size 0.3556 1.2192)
			(layers "F.Cu" "F.Mask" "F.Paste")
			(net "NIC4_PWRBRK_R_N")
		)
		(pad "B1" smd rect
			(at -1.27762 -18.465038 270)
			(size 0.3556 1.2192)
			(layers "F.Cu" "F.Mask" "F.Paste")
			(net "P12V_NIC4")
		)
		(pad "B2" smd rect
			(at -1.27762 -17.86509 270)
			(size 0.3556 1.2192)
			(layers "F.Cu" "F.Mask" "F.Paste")
			(net "P12V_NIC4")
		)
		(pad "B3" smd rect
			(at -1.27762 -17.264888 270)
			(size 0.3556 1.2192)
			(layers "F.Cu" "F.Mask" "F.Paste")
			(net "P12V_NIC4")
		)
		(pad "B4" smd rect
			(at -1.27762 -16.66494 270)
			(size 0.3556 1.2192)
			(layers "F.Cu" "F.Mask" "F.Paste")
			(net "P12V_NIC4")
		)
		(pad "B5" smd rect
			(at -1.27762 -16.064992 270)
			(size 0.3556 1.2192)
			(layers "F.Cu" "F.Mask" "F.Paste")
			(net "P12V_NIC4")
		)
		(pad "B6" smd rect
			(at -1.27762 -15.465044 270)
			(size 0.3556 1.2192)
			(layers "F.Cu" "F.Mask" "F.Paste")
			(net "P12V_NIC4")
		)
		(pad "B7" smd rect
			(at -1.27762 -14.865096 270)
			(size 0.3556 1.2192)
			(layers "F.Cu" "F.Mask" "F.Paste")
			(net "NIC4_BIF0_N")
		)
		(pad "B8" smd rect
			(at -1.27762 -14.264894 270)
			(size 0.3556 1.2192)
			(layers "F.Cu" "F.Mask" "F.Paste")
			(net "NIC4_BIF1_N")
		)
		(pad "B9" smd rect
			(at -1.27762 -13.664946 270)
			(size 0.3556 1.2192)
			(layers "F.Cu" "F.Mask" "F.Paste")
			(net "NIC4_BIF2_N")
		)
		(pad "B10" smd rect
			(at -1.27762 -13.064998 270)
			(size 0.3556 1.2192)
			(layers "F.Cu" "F.Mask" "F.Paste")
			(net "RST_NIC4_PERST0_R_N")
		)
		(pad "B11" smd rect
			(at -1.27762 -12.46505 270)
			(size 0.3556 1.2192)
			(layers "F.Cu" "F.Mask" "F.Paste")
			(net "P3V3_NIC4")
		)
		(pad "B12" smd rect
			(at -1.27762 -11.865102 270)
			(size 0.3556 1.2192)
			(layers "F.Cu" "F.Mask" "F.Paste")
			(net "NIC4_AUX_PWR_EN_R")
		)
		(pad "B13" smd rect
			(at -1.27762 -11.2649 270)
			(size 0.3556 1.2192)
			(layers "F.Cu" "F.Mask" "F.Paste")
			(net "GND")
		)
		(pad "B14" smd rect
			(at -1.27762 -10.664952 270)
			(size 0.3556 1.2192)
			(layers "F.Cu" "F.Mask" "F.Paste")
			(net "CLK_100M_DB2000QL_NIC4_R_DN")
		)
		(pad "B15" smd rect
			(at -1.27762 -10.065004 270)
			(size 0.3556 1.2192)
			(layers "F.Cu" "F.Mask" "F.Paste")
			(net "CLK_100M_DB2000QL_NIC4_R_DP")
		)
		(pad "B16" smd rect
			(at -1.27762 -9.465056 270)
			(size 0.3556 1.2192)
			(layers "F.Cu" "F.Mask" "F.Paste")
			(net "GND")
		)
		(pad "B17" smd rect
			(at -1.27762 -8.865108 270)
			(size 0.3556 1.2192)
			(layers "F.Cu" "F.Mask" "F.Paste")
			(net "P5E_PEX2_STN1_TX_C_DP<31>")
		)
		(pad "B18" smd rect
			(at -1.27762 -8.264906 270)
			(size 0.3556 1.2192)
			(layers "F.Cu" "F.Mask" "F.Paste")
			(net "P5E_PEX2_STN1_TX_C_DN<31>")
		)
		(pad "B19" smd rect
			(at -1.27762 -7.664958 270)
			(size 0.3556 1.2192)
			(layers "F.Cu" "F.Mask" "F.Paste")
			(net "GND")
		)
		(pad "B20" smd rect
			(at -1.27762 -7.06501 270)
			(size 0.3556 1.2192)
			(layers "F.Cu" "F.Mask" "F.Paste")
			(net "P5E_PEX2_STN1_TX_C_DN<30>")
		)
		(pad "B21" smd rect
			(at -1.27762 -6.465062 270)
			(size 0.3556 1.2192)
			(layers "F.Cu" "F.Mask" "F.Paste")
			(net "P5E_PEX2_STN1_TX_C_DP<30>")
		)
		(pad "B22" smd rect
			(at -1.27762 -5.865114 270)
			(size 0.3556 1.2192)
			(layers "F.Cu" "F.Mask" "F.Paste")
			(net "GND")
		)
		(pad "B23" smd rect
			(at -1.27762 -5.264912 270)
			(size 0.3556 1.2192)
			(layers "F.Cu" "F.Mask" "F.Paste")
			(net "P5E_PEX2_STN1_TX_C_DP<29>")
		)
		(pad "B24" smd rect
			(at -1.27762 -4.664964 270)
			(size 0.3556 1.2192)
			(layers "F.Cu" "F.Mask" "F.Paste")
			(net "P5E_PEX2_STN1_TX_C_DN<29>")
		)
		(pad "B25" smd rect
			(at -1.27762 -4.065016 270)
			(size 0.3556 1.2192)
			(layers "F.Cu" "F.Mask" "F.Paste")
			(net "GND")
		)
		(pad "B26" smd rect
			(at -1.27762 -3.465068 270)
			(size 0.3556 1.2192)
			(layers "F.Cu" "F.Mask" "F.Paste")
			(net "P5E_PEX2_STN1_TX_C_DN<28>")
		)
		(pad "B27" smd rect
			(at -1.27762 -2.86512 270)
			(size 0.3556 1.2192)
			(layers "F.Cu" "F.Mask" "F.Paste")
			(net "P5E_PEX2_STN1_TX_C_DP<28>")
		)
		(pad "B28" smd rect
			(at -1.27762 -2.264918 270)
			(size 0.3556 1.2192)
			(layers "F.Cu" "F.Mask" "F.Paste")
			(net "GND")
		)
		(pad "B29" smd rect
			(at -1.27762 1.74498 270)
			(size 0.3556 1.2192)
			(layers "F.Cu" "F.Mask" "F.Paste")
			(net "GND")
		)
		(pad "B30" smd rect
			(at -1.27762 2.344928 270)
			(size 0.3556 1.2192)
			(layers "F.Cu" "F.Mask" "F.Paste")
			(net "P5E_PEX2_STN1_TX_C_DP<27>")
		)
		(pad "B31" smd rect
			(at -1.27762 2.944876 270)
			(size 0.3556 1.2192)
			(layers "F.Cu" "F.Mask" "F.Paste")
			(net "P5E_PEX2_STN1_TX_C_DN<27>")
		)
		(pad "B32" smd rect
			(at -1.27762 3.545078 270)
			(size 0.3556 1.2192)
			(layers "F.Cu" "F.Mask" "F.Paste")
			(net "GND")
		)
		(pad "B33" smd rect
			(at -1.27762 4.145026 270)
			(size 0.3556 1.2192)
			(layers "F.Cu" "F.Mask" "F.Paste")
			(net "P5E_PEX2_STN1_TX_C_DN<26>")
		)
		(pad "B34" smd rect
			(at -1.27762 4.744974 270)
			(size 0.3556 1.2192)
			(layers "F.Cu" "F.Mask" "F.Paste")
			(net "P5E_PEX2_STN1_TX_C_DP<26>")
		)
		(pad "B35" smd rect
			(at -1.27762 5.344922 270)
			(size 0.3556 1.2192)
			(layers "F.Cu" "F.Mask" "F.Paste")
			(net "GND")
		)
		(pad "B36" smd rect
			(at -1.27762 5.945124 270)
			(size 0.3556 1.2192)
			(layers "F.Cu" "F.Mask" "F.Paste")
			(net "P5E_PEX2_STN1_TX_C_DP<25>")
		)
		(pad "B37" smd rect
			(at -1.27762 6.545072 270)
			(size 0.3556 1.2192)
			(layers "F.Cu" "F.Mask" "F.Paste")
			(net "P5E_PEX2_STN1_TX_C_DN<25>")
		)
		(pad "B38" smd rect
			(at -1.27762 7.14502 270)
			(size 0.3556 1.2192)
			(layers "F.Cu" "F.Mask" "F.Paste")
			(net "GND")
		)
		(pad "B39" smd rect
			(at -1.27762 7.744968 270)
			(size 0.3556 1.2192)
			(layers "F.Cu" "F.Mask" "F.Paste")
			(net "P5E_PEX2_STN1_TX_C_DN<24>")
		)
		(pad "B40" smd rect
			(at -1.27762 8.344916 270)
			(size 0.3556 1.2192)
			(layers "F.Cu" "F.Mask" "F.Paste")
			(net "P5E_PEX2_STN1_TX_C_DP<24>")
		)
		(pad "B41" smd rect
			(at -1.27762 8.945118 270)
			(size 0.3556 1.2192)
			(layers "F.Cu" "F.Mask" "F.Paste")
			(net "GND")
		)
		(pad "B42" smd rect
			(at -1.27762 9.545066 270)
			(size 0.3556 1.2192)
			(layers "F.Cu" "F.Mask" "F.Paste")
			(net "PRSNTB0_NIC4_N")
		)
		(pad "B43" smd rect
			(at -1.27762 14.454886 270)
			(size 0.3556 1.2192)
			(layers "F.Cu" "F.Mask" "F.Paste")
			(net "GND")
		)
		(pad "B44" smd rect
			(at -1.27762 15.055088 270)
			(size 0.3556 1.2192)
			(layers "F.Cu" "F.Mask" "F.Paste")
			(net "P5E_PEX2_STN1_TX_C_DP<23>")
		)
		(pad "B45" smd rect
			(at -1.27762 15.655036 270)
			(size 0.3556 1.2192)
			(layers "F.Cu" "F.Mask" "F.Paste")
			(net "P5E_PEX2_STN1_TX_C_DN<23>")
		)
		(pad "B46" smd rect
			(at -1.27762 16.254984 270)
			(size 0.3556 1.2192)
			(layers "F.Cu" "F.Mask" "F.Paste")
			(net "GND")
		)
		(pad "B47" smd rect
			(at -1.27762 16.854932 270)
			(size 0.3556 1.2192)
			(layers "F.Cu" "F.Mask" "F.Paste")
			(net "P5E_PEX2_STN1_TX_C_DN<22>")
		)
		(pad "B48" smd rect
			(at -1.27762 17.45488 270)
			(size 0.3556 1.2192)
			(layers "F.Cu" "F.Mask" "F.Paste")
			(net "P5E_PEX2_STN1_TX_C_DP<22>")
		)
		(pad "B49" smd rect
			(at -1.27762 18.055082 270)
			(size 0.3556 1.2192)
			(layers "F.Cu" "F.Mask" "F.Paste")
			(net "GND")
		)
		(pad "B50" smd rect
			(at -1.27762 18.65503 270)
			(size 0.3556 1.2192)
			(layers "F.Cu" "F.Mask" "F.Paste")
			(net "P5E_PEX2_STN1_TX_C_DP<21>")
		)
		(pad "B51" smd rect
			(at -1.27762 19.254978 270)
			(size 0.3556 1.2192)
			(layers "F.Cu" "F.Mask" "F.Paste")
			(net "P5E_PEX2_STN1_TX_C_DN<21>")
		)
		(pad "B52" smd rect
			(at -1.27762 19.854926 270)
			(size 0.3556 1.2192)
			(layers "F.Cu" "F.Mask" "F.Paste")
			(net "GND")
		)
		(pad "B53" smd rect
			(at -1.27762 20.455128 270)
			(size 0.3556 1.2192)
			(layers "F.Cu" "F.Mask" "F.Paste")
			(net "P5E_PEX2_STN1_TX_C_DN<20>")
		)
		(pad "B54" smd rect
			(at -1.27762 21.055076 270)
			(size 0.3556 1.2192)
			(layers "F.Cu" "F.Mask" "F.Paste")
			(net "P5E_PEX2_STN1_TX_C_DP<20>")
		)
		(pad "B55" smd rect
			(at -1.27762 21.655024 270)
			(size 0.3556 1.2192)
			(layers "F.Cu" "F.Mask" "F.Paste")
			(net "GND")
		)
		(pad "B56" smd rect
			(at -1.27762 22.254972 270)
			(size 0.3556 1.2192)
			(layers "F.Cu" "F.Mask" "F.Paste")
			(net "P5E_PEX2_STN1_TX_C_DP<19>")
		)
		(pad "B57" smd rect
			(at -1.27762 22.85492 270)
			(size 0.3556 1.2192)
			(layers "F.Cu" "F.Mask" "F.Paste")
			(net "P5E_PEX2_STN1_TX_C_DN<19>")
		)
		(pad "B58" smd rect
			(at -1.27762 23.455122 270)
			(size 0.3556 1.2192)
			(layers "F.Cu" "F.Mask" "F.Paste")
			(net "GND")
		)
		(pad "B59" smd rect
			(at -1.27762 24.05507 270)
			(size 0.3556 1.2192)
			(layers "F.Cu" "F.Mask" "F.Paste")
			(net "P5E_PEX2_STN1_TX_C_DN<18>")
		)
		(pad "B60" smd rect
			(at -1.27762 24.655018 270)
			(size 0.3556 1.2192)
			(layers "F.Cu" "F.Mask" "F.Paste")
			(net "P5E_PEX2_STN1_TX_C_DP<18>")
		)
		(pad "B61" smd rect
			(at -1.27762 25.254966 270)
			(size 0.3556 1.2192)
			(layers "F.Cu" "F.Mask" "F.Paste")
			(net "GND")
		)
		(pad "B62" smd rect
			(at -1.27762 25.854914 270)
			(size 0.3556 1.2192)
			(layers "F.Cu" "F.Mask" "F.Paste")
			(net "P5E_PEX2_STN1_TX_C_DP<17>")
		)
		(pad "B63" smd rect
			(at -1.27762 26.455116 270)
			(size 0.3556 1.2192)
			(layers "F.Cu" "F.Mask" "F.Paste")
			(net "P5E_PEX2_STN1_TX_C_DN<17>")
		)
		(pad "B64" smd rect
			(at -1.27762 27.055064 270)
			(size 0.3556 1.2192)
			(layers "F.Cu" "F.Mask" "F.Paste")
			(net "GND")
		)
		(pad "B65" smd rect
			(at -1.27762 27.655012 270)
			(size 0.3556 1.2192)
			(layers "F.Cu" "F.Mask" "F.Paste")
			(net "P5E_PEX2_STN1_TX_C_DN<16>")
		)
		(pad "B66" smd rect
			(at -1.27762 28.25496 270)
			(size 0.3556 1.2192)
			(layers "F.Cu" "F.Mask" "F.Paste")
			(net "P5E_PEX2_STN1_TX_C_DP<16>")
		)
		(pad "B67" smd rect
			(at -1.27762 28.854908 270)
			(size 0.3556 1.2192)
			(layers "F.Cu" "F.Mask" "F.Paste")
			(net "GND")
		)
		(pad "B68" smd rect
			(at -1.27762 29.45511 270)
			(size 0.3556 1.2192)
			(layers "F.Cu" "F.Mask" "F.Paste")
			(net "Net_2633")
		)
		(pad "B69" smd rect
			(at -1.27762 30.055058 270)
			(size 0.3556 1.2192)
			(layers "F.Cu" "F.Mask" "F.Paste")
			(net "Net_2634")
		)
		(pad "B70" smd rect
			(at -1.27762 30.655006 270)
			(size 0.3556 1.2192)
			(layers "F.Cu" "F.Mask" "F.Paste")
			(net "PRSNTB3_NIC4_N")
		)
		(pad "G1" thru_hole oval
			(at 1.022604 -34.034984 270)
			(size 1.6256 3.4798)
			(drill oval 1.1176 2.4638)
			(layers "*.Cu" "*.Mask")
			(remove_unused_layers no)
			(net "GND")
			(clearance 0.127)
			(thermal_gap 0.127)
		)
		(pad "G2" thru_hole oval
			(at 1.022604 -20.625054 270)
			(size 1.6256 3.4798)
			(drill oval 1.1176 2.4638)
			(layers "*.Cu" "*.Mask")
			(remove_unused_layers no)
			(net "GND")
			(clearance 0.127)
			(thermal_gap 0.127)
		)
		(pad "G3" thru_hole oval
			(at 1.022604 -0.255016 270)
			(size 1.6256 3.4798)
			(drill oval 1.1176 2.4638)
			(layers "*.Cu" "*.Mask")
			(remove_unused_layers no)
			(net "GND")
			(clearance 0.127)
			(thermal_gap 0.127)
		)
		(pad "G4" thru_hole oval
			(at 1.022604 12.005056 270)
			(size 1.6256 3.4798)
			(drill oval 1.1176 2.4638)
			(layers "*.Cu" "*.Mask")
			(remove_unused_layers no)
			(net "GND")
			(clearance 0.127)
			(thermal_gap 0.127)
		)
		(pad "G5" thru_hole oval
			(at 1.022604 34.034984 270)
			(size 1.5748 3.4798)
			(drill oval 1.1176 2.4638)
			(layers "*.Cu" "*.Mask")
			(remove_unused_layers no)
			(net "GND")
			(clearance 0.1524)
			(thermal_gap 0.1524)
		)
		(pad "G6" thru_hole circle
			(at -3.16738 -20.625054)
			(size 1.6256 1.6256)
			(drill 1.1176)
			(layers "*.Cu" "*.Mask")
			(remove_unused_layers no)
			(net "GND")
			(clearance 0)
		)
		(pad "G7" thru_hole circle
			(at -3.16738 12.005056)
			(size 1.6256 1.6256)
			(drill 1.1176)
			(layers "*.Cu" "*.Mask")
			(remove_unused_layers no)
			(net "GND")
			(clearance 0)
		)
		(pad "G8" thru_hole circle
			(at 4.20243 -20.625054)
			(size 1.6256 1.6256)
			(drill 1.1176)
			(layers "*.Cu" "*.Mask")
			(remove_unused_layers no)
			(net "GND")
			(clearance 0)
		)
		(pad "G9" thru_hole circle
			(at 4.20243 12.005056)
			(size 1.6256 1.6256)
			(drill 1.1176)
			(layers "*.Cu" "*.Mask")
			(remove_unused_layers no)
			(net "GND")
			(clearance 0)
		)
		(pad "OA1" smd rect
			(at 3.322574 -30.660086 270)
			(size 0.3556 1.2192)
			(layers "F.Cu" "F.Mask" "F.Paste")
			(net "RST_NIC4_PERST2_R_N")
		)
		(pad "OA2" smd rect
			(at 3.322574 -30.059884 270)
			(size 0.3556 1.2192)
			(layers "F.Cu" "F.Mask" "F.Paste")
			(net "RST_NIC4_PERST3_R_N")
		)
		(pad "OA3" smd rect
			(at 3.322574 -29.459936 270)
			(size 0.3556 1.2192)
			(layers "F.Cu" "F.Mask" "F.Paste")
			(net "Net_2637")
		)
		(pad "OA4" smd rect
			(at 3.322574 -28.859988 270)
			(size 0.3556 1.2192)
			(layers "F.Cu" "F.Mask" "F.Paste")
			(net "NIC4_RBT_ARB_IN")
		)
		(pad "OA5" smd rect
			(at 3.322574 -28.26004 270)
			(size 0.3556 1.2192)
			(layers "F.Cu" "F.Mask" "F.Paste")
			(net "NIC4_RBT_ARB_OUT")
		)
		(pad "OA6" smd rect
			(at 3.322574 -27.660092 270)
			(size 0.3556 1.2192)
			(layers "F.Cu" "F.Mask" "F.Paste")
			(net "NIC4_SLOT_ID1")
		)
		(pad "OA7" smd rect
			(at 3.322574 -27.05989 270)
			(size 0.3556 1.2192)
			(layers "F.Cu" "F.Mask" "F.Paste")
			(net "NCSI_NIC4_TX_EN")
		)
		(pad "OA8" smd rect
			(at 3.322574 -26.459942 270)
			(size 0.3556 1.2192)
			(layers "F.Cu" "F.Mask" "F.Paste")
			(net "NCSI_NIC4_TXD1")
		)
		(pad "OA9" smd rect
			(at 3.322574 -25.859994 270)
			(size 0.3556 1.2192)
			(layers "F.Cu" "F.Mask" "F.Paste")
			(net "NCSI_NIC4_TXD0")
		)
		(pad "OA10" smd rect
			(at 3.322574 -25.260046 270)
			(size 0.3556 1.2192)
			(layers "F.Cu" "F.Mask" "F.Paste")
			(net "GND")
		)
		(pad "OA11" smd rect
			(at 3.322574 -24.660098 270)
			(size 0.3556 1.2192)
			(layers "F.Cu" "F.Mask" "F.Paste")
			(net "Net_2629")
		)
		(pad "OA12" smd rect
			(at 3.322574 -24.059896 270)
			(size 0.3556 1.2192)
			(layers "F.Cu" "F.Mask" "F.Paste")
			(net "Net_2632")
		)
		(pad "OA13" smd rect
			(at 3.322574 -23.459948 270)
			(size 0.3556 1.2192)
			(layers "F.Cu" "F.Mask" "F.Paste")
			(net "GND")
		)
		(pad "OA14" smd rect
			(at 3.322574 -22.86 270)
			(size 0.3556 1.2192)
			(layers "F.Cu" "F.Mask" "F.Paste")
			(net "CLK_50M_NIC4_RBT_REF")
		)
		(pad "OB1" smd rect
			(at -1.27762 -30.660086 270)
			(size 0.3556 1.2192)
			(layers "F.Cu" "F.Mask" "F.Paste")
			(net "PWRGD_NIC4_PWR_GOOD")
		)
		(pad "OB2" smd rect
			(at -1.27762 -30.059884 270)
			(size 0.3556 1.2192)
			(layers "F.Cu" "F.Mask" "F.Paste")
			(net "NIC4_MAIN_PWR_EN_R")
		)
		(pad "OB3" smd rect
			(at -1.27762 -29.459936 270)
			(size 0.3556 1.2192)
			(layers "F.Cu" "F.Mask" "F.Paste")
			(net "NIC4_LD_N")
		)
		(pad "OB4" smd rect
			(at -1.27762 -28.859988 270)
			(size 0.3556 1.2192)
			(layers "F.Cu" "F.Mask" "F.Paste")
			(net "NIC4_DATA_IN")
		)
		(pad "OB5" smd rect
			(at -1.27762 -28.26004 270)
			(size 0.3556 1.2192)
			(layers "F.Cu" "F.Mask" "F.Paste")
			(net "NIC4_DATA_OUT")
		)
		(pad "OB6" smd rect
			(at -1.27762 -27.660092 270)
			(size 0.3556 1.2192)
			(layers "F.Cu" "F.Mask" "F.Paste")
			(net "NIC4_CLK")
		)
		(pad "OB7" smd rect
			(at -1.27762 -27.05989 270)
			(size 0.3556 1.2192)
			(layers "F.Cu" "F.Mask" "F.Paste")
			(net "NIC4_SLOT_ID0")
		)
		(pad "OB8" smd rect
			(at -1.27762 -26.459942 270)
			(size 0.3556 1.2192)
			(layers "F.Cu" "F.Mask" "F.Paste")
			(net "NCSI_NIC4_RXD1")
		)
		(pad "OB9" smd rect
			(at -1.27762 -25.859994 270)
			(size 0.3556 1.2192)
			(layers "F.Cu" "F.Mask" "F.Paste")
			(net "NCSI_NIC4_RXD0")
		)
		(pad "OB10" smd rect
			(at -1.27762 -25.260046 270)
			(size 0.3556 1.2192)
			(layers "F.Cu" "F.Mask" "F.Paste")
			(net "GND")
		)
		(pad "OB11" smd rect
			(at -1.27762 -24.660098 270)
			(size 0.3556 1.2192)
			(layers "F.Cu" "F.Mask" "F.Paste")
			(net "Net_2628")
		)
		(pad "OB12" smd rect
			(at -1.27762 -24.059896 270)
			(size 0.3556 1.2192)
			(layers "F.Cu" "F.Mask" "F.Paste")
			(net "Net_2631")
		)
		(pad "OB13" smd rect
			(at -1.27762 -23.459948 270)
			(size 0.3556 1.2192)
			(layers "F.Cu" "F.Mask" "F.Paste")
			(net "GND")
		)
		(pad "OB14" smd rect
			(at -1.27762 -22.86 270)
			(size 0.3556 1.2192)
			(layers "F.Cu" "F.Mask" "F.Paste")
			(net "NCSI_NIC4_CRS_DV")
		)
		(zone
			(layers "F.Cu" "B.Cu" "In1.Cu" "In2.Cu" "In3.Cu" "In4.Cu" "In5.Cu" "In6.Cu"
				"In7.Cu" "In8.Cu" "In9.Cu" "In10.Cu" "In11.Cu" "In12.Cu" "In13.Cu" "In14.Cu"
				"In15.Cu" "In16.Cu"
			)
			(hatch none 0.5)
			(connect_pads
				(clearance 0)
			)
			(min_thickness 0.25)
			(keepout
				(tracks not_allowed)
				(vias allowed)
				(pads allowed)
				(copperpour not_allowed)
				(footprints allowed)
			)
			(placement
				(enabled no)
				(sheetname "")
			)
			(fill
				(thermal_gap 0.5)
				(thermal_bridge_width 0.5)
				(island_removal_mode 0)
			)
			(polygon
				(pts
					(arc
						(start 279.859232 -160.1851)
						(mid 277.725632 -160.1851)
						(end 279.859232 -160.1851)
					)
				)
			)
		)
		(zone
			(layers "F.Cu" "B.Cu" "In1.Cu" "In2.Cu" "In3.Cu" "In4.Cu" "In5.Cu" "In6.Cu"
				"In7.Cu" "In8.Cu" "In9.Cu" "In10.Cu" "In11.Cu" "In12.Cu" "In13.Cu" "In14.Cu"
				"In15.Cu" "In16.Cu"
			)
			(hatch none 0.5)
			(connect_pads
				(clearance 0)
			)
			(min_thickness 0.25)
			(keepout
				(tracks not_allowed)
				(vias allowed)
				(pads allowed)
				(copperpour not_allowed)
				(footprints allowed)
			)
			(placement
				(enabled no)
				(sheetname "")
			)
			(fill
				(thermal_gap 0.5)
				(thermal_bridge_width 0.5)
				(island_removal_mode 0)
			)
			(polygon
				(pts
					(arc
						(start 281.609292 -95.214948)
						(mid 279.475692 -95.214948)
						(end 281.609292 -95.214948)
					)
				)
			)
		)
	)
	(footprint ""
		(layer "F.Cu")
		(at 78.267814 -51.019456)
		(property "Reference" "PC386"
			(at 0 0 0)
			(layer "F.SilkS")
			(hide yes)
			(effects
				(font
					(size 1.27 1.27)
				)
			)
		)
		(property "Value" ""
			(at 0 0 0)
			(layer "F.Fab")
			(effects
				(font
					(size 1.27 1.27)
				)
			)
		)
		(duplicate_pad_numbers_are_jumpers no)
		(fp_line
			(start -0.7874 -0.4064)
			(end 0.7874 -0.4064)
			(stroke
				(width 0.1524)
				(type default)
			)
			(layer "F.SilkS")
		)
		(fp_line
			(start -0.7874 0.4064)
			(end -0.7874 -0.4064)
			(stroke
				(width 0.1524)
				(type default)
			)
			(layer "F.SilkS")
		)
		(fp_line
			(start 0.7874 -0.4064)
			(end 0.7874 0.4064)
			(stroke
				(width 0.1524)
				(type default)
			)
			(layer "F.SilkS")
		)
		(fp_line
			(start 0.7874 0.4064)
			(end -0.7874 0.4064)
			(stroke
				(width 0.1524)
				(type default)
			)
			(layer "F.SilkS")
		)
		(fp_line
			(start -0.6858 -0.3048)
			(end -0.1016 -0.3048)
			(stroke
				(width 0.1)
				(type default)
			)
			(layer "F.Fab")
		)
		(fp_line
			(start -0.6858 0.3048)
			(end -0.6858 -0.3048)
			(stroke
				(width 0.1)
				(type default)
			)
			(layer "F.Fab")
		)
		(fp_line
			(start -0.1016 -0.3048)
			(end -0.1016 -0.2794)
			(stroke
				(width 0.1)
				(type default)
			)
			(layer "F.Fab")
		)
		(fp_line
			(start -0.1016 -0.2794)
			(end 0.1016 -0.2794)
			(stroke
				(width 0.1)
				(type default)
			)
			(layer "F.Fab")
		)
		(fp_line
			(start -0.1016 0.2794)
			(end -0.1016 0.3048)
			(stroke
				(width 0.1)
				(type default)
			)
			(layer "F.Fab")
		)
		(fp_line
			(start -0.1016 0.3048)
			(end -0.6858 0.3048)
			(stroke
				(width 0.1)
				(type default)
			)
			(layer "F.Fab")
		)
		(fp_line
			(start 0.1016 -0.3048)
			(end 0.6858 -0.3048)
			(stroke
				(width 0.1)
				(type default)
			)
			(layer "F.Fab")
		)
		(fp_line
			(start 0.1016 -0.2794)
			(end 0.1016 -0.3048)
			(stroke
				(width 0.1)
				(type default)
			)
			(layer "F.Fab")
		)
		(fp_line
			(start 0.1016 0.2794)
			(end -0.1016 0.2794)
			(stroke
				(width 0.1)
				(type default)
			)
			(layer "F.Fab")
		)
		(fp_line
			(start 0.1016 0.3048)
			(end 0.1016 0.2794)
			(stroke
				(width 0.1)
				(type default)
			)
			(layer "F.Fab")
		)
		(fp_line
			(start 0.6858 -0.3048)
			(end 0.6858 0.3048)
			(stroke
				(width 0.1)
				(type default)
			)
			(layer "F.Fab")
		)
		(fp_line
			(start 0.6858 0.3048)
			(end 0.1016 0.3048)
			(stroke
				(width 0.1)
				(type default)
			)
			(layer "F.Fab")
		)
		(pad "1" smd rect
			(at -0.40005 0 180)
			(size 0.4572 0.508)
			(layers "F.Cu" "F.Mask" "F.Paste")
			(net "P12V_SSD2_SS")
		)
		(pad "2" smd rect
			(at 0.40005 0 180)
			(size 0.4572 0.508)
			(layers "F.Cu" "F.Mask" "F.Paste")
			(net "GND")
		)
	)
	(footprint ""
		(layer "F.Cu")
		(at 353.196398 -205.150466 -90)
		(property "Reference" "R5779"
			(at 0 0 270)
			(layer "F.SilkS")
			(hide yes)
			(effects
				(font
					(size 1.27 1.27)
				)
			)
		)
		(property "Value" ""
			(at 0 0 270)
			(layer "F.Fab")
			(effects
				(font
					(size 1.27 1.27)
				)
			)
		)
		(duplicate_pad_numbers_are_jumpers no)
		(fp_line
			(start -0.7874 0.4064)
			(end -0.7874 -0.4064)
			(stroke
				(width 0.1524)
				(type default)
			)
			(layer "F.SilkS")
		)
		(fp_line
			(start 0.7874 0.4064)
			(end -0.7874 0.4064)
			(stroke
				(width 0.1524)
				(type default)
			)
			(layer "F.SilkS")
		)
		(fp_line
			(start -0.7874 -0.4064)
			(end 0.7874 -0.4064)
			(stroke
				(width 0.1524)
				(type default)
			)
			(layer "F.SilkS")
		)
		(fp_line
			(start 0.7874 -0.4064)
			(end 0.7874 0.4064)
			(stroke
				(width 0.1524)
				(type default)
			)
			(layer "F.SilkS")
		)
		(fp_line
			(start -0.67945 0.3048)
			(end -0.67945 -0.305054)
			(stroke
				(width 0.1)
				(type default)
			)
			(layer "F.Fab")
		)
		(fp_line
			(start -0.12065 0.3048)
			(end -0.67945 0.3048)
			(stroke
				(width 0.1)
				(type default)
			)
			(layer "F.Fab")
		)
		(fp_line
			(start 0.120396 0.3048)
			(end 0.120396 0.2794)
			(stroke
				(width 0.1)
				(type default)
			)
			(layer "F.Fab")
		)
		(fp_line
			(start 0.67945 0.3048)
			(end 0.120396 0.3048)
			(stroke
				(width 0.1)
				(type default)
			)
			(layer "F.Fab")
		)
		(fp_line
			(start -0.12065 0.2794)
			(end -0.12065 0.3048)
			(stroke
				(width 0.1)
				(type default)
			)
			(layer "F.Fab")
		)
		(fp_line
			(start 0.120396 0.2794)
			(end -0.12065 0.2794)
			(stroke
				(width 0.1)
				(type default)
			)
			(layer "F.Fab")
		)
		(fp_line
			(start -0.12065 -0.2794)
			(end 0.12065 -0.2794)
			(stroke
				(width 0.1)
				(type default)
			)
			(layer "F.Fab")
		)
		(fp_line
			(start 0.12065 -0.2794)
			(end 0.12065 -0.3048)
			(stroke
				(width 0.1)
				(type default)
			)
			(layer "F.Fab")
		)
		(fp_line
			(start 0.12065 -0.3048)
			(end 0.67945 -0.3048)
			(stroke
				(width 0.1)
				(type default)
			)
			(layer "F.Fab")
		)
		(fp_line
			(start 0.67945 -0.3048)
			(end 0.67945 0.3048)
			(stroke
				(width 0.1)
				(type default)
			)
			(layer "F.Fab")
		)
		(fp_line
			(start -0.67945 -0.305054)
			(end -0.12065 -0.305054)
			(stroke
				(width 0.1)
				(type default)
			)
			(layer "F.Fab")
		)
		(fp_line
			(start -0.12065 -0.305054)
			(end -0.12065 -0.2794)
			(stroke
				(width 0.1)
				(type default)
			)
			(layer "F.Fab")
		)
		(pad "1" smd circle
			(at -0.40005 0 270)
			(size 0 0)
			(layers "F.Cu" "F.Mask" "F.Paste")
			(net "FM_PFR_LED_BLUE")
		)
		(pad "2" smd circle
			(at 0.40005 0 270)
			(size 0 0)
			(layers "F.Cu" "F.Mask" "F.Paste")
			(net "FM_PFR_LED_BLUE_R")
		)
	)
	(footprint ""
		(layer "F.Cu")
		(at 149.211538 -261.434834)
		(property "Reference" "L107"
			(at 0 0 0)
			(layer "F.SilkS")
			(hide yes)
			(effects
				(font
					(size 1.27 1.27)
				)
			)
		)
		(property "Value" ""
			(at 0 0 0)
			(layer "F.Fab")
			(effects
				(font
					(size 1.27 1.27)
				)
			)
		)
		(duplicate_pad_numbers_are_jumpers no)
		(fp_line
			(start -1.63576 -0.8128)
			(end -1.63576 0.8128)
			(stroke
				(width 0.1524)
				(type default)
			)
			(layer "F.SilkS")
		)
		(fp_line
			(start -1.63576 -0.8128)
			(end 1.63576 -0.8128)
			(stroke
				(width 0.1524)
				(type default)
			)
			(layer "F.SilkS")
		)
		(fp_line
			(start 1.63576 -0.8128)
			(end 1.63576 0.8128)
			(stroke
				(width 0.1524)
				(type default)
			)
			(layer "F.SilkS")
		)
		(fp_line
			(start 1.63576 0.8128)
			(end -1.63576 0.8128)
			(stroke
				(width 0.1524)
				(type default)
			)
			(layer "F.SilkS")
		)
		(fp_line
			(start -1.56083 -0.738632)
			(end -1.56083 0.7366)
			(stroke
				(width 0.1)
				(type default)
			)
			(layer "F.Fab")
		)
		(fp_line
			(start -1.56083 0.7366)
			(end -1.524 0.7366)
			(stroke
				(width 0.1)
				(type default)
			)
			(layer "F.Fab")
		)
		(fp_line
			(start -1.524 0.7366)
			(end 1.524 0.7366)
			(stroke
				(width 0.1)
				(type default)
			)
			(layer "F.Fab")
		)
		(fp_line
			(start 1.524 0.7366)
			(end 1.560576 0.7366)
			(stroke
				(width 0.1)
				(type default)
			)
			(layer "F.Fab")
		)
		(fp_line
			(start 1.560576 -0.738632)
			(end -1.56083 -0.738632)
			(stroke
				(width 0.1)
				(type default)
			)
			(layer "F.Fab")
		)
		(fp_line
			(start 1.560576 0.7366)
			(end 1.560576 -0.738632)
			(stroke
				(width 0.1)
				(type default)
			)
			(layer "F.Fab")
		)
		(pad "1" smd rect
			(at -0.94996 0 180)
			(size 1.1176 1.3716)
			(layers "F.Cu" "F.Mask" "F.Paste")
			(net "P1V8_PLL0_PEX1")
		)
		(pad "2" smd rect
			(at 0.94996 0 180)
			(size 1.1176 1.3716)
			(layers "F.Cu" "F.Mask" "F.Paste")
			(net "PCEPLL3_VDDA18_PEX1")
		)
	)
	(footprint ""
		(layer "F.Cu")
		(at 132.531612 -162.003994 -90)
		(property "Reference" "R946"
			(at 0 0 270)
			(layer "F.SilkS")
			(hide yes)
			(effects
				(font
					(size 1.27 1.27)
				)
			)
		)
		(property "Value" ""
			(at 0 0 270)
			(layer "F.Fab")
			(effects
				(font
					(size 1.27 1.27)
				)
			)
		)
		(duplicate_pad_numbers_are_jumpers no)
		(fp_line
			(start -0.7874 0.4064)
			(end -0.7874 -0.4064)
			(stroke
				(width 0.1524)
				(type default)
			)
			(layer "F.SilkS")
		)
		(fp_line
			(start 0.7874 0.4064)
			(end -0.7874 0.4064)
			(stroke
				(width 0.1524)
				(type default)
			)
			(layer "F.SilkS")
		)
		(fp_line
			(start -0.7874 -0.4064)
			(end 0.7874 -0.4064)
			(stroke
				(width 0.1524)
				(type default)
			)
			(layer "F.SilkS")
		)
		(fp_line
			(start 0.7874 -0.4064)
			(end 0.7874 0.4064)
			(stroke
				(width 0.1524)
				(type default)
			)
			(layer "F.SilkS")
		)
		(fp_line
			(start -0.67945 0.3048)
			(end -0.67945 -0.305054)
			(stroke
				(width 0.1)
				(type default)
			)
			(layer "F.Fab")
		)
		(fp_line
			(start -0.12065 0.3048)
			(end -0.67945 0.3048)
			(stroke
				(width 0.1)
				(type default)
			)
			(layer "F.Fab")
		)
		(fp_line
			(start 0.120396 0.3048)
			(end 0.120396 0.2794)
			(stroke
				(width 0.1)
				(type default)
			)
			(layer "F.Fab")
		)
		(fp_line
			(start 0.67945 0.3048)
			(end 0.120396 0.3048)
			(stroke
				(width 0.1)
				(type default)
			)
			(layer "F.Fab")
		)
		(fp_line
			(start -0.12065 0.2794)
			(end -0.12065 0.3048)
			(stroke
				(width 0.1)
				(type default)
			)
			(layer "F.Fab")
		)
		(fp_line
			(start 0.120396 0.2794)
			(end -0.12065 0.2794)
			(stroke
				(width 0.1)
				(type default)
			)
			(layer "F.Fab")
		)
		(fp_line
			(start -0.12065 -0.2794)
			(end 0.12065 -0.2794)
			(stroke
				(width 0.1)
				(type default)
			)
			(layer "F.Fab")
		)
		(fp_line
			(start 0.12065 -0.2794)
			(end 0.12065 -0.3048)
			(stroke
				(width 0.1)
				(type default)
			)
			(layer "F.Fab")
		)
		(fp_line
			(start 0.12065 -0.3048)
			(end 0.67945 -0.3048)
			(stroke
				(width 0.1)
				(type default)
			)
			(layer "F.Fab")
		)
		(fp_line
			(start 0.67945 -0.3048)
			(end 0.67945 0.3048)
			(stroke
				(width 0.1)
				(type default)
			)
			(layer "F.Fab")
		)
		(fp_line
			(start -0.67945 -0.305054)
			(end -0.12065 -0.305054)
			(stroke
				(width 0.1)
				(type default)
			)
			(layer "F.Fab")
		)
		(fp_line
			(start -0.12065 -0.305054)
			(end -0.12065 -0.2794)
			(stroke
				(width 0.1)
				(type default)
			)
			(layer "F.Fab")
		)
		(pad "1" smd circle
			(at -0.40005 0 270)
			(size 0 0)
			(layers "F.Cu" "F.Mask" "F.Paste")
			(net "HP_NIC2_EN")
		)
		(pad "2" smd circle
			(at 0.40005 0 270)
			(size 0 0)
			(layers "F.Cu" "F.Mask" "F.Paste")
			(net "P12V_NIC2_CO_EN")
		)
	)
	(footprint ""
		(layer "F.Cu")
		(at 250.631198 -123.903994 -90)
		(property "Reference" "PC455"
			(at 0 0 270)
			(layer "F.SilkS")
			(hide yes)
			(effects
				(font
					(size 1.27 1.27)
				)
			)
		)
		(property "Value" ""
			(at 0 0 270)
			(layer "F.Fab")
			(effects
				(font
					(size 1.27 1.27)
				)
			)
		)
		(duplicate_pad_numbers_are_jumpers no)
		(fp_line
			(start -1.524 0.762)
			(end -1.524 -0.762)
			(stroke
				(width 0.1524)
				(type default)
			)
			(layer "F.SilkS")
		)
		(fp_line
			(start 1.524 0.762)
			(end -1.524 0.762)
			(stroke
				(width 0.1524)
				(type default)
			)
			(layer "F.SilkS")
		)
		(fp_line
			(start -1.524 -0.762)
			(end 1.524 -0.762)
			(stroke
				(width 0.1524)
				(type default)
			)
			(layer "F.SilkS")
		)
		(fp_line
			(start 1.524 -0.762)
			(end 1.524 0.762)
			(stroke
				(width 0.1524)
				(type default)
			)
			(layer "F.SilkS")
		)
		(fp_line
			(start -1.1049 0.724916)
			(end 1.1049 0.724916)
			(stroke
				(width 0.1)
				(type default)
			)
			(layer "F.Fab")
		)
		(fp_line
			(start 1.1049 0.724916)
			(end 1.1049 -0.724916)
			(stroke
				(width 0.1)
				(type default)
			)
			(layer "F.Fab")
		)
		(fp_line
			(start -1.1049 -0.724916)
			(end -1.1049 0.724916)
			(stroke
				(width 0.1)
				(type default)
			)
			(layer "F.Fab")
		)
		(fp_line
			(start 1.1049 -0.724916)
			(end -1.1049 -0.724916)
			(stroke
				(width 0.1)
				(type default)
			)
			(layer "F.Fab")
		)
		(pad "1" smd rect
			(at -0.889 0 90)
			(size 1.016 1.27)
			(layers "F.Cu" "F.Mask" "F.Paste")
			(net "P3V3_NIC4")
		)
		(pad "2" smd rect
			(at 0.889 0 90)
			(size 1.016 1.27)
			(layers "F.Cu" "F.Mask" "F.Paste")
			(net "GND")
		)
	)
	(footprint ""
		(layer "F.Cu")
		(at 212.574886 -231.150922 90)
		(property "Reference" "R1542"
			(at 0 0 90)
			(layer "F.SilkS")
			(hide yes)
			(effects
				(font
					(size 1.27 1.27)
				)
			)
		)
		(property "Value" ""
			(at 0 0 90)
			(layer "F.Fab")
			(effects
				(font
					(size 1.27 1.27)
				)
			)
		)
		(duplicate_pad_numbers_are_jumpers no)
		(fp_line
			(start 0.7874 -0.4064)
			(end 0.7874 0.4064)
			(stroke
				(width 0.1524)
				(type default)
			)
			(layer "F.SilkS")
		)
		(fp_line
			(start -0.7874 -0.4064)
			(end 0.7874 -0.4064)
			(stroke
				(width 0.1524)
				(type default)
			)
			(layer "F.SilkS")
		)
		(fp_line
			(start 0.7874 0.4064)
			(end -0.7874 0.4064)
			(stroke
				(width 0.1524)
				(type default)
			)
			(layer "F.SilkS")
		)
		(fp_line
			(start -0.7874 0.4064)
			(end -0.7874 -0.4064)
			(stroke
				(width 0.1524)
				(type default)
			)
			(layer "F.SilkS")
		)
		(fp_line
			(start -0.12065 -0.305054)
			(end -0.12065 -0.2794)
			(stroke
				(width 0.1)
				(type default)
			)
			(layer "F.Fab")
		)
		(fp_line
			(start -0.67945 -0.305054)
			(end -0.12065 -0.305054)
			(stroke
				(width 0.1)
				(type default)
			)
			(layer "F.Fab")
		)
		(fp_line
			(start 0.67945 -0.3048)
			(end 0.67945 0.3048)
			(stroke
				(width 0.1)
				(type default)
			)
			(layer "F.Fab")
		)
		(fp_line
			(start 0.12065 -0.3048)
			(end 0.67945 -0.3048)
			(stroke
				(width 0.1)
				(type default)
			)
			(layer "F.Fab")
		)
		(fp_line
			(start 0.12065 -0.2794)
			(end 0.12065 -0.3048)
			(stroke
				(width 0.1)
				(type default)
			)
			(layer "F.Fab")
		)
		(fp_line
			(start -0.12065 -0.2794)
			(end 0.12065 -0.2794)
			(stroke
				(width 0.1)
				(type default)
			)
			(layer "F.Fab")
		)
		(fp_line
			(start 0.120396 0.2794)
			(end -0.12065 0.2794)
			(stroke
				(width 0.1)
				(type default)
			)
			(layer "F.Fab")
		)
		(fp_line
			(start -0.12065 0.2794)
			(end -0.12065 0.3048)
			(stroke
				(width 0.1)
				(type default)
			)
			(layer "F.Fab")
		)
		(fp_line
			(start 0.67945 0.3048)
			(end 0.120396 0.3048)
			(stroke
				(width 0.1)
				(type default)
			)
			(layer "F.Fab")
		)
		(fp_line
			(start 0.120396 0.3048)
			(end 0.120396 0.2794)
			(stroke
				(width 0.1)
				(type default)
			)
			(layer "F.Fab")
		)
		(fp_line
			(start -0.12065 0.3048)
			(end -0.67945 0.3048)
			(stroke
				(width 0.1)
				(type default)
			)
			(layer "F.Fab")
		)
		(fp_line
			(start -0.67945 0.3048)
			(end -0.67945 -0.305054)
			(stroke
				(width 0.1)
				(type default)
			)
			(layer "F.Fab")
		)
		(pad "1" smd circle
			(at -0.40005 0 90)
			(size 0 0)
			(layers "F.Cu" "F.Mask" "F.Paste")
			(net "SMB_PEX_LS_R_SDA")
		)
		(pad "2" smd circle
			(at 0.40005 0 90)
			(size 0 0)
			(layers "F.Cu" "F.Mask" "F.Paste")
			(net "SMB_PEX0_SDA")
		)
	)
	(footprint ""
		(layer "F.Cu")
		(at 215.488774 -109.058202)
		(property "Reference" "R716"
			(at 0 0 0)
			(layer "F.SilkS")
			(hide yes)
			(effects
				(font
					(size 1.27 1.27)
				)
			)
		)
		(property "Value" ""
			(at 0 0 0)
			(layer "F.Fab")
			(effects
				(font
					(size 1.27 1.27)
				)
			)
		)
		(duplicate_pad_numbers_are_jumpers no)
		(fp_line
			(start -3.937508 -1.8796)
			(end -3.937508 1.8796)
			(stroke
				(width 0.1524)
				(type default)
			)
			(layer "F.SilkS")
		)
		(fp_line
			(start -3.937508 1.8796)
			(end 3.937508 1.8796)
			(stroke
				(width 0.1524)
				(type default)
			)
			(layer "F.SilkS")
		)
		(fp_line
			(start 3.937508 -1.8796)
			(end -3.937508 -1.8796)
			(stroke
				(width 0.1524)
				(type default)
			)
			(layer "F.SilkS")
		)
		(fp_line
			(start 3.937508 1.8796)
			(end 3.937508 -1.8796)
			(stroke
				(width 0.1524)
				(type default)
			)
			(layer "F.SilkS")
		)
		(fp_line
			(start -3.275076 -1.674876)
			(end -3.275076 1.674876)
			(stroke
				(width 0.1)
				(type default)
			)
			(layer "F.Fab")
		)
		(fp_line
			(start -3.275076 1.674876)
			(end 3.275076 1.674876)
			(stroke
				(width 0.1)
				(type default)
			)
			(layer "F.Fab")
		)
		(fp_line
			(start 3.275076 -1.674876)
			(end -3.275076 -1.674876)
			(stroke
				(width 0.1)
				(type default)
			)
			(layer "F.Fab")
		)
		(fp_line
			(start 3.275076 1.674876)
			(end 3.275076 -1.674876)
			(stroke
				(width 0.1)
				(type default)
			)
			(layer "F.Fab")
		)
		(pad "1" smd rect
			(at -2.350008 0)
			(size 2.921 3.5052)
			(layers "F.Cu" "F.Mask" "F.Paste")
			(net "P12V_NIC3")
		)
		(pad "2" smd rect
			(at 2.350008 0)
			(size 2.921 3.5052)
			(layers "F.Cu" "F.Mask" "F.Paste")
			(net "P12V_NIC3_R")
		)
	)
	(footprint ""
		(layer "F.Cu")
		(at 359.156 -188.214)
		(property "Reference" "R4606"
			(at 0 0 0)
			(layer "F.SilkS")
			(hide yes)
			(effects
				(font
					(size 1.27 1.27)
				)
			)
		)
		(property "Value" ""
			(at 0 0 0)
			(layer "F.Fab")
			(effects
				(font
					(size 1.27 1.27)
				)
			)
		)
		(duplicate_pad_numbers_are_jumpers no)
		(fp_line
			(start -0.7874 -0.4064)
			(end 0.7874 -0.4064)
			(stroke
				(width 0.1524)
				(type default)
			)
			(layer "F.SilkS")
		)
		(fp_line
			(start -0.7874 0.4064)
			(end -0.7874 -0.4064)
			(stroke
				(width 0.1524)
				(type default)
			)
			(layer "F.SilkS")
		)
		(fp_line
			(start 0.7874 -0.4064)
			(end 0.7874 0.4064)
			(stroke
				(width 0.1524)
				(type default)
			)
			(layer "F.SilkS")
		)
		(fp_line
			(start 0.7874 0.4064)
			(end -0.7874 0.4064)
			(stroke
				(width 0.1524)
				(type default)
			)
			(layer "F.SilkS")
		)
		(fp_line
			(start -0.67945 -0.305054)
			(end -0.12065 -0.305054)
			(stroke
				(width 0.1)
				(type default)
			)
			(layer "F.Fab")
		)
		(fp_line
			(start -0.67945 0.3048)
			(end -0.67945 -0.305054)
			(stroke
				(width 0.1)
				(type default)
			)
			(layer "F.Fab")
		)
		(fp_line
			(start -0.12065 -0.305054)
			(end -0.12065 -0.2794)
			(stroke
				(width 0.1)
				(type default)
			)
			(layer "F.Fab")
		)
		(fp_line
			(start -0.12065 -0.2794)
			(end 0.12065 -0.2794)
			(stroke
				(width 0.1)
				(type default)
			)
			(layer "F.Fab")
		)
		(fp_line
			(start -0.12065 0.2794)
			(end -0.12065 0.3048)
			(stroke
				(width 0.1)
				(type default)
			)
			(layer "F.Fab")
		)
		(fp_line
			(start -0.12065 0.3048)
			(end -0.67945 0.3048)
			(stroke
				(width 0.1)
				(type default)
			)
			(layer "F.Fab")
		)
		(fp_line
			(start 0.120396 0.2794)
			(end -0.12065 0.2794)
			(stroke
				(width 0.1)
				(type default)
			)
			(layer "F.Fab")
		)
		(fp_line
			(start 0.120396 0.3048)
			(end 0.120396 0.2794)
			(stroke
				(width 0.1)
				(type default)
			)
			(layer "F.Fab")
		)
		(fp_line
			(start 0.12065 -0.3048)
			(end 0.67945 -0.3048)
			(stroke
				(width 0.1)
				(type default)
			)
			(layer "F.Fab")
		)
		(fp_line
			(start 0.12065 -0.2794)
			(end 0.12065 -0.3048)
			(stroke
				(width 0.1)
				(type default)
			)
			(layer "F.Fab")
		)
		(fp_line
			(start 0.67945 -0.3048)
			(end 0.67945 0.3048)
			(stroke
				(width 0.1)
				(type default)
			)
			(layer "F.Fab")
		)
		(fp_line
			(start 0.67945 0.3048)
			(end 0.120396 0.3048)
			(stroke
				(width 0.1)
				(type default)
			)
			(layer "F.Fab")
		)
		(pad "1" smd circle
			(at -0.40005 0)
			(size 0 0)
			(layers "F.Cu" "F.Mask" "F.Paste")
			(net "P3V3_AUX")
		)
		(pad "2" smd circle
			(at 0.40005 0)
			(size 0 0)
			(layers "F.Cu" "F.Mask" "F.Paste")
			(net "RST_PEX_SSD2_PERST_R_N")
		)
	)
	(footprint ""
		(layer "F.Cu")
		(at 447.173858 -103.668068)
		(property "Reference" "PC825"
			(at 0 0 0)
			(layer "F.SilkS")
			(hide yes)
			(effects
				(font
					(size 1.27 1.27)
				)
			)
		)
		(property "Value" ""
			(at 0 0 0)
			(layer "F.Fab")
			(effects
				(font
					(size 1.27 1.27)
				)
			)
		)
		(duplicate_pad_numbers_are_jumpers no)
		(fp_line
			(start -1.524 -0.762)
			(end 1.524 -0.762)
			(stroke
				(width 0.1524)
				(type default)
			)
			(layer "F.SilkS")
		)
		(fp_line
			(start -1.524 0.762)
			(end -1.524 -0.762)
			(stroke
				(width 0.1524)
				(type default)
			)
			(layer "F.SilkS")
		)
		(fp_line
			(start 1.524 -0.762)
			(end 1.524 0.762)
			(stroke
				(width 0.1524)
				(type default)
			)
			(layer "F.SilkS")
		)
		(fp_line
			(start 1.524 0.762)
			(end -1.524 0.762)
			(stroke
				(width 0.1524)
				(type default)
			)
			(layer "F.SilkS")
		)
		(fp_line
			(start -1.1049 -0.724916)
			(end -1.1049 0.724916)
			(stroke
				(width 0.1)
				(type default)
			)
			(layer "F.Fab")
		)
		(fp_line
			(start -1.1049 0.724916)
			(end 1.1049 0.724916)
			(stroke
				(width 0.1)
				(type default)
			)
			(layer "F.Fab")
		)
		(fp_line
			(start 1.1049 -0.724916)
			(end -1.1049 -0.724916)
			(stroke
				(width 0.1)
				(type default)
			)
			(layer "F.Fab")
		)
		(fp_line
			(start 1.1049 0.724916)
			(end 1.1049 -0.724916)
			(stroke
				(width 0.1)
				(type default)
			)
			(layer "F.Fab")
		)
		(pad "1" smd rect
			(at -0.889 0 180)
			(size 1.016 1.27)
			(layers "F.Cu" "F.Mask" "F.Paste")
			(net "P12V_NIC7_R")
		)
		(pad "2" smd rect
			(at 0.889 0 180)
			(size 1.016 1.27)
			(layers "F.Cu" "F.Mask" "F.Paste")
			(net "GND")
		)
	)
	(footprint ""
		(layer "F.Cu")
		(at 114.945668 -356.244906 90)
		(property "Reference" "C360"
			(at 0 0 90)
			(layer "F.SilkS")
			(hide yes)
			(effects
				(font
					(size 1.27 1.27)
				)
			)
		)
		(property "Value" ""
			(at 0 0 90)
			(layer "F.Fab")
			(effects
				(font
					(size 1.27 1.27)
				)
			)
		)
		(duplicate_pad_numbers_are_jumpers no)
		(fp_line
			(start 0.299974 -0.150114)
			(end 0.299974 0.150114)
			(stroke
				(width 0.1)
				(type default)
			)
			(layer "F.Fab")
		)
		(fp_line
			(start -0.299974 -0.150114)
			(end 0.299974 -0.150114)
			(stroke
				(width 0.1)
				(type default)
			)
			(layer "F.Fab")
		)
		(fp_line
			(start 0.299974 0.150114)
			(end -0.299974 0.150114)
			(stroke
				(width 0.1)
				(type default)
			)
			(layer "F.Fab")
		)
		(fp_line
			(start -0.299974 0.150114)
			(end -0.299974 -0.150114)
			(stroke
				(width 0.1)
				(type default)
			)
			(layer "F.Fab")
		)
		(pad "1" smd rect
			(at -0.2667 0 90)
			(size 0.3048 0.381)
			(layers "F.Cu" "F.Mask" "F.Paste")
			(net "P5E_PEX1_STN6_TX_DP<101>")
		)
		(pad "2" smd rect
			(at 0.2667 0 90)
			(size 0.3048 0.381)
			(layers "F.Cu" "F.Mask" "F.Paste")
			(net "P5E_PEX1_STN6_TX_C_DP<101>")
		)
	)
	(footprint ""
		(layer "F.Cu")
		(at 124.808742 -166.674038 90)
		(property "Reference" "C4451"
			(at 0 0 90)
			(layer "F.SilkS")
			(hide yes)
			(effects
				(font
					(size 1.27 1.27)
				)
			)
		)
		(property "Value" ""
			(at 0 0 90)
			(layer "F.Fab")
			(effects
				(font
					(size 1.27 1.27)
				)
			)
		)
		(duplicate_pad_numbers_are_jumpers no)
		(fp_line
			(start 0.7874 -0.4064)
			(end 0.7874 0.4064)
			(stroke
				(width 0.1524)
				(type default)
			)
			(layer "F.SilkS")
		)
		(fp_line
			(start -0.7874 -0.4064)
			(end 0.7874 -0.4064)
			(stroke
				(width 0.1524)
				(type default)
			)
			(layer "F.SilkS")
		)
		(fp_line
			(start 0.7874 0.4064)
			(end -0.7874 0.4064)
			(stroke
				(width 0.1524)
				(type default)
			)
			(layer "F.SilkS")
		)
		(fp_line
			(start -0.7874 0.4064)
			(end -0.7874 -0.4064)
			(stroke
				(width 0.1524)
				(type default)
			)
			(layer "F.SilkS")
		)
		(fp_line
			(start -0.12065 -0.305054)
			(end -0.12065 -0.2794)
			(stroke
				(width 0.1)
				(type default)
			)
			(layer "F.Fab")
		)
		(fp_line
			(start -0.67945 -0.305054)
			(end -0.12065 -0.305054)
			(stroke
				(width 0.1)
				(type default)
			)
			(layer "F.Fab")
		)
		(fp_line
			(start 0.67945 -0.3048)
			(end 0.67945 0.3048)
			(stroke
				(width 0.1)
				(type default)
			)
			(layer "F.Fab")
		)
		(fp_line
			(start 0.12065 -0.3048)
			(end 0.67945 -0.3048)
			(stroke
				(width 0.1)
				(type default)
			)
			(layer "F.Fab")
		)
		(fp_line
			(start 0.12065 -0.2794)
			(end 0.12065 -0.3048)
			(stroke
				(width 0.1)
				(type default)
			)
			(layer "F.Fab")
		)
		(fp_line
			(start -0.12065 -0.2794)
			(end 0.12065 -0.2794)
			(stroke
				(width 0.1)
				(type default)
			)
			(layer "F.Fab")
		)
		(fp_line
			(start 0.120396 0.2794)
			(end -0.12065 0.2794)
			(stroke
				(width 0.1)
				(type default)
			)
			(layer "F.Fab")
		)
		(fp_line
			(start -0.12065 0.2794)
			(end -0.12065 0.3048)
			(stroke
				(width 0.1)
				(type default)
			)
			(layer "F.Fab")
		)
		(fp_line
			(start 0.67945 0.3048)
			(end 0.120396 0.3048)
			(stroke
				(width 0.1)
				(type default)
			)
			(layer "F.Fab")
		)
		(fp_line
			(start 0.120396 0.3048)
			(end 0.120396 0.2794)
			(stroke
				(width 0.1)
				(type default)
			)
			(layer "F.Fab")
		)
		(fp_line
			(start -0.12065 0.3048)
			(end -0.67945 0.3048)
			(stroke
				(width 0.1)
				(type default)
			)
			(layer "F.Fab")
		)
		(fp_line
			(start -0.67945 0.3048)
			(end -0.67945 -0.305054)
			(stroke
				(width 0.1)
				(type default)
			)
			(layer "F.Fab")
		)
		(pad "1" smd circle
			(at -0.40005 0 90)
			(size 0 0)
			(layers "F.Cu" "F.Mask" "F.Paste")
			(net "GND")
		)
		(pad "2" smd circle
			(at 0.40005 0 90)
			(size 0 0)
			(layers "F.Cu" "F.Mask" "F.Paste")
			(net "P3V3_AUX")
		)
	)
	(footprint ""
		(layer "F.Cu")
		(at 100.845874 -46.4439 180)
		(property "Reference" "U56"
			(at -0.042926 -2.35077 0)
			(unlocked yes)
			(layer "F.SilkS")
			(effects
				(font
					(size 0.7874 0.5842)
					(thickness 0.1524)
				)
			)
		)
		(property "Value" ""
			(at 0 0 180)
			(layer "F.Fab")
			(effects
				(font
					(size 1.27 1.27)
				)
			)
		)
		(duplicate_pad_numbers_are_jumpers no)
		(fp_line
			(start 1.500124 1.500124)
			(end 1.004062 1.500124)
			(stroke
				(width 0.1524)
				(type default)
			)
			(layer "F.SilkS")
		)
		(fp_line
			(start 1.500124 1.004062)
			(end 1.500124 1.500124)
			(stroke
				(width 0.1524)
				(type default)
			)
			(layer "F.SilkS")
		)
		(fp_line
			(start 1.500124 -1.500124)
			(end 1.500124 -1.004062)
			(stroke
				(width 0.1524)
				(type default)
			)
			(layer "F.SilkS")
		)
		(fp_line
			(start 1.004062 -1.500124)
			(end 1.500124 -1.500124)
			(stroke
				(width 0.1524)
				(type default)
			)
			(layer "F.SilkS")
		)
		(fp_line
			(start -1.004062 1.500124)
			(end -1.500124 1.500124)
			(stroke
				(width 0.1524)
				(type default)
			)
			(layer "F.SilkS")
		)
		(fp_line
			(start -1.500124 1.500124)
			(end -1.500124 1.004062)
			(stroke
				(width 0.1524)
				(type default)
			)
			(layer "F.SilkS")
		)
		(fp_line
			(start -1.500124 -1.004062)
			(end -1.500124 -1.500124)
			(stroke
				(width 0.1524)
				(type default)
			)
			(layer "F.SilkS")
		)
		(fp_line
			(start -1.500124 -1.500124)
			(end -1.004062 -1.500124)
			(stroke
				(width 0.1524)
				(type default)
			)
			(layer "F.SilkS")
		)
		(fp_poly
			(pts
				(xy -1.947926 -2.04216) (xy -2.666238 -1.323848) (xy -1.588516 -0.964438)
			)
			(stroke
				(width 0)
				(type default)
			)
			(fill yes)
			(layer "F.SilkS")
		)
		(fp_line
			(start 1.500124 1.500124)
			(end -1.500124 1.500124)
			(stroke
				(width 0.1)
				(type default)
			)
			(layer "F.Fab")
		)
		(fp_line
			(start 1.500124 -1.500124)
			(end 1.500124 1.500124)
			(stroke
				(width 0.1)
				(type default)
			)
			(layer "F.Fab")
		)
		(fp_line
			(start -1.500124 1.500124)
			(end -1.500124 -1.500124)
			(stroke
				(width 0.1)
				(type default)
			)
			(layer "F.Fab")
		)
		(fp_line
			(start -1.500124 -1.500124)
			(end 1.500124 -1.500124)
			(stroke
				(width 0.1)
				(type default)
			)
			(layer "F.Fab")
		)
		(fp_poly
			(pts
				(xy -2.847848 -1.258062) (xy -2.847848 -0.242062) (xy -1.831848 -0.750062)
			)
			(stroke
				(width 0)
				(type default)
			)
			(fill yes)
			(layer "F.Fab")
		)
		(pad "1" smd rect
			(at -1.400048 -0.750062 90)
			(size 0.2286 0.6096)
			(layers "F.Cu" "F.Mask" "F.Paste")
			(net "SSD3_ADC_A1")
		)
		(pad "2" smd rect
			(at -1.400048 -0.249936 90)
			(size 0.2286 0.6096)
			(layers "F.Cu" "F.Mask" "F.Paste")
			(net "SSD3_ADC_A0")
		)
		(pad "3" smd rect
			(at -1.400048 0.249936 90)
			(size 0.2286 0.6096)
			(layers "F.Cu" "F.Mask" "F.Paste")
			(net "SSD3_ADC_ALERT_N")
		)
		(pad "4" smd rect
			(at -1.400048 0.750062 90)
			(size 0.2286 0.6096)
			(layers "F.Cu" "F.Mask" "F.Paste")
			(net "SMB_SSD3_ADC_SDA")
		)
		(pad "5" smd rect
			(at -0.750062 1.400048 180)
			(size 0.2286 0.6096)
			(layers "F.Cu" "F.Mask" "F.Paste")
			(net "SMB_SSD3_ADC_SCL")
		)
		(pad "6" smd rect
			(at -0.249936 1.400048 180)
			(size 0.2286 0.6096)
			(layers "F.Cu" "F.Mask" "F.Paste")
			(net "Net_8744")
		)
		(pad "7" smd rect
			(at 0.249936 1.400048 180)
			(size 0.2286 0.6096)
			(layers "F.Cu" "F.Mask" "F.Paste")
			(net "Net_8743")
		)
		(pad "8" smd rect
			(at 0.750062 1.400048 180)
			(size 0.2286 0.6096)
			(layers "F.Cu" "F.Mask" "F.Paste")
			(net "Net_8742")
		)
		(pad "9" smd rect
			(at 1.400048 0.750062 90)
			(size 0.2286 0.6096)
			(layers "F.Cu" "F.Mask" "F.Paste")
			(net "P3V3_AUX")
		)
		(pad "10" smd rect
			(at 1.400048 0.249936 90)
			(size 0.2286 0.6096)
			(layers "F.Cu" "F.Mask" "F.Paste")
			(net "GND")
		)
		(pad "11" smd rect
			(at 1.400048 -0.249936 90)
			(size 0.2286 0.6096)
			(layers "F.Cu" "F.Mask" "F.Paste")
			(net "P12V_SSD3_R")
		)
		(pad "12" smd rect
			(at 1.400048 -0.750062 90)
			(size 0.2286 0.6096)
			(layers "F.Cu" "F.Mask" "F.Paste")
			(net "P12V_SSD3_VIN_N")
		)
		(pad "13" smd rect
			(at 0.750062 -1.400048 180)
			(size 0.2286 0.6096)
			(layers "F.Cu" "F.Mask" "F.Paste")
			(net "P12V_SSD3_VIN_P")
		)
		(pad "14" smd rect
			(at 0.249936 -1.400048 180)
			(size 0.2286 0.6096)
			(layers "F.Cu" "F.Mask" "F.Paste")
			(net "Net_8741")
		)
		(pad "15" smd rect
			(at -0.249936 -1.400048 180)
			(size 0.2286 0.6096)
			(layers "F.Cu" "F.Mask" "F.Paste")
			(net "Net_8740")
		)
		(pad "16" smd rect
			(at -0.750062 -1.400048 180)
			(size 0.2286 0.6096)
			(layers "F.Cu" "F.Mask" "F.Paste")
			(net "Net_8739")
		)
		(pad "TH" smd rect
			(at 0 0 180)
			(size 1.7018 1.7018)
			(layers "F.Cu" "F.Mask" "F.Paste")
			(net "GND")
		)
		(zone
			(layer "F.Cu")
			(hatch none 0.5)
			(connect_pads
				(clearance 0)
			)
			(min_thickness 0.25)
			(keepout
				(tracks not_allowed)
				(vias allowed)
				(pads allowed)
				(copperpour not_allowed)
				(footprints allowed)
			)
			(placement
				(enabled no)
				(sheetname "")
			)
			(fill
				(thermal_gap 0.5)
				(thermal_bridge_width 0.5)
				(island_removal_mode 0)
			)
			(polygon
				(pts
					(xy 101.890322 -46.4185) (xy 101.890322 -45.399452) (xy 99.801426 -45.399452) (xy 99.801426 -47.488348)
					(xy 101.890322 -47.488348) (xy 101.890322 -46.4439) (xy 101.747574 -46.4439) (xy 101.747574 -47.3456)
					(xy 99.944174 -47.3456) (xy 99.944174 -45.5422) (xy 101.747574 -45.5422) (xy 101.747574 -46.4185)
				)
			)
		)
	)
	(footprint ""
		(layer "F.Cu")
		(at 334.602582 -284.834838 90)
		(property "Reference" "PC139"
			(at 0 0 90)
			(layer "F.SilkS")
			(hide yes)
			(effects
				(font
					(size 1.27 1.27)
				)
			)
		)
		(property "Value" ""
			(at 0 0 90)
			(layer "F.Fab")
			(effects
				(font
					(size 1.27 1.27)
				)
			)
		)
		(duplicate_pad_numbers_are_jumpers no)
		(fp_line
			(start 0.7874 -0.4064)
			(end 0.7874 0.4064)
			(stroke
				(width 0.1524)
				(type default)
			)
			(layer "F.SilkS")
		)
		(fp_line
			(start -0.7874 -0.4064)
			(end 0.7874 -0.4064)
			(stroke
				(width 0.1524)
				(type default)
			)
			(layer "F.SilkS")
		)
		(fp_line
			(start 0.7874 0.4064)
			(end -0.7874 0.4064)
			(stroke
				(width 0.1524)
				(type default)
			)
			(layer "F.SilkS")
		)
		(fp_line
			(start -0.7874 0.4064)
			(end -0.7874 -0.4064)
			(stroke
				(width 0.1524)
				(type default)
			)
			(layer "F.SilkS")
		)
		(fp_line
			(start -0.12065 -0.305054)
			(end -0.12065 -0.2794)
			(stroke
				(width 0.1)
				(type default)
			)
			(layer "F.Fab")
		)
		(fp_line
			(start -0.67945 -0.305054)
			(end -0.12065 -0.305054)
			(stroke
				(width 0.1)
				(type default)
			)
			(layer "F.Fab")
		)
		(fp_line
			(start 0.67945 -0.3048)
			(end 0.67945 0.3048)
			(stroke
				(width 0.1)
				(type default)
			)
			(layer "F.Fab")
		)
		(fp_line
			(start 0.12065 -0.3048)
			(end 0.67945 -0.3048)
			(stroke
				(width 0.1)
				(type default)
			)
			(layer "F.Fab")
		)
		(fp_line
			(start 0.12065 -0.2794)
			(end 0.12065 -0.3048)
			(stroke
				(width 0.1)
				(type default)
			)
			(layer "F.Fab")
		)
		(fp_line
			(start -0.12065 -0.2794)
			(end 0.12065 -0.2794)
			(stroke
				(width 0.1)
				(type default)
			)
			(layer "F.Fab")
		)
		(fp_line
			(start 0.120396 0.2794)
			(end -0.12065 0.2794)
			(stroke
				(width 0.1)
				(type default)
			)
			(layer "F.Fab")
		)
		(fp_line
			(start -0.12065 0.2794)
			(end -0.12065 0.3048)
			(stroke
				(width 0.1)
				(type default)
			)
			(layer "F.Fab")
		)
		(fp_line
			(start 0.67945 0.3048)
			(end 0.120396 0.3048)
			(stroke
				(width 0.1)
				(type default)
			)
			(layer "F.Fab")
		)
		(fp_line
			(start 0.120396 0.3048)
			(end 0.120396 0.2794)
			(stroke
				(width 0.1)
				(type default)
			)
			(layer "F.Fab")
		)
		(fp_line
			(start -0.12065 0.3048)
			(end -0.67945 0.3048)
			(stroke
				(width 0.1)
				(type default)
			)
			(layer "F.Fab")
		)
		(fp_line
			(start -0.67945 0.3048)
			(end -0.67945 -0.305054)
			(stroke
				(width 0.1)
				(type default)
			)
			(layer "F.Fab")
		)
		(pad "1" smd circle
			(at -0.40005 0 90)
			(size 0 0)
			(layers "F.Cu" "F.Mask" "F.Paste")
			(net "SW_P12V_P0V8_PEX2_FLT")
		)
		(pad "2" smd circle
			(at 0.40005 0 90)
			(size 0 0)
			(layers "F.Cu" "F.Mask" "F.Paste")
			(net "GND")
		)
	)
	(footprint ""
		(layer "F.Cu")
		(at 269.19809 -369.947444)
		(property "Reference" "PR6615"
			(at 0 0 0)
			(layer "F.SilkS")
			(hide yes)
			(effects
				(font
					(size 1.27 1.27)
				)
			)
		)
		(property "Value" ""
			(at 0 0 0)
			(layer "F.Fab")
			(effects
				(font
					(size 1.27 1.27)
				)
			)
		)
		(duplicate_pad_numbers_are_jumpers no)
		(fp_line
			(start -0.7874 -0.4064)
			(end 0.7874 -0.4064)
			(stroke
				(width 0.1524)
				(type default)
			)
			(layer "F.SilkS")
		)
		(fp_line
			(start -0.7874 0.4064)
			(end -0.7874 -0.4064)
			(stroke
				(width 0.1524)
				(type default)
			)
			(layer "F.SilkS")
		)
		(fp_line
			(start 0.7874 -0.4064)
			(end 0.7874 0.4064)
			(stroke
				(width 0.1524)
				(type default)
			)
			(layer "F.SilkS")
		)
		(fp_line
			(start 0.7874 0.4064)
			(end -0.7874 0.4064)
			(stroke
				(width 0.1524)
				(type default)
			)
			(layer "F.SilkS")
		)
		(fp_line
			(start -0.67945 -0.305054)
			(end -0.12065 -0.305054)
			(stroke
				(width 0.1)
				(type default)
			)
			(layer "F.Fab")
		)
		(fp_line
			(start -0.67945 0.3048)
			(end -0.67945 -0.305054)
			(stroke
				(width 0.1)
				(type default)
			)
			(layer "F.Fab")
		)
		(fp_line
			(start -0.12065 -0.305054)
			(end -0.12065 -0.2794)
			(stroke
				(width 0.1)
				(type default)
			)
			(layer "F.Fab")
		)
		(fp_line
			(start -0.12065 -0.2794)
			(end 0.12065 -0.2794)
			(stroke
				(width 0.1)
				(type default)
			)
			(layer "F.Fab")
		)
		(fp_line
			(start -0.12065 0.2794)
			(end -0.12065 0.3048)
			(stroke
				(width 0.1)
				(type default)
			)
			(layer "F.Fab")
		)
		(fp_line
			(start -0.12065 0.3048)
			(end -0.67945 0.3048)
			(stroke
				(width 0.1)
				(type default)
			)
			(layer "F.Fab")
		)
		(fp_line
			(start 0.120396 0.2794)
			(end -0.12065 0.2794)
			(stroke
				(width 0.1)
				(type default)
			)
			(layer "F.Fab")
		)
		(fp_line
			(start 0.120396 0.3048)
			(end 0.120396 0.2794)
			(stroke
				(width 0.1)
				(type default)
			)
			(layer "F.Fab")
		)
		(fp_line
			(start 0.12065 -0.3048)
			(end 0.67945 -0.3048)
			(stroke
				(width 0.1)
				(type default)
			)
			(layer "F.Fab")
		)
		(fp_line
			(start 0.12065 -0.2794)
			(end 0.12065 -0.3048)
			(stroke
				(width 0.1)
				(type default)
			)
			(layer "F.Fab")
		)
		(fp_line
			(start 0.67945 -0.3048)
			(end 0.67945 0.3048)
			(stroke
				(width 0.1)
				(type default)
			)
			(layer "F.Fab")
		)
		(fp_line
			(start 0.67945 0.3048)
			(end 0.120396 0.3048)
			(stroke
				(width 0.1)
				(type default)
			)
			(layer "F.Fab")
		)
		(pad "1" smd circle
			(at -0.40005 0)
			(size 0 0)
			(layers "F.Cu" "F.Mask" "F.Paste")
			(net "LTC4282_TEMP_R_D-")
		)
		(pad "2" smd circle
			(at 0.40005 0)
			(size 0 0)
			(layers "F.Cu" "F.Mask" "F.Paste")
			(net "LTC4282_TEMP_D-")
		)
	)
	(footprint ""
		(layer "F.Cu")
		(at 7.320026 -20.72005)
		(property "Reference" "H127"
			(at -1.133602 2.425954 0)
			(unlocked yes)
			(layer "B.SilkS")
			(effects
				(font
					(size 0.7874 0.5842)
					(thickness 0.1524)
				)
				(justify left mirror)
			)
		)
		(property "Value" ""
			(at 0 0 0)
			(layer "F.Fab")
			(effects
				(font
					(size 1.27 1.27)
				)
			)
		)
		(duplicate_pad_numbers_are_jumpers no)
		(pad "1" thru_hole rect
			(at 0 0)
			(size 4.2164 5.0038)
			(drill 2.0066
				(offset 0.099822 0)
			)
			(layers "*.Cu" "*.Mask")
			(remove_unused_layers no)
			(net "Net_8536")
			(clearance -0.8509)
			(padstack
				(mode front_inner_back)
				(layer "Inner"
					(shape circle)
					(size 4.0132 4.0132)
					(clearance -0.7493)
				)
				(layer "B.Cu"
					(shape circle)
					(size 4.0132 4.0132)
					(clearance -0.7493)
				)
			)
		)
	)
	(footprint ""
		(layer "F.Cu")
		(at 6.709156 -27.04973 180)
		(property "Reference" "C2764"
			(at 0 0 180)
			(layer "F.SilkS")
			(hide yes)
			(effects
				(font
					(size 1.27 1.27)
				)
			)
		)
		(property "Value" ""
			(at 0 0 180)
			(layer "F.Fab")
			(effects
				(font
					(size 1.27 1.27)
				)
			)
		)
		(duplicate_pad_numbers_are_jumpers no)
		(fp_line
			(start 0.7874 0.4064)
			(end -0.7874 0.4064)
			(stroke
				(width 0.1524)
				(type default)
			)
			(layer "F.SilkS")
		)
		(fp_line
			(start 0.7874 -0.4064)
			(end 0.7874 0.4064)
			(stroke
				(width 0.1524)
				(type default)
			)
			(layer "F.SilkS")
		)
		(fp_line
			(start -0.7874 0.4064)
			(end -0.7874 -0.4064)
			(stroke
				(width 0.1524)
				(type default)
			)
			(layer "F.SilkS")
		)
		(fp_line
			(start -0.7874 -0.4064)
			(end 0.7874 -0.4064)
			(stroke
				(width 0.1524)
				(type default)
			)
			(layer "F.SilkS")
		)
		(fp_line
			(start 0.67945 0.3048)
			(end 0.120396 0.3048)
			(stroke
				(width 0.1)
				(type default)
			)
			(layer "F.Fab")
		)
		(fp_line
			(start 0.67945 -0.3048)
			(end 0.67945 0.3048)
			(stroke
				(width 0.1)
				(type default)
			)
			(layer "F.Fab")
		)
		(fp_line
			(start 0.12065 -0.2794)
			(end 0.12065 -0.3048)
			(stroke
				(width 0.1)
				(type default)
			)
			(layer "F.Fab")
		)
		(fp_line
			(start 0.12065 -0.3048)
			(end 0.67945 -0.3048)
			(stroke
				(width 0.1)
				(type default)
			)
			(layer "F.Fab")
		)
		(fp_line
			(start 0.120396 0.3048)
			(end 0.120396 0.2794)
			(stroke
				(width 0.1)
				(type default)
			)
			(layer "F.Fab")
		)
		(fp_line
			(start 0.120396 0.2794)
			(end -0.12065 0.2794)
			(stroke
				(width 0.1)
				(type default)
			)
			(layer "F.Fab")
		)
		(fp_line
			(start -0.12065 0.3048)
			(end -0.67945 0.3048)
			(stroke
				(width 0.1)
				(type default)
			)
			(layer "F.Fab")
		)
		(fp_line
			(start -0.12065 0.2794)
			(end -0.12065 0.3048)
			(stroke
				(width 0.1)
				(type default)
			)
			(layer "F.Fab")
		)
		(fp_line
			(start -0.12065 -0.2794)
			(end 0.12065 -0.2794)
			(stroke
				(width 0.1)
				(type default)
			)
			(layer "F.Fab")
		)
		(fp_line
			(start -0.12065 -0.305054)
			(end -0.12065 -0.2794)
			(stroke
				(width 0.1)
				(type default)
			)
			(layer "F.Fab")
		)
		(fp_line
			(start -0.67945 0.3048)
			(end -0.67945 -0.305054)
			(stroke
				(width 0.1)
				(type default)
			)
			(layer "F.Fab")
		)
		(fp_line
			(start -0.67945 -0.305054)
			(end -0.12065 -0.305054)
			(stroke
				(width 0.1)
				(type default)
			)
			(layer "F.Fab")
		)
		(pad "1" smd circle
			(at -0.40005 0 180)
			(size 0 0)
			(layers "F.Cu" "F.Mask" "F.Paste")
			(net "PRSNT_SSD0_R_N")
		)
		(pad "2" smd circle
			(at 0.40005 0 180)
			(size 0 0)
			(layers "F.Cu" "F.Mask" "F.Paste")
			(net "GND")
		)
	)
	(footprint ""
		(layer "F.Cu")
		(at 100.646992 -54.3941)
		(property "Reference" "PU36"
			(at -1.743964 2.828798 0)
			(unlocked yes)
			(layer "F.SilkS")
			(effects
				(font
					(size 0.7874 0.5842)
					(thickness 0.1524)
				)
				(justify left)
			)
		)
		(property "Value" ""
			(at 0 0 0)
			(layer "F.Fab")
			(effects
				(font
					(size 1.27 1.27)
				)
			)
		)
		(duplicate_pad_numbers_are_jumpers no)
		(fp_line
			(start -1.943608 -1.549908)
			(end 1.943608 -1.549908)
			(stroke
				(width 0.1524)
				(type default)
			)
			(layer "F.SilkS")
		)
		(fp_line
			(start -1.943608 1.549908)
			(end -1.943608 -1.549908)
			(stroke
				(width 0.1524)
				(type default)
			)
			(layer "F.SilkS")
		)
		(fp_line
			(start 1.943608 -1.549908)
			(end 1.943608 1.549908)
			(stroke
				(width 0.1524)
				(type default)
			)
			(layer "F.SilkS")
		)
		(fp_line
			(start 1.943608 1.549908)
			(end -1.943608 1.549908)
			(stroke
				(width 0.1524)
				(type default)
			)
			(layer "F.SilkS")
		)
		(fp_poly
			(pts
				(xy -2.019808 -1.549908) (xy -1.257808 -1.549908) (xy -1.257808 -1.880108) (xy -2.019808 -1.880108)
			)
			(stroke
				(width 0)
				(type default)
			)
			(fill yes)
			(layer "F.SilkS")
		)
		(fp_line
			(start -1.549908 -1.549908)
			(end 1.549908 -1.549908)
			(stroke
				(width 0.1)
				(type default)
			)
			(layer "F.Fab")
		)
		(fp_line
			(start -1.549908 1.549908)
			(end -1.549908 -1.549908)
			(stroke
				(width 0.1)
				(type default)
			)
			(layer "F.Fab")
		)
		(fp_line
			(start 1.549908 -1.549908)
			(end 1.549908 1.549908)
			(stroke
				(width 0.1)
				(type default)
			)
			(layer "F.Fab")
		)
		(fp_line
			(start 1.549908 1.549908)
			(end -1.549908 1.549908)
			(stroke
				(width 0.1)
				(type default)
			)
			(layer "F.Fab")
		)
		(fp_poly
			(pts
				(xy -2.019808 -1.549908) (xy -1.257808 -1.549908) (xy -1.257808 -1.880108) (xy -2.019808 -1.880108)
			)
			(stroke
				(width 0)
				(type default)
			)
			(fill yes)
			(layer "F.Fab")
		)
		(pad "1" smd rect
			(at -1.500124 -1.249934 270)
			(size 0.2794 0.6096)
			(layers "F.Cu" "F.Mask" "F.Paste")
			(net "P12V_SSD3_R")
		)
		(pad "2" smd rect
			(at -1.500124 -0.750062 270)
			(size 0.2794 0.6096)
			(layers "F.Cu" "F.Mask" "F.Paste")
			(net "P12V_SSD3_R")
		)
		(pad "3" smd rect
			(at -1.500124 -0.249936 270)
			(size 0.2794 0.6096)
			(layers "F.Cu" "F.Mask" "F.Paste")
			(net "P12V_SSD3_R")
		)
		(pad "4" smd rect
			(at -1.500124 0.249936 270)
			(size 0.2794 0.6096)
			(layers "F.Cu" "F.Mask" "F.Paste")
			(net "P12V_SSD3_R")
		)
		(pad "5" smd rect
			(at -1.500124 0.750062 270)
			(size 0.2794 0.6096)
			(layers "F.Cu" "F.Mask" "F.Paste")
			(net "P12V_SSD3_R")
		)
		(pad "6" smd rect
			(at -1.500124 1.249934 270)
			(size 0.2794 0.6096)
			(layers "F.Cu" "F.Mask" "F.Paste")
			(net "GND")
		)
		(pad "7" smd rect
			(at 1.500124 1.249934 270)
			(size 0.2794 0.6096)
			(layers "F.Cu" "F.Mask" "F.Paste")
			(net "P12V_SSD3_SS")
		)
		(pad "8" smd rect
			(at 1.500124 0.750062 270)
			(size 0.2794 0.6096)
			(layers "F.Cu" "F.Mask" "F.Paste")
			(net "PWRGD_P12V_SSD3")
		)
		(pad "9" smd rect
			(at 1.500124 0.249936 270)
			(size 0.2794 0.6096)
			(layers "F.Cu" "F.Mask" "F.Paste")
			(net "P12V_SSD3_OCP")
		)
		(pad "10" smd rect
			(at 1.500124 -0.249936 270)
			(size 0.2794 0.6096)
			(layers "F.Cu" "F.Mask" "F.Paste")
			(net "P5V_AUX")
		)
		(pad "11" smd rect
			(at 1.500124 -0.750062 270)
			(size 0.2794 0.6096)
			(layers "F.Cu" "F.Mask" "F.Paste")
			(net "SSD3_PWR_EN_R")
		)
		(pad "12" smd rect
			(at 1.500124 -1.249934 270)
			(size 0.2794 0.6096)
			(layers "F.Cu" "F.Mask" "F.Paste")
			(net "P12V_AUX")
		)
		(pad "13" smd rect
			(at 0 0)
			(size 1.9812 2.7178)
			(layers "F.Cu" "F.Mask" "F.Paste")
			(net "P12V_AUX")
		)
		(zone
			(layer "F.Cu")
			(hatch none 0.5)
			(connect_pads
				(clearance 0)
			)
			(min_thickness 0.25)
			(keepout
				(tracks not_allowed)
				(vias allowed)
				(pads allowed)
				(copperpour not_allowed)
				(footprints allowed)
			)
			(placement
				(enabled no)
				(sheetname "")
			)
			(fill
				(thermal_gap 0.5)
				(thermal_bridge_width 0.5)
				(island_removal_mode 0)
			)
			(polygon
				(pts
					(xy 101.789992 -55.9435) (xy 101.789992 -55.8165) (xy 101.789992 -52.8447) (xy 101.789992 -52.844192)
					(xy 99.503992 -52.844192) (xy 99.503992 -52.8447) (xy 99.503992 -52.9717) (xy 99.503992 -54.3941)
					(xy 99.605592 -54.3941) (xy 99.605592 -52.9717) (xy 101.688392 -52.9717) (xy 101.688392 -55.8165)
					(xy 99.605592 -55.8165) (xy 99.605592 -54.4195) (xy 99.503992 -54.4195) (xy 99.503992 -55.8165)
					(xy 99.503992 -55.9435) (xy 99.503992 -55.944008) (xy 101.789992 -55.944008)
				)
			)
		)
	)
	(footprint ""
		(layer "F.Cu")
		(at 196.119242 -129.880106 180)
		(property "Reference" "C235"
			(at 0 0 180)
			(layer "F.SilkS")
			(hide yes)
			(effects
				(font
					(size 1.27 1.27)
				)
			)
		)
		(property "Value" ""
			(at 0 0 180)
			(layer "F.Fab")
			(effects
				(font
					(size 1.27 1.27)
				)
			)
		)
		(duplicate_pad_numbers_are_jumpers no)
		(fp_line
			(start 0.299974 0.150114)
			(end -0.299974 0.150114)
			(stroke
				(width 0.1)
				(type default)
			)
			(layer "F.Fab")
		)
		(fp_line
			(start 0.299974 -0.150114)
			(end 0.299974 0.150114)
			(stroke
				(width 0.1)
				(type default)
			)
			(layer "F.Fab")
		)
		(fp_line
			(start -0.299974 0.150114)
			(end -0.299974 -0.150114)
			(stroke
				(width 0.1)
				(type default)
			)
			(layer "F.Fab")
		)
		(fp_line
			(start -0.299974 -0.150114)
			(end 0.299974 -0.150114)
			(stroke
				(width 0.1)
				(type default)
			)
			(layer "F.Fab")
		)
		(pad "1" smd rect
			(at -0.2667 0 180)
			(size 0.3048 0.381)
			(layers "F.Cu" "F.Mask" "F.Paste")
			(net "P5E_PEX1_STN0_TX_DN<4>")
		)
		(pad "2" smd rect
			(at 0.2667 0 180)
			(size 0.3048 0.381)
			(layers "F.Cu" "F.Mask" "F.Paste")
			(net "P5E_PEX1_STN0_TX_C_DN<4>")
		)
	)
	(footprint ""
		(layer "F.Cu")
		(at 258.369562 -215.56472)
		(property "Reference" "C2848"
			(at 0 0 0)
			(layer "F.SilkS")
			(hide yes)
			(effects
				(font
					(size 1.27 1.27)
				)
			)
		)
		(property "Value" ""
			(at 0 0 0)
			(layer "F.Fab")
			(effects
				(font
					(size 1.27 1.27)
				)
			)
		)
		(duplicate_pad_numbers_are_jumpers no)
		(fp_line
			(start -0.7874 -0.4064)
			(end 0.7874 -0.4064)
			(stroke
				(width 0.1524)
				(type default)
			)
			(layer "F.SilkS")
		)
		(fp_line
			(start -0.7874 0.4064)
			(end -0.7874 -0.4064)
			(stroke
				(width 0.1524)
				(type default)
			)
			(layer "F.SilkS")
		)
		(fp_line
			(start 0.7874 -0.4064)
			(end 0.7874 0.4064)
			(stroke
				(width 0.1524)
				(type default)
			)
			(layer "F.SilkS")
		)
		(fp_line
			(start 0.7874 0.4064)
			(end -0.7874 0.4064)
			(stroke
				(width 0.1524)
				(type default)
			)
			(layer "F.SilkS")
		)
		(fp_line
			(start -0.67945 -0.305054)
			(end -0.12065 -0.305054)
			(stroke
				(width 0.1)
				(type default)
			)
			(layer "F.Fab")
		)
		(fp_line
			(start -0.67945 0.3048)
			(end -0.67945 -0.305054)
			(stroke
				(width 0.1)
				(type default)
			)
			(layer "F.Fab")
		)
		(fp_line
			(start -0.12065 -0.305054)
			(end -0.12065 -0.2794)
			(stroke
				(width 0.1)
				(type default)
			)
			(layer "F.Fab")
		)
		(fp_line
			(start -0.12065 -0.2794)
			(end 0.12065 -0.2794)
			(stroke
				(width 0.1)
				(type default)
			)
			(layer "F.Fab")
		)
		(fp_line
			(start -0.12065 0.2794)
			(end -0.12065 0.3048)
			(stroke
				(width 0.1)
				(type default)
			)
			(layer "F.Fab")
		)
		(fp_line
			(start -0.12065 0.3048)
			(end -0.67945 0.3048)
			(stroke
				(width 0.1)
				(type default)
			)
			(layer "F.Fab")
		)
		(fp_line
			(start 0.120396 0.2794)
			(end -0.12065 0.2794)
			(stroke
				(width 0.1)
				(type default)
			)
			(layer "F.Fab")
		)
		(fp_line
			(start 0.120396 0.3048)
			(end 0.120396 0.2794)
			(stroke
				(width 0.1)
				(type default)
			)
			(layer "F.Fab")
		)
		(fp_line
			(start 0.12065 -0.3048)
			(end 0.67945 -0.3048)
			(stroke
				(width 0.1)
				(type default)
			)
			(layer "F.Fab")
		)
		(fp_line
			(start 0.12065 -0.2794)
			(end 0.12065 -0.3048)
			(stroke
				(width 0.1)
				(type default)
			)
			(layer "F.Fab")
		)
		(fp_line
			(start 0.67945 -0.3048)
			(end 0.67945 0.3048)
			(stroke
				(width 0.1)
				(type default)
			)
			(layer "F.Fab")
		)
		(fp_line
			(start 0.67945 0.3048)
			(end 0.120396 0.3048)
			(stroke
				(width 0.1)
				(type default)
			)
			(layer "F.Fab")
		)
		(pad "1" smd circle
			(at -0.40005 0)
			(size 0 0)
			(layers "F.Cu" "F.Mask" "F.Paste")
			(net "P5V_AUX")
		)
		(pad "2" smd circle
			(at 0.40005 0)
			(size 0 0)
			(layers "F.Cu" "F.Mask" "F.Paste")
			(net "GND")
		)
	)
	(footprint ""
		(layer "F.Cu")
		(at 82.661506 -151.596852 180)
		(property "Reference" "C6"
			(at 0 0 180)
			(layer "F.SilkS")
			(hide yes)
			(effects
				(font
					(size 1.27 1.27)
				)
			)
		)
		(property "Value" ""
			(at 0 0 180)
			(layer "F.Fab")
			(effects
				(font
					(size 1.27 1.27)
				)
			)
		)
		(duplicate_pad_numbers_are_jumpers no)
		(fp_line
			(start 0.299974 0.150114)
			(end -0.299974 0.150114)
			(stroke
				(width 0.1)
				(type default)
			)
			(layer "F.Fab")
		)
		(fp_line
			(start 0.299974 -0.150114)
			(end 0.299974 0.150114)
			(stroke
				(width 0.1)
				(type default)
			)
			(layer "F.Fab")
		)
		(fp_line
			(start -0.299974 0.150114)
			(end -0.299974 -0.150114)
			(stroke
				(width 0.1)
				(type default)
			)
			(layer "F.Fab")
		)
		(fp_line
			(start -0.299974 -0.150114)
			(end 0.299974 -0.150114)
			(stroke
				(width 0.1)
				(type default)
			)
			(layer "F.Fab")
		)
		(pad "1" smd rect
			(at -0.2667 0 180)
			(size 0.3048 0.381)
			(layers "F.Cu" "F.Mask" "F.Paste")
			(net "P5E_PEX0_STN0_TX_DN<13>")
		)
		(pad "2" smd rect
			(at 0.2667 0 180)
			(size 0.3048 0.381)
			(layers "F.Cu" "F.Mask" "F.Paste")
			(net "P5E_PEX0_STN0_TX_C_DN<13>")
		)
	)
	(footprint ""
		(layer "F.Cu")
		(at 376.312684 -87.6808)
		(property "Reference" "R1744"
			(at 0 0 0)
			(layer "F.SilkS")
			(hide yes)
			(effects
				(font
					(size 1.27 1.27)
				)
			)
		)
		(property "Value" ""
			(at 0 0 0)
			(layer "F.Fab")
			(effects
				(font
					(size 1.27 1.27)
				)
			)
		)
		(duplicate_pad_numbers_are_jumpers no)
		(fp_line
			(start -0.7874 -0.4064)
			(end 0.7874 -0.4064)
			(stroke
				(width 0.1524)
				(type default)
			)
			(layer "F.SilkS")
		)
		(fp_line
			(start -0.7874 0.4064)
			(end -0.7874 -0.4064)
			(stroke
				(width 0.1524)
				(type default)
			)
			(layer "F.SilkS")
		)
		(fp_line
			(start 0.7874 -0.4064)
			(end 0.7874 0.4064)
			(stroke
				(width 0.1524)
				(type default)
			)
			(layer "F.SilkS")
		)
		(fp_line
			(start 0.7874 0.4064)
			(end -0.7874 0.4064)
			(stroke
				(width 0.1524)
				(type default)
			)
			(layer "F.SilkS")
		)
		(fp_line
			(start -0.67945 -0.305054)
			(end -0.12065 -0.305054)
			(stroke
				(width 0.1)
				(type default)
			)
			(layer "F.Fab")
		)
		(fp_line
			(start -0.67945 0.3048)
			(end -0.67945 -0.305054)
			(stroke
				(width 0.1)
				(type default)
			)
			(layer "F.Fab")
		)
		(fp_line
			(start -0.12065 -0.305054)
			(end -0.12065 -0.2794)
			(stroke
				(width 0.1)
				(type default)
			)
			(layer "F.Fab")
		)
		(fp_line
			(start -0.12065 -0.2794)
			(end 0.12065 -0.2794)
			(stroke
				(width 0.1)
				(type default)
			)
			(layer "F.Fab")
		)
		(fp_line
			(start -0.12065 0.2794)
			(end -0.12065 0.3048)
			(stroke
				(width 0.1)
				(type default)
			)
			(layer "F.Fab")
		)
		(fp_line
			(start -0.12065 0.3048)
			(end -0.67945 0.3048)
			(stroke
				(width 0.1)
				(type default)
			)
			(layer "F.Fab")
		)
		(fp_line
			(start 0.120396 0.2794)
			(end -0.12065 0.2794)
			(stroke
				(width 0.1)
				(type default)
			)
			(layer "F.Fab")
		)
		(fp_line
			(start 0.120396 0.3048)
			(end 0.120396 0.2794)
			(stroke
				(width 0.1)
				(type default)
			)
			(layer "F.Fab")
		)
		(fp_line
			(start 0.12065 -0.3048)
			(end 0.67945 -0.3048)
			(stroke
				(width 0.1)
				(type default)
			)
			(layer "F.Fab")
		)
		(fp_line
			(start 0.12065 -0.2794)
			(end 0.12065 -0.3048)
			(stroke
				(width 0.1)
				(type default)
			)
			(layer "F.Fab")
		)
		(fp_line
			(start 0.67945 -0.3048)
			(end 0.67945 0.3048)
			(stroke
				(width 0.1)
				(type default)
			)
			(layer "F.Fab")
		)
		(fp_line
			(start 0.67945 0.3048)
			(end 0.120396 0.3048)
			(stroke
				(width 0.1)
				(type default)
			)
			(layer "F.Fab")
		)
		(pad "1" smd circle
			(at -0.40005 0)
			(size 0 0)
			(layers "F.Cu" "F.Mask" "F.Paste")
			(net "P3V3_AUX")
		)
		(pad "2" smd circle
			(at 0.40005 0)
			(size 0 0)
			(layers "F.Cu" "F.Mask" "F.Paste")
			(net "SMB_BIC_I2C6_MUX_NIC_ADC_R_SCL")
		)
	)
	(footprint ""
		(layer "F.Cu")
		(at 221.647512 -231.416606 -90)
		(property "Reference" "R4548"
			(at 0 0 270)
			(layer "F.SilkS")
			(hide yes)
			(effects
				(font
					(size 1.27 1.27)
				)
			)
		)
		(property "Value" ""
			(at 0 0 270)
			(layer "F.Fab")
			(effects
				(font
					(size 1.27 1.27)
				)
			)
		)
		(duplicate_pad_numbers_are_jumpers no)
		(fp_line
			(start -0.7874 0.4064)
			(end -0.7874 -0.4064)
			(stroke
				(width 0.1524)
				(type default)
			)
			(layer "F.SilkS")
		)
		(fp_line
			(start 0.7874 0.4064)
			(end -0.7874 0.4064)
			(stroke
				(width 0.1524)
				(type default)
			)
			(layer "F.SilkS")
		)
		(fp_line
			(start -0.7874 -0.4064)
			(end 0.7874 -0.4064)
			(stroke
				(width 0.1524)
				(type default)
			)
			(layer "F.SilkS")
		)
		(fp_line
			(start 0.7874 -0.4064)
			(end 0.7874 0.4064)
			(stroke
				(width 0.1524)
				(type default)
			)
			(layer "F.SilkS")
		)
		(fp_line
			(start -0.67945 0.3048)
			(end -0.67945 -0.305054)
			(stroke
				(width 0.1)
				(type default)
			)
			(layer "F.Fab")
		)
		(fp_line
			(start -0.12065 0.3048)
			(end -0.67945 0.3048)
			(stroke
				(width 0.1)
				(type default)
			)
			(layer "F.Fab")
		)
		(fp_line
			(start 0.120396 0.3048)
			(end 0.120396 0.2794)
			(stroke
				(width 0.1)
				(type default)
			)
			(layer "F.Fab")
		)
		(fp_line
			(start 0.67945 0.3048)
			(end 0.120396 0.3048)
			(stroke
				(width 0.1)
				(type default)
			)
			(layer "F.Fab")
		)
		(fp_line
			(start -0.12065 0.2794)
			(end -0.12065 0.3048)
			(stroke
				(width 0.1)
				(type default)
			)
			(layer "F.Fab")
		)
		(fp_line
			(start 0.120396 0.2794)
			(end -0.12065 0.2794)
			(stroke
				(width 0.1)
				(type default)
			)
			(layer "F.Fab")
		)
		(fp_line
			(start -0.12065 -0.2794)
			(end 0.12065 -0.2794)
			(stroke
				(width 0.1)
				(type default)
			)
			(layer "F.Fab")
		)
		(fp_line
			(start 0.12065 -0.2794)
			(end 0.12065 -0.3048)
			(stroke
				(width 0.1)
				(type default)
			)
			(layer "F.Fab")
		)
		(fp_line
			(start 0.12065 -0.3048)
			(end 0.67945 -0.3048)
			(stroke
				(width 0.1)
				(type default)
			)
			(layer "F.Fab")
		)
		(fp_line
			(start 0.67945 -0.3048)
			(end 0.67945 0.3048)
			(stroke
				(width 0.1)
				(type default)
			)
			(layer "F.Fab")
		)
		(fp_line
			(start -0.67945 -0.305054)
			(end -0.12065 -0.305054)
			(stroke
				(width 0.1)
				(type default)
			)
			(layer "F.Fab")
		)
		(fp_line
			(start -0.12065 -0.305054)
			(end -0.12065 -0.2794)
			(stroke
				(width 0.1)
				(type default)
			)
			(layer "F.Fab")
		)
		(pad "1" smd circle
			(at -0.40005 0 270)
			(size 0 0)
			(layers "F.Cu" "F.Mask" "F.Paste")
			(net "GND")
		)
		(pad "2" smd circle
			(at 0.40005 0 270)
			(size 0 0)
			(layers "F.Cu" "F.Mask" "F.Paste")
			(net "REV_ID1")
		)
	)
	(footprint ""
		(layer "F.Cu")
		(at 288.573718 -27.006296 -90)
		(property "Reference" "PC954"
			(at 0 0 270)
			(layer "F.SilkS")
			(hide yes)
			(effects
				(font
					(size 1.27 1.27)
				)
			)
		)
		(property "Value" ""
			(at 0 0 270)
			(layer "F.Fab")
			(effects
				(font
					(size 1.27 1.27)
				)
			)
		)
		(duplicate_pad_numbers_are_jumpers no)
		(fp_line
			(start -0.7874 0.4064)
			(end -0.7874 -0.4064)
			(stroke
				(width 0.1524)
				(type default)
			)
			(layer "F.SilkS")
		)
		(fp_line
			(start 0.7874 0.4064)
			(end -0.7874 0.4064)
			(stroke
				(width 0.1524)
				(type default)
			)
			(layer "F.SilkS")
		)
		(fp_line
			(start -0.7874 -0.4064)
			(end 0.7874 -0.4064)
			(stroke
				(width 0.1524)
				(type default)
			)
			(layer "F.SilkS")
		)
		(fp_line
			(start 0.7874 -0.4064)
			(end 0.7874 0.4064)
			(stroke
				(width 0.1524)
				(type default)
			)
			(layer "F.SilkS")
		)
		(fp_line
			(start -0.67945 0.3048)
			(end -0.67945 -0.305054)
			(stroke
				(width 0.1)
				(type default)
			)
			(layer "F.Fab")
		)
		(fp_line
			(start -0.12065 0.3048)
			(end -0.67945 0.3048)
			(stroke
				(width 0.1)
				(type default)
			)
			(layer "F.Fab")
		)
		(fp_line
			(start 0.120396 0.3048)
			(end 0.120396 0.2794)
			(stroke
				(width 0.1)
				(type default)
			)
			(layer "F.Fab")
		)
		(fp_line
			(start 0.67945 0.3048)
			(end 0.120396 0.3048)
			(stroke
				(width 0.1)
				(type default)
			)
			(layer "F.Fab")
		)
		(fp_line
			(start -0.12065 0.2794)
			(end -0.12065 0.3048)
			(stroke
				(width 0.1)
				(type default)
			)
			(layer "F.Fab")
		)
		(fp_line
			(start 0.120396 0.2794)
			(end -0.12065 0.2794)
			(stroke
				(width 0.1)
				(type default)
			)
			(layer "F.Fab")
		)
		(fp_line
			(start -0.12065 -0.2794)
			(end 0.12065 -0.2794)
			(stroke
				(width 0.1)
				(type default)
			)
			(layer "F.Fab")
		)
		(fp_line
			(start 0.12065 -0.2794)
			(end 0.12065 -0.3048)
			(stroke
				(width 0.1)
				(type default)
			)
			(layer "F.Fab")
		)
		(fp_line
			(start 0.12065 -0.3048)
			(end 0.67945 -0.3048)
			(stroke
				(width 0.1)
				(type default)
			)
			(layer "F.Fab")
		)
		(fp_line
			(start 0.67945 -0.3048)
			(end 0.67945 0.3048)
			(stroke
				(width 0.1)
				(type default)
			)
			(layer "F.Fab")
		)
		(fp_line
			(start -0.67945 -0.305054)
			(end -0.12065 -0.305054)
			(stroke
				(width 0.1)
				(type default)
			)
			(layer "F.Fab")
		)
		(fp_line
			(start -0.12065 -0.305054)
			(end -0.12065 -0.2794)
			(stroke
				(width 0.1)
				(type default)
			)
			(layer "F.Fab")
		)
		(pad "1" smd circle
			(at -0.40005 0 270)
			(size 0 0)
			(layers "F.Cu" "F.Mask" "F.Paste")
			(net "P3V3_SSD10_CO_MODE")
		)
		(pad "2" smd circle
			(at 0.40005 0 270)
			(size 0 0)
			(layers "F.Cu" "F.Mask" "F.Paste")
			(net "GND")
		)
	)
	(footprint ""
		(layer "F.Cu")
		(at 400.543776 -45.88891)
		(property "Reference" "R652"
			(at 0 0 0)
			(layer "F.SilkS")
			(hide yes)
			(effects
				(font
					(size 1.27 1.27)
				)
			)
		)
		(property "Value" ""
			(at 0 0 0)
			(layer "F.Fab")
			(effects
				(font
					(size 1.27 1.27)
				)
			)
		)
		(duplicate_pad_numbers_are_jumpers no)
		(fp_line
			(start -0.7874 -0.4064)
			(end 0.7874 -0.4064)
			(stroke
				(width 0.1524)
				(type default)
			)
			(layer "F.SilkS")
		)
		(fp_line
			(start -0.7874 0.4064)
			(end -0.7874 -0.4064)
			(stroke
				(width 0.1524)
				(type default)
			)
			(layer "F.SilkS")
		)
		(fp_line
			(start 0.7874 -0.4064)
			(end 0.7874 0.4064)
			(stroke
				(width 0.1524)
				(type default)
			)
			(layer "F.SilkS")
		)
		(fp_line
			(start 0.7874 0.4064)
			(end -0.7874 0.4064)
			(stroke
				(width 0.1524)
				(type default)
			)
			(layer "F.SilkS")
		)
		(fp_line
			(start -0.67945 -0.305054)
			(end -0.12065 -0.305054)
			(stroke
				(width 0.1)
				(type default)
			)
			(layer "F.Fab")
		)
		(fp_line
			(start -0.67945 0.3048)
			(end -0.67945 -0.305054)
			(stroke
				(width 0.1)
				(type default)
			)
			(layer "F.Fab")
		)
		(fp_line
			(start -0.12065 -0.305054)
			(end -0.12065 -0.2794)
			(stroke
				(width 0.1)
				(type default)
			)
			(layer "F.Fab")
		)
		(fp_line
			(start -0.12065 -0.2794)
			(end 0.12065 -0.2794)
			(stroke
				(width 0.1)
				(type default)
			)
			(layer "F.Fab")
		)
		(fp_line
			(start -0.12065 0.2794)
			(end -0.12065 0.3048)
			(stroke
				(width 0.1)
				(type default)
			)
			(layer "F.Fab")
		)
		(fp_line
			(start -0.12065 0.3048)
			(end -0.67945 0.3048)
			(stroke
				(width 0.1)
				(type default)
			)
			(layer "F.Fab")
		)
		(fp_line
			(start 0.120396 0.2794)
			(end -0.12065 0.2794)
			(stroke
				(width 0.1)
				(type default)
			)
			(layer "F.Fab")
		)
		(fp_line
			(start 0.120396 0.3048)
			(end 0.120396 0.2794)
			(stroke
				(width 0.1)
				(type default)
			)
			(layer "F.Fab")
		)
		(fp_line
			(start 0.12065 -0.3048)
			(end 0.67945 -0.3048)
			(stroke
				(width 0.1)
				(type default)
			)
			(layer "F.Fab")
		)
		(fp_line
			(start 0.12065 -0.2794)
			(end 0.12065 -0.3048)
			(stroke
				(width 0.1)
				(type default)
			)
			(layer "F.Fab")
		)
		(fp_line
			(start 0.67945 -0.3048)
			(end 0.67945 0.3048)
			(stroke
				(width 0.1)
				(type default)
			)
			(layer "F.Fab")
		)
		(fp_line
			(start 0.67945 0.3048)
			(end 0.120396 0.3048)
			(stroke
				(width 0.1)
				(type default)
			)
			(layer "F.Fab")
		)
		(pad "1" smd circle
			(at -0.40005 0)
			(size 0 0)
			(layers "F.Cu" "F.Mask" "F.Paste")
			(net "SSD13_ADC_A0")
		)
		(pad "2" smd circle
			(at 0.40005 0)
			(size 0 0)
			(layers "F.Cu" "F.Mask" "F.Paste")
			(net "GND")
		)
	)
	(footprint ""
		(layer "F.Cu")
		(at 93.003878 -291.722048 90)
		(property "Reference" "C2754"
			(at 0 0 90)
			(layer "F.SilkS")
			(hide yes)
			(effects
				(font
					(size 1.27 1.27)
				)
			)
		)
		(property "Value" ""
			(at 0 0 90)
			(layer "F.Fab")
			(effects
				(font
					(size 1.27 1.27)
				)
			)
		)
		(duplicate_pad_numbers_are_jumpers no)
		(fp_line
			(start 0.7874 -0.4064)
			(end 0.7874 0.4064)
			(stroke
				(width 0.1524)
				(type default)
			)
			(layer "F.SilkS")
		)
		(fp_line
			(start -0.7874 -0.4064)
			(end 0.7874 -0.4064)
			(stroke
				(width 0.1524)
				(type default)
			)
			(layer "F.SilkS")
		)
		(fp_line
			(start 0.7874 0.4064)
			(end -0.7874 0.4064)
			(stroke
				(width 0.1524)
				(type default)
			)
			(layer "F.SilkS")
		)
		(fp_line
			(start -0.7874 0.4064)
			(end -0.7874 -0.4064)
			(stroke
				(width 0.1524)
				(type default)
			)
			(layer "F.SilkS")
		)
		(fp_line
			(start -0.12065 -0.305054)
			(end -0.12065 -0.2794)
			(stroke
				(width 0.1)
				(type default)
			)
			(layer "F.Fab")
		)
		(fp_line
			(start -0.67945 -0.305054)
			(end -0.12065 -0.305054)
			(stroke
				(width 0.1)
				(type default)
			)
			(layer "F.Fab")
		)
		(fp_line
			(start 0.67945 -0.3048)
			(end 0.67945 0.3048)
			(stroke
				(width 0.1)
				(type default)
			)
			(layer "F.Fab")
		)
		(fp_line
			(start 0.12065 -0.3048)
			(end 0.67945 -0.3048)
			(stroke
				(width 0.1)
				(type default)
			)
			(layer "F.Fab")
		)
		(fp_line
			(start 0.12065 -0.2794)
			(end 0.12065 -0.3048)
			(stroke
				(width 0.1)
				(type default)
			)
			(layer "F.Fab")
		)
		(fp_line
			(start -0.12065 -0.2794)
			(end 0.12065 -0.2794)
			(stroke
				(width 0.1)
				(type default)
			)
			(layer "F.Fab")
		)
		(fp_line
			(start 0.120396 0.2794)
			(end -0.12065 0.2794)
			(stroke
				(width 0.1)
				(type default)
			)
			(layer "F.Fab")
		)
		(fp_line
			(start -0.12065 0.2794)
			(end -0.12065 0.3048)
			(stroke
				(width 0.1)
				(type default)
			)
			(layer "F.Fab")
		)
		(fp_line
			(start 0.67945 0.3048)
			(end 0.120396 0.3048)
			(stroke
				(width 0.1)
				(type default)
			)
			(layer "F.Fab")
		)
		(fp_line
			(start 0.120396 0.3048)
			(end 0.120396 0.2794)
			(stroke
				(width 0.1)
				(type default)
			)
			(layer "F.Fab")
		)
		(fp_line
			(start -0.12065 0.3048)
			(end -0.67945 0.3048)
			(stroke
				(width 0.1)
				(type default)
			)
			(layer "F.Fab")
		)
		(fp_line
			(start -0.67945 0.3048)
			(end -0.67945 -0.305054)
			(stroke
				(width 0.1)
				(type default)
			)
			(layer "F.Fab")
		)
		(pad "1" smd circle
			(at -0.40005 0 90)
			(size 0 0)
			(layers "F.Cu" "F.Mask" "F.Paste")
			(net "GND")
		)
		(pad "2" smd circle
			(at 0.40005 0 90)
			(size 0 0)
			(layers "F.Cu" "F.Mask" "F.Paste")
			(net "P3V3_AUX")
		)
	)
	(footprint ""
		(layer "F.Cu")
		(at 168.378632 -356.244906 90)
		(property "Reference" "C394"
			(at 0 0 90)
			(layer "F.SilkS")
			(hide yes)
			(effects
				(font
					(size 1.27 1.27)
				)
			)
		)
		(property "Value" ""
			(at 0 0 90)
			(layer "F.Fab")
			(effects
				(font
					(size 1.27 1.27)
				)
			)
		)
		(duplicate_pad_numbers_are_jumpers no)
		(fp_line
			(start 0.299974 -0.150114)
			(end 0.299974 0.150114)
			(stroke
				(width 0.1)
				(type default)
			)
			(layer "F.Fab")
		)
		(fp_line
			(start -0.299974 -0.150114)
			(end 0.299974 -0.150114)
			(stroke
				(width 0.1)
				(type default)
			)
			(layer "F.Fab")
		)
		(fp_line
			(start 0.299974 0.150114)
			(end -0.299974 0.150114)
			(stroke
				(width 0.1)
				(type default)
			)
			(layer "F.Fab")
		)
		(fp_line
			(start -0.299974 0.150114)
			(end -0.299974 -0.150114)
			(stroke
				(width 0.1)
				(type default)
			)
			(layer "F.Fab")
		)
		(pad "1" smd rect
			(at -0.2667 0 90)
			(size 0.3048 0.381)
			(layers "F.Cu" "F.Mask" "F.Paste")
			(net "P5E_PEX1_STN7_TX_DP<116>")
		)
		(pad "2" smd rect
			(at 0.2667 0 90)
			(size 0.3048 0.381)
			(layers "F.Cu" "F.Mask" "F.Paste")
			(net "P5E_PEX1_STN7_TX_C_DP<116>")
		)
	)
	(footprint ""
		(layer "F.Cu")
		(at 31.29407 -34.248852)
		(property "Reference" "R5648"
			(at 0 0 0)
			(layer "F.SilkS")
			(hide yes)
			(effects
				(font
					(size 1.27 1.27)
				)
			)
		)
		(property "Value" ""
			(at 0 0 0)
			(layer "F.Fab")
			(effects
				(font
					(size 1.27 1.27)
				)
			)
		)
		(duplicate_pad_numbers_are_jumpers no)
		(fp_line
			(start -0.7874 -0.4064)
			(end 0.7874 -0.4064)
			(stroke
				(width 0.1524)
				(type default)
			)
			(layer "F.SilkS")
		)
		(fp_line
			(start -0.7874 0.4064)
			(end -0.7874 -0.4064)
			(stroke
				(width 0.1524)
				(type default)
			)
			(layer "F.SilkS")
		)
		(fp_line
			(start 0.7874 -0.4064)
			(end 0.7874 0.4064)
			(stroke
				(width 0.1524)
				(type default)
			)
			(layer "F.SilkS")
		)
		(fp_line
			(start 0.7874 0.4064)
			(end -0.7874 0.4064)
			(stroke
				(width 0.1524)
				(type default)
			)
			(layer "F.SilkS")
		)
		(fp_line
			(start -0.67945 -0.305054)
			(end -0.12065 -0.305054)
			(stroke
				(width 0.1)
				(type default)
			)
			(layer "F.Fab")
		)
		(fp_line
			(start -0.67945 0.3048)
			(end -0.67945 -0.305054)
			(stroke
				(width 0.1)
				(type default)
			)
			(layer "F.Fab")
		)
		(fp_line
			(start -0.12065 -0.305054)
			(end -0.12065 -0.2794)
			(stroke
				(width 0.1)
				(type default)
			)
			(layer "F.Fab")
		)
		(fp_line
			(start -0.12065 -0.2794)
			(end 0.12065 -0.2794)
			(stroke
				(width 0.1)
				(type default)
			)
			(layer "F.Fab")
		)
		(fp_line
			(start -0.12065 0.2794)
			(end -0.12065 0.3048)
			(stroke
				(width 0.1)
				(type default)
			)
			(layer "F.Fab")
		)
		(fp_line
			(start -0.12065 0.3048)
			(end -0.67945 0.3048)
			(stroke
				(width 0.1)
				(type default)
			)
			(layer "F.Fab")
		)
		(fp_line
			(start 0.120396 0.2794)
			(end -0.12065 0.2794)
			(stroke
				(width 0.1)
				(type default)
			)
			(layer "F.Fab")
		)
		(fp_line
			(start 0.120396 0.3048)
			(end 0.120396 0.2794)
			(stroke
				(width 0.1)
				(type default)
			)
			(layer "F.Fab")
		)
		(fp_line
			(start 0.12065 -0.3048)
			(end 0.67945 -0.3048)
			(stroke
				(width 0.1)
				(type default)
			)
			(layer "F.Fab")
		)
		(fp_line
			(start 0.12065 -0.2794)
			(end 0.12065 -0.3048)
			(stroke
				(width 0.1)
				(type default)
			)
			(layer "F.Fab")
		)
		(fp_line
			(start 0.67945 -0.3048)
			(end 0.67945 0.3048)
			(stroke
				(width 0.1)
				(type default)
			)
			(layer "F.Fab")
		)
		(fp_line
			(start 0.67945 0.3048)
			(end 0.120396 0.3048)
			(stroke
				(width 0.1)
				(type default)
			)
			(layer "F.Fab")
		)
		(pad "1" smd circle
			(at -0.40005 0)
			(size 0 0)
			(layers "F.Cu" "F.Mask" "F.Paste")
			(net "RST_SMB_SSD1_ISO_N")
		)
		(pad "2" smd circle
			(at 0.40005 0)
			(size 0 0)
			(layers "F.Cu" "F.Mask" "F.Paste")
			(net "P3V3_SSD1")
		)
	)
	(footprint ""
		(layer "F.Cu")
		(at 131.30149 -55.78475 -90)
		(property "Reference" "PD23"
			(at 3.96875 2.11582 90)
			(unlocked yes)
			(layer "F.SilkS")
			(effects
				(font
					(size 0.7874 0.5842)
					(thickness 0.1524)
				)
				(justify left)
			)
		)
		(property "Value" ""
			(at 0 0 270)
			(layer "F.Fab")
			(effects
				(font
					(size 1.27 1.27)
				)
			)
		)
		(duplicate_pad_numbers_are_jumpers no)
		(fp_line
			(start -3.400044 1.459992)
			(end -3.400044 -1.459992)
			(stroke
				(width 0.1524)
				(type default)
			)
			(layer "F.SilkS")
		)
		(fp_line
			(start 4.107942 1.459992)
			(end -3.400044 1.459992)
			(stroke
				(width 0.1524)
				(type default)
			)
			(layer "F.SilkS")
		)
		(fp_line
			(start -3.400044 -1.459992)
			(end 4.107942 -1.459992)
			(stroke
				(width 0.1524)
				(type default)
			)
			(layer "F.SilkS")
		)
		(fp_line
			(start 4.107942 -1.459992)
			(end 4.107942 1.459992)
			(stroke
				(width 0.1524)
				(type default)
			)
			(layer "F.SilkS")
		)
		(fp_poly
			(pts
				(xy 4.107942 -1.459992) (xy 4.107942 1.459992) (xy 3.308096 1.459992) (xy 3.308096 -1.459992)
			)
			(stroke
				(width 0)
				(type default)
			)
			(fill yes)
			(layer "F.SilkS")
		)
		(fp_line
			(start -2.29997 1.459992)
			(end -2.29997 -1.459992)
			(stroke
				(width 0.1)
				(type default)
			)
			(layer "F.Fab")
		)
		(fp_line
			(start 2.29997 1.459992)
			(end -2.29997 1.459992)
			(stroke
				(width 0.1)
				(type default)
			)
			(layer "F.Fab")
		)
		(fp_line
			(start -2.29997 -1.459992)
			(end 2.29997 -1.459992)
			(stroke
				(width 0.1)
				(type default)
			)
			(layer "F.Fab")
		)
		(fp_line
			(start 2.29997 -1.459992)
			(end 2.29997 1.459992)
			(stroke
				(width 0.1)
				(type default)
			)
			(layer "F.Fab")
		)
		(fp_text user "-"
			(at 5.4102 0.29845 90)
			(unlocked yes)
			(layer "F.SilkS")
			(effects
				(font
					(size 1.905 1.4224)
					(thickness 0.1524)
				)
				(justify left)
			)
		)
		(fp_text user "+"
			(at -4.7752 -0.12065 270)
			(unlocked yes)
			(layer "F.SilkS")
			(effects
				(font
					(size 1.905 1.4224)
					(thickness 0.1524)
				)
				(justify left)
			)
		)
		(fp_text user "-"
			(at 5.4102 0.29845 90)
			(unlocked yes)
			(layer "F.Fab")
			(effects
				(font
					(size 1.905 1.4224)
					(thickness 0.1524)
				)
				(justify left)
			)
		)
		(fp_text user "+"
			(at -4.7752 -0.12065 270)
			(unlocked yes)
			(layer "F.Fab")
			(effects
				(font
					(size 1.905 1.4224)
					(thickness 0.1524)
				)
				(justify left)
			)
		)
		(pad "A" smd rect
			(at -1.999996 0)
			(size 1.7018 2.5146)
			(layers "F.Cu" "F.Mask" "F.Paste")
			(net "GND")
		)
		(pad "C" smd rect
			(at 1.999996 0)
			(size 1.7018 2.5146)
			(layers "F.Cu" "F.Mask" "F.Paste")
			(net "P12V_SSD4_R")
		)
	)
	(footprint ""
		(layer "F.Cu")
		(at 162.67557 -69.47916 180)
		(property "Reference" "PU108"
			(at -1.9685 4.13004 90)
			(unlocked yes)
			(layer "F.SilkS")
			(effects
				(font
					(size 0.7874 0.5842)
					(thickness 0.1524)
				)
			)
		)
		(property "Value" ""
			(at 0 0 180)
			(layer "F.Fab")
			(effects
				(font
					(size 1.27 1.27)
				)
			)
		)
		(duplicate_pad_numbers_are_jumpers no)
		(fp_line
			(start 1.239774 1.495298)
			(end -1.239774 1.495298)
			(stroke
				(width 0.1524)
				(type default)
			)
			(layer "F.SilkS")
		)
		(fp_line
			(start 1.239774 -1.495298)
			(end 1.239774 1.495298)
			(stroke
				(width 0.1524)
				(type default)
			)
			(layer "F.SilkS")
		)
		(fp_line
			(start -1.239774 1.495298)
			(end -1.239774 -1.495298)
			(stroke
				(width 0.1524)
				(type default)
			)
			(layer "F.SilkS")
		)
		(fp_line
			(start -1.239774 -1.495298)
			(end 1.239774 -1.495298)
			(stroke
				(width 0.1524)
				(type default)
			)
			(layer "F.SilkS")
		)
		(fp_poly
			(pts
				(xy -1.7399 -1.288542) (xy -2.458212 -0.57023) (xy -1.38049 -0.21082)
			)
			(stroke
				(width 0)
				(type default)
			)
			(fill yes)
			(layer "F.SilkS")
		)
		(fp_line
			(start 0.8001 1.050036)
			(end -0.8001 1.050036)
			(stroke
				(width 0.1)
				(type default)
			)
			(layer "F.Fab")
		)
		(fp_line
			(start 0.8001 -1.050036)
			(end 0.8001 1.050036)
			(stroke
				(width 0.1)
				(type default)
			)
			(layer "F.Fab")
		)
		(fp_line
			(start -0.8001 1.050036)
			(end -0.8001 -1.050036)
			(stroke
				(width 0.1)
				(type default)
			)
			(layer "F.Fab")
		)
		(fp_line
			(start -0.8001 -1.050036)
			(end 0.8001 -1.050036)
			(stroke
				(width 0.1)
				(type default)
			)
			(layer "F.Fab")
		)
		(fp_poly
			(pts
				(xy -2.458974 -0.508) (xy -2.458974 0.508) (xy -1.442974 0)
			)
			(stroke
				(width 0)
				(type default)
			)
			(fill yes)
			(layer "F.Fab")
		)
		(pad "1_2" smd circle
			(at -0.374904 0 270)
			(size 0 0)
			(layers "F.Cu" "F.Mask" "F.Paste")
			(net "P12V_AUX")
		)
		(pad "3" smd rect
			(at -0.499872 0.999998 180)
			(size 0.254 0.7112)
			(layers "F.Cu" "F.Mask" "F.Paste")
			(net "GND")
		)
		(pad "4" smd rect
			(at 0 0.999998 180)
			(size 0.254 0.7112)
			(layers "F.Cu" "F.Mask" "F.Paste")
			(net "P12V_SSD5_CO_ILIMIT")
		)
		(pad "5" smd rect
			(at 0.499872 0.999998 180)
			(size 0.254 0.7112)
			(layers "F.Cu" "F.Mask" "F.Paste")
			(net "P12V_SSD5_CO_MODE")
		)
		(pad "6_7" smd circle
			(at 0.374904 0 90)
			(size 0 0)
			(layers "F.Cu" "F.Mask" "F.Paste")
			(net "P12V_SSD5_R")
		)
		(pad "8" smd rect
			(at 0.499872 -0.999998 180)
			(size 0.254 0.7112)
			(layers "F.Cu" "F.Mask" "F.Paste")
			(net "P12V_SSD5_CO_GATE")
		)
		(pad "9" smd rect
			(at 0 -0.999998 180)
			(size 0.254 0.7112)
			(layers "F.Cu" "F.Mask" "F.Paste")
			(net "P12V_SSD5_CO_EN")
		)
		(pad "10" smd rect
			(at -0.499872 -0.999998 180)
			(size 0.254 0.7112)
			(layers "F.Cu" "F.Mask" "F.Paste")
			(net "P12V_SSD5_CO_DV_DT")
		)
	)
	(footprint ""
		(layer "F.Cu")
		(at 296.957242 -453.647556)
		(property "Reference" "X69"
			(at -0.1778 -1.92913 0)
			(unlocked yes)
			(layer "F.SilkS")
			(effects
				(font
					(size 0.7874 0.5842)
					(thickness 0.1524)
				)
				(justify left)
			)
		)
		(property "Value" ""
			(at 0 0 0)
			(layer "F.Fab")
			(effects
				(font
					(size 1.27 1.27)
				)
			)
		)
		(property "Device Type" "TP_TDR_4P_FTS_MPKT4_H025P0200_IO_TP15_TP_TDR_4P_DIP"
			(at 1.30175 1.27 90)
			(unlocked yes)
			(layer "F.Fab")
			(hide yes)
			(effects
				(font
					(size 0.635 0.4064)
					(thickness 0.1524)
				)
			)
		)
		(property "User Part Number" "TP15"
			(at 1.30175 1.27 90)
			(unlocked yes)
			(layer "Cmts.User")
			(hide yes)
			(effects
				(font
					(size 0.635 0.4064)
					(thickness 0.1524)
				)
			)
		)
		(duplicate_pad_numbers_are_jumpers no)
		(fp_line
			(start 0 -1.27)
			(end 0 -0.635)
			(stroke
				(width 0.1524)
				(type default)
			)
			(layer "F.SilkS")
		)
		(fp_line
			(start 0 0.635)
			(end 0 1.905)
			(stroke
				(width 0.1524)
				(type default)
			)
			(layer "F.SilkS")
		)
		(fp_line
			(start 0 3.175)
			(end 0 3.81)
			(stroke
				(width 0.1524)
				(type default)
			)
			(layer "F.SilkS")
		)
		(fp_line
			(start 0 3.81)
			(end 2.54 3.81)
			(stroke
				(width 0.1524)
				(type default)
			)
			(layer "F.SilkS")
		)
		(fp_line
			(start 2.54 -1.27)
			(end 0 -1.27)
			(stroke
				(width 0.1524)
				(type default)
			)
			(layer "F.SilkS")
		)
		(fp_line
			(start 2.54 -1.1303)
			(end 2.54 -1.27)
			(stroke
				(width 0.1524)
				(type default)
			)
			(layer "F.SilkS")
		)
		(fp_line
			(start 2.54 1.4097)
			(end 2.54 1.1303)
			(stroke
				(width 0.1524)
				(type default)
			)
			(layer "F.SilkS")
		)
		(fp_line
			(start 2.54 3.81)
			(end 2.54 3.6703)
			(stroke
				(width 0.1524)
				(type default)
			)
			(layer "F.SilkS")
		)
		(fp_poly
			(pts
				(xy -0.761746 0) (xy -2.285746 -0.762) (xy -2.285746 0.762)
			)
			(stroke
				(width 0)
				(type default)
			)
			(fill yes)
			(layer "F.SilkS")
		)
		(fp_line
			(start 0 -1.27)
			(end 0 3.81)
			(stroke
				(width 0.1)
				(type default)
			)
			(layer "F.Fab")
		)
		(fp_line
			(start 0 3.81)
			(end 2.54 3.81)
			(stroke
				(width 0.1)
				(type default)
			)
			(layer "F.Fab")
		)
		(fp_line
			(start 2.54 -1.27)
			(end 0 -1.27)
			(stroke
				(width 0.1)
				(type default)
			)
			(layer "F.Fab")
		)
		(fp_line
			(start 2.54 3.81)
			(end 2.54 -1.27)
			(stroke
				(width 0.1)
				(type default)
			)
			(layer "F.Fab")
		)
		(fp_poly
			(pts
				(xy -0.761746 0) (xy -2.285746 -0.762) (xy -2.285746 0.762)
			)
			(stroke
				(width 0)
				(type default)
			)
			(fill yes)
			(layer "F.Fab")
		)
		(pad "1" thru_hole circle
			(at 0 0)
			(size 1.0033 1.0033)
			(drill 0.249936)
			(layers "*.Cu" "*.Mask")
			(remove_unused_layers no)
			(net "TDR_DIFF_100_IN1_DIN")
			(clearance 0.10795)
			(thermal_gap 0.10795)
			(padstack
				(mode front_inner_back)
				(layer "Inner"
					(shape circle)
					(size 0.8001 0.8001)
					(clearance 0.1524)
				)
				(layer "B.Cu"
					(shape circle)
					(size 1.0033 1.0033)
					(clearance 0.10795)
				)
			)
		)
		(pad "2" thru_hole circle
			(at 2.54 0)
			(size 1.9939 1.9939)
			(drill 0.249936)
			(layers "*.Cu" "*.Mask")
			(remove_unused_layers no)
			(net "COUPON_GND1")
			(clearance 0.10795)
			(thermal_gap 0.10795)
			(padstack
				(mode front_inner_back)
				(layer "Inner"
					(shape circle)
					(size 0.8001 0.8001)
					(clearance 0.1524)
				)
				(layer "B.Cu"
					(shape circle)
					(size 1.9939 1.9939)
					(clearance 0.10795)
				)
			)
		)
		(pad "3" thru_hole circle
			(at 2.54 2.54)
			(size 1.9939 1.9939)
			(drill 0.249936)
			(layers "*.Cu" "*.Mask")
			(remove_unused_layers no)
			(net "COUPON_GND1")
			(clearance 0.10795)
			(thermal_gap 0.10795)
			(padstack
				(mode front_inner_back)
				(layer "Inner"
					(shape circle)
					(size 0.8001 0.8001)
					(clearance 0.1524)
				)
				(layer "B.Cu"
					(shape circle)
					(size 1.9939 1.9939)
					(clearance 0.10795)
				)
			)
		)
		(pad "4" thru_hole circle
			(at 0 2.54)
			(size 1.0033 1.0033)
			(drill 0.249936)
			(layers "*.Cu" "*.Mask")
			(remove_unused_layers no)
			(net "TDR_DIFF_100_IN1_DIP")
			(clearance 0.10795)
			(thermal_gap 0.10795)
			(padstack
				(mode front_inner_back)
				(layer "Inner"
					(shape circle)
					(size 0.8001 0.8001)
					(clearance 0.1524)
				)
				(layer "B.Cu"
					(shape circle)
					(size 1.0033 1.0033)
					(clearance 0.10795)
				)
			)
		)
	)
	(footprint ""
		(layer "F.Cu")
		(at 38.599872 -151.279352 180)
		(property "Reference" "R16"
			(at 0 0 180)
			(layer "F.SilkS")
			(hide yes)
			(effects
				(font
					(size 1.27 1.27)
				)
			)
		)
		(property "Value" ""
			(at 0 0 180)
			(layer "F.Fab")
			(effects
				(font
					(size 1.27 1.27)
				)
			)
		)
		(duplicate_pad_numbers_are_jumpers no)
		(fp_line
			(start 0.7874 0.4064)
			(end -0.7874 0.4064)
			(stroke
				(width 0.1524)
				(type default)
			)
			(layer "F.SilkS")
		)
		(fp_line
			(start 0.7874 -0.4064)
			(end 0.7874 0.4064)
			(stroke
				(width 0.1524)
				(type default)
			)
			(layer "F.SilkS")
		)
		(fp_line
			(start -0.7874 0.4064)
			(end -0.7874 -0.4064)
			(stroke
				(width 0.1524)
				(type default)
			)
			(layer "F.SilkS")
		)
		(fp_line
			(start -0.7874 -0.4064)
			(end 0.7874 -0.4064)
			(stroke
				(width 0.1524)
				(type default)
			)
			(layer "F.SilkS")
		)
		(fp_line
			(start 0.67945 0.3048)
			(end 0.120396 0.3048)
			(stroke
				(width 0.1)
				(type default)
			)
			(layer "F.Fab")
		)
		(fp_line
			(start 0.67945 -0.3048)
			(end 0.67945 0.3048)
			(stroke
				(width 0.1)
				(type default)
			)
			(layer "F.Fab")
		)
		(fp_line
			(start 0.12065 -0.2794)
			(end 0.12065 -0.3048)
			(stroke
				(width 0.1)
				(type default)
			)
			(layer "F.Fab")
		)
		(fp_line
			(start 0.12065 -0.3048)
			(end 0.67945 -0.3048)
			(stroke
				(width 0.1)
				(type default)
			)
			(layer "F.Fab")
		)
		(fp_line
			(start 0.120396 0.3048)
			(end 0.120396 0.2794)
			(stroke
				(width 0.1)
				(type default)
			)
			(layer "F.Fab")
		)
		(fp_line
			(start 0.120396 0.2794)
			(end -0.12065 0.2794)
			(stroke
				(width 0.1)
				(type default)
			)
			(layer "F.Fab")
		)
		(fp_line
			(start -0.12065 0.3048)
			(end -0.67945 0.3048)
			(stroke
				(width 0.1)
				(type default)
			)
			(layer "F.Fab")
		)
		(fp_line
			(start -0.12065 0.2794)
			(end -0.12065 0.3048)
			(stroke
				(width 0.1)
				(type default)
			)
			(layer "F.Fab")
		)
		(fp_line
			(start -0.12065 -0.2794)
			(end 0.12065 -0.2794)
			(stroke
				(width 0.1)
				(type default)
			)
			(layer "F.Fab")
		)
		(fp_line
			(start -0.12065 -0.305054)
			(end -0.12065 -0.2794)
			(stroke
				(width 0.1)
				(type default)
			)
			(layer "F.Fab")
		)
		(fp_line
			(start -0.67945 0.3048)
			(end -0.67945 -0.305054)
			(stroke
				(width 0.1)
				(type default)
			)
			(layer "F.Fab")
		)
		(fp_line
			(start -0.67945 -0.305054)
			(end -0.12065 -0.305054)
			(stroke
				(width 0.1)
				(type default)
			)
			(layer "F.Fab")
		)
		(pad "1" smd circle
			(at -0.40005 0 180)
			(size 0 0)
			(layers "F.Cu" "F.Mask" "F.Paste")
			(net "NCSI_NIC0_RXD0")
		)
		(pad "2" smd circle
			(at 0.40005 0 180)
			(size 0 0)
			(layers "F.Cu" "F.Mask" "F.Paste")
			(net "GND")
		)
	)
	(footprint ""
		(layer "F.Cu")
		(at 102.521512 -87.487506 180)
		(property "Reference" "C2670"
			(at 0 0 180)
			(layer "F.SilkS")
			(hide yes)
			(effects
				(font
					(size 1.27 1.27)
				)
			)
		)
		(property "Value" ""
			(at 0 0 180)
			(layer "F.Fab")
			(effects
				(font
					(size 1.27 1.27)
				)
			)
		)
		(duplicate_pad_numbers_are_jumpers no)
		(fp_line
			(start 1.2954 0.5842)
			(end -1.2954 0.5842)
			(stroke
				(width 0.1524)
				(type default)
			)
			(layer "F.SilkS")
		)
		(fp_line
			(start 1.2954 -0.5842)
			(end 1.2954 0.5842)
			(stroke
				(width 0.1524)
				(type default)
			)
			(layer "F.SilkS")
		)
		(fp_line
			(start -1.2954 0.5842)
			(end -1.2954 -0.5842)
			(stroke
				(width 0.1524)
				(type default)
			)
			(layer "F.SilkS")
		)
		(fp_line
			(start -1.2954 -0.5842)
			(end 1.2954 -0.5842)
			(stroke
				(width 0.1524)
				(type default)
			)
			(layer "F.SilkS")
		)
		(fp_line
			(start 1.1938 0.4064)
			(end 0.8636 0.4064)
			(stroke
				(width 0.1)
				(type default)
			)
			(layer "F.Fab")
		)
		(fp_line
			(start 1.1938 -0.4064)
			(end 1.1938 0.4064)
			(stroke
				(width 0.1)
				(type default)
			)
			(layer "F.Fab")
		)
		(fp_line
			(start 0.8636 0.4572)
			(end -0.8636 0.4572)
			(stroke
				(width 0.1)
				(type default)
			)
			(layer "F.Fab")
		)
		(fp_line
			(start 0.8636 0.4064)
			(end 0.8636 0.4572)
			(stroke
				(width 0.1)
				(type default)
			)
			(layer "F.Fab")
		)
		(fp_line
			(start 0.8636 -0.4064)
			(end 1.1938 -0.4064)
			(stroke
				(width 0.1)
				(type default)
			)
			(layer "F.Fab")
		)
		(fp_line
			(start 0.8636 -0.4572)
			(end 0.8636 -0.4064)
			(stroke
				(width 0.1)
				(type default)
			)
			(layer "F.Fab")
		)
		(fp_line
			(start -0.8636 0.4572)
			(end -0.8636 0.4064)
			(stroke
				(width 0.1)
				(type default)
			)
			(layer "F.Fab")
		)
		(fp_line
			(start -0.8636 0.4064)
			(end -1.1938 0.4064)
			(stroke
				(width 0.1)
				(type default)
			)
			(layer "F.Fab")
		)
		(fp_line
			(start -0.8636 -0.4064)
			(end -0.8636 -0.4572)
			(stroke
				(width 0.1)
				(type default)
			)
			(layer "F.Fab")
		)
		(fp_line
			(start -0.8636 -0.4572)
			(end 0.8636 -0.4572)
			(stroke
				(width 0.1)
				(type default)
			)
			(layer "F.Fab")
		)
		(fp_line
			(start -1.1938 0.4064)
			(end -1.1938 -0.4064)
			(stroke
				(width 0.1)
				(type default)
			)
			(layer "F.Fab")
		)
		(fp_line
			(start -1.1938 -0.4064)
			(end -0.8636 -0.4064)
			(stroke
				(width 0.1)
				(type default)
			)
			(layer "F.Fab")
		)
		(pad "1" smd rect
			(at -0.7366 0 90)
			(size 0.7112 0.8128)
			(layers "F.Cu" "F.Mask" "F.Paste")
			(net "P3V3_VDDAR_9ZXL0851_0_7")
		)
		(pad "2" smd rect
			(at 0.7366 0 90)
			(size 0.7112 0.8128)
			(layers "F.Cu" "F.Mask" "F.Paste")
			(net "GND")
		)
	)
	(footprint ""
		(layer "F.Cu")
		(at 458.452982 -116.230654 90)
		(property "Reference" "PR7058"
			(at 0 0 90)
			(layer "F.SilkS")
			(hide yes)
			(effects
				(font
					(size 1.27 1.27)
				)
			)
		)
		(property "Value" ""
			(at 0 0 90)
			(layer "F.Fab")
			(effects
				(font
					(size 1.27 1.27)
				)
			)
		)
		(duplicate_pad_numbers_are_jumpers no)
		(fp_line
			(start 0.7874 -0.4064)
			(end 0.7874 0.4064)
			(stroke
				(width 0.1524)
				(type default)
			)
			(layer "F.SilkS")
		)
		(fp_line
			(start -0.7874 -0.4064)
			(end 0.7874 -0.4064)
			(stroke
				(width 0.1524)
				(type default)
			)
			(layer "F.SilkS")
		)
		(fp_line
			(start 0.7874 0.4064)
			(end -0.7874 0.4064)
			(stroke
				(width 0.1524)
				(type default)
			)
			(layer "F.SilkS")
		)
		(fp_line
			(start -0.7874 0.4064)
			(end -0.7874 -0.4064)
			(stroke
				(width 0.1524)
				(type default)
			)
			(layer "F.SilkS")
		)
		(fp_line
			(start -0.12065 -0.305054)
			(end -0.12065 -0.2794)
			(stroke
				(width 0.1)
				(type default)
			)
			(layer "F.Fab")
		)
		(fp_line
			(start -0.67945 -0.305054)
			(end -0.12065 -0.305054)
			(stroke
				(width 0.1)
				(type default)
			)
			(layer "F.Fab")
		)
		(fp_line
			(start 0.67945 -0.3048)
			(end 0.67945 0.3048)
			(stroke
				(width 0.1)
				(type default)
			)
			(layer "F.Fab")
		)
		(fp_line
			(start 0.12065 -0.3048)
			(end 0.67945 -0.3048)
			(stroke
				(width 0.1)
				(type default)
			)
			(layer "F.Fab")
		)
		(fp_line
			(start 0.12065 -0.2794)
			(end 0.12065 -0.3048)
			(stroke
				(width 0.1)
				(type default)
			)
			(layer "F.Fab")
		)
		(fp_line
			(start -0.12065 -0.2794)
			(end 0.12065 -0.2794)
			(stroke
				(width 0.1)
				(type default)
			)
			(layer "F.Fab")
		)
		(fp_line
			(start 0.120396 0.2794)
			(end -0.12065 0.2794)
			(stroke
				(width 0.1)
				(type default)
			)
			(layer "F.Fab")
		)
		(fp_line
			(start -0.12065 0.2794)
			(end -0.12065 0.3048)
			(stroke
				(width 0.1)
				(type default)
			)
			(layer "F.Fab")
		)
		(fp_line
			(start 0.67945 0.3048)
			(end 0.120396 0.3048)
			(stroke
				(width 0.1)
				(type default)
			)
			(layer "F.Fab")
		)
		(fp_line
			(start 0.120396 0.3048)
			(end 0.120396 0.2794)
			(stroke
				(width 0.1)
				(type default)
			)
			(layer "F.Fab")
		)
		(fp_line
			(start -0.12065 0.3048)
			(end -0.67945 0.3048)
			(stroke
				(width 0.1)
				(type default)
			)
			(layer "F.Fab")
		)
		(fp_line
			(start -0.67945 0.3048)
			(end -0.67945 -0.305054)
			(stroke
				(width 0.1)
				(type default)
			)
			(layer "F.Fab")
		)
		(pad "1" smd circle
			(at -0.40005 0 90)
			(size 0 0)
			(layers "F.Cu" "F.Mask" "F.Paste")
			(net "P12V_NIC7_CO_FLTB")
		)
		(pad "2" smd circle
			(at 0.40005 0 90)
			(size 0 0)
			(layers "F.Cu" "F.Mask" "F.Paste")
			(net "P3V3_AUX")
		)
	)
	(footprint ""
		(layer "F.Cu")
		(at 162.5346 -34.546286 180)
		(property "Reference" "C284"
			(at 0 0 180)
			(layer "F.SilkS")
			(hide yes)
			(effects
				(font
					(size 1.27 1.27)
				)
			)
		)
		(property "Value" ""
			(at 0 0 180)
			(layer "F.Fab")
			(effects
				(font
					(size 1.27 1.27)
				)
			)
		)
		(duplicate_pad_numbers_are_jumpers no)
		(fp_line
			(start 0.299974 0.150114)
			(end -0.299974 0.150114)
			(stroke
				(width 0.1)
				(type default)
			)
			(layer "F.Fab")
		)
		(fp_line
			(start 0.299974 -0.150114)
			(end 0.299974 0.150114)
			(stroke
				(width 0.1)
				(type default)
			)
			(layer "F.Fab")
		)
		(fp_line
			(start -0.299974 0.150114)
			(end -0.299974 -0.150114)
			(stroke
				(width 0.1)
				(type default)
			)
			(layer "F.Fab")
		)
		(fp_line
			(start -0.299974 -0.150114)
			(end 0.299974 -0.150114)
			(stroke
				(width 0.1)
				(type default)
			)
			(layer "F.Fab")
		)
		(pad "1" smd rect
			(at -0.2667 0 180)
			(size 0.3048 0.381)
			(layers "F.Cu" "F.Mask" "F.Paste")
			(net "P5E_PEX1_STN2_TX_DP<43>")
		)
		(pad "2" smd rect
			(at 0.2667 0 180)
			(size 0.3048 0.381)
			(layers "F.Cu" "F.Mask" "F.Paste")
			(net "P5E_PEX1_STN2_TX_C_DP<43>")
		)
	)
	(footprint ""
		(layer "F.Cu")
		(at 219.615512 -231.416606 -90)
		(property "Reference" "R4549"
			(at 0 0 270)
			(layer "F.SilkS")
			(hide yes)
			(effects
				(font
					(size 1.27 1.27)
				)
			)
		)
		(property "Value" ""
			(at 0 0 270)
			(layer "F.Fab")
			(effects
				(font
					(size 1.27 1.27)
				)
			)
		)
		(duplicate_pad_numbers_are_jumpers no)
		(fp_line
			(start -0.7874 0.4064)
			(end -0.7874 -0.4064)
			(stroke
				(width 0.1524)
				(type default)
			)
			(layer "F.SilkS")
		)
		(fp_line
			(start 0.7874 0.4064)
			(end -0.7874 0.4064)
			(stroke
				(width 0.1524)
				(type default)
			)
			(layer "F.SilkS")
		)
		(fp_line
			(start -0.7874 -0.4064)
			(end 0.7874 -0.4064)
			(stroke
				(width 0.1524)
				(type default)
			)
			(layer "F.SilkS")
		)
		(fp_line
			(start 0.7874 -0.4064)
			(end 0.7874 0.4064)
			(stroke
				(width 0.1524)
				(type default)
			)
			(layer "F.SilkS")
		)
		(fp_line
			(start -0.67945 0.3048)
			(end -0.67945 -0.305054)
			(stroke
				(width 0.1)
				(type default)
			)
			(layer "F.Fab")
		)
		(fp_line
			(start -0.12065 0.3048)
			(end -0.67945 0.3048)
			(stroke
				(width 0.1)
				(type default)
			)
			(layer "F.Fab")
		)
		(fp_line
			(start 0.120396 0.3048)
			(end 0.120396 0.2794)
			(stroke
				(width 0.1)
				(type default)
			)
			(layer "F.Fab")
		)
		(fp_line
			(start 0.67945 0.3048)
			(end 0.120396 0.3048)
			(stroke
				(width 0.1)
				(type default)
			)
			(layer "F.Fab")
		)
		(fp_line
			(start -0.12065 0.2794)
			(end -0.12065 0.3048)
			(stroke
				(width 0.1)
				(type default)
			)
			(layer "F.Fab")
		)
		(fp_line
			(start 0.120396 0.2794)
			(end -0.12065 0.2794)
			(stroke
				(width 0.1)
				(type default)
			)
			(layer "F.Fab")
		)
		(fp_line
			(start -0.12065 -0.2794)
			(end 0.12065 -0.2794)
			(stroke
				(width 0.1)
				(type default)
			)
			(layer "F.Fab")
		)
		(fp_line
			(start 0.12065 -0.2794)
			(end 0.12065 -0.3048)
			(stroke
				(width 0.1)
				(type default)
			)
			(layer "F.Fab")
		)
		(fp_line
			(start 0.12065 -0.3048)
			(end 0.67945 -0.3048)
			(stroke
				(width 0.1)
				(type default)
			)
			(layer "F.Fab")
		)
		(fp_line
			(start 0.67945 -0.3048)
			(end 0.67945 0.3048)
			(stroke
				(width 0.1)
				(type default)
			)
			(layer "F.Fab")
		)
		(fp_line
			(start -0.67945 -0.305054)
			(end -0.12065 -0.305054)
			(stroke
				(width 0.1)
				(type default)
			)
			(layer "F.Fab")
		)
		(fp_line
			(start -0.12065 -0.305054)
			(end -0.12065 -0.2794)
			(stroke
				(width 0.1)
				(type default)
			)
			(layer "F.Fab")
		)
		(pad "1" smd circle
			(at -0.40005 0 270)
			(size 0 0)
			(layers "F.Cu" "F.Mask" "F.Paste")
			(net "GND")
		)
		(pad "2" smd circle
			(at 0.40005 0 270)
			(size 0 0)
			(layers "F.Cu" "F.Mask" "F.Paste")
			(net "REV_ID2")
		)
	)
	(footprint ""
		(layer "F.Cu")
		(at 26.243788 -43.85691)
		(property "Reference" "R510"
			(at 0 0 0)
			(layer "F.SilkS")
			(hide yes)
			(effects
				(font
					(size 1.27 1.27)
				)
			)
		)
		(property "Value" ""
			(at 0 0 0)
			(layer "F.Fab")
			(effects
				(font
					(size 1.27 1.27)
				)
			)
		)
		(duplicate_pad_numbers_are_jumpers no)
		(fp_line
			(start -0.7874 -0.4064)
			(end 0.7874 -0.4064)
			(stroke
				(width 0.1524)
				(type default)
			)
			(layer "F.SilkS")
		)
		(fp_line
			(start -0.7874 0.4064)
			(end -0.7874 -0.4064)
			(stroke
				(width 0.1524)
				(type default)
			)
			(layer "F.SilkS")
		)
		(fp_line
			(start 0.7874 -0.4064)
			(end 0.7874 0.4064)
			(stroke
				(width 0.1524)
				(type default)
			)
			(layer "F.SilkS")
		)
		(fp_line
			(start 0.7874 0.4064)
			(end -0.7874 0.4064)
			(stroke
				(width 0.1524)
				(type default)
			)
			(layer "F.SilkS")
		)
		(fp_line
			(start -0.67945 -0.305054)
			(end -0.12065 -0.305054)
			(stroke
				(width 0.1)
				(type default)
			)
			(layer "F.Fab")
		)
		(fp_line
			(start -0.67945 0.3048)
			(end -0.67945 -0.305054)
			(stroke
				(width 0.1)
				(type default)
			)
			(layer "F.Fab")
		)
		(fp_line
			(start -0.12065 -0.305054)
			(end -0.12065 -0.2794)
			(stroke
				(width 0.1)
				(type default)
			)
			(layer "F.Fab")
		)
		(fp_line
			(start -0.12065 -0.2794)
			(end 0.12065 -0.2794)
			(stroke
				(width 0.1)
				(type default)
			)
			(layer "F.Fab")
		)
		(fp_line
			(start -0.12065 0.2794)
			(end -0.12065 0.3048)
			(stroke
				(width 0.1)
				(type default)
			)
			(layer "F.Fab")
		)
		(fp_line
			(start -0.12065 0.3048)
			(end -0.67945 0.3048)
			(stroke
				(width 0.1)
				(type default)
			)
			(layer "F.Fab")
		)
		(fp_line
			(start 0.120396 0.2794)
			(end -0.12065 0.2794)
			(stroke
				(width 0.1)
				(type default)
			)
			(layer "F.Fab")
		)
		(fp_line
			(start 0.120396 0.3048)
			(end 0.120396 0.2794)
			(stroke
				(width 0.1)
				(type default)
			)
			(layer "F.Fab")
		)
		(fp_line
			(start 0.12065 -0.3048)
			(end 0.67945 -0.3048)
			(stroke
				(width 0.1)
				(type default)
			)
			(layer "F.Fab")
		)
		(fp_line
			(start 0.12065 -0.2794)
			(end 0.12065 -0.3048)
			(stroke
				(width 0.1)
				(type default)
			)
			(layer "F.Fab")
		)
		(fp_line
			(start 0.67945 -0.3048)
			(end 0.67945 0.3048)
			(stroke
				(width 0.1)
				(type default)
			)
			(layer "F.Fab")
		)
		(fp_line
			(start 0.67945 0.3048)
			(end 0.120396 0.3048)
			(stroke
				(width 0.1)
				(type default)
			)
			(layer "F.Fab")
		)
		(pad "1" smd circle
			(at -0.40005 0)
			(size 0 0)
			(layers "F.Cu" "F.Mask" "F.Paste")
			(net "SSD0_ADC_A1")
		)
		(pad "2" smd circle
			(at 0.40005 0)
			(size 0 0)
			(layers "F.Cu" "F.Mask" "F.Paste")
			(net "GND")
		)
	)
	(footprint ""
		(layer "F.Cu")
		(at 359.534206 -137.01776 180)
		(property "Reference" "PU27"
			(at 2.610358 -2.85369 0)
			(unlocked yes)
			(layer "F.SilkS")
			(effects
				(font
					(size 0.7874 0.5842)
					(thickness 0.1524)
				)
				(justify left)
			)
		)
		(property "Value" ""
			(at 0 0 180)
			(layer "F.Fab")
			(effects
				(font
					(size 1.27 1.27)
				)
			)
		)
		(duplicate_pad_numbers_are_jumpers no)
		(fp_line
			(start 1.943608 1.549908)
			(end -1.943608 1.549908)
			(stroke
				(width 0.1524)
				(type default)
			)
			(layer "F.SilkS")
		)
		(fp_line
			(start 1.943608 -1.549908)
			(end 1.943608 1.549908)
			(stroke
				(width 0.1524)
				(type default)
			)
			(layer "F.SilkS")
		)
		(fp_line
			(start -1.943608 1.549908)
			(end -1.943608 -1.549908)
			(stroke
				(width 0.1524)
				(type default)
			)
			(layer "F.SilkS")
		)
		(fp_line
			(start -1.943608 -1.549908)
			(end 1.943608 -1.549908)
			(stroke
				(width 0.1524)
				(type default)
			)
			(layer "F.SilkS")
		)
		(fp_poly
			(pts
				(xy -2.019808 -1.549908) (xy -1.257808 -1.549908) (xy -1.257808 -1.880108) (xy -2.019808 -1.880108)
			)
			(stroke
				(width 0)
				(type default)
			)
			(fill yes)
			(layer "F.SilkS")
		)
		(fp_line
			(start 1.549908 1.549908)
			(end -1.549908 1.549908)
			(stroke
				(width 0.1)
				(type default)
			)
			(layer "F.Fab")
		)
		(fp_line
			(start 1.549908 -1.549908)
			(end 1.549908 1.549908)
			(stroke
				(width 0.1)
				(type default)
			)
			(layer "F.Fab")
		)
		(fp_line
			(start -1.549908 1.549908)
			(end -1.549908 -1.549908)
			(stroke
				(width 0.1)
				(type default)
			)
			(layer "F.Fab")
		)
		(fp_line
			(start -1.549908 -1.549908)
			(end 1.549908 -1.549908)
			(stroke
				(width 0.1)
				(type default)
			)
			(layer "F.Fab")
		)
		(fp_poly
			(pts
				(xy -2.019808 -1.549908) (xy -1.257808 -1.549908) (xy -1.257808 -1.880108) (xy -2.019808 -1.880108)
			)
			(stroke
				(width 0)
				(type default)
			)
			(fill yes)
			(layer "F.Fab")
		)
		(pad "1" smd rect
			(at -1.500124 -1.249934 90)
			(size 0.2794 0.6096)
			(layers "F.Cu" "F.Mask" "F.Paste")
			(net "P12V_NIC6_R")
		)
		(pad "2" smd rect
			(at -1.500124 -0.750062 90)
			(size 0.2794 0.6096)
			(layers "F.Cu" "F.Mask" "F.Paste")
			(net "P12V_NIC6_R")
		)
		(pad "3" smd rect
			(at -1.500124 -0.249936 90)
			(size 0.2794 0.6096)
			(layers "F.Cu" "F.Mask" "F.Paste")
			(net "P12V_NIC6_R")
		)
		(pad "4" smd rect
			(at -1.500124 0.249936 90)
			(size 0.2794 0.6096)
			(layers "F.Cu" "F.Mask" "F.Paste")
			(net "P12V_NIC6_R")
		)
		(pad "5" smd rect
			(at -1.500124 0.750062 90)
			(size 0.2794 0.6096)
			(layers "F.Cu" "F.Mask" "F.Paste")
			(net "P12V_NIC6_R")
		)
		(pad "6" smd rect
			(at -1.500124 1.249934 90)
			(size 0.2794 0.6096)
			(layers "F.Cu" "F.Mask" "F.Paste")
			(net "GND")
		)
		(pad "7" smd rect
			(at 1.500124 1.249934 90)
			(size 0.2794 0.6096)
			(layers "F.Cu" "F.Mask" "F.Paste")
			(net "P12V_NIC6_SS")
		)
		(pad "8" smd rect
			(at 1.500124 0.750062 90)
			(size 0.2794 0.6096)
			(layers "F.Cu" "F.Mask" "F.Paste")
			(net "PWRGD_P12V_NIC6")
		)
		(pad "9" smd rect
			(at 1.500124 0.249936 90)
			(size 0.2794 0.6096)
			(layers "F.Cu" "F.Mask" "F.Paste")
			(net "P12V_NIC6_OCP")
		)
		(pad "10" smd rect
			(at 1.500124 -0.249936 90)
			(size 0.2794 0.6096)
			(layers "F.Cu" "F.Mask" "F.Paste")
			(net "P5V_AUX")
		)
		(pad "11" smd rect
			(at 1.500124 -0.750062 90)
			(size 0.2794 0.6096)
			(layers "F.Cu" "F.Mask" "F.Paste")
			(net "P12V_NIC6_EN_R")
		)
		(pad "12" smd rect
			(at 1.500124 -1.249934 90)
			(size 0.2794 0.6096)
			(layers "F.Cu" "F.Mask" "F.Paste")
			(net "P12V_AUX")
		)
		(pad "13" smd rect
			(at 0 0 180)
			(size 1.9812 2.7178)
			(layers "F.Cu" "F.Mask" "F.Paste")
			(net "P12V_AUX")
		)
		(zone
			(layer "F.Cu")
			(hatch none 0.5)
			(connect_pads
				(clearance 0)
			)
			(min_thickness 0.25)
			(keepout
				(tracks not_allowed)
				(vias allowed)
				(pads allowed)
				(copperpour not_allowed)
				(footprints allowed)
			)
			(placement
				(enabled no)
				(sheetname "")
			)
			(fill
				(thermal_gap 0.5)
				(thermal_bridge_width 0.5)
				(island_removal_mode 0)
			)
			(polygon
				(pts
					(xy 358.391206 -135.46836) (xy 358.391206 -135.59536) (xy 358.391206 -138.56716) (xy 358.391206 -138.567668)
					(xy 360.677206 -138.567668) (xy 360.677206 -138.56716) (xy 360.677206 -138.44016) (xy 360.677206 -137.01776)
					(xy 360.575606 -137.01776) (xy 360.575606 -138.44016) (xy 358.492806 -138.44016) (xy 358.492806 -135.59536)
					(xy 360.575606 -135.59536) (xy 360.575606 -136.99236) (xy 360.677206 -136.99236) (xy 360.677206 -135.59536)
					(xy 360.677206 -135.46836) (xy 360.677206 -135.467852) (xy 358.391206 -135.467852)
				)
			)
		)
	)
	(footprint ""
		(layer "F.Cu")
		(at 38.599872 -150.263352 180)
		(property "Reference" "R15"
			(at 0 0 180)
			(layer "F.SilkS")
			(hide yes)
			(effects
				(font
					(size 1.27 1.27)
				)
			)
		)
		(property "Value" ""
			(at 0 0 180)
			(layer "F.Fab")
			(effects
				(font
					(size 1.27 1.27)
				)
			)
		)
		(duplicate_pad_numbers_are_jumpers no)
		(fp_line
			(start 0.7874 0.4064)
			(end -0.7874 0.4064)
			(stroke
				(width 0.1524)
				(type default)
			)
			(layer "F.SilkS")
		)
		(fp_line
			(start 0.7874 -0.4064)
			(end 0.7874 0.4064)
			(stroke
				(width 0.1524)
				(type default)
			)
			(layer "F.SilkS")
		)
		(fp_line
			(start -0.7874 0.4064)
			(end -0.7874 -0.4064)
			(stroke
				(width 0.1524)
				(type default)
			)
			(layer "F.SilkS")
		)
		(fp_line
			(start -0.7874 -0.4064)
			(end 0.7874 -0.4064)
			(stroke
				(width 0.1524)
				(type default)
			)
			(layer "F.SilkS")
		)
		(fp_line
			(start 0.67945 0.3048)
			(end 0.120396 0.3048)
			(stroke
				(width 0.1)
				(type default)
			)
			(layer "F.Fab")
		)
		(fp_line
			(start 0.67945 -0.3048)
			(end 0.67945 0.3048)
			(stroke
				(width 0.1)
				(type default)
			)
			(layer "F.Fab")
		)
		(fp_line
			(start 0.12065 -0.2794)
			(end 0.12065 -0.3048)
			(stroke
				(width 0.1)
				(type default)
			)
			(layer "F.Fab")
		)
		(fp_line
			(start 0.12065 -0.3048)
			(end 0.67945 -0.3048)
			(stroke
				(width 0.1)
				(type default)
			)
			(layer "F.Fab")
		)
		(fp_line
			(start 0.120396 0.3048)
			(end 0.120396 0.2794)
			(stroke
				(width 0.1)
				(type default)
			)
			(layer "F.Fab")
		)
		(fp_line
			(start 0.120396 0.2794)
			(end -0.12065 0.2794)
			(stroke
				(width 0.1)
				(type default)
			)
			(layer "F.Fab")
		)
		(fp_line
			(start -0.12065 0.3048)
			(end -0.67945 0.3048)
			(stroke
				(width 0.1)
				(type default)
			)
			(layer "F.Fab")
		)
		(fp_line
			(start -0.12065 0.2794)
			(end -0.12065 0.3048)
			(stroke
				(width 0.1)
				(type default)
			)
			(layer "F.Fab")
		)
		(fp_line
			(start -0.12065 -0.2794)
			(end 0.12065 -0.2794)
			(stroke
				(width 0.1)
				(type default)
			)
			(layer "F.Fab")
		)
		(fp_line
			(start -0.12065 -0.305054)
			(end -0.12065 -0.2794)
			(stroke
				(width 0.1)
				(type default)
			)
			(layer "F.Fab")
		)
		(fp_line
			(start -0.67945 0.3048)
			(end -0.67945 -0.305054)
			(stroke
				(width 0.1)
				(type default)
			)
			(layer "F.Fab")
		)
		(fp_line
			(start -0.67945 -0.305054)
			(end -0.12065 -0.305054)
			(stroke
				(width 0.1)
				(type default)
			)
			(layer "F.Fab")
		)
		(pad "1" smd circle
			(at -0.40005 0 180)
			(size 0 0)
			(layers "F.Cu" "F.Mask" "F.Paste")
			(net "NCSI_NIC0_CRS_DV")
		)
		(pad "2" smd circle
			(at 0.40005 0 180)
			(size 0 0)
			(layers "F.Cu" "F.Mask" "F.Paste")
			(net "GND")
		)
	)
	(footprint ""
		(layer "F.Cu")
		(at 104.003094 -397.512286 90)
		(property "Reference" "C3637"
			(at 0 0 90)
			(layer "F.SilkS")
			(hide yes)
			(effects
				(font
					(size 1.27 1.27)
				)
			)
		)
		(property "Value" ""
			(at 0 0 90)
			(layer "F.Fab")
			(effects
				(font
					(size 1.27 1.27)
				)
			)
		)
		(duplicate_pad_numbers_are_jumpers no)
		(fp_line
			(start 0.7874 -0.4064)
			(end 0.7874 0.4064)
			(stroke
				(width 0.1524)
				(type default)
			)
			(layer "F.SilkS")
		)
		(fp_line
			(start -0.7874 -0.4064)
			(end 0.7874 -0.4064)
			(stroke
				(width 0.1524)
				(type default)
			)
			(layer "F.SilkS")
		)
		(fp_line
			(start 0.7874 0.4064)
			(end -0.7874 0.4064)
			(stroke
				(width 0.1524)
				(type default)
			)
			(layer "F.SilkS")
		)
		(fp_line
			(start -0.7874 0.4064)
			(end -0.7874 -0.4064)
			(stroke
				(width 0.1524)
				(type default)
			)
			(layer "F.SilkS")
		)
		(fp_line
			(start -0.12065 -0.305054)
			(end -0.12065 -0.2794)
			(stroke
				(width 0.1)
				(type default)
			)
			(layer "F.Fab")
		)
		(fp_line
			(start -0.67945 -0.305054)
			(end -0.12065 -0.305054)
			(stroke
				(width 0.1)
				(type default)
			)
			(layer "F.Fab")
		)
		(fp_line
			(start 0.67945 -0.3048)
			(end 0.67945 0.3048)
			(stroke
				(width 0.1)
				(type default)
			)
			(layer "F.Fab")
		)
		(fp_line
			(start 0.12065 -0.3048)
			(end 0.67945 -0.3048)
			(stroke
				(width 0.1)
				(type default)
			)
			(layer "F.Fab")
		)
		(fp_line
			(start 0.12065 -0.2794)
			(end 0.12065 -0.3048)
			(stroke
				(width 0.1)
				(type default)
			)
			(layer "F.Fab")
		)
		(fp_line
			(start -0.12065 -0.2794)
			(end 0.12065 -0.2794)
			(stroke
				(width 0.1)
				(type default)
			)
			(layer "F.Fab")
		)
		(fp_line
			(start 0.120396 0.2794)
			(end -0.12065 0.2794)
			(stroke
				(width 0.1)
				(type default)
			)
			(layer "F.Fab")
		)
		(fp_line
			(start -0.12065 0.2794)
			(end -0.12065 0.3048)
			(stroke
				(width 0.1)
				(type default)
			)
			(layer "F.Fab")
		)
		(fp_line
			(start 0.67945 0.3048)
			(end 0.120396 0.3048)
			(stroke
				(width 0.1)
				(type default)
			)
			(layer "F.Fab")
		)
		(fp_line
			(start 0.120396 0.3048)
			(end 0.120396 0.2794)
			(stroke
				(width 0.1)
				(type default)
			)
			(layer "F.Fab")
		)
		(fp_line
			(start -0.12065 0.3048)
			(end -0.67945 0.3048)
			(stroke
				(width 0.1)
				(type default)
			)
			(layer "F.Fab")
		)
		(fp_line
			(start -0.67945 0.3048)
			(end -0.67945 -0.305054)
			(stroke
				(width 0.1)
				(type default)
			)
			(layer "F.Fab")
		)
		(pad "1" smd circle
			(at -0.40005 0 90)
			(size 0 0)
			(layers "F.Cu" "F.Mask" "F.Paste")
			(net "RST_BIC_USB_HUB_R1_N")
		)
		(pad "2" smd circle
			(at 0.40005 0 90)
			(size 0 0)
			(layers "F.Cu" "F.Mask" "F.Paste")
			(net "GND")
		)
	)
	(footprint ""
		(layer "F.Cu")
		(at 52.459382 -22.955504 90)
		(property "Reference" "R1644"
			(at 0 0 90)
			(layer "F.SilkS")
			(hide yes)
			(effects
				(font
					(size 1.27 1.27)
				)
			)
		)
		(property "Value" ""
			(at 0 0 90)
			(layer "F.Fab")
			(effects
				(font
					(size 1.27 1.27)
				)
			)
		)
		(duplicate_pad_numbers_are_jumpers no)
		(fp_line
			(start 0.7874 -0.4064)
			(end 0.7874 0.4064)
			(stroke
				(width 0.1524)
				(type default)
			)
			(layer "F.SilkS")
		)
		(fp_line
			(start -0.7874 -0.4064)
			(end 0.7874 -0.4064)
			(stroke
				(width 0.1524)
				(type default)
			)
			(layer "F.SilkS")
		)
		(fp_line
			(start 0.7874 0.4064)
			(end -0.7874 0.4064)
			(stroke
				(width 0.1524)
				(type default)
			)
			(layer "F.SilkS")
		)
		(fp_line
			(start -0.7874 0.4064)
			(end -0.7874 -0.4064)
			(stroke
				(width 0.1524)
				(type default)
			)
			(layer "F.SilkS")
		)
		(fp_line
			(start -0.12065 -0.305054)
			(end -0.12065 -0.2794)
			(stroke
				(width 0.1)
				(type default)
			)
			(layer "F.Fab")
		)
		(fp_line
			(start -0.67945 -0.305054)
			(end -0.12065 -0.305054)
			(stroke
				(width 0.1)
				(type default)
			)
			(layer "F.Fab")
		)
		(fp_line
			(start 0.67945 -0.3048)
			(end 0.67945 0.3048)
			(stroke
				(width 0.1)
				(type default)
			)
			(layer "F.Fab")
		)
		(fp_line
			(start 0.12065 -0.3048)
			(end 0.67945 -0.3048)
			(stroke
				(width 0.1)
				(type default)
			)
			(layer "F.Fab")
		)
		(fp_line
			(start 0.12065 -0.2794)
			(end 0.12065 -0.3048)
			(stroke
				(width 0.1)
				(type default)
			)
			(layer "F.Fab")
		)
		(fp_line
			(start -0.12065 -0.2794)
			(end 0.12065 -0.2794)
			(stroke
				(width 0.1)
				(type default)
			)
			(layer "F.Fab")
		)
		(fp_line
			(start 0.120396 0.2794)
			(end -0.12065 0.2794)
			(stroke
				(width 0.1)
				(type default)
			)
			(layer "F.Fab")
		)
		(fp_line
			(start -0.12065 0.2794)
			(end -0.12065 0.3048)
			(stroke
				(width 0.1)
				(type default)
			)
			(layer "F.Fab")
		)
		(fp_line
			(start 0.67945 0.3048)
			(end 0.120396 0.3048)
			(stroke
				(width 0.1)
				(type default)
			)
			(layer "F.Fab")
		)
		(fp_line
			(start 0.120396 0.3048)
			(end 0.120396 0.2794)
			(stroke
				(width 0.1)
				(type default)
			)
			(layer "F.Fab")
		)
		(fp_line
			(start -0.12065 0.3048)
			(end -0.67945 0.3048)
			(stroke
				(width 0.1)
				(type default)
			)
			(layer "F.Fab")
		)
		(fp_line
			(start -0.67945 0.3048)
			(end -0.67945 -0.305054)
			(stroke
				(width 0.1)
				(type default)
			)
			(layer "F.Fab")
		)
		(pad "1" smd circle
			(at -0.40005 0 90)
			(size 0 0)
			(layers "F.Cu" "F.Mask" "F.Paste")
			(net "SMB_BIC_I2C9_MUX0_SSD1_R_SCL")
		)
		(pad "2" smd circle
			(at 0.40005 0 90)
			(size 0 0)
			(layers "F.Cu" "F.Mask" "F.Paste")
			(net "SMB_ISO_SSD1_SCL")
		)
	)
	(footprint ""
		(layer "F.Cu")
		(at 115.356386 -88.469978 180)
		(property "Reference" "R1148"
			(at 0 0 180)
			(layer "F.SilkS")
			(hide yes)
			(effects
				(font
					(size 1.27 1.27)
				)
			)
		)
		(property "Value" ""
			(at 0 0 180)
			(layer "F.Fab")
			(effects
				(font
					(size 1.27 1.27)
				)
			)
		)
		(duplicate_pad_numbers_are_jumpers no)
		(fp_line
			(start -0.7874 -0.4064)
			(end 0.7874 -0.4064)
			(stroke
				(width 0.1524)
				(type default)
			)
			(layer "F.SilkS")
		)
		(fp_line
			(start 0.67945 0.3048)
			(end 0.120396 0.3048)
			(stroke
				(width 0.1)
				(type default)
			)
			(layer "F.Fab")
		)
		(fp_line
			(start 0.67945 -0.3048)
			(end 0.67945 0.3048)
			(stroke
				(width 0.1)
				(type default)
			)
			(layer "F.Fab")
		)
		(fp_line
			(start 0.12065 -0.2794)
			(end 0.12065 -0.3048)
			(stroke
				(width 0.1)
				(type default)
			)
			(layer "F.Fab")
		)
		(fp_line
			(start 0.12065 -0.3048)
			(end 0.67945 -0.3048)
			(stroke
				(width 0.1)
				(type default)
			)
			(layer "F.Fab")
		)
		(fp_line
			(start 0.120396 0.3048)
			(end 0.120396 0.2794)
			(stroke
				(width 0.1)
				(type default)
			)
			(layer "F.Fab")
		)
		(fp_line
			(start 0.120396 0.2794)
			(end -0.12065 0.2794)
			(stroke
				(width 0.1)
				(type default)
			)
			(layer "F.Fab")
		)
		(fp_line
			(start -0.12065 0.3048)
			(end -0.67945 0.3048)
			(stroke
				(width 0.1)
				(type default)
			)
			(layer "F.Fab")
		)
		(fp_line
			(start -0.12065 0.2794)
			(end -0.12065 0.3048)
			(stroke
				(width 0.1)
				(type default)
			)
			(layer "F.Fab")
		)
		(fp_line
			(start -0.12065 -0.2794)
			(end 0.12065 -0.2794)
			(stroke
				(width 0.1)
				(type default)
			)
			(layer "F.Fab")
		)
		(fp_line
			(start -0.12065 -0.305054)
			(end -0.12065 -0.2794)
			(stroke
				(width 0.1)
				(type default)
			)
			(layer "F.Fab")
		)
		(fp_line
			(start -0.67945 0.3048)
			(end -0.67945 -0.305054)
			(stroke
				(width 0.1)
				(type default)
			)
			(layer "F.Fab")
		)
		(fp_line
			(start -0.67945 -0.305054)
			(end -0.12065 -0.305054)
			(stroke
				(width 0.1)
				(type default)
			)
			(layer "F.Fab")
		)
		(pad "1" smd circle
			(at -0.40005 0 180)
			(size 0 0)
			(layers "F.Cu" "F.Mask" "F.Paste")
			(net "CLK_100M_DB800ZL_SSD6_R_DP")
		)
		(pad "2" smd circle
			(at 0.40005 0 180)
			(size 0 0)
			(layers "F.Cu" "F.Mask" "F.Paste")
			(net "CLK_100M_DB800ZL_SSD6_DP")
		)
	)
	(footprint ""
		(layer "F.Cu")
		(at 312.477404 -350.098614 90)
		(property "Reference" "C549"
			(at 0 0 90)
			(layer "F.SilkS")
			(hide yes)
			(effects
				(font
					(size 1.27 1.27)
				)
			)
		)
		(property "Value" ""
			(at 0 0 90)
			(layer "F.Fab")
			(effects
				(font
					(size 1.27 1.27)
				)
			)
		)
		(duplicate_pad_numbers_are_jumpers no)
		(fp_line
			(start 0.299974 -0.150114)
			(end 0.299974 0.150114)
			(stroke
				(width 0.1)
				(type default)
			)
			(layer "F.Fab")
		)
		(fp_line
			(start -0.299974 -0.150114)
			(end 0.299974 -0.150114)
			(stroke
				(width 0.1)
				(type default)
			)
			(layer "F.Fab")
		)
		(fp_line
			(start 0.299974 0.150114)
			(end -0.299974 0.150114)
			(stroke
				(width 0.1)
				(type default)
			)
			(layer "F.Fab")
		)
		(fp_line
			(start -0.299974 0.150114)
			(end -0.299974 -0.150114)
			(stroke
				(width 0.1)
				(type default)
			)
			(layer "F.Fab")
		)
		(pad "1" smd rect
			(at -0.2667 0 90)
			(size 0.3048 0.381)
			(layers "F.Cu" "F.Mask" "F.Paste")
			(net "P5E_PEX2_STN5_TX_DP<80>")
		)
		(pad "2" smd rect
			(at 0.2667 0 90)
			(size 0.3048 0.381)
			(layers "F.Cu" "F.Mask" "F.Paste")
			(net "P5E_PEX2_STN5_TX_C_DP<80>")
		)
	)
	(footprint ""
		(layer "F.Cu")
		(at 324.587108 -300.650402 -90)
		(property "Reference" "R3977"
			(at 0 0 270)
			(layer "F.SilkS")
			(hide yes)
			(effects
				(font
					(size 1.27 1.27)
				)
			)
		)
		(property "Value" ""
			(at 0 0 270)
			(layer "F.Fab")
			(effects
				(font
					(size 1.27 1.27)
				)
			)
		)
		(duplicate_pad_numbers_are_jumpers no)
		(fp_line
			(start -0.7874 0.4064)
			(end -0.7874 -0.4064)
			(stroke
				(width 0.1524)
				(type default)
			)
			(layer "F.SilkS")
		)
		(fp_line
			(start 0.7874 0.4064)
			(end -0.7874 0.4064)
			(stroke
				(width 0.1524)
				(type default)
			)
			(layer "F.SilkS")
		)
		(fp_line
			(start -0.7874 -0.4064)
			(end 0.7874 -0.4064)
			(stroke
				(width 0.1524)
				(type default)
			)
			(layer "F.SilkS")
		)
		(fp_line
			(start 0.7874 -0.4064)
			(end 0.7874 0.4064)
			(stroke
				(width 0.1524)
				(type default)
			)
			(layer "F.SilkS")
		)
		(fp_line
			(start -0.67945 0.3048)
			(end -0.67945 -0.305054)
			(stroke
				(width 0.1)
				(type default)
			)
			(layer "F.Fab")
		)
		(fp_line
			(start -0.12065 0.3048)
			(end -0.67945 0.3048)
			(stroke
				(width 0.1)
				(type default)
			)
			(layer "F.Fab")
		)
		(fp_line
			(start 0.120396 0.3048)
			(end 0.120396 0.2794)
			(stroke
				(width 0.1)
				(type default)
			)
			(layer "F.Fab")
		)
		(fp_line
			(start 0.67945 0.3048)
			(end 0.120396 0.3048)
			(stroke
				(width 0.1)
				(type default)
			)
			(layer "F.Fab")
		)
		(fp_line
			(start -0.12065 0.2794)
			(end -0.12065 0.3048)
			(stroke
				(width 0.1)
				(type default)
			)
			(layer "F.Fab")
		)
		(fp_line
			(start 0.120396 0.2794)
			(end -0.12065 0.2794)
			(stroke
				(width 0.1)
				(type default)
			)
			(layer "F.Fab")
		)
		(fp_line
			(start -0.12065 -0.2794)
			(end 0.12065 -0.2794)
			(stroke
				(width 0.1)
				(type default)
			)
			(layer "F.Fab")
		)
		(fp_line
			(start 0.12065 -0.2794)
			(end 0.12065 -0.3048)
			(stroke
				(width 0.1)
				(type default)
			)
			(layer "F.Fab")
		)
		(fp_line
			(start 0.12065 -0.3048)
			(end 0.67945 -0.3048)
			(stroke
				(width 0.1)
				(type default)
			)
			(layer "F.Fab")
		)
		(fp_line
			(start 0.67945 -0.3048)
			(end 0.67945 0.3048)
			(stroke
				(width 0.1)
				(type default)
			)
			(layer "F.Fab")
		)
		(fp_line
			(start -0.67945 -0.305054)
			(end -0.12065 -0.305054)
			(stroke
				(width 0.1)
				(type default)
			)
			(layer "F.Fab")
		)
		(fp_line
			(start -0.12065 -0.305054)
			(end -0.12065 -0.2794)
			(stroke
				(width 0.1)
				(type default)
			)
			(layer "F.Fab")
		)
		(pad "1" smd circle
			(at -0.40005 0 270)
			(size 0 0)
			(layers "F.Cu" "F.Mask" "F.Paste")
			(net "I2C0_PEX2_SHPC_SCL")
		)
		(pad "2" smd circle
			(at 0.40005 0 270)
			(size 0 0)
			(layers "F.Cu" "F.Mask" "F.Paste")
			(net "I2C_PEX2_HOST_SCL")
		)
	)
	(footprint ""
		(layer "F.Cu")
		(at 217.235786 -219.318586 180)
		(property "Reference" "R1498"
			(at 0 0 180)
			(layer "F.SilkS")
			(hide yes)
			(effects
				(font
					(size 1.27 1.27)
				)
			)
		)
		(property "Value" ""
			(at 0 0 180)
			(layer "F.Fab")
			(effects
				(font
					(size 1.27 1.27)
				)
			)
		)
		(duplicate_pad_numbers_are_jumpers no)
		(fp_line
			(start 0.7874 0.4064)
			(end -0.7874 0.4064)
			(stroke
				(width 0.1524)
				(type default)
			)
			(layer "F.SilkS")
		)
		(fp_line
			(start 0.7874 -0.4064)
			(end 0.7874 0.4064)
			(stroke
				(width 0.1524)
				(type default)
			)
			(layer "F.SilkS")
		)
		(fp_line
			(start -0.7874 0.4064)
			(end -0.7874 -0.4064)
			(stroke
				(width 0.1524)
				(type default)
			)
			(layer "F.SilkS")
		)
		(fp_line
			(start -0.7874 -0.4064)
			(end 0.7874 -0.4064)
			(stroke
				(width 0.1524)
				(type default)
			)
			(layer "F.SilkS")
		)
		(fp_line
			(start 0.67945 0.3048)
			(end 0.120396 0.3048)
			(stroke
				(width 0.1)
				(type default)
			)
			(layer "F.Fab")
		)
		(fp_line
			(start 0.67945 -0.3048)
			(end 0.67945 0.3048)
			(stroke
				(width 0.1)
				(type default)
			)
			(layer "F.Fab")
		)
		(fp_line
			(start 0.12065 -0.2794)
			(end 0.12065 -0.3048)
			(stroke
				(width 0.1)
				(type default)
			)
			(layer "F.Fab")
		)
		(fp_line
			(start 0.12065 -0.3048)
			(end 0.67945 -0.3048)
			(stroke
				(width 0.1)
				(type default)
			)
			(layer "F.Fab")
		)
		(fp_line
			(start 0.120396 0.3048)
			(end 0.120396 0.2794)
			(stroke
				(width 0.1)
				(type default)
			)
			(layer "F.Fab")
		)
		(fp_line
			(start 0.120396 0.2794)
			(end -0.12065 0.2794)
			(stroke
				(width 0.1)
				(type default)
			)
			(layer "F.Fab")
		)
		(fp_line
			(start -0.12065 0.3048)
			(end -0.67945 0.3048)
			(stroke
				(width 0.1)
				(type default)
			)
			(layer "F.Fab")
		)
		(fp_line
			(start -0.12065 0.2794)
			(end -0.12065 0.3048)
			(stroke
				(width 0.1)
				(type default)
			)
			(layer "F.Fab")
		)
		(fp_line
			(start -0.12065 -0.2794)
			(end 0.12065 -0.2794)
			(stroke
				(width 0.1)
				(type default)
			)
			(layer "F.Fab")
		)
		(fp_line
			(start -0.12065 -0.305054)
			(end -0.12065 -0.2794)
			(stroke
				(width 0.1)
				(type default)
			)
			(layer "F.Fab")
		)
		(fp_line
			(start -0.67945 0.3048)
			(end -0.67945 -0.305054)
			(stroke
				(width 0.1)
				(type default)
			)
			(layer "F.Fab")
		)
		(fp_line
			(start -0.67945 -0.305054)
			(end -0.12065 -0.305054)
			(stroke
				(width 0.1)
				(type default)
			)
			(layer "F.Fab")
		)
		(pad "1" smd circle
			(at -0.40005 0 180)
			(size 0 0)
			(layers "F.Cu" "F.Mask" "F.Paste")
			(net "SMB_NIC4_SCL")
		)
		(pad "2" smd circle
			(at 0.40005 0 180)
			(size 0 0)
			(layers "F.Cu" "F.Mask" "F.Paste")
			(net "SMB_NIC4_R_SCL")
		)
	)
	(footprint ""
		(layer "F.Cu")
		(at 133.88848 -249.644916)
		(property "Reference" "PJP1"
			(at -1.4224 -4.562348 0)
			(unlocked yes)
			(layer "F.SilkS")
			(effects
				(font
					(size 0.7874 0.5842)
					(thickness 0.1524)
				)
				(justify left)
			)
		)
		(property "Value" ""
			(at 0 0 0)
			(layer "F.Fab")
			(effects
				(font
					(size 1.27 1.27)
				)
			)
		)
		(duplicate_pad_numbers_are_jumpers no)
		(fp_line
			(start -1.27 -3.81)
			(end 1.27 -3.81)
			(stroke
				(width 0.1524)
				(type default)
			)
			(layer "F.SilkS")
		)
		(fp_line
			(start -1.27 -0.7747)
			(end -1.27 -3.81)
			(stroke
				(width 0.1524)
				(type default)
			)
			(layer "F.SilkS")
		)
		(fp_line
			(start -1.27 3.81)
			(end -1.27 0.7747)
			(stroke
				(width 0.1524)
				(type default)
			)
			(layer "F.SilkS")
		)
		(fp_line
			(start 1.27 -3.81)
			(end 1.27 -3.3147)
			(stroke
				(width 0.1524)
				(type default)
			)
			(layer "F.SilkS")
		)
		(fp_line
			(start 1.27 -1.7653)
			(end 1.27 1.7653)
			(stroke
				(width 0.1524)
				(type default)
			)
			(layer "F.SilkS")
		)
		(fp_line
			(start 1.27 3.3147)
			(end 1.27 3.81)
			(stroke
				(width 0.1524)
				(type default)
			)
			(layer "F.SilkS")
		)
		(fp_line
			(start 1.27 3.81)
			(end -1.27 3.81)
			(stroke
				(width 0.1524)
				(type default)
			)
			(layer "F.SilkS")
		)
		(fp_poly
			(pts
				(xy 4.3942 -3.048) (xy 4.3942 -2.032) (xy 3.3782 -2.54)
			)
			(stroke
				(width 0)
				(type default)
			)
			(fill yes)
			(layer "F.SilkS")
		)
		(fp_line
			(start -1.27 -3.81)
			(end -1.27 3.81)
			(stroke
				(width 0.1)
				(type default)
			)
			(layer "F.Fab")
		)
		(fp_line
			(start -1.27 3.81)
			(end 1.27 3.81)
			(stroke
				(width 0.1)
				(type default)
			)
			(layer "F.Fab")
		)
		(fp_line
			(start 1.27 -3.81)
			(end -1.27 -3.81)
			(stroke
				(width 0.1)
				(type default)
			)
			(layer "F.Fab")
		)
		(fp_line
			(start 1.27 3.81)
			(end 1.27 -3.81)
			(stroke
				(width 0.1)
				(type default)
			)
			(layer "F.Fab")
		)
		(fp_poly
			(pts
				(xy 4.3942 -3.048) (xy 4.3942 -2.032) (xy 3.3782 -2.54)
			)
			(stroke
				(width 0)
				(type default)
			)
			(fill yes)
			(layer "F.Fab")
		)
		(fp_text user "3"
			(at 3.921252 2.54 90)
			(unlocked yes)
			(layer "F.SilkS")
			(effects
				(font
					(size 0.7874 0.5842)
					(thickness 0.1524)
				)
			)
		)
		(fp_text user "3"
			(at 3.921252 2.54 90)
			(unlocked yes)
			(layer "F.Fab")
			(effects
				(font
					(size 0.7874 0.5842)
					(thickness 0.1524)
				)
			)
		)
		(pad "1" smd rect
			(at 1.459992 -2.54 90)
			(size 1.27 3.429)
			(layers "F.Cu" "F.Mask" "F.Paste")
			(net "SMB_PJP1_SDA")
		)
		(pad "2" smd rect
			(at -1.459992 0 90)
			(size 1.27 3.429)
			(layers "F.Cu" "F.Mask" "F.Paste")
			(net "SMB_PJP1_SCL")
		)
		(pad "3" smd rect
			(at 1.459992 2.54 90)
			(size 1.27 3.429)
			(layers "F.Cu" "F.Mask" "F.Paste")
			(net "GND")
		)
	)
	(footprint ""
		(layer "F.Cu")
		(at 363.842808 -162.003994 -90)
		(property "Reference" "C981"
			(at 0 0 270)
			(layer "F.SilkS")
			(hide yes)
			(effects
				(font
					(size 1.27 1.27)
				)
			)
		)
		(property "Value" ""
			(at 0 0 270)
			(layer "F.Fab")
			(effects
				(font
					(size 1.27 1.27)
				)
			)
		)
		(duplicate_pad_numbers_are_jumpers no)
		(fp_line
			(start -0.7874 0.4064)
			(end -0.7874 -0.4064)
			(stroke
				(width 0.1524)
				(type default)
			)
			(layer "F.SilkS")
		)
		(fp_line
			(start 0.7874 0.4064)
			(end -0.7874 0.4064)
			(stroke
				(width 0.1524)
				(type default)
			)
			(layer "F.SilkS")
		)
		(fp_line
			(start -0.7874 -0.4064)
			(end 0.7874 -0.4064)
			(stroke
				(width 0.1524)
				(type default)
			)
			(layer "F.SilkS")
		)
		(fp_line
			(start 0.7874 -0.4064)
			(end 0.7874 0.4064)
			(stroke
				(width 0.1524)
				(type default)
			)
			(layer "F.SilkS")
		)
		(fp_line
			(start -0.67945 0.3048)
			(end -0.67945 -0.305054)
			(stroke
				(width 0.1)
				(type default)
			)
			(layer "F.Fab")
		)
		(fp_line
			(start -0.12065 0.3048)
			(end -0.67945 0.3048)
			(stroke
				(width 0.1)
				(type default)
			)
			(layer "F.Fab")
		)
		(fp_line
			(start 0.120396 0.3048)
			(end 0.120396 0.2794)
			(stroke
				(width 0.1)
				(type default)
			)
			(layer "F.Fab")
		)
		(fp_line
			(start 0.67945 0.3048)
			(end 0.120396 0.3048)
			(stroke
				(width 0.1)
				(type default)
			)
			(layer "F.Fab")
		)
		(fp_line
			(start -0.12065 0.2794)
			(end -0.12065 0.3048)
			(stroke
				(width 0.1)
				(type default)
			)
			(layer "F.Fab")
		)
		(fp_line
			(start 0.120396 0.2794)
			(end -0.12065 0.2794)
			(stroke
				(width 0.1)
				(type default)
			)
			(layer "F.Fab")
		)
		(fp_line
			(start -0.12065 -0.2794)
			(end 0.12065 -0.2794)
			(stroke
				(width 0.1)
				(type default)
			)
			(layer "F.Fab")
		)
		(fp_line
			(start 0.12065 -0.2794)
			(end 0.12065 -0.3048)
			(stroke
				(width 0.1)
				(type default)
			)
			(layer "F.Fab")
		)
		(fp_line
			(start 0.12065 -0.3048)
			(end 0.67945 -0.3048)
			(stroke
				(width 0.1)
				(type default)
			)
			(layer "F.Fab")
		)
		(fp_line
			(start 0.67945 -0.3048)
			(end 0.67945 0.3048)
			(stroke
				(width 0.1)
				(type default)
			)
			(layer "F.Fab")
		)
		(fp_line
			(start -0.67945 -0.305054)
			(end -0.12065 -0.305054)
			(stroke
				(width 0.1)
				(type default)
			)
			(layer "F.Fab")
		)
		(fp_line
			(start -0.12065 -0.305054)
			(end -0.12065 -0.2794)
			(stroke
				(width 0.1)
				(type default)
			)
			(layer "F.Fab")
		)
		(pad "1" smd circle
			(at -0.40005 0 270)
			(size 0 0)
			(layers "F.Cu" "F.Mask" "F.Paste")
			(net "GND")
		)
		(pad "2" smd circle
			(at 0.40005 0 270)
			(size 0 0)
			(layers "F.Cu" "F.Mask" "F.Paste")
			(net "P12V_NIC6_CO_EN")
		)
	)
	(footprint ""
		(layer "F.Cu")
		(at 36.638484 -112.809782)
		(property "Reference" "C50"
			(at 0 0 0)
			(layer "F.SilkS")
			(hide yes)
			(effects
				(font
					(size 1.27 1.27)
				)
			)
		)
		(property "Value" ""
			(at 0 0 0)
			(layer "F.Fab")
			(effects
				(font
					(size 1.27 1.27)
				)
			)
		)
		(duplicate_pad_numbers_are_jumpers no)
		(fp_line
			(start -0.299974 -0.150114)
			(end 0.299974 -0.150114)
			(stroke
				(width 0.1)
				(type default)
			)
			(layer "F.Fab")
		)
		(fp_line
			(start -0.299974 0.150114)
			(end -0.299974 -0.150114)
			(stroke
				(width 0.1)
				(type default)
			)
			(layer "F.Fab")
		)
		(fp_line
			(start 0.299974 -0.150114)
			(end 0.299974 0.150114)
			(stroke
				(width 0.1)
				(type default)
			)
			(layer "F.Fab")
		)
		(fp_line
			(start 0.299974 0.150114)
			(end -0.299974 0.150114)
			(stroke
				(width 0.1)
				(type default)
			)
			(layer "F.Fab")
		)
		(pad "1" smd rect
			(at -0.2667 0)
			(size 0.3048 0.381)
			(layers "F.Cu" "F.Mask" "F.Paste")
			(net "P5E_PEX0_STN1_TX_DP<23>")
		)
		(pad "2" smd rect
			(at 0.2667 0)
			(size 0.3048 0.381)
			(layers "F.Cu" "F.Mask" "F.Paste")
			(net "P5E_PEX0_STN1_TX_C_DP<23>")
		)
	)
	(footprint ""
		(layer "F.Cu")
		(at 257.558286 -250.070874 -90)
		(property "Reference" "R1343"
			(at 0 0 270)
			(layer "F.SilkS")
			(hide yes)
			(effects
				(font
					(size 1.27 1.27)
				)
			)
		)
		(property "Value" ""
			(at 0 0 270)
			(layer "F.Fab")
			(effects
				(font
					(size 1.27 1.27)
				)
			)
		)
		(duplicate_pad_numbers_are_jumpers no)
		(fp_line
			(start -0.7874 0.4064)
			(end -0.7874 -0.4064)
			(stroke
				(width 0.1524)
				(type default)
			)
			(layer "F.SilkS")
		)
		(fp_line
			(start 0.7874 0.4064)
			(end -0.7874 0.4064)
			(stroke
				(width 0.1524)
				(type default)
			)
			(layer "F.SilkS")
		)
		(fp_line
			(start -0.7874 -0.4064)
			(end 0.7874 -0.4064)
			(stroke
				(width 0.1524)
				(type default)
			)
			(layer "F.SilkS")
		)
		(fp_line
			(start 0.7874 -0.4064)
			(end 0.7874 0.4064)
			(stroke
				(width 0.1524)
				(type default)
			)
			(layer "F.SilkS")
		)
		(fp_line
			(start -0.67945 0.3048)
			(end -0.67945 -0.305054)
			(stroke
				(width 0.1)
				(type default)
			)
			(layer "F.Fab")
		)
		(fp_line
			(start -0.12065 0.3048)
			(end -0.67945 0.3048)
			(stroke
				(width 0.1)
				(type default)
			)
			(layer "F.Fab")
		)
		(fp_line
			(start 0.120396 0.3048)
			(end 0.120396 0.2794)
			(stroke
				(width 0.1)
				(type default)
			)
			(layer "F.Fab")
		)
		(fp_line
			(start 0.67945 0.3048)
			(end 0.120396 0.3048)
			(stroke
				(width 0.1)
				(type default)
			)
			(layer "F.Fab")
		)
		(fp_line
			(start -0.12065 0.2794)
			(end -0.12065 0.3048)
			(stroke
				(width 0.1)
				(type default)
			)
			(layer "F.Fab")
		)
		(fp_line
			(start 0.120396 0.2794)
			(end -0.12065 0.2794)
			(stroke
				(width 0.1)
				(type default)
			)
			(layer "F.Fab")
		)
		(fp_line
			(start -0.12065 -0.2794)
			(end 0.12065 -0.2794)
			(stroke
				(width 0.1)
				(type default)
			)
			(layer "F.Fab")
		)
		(fp_line
			(start 0.12065 -0.2794)
			(end 0.12065 -0.3048)
			(stroke
				(width 0.1)
				(type default)
			)
			(layer "F.Fab")
		)
		(fp_line
			(start 0.12065 -0.3048)
			(end 0.67945 -0.3048)
			(stroke
				(width 0.1)
				(type default)
			)
			(layer "F.Fab")
		)
		(fp_line
			(start 0.67945 -0.3048)
			(end 0.67945 0.3048)
			(stroke
				(width 0.1)
				(type default)
			)
			(layer "F.Fab")
		)
		(fp_line
			(start -0.67945 -0.305054)
			(end -0.12065 -0.305054)
			(stroke
				(width 0.1)
				(type default)
			)
			(layer "F.Fab")
		)
		(fp_line
			(start -0.12065 -0.305054)
			(end -0.12065 -0.2794)
			(stroke
				(width 0.1)
				(type default)
			)
			(layer "F.Fab")
		)
		(pad "1" smd circle
			(at -0.40005 0 270)
			(size 0 0)
			(layers "F.Cu" "F.Mask" "F.Paste")
			(net "PEX2_MODE_SEL7")
		)
		(pad "2" smd circle
			(at 0.40005 0 270)
			(size 0 0)
			(layers "F.Cu" "F.Mask" "F.Paste")
			(net "P1V8_PEX")
		)
	)
	(footprint ""
		(layer "F.Cu")
		(at 17.792446 -31.825184 180)
		(property "Reference" "C68"
			(at 0 0 180)
			(layer "F.SilkS")
			(hide yes)
			(effects
				(font
					(size 1.27 1.27)
				)
			)
		)
		(property "Value" ""
			(at 0 0 180)
			(layer "F.Fab")
			(effects
				(font
					(size 1.27 1.27)
				)
			)
		)
		(duplicate_pad_numbers_are_jumpers no)
		(fp_line
			(start 0.299974 0.150114)
			(end -0.299974 0.150114)
			(stroke
				(width 0.1)
				(type default)
			)
			(layer "F.Fab")
		)
		(fp_line
			(start 0.299974 -0.150114)
			(end 0.299974 0.150114)
			(stroke
				(width 0.1)
				(type default)
			)
			(layer "F.Fab")
		)
		(fp_line
			(start -0.299974 0.150114)
			(end -0.299974 -0.150114)
			(stroke
				(width 0.1)
				(type default)
			)
			(layer "F.Fab")
		)
		(fp_line
			(start -0.299974 -0.150114)
			(end 0.299974 -0.150114)
			(stroke
				(width 0.1)
				(type default)
			)
			(layer "F.Fab")
		)
		(pad "1" smd rect
			(at -0.2667 0 180)
			(size 0.3048 0.381)
			(layers "F.Cu" "F.Mask" "F.Paste")
			(net "P5E_PEX0_STN2_TX_DN<46>")
		)
		(pad "2" smd rect
			(at 0.2667 0 180)
			(size 0.3048 0.381)
			(layers "F.Cu" "F.Mask" "F.Paste")
			(net "P5E_PEX0_STN2_TX_C_DN<46>")
		)
	)
	(footprint ""
		(layer "F.Cu")
		(at 148.511514 -290.044632 -90)
		(property "Reference" "R4572"
			(at 0 0 270)
			(layer "F.SilkS")
			(hide yes)
			(effects
				(font
					(size 1.27 1.27)
				)
			)
		)
		(property "Value" ""
			(at 0 0 270)
			(layer "F.Fab")
			(effects
				(font
					(size 1.27 1.27)
				)
			)
		)
		(duplicate_pad_numbers_are_jumpers no)
		(fp_line
			(start -0.7874 0.4064)
			(end -0.7874 -0.4064)
			(stroke
				(width 0.1524)
				(type default)
			)
			(layer "F.SilkS")
		)
		(fp_line
			(start 0.7874 0.4064)
			(end -0.7874 0.4064)
			(stroke
				(width 0.1524)
				(type default)
			)
			(layer "F.SilkS")
		)
		(fp_line
			(start -0.7874 -0.4064)
			(end 0.7874 -0.4064)
			(stroke
				(width 0.1524)
				(type default)
			)
			(layer "F.SilkS")
		)
		(fp_line
			(start 0.7874 -0.4064)
			(end 0.7874 0.4064)
			(stroke
				(width 0.1524)
				(type default)
			)
			(layer "F.SilkS")
		)
		(fp_line
			(start -0.67945 0.3048)
			(end -0.67945 -0.305054)
			(stroke
				(width 0.1)
				(type default)
			)
			(layer "F.Fab")
		)
		(fp_line
			(start -0.12065 0.3048)
			(end -0.67945 0.3048)
			(stroke
				(width 0.1)
				(type default)
			)
			(layer "F.Fab")
		)
		(fp_line
			(start 0.120396 0.3048)
			(end 0.120396 0.2794)
			(stroke
				(width 0.1)
				(type default)
			)
			(layer "F.Fab")
		)
		(fp_line
			(start 0.67945 0.3048)
			(end 0.120396 0.3048)
			(stroke
				(width 0.1)
				(type default)
			)
			(layer "F.Fab")
		)
		(fp_line
			(start -0.12065 0.2794)
			(end -0.12065 0.3048)
			(stroke
				(width 0.1)
				(type default)
			)
			(layer "F.Fab")
		)
		(fp_line
			(start 0.120396 0.2794)
			(end -0.12065 0.2794)
			(stroke
				(width 0.1)
				(type default)
			)
			(layer "F.Fab")
		)
		(fp_line
			(start -0.12065 -0.2794)
			(end 0.12065 -0.2794)
			(stroke
				(width 0.1)
				(type default)
			)
			(layer "F.Fab")
		)
		(fp_line
			(start 0.12065 -0.2794)
			(end 0.12065 -0.3048)
			(stroke
				(width 0.1)
				(type default)
			)
			(layer "F.Fab")
		)
		(fp_line
			(start 0.12065 -0.3048)
			(end 0.67945 -0.3048)
			(stroke
				(width 0.1)
				(type default)
			)
			(layer "F.Fab")
		)
		(fp_line
			(start 0.67945 -0.3048)
			(end 0.67945 0.3048)
			(stroke
				(width 0.1)
				(type default)
			)
			(layer "F.Fab")
		)
		(fp_line
			(start -0.67945 -0.305054)
			(end -0.12065 -0.305054)
			(stroke
				(width 0.1)
				(type default)
			)
			(layer "F.Fab")
		)
		(fp_line
			(start -0.12065 -0.305054)
			(end -0.12065 -0.2794)
			(stroke
				(width 0.1)
				(type default)
			)
			(layer "F.Fab")
		)
		(pad "1" smd circle
			(at -0.40005 0 270)
			(size 0 0)
			(layers "F.Cu" "F.Mask" "F.Paste")
			(net "PCEPLL4_VDDA18_PEX1")
		)
		(pad "2" smd circle
			(at 0.40005 0 270)
			(size 0 0)
			(layers "F.Cu" "F.Mask" "F.Paste")
			(net "PCEPLL4_VDDA18_PEX1_R")
		)
	)
	(footprint ""
		(layer "F.Cu")
		(at 336.042 -141.859)
		(property "Reference" "R4796"
			(at 0 0 0)
			(layer "F.SilkS")
			(hide yes)
			(effects
				(font
					(size 1.27 1.27)
				)
			)
		)
		(property "Value" ""
			(at 0 0 0)
			(layer "F.Fab")
			(effects
				(font
					(size 1.27 1.27)
				)
			)
		)
		(duplicate_pad_numbers_are_jumpers no)
		(fp_line
			(start -0.7874 -0.4064)
			(end 0.7874 -0.4064)
			(stroke
				(width 0.1524)
				(type default)
			)
			(layer "F.SilkS")
		)
		(fp_line
			(start -0.7874 0.4064)
			(end -0.7874 -0.4064)
			(stroke
				(width 0.1524)
				(type default)
			)
			(layer "F.SilkS")
		)
		(fp_line
			(start 0.7874 -0.4064)
			(end 0.7874 0.4064)
			(stroke
				(width 0.1524)
				(type default)
			)
			(layer "F.SilkS")
		)
		(fp_line
			(start 0.7874 0.4064)
			(end -0.7874 0.4064)
			(stroke
				(width 0.1524)
				(type default)
			)
			(layer "F.SilkS")
		)
		(fp_line
			(start -0.67945 -0.305054)
			(end -0.12065 -0.305054)
			(stroke
				(width 0.1)
				(type default)
			)
			(layer "F.Fab")
		)
		(fp_line
			(start -0.67945 0.3048)
			(end -0.67945 -0.305054)
			(stroke
				(width 0.1)
				(type default)
			)
			(layer "F.Fab")
		)
		(fp_line
			(start -0.12065 -0.305054)
			(end -0.12065 -0.2794)
			(stroke
				(width 0.1)
				(type default)
			)
			(layer "F.Fab")
		)
		(fp_line
			(start -0.12065 -0.2794)
			(end 0.12065 -0.2794)
			(stroke
				(width 0.1)
				(type default)
			)
			(layer "F.Fab")
		)
		(fp_line
			(start -0.12065 0.2794)
			(end -0.12065 0.3048)
			(stroke
				(width 0.1)
				(type default)
			)
			(layer "F.Fab")
		)
		(fp_line
			(start -0.12065 0.3048)
			(end -0.67945 0.3048)
			(stroke
				(width 0.1)
				(type default)
			)
			(layer "F.Fab")
		)
		(fp_line
			(start 0.120396 0.2794)
			(end -0.12065 0.2794)
			(stroke
				(width 0.1)
				(type default)
			)
			(layer "F.Fab")
		)
		(fp_line
			(start 0.120396 0.3048)
			(end 0.120396 0.2794)
			(stroke
				(width 0.1)
				(type default)
			)
			(layer "F.Fab")
		)
		(fp_line
			(start 0.12065 -0.3048)
			(end 0.67945 -0.3048)
			(stroke
				(width 0.1)
				(type default)
			)
			(layer "F.Fab")
		)
		(fp_line
			(start 0.12065 -0.2794)
			(end 0.12065 -0.3048)
			(stroke
				(width 0.1)
				(type default)
			)
			(layer "F.Fab")
		)
		(fp_line
			(start 0.67945 -0.3048)
			(end 0.67945 0.3048)
			(stroke
				(width 0.1)
				(type default)
			)
			(layer "F.Fab")
		)
		(fp_line
			(start 0.67945 0.3048)
			(end 0.120396 0.3048)
			(stroke
				(width 0.1)
				(type default)
			)
			(layer "F.Fab")
		)
		(pad "1" smd circle
			(at -0.40005 0)
			(size 0 0)
			(layers "F.Cu" "F.Mask" "F.Paste")
			(net "P3V3_AUX")
		)
		(pad "2" smd circle
			(at 0.40005 0)
			(size 0 0)
			(layers "F.Cu" "F.Mask" "F.Paste")
			(net "RST_PEX_SSD15_PERST_R_N")
		)
	)
	(footprint ""
		(layer "F.Cu")
		(at 136.275064 -48.753014 180)
		(property "Reference" "C315"
			(at 0 0 180)
			(layer "F.SilkS")
			(hide yes)
			(effects
				(font
					(size 1.27 1.27)
				)
			)
		)
		(property "Value" ""
			(at 0 0 180)
			(layer "F.Fab")
			(effects
				(font
					(size 1.27 1.27)
				)
			)
		)
		(duplicate_pad_numbers_are_jumpers no)
		(fp_line
			(start 0.7874 0.4064)
			(end -0.7874 0.4064)
			(stroke
				(width 0.1524)
				(type default)
			)
			(layer "F.SilkS")
		)
		(fp_line
			(start 0.7874 -0.4064)
			(end 0.7874 0.4064)
			(stroke
				(width 0.1524)
				(type default)
			)
			(layer "F.SilkS")
		)
		(fp_line
			(start -0.7874 0.4064)
			(end -0.7874 -0.4064)
			(stroke
				(width 0.1524)
				(type default)
			)
			(layer "F.SilkS")
		)
		(fp_line
			(start -0.7874 -0.4064)
			(end 0.7874 -0.4064)
			(stroke
				(width 0.1524)
				(type default)
			)
			(layer "F.SilkS")
		)
		(fp_line
			(start 0.67945 0.3048)
			(end 0.120396 0.3048)
			(stroke
				(width 0.1)
				(type default)
			)
			(layer "F.Fab")
		)
		(fp_line
			(start 0.67945 -0.3048)
			(end 0.67945 0.3048)
			(stroke
				(width 0.1)
				(type default)
			)
			(layer "F.Fab")
		)
		(fp_line
			(start 0.12065 -0.2794)
			(end 0.12065 -0.3048)
			(stroke
				(width 0.1)
				(type default)
			)
			(layer "F.Fab")
		)
		(fp_line
			(start 0.12065 -0.3048)
			(end 0.67945 -0.3048)
			(stroke
				(width 0.1)
				(type default)
			)
			(layer "F.Fab")
		)
		(fp_line
			(start 0.120396 0.3048)
			(end 0.120396 0.2794)
			(stroke
				(width 0.1)
				(type default)
			)
			(layer "F.Fab")
		)
		(fp_line
			(start 0.120396 0.2794)
			(end -0.12065 0.2794)
			(stroke
				(width 0.1)
				(type default)
			)
			(layer "F.Fab")
		)
		(fp_line
			(start -0.12065 0.3048)
			(end -0.67945 0.3048)
			(stroke
				(width 0.1)
				(type default)
			)
			(layer "F.Fab")
		)
		(fp_line
			(start -0.12065 0.2794)
			(end -0.12065 0.3048)
			(stroke
				(width 0.1)
				(type default)
			)
			(layer "F.Fab")
		)
		(fp_line
			(start -0.12065 -0.2794)
			(end 0.12065 -0.2794)
			(stroke
				(width 0.1)
				(type default)
			)
			(layer "F.Fab")
		)
		(fp_line
			(start -0.12065 -0.305054)
			(end -0.12065 -0.2794)
			(stroke
				(width 0.1)
				(type default)
			)
			(layer "F.Fab")
		)
		(fp_line
			(start -0.67945 0.3048)
			(end -0.67945 -0.305054)
			(stroke
				(width 0.1)
				(type default)
			)
			(layer "F.Fab")
		)
		(fp_line
			(start -0.67945 -0.305054)
			(end -0.12065 -0.305054)
			(stroke
				(width 0.1)
				(type default)
			)
			(layer "F.Fab")
		)
		(pad "1" smd circle
			(at -0.40005 0 180)
			(size 0 0)
			(layers "F.Cu" "F.Mask" "F.Paste")
			(net "P3V3_AUX")
		)
		(pad "2" smd circle
			(at 0.40005 0 180)
			(size 0 0)
			(layers "F.Cu" "F.Mask" "F.Paste")
			(net "GND")
		)
	)
	(footprint ""
		(layer "F.Cu")
		(at 314.119768 8.109712 180)
		(property "Reference" "DE13T_1"
			(at 2.817368 3.079242 0)
			(unlocked yes)
			(layer "F.SilkS")
			(effects
				(font
					(size 0.7874 0.5842)
					(thickness 0.1524)
				)
				(justify left)
			)
		)
		(property "Value" ""
			(at 0 0 180)
			(layer "F.Fab")
			(effects
				(font
					(size 1.27 1.27)
				)
			)
		)
		(duplicate_pad_numbers_are_jumpers no)
		(fp_line
			(start 1.2192 2.1082)
			(end -1.2192 2.1082)
			(stroke
				(width 0.1524)
				(type default)
			)
			(layer "F.SilkS")
		)
		(fp_line
			(start 1.2192 -2.1082)
			(end 1.2192 2.1082)
			(stroke
				(width 0.1524)
				(type default)
			)
			(layer "F.SilkS")
		)
		(fp_line
			(start -1.2192 2.1082)
			(end -1.2192 -2.1082)
			(stroke
				(width 0.1524)
				(type default)
			)
			(layer "F.SilkS")
		)
		(fp_line
			(start -1.2192 -2.1082)
			(end 1.2192 -2.1082)
			(stroke
				(width 0.1524)
				(type default)
			)
			(layer "F.SilkS")
		)
		(pad "" np_thru_hole circle
			(at -2.8829 -1.27 90)
			(size 1.0414 1.0414)
			(drill 1.0414)
			(layers "*.Cu" "*.Mask")
			(clearance 0.381)
			(thermal_gap 0.381)
		)
		(pad "" np_thru_hole circle
			(at -2.8829 1.27 90)
			(size 1.0414 1.0414)
			(drill 1.0414)
			(layers "*.Cu" "*.Mask")
			(clearance 0.381)
			(thermal_gap 0.381)
		)
		(pad "" np_thru_hole circle
			(at 3.4671 -1.27 90)
			(size 1.0414 1.0414)
			(drill 1.0414)
			(layers "*.Cu" "*.Mask")
			(clearance 0.381)
			(thermal_gap 0.381)
		)
		(pad "" np_thru_hole circle
			(at 3.4671 1.27 90)
			(size 1.0414 1.0414)
			(drill 1.0414)
			(layers "*.Cu" "*.Mask")
			(clearance 0.381)
			(thermal_gap 0.381)
		)
		(pad "1" smd rect
			(at 0.8255 -0.249936 90)
			(size 0.3048 0.508)
			(layers "F.Cu" "F.Mask" "F.Paste")
			(net "85_10INCH_IN1_DP")
		)
		(pad "2" smd rect
			(at 0.8255 0.249936 90)
			(size 0.3048 0.508)
			(layers "F.Cu" "F.Mask" "F.Paste")
			(net "85_10INCH_IN1_DN")
		)
		(pad "3" smd circle
			(at 0 0 180)
			(size 0 0)
			(layers "F.Cu" "F.Mask" "F.Paste")
			(net "COUPON_GND2")
		)
		(zone
			(layer "F.Cu")
			(hatch none 0.5)
			(connect_pads
				(clearance 0)
			)
			(min_thickness 0.25)
			(keepout
				(tracks not_allowed)
				(vias allowed)
				(pads allowed)
				(copperpour not_allowed)
				(footprints allowed)
			)
			(placement
				(enabled no)
				(sheetname "")
			)
			(fill
				(thermal_gap 0.5)
				(thermal_bridge_width 0.5)
				(island_removal_mode 0)
			)
			(polygon
				(pts
					(xy 313.002168 8.658352) (xy 313.002168 8.562848) (xy 313.599068 8.562848) (xy 313.599068 8.156448)
					(xy 313.002168 8.156448) (xy 313.002168 8.062976) (xy 313.599068 8.062976) (xy 313.599068 7.656576)
					(xy 313.002168 7.656576) (xy 313.002168 7.561072) (xy 313.700668 7.561072) (xy 313.700668 8.658352)
				)
			)
		)
		(zone
			(layers "F.Cu" "B.Cu" "In1.Cu" "In2.Cu" "In3.Cu" "In4.Cu" "In5.Cu" "In6.Cu"
				"In7.Cu" "In8.Cu" "In9.Cu" "In10.Cu" "In11.Cu" "In12.Cu" "In13.Cu" "In14.Cu"
				"In15.Cu" "In16.Cu"
			)
			(hatch none 0.5)
			(connect_pads
				(clearance 0)
			)
			(min_thickness 0.25)
			(keepout
				(tracks not_allowed)
				(vias allowed)
				(pads allowed)
				(copperpour not_allowed)
				(footprints allowed)
			)
			(placement
				(enabled no)
				(sheetname "")
			)
			(fill
				(thermal_gap 0.5)
				(thermal_bridge_width 0.5)
				(island_removal_mode 0)
			)
			(polygon
				(pts
					(arc
						(start 311.579768 6.839712)
						(mid 309.725568 6.839712)
						(end 311.579768 6.839712)
					)
				)
			)
		)
		(zone
			(layers "F.Cu" "B.Cu" "In1.Cu" "In2.Cu" "In3.Cu" "In4.Cu" "In5.Cu" "In6.Cu"
				"In7.Cu" "In8.Cu" "In9.Cu" "In10.Cu" "In11.Cu" "In12.Cu" "In13.Cu" "In14.Cu"
				"In15.Cu" "In16.Cu"
			)
			(hatch none 0.5)
			(connect_pads
				(clearance 0)
			)
			(min_thickness 0.25)
			(keepout
				(tracks not_allowed)
				(vias allowed)
				(pads allowed)
				(copperpour not_allowed)
				(footprints allowed)
			)
			(placement
				(enabled no)
				(sheetname "")
			)
			(fill
				(thermal_gap 0.5)
				(thermal_bridge_width 0.5)
				(island_removal_mode 0)
			)
			(polygon
				(pts
					(arc
						(start 311.579768 9.379712)
						(mid 309.725568 9.379712)
						(end 311.579768 9.379712)
					)
				)
			)
		)
		(zone
			(layers "F.Cu" "B.Cu" "In1.Cu" "In2.Cu" "In3.Cu" "In4.Cu" "In5.Cu" "In6.Cu"
				"In7.Cu" "In8.Cu" "In9.Cu" "In10.Cu" "In11.Cu" "In12.Cu" "In13.Cu" "In14.Cu"
				"In15.Cu" "In16.Cu"
			)
			(hatch none 0.5)
			(connect_pads
				(clearance 0)
			)
			(min_thickness 0.25)
			(keepout
				(tracks not_allowed)
				(vias allowed)
				(pads allowed)
				(copperpour not_allowed)
				(footprints allowed)
			)
			(placement
				(enabled no)
				(sheetname "")
			)
			(fill
				(thermal_gap 0.5)
				(thermal_bridge_width 0.5)
				(island_removal_mode 0)
			)
			(polygon
				(pts
					(arc
						(start 317.929768 6.839712)
						(mid 316.075568 6.839712)
						(end 317.929768 6.839712)
					)
				)
			)
		)
		(zone
			(layers "F.Cu" "B.Cu" "In1.Cu" "In2.Cu" "In3.Cu" "In4.Cu" "In5.Cu" "In6.Cu"
				"In7.Cu" "In8.Cu" "In9.Cu" "In10.Cu" "In11.Cu" "In12.Cu" "In13.Cu" "In14.Cu"
				"In15.Cu" "In16.Cu"
			)
			(hatch none 0.5)
			(connect_pads
				(clearance 0)
			)
			(min_thickness 0.25)
			(keepout
				(tracks not_allowed)
				(vias allowed)
				(pads allowed)
				(copperpour not_allowed)
				(footprints allowed)
			)
			(placement
				(enabled no)
				(sheetname "")
			)
			(fill
				(thermal_gap 0.5)
				(thermal_bridge_width 0.5)
				(island_removal_mode 0)
			)
			(polygon
				(pts
					(arc
						(start 317.929768 9.379712)
						(mid 316.075568 9.379712)
						(end 317.929768 9.379712)
					)
				)
			)
		)
	)
	(footprint ""
		(layer "F.Cu")
		(at 185.89244 -28.225242 180)
		(property "Reference" "C299"
			(at 0 0 180)
			(layer "F.SilkS")
			(hide yes)
			(effects
				(font
					(size 1.27 1.27)
				)
			)
		)
		(property "Value" ""
			(at 0 0 180)
			(layer "F.Fab")
			(effects
				(font
					(size 1.27 1.27)
				)
			)
		)
		(duplicate_pad_numbers_are_jumpers no)
		(fp_line
			(start 0.299974 0.150114)
			(end -0.299974 0.150114)
			(stroke
				(width 0.1)
				(type default)
			)
			(layer "F.Fab")
		)
		(fp_line
			(start 0.299974 -0.150114)
			(end 0.299974 0.150114)
			(stroke
				(width 0.1)
				(type default)
			)
			(layer "F.Fab")
		)
		(fp_line
			(start -0.299974 0.150114)
			(end -0.299974 -0.150114)
			(stroke
				(width 0.1)
				(type default)
			)
			(layer "F.Fab")
		)
		(fp_line
			(start -0.299974 -0.150114)
			(end 0.299974 -0.150114)
			(stroke
				(width 0.1)
				(type default)
			)
			(layer "F.Fab")
		)
		(pad "1" smd rect
			(at -0.2667 0 180)
			(size 0.3048 0.381)
			(layers "F.Cu" "F.Mask" "F.Paste")
			(net "P5E_PEX1_STN2_TX_DN<36>")
		)
		(pad "2" smd rect
			(at 0.2667 0 180)
			(size 0.3048 0.381)
			(layers "F.Cu" "F.Mask" "F.Paste")
			(net "P5E_PEX1_STN2_TX_C_DN<36>")
		)
	)
	(footprint ""
		(layer "F.Cu")
		(at 355.854 -165.608 180)
		(property "Reference" "R4729"
			(at 0 0 180)
			(layer "F.SilkS")
			(hide yes)
			(effects
				(font
					(size 1.27 1.27)
				)
			)
		)
		(property "Value" ""
			(at 0 0 180)
			(layer "F.Fab")
			(effects
				(font
					(size 1.27 1.27)
				)
			)
		)
		(duplicate_pad_numbers_are_jumpers no)
		(fp_line
			(start 0.7874 0.4064)
			(end -0.7874 0.4064)
			(stroke
				(width 0.1524)
				(type default)
			)
			(layer "F.SilkS")
		)
		(fp_line
			(start 0.7874 -0.4064)
			(end 0.7874 0.4064)
			(stroke
				(width 0.1524)
				(type default)
			)
			(layer "F.SilkS")
		)
		(fp_line
			(start -0.7874 0.4064)
			(end -0.7874 -0.4064)
			(stroke
				(width 0.1524)
				(type default)
			)
			(layer "F.SilkS")
		)
		(fp_line
			(start -0.7874 -0.4064)
			(end 0.7874 -0.4064)
			(stroke
				(width 0.1524)
				(type default)
			)
			(layer "F.SilkS")
		)
		(fp_line
			(start 0.67945 0.3048)
			(end 0.120396 0.3048)
			(stroke
				(width 0.1)
				(type default)
			)
			(layer "F.Fab")
		)
		(fp_line
			(start 0.67945 -0.3048)
			(end 0.67945 0.3048)
			(stroke
				(width 0.1)
				(type default)
			)
			(layer "F.Fab")
		)
		(fp_line
			(start 0.12065 -0.2794)
			(end 0.12065 -0.3048)
			(stroke
				(width 0.1)
				(type default)
			)
			(layer "F.Fab")
		)
		(fp_line
			(start 0.12065 -0.3048)
			(end 0.67945 -0.3048)
			(stroke
				(width 0.1)
				(type default)
			)
			(layer "F.Fab")
		)
		(fp_line
			(start 0.120396 0.3048)
			(end 0.120396 0.2794)
			(stroke
				(width 0.1)
				(type default)
			)
			(layer "F.Fab")
		)
		(fp_line
			(start 0.120396 0.2794)
			(end -0.12065 0.2794)
			(stroke
				(width 0.1)
				(type default)
			)
			(layer "F.Fab")
		)
		(fp_line
			(start -0.12065 0.3048)
			(end -0.67945 0.3048)
			(stroke
				(width 0.1)
				(type default)
			)
			(layer "F.Fab")
		)
		(fp_line
			(start -0.12065 0.2794)
			(end -0.12065 0.3048)
			(stroke
				(width 0.1)
				(type default)
			)
			(layer "F.Fab")
		)
		(fp_line
			(start -0.12065 -0.2794)
			(end 0.12065 -0.2794)
			(stroke
				(width 0.1)
				(type default)
			)
			(layer "F.Fab")
		)
		(fp_line
			(start -0.12065 -0.305054)
			(end -0.12065 -0.2794)
			(stroke
				(width 0.1)
				(type default)
			)
			(layer "F.Fab")
		)
		(fp_line
			(start -0.67945 0.3048)
			(end -0.67945 -0.305054)
			(stroke
				(width 0.1)
				(type default)
			)
			(layer "F.Fab")
		)
		(fp_line
			(start -0.67945 -0.305054)
			(end -0.12065 -0.305054)
			(stroke
				(width 0.1)
				(type default)
			)
			(layer "F.Fab")
		)
		(pad "1" smd circle
			(at -0.40005 0 180)
			(size 0 0)
			(layers "F.Cu" "F.Mask" "F.Paste")
			(net "P3V3_AUX")
		)
		(pad "2" smd circle
			(at 0.40005 0 180)
			(size 0 0)
			(layers "F.Cu" "F.Mask" "F.Paste")
			(net "NIC5_PEX_PWR_EN_R")
		)
	)
	(footprint ""
		(layer "F.Cu")
		(at 394.787628 -25.342342 -90)
		(property "Reference" "R449"
			(at 0 0 270)
			(layer "F.SilkS")
			(hide yes)
			(effects
				(font
					(size 1.27 1.27)
				)
			)
		)
		(property "Value" ""
			(at 0 0 270)
			(layer "F.Fab")
			(effects
				(font
					(size 1.27 1.27)
				)
			)
		)
		(duplicate_pad_numbers_are_jumpers no)
		(fp_line
			(start -0.7874 0.4064)
			(end -0.7874 -0.4064)
			(stroke
				(width 0.1524)
				(type default)
			)
			(layer "F.SilkS")
		)
		(fp_line
			(start 0.7874 0.4064)
			(end -0.7874 0.4064)
			(stroke
				(width 0.1524)
				(type default)
			)
			(layer "F.SilkS")
		)
		(fp_line
			(start -0.7874 -0.4064)
			(end 0.7874 -0.4064)
			(stroke
				(width 0.1524)
				(type default)
			)
			(layer "F.SilkS")
		)
		(fp_line
			(start 0.7874 -0.4064)
			(end 0.7874 0.4064)
			(stroke
				(width 0.1524)
				(type default)
			)
			(layer "F.SilkS")
		)
		(fp_line
			(start -0.67945 0.3048)
			(end -0.67945 -0.305054)
			(stroke
				(width 0.1)
				(type default)
			)
			(layer "F.Fab")
		)
		(fp_line
			(start -0.12065 0.3048)
			(end -0.67945 0.3048)
			(stroke
				(width 0.1)
				(type default)
			)
			(layer "F.Fab")
		)
		(fp_line
			(start 0.120396 0.3048)
			(end 0.120396 0.2794)
			(stroke
				(width 0.1)
				(type default)
			)
			(layer "F.Fab")
		)
		(fp_line
			(start 0.67945 0.3048)
			(end 0.120396 0.3048)
			(stroke
				(width 0.1)
				(type default)
			)
			(layer "F.Fab")
		)
		(fp_line
			(start -0.12065 0.2794)
			(end -0.12065 0.3048)
			(stroke
				(width 0.1)
				(type default)
			)
			(layer "F.Fab")
		)
		(fp_line
			(start 0.120396 0.2794)
			(end -0.12065 0.2794)
			(stroke
				(width 0.1)
				(type default)
			)
			(layer "F.Fab")
		)
		(fp_line
			(start -0.12065 -0.2794)
			(end 0.12065 -0.2794)
			(stroke
				(width 0.1)
				(type default)
			)
			(layer "F.Fab")
		)
		(fp_line
			(start 0.12065 -0.2794)
			(end 0.12065 -0.3048)
			(stroke
				(width 0.1)
				(type default)
			)
			(layer "F.Fab")
		)
		(fp_line
			(start 0.12065 -0.3048)
			(end 0.67945 -0.3048)
			(stroke
				(width 0.1)
				(type default)
			)
			(layer "F.Fab")
		)
		(fp_line
			(start 0.67945 -0.3048)
			(end 0.67945 0.3048)
			(stroke
				(width 0.1)
				(type default)
			)
			(layer "F.Fab")
		)
		(fp_line
			(start -0.67945 -0.305054)
			(end -0.12065 -0.305054)
			(stroke
				(width 0.1)
				(type default)
			)
			(layer "F.Fab")
		)
		(fp_line
			(start -0.12065 -0.305054)
			(end -0.12065 -0.2794)
			(stroke
				(width 0.1)
				(type default)
			)
			(layer "F.Fab")
		)
		(pad "1" smd circle
			(at -0.40005 0 270)
			(size 0 0)
			(layers "F.Cu" "F.Mask" "F.Paste")
			(net "GND")
		)
		(pad "2" smd circle
			(at 0.40005 0 270)
			(size 0 0)
			(layers "F.Cu" "F.Mask" "F.Paste")
			(net "DUALPORT_N_SSD13")
		)
	)
	(footprint ""
		(layer "F.Cu")
		(at 356.071932 -24.807418)
		(property "Reference" "R446"
			(at 0 0 0)
			(layer "F.SilkS")
			(hide yes)
			(effects
				(font
					(size 1.27 1.27)
				)
			)
		)
		(property "Value" ""
			(at 0 0 0)
			(layer "F.Fab")
			(effects
				(font
					(size 1.27 1.27)
				)
			)
		)
		(duplicate_pad_numbers_are_jumpers no)
		(fp_line
			(start -0.7874 -0.4064)
			(end 0.7874 -0.4064)
			(stroke
				(width 0.1524)
				(type default)
			)
			(layer "F.SilkS")
		)
		(fp_line
			(start -0.7874 0.4064)
			(end -0.7874 -0.4064)
			(stroke
				(width 0.1524)
				(type default)
			)
			(layer "F.SilkS")
		)
		(fp_line
			(start 0.7874 -0.4064)
			(end 0.7874 0.4064)
			(stroke
				(width 0.1524)
				(type default)
			)
			(layer "F.SilkS")
		)
		(fp_line
			(start 0.7874 0.4064)
			(end -0.7874 0.4064)
			(stroke
				(width 0.1524)
				(type default)
			)
			(layer "F.SilkS")
		)
		(fp_line
			(start -0.67945 -0.305054)
			(end -0.12065 -0.305054)
			(stroke
				(width 0.1)
				(type default)
			)
			(layer "F.Fab")
		)
		(fp_line
			(start -0.67945 0.3048)
			(end -0.67945 -0.305054)
			(stroke
				(width 0.1)
				(type default)
			)
			(layer "F.Fab")
		)
		(fp_line
			(start -0.12065 -0.305054)
			(end -0.12065 -0.2794)
			(stroke
				(width 0.1)
				(type default)
			)
			(layer "F.Fab")
		)
		(fp_line
			(start -0.12065 -0.2794)
			(end 0.12065 -0.2794)
			(stroke
				(width 0.1)
				(type default)
			)
			(layer "F.Fab")
		)
		(fp_line
			(start -0.12065 0.2794)
			(end -0.12065 0.3048)
			(stroke
				(width 0.1)
				(type default)
			)
			(layer "F.Fab")
		)
		(fp_line
			(start -0.12065 0.3048)
			(end -0.67945 0.3048)
			(stroke
				(width 0.1)
				(type default)
			)
			(layer "F.Fab")
		)
		(fp_line
			(start 0.120396 0.2794)
			(end -0.12065 0.2794)
			(stroke
				(width 0.1)
				(type default)
			)
			(layer "F.Fab")
		)
		(fp_line
			(start 0.120396 0.3048)
			(end 0.120396 0.2794)
			(stroke
				(width 0.1)
				(type default)
			)
			(layer "F.Fab")
		)
		(fp_line
			(start 0.12065 -0.3048)
			(end 0.67945 -0.3048)
			(stroke
				(width 0.1)
				(type default)
			)
			(layer "F.Fab")
		)
		(fp_line
			(start 0.12065 -0.2794)
			(end 0.12065 -0.3048)
			(stroke
				(width 0.1)
				(type default)
			)
			(layer "F.Fab")
		)
		(fp_line
			(start 0.67945 -0.3048)
			(end 0.67945 0.3048)
			(stroke
				(width 0.1)
				(type default)
			)
			(layer "F.Fab")
		)
		(fp_line
			(start 0.67945 0.3048)
			(end 0.120396 0.3048)
			(stroke
				(width 0.1)
				(type default)
			)
			(layer "F.Fab")
		)
		(pad "1" smd circle
			(at -0.40005 0)
			(size 0 0)
			(layers "F.Cu" "F.Mask" "F.Paste")
			(net "P3V3_SSD12")
		)
		(pad "2" smd circle
			(at 0.40005 0)
			(size 0 0)
			(layers "F.Cu" "F.Mask" "F.Paste")
			(net "PU_CLKREQ12")
		)
	)
	(footprint ""
		(layer "F.Cu")
		(at 283.416502 -356.244906 90)
		(property "Reference" "C597"
			(at 0 0 90)
			(layer "F.SilkS")
			(hide yes)
			(effects
				(font
					(size 1.27 1.27)
				)
			)
		)
		(property "Value" ""
			(at 0 0 90)
			(layer "F.Fab")
			(effects
				(font
					(size 1.27 1.27)
				)
			)
		)
		(duplicate_pad_numbers_are_jumpers no)
		(fp_line
			(start 0.299974 -0.150114)
			(end 0.299974 0.150114)
			(stroke
				(width 0.1)
				(type default)
			)
			(layer "F.Fab")
		)
		(fp_line
			(start -0.299974 -0.150114)
			(end 0.299974 -0.150114)
			(stroke
				(width 0.1)
				(type default)
			)
			(layer "F.Fab")
		)
		(fp_line
			(start 0.299974 0.150114)
			(end -0.299974 0.150114)
			(stroke
				(width 0.1)
				(type default)
			)
			(layer "F.Fab")
		)
		(fp_line
			(start -0.299974 0.150114)
			(end -0.299974 -0.150114)
			(stroke
				(width 0.1)
				(type default)
			)
			(layer "F.Fab")
		)
		(pad "1" smd rect
			(at -0.2667 0 90)
			(size 0.3048 0.381)
			(layers "F.Cu" "F.Mask" "F.Paste")
			(net "P5E_PEX2_STN7_TX_DP<120>")
		)
		(pad "2" smd rect
			(at 0.2667 0 90)
			(size 0.3048 0.381)
			(layers "F.Cu" "F.Mask" "F.Paste")
			(net "P5E_PEX2_STN7_TX_C_DP<120>")
		)
	)
	(footprint ""
		(layer "F.Cu")
		(at 318.929512 -300.62043 90)
		(property "Reference" "R6394"
			(at 0 0 90)
			(layer "F.SilkS")
			(hide yes)
			(effects
				(font
					(size 1.27 1.27)
				)
			)
		)
		(property "Value" ""
			(at 0 0 90)
			(layer "F.Fab")
			(effects
				(font
					(size 1.27 1.27)
				)
			)
		)
		(duplicate_pad_numbers_are_jumpers no)
		(fp_line
			(start 0.7874 -0.4064)
			(end 0.7874 0.4064)
			(stroke
				(width 0.1524)
				(type default)
			)
			(layer "F.SilkS")
		)
		(fp_line
			(start -0.7874 -0.4064)
			(end 0.7874 -0.4064)
			(stroke
				(width 0.1524)
				(type default)
			)
			(layer "F.SilkS")
		)
		(fp_line
			(start 0.7874 0.4064)
			(end -0.7874 0.4064)
			(stroke
				(width 0.1524)
				(type default)
			)
			(layer "F.SilkS")
		)
		(fp_line
			(start -0.7874 0.4064)
			(end -0.7874 -0.4064)
			(stroke
				(width 0.1524)
				(type default)
			)
			(layer "F.SilkS")
		)
		(fp_line
			(start -0.12065 -0.305054)
			(end -0.12065 -0.2794)
			(stroke
				(width 0.1)
				(type default)
			)
			(layer "F.Fab")
		)
		(fp_line
			(start -0.67945 -0.305054)
			(end -0.12065 -0.305054)
			(stroke
				(width 0.1)
				(type default)
			)
			(layer "F.Fab")
		)
		(fp_line
			(start 0.67945 -0.3048)
			(end 0.67945 0.3048)
			(stroke
				(width 0.1)
				(type default)
			)
			(layer "F.Fab")
		)
		(fp_line
			(start 0.12065 -0.3048)
			(end 0.67945 -0.3048)
			(stroke
				(width 0.1)
				(type default)
			)
			(layer "F.Fab")
		)
		(fp_line
			(start 0.12065 -0.2794)
			(end 0.12065 -0.3048)
			(stroke
				(width 0.1)
				(type default)
			)
			(layer "F.Fab")
		)
		(fp_line
			(start -0.12065 -0.2794)
			(end 0.12065 -0.2794)
			(stroke
				(width 0.1)
				(type default)
			)
			(layer "F.Fab")
		)
		(fp_line
			(start 0.120396 0.2794)
			(end -0.12065 0.2794)
			(stroke
				(width 0.1)
				(type default)
			)
			(layer "F.Fab")
		)
		(fp_line
			(start -0.12065 0.2794)
			(end -0.12065 0.3048)
			(stroke
				(width 0.1)
				(type default)
			)
			(layer "F.Fab")
		)
		(fp_line
			(start 0.67945 0.3048)
			(end 0.120396 0.3048)
			(stroke
				(width 0.1)
				(type default)
			)
			(layer "F.Fab")
		)
		(fp_line
			(start 0.120396 0.3048)
			(end 0.120396 0.2794)
			(stroke
				(width 0.1)
				(type default)
			)
			(layer "F.Fab")
		)
		(fp_line
			(start -0.12065 0.3048)
			(end -0.67945 0.3048)
			(stroke
				(width 0.1)
				(type default)
			)
			(layer "F.Fab")
		)
		(fp_line
			(start -0.67945 0.3048)
			(end -0.67945 -0.305054)
			(stroke
				(width 0.1)
				(type default)
			)
			(layer "F.Fab")
		)
		(pad "1" smd circle
			(at -0.40005 0 90)
			(size 0 0)
			(layers "F.Cu" "F.Mask" "F.Paste")
			(net "RST_PEX2_S3_PERST_N")
		)
		(pad "2" smd circle
			(at 0.40005 0 90)
			(size 0 0)
			(layers "F.Cu" "F.Mask" "F.Paste")
			(net "RST_PEX2_S3_PERST_R_N")
		)
	)
	(footprint ""
		(layer "F.Cu")
		(at 280.790396 -414.88995 -90)
		(property "Reference" "R1815"
			(at 0 0 270)
			(layer "F.SilkS")
			(hide yes)
			(effects
				(font
					(size 1.27 1.27)
				)
			)
		)
		(property "Value" ""
			(at 0 0 270)
			(layer "F.Fab")
			(effects
				(font
					(size 1.27 1.27)
				)
			)
		)
		(duplicate_pad_numbers_are_jumpers no)
		(fp_line
			(start -0.7874 0.4064)
			(end -0.7874 -0.4064)
			(stroke
				(width 0.1524)
				(type default)
			)
			(layer "F.SilkS")
		)
		(fp_line
			(start 0.7874 0.4064)
			(end -0.7874 0.4064)
			(stroke
				(width 0.1524)
				(type default)
			)
			(layer "F.SilkS")
		)
		(fp_line
			(start -0.7874 -0.4064)
			(end 0.7874 -0.4064)
			(stroke
				(width 0.1524)
				(type default)
			)
			(layer "F.SilkS")
		)
		(fp_line
			(start 0.7874 -0.4064)
			(end 0.7874 0.4064)
			(stroke
				(width 0.1524)
				(type default)
			)
			(layer "F.SilkS")
		)
		(fp_line
			(start -0.67945 0.3048)
			(end -0.67945 -0.305054)
			(stroke
				(width 0.1)
				(type default)
			)
			(layer "F.Fab")
		)
		(fp_line
			(start -0.12065 0.3048)
			(end -0.67945 0.3048)
			(stroke
				(width 0.1)
				(type default)
			)
			(layer "F.Fab")
		)
		(fp_line
			(start 0.120396 0.3048)
			(end 0.120396 0.2794)
			(stroke
				(width 0.1)
				(type default)
			)
			(layer "F.Fab")
		)
		(fp_line
			(start 0.67945 0.3048)
			(end 0.120396 0.3048)
			(stroke
				(width 0.1)
				(type default)
			)
			(layer "F.Fab")
		)
		(fp_line
			(start -0.12065 0.2794)
			(end -0.12065 0.3048)
			(stroke
				(width 0.1)
				(type default)
			)
			(layer "F.Fab")
		)
		(fp_line
			(start 0.120396 0.2794)
			(end -0.12065 0.2794)
			(stroke
				(width 0.1)
				(type default)
			)
			(layer "F.Fab")
		)
		(fp_line
			(start -0.12065 -0.2794)
			(end 0.12065 -0.2794)
			(stroke
				(width 0.1)
				(type default)
			)
			(layer "F.Fab")
		)
		(fp_line
			(start 0.12065 -0.2794)
			(end 0.12065 -0.3048)
			(stroke
				(width 0.1)
				(type default)
			)
			(layer "F.Fab")
		)
		(fp_line
			(start 0.12065 -0.3048)
			(end 0.67945 -0.3048)
			(stroke
				(width 0.1)
				(type default)
			)
			(layer "F.Fab")
		)
		(fp_line
			(start 0.67945 -0.3048)
			(end 0.67945 0.3048)
			(stroke
				(width 0.1)
				(type default)
			)
			(layer "F.Fab")
		)
		(fp_line
			(start -0.67945 -0.305054)
			(end -0.12065 -0.305054)
			(stroke
				(width 0.1)
				(type default)
			)
			(layer "F.Fab")
		)
		(fp_line
			(start -0.12065 -0.305054)
			(end -0.12065 -0.2794)
			(stroke
				(width 0.1)
				(type default)
			)
			(layer "F.Fab")
		)
		(pad "1" smd circle
			(at -0.40005 0 270)
			(size 0 0)
			(layers "F.Cu" "F.Mask" "F.Paste")
			(net "MB_BIC_MON")
		)
		(pad "2" smd circle
			(at 0.40005 0 270)
			(size 0 0)
			(layers "F.Cu" "F.Mask" "F.Paste")
			(net "MB_BIC_R_MON")
		)
	)
	(footprint ""
		(layer "F.Cu")
		(at 313.784234 -457.938886 -90)
		(property "Reference" "J50"
			(at -2.4257 -5.635752 90)
			(unlocked yes)
			(layer "F.SilkS")
			(effects
				(font
					(size 0.7874 0.5842)
					(thickness 0.1524)
				)
			)
		)
		(property "Value" ""
			(at 0 0 270)
			(layer "F.Fab")
			(effects
				(font
					(size 1.27 1.27)
				)
			)
		)
		(duplicate_pad_numbers_are_jumpers no)
		(fp_line
			(start 0 4.011168)
			(end -3.330702 -4.771136)
			(stroke
				(width 0.1524)
				(type default)
			)
			(layer "F.SilkS")
		)
		(fp_line
			(start -3.330702 -4.771136)
			(end 3.330702 -4.771136)
			(stroke
				(width 0.1524)
				(type default)
			)
			(layer "F.SilkS")
		)
		(fp_line
			(start 3.330702 -4.771136)
			(end 0 4.011168)
			(stroke
				(width 0.1524)
				(type default)
			)
			(layer "F.SilkS")
		)
		(fp_line
			(start 0 4.011168)
			(end -3.330702 -4.771136)
			(stroke
				(width 0.1)
				(type default)
			)
			(layer "F.Fab")
		)
		(fp_line
			(start -3.330702 -4.771136)
			(end 3.330702 -4.771136)
			(stroke
				(width 0.1)
				(type default)
			)
			(layer "F.Fab")
		)
		(fp_line
			(start 3.330702 -4.771136)
			(end 0 4.011168)
			(stroke
				(width 0.1)
				(type default)
			)
			(layer "F.Fab")
		)
		(pad "1" thru_hole circle
			(at 0 0 270)
			(size 2.159 2.159)
			(drill 1.7018)
			(layers "*.Cu" "*.Mask")
			(remove_unused_layers no)
			(net "COUPON_GND1")
			(clearance 0.0254)
			(thermal_gap 0.0254)
		)
		(pad "2" thru_hole circle
			(at -1.27 -3.348736 270)
			(size 2.159 2.159)
			(drill 1.7018)
			(layers "*.Cu" "*.Mask")
			(remove_unused_layers no)
			(net "TDR_SE_50_OHM_IN4")
			(clearance 0.0254)
			(thermal_gap 0.0254)
		)
		(pad "3" thru_hole circle
			(at 1.27 -3.348736 270)
			(size 2.159 2.159)
			(drill 1.7018)
			(layers "*.Cu" "*.Mask")
			(remove_unused_layers no)
			(net "TDR_SE_50_OHM_IN4")
			(clearance 0.0254)
			(thermal_gap 0.0254)
		)
	)
	(footprint ""
		(layer "F.Cu")
		(at 336.443574 -42.84091)
		(property "Reference" "R627"
			(at 0 0 0)
			(layer "F.SilkS")
			(hide yes)
			(effects
				(font
					(size 1.27 1.27)
				)
			)
		)
		(property "Value" ""
			(at 0 0 0)
			(layer "F.Fab")
			(effects
				(font
					(size 1.27 1.27)
				)
			)
		)
		(duplicate_pad_numbers_are_jumpers no)
		(fp_line
			(start -0.7874 -0.4064)
			(end 0.7874 -0.4064)
			(stroke
				(width 0.1524)
				(type default)
			)
			(layer "F.SilkS")
		)
		(fp_line
			(start -0.7874 0.4064)
			(end -0.7874 -0.4064)
			(stroke
				(width 0.1524)
				(type default)
			)
			(layer "F.SilkS")
		)
		(fp_line
			(start 0.7874 -0.4064)
			(end 0.7874 0.4064)
			(stroke
				(width 0.1524)
				(type default)
			)
			(layer "F.SilkS")
		)
		(fp_line
			(start 0.7874 0.4064)
			(end -0.7874 0.4064)
			(stroke
				(width 0.1524)
				(type default)
			)
			(layer "F.SilkS")
		)
		(fp_line
			(start -0.67945 -0.305054)
			(end -0.12065 -0.305054)
			(stroke
				(width 0.1)
				(type default)
			)
			(layer "F.Fab")
		)
		(fp_line
			(start -0.67945 0.3048)
			(end -0.67945 -0.305054)
			(stroke
				(width 0.1)
				(type default)
			)
			(layer "F.Fab")
		)
		(fp_line
			(start -0.12065 -0.305054)
			(end -0.12065 -0.2794)
			(stroke
				(width 0.1)
				(type default)
			)
			(layer "F.Fab")
		)
		(fp_line
			(start -0.12065 -0.2794)
			(end 0.12065 -0.2794)
			(stroke
				(width 0.1)
				(type default)
			)
			(layer "F.Fab")
		)
		(fp_line
			(start -0.12065 0.2794)
			(end -0.12065 0.3048)
			(stroke
				(width 0.1)
				(type default)
			)
			(layer "F.Fab")
		)
		(fp_line
			(start -0.12065 0.3048)
			(end -0.67945 0.3048)
			(stroke
				(width 0.1)
				(type default)
			)
			(layer "F.Fab")
		)
		(fp_line
			(start 0.120396 0.2794)
			(end -0.12065 0.2794)
			(stroke
				(width 0.1)
				(type default)
			)
			(layer "F.Fab")
		)
		(fp_line
			(start 0.120396 0.3048)
			(end 0.120396 0.2794)
			(stroke
				(width 0.1)
				(type default)
			)
			(layer "F.Fab")
		)
		(fp_line
			(start 0.12065 -0.3048)
			(end 0.67945 -0.3048)
			(stroke
				(width 0.1)
				(type default)
			)
			(layer "F.Fab")
		)
		(fp_line
			(start 0.12065 -0.2794)
			(end 0.12065 -0.3048)
			(stroke
				(width 0.1)
				(type default)
			)
			(layer "F.Fab")
		)
		(fp_line
			(start 0.67945 -0.3048)
			(end 0.67945 0.3048)
			(stroke
				(width 0.1)
				(type default)
			)
			(layer "F.Fab")
		)
		(fp_line
			(start 0.67945 0.3048)
			(end 0.120396 0.3048)
			(stroke
				(width 0.1)
				(type default)
			)
			(layer "F.Fab")
		)
		(pad "1" smd circle
			(at -0.40005 0)
			(size 0 0)
			(layers "F.Cu" "F.Mask" "F.Paste")
			(net "SSD11_ADC_A1")
		)
		(pad "2" smd circle
			(at 0.40005 0)
			(size 0 0)
			(layers "F.Cu" "F.Mask" "F.Paste")
			(net "P3V3_AUX")
		)
	)
	(footprint ""
		(layer "F.Cu")
		(at 345.694 -205.232 90)
		(property "Reference" "R4144"
			(at 0 0 90)
			(layer "F.SilkS")
			(hide yes)
			(effects
				(font
					(size 1.27 1.27)
				)
			)
		)
		(property "Value" ""
			(at 0 0 90)
			(layer "F.Fab")
			(effects
				(font
					(size 1.27 1.27)
				)
			)
		)
		(duplicate_pad_numbers_are_jumpers no)
		(fp_line
			(start 0.7874 -0.4064)
			(end 0.7874 0.4064)
			(stroke
				(width 0.1524)
				(type default)
			)
			(layer "F.SilkS")
		)
		(fp_line
			(start -0.7874 -0.4064)
			(end 0.7874 -0.4064)
			(stroke
				(width 0.1524)
				(type default)
			)
			(layer "F.SilkS")
		)
		(fp_line
			(start 0.7874 0.4064)
			(end -0.7874 0.4064)
			(stroke
				(width 0.1524)
				(type default)
			)
			(layer "F.SilkS")
		)
		(fp_line
			(start -0.7874 0.4064)
			(end -0.7874 -0.4064)
			(stroke
				(width 0.1524)
				(type default)
			)
			(layer "F.SilkS")
		)
		(fp_line
			(start -0.12065 -0.305054)
			(end -0.12065 -0.2794)
			(stroke
				(width 0.1)
				(type default)
			)
			(layer "F.Fab")
		)
		(fp_line
			(start -0.67945 -0.305054)
			(end -0.12065 -0.305054)
			(stroke
				(width 0.1)
				(type default)
			)
			(layer "F.Fab")
		)
		(fp_line
			(start 0.67945 -0.3048)
			(end 0.67945 0.3048)
			(stroke
				(width 0.1)
				(type default)
			)
			(layer "F.Fab")
		)
		(fp_line
			(start 0.12065 -0.3048)
			(end 0.67945 -0.3048)
			(stroke
				(width 0.1)
				(type default)
			)
			(layer "F.Fab")
		)
		(fp_line
			(start 0.12065 -0.2794)
			(end 0.12065 -0.3048)
			(stroke
				(width 0.1)
				(type default)
			)
			(layer "F.Fab")
		)
		(fp_line
			(start -0.12065 -0.2794)
			(end 0.12065 -0.2794)
			(stroke
				(width 0.1)
				(type default)
			)
			(layer "F.Fab")
		)
		(fp_line
			(start 0.120396 0.2794)
			(end -0.12065 0.2794)
			(stroke
				(width 0.1)
				(type default)
			)
			(layer "F.Fab")
		)
		(fp_line
			(start -0.12065 0.2794)
			(end -0.12065 0.3048)
			(stroke
				(width 0.1)
				(type default)
			)
			(layer "F.Fab")
		)
		(fp_line
			(start 0.67945 0.3048)
			(end 0.120396 0.3048)
			(stroke
				(width 0.1)
				(type default)
			)
			(layer "F.Fab")
		)
		(fp_line
			(start 0.120396 0.3048)
			(end 0.120396 0.2794)
			(stroke
				(width 0.1)
				(type default)
			)
			(layer "F.Fab")
		)
		(fp_line
			(start -0.12065 0.3048)
			(end -0.67945 0.3048)
			(stroke
				(width 0.1)
				(type default)
			)
			(layer "F.Fab")
		)
		(fp_line
			(start -0.67945 0.3048)
			(end -0.67945 -0.305054)
			(stroke
				(width 0.1)
				(type default)
			)
			(layer "F.Fab")
		)
		(pad "1" smd circle
			(at -0.40005 0 90)
			(size 0 0)
			(layers "F.Cu" "F.Mask" "F.Paste")
			(net "SSD15_PWRDIS_R")
		)
		(pad "2" smd circle
			(at 0.40005 0 90)
			(size 0 0)
			(layers "F.Cu" "F.Mask" "F.Paste")
			(net "SSD15_PWRDIS")
		)
	)
	(footprint ""
		(layer "F.Cu")
		(at 60.389262 -390.07161 90)
		(property "Reference" "R6256"
			(at 0 0 90)
			(layer "F.SilkS")
			(hide yes)
			(effects
				(font
					(size 1.27 1.27)
				)
			)
		)
		(property "Value" ""
			(at 0 0 90)
			(layer "F.Fab")
			(effects
				(font
					(size 1.27 1.27)
				)
			)
		)
		(duplicate_pad_numbers_are_jumpers no)
		(fp_line
			(start 0.7874 -0.4064)
			(end 0.7874 0.4064)
			(stroke
				(width 0.1524)
				(type default)
			)
			(layer "F.SilkS")
		)
		(fp_line
			(start -0.7874 -0.4064)
			(end 0.7874 -0.4064)
			(stroke
				(width 0.1524)
				(type default)
			)
			(layer "F.SilkS")
		)
		(fp_line
			(start 0.7874 0.4064)
			(end -0.7874 0.4064)
			(stroke
				(width 0.1524)
				(type default)
			)
			(layer "F.SilkS")
		)
		(fp_line
			(start -0.7874 0.4064)
			(end -0.7874 -0.4064)
			(stroke
				(width 0.1524)
				(type default)
			)
			(layer "F.SilkS")
		)
		(fp_line
			(start -0.12065 -0.305054)
			(end -0.12065 -0.2794)
			(stroke
				(width 0.1)
				(type default)
			)
			(layer "F.Fab")
		)
		(fp_line
			(start -0.67945 -0.305054)
			(end -0.12065 -0.305054)
			(stroke
				(width 0.1)
				(type default)
			)
			(layer "F.Fab")
		)
		(fp_line
			(start 0.67945 -0.3048)
			(end 0.67945 0.3048)
			(stroke
				(width 0.1)
				(type default)
			)
			(layer "F.Fab")
		)
		(fp_line
			(start 0.12065 -0.3048)
			(end 0.67945 -0.3048)
			(stroke
				(width 0.1)
				(type default)
			)
			(layer "F.Fab")
		)
		(fp_line
			(start 0.12065 -0.2794)
			(end 0.12065 -0.3048)
			(stroke
				(width 0.1)
				(type default)
			)
			(layer "F.Fab")
		)
		(fp_line
			(start -0.12065 -0.2794)
			(end 0.12065 -0.2794)
			(stroke
				(width 0.1)
				(type default)
			)
			(layer "F.Fab")
		)
		(fp_line
			(start 0.120396 0.2794)
			(end -0.12065 0.2794)
			(stroke
				(width 0.1)
				(type default)
			)
			(layer "F.Fab")
		)
		(fp_line
			(start -0.12065 0.2794)
			(end -0.12065 0.3048)
			(stroke
				(width 0.1)
				(type default)
			)
			(layer "F.Fab")
		)
		(fp_line
			(start 0.67945 0.3048)
			(end 0.120396 0.3048)
			(stroke
				(width 0.1)
				(type default)
			)
			(layer "F.Fab")
		)
		(fp_line
			(start 0.120396 0.3048)
			(end 0.120396 0.2794)
			(stroke
				(width 0.1)
				(type default)
			)
			(layer "F.Fab")
		)
		(fp_line
			(start -0.12065 0.3048)
			(end -0.67945 0.3048)
			(stroke
				(width 0.1)
				(type default)
			)
			(layer "F.Fab")
		)
		(fp_line
			(start -0.67945 0.3048)
			(end -0.67945 -0.305054)
			(stroke
				(width 0.1)
				(type default)
			)
			(layer "F.Fab")
		)
		(pad "1" smd circle
			(at -0.40005 0 90)
			(size 0 0)
			(layers "F.Cu" "F.Mask" "F.Paste")
			(net "GPU_HGX_DETECT_R_N")
		)
		(pad "2" smd circle
			(at 0.40005 0 90)
			(size 0 0)
			(layers "F.Cu" "F.Mask" "F.Paste")
			(net "GPU_HGX_DETECT_N")
		)
	)
	(footprint ""
		(layer "F.Cu")
		(at 258.54533 -191.654684)
		(property "Reference" "R4901"
			(at 0 0 0)
			(layer "F.SilkS")
			(hide yes)
			(effects
				(font
					(size 1.27 1.27)
				)
			)
		)
		(property "Value" ""
			(at 0 0 0)
			(layer "F.Fab")
			(effects
				(font
					(size 1.27 1.27)
				)
			)
		)
		(duplicate_pad_numbers_are_jumpers no)
		(fp_line
			(start -0.7874 -0.4064)
			(end 0.7874 -0.4064)
			(stroke
				(width 0.1524)
				(type default)
			)
			(layer "F.SilkS")
		)
		(fp_line
			(start -0.7874 0.4064)
			(end -0.7874 -0.4064)
			(stroke
				(width 0.1524)
				(type default)
			)
			(layer "F.SilkS")
		)
		(fp_line
			(start 0.7874 -0.4064)
			(end 0.7874 0.4064)
			(stroke
				(width 0.1524)
				(type default)
			)
			(layer "F.SilkS")
		)
		(fp_line
			(start 0.7874 0.4064)
			(end -0.7874 0.4064)
			(stroke
				(width 0.1524)
				(type default)
			)
			(layer "F.SilkS")
		)
		(fp_line
			(start -0.67945 -0.305054)
			(end -0.12065 -0.305054)
			(stroke
				(width 0.1)
				(type default)
			)
			(layer "F.Fab")
		)
		(fp_line
			(start -0.67945 0.3048)
			(end -0.67945 -0.305054)
			(stroke
				(width 0.1)
				(type default)
			)
			(layer "F.Fab")
		)
		(fp_line
			(start -0.12065 -0.305054)
			(end -0.12065 -0.2794)
			(stroke
				(width 0.1)
				(type default)
			)
			(layer "F.Fab")
		)
		(fp_line
			(start -0.12065 -0.2794)
			(end 0.12065 -0.2794)
			(stroke
				(width 0.1)
				(type default)
			)
			(layer "F.Fab")
		)
		(fp_line
			(start -0.12065 0.2794)
			(end -0.12065 0.3048)
			(stroke
				(width 0.1)
				(type default)
			)
			(layer "F.Fab")
		)
		(fp_line
			(start -0.12065 0.3048)
			(end -0.67945 0.3048)
			(stroke
				(width 0.1)
				(type default)
			)
			(layer "F.Fab")
		)
		(fp_line
			(start 0.120396 0.2794)
			(end -0.12065 0.2794)
			(stroke
				(width 0.1)
				(type default)
			)
			(layer "F.Fab")
		)
		(fp_line
			(start 0.120396 0.3048)
			(end 0.120396 0.2794)
			(stroke
				(width 0.1)
				(type default)
			)
			(layer "F.Fab")
		)
		(fp_line
			(start 0.12065 -0.3048)
			(end 0.67945 -0.3048)
			(stroke
				(width 0.1)
				(type default)
			)
			(layer "F.Fab")
		)
		(fp_line
			(start 0.12065 -0.2794)
			(end 0.12065 -0.3048)
			(stroke
				(width 0.1)
				(type default)
			)
			(layer "F.Fab")
		)
		(fp_line
			(start 0.67945 -0.3048)
			(end 0.67945 0.3048)
			(stroke
				(width 0.1)
				(type default)
			)
			(layer "F.Fab")
		)
		(fp_line
			(start 0.67945 0.3048)
			(end 0.120396 0.3048)
			(stroke
				(width 0.1)
				(type default)
			)
			(layer "F.Fab")
		)
		(pad "1" smd circle
			(at -0.40005 0)
			(size 0 0)
			(layers "F.Cu" "F.Mask" "F.Paste")
			(net "JTAG_FPGA_TCK")
		)
		(pad "2" smd circle
			(at 0.40005 0)
			(size 0 0)
			(layers "F.Cu" "F.Mask" "F.Paste")
			(net "JTAG_CONN_TCK")
		)
	)
	(footprint ""
		(layer "F.Cu")
		(at 20.48764 -25.342342 -90)
		(property "Reference" "R411"
			(at 0 0 270)
			(layer "F.SilkS")
			(hide yes)
			(effects
				(font
					(size 1.27 1.27)
				)
			)
		)
		(property "Value" ""
			(at 0 0 270)
			(layer "F.Fab")
			(effects
				(font
					(size 1.27 1.27)
				)
			)
		)
		(duplicate_pad_numbers_are_jumpers no)
		(fp_line
			(start -0.7874 0.4064)
			(end -0.7874 -0.4064)
			(stroke
				(width 0.1524)
				(type default)
			)
			(layer "F.SilkS")
		)
		(fp_line
			(start 0.7874 0.4064)
			(end -0.7874 0.4064)
			(stroke
				(width 0.1524)
				(type default)
			)
			(layer "F.SilkS")
		)
		(fp_line
			(start -0.7874 -0.4064)
			(end 0.7874 -0.4064)
			(stroke
				(width 0.1524)
				(type default)
			)
			(layer "F.SilkS")
		)
		(fp_line
			(start 0.7874 -0.4064)
			(end 0.7874 0.4064)
			(stroke
				(width 0.1524)
				(type default)
			)
			(layer "F.SilkS")
		)
		(fp_line
			(start -0.67945 0.3048)
			(end -0.67945 -0.305054)
			(stroke
				(width 0.1)
				(type default)
			)
			(layer "F.Fab")
		)
		(fp_line
			(start -0.12065 0.3048)
			(end -0.67945 0.3048)
			(stroke
				(width 0.1)
				(type default)
			)
			(layer "F.Fab")
		)
		(fp_line
			(start 0.120396 0.3048)
			(end 0.120396 0.2794)
			(stroke
				(width 0.1)
				(type default)
			)
			(layer "F.Fab")
		)
		(fp_line
			(start 0.67945 0.3048)
			(end 0.120396 0.3048)
			(stroke
				(width 0.1)
				(type default)
			)
			(layer "F.Fab")
		)
		(fp_line
			(start -0.12065 0.2794)
			(end -0.12065 0.3048)
			(stroke
				(width 0.1)
				(type default)
			)
			(layer "F.Fab")
		)
		(fp_line
			(start 0.120396 0.2794)
			(end -0.12065 0.2794)
			(stroke
				(width 0.1)
				(type default)
			)
			(layer "F.Fab")
		)
		(fp_line
			(start -0.12065 -0.2794)
			(end 0.12065 -0.2794)
			(stroke
				(width 0.1)
				(type default)
			)
			(layer "F.Fab")
		)
		(fp_line
			(start 0.12065 -0.2794)
			(end 0.12065 -0.3048)
			(stroke
				(width 0.1)
				(type default)
			)
			(layer "F.Fab")
		)
		(fp_line
			(start 0.12065 -0.3048)
			(end 0.67945 -0.3048)
			(stroke
				(width 0.1)
				(type default)
			)
			(layer "F.Fab")
		)
		(fp_line
			(start 0.67945 -0.3048)
			(end 0.67945 0.3048)
			(stroke
				(width 0.1)
				(type default)
			)
			(layer "F.Fab")
		)
		(fp_line
			(start -0.67945 -0.305054)
			(end -0.12065 -0.305054)
			(stroke
				(width 0.1)
				(type default)
			)
			(layer "F.Fab")
		)
		(fp_line
			(start -0.12065 -0.305054)
			(end -0.12065 -0.2794)
			(stroke
				(width 0.1)
				(type default)
			)
			(layer "F.Fab")
		)
		(pad "1" smd circle
			(at -0.40005 0 270)
			(size 0 0)
			(layers "F.Cu" "F.Mask" "F.Paste")
			(net "GND")
		)
		(pad "2" smd circle
			(at 0.40005 0 270)
			(size 0 0)
			(layers "F.Cu" "F.Mask" "F.Paste")
			(net "DUALPORT_N_SSD0")
		)
	)
	(footprint ""
		(layer "F.Cu")
		(at 168.367202 -57.332626)
		(property "Reference" "R6836"
			(at 0 0 0)
			(layer "F.SilkS")
			(hide yes)
			(effects
				(font
					(size 1.27 1.27)
				)
			)
		)
		(property "Value" ""
			(at 0 0 0)
			(layer "F.Fab")
			(effects
				(font
					(size 1.27 1.27)
				)
			)
		)
		(duplicate_pad_numbers_are_jumpers no)
		(fp_line
			(start -0.7874 -0.4064)
			(end 0.7874 -0.4064)
			(stroke
				(width 0.1524)
				(type default)
			)
			(layer "F.SilkS")
		)
		(fp_line
			(start -0.7874 0.4064)
			(end -0.7874 -0.4064)
			(stroke
				(width 0.1524)
				(type default)
			)
			(layer "F.SilkS")
		)
		(fp_line
			(start 0.7874 -0.4064)
			(end 0.7874 0.4064)
			(stroke
				(width 0.1524)
				(type default)
			)
			(layer "F.SilkS")
		)
		(fp_line
			(start 0.7874 0.4064)
			(end -0.7874 0.4064)
			(stroke
				(width 0.1524)
				(type default)
			)
			(layer "F.SilkS")
		)
		(fp_line
			(start -0.67945 -0.305054)
			(end -0.12065 -0.305054)
			(stroke
				(width 0.1)
				(type default)
			)
			(layer "F.Fab")
		)
		(fp_line
			(start -0.67945 0.3048)
			(end -0.67945 -0.305054)
			(stroke
				(width 0.1)
				(type default)
			)
			(layer "F.Fab")
		)
		(fp_line
			(start -0.12065 -0.305054)
			(end -0.12065 -0.2794)
			(stroke
				(width 0.1)
				(type default)
			)
			(layer "F.Fab")
		)
		(fp_line
			(start -0.12065 -0.2794)
			(end 0.12065 -0.2794)
			(stroke
				(width 0.1)
				(type default)
			)
			(layer "F.Fab")
		)
		(fp_line
			(start -0.12065 0.2794)
			(end -0.12065 0.3048)
			(stroke
				(width 0.1)
				(type default)
			)
			(layer "F.Fab")
		)
		(fp_line
			(start -0.12065 0.3048)
			(end -0.67945 0.3048)
			(stroke
				(width 0.1)
				(type default)
			)
			(layer "F.Fab")
		)
		(fp_line
			(start 0.120396 0.2794)
			(end -0.12065 0.2794)
			(stroke
				(width 0.1)
				(type default)
			)
			(layer "F.Fab")
		)
		(fp_line
			(start 0.120396 0.3048)
			(end 0.120396 0.2794)
			(stroke
				(width 0.1)
				(type default)
			)
			(layer "F.Fab")
		)
		(fp_line
			(start 0.12065 -0.3048)
			(end 0.67945 -0.3048)
			(stroke
				(width 0.1)
				(type default)
			)
			(layer "F.Fab")
		)
		(fp_line
			(start 0.12065 -0.2794)
			(end 0.12065 -0.3048)
			(stroke
				(width 0.1)
				(type default)
			)
			(layer "F.Fab")
		)
		(fp_line
			(start 0.67945 -0.3048)
			(end 0.67945 0.3048)
			(stroke
				(width 0.1)
				(type default)
			)
			(layer "F.Fab")
		)
		(fp_line
			(start 0.67945 0.3048)
			(end 0.120396 0.3048)
			(stroke
				(width 0.1)
				(type default)
			)
			(layer "F.Fab")
		)
		(pad "1" smd circle
			(at -0.40005 0)
			(size 0 0)
			(layers "F.Cu" "F.Mask" "F.Paste")
			(net "SSD5_PWR_EN_R")
		)
		(pad "2" smd circle
			(at 0.40005 0)
			(size 0 0)
			(layers "F.Cu" "F.Mask" "F.Paste")
			(net "GND")
		)
	)
	(footprint ""
		(layer "F.Cu")
		(at 386.90804 -153.3144 180)
		(property "Reference" "R331"
			(at 0 0 180)
			(layer "F.SilkS")
			(hide yes)
			(effects
				(font
					(size 1.27 1.27)
				)
			)
		)
		(property "Value" ""
			(at 0 0 180)
			(layer "F.Fab")
			(effects
				(font
					(size 1.27 1.27)
				)
			)
		)
		(duplicate_pad_numbers_are_jumpers no)
		(fp_line
			(start 0.7874 0.4064)
			(end -0.7874 0.4064)
			(stroke
				(width 0.1524)
				(type default)
			)
			(layer "F.SilkS")
		)
		(fp_line
			(start 0.7874 -0.4064)
			(end 0.7874 0.4064)
			(stroke
				(width 0.1524)
				(type default)
			)
			(layer "F.SilkS")
		)
		(fp_line
			(start -0.7874 0.4064)
			(end -0.7874 -0.4064)
			(stroke
				(width 0.1524)
				(type default)
			)
			(layer "F.SilkS")
		)
		(fp_line
			(start -0.7874 -0.4064)
			(end 0.7874 -0.4064)
			(stroke
				(width 0.1524)
				(type default)
			)
			(layer "F.SilkS")
		)
		(fp_line
			(start 0.67945 0.3048)
			(end 0.120396 0.3048)
			(stroke
				(width 0.1)
				(type default)
			)
			(layer "F.Fab")
		)
		(fp_line
			(start 0.67945 -0.3048)
			(end 0.67945 0.3048)
			(stroke
				(width 0.1)
				(type default)
			)
			(layer "F.Fab")
		)
		(fp_line
			(start 0.12065 -0.2794)
			(end 0.12065 -0.3048)
			(stroke
				(width 0.1)
				(type default)
			)
			(layer "F.Fab")
		)
		(fp_line
			(start 0.12065 -0.3048)
			(end 0.67945 -0.3048)
			(stroke
				(width 0.1)
				(type default)
			)
			(layer "F.Fab")
		)
		(fp_line
			(start 0.120396 0.3048)
			(end 0.120396 0.2794)
			(stroke
				(width 0.1)
				(type default)
			)
			(layer "F.Fab")
		)
		(fp_line
			(start 0.120396 0.2794)
			(end -0.12065 0.2794)
			(stroke
				(width 0.1)
				(type default)
			)
			(layer "F.Fab")
		)
		(fp_line
			(start -0.12065 0.3048)
			(end -0.67945 0.3048)
			(stroke
				(width 0.1)
				(type default)
			)
			(layer "F.Fab")
		)
		(fp_line
			(start -0.12065 0.2794)
			(end -0.12065 0.3048)
			(stroke
				(width 0.1)
				(type default)
			)
			(layer "F.Fab")
		)
		(fp_line
			(start -0.12065 -0.2794)
			(end 0.12065 -0.2794)
			(stroke
				(width 0.1)
				(type default)
			)
			(layer "F.Fab")
		)
		(fp_line
			(start -0.12065 -0.305054)
			(end -0.12065 -0.2794)
			(stroke
				(width 0.1)
				(type default)
			)
			(layer "F.Fab")
		)
		(fp_line
			(start -0.67945 0.3048)
			(end -0.67945 -0.305054)
			(stroke
				(width 0.1)
				(type default)
			)
			(layer "F.Fab")
		)
		(fp_line
			(start -0.67945 -0.305054)
			(end -0.12065 -0.305054)
			(stroke
				(width 0.1)
				(type default)
			)
			(layer "F.Fab")
		)
		(pad "1" smd circle
			(at -0.40005 0 180)
			(size 0 0)
			(layers "F.Cu" "F.Mask" "F.Paste")
			(net "NIC6_SLOT_ID0")
		)
		(pad "2" smd circle
			(at 0.40005 0 180)
			(size 0 0)
			(layers "F.Cu" "F.Mask" "F.Paste")
			(net "P3V3_NIC6")
		)
	)
	(footprint ""
		(layer "F.Cu")
		(at 95.105728 -245.824248 180)
		(property "Reference" "R818"
			(at 0 0 180)
			(layer "F.SilkS")
			(hide yes)
			(effects
				(font
					(size 1.27 1.27)
				)
			)
		)
		(property "Value" ""
			(at 0 0 180)
			(layer "F.Fab")
			(effects
				(font
					(size 1.27 1.27)
				)
			)
		)
		(duplicate_pad_numbers_are_jumpers no)
		(fp_line
			(start 0.7874 0.4064)
			(end -0.7874 0.4064)
			(stroke
				(width 0.1524)
				(type default)
			)
			(layer "F.SilkS")
		)
		(fp_line
			(start 0.7874 -0.4064)
			(end 0.7874 0.4064)
			(stroke
				(width 0.1524)
				(type default)
			)
			(layer "F.SilkS")
		)
		(fp_line
			(start -0.7874 0.4064)
			(end -0.7874 -0.4064)
			(stroke
				(width 0.1524)
				(type default)
			)
			(layer "F.SilkS")
		)
		(fp_line
			(start -0.7874 -0.4064)
			(end 0.7874 -0.4064)
			(stroke
				(width 0.1524)
				(type default)
			)
			(layer "F.SilkS")
		)
		(fp_line
			(start 0.67945 0.3048)
			(end 0.120396 0.3048)
			(stroke
				(width 0.1)
				(type default)
			)
			(layer "F.Fab")
		)
		(fp_line
			(start 0.67945 -0.3048)
			(end 0.67945 0.3048)
			(stroke
				(width 0.1)
				(type default)
			)
			(layer "F.Fab")
		)
		(fp_line
			(start 0.12065 -0.2794)
			(end 0.12065 -0.3048)
			(stroke
				(width 0.1)
				(type default)
			)
			(layer "F.Fab")
		)
		(fp_line
			(start 0.12065 -0.3048)
			(end 0.67945 -0.3048)
			(stroke
				(width 0.1)
				(type default)
			)
			(layer "F.Fab")
		)
		(fp_line
			(start 0.120396 0.3048)
			(end 0.120396 0.2794)
			(stroke
				(width 0.1)
				(type default)
			)
			(layer "F.Fab")
		)
		(fp_line
			(start 0.120396 0.2794)
			(end -0.12065 0.2794)
			(stroke
				(width 0.1)
				(type default)
			)
			(layer "F.Fab")
		)
		(fp_line
			(start -0.12065 0.3048)
			(end -0.67945 0.3048)
			(stroke
				(width 0.1)
				(type default)
			)
			(layer "F.Fab")
		)
		(fp_line
			(start -0.12065 0.2794)
			(end -0.12065 0.3048)
			(stroke
				(width 0.1)
				(type default)
			)
			(layer "F.Fab")
		)
		(fp_line
			(start -0.12065 -0.2794)
			(end 0.12065 -0.2794)
			(stroke
				(width 0.1)
				(type default)
			)
			(layer "F.Fab")
		)
		(fp_line
			(start -0.12065 -0.305054)
			(end -0.12065 -0.2794)
			(stroke
				(width 0.1)
				(type default)
			)
			(layer "F.Fab")
		)
		(fp_line
			(start -0.67945 0.3048)
			(end -0.67945 -0.305054)
			(stroke
				(width 0.1)
				(type default)
			)
			(layer "F.Fab")
		)
		(fp_line
			(start -0.67945 -0.305054)
			(end -0.12065 -0.305054)
			(stroke
				(width 0.1)
				(type default)
			)
			(layer "F.Fab")
		)
		(pad "1" smd circle
			(at -0.40005 0 180)
			(size 0 0)
			(layers "F.Cu" "F.Mask" "F.Paste")
			(net "PEX_P1V8_ADC_A1")
		)
		(pad "2" smd circle
			(at 0.40005 0 180)
			(size 0 0)
			(layers "F.Cu" "F.Mask" "F.Paste")
			(net "GND")
		)
	)
	(footprint ""
		(layer "F.Cu")
		(at 25.524968 -356.244906 90)
		(property "Reference" "C2158"
			(at 0 0 90)
			(layer "F.SilkS")
			(hide yes)
			(effects
				(font
					(size 1.27 1.27)
				)
			)
		)
		(property "Value" ""
			(at 0 0 90)
			(layer "F.Fab")
			(effects
				(font
					(size 1.27 1.27)
				)
			)
		)
		(duplicate_pad_numbers_are_jumpers no)
		(fp_line
			(start 0.299974 -0.150114)
			(end 0.299974 0.150114)
			(stroke
				(width 0.1)
				(type default)
			)
			(layer "F.Fab")
		)
		(fp_line
			(start -0.299974 -0.150114)
			(end 0.299974 -0.150114)
			(stroke
				(width 0.1)
				(type default)
			)
			(layer "F.Fab")
		)
		(fp_line
			(start 0.299974 0.150114)
			(end -0.299974 0.150114)
			(stroke
				(width 0.1)
				(type default)
			)
			(layer "F.Fab")
		)
		(fp_line
			(start -0.299974 0.150114)
			(end -0.299974 -0.150114)
			(stroke
				(width 0.1)
				(type default)
			)
			(layer "F.Fab")
		)
		(pad "1" smd rect
			(at -0.2667 0 90)
			(size 0.3048 0.381)
			(layers "F.Cu" "F.Mask" "F.Paste")
			(net "P5E_PEX0_STN4_TX_DP<76>")
		)
		(pad "2" smd rect
			(at 0.2667 0 90)
			(size 0.3048 0.381)
			(layers "F.Cu" "F.Mask" "F.Paste")
			(net "P5E_PEX0_STN4_TX_C_DP<76>")
		)
	)
	(footprint ""
		(layer "F.Cu")
		(at 216.022936 -188.652404 90)
		(property "Reference" "R5414"
			(at 0 0 90)
			(layer "F.SilkS")
			(hide yes)
			(effects
				(font
					(size 1.27 1.27)
				)
			)
		)
		(property "Value" ""
			(at 0 0 90)
			(layer "F.Fab")
			(effects
				(font
					(size 1.27 1.27)
				)
			)
		)
		(duplicate_pad_numbers_are_jumpers no)
		(fp_line
			(start 0.7874 -0.4064)
			(end 0.7874 0.4064)
			(stroke
				(width 0.1524)
				(type default)
			)
			(layer "F.SilkS")
		)
		(fp_line
			(start -0.7874 -0.4064)
			(end 0.7874 -0.4064)
			(stroke
				(width 0.1524)
				(type default)
			)
			(layer "F.SilkS")
		)
		(fp_line
			(start 0.7874 0.4064)
			(end -0.7874 0.4064)
			(stroke
				(width 0.1524)
				(type default)
			)
			(layer "F.SilkS")
		)
		(fp_line
			(start -0.7874 0.4064)
			(end -0.7874 -0.4064)
			(stroke
				(width 0.1524)
				(type default)
			)
			(layer "F.SilkS")
		)
		(fp_line
			(start -0.12065 -0.305054)
			(end -0.12065 -0.2794)
			(stroke
				(width 0.1)
				(type default)
			)
			(layer "F.Fab")
		)
		(fp_line
			(start -0.67945 -0.305054)
			(end -0.12065 -0.305054)
			(stroke
				(width 0.1)
				(type default)
			)
			(layer "F.Fab")
		)
		(fp_line
			(start 0.67945 -0.3048)
			(end 0.67945 0.3048)
			(stroke
				(width 0.1)
				(type default)
			)
			(layer "F.Fab")
		)
		(fp_line
			(start 0.12065 -0.3048)
			(end 0.67945 -0.3048)
			(stroke
				(width 0.1)
				(type default)
			)
			(layer "F.Fab")
		)
		(fp_line
			(start 0.12065 -0.2794)
			(end 0.12065 -0.3048)
			(stroke
				(width 0.1)
				(type default)
			)
			(layer "F.Fab")
		)
		(fp_line
			(start -0.12065 -0.2794)
			(end 0.12065 -0.2794)
			(stroke
				(width 0.1)
				(type default)
			)
			(layer "F.Fab")
		)
		(fp_line
			(start 0.120396 0.2794)
			(end -0.12065 0.2794)
			(stroke
				(width 0.1)
				(type default)
			)
			(layer "F.Fab")
		)
		(fp_line
			(start -0.12065 0.2794)
			(end -0.12065 0.3048)
			(stroke
				(width 0.1)
				(type default)
			)
			(layer "F.Fab")
		)
		(fp_line
			(start 0.67945 0.3048)
			(end 0.120396 0.3048)
			(stroke
				(width 0.1)
				(type default)
			)
			(layer "F.Fab")
		)
		(fp_line
			(start 0.120396 0.3048)
			(end 0.120396 0.2794)
			(stroke
				(width 0.1)
				(type default)
			)
			(layer "F.Fab")
		)
		(fp_line
			(start -0.12065 0.3048)
			(end -0.67945 0.3048)
			(stroke
				(width 0.1)
				(type default)
			)
			(layer "F.Fab")
		)
		(fp_line
			(start -0.67945 0.3048)
			(end -0.67945 -0.305054)
			(stroke
				(width 0.1)
				(type default)
			)
			(layer "F.Fab")
		)
		(pad "1" smd circle
			(at -0.40005 0 90)
			(size 0 0)
			(layers "F.Cu" "F.Mask" "F.Paste")
			(net "BIC_SEL_FLASH_SW0_R")
		)
		(pad "2" smd circle
			(at 0.40005 0 90)
			(size 0 0)
			(layers "F.Cu" "F.Mask" "F.Paste")
			(net "GND")
		)
	)
	(footprint ""
		(layer "F.Cu")
		(at 149.080728 -380.412498)
		(property "Reference" "R1840"
			(at 0 0 0)
			(layer "F.SilkS")
			(hide yes)
			(effects
				(font
					(size 1.27 1.27)
				)
			)
		)
		(property "Value" ""
			(at 0 0 0)
			(layer "F.Fab")
			(effects
				(font
					(size 1.27 1.27)
				)
			)
		)
		(duplicate_pad_numbers_are_jumpers no)
		(fp_line
			(start -0.7874 -0.4064)
			(end 0.7874 -0.4064)
			(stroke
				(width 0.1524)
				(type default)
			)
			(layer "F.SilkS")
		)
		(fp_line
			(start -0.7874 0.4064)
			(end -0.7874 -0.4064)
			(stroke
				(width 0.1524)
				(type default)
			)
			(layer "F.SilkS")
		)
		(fp_line
			(start 0.7874 -0.4064)
			(end 0.7874 0.4064)
			(stroke
				(width 0.1524)
				(type default)
			)
			(layer "F.SilkS")
		)
		(fp_line
			(start 0.7874 0.4064)
			(end -0.7874 0.4064)
			(stroke
				(width 0.1524)
				(type default)
			)
			(layer "F.SilkS")
		)
		(fp_line
			(start -0.67945 -0.305054)
			(end -0.12065 -0.305054)
			(stroke
				(width 0.1)
				(type default)
			)
			(layer "F.Fab")
		)
		(fp_line
			(start -0.67945 0.3048)
			(end -0.67945 -0.305054)
			(stroke
				(width 0.1)
				(type default)
			)
			(layer "F.Fab")
		)
		(fp_line
			(start -0.12065 -0.305054)
			(end -0.12065 -0.2794)
			(stroke
				(width 0.1)
				(type default)
			)
			(layer "F.Fab")
		)
		(fp_line
			(start -0.12065 -0.2794)
			(end 0.12065 -0.2794)
			(stroke
				(width 0.1)
				(type default)
			)
			(layer "F.Fab")
		)
		(fp_line
			(start -0.12065 0.2794)
			(end -0.12065 0.3048)
			(stroke
				(width 0.1)
				(type default)
			)
			(layer "F.Fab")
		)
		(fp_line
			(start -0.12065 0.3048)
			(end -0.67945 0.3048)
			(stroke
				(width 0.1)
				(type default)
			)
			(layer "F.Fab")
		)
		(fp_line
			(start 0.120396 0.2794)
			(end -0.12065 0.2794)
			(stroke
				(width 0.1)
				(type default)
			)
			(layer "F.Fab")
		)
		(fp_line
			(start 0.120396 0.3048)
			(end 0.120396 0.2794)
			(stroke
				(width 0.1)
				(type default)
			)
			(layer "F.Fab")
		)
		(fp_line
			(start 0.12065 -0.3048)
			(end 0.67945 -0.3048)
			(stroke
				(width 0.1)
				(type default)
			)
			(layer "F.Fab")
		)
		(fp_line
			(start 0.12065 -0.2794)
			(end 0.12065 -0.3048)
			(stroke
				(width 0.1)
				(type default)
			)
			(layer "F.Fab")
		)
		(fp_line
			(start 0.67945 -0.3048)
			(end 0.67945 0.3048)
			(stroke
				(width 0.1)
				(type default)
			)
			(layer "F.Fab")
		)
		(fp_line
			(start 0.67945 0.3048)
			(end 0.120396 0.3048)
			(stroke
				(width 0.1)
				(type default)
			)
			(layer "F.Fab")
		)
		(pad "1" smd circle
			(at -0.40005 0)
			(size 0 0)
			(layers "F.Cu" "F.Mask" "F.Paste")
			(net "GPU_3V3IO_RSVD0_FFU_R")
		)
		(pad "2" smd circle
			(at 0.40005 0)
			(size 0 0)
			(layers "F.Cu" "F.Mask" "F.Paste")
			(net "GPU_3V3IO_RSVD0_FFU")
		)
	)
	(footprint ""
		(layer "F.Cu")
		(at 367.798604 -66.32194 -90)
		(property "Reference" "PC882"
			(at 0 0 270)
			(layer "F.SilkS")
			(hide yes)
			(effects
				(font
					(size 1.27 1.27)
				)
			)
		)
		(property "Value" ""
			(at 0 0 270)
			(layer "F.Fab")
			(effects
				(font
					(size 1.27 1.27)
				)
			)
		)
		(duplicate_pad_numbers_are_jumpers no)
		(fp_line
			(start -0.7874 0.4064)
			(end -0.7874 -0.4064)
			(stroke
				(width 0.1524)
				(type default)
			)
			(layer "F.SilkS")
		)
		(fp_line
			(start 0.7874 0.4064)
			(end -0.7874 0.4064)
			(stroke
				(width 0.1524)
				(type default)
			)
			(layer "F.SilkS")
		)
		(fp_line
			(start -0.7874 -0.4064)
			(end 0.7874 -0.4064)
			(stroke
				(width 0.1524)
				(type default)
			)
			(layer "F.SilkS")
		)
		(fp_line
			(start 0.7874 -0.4064)
			(end 0.7874 0.4064)
			(stroke
				(width 0.1524)
				(type default)
			)
			(layer "F.SilkS")
		)
		(fp_line
			(start -0.67945 0.3048)
			(end -0.67945 -0.305054)
			(stroke
				(width 0.1)
				(type default)
			)
			(layer "F.Fab")
		)
		(fp_line
			(start -0.12065 0.3048)
			(end -0.67945 0.3048)
			(stroke
				(width 0.1)
				(type default)
			)
			(layer "F.Fab")
		)
		(fp_line
			(start 0.120396 0.3048)
			(end 0.120396 0.2794)
			(stroke
				(width 0.1)
				(type default)
			)
			(layer "F.Fab")
		)
		(fp_line
			(start 0.67945 0.3048)
			(end 0.120396 0.3048)
			(stroke
				(width 0.1)
				(type default)
			)
			(layer "F.Fab")
		)
		(fp_line
			(start -0.12065 0.2794)
			(end -0.12065 0.3048)
			(stroke
				(width 0.1)
				(type default)
			)
			(layer "F.Fab")
		)
		(fp_line
			(start 0.120396 0.2794)
			(end -0.12065 0.2794)
			(stroke
				(width 0.1)
				(type default)
			)
			(layer "F.Fab")
		)
		(fp_line
			(start -0.12065 -0.2794)
			(end 0.12065 -0.2794)
			(stroke
				(width 0.1)
				(type default)
			)
			(layer "F.Fab")
		)
		(fp_line
			(start 0.12065 -0.2794)
			(end 0.12065 -0.3048)
			(stroke
				(width 0.1)
				(type default)
			)
			(layer "F.Fab")
		)
		(fp_line
			(start 0.12065 -0.3048)
			(end 0.67945 -0.3048)
			(stroke
				(width 0.1)
				(type default)
			)
			(layer "F.Fab")
		)
		(fp_line
			(start 0.67945 -0.3048)
			(end 0.67945 0.3048)
			(stroke
				(width 0.1)
				(type default)
			)
			(layer "F.Fab")
		)
		(fp_line
			(start -0.67945 -0.305054)
			(end -0.12065 -0.305054)
			(stroke
				(width 0.1)
				(type default)
			)
			(layer "F.Fab")
		)
		(fp_line
			(start -0.12065 -0.305054)
			(end -0.12065 -0.2794)
			(stroke
				(width 0.1)
				(type default)
			)
			(layer "F.Fab")
		)
		(pad "1" smd circle
			(at -0.40005 0 270)
			(size 0 0)
			(layers "F.Cu" "F.Mask" "F.Paste")
			(net "P12V_SSD12_CO_GATE")
		)
		(pad "2" smd circle
			(at 0.40005 0 270)
			(size 0 0)
			(layers "F.Cu" "F.Mask" "F.Paste")
			(net "GND")
		)
	)
	(footprint ""
		(layer "F.Cu")
		(at 484.108506 -524.787368 180)
		(property "Reference" "J34_OTH"
			(at -3.2385 -1.402334 0)
			(unlocked yes)
			(layer "B.SilkS")
			(effects
				(font
					(size 0.7874 0.5842)
					(thickness 0.1524)
				)
				(justify mirror)
			)
		)
		(property "Value" ""
			(at 0 0 180)
			(layer "F.Fab")
			(effects
				(font
					(size 1.27 1.27)
				)
			)
		)
		(duplicate_pad_numbers_are_jumpers no)
		(pad "1" thru_hole circle
			(at 0 0 180)
			(size 0.4572 0.4572)
			(drill 0.2032)
			(layers "*.Cu" "*.Mask")
			(remove_unused_layers no)
			(net "Net_9102")
			(clearance 0.127)
			(thermal_gap 0.127)
			(padstack
				(mode front_inner_back)
				(layer "Inner"
					(shape circle)
					(size 0.4572 0.4572)
					(clearance 0.127)
				)
				(layer "B.Cu"
					(shape circle)
					(size 0.508 0.508)
					(clearance 0.1016)
				)
			)
		)
	)
	(footprint ""
		(layer "F.Cu")
		(at 338.074 -184.023 180)
		(property "Reference" "R4761"
			(at 0 0 180)
			(layer "F.SilkS")
			(hide yes)
			(effects
				(font
					(size 1.27 1.27)
				)
			)
		)
		(property "Value" ""
			(at 0 0 180)
			(layer "F.Fab")
			(effects
				(font
					(size 1.27 1.27)
				)
			)
		)
		(duplicate_pad_numbers_are_jumpers no)
		(fp_line
			(start 0.7874 0.4064)
			(end -0.7874 0.4064)
			(stroke
				(width 0.1524)
				(type default)
			)
			(layer "F.SilkS")
		)
		(fp_line
			(start 0.7874 -0.4064)
			(end 0.7874 0.4064)
			(stroke
				(width 0.1524)
				(type default)
			)
			(layer "F.SilkS")
		)
		(fp_line
			(start -0.7874 0.4064)
			(end -0.7874 -0.4064)
			(stroke
				(width 0.1524)
				(type default)
			)
			(layer "F.SilkS")
		)
		(fp_line
			(start -0.7874 -0.4064)
			(end 0.7874 -0.4064)
			(stroke
				(width 0.1524)
				(type default)
			)
			(layer "F.SilkS")
		)
		(fp_line
			(start 0.67945 0.3048)
			(end 0.120396 0.3048)
			(stroke
				(width 0.1)
				(type default)
			)
			(layer "F.Fab")
		)
		(fp_line
			(start 0.67945 -0.3048)
			(end 0.67945 0.3048)
			(stroke
				(width 0.1)
				(type default)
			)
			(layer "F.Fab")
		)
		(fp_line
			(start 0.12065 -0.2794)
			(end 0.12065 -0.3048)
			(stroke
				(width 0.1)
				(type default)
			)
			(layer "F.Fab")
		)
		(fp_line
			(start 0.12065 -0.3048)
			(end 0.67945 -0.3048)
			(stroke
				(width 0.1)
				(type default)
			)
			(layer "F.Fab")
		)
		(fp_line
			(start 0.120396 0.3048)
			(end 0.120396 0.2794)
			(stroke
				(width 0.1)
				(type default)
			)
			(layer "F.Fab")
		)
		(fp_line
			(start 0.120396 0.2794)
			(end -0.12065 0.2794)
			(stroke
				(width 0.1)
				(type default)
			)
			(layer "F.Fab")
		)
		(fp_line
			(start -0.12065 0.3048)
			(end -0.67945 0.3048)
			(stroke
				(width 0.1)
				(type default)
			)
			(layer "F.Fab")
		)
		(fp_line
			(start -0.12065 0.2794)
			(end -0.12065 0.3048)
			(stroke
				(width 0.1)
				(type default)
			)
			(layer "F.Fab")
		)
		(fp_line
			(start -0.12065 -0.2794)
			(end 0.12065 -0.2794)
			(stroke
				(width 0.1)
				(type default)
			)
			(layer "F.Fab")
		)
		(fp_line
			(start -0.12065 -0.305054)
			(end -0.12065 -0.2794)
			(stroke
				(width 0.1)
				(type default)
			)
			(layer "F.Fab")
		)
		(fp_line
			(start -0.67945 0.3048)
			(end -0.67945 -0.305054)
			(stroke
				(width 0.1)
				(type default)
			)
			(layer "F.Fab")
		)
		(fp_line
			(start -0.67945 -0.305054)
			(end -0.12065 -0.305054)
			(stroke
				(width 0.1)
				(type default)
			)
			(layer "F.Fab")
		)
		(pad "1" smd circle
			(at -0.40005 0 180)
			(size 0 0)
			(layers "F.Cu" "F.Mask" "F.Paste")
			(net "GND")
		)
		(pad "2" smd circle
			(at 0.40005 0 180)
			(size 0 0)
			(layers "F.Cu" "F.Mask" "F.Paste")
			(net "PCA9555_0_PEX2_A2")
		)
	)
	(footprint ""
		(layer "F.Cu")
		(at 379.694186 -29.507688 -90)
		(property "Reference" "PC966"
			(at 0 0 270)
			(layer "F.SilkS")
			(hide yes)
			(effects
				(font
					(size 1.27 1.27)
				)
			)
		)
		(property "Value" ""
			(at 0 0 270)
			(layer "F.Fab")
			(effects
				(font
					(size 1.27 1.27)
				)
			)
		)
		(duplicate_pad_numbers_are_jumpers no)
		(fp_line
			(start -1.524 0.762)
			(end -1.524 -0.762)
			(stroke
				(width 0.1524)
				(type default)
			)
			(layer "F.SilkS")
		)
		(fp_line
			(start 1.524 0.762)
			(end -1.524 0.762)
			(stroke
				(width 0.1524)
				(type default)
			)
			(layer "F.SilkS")
		)
		(fp_line
			(start -1.524 -0.762)
			(end 1.524 -0.762)
			(stroke
				(width 0.1524)
				(type default)
			)
			(layer "F.SilkS")
		)
		(fp_line
			(start 1.524 -0.762)
			(end 1.524 0.762)
			(stroke
				(width 0.1524)
				(type default)
			)
			(layer "F.SilkS")
		)
		(fp_line
			(start -1.1049 0.724916)
			(end 1.1049 0.724916)
			(stroke
				(width 0.1)
				(type default)
			)
			(layer "F.Fab")
		)
		(fp_line
			(start 1.1049 0.724916)
			(end 1.1049 -0.724916)
			(stroke
				(width 0.1)
				(type default)
			)
			(layer "F.Fab")
		)
		(fp_line
			(start -1.1049 -0.724916)
			(end -1.1049 0.724916)
			(stroke
				(width 0.1)
				(type default)
			)
			(layer "F.Fab")
		)
		(fp_line
			(start 1.1049 -0.724916)
			(end -1.1049 -0.724916)
			(stroke
				(width 0.1)
				(type default)
			)
			(layer "F.Fab")
		)
		(pad "1" smd rect
			(at -0.889 0 90)
			(size 1.016 1.27)
			(layers "F.Cu" "F.Mask" "F.Paste")
			(net "P3V3_SSD13")
		)
		(pad "2" smd rect
			(at 0.889 0 90)
			(size 1.016 1.27)
			(layers "F.Cu" "F.Mask" "F.Paste")
			(net "GND")
		)
	)
	(footprint ""
		(layer "F.Cu")
		(at 400.567906 -51.019456)
		(property "Reference" "PC423"
			(at 0 0 0)
			(layer "F.SilkS")
			(hide yes)
			(effects
				(font
					(size 1.27 1.27)
				)
			)
		)
		(property "Value" ""
			(at 0 0 0)
			(layer "F.Fab")
			(effects
				(font
					(size 1.27 1.27)
				)
			)
		)
		(duplicate_pad_numbers_are_jumpers no)
		(fp_line
			(start -0.7874 -0.4064)
			(end 0.7874 -0.4064)
			(stroke
				(width 0.1524)
				(type default)
			)
			(layer "F.SilkS")
		)
		(fp_line
			(start -0.7874 0.4064)
			(end -0.7874 -0.4064)
			(stroke
				(width 0.1524)
				(type default)
			)
			(layer "F.SilkS")
		)
		(fp_line
			(start 0.7874 -0.4064)
			(end 0.7874 0.4064)
			(stroke
				(width 0.1524)
				(type default)
			)
			(layer "F.SilkS")
		)
		(fp_line
			(start 0.7874 0.4064)
			(end -0.7874 0.4064)
			(stroke
				(width 0.1524)
				(type default)
			)
			(layer "F.SilkS")
		)
		(fp_line
			(start -0.67945 -0.305054)
			(end -0.12065 -0.305054)
			(stroke
				(width 0.1)
				(type default)
			)
			(layer "F.Fab")
		)
		(fp_line
			(start -0.67945 0.3048)
			(end -0.67945 -0.305054)
			(stroke
				(width 0.1)
				(type default)
			)
			(layer "F.Fab")
		)
		(fp_line
			(start -0.12065 -0.305054)
			(end -0.12065 -0.2794)
			(stroke
				(width 0.1)
				(type default)
			)
			(layer "F.Fab")
		)
		(fp_line
			(start -0.12065 -0.2794)
			(end 0.12065 -0.2794)
			(stroke
				(width 0.1)
				(type default)
			)
			(layer "F.Fab")
		)
		(fp_line
			(start -0.12065 0.2794)
			(end -0.12065 0.3048)
			(stroke
				(width 0.1)
				(type default)
			)
			(layer "F.Fab")
		)
		(fp_line
			(start -0.12065 0.3048)
			(end -0.67945 0.3048)
			(stroke
				(width 0.1)
				(type default)
			)
			(layer "F.Fab")
		)
		(fp_line
			(start 0.120396 0.2794)
			(end -0.12065 0.2794)
			(stroke
				(width 0.1)
				(type default)
			)
			(layer "F.Fab")
		)
		(fp_line
			(start 0.120396 0.3048)
			(end 0.120396 0.2794)
			(stroke
				(width 0.1)
				(type default)
			)
			(layer "F.Fab")
		)
		(fp_line
			(start 0.12065 -0.3048)
			(end 0.67945 -0.3048)
			(stroke
				(width 0.1)
				(type default)
			)
			(layer "F.Fab")
		)
		(fp_line
			(start 0.12065 -0.2794)
			(end 0.12065 -0.3048)
			(stroke
				(width 0.1)
				(type default)
			)
			(layer "F.Fab")
		)
		(fp_line
			(start 0.67945 -0.3048)
			(end 0.67945 0.3048)
			(stroke
				(width 0.1)
				(type default)
			)
			(layer "F.Fab")
		)
		(fp_line
			(start 0.67945 0.3048)
			(end 0.120396 0.3048)
			(stroke
				(width 0.1)
				(type default)
			)
			(layer "F.Fab")
		)
		(pad "1" smd circle
			(at -0.40005 0)
			(size 0 0)
			(layers "F.Cu" "F.Mask" "F.Paste")
			(net "P12V_SSD13_SS")
		)
		(pad "2" smd circle
			(at 0.40005 0)
			(size 0 0)
			(layers "F.Cu" "F.Mask" "F.Paste")
			(net "GND")
		)
	)
	(footprint ""
		(layer "F.Cu")
		(at 33.854136 -307.415438 45)
		(property "Reference" "R1186"
			(at 0 0 45)
			(layer "F.SilkS")
			(hide yes)
			(effects
				(font
					(size 1.27 1.27)
				)
			)
		)
		(property "Value" ""
			(at 0 0 45)
			(layer "F.Fab")
			(effects
				(font
					(size 1.27 1.27)
				)
			)
		)
		(duplicate_pad_numbers_are_jumpers no)
		(fp_line
			(start -0.787389 -0.406267)
			(end 0.787389 -0.406267)
			(stroke
				(width 0.1524)
				(type default)
			)
			(layer "F.SilkS")
		)
		(fp_line
			(start -0.787389 0.406267)
			(end -0.787389 -0.406267)
			(stroke
				(width 0.1524)
				(type default)
			)
			(layer "F.SilkS")
		)
		(fp_line
			(start 0.787389 -0.406267)
			(end 0.787389 0.406267)
			(stroke
				(width 0.1524)
				(type default)
			)
			(layer "F.SilkS")
		)
		(fp_line
			(start 0.787389 0.406267)
			(end -0.787389 0.406267)
			(stroke
				(width 0.1524)
				(type default)
			)
			(layer "F.SilkS")
		)
		(fp_line
			(start -0.679446 -0.305149)
			(end -0.120695 -0.304969)
			(stroke
				(width 0.1)
				(type default)
			)
			(layer "F.Fab")
		)
		(fp_line
			(start -0.120695 -0.304969)
			(end -0.120695 -0.279466)
			(stroke
				(width 0.1)
				(type default)
			)
			(layer "F.Fab")
		)
		(fp_line
			(start -0.120695 -0.279466)
			(end 0.120695 -0.279466)
			(stroke
				(width 0.1)
				(type default)
			)
			(layer "F.Fab")
		)
		(fp_line
			(start -0.679446 0.30479)
			(end -0.679446 -0.305149)
			(stroke
				(width 0.1)
				(type default)
			)
			(layer "F.Fab")
		)
		(fp_line
			(start 0.120515 -0.30479)
			(end 0.679446 -0.30479)
			(stroke
				(width 0.1)
				(type default)
			)
			(layer "F.Fab")
		)
		(fp_line
			(start 0.120695 -0.279466)
			(end 0.120515 -0.30479)
			(stroke
				(width 0.1)
				(type default)
			)
			(layer "F.Fab")
		)
		(fp_line
			(start -0.120695 0.279466)
			(end -0.120515 0.30479)
			(stroke
				(width 0.1)
				(type default)
			)
			(layer "F.Fab")
		)
		(fp_line
			(start -0.120515 0.30479)
			(end -0.679446 0.30479)
			(stroke
				(width 0.1)
				(type default)
			)
			(layer "F.Fab")
		)
		(fp_line
			(start 0.679446 -0.30479)
			(end 0.679446 0.30479)
			(stroke
				(width 0.1)
				(type default)
			)
			(layer "F.Fab")
		)
		(fp_line
			(start 0.120335 0.279466)
			(end -0.120695 0.279466)
			(stroke
				(width 0.1)
				(type default)
			)
			(layer "F.Fab")
		)
		(fp_line
			(start 0.120515 0.30479)
			(end 0.120335 0.279466)
			(stroke
				(width 0.1)
				(type default)
			)
			(layer "F.Fab")
		)
		(fp_line
			(start 0.679446 0.30479)
			(end 0.120515 0.30479)
			(stroke
				(width 0.1)
				(type default)
			)
			(layer "F.Fab")
		)
		(pad "1" smd circle
			(at -0.40005 0 45)
			(size 0 0)
			(layers "F.Cu" "F.Mask" "F.Paste")
			(net "GND")
		)
		(pad "2" smd circle
			(at 0.40005 0 45)
			(size 0 0)
			(layers "F.Cu" "F.Mask" "F.Paste")
			(net "PEX0_DBG_MODE1")
		)
	)
	(footprint ""
		(layer "F.Cu")
		(at 52.243736 -48.93691 180)
		(property "Reference" "R523"
			(at 0 0 180)
			(layer "F.SilkS")
			(hide yes)
			(effects
				(font
					(size 1.27 1.27)
				)
			)
		)
		(property "Value" ""
			(at 0 0 180)
			(layer "F.Fab")
			(effects
				(font
					(size 1.27 1.27)
				)
			)
		)
		(duplicate_pad_numbers_are_jumpers no)
		(fp_line
			(start 0.7874 0.4064)
			(end -0.7874 0.4064)
			(stroke
				(width 0.1524)
				(type default)
			)
			(layer "F.SilkS")
		)
		(fp_line
			(start 0.7874 -0.4064)
			(end 0.7874 0.4064)
			(stroke
				(width 0.1524)
				(type default)
			)
			(layer "F.SilkS")
		)
		(fp_line
			(start -0.7874 0.4064)
			(end -0.7874 -0.4064)
			(stroke
				(width 0.1524)
				(type default)
			)
			(layer "F.SilkS")
		)
		(fp_line
			(start -0.7874 -0.4064)
			(end 0.7874 -0.4064)
			(stroke
				(width 0.1524)
				(type default)
			)
			(layer "F.SilkS")
		)
		(fp_line
			(start 0.67945 0.3048)
			(end 0.120396 0.3048)
			(stroke
				(width 0.1)
				(type default)
			)
			(layer "F.Fab")
		)
		(fp_line
			(start 0.67945 -0.3048)
			(end 0.67945 0.3048)
			(stroke
				(width 0.1)
				(type default)
			)
			(layer "F.Fab")
		)
		(fp_line
			(start 0.12065 -0.2794)
			(end 0.12065 -0.3048)
			(stroke
				(width 0.1)
				(type default)
			)
			(layer "F.Fab")
		)
		(fp_line
			(start 0.12065 -0.3048)
			(end 0.67945 -0.3048)
			(stroke
				(width 0.1)
				(type default)
			)
			(layer "F.Fab")
		)
		(fp_line
			(start 0.120396 0.3048)
			(end 0.120396 0.2794)
			(stroke
				(width 0.1)
				(type default)
			)
			(layer "F.Fab")
		)
		(fp_line
			(start 0.120396 0.2794)
			(end -0.12065 0.2794)
			(stroke
				(width 0.1)
				(type default)
			)
			(layer "F.Fab")
		)
		(fp_line
			(start -0.12065 0.3048)
			(end -0.67945 0.3048)
			(stroke
				(width 0.1)
				(type default)
			)
			(layer "F.Fab")
		)
		(fp_line
			(start -0.12065 0.2794)
			(end -0.12065 0.3048)
			(stroke
				(width 0.1)
				(type default)
			)
			(layer "F.Fab")
		)
		(fp_line
			(start -0.12065 -0.2794)
			(end 0.12065 -0.2794)
			(stroke
				(width 0.1)
				(type default)
			)
			(layer "F.Fab")
		)
		(fp_line
			(start -0.12065 -0.305054)
			(end -0.12065 -0.2794)
			(stroke
				(width 0.1)
				(type default)
			)
			(layer "F.Fab")
		)
		(fp_line
			(start -0.67945 0.3048)
			(end -0.67945 -0.305054)
			(stroke
				(width 0.1)
				(type default)
			)
			(layer "F.Fab")
		)
		(fp_line
			(start -0.67945 -0.305054)
			(end -0.12065 -0.305054)
			(stroke
				(width 0.1)
				(type default)
			)
			(layer "F.Fab")
		)
		(pad "1" smd circle
			(at -0.40005 0 180)
			(size 0 0)
			(layers "F.Cu" "F.Mask" "F.Paste")
			(net "SMB_BIC_I2C6_MUX_SSD_0_7_ADC_R_SDA")
		)
		(pad "2" smd circle
			(at 0.40005 0 180)
			(size 0 0)
			(layers "F.Cu" "F.Mask" "F.Paste")
			(net "SMB_SSD1_ADC_SDA")
		)
	)
	(footprint ""
		(layer "F.Cu")
		(at 204.591158 -83.659472)
		(property "Reference" "R4331"
			(at 0 0 0)
			(layer "F.SilkS")
			(hide yes)
			(effects
				(font
					(size 1.27 1.27)
				)
			)
		)
		(property "Value" ""
			(at 0 0 0)
			(layer "F.Fab")
			(effects
				(font
					(size 1.27 1.27)
				)
			)
		)
		(duplicate_pad_numbers_are_jumpers no)
		(fp_line
			(start -0.7874 -0.4064)
			(end 0.7874 -0.4064)
			(stroke
				(width 0.1524)
				(type default)
			)
			(layer "F.SilkS")
		)
		(fp_line
			(start -0.7874 0.4064)
			(end -0.7874 -0.4064)
			(stroke
				(width 0.1524)
				(type default)
			)
			(layer "F.SilkS")
		)
		(fp_line
			(start 0.7874 -0.4064)
			(end 0.7874 0.4064)
			(stroke
				(width 0.1524)
				(type default)
			)
			(layer "F.SilkS")
		)
		(fp_line
			(start 0.7874 0.4064)
			(end -0.7874 0.4064)
			(stroke
				(width 0.1524)
				(type default)
			)
			(layer "F.SilkS")
		)
		(fp_line
			(start -0.67945 -0.305054)
			(end -0.12065 -0.305054)
			(stroke
				(width 0.1)
				(type default)
			)
			(layer "F.Fab")
		)
		(fp_line
			(start -0.67945 0.3048)
			(end -0.67945 -0.305054)
			(stroke
				(width 0.1)
				(type default)
			)
			(layer "F.Fab")
		)
		(fp_line
			(start -0.12065 -0.305054)
			(end -0.12065 -0.2794)
			(stroke
				(width 0.1)
				(type default)
			)
			(layer "F.Fab")
		)
		(fp_line
			(start -0.12065 -0.2794)
			(end 0.12065 -0.2794)
			(stroke
				(width 0.1)
				(type default)
			)
			(layer "F.Fab")
		)
		(fp_line
			(start -0.12065 0.2794)
			(end -0.12065 0.3048)
			(stroke
				(width 0.1)
				(type default)
			)
			(layer "F.Fab")
		)
		(fp_line
			(start -0.12065 0.3048)
			(end -0.67945 0.3048)
			(stroke
				(width 0.1)
				(type default)
			)
			(layer "F.Fab")
		)
		(fp_line
			(start 0.120396 0.2794)
			(end -0.12065 0.2794)
			(stroke
				(width 0.1)
				(type default)
			)
			(layer "F.Fab")
		)
		(fp_line
			(start 0.120396 0.3048)
			(end 0.120396 0.2794)
			(stroke
				(width 0.1)
				(type default)
			)
			(layer "F.Fab")
		)
		(fp_line
			(start 0.12065 -0.3048)
			(end 0.67945 -0.3048)
			(stroke
				(width 0.1)
				(type default)
			)
			(layer "F.Fab")
		)
		(fp_line
			(start 0.12065 -0.2794)
			(end 0.12065 -0.3048)
			(stroke
				(width 0.1)
				(type default)
			)
			(layer "F.Fab")
		)
		(fp_line
			(start 0.67945 -0.3048)
			(end 0.67945 0.3048)
			(stroke
				(width 0.1)
				(type default)
			)
			(layer "F.Fab")
		)
		(fp_line
			(start 0.67945 0.3048)
			(end 0.120396 0.3048)
			(stroke
				(width 0.1)
				(type default)
			)
			(layer "F.Fab")
		)
		(pad "1" smd circle
			(at -0.40005 0)
			(size 0 0)
			(layers "F.Cu" "F.Mask" "F.Paste")
			(net "P3V3_AUX")
		)
		(pad "2" smd circle
			(at 0.40005 0)
			(size 0 0)
			(layers "F.Cu" "F.Mask" "F.Paste")
			(net "SSD1_LED_R")
		)
	)
	(footprint ""
		(layer "F.Cu")
		(at 41.984168 -356.244906 90)
		(property "Reference" "C170"
			(at 0 0 90)
			(layer "F.SilkS")
			(hide yes)
			(effects
				(font
					(size 1.27 1.27)
				)
			)
		)
		(property "Value" ""
			(at 0 0 90)
			(layer "F.Fab")
			(effects
				(font
					(size 1.27 1.27)
				)
			)
		)
		(duplicate_pad_numbers_are_jumpers no)
		(fp_line
			(start 0.299974 -0.150114)
			(end 0.299974 0.150114)
			(stroke
				(width 0.1)
				(type default)
			)
			(layer "F.Fab")
		)
		(fp_line
			(start -0.299974 -0.150114)
			(end 0.299974 -0.150114)
			(stroke
				(width 0.1)
				(type default)
			)
			(layer "F.Fab")
		)
		(fp_line
			(start 0.299974 0.150114)
			(end -0.299974 0.150114)
			(stroke
				(width 0.1)
				(type default)
			)
			(layer "F.Fab")
		)
		(fp_line
			(start -0.299974 0.150114)
			(end -0.299974 -0.150114)
			(stroke
				(width 0.1)
				(type default)
			)
			(layer "F.Fab")
		)
		(pad "1" smd rect
			(at -0.2667 0 90)
			(size 0.3048 0.381)
			(layers "F.Cu" "F.Mask" "F.Paste")
			(net "P5E_PEX0_STN7_TX_DN<123>")
		)
		(pad "2" smd rect
			(at 0.2667 0 90)
			(size 0.3048 0.381)
			(layers "F.Cu" "F.Mask" "F.Paste")
			(net "P5E_PEX0_STN7_TX_C_DN<123>")
		)
	)
	(footprint ""
		(layer "F.Cu")
		(at 284.443678 -45.88891)
		(property "Reference" "R609"
			(at 0 0 0)
			(layer "F.SilkS")
			(hide yes)
			(effects
				(font
					(size 1.27 1.27)
				)
			)
		)
		(property "Value" ""
			(at 0 0 0)
			(layer "F.Fab")
			(effects
				(font
					(size 1.27 1.27)
				)
			)
		)
		(duplicate_pad_numbers_are_jumpers no)
		(fp_line
			(start -0.7874 -0.4064)
			(end 0.7874 -0.4064)
			(stroke
				(width 0.1524)
				(type default)
			)
			(layer "F.SilkS")
		)
		(fp_line
			(start -0.7874 0.4064)
			(end -0.7874 -0.4064)
			(stroke
				(width 0.1524)
				(type default)
			)
			(layer "F.SilkS")
		)
		(fp_line
			(start 0.7874 -0.4064)
			(end 0.7874 0.4064)
			(stroke
				(width 0.1524)
				(type default)
			)
			(layer "F.SilkS")
		)
		(fp_line
			(start 0.7874 0.4064)
			(end -0.7874 0.4064)
			(stroke
				(width 0.1524)
				(type default)
			)
			(layer "F.SilkS")
		)
		(fp_line
			(start -0.67945 -0.305054)
			(end -0.12065 -0.305054)
			(stroke
				(width 0.1)
				(type default)
			)
			(layer "F.Fab")
		)
		(fp_line
			(start -0.67945 0.3048)
			(end -0.67945 -0.305054)
			(stroke
				(width 0.1)
				(type default)
			)
			(layer "F.Fab")
		)
		(fp_line
			(start -0.12065 -0.305054)
			(end -0.12065 -0.2794)
			(stroke
				(width 0.1)
				(type default)
			)
			(layer "F.Fab")
		)
		(fp_line
			(start -0.12065 -0.2794)
			(end 0.12065 -0.2794)
			(stroke
				(width 0.1)
				(type default)
			)
			(layer "F.Fab")
		)
		(fp_line
			(start -0.12065 0.2794)
			(end -0.12065 0.3048)
			(stroke
				(width 0.1)
				(type default)
			)
			(layer "F.Fab")
		)
		(fp_line
			(start -0.12065 0.3048)
			(end -0.67945 0.3048)
			(stroke
				(width 0.1)
				(type default)
			)
			(layer "F.Fab")
		)
		(fp_line
			(start 0.120396 0.2794)
			(end -0.12065 0.2794)
			(stroke
				(width 0.1)
				(type default)
			)
			(layer "F.Fab")
		)
		(fp_line
			(start 0.120396 0.3048)
			(end 0.120396 0.2794)
			(stroke
				(width 0.1)
				(type default)
			)
			(layer "F.Fab")
		)
		(fp_line
			(start 0.12065 -0.3048)
			(end 0.67945 -0.3048)
			(stroke
				(width 0.1)
				(type default)
			)
			(layer "F.Fab")
		)
		(fp_line
			(start 0.12065 -0.2794)
			(end 0.12065 -0.3048)
			(stroke
				(width 0.1)
				(type default)
			)
			(layer "F.Fab")
		)
		(fp_line
			(start 0.67945 -0.3048)
			(end 0.67945 0.3048)
			(stroke
				(width 0.1)
				(type default)
			)
			(layer "F.Fab")
		)
		(fp_line
			(start 0.67945 0.3048)
			(end 0.120396 0.3048)
			(stroke
				(width 0.1)
				(type default)
			)
			(layer "F.Fab")
		)
		(pad "1" smd circle
			(at -0.40005 0)
			(size 0 0)
			(layers "F.Cu" "F.Mask" "F.Paste")
			(net "SSD9_ADC_A0")
		)
		(pad "2" smd circle
			(at 0.40005 0)
			(size 0 0)
			(layers "F.Cu" "F.Mask" "F.Paste")
			(net "GND")
		)
	)
	(footprint ""
		(layer "F.Cu")
		(at 292.320472 -26.666444 -90)
		(property "Reference" "R4073"
			(at 0 0 270)
			(layer "F.SilkS")
			(hide yes)
			(effects
				(font
					(size 1.27 1.27)
				)
			)
		)
		(property "Value" ""
			(at 0 0 270)
			(layer "F.Fab")
			(effects
				(font
					(size 1.27 1.27)
				)
			)
		)
		(duplicate_pad_numbers_are_jumpers no)
		(fp_line
			(start -0.7874 0.4064)
			(end -0.7874 -0.4064)
			(stroke
				(width 0.1524)
				(type default)
			)
			(layer "F.SilkS")
		)
		(fp_line
			(start 0.7874 0.4064)
			(end -0.7874 0.4064)
			(stroke
				(width 0.1524)
				(type default)
			)
			(layer "F.SilkS")
		)
		(fp_line
			(start -0.7874 -0.4064)
			(end 0.7874 -0.4064)
			(stroke
				(width 0.1524)
				(type default)
			)
			(layer "F.SilkS")
		)
		(fp_line
			(start 0.7874 -0.4064)
			(end 0.7874 0.4064)
			(stroke
				(width 0.1524)
				(type default)
			)
			(layer "F.SilkS")
		)
		(fp_line
			(start -0.67945 0.3048)
			(end -0.67945 -0.305054)
			(stroke
				(width 0.1)
				(type default)
			)
			(layer "F.Fab")
		)
		(fp_line
			(start -0.12065 0.3048)
			(end -0.67945 0.3048)
			(stroke
				(width 0.1)
				(type default)
			)
			(layer "F.Fab")
		)
		(fp_line
			(start 0.120396 0.3048)
			(end 0.120396 0.2794)
			(stroke
				(width 0.1)
				(type default)
			)
			(layer "F.Fab")
		)
		(fp_line
			(start 0.67945 0.3048)
			(end 0.120396 0.3048)
			(stroke
				(width 0.1)
				(type default)
			)
			(layer "F.Fab")
		)
		(fp_line
			(start -0.12065 0.2794)
			(end -0.12065 0.3048)
			(stroke
				(width 0.1)
				(type default)
			)
			(layer "F.Fab")
		)
		(fp_line
			(start 0.120396 0.2794)
			(end -0.12065 0.2794)
			(stroke
				(width 0.1)
				(type default)
			)
			(layer "F.Fab")
		)
		(fp_line
			(start -0.12065 -0.2794)
			(end 0.12065 -0.2794)
			(stroke
				(width 0.1)
				(type default)
			)
			(layer "F.Fab")
		)
		(fp_line
			(start 0.12065 -0.2794)
			(end 0.12065 -0.3048)
			(stroke
				(width 0.1)
				(type default)
			)
			(layer "F.Fab")
		)
		(fp_line
			(start 0.12065 -0.3048)
			(end 0.67945 -0.3048)
			(stroke
				(width 0.1)
				(type default)
			)
			(layer "F.Fab")
		)
		(fp_line
			(start 0.67945 -0.3048)
			(end 0.67945 0.3048)
			(stroke
				(width 0.1)
				(type default)
			)
			(layer "F.Fab")
		)
		(fp_line
			(start -0.67945 -0.305054)
			(end -0.12065 -0.305054)
			(stroke
				(width 0.1)
				(type default)
			)
			(layer "F.Fab")
		)
		(fp_line
			(start -0.12065 -0.305054)
			(end -0.12065 -0.2794)
			(stroke
				(width 0.1)
				(type default)
			)
			(layer "F.Fab")
		)
		(pad "1" smd circle
			(at -0.40005 0 270)
			(size 0 0)
			(layers "F.Cu" "F.Mask" "F.Paste")
			(net "PRSNT_SSD10_R_N")
		)
		(pad "2" smd circle
			(at 0.40005 0 270)
			(size 0 0)
			(layers "F.Cu" "F.Mask" "F.Paste")
			(net "PRSNT_SSD10_N")
		)
	)
	(footprint ""
		(layer "F.Cu")
		(at 364.342934 -279.486868 -90)
		(property "Reference" "PR163"
			(at 0 0 270)
			(layer "F.SilkS")
			(hide yes)
			(effects
				(font
					(size 1.27 1.27)
				)
			)
		)
		(property "Value" ""
			(at 0 0 270)
			(layer "F.Fab")
			(effects
				(font
					(size 1.27 1.27)
				)
			)
		)
		(duplicate_pad_numbers_are_jumpers no)
		(fp_line
			(start -0.7874 0.4064)
			(end -0.7874 -0.4064)
			(stroke
				(width 0.1524)
				(type default)
			)
			(layer "F.SilkS")
		)
		(fp_line
			(start 0.7874 0.4064)
			(end -0.7874 0.4064)
			(stroke
				(width 0.1524)
				(type default)
			)
			(layer "F.SilkS")
		)
		(fp_line
			(start -0.7874 -0.4064)
			(end 0.7874 -0.4064)
			(stroke
				(width 0.1524)
				(type default)
			)
			(layer "F.SilkS")
		)
		(fp_line
			(start 0.7874 -0.4064)
			(end 0.7874 0.4064)
			(stroke
				(width 0.1524)
				(type default)
			)
			(layer "F.SilkS")
		)
		(fp_line
			(start -0.67945 0.3048)
			(end -0.67945 -0.305054)
			(stroke
				(width 0.1)
				(type default)
			)
			(layer "F.Fab")
		)
		(fp_line
			(start -0.12065 0.3048)
			(end -0.67945 0.3048)
			(stroke
				(width 0.1)
				(type default)
			)
			(layer "F.Fab")
		)
		(fp_line
			(start 0.120396 0.3048)
			(end 0.120396 0.2794)
			(stroke
				(width 0.1)
				(type default)
			)
			(layer "F.Fab")
		)
		(fp_line
			(start 0.67945 0.3048)
			(end 0.120396 0.3048)
			(stroke
				(width 0.1)
				(type default)
			)
			(layer "F.Fab")
		)
		(fp_line
			(start -0.12065 0.2794)
			(end -0.12065 0.3048)
			(stroke
				(width 0.1)
				(type default)
			)
			(layer "F.Fab")
		)
		(fp_line
			(start 0.120396 0.2794)
			(end -0.12065 0.2794)
			(stroke
				(width 0.1)
				(type default)
			)
			(layer "F.Fab")
		)
		(fp_line
			(start -0.12065 -0.2794)
			(end 0.12065 -0.2794)
			(stroke
				(width 0.1)
				(type default)
			)
			(layer "F.Fab")
		)
		(fp_line
			(start 0.12065 -0.2794)
			(end 0.12065 -0.3048)
			(stroke
				(width 0.1)
				(type default)
			)
			(layer "F.Fab")
		)
		(fp_line
			(start 0.12065 -0.3048)
			(end 0.67945 -0.3048)
			(stroke
				(width 0.1)
				(type default)
			)
			(layer "F.Fab")
		)
		(fp_line
			(start 0.67945 -0.3048)
			(end 0.67945 0.3048)
			(stroke
				(width 0.1)
				(type default)
			)
			(layer "F.Fab")
		)
		(fp_line
			(start -0.67945 -0.305054)
			(end -0.12065 -0.305054)
			(stroke
				(width 0.1)
				(type default)
			)
			(layer "F.Fab")
		)
		(fp_line
			(start -0.12065 -0.305054)
			(end -0.12065 -0.2794)
			(stroke
				(width 0.1)
				(type default)
			)
			(layer "F.Fab")
		)
		(pad "1" smd circle
			(at -0.40005 0 270)
			(size 0 0)
			(layers "F.Cu" "F.Mask" "F.Paste")
			(net "P0V8_PEX3_LSET2")
		)
		(pad "2" smd circle
			(at 0.40005 0 270)
			(size 0 0)
			(layers "F.Cu" "F.Mask" "F.Paste")
			(net "GND")
		)
	)
	(footprint ""
		(layer "F.Cu")
		(at 264.670286 -252.356874 -90)
		(property "Reference" "R1364"
			(at 0 0 270)
			(layer "F.SilkS")
			(hide yes)
			(effects
				(font
					(size 1.27 1.27)
				)
			)
		)
		(property "Value" ""
			(at 0 0 270)
			(layer "F.Fab")
			(effects
				(font
					(size 1.27 1.27)
				)
			)
		)
		(duplicate_pad_numbers_are_jumpers no)
		(fp_line
			(start -0.7874 0.4064)
			(end -0.7874 -0.4064)
			(stroke
				(width 0.1524)
				(type default)
			)
			(layer "F.SilkS")
		)
		(fp_line
			(start 0.7874 0.4064)
			(end -0.7874 0.4064)
			(stroke
				(width 0.1524)
				(type default)
			)
			(layer "F.SilkS")
		)
		(fp_line
			(start -0.7874 -0.4064)
			(end 0.7874 -0.4064)
			(stroke
				(width 0.1524)
				(type default)
			)
			(layer "F.SilkS")
		)
		(fp_line
			(start 0.7874 -0.4064)
			(end 0.7874 0.4064)
			(stroke
				(width 0.1524)
				(type default)
			)
			(layer "F.SilkS")
		)
		(fp_line
			(start -0.67945 0.3048)
			(end -0.67945 -0.305054)
			(stroke
				(width 0.1)
				(type default)
			)
			(layer "F.Fab")
		)
		(fp_line
			(start -0.12065 0.3048)
			(end -0.67945 0.3048)
			(stroke
				(width 0.1)
				(type default)
			)
			(layer "F.Fab")
		)
		(fp_line
			(start 0.120396 0.3048)
			(end 0.120396 0.2794)
			(stroke
				(width 0.1)
				(type default)
			)
			(layer "F.Fab")
		)
		(fp_line
			(start 0.67945 0.3048)
			(end 0.120396 0.3048)
			(stroke
				(width 0.1)
				(type default)
			)
			(layer "F.Fab")
		)
		(fp_line
			(start -0.12065 0.2794)
			(end -0.12065 0.3048)
			(stroke
				(width 0.1)
				(type default)
			)
			(layer "F.Fab")
		)
		(fp_line
			(start 0.120396 0.2794)
			(end -0.12065 0.2794)
			(stroke
				(width 0.1)
				(type default)
			)
			(layer "F.Fab")
		)
		(fp_line
			(start -0.12065 -0.2794)
			(end 0.12065 -0.2794)
			(stroke
				(width 0.1)
				(type default)
			)
			(layer "F.Fab")
		)
		(fp_line
			(start 0.12065 -0.2794)
			(end 0.12065 -0.3048)
			(stroke
				(width 0.1)
				(type default)
			)
			(layer "F.Fab")
		)
		(fp_line
			(start 0.12065 -0.3048)
			(end 0.67945 -0.3048)
			(stroke
				(width 0.1)
				(type default)
			)
			(layer "F.Fab")
		)
		(fp_line
			(start 0.67945 -0.3048)
			(end 0.67945 0.3048)
			(stroke
				(width 0.1)
				(type default)
			)
			(layer "F.Fab")
		)
		(fp_line
			(start -0.67945 -0.305054)
			(end -0.12065 -0.305054)
			(stroke
				(width 0.1)
				(type default)
			)
			(layer "F.Fab")
		)
		(fp_line
			(start -0.12065 -0.305054)
			(end -0.12065 -0.2794)
			(stroke
				(width 0.1)
				(type default)
			)
			(layer "F.Fab")
		)
		(pad "1" smd circle
			(at -0.40005 0 270)
			(size 0 0)
			(layers "F.Cu" "F.Mask" "F.Paste")
			(net "GND")
		)
		(pad "2" smd circle
			(at 0.40005 0 270)
			(size 0 0)
			(layers "F.Cu" "F.Mask" "F.Paste")
			(net "PEX2_MODE_SEL8")
		)
	)
	(footprint ""
		(layer "F.Cu")
		(at 377.3805 -356.244906 90)
		(property "Reference" "C768"
			(at 0 0 90)
			(layer "F.SilkS")
			(hide yes)
			(effects
				(font
					(size 1.27 1.27)
				)
			)
		)
		(property "Value" ""
			(at 0 0 90)
			(layer "F.Fab")
			(effects
				(font
					(size 1.27 1.27)
				)
			)
		)
		(duplicate_pad_numbers_are_jumpers no)
		(fp_line
			(start 0.299974 -0.150114)
			(end 0.299974 0.150114)
			(stroke
				(width 0.1)
				(type default)
			)
			(layer "F.Fab")
		)
		(fp_line
			(start -0.299974 -0.150114)
			(end 0.299974 -0.150114)
			(stroke
				(width 0.1)
				(type default)
			)
			(layer "F.Fab")
		)
		(fp_line
			(start 0.299974 0.150114)
			(end -0.299974 0.150114)
			(stroke
				(width 0.1)
				(type default)
			)
			(layer "F.Fab")
		)
		(fp_line
			(start -0.299974 0.150114)
			(end -0.299974 -0.150114)
			(stroke
				(width 0.1)
				(type default)
			)
			(layer "F.Fab")
		)
		(pad "1" smd rect
			(at -0.2667 0 90)
			(size 0.3048 0.381)
			(layers "F.Cu" "F.Mask" "F.Paste")
			(net "P5E_PEX3_STN6_TX_DP<108>")
		)
		(pad "2" smd rect
			(at 0.2667 0 90)
			(size 0.3048 0.381)
			(layers "F.Cu" "F.Mask" "F.Paste")
			(net "P5E_PEX3_STN6_TX_C_DP<108>")
		)
	)
	(footprint ""
		(layer "F.Cu")
		(at 111.291878 -128.170686 90)
		(property "Reference" "PC300"
			(at 0 0 90)
			(layer "F.SilkS")
			(hide yes)
			(effects
				(font
					(size 1.27 1.27)
				)
			)
		)
		(property "Value" ""
			(at 0 0 90)
			(layer "F.Fab")
			(effects
				(font
					(size 1.27 1.27)
				)
			)
		)
		(duplicate_pad_numbers_are_jumpers no)
		(fp_line
			(start 0.7874 -0.4064)
			(end 0.7874 0.4064)
			(stroke
				(width 0.1524)
				(type default)
			)
			(layer "F.SilkS")
		)
		(fp_line
			(start -0.7874 -0.4064)
			(end 0.7874 -0.4064)
			(stroke
				(width 0.1524)
				(type default)
			)
			(layer "F.SilkS")
		)
		(fp_line
			(start 0.7874 0.4064)
			(end -0.7874 0.4064)
			(stroke
				(width 0.1524)
				(type default)
			)
			(layer "F.SilkS")
		)
		(fp_line
			(start -0.7874 0.4064)
			(end -0.7874 -0.4064)
			(stroke
				(width 0.1524)
				(type default)
			)
			(layer "F.SilkS")
		)
		(fp_line
			(start -0.12065 -0.305054)
			(end -0.12065 -0.2794)
			(stroke
				(width 0.1)
				(type default)
			)
			(layer "F.Fab")
		)
		(fp_line
			(start -0.67945 -0.305054)
			(end -0.12065 -0.305054)
			(stroke
				(width 0.1)
				(type default)
			)
			(layer "F.Fab")
		)
		(fp_line
			(start 0.67945 -0.3048)
			(end 0.67945 0.3048)
			(stroke
				(width 0.1)
				(type default)
			)
			(layer "F.Fab")
		)
		(fp_line
			(start 0.12065 -0.3048)
			(end 0.67945 -0.3048)
			(stroke
				(width 0.1)
				(type default)
			)
			(layer "F.Fab")
		)
		(fp_line
			(start 0.12065 -0.2794)
			(end 0.12065 -0.3048)
			(stroke
				(width 0.1)
				(type default)
			)
			(layer "F.Fab")
		)
		(fp_line
			(start -0.12065 -0.2794)
			(end 0.12065 -0.2794)
			(stroke
				(width 0.1)
				(type default)
			)
			(layer "F.Fab")
		)
		(fp_line
			(start 0.120396 0.2794)
			(end -0.12065 0.2794)
			(stroke
				(width 0.1)
				(type default)
			)
			(layer "F.Fab")
		)
		(fp_line
			(start -0.12065 0.2794)
			(end -0.12065 0.3048)
			(stroke
				(width 0.1)
				(type default)
			)
			(layer "F.Fab")
		)
		(fp_line
			(start 0.67945 0.3048)
			(end 0.120396 0.3048)
			(stroke
				(width 0.1)
				(type default)
			)
			(layer "F.Fab")
		)
		(fp_line
			(start 0.120396 0.3048)
			(end 0.120396 0.2794)
			(stroke
				(width 0.1)
				(type default)
			)
			(layer "F.Fab")
		)
		(fp_line
			(start -0.12065 0.3048)
			(end -0.67945 0.3048)
			(stroke
				(width 0.1)
				(type default)
			)
			(layer "F.Fab")
		)
		(fp_line
			(start -0.67945 0.3048)
			(end -0.67945 -0.305054)
			(stroke
				(width 0.1)
				(type default)
			)
			(layer "F.Fab")
		)
		(pad "1" smd circle
			(at -0.40005 0 90)
			(size 0 0)
			(layers "F.Cu" "F.Mask" "F.Paste")
			(net "P3V3")
		)
		(pad "2" smd circle
			(at 0.40005 0 90)
			(size 0 0)
			(layers "F.Cu" "F.Mask" "F.Paste")
			(net "GND")
		)
	)
	(footprint ""
		(layer "F.Cu")
		(at 209.103976 -291.722048 90)
		(property "Reference" "C2756"
			(at 0 0 90)
			(layer "F.SilkS")
			(hide yes)
			(effects
				(font
					(size 1.27 1.27)
				)
			)
		)
		(property "Value" ""
			(at 0 0 90)
			(layer "F.Fab")
			(effects
				(font
					(size 1.27 1.27)
				)
			)
		)
		(duplicate_pad_numbers_are_jumpers no)
		(fp_line
			(start 0.7874 -0.4064)
			(end 0.7874 0.4064)
			(stroke
				(width 0.1524)
				(type default)
			)
			(layer "F.SilkS")
		)
		(fp_line
			(start -0.7874 -0.4064)
			(end 0.7874 -0.4064)
			(stroke
				(width 0.1524)
				(type default)
			)
			(layer "F.SilkS")
		)
		(fp_line
			(start 0.7874 0.4064)
			(end -0.7874 0.4064)
			(stroke
				(width 0.1524)
				(type default)
			)
			(layer "F.SilkS")
		)
		(fp_line
			(start -0.7874 0.4064)
			(end -0.7874 -0.4064)
			(stroke
				(width 0.1524)
				(type default)
			)
			(layer "F.SilkS")
		)
		(fp_line
			(start -0.12065 -0.305054)
			(end -0.12065 -0.2794)
			(stroke
				(width 0.1)
				(type default)
			)
			(layer "F.Fab")
		)
		(fp_line
			(start -0.67945 -0.305054)
			(end -0.12065 -0.305054)
			(stroke
				(width 0.1)
				(type default)
			)
			(layer "F.Fab")
		)
		(fp_line
			(start 0.67945 -0.3048)
			(end 0.67945 0.3048)
			(stroke
				(width 0.1)
				(type default)
			)
			(layer "F.Fab")
		)
		(fp_line
			(start 0.12065 -0.3048)
			(end 0.67945 -0.3048)
			(stroke
				(width 0.1)
				(type default)
			)
			(layer "F.Fab")
		)
		(fp_line
			(start 0.12065 -0.2794)
			(end 0.12065 -0.3048)
			(stroke
				(width 0.1)
				(type default)
			)
			(layer "F.Fab")
		)
		(fp_line
			(start -0.12065 -0.2794)
			(end 0.12065 -0.2794)
			(stroke
				(width 0.1)
				(type default)
			)
			(layer "F.Fab")
		)
		(fp_line
			(start 0.120396 0.2794)
			(end -0.12065 0.2794)
			(stroke
				(width 0.1)
				(type default)
			)
			(layer "F.Fab")
		)
		(fp_line
			(start -0.12065 0.2794)
			(end -0.12065 0.3048)
			(stroke
				(width 0.1)
				(type default)
			)
			(layer "F.Fab")
		)
		(fp_line
			(start 0.67945 0.3048)
			(end 0.120396 0.3048)
			(stroke
				(width 0.1)
				(type default)
			)
			(layer "F.Fab")
		)
		(fp_line
			(start 0.120396 0.3048)
			(end 0.120396 0.2794)
			(stroke
				(width 0.1)
				(type default)
			)
			(layer "F.Fab")
		)
		(fp_line
			(start -0.12065 0.3048)
			(end -0.67945 0.3048)
			(stroke
				(width 0.1)
				(type default)
			)
			(layer "F.Fab")
		)
		(fp_line
			(start -0.67945 0.3048)
			(end -0.67945 -0.305054)
			(stroke
				(width 0.1)
				(type default)
			)
			(layer "F.Fab")
		)
		(pad "1" smd circle
			(at -0.40005 0 90)
			(size 0 0)
			(layers "F.Cu" "F.Mask" "F.Paste")
			(net "GND")
		)
		(pad "2" smd circle
			(at 0.40005 0 90)
			(size 0 0)
			(layers "F.Cu" "F.Mask" "F.Paste")
			(net "P3V3_AUX")
		)
	)
	(footprint ""
		(layer "F.Cu")
		(at 381.43561 -308.13375 -135)
		(property "Reference" "R1401"
			(at 0 0 225)
			(layer "F.SilkS")
			(hide yes)
			(effects
				(font
					(size 1.27 1.27)
				)
			)
		)
		(property "Value" ""
			(at 0 0 225)
			(layer "F.Fab")
			(effects
				(font
					(size 1.27 1.27)
				)
			)
		)
		(duplicate_pad_numbers_are_jumpers no)
		(fp_line
			(start 0.787389 0.406267)
			(end -0.787389 0.406267)
			(stroke
				(width 0.1524)
				(type default)
			)
			(layer "F.SilkS")
		)
		(fp_line
			(start 0.787389 -0.406267)
			(end 0.787389 0.406267)
			(stroke
				(width 0.1524)
				(type default)
			)
			(layer "F.SilkS")
		)
		(fp_line
			(start -0.787389 0.406267)
			(end -0.787389 -0.406267)
			(stroke
				(width 0.1524)
				(type default)
			)
			(layer "F.SilkS")
		)
		(fp_line
			(start -0.787389 -0.406267)
			(end 0.787389 -0.406267)
			(stroke
				(width 0.1524)
				(type default)
			)
			(layer "F.SilkS")
		)
		(fp_line
			(start 0.679446 0.30479)
			(end 0.120515 0.30479)
			(stroke
				(width 0.1)
				(type default)
			)
			(layer "F.Fab")
		)
		(fp_line
			(start 0.120515 0.30479)
			(end 0.120335 0.279466)
			(stroke
				(width 0.1)
				(type default)
			)
			(layer "F.Fab")
		)
		(fp_line
			(start 0.120335 0.279466)
			(end -0.120695 0.279466)
			(stroke
				(width 0.1)
				(type default)
			)
			(layer "F.Fab")
		)
		(fp_line
			(start 0.679446 -0.30479)
			(end 0.679446 0.30479)
			(stroke
				(width 0.1)
				(type default)
			)
			(layer "F.Fab")
		)
		(fp_line
			(start -0.120515 0.30479)
			(end -0.679446 0.30479)
			(stroke
				(width 0.1)
				(type default)
			)
			(layer "F.Fab")
		)
		(fp_line
			(start -0.120695 0.279466)
			(end -0.120515 0.30479)
			(stroke
				(width 0.1)
				(type default)
			)
			(layer "F.Fab")
		)
		(fp_line
			(start 0.120695 -0.279466)
			(end 0.120515 -0.30479)
			(stroke
				(width 0.1)
				(type default)
			)
			(layer "F.Fab")
		)
		(fp_line
			(start 0.120515 -0.30479)
			(end 0.679446 -0.30479)
			(stroke
				(width 0.1)
				(type default)
			)
			(layer "F.Fab")
		)
		(fp_line
			(start -0.679446 0.30479)
			(end -0.679446 -0.305149)
			(stroke
				(width 0.1)
				(type default)
			)
			(layer "F.Fab")
		)
		(fp_line
			(start -0.120695 -0.279466)
			(end 0.120695 -0.279466)
			(stroke
				(width 0.1)
				(type default)
			)
			(layer "F.Fab")
		)
		(fp_line
			(start -0.120695 -0.304969)
			(end -0.120695 -0.279466)
			(stroke
				(width 0.1)
				(type default)
			)
			(layer "F.Fab")
		)
		(fp_line
			(start -0.679446 -0.305149)
			(end -0.120695 -0.304969)
			(stroke
				(width 0.1)
				(type default)
			)
			(layer "F.Fab")
		)
		(pad "1" smd circle
			(at -0.40005 0 225)
			(size 0 0)
			(layers "F.Cu" "F.Mask" "F.Paste")
			(net "PEX3_DBG_MODE1")
		)
		(pad "2" smd circle
			(at 0.40005 0 225)
			(size 0 0)
			(layers "F.Cu" "F.Mask" "F.Paste")
			(net "P1V8_PEX")
		)
	)
	(footprint ""
		(layer "F.Cu")
		(at 338.291424 -268.278102 -90)
		(property "Reference" "PC984"
			(at 0 0 270)
			(layer "F.SilkS")
			(hide yes)
			(effects
				(font
					(size 1.27 1.27)
				)
			)
		)
		(property "Value" ""
			(at 0 0 270)
			(layer "F.Fab")
			(effects
				(font
					(size 1.27 1.27)
				)
			)
		)
		(duplicate_pad_numbers_are_jumpers no)
		(fp_line
			(start -0.7874 0.4064)
			(end -0.7874 -0.4064)
			(stroke
				(width 0.1524)
				(type default)
			)
			(layer "F.SilkS")
		)
		(fp_line
			(start 0.7874 0.4064)
			(end -0.7874 0.4064)
			(stroke
				(width 0.1524)
				(type default)
			)
			(layer "F.SilkS")
		)
		(fp_line
			(start -0.7874 -0.4064)
			(end 0.7874 -0.4064)
			(stroke
				(width 0.1524)
				(type default)
			)
			(layer "F.SilkS")
		)
		(fp_line
			(start 0.7874 -0.4064)
			(end 0.7874 0.4064)
			(stroke
				(width 0.1524)
				(type default)
			)
			(layer "F.SilkS")
		)
		(fp_line
			(start -0.67945 0.3048)
			(end -0.67945 -0.305054)
			(stroke
				(width 0.1)
				(type default)
			)
			(layer "F.Fab")
		)
		(fp_line
			(start -0.12065 0.3048)
			(end -0.67945 0.3048)
			(stroke
				(width 0.1)
				(type default)
			)
			(layer "F.Fab")
		)
		(fp_line
			(start 0.120396 0.3048)
			(end 0.120396 0.2794)
			(stroke
				(width 0.1)
				(type default)
			)
			(layer "F.Fab")
		)
		(fp_line
			(start 0.67945 0.3048)
			(end 0.120396 0.3048)
			(stroke
				(width 0.1)
				(type default)
			)
			(layer "F.Fab")
		)
		(fp_line
			(start -0.12065 0.2794)
			(end -0.12065 0.3048)
			(stroke
				(width 0.1)
				(type default)
			)
			(layer "F.Fab")
		)
		(fp_line
			(start 0.120396 0.2794)
			(end -0.12065 0.2794)
			(stroke
				(width 0.1)
				(type default)
			)
			(layer "F.Fab")
		)
		(fp_line
			(start -0.12065 -0.2794)
			(end 0.12065 -0.2794)
			(stroke
				(width 0.1)
				(type default)
			)
			(layer "F.Fab")
		)
		(fp_line
			(start 0.12065 -0.2794)
			(end 0.12065 -0.3048)
			(stroke
				(width 0.1)
				(type default)
			)
			(layer "F.Fab")
		)
		(fp_line
			(start 0.12065 -0.3048)
			(end 0.67945 -0.3048)
			(stroke
				(width 0.1)
				(type default)
			)
			(layer "F.Fab")
		)
		(fp_line
			(start 0.67945 -0.3048)
			(end 0.67945 0.3048)
			(stroke
				(width 0.1)
				(type default)
			)
			(layer "F.Fab")
		)
		(fp_line
			(start -0.67945 -0.305054)
			(end -0.12065 -0.305054)
			(stroke
				(width 0.1)
				(type default)
			)
			(layer "F.Fab")
		)
		(fp_line
			(start -0.12065 -0.305054)
			(end -0.12065 -0.2794)
			(stroke
				(width 0.1)
				(type default)
			)
			(layer "F.Fab")
		)
		(pad "1" smd circle
			(at -0.40005 0 270)
			(size 0 0)
			(layers "F.Cu" "F.Mask" "F.Paste")
			(net "P12V_AUX")
		)
		(pad "2" smd circle
			(at 0.40005 0 270)
			(size 0 0)
			(layers "F.Cu" "F.Mask" "F.Paste")
			(net "GND")
		)
	)
	(footprint ""
		(layer "F.Cu")
		(at 434.29428 -304.31486 90)
		(property "Reference" "R3994"
			(at 0 0 90)
			(layer "F.SilkS")
			(hide yes)
			(effects
				(font
					(size 1.27 1.27)
				)
			)
		)
		(property "Value" ""
			(at 0 0 90)
			(layer "F.Fab")
			(effects
				(font
					(size 1.27 1.27)
				)
			)
		)
		(duplicate_pad_numbers_are_jumpers no)
		(fp_line
			(start 0.7874 -0.4064)
			(end 0.7874 0.4064)
			(stroke
				(width 0.1524)
				(type default)
			)
			(layer "F.SilkS")
		)
		(fp_line
			(start -0.7874 -0.4064)
			(end 0.7874 -0.4064)
			(stroke
				(width 0.1524)
				(type default)
			)
			(layer "F.SilkS")
		)
		(fp_line
			(start 0.7874 0.4064)
			(end -0.7874 0.4064)
			(stroke
				(width 0.1524)
				(type default)
			)
			(layer "F.SilkS")
		)
		(fp_line
			(start -0.7874 0.4064)
			(end -0.7874 -0.4064)
			(stroke
				(width 0.1524)
				(type default)
			)
			(layer "F.SilkS")
		)
		(fp_line
			(start -0.12065 -0.305054)
			(end -0.12065 -0.2794)
			(stroke
				(width 0.1)
				(type default)
			)
			(layer "F.Fab")
		)
		(fp_line
			(start -0.67945 -0.305054)
			(end -0.12065 -0.305054)
			(stroke
				(width 0.1)
				(type default)
			)
			(layer "F.Fab")
		)
		(fp_line
			(start 0.67945 -0.3048)
			(end 0.67945 0.3048)
			(stroke
				(width 0.1)
				(type default)
			)
			(layer "F.Fab")
		)
		(fp_line
			(start 0.12065 -0.3048)
			(end 0.67945 -0.3048)
			(stroke
				(width 0.1)
				(type default)
			)
			(layer "F.Fab")
		)
		(fp_line
			(start 0.12065 -0.2794)
			(end 0.12065 -0.3048)
			(stroke
				(width 0.1)
				(type default)
			)
			(layer "F.Fab")
		)
		(fp_line
			(start -0.12065 -0.2794)
			(end 0.12065 -0.2794)
			(stroke
				(width 0.1)
				(type default)
			)
			(layer "F.Fab")
		)
		(fp_line
			(start 0.120396 0.2794)
			(end -0.12065 0.2794)
			(stroke
				(width 0.1)
				(type default)
			)
			(layer "F.Fab")
		)
		(fp_line
			(start -0.12065 0.2794)
			(end -0.12065 0.3048)
			(stroke
				(width 0.1)
				(type default)
			)
			(layer "F.Fab")
		)
		(fp_line
			(start 0.67945 0.3048)
			(end 0.120396 0.3048)
			(stroke
				(width 0.1)
				(type default)
			)
			(layer "F.Fab")
		)
		(fp_line
			(start 0.120396 0.3048)
			(end 0.120396 0.2794)
			(stroke
				(width 0.1)
				(type default)
			)
			(layer "F.Fab")
		)
		(fp_line
			(start -0.12065 0.3048)
			(end -0.67945 0.3048)
			(stroke
				(width 0.1)
				(type default)
			)
			(layer "F.Fab")
		)
		(fp_line
			(start -0.67945 0.3048)
			(end -0.67945 -0.305054)
			(stroke
				(width 0.1)
				(type default)
			)
			(layer "F.Fab")
		)
		(pad "1" smd circle
			(at -0.40005 0 90)
			(size 0 0)
			(layers "F.Cu" "F.Mask" "F.Paste")
			(net "SMB_PEX3_SLAVE_SCL")
		)
		(pad "2" smd circle
			(at 0.40005 0 90)
			(size 0 0)
			(layers "F.Cu" "F.Mask" "F.Paste")
			(net "SMB_PEX3_R_SCL")
		)
	)
	(footprint ""
		(layer "F.Cu")
		(at 183.326024 8.083804)
		(property "Reference" "DE11T_2"
			(at -3.6068 -2.962148 0)
			(unlocked yes)
			(layer "F.SilkS")
			(effects
				(font
					(size 0.7874 0.5842)
					(thickness 0.1524)
				)
				(justify left)
			)
		)
		(property "Value" ""
			(at 0 0 0)
			(layer "F.Fab")
			(effects
				(font
					(size 1.27 1.27)
				)
			)
		)
		(duplicate_pad_numbers_are_jumpers no)
		(fp_line
			(start -1.2192 -2.1082)
			(end 1.2192 -2.1082)
			(stroke
				(width 0.1524)
				(type default)
			)
			(layer "F.SilkS")
		)
		(fp_line
			(start -1.2192 2.1082)
			(end -1.2192 -2.1082)
			(stroke
				(width 0.1524)
				(type default)
			)
			(layer "F.SilkS")
		)
		(fp_line
			(start 1.2192 -2.1082)
			(end 1.2192 2.1082)
			(stroke
				(width 0.1524)
				(type default)
			)
			(layer "F.SilkS")
		)
		(fp_line
			(start 1.2192 2.1082)
			(end -1.2192 2.1082)
			(stroke
				(width 0.1524)
				(type default)
			)
			(layer "F.SilkS")
		)
		(pad "" np_thru_hole circle
			(at -2.8829 -1.27 270)
			(size 1.0414 1.0414)
			(drill 1.0414)
			(layers "*.Cu" "*.Mask")
			(clearance 0.381)
			(thermal_gap 0.381)
		)
		(pad "" np_thru_hole circle
			(at -2.8829 1.27 270)
			(size 1.0414 1.0414)
			(drill 1.0414)
			(layers "*.Cu" "*.Mask")
			(clearance 0.381)
			(thermal_gap 0.381)
		)
		(pad "" np_thru_hole circle
			(at 3.4671 -1.27 270)
			(size 1.0414 1.0414)
			(drill 1.0414)
			(layers "*.Cu" "*.Mask")
			(clearance 0.381)
			(thermal_gap 0.381)
		)
		(pad "" np_thru_hole circle
			(at 3.4671 1.27 270)
			(size 1.0414 1.0414)
			(drill 1.0414)
			(layers "*.Cu" "*.Mask")
			(clearance 0.381)
			(thermal_gap 0.381)
		)
		(pad "1" smd rect
			(at 0.8255 -0.249936 270)
			(size 0.3048 0.508)
			(layers "F.Cu" "F.Mask" "F.Paste")
			(net "85_10INCH_TOP_DP")
		)
		(pad "2" smd rect
			(at 0.8255 0.249936 270)
			(size 0.3048 0.508)
			(layers "F.Cu" "F.Mask" "F.Paste")
			(net "85_10INCH_TOP_DN")
		)
		(pad "3" smd circle
			(at 0 0)
			(size 0 0)
			(layers "F.Cu" "F.Mask" "F.Paste")
			(net "COUPON_GND2")
		)
		(zone
			(layer "F.Cu")
			(hatch none 0.5)
			(connect_pads
				(clearance 0)
			)
			(min_thickness 0.25)
			(keepout
				(tracks not_allowed)
				(vias allowed)
				(pads allowed)
				(copperpour not_allowed)
				(footprints allowed)
			)
			(placement
				(enabled no)
				(sheetname "")
			)
			(fill
				(thermal_gap 0.5)
				(thermal_bridge_width 0.5)
				(island_removal_mode 0)
			)
			(polygon
				(pts
					(xy 184.443624 7.535164) (xy 184.443624 7.630668) (xy 183.846724 7.630668) (xy 183.846724 8.037068)
					(xy 184.443624 8.037068) (xy 184.443624 8.13054) (xy 183.846724 8.13054) (xy 183.846724 8.53694)
					(xy 184.443624 8.53694) (xy 184.443624 8.632444) (xy 183.745124 8.632444) (xy 183.745124 7.535164)
				)
			)
		)
		(zone
			(layers "F.Cu" "B.Cu" "In1.Cu" "In2.Cu" "In3.Cu" "In4.Cu" "In5.Cu" "In6.Cu"
				"In7.Cu" "In8.Cu" "In9.Cu" "In10.Cu" "In11.Cu" "In12.Cu" "In13.Cu" "In14.Cu"
				"In15.Cu" "In16.Cu"
			)
			(hatch none 0.5)
			(connect_pads
				(clearance 0)
			)
			(min_thickness 0.25)
			(keepout
				(tracks not_allowed)
				(vias allowed)
				(pads allowed)
				(copperpour not_allowed)
				(footprints allowed)
			)
			(placement
				(enabled no)
				(sheetname "")
			)
			(fill
				(thermal_gap 0.5)
				(thermal_bridge_width 0.5)
				(island_removal_mode 0)
			)
			(polygon
				(pts
					(arc
						(start 181.370224 6.813804)
						(mid 179.516024 6.813804)
						(end 181.370224 6.813804)
					)
				)
			)
		)
		(zone
			(layers "F.Cu" "B.Cu" "In1.Cu" "In2.Cu" "In3.Cu" "In4.Cu" "In5.Cu" "In6.Cu"
				"In7.Cu" "In8.Cu" "In9.Cu" "In10.Cu" "In11.Cu" "In12.Cu" "In13.Cu" "In14.Cu"
				"In15.Cu" "In16.Cu"
			)
			(hatch none 0.5)
			(connect_pads
				(clearance 0)
			)
			(min_thickness 0.25)
			(keepout
				(tracks not_allowed)
				(vias allowed)
				(pads allowed)
				(copperpour not_allowed)
				(footprints allowed)
			)
			(placement
				(enabled no)
				(sheetname "")
			)
			(fill
				(thermal_gap 0.5)
				(thermal_bridge_width 0.5)
				(island_removal_mode 0)
			)
			(polygon
				(pts
					(arc
						(start 181.370224 9.353804)
						(mid 179.516024 9.353804)
						(end 181.370224 9.353804)
					)
				)
			)
		)
		(zone
			(layers "F.Cu" "B.Cu" "In1.Cu" "In2.Cu" "In3.Cu" "In4.Cu" "In5.Cu" "In6.Cu"
				"In7.Cu" "In8.Cu" "In9.Cu" "In10.Cu" "In11.Cu" "In12.Cu" "In13.Cu" "In14.Cu"
				"In15.Cu" "In16.Cu"
			)
			(hatch none 0.5)
			(connect_pads
				(clearance 0)
			)
			(min_thickness 0.25)
			(keepout
				(tracks not_allowed)
				(vias allowed)
				(pads allowed)
				(copperpour not_allowed)
				(footprints allowed)
			)
			(placement
				(enabled no)
				(sheetname "")
			)
			(fill
				(thermal_gap 0.5)
				(thermal_bridge_width 0.5)
				(island_removal_mode 0)
			)
			(polygon
				(pts
					(arc
						(start 187.720224 6.813804)
						(mid 185.866024 6.813804)
						(end 187.720224 6.813804)
					)
				)
			)
		)
		(zone
			(layers "F.Cu" "B.Cu" "In1.Cu" "In2.Cu" "In3.Cu" "In4.Cu" "In5.Cu" "In6.Cu"
				"In7.Cu" "In8.Cu" "In9.Cu" "In10.Cu" "In11.Cu" "In12.Cu" "In13.Cu" "In14.Cu"
				"In15.Cu" "In16.Cu"
			)
			(hatch none 0.5)
			(connect_pads
				(clearance 0)
			)
			(min_thickness 0.25)
			(keepout
				(tracks not_allowed)
				(vias allowed)
				(pads allowed)
				(copperpour not_allowed)
				(footprints allowed)
			)
			(placement
				(enabled no)
				(sheetname "")
			)
			(fill
				(thermal_gap 0.5)
				(thermal_bridge_width 0.5)
				(island_removal_mode 0)
			)
			(polygon
				(pts
					(arc
						(start 187.720224 9.353804)
						(mid 185.866024 9.353804)
						(end 187.720224 9.353804)
					)
				)
			)
		)
	)
	(footprint ""
		(layer "F.Cu")
		(at 470.347548 -538.74416 180)
		(property "Reference" "J44_OTH"
			(at -3.2385 -1.402334 0)
			(unlocked yes)
			(layer "B.SilkS")
			(effects
				(font
					(size 0.7874 0.5842)
					(thickness 0.1524)
				)
				(justify mirror)
			)
		)
		(property "Value" ""
			(at 0 0 180)
			(layer "F.Fab")
			(effects
				(font
					(size 1.27 1.27)
				)
			)
		)
		(duplicate_pad_numbers_are_jumpers no)
		(pad "1" thru_hole circle
			(at 0 0 180)
			(size 0.4572 0.4572)
			(drill 0.2032)
			(layers "*.Cu" "*.Mask")
			(remove_unused_layers no)
			(net "Net_9092")
			(clearance 0.127)
			(thermal_gap 0.127)
			(padstack
				(mode front_inner_back)
				(layer "Inner"
					(shape circle)
					(size 0.4572 0.4572)
					(clearance 0.127)
				)
				(layer "B.Cu"
					(shape circle)
					(size 0.508 0.508)
					(clearance 0.1016)
				)
			)
		)
	)
	(footprint ""
		(layer "F.Cu")
		(at 284.467808 -52.035456 180)
		(property "Reference" "R871"
			(at 0 0 180)
			(layer "F.SilkS")
			(hide yes)
			(effects
				(font
					(size 1.27 1.27)
				)
			)
		)
		(property "Value" ""
			(at 0 0 180)
			(layer "F.Fab")
			(effects
				(font
					(size 1.27 1.27)
				)
			)
		)
		(duplicate_pad_numbers_are_jumpers no)
		(fp_line
			(start 0.7874 0.4064)
			(end -0.7874 0.4064)
			(stroke
				(width 0.1524)
				(type default)
			)
			(layer "F.SilkS")
		)
		(fp_line
			(start 0.7874 -0.4064)
			(end 0.7874 0.4064)
			(stroke
				(width 0.1524)
				(type default)
			)
			(layer "F.SilkS")
		)
		(fp_line
			(start -0.7874 0.4064)
			(end -0.7874 -0.4064)
			(stroke
				(width 0.1524)
				(type default)
			)
			(layer "F.SilkS")
		)
		(fp_line
			(start -0.7874 -0.4064)
			(end 0.7874 -0.4064)
			(stroke
				(width 0.1524)
				(type default)
			)
			(layer "F.SilkS")
		)
		(fp_line
			(start 0.67945 0.3048)
			(end 0.120396 0.3048)
			(stroke
				(width 0.1)
				(type default)
			)
			(layer "F.Fab")
		)
		(fp_line
			(start 0.67945 -0.3048)
			(end 0.67945 0.3048)
			(stroke
				(width 0.1)
				(type default)
			)
			(layer "F.Fab")
		)
		(fp_line
			(start 0.12065 -0.2794)
			(end 0.12065 -0.3048)
			(stroke
				(width 0.1)
				(type default)
			)
			(layer "F.Fab")
		)
		(fp_line
			(start 0.12065 -0.3048)
			(end 0.67945 -0.3048)
			(stroke
				(width 0.1)
				(type default)
			)
			(layer "F.Fab")
		)
		(fp_line
			(start 0.120396 0.3048)
			(end 0.120396 0.2794)
			(stroke
				(width 0.1)
				(type default)
			)
			(layer "F.Fab")
		)
		(fp_line
			(start 0.120396 0.2794)
			(end -0.12065 0.2794)
			(stroke
				(width 0.1)
				(type default)
			)
			(layer "F.Fab")
		)
		(fp_line
			(start -0.12065 0.3048)
			(end -0.67945 0.3048)
			(stroke
				(width 0.1)
				(type default)
			)
			(layer "F.Fab")
		)
		(fp_line
			(start -0.12065 0.2794)
			(end -0.12065 0.3048)
			(stroke
				(width 0.1)
				(type default)
			)
			(layer "F.Fab")
		)
		(fp_line
			(start -0.12065 -0.2794)
			(end 0.12065 -0.2794)
			(stroke
				(width 0.1)
				(type default)
			)
			(layer "F.Fab")
		)
		(fp_line
			(start -0.12065 -0.305054)
			(end -0.12065 -0.2794)
			(stroke
				(width 0.1)
				(type default)
			)
			(layer "F.Fab")
		)
		(fp_line
			(start -0.67945 0.3048)
			(end -0.67945 -0.305054)
			(stroke
				(width 0.1)
				(type default)
			)
			(layer "F.Fab")
		)
		(fp_line
			(start -0.67945 -0.305054)
			(end -0.12065 -0.305054)
			(stroke
				(width 0.1)
				(type default)
			)
			(layer "F.Fab")
		)
		(pad "1" smd circle
			(at -0.40005 0 180)
			(size 0 0)
			(layers "F.Cu" "F.Mask" "F.Paste")
			(net "P3V3_AUX")
		)
		(pad "2" smd circle
			(at 0.40005 0 180)
			(size 0 0)
			(layers "F.Cu" "F.Mask" "F.Paste")
			(net "PWRGD_P12V_SSD9")
		)
	)
	(footprint ""
		(layer "F.Cu")
		(at 339.523324 -279.486868 -90)
		(property "Reference" "PR151"
			(at 0 0 270)
			(layer "F.SilkS")
			(hide yes)
			(effects
				(font
					(size 1.27 1.27)
				)
			)
		)
		(property "Value" ""
			(at 0 0 270)
			(layer "F.Fab")
			(effects
				(font
					(size 1.27 1.27)
				)
			)
		)
		(duplicate_pad_numbers_are_jumpers no)
		(fp_line
			(start -0.7874 0.4064)
			(end -0.7874 -0.4064)
			(stroke
				(width 0.1524)
				(type default)
			)
			(layer "F.SilkS")
		)
		(fp_line
			(start 0.7874 0.4064)
			(end -0.7874 0.4064)
			(stroke
				(width 0.1524)
				(type default)
			)
			(layer "F.SilkS")
		)
		(fp_line
			(start -0.7874 -0.4064)
			(end 0.7874 -0.4064)
			(stroke
				(width 0.1524)
				(type default)
			)
			(layer "F.SilkS")
		)
		(fp_line
			(start 0.7874 -0.4064)
			(end 0.7874 0.4064)
			(stroke
				(width 0.1524)
				(type default)
			)
			(layer "F.SilkS")
		)
		(fp_line
			(start -0.67945 0.3048)
			(end -0.67945 -0.305054)
			(stroke
				(width 0.1)
				(type default)
			)
			(layer "F.Fab")
		)
		(fp_line
			(start -0.12065 0.3048)
			(end -0.67945 0.3048)
			(stroke
				(width 0.1)
				(type default)
			)
			(layer "F.Fab")
		)
		(fp_line
			(start 0.120396 0.3048)
			(end 0.120396 0.2794)
			(stroke
				(width 0.1)
				(type default)
			)
			(layer "F.Fab")
		)
		(fp_line
			(start 0.67945 0.3048)
			(end 0.120396 0.3048)
			(stroke
				(width 0.1)
				(type default)
			)
			(layer "F.Fab")
		)
		(fp_line
			(start -0.12065 0.2794)
			(end -0.12065 0.3048)
			(stroke
				(width 0.1)
				(type default)
			)
			(layer "F.Fab")
		)
		(fp_line
			(start 0.120396 0.2794)
			(end -0.12065 0.2794)
			(stroke
				(width 0.1)
				(type default)
			)
			(layer "F.Fab")
		)
		(fp_line
			(start -0.12065 -0.2794)
			(end 0.12065 -0.2794)
			(stroke
				(width 0.1)
				(type default)
			)
			(layer "F.Fab")
		)
		(fp_line
			(start 0.12065 -0.2794)
			(end 0.12065 -0.3048)
			(stroke
				(width 0.1)
				(type default)
			)
			(layer "F.Fab")
		)
		(fp_line
			(start 0.12065 -0.3048)
			(end 0.67945 -0.3048)
			(stroke
				(width 0.1)
				(type default)
			)
			(layer "F.Fab")
		)
		(fp_line
			(start 0.67945 -0.3048)
			(end 0.67945 0.3048)
			(stroke
				(width 0.1)
				(type default)
			)
			(layer "F.Fab")
		)
		(fp_line
			(start -0.67945 -0.305054)
			(end -0.12065 -0.305054)
			(stroke
				(width 0.1)
				(type default)
			)
			(layer "F.Fab")
		)
		(fp_line
			(start -0.12065 -0.305054)
			(end -0.12065 -0.2794)
			(stroke
				(width 0.1)
				(type default)
			)
			(layer "F.Fab")
		)
		(pad "1" smd circle
			(at -0.40005 0 270)
			(size 0 0)
			(layers "F.Cu" "F.Mask" "F.Paste")
			(net "P0V8_PEX2_LSET1")
		)
		(pad "2" smd circle
			(at 0.40005 0 270)
			(size 0 0)
			(layers "F.Cu" "F.Mask" "F.Paste")
			(net "GND")
		)
	)
	(footprint ""
		(layer "F.Cu")
		(at 362.953808 -162.003994 -90)
		(property "Reference" "R960"
			(at 0 0 270)
			(layer "F.SilkS")
			(hide yes)
			(effects
				(font
					(size 1.27 1.27)
				)
			)
		)
		(property "Value" ""
			(at 0 0 270)
			(layer "F.Fab")
			(effects
				(font
					(size 1.27 1.27)
				)
			)
		)
		(duplicate_pad_numbers_are_jumpers no)
		(fp_line
			(start -0.7874 0.4064)
			(end -0.7874 -0.4064)
			(stroke
				(width 0.1524)
				(type default)
			)
			(layer "F.SilkS")
		)
		(fp_line
			(start 0.7874 0.4064)
			(end -0.7874 0.4064)
			(stroke
				(width 0.1524)
				(type default)
			)
			(layer "F.SilkS")
		)
		(fp_line
			(start -0.7874 -0.4064)
			(end 0.7874 -0.4064)
			(stroke
				(width 0.1524)
				(type default)
			)
			(layer "F.SilkS")
		)
		(fp_line
			(start 0.7874 -0.4064)
			(end 0.7874 0.4064)
			(stroke
				(width 0.1524)
				(type default)
			)
			(layer "F.SilkS")
		)
		(fp_line
			(start -0.67945 0.3048)
			(end -0.67945 -0.305054)
			(stroke
				(width 0.1)
				(type default)
			)
			(layer "F.Fab")
		)
		(fp_line
			(start -0.12065 0.3048)
			(end -0.67945 0.3048)
			(stroke
				(width 0.1)
				(type default)
			)
			(layer "F.Fab")
		)
		(fp_line
			(start 0.120396 0.3048)
			(end 0.120396 0.2794)
			(stroke
				(width 0.1)
				(type default)
			)
			(layer "F.Fab")
		)
		(fp_line
			(start 0.67945 0.3048)
			(end 0.120396 0.3048)
			(stroke
				(width 0.1)
				(type default)
			)
			(layer "F.Fab")
		)
		(fp_line
			(start -0.12065 0.2794)
			(end -0.12065 0.3048)
			(stroke
				(width 0.1)
				(type default)
			)
			(layer "F.Fab")
		)
		(fp_line
			(start 0.120396 0.2794)
			(end -0.12065 0.2794)
			(stroke
				(width 0.1)
				(type default)
			)
			(layer "F.Fab")
		)
		(fp_line
			(start -0.12065 -0.2794)
			(end 0.12065 -0.2794)
			(stroke
				(width 0.1)
				(type default)
			)
			(layer "F.Fab")
		)
		(fp_line
			(start 0.12065 -0.2794)
			(end 0.12065 -0.3048)
			(stroke
				(width 0.1)
				(type default)
			)
			(layer "F.Fab")
		)
		(fp_line
			(start 0.12065 -0.3048)
			(end 0.67945 -0.3048)
			(stroke
				(width 0.1)
				(type default)
			)
			(layer "F.Fab")
		)
		(fp_line
			(start 0.67945 -0.3048)
			(end 0.67945 0.3048)
			(stroke
				(width 0.1)
				(type default)
			)
			(layer "F.Fab")
		)
		(fp_line
			(start -0.67945 -0.305054)
			(end -0.12065 -0.305054)
			(stroke
				(width 0.1)
				(type default)
			)
			(layer "F.Fab")
		)
		(fp_line
			(start -0.12065 -0.305054)
			(end -0.12065 -0.2794)
			(stroke
				(width 0.1)
				(type default)
			)
			(layer "F.Fab")
		)
		(pad "1" smd circle
			(at -0.40005 0 270)
			(size 0 0)
			(layers "F.Cu" "F.Mask" "F.Paste")
			(net "GND")
		)
		(pad "2" smd circle
			(at 0.40005 0 270)
			(size 0 0)
			(layers "F.Cu" "F.Mask" "F.Paste")
			(net "P12V_NIC6_CO_EN")
		)
	)
	(footprint ""
		(layer "F.Cu")
		(at 451.298056 -266.996672 180)
		(property "Reference" "L130"
			(at 0 0 180)
			(layer "F.SilkS")
			(hide yes)
			(effects
				(font
					(size 1.27 1.27)
				)
			)
		)
		(property "Value" ""
			(at 0 0 180)
			(layer "F.Fab")
			(effects
				(font
					(size 1.27 1.27)
				)
			)
		)
		(duplicate_pad_numbers_are_jumpers no)
		(fp_line
			(start 2.248154 4.9911)
			(end 2.248154 1.680464)
			(stroke
				(width 0.1524)
				(type default)
			)
			(layer "F.SilkS")
		)
		(fp_line
			(start 2.248154 -1.701292)
			(end 2.248154 -4.9911)
			(stroke
				(width 0.1524)
				(type default)
			)
			(layer "F.SilkS")
		)
		(fp_line
			(start 2.248154 -4.9911)
			(end -2.248154 -4.9911)
			(stroke
				(width 0.1524)
				(type default)
			)
			(layer "F.SilkS")
		)
		(fp_line
			(start -2.248154 4.9911)
			(end 2.248154 4.9911)
			(stroke
				(width 0.1524)
				(type default)
			)
			(layer "F.SilkS")
		)
		(fp_line
			(start -2.248154 1.790192)
			(end -2.248154 4.9911)
			(stroke
				(width 0.1524)
				(type default)
			)
			(layer "F.SilkS")
		)
		(fp_line
			(start -2.248154 -4.9911)
			(end -2.248154 -1.701292)
			(stroke
				(width 0.1524)
				(type default)
			)
			(layer "F.SilkS")
		)
		(fp_line
			(start 1.700022 0.899922)
			(end 1.700022 -0.899922)
			(stroke
				(width 0.1)
				(type default)
			)
			(layer "F.Fab")
		)
		(fp_line
			(start 1.700022 -0.899922)
			(end -1.700022 -0.899922)
			(stroke
				(width 0.1)
				(type default)
			)
			(layer "F.Fab")
		)
		(fp_line
			(start -1.700022 0.899922)
			(end 1.700022 0.899922)
			(stroke
				(width 0.1)
				(type default)
			)
			(layer "F.Fab")
		)
		(fp_line
			(start -1.700022 -0.899922)
			(end -1.700022 0.899922)
			(stroke
				(width 0.1)
				(type default)
			)
			(layer "F.Fab")
		)
		(pad "1" smd rect
			(at -1.575054 0 180)
			(size 1.1684 9.8044)
			(layers "F.Cu" "F.Mask" "F.Paste")
			(net "P1V25_PEX3")
		)
		(pad "2" smd rect
			(at 1.575054 0 180)
			(size 1.1684 9.8044)
			(layers "F.Cu" "F.Mask" "F.Paste")
			(net "P1V25_SERDES_VDDPLL_PEX3")
		)
	)
	(footprint ""
		(layer "F.Cu")
		(at 330.374752 -48.753014 180)
		(property "Reference" "C327"
			(at 0 0 180)
			(layer "F.SilkS")
			(hide yes)
			(effects
				(font
					(size 1.27 1.27)
				)
			)
		)
		(property "Value" ""
			(at 0 0 180)
			(layer "F.Fab")
			(effects
				(font
					(size 1.27 1.27)
				)
			)
		)
		(duplicate_pad_numbers_are_jumpers no)
		(fp_line
			(start 0.7874 0.4064)
			(end -0.7874 0.4064)
			(stroke
				(width 0.1524)
				(type default)
			)
			(layer "F.SilkS")
		)
		(fp_line
			(start 0.7874 -0.4064)
			(end 0.7874 0.4064)
			(stroke
				(width 0.1524)
				(type default)
			)
			(layer "F.SilkS")
		)
		(fp_line
			(start -0.7874 0.4064)
			(end -0.7874 -0.4064)
			(stroke
				(width 0.1524)
				(type default)
			)
			(layer "F.SilkS")
		)
		(fp_line
			(start -0.7874 -0.4064)
			(end 0.7874 -0.4064)
			(stroke
				(width 0.1524)
				(type default)
			)
			(layer "F.SilkS")
		)
		(fp_line
			(start 0.67945 0.3048)
			(end 0.120396 0.3048)
			(stroke
				(width 0.1)
				(type default)
			)
			(layer "F.Fab")
		)
		(fp_line
			(start 0.67945 -0.3048)
			(end 0.67945 0.3048)
			(stroke
				(width 0.1)
				(type default)
			)
			(layer "F.Fab")
		)
		(fp_line
			(start 0.12065 -0.2794)
			(end 0.12065 -0.3048)
			(stroke
				(width 0.1)
				(type default)
			)
			(layer "F.Fab")
		)
		(fp_line
			(start 0.12065 -0.3048)
			(end 0.67945 -0.3048)
			(stroke
				(width 0.1)
				(type default)
			)
			(layer "F.Fab")
		)
		(fp_line
			(start 0.120396 0.3048)
			(end 0.120396 0.2794)
			(stroke
				(width 0.1)
				(type default)
			)
			(layer "F.Fab")
		)
		(fp_line
			(start 0.120396 0.2794)
			(end -0.12065 0.2794)
			(stroke
				(width 0.1)
				(type default)
			)
			(layer "F.Fab")
		)
		(fp_line
			(start -0.12065 0.3048)
			(end -0.67945 0.3048)
			(stroke
				(width 0.1)
				(type default)
			)
			(layer "F.Fab")
		)
		(fp_line
			(start -0.12065 0.2794)
			(end -0.12065 0.3048)
			(stroke
				(width 0.1)
				(type default)
			)
			(layer "F.Fab")
		)
		(fp_line
			(start -0.12065 -0.2794)
			(end 0.12065 -0.2794)
			(stroke
				(width 0.1)
				(type default)
			)
			(layer "F.Fab")
		)
		(fp_line
			(start -0.12065 -0.305054)
			(end -0.12065 -0.2794)
			(stroke
				(width 0.1)
				(type default)
			)
			(layer "F.Fab")
		)
		(fp_line
			(start -0.67945 0.3048)
			(end -0.67945 -0.305054)
			(stroke
				(width 0.1)
				(type default)
			)
			(layer "F.Fab")
		)
		(fp_line
			(start -0.67945 -0.305054)
			(end -0.12065 -0.305054)
			(stroke
				(width 0.1)
				(type default)
			)
			(layer "F.Fab")
		)
		(pad "1" smd circle
			(at -0.40005 0 180)
			(size 0 0)
			(layers "F.Cu" "F.Mask" "F.Paste")
			(net "P3V3_AUX")
		)
		(pad "2" smd circle
			(at 0.40005 0 180)
			(size 0 0)
			(layers "F.Cu" "F.Mask" "F.Paste")
			(net "GND")
		)
	)
	(footprint ""
		(layer "F.Cu")
		(at 448.328288 -405.070818 90)
		(property "Reference" "R5603"
			(at 0 0 90)
			(layer "F.SilkS")
			(hide yes)
			(effects
				(font
					(size 1.27 1.27)
				)
			)
		)
		(property "Value" ""
			(at 0 0 90)
			(layer "F.Fab")
			(effects
				(font
					(size 1.27 1.27)
				)
			)
		)
		(duplicate_pad_numbers_are_jumpers no)
		(fp_line
			(start 0.7874 -0.4064)
			(end 0.7874 0.4064)
			(stroke
				(width 0.1524)
				(type default)
			)
			(layer "F.SilkS")
		)
		(fp_line
			(start -0.7874 -0.4064)
			(end 0.7874 -0.4064)
			(stroke
				(width 0.1524)
				(type default)
			)
			(layer "F.SilkS")
		)
		(fp_line
			(start 0.7874 0.4064)
			(end -0.7874 0.4064)
			(stroke
				(width 0.1524)
				(type default)
			)
			(layer "F.SilkS")
		)
		(fp_line
			(start -0.7874 0.4064)
			(end -0.7874 -0.4064)
			(stroke
				(width 0.1524)
				(type default)
			)
			(layer "F.SilkS")
		)
		(fp_line
			(start -0.12065 -0.305054)
			(end -0.12065 -0.2794)
			(stroke
				(width 0.1)
				(type default)
			)
			(layer "F.Fab")
		)
		(fp_line
			(start -0.67945 -0.305054)
			(end -0.12065 -0.305054)
			(stroke
				(width 0.1)
				(type default)
			)
			(layer "F.Fab")
		)
		(fp_line
			(start 0.67945 -0.3048)
			(end 0.67945 0.3048)
			(stroke
				(width 0.1)
				(type default)
			)
			(layer "F.Fab")
		)
		(fp_line
			(start 0.12065 -0.3048)
			(end 0.67945 -0.3048)
			(stroke
				(width 0.1)
				(type default)
			)
			(layer "F.Fab")
		)
		(fp_line
			(start 0.12065 -0.2794)
			(end 0.12065 -0.3048)
			(stroke
				(width 0.1)
				(type default)
			)
			(layer "F.Fab")
		)
		(fp_line
			(start -0.12065 -0.2794)
			(end 0.12065 -0.2794)
			(stroke
				(width 0.1)
				(type default)
			)
			(layer "F.Fab")
		)
		(fp_line
			(start 0.120396 0.2794)
			(end -0.12065 0.2794)
			(stroke
				(width 0.1)
				(type default)
			)
			(layer "F.Fab")
		)
		(fp_line
			(start -0.12065 0.2794)
			(end -0.12065 0.3048)
			(stroke
				(width 0.1)
				(type default)
			)
			(layer "F.Fab")
		)
		(fp_line
			(start 0.67945 0.3048)
			(end 0.120396 0.3048)
			(stroke
				(width 0.1)
				(type default)
			)
			(layer "F.Fab")
		)
		(fp_line
			(start 0.120396 0.3048)
			(end 0.120396 0.2794)
			(stroke
				(width 0.1)
				(type default)
			)
			(layer "F.Fab")
		)
		(fp_line
			(start -0.12065 0.3048)
			(end -0.67945 0.3048)
			(stroke
				(width 0.1)
				(type default)
			)
			(layer "F.Fab")
		)
		(fp_line
			(start -0.67945 0.3048)
			(end -0.67945 -0.305054)
			(stroke
				(width 0.1)
				(type default)
			)
			(layer "F.Fab")
		)
		(pad "1" smd circle
			(at -0.40005 0 90)
			(size 0 0)
			(layers "F.Cu" "F.Mask" "F.Paste")
			(net "SMB_BIC_I2C6_MUX_THERMAL_R1_SCL")
		)
		(pad "2" smd circle
			(at 0.40005 0 90)
			(size 0 0)
			(layers "F.Cu" "F.Mask" "F.Paste")
			(net "SMB_LM75_1_SCL")
		)
	)
	(footprint ""
		(layer "F.Cu")
		(at 271.480534 -136.729724)
		(property "Reference" "C456"
			(at 0 0 0)
			(layer "F.SilkS")
			(hide yes)
			(effects
				(font
					(size 1.27 1.27)
				)
			)
		)
		(property "Value" ""
			(at 0 0 0)
			(layer "F.Fab")
			(effects
				(font
					(size 1.27 1.27)
				)
			)
		)
		(duplicate_pad_numbers_are_jumpers no)
		(fp_line
			(start -0.299974 -0.150114)
			(end 0.299974 -0.150114)
			(stroke
				(width 0.1)
				(type default)
			)
			(layer "F.Fab")
		)
		(fp_line
			(start -0.299974 0.150114)
			(end -0.299974 -0.150114)
			(stroke
				(width 0.1)
				(type default)
			)
			(layer "F.Fab")
		)
		(fp_line
			(start 0.299974 -0.150114)
			(end 0.299974 0.150114)
			(stroke
				(width 0.1)
				(type default)
			)
			(layer "F.Fab")
		)
		(fp_line
			(start 0.299974 0.150114)
			(end -0.299974 0.150114)
			(stroke
				(width 0.1)
				(type default)
			)
			(layer "F.Fab")
		)
		(pad "1" smd rect
			(at -0.2667 0)
			(size 0.3048 0.381)
			(layers "F.Cu" "F.Mask" "F.Paste")
			(net "P5E_PEX2_STN1_TX_DP<31>")
		)
		(pad "2" smd rect
			(at 0.2667 0)
			(size 0.3048 0.381)
			(layers "F.Cu" "F.Mask" "F.Paste")
			(net "P5E_PEX2_STN1_TX_C_DP<31>")
		)
	)
	(footprint ""
		(layer "F.Cu")
		(at 257.20929 -77.279754 -90)
		(property "Reference" "R1055"
			(at 0 0 270)
			(layer "F.SilkS")
			(hide yes)
			(effects
				(font
					(size 1.27 1.27)
				)
			)
		)
		(property "Value" ""
			(at 0 0 270)
			(layer "F.Fab")
			(effects
				(font
					(size 1.27 1.27)
				)
			)
		)
		(duplicate_pad_numbers_are_jumpers no)
		(fp_line
			(start -0.7874 0.4064)
			(end -0.7874 -0.4064)
			(stroke
				(width 0.1524)
				(type default)
			)
			(layer "F.SilkS")
		)
		(fp_line
			(start 0.7874 0.4064)
			(end -0.7874 0.4064)
			(stroke
				(width 0.1524)
				(type default)
			)
			(layer "F.SilkS")
		)
		(fp_line
			(start -0.7874 -0.4064)
			(end 0.7874 -0.4064)
			(stroke
				(width 0.1524)
				(type default)
			)
			(layer "F.SilkS")
		)
		(fp_line
			(start 0.7874 -0.4064)
			(end 0.7874 0.4064)
			(stroke
				(width 0.1524)
				(type default)
			)
			(layer "F.SilkS")
		)
		(fp_line
			(start -0.67945 0.3048)
			(end -0.67945 -0.305054)
			(stroke
				(width 0.1)
				(type default)
			)
			(layer "F.Fab")
		)
		(fp_line
			(start -0.12065 0.3048)
			(end -0.67945 0.3048)
			(stroke
				(width 0.1)
				(type default)
			)
			(layer "F.Fab")
		)
		(fp_line
			(start 0.120396 0.3048)
			(end 0.120396 0.2794)
			(stroke
				(width 0.1)
				(type default)
			)
			(layer "F.Fab")
		)
		(fp_line
			(start 0.67945 0.3048)
			(end 0.120396 0.3048)
			(stroke
				(width 0.1)
				(type default)
			)
			(layer "F.Fab")
		)
		(fp_line
			(start -0.12065 0.2794)
			(end -0.12065 0.3048)
			(stroke
				(width 0.1)
				(type default)
			)
			(layer "F.Fab")
		)
		(fp_line
			(start 0.120396 0.2794)
			(end -0.12065 0.2794)
			(stroke
				(width 0.1)
				(type default)
			)
			(layer "F.Fab")
		)
		(fp_line
			(start -0.12065 -0.2794)
			(end 0.12065 -0.2794)
			(stroke
				(width 0.1)
				(type default)
			)
			(layer "F.Fab")
		)
		(fp_line
			(start 0.12065 -0.2794)
			(end 0.12065 -0.3048)
			(stroke
				(width 0.1)
				(type default)
			)
			(layer "F.Fab")
		)
		(fp_line
			(start 0.12065 -0.3048)
			(end 0.67945 -0.3048)
			(stroke
				(width 0.1)
				(type default)
			)
			(layer "F.Fab")
		)
		(fp_line
			(start 0.67945 -0.3048)
			(end 0.67945 0.3048)
			(stroke
				(width 0.1)
				(type default)
			)
			(layer "F.Fab")
		)
		(fp_line
			(start -0.67945 -0.305054)
			(end -0.12065 -0.305054)
			(stroke
				(width 0.1)
				(type default)
			)
			(layer "F.Fab")
		)
		(fp_line
			(start -0.12065 -0.305054)
			(end -0.12065 -0.2794)
			(stroke
				(width 0.1)
				(type default)
			)
			(layer "F.Fab")
		)
		(pad "1" smd circle
			(at -0.40005 0 270)
			(size 0 0)
			(layers "F.Cu" "F.Mask" "F.Paste")
			(net "FM_CLK_EN_R")
		)
		(pad "2" smd circle
			(at 0.40005 0 270)
			(size 0 0)
			(layers "F.Cu" "F.Mask" "F.Paste")
			(net "P3V3")
		)
	)
	(footprint ""
		(layer "F.Cu")
		(at 352.920554 -86.073234)
		(property "Reference" "R1621"
			(at 0 0 0)
			(layer "F.SilkS")
			(hide yes)
			(effects
				(font
					(size 1.27 1.27)
				)
			)
		)
		(property "Value" ""
			(at 0 0 0)
			(layer "F.Fab")
			(effects
				(font
					(size 1.27 1.27)
				)
			)
		)
		(duplicate_pad_numbers_are_jumpers no)
		(fp_line
			(start -0.7874 -0.4064)
			(end 0.7874 -0.4064)
			(stroke
				(width 0.1524)
				(type default)
			)
			(layer "F.SilkS")
		)
		(fp_line
			(start -0.7874 0.4064)
			(end -0.7874 -0.4064)
			(stroke
				(width 0.1524)
				(type default)
			)
			(layer "F.SilkS")
		)
		(fp_line
			(start 0.7874 -0.4064)
			(end 0.7874 0.4064)
			(stroke
				(width 0.1524)
				(type default)
			)
			(layer "F.SilkS")
		)
		(fp_line
			(start 0.7874 0.4064)
			(end -0.7874 0.4064)
			(stroke
				(width 0.1524)
				(type default)
			)
			(layer "F.SilkS")
		)
		(fp_line
			(start -0.67945 -0.305054)
			(end -0.12065 -0.305054)
			(stroke
				(width 0.1)
				(type default)
			)
			(layer "F.Fab")
		)
		(fp_line
			(start -0.67945 0.3048)
			(end -0.67945 -0.305054)
			(stroke
				(width 0.1)
				(type default)
			)
			(layer "F.Fab")
		)
		(fp_line
			(start -0.12065 -0.305054)
			(end -0.12065 -0.2794)
			(stroke
				(width 0.1)
				(type default)
			)
			(layer "F.Fab")
		)
		(fp_line
			(start -0.12065 -0.2794)
			(end 0.12065 -0.2794)
			(stroke
				(width 0.1)
				(type default)
			)
			(layer "F.Fab")
		)
		(fp_line
			(start -0.12065 0.2794)
			(end -0.12065 0.3048)
			(stroke
				(width 0.1)
				(type default)
			)
			(layer "F.Fab")
		)
		(fp_line
			(start -0.12065 0.3048)
			(end -0.67945 0.3048)
			(stroke
				(width 0.1)
				(type default)
			)
			(layer "F.Fab")
		)
		(fp_line
			(start 0.120396 0.2794)
			(end -0.12065 0.2794)
			(stroke
				(width 0.1)
				(type default)
			)
			(layer "F.Fab")
		)
		(fp_line
			(start 0.120396 0.3048)
			(end 0.120396 0.2794)
			(stroke
				(width 0.1)
				(type default)
			)
			(layer "F.Fab")
		)
		(fp_line
			(start 0.12065 -0.3048)
			(end 0.67945 -0.3048)
			(stroke
				(width 0.1)
				(type default)
			)
			(layer "F.Fab")
		)
		(fp_line
			(start 0.12065 -0.2794)
			(end 0.12065 -0.3048)
			(stroke
				(width 0.1)
				(type default)
			)
			(layer "F.Fab")
		)
		(fp_line
			(start 0.67945 -0.3048)
			(end 0.67945 0.3048)
			(stroke
				(width 0.1)
				(type default)
			)
			(layer "F.Fab")
		)
		(fp_line
			(start 0.67945 0.3048)
			(end 0.120396 0.3048)
			(stroke
				(width 0.1)
				(type default)
			)
			(layer "F.Fab")
		)
		(pad "1" smd circle
			(at -0.40005 0)
			(size 0 0)
			(layers "F.Cu" "F.Mask" "F.Paste")
			(net "SMB_BIC_I2C9_MUX1_SSD9_R_SCL")
		)
		(pad "2" smd circle
			(at 0.40005 0)
			(size 0 0)
			(layers "F.Cu" "F.Mask" "F.Paste")
			(net "SMB_BIC_I2C9_MUX1_SSD9_SCL")
		)
	)
	(footprint ""
		(layer "F.Cu")
		(at 193.250312 -350.098614 90)
		(property "Reference" "C2540"
			(at 0 0 90)
			(layer "F.SilkS")
			(hide yes)
			(effects
				(font
					(size 1.27 1.27)
				)
			)
		)
		(property "Value" ""
			(at 0 0 90)
			(layer "F.Fab")
			(effects
				(font
					(size 1.27 1.27)
				)
			)
		)
		(duplicate_pad_numbers_are_jumpers no)
		(fp_line
			(start 0.299974 -0.150114)
			(end 0.299974 0.150114)
			(stroke
				(width 0.1)
				(type default)
			)
			(layer "F.Fab")
		)
		(fp_line
			(start -0.299974 -0.150114)
			(end 0.299974 -0.150114)
			(stroke
				(width 0.1)
				(type default)
			)
			(layer "F.Fab")
		)
		(fp_line
			(start 0.299974 0.150114)
			(end -0.299974 0.150114)
			(stroke
				(width 0.1)
				(type default)
			)
			(layer "F.Fab")
		)
		(fp_line
			(start -0.299974 0.150114)
			(end -0.299974 -0.150114)
			(stroke
				(width 0.1)
				(type default)
			)
			(layer "F.Fab")
		)
		(pad "1" smd rect
			(at -0.2667 0 90)
			(size 0.3048 0.381)
			(layers "F.Cu" "F.Mask" "F.Paste")
			(net "P5E_PEX1_STN4_TX_DP<65>")
		)
		(pad "2" smd rect
			(at 0.2667 0 90)
			(size 0.3048 0.381)
			(layers "F.Cu" "F.Mask" "F.Paste")
			(net "P5E_PEX1_STN4_TX_C_DP<65>")
		)
	)
	(footprint ""
		(layer "F.Cu")
		(at 15.142718 -70.844918 -90)
		(property "Reference" "PD86"
			(at 2.112518 2.187448 90)
			(unlocked yes)
			(layer "F.SilkS")
			(effects
				(font
					(size 0.7874 0.5842)
					(thickness 0.1524)
				)
				(justify left)
			)
		)
		(property "Value" ""
			(at 0 0 270)
			(layer "F.Fab")
			(effects
				(font
					(size 1.27 1.27)
				)
			)
		)
		(duplicate_pad_numbers_are_jumpers no)
		(fp_line
			(start -3.400044 1.459992)
			(end -3.400044 -1.459992)
			(stroke
				(width 0.1524)
				(type default)
			)
			(layer "F.SilkS")
		)
		(fp_line
			(start 4.107942 1.459992)
			(end -3.400044 1.459992)
			(stroke
				(width 0.1524)
				(type default)
			)
			(layer "F.SilkS")
		)
		(fp_line
			(start -3.400044 -1.459992)
			(end 4.107942 -1.459992)
			(stroke
				(width 0.1524)
				(type default)
			)
			(layer "F.SilkS")
		)
		(fp_line
			(start 4.107942 -1.459992)
			(end 4.107942 1.459992)
			(stroke
				(width 0.1524)
				(type default)
			)
			(layer "F.SilkS")
		)
		(fp_poly
			(pts
				(xy 4.107942 -1.459992) (xy 4.107942 1.459992) (xy 3.308096 1.459992) (xy 3.308096 -1.459992)
			)
			(stroke
				(width 0)
				(type default)
			)
			(fill yes)
			(layer "F.SilkS")
		)
		(fp_line
			(start -2.29997 1.459992)
			(end -2.29997 -1.459992)
			(stroke
				(width 0.1)
				(type default)
			)
			(layer "F.Fab")
		)
		(fp_line
			(start 2.29997 1.459992)
			(end -2.29997 1.459992)
			(stroke
				(width 0.1)
				(type default)
			)
			(layer "F.Fab")
		)
		(fp_line
			(start -2.29997 -1.459992)
			(end 2.29997 -1.459992)
			(stroke
				(width 0.1)
				(type default)
			)
			(layer "F.Fab")
		)
		(fp_line
			(start 2.29997 -1.459992)
			(end 2.29997 1.459992)
			(stroke
				(width 0.1)
				(type default)
			)
			(layer "F.Fab")
		)
		(fp_text user "-"
			(at 5.4102 0.29845 90)
			(unlocked yes)
			(layer "F.SilkS")
			(effects
				(font
					(size 1.905 1.4224)
					(thickness 0.1524)
				)
				(justify left)
			)
		)
		(fp_text user "+"
			(at -4.729734 -1.377442 270)
			(unlocked yes)
			(layer "F.SilkS")
			(effects
				(font
					(size 1.905 1.4224)
					(thickness 0.1524)
				)
				(justify left)
			)
		)
		(fp_text user "-"
			(at 5.4102 0.29845 90)
			(unlocked yes)
			(layer "F.Fab")
			(effects
				(font
					(size 1.905 1.4224)
					(thickness 0.1524)
				)
				(justify left)
			)
		)
		(fp_text user "+"
			(at -4.7752 -0.12065 270)
			(unlocked yes)
			(layer "F.Fab")
			(effects
				(font
					(size 1.905 1.4224)
					(thickness 0.1524)
				)
				(justify left)
			)
		)
		(pad "A" smd rect
			(at -1.999996 0)
			(size 1.7018 2.5146)
			(layers "F.Cu" "F.Mask" "F.Paste")
			(net "GND")
		)
		(pad "C" smd rect
			(at 1.999996 0)
			(size 1.7018 2.5146)
			(layers "F.Cu" "F.Mask" "F.Paste")
			(net "P12V_SSD0_R")
		)
	)
	(footprint ""
		(layer "F.Cu")
		(at 327.533 -209.169)
		(property "Reference" "R5910"
			(at 0 0 0)
			(layer "F.SilkS")
			(hide yes)
			(effects
				(font
					(size 1.27 1.27)
				)
			)
		)
		(property "Value" ""
			(at 0 0 0)
			(layer "F.Fab")
			(effects
				(font
					(size 1.27 1.27)
				)
			)
		)
		(duplicate_pad_numbers_are_jumpers no)
		(fp_line
			(start -0.7874 -0.4064)
			(end 0.7874 -0.4064)
			(stroke
				(width 0.1524)
				(type default)
			)
			(layer "F.SilkS")
		)
		(fp_line
			(start -0.7874 0.4064)
			(end -0.7874 -0.4064)
			(stroke
				(width 0.1524)
				(type default)
			)
			(layer "F.SilkS")
		)
		(fp_line
			(start 0.7874 -0.4064)
			(end 0.7874 0.4064)
			(stroke
				(width 0.1524)
				(type default)
			)
			(layer "F.SilkS")
		)
		(fp_line
			(start 0.7874 0.4064)
			(end -0.7874 0.4064)
			(stroke
				(width 0.1524)
				(type default)
			)
			(layer "F.SilkS")
		)
		(fp_line
			(start -0.67945 -0.305054)
			(end -0.12065 -0.305054)
			(stroke
				(width 0.1)
				(type default)
			)
			(layer "F.Fab")
		)
		(fp_line
			(start -0.67945 0.3048)
			(end -0.67945 -0.305054)
			(stroke
				(width 0.1)
				(type default)
			)
			(layer "F.Fab")
		)
		(fp_line
			(start -0.12065 -0.305054)
			(end -0.12065 -0.2794)
			(stroke
				(width 0.1)
				(type default)
			)
			(layer "F.Fab")
		)
		(fp_line
			(start -0.12065 -0.2794)
			(end 0.12065 -0.2794)
			(stroke
				(width 0.1)
				(type default)
			)
			(layer "F.Fab")
		)
		(fp_line
			(start -0.12065 0.2794)
			(end -0.12065 0.3048)
			(stroke
				(width 0.1)
				(type default)
			)
			(layer "F.Fab")
		)
		(fp_line
			(start -0.12065 0.3048)
			(end -0.67945 0.3048)
			(stroke
				(width 0.1)
				(type default)
			)
			(layer "F.Fab")
		)
		(fp_line
			(start 0.120396 0.2794)
			(end -0.12065 0.2794)
			(stroke
				(width 0.1)
				(type default)
			)
			(layer "F.Fab")
		)
		(fp_line
			(start 0.120396 0.3048)
			(end 0.120396 0.2794)
			(stroke
				(width 0.1)
				(type default)
			)
			(layer "F.Fab")
		)
		(fp_line
			(start 0.12065 -0.3048)
			(end 0.67945 -0.3048)
			(stroke
				(width 0.1)
				(type default)
			)
			(layer "F.Fab")
		)
		(fp_line
			(start 0.12065 -0.2794)
			(end 0.12065 -0.3048)
			(stroke
				(width 0.1)
				(type default)
			)
			(layer "F.Fab")
		)
		(fp_line
			(start 0.67945 -0.3048)
			(end 0.67945 0.3048)
			(stroke
				(width 0.1)
				(type default)
			)
			(layer "F.Fab")
		)
		(fp_line
			(start 0.67945 0.3048)
			(end 0.120396 0.3048)
			(stroke
				(width 0.1)
				(type default)
			)
			(layer "F.Fab")
		)
		(pad "1" smd circle
			(at -0.40005 0)
			(size 0 0)
			(layers "F.Cu" "F.Mask" "F.Paste")
			(net "HSC_TIMER_N")
		)
		(pad "2" smd circle
			(at 0.40005 0)
			(size 0 0)
			(layers "F.Cu" "F.Mask" "F.Paste")
			(net "HSC_TIMER_R_N")
		)
	)
	(footprint ""
		(layer "F.Cu")
		(at 187.946792 -350.098614 90)
		(property "Reference" "C2537"
			(at 0 0 90)
			(layer "F.SilkS")
			(hide yes)
			(effects
				(font
					(size 1.27 1.27)
				)
			)
		)
		(property "Value" ""
			(at 0 0 90)
			(layer "F.Fab")
			(effects
				(font
					(size 1.27 1.27)
				)
			)
		)
		(duplicate_pad_numbers_are_jumpers no)
		(fp_line
			(start 0.299974 -0.150114)
			(end 0.299974 0.150114)
			(stroke
				(width 0.1)
				(type default)
			)
			(layer "F.Fab")
		)
		(fp_line
			(start -0.299974 -0.150114)
			(end 0.299974 -0.150114)
			(stroke
				(width 0.1)
				(type default)
			)
			(layer "F.Fab")
		)
		(fp_line
			(start 0.299974 0.150114)
			(end -0.299974 0.150114)
			(stroke
				(width 0.1)
				(type default)
			)
			(layer "F.Fab")
		)
		(fp_line
			(start -0.299974 0.150114)
			(end -0.299974 -0.150114)
			(stroke
				(width 0.1)
				(type default)
			)
			(layer "F.Fab")
		)
		(pad "1" smd rect
			(at -0.2667 0 90)
			(size 0.3048 0.381)
			(layers "F.Cu" "F.Mask" "F.Paste")
			(net "P5E_PEX1_STN4_TX_DN<67>")
		)
		(pad "2" smd rect
			(at 0.2667 0 90)
			(size 0.3048 0.381)
			(layers "F.Cu" "F.Mask" "F.Paste")
			(net "P5E_PEX1_STN4_TX_C_DN<67>")
		)
	)
	(footprint ""
		(layer "F.Cu")
		(at 450.573902 -26.31186 -90)
		(property "Reference" "U407"
			(at -0.05334 -2.461768 90)
			(unlocked yes)
			(layer "F.SilkS")
			(effects
				(font
					(size 0.7874 0.5842)
					(thickness 0.1524)
				)
			)
		)
		(property "Value" ""
			(at 0 0 270)
			(layer "F.Fab")
			(effects
				(font
					(size 1.27 1.27)
				)
			)
		)
		(duplicate_pad_numbers_are_jumpers no)
		(fp_line
			(start -1.949958 1.610106)
			(end -1.949958 -1.610106)
			(stroke
				(width 0.1524)
				(type default)
			)
			(layer "F.SilkS")
		)
		(fp_line
			(start 1.949958 1.610106)
			(end -1.949958 1.610106)
			(stroke
				(width 0.1524)
				(type default)
			)
			(layer "F.SilkS")
		)
		(fp_line
			(start 1.949958 -1.560068)
			(end 1.949958 1.610106)
			(stroke
				(width 0.1524)
				(type default)
			)
			(layer "F.SilkS")
		)
		(fp_line
			(start -1.949958 -1.610106)
			(end 1.949958 -1.610106)
			(stroke
				(width 0.1524)
				(type default)
			)
			(layer "F.SilkS")
		)
		(fp_line
			(start -0.750062 1.560068)
			(end -0.750062 -1.560068)
			(stroke
				(width 0.1)
				(type default)
			)
			(layer "F.Fab")
		)
		(fp_line
			(start 0.750062 1.560068)
			(end -0.750062 1.560068)
			(stroke
				(width 0.1)
				(type default)
			)
			(layer "F.Fab")
		)
		(fp_line
			(start -0.750062 -1.560068)
			(end 0.750062 -1.560068)
			(stroke
				(width 0.1)
				(type default)
			)
			(layer "F.Fab")
		)
		(fp_line
			(start 0.750062 -1.560068)
			(end 0.750062 1.560068)
			(stroke
				(width 0.1)
				(type default)
			)
			(layer "F.Fab")
		)
		(pad "D" smd rect
			(at 1.100074 0 180)
			(size 1.016 1.4224)
			(layers "F.Cu" "F.Mask" "F.Paste")
			(net "SSD15_LED_ISO_N")
		)
		(pad "G" smd rect
			(at -1.100074 -0.94996 180)
			(size 1.016 1.4224)
			(layers "F.Cu" "F.Mask" "F.Paste")
			(net "SSD15_LED_R")
		)
		(pad "S" smd rect
			(at -1.100074 0.94996 180)
			(size 1.016 1.4224)
			(layers "F.Cu" "F.Mask" "F.Paste")
			(net "GND")
		)
	)
	(footprint ""
		(layer "F.Cu")
		(at 147.219162 -240.716562 180)
		(property "Reference" "U431"
			(at -4.548632 0.282702 0)
			(unlocked yes)
			(layer "F.SilkS")
			(effects
				(font
					(size 0.7874 0.5842)
					(thickness 0.1524)
				)
				(justify left)
			)
		)
		(property "Value" ""
			(at 0 0 180)
			(layer "F.Fab")
			(effects
				(font
					(size 1.27 1.27)
				)
			)
		)
		(duplicate_pad_numbers_are_jumpers no)
		(fp_line
			(start 1.525016 1.525016)
			(end 1.525016 1.3208)
			(stroke
				(width 0.1524)
				(type default)
			)
			(layer "F.SilkS")
		)
		(fp_line
			(start 1.525016 1.525016)
			(end -1.525016 1.525016)
			(stroke
				(width 0.1524)
				(type default)
			)
			(layer "F.SilkS")
		)
		(fp_line
			(start 1.525016 -1.3208)
			(end 1.525016 -1.525016)
			(stroke
				(width 0.1524)
				(type default)
			)
			(layer "F.SilkS")
		)
		(fp_line
			(start 1.525016 -1.525016)
			(end 0.9398 -1.525016)
			(stroke
				(width 0.1524)
				(type default)
			)
			(layer "F.SilkS")
		)
		(fp_line
			(start 1.525016 -1.525016)
			(end -1.525016 -1.525016)
			(stroke
				(width 0.1524)
				(type default)
			)
			(layer "F.SilkS")
		)
		(fp_line
			(start 0.9906 1.525016)
			(end 1.525016 1.525016)
			(stroke
				(width 0.1524)
				(type default)
			)
			(layer "F.SilkS")
		)
		(fp_line
			(start -0.8636 -1.525016)
			(end -1.525016 -1.525016)
			(stroke
				(width 0.1524)
				(type default)
			)
			(layer "F.SilkS")
		)
		(fp_line
			(start -1.525016 1.525016)
			(end -0.889 1.525016)
			(stroke
				(width 0.1524)
				(type default)
			)
			(layer "F.SilkS")
		)
		(fp_line
			(start -1.525016 1.3208)
			(end -1.525016 1.525016)
			(stroke
				(width 0.1524)
				(type default)
			)
			(layer "F.SilkS")
		)
		(fp_line
			(start -1.525016 -1.525016)
			(end -1.525016 -1.3208)
			(stroke
				(width 0.1524)
				(type default)
			)
			(layer "F.SilkS")
		)
		(fp_poly
			(pts
				(xy -2.253996 -0.994156) (xy -1.954022 -1.894332) (xy -2.55397 -1.894332)
			)
			(stroke
				(width 0)
				(type default)
			)
			(fill yes)
			(layer "F.SilkS")
		)
		(fp_line
			(start 1.525016 1.525016)
			(end -1.525016 1.525016)
			(stroke
				(width 0.1)
				(type default)
			)
			(layer "F.Fab")
		)
		(fp_line
			(start 1.525016 -1.525016)
			(end 1.525016 1.525016)
			(stroke
				(width 0.1)
				(type default)
			)
			(layer "F.Fab")
		)
		(fp_line
			(start -1.525016 1.525016)
			(end -1.525016 -1.525016)
			(stroke
				(width 0.1)
				(type default)
			)
			(layer "F.Fab")
		)
		(fp_line
			(start -1.525016 -1.525016)
			(end 1.525016 -1.525016)
			(stroke
				(width 0.1)
				(type default)
			)
			(layer "F.Fab")
		)
		(fp_poly
			(pts
				(xy -2.0701 -0.999998) (xy -2.977896 -1.302512) (xy -2.977896 -0.697484)
			)
			(stroke
				(width 0)
				(type default)
			)
			(fill yes)
			(layer "F.Fab")
		)
		(pad "1" smd rect
			(at -1.550162 -0.999998 90)
			(size 0.2794 0.9144)
			(layers "F.Cu" "F.Mask" "F.Paste")
			(net "P1V8_PLL0_PEX1")
		)
		(pad "2" smd rect
			(at -1.550162 -0.500126 90)
			(size 0.2794 0.9144)
			(layers "F.Cu" "F.Mask" "F.Paste")
			(net "P1V8_PLL0_PEX1")
		)
		(pad "3" smd rect
			(at -1.550162 0 90)
			(size 0.2794 0.9144)
			(layers "F.Cu" "F.Mask" "F.Paste")
			(net "P1V8_PLL0_PEX1")
		)
		(pad "4" smd rect
			(at -1.550162 0.500126 90)
			(size 0.2794 0.9144)
			(layers "F.Cu" "F.Mask" "F.Paste")
			(net "P1V8_PLL_PEX1_ADJ")
		)
		(pad "5" smd rect
			(at -1.550162 0.999998 270)
			(size 0.2794 0.9144)
			(layers "F.Cu" "F.Mask" "F.Paste")
			(net "PWRGD_PEX1_P1V8_PLL")
		)
		(pad "6" smd rect
			(at 1.550162 0.999998 270)
			(size 0.2794 0.9144)
			(layers "F.Cu" "F.Mask" "F.Paste")
			(net "PEX1_P1V8_PLL_EN")
		)
		(pad "7" smd rect
			(at 1.550162 0.500126 90)
			(size 0.2794 0.9144)
			(layers "F.Cu" "F.Mask" "F.Paste")
			(net "P3V3_AUX")
		)
		(pad "8" smd rect
			(at 1.550162 0 90)
			(size 0.2794 0.9144)
			(layers "F.Cu" "F.Mask" "F.Paste")
			(net "P3V3_AUX")
		)
		(pad "9" smd rect
			(at 1.550162 -0.500126 90)
			(size 0.2794 0.9144)
			(layers "F.Cu" "F.Mask" "F.Paste")
			(net "P3V3_AUX")
		)
		(pad "10" smd rect
			(at 1.550162 -0.999998 90)
			(size 0.2794 0.9144)
			(layers "F.Cu" "F.Mask" "F.Paste")
			(net "P5V_AUX")
		)
		(pad "TH" smd rect
			(at 0 0 180)
			(size 1.7526 2.667)
			(layers "F.Cu" "F.Mask" "F.Paste")
			(net "GND")
		)
		(zone
			(layer "F.Cu")
			(hatch none 0.5)
			(connect_pads
				(clearance 0)
			)
			(min_thickness 0.25)
			(keepout
				(tracks not_allowed)
				(vias allowed)
				(pads allowed)
				(copperpour not_allowed)
				(footprints allowed)
			)
			(placement
				(enabled no)
				(sheetname "")
			)
			(fill
				(thermal_gap 0.5)
				(thermal_bridge_width 0.5)
				(island_removal_mode 0)
			)
			(polygon
				(pts
					(xy 148.235924 -239.183164) (xy 148.235924 -242.231164) (xy 146.203924 -242.231164) (xy 146.203924 -239.183164)
					(xy 148.134324 -239.183164) (xy 148.134324 -239.310164) (xy 146.280124 -239.310164) (xy 146.280124 -242.129564)
					(xy 148.159724 -242.129564) (xy 148.159724 -239.183164)
				)
			)
		)
	)
	(footprint ""
		(layer "F.Cu")
		(at 381.40386 -356.244906 90)
		(property "Reference" "C789"
			(at 0 0 90)
			(layer "F.SilkS")
			(hide yes)
			(effects
				(font
					(size 1.27 1.27)
				)
			)
		)
		(property "Value" ""
			(at 0 0 90)
			(layer "F.Fab")
			(effects
				(font
					(size 1.27 1.27)
				)
			)
		)
		(duplicate_pad_numbers_are_jumpers no)
		(fp_line
			(start 0.299974 -0.150114)
			(end 0.299974 0.150114)
			(stroke
				(width 0.1)
				(type default)
			)
			(layer "F.Fab")
		)
		(fp_line
			(start -0.299974 -0.150114)
			(end 0.299974 -0.150114)
			(stroke
				(width 0.1)
				(type default)
			)
			(layer "F.Fab")
		)
		(fp_line
			(start 0.299974 0.150114)
			(end -0.299974 0.150114)
			(stroke
				(width 0.1)
				(type default)
			)
			(layer "F.Fab")
		)
		(fp_line
			(start -0.299974 0.150114)
			(end -0.299974 -0.150114)
			(stroke
				(width 0.1)
				(type default)
			)
			(layer "F.Fab")
		)
		(pad "1" smd rect
			(at -0.2667 0 90)
			(size 0.3048 0.381)
			(layers "F.Cu" "F.Mask" "F.Paste")
			(net "P5E_PEX3_STN6_TX_DN<98>")
		)
		(pad "2" smd rect
			(at 0.2667 0 90)
			(size 0.3048 0.381)
			(layers "F.Cu" "F.Mask" "F.Paste")
			(net "P5E_PEX3_STN6_TX_C_DN<98>")
		)
	)
	(footprint ""
		(layer "F.Cu")
		(at 426.543724 -49.95291 180)
		(property "Reference" "R5907"
			(at 0 0 180)
			(layer "F.SilkS")
			(hide yes)
			(effects
				(font
					(size 1.27 1.27)
				)
			)
		)
		(property "Value" ""
			(at 0 0 180)
			(layer "F.Fab")
			(effects
				(font
					(size 1.27 1.27)
				)
			)
		)
		(duplicate_pad_numbers_are_jumpers no)
		(fp_line
			(start 0.7874 0.4064)
			(end -0.7874 0.4064)
			(stroke
				(width 0.1524)
				(type default)
			)
			(layer "F.SilkS")
		)
		(fp_line
			(start 0.7874 -0.4064)
			(end 0.7874 0.4064)
			(stroke
				(width 0.1524)
				(type default)
			)
			(layer "F.SilkS")
		)
		(fp_line
			(start -0.7874 0.4064)
			(end -0.7874 -0.4064)
			(stroke
				(width 0.1524)
				(type default)
			)
			(layer "F.SilkS")
		)
		(fp_line
			(start -0.7874 -0.4064)
			(end 0.7874 -0.4064)
			(stroke
				(width 0.1524)
				(type default)
			)
			(layer "F.SilkS")
		)
		(fp_line
			(start 0.67945 0.3048)
			(end 0.120396 0.3048)
			(stroke
				(width 0.1)
				(type default)
			)
			(layer "F.Fab")
		)
		(fp_line
			(start 0.67945 -0.3048)
			(end 0.67945 0.3048)
			(stroke
				(width 0.1)
				(type default)
			)
			(layer "F.Fab")
		)
		(fp_line
			(start 0.12065 -0.2794)
			(end 0.12065 -0.3048)
			(stroke
				(width 0.1)
				(type default)
			)
			(layer "F.Fab")
		)
		(fp_line
			(start 0.12065 -0.3048)
			(end 0.67945 -0.3048)
			(stroke
				(width 0.1)
				(type default)
			)
			(layer "F.Fab")
		)
		(fp_line
			(start 0.120396 0.3048)
			(end 0.120396 0.2794)
			(stroke
				(width 0.1)
				(type default)
			)
			(layer "F.Fab")
		)
		(fp_line
			(start 0.120396 0.2794)
			(end -0.12065 0.2794)
			(stroke
				(width 0.1)
				(type default)
			)
			(layer "F.Fab")
		)
		(fp_line
			(start -0.12065 0.3048)
			(end -0.67945 0.3048)
			(stroke
				(width 0.1)
				(type default)
			)
			(layer "F.Fab")
		)
		(fp_line
			(start -0.12065 0.2794)
			(end -0.12065 0.3048)
			(stroke
				(width 0.1)
				(type default)
			)
			(layer "F.Fab")
		)
		(fp_line
			(start -0.12065 -0.2794)
			(end 0.12065 -0.2794)
			(stroke
				(width 0.1)
				(type default)
			)
			(layer "F.Fab")
		)
		(fp_line
			(start -0.12065 -0.305054)
			(end -0.12065 -0.2794)
			(stroke
				(width 0.1)
				(type default)
			)
			(layer "F.Fab")
		)
		(fp_line
			(start -0.67945 0.3048)
			(end -0.67945 -0.305054)
			(stroke
				(width 0.1)
				(type default)
			)
			(layer "F.Fab")
		)
		(fp_line
			(start -0.67945 -0.305054)
			(end -0.12065 -0.305054)
			(stroke
				(width 0.1)
				(type default)
			)
			(layer "F.Fab")
		)
		(pad "1" smd circle
			(at -0.40005 0 180)
			(size 0 0)
			(layers "F.Cu" "F.Mask" "F.Paste")
			(net "SSD14_ADC_A0")
		)
		(pad "2" smd circle
			(at 0.40005 0 180)
			(size 0 0)
			(layers "F.Cu" "F.Mask" "F.Paste")
			(net "SMB_SSD14_ADC_SDA")
		)
	)
	(footprint ""
		(layer "F.Cu")
		(at 39.280592 -133.129782)
		(property "Reference" "C38"
			(at 0 0 0)
			(layer "F.SilkS")
			(hide yes)
			(effects
				(font
					(size 1.27 1.27)
				)
			)
		)
		(property "Value" ""
			(at 0 0 0)
			(layer "F.Fab")
			(effects
				(font
					(size 1.27 1.27)
				)
			)
		)
		(duplicate_pad_numbers_are_jumpers no)
		(fp_line
			(start -0.299974 -0.150114)
			(end 0.299974 -0.150114)
			(stroke
				(width 0.1)
				(type default)
			)
			(layer "F.Fab")
		)
		(fp_line
			(start -0.299974 0.150114)
			(end -0.299974 -0.150114)
			(stroke
				(width 0.1)
				(type default)
			)
			(layer "F.Fab")
		)
		(fp_line
			(start 0.299974 -0.150114)
			(end 0.299974 0.150114)
			(stroke
				(width 0.1)
				(type default)
			)
			(layer "F.Fab")
		)
		(fp_line
			(start 0.299974 0.150114)
			(end -0.299974 0.150114)
			(stroke
				(width 0.1)
				(type default)
			)
			(layer "F.Fab")
		)
		(pad "1" smd rect
			(at -0.2667 0)
			(size 0.3048 0.381)
			(layers "F.Cu" "F.Mask" "F.Paste")
			(net "P5E_PEX0_STN1_TX_DP<29>")
		)
		(pad "2" smd rect
			(at 0.2667 0)
			(size 0.3048 0.381)
			(layers "F.Cu" "F.Mask" "F.Paste")
			(net "P5E_PEX0_STN1_TX_C_DP<29>")
		)
	)
	(footprint ""
		(layer "F.Cu")
		(at 363.474 -195.707)
		(property "Reference" "R4662"
			(at 0 0 0)
			(layer "F.SilkS")
			(hide yes)
			(effects
				(font
					(size 1.27 1.27)
				)
			)
		)
		(property "Value" ""
			(at 0 0 0)
			(layer "F.Fab")
			(effects
				(font
					(size 1.27 1.27)
				)
			)
		)
		(duplicate_pad_numbers_are_jumpers no)
		(fp_line
			(start -0.7874 -0.4064)
			(end 0.7874 -0.4064)
			(stroke
				(width 0.1524)
				(type default)
			)
			(layer "F.SilkS")
		)
		(fp_line
			(start -0.7874 0.4064)
			(end -0.7874 -0.4064)
			(stroke
				(width 0.1524)
				(type default)
			)
			(layer "F.SilkS")
		)
		(fp_line
			(start 0.7874 -0.4064)
			(end 0.7874 0.4064)
			(stroke
				(width 0.1524)
				(type default)
			)
			(layer "F.SilkS")
		)
		(fp_line
			(start 0.7874 0.4064)
			(end -0.7874 0.4064)
			(stroke
				(width 0.1524)
				(type default)
			)
			(layer "F.SilkS")
		)
		(fp_line
			(start -0.67945 -0.305054)
			(end -0.12065 -0.305054)
			(stroke
				(width 0.1)
				(type default)
			)
			(layer "F.Fab")
		)
		(fp_line
			(start -0.67945 0.3048)
			(end -0.67945 -0.305054)
			(stroke
				(width 0.1)
				(type default)
			)
			(layer "F.Fab")
		)
		(fp_line
			(start -0.12065 -0.305054)
			(end -0.12065 -0.2794)
			(stroke
				(width 0.1)
				(type default)
			)
			(layer "F.Fab")
		)
		(fp_line
			(start -0.12065 -0.2794)
			(end 0.12065 -0.2794)
			(stroke
				(width 0.1)
				(type default)
			)
			(layer "F.Fab")
		)
		(fp_line
			(start -0.12065 0.2794)
			(end -0.12065 0.3048)
			(stroke
				(width 0.1)
				(type default)
			)
			(layer "F.Fab")
		)
		(fp_line
			(start -0.12065 0.3048)
			(end -0.67945 0.3048)
			(stroke
				(width 0.1)
				(type default)
			)
			(layer "F.Fab")
		)
		(fp_line
			(start 0.120396 0.2794)
			(end -0.12065 0.2794)
			(stroke
				(width 0.1)
				(type default)
			)
			(layer "F.Fab")
		)
		(fp_line
			(start 0.120396 0.3048)
			(end 0.120396 0.2794)
			(stroke
				(width 0.1)
				(type default)
			)
			(layer "F.Fab")
		)
		(fp_line
			(start 0.12065 -0.3048)
			(end 0.67945 -0.3048)
			(stroke
				(width 0.1)
				(type default)
			)
			(layer "F.Fab")
		)
		(fp_line
			(start 0.12065 -0.2794)
			(end 0.12065 -0.3048)
			(stroke
				(width 0.1)
				(type default)
			)
			(layer "F.Fab")
		)
		(fp_line
			(start 0.67945 -0.3048)
			(end 0.67945 0.3048)
			(stroke
				(width 0.1)
				(type default)
			)
			(layer "F.Fab")
		)
		(fp_line
			(start 0.67945 0.3048)
			(end 0.120396 0.3048)
			(stroke
				(width 0.1)
				(type default)
			)
			(layer "F.Fab")
		)
		(pad "1" smd circle
			(at -0.40005 0)
			(size 0 0)
			(layers "F.Cu" "F.Mask" "F.Paste")
			(net "P3V3_AUX")
		)
		(pad "2" smd circle
			(at 0.40005 0)
			(size 0 0)
			(layers "F.Cu" "F.Mask" "F.Paste")
			(net "SSD5_PEX_PWR_EN_R")
		)
	)
	(footprint ""
		(layer "F.Cu")
		(at 428.319438 -153.390346 180)
		(property "Reference" "C637"
			(at 0 0 180)
			(layer "F.SilkS")
			(hide yes)
			(effects
				(font
					(size 1.27 1.27)
				)
			)
		)
		(property "Value" ""
			(at 0 0 180)
			(layer "F.Fab")
			(effects
				(font
					(size 1.27 1.27)
				)
			)
		)
		(duplicate_pad_numbers_are_jumpers no)
		(fp_line
			(start 0.299974 0.150114)
			(end -0.299974 0.150114)
			(stroke
				(width 0.1)
				(type default)
			)
			(layer "F.Fab")
		)
		(fp_line
			(start 0.299974 -0.150114)
			(end 0.299974 0.150114)
			(stroke
				(width 0.1)
				(type default)
			)
			(layer "F.Fab")
		)
		(fp_line
			(start -0.299974 0.150114)
			(end -0.299974 -0.150114)
			(stroke
				(width 0.1)
				(type default)
			)
			(layer "F.Fab")
		)
		(fp_line
			(start -0.299974 -0.150114)
			(end 0.299974 -0.150114)
			(stroke
				(width 0.1)
				(type default)
			)
			(layer "F.Fab")
		)
		(pad "1" smd rect
			(at -0.2667 0 180)
			(size 0.3048 0.381)
			(layers "F.Cu" "F.Mask" "F.Paste")
			(net "P5E_PEX3_STN0_TX_DP<14>")
		)
		(pad "2" smd rect
			(at 0.2667 0 180)
			(size 0.3048 0.381)
			(layers "F.Cu" "F.Mask" "F.Paste")
			(net "P5E_PEX3_STN0_TX_C_DP<14>")
		)
	)
	(footprint ""
		(layer "F.Cu")
		(at 258.46786 -52.035456 180)
		(property "Reference" "R869"
			(at 0 0 180)
			(layer "F.SilkS")
			(hide yes)
			(effects
				(font
					(size 1.27 1.27)
				)
			)
		)
		(property "Value" ""
			(at 0 0 180)
			(layer "F.Fab")
			(effects
				(font
					(size 1.27 1.27)
				)
			)
		)
		(duplicate_pad_numbers_are_jumpers no)
		(fp_line
			(start 0.7874 0.4064)
			(end -0.7874 0.4064)
			(stroke
				(width 0.1524)
				(type default)
			)
			(layer "F.SilkS")
		)
		(fp_line
			(start 0.7874 -0.4064)
			(end 0.7874 0.4064)
			(stroke
				(width 0.1524)
				(type default)
			)
			(layer "F.SilkS")
		)
		(fp_line
			(start -0.7874 0.4064)
			(end -0.7874 -0.4064)
			(stroke
				(width 0.1524)
				(type default)
			)
			(layer "F.SilkS")
		)
		(fp_line
			(start -0.7874 -0.4064)
			(end 0.7874 -0.4064)
			(stroke
				(width 0.1524)
				(type default)
			)
			(layer "F.SilkS")
		)
		(fp_line
			(start 0.67945 0.3048)
			(end 0.120396 0.3048)
			(stroke
				(width 0.1)
				(type default)
			)
			(layer "F.Fab")
		)
		(fp_line
			(start 0.67945 -0.3048)
			(end 0.67945 0.3048)
			(stroke
				(width 0.1)
				(type default)
			)
			(layer "F.Fab")
		)
		(fp_line
			(start 0.12065 -0.2794)
			(end 0.12065 -0.3048)
			(stroke
				(width 0.1)
				(type default)
			)
			(layer "F.Fab")
		)
		(fp_line
			(start 0.12065 -0.3048)
			(end 0.67945 -0.3048)
			(stroke
				(width 0.1)
				(type default)
			)
			(layer "F.Fab")
		)
		(fp_line
			(start 0.120396 0.3048)
			(end 0.120396 0.2794)
			(stroke
				(width 0.1)
				(type default)
			)
			(layer "F.Fab")
		)
		(fp_line
			(start 0.120396 0.2794)
			(end -0.12065 0.2794)
			(stroke
				(width 0.1)
				(type default)
			)
			(layer "F.Fab")
		)
		(fp_line
			(start -0.12065 0.3048)
			(end -0.67945 0.3048)
			(stroke
				(width 0.1)
				(type default)
			)
			(layer "F.Fab")
		)
		(fp_line
			(start -0.12065 0.2794)
			(end -0.12065 0.3048)
			(stroke
				(width 0.1)
				(type default)
			)
			(layer "F.Fab")
		)
		(fp_line
			(start -0.12065 -0.2794)
			(end 0.12065 -0.2794)
			(stroke
				(width 0.1)
				(type default)
			)
			(layer "F.Fab")
		)
		(fp_line
			(start -0.12065 -0.305054)
			(end -0.12065 -0.2794)
			(stroke
				(width 0.1)
				(type default)
			)
			(layer "F.Fab")
		)
		(fp_line
			(start -0.67945 0.3048)
			(end -0.67945 -0.305054)
			(stroke
				(width 0.1)
				(type default)
			)
			(layer "F.Fab")
		)
		(fp_line
			(start -0.67945 -0.305054)
			(end -0.12065 -0.305054)
			(stroke
				(width 0.1)
				(type default)
			)
			(layer "F.Fab")
		)
		(pad "1" smd circle
			(at -0.40005 0 180)
			(size 0 0)
			(layers "F.Cu" "F.Mask" "F.Paste")
			(net "P3V3_AUX")
		)
		(pad "2" smd circle
			(at 0.40005 0 180)
			(size 0 0)
			(layers "F.Cu" "F.Mask" "F.Paste")
			(net "PWRGD_P12V_SSD8")
		)
	)
	(footprint ""
		(layer "F.Cu")
		(at 418.092382 -31.825184 180)
		(property "Reference" "C717"
			(at 0 0 180)
			(layer "F.SilkS")
			(hide yes)
			(effects
				(font
					(size 1.27 1.27)
				)
			)
		)
		(property "Value" ""
			(at 0 0 180)
			(layer "F.Fab")
			(effects
				(font
					(size 1.27 1.27)
				)
			)
		)
		(duplicate_pad_numbers_are_jumpers no)
		(fp_line
			(start 0.299974 0.150114)
			(end -0.299974 0.150114)
			(stroke
				(width 0.1)
				(type default)
			)
			(layer "F.Fab")
		)
		(fp_line
			(start 0.299974 -0.150114)
			(end 0.299974 0.150114)
			(stroke
				(width 0.1)
				(type default)
			)
			(layer "F.Fab")
		)
		(fp_line
			(start -0.299974 0.150114)
			(end -0.299974 -0.150114)
			(stroke
				(width 0.1)
				(type default)
			)
			(layer "F.Fab")
		)
		(fp_line
			(start -0.299974 -0.150114)
			(end 0.299974 -0.150114)
			(stroke
				(width 0.1)
				(type default)
			)
			(layer "F.Fab")
		)
		(pad "1" smd rect
			(at -0.2667 0 180)
			(size 0.3048 0.381)
			(layers "F.Cu" "F.Mask" "F.Paste")
			(net "P5E_PEX3_STN2_TX_DN<38>")
		)
		(pad "2" smd rect
			(at 0.2667 0 180)
			(size 0.3048 0.381)
			(layers "F.Cu" "F.Mask" "F.Paste")
			(net "P5E_PEX3_STN2_TX_C_DN<38>")
		)
	)
	(footprint ""
		(layer "F.Cu")
		(at 137.622788 -356.244906 90)
		(property "Reference" "C2250"
			(at 0 0 90)
			(layer "F.SilkS")
			(hide yes)
			(effects
				(font
					(size 1.27 1.27)
				)
			)
		)
		(property "Value" ""
			(at 0 0 90)
			(layer "F.Fab")
			(effects
				(font
					(size 1.27 1.27)
				)
			)
		)
		(duplicate_pad_numbers_are_jumpers no)
		(fp_line
			(start 0.299974 -0.150114)
			(end 0.299974 0.150114)
			(stroke
				(width 0.1)
				(type default)
			)
			(layer "F.Fab")
		)
		(fp_line
			(start -0.299974 -0.150114)
			(end 0.299974 -0.150114)
			(stroke
				(width 0.1)
				(type default)
			)
			(layer "F.Fab")
		)
		(fp_line
			(start 0.299974 0.150114)
			(end -0.299974 0.150114)
			(stroke
				(width 0.1)
				(type default)
			)
			(layer "F.Fab")
		)
		(fp_line
			(start -0.299974 0.150114)
			(end -0.299974 -0.150114)
			(stroke
				(width 0.1)
				(type default)
			)
			(layer "F.Fab")
		)
		(pad "1" smd rect
			(at -0.2667 0 90)
			(size 0.3048 0.381)
			(layers "F.Cu" "F.Mask" "F.Paste")
			(net "P5E_PEX1_STN5_TX_DN<92>")
		)
		(pad "2" smd rect
			(at 0.2667 0 90)
			(size 0.3048 0.381)
			(layers "F.Cu" "F.Mask" "F.Paste")
			(net "P5E_PEX1_STN5_TX_C_DN<92>")
		)
	)
	(footprint ""
		(layer "F.Cu")
		(at 363.474 -212.979 180)
		(property "Reference" "R4620"
			(at 0 0 180)
			(layer "F.SilkS")
			(hide yes)
			(effects
				(font
					(size 1.27 1.27)
				)
			)
		)
		(property "Value" ""
			(at 0 0 180)
			(layer "F.Fab")
			(effects
				(font
					(size 1.27 1.27)
				)
			)
		)
		(duplicate_pad_numbers_are_jumpers no)
		(fp_line
			(start 0.7874 0.4064)
			(end -0.7874 0.4064)
			(stroke
				(width 0.1524)
				(type default)
			)
			(layer "F.SilkS")
		)
		(fp_line
			(start 0.7874 -0.4064)
			(end 0.7874 0.4064)
			(stroke
				(width 0.1524)
				(type default)
			)
			(layer "F.SilkS")
		)
		(fp_line
			(start -0.7874 0.4064)
			(end -0.7874 -0.4064)
			(stroke
				(width 0.1524)
				(type default)
			)
			(layer "F.SilkS")
		)
		(fp_line
			(start -0.7874 -0.4064)
			(end 0.7874 -0.4064)
			(stroke
				(width 0.1524)
				(type default)
			)
			(layer "F.SilkS")
		)
		(fp_line
			(start 0.67945 0.3048)
			(end 0.120396 0.3048)
			(stroke
				(width 0.1)
				(type default)
			)
			(layer "F.Fab")
		)
		(fp_line
			(start 0.67945 -0.3048)
			(end 0.67945 0.3048)
			(stroke
				(width 0.1)
				(type default)
			)
			(layer "F.Fab")
		)
		(fp_line
			(start 0.12065 -0.2794)
			(end 0.12065 -0.3048)
			(stroke
				(width 0.1)
				(type default)
			)
			(layer "F.Fab")
		)
		(fp_line
			(start 0.12065 -0.3048)
			(end 0.67945 -0.3048)
			(stroke
				(width 0.1)
				(type default)
			)
			(layer "F.Fab")
		)
		(fp_line
			(start 0.120396 0.3048)
			(end 0.120396 0.2794)
			(stroke
				(width 0.1)
				(type default)
			)
			(layer "F.Fab")
		)
		(fp_line
			(start 0.120396 0.2794)
			(end -0.12065 0.2794)
			(stroke
				(width 0.1)
				(type default)
			)
			(layer "F.Fab")
		)
		(fp_line
			(start -0.12065 0.3048)
			(end -0.67945 0.3048)
			(stroke
				(width 0.1)
				(type default)
			)
			(layer "F.Fab")
		)
		(fp_line
			(start -0.12065 0.2794)
			(end -0.12065 0.3048)
			(stroke
				(width 0.1)
				(type default)
			)
			(layer "F.Fab")
		)
		(fp_line
			(start -0.12065 -0.2794)
			(end 0.12065 -0.2794)
			(stroke
				(width 0.1)
				(type default)
			)
			(layer "F.Fab")
		)
		(fp_line
			(start -0.12065 -0.305054)
			(end -0.12065 -0.2794)
			(stroke
				(width 0.1)
				(type default)
			)
			(layer "F.Fab")
		)
		(fp_line
			(start -0.67945 0.3048)
			(end -0.67945 -0.305054)
			(stroke
				(width 0.1)
				(type default)
			)
			(layer "F.Fab")
		)
		(fp_line
			(start -0.67945 -0.305054)
			(end -0.12065 -0.305054)
			(stroke
				(width 0.1)
				(type default)
			)
			(layer "F.Fab")
		)
		(pad "1" smd circle
			(at -0.40005 0 180)
			(size 0 0)
			(layers "F.Cu" "F.Mask" "F.Paste")
			(net "PCA9555_0_PEX0_A2")
		)
		(pad "2" smd circle
			(at 0.40005 0 180)
			(size 0 0)
			(layers "F.Cu" "F.Mask" "F.Paste")
			(net "P3V3_AUX")
		)
	)
	(footprint ""
		(layer "F.Cu")
		(at 97.633028 -98.968052 -90)
		(property "Reference" "PU24"
			(at 1.748028 2.319274 90)
			(unlocked yes)
			(layer "F.SilkS")
			(effects
				(font
					(size 0.7874 0.5842)
					(thickness 0.1524)
				)
				(justify left)
			)
		)
		(property "Value" ""
			(at 0 0 270)
			(layer "F.Fab")
			(effects
				(font
					(size 1.27 1.27)
				)
			)
		)
		(duplicate_pad_numbers_are_jumpers no)
		(fp_line
			(start -1.943608 1.549908)
			(end -1.943608 -1.549908)
			(stroke
				(width 0.1524)
				(type default)
			)
			(layer "F.SilkS")
		)
		(fp_line
			(start 1.943608 1.549908)
			(end -1.943608 1.549908)
			(stroke
				(width 0.1524)
				(type default)
			)
			(layer "F.SilkS")
		)
		(fp_line
			(start -1.943608 -1.549908)
			(end 1.943608 -1.549908)
			(stroke
				(width 0.1524)
				(type default)
			)
			(layer "F.SilkS")
		)
		(fp_line
			(start 1.943608 -1.549908)
			(end 1.943608 1.549908)
			(stroke
				(width 0.1524)
				(type default)
			)
			(layer "F.SilkS")
		)
		(fp_poly
			(pts
				(xy -2.019808 -1.549908) (xy -1.257808 -1.549908) (xy -1.257808 -1.880108) (xy -2.019808 -1.880108)
			)
			(stroke
				(width 0)
				(type default)
			)
			(fill yes)
			(layer "F.SilkS")
		)
		(fp_line
			(start -1.549908 1.549908)
			(end -1.549908 -1.549908)
			(stroke
				(width 0.1)
				(type default)
			)
			(layer "F.Fab")
		)
		(fp_line
			(start 1.549908 1.549908)
			(end -1.549908 1.549908)
			(stroke
				(width 0.1)
				(type default)
			)
			(layer "F.Fab")
		)
		(fp_line
			(start -1.549908 -1.549908)
			(end 1.549908 -1.549908)
			(stroke
				(width 0.1)
				(type default)
			)
			(layer "F.Fab")
		)
		(fp_line
			(start 1.549908 -1.549908)
			(end 1.549908 1.549908)
			(stroke
				(width 0.1)
				(type default)
			)
			(layer "F.Fab")
		)
		(fp_poly
			(pts
				(xy -2.019808 -1.549908) (xy -1.257808 -1.549908) (xy -1.257808 -1.880108) (xy -2.019808 -1.880108)
			)
			(stroke
				(width 0)
				(type default)
			)
			(fill yes)
			(layer "F.Fab")
		)
		(pad "1" smd rect
			(at -1.500124 -1.249934 180)
			(size 0.2794 0.6096)
			(layers "F.Cu" "F.Mask" "F.Paste")
			(net "P12V_NIC1_R")
		)
		(pad "2" smd rect
			(at -1.500124 -0.750062 180)
			(size 0.2794 0.6096)
			(layers "F.Cu" "F.Mask" "F.Paste")
			(net "P12V_NIC1_R")
		)
		(pad "3" smd rect
			(at -1.500124 -0.249936 180)
			(size 0.2794 0.6096)
			(layers "F.Cu" "F.Mask" "F.Paste")
			(net "P12V_NIC1_R")
		)
		(pad "4" smd rect
			(at -1.500124 0.249936 180)
			(size 0.2794 0.6096)
			(layers "F.Cu" "F.Mask" "F.Paste")
			(net "P12V_NIC1_R")
		)
		(pad "5" smd rect
			(at -1.500124 0.750062 180)
			(size 0.2794 0.6096)
			(layers "F.Cu" "F.Mask" "F.Paste")
			(net "P12V_NIC1_R")
		)
		(pad "6" smd rect
			(at -1.500124 1.249934 180)
			(size 0.2794 0.6096)
			(layers "F.Cu" "F.Mask" "F.Paste")
			(net "GND")
		)
		(pad "7" smd rect
			(at 1.500124 1.249934 180)
			(size 0.2794 0.6096)
			(layers "F.Cu" "F.Mask" "F.Paste")
			(net "P12V_NIC1_SS")
		)
		(pad "8" smd rect
			(at 1.500124 0.750062 180)
			(size 0.2794 0.6096)
			(layers "F.Cu" "F.Mask" "F.Paste")
			(net "PWRGD_P12V_NIC1")
		)
		(pad "9" smd rect
			(at 1.500124 0.249936 180)
			(size 0.2794 0.6096)
			(layers "F.Cu" "F.Mask" "F.Paste")
			(net "P12V_NIC1_OCP")
		)
		(pad "10" smd rect
			(at 1.500124 -0.249936 180)
			(size 0.2794 0.6096)
			(layers "F.Cu" "F.Mask" "F.Paste")
			(net "P5V_AUX")
		)
		(pad "11" smd rect
			(at 1.500124 -0.750062 180)
			(size 0.2794 0.6096)
			(layers "F.Cu" "F.Mask" "F.Paste")
			(net "P12V_NIC1_EN_R")
		)
		(pad "12" smd rect
			(at 1.500124 -1.249934 180)
			(size 0.2794 0.6096)
			(layers "F.Cu" "F.Mask" "F.Paste")
			(net "P12V_AUX")
		)
		(pad "13" smd rect
			(at 0 0 270)
			(size 1.9812 2.7178)
			(layers "F.Cu" "F.Mask" "F.Paste")
			(net "P12V_AUX")
		)
		(zone
			(layer "F.Cu")
			(hatch none 0.5)
			(connect_pads
				(clearance 0)
			)
			(min_thickness 0.25)
			(keepout
				(tracks not_allowed)
				(vias allowed)
				(pads allowed)
				(copperpour not_allowed)
				(footprints allowed)
			)
			(placement
				(enabled no)
				(sheetname "")
			)
			(fill
				(thermal_gap 0.5)
				(thermal_bridge_width 0.5)
				(island_removal_mode 0)
			)
			(polygon
				(pts
					(xy 99.182428 -97.825052) (xy 99.055428 -97.825052) (xy 96.083628 -97.825052) (xy 96.08312 -97.825052)
					(xy 96.08312 -100.111052) (xy 96.083628 -100.111052) (xy 96.210628 -100.111052) (xy 97.633028 -100.111052)
					(xy 97.633028 -100.009452) (xy 96.210628 -100.009452) (xy 96.210628 -97.926652) (xy 99.055428 -97.926652)
					(xy 99.055428 -100.009452) (xy 97.658428 -100.009452) (xy 97.658428 -100.111052) (xy 99.055428 -100.111052)
					(xy 99.182428 -100.111052) (xy 99.182936 -100.111052) (xy 99.182936 -97.825052)
				)
			)
		)
	)
	(footprint ""
		(layer "F.Cu")
		(at 371.956584 -17.419574 180)
		(property "Reference" "R1716"
			(at 0 0 180)
			(layer "F.SilkS")
			(hide yes)
			(effects
				(font
					(size 1.27 1.27)
				)
			)
		)
		(property "Value" ""
			(at 0 0 180)
			(layer "F.Fab")
			(effects
				(font
					(size 1.27 1.27)
				)
			)
		)
		(duplicate_pad_numbers_are_jumpers no)
		(fp_line
			(start 0.7874 0.4064)
			(end -0.7874 0.4064)
			(stroke
				(width 0.1524)
				(type default)
			)
			(layer "F.SilkS")
		)
		(fp_line
			(start 0.7874 -0.4064)
			(end 0.7874 0.4064)
			(stroke
				(width 0.1524)
				(type default)
			)
			(layer "F.SilkS")
		)
		(fp_line
			(start -0.7874 0.4064)
			(end -0.7874 -0.4064)
			(stroke
				(width 0.1524)
				(type default)
			)
			(layer "F.SilkS")
		)
		(fp_line
			(start -0.7874 -0.4064)
			(end 0.7874 -0.4064)
			(stroke
				(width 0.1524)
				(type default)
			)
			(layer "F.SilkS")
		)
		(fp_line
			(start 0.67945 0.3048)
			(end 0.120396 0.3048)
			(stroke
				(width 0.1)
				(type default)
			)
			(layer "F.Fab")
		)
		(fp_line
			(start 0.67945 -0.3048)
			(end 0.67945 0.3048)
			(stroke
				(width 0.1)
				(type default)
			)
			(layer "F.Fab")
		)
		(fp_line
			(start 0.12065 -0.2794)
			(end 0.12065 -0.3048)
			(stroke
				(width 0.1)
				(type default)
			)
			(layer "F.Fab")
		)
		(fp_line
			(start 0.12065 -0.3048)
			(end 0.67945 -0.3048)
			(stroke
				(width 0.1)
				(type default)
			)
			(layer "F.Fab")
		)
		(fp_line
			(start 0.120396 0.3048)
			(end 0.120396 0.2794)
			(stroke
				(width 0.1)
				(type default)
			)
			(layer "F.Fab")
		)
		(fp_line
			(start 0.120396 0.2794)
			(end -0.12065 0.2794)
			(stroke
				(width 0.1)
				(type default)
			)
			(layer "F.Fab")
		)
		(fp_line
			(start -0.12065 0.3048)
			(end -0.67945 0.3048)
			(stroke
				(width 0.1)
				(type default)
			)
			(layer "F.Fab")
		)
		(fp_line
			(start -0.12065 0.2794)
			(end -0.12065 0.3048)
			(stroke
				(width 0.1)
				(type default)
			)
			(layer "F.Fab")
		)
		(fp_line
			(start -0.12065 -0.2794)
			(end 0.12065 -0.2794)
			(stroke
				(width 0.1)
				(type default)
			)
			(layer "F.Fab")
		)
		(fp_line
			(start -0.12065 -0.305054)
			(end -0.12065 -0.2794)
			(stroke
				(width 0.1)
				(type default)
			)
			(layer "F.Fab")
		)
		(fp_line
			(start -0.67945 0.3048)
			(end -0.67945 -0.305054)
			(stroke
				(width 0.1)
				(type default)
			)
			(layer "F.Fab")
		)
		(fp_line
			(start -0.67945 -0.305054)
			(end -0.12065 -0.305054)
			(stroke
				(width 0.1)
				(type default)
			)
			(layer "F.Fab")
		)
		(pad "1" smd circle
			(at -0.40005 0 180)
			(size 0 0)
			(layers "F.Cu" "F.Mask" "F.Paste")
			(net "P3V3_SSD12")
		)
		(pad "2" smd circle
			(at 0.40005 0 180)
			(size 0 0)
			(layers "F.Cu" "F.Mask" "F.Paste")
			(net "SMB_ISO_SSD12_SCL")
		)
	)
	(footprint ""
		(layer "F.Cu")
		(at 20.399756 -174.271178 180)
		(property "Reference" "R501"
			(at 0 0 180)
			(layer "F.SilkS")
			(hide yes)
			(effects
				(font
					(size 1.27 1.27)
				)
			)
		)
		(property "Value" ""
			(at 0 0 180)
			(layer "F.Fab")
			(effects
				(font
					(size 1.27 1.27)
				)
			)
		)
		(duplicate_pad_numbers_are_jumpers no)
		(fp_line
			(start 0.7874 0.4064)
			(end -0.7874 0.4064)
			(stroke
				(width 0.1524)
				(type default)
			)
			(layer "F.SilkS")
		)
		(fp_line
			(start 0.7874 -0.4064)
			(end 0.7874 0.4064)
			(stroke
				(width 0.1524)
				(type default)
			)
			(layer "F.SilkS")
		)
		(fp_line
			(start -0.7874 0.4064)
			(end -0.7874 -0.4064)
			(stroke
				(width 0.1524)
				(type default)
			)
			(layer "F.SilkS")
		)
		(fp_line
			(start -0.7874 -0.4064)
			(end 0.7874 -0.4064)
			(stroke
				(width 0.1524)
				(type default)
			)
			(layer "F.SilkS")
		)
		(fp_line
			(start 0.67945 0.3048)
			(end 0.120396 0.3048)
			(stroke
				(width 0.1)
				(type default)
			)
			(layer "F.Fab")
		)
		(fp_line
			(start 0.67945 -0.3048)
			(end 0.67945 0.3048)
			(stroke
				(width 0.1)
				(type default)
			)
			(layer "F.Fab")
		)
		(fp_line
			(start 0.12065 -0.2794)
			(end 0.12065 -0.3048)
			(stroke
				(width 0.1)
				(type default)
			)
			(layer "F.Fab")
		)
		(fp_line
			(start 0.12065 -0.3048)
			(end 0.67945 -0.3048)
			(stroke
				(width 0.1)
				(type default)
			)
			(layer "F.Fab")
		)
		(fp_line
			(start 0.120396 0.3048)
			(end 0.120396 0.2794)
			(stroke
				(width 0.1)
				(type default)
			)
			(layer "F.Fab")
		)
		(fp_line
			(start 0.120396 0.2794)
			(end -0.12065 0.2794)
			(stroke
				(width 0.1)
				(type default)
			)
			(layer "F.Fab")
		)
		(fp_line
			(start -0.12065 0.3048)
			(end -0.67945 0.3048)
			(stroke
				(width 0.1)
				(type default)
			)
			(layer "F.Fab")
		)
		(fp_line
			(start -0.12065 0.2794)
			(end -0.12065 0.3048)
			(stroke
				(width 0.1)
				(type default)
			)
			(layer "F.Fab")
		)
		(fp_line
			(start -0.12065 -0.2794)
			(end 0.12065 -0.2794)
			(stroke
				(width 0.1)
				(type default)
			)
			(layer "F.Fab")
		)
		(fp_line
			(start -0.12065 -0.305054)
			(end -0.12065 -0.2794)
			(stroke
				(width 0.1)
				(type default)
			)
			(layer "F.Fab")
		)
		(fp_line
			(start -0.67945 0.3048)
			(end -0.67945 -0.305054)
			(stroke
				(width 0.1)
				(type default)
			)
			(layer "F.Fab")
		)
		(fp_line
			(start -0.67945 -0.305054)
			(end -0.12065 -0.305054)
			(stroke
				(width 0.1)
				(type default)
			)
			(layer "F.Fab")
		)
		(pad "1" smd circle
			(at -0.40005 0 180)
			(size 0 0)
			(layers "F.Cu" "F.Mask" "F.Paste")
			(net "P5V_AUX")
		)
		(pad "2" smd circle
			(at 0.40005 0 180)
			(size 0 0)
			(layers "F.Cu" "F.Mask" "F.Paste")
			(net "PWRGD_P5V_AUX")
		)
	)
	(footprint ""
		(layer "F.Cu")
		(at 135.626856 -55.418228 90)
		(property "Reference" "PC358"
			(at 0 0 90)
			(layer "F.SilkS")
			(hide yes)
			(effects
				(font
					(size 1.27 1.27)
				)
			)
		)
		(property "Value" ""
			(at 0 0 90)
			(layer "F.Fab")
			(effects
				(font
					(size 1.27 1.27)
				)
			)
		)
		(duplicate_pad_numbers_are_jumpers no)
		(fp_line
			(start 0.7874 -0.4064)
			(end 0.7874 0.4064)
			(stroke
				(width 0.1524)
				(type default)
			)
			(layer "F.SilkS")
		)
		(fp_line
			(start -0.7874 -0.4064)
			(end 0.7874 -0.4064)
			(stroke
				(width 0.1524)
				(type default)
			)
			(layer "F.SilkS")
		)
		(fp_line
			(start 0.7874 0.4064)
			(end -0.7874 0.4064)
			(stroke
				(width 0.1524)
				(type default)
			)
			(layer "F.SilkS")
		)
		(fp_line
			(start -0.7874 0.4064)
			(end -0.7874 -0.4064)
			(stroke
				(width 0.1524)
				(type default)
			)
			(layer "F.SilkS")
		)
		(fp_line
			(start -0.12065 -0.305054)
			(end -0.12065 -0.2794)
			(stroke
				(width 0.1)
				(type default)
			)
			(layer "F.Fab")
		)
		(fp_line
			(start -0.67945 -0.305054)
			(end -0.12065 -0.305054)
			(stroke
				(width 0.1)
				(type default)
			)
			(layer "F.Fab")
		)
		(fp_line
			(start 0.67945 -0.3048)
			(end 0.67945 0.3048)
			(stroke
				(width 0.1)
				(type default)
			)
			(layer "F.Fab")
		)
		(fp_line
			(start 0.12065 -0.3048)
			(end 0.67945 -0.3048)
			(stroke
				(width 0.1)
				(type default)
			)
			(layer "F.Fab")
		)
		(fp_line
			(start 0.12065 -0.2794)
			(end 0.12065 -0.3048)
			(stroke
				(width 0.1)
				(type default)
			)
			(layer "F.Fab")
		)
		(fp_line
			(start -0.12065 -0.2794)
			(end 0.12065 -0.2794)
			(stroke
				(width 0.1)
				(type default)
			)
			(layer "F.Fab")
		)
		(fp_line
			(start 0.120396 0.2794)
			(end -0.12065 0.2794)
			(stroke
				(width 0.1)
				(type default)
			)
			(layer "F.Fab")
		)
		(fp_line
			(start -0.12065 0.2794)
			(end -0.12065 0.3048)
			(stroke
				(width 0.1)
				(type default)
			)
			(layer "F.Fab")
		)
		(fp_line
			(start 0.67945 0.3048)
			(end 0.120396 0.3048)
			(stroke
				(width 0.1)
				(type default)
			)
			(layer "F.Fab")
		)
		(fp_line
			(start 0.120396 0.3048)
			(end 0.120396 0.2794)
			(stroke
				(width 0.1)
				(type default)
			)
			(layer "F.Fab")
		)
		(fp_line
			(start -0.12065 0.3048)
			(end -0.67945 0.3048)
			(stroke
				(width 0.1)
				(type default)
			)
			(layer "F.Fab")
		)
		(fp_line
			(start -0.67945 0.3048)
			(end -0.67945 -0.305054)
			(stroke
				(width 0.1)
				(type default)
			)
			(layer "F.Fab")
		)
		(pad "1" smd circle
			(at -0.40005 0 90)
			(size 0 0)
			(layers "F.Cu" "F.Mask" "F.Paste")
			(net "P12V_SSD4_R")
		)
		(pad "2" smd circle
			(at 0.40005 0 90)
			(size 0 0)
			(layers "F.Cu" "F.Mask" "F.Paste")
			(net "GND")
		)
	)
	(footprint ""
		(layer "F.Cu")
		(at 339.229192 -105.253536)
		(property "Reference" "PD97"
			(at 1.130808 2.791206 0)
			(unlocked yes)
			(layer "F.SilkS")
			(effects
				(font
					(size 0.7874 0.5842)
					(thickness 0.1524)
				)
				(justify left)
			)
		)
		(property "Value" ""
			(at 0 0 0)
			(layer "F.Fab")
			(effects
				(font
					(size 1.27 1.27)
				)
			)
		)
		(duplicate_pad_numbers_are_jumpers no)
		(fp_line
			(start -3.656584 -1.970024)
			(end -3.656584 1.970024)
			(stroke
				(width 0.1524)
				(type default)
			)
			(layer "F.SilkS")
		)
		(fp_line
			(start -3.656584 1.970024)
			(end 4.240784 1.970024)
			(stroke
				(width 0.1524)
				(type default)
			)
			(layer "F.SilkS")
		)
		(fp_line
			(start 4.240784 -1.970024)
			(end -3.656584 -1.970024)
			(stroke
				(width 0.1524)
				(type default)
			)
			(layer "F.SilkS")
		)
		(fp_line
			(start 4.240784 1.970024)
			(end 4.240784 -1.970024)
			(stroke
				(width 0.1524)
				(type default)
			)
			(layer "F.SilkS")
		)
		(fp_rect
			(start 3.580384 1.970024)
			(end 4.240784 -1.970024)
			(stroke
				(width 0)
				(type default)
			)
			(fill yes)
			(layer "F.SilkS")
		)
		(fp_line
			(start -2.3749 -1.970024)
			(end -2.3749 1.970024)
			(stroke
				(width 0.1)
				(type default)
			)
			(layer "F.Fab")
		)
		(fp_line
			(start -2.3749 1.970024)
			(end 2.3749 1.970024)
			(stroke
				(width 0.1)
				(type default)
			)
			(layer "F.Fab")
		)
		(fp_line
			(start 2.3749 -1.970024)
			(end -2.3749 -1.970024)
			(stroke
				(width 0.1)
				(type default)
			)
			(layer "F.Fab")
		)
		(fp_line
			(start 2.3749 1.970024)
			(end 2.3749 -1.970024)
			(stroke
				(width 0.1)
				(type default)
			)
			(layer "F.Fab")
		)
		(fp_text user "+"
			(at -4.9784 -0.23495 0)
			(unlocked yes)
			(layer "F.Fab")
			(effects
				(font
					(size 1.905 1.4224)
					(thickness 0.1524)
				)
				(justify left)
			)
		)
		(fp_text user "-"
			(at 4.1656 -0.23495 0)
			(unlocked yes)
			(layer "F.Fab")
			(effects
				(font
					(size 1.905 1.4224)
					(thickness 0.1524)
				)
				(justify left)
			)
		)
		(pad "A" smd rect
			(at -2.450084 0)
			(size 2.159 2.2606)
			(layers "F.Cu" "F.Mask" "F.Paste")
			(net "GND")
		)
		(pad "C" smd rect
			(at 2.450084 0)
			(size 2.159 2.2606)
			(layers "F.Cu" "F.Mask" "F.Paste")
			(net "P12V_AUX")
		)
	)
	(footprint ""
		(layer "F.Cu")
		(at 352.920554 -88.359234)
		(property "Reference" "R1617"
			(at 0 0 0)
			(layer "F.SilkS")
			(hide yes)
			(effects
				(font
					(size 1.27 1.27)
				)
			)
		)
		(property "Value" ""
			(at 0 0 0)
			(layer "F.Fab")
			(effects
				(font
					(size 1.27 1.27)
				)
			)
		)
		(duplicate_pad_numbers_are_jumpers no)
		(fp_line
			(start -0.7874 -0.4064)
			(end 0.7874 -0.4064)
			(stroke
				(width 0.1524)
				(type default)
			)
			(layer "F.SilkS")
		)
		(fp_line
			(start -0.7874 0.4064)
			(end -0.7874 -0.4064)
			(stroke
				(width 0.1524)
				(type default)
			)
			(layer "F.SilkS")
		)
		(fp_line
			(start 0.7874 -0.4064)
			(end 0.7874 0.4064)
			(stroke
				(width 0.1524)
				(type default)
			)
			(layer "F.SilkS")
		)
		(fp_line
			(start 0.7874 0.4064)
			(end -0.7874 0.4064)
			(stroke
				(width 0.1524)
				(type default)
			)
			(layer "F.SilkS")
		)
		(fp_line
			(start -0.67945 -0.305054)
			(end -0.12065 -0.305054)
			(stroke
				(width 0.1)
				(type default)
			)
			(layer "F.Fab")
		)
		(fp_line
			(start -0.67945 0.3048)
			(end -0.67945 -0.305054)
			(stroke
				(width 0.1)
				(type default)
			)
			(layer "F.Fab")
		)
		(fp_line
			(start -0.12065 -0.305054)
			(end -0.12065 -0.2794)
			(stroke
				(width 0.1)
				(type default)
			)
			(layer "F.Fab")
		)
		(fp_line
			(start -0.12065 -0.2794)
			(end 0.12065 -0.2794)
			(stroke
				(width 0.1)
				(type default)
			)
			(layer "F.Fab")
		)
		(fp_line
			(start -0.12065 0.2794)
			(end -0.12065 0.3048)
			(stroke
				(width 0.1)
				(type default)
			)
			(layer "F.Fab")
		)
		(fp_line
			(start -0.12065 0.3048)
			(end -0.67945 0.3048)
			(stroke
				(width 0.1)
				(type default)
			)
			(layer "F.Fab")
		)
		(fp_line
			(start 0.120396 0.2794)
			(end -0.12065 0.2794)
			(stroke
				(width 0.1)
				(type default)
			)
			(layer "F.Fab")
		)
		(fp_line
			(start 0.120396 0.3048)
			(end 0.120396 0.2794)
			(stroke
				(width 0.1)
				(type default)
			)
			(layer "F.Fab")
		)
		(fp_line
			(start 0.12065 -0.3048)
			(end 0.67945 -0.3048)
			(stroke
				(width 0.1)
				(type default)
			)
			(layer "F.Fab")
		)
		(fp_line
			(start 0.12065 -0.2794)
			(end 0.12065 -0.3048)
			(stroke
				(width 0.1)
				(type default)
			)
			(layer "F.Fab")
		)
		(fp_line
			(start 0.67945 -0.3048)
			(end 0.67945 0.3048)
			(stroke
				(width 0.1)
				(type default)
			)
			(layer "F.Fab")
		)
		(fp_line
			(start 0.67945 0.3048)
			(end 0.120396 0.3048)
			(stroke
				(width 0.1)
				(type default)
			)
			(layer "F.Fab")
		)
		(pad "1" smd circle
			(at -0.40005 0)
			(size 0 0)
			(layers "F.Cu" "F.Mask" "F.Paste")
			(net "SMB_BIC_I2C9_MUX1_SSD8_R_SCL")
		)
		(pad "2" smd circle
			(at 0.40005 0)
			(size 0 0)
			(layers "F.Cu" "F.Mask" "F.Paste")
			(net "SMB_BIC_I2C9_MUX1_SSD8_SCL")
		)
	)
	(footprint ""
		(layer "F.Cu")
		(at 72.43445 -30.03169 180)
		(property "Reference" "C86"
			(at 0 0 180)
			(layer "F.SilkS")
			(hide yes)
			(effects
				(font
					(size 1.27 1.27)
				)
			)
		)
		(property "Value" ""
			(at 0 0 180)
			(layer "F.Fab")
			(effects
				(font
					(size 1.27 1.27)
				)
			)
		)
		(duplicate_pad_numbers_are_jumpers no)
		(fp_line
			(start 0.299974 0.150114)
			(end -0.299974 0.150114)
			(stroke
				(width 0.1)
				(type default)
			)
			(layer "F.Fab")
		)
		(fp_line
			(start 0.299974 -0.150114)
			(end 0.299974 0.150114)
			(stroke
				(width 0.1)
				(type default)
			)
			(layer "F.Fab")
		)
		(fp_line
			(start -0.299974 0.150114)
			(end -0.299974 -0.150114)
			(stroke
				(width 0.1)
				(type default)
			)
			(layer "F.Fab")
		)
		(fp_line
			(start -0.299974 -0.150114)
			(end 0.299974 -0.150114)
			(stroke
				(width 0.1)
				(type default)
			)
			(layer "F.Fab")
		)
		(pad "1" smd rect
			(at -0.2667 0 180)
			(size 0.3048 0.381)
			(layers "F.Cu" "F.Mask" "F.Paste")
			(net "P5E_PEX0_STN2_TX_DN<37>")
		)
		(pad "2" smd rect
			(at 0.2667 0 180)
			(size 0.3048 0.381)
			(layers "F.Cu" "F.Mask" "F.Paste")
			(net "P5E_PEX0_STN2_TX_C_DN<37>")
		)
	)
	(footprint ""
		(layer "F.Cu")
		(at 82.661506 -136.20115 180)
		(property "Reference" "C17"
			(at 0 0 180)
			(layer "F.SilkS")
			(hide yes)
			(effects
				(font
					(size 1.27 1.27)
				)
			)
		)
		(property "Value" ""
			(at 0 0 180)
			(layer "F.Fab")
			(effects
				(font
					(size 1.27 1.27)
				)
			)
		)
		(duplicate_pad_numbers_are_jumpers no)
		(fp_line
			(start 0.299974 0.150114)
			(end -0.299974 0.150114)
			(stroke
				(width 0.1)
				(type default)
			)
			(layer "F.Fab")
		)
		(fp_line
			(start 0.299974 -0.150114)
			(end 0.299974 0.150114)
			(stroke
				(width 0.1)
				(type default)
			)
			(layer "F.Fab")
		)
		(fp_line
			(start -0.299974 0.150114)
			(end -0.299974 -0.150114)
			(stroke
				(width 0.1)
				(type default)
			)
			(layer "F.Fab")
		)
		(fp_line
			(start -0.299974 -0.150114)
			(end 0.299974 -0.150114)
			(stroke
				(width 0.1)
				(type default)
			)
			(layer "F.Fab")
		)
		(pad "1" smd rect
			(at -0.2667 0 180)
			(size 0.3048 0.381)
			(layers "F.Cu" "F.Mask" "F.Paste")
			(net "P5E_PEX0_STN0_TX_DP<7>")
		)
		(pad "2" smd rect
			(at 0.2667 0 180)
			(size 0.3048 0.381)
			(layers "F.Cu" "F.Mask" "F.Paste")
			(net "P5E_PEX0_STN0_TX_C_DP<7>")
		)
	)
	(footprint ""
		(layer "F.Cu")
		(at 314.861448 -151.596852 180)
		(property "Reference" "C428"
			(at 0 0 180)
			(layer "F.SilkS")
			(hide yes)
			(effects
				(font
					(size 1.27 1.27)
				)
			)
		)
		(property "Value" ""
			(at 0 0 180)
			(layer "F.Fab")
			(effects
				(font
					(size 1.27 1.27)
				)
			)
		)
		(duplicate_pad_numbers_are_jumpers no)
		(fp_line
			(start 0.299974 0.150114)
			(end -0.299974 0.150114)
			(stroke
				(width 0.1)
				(type default)
			)
			(layer "F.Fab")
		)
		(fp_line
			(start 0.299974 -0.150114)
			(end 0.299974 0.150114)
			(stroke
				(width 0.1)
				(type default)
			)
			(layer "F.Fab")
		)
		(fp_line
			(start -0.299974 0.150114)
			(end -0.299974 -0.150114)
			(stroke
				(width 0.1)
				(type default)
			)
			(layer "F.Fab")
		)
		(fp_line
			(start -0.299974 -0.150114)
			(end 0.299974 -0.150114)
			(stroke
				(width 0.1)
				(type default)
			)
			(layer "F.Fab")
		)
		(pad "1" smd rect
			(at -0.2667 0 180)
			(size 0.3048 0.381)
			(layers "F.Cu" "F.Mask" "F.Paste")
			(net "P5E_PEX2_STN0_TX_DN<13>")
		)
		(pad "2" smd rect
			(at 0.2667 0 180)
			(size 0.3048 0.381)
			(layers "F.Cu" "F.Mask" "F.Paste")
			(net "P5E_PEX2_STN0_TX_C_DN<13>")
		)
	)
	(footprint ""
		(layer "F.Cu")
		(at 57.866788 -52.543456 180)
		(property "Reference" "PC524"
			(at 0 0 180)
			(layer "F.SilkS")
			(hide yes)
			(effects
				(font
					(size 1.27 1.27)
				)
			)
		)
		(property "Value" ""
			(at 0 0 180)
			(layer "F.Fab")
			(effects
				(font
					(size 1.27 1.27)
				)
			)
		)
		(duplicate_pad_numbers_are_jumpers no)
		(fp_line
			(start 0.7874 0.4064)
			(end -0.7874 0.4064)
			(stroke
				(width 0.1524)
				(type default)
			)
			(layer "F.SilkS")
		)
		(fp_line
			(start 0.7874 -0.4064)
			(end 0.7874 0.4064)
			(stroke
				(width 0.1524)
				(type default)
			)
			(layer "F.SilkS")
		)
		(fp_line
			(start -0.7874 0.4064)
			(end -0.7874 -0.4064)
			(stroke
				(width 0.1524)
				(type default)
			)
			(layer "F.SilkS")
		)
		(fp_line
			(start -0.7874 -0.4064)
			(end 0.7874 -0.4064)
			(stroke
				(width 0.1524)
				(type default)
			)
			(layer "F.SilkS")
		)
		(fp_line
			(start 0.67945 0.3048)
			(end 0.120396 0.3048)
			(stroke
				(width 0.1)
				(type default)
			)
			(layer "F.Fab")
		)
		(fp_line
			(start 0.67945 -0.3048)
			(end 0.67945 0.3048)
			(stroke
				(width 0.1)
				(type default)
			)
			(layer "F.Fab")
		)
		(fp_line
			(start 0.12065 -0.2794)
			(end 0.12065 -0.3048)
			(stroke
				(width 0.1)
				(type default)
			)
			(layer "F.Fab")
		)
		(fp_line
			(start 0.12065 -0.3048)
			(end 0.67945 -0.3048)
			(stroke
				(width 0.1)
				(type default)
			)
			(layer "F.Fab")
		)
		(fp_line
			(start 0.120396 0.3048)
			(end 0.120396 0.2794)
			(stroke
				(width 0.1)
				(type default)
			)
			(layer "F.Fab")
		)
		(fp_line
			(start 0.120396 0.2794)
			(end -0.12065 0.2794)
			(stroke
				(width 0.1)
				(type default)
			)
			(layer "F.Fab")
		)
		(fp_line
			(start -0.12065 0.3048)
			(end -0.67945 0.3048)
			(stroke
				(width 0.1)
				(type default)
			)
			(layer "F.Fab")
		)
		(fp_line
			(start -0.12065 0.2794)
			(end -0.12065 0.3048)
			(stroke
				(width 0.1)
				(type default)
			)
			(layer "F.Fab")
		)
		(fp_line
			(start -0.12065 -0.2794)
			(end 0.12065 -0.2794)
			(stroke
				(width 0.1)
				(type default)
			)
			(layer "F.Fab")
		)
		(fp_line
			(start -0.12065 -0.305054)
			(end -0.12065 -0.2794)
			(stroke
				(width 0.1)
				(type default)
			)
			(layer "F.Fab")
		)
		(fp_line
			(start -0.67945 0.3048)
			(end -0.67945 -0.305054)
			(stroke
				(width 0.1)
				(type default)
			)
			(layer "F.Fab")
		)
		(fp_line
			(start -0.67945 -0.305054)
			(end -0.12065 -0.305054)
			(stroke
				(width 0.1)
				(type default)
			)
			(layer "F.Fab")
		)
		(pad "1" smd circle
			(at -0.40005 0 180)
			(size 0 0)
			(layers "F.Cu" "F.Mask" "F.Paste")
			(net "P3V3_SSD2")
		)
		(pad "2" smd circle
			(at 0.40005 0 180)
			(size 0 0)
			(layers "F.Cu" "F.Mask" "F.Paste")
			(net "GND")
		)
	)
	(footprint ""
		(layer "F.Cu")
		(at 328.01814 -95.31477 90)
		(property "Reference" "R856"
			(at 0 0 90)
			(layer "F.SilkS")
			(hide yes)
			(effects
				(font
					(size 1.27 1.27)
				)
			)
		)
		(property "Value" ""
			(at 0 0 90)
			(layer "F.Fab")
			(effects
				(font
					(size 1.27 1.27)
				)
			)
		)
		(duplicate_pad_numbers_are_jumpers no)
		(fp_line
			(start 0.7874 -0.4064)
			(end 0.7874 0.4064)
			(stroke
				(width 0.1524)
				(type default)
			)
			(layer "F.SilkS")
		)
		(fp_line
			(start -0.7874 -0.4064)
			(end 0.7874 -0.4064)
			(stroke
				(width 0.1524)
				(type default)
			)
			(layer "F.SilkS")
		)
		(fp_line
			(start 0.7874 0.4064)
			(end -0.7874 0.4064)
			(stroke
				(width 0.1524)
				(type default)
			)
			(layer "F.SilkS")
		)
		(fp_line
			(start -0.7874 0.4064)
			(end -0.7874 -0.4064)
			(stroke
				(width 0.1524)
				(type default)
			)
			(layer "F.SilkS")
		)
		(fp_line
			(start -0.12065 -0.305054)
			(end -0.12065 -0.2794)
			(stroke
				(width 0.1)
				(type default)
			)
			(layer "F.Fab")
		)
		(fp_line
			(start -0.67945 -0.305054)
			(end -0.12065 -0.305054)
			(stroke
				(width 0.1)
				(type default)
			)
			(layer "F.Fab")
		)
		(fp_line
			(start 0.67945 -0.3048)
			(end 0.67945 0.3048)
			(stroke
				(width 0.1)
				(type default)
			)
			(layer "F.Fab")
		)
		(fp_line
			(start 0.12065 -0.3048)
			(end 0.67945 -0.3048)
			(stroke
				(width 0.1)
				(type default)
			)
			(layer "F.Fab")
		)
		(fp_line
			(start 0.12065 -0.2794)
			(end 0.12065 -0.3048)
			(stroke
				(width 0.1)
				(type default)
			)
			(layer "F.Fab")
		)
		(fp_line
			(start -0.12065 -0.2794)
			(end 0.12065 -0.2794)
			(stroke
				(width 0.1)
				(type default)
			)
			(layer "F.Fab")
		)
		(fp_line
			(start 0.120396 0.2794)
			(end -0.12065 0.2794)
			(stroke
				(width 0.1)
				(type default)
			)
			(layer "F.Fab")
		)
		(fp_line
			(start -0.12065 0.2794)
			(end -0.12065 0.3048)
			(stroke
				(width 0.1)
				(type default)
			)
			(layer "F.Fab")
		)
		(fp_line
			(start 0.67945 0.3048)
			(end 0.120396 0.3048)
			(stroke
				(width 0.1)
				(type default)
			)
			(layer "F.Fab")
		)
		(fp_line
			(start 0.120396 0.3048)
			(end 0.120396 0.2794)
			(stroke
				(width 0.1)
				(type default)
			)
			(layer "F.Fab")
		)
		(fp_line
			(start -0.12065 0.3048)
			(end -0.67945 0.3048)
			(stroke
				(width 0.1)
				(type default)
			)
			(layer "F.Fab")
		)
		(fp_line
			(start -0.67945 0.3048)
			(end -0.67945 -0.305054)
			(stroke
				(width 0.1)
				(type default)
			)
			(layer "F.Fab")
		)
		(pad "1" smd circle
			(at -0.40005 0 90)
			(size 0 0)
			(layers "F.Cu" "F.Mask" "F.Paste")
			(net "P3V3_AUX")
		)
		(pad "2" smd circle
			(at 0.40005 0 90)
			(size 0 0)
			(layers "F.Cu" "F.Mask" "F.Paste")
			(net "PWRGD_P12V_NIC5")
		)
	)
	(footprint ""
		(layer "F.Cu")
		(at 361.188 -188.214 180)
		(property "Reference" "R4644"
			(at 0 0 180)
			(layer "F.SilkS")
			(hide yes)
			(effects
				(font
					(size 1.27 1.27)
				)
			)
		)
		(property "Value" ""
			(at 0 0 180)
			(layer "F.Fab")
			(effects
				(font
					(size 1.27 1.27)
				)
			)
		)
		(duplicate_pad_numbers_are_jumpers no)
		(fp_line
			(start 0.7874 0.4064)
			(end -0.7874 0.4064)
			(stroke
				(width 0.1524)
				(type default)
			)
			(layer "F.SilkS")
		)
		(fp_line
			(start 0.7874 -0.4064)
			(end 0.7874 0.4064)
			(stroke
				(width 0.1524)
				(type default)
			)
			(layer "F.SilkS")
		)
		(fp_line
			(start -0.7874 0.4064)
			(end -0.7874 -0.4064)
			(stroke
				(width 0.1524)
				(type default)
			)
			(layer "F.SilkS")
		)
		(fp_line
			(start -0.7874 -0.4064)
			(end 0.7874 -0.4064)
			(stroke
				(width 0.1524)
				(type default)
			)
			(layer "F.SilkS")
		)
		(fp_line
			(start 0.67945 0.3048)
			(end 0.120396 0.3048)
			(stroke
				(width 0.1)
				(type default)
			)
			(layer "F.Fab")
		)
		(fp_line
			(start 0.67945 -0.3048)
			(end 0.67945 0.3048)
			(stroke
				(width 0.1)
				(type default)
			)
			(layer "F.Fab")
		)
		(fp_line
			(start 0.12065 -0.2794)
			(end 0.12065 -0.3048)
			(stroke
				(width 0.1)
				(type default)
			)
			(layer "F.Fab")
		)
		(fp_line
			(start 0.12065 -0.3048)
			(end 0.67945 -0.3048)
			(stroke
				(width 0.1)
				(type default)
			)
			(layer "F.Fab")
		)
		(fp_line
			(start 0.120396 0.3048)
			(end 0.120396 0.2794)
			(stroke
				(width 0.1)
				(type default)
			)
			(layer "F.Fab")
		)
		(fp_line
			(start 0.120396 0.2794)
			(end -0.12065 0.2794)
			(stroke
				(width 0.1)
				(type default)
			)
			(layer "F.Fab")
		)
		(fp_line
			(start -0.12065 0.3048)
			(end -0.67945 0.3048)
			(stroke
				(width 0.1)
				(type default)
			)
			(layer "F.Fab")
		)
		(fp_line
			(start -0.12065 0.2794)
			(end -0.12065 0.3048)
			(stroke
				(width 0.1)
				(type default)
			)
			(layer "F.Fab")
		)
		(fp_line
			(start -0.12065 -0.2794)
			(end 0.12065 -0.2794)
			(stroke
				(width 0.1)
				(type default)
			)
			(layer "F.Fab")
		)
		(fp_line
			(start -0.12065 -0.305054)
			(end -0.12065 -0.2794)
			(stroke
				(width 0.1)
				(type default)
			)
			(layer "F.Fab")
		)
		(fp_line
			(start -0.67945 0.3048)
			(end -0.67945 -0.305054)
			(stroke
				(width 0.1)
				(type default)
			)
			(layer "F.Fab")
		)
		(fp_line
			(start -0.67945 -0.305054)
			(end -0.12065 -0.305054)
			(stroke
				(width 0.1)
				(type default)
			)
			(layer "F.Fab")
		)
		(pad "1" smd circle
			(at -0.40005 0 180)
			(size 0 0)
			(layers "F.Cu" "F.Mask" "F.Paste")
			(net "RST_PEX_SSD2_PERST_N")
		)
		(pad "2" smd circle
			(at 0.40005 0 180)
			(size 0 0)
			(layers "F.Cu" "F.Mask" "F.Paste")
			(net "RST_PEX_SSD2_PERST_R_N")
		)
	)
	(footprint ""
		(layer "F.Cu")
		(at 5.656326 -66.567812 180)
		(property "Reference" "R5868"
			(at 0 0 180)
			(layer "F.SilkS")
			(hide yes)
			(effects
				(font
					(size 1.27 1.27)
				)
			)
		)
		(property "Value" ""
			(at 0 0 180)
			(layer "F.Fab")
			(effects
				(font
					(size 1.27 1.27)
				)
			)
		)
		(duplicate_pad_numbers_are_jumpers no)
		(fp_line
			(start 0.7874 0.4064)
			(end -0.7874 0.4064)
			(stroke
				(width 0.1524)
				(type default)
			)
			(layer "F.SilkS")
		)
		(fp_line
			(start 0.7874 -0.4064)
			(end 0.7874 0.4064)
			(stroke
				(width 0.1524)
				(type default)
			)
			(layer "F.SilkS")
		)
		(fp_line
			(start -0.7874 0.4064)
			(end -0.7874 -0.4064)
			(stroke
				(width 0.1524)
				(type default)
			)
			(layer "F.SilkS")
		)
		(fp_line
			(start -0.7874 -0.4064)
			(end 0.7874 -0.4064)
			(stroke
				(width 0.1524)
				(type default)
			)
			(layer "F.SilkS")
		)
		(fp_line
			(start 0.67945 0.3048)
			(end 0.120396 0.3048)
			(stroke
				(width 0.1)
				(type default)
			)
			(layer "F.Fab")
		)
		(fp_line
			(start 0.67945 -0.3048)
			(end 0.67945 0.3048)
			(stroke
				(width 0.1)
				(type default)
			)
			(layer "F.Fab")
		)
		(fp_line
			(start 0.12065 -0.2794)
			(end 0.12065 -0.3048)
			(stroke
				(width 0.1)
				(type default)
			)
			(layer "F.Fab")
		)
		(fp_line
			(start 0.12065 -0.3048)
			(end 0.67945 -0.3048)
			(stroke
				(width 0.1)
				(type default)
			)
			(layer "F.Fab")
		)
		(fp_line
			(start 0.120396 0.3048)
			(end 0.120396 0.2794)
			(stroke
				(width 0.1)
				(type default)
			)
			(layer "F.Fab")
		)
		(fp_line
			(start 0.120396 0.2794)
			(end -0.12065 0.2794)
			(stroke
				(width 0.1)
				(type default)
			)
			(layer "F.Fab")
		)
		(fp_line
			(start -0.12065 0.3048)
			(end -0.67945 0.3048)
			(stroke
				(width 0.1)
				(type default)
			)
			(layer "F.Fab")
		)
		(fp_line
			(start -0.12065 0.2794)
			(end -0.12065 0.3048)
			(stroke
				(width 0.1)
				(type default)
			)
			(layer "F.Fab")
		)
		(fp_line
			(start -0.12065 -0.2794)
			(end 0.12065 -0.2794)
			(stroke
				(width 0.1)
				(type default)
			)
			(layer "F.Fab")
		)
		(fp_line
			(start -0.12065 -0.305054)
			(end -0.12065 -0.2794)
			(stroke
				(width 0.1)
				(type default)
			)
			(layer "F.Fab")
		)
		(fp_line
			(start -0.67945 0.3048)
			(end -0.67945 -0.305054)
			(stroke
				(width 0.1)
				(type default)
			)
			(layer "F.Fab")
		)
		(fp_line
			(start -0.67945 -0.305054)
			(end -0.12065 -0.305054)
			(stroke
				(width 0.1)
				(type default)
			)
			(layer "F.Fab")
		)
		(pad "1" smd circle
			(at -0.40005 0 180)
			(size 0 0)
			(layers "F.Cu" "F.Mask" "F.Paste")
			(net "P3V3_AUX")
		)
		(pad "2" smd circle
			(at 0.40005 0 180)
			(size 0 0)
			(layers "F.Cu" "F.Mask" "F.Paste")
			(net "PWRGD_P3V3_SSD0_D")
		)
	)
	(footprint ""
		(layer "F.Cu")
		(at 400.567906 -54.067456)
		(property "Reference" "PR230"
			(at 0 0 0)
			(layer "F.SilkS")
			(hide yes)
			(effects
				(font
					(size 1.27 1.27)
				)
			)
		)
		(property "Value" ""
			(at 0 0 0)
			(layer "F.Fab")
			(effects
				(font
					(size 1.27 1.27)
				)
			)
		)
		(duplicate_pad_numbers_are_jumpers no)
		(fp_line
			(start -0.7874 -0.4064)
			(end 0.7874 -0.4064)
			(stroke
				(width 0.1524)
				(type default)
			)
			(layer "F.SilkS")
		)
		(fp_line
			(start -0.7874 0.4064)
			(end -0.7874 -0.4064)
			(stroke
				(width 0.1524)
				(type default)
			)
			(layer "F.SilkS")
		)
		(fp_line
			(start 0.7874 -0.4064)
			(end 0.7874 0.4064)
			(stroke
				(width 0.1524)
				(type default)
			)
			(layer "F.SilkS")
		)
		(fp_line
			(start 0.7874 0.4064)
			(end -0.7874 0.4064)
			(stroke
				(width 0.1524)
				(type default)
			)
			(layer "F.SilkS")
		)
		(fp_line
			(start -0.67945 -0.305054)
			(end -0.12065 -0.305054)
			(stroke
				(width 0.1)
				(type default)
			)
			(layer "F.Fab")
		)
		(fp_line
			(start -0.67945 0.3048)
			(end -0.67945 -0.305054)
			(stroke
				(width 0.1)
				(type default)
			)
			(layer "F.Fab")
		)
		(fp_line
			(start -0.12065 -0.305054)
			(end -0.12065 -0.2794)
			(stroke
				(width 0.1)
				(type default)
			)
			(layer "F.Fab")
		)
		(fp_line
			(start -0.12065 -0.2794)
			(end 0.12065 -0.2794)
			(stroke
				(width 0.1)
				(type default)
			)
			(layer "F.Fab")
		)
		(fp_line
			(start -0.12065 0.2794)
			(end -0.12065 0.3048)
			(stroke
				(width 0.1)
				(type default)
			)
			(layer "F.Fab")
		)
		(fp_line
			(start -0.12065 0.3048)
			(end -0.67945 0.3048)
			(stroke
				(width 0.1)
				(type default)
			)
			(layer "F.Fab")
		)
		(fp_line
			(start 0.120396 0.2794)
			(end -0.12065 0.2794)
			(stroke
				(width 0.1)
				(type default)
			)
			(layer "F.Fab")
		)
		(fp_line
			(start 0.120396 0.3048)
			(end 0.120396 0.2794)
			(stroke
				(width 0.1)
				(type default)
			)
			(layer "F.Fab")
		)
		(fp_line
			(start 0.12065 -0.3048)
			(end 0.67945 -0.3048)
			(stroke
				(width 0.1)
				(type default)
			)
			(layer "F.Fab")
		)
		(fp_line
			(start 0.12065 -0.2794)
			(end 0.12065 -0.3048)
			(stroke
				(width 0.1)
				(type default)
			)
			(layer "F.Fab")
		)
		(fp_line
			(start 0.67945 -0.3048)
			(end 0.67945 0.3048)
			(stroke
				(width 0.1)
				(type default)
			)
			(layer "F.Fab")
		)
		(fp_line
			(start 0.67945 0.3048)
			(end 0.120396 0.3048)
			(stroke
				(width 0.1)
				(type default)
			)
			(layer "F.Fab")
		)
		(pad "1" smd circle
			(at -0.40005 0)
			(size 0 0)
			(layers "F.Cu" "F.Mask" "F.Paste")
			(net "P12V_SSD13_OCP")
		)
		(pad "2" smd circle
			(at 0.40005 0)
			(size 0 0)
			(layers "F.Cu" "F.Mask" "F.Paste")
			(net "GND")
		)
	)
	(footprint ""
		(layer "F.Cu")
		(at 271.899888 -378.70003)
		(property "Reference" "H78"
			(at 7.60222 -4.224782 0)
			(unlocked yes)
			(layer "F.SilkS")
			(effects
				(font
					(size 0.7874 0.5842)
					(thickness 0.1524)
				)
				(justify left)
			)
		)
		(property "Value" ""
			(at 0 0 0)
			(layer "F.Fab")
			(effects
				(font
					(size 1.27 1.27)
				)
			)
		)
		(duplicate_pad_numbers_are_jumpers no)
		(fp_arc
			(start 1.57988 -7.842504)
			(mid 6.190226 -5.067585)
			(end 7.999984 0)
			(stroke
				(width 0.1524)
				(type default)
			)
			(layer "F.SilkS")
		)
		(fp_arc
			(start 7.999984 0)
			(mid -3.377445 7.252026)
			(end -5.148072 -6.123432)
			(stroke
				(width 0.1524)
				(type default)
			)
			(layer "F.SilkS")
		)
		(fp_arc
			(start 1.711198 -7.814818)
			(mid 6.232558 -5.015484)
			(end 7.999984 0)
			(stroke
				(width 0.1524)
				(type default)
			)
			(layer "B.SilkS")
		)
		(fp_arc
			(start 7.999984 0)
			(mid -3.325733 7.27586)
			(end -5.234686 -6.049518)
			(stroke
				(width 0.1524)
				(type default)
			)
			(layer "B.SilkS")
		)
		(fp_circle
			(center 0 0)
			(end 7.999984 0)
			(stroke
				(width 0.1)
				(type default)
			)
			(fill no)
			(layer "B.Fab")
		)
		(fp_circle
			(center 0 0)
			(end 7.999984 0)
			(stroke
				(width 0.1)
				(type default)
			)
			(fill no)
			(layer "F.Fab")
		)
		(pad "" np_thru_hole circle
			(at 0 0)
			(size 3.4036 3.4036)
			(drill 3.4036)
			(layers "*.Cu" "*.Mask")
			(clearance 0.381)
			(thermal_gap 0.381)
		)
		(pad "2" thru_hole circle
			(at 3.606292 0)
			(size 0.762 0.762)
			(drill 0.5588)
			(layers "*.Cu" "*.Mask")
			(remove_unused_layers no)
			(net "GND")
			(clearance 0.1524)
			(thermal_gap 0.1524)
		)
		(pad "3" thru_hole circle
			(at 2.549906 -2.549906)
			(size 0.762 0.762)
			(drill 0.5588)
			(layers "*.Cu" "*.Mask")
			(remove_unused_layers no)
			(net "GND")
			(clearance 0.1524)
			(thermal_gap 0.1524)
		)
		(pad "4" thru_hole circle
			(at 0 -3.606292)
			(size 0.762 0.762)
			(drill 0.5588)
			(layers "*.Cu" "*.Mask")
			(remove_unused_layers no)
			(net "GND")
			(clearance 0.1524)
			(thermal_gap 0.1524)
		)
		(pad "5" thru_hole circle
			(at -2.549906 -2.549906)
			(size 0.762 0.762)
			(drill 0.5588)
			(layers "*.Cu" "*.Mask")
			(remove_unused_layers no)
			(net "GND")
			(clearance 0.1524)
			(thermal_gap 0.1524)
		)
		(pad "6" thru_hole circle
			(at -3.606292 0)
			(size 0.762 0.762)
			(drill 0.5588)
			(layers "*.Cu" "*.Mask")
			(remove_unused_layers no)
			(net "GND")
			(clearance 0.1524)
			(thermal_gap 0.1524)
		)
		(pad "7" thru_hole circle
			(at -2.549906 2.549906)
			(size 0.762 0.762)
			(drill 0.5588)
			(layers "*.Cu" "*.Mask")
			(remove_unused_layers no)
			(net "GND")
			(clearance 0.1524)
			(thermal_gap 0.1524)
		)
		(pad "8" thru_hole circle
			(at 0 3.606292)
			(size 0.762 0.762)
			(drill 0.5588)
			(layers "*.Cu" "*.Mask")
			(remove_unused_layers no)
			(net "GND")
			(clearance 0.1524)
			(thermal_gap 0.1524)
		)
		(pad "9" thru_hole circle
			(at 2.549906 2.549906)
			(size 0.762 0.762)
			(drill 0.5588)
			(layers "*.Cu" "*.Mask")
			(remove_unused_layers no)
			(net "GND")
			(clearance 0.1524)
			(thermal_gap 0.1524)
		)
		(zone
			(layer "F.Cu")
			(hatch none 0.5)
			(connect_pads
				(clearance 0)
			)
			(min_thickness 0.25)
			(keepout
				(tracks not_allowed)
				(vias allowed)
				(pads allowed)
				(copperpour not_allowed)
				(footprints allowed)
			)
			(placement
				(enabled no)
				(sheetname "")
			)
			(fill
				(thermal_gap 0.5)
				(thermal_bridge_width 0.5)
				(island_removal_mode 0)
			)
			(polygon
				(pts
					(arc
						(start 271.899888 -370.700046)
						(mid 263.899904 -378.70003)
						(end 271.899888 -386.700014)
					)
					(arc
						(start 271.899888 -383.95402)
						(mid 266.645898 -378.70003)
						(end 271.899888 -373.44604)
					)
				)
			)
		)
		(zone
			(layer "F.Cu")
			(hatch none 0.5)
			(connect_pads
				(clearance 0)
			)
			(min_thickness 0.25)
			(keepout
				(tracks not_allowed)
				(vias allowed)
				(pads allowed)
				(copperpour not_allowed)
				(footprints allowed)
			)
			(placement
				(enabled no)
				(sheetname "")
			)
			(fill
				(thermal_gap 0.5)
				(thermal_bridge_width 0.5)
				(island_removal_mode 0)
			)
			(polygon
				(pts
					(arc
						(start 271.899888 -370.700046)
						(mid 279.899872 -378.70003)
						(end 271.899888 -386.700014)
					)
					(arc
						(start 271.899888 -383.95402)
						(mid 277.153878 -378.70003)
						(end 271.899888 -373.44604)
					)
				)
			)
		)
		(zone
			(layers "F.Cu" "B.Cu" "In1.Cu" "In2.Cu" "In3.Cu" "In4.Cu" "In5.Cu" "In6.Cu"
				"In7.Cu" "In8.Cu" "In9.Cu" "In10.Cu" "In11.Cu" "In12.Cu" "In13.Cu" "In14.Cu"
				"In15.Cu" "In16.Cu"
			)
			(hatch none 0.5)
			(connect_pads
				(clearance 0)
			)
			(min_thickness 0.25)
			(keepout
				(tracks not_allowed)
				(vias allowed)
				(pads allowed)
				(copperpour not_allowed)
				(footprints allowed)
			)
			(placement
				(enabled no)
				(sheetname "")
			)
			(fill
				(thermal_gap 0.5)
				(thermal_bridge_width 0.5)
				(island_removal_mode 0)
			)
			(polygon
				(pts
					(arc
						(start 274.109688 -378.70003)
						(mid 269.690088 -378.70003)
						(end 274.109688 -378.70003)
					)
				)
			)
		)
		(zone
			(layer "B.Cu")
			(hatch none 0.5)
			(connect_pads
				(clearance 0)
			)
			(min_thickness 0.25)
			(keepout
				(tracks not_allowed)
				(vias allowed)
				(pads allowed)
				(copperpour not_allowed)
				(footprints allowed)
			)
			(placement
				(enabled no)
				(sheetname "")
			)
			(fill
				(thermal_gap 0.5)
				(thermal_bridge_width 0.5)
				(island_removal_mode 0)
			)
			(polygon
				(pts
					(arc
						(start 271.899888 -373.19204)
						(mid 266.391898 -378.70003)
						(end 271.899888 -384.20802)
					)
					(arc
						(start 271.899888 -383.72542)
						(mid 266.874498 -378.70003)
						(end 271.899888 -373.67464)
					)
				)
			)
		)
		(zone
			(layer "B.Cu")
			(hatch none 0.5)
			(connect_pads
				(clearance 0)
			)
			(min_thickness 0.25)
			(keepout
				(tracks not_allowed)
				(vias allowed)
				(pads allowed)
				(copperpour not_allowed)
				(footprints allowed)
			)
			(placement
				(enabled no)
				(sheetname "")
			)
			(fill
				(thermal_gap 0.5)
				(thermal_bridge_width 0.5)
				(island_removal_mode 0)
			)
			(polygon
				(pts
					(arc
						(start 271.899888 -373.19204)
						(mid 277.407878 -378.70003)
						(end 271.899888 -384.20802)
					)
					(arc
						(start 271.899888 -383.72542)
						(mid 276.925278 -378.70003)
						(end 271.899888 -373.67464)
					)
				)
			)
		)
	)
	(footprint ""
		(layer "F.Cu")
		(at 30.081982 -289.790632 180)
		(property "Reference" "C3049"
			(at 0 0 180)
			(layer "F.SilkS")
			(hide yes)
			(effects
				(font
					(size 1.27 1.27)
				)
			)
		)
		(property "Value" ""
			(at 0 0 180)
			(layer "F.Fab")
			(effects
				(font
					(size 1.27 1.27)
				)
			)
		)
		(duplicate_pad_numbers_are_jumpers no)
		(fp_line
			(start 1.2954 0.5842)
			(end -1.2954 0.5842)
			(stroke
				(width 0.1524)
				(type default)
			)
			(layer "F.SilkS")
		)
		(fp_line
			(start 1.2954 -0.5842)
			(end 1.2954 0.5842)
			(stroke
				(width 0.1524)
				(type default)
			)
			(layer "F.SilkS")
		)
		(fp_line
			(start -1.2954 0.5842)
			(end -1.2954 -0.5842)
			(stroke
				(width 0.1524)
				(type default)
			)
			(layer "F.SilkS")
		)
		(fp_line
			(start -1.2954 -0.5842)
			(end 1.2954 -0.5842)
			(stroke
				(width 0.1524)
				(type default)
			)
			(layer "F.SilkS")
		)
		(fp_line
			(start 1.1938 0.4064)
			(end 0.8636 0.4064)
			(stroke
				(width 0.1)
				(type default)
			)
			(layer "F.Fab")
		)
		(fp_line
			(start 1.1938 -0.4064)
			(end 1.1938 0.4064)
			(stroke
				(width 0.1)
				(type default)
			)
			(layer "F.Fab")
		)
		(fp_line
			(start 0.8636 0.4572)
			(end -0.8636 0.4572)
			(stroke
				(width 0.1)
				(type default)
			)
			(layer "F.Fab")
		)
		(fp_line
			(start 0.8636 0.4064)
			(end 0.8636 0.4572)
			(stroke
				(width 0.1)
				(type default)
			)
			(layer "F.Fab")
		)
		(fp_line
			(start 0.8636 -0.4064)
			(end 1.1938 -0.4064)
			(stroke
				(width 0.1)
				(type default)
			)
			(layer "F.Fab")
		)
		(fp_line
			(start 0.8636 -0.4572)
			(end 0.8636 -0.4064)
			(stroke
				(width 0.1)
				(type default)
			)
			(layer "F.Fab")
		)
		(fp_line
			(start -0.8636 0.4572)
			(end -0.8636 0.4064)
			(stroke
				(width 0.1)
				(type default)
			)
			(layer "F.Fab")
		)
		(fp_line
			(start -0.8636 0.4064)
			(end -1.1938 0.4064)
			(stroke
				(width 0.1)
				(type default)
			)
			(layer "F.Fab")
		)
		(fp_line
			(start -0.8636 -0.4064)
			(end -0.8636 -0.4572)
			(stroke
				(width 0.1)
				(type default)
			)
			(layer "F.Fab")
		)
		(fp_line
			(start -0.8636 -0.4572)
			(end 0.8636 -0.4572)
			(stroke
				(width 0.1)
				(type default)
			)
			(layer "F.Fab")
		)
		(fp_line
			(start -1.1938 0.4064)
			(end -1.1938 -0.4064)
			(stroke
				(width 0.1)
				(type default)
			)
			(layer "F.Fab")
		)
		(fp_line
			(start -1.1938 -0.4064)
			(end -0.8636 -0.4064)
			(stroke
				(width 0.1)
				(type default)
			)
			(layer "F.Fab")
		)
		(pad "1" smd rect
			(at -0.7366 0 90)
			(size 0.7112 0.8128)
			(layers "F.Cu" "F.Mask" "F.Paste")
			(net "PCEPLL4_VDDA18_PEX0_R")
		)
		(pad "2" smd rect
			(at 0.7366 0 90)
			(size 0.7112 0.8128)
			(layers "F.Cu" "F.Mask" "F.Paste")
			(net "GND")
		)
	)
	(footprint ""
		(layer "F.Cu")
		(at 326.154542 -124.159264 180)
		(property "Reference" "PC486"
			(at 0 0 180)
			(layer "F.SilkS")
			(hide yes)
			(effects
				(font
					(size 1.27 1.27)
				)
			)
		)
		(property "Value" ""
			(at 0 0 180)
			(layer "F.Fab")
			(effects
				(font
					(size 1.27 1.27)
				)
			)
		)
		(duplicate_pad_numbers_are_jumpers no)
		(fp_line
			(start 0.7874 0.4064)
			(end -0.7874 0.4064)
			(stroke
				(width 0.1524)
				(type default)
			)
			(layer "F.SilkS")
		)
		(fp_line
			(start 0.7874 -0.4064)
			(end 0.7874 0.4064)
			(stroke
				(width 0.1524)
				(type default)
			)
			(layer "F.SilkS")
		)
		(fp_line
			(start -0.7874 0.4064)
			(end -0.7874 -0.4064)
			(stroke
				(width 0.1524)
				(type default)
			)
			(layer "F.SilkS")
		)
		(fp_line
			(start -0.7874 -0.4064)
			(end 0.7874 -0.4064)
			(stroke
				(width 0.1524)
				(type default)
			)
			(layer "F.SilkS")
		)
		(fp_line
			(start 0.67945 0.3048)
			(end 0.120396 0.3048)
			(stroke
				(width 0.1)
				(type default)
			)
			(layer "F.Fab")
		)
		(fp_line
			(start 0.67945 -0.3048)
			(end 0.67945 0.3048)
			(stroke
				(width 0.1)
				(type default)
			)
			(layer "F.Fab")
		)
		(fp_line
			(start 0.12065 -0.2794)
			(end 0.12065 -0.3048)
			(stroke
				(width 0.1)
				(type default)
			)
			(layer "F.Fab")
		)
		(fp_line
			(start 0.12065 -0.3048)
			(end 0.67945 -0.3048)
			(stroke
				(width 0.1)
				(type default)
			)
			(layer "F.Fab")
		)
		(fp_line
			(start 0.120396 0.3048)
			(end 0.120396 0.2794)
			(stroke
				(width 0.1)
				(type default)
			)
			(layer "F.Fab")
		)
		(fp_line
			(start 0.120396 0.2794)
			(end -0.12065 0.2794)
			(stroke
				(width 0.1)
				(type default)
			)
			(layer "F.Fab")
		)
		(fp_line
			(start -0.12065 0.3048)
			(end -0.67945 0.3048)
			(stroke
				(width 0.1)
				(type default)
			)
			(layer "F.Fab")
		)
		(fp_line
			(start -0.12065 0.2794)
			(end -0.12065 0.3048)
			(stroke
				(width 0.1)
				(type default)
			)
			(layer "F.Fab")
		)
		(fp_line
			(start -0.12065 -0.2794)
			(end 0.12065 -0.2794)
			(stroke
				(width 0.1)
				(type default)
			)
			(layer "F.Fab")
		)
		(fp_line
			(start -0.12065 -0.305054)
			(end -0.12065 -0.2794)
			(stroke
				(width 0.1)
				(type default)
			)
			(layer "F.Fab")
		)
		(fp_line
			(start -0.67945 0.3048)
			(end -0.67945 -0.305054)
			(stroke
				(width 0.1)
				(type default)
			)
			(layer "F.Fab")
		)
		(fp_line
			(start -0.67945 -0.305054)
			(end -0.12065 -0.305054)
			(stroke
				(width 0.1)
				(type default)
			)
			(layer "F.Fab")
		)
		(pad "1" smd circle
			(at -0.40005 0 180)
			(size 0 0)
			(layers "F.Cu" "F.Mask" "F.Paste")
			(net "P3V3_AUX")
		)
		(pad "2" smd circle
			(at 0.40005 0 180)
			(size 0 0)
			(layers "F.Cu" "F.Mask" "F.Paste")
			(net "GND")
		)
	)
	(footprint ""
		(layer "F.Cu")
		(at 221.332806 -254.18542 -90)
		(property "Reference" "C4283"
			(at 0 0 270)
			(layer "F.SilkS")
			(hide yes)
			(effects
				(font
					(size 1.27 1.27)
				)
			)
		)
		(property "Value" ""
			(at 0 0 270)
			(layer "F.Fab")
			(effects
				(font
					(size 1.27 1.27)
				)
			)
		)
		(duplicate_pad_numbers_are_jumpers no)
		(fp_line
			(start -1.2954 0.5842)
			(end -1.2954 -0.5842)
			(stroke
				(width 0.1524)
				(type default)
			)
			(layer "F.SilkS")
		)
		(fp_line
			(start 1.2954 0.5842)
			(end -1.2954 0.5842)
			(stroke
				(width 0.1524)
				(type default)
			)
			(layer "F.SilkS")
		)
		(fp_line
			(start -1.2954 -0.5842)
			(end 1.2954 -0.5842)
			(stroke
				(width 0.1524)
				(type default)
			)
			(layer "F.SilkS")
		)
		(fp_line
			(start 1.2954 -0.5842)
			(end 1.2954 0.5842)
			(stroke
				(width 0.1524)
				(type default)
			)
			(layer "F.SilkS")
		)
		(fp_line
			(start -0.8636 0.4572)
			(end -0.8636 0.4064)
			(stroke
				(width 0.1)
				(type default)
			)
			(layer "F.Fab")
		)
		(fp_line
			(start 0.8636 0.4572)
			(end -0.8636 0.4572)
			(stroke
				(width 0.1)
				(type default)
			)
			(layer "F.Fab")
		)
		(fp_line
			(start -1.1938 0.4064)
			(end -1.1938 -0.4064)
			(stroke
				(width 0.1)
				(type default)
			)
			(layer "F.Fab")
		)
		(fp_line
			(start -0.8636 0.4064)
			(end -1.1938 0.4064)
			(stroke
				(width 0.1)
				(type default)
			)
			(layer "F.Fab")
		)
		(fp_line
			(start 0.8636 0.4064)
			(end 0.8636 0.4572)
			(stroke
				(width 0.1)
				(type default)
			)
			(layer "F.Fab")
		)
		(fp_line
			(start 1.1938 0.4064)
			(end 0.8636 0.4064)
			(stroke
				(width 0.1)
				(type default)
			)
			(layer "F.Fab")
		)
		(fp_line
			(start -1.1938 -0.4064)
			(end -0.8636 -0.4064)
			(stroke
				(width 0.1)
				(type default)
			)
			(layer "F.Fab")
		)
		(fp_line
			(start -0.8636 -0.4064)
			(end -0.8636 -0.4572)
			(stroke
				(width 0.1)
				(type default)
			)
			(layer "F.Fab")
		)
		(fp_line
			(start 0.8636 -0.4064)
			(end 1.1938 -0.4064)
			(stroke
				(width 0.1)
				(type default)
			)
			(layer "F.Fab")
		)
		(fp_line
			(start 1.1938 -0.4064)
			(end 1.1938 0.4064)
			(stroke
				(width 0.1)
				(type default)
			)
			(layer "F.Fab")
		)
		(fp_line
			(start -0.8636 -0.4572)
			(end 0.8636 -0.4572)
			(stroke
				(width 0.1)
				(type default)
			)
			(layer "F.Fab")
		)
		(fp_line
			(start 0.8636 -0.4572)
			(end 0.8636 -0.4064)
			(stroke
				(width 0.1)
				(type default)
			)
			(layer "F.Fab")
		)
		(pad "1" smd rect
			(at -0.7366 0 180)
			(size 0.7112 0.8128)
			(layers "F.Cu" "F.Mask" "F.Paste")
			(net "P1V25_SERDES_VDDPLL_PEX1_C1")
		)
		(pad "2" smd rect
			(at 0.7366 0 180)
			(size 0.7112 0.8128)
			(layers "F.Cu" "F.Mask" "F.Paste")
			(net "GND")
		)
	)
	(footprint ""
		(layer "F.Cu")
		(at 361.188 -179.07 180)
		(property "Reference" "R4705"
			(at 0 0 180)
			(layer "F.SilkS")
			(hide yes)
			(effects
				(font
					(size 1.27 1.27)
				)
			)
		)
		(property "Value" ""
			(at 0 0 180)
			(layer "F.Fab")
			(effects
				(font
					(size 1.27 1.27)
				)
			)
		)
		(duplicate_pad_numbers_are_jumpers no)
		(fp_line
			(start 0.7874 0.4064)
			(end -0.7874 0.4064)
			(stroke
				(width 0.1524)
				(type default)
			)
			(layer "F.SilkS")
		)
		(fp_line
			(start 0.7874 -0.4064)
			(end 0.7874 0.4064)
			(stroke
				(width 0.1524)
				(type default)
			)
			(layer "F.SilkS")
		)
		(fp_line
			(start -0.7874 0.4064)
			(end -0.7874 -0.4064)
			(stroke
				(width 0.1524)
				(type default)
			)
			(layer "F.SilkS")
		)
		(fp_line
			(start -0.7874 -0.4064)
			(end 0.7874 -0.4064)
			(stroke
				(width 0.1524)
				(type default)
			)
			(layer "F.SilkS")
		)
		(fp_line
			(start 0.67945 0.3048)
			(end 0.120396 0.3048)
			(stroke
				(width 0.1)
				(type default)
			)
			(layer "F.Fab")
		)
		(fp_line
			(start 0.67945 -0.3048)
			(end 0.67945 0.3048)
			(stroke
				(width 0.1)
				(type default)
			)
			(layer "F.Fab")
		)
		(fp_line
			(start 0.12065 -0.2794)
			(end 0.12065 -0.3048)
			(stroke
				(width 0.1)
				(type default)
			)
			(layer "F.Fab")
		)
		(fp_line
			(start 0.12065 -0.3048)
			(end 0.67945 -0.3048)
			(stroke
				(width 0.1)
				(type default)
			)
			(layer "F.Fab")
		)
		(fp_line
			(start 0.120396 0.3048)
			(end 0.120396 0.2794)
			(stroke
				(width 0.1)
				(type default)
			)
			(layer "F.Fab")
		)
		(fp_line
			(start 0.120396 0.2794)
			(end -0.12065 0.2794)
			(stroke
				(width 0.1)
				(type default)
			)
			(layer "F.Fab")
		)
		(fp_line
			(start -0.12065 0.3048)
			(end -0.67945 0.3048)
			(stroke
				(width 0.1)
				(type default)
			)
			(layer "F.Fab")
		)
		(fp_line
			(start -0.12065 0.2794)
			(end -0.12065 0.3048)
			(stroke
				(width 0.1)
				(type default)
			)
			(layer "F.Fab")
		)
		(fp_line
			(start -0.12065 -0.2794)
			(end 0.12065 -0.2794)
			(stroke
				(width 0.1)
				(type default)
			)
			(layer "F.Fab")
		)
		(fp_line
			(start -0.12065 -0.305054)
			(end -0.12065 -0.2794)
			(stroke
				(width 0.1)
				(type default)
			)
			(layer "F.Fab")
		)
		(fp_line
			(start -0.67945 0.3048)
			(end -0.67945 -0.305054)
			(stroke
				(width 0.1)
				(type default)
			)
			(layer "F.Fab")
		)
		(fp_line
			(start -0.67945 -0.305054)
			(end -0.12065 -0.305054)
			(stroke
				(width 0.1)
				(type default)
			)
			(layer "F.Fab")
		)
		(pad "1" smd circle
			(at -0.40005 0 180)
			(size 0 0)
			(layers "F.Cu" "F.Mask" "F.Paste")
			(net "PRSNT_SSD6_FPGA_PCA9555_N")
		)
		(pad "2" smd circle
			(at 0.40005 0 180)
			(size 0 0)
			(layers "F.Cu" "F.Mask" "F.Paste")
			(net "PRSNT_SSD6_FPGA_R_N")
		)
	)
	(footprint ""
		(layer "F.Cu")
		(at 133.892544 -31.825184 180)
		(property "Reference" "C279"
			(at 0 0 180)
			(layer "F.SilkS")
			(hide yes)
			(effects
				(font
					(size 1.27 1.27)
				)
			)
		)
		(property "Value" ""
			(at 0 0 180)
			(layer "F.Fab")
			(effects
				(font
					(size 1.27 1.27)
				)
			)
		)
		(duplicate_pad_numbers_are_jumpers no)
		(fp_line
			(start 0.299974 0.150114)
			(end -0.299974 0.150114)
			(stroke
				(width 0.1)
				(type default)
			)
			(layer "F.Fab")
		)
		(fp_line
			(start 0.299974 -0.150114)
			(end 0.299974 0.150114)
			(stroke
				(width 0.1)
				(type default)
			)
			(layer "F.Fab")
		)
		(fp_line
			(start -0.299974 0.150114)
			(end -0.299974 -0.150114)
			(stroke
				(width 0.1)
				(type default)
			)
			(layer "F.Fab")
		)
		(fp_line
			(start -0.299974 -0.150114)
			(end 0.299974 -0.150114)
			(stroke
				(width 0.1)
				(type default)
			)
			(layer "F.Fab")
		)
		(pad "1" smd rect
			(at -0.2667 0 180)
			(size 0.3048 0.381)
			(layers "F.Cu" "F.Mask" "F.Paste")
			(net "P5E_PEX1_STN2_TX_DN<46>")
		)
		(pad "2" smd rect
			(at 0.2667 0 180)
			(size 0.3048 0.381)
			(layers "F.Cu" "F.Mask" "F.Paste")
			(net "P5E_PEX1_STN2_TX_C_DN<46>")
		)
	)
	(footprint ""
		(layer "F.Cu")
		(at 323.476112 -297.46448 180)
		(property "Reference" "R3988"
			(at 0 0 180)
			(layer "F.SilkS")
			(hide yes)
			(effects
				(font
					(size 1.27 1.27)
				)
			)
		)
		(property "Value" ""
			(at 0 0 180)
			(layer "F.Fab")
			(effects
				(font
					(size 1.27 1.27)
				)
			)
		)
		(duplicate_pad_numbers_are_jumpers no)
		(fp_line
			(start 0.7874 0.4064)
			(end -0.7874 0.4064)
			(stroke
				(width 0.1524)
				(type default)
			)
			(layer "F.SilkS")
		)
		(fp_line
			(start 0.7874 -0.4064)
			(end 0.7874 0.4064)
			(stroke
				(width 0.1524)
				(type default)
			)
			(layer "F.SilkS")
		)
		(fp_line
			(start -0.7874 0.4064)
			(end -0.7874 -0.4064)
			(stroke
				(width 0.1524)
				(type default)
			)
			(layer "F.SilkS")
		)
		(fp_line
			(start -0.7874 -0.4064)
			(end 0.7874 -0.4064)
			(stroke
				(width 0.1524)
				(type default)
			)
			(layer "F.SilkS")
		)
		(fp_line
			(start 0.67945 0.3048)
			(end 0.120396 0.3048)
			(stroke
				(width 0.1)
				(type default)
			)
			(layer "F.Fab")
		)
		(fp_line
			(start 0.67945 -0.3048)
			(end 0.67945 0.3048)
			(stroke
				(width 0.1)
				(type default)
			)
			(layer "F.Fab")
		)
		(fp_line
			(start 0.12065 -0.2794)
			(end 0.12065 -0.3048)
			(stroke
				(width 0.1)
				(type default)
			)
			(layer "F.Fab")
		)
		(fp_line
			(start 0.12065 -0.3048)
			(end 0.67945 -0.3048)
			(stroke
				(width 0.1)
				(type default)
			)
			(layer "F.Fab")
		)
		(fp_line
			(start 0.120396 0.3048)
			(end 0.120396 0.2794)
			(stroke
				(width 0.1)
				(type default)
			)
			(layer "F.Fab")
		)
		(fp_line
			(start 0.120396 0.2794)
			(end -0.12065 0.2794)
			(stroke
				(width 0.1)
				(type default)
			)
			(layer "F.Fab")
		)
		(fp_line
			(start -0.12065 0.3048)
			(end -0.67945 0.3048)
			(stroke
				(width 0.1)
				(type default)
			)
			(layer "F.Fab")
		)
		(fp_line
			(start -0.12065 0.2794)
			(end -0.12065 0.3048)
			(stroke
				(width 0.1)
				(type default)
			)
			(layer "F.Fab")
		)
		(fp_line
			(start -0.12065 -0.2794)
			(end 0.12065 -0.2794)
			(stroke
				(width 0.1)
				(type default)
			)
			(layer "F.Fab")
		)
		(fp_line
			(start -0.12065 -0.305054)
			(end -0.12065 -0.2794)
			(stroke
				(width 0.1)
				(type default)
			)
			(layer "F.Fab")
		)
		(fp_line
			(start -0.67945 0.3048)
			(end -0.67945 -0.305054)
			(stroke
				(width 0.1)
				(type default)
			)
			(layer "F.Fab")
		)
		(fp_line
			(start -0.67945 -0.305054)
			(end -0.12065 -0.305054)
			(stroke
				(width 0.1)
				(type default)
			)
			(layer "F.Fab")
		)
		(pad "1" smd circle
			(at -0.40005 0 180)
			(size 0 0)
			(layers "F.Cu" "F.Mask" "F.Paste")
			(net "SMB_PEX2_HOST_LS_SCL")
		)
		(pad "2" smd circle
			(at 0.40005 0 180)
			(size 0 0)
			(layers "F.Cu" "F.Mask" "F.Paste")
			(net "I2C_PEX2_HOST_R_SCL")
		)
	)
	(footprint ""
		(layer "F.Cu")
		(at 374.27154 -343.952322 90)
		(property "Reference" "C780"
			(at 0 0 90)
			(layer "F.SilkS")
			(hide yes)
			(effects
				(font
					(size 1.27 1.27)
				)
			)
		)
		(property "Value" ""
			(at 0 0 90)
			(layer "F.Fab")
			(effects
				(font
					(size 1.27 1.27)
				)
			)
		)
		(duplicate_pad_numbers_are_jumpers no)
		(fp_line
			(start 0.299974 -0.150114)
			(end 0.299974 0.150114)
			(stroke
				(width 0.1)
				(type default)
			)
			(layer "F.Fab")
		)
		(fp_line
			(start -0.299974 -0.150114)
			(end 0.299974 -0.150114)
			(stroke
				(width 0.1)
				(type default)
			)
			(layer "F.Fab")
		)
		(fp_line
			(start 0.299974 0.150114)
			(end -0.299974 0.150114)
			(stroke
				(width 0.1)
				(type default)
			)
			(layer "F.Fab")
		)
		(fp_line
			(start -0.299974 0.150114)
			(end -0.299974 -0.150114)
			(stroke
				(width 0.1)
				(type default)
			)
			(layer "F.Fab")
		)
		(pad "1" smd rect
			(at -0.2667 0 90)
			(size 0.3048 0.381)
			(layers "F.Cu" "F.Mask" "F.Paste")
			(net "P5E_PEX3_STN6_TX_DP<102>")
		)
		(pad "2" smd rect
			(at 0.2667 0 90)
			(size 0.3048 0.381)
			(layers "F.Cu" "F.Mask" "F.Paste")
			(net "P5E_PEX3_STN6_TX_C_DP<102>")
		)
	)
	(footprint ""
		(layer "F.Cu")
		(at 327.533 -212.217)
		(property "Reference" "R4158"
			(at 0 0 0)
			(layer "F.SilkS")
			(hide yes)
			(effects
				(font
					(size 1.27 1.27)
				)
			)
		)
		(property "Value" ""
			(at 0 0 0)
			(layer "F.Fab")
			(effects
				(font
					(size 1.27 1.27)
				)
			)
		)
		(duplicate_pad_numbers_are_jumpers no)
		(fp_line
			(start -0.7874 -0.4064)
			(end 0.7874 -0.4064)
			(stroke
				(width 0.1524)
				(type default)
			)
			(layer "F.SilkS")
		)
		(fp_line
			(start -0.7874 0.4064)
			(end -0.7874 -0.4064)
			(stroke
				(width 0.1524)
				(type default)
			)
			(layer "F.SilkS")
		)
		(fp_line
			(start 0.7874 -0.4064)
			(end 0.7874 0.4064)
			(stroke
				(width 0.1524)
				(type default)
			)
			(layer "F.SilkS")
		)
		(fp_line
			(start 0.7874 0.4064)
			(end -0.7874 0.4064)
			(stroke
				(width 0.1524)
				(type default)
			)
			(layer "F.SilkS")
		)
		(fp_line
			(start -0.67945 -0.305054)
			(end -0.12065 -0.305054)
			(stroke
				(width 0.1)
				(type default)
			)
			(layer "F.Fab")
		)
		(fp_line
			(start -0.67945 0.3048)
			(end -0.67945 -0.305054)
			(stroke
				(width 0.1)
				(type default)
			)
			(layer "F.Fab")
		)
		(fp_line
			(start -0.12065 -0.305054)
			(end -0.12065 -0.2794)
			(stroke
				(width 0.1)
				(type default)
			)
			(layer "F.Fab")
		)
		(fp_line
			(start -0.12065 -0.2794)
			(end 0.12065 -0.2794)
			(stroke
				(width 0.1)
				(type default)
			)
			(layer "F.Fab")
		)
		(fp_line
			(start -0.12065 0.2794)
			(end -0.12065 0.3048)
			(stroke
				(width 0.1)
				(type default)
			)
			(layer "F.Fab")
		)
		(fp_line
			(start -0.12065 0.3048)
			(end -0.67945 0.3048)
			(stroke
				(width 0.1)
				(type default)
			)
			(layer "F.Fab")
		)
		(fp_line
			(start 0.120396 0.2794)
			(end -0.12065 0.2794)
			(stroke
				(width 0.1)
				(type default)
			)
			(layer "F.Fab")
		)
		(fp_line
			(start 0.120396 0.3048)
			(end 0.120396 0.2794)
			(stroke
				(width 0.1)
				(type default)
			)
			(layer "F.Fab")
		)
		(fp_line
			(start 0.12065 -0.3048)
			(end 0.67945 -0.3048)
			(stroke
				(width 0.1)
				(type default)
			)
			(layer "F.Fab")
		)
		(fp_line
			(start 0.12065 -0.2794)
			(end 0.12065 -0.3048)
			(stroke
				(width 0.1)
				(type default)
			)
			(layer "F.Fab")
		)
		(fp_line
			(start 0.67945 -0.3048)
			(end 0.67945 0.3048)
			(stroke
				(width 0.1)
				(type default)
			)
			(layer "F.Fab")
		)
		(fp_line
			(start 0.67945 0.3048)
			(end 0.120396 0.3048)
			(stroke
				(width 0.1)
				(type default)
			)
			(layer "F.Fab")
		)
		(pad "1" smd circle
			(at -0.40005 0)
			(size 0 0)
			(layers "F.Cu" "F.Mask" "F.Paste")
			(net "PRSNT_SSD11_FPGA_R_N")
		)
		(pad "2" smd circle
			(at 0.40005 0)
			(size 0 0)
			(layers "F.Cu" "F.Mask" "F.Paste")
			(net "PRSNT_SSD11_FPGA_N")
		)
	)
	(footprint ""
		(layer "F.Cu")
		(at 451.622668 -258.331208 -90)
		(property "Reference" "R6562"
			(at 0 0 270)
			(layer "F.SilkS")
			(hide yes)
			(effects
				(font
					(size 1.27 1.27)
				)
			)
		)
		(property "Value" ""
			(at 0 0 270)
			(layer "F.Fab")
			(effects
				(font
					(size 1.27 1.27)
				)
			)
		)
		(duplicate_pad_numbers_are_jumpers no)
		(fp_line
			(start -0.7874 0.4064)
			(end -0.7874 -0.4064)
			(stroke
				(width 0.1524)
				(type default)
			)
			(layer "F.SilkS")
		)
		(fp_line
			(start 0.7874 0.4064)
			(end -0.7874 0.4064)
			(stroke
				(width 0.1524)
				(type default)
			)
			(layer "F.SilkS")
		)
		(fp_line
			(start -0.7874 -0.4064)
			(end 0.7874 -0.4064)
			(stroke
				(width 0.1524)
				(type default)
			)
			(layer "F.SilkS")
		)
		(fp_line
			(start 0.7874 -0.4064)
			(end 0.7874 0.4064)
			(stroke
				(width 0.1524)
				(type default)
			)
			(layer "F.SilkS")
		)
		(fp_line
			(start -0.67945 0.3048)
			(end -0.67945 -0.305054)
			(stroke
				(width 0.1)
				(type default)
			)
			(layer "F.Fab")
		)
		(fp_line
			(start -0.12065 0.3048)
			(end -0.67945 0.3048)
			(stroke
				(width 0.1)
				(type default)
			)
			(layer "F.Fab")
		)
		(fp_line
			(start 0.120396 0.3048)
			(end 0.120396 0.2794)
			(stroke
				(width 0.1)
				(type default)
			)
			(layer "F.Fab")
		)
		(fp_line
			(start 0.67945 0.3048)
			(end 0.120396 0.3048)
			(stroke
				(width 0.1)
				(type default)
			)
			(layer "F.Fab")
		)
		(fp_line
			(start -0.12065 0.2794)
			(end -0.12065 0.3048)
			(stroke
				(width 0.1)
				(type default)
			)
			(layer "F.Fab")
		)
		(fp_line
			(start 0.120396 0.2794)
			(end -0.12065 0.2794)
			(stroke
				(width 0.1)
				(type default)
			)
			(layer "F.Fab")
		)
		(fp_line
			(start -0.12065 -0.2794)
			(end 0.12065 -0.2794)
			(stroke
				(width 0.1)
				(type default)
			)
			(layer "F.Fab")
		)
		(fp_line
			(start 0.12065 -0.2794)
			(end 0.12065 -0.3048)
			(stroke
				(width 0.1)
				(type default)
			)
			(layer "F.Fab")
		)
		(fp_line
			(start 0.12065 -0.3048)
			(end 0.67945 -0.3048)
			(stroke
				(width 0.1)
				(type default)
			)
			(layer "F.Fab")
		)
		(fp_line
			(start 0.67945 -0.3048)
			(end 0.67945 0.3048)
			(stroke
				(width 0.1)
				(type default)
			)
			(layer "F.Fab")
		)
		(fp_line
			(start -0.67945 -0.305054)
			(end -0.12065 -0.305054)
			(stroke
				(width 0.1)
				(type default)
			)
			(layer "F.Fab")
		)
		(fp_line
			(start -0.12065 -0.305054)
			(end -0.12065 -0.2794)
			(stroke
				(width 0.1)
				(type default)
			)
			(layer "F.Fab")
		)
		(pad "1" smd circle
			(at -0.40005 0 270)
			(size 0 0)
			(layers "F.Cu" "F.Mask" "F.Paste")
			(net "P1V25_SERDES_VDDPLL_PEX3")
		)
		(pad "2" smd circle
			(at 0.40005 0 270)
			(size 0 0)
			(layers "F.Cu" "F.Mask" "F.Paste")
			(net "P1V25_SERDES_VDDPLL_PEX3_C9")
		)
	)
	(footprint ""
		(layer "F.Cu")
		(at 319.609724 -343.952322 90)
		(property "Reference" "C556"
			(at 0 0 90)
			(layer "F.SilkS")
			(hide yes)
			(effects
				(font
					(size 1.27 1.27)
				)
			)
		)
		(property "Value" ""
			(at 0 0 90)
			(layer "F.Fab")
			(effects
				(font
					(size 1.27 1.27)
				)
			)
		)
		(duplicate_pad_numbers_are_jumpers no)
		(fp_line
			(start 0.299974 -0.150114)
			(end 0.299974 0.150114)
			(stroke
				(width 0.1)
				(type default)
			)
			(layer "F.Fab")
		)
		(fp_line
			(start -0.299974 -0.150114)
			(end 0.299974 -0.150114)
			(stroke
				(width 0.1)
				(type default)
			)
			(layer "F.Fab")
		)
		(fp_line
			(start 0.299974 0.150114)
			(end -0.299974 0.150114)
			(stroke
				(width 0.1)
				(type default)
			)
			(layer "F.Fab")
		)
		(fp_line
			(start -0.299974 0.150114)
			(end -0.299974 -0.150114)
			(stroke
				(width 0.1)
				(type default)
			)
			(layer "F.Fab")
		)
		(pad "1" smd rect
			(at -0.2667 0 90)
			(size 0.3048 0.381)
			(layers "F.Cu" "F.Mask" "F.Paste")
			(net "P5E_PEX2_STN6_TX_DN<109>")
		)
		(pad "2" smd rect
			(at 0.2667 0 90)
			(size 0.3048 0.381)
			(layers "F.Cu" "F.Mask" "F.Paste")
			(net "P5E_PEX2_STN6_TX_C_DN<109>")
		)
	)
	(footprint ""
		(layer "F.Cu")
		(at 26.374344 -250.070874 -90)
		(property "Reference" "R1154"
			(at 0 0 270)
			(layer "F.SilkS")
			(hide yes)
			(effects
				(font
					(size 1.27 1.27)
				)
			)
		)
		(property "Value" ""
			(at 0 0 270)
			(layer "F.Fab")
			(effects
				(font
					(size 1.27 1.27)
				)
			)
		)
		(duplicate_pad_numbers_are_jumpers no)
		(fp_line
			(start -0.7874 0.4064)
			(end -0.7874 -0.4064)
			(stroke
				(width 0.1524)
				(type default)
			)
			(layer "F.SilkS")
		)
		(fp_line
			(start 0.7874 0.4064)
			(end -0.7874 0.4064)
			(stroke
				(width 0.1524)
				(type default)
			)
			(layer "F.SilkS")
		)
		(fp_line
			(start -0.7874 -0.4064)
			(end 0.7874 -0.4064)
			(stroke
				(width 0.1524)
				(type default)
			)
			(layer "F.SilkS")
		)
		(fp_line
			(start 0.7874 -0.4064)
			(end 0.7874 0.4064)
			(stroke
				(width 0.1524)
				(type default)
			)
			(layer "F.SilkS")
		)
		(fp_line
			(start -0.67945 0.3048)
			(end -0.67945 -0.305054)
			(stroke
				(width 0.1)
				(type default)
			)
			(layer "F.Fab")
		)
		(fp_line
			(start -0.12065 0.3048)
			(end -0.67945 0.3048)
			(stroke
				(width 0.1)
				(type default)
			)
			(layer "F.Fab")
		)
		(fp_line
			(start 0.120396 0.3048)
			(end 0.120396 0.2794)
			(stroke
				(width 0.1)
				(type default)
			)
			(layer "F.Fab")
		)
		(fp_line
			(start 0.67945 0.3048)
			(end 0.120396 0.3048)
			(stroke
				(width 0.1)
				(type default)
			)
			(layer "F.Fab")
		)
		(fp_line
			(start -0.12065 0.2794)
			(end -0.12065 0.3048)
			(stroke
				(width 0.1)
				(type default)
			)
			(layer "F.Fab")
		)
		(fp_line
			(start 0.120396 0.2794)
			(end -0.12065 0.2794)
			(stroke
				(width 0.1)
				(type default)
			)
			(layer "F.Fab")
		)
		(fp_line
			(start -0.12065 -0.2794)
			(end 0.12065 -0.2794)
			(stroke
				(width 0.1)
				(type default)
			)
			(layer "F.Fab")
		)
		(fp_line
			(start 0.12065 -0.2794)
			(end 0.12065 -0.3048)
			(stroke
				(width 0.1)
				(type default)
			)
			(layer "F.Fab")
		)
		(fp_line
			(start 0.12065 -0.3048)
			(end 0.67945 -0.3048)
			(stroke
				(width 0.1)
				(type default)
			)
			(layer "F.Fab")
		)
		(fp_line
			(start 0.67945 -0.3048)
			(end 0.67945 0.3048)
			(stroke
				(width 0.1)
				(type default)
			)
			(layer "F.Fab")
		)
		(fp_line
			(start -0.67945 -0.305054)
			(end -0.12065 -0.305054)
			(stroke
				(width 0.1)
				(type default)
			)
			(layer "F.Fab")
		)
		(fp_line
			(start -0.12065 -0.305054)
			(end -0.12065 -0.2794)
			(stroke
				(width 0.1)
				(type default)
			)
			(layer "F.Fab")
		)
		(pad "1" smd circle
			(at -0.40005 0 270)
			(size 0 0)
			(layers "F.Cu" "F.Mask" "F.Paste")
			(net "PEX0_MODE_SEL2")
		)
		(pad "2" smd circle
			(at 0.40005 0 270)
			(size 0 0)
			(layers "F.Cu" "F.Mask" "F.Paste")
			(net "P1V8_PEX")
		)
	)
	(footprint ""
		(layer "F.Cu")
		(at 491.81893 -526.883122)
		(property "Reference" "J4_23"
			(at -0.5842 -1.31953 0)
			(unlocked yes)
			(layer "B.SilkS")
			(effects
				(font
					(size 0.7874 0.5842)
					(thickness 0.1524)
				)
				(justify left mirror)
			)
		)
		(property "Value" ""
			(at 0 0 0)
			(layer "F.Fab")
			(effects
				(font
					(size 1.27 1.27)
				)
			)
		)
		(duplicate_pad_numbers_are_jumpers no)
		(pad "1" thru_hole circle
			(at 0 0)
			(size 0.4572 0.4572)
			(drill 0.2032)
			(layers "*.Cu" "*.Mask")
			(remove_unused_layers no)
			(net "Net_9329")
			(clearance 0.127)
			(thermal_gap 0.127)
			(padstack
				(mode front_inner_back)
				(layer "Inner"
					(shape circle)
					(size 0.4572 0.4572)
					(clearance 0.127)
				)
				(layer "B.Cu"
					(shape circle)
					(size 0.508 0.508)
					(clearance 0.1016)
				)
			)
		)
	)
	(footprint ""
		(layer "F.Cu")
		(at 225.711512 -231.416606 -90)
		(property "Reference" "R4542"
			(at 0 0 270)
			(layer "F.SilkS")
			(hide yes)
			(effects
				(font
					(size 1.27 1.27)
				)
			)
		)
		(property "Value" ""
			(at 0 0 270)
			(layer "F.Fab")
			(effects
				(font
					(size 1.27 1.27)
				)
			)
		)
		(duplicate_pad_numbers_are_jumpers no)
		(fp_line
			(start -0.7874 0.4064)
			(end -0.7874 -0.4064)
			(stroke
				(width 0.1524)
				(type default)
			)
			(layer "F.SilkS")
		)
		(fp_line
			(start 0.7874 0.4064)
			(end -0.7874 0.4064)
			(stroke
				(width 0.1524)
				(type default)
			)
			(layer "F.SilkS")
		)
		(fp_line
			(start -0.7874 -0.4064)
			(end 0.7874 -0.4064)
			(stroke
				(width 0.1524)
				(type default)
			)
			(layer "F.SilkS")
		)
		(fp_line
			(start 0.7874 -0.4064)
			(end 0.7874 0.4064)
			(stroke
				(width 0.1524)
				(type default)
			)
			(layer "F.SilkS")
		)
		(fp_line
			(start -0.67945 0.3048)
			(end -0.67945 -0.305054)
			(stroke
				(width 0.1)
				(type default)
			)
			(layer "F.Fab")
		)
		(fp_line
			(start -0.12065 0.3048)
			(end -0.67945 0.3048)
			(stroke
				(width 0.1)
				(type default)
			)
			(layer "F.Fab")
		)
		(fp_line
			(start 0.120396 0.3048)
			(end 0.120396 0.2794)
			(stroke
				(width 0.1)
				(type default)
			)
			(layer "F.Fab")
		)
		(fp_line
			(start 0.67945 0.3048)
			(end 0.120396 0.3048)
			(stroke
				(width 0.1)
				(type default)
			)
			(layer "F.Fab")
		)
		(fp_line
			(start -0.12065 0.2794)
			(end -0.12065 0.3048)
			(stroke
				(width 0.1)
				(type default)
			)
			(layer "F.Fab")
		)
		(fp_line
			(start 0.120396 0.2794)
			(end -0.12065 0.2794)
			(stroke
				(width 0.1)
				(type default)
			)
			(layer "F.Fab")
		)
		(fp_line
			(start -0.12065 -0.2794)
			(end 0.12065 -0.2794)
			(stroke
				(width 0.1)
				(type default)
			)
			(layer "F.Fab")
		)
		(fp_line
			(start 0.12065 -0.2794)
			(end 0.12065 -0.3048)
			(stroke
				(width 0.1)
				(type default)
			)
			(layer "F.Fab")
		)
		(fp_line
			(start 0.12065 -0.3048)
			(end 0.67945 -0.3048)
			(stroke
				(width 0.1)
				(type default)
			)
			(layer "F.Fab")
		)
		(fp_line
			(start 0.67945 -0.3048)
			(end 0.67945 0.3048)
			(stroke
				(width 0.1)
				(type default)
			)
			(layer "F.Fab")
		)
		(fp_line
			(start -0.67945 -0.305054)
			(end -0.12065 -0.305054)
			(stroke
				(width 0.1)
				(type default)
			)
			(layer "F.Fab")
		)
		(fp_line
			(start -0.12065 -0.305054)
			(end -0.12065 -0.2794)
			(stroke
				(width 0.1)
				(type default)
			)
			(layer "F.Fab")
		)
		(pad "1" smd circle
			(at -0.40005 0 270)
			(size 0 0)
			(layers "F.Cu" "F.Mask" "F.Paste")
			(net "NIC6_MAIN_PWR_BIC_EN_R")
		)
		(pad "2" smd circle
			(at 0.40005 0 270)
			(size 0 0)
			(layers "F.Cu" "F.Mask" "F.Paste")
			(net "NIC6_MAIN_PWR_BIC_EN")
		)
	)
	(footprint ""
		(layer "F.Cu")
		(at 441.273692 -350.098614 90)
		(property "Reference" "C2470"
			(at 0 0 90)
			(layer "F.SilkS")
			(hide yes)
			(effects
				(font
					(size 1.27 1.27)
				)
			)
		)
		(property "Value" ""
			(at 0 0 90)
			(layer "F.Fab")
			(effects
				(font
					(size 1.27 1.27)
				)
			)
		)
		(duplicate_pad_numbers_are_jumpers no)
		(fp_line
			(start 0.299974 -0.150114)
			(end 0.299974 0.150114)
			(stroke
				(width 0.1)
				(type default)
			)
			(layer "F.Fab")
		)
		(fp_line
			(start -0.299974 -0.150114)
			(end 0.299974 -0.150114)
			(stroke
				(width 0.1)
				(type default)
			)
			(layer "F.Fab")
		)
		(fp_line
			(start 0.299974 0.150114)
			(end -0.299974 0.150114)
			(stroke
				(width 0.1)
				(type default)
			)
			(layer "F.Fab")
		)
		(fp_line
			(start -0.299974 0.150114)
			(end -0.299974 -0.150114)
			(stroke
				(width 0.1)
				(type default)
			)
			(layer "F.Fab")
		)
		(pad "1" smd rect
			(at -0.2667 0 90)
			(size 0.3048 0.381)
			(layers "F.Cu" "F.Mask" "F.Paste")
			(net "P5E_PEX3_STN4_TX_DN<64>")
		)
		(pad "2" smd rect
			(at 0.2667 0 90)
			(size 0.3048 0.381)
			(layers "F.Cu" "F.Mask" "F.Paste")
			(net "P5E_PEX3_STN4_TX_C_DN<64>")
		)
	)
	(footprint ""
		(layer "F.Cu")
		(at 211.892388 -31.825184 180)
		(property "Reference" "C303"
			(at 0 0 180)
			(layer "F.SilkS")
			(hide yes)
			(effects
				(font
					(size 1.27 1.27)
				)
			)
		)
		(property "Value" ""
			(at 0 0 180)
			(layer "F.Fab")
			(effects
				(font
					(size 1.27 1.27)
				)
			)
		)
		(duplicate_pad_numbers_are_jumpers no)
		(fp_line
			(start 0.299974 0.150114)
			(end -0.299974 0.150114)
			(stroke
				(width 0.1)
				(type default)
			)
			(layer "F.Fab")
		)
		(fp_line
			(start 0.299974 -0.150114)
			(end 0.299974 0.150114)
			(stroke
				(width 0.1)
				(type default)
			)
			(layer "F.Fab")
		)
		(fp_line
			(start -0.299974 0.150114)
			(end -0.299974 -0.150114)
			(stroke
				(width 0.1)
				(type default)
			)
			(layer "F.Fab")
		)
		(fp_line
			(start -0.299974 -0.150114)
			(end 0.299974 -0.150114)
			(stroke
				(width 0.1)
				(type default)
			)
			(layer "F.Fab")
		)
		(pad "1" smd rect
			(at -0.2667 0 180)
			(size 0.3048 0.381)
			(layers "F.Cu" "F.Mask" "F.Paste")
			(net "P5E_PEX1_STN2_TX_DN<34>")
		)
		(pad "2" smd rect
			(at 0.2667 0 180)
			(size 0.3048 0.381)
			(layers "F.Cu" "F.Mask" "F.Paste")
			(net "P5E_PEX1_STN2_TX_C_DN<34>")
		)
	)
	(footprint ""
		(layer "F.Cu")
		(at 233.326178 -37.929566 90)
		(property "Reference" "R5564"
			(at 0 0 90)
			(layer "F.SilkS")
			(hide yes)
			(effects
				(font
					(size 1.27 1.27)
				)
			)
		)
		(property "Value" ""
			(at 0 0 90)
			(layer "F.Fab")
			(effects
				(font
					(size 1.27 1.27)
				)
			)
		)
		(duplicate_pad_numbers_are_jumpers no)
		(fp_line
			(start 0.7874 -0.4064)
			(end 0.7874 0.4064)
			(stroke
				(width 0.1524)
				(type default)
			)
			(layer "F.SilkS")
		)
		(fp_line
			(start -0.7874 -0.4064)
			(end 0.7874 -0.4064)
			(stroke
				(width 0.1524)
				(type default)
			)
			(layer "F.SilkS")
		)
		(fp_line
			(start 0.7874 0.4064)
			(end -0.7874 0.4064)
			(stroke
				(width 0.1524)
				(type default)
			)
			(layer "F.SilkS")
		)
		(fp_line
			(start -0.7874 0.4064)
			(end -0.7874 -0.4064)
			(stroke
				(width 0.1524)
				(type default)
			)
			(layer "F.SilkS")
		)
		(fp_line
			(start -0.12065 -0.305054)
			(end -0.12065 -0.2794)
			(stroke
				(width 0.1)
				(type default)
			)
			(layer "F.Fab")
		)
		(fp_line
			(start -0.67945 -0.305054)
			(end -0.12065 -0.305054)
			(stroke
				(width 0.1)
				(type default)
			)
			(layer "F.Fab")
		)
		(fp_line
			(start 0.67945 -0.3048)
			(end 0.67945 0.3048)
			(stroke
				(width 0.1)
				(type default)
			)
			(layer "F.Fab")
		)
		(fp_line
			(start 0.12065 -0.3048)
			(end 0.67945 -0.3048)
			(stroke
				(width 0.1)
				(type default)
			)
			(layer "F.Fab")
		)
		(fp_line
			(start 0.12065 -0.2794)
			(end 0.12065 -0.3048)
			(stroke
				(width 0.1)
				(type default)
			)
			(layer "F.Fab")
		)
		(fp_line
			(start -0.12065 -0.2794)
			(end 0.12065 -0.2794)
			(stroke
				(width 0.1)
				(type default)
			)
			(layer "F.Fab")
		)
		(fp_line
			(start 0.120396 0.2794)
			(end -0.12065 0.2794)
			(stroke
				(width 0.1)
				(type default)
			)
			(layer "F.Fab")
		)
		(fp_line
			(start -0.12065 0.2794)
			(end -0.12065 0.3048)
			(stroke
				(width 0.1)
				(type default)
			)
			(layer "F.Fab")
		)
		(fp_line
			(start 0.67945 0.3048)
			(end 0.120396 0.3048)
			(stroke
				(width 0.1)
				(type default)
			)
			(layer "F.Fab")
		)
		(fp_line
			(start 0.120396 0.3048)
			(end 0.120396 0.2794)
			(stroke
				(width 0.1)
				(type default)
			)
			(layer "F.Fab")
		)
		(fp_line
			(start -0.12065 0.3048)
			(end -0.67945 0.3048)
			(stroke
				(width 0.1)
				(type default)
			)
			(layer "F.Fab")
		)
		(fp_line
			(start -0.67945 0.3048)
			(end -0.67945 -0.305054)
			(stroke
				(width 0.1)
				(type default)
			)
			(layer "F.Fab")
		)
		(pad "1" smd circle
			(at -0.40005 0 90)
			(size 0 0)
			(layers "F.Cu" "F.Mask" "F.Paste")
			(net "SSD8_AUX_P3V3_EN_R")
		)
		(pad "2" smd circle
			(at 0.40005 0 90)
			(size 0 0)
			(layers "F.Cu" "F.Mask" "F.Paste")
			(net "SSD8_AUX_P3V3_EN")
		)
	)
	(footprint ""
		(layer "F.Cu")
		(at 89.012268 -300.64202 -90)
		(property "Reference" "R3883"
			(at 0 0 270)
			(layer "F.SilkS")
			(hide yes)
			(effects
				(font
					(size 1.27 1.27)
				)
			)
		)
		(property "Value" ""
			(at 0 0 270)
			(layer "F.Fab")
			(effects
				(font
					(size 1.27 1.27)
				)
			)
		)
		(duplicate_pad_numbers_are_jumpers no)
		(fp_line
			(start -0.7874 0.4064)
			(end -0.7874 -0.4064)
			(stroke
				(width 0.1524)
				(type default)
			)
			(layer "F.SilkS")
		)
		(fp_line
			(start 0.7874 0.4064)
			(end -0.7874 0.4064)
			(stroke
				(width 0.1524)
				(type default)
			)
			(layer "F.SilkS")
		)
		(fp_line
			(start -0.7874 -0.4064)
			(end 0.7874 -0.4064)
			(stroke
				(width 0.1524)
				(type default)
			)
			(layer "F.SilkS")
		)
		(fp_line
			(start 0.7874 -0.4064)
			(end 0.7874 0.4064)
			(stroke
				(width 0.1524)
				(type default)
			)
			(layer "F.SilkS")
		)
		(fp_line
			(start -0.67945 0.3048)
			(end -0.67945 -0.305054)
			(stroke
				(width 0.1)
				(type default)
			)
			(layer "F.Fab")
		)
		(fp_line
			(start -0.12065 0.3048)
			(end -0.67945 0.3048)
			(stroke
				(width 0.1)
				(type default)
			)
			(layer "F.Fab")
		)
		(fp_line
			(start 0.120396 0.3048)
			(end 0.120396 0.2794)
			(stroke
				(width 0.1)
				(type default)
			)
			(layer "F.Fab")
		)
		(fp_line
			(start 0.67945 0.3048)
			(end 0.120396 0.3048)
			(stroke
				(width 0.1)
				(type default)
			)
			(layer "F.Fab")
		)
		(fp_line
			(start -0.12065 0.2794)
			(end -0.12065 0.3048)
			(stroke
				(width 0.1)
				(type default)
			)
			(layer "F.Fab")
		)
		(fp_line
			(start 0.120396 0.2794)
			(end -0.12065 0.2794)
			(stroke
				(width 0.1)
				(type default)
			)
			(layer "F.Fab")
		)
		(fp_line
			(start -0.12065 -0.2794)
			(end 0.12065 -0.2794)
			(stroke
				(width 0.1)
				(type default)
			)
			(layer "F.Fab")
		)
		(fp_line
			(start 0.12065 -0.2794)
			(end 0.12065 -0.3048)
			(stroke
				(width 0.1)
				(type default)
			)
			(layer "F.Fab")
		)
		(fp_line
			(start 0.12065 -0.3048)
			(end 0.67945 -0.3048)
			(stroke
				(width 0.1)
				(type default)
			)
			(layer "F.Fab")
		)
		(fp_line
			(start 0.67945 -0.3048)
			(end 0.67945 0.3048)
			(stroke
				(width 0.1)
				(type default)
			)
			(layer "F.Fab")
		)
		(fp_line
			(start -0.67945 -0.305054)
			(end -0.12065 -0.305054)
			(stroke
				(width 0.1)
				(type default)
			)
			(layer "F.Fab")
		)
		(fp_line
			(start -0.12065 -0.305054)
			(end -0.12065 -0.2794)
			(stroke
				(width 0.1)
				(type default)
			)
			(layer "F.Fab")
		)
		(pad "1" smd circle
			(at -0.40005 0 270)
			(size 0 0)
			(layers "F.Cu" "F.Mask" "F.Paste")
			(net "I2C0_PEX0_SHPC_SDA")
		)
		(pad "2" smd circle
			(at 0.40005 0 270)
			(size 0 0)
			(layers "F.Cu" "F.Mask" "F.Paste")
			(net "I2C_PEX0_HOST_SDA")
		)
	)
	(footprint ""
		(layer "F.Cu")
		(at 462.465674 -278.67483)
		(property "Reference" "R801"
			(at 0 0 0)
			(layer "F.SilkS")
			(hide yes)
			(effects
				(font
					(size 1.27 1.27)
				)
			)
		)
		(property "Value" ""
			(at 0 0 0)
			(layer "F.Fab")
			(effects
				(font
					(size 1.27 1.27)
				)
			)
		)
		(duplicate_pad_numbers_are_jumpers no)
		(fp_line
			(start -0.7874 -0.4064)
			(end 0.7874 -0.4064)
			(stroke
				(width 0.1524)
				(type default)
			)
			(layer "F.SilkS")
		)
		(fp_line
			(start -0.7874 0.4064)
			(end -0.7874 -0.4064)
			(stroke
				(width 0.1524)
				(type default)
			)
			(layer "F.SilkS")
		)
		(fp_line
			(start 0.7874 -0.4064)
			(end 0.7874 0.4064)
			(stroke
				(width 0.1524)
				(type default)
			)
			(layer "F.SilkS")
		)
		(fp_line
			(start 0.7874 0.4064)
			(end -0.7874 0.4064)
			(stroke
				(width 0.1524)
				(type default)
			)
			(layer "F.SilkS")
		)
		(fp_line
			(start -0.67945 -0.305054)
			(end -0.12065 -0.305054)
			(stroke
				(width 0.1)
				(type default)
			)
			(layer "F.Fab")
		)
		(fp_line
			(start -0.67945 0.3048)
			(end -0.67945 -0.305054)
			(stroke
				(width 0.1)
				(type default)
			)
			(layer "F.Fab")
		)
		(fp_line
			(start -0.12065 -0.305054)
			(end -0.12065 -0.2794)
			(stroke
				(width 0.1)
				(type default)
			)
			(layer "F.Fab")
		)
		(fp_line
			(start -0.12065 -0.2794)
			(end 0.12065 -0.2794)
			(stroke
				(width 0.1)
				(type default)
			)
			(layer "F.Fab")
		)
		(fp_line
			(start -0.12065 0.2794)
			(end -0.12065 0.3048)
			(stroke
				(width 0.1)
				(type default)
			)
			(layer "F.Fab")
		)
		(fp_line
			(start -0.12065 0.3048)
			(end -0.67945 0.3048)
			(stroke
				(width 0.1)
				(type default)
			)
			(layer "F.Fab")
		)
		(fp_line
			(start 0.120396 0.2794)
			(end -0.12065 0.2794)
			(stroke
				(width 0.1)
				(type default)
			)
			(layer "F.Fab")
		)
		(fp_line
			(start 0.120396 0.3048)
			(end 0.120396 0.2794)
			(stroke
				(width 0.1)
				(type default)
			)
			(layer "F.Fab")
		)
		(fp_line
			(start 0.12065 -0.3048)
			(end 0.67945 -0.3048)
			(stroke
				(width 0.1)
				(type default)
			)
			(layer "F.Fab")
		)
		(fp_line
			(start 0.12065 -0.2794)
			(end 0.12065 -0.3048)
			(stroke
				(width 0.1)
				(type default)
			)
			(layer "F.Fab")
		)
		(fp_line
			(start 0.67945 -0.3048)
			(end 0.67945 0.3048)
			(stroke
				(width 0.1)
				(type default)
			)
			(layer "F.Fab")
		)
		(fp_line
			(start 0.67945 0.3048)
			(end 0.120396 0.3048)
			(stroke
				(width 0.1)
				(type default)
			)
			(layer "F.Fab")
		)
		(pad "1" smd circle
			(at -0.40005 0)
			(size 0 0)
			(layers "F.Cu" "F.Mask" "F.Paste")
			(net "P3V3_AUX")
		)
		(pad "2" smd circle
			(at 0.40005 0)
			(size 0 0)
			(layers "F.Cu" "F.Mask" "F.Paste")
			(net "PEX_ADC_ALERT_N")
		)
	)
	(footprint ""
		(layer "F.Cu")
		(at 378.079 -203.2 90)
		(property "Reference" "C3600"
			(at 0 0 90)
			(layer "F.SilkS")
			(hide yes)
			(effects
				(font
					(size 1.27 1.27)
				)
			)
		)
		(property "Value" ""
			(at 0 0 90)
			(layer "F.Fab")
			(effects
				(font
					(size 1.27 1.27)
				)
			)
		)
		(duplicate_pad_numbers_are_jumpers no)
		(fp_line
			(start 0.7874 -0.4064)
			(end 0.7874 0.4064)
			(stroke
				(width 0.1524)
				(type default)
			)
			(layer "F.SilkS")
		)
		(fp_line
			(start -0.7874 -0.4064)
			(end 0.7874 -0.4064)
			(stroke
				(width 0.1524)
				(type default)
			)
			(layer "F.SilkS")
		)
		(fp_line
			(start 0.7874 0.4064)
			(end -0.7874 0.4064)
			(stroke
				(width 0.1524)
				(type default)
			)
			(layer "F.SilkS")
		)
		(fp_line
			(start -0.7874 0.4064)
			(end -0.7874 -0.4064)
			(stroke
				(width 0.1524)
				(type default)
			)
			(layer "F.SilkS")
		)
		(fp_line
			(start -0.12065 -0.305054)
			(end -0.12065 -0.2794)
			(stroke
				(width 0.1)
				(type default)
			)
			(layer "F.Fab")
		)
		(fp_line
			(start -0.67945 -0.305054)
			(end -0.12065 -0.305054)
			(stroke
				(width 0.1)
				(type default)
			)
			(layer "F.Fab")
		)
		(fp_line
			(start 0.67945 -0.3048)
			(end 0.67945 0.3048)
			(stroke
				(width 0.1)
				(type default)
			)
			(layer "F.Fab")
		)
		(fp_line
			(start 0.12065 -0.3048)
			(end 0.67945 -0.3048)
			(stroke
				(width 0.1)
				(type default)
			)
			(layer "F.Fab")
		)
		(fp_line
			(start 0.12065 -0.2794)
			(end 0.12065 -0.3048)
			(stroke
				(width 0.1)
				(type default)
			)
			(layer "F.Fab")
		)
		(fp_line
			(start -0.12065 -0.2794)
			(end 0.12065 -0.2794)
			(stroke
				(width 0.1)
				(type default)
			)
			(layer "F.Fab")
		)
		(fp_line
			(start 0.120396 0.2794)
			(end -0.12065 0.2794)
			(stroke
				(width 0.1)
				(type default)
			)
			(layer "F.Fab")
		)
		(fp_line
			(start -0.12065 0.2794)
			(end -0.12065 0.3048)
			(stroke
				(width 0.1)
				(type default)
			)
			(layer "F.Fab")
		)
		(fp_line
			(start 0.67945 0.3048)
			(end 0.120396 0.3048)
			(stroke
				(width 0.1)
				(type default)
			)
			(layer "F.Fab")
		)
		(fp_line
			(start 0.120396 0.3048)
			(end 0.120396 0.2794)
			(stroke
				(width 0.1)
				(type default)
			)
			(layer "F.Fab")
		)
		(fp_line
			(start -0.12065 0.3048)
			(end -0.67945 0.3048)
			(stroke
				(width 0.1)
				(type default)
			)
			(layer "F.Fab")
		)
		(fp_line
			(start -0.67945 0.3048)
			(end -0.67945 -0.305054)
			(stroke
				(width 0.1)
				(type default)
			)
			(layer "F.Fab")
		)
		(pad "1" smd circle
			(at -0.40005 0 90)
			(size 0 0)
			(layers "F.Cu" "F.Mask" "F.Paste")
			(net "P3V3_AUX")
		)
		(pad "2" smd circle
			(at 0.40005 0 90)
			(size 0 0)
			(layers "F.Cu" "F.Mask" "F.Paste")
			(net "GND")
		)
	)
	(footprint ""
		(layer "F.Cu")
		(at 284.330902 -350.098614 90)
		(property "Reference" "C2356"
			(at 0 0 90)
			(layer "F.SilkS")
			(hide yes)
			(effects
				(font
					(size 1.27 1.27)
				)
			)
		)
		(property "Value" ""
			(at 0 0 90)
			(layer "F.Fab")
			(effects
				(font
					(size 1.27 1.27)
				)
			)
		)
		(duplicate_pad_numbers_are_jumpers no)
		(fp_line
			(start 0.299974 -0.150114)
			(end 0.299974 0.150114)
			(stroke
				(width 0.1)
				(type default)
			)
			(layer "F.Fab")
		)
		(fp_line
			(start -0.299974 -0.150114)
			(end 0.299974 -0.150114)
			(stroke
				(width 0.1)
				(type default)
			)
			(layer "F.Fab")
		)
		(fp_line
			(start 0.299974 0.150114)
			(end -0.299974 0.150114)
			(stroke
				(width 0.1)
				(type default)
			)
			(layer "F.Fab")
		)
		(fp_line
			(start -0.299974 0.150114)
			(end -0.299974 -0.150114)
			(stroke
				(width 0.1)
				(type default)
			)
			(layer "F.Fab")
		)
		(pad "1" smd rect
			(at -0.2667 0 90)
			(size 0.3048 0.381)
			(layers "F.Cu" "F.Mask" "F.Paste")
			(net "P5E_PEX2_STN4_TX_DN<72>")
		)
		(pad "2" smd rect
			(at 0.2667 0 90)
			(size 0.3048 0.381)
			(layers "F.Cu" "F.Mask" "F.Paste")
			(net "P5E_PEX2_STN4_TX_C_DN<72>")
		)
	)
	(footprint ""
		(layer "F.Cu")
		(at 344.511884 -112.547654)
		(property "Reference" "PC817"
			(at 0 0 0)
			(layer "F.SilkS")
			(hide yes)
			(effects
				(font
					(size 1.27 1.27)
				)
			)
		)
		(property "Value" ""
			(at 0 0 0)
			(layer "F.Fab")
			(effects
				(font
					(size 1.27 1.27)
				)
			)
		)
		(duplicate_pad_numbers_are_jumpers no)
		(fp_line
			(start -0.7874 -0.4064)
			(end 0.7874 -0.4064)
			(stroke
				(width 0.1524)
				(type default)
			)
			(layer "F.SilkS")
		)
		(fp_line
			(start -0.7874 0.4064)
			(end -0.7874 -0.4064)
			(stroke
				(width 0.1524)
				(type default)
			)
			(layer "F.SilkS")
		)
		(fp_line
			(start 0.7874 -0.4064)
			(end 0.7874 0.4064)
			(stroke
				(width 0.1524)
				(type default)
			)
			(layer "F.SilkS")
		)
		(fp_line
			(start 0.7874 0.4064)
			(end -0.7874 0.4064)
			(stroke
				(width 0.1524)
				(type default)
			)
			(layer "F.SilkS")
		)
		(fp_line
			(start -0.67945 -0.305054)
			(end -0.12065 -0.305054)
			(stroke
				(width 0.1)
				(type default)
			)
			(layer "F.Fab")
		)
		(fp_line
			(start -0.67945 0.3048)
			(end -0.67945 -0.305054)
			(stroke
				(width 0.1)
				(type default)
			)
			(layer "F.Fab")
		)
		(fp_line
			(start -0.12065 -0.305054)
			(end -0.12065 -0.2794)
			(stroke
				(width 0.1)
				(type default)
			)
			(layer "F.Fab")
		)
		(fp_line
			(start -0.12065 -0.2794)
			(end 0.12065 -0.2794)
			(stroke
				(width 0.1)
				(type default)
			)
			(layer "F.Fab")
		)
		(fp_line
			(start -0.12065 0.2794)
			(end -0.12065 0.3048)
			(stroke
				(width 0.1)
				(type default)
			)
			(layer "F.Fab")
		)
		(fp_line
			(start -0.12065 0.3048)
			(end -0.67945 0.3048)
			(stroke
				(width 0.1)
				(type default)
			)
			(layer "F.Fab")
		)
		(fp_line
			(start 0.120396 0.2794)
			(end -0.12065 0.2794)
			(stroke
				(width 0.1)
				(type default)
			)
			(layer "F.Fab")
		)
		(fp_line
			(start 0.120396 0.3048)
			(end 0.120396 0.2794)
			(stroke
				(width 0.1)
				(type default)
			)
			(layer "F.Fab")
		)
		(fp_line
			(start 0.12065 -0.3048)
			(end 0.67945 -0.3048)
			(stroke
				(width 0.1)
				(type default)
			)
			(layer "F.Fab")
		)
		(fp_line
			(start 0.12065 -0.2794)
			(end 0.12065 -0.3048)
			(stroke
				(width 0.1)
				(type default)
			)
			(layer "F.Fab")
		)
		(fp_line
			(start 0.67945 -0.3048)
			(end 0.67945 0.3048)
			(stroke
				(width 0.1)
				(type default)
			)
			(layer "F.Fab")
		)
		(fp_line
			(start 0.67945 0.3048)
			(end 0.120396 0.3048)
			(stroke
				(width 0.1)
				(type default)
			)
			(layer "F.Fab")
		)
		(pad "1" smd circle
			(at -0.40005 0)
			(size 0 0)
			(layers "F.Cu" "F.Mask" "F.Paste")
			(net "P12V_NIC5_CO_ISET_R")
		)
		(pad "2" smd circle
			(at 0.40005 0)
			(size 0 0)
			(layers "F.Cu" "F.Mask" "F.Paste")
			(net "GND")
		)
	)
	(footprint ""
		(layer "F.Cu")
		(at 347.842586 -257.13055 180)
		(property "Reference" "PC136"
			(at 0 0 180)
			(layer "F.SilkS")
			(hide yes)
			(effects
				(font
					(size 1.27 1.27)
				)
			)
		)
		(property "Value" ""
			(at 0 0 180)
			(layer "F.Fab")
			(effects
				(font
					(size 1.27 1.27)
				)
			)
		)
		(duplicate_pad_numbers_are_jumpers no)
		(fp_line
			(start 0.7874 0.4064)
			(end -0.7874 0.4064)
			(stroke
				(width 0.1524)
				(type default)
			)
			(layer "F.SilkS")
		)
		(fp_line
			(start 0.7874 -0.4064)
			(end 0.7874 0.4064)
			(stroke
				(width 0.1524)
				(type default)
			)
			(layer "F.SilkS")
		)
		(fp_line
			(start -0.7874 0.4064)
			(end -0.7874 -0.4064)
			(stroke
				(width 0.1524)
				(type default)
			)
			(layer "F.SilkS")
		)
		(fp_line
			(start -0.7874 -0.4064)
			(end 0.7874 -0.4064)
			(stroke
				(width 0.1524)
				(type default)
			)
			(layer "F.SilkS")
		)
		(fp_line
			(start 0.67945 0.3048)
			(end 0.120396 0.3048)
			(stroke
				(width 0.1)
				(type default)
			)
			(layer "F.Fab")
		)
		(fp_line
			(start 0.67945 -0.3048)
			(end 0.67945 0.3048)
			(stroke
				(width 0.1)
				(type default)
			)
			(layer "F.Fab")
		)
		(fp_line
			(start 0.12065 -0.2794)
			(end 0.12065 -0.3048)
			(stroke
				(width 0.1)
				(type default)
			)
			(layer "F.Fab")
		)
		(fp_line
			(start 0.12065 -0.3048)
			(end 0.67945 -0.3048)
			(stroke
				(width 0.1)
				(type default)
			)
			(layer "F.Fab")
		)
		(fp_line
			(start 0.120396 0.3048)
			(end 0.120396 0.2794)
			(stroke
				(width 0.1)
				(type default)
			)
			(layer "F.Fab")
		)
		(fp_line
			(start 0.120396 0.2794)
			(end -0.12065 0.2794)
			(stroke
				(width 0.1)
				(type default)
			)
			(layer "F.Fab")
		)
		(fp_line
			(start -0.12065 0.3048)
			(end -0.67945 0.3048)
			(stroke
				(width 0.1)
				(type default)
			)
			(layer "F.Fab")
		)
		(fp_line
			(start -0.12065 0.2794)
			(end -0.12065 0.3048)
			(stroke
				(width 0.1)
				(type default)
			)
			(layer "F.Fab")
		)
		(fp_line
			(start -0.12065 -0.2794)
			(end 0.12065 -0.2794)
			(stroke
				(width 0.1)
				(type default)
			)
			(layer "F.Fab")
		)
		(fp_line
			(start -0.12065 -0.305054)
			(end -0.12065 -0.2794)
			(stroke
				(width 0.1)
				(type default)
			)
			(layer "F.Fab")
		)
		(fp_line
			(start -0.67945 0.3048)
			(end -0.67945 -0.305054)
			(stroke
				(width 0.1)
				(type default)
			)
			(layer "F.Fab")
		)
		(fp_line
			(start -0.67945 -0.305054)
			(end -0.12065 -0.305054)
			(stroke
				(width 0.1)
				(type default)
			)
			(layer "F.Fab")
		)
		(pad "1" smd circle
			(at -0.40005 0 180)
			(size 0 0)
			(layers "F.Cu" "F.Mask" "F.Paste")
			(net "P0V8_PEX2_VINSEN")
		)
		(pad "2" smd circle
			(at 0.40005 0 180)
			(size 0 0)
			(layers "F.Cu" "F.Mask" "F.Paste")
			(net "GND")
		)
	)
	(footprint ""
		(layer "F.Cu")
		(at 266.683744 -336.197194)
		(property "Reference" "C4484"
			(at 0 0 0)
			(layer "F.SilkS")
			(hide yes)
			(effects
				(font
					(size 1.27 1.27)
				)
			)
		)
		(property "Value" ""
			(at 0 0 0)
			(layer "F.Fab")
			(effects
				(font
					(size 1.27 1.27)
				)
			)
		)
		(duplicate_pad_numbers_are_jumpers no)
		(fp_line
			(start -0.7874 -0.4064)
			(end 0.7874 -0.4064)
			(stroke
				(width 0.1524)
				(type default)
			)
			(layer "F.SilkS")
		)
		(fp_line
			(start -0.7874 0.4064)
			(end -0.7874 -0.4064)
			(stroke
				(width 0.1524)
				(type default)
			)
			(layer "F.SilkS")
		)
		(fp_line
			(start 0.7874 -0.4064)
			(end 0.7874 0.4064)
			(stroke
				(width 0.1524)
				(type default)
			)
			(layer "F.SilkS")
		)
		(fp_line
			(start 0.7874 0.4064)
			(end -0.7874 0.4064)
			(stroke
				(width 0.1524)
				(type default)
			)
			(layer "F.SilkS")
		)
		(fp_line
			(start -0.67945 -0.305054)
			(end -0.12065 -0.305054)
			(stroke
				(width 0.1)
				(type default)
			)
			(layer "F.Fab")
		)
		(fp_line
			(start -0.67945 0.3048)
			(end -0.67945 -0.305054)
			(stroke
				(width 0.1)
				(type default)
			)
			(layer "F.Fab")
		)
		(fp_line
			(start -0.12065 -0.305054)
			(end -0.12065 -0.2794)
			(stroke
				(width 0.1)
				(type default)
			)
			(layer "F.Fab")
		)
		(fp_line
			(start -0.12065 -0.2794)
			(end 0.12065 -0.2794)
			(stroke
				(width 0.1)
				(type default)
			)
			(layer "F.Fab")
		)
		(fp_line
			(start -0.12065 0.2794)
			(end -0.12065 0.3048)
			(stroke
				(width 0.1)
				(type default)
			)
			(layer "F.Fab")
		)
		(fp_line
			(start -0.12065 0.3048)
			(end -0.67945 0.3048)
			(stroke
				(width 0.1)
				(type default)
			)
			(layer "F.Fab")
		)
		(fp_line
			(start 0.120396 0.2794)
			(end -0.12065 0.2794)
			(stroke
				(width 0.1)
				(type default)
			)
			(layer "F.Fab")
		)
		(fp_line
			(start 0.120396 0.3048)
			(end 0.120396 0.2794)
			(stroke
				(width 0.1)
				(type default)
			)
			(layer "F.Fab")
		)
		(fp_line
			(start 0.12065 -0.3048)
			(end 0.67945 -0.3048)
			(stroke
				(width 0.1)
				(type default)
			)
			(layer "F.Fab")
		)
		(fp_line
			(start 0.12065 -0.2794)
			(end 0.12065 -0.3048)
			(stroke
				(width 0.1)
				(type default)
			)
			(layer "F.Fab")
		)
		(fp_line
			(start 0.67945 -0.3048)
			(end 0.67945 0.3048)
			(stroke
				(width 0.1)
				(type default)
			)
			(layer "F.Fab")
		)
		(fp_line
			(start 0.67945 0.3048)
			(end 0.120396 0.3048)
			(stroke
				(width 0.1)
				(type default)
			)
			(layer "F.Fab")
		)
		(pad "1" smd circle
			(at -0.40005 0)
			(size 0 0)
			(layers "F.Cu" "F.Mask" "F.Paste")
			(net "P12V_AUX")
		)
		(pad "2" smd circle
			(at 0.40005 0)
			(size 0 0)
			(layers "F.Cu" "F.Mask" "F.Paste")
			(net "GND")
		)
	)
	(footprint ""
		(layer "F.Cu")
		(at 228.79304 -92.041726 180)
		(property "Reference" "R1022"
			(at 0 0 180)
			(layer "F.SilkS")
			(hide yes)
			(effects
				(font
					(size 1.27 1.27)
				)
			)
		)
		(property "Value" ""
			(at 0 0 180)
			(layer "F.Fab")
			(effects
				(font
					(size 1.27 1.27)
				)
			)
		)
		(duplicate_pad_numbers_are_jumpers no)
		(fp_line
			(start 0.7874 0.4064)
			(end -0.7874 0.4064)
			(stroke
				(width 0.1524)
				(type default)
			)
			(layer "F.SilkS")
		)
		(fp_line
			(start 0.7874 -0.4064)
			(end 0.7874 0.4064)
			(stroke
				(width 0.1524)
				(type default)
			)
			(layer "F.SilkS")
		)
		(fp_line
			(start -0.7874 0.4064)
			(end -0.7874 -0.4064)
			(stroke
				(width 0.1524)
				(type default)
			)
			(layer "F.SilkS")
		)
		(fp_line
			(start -0.7874 -0.4064)
			(end 0.7874 -0.4064)
			(stroke
				(width 0.1524)
				(type default)
			)
			(layer "F.SilkS")
		)
		(fp_line
			(start 0.67945 0.3048)
			(end 0.120396 0.3048)
			(stroke
				(width 0.1)
				(type default)
			)
			(layer "F.Fab")
		)
		(fp_line
			(start 0.67945 -0.3048)
			(end 0.67945 0.3048)
			(stroke
				(width 0.1)
				(type default)
			)
			(layer "F.Fab")
		)
		(fp_line
			(start 0.12065 -0.2794)
			(end 0.12065 -0.3048)
			(stroke
				(width 0.1)
				(type default)
			)
			(layer "F.Fab")
		)
		(fp_line
			(start 0.12065 -0.3048)
			(end 0.67945 -0.3048)
			(stroke
				(width 0.1)
				(type default)
			)
			(layer "F.Fab")
		)
		(fp_line
			(start 0.120396 0.3048)
			(end 0.120396 0.2794)
			(stroke
				(width 0.1)
				(type default)
			)
			(layer "F.Fab")
		)
		(fp_line
			(start 0.120396 0.2794)
			(end -0.12065 0.2794)
			(stroke
				(width 0.1)
				(type default)
			)
			(layer "F.Fab")
		)
		(fp_line
			(start -0.12065 0.3048)
			(end -0.67945 0.3048)
			(stroke
				(width 0.1)
				(type default)
			)
			(layer "F.Fab")
		)
		(fp_line
			(start -0.12065 0.2794)
			(end -0.12065 0.3048)
			(stroke
				(width 0.1)
				(type default)
			)
			(layer "F.Fab")
		)
		(fp_line
			(start -0.12065 -0.2794)
			(end 0.12065 -0.2794)
			(stroke
				(width 0.1)
				(type default)
			)
			(layer "F.Fab")
		)
		(fp_line
			(start -0.12065 -0.305054)
			(end -0.12065 -0.2794)
			(stroke
				(width 0.1)
				(type default)
			)
			(layer "F.Fab")
		)
		(fp_line
			(start -0.67945 0.3048)
			(end -0.67945 -0.305054)
			(stroke
				(width 0.1)
				(type default)
			)
			(layer "F.Fab")
		)
		(fp_line
			(start -0.67945 -0.305054)
			(end -0.12065 -0.305054)
			(stroke
				(width 0.1)
				(type default)
			)
			(layer "F.Fab")
		)
		(pad "1" smd circle
			(at -0.40005 0 180)
			(size 0 0)
			(layers "F.Cu" "F.Mask" "F.Paste")
			(net "PEX_USB_HUB_PGANG")
		)
		(pad "2" smd circle
			(at 0.40005 0 180)
			(size 0 0)
			(layers "F.Cu" "F.Mask" "F.Paste")
			(net "GND")
		)
	)
	(footprint ""
		(layer "F.Cu")
		(at 130.419856 -170.599862 90)
		(property "Reference" "R1085"
			(at 0 0 90)
			(layer "F.SilkS")
			(hide yes)
			(effects
				(font
					(size 1.27 1.27)
				)
			)
		)
		(property "Value" ""
			(at 0 0 90)
			(layer "F.Fab")
			(effects
				(font
					(size 1.27 1.27)
				)
			)
		)
		(duplicate_pad_numbers_are_jumpers no)
		(fp_line
			(start -0.7874 -0.4064)
			(end 0.7874 -0.4064)
			(stroke
				(width 0.1524)
				(type default)
			)
			(layer "F.SilkS")
		)
		(fp_line
			(start -0.12065 -0.305054)
			(end -0.12065 -0.2794)
			(stroke
				(width 0.1)
				(type default)
			)
			(layer "F.Fab")
		)
		(fp_line
			(start -0.67945 -0.305054)
			(end -0.12065 -0.305054)
			(stroke
				(width 0.1)
				(type default)
			)
			(layer "F.Fab")
		)
		(fp_line
			(start 0.67945 -0.3048)
			(end 0.67945 0.3048)
			(stroke
				(width 0.1)
				(type default)
			)
			(layer "F.Fab")
		)
		(fp_line
			(start 0.12065 -0.3048)
			(end 0.67945 -0.3048)
			(stroke
				(width 0.1)
				(type default)
			)
			(layer "F.Fab")
		)
		(fp_line
			(start 0.12065 -0.2794)
			(end 0.12065 -0.3048)
			(stroke
				(width 0.1)
				(type default)
			)
			(layer "F.Fab")
		)
		(fp_line
			(start -0.12065 -0.2794)
			(end 0.12065 -0.2794)
			(stroke
				(width 0.1)
				(type default)
			)
			(layer "F.Fab")
		)
		(fp_line
			(start 0.120396 0.2794)
			(end -0.12065 0.2794)
			(stroke
				(width 0.1)
				(type default)
			)
			(layer "F.Fab")
		)
		(fp_line
			(start -0.12065 0.2794)
			(end -0.12065 0.3048)
			(stroke
				(width 0.1)
				(type default)
			)
			(layer "F.Fab")
		)
		(fp_line
			(start 0.67945 0.3048)
			(end 0.120396 0.3048)
			(stroke
				(width 0.1)
				(type default)
			)
			(layer "F.Fab")
		)
		(fp_line
			(start 0.120396 0.3048)
			(end 0.120396 0.2794)
			(stroke
				(width 0.1)
				(type default)
			)
			(layer "F.Fab")
		)
		(fp_line
			(start -0.12065 0.3048)
			(end -0.67945 0.3048)
			(stroke
				(width 0.1)
				(type default)
			)
			(layer "F.Fab")
		)
		(fp_line
			(start -0.67945 0.3048)
			(end -0.67945 -0.305054)
			(stroke
				(width 0.1)
				(type default)
			)
			(layer "F.Fab")
		)
		(pad "1" smd circle
			(at -0.40005 0 90)
			(size 0 0)
			(layers "F.Cu" "F.Mask" "F.Paste")
			(net "CLK_100M_DB2000QL_PEX3_S1_R_DP")
		)
		(pad "2" smd circle
			(at 0.40005 0 90)
			(size 0 0)
			(layers "F.Cu" "F.Mask" "F.Paste")
			(net "CLK_100M_DB2000QL_PEX3_S1_DP")
		)
	)
	(footprint ""
		(layer "F.Cu")
		(at 121.750328 -50.96383 180)
		(property "Reference" "PC503"
			(at 0 0 180)
			(layer "F.SilkS")
			(hide yes)
			(effects
				(font
					(size 1.27 1.27)
				)
			)
		)
		(property "Value" ""
			(at 0 0 180)
			(layer "F.Fab")
			(effects
				(font
					(size 1.27 1.27)
				)
			)
		)
		(duplicate_pad_numbers_are_jumpers no)
		(fp_line
			(start 1.524 0.762)
			(end -1.524 0.762)
			(stroke
				(width 0.1524)
				(type default)
			)
			(layer "F.SilkS")
		)
		(fp_line
			(start 1.524 -0.762)
			(end 1.524 0.762)
			(stroke
				(width 0.1524)
				(type default)
			)
			(layer "F.SilkS")
		)
		(fp_line
			(start -1.524 0.762)
			(end -1.524 -0.762)
			(stroke
				(width 0.1524)
				(type default)
			)
			(layer "F.SilkS")
		)
		(fp_line
			(start -1.524 -0.762)
			(end 1.524 -0.762)
			(stroke
				(width 0.1524)
				(type default)
			)
			(layer "F.SilkS")
		)
		(fp_line
			(start 1.1049 0.724916)
			(end 1.1049 -0.724916)
			(stroke
				(width 0.1)
				(type default)
			)
			(layer "F.Fab")
		)
		(fp_line
			(start 1.1049 -0.724916)
			(end -1.1049 -0.724916)
			(stroke
				(width 0.1)
				(type default)
			)
			(layer "F.Fab")
		)
		(fp_line
			(start -1.1049 0.724916)
			(end 1.1049 0.724916)
			(stroke
				(width 0.1)
				(type default)
			)
			(layer "F.Fab")
		)
		(fp_line
			(start -1.1049 -0.724916)
			(end -1.1049 0.724916)
			(stroke
				(width 0.1)
				(type default)
			)
			(layer "F.Fab")
		)
		(pad "1" smd rect
			(at -0.889 0)
			(size 1.016 1.27)
			(layers "F.Cu" "F.Mask" "F.Paste")
			(net "P3V3_SSD4")
		)
		(pad "2" smd rect
			(at 0.889 0)
			(size 1.016 1.27)
			(layers "F.Cu" "F.Mask" "F.Paste")
			(net "GND")
		)
	)
	(footprint ""
		(layer "F.Cu")
		(at 229.358444 -273.056858 90)
		(property "Reference" "C4295"
			(at 0 0 90)
			(layer "F.SilkS")
			(hide yes)
			(effects
				(font
					(size 1.27 1.27)
				)
			)
		)
		(property "Value" ""
			(at 0 0 90)
			(layer "F.Fab")
			(effects
				(font
					(size 1.27 1.27)
				)
			)
		)
		(duplicate_pad_numbers_are_jumpers no)
		(fp_line
			(start 0.299974 -0.150114)
			(end 0.299974 0.150114)
			(stroke
				(width 0.1)
				(type default)
			)
			(layer "F.Fab")
		)
		(fp_line
			(start -0.299974 -0.150114)
			(end 0.299974 -0.150114)
			(stroke
				(width 0.1)
				(type default)
			)
			(layer "F.Fab")
		)
		(fp_line
			(start 0.299974 0.150114)
			(end -0.299974 0.150114)
			(stroke
				(width 0.1)
				(type default)
			)
			(layer "F.Fab")
		)
		(fp_line
			(start -0.299974 0.150114)
			(end -0.299974 -0.150114)
			(stroke
				(width 0.1)
				(type default)
			)
			(layer "F.Fab")
		)
		(pad "1" smd rect
			(at -0.2667 0 90)
			(size 0.3048 0.381)
			(layers "F.Cu" "F.Mask" "F.Paste")
			(net "P1V25_SERDES_VDDPLL_PEX1")
		)
		(pad "2" smd rect
			(at 0.2667 0 90)
			(size 0.3048 0.381)
			(layers "F.Cu" "F.Mask" "F.Paste")
			(net "GND")
		)
	)
	(footprint ""
		(layer "F.Cu")
		(at 15.243302 -394.13053 90)
		(property "Reference" "R6842"
			(at 0 0 90)
			(layer "F.SilkS")
			(hide yes)
			(effects
				(font
					(size 1.27 1.27)
				)
			)
		)
		(property "Value" ""
			(at 0 0 90)
			(layer "F.Fab")
			(effects
				(font
					(size 1.27 1.27)
				)
			)
		)
		(duplicate_pad_numbers_are_jumpers no)
		(fp_line
			(start 0.7874 -0.4064)
			(end 0.7874 0.4064)
			(stroke
				(width 0.1524)
				(type default)
			)
			(layer "F.SilkS")
		)
		(fp_line
			(start -0.7874 -0.4064)
			(end 0.7874 -0.4064)
			(stroke
				(width 0.1524)
				(type default)
			)
			(layer "F.SilkS")
		)
		(fp_line
			(start 0.7874 0.4064)
			(end -0.7874 0.4064)
			(stroke
				(width 0.1524)
				(type default)
			)
			(layer "F.SilkS")
		)
		(fp_line
			(start -0.7874 0.4064)
			(end -0.7874 -0.4064)
			(stroke
				(width 0.1524)
				(type default)
			)
			(layer "F.SilkS")
		)
		(fp_line
			(start -0.12065 -0.305054)
			(end -0.12065 -0.2794)
			(stroke
				(width 0.1)
				(type default)
			)
			(layer "F.Fab")
		)
		(fp_line
			(start -0.67945 -0.305054)
			(end -0.12065 -0.305054)
			(stroke
				(width 0.1)
				(type default)
			)
			(layer "F.Fab")
		)
		(fp_line
			(start 0.67945 -0.3048)
			(end 0.67945 0.3048)
			(stroke
				(width 0.1)
				(type default)
			)
			(layer "F.Fab")
		)
		(fp_line
			(start 0.12065 -0.3048)
			(end 0.67945 -0.3048)
			(stroke
				(width 0.1)
				(type default)
			)
			(layer "F.Fab")
		)
		(fp_line
			(start 0.12065 -0.2794)
			(end 0.12065 -0.3048)
			(stroke
				(width 0.1)
				(type default)
			)
			(layer "F.Fab")
		)
		(fp_line
			(start -0.12065 -0.2794)
			(end 0.12065 -0.2794)
			(stroke
				(width 0.1)
				(type default)
			)
			(layer "F.Fab")
		)
		(fp_line
			(start 0.120396 0.2794)
			(end -0.12065 0.2794)
			(stroke
				(width 0.1)
				(type default)
			)
			(layer "F.Fab")
		)
		(fp_line
			(start -0.12065 0.2794)
			(end -0.12065 0.3048)
			(stroke
				(width 0.1)
				(type default)
			)
			(layer "F.Fab")
		)
		(fp_line
			(start 0.67945 0.3048)
			(end 0.120396 0.3048)
			(stroke
				(width 0.1)
				(type default)
			)
			(layer "F.Fab")
		)
		(fp_line
			(start 0.120396 0.3048)
			(end 0.120396 0.2794)
			(stroke
				(width 0.1)
				(type default)
			)
			(layer "F.Fab")
		)
		(fp_line
			(start -0.12065 0.3048)
			(end -0.67945 0.3048)
			(stroke
				(width 0.1)
				(type default)
			)
			(layer "F.Fab")
		)
		(fp_line
			(start -0.67945 0.3048)
			(end -0.67945 -0.305054)
			(stroke
				(width 0.1)
				(type default)
			)
			(layer "F.Fab")
		)
		(pad "1" smd circle
			(at -0.40005 0 90)
			(size 0 0)
			(layers "F.Cu" "F.Mask" "F.Paste")
			(net "BIC_USB_8042_HUB_FULLPWRMGMTZ")
		)
		(pad "2" smd circle
			(at 0.40005 0 90)
			(size 0 0)
			(layers "F.Cu" "F.Mask" "F.Paste")
			(net "P3V3_USB_HUB")
		)
	)
	(footprint ""
		(layer "F.Cu")
		(at 446.47485 -48.753014 180)
		(property "Reference" "C339"
			(at 0 0 180)
			(layer "F.SilkS")
			(hide yes)
			(effects
				(font
					(size 1.27 1.27)
				)
			)
		)
		(property "Value" ""
			(at 0 0 180)
			(layer "F.Fab")
			(effects
				(font
					(size 1.27 1.27)
				)
			)
		)
		(duplicate_pad_numbers_are_jumpers no)
		(fp_line
			(start 0.7874 0.4064)
			(end -0.7874 0.4064)
			(stroke
				(width 0.1524)
				(type default)
			)
			(layer "F.SilkS")
		)
		(fp_line
			(start 0.7874 -0.4064)
			(end 0.7874 0.4064)
			(stroke
				(width 0.1524)
				(type default)
			)
			(layer "F.SilkS")
		)
		(fp_line
			(start -0.7874 0.4064)
			(end -0.7874 -0.4064)
			(stroke
				(width 0.1524)
				(type default)
			)
			(layer "F.SilkS")
		)
		(fp_line
			(start -0.7874 -0.4064)
			(end 0.7874 -0.4064)
			(stroke
				(width 0.1524)
				(type default)
			)
			(layer "F.SilkS")
		)
		(fp_line
			(start 0.67945 0.3048)
			(end 0.120396 0.3048)
			(stroke
				(width 0.1)
				(type default)
			)
			(layer "F.Fab")
		)
		(fp_line
			(start 0.67945 -0.3048)
			(end 0.67945 0.3048)
			(stroke
				(width 0.1)
				(type default)
			)
			(layer "F.Fab")
		)
		(fp_line
			(start 0.12065 -0.2794)
			(end 0.12065 -0.3048)
			(stroke
				(width 0.1)
				(type default)
			)
			(layer "F.Fab")
		)
		(fp_line
			(start 0.12065 -0.3048)
			(end 0.67945 -0.3048)
			(stroke
				(width 0.1)
				(type default)
			)
			(layer "F.Fab")
		)
		(fp_line
			(start 0.120396 0.3048)
			(end 0.120396 0.2794)
			(stroke
				(width 0.1)
				(type default)
			)
			(layer "F.Fab")
		)
		(fp_line
			(start 0.120396 0.2794)
			(end -0.12065 0.2794)
			(stroke
				(width 0.1)
				(type default)
			)
			(layer "F.Fab")
		)
		(fp_line
			(start -0.12065 0.3048)
			(end -0.67945 0.3048)
			(stroke
				(width 0.1)
				(type default)
			)
			(layer "F.Fab")
		)
		(fp_line
			(start -0.12065 0.2794)
			(end -0.12065 0.3048)
			(stroke
				(width 0.1)
				(type default)
			)
			(layer "F.Fab")
		)
		(fp_line
			(start -0.12065 -0.2794)
			(end 0.12065 -0.2794)
			(stroke
				(width 0.1)
				(type default)
			)
			(layer "F.Fab")
		)
		(fp_line
			(start -0.12065 -0.305054)
			(end -0.12065 -0.2794)
			(stroke
				(width 0.1)
				(type default)
			)
			(layer "F.Fab")
		)
		(fp_line
			(start -0.67945 0.3048)
			(end -0.67945 -0.305054)
			(stroke
				(width 0.1)
				(type default)
			)
			(layer "F.Fab")
		)
		(fp_line
			(start -0.67945 -0.305054)
			(end -0.12065 -0.305054)
			(stroke
				(width 0.1)
				(type default)
			)
			(layer "F.Fab")
		)
		(pad "1" smd circle
			(at -0.40005 0 180)
			(size 0 0)
			(layers "F.Cu" "F.Mask" "F.Paste")
			(net "P3V3_AUX")
		)
		(pad "2" smd circle
			(at 0.40005 0 180)
			(size 0 0)
			(layers "F.Cu" "F.Mask" "F.Paste")
			(net "GND")
		)
	)
	(footprint ""
		(layer "F.Cu")
		(at 208.466436 -210.829652 180)
		(property "Reference" "R6296"
			(at 0 0 180)
			(layer "F.SilkS")
			(hide yes)
			(effects
				(font
					(size 1.27 1.27)
				)
			)
		)
		(property "Value" ""
			(at 0 0 180)
			(layer "F.Fab")
			(effects
				(font
					(size 1.27 1.27)
				)
			)
		)
		(duplicate_pad_numbers_are_jumpers no)
		(fp_line
			(start 0.7874 0.4064)
			(end -0.7874 0.4064)
			(stroke
				(width 0.1524)
				(type default)
			)
			(layer "F.SilkS")
		)
		(fp_line
			(start 0.7874 -0.4064)
			(end 0.7874 0.4064)
			(stroke
				(width 0.1524)
				(type default)
			)
			(layer "F.SilkS")
		)
		(fp_line
			(start -0.7874 0.4064)
			(end -0.7874 -0.4064)
			(stroke
				(width 0.1524)
				(type default)
			)
			(layer "F.SilkS")
		)
		(fp_line
			(start -0.7874 -0.4064)
			(end 0.7874 -0.4064)
			(stroke
				(width 0.1524)
				(type default)
			)
			(layer "F.SilkS")
		)
		(fp_line
			(start 0.67945 0.3048)
			(end 0.120396 0.3048)
			(stroke
				(width 0.1)
				(type default)
			)
			(layer "F.Fab")
		)
		(fp_line
			(start 0.67945 -0.3048)
			(end 0.67945 0.3048)
			(stroke
				(width 0.1)
				(type default)
			)
			(layer "F.Fab")
		)
		(fp_line
			(start 0.12065 -0.2794)
			(end 0.12065 -0.3048)
			(stroke
				(width 0.1)
				(type default)
			)
			(layer "F.Fab")
		)
		(fp_line
			(start 0.12065 -0.3048)
			(end 0.67945 -0.3048)
			(stroke
				(width 0.1)
				(type default)
			)
			(layer "F.Fab")
		)
		(fp_line
			(start 0.120396 0.3048)
			(end 0.120396 0.2794)
			(stroke
				(width 0.1)
				(type default)
			)
			(layer "F.Fab")
		)
		(fp_line
			(start 0.120396 0.2794)
			(end -0.12065 0.2794)
			(stroke
				(width 0.1)
				(type default)
			)
			(layer "F.Fab")
		)
		(fp_line
			(start -0.12065 0.3048)
			(end -0.67945 0.3048)
			(stroke
				(width 0.1)
				(type default)
			)
			(layer "F.Fab")
		)
		(fp_line
			(start -0.12065 0.2794)
			(end -0.12065 0.3048)
			(stroke
				(width 0.1)
				(type default)
			)
			(layer "F.Fab")
		)
		(fp_line
			(start -0.12065 -0.2794)
			(end 0.12065 -0.2794)
			(stroke
				(width 0.1)
				(type default)
			)
			(layer "F.Fab")
		)
		(fp_line
			(start -0.12065 -0.305054)
			(end -0.12065 -0.2794)
			(stroke
				(width 0.1)
				(type default)
			)
			(layer "F.Fab")
		)
		(fp_line
			(start -0.67945 0.3048)
			(end -0.67945 -0.305054)
			(stroke
				(width 0.1)
				(type default)
			)
			(layer "F.Fab")
		)
		(fp_line
			(start -0.67945 -0.305054)
			(end -0.12065 -0.305054)
			(stroke
				(width 0.1)
				(type default)
			)
			(layer "F.Fab")
		)
		(pad "1" smd circle
			(at -0.40005 0 180)
			(size 0 0)
			(layers "F.Cu" "F.Mask" "F.Paste")
			(net "GND")
		)
		(pad "2" smd circle
			(at 0.40005 0 180)
			(size 0 0)
			(layers "F.Cu" "F.Mask" "F.Paste")
			(net "UART_BIC_DEBUG_R_RX")
		)
	)
	(footprint ""
		(layer "F.Cu")
		(at 315.493908 -35.264852)
		(property "Reference" "R5692"
			(at 0 0 0)
			(layer "F.SilkS")
			(hide yes)
			(effects
				(font
					(size 1.27 1.27)
				)
			)
		)
		(property "Value" ""
			(at 0 0 0)
			(layer "F.Fab")
			(effects
				(font
					(size 1.27 1.27)
				)
			)
		)
		(duplicate_pad_numbers_are_jumpers no)
		(fp_line
			(start -0.7874 -0.4064)
			(end 0.7874 -0.4064)
			(stroke
				(width 0.1524)
				(type default)
			)
			(layer "F.SilkS")
		)
		(fp_line
			(start -0.7874 0.4064)
			(end -0.7874 -0.4064)
			(stroke
				(width 0.1524)
				(type default)
			)
			(layer "F.SilkS")
		)
		(fp_line
			(start 0.7874 -0.4064)
			(end 0.7874 0.4064)
			(stroke
				(width 0.1524)
				(type default)
			)
			(layer "F.SilkS")
		)
		(fp_line
			(start 0.7874 0.4064)
			(end -0.7874 0.4064)
			(stroke
				(width 0.1524)
				(type default)
			)
			(layer "F.SilkS")
		)
		(fp_line
			(start -0.67945 -0.305054)
			(end -0.12065 -0.305054)
			(stroke
				(width 0.1)
				(type default)
			)
			(layer "F.Fab")
		)
		(fp_line
			(start -0.67945 0.3048)
			(end -0.67945 -0.305054)
			(stroke
				(width 0.1)
				(type default)
			)
			(layer "F.Fab")
		)
		(fp_line
			(start -0.12065 -0.305054)
			(end -0.12065 -0.2794)
			(stroke
				(width 0.1)
				(type default)
			)
			(layer "F.Fab")
		)
		(fp_line
			(start -0.12065 -0.2794)
			(end 0.12065 -0.2794)
			(stroke
				(width 0.1)
				(type default)
			)
			(layer "F.Fab")
		)
		(fp_line
			(start -0.12065 0.2794)
			(end -0.12065 0.3048)
			(stroke
				(width 0.1)
				(type default)
			)
			(layer "F.Fab")
		)
		(fp_line
			(start -0.12065 0.3048)
			(end -0.67945 0.3048)
			(stroke
				(width 0.1)
				(type default)
			)
			(layer "F.Fab")
		)
		(fp_line
			(start 0.120396 0.2794)
			(end -0.12065 0.2794)
			(stroke
				(width 0.1)
				(type default)
			)
			(layer "F.Fab")
		)
		(fp_line
			(start 0.120396 0.3048)
			(end 0.120396 0.2794)
			(stroke
				(width 0.1)
				(type default)
			)
			(layer "F.Fab")
		)
		(fp_line
			(start 0.12065 -0.3048)
			(end 0.67945 -0.3048)
			(stroke
				(width 0.1)
				(type default)
			)
			(layer "F.Fab")
		)
		(fp_line
			(start 0.12065 -0.2794)
			(end 0.12065 -0.3048)
			(stroke
				(width 0.1)
				(type default)
			)
			(layer "F.Fab")
		)
		(fp_line
			(start 0.67945 -0.3048)
			(end 0.67945 0.3048)
			(stroke
				(width 0.1)
				(type default)
			)
			(layer "F.Fab")
		)
		(fp_line
			(start 0.67945 0.3048)
			(end 0.120396 0.3048)
			(stroke
				(width 0.1)
				(type default)
			)
			(layer "F.Fab")
		)
		(pad "1" smd circle
			(at -0.40005 0)
			(size 0 0)
			(layers "F.Cu" "F.Mask" "F.Paste")
			(net "RST_SMB_SSD11_ISO_N")
		)
		(pad "2" smd circle
			(at 0.40005 0)
			(size 0 0)
			(layers "F.Cu" "F.Mask" "F.Paste")
			(net "GND")
		)
	)
	(footprint ""
		(layer "F.Cu")
		(at 312.739532 -158.219648)
		(property "Reference" "R263"
			(at 0 0 0)
			(layer "F.SilkS")
			(hide yes)
			(effects
				(font
					(size 1.27 1.27)
				)
			)
		)
		(property "Value" ""
			(at 0 0 0)
			(layer "F.Fab")
			(effects
				(font
					(size 1.27 1.27)
				)
			)
		)
		(duplicate_pad_numbers_are_jumpers no)
		(fp_line
			(start -0.7874 -0.4064)
			(end 0.7874 -0.4064)
			(stroke
				(width 0.1524)
				(type default)
			)
			(layer "F.SilkS")
		)
		(fp_line
			(start -0.7874 0.4064)
			(end -0.7874 -0.4064)
			(stroke
				(width 0.1524)
				(type default)
			)
			(layer "F.SilkS")
		)
		(fp_line
			(start 0.7874 -0.4064)
			(end 0.7874 0.4064)
			(stroke
				(width 0.1524)
				(type default)
			)
			(layer "F.SilkS")
		)
		(fp_line
			(start 0.7874 0.4064)
			(end -0.7874 0.4064)
			(stroke
				(width 0.1524)
				(type default)
			)
			(layer "F.SilkS")
		)
		(fp_line
			(start -0.67945 -0.305054)
			(end -0.12065 -0.305054)
			(stroke
				(width 0.1)
				(type default)
			)
			(layer "F.Fab")
		)
		(fp_line
			(start -0.67945 0.3048)
			(end -0.67945 -0.305054)
			(stroke
				(width 0.1)
				(type default)
			)
			(layer "F.Fab")
		)
		(fp_line
			(start -0.12065 -0.305054)
			(end -0.12065 -0.2794)
			(stroke
				(width 0.1)
				(type default)
			)
			(layer "F.Fab")
		)
		(fp_line
			(start -0.12065 -0.2794)
			(end 0.12065 -0.2794)
			(stroke
				(width 0.1)
				(type default)
			)
			(layer "F.Fab")
		)
		(fp_line
			(start -0.12065 0.2794)
			(end -0.12065 0.3048)
			(stroke
				(width 0.1)
				(type default)
			)
			(layer "F.Fab")
		)
		(fp_line
			(start -0.12065 0.3048)
			(end -0.67945 0.3048)
			(stroke
				(width 0.1)
				(type default)
			)
			(layer "F.Fab")
		)
		(fp_line
			(start 0.120396 0.2794)
			(end -0.12065 0.2794)
			(stroke
				(width 0.1)
				(type default)
			)
			(layer "F.Fab")
		)
		(fp_line
			(start 0.120396 0.3048)
			(end 0.120396 0.2794)
			(stroke
				(width 0.1)
				(type default)
			)
			(layer "F.Fab")
		)
		(fp_line
			(start 0.12065 -0.3048)
			(end 0.67945 -0.3048)
			(stroke
				(width 0.1)
				(type default)
			)
			(layer "F.Fab")
		)
		(fp_line
			(start 0.12065 -0.2794)
			(end 0.12065 -0.3048)
			(stroke
				(width 0.1)
				(type default)
			)
			(layer "F.Fab")
		)
		(fp_line
			(start 0.67945 -0.3048)
			(end 0.67945 0.3048)
			(stroke
				(width 0.1)
				(type default)
			)
			(layer "F.Fab")
		)
		(fp_line
			(start 0.67945 0.3048)
			(end 0.120396 0.3048)
			(stroke
				(width 0.1)
				(type default)
			)
			(layer "F.Fab")
		)
		(pad "1" smd circle
			(at -0.40005 0)
			(size 0 0)
			(layers "F.Cu" "F.Mask" "F.Paste")
			(net "PRSNTB3_NIC5_N")
		)
		(pad "2" smd circle
			(at 0.40005 0)
			(size 0 0)
			(layers "F.Cu" "F.Mask" "F.Paste")
			(net "P3V3_AUX")
		)
	)
	(footprint ""
		(layer "F.Cu")
		(at 194.343782 -44.87291)
		(property "Reference" "R572"
			(at 0 0 0)
			(layer "F.SilkS")
			(hide yes)
			(effects
				(font
					(size 1.27 1.27)
				)
			)
		)
		(property "Value" ""
			(at 0 0 0)
			(layer "F.Fab")
			(effects
				(font
					(size 1.27 1.27)
				)
			)
		)
		(duplicate_pad_numbers_are_jumpers no)
		(fp_line
			(start -0.7874 -0.4064)
			(end 0.7874 -0.4064)
			(stroke
				(width 0.1524)
				(type default)
			)
			(layer "F.SilkS")
		)
		(fp_line
			(start -0.7874 0.4064)
			(end -0.7874 -0.4064)
			(stroke
				(width 0.1524)
				(type default)
			)
			(layer "F.SilkS")
		)
		(fp_line
			(start 0.7874 -0.4064)
			(end 0.7874 0.4064)
			(stroke
				(width 0.1524)
				(type default)
			)
			(layer "F.SilkS")
		)
		(fp_line
			(start 0.7874 0.4064)
			(end -0.7874 0.4064)
			(stroke
				(width 0.1524)
				(type default)
			)
			(layer "F.SilkS")
		)
		(fp_line
			(start -0.67945 -0.305054)
			(end -0.12065 -0.305054)
			(stroke
				(width 0.1)
				(type default)
			)
			(layer "F.Fab")
		)
		(fp_line
			(start -0.67945 0.3048)
			(end -0.67945 -0.305054)
			(stroke
				(width 0.1)
				(type default)
			)
			(layer "F.Fab")
		)
		(fp_line
			(start -0.12065 -0.305054)
			(end -0.12065 -0.2794)
			(stroke
				(width 0.1)
				(type default)
			)
			(layer "F.Fab")
		)
		(fp_line
			(start -0.12065 -0.2794)
			(end 0.12065 -0.2794)
			(stroke
				(width 0.1)
				(type default)
			)
			(layer "F.Fab")
		)
		(fp_line
			(start -0.12065 0.2794)
			(end -0.12065 0.3048)
			(stroke
				(width 0.1)
				(type default)
			)
			(layer "F.Fab")
		)
		(fp_line
			(start -0.12065 0.3048)
			(end -0.67945 0.3048)
			(stroke
				(width 0.1)
				(type default)
			)
			(layer "F.Fab")
		)
		(fp_line
			(start 0.120396 0.2794)
			(end -0.12065 0.2794)
			(stroke
				(width 0.1)
				(type default)
			)
			(layer "F.Fab")
		)
		(fp_line
			(start 0.120396 0.3048)
			(end 0.120396 0.2794)
			(stroke
				(width 0.1)
				(type default)
			)
			(layer "F.Fab")
		)
		(fp_line
			(start 0.12065 -0.3048)
			(end 0.67945 -0.3048)
			(stroke
				(width 0.1)
				(type default)
			)
			(layer "F.Fab")
		)
		(fp_line
			(start 0.12065 -0.2794)
			(end 0.12065 -0.3048)
			(stroke
				(width 0.1)
				(type default)
			)
			(layer "F.Fab")
		)
		(fp_line
			(start 0.67945 -0.3048)
			(end 0.67945 0.3048)
			(stroke
				(width 0.1)
				(type default)
			)
			(layer "F.Fab")
		)
		(fp_line
			(start 0.67945 0.3048)
			(end 0.120396 0.3048)
			(stroke
				(width 0.1)
				(type default)
			)
			(layer "F.Fab")
		)
		(pad "1" smd circle
			(at -0.40005 0)
			(size 0 0)
			(layers "F.Cu" "F.Mask" "F.Paste")
			(net "SSD6_ADC_A0")
		)
		(pad "2" smd circle
			(at 0.40005 0)
			(size 0 0)
			(layers "F.Cu" "F.Mask" "F.Paste")
			(net "P3V3_AUX")
		)
	)
	(footprint ""
		(layer "F.Cu")
		(at 320.17589 -306.075842 90)
		(property "Reference" "R3974"
			(at 0 0 90)
			(layer "F.SilkS")
			(hide yes)
			(effects
				(font
					(size 1.27 1.27)
				)
			)
		)
		(property "Value" ""
			(at 0 0 90)
			(layer "F.Fab")
			(effects
				(font
					(size 1.27 1.27)
				)
			)
		)
		(duplicate_pad_numbers_are_jumpers no)
		(fp_line
			(start 0.7874 -0.4064)
			(end 0.7874 0.4064)
			(stroke
				(width 0.1524)
				(type default)
			)
			(layer "F.SilkS")
		)
		(fp_line
			(start -0.7874 -0.4064)
			(end 0.7874 -0.4064)
			(stroke
				(width 0.1524)
				(type default)
			)
			(layer "F.SilkS")
		)
		(fp_line
			(start 0.7874 0.4064)
			(end -0.7874 0.4064)
			(stroke
				(width 0.1524)
				(type default)
			)
			(layer "F.SilkS")
		)
		(fp_line
			(start -0.7874 0.4064)
			(end -0.7874 -0.4064)
			(stroke
				(width 0.1524)
				(type default)
			)
			(layer "F.SilkS")
		)
		(fp_line
			(start -0.12065 -0.305054)
			(end -0.12065 -0.2794)
			(stroke
				(width 0.1)
				(type default)
			)
			(layer "F.Fab")
		)
		(fp_line
			(start -0.67945 -0.305054)
			(end -0.12065 -0.305054)
			(stroke
				(width 0.1)
				(type default)
			)
			(layer "F.Fab")
		)
		(fp_line
			(start 0.67945 -0.3048)
			(end 0.67945 0.3048)
			(stroke
				(width 0.1)
				(type default)
			)
			(layer "F.Fab")
		)
		(fp_line
			(start 0.12065 -0.3048)
			(end 0.67945 -0.3048)
			(stroke
				(width 0.1)
				(type default)
			)
			(layer "F.Fab")
		)
		(fp_line
			(start 0.12065 -0.2794)
			(end 0.12065 -0.3048)
			(stroke
				(width 0.1)
				(type default)
			)
			(layer "F.Fab")
		)
		(fp_line
			(start -0.12065 -0.2794)
			(end 0.12065 -0.2794)
			(stroke
				(width 0.1)
				(type default)
			)
			(layer "F.Fab")
		)
		(fp_line
			(start 0.120396 0.2794)
			(end -0.12065 0.2794)
			(stroke
				(width 0.1)
				(type default)
			)
			(layer "F.Fab")
		)
		(fp_line
			(start -0.12065 0.2794)
			(end -0.12065 0.3048)
			(stroke
				(width 0.1)
				(type default)
			)
			(layer "F.Fab")
		)
		(fp_line
			(start 0.67945 0.3048)
			(end 0.120396 0.3048)
			(stroke
				(width 0.1)
				(type default)
			)
			(layer "F.Fab")
		)
		(fp_line
			(start 0.120396 0.3048)
			(end 0.120396 0.2794)
			(stroke
				(width 0.1)
				(type default)
			)
			(layer "F.Fab")
		)
		(fp_line
			(start -0.12065 0.3048)
			(end -0.67945 0.3048)
			(stroke
				(width 0.1)
				(type default)
			)
			(layer "F.Fab")
		)
		(fp_line
			(start -0.67945 0.3048)
			(end -0.67945 -0.305054)
			(stroke
				(width 0.1)
				(type default)
			)
			(layer "F.Fab")
		)
		(pad "1" smd circle
			(at -0.40005 0 90)
			(size 0 0)
			(layers "F.Cu" "F.Mask" "F.Paste")
			(net "SMB_PEX2_SLAVE_SDA")
		)
		(pad "2" smd circle
			(at 0.40005 0 90)
			(size 0 0)
			(layers "F.Cu" "F.Mask" "F.Paste")
			(net "SMB_PEX2_R_SDA")
		)
	)
	(footprint ""
		(layer "F.Cu")
		(at 9.62914 -313.51347 180)
		(property "Reference" "PC205"
			(at 0 0 180)
			(layer "F.SilkS")
			(hide yes)
			(effects
				(font
					(size 1.27 1.27)
				)
			)
		)
		(property "Value" ""
			(at 0 0 180)
			(layer "F.Fab")
			(effects
				(font
					(size 1.27 1.27)
				)
			)
		)
		(duplicate_pad_numbers_are_jumpers no)
		(fp_line
			(start 1.524 0.762)
			(end -1.524 0.762)
			(stroke
				(width 0.1524)
				(type default)
			)
			(layer "F.SilkS")
		)
		(fp_line
			(start 1.524 -0.762)
			(end 1.524 0.762)
			(stroke
				(width 0.1524)
				(type default)
			)
			(layer "F.SilkS")
		)
		(fp_line
			(start -1.524 0.762)
			(end -1.524 -0.762)
			(stroke
				(width 0.1524)
				(type default)
			)
			(layer "F.SilkS")
		)
		(fp_line
			(start -1.524 -0.762)
			(end 1.524 -0.762)
			(stroke
				(width 0.1524)
				(type default)
			)
			(layer "F.SilkS")
		)
		(fp_line
			(start 1.1049 0.724916)
			(end 1.1049 -0.724916)
			(stroke
				(width 0.1)
				(type default)
			)
			(layer "F.Fab")
		)
		(fp_line
			(start 1.1049 -0.724916)
			(end -1.1049 -0.724916)
			(stroke
				(width 0.1)
				(type default)
			)
			(layer "F.Fab")
		)
		(fp_line
			(start -1.1049 0.724916)
			(end 1.1049 0.724916)
			(stroke
				(width 0.1)
				(type default)
			)
			(layer "F.Fab")
		)
		(fp_line
			(start -1.1049 -0.724916)
			(end -1.1049 0.724916)
			(stroke
				(width 0.1)
				(type default)
			)
			(layer "F.Fab")
		)
		(pad "1" smd rect
			(at -0.889 0)
			(size 1.016 1.27)
			(layers "F.Cu" "F.Mask" "F.Paste")
			(net "SW_P12V_P1V25_PEX0_FLT")
		)
		(pad "2" smd rect
			(at 0.889 0)
			(size 1.016 1.27)
			(layers "F.Cu" "F.Mask" "F.Paste")
			(net "GND")
		)
	)
	(footprint ""
		(layer "F.Cu")
		(at 464.09991 -313.85002)
		(property "Reference" "H137"
			(at -2.322068 -4.41071 0)
			(unlocked yes)
			(layer "F.SilkS")
			(effects
				(font
					(size 0.7874 0.5842)
					(thickness 0.1524)
				)
				(justify left)
			)
		)
		(property "Value" ""
			(at 0 0 0)
			(layer "F.Fab")
			(effects
				(font
					(size 1.27 1.27)
				)
			)
		)
		(duplicate_pad_numbers_are_jumpers no)
		(pad "1" thru_hole circle
			(at 0 0)
			(size 6.5024 6.5024)
			(drill 3.2004)
			(layers "*.Cu" "*.Mask")
			(remove_unused_layers no)
			(net "GND")
			(clearance -1.397)
		)
	)
	(footprint ""
		(layer "F.Cu")
		(at 89.851992 -289.230816 90)
		(property "Reference" "R3880"
			(at 0 0 90)
			(layer "F.SilkS")
			(hide yes)
			(effects
				(font
					(size 1.27 1.27)
				)
			)
		)
		(property "Value" ""
			(at 0 0 90)
			(layer "F.Fab")
			(effects
				(font
					(size 1.27 1.27)
				)
			)
		)
		(duplicate_pad_numbers_are_jumpers no)
		(fp_line
			(start 0.7874 -0.4064)
			(end 0.7874 0.4064)
			(stroke
				(width 0.1524)
				(type default)
			)
			(layer "F.SilkS")
		)
		(fp_line
			(start -0.7874 -0.4064)
			(end 0.7874 -0.4064)
			(stroke
				(width 0.1524)
				(type default)
			)
			(layer "F.SilkS")
		)
		(fp_line
			(start 0.7874 0.4064)
			(end -0.7874 0.4064)
			(stroke
				(width 0.1524)
				(type default)
			)
			(layer "F.SilkS")
		)
		(fp_line
			(start -0.7874 0.4064)
			(end -0.7874 -0.4064)
			(stroke
				(width 0.1524)
				(type default)
			)
			(layer "F.SilkS")
		)
		(fp_line
			(start -0.12065 -0.305054)
			(end -0.12065 -0.2794)
			(stroke
				(width 0.1)
				(type default)
			)
			(layer "F.Fab")
		)
		(fp_line
			(start -0.67945 -0.305054)
			(end -0.12065 -0.305054)
			(stroke
				(width 0.1)
				(type default)
			)
			(layer "F.Fab")
		)
		(fp_line
			(start 0.67945 -0.3048)
			(end 0.67945 0.3048)
			(stroke
				(width 0.1)
				(type default)
			)
			(layer "F.Fab")
		)
		(fp_line
			(start 0.12065 -0.3048)
			(end 0.67945 -0.3048)
			(stroke
				(width 0.1)
				(type default)
			)
			(layer "F.Fab")
		)
		(fp_line
			(start 0.12065 -0.2794)
			(end 0.12065 -0.3048)
			(stroke
				(width 0.1)
				(type default)
			)
			(layer "F.Fab")
		)
		(fp_line
			(start -0.12065 -0.2794)
			(end 0.12065 -0.2794)
			(stroke
				(width 0.1)
				(type default)
			)
			(layer "F.Fab")
		)
		(fp_line
			(start 0.120396 0.2794)
			(end -0.12065 0.2794)
			(stroke
				(width 0.1)
				(type default)
			)
			(layer "F.Fab")
		)
		(fp_line
			(start -0.12065 0.2794)
			(end -0.12065 0.3048)
			(stroke
				(width 0.1)
				(type default)
			)
			(layer "F.Fab")
		)
		(fp_line
			(start 0.67945 0.3048)
			(end 0.120396 0.3048)
			(stroke
				(width 0.1)
				(type default)
			)
			(layer "F.Fab")
		)
		(fp_line
			(start 0.120396 0.3048)
			(end 0.120396 0.2794)
			(stroke
				(width 0.1)
				(type default)
			)
			(layer "F.Fab")
		)
		(fp_line
			(start -0.12065 0.3048)
			(end -0.67945 0.3048)
			(stroke
				(width 0.1)
				(type default)
			)
			(layer "F.Fab")
		)
		(fp_line
			(start -0.67945 0.3048)
			(end -0.67945 -0.305054)
			(stroke
				(width 0.1)
				(type default)
			)
			(layer "F.Fab")
		)
		(pad "1" smd circle
			(at -0.40005 0 90)
			(size 0 0)
			(layers "F.Cu" "F.Mask" "F.Paste")
			(net "SMB_PEX0_PCA9555_SDA")
		)
		(pad "2" smd circle
			(at 0.40005 0 90)
			(size 0 0)
			(layers "F.Cu" "F.Mask" "F.Paste")
			(net "SMB_PEX0_HOST_LS_SDA")
		)
	)
	(footprint ""
		(layer "F.Cu")
		(at 342.493854 -219.587064)
		(property "Reference" "U6"
			(at -10.3632 -10.963148 0)
			(unlocked yes)
			(layer "F.SilkS")
			(effects
				(font
					(size 0.7874 0.5842)
					(thickness 0.1524)
				)
				(justify left)
			)
		)
		(property "Value" ""
			(at 0 0 0)
			(layer "F.Fab")
			(effects
				(font
					(size 1.27 1.27)
				)
			)
		)
		(duplicate_pad_numbers_are_jumpers no)
		(fp_line
			(start -9.500108 -9.500108)
			(end -9.500108 9.500108)
			(stroke
				(width 0.1524)
				(type default)
			)
			(layer "F.SilkS")
		)
		(fp_line
			(start -9.500108 9.500108)
			(end 9.500108 9.500108)
			(stroke
				(width 0.1524)
				(type default)
			)
			(layer "F.SilkS")
		)
		(fp_line
			(start 9.500108 -9.500108)
			(end -9.500108 -9.500108)
			(stroke
				(width 0.1524)
				(type default)
			)
			(layer "F.SilkS")
		)
		(fp_line
			(start 9.500108 9.500108)
			(end 9.500108 -9.500108)
			(stroke
				(width 0.1524)
				(type default)
			)
			(layer "F.SilkS")
		)
		(fp_poly
			(pts
				(xy -9.500108 -9.500108) (xy -7.599934 -9.500108) (xy -7.599934 -10.262108) (xy -10.262108 -10.262108)
				(xy -10.262108 -7.599934) (xy -9.500108 -7.599934)
			)
			(stroke
				(width 0)
				(type default)
			)
			(fill yes)
			(layer "F.SilkS")
		)
		(fp_line
			(start -9.500108 -9.500108)
			(end -9.500108 9.500108)
			(stroke
				(width 0.1)
				(type default)
			)
			(layer "F.Fab")
		)
		(fp_line
			(start -9.500108 9.500108)
			(end 9.500108 9.500108)
			(stroke
				(width 0.1)
				(type default)
			)
			(layer "F.Fab")
		)
		(fp_line
			(start 9.500108 -9.500108)
			(end -9.500108 -9.500108)
			(stroke
				(width 0.1)
				(type default)
			)
			(layer "F.Fab")
		)
		(fp_line
			(start 9.500108 9.500108)
			(end 9.500108 -9.500108)
			(stroke
				(width 0.1)
				(type default)
			)
			(layer "F.Fab")
		)
		(fp_poly
			(pts
				(xy -9.500108 -9.500108) (xy -7.599934 -9.500108) (xy -7.599934 -10.262108) (xy -10.262108 -10.262108)
				(xy -10.262108 -7.599934) (xy -9.500108 -7.599934)
			)
			(stroke
				(width 0)
				(type default)
			)
			(fill yes)
			(layer "F.Fab")
		)
		(pad "A1" smd circle
			(at -8.400034 -8.400034)
			(size 0.4064 0.4064)
			(layers "F.Cu" "F.Mask" "F.Paste")
			(net "GND")
		)
		(pad "A2" smd circle
			(at -7.599934 -8.400034)
			(size 0.4064 0.4064)
			(layers "F.Cu" "F.Mask" "F.Paste")
			(net "RST_MB_PERST_1_ISO_R_N")
		)
		(pad "A3" smd circle
			(at -6.800088 -8.400034)
			(size 0.4064 0.4064)
			(layers "F.Cu" "F.Mask" "F.Paste")
			(net "RST_GPU_PERST_0_N")
		)
		(pad "A4" smd circle
			(at -5.999988 -8.400034)
			(size 0.4064 0.4064)
			(layers "F.Cu" "F.Mask" "F.Paste")
			(net "PRSNT_SSD2_R_N")
		)
		(pad "A5" smd circle
			(at -5.199888 -8.400034)
			(size 0.4064 0.4064)
			(layers "F.Cu" "F.Mask" "F.Paste")
			(net "SSD2_PWRDIS")
		)
		(pad "A6" smd circle
			(at -4.400042 -8.400034)
			(size 0.4064 0.4064)
			(layers "F.Cu" "F.Mask" "F.Paste")
			(net "JP_FPGA_DEBUG_N")
		)
		(pad "A7" smd circle
			(at -3.599942 -8.400034)
			(size 0.4064 0.4064)
			(layers "F.Cu" "F.Mask" "F.Paste")
			(net "FM_SOL_UART_CH_SEL_R")
		)
		(pad "A8" smd circle
			(at -2.800096 -8.400034)
			(size 0.4064 0.4064)
			(layers "F.Cu" "F.Mask" "F.Paste")
			(net "SMB_PEX2_FPGA_SDA")
		)
		(pad "A9" smd circle
			(at -1.999996 -8.400034)
			(size 0.4064 0.4064)
			(layers "F.Cu" "F.Mask" "F.Paste")
			(net "PWRGD_P12V_SSD0_R")
		)
		(pad "A10" smd circle
			(at -1.199896 -8.400034)
			(size 0.4064 0.4064)
			(layers "F.Cu" "F.Mask" "F.Paste")
			(net "PRSNT_SSD1_R_N")
		)
		(pad "A11" smd circle
			(at -0.40005 -8.400034)
			(size 0.4064 0.4064)
			(layers "F.Cu" "F.Mask" "F.Paste")
			(net "SSD1_PWRDIS")
		)
		(pad "A12" smd circle
			(at 0.40005 -8.400034)
			(size 0.4064 0.4064)
			(layers "F.Cu" "F.Mask" "F.Paste")
			(net "SMB_BIC_FPGA_R_SDA")
		)
		(pad "A13" smd circle
			(at 1.199896 -8.400034)
			(size 0.4064 0.4064)
			(layers "F.Cu" "F.Mask" "F.Paste")
			(net "PWRGD_P12V_SSD3_R")
		)
		(pad "A14" smd circle
			(at 1.999996 -8.400034)
			(size 0.4064 0.4064)
			(layers "F.Cu" "F.Mask" "F.Paste")
			(net "RST_SSD3_PERST_N")
		)
		(pad "A15" smd circle
			(at 2.800096 -8.400034)
			(size 0.4064 0.4064)
			(layers "F.Cu" "F.Mask" "F.Paste")
			(net "SSD4_PWRDIS")
		)
		(pad "A16" smd circle
			(at 3.599942 -8.400034)
			(size 0.4064 0.4064)
			(layers "F.Cu" "F.Mask" "F.Paste")
			(net "PWRGD_P12V_SSD5_R")
		)
		(pad "A17" smd circle
			(at 4.400042 -8.400034)
			(size 0.4064 0.4064)
			(layers "F.Cu" "F.Mask" "F.Paste")
			(net "RST_SSD5_PERST_N")
		)
		(pad "A18" smd circle
			(at 5.199888 -8.400034)
			(size 0.4064 0.4064)
			(layers "F.Cu" "F.Mask" "F.Paste")
			(net "PWRGD_P3V3_SSD6_R")
		)
		(pad "A19" smd circle
			(at 5.999988 -8.400034)
			(size 0.4064 0.4064)
			(layers "F.Cu" "F.Mask" "F.Paste")
			(net "SSD6_CLK_EN_N")
		)
		(pad "A20" smd circle
			(at 6.800088 -8.400034)
			(size 0.4064 0.4064)
			(layers "F.Cu" "F.Mask" "F.Paste")
			(net "SSD7_PWR_EN")
		)
		(pad "A21" smd circle
			(at 7.599934 -8.400034)
			(size 0.4064 0.4064)
			(layers "F.Cu" "F.Mask" "F.Paste")
			(net "BIC_FORCE_THROTTLE_R_N")
		)
		(pad "A22" smd circle
			(at 8.400034 -8.400034)
			(size 0.4064 0.4064)
			(layers "F.Cu" "F.Mask" "F.Paste")
			(net "GND")
		)
		(pad "AA1" smd circle
			(at -8.400034 7.599934)
			(size 0.4064 0.4064)
			(layers "F.Cu" "F.Mask" "F.Paste")
			(net "SSD12_PEX_PWR_EN_R")
		)
		(pad "AA2" smd circle
			(at -7.599934 7.599934)
			(size 0.4064 0.4064)
			(layers "F.Cu" "F.Mask" "F.Paste")
			(net "PRSNT_SSD8_R_N")
		)
		(pad "AA3" smd circle
			(at -6.800088 7.599934)
			(size 0.4064 0.4064)
			(layers "F.Cu" "F.Mask" "F.Paste")
			(net "SSD8_PWRDIS")
		)
		(pad "AA4" smd circle
			(at -5.999988 7.599934)
			(size 0.4064 0.4064)
			(layers "F.Cu" "F.Mask" "F.Paste")
			(net "PWRGD_P12V_SSD9_R")
		)
		(pad "AA5" smd circle
			(at -5.199888 7.599934)
			(size 0.4064 0.4064)
			(layers "F.Cu" "F.Mask" "F.Paste")
			(net "RST_SSD9_PERST_N")
		)
		(pad "AA6" smd circle
			(at -4.400042 7.599934)
			(size 0.4064 0.4064)
			(layers "F.Cu" "F.Mask" "F.Paste")
			(net "PWRGD_P3V3_SSD10_R")
		)
		(pad "AA7" smd circle
			(at -3.599942 7.599934)
			(size 0.4064 0.4064)
			(layers "F.Cu" "F.Mask" "F.Paste")
			(net "SSD10_CLK_EN_N")
		)
		(pad "AA8" smd circle
			(at -2.800096 7.599934)
			(size 0.4064 0.4064)
			(layers "F.Cu" "F.Mask" "F.Paste")
			(net "PRSNT_SSD12_R_N")
		)
		(pad "AA9" smd circle
			(at -1.999996 7.599934)
			(size 0.4064 0.4064)
			(layers "F.Cu" "F.Mask" "F.Paste")
			(net "SSD12_PWRDIS")
		)
		(pad "AA10" smd circle
			(at -1.199896 7.599934)
			(size 0.4064 0.4064)
			(layers "F.Cu" "F.Mask" "F.Paste")
			(net "RST_SSD13_PERST_N")
		)
		(pad "AA11" smd circle
			(at -0.40005 7.599934)
			(size 0.4064 0.4064)
			(layers "F.Cu" "F.Mask" "F.Paste")
			(net "PWRGD_P3V3_SSD14_R")
		)
		(pad "AA12" smd circle
			(at 0.40005 7.599934)
			(size 0.4064 0.4064)
			(layers "F.Cu" "F.Mask" "F.Paste")
			(net "PWRGD_P12V_SSD15_R")
		)
		(pad "AA13" smd circle
			(at 1.199896 7.599934)
			(size 0.4064 0.4064)
			(layers "F.Cu" "F.Mask" "F.Paste")
			(net "RST_SSD15_PERST_N")
		)
		(pad "AA14" smd circle
			(at 1.999996 7.599934)
			(size 0.4064 0.4064)
			(layers "F.Cu" "F.Mask" "F.Paste")
			(net "SSD1_PEX_PWR_EN_R")
		)
		(pad "AA15" smd circle
			(at 2.800096 7.599934)
			(size 0.4064 0.4064)
			(layers "F.Cu" "F.Mask" "F.Paste")
			(net "PRSNT_SSD2_FPGA_N")
		)
		(pad "AA16" smd circle
			(at 3.599942 7.599934)
			(size 0.4064 0.4064)
			(layers "F.Cu" "F.Mask" "F.Paste")
			(net "FPGA_PEX1_MODE_SEL2")
		)
		(pad "AA17" smd circle
			(at 4.400042 7.599934)
			(size 0.4064 0.4064)
			(layers "F.Cu" "F.Mask" "F.Paste")
			(net "SSD3_PWRDIS_BIC_R")
		)
		(pad "AA18" smd circle
			(at 5.199888 7.599934)
			(size 0.4064 0.4064)
			(layers "F.Cu" "F.Mask" "F.Paste")
			(net "RST_PEX_SSD4_PERST_R_N")
		)
		(pad "AA19" smd circle
			(at 5.999988 7.599934)
			(size 0.4064 0.4064)
			(layers "F.Cu" "F.Mask" "F.Paste")
			(net "SSD5_PEX_PWR_EN_R")
		)
		(pad "AA20" smd circle
			(at 6.800088 7.599934)
			(size 0.4064 0.4064)
			(layers "F.Cu" "F.Mask" "F.Paste")
			(net "PRSNT_SSD6_FPGA_N")
		)
		(pad "AA21" smd circle
			(at 7.599934 7.599934)
			(size 0.4064 0.4064)
			(layers "F.Cu" "F.Mask" "F.Paste")
			(net "FPGA_PEX3_MODE_SEL2")
		)
		(pad "AA22" smd circle
			(at 8.400034 7.599934)
			(size 0.4064 0.4064)
			(layers "F.Cu" "F.Mask" "F.Paste")
			(net "PWRGD_PEX2_P1V8_PLL_R")
		)
		(pad "AB1" smd circle
			(at -8.400034 8.400034)
			(size 0.4064 0.4064)
			(layers "F.Cu" "F.Mask" "F.Paste")
			(net "GND")
		)
		(pad "AB2" smd circle
			(at -7.599934 8.400034)
			(size 0.4064 0.4064)
			(layers "F.Cu" "F.Mask" "F.Paste")
			(net "PWRGD_P12V_SSD8_R")
		)
		(pad "AB3" smd circle
			(at -6.800088 8.400034)
			(size 0.4064 0.4064)
			(layers "F.Cu" "F.Mask" "F.Paste")
			(net "RST_SSD8_PERST_N")
		)
		(pad "AB4" smd circle
			(at -5.999988 8.400034)
			(size 0.4064 0.4064)
			(layers "F.Cu" "F.Mask" "F.Paste")
			(net "PWRGD_P3V3_SSD9_R")
		)
		(pad "AB5" smd circle
			(at -5.199888 8.400034)
			(size 0.4064 0.4064)
			(layers "F.Cu" "F.Mask" "F.Paste")
			(net "SSD9_CLK_EN_N")
		)
		(pad "AB6" smd circle
			(at -4.400042 8.400034)
			(size 0.4064 0.4064)
			(layers "F.Cu" "F.Mask" "F.Paste")
			(net "SSD10_PWR_EN")
		)
		(pad "AB7" smd circle
			(at -3.599942 8.400034)
			(size 0.4064 0.4064)
			(layers "F.Cu" "F.Mask" "F.Paste")
			(net "PRSNT_SSD11_R_N")
		)
		(pad "AB8" smd circle
			(at -2.800096 8.400034)
			(size 0.4064 0.4064)
			(layers "F.Cu" "F.Mask" "F.Paste")
			(net "PWRGD_P12V_SSD12_R")
		)
		(pad "AB9" smd circle
			(at -1.999996 8.400034)
			(size 0.4064 0.4064)
			(layers "F.Cu" "F.Mask" "F.Paste")
			(net "RST_SSD12_PERST_N")
		)
		(pad "AB10" smd circle
			(at -1.199896 8.400034)
			(size 0.4064 0.4064)
			(layers "F.Cu" "F.Mask" "F.Paste")
			(net "SSD13_CLK_EN_N")
		)
		(pad "AB11" smd circle
			(at -0.40005 8.400034)
			(size 0.4064 0.4064)
			(layers "F.Cu" "F.Mask" "F.Paste")
			(net "SSD14_PWR_EN")
		)
		(pad "AB12" smd circle
			(at 0.40005 8.400034)
			(size 0.4064 0.4064)
			(layers "F.Cu" "F.Mask" "F.Paste")
			(net "PRSNT_SSD15_R_N")
		)
		(pad "AB13" smd circle
			(at 1.199896 8.400034)
			(size 0.4064 0.4064)
			(layers "F.Cu" "F.Mask" "F.Paste")
			(net "SSD15_PWRDIS")
		)
		(pad "AB14" smd circle
			(at 1.999996 8.400034)
			(size 0.4064 0.4064)
			(layers "F.Cu" "F.Mask" "F.Paste")
			(net "PRSNT_SSD1_FPGA_N")
		)
		(pad "AB15" smd circle
			(at 2.800096 8.400034)
			(size 0.4064 0.4064)
			(layers "F.Cu" "F.Mask" "F.Paste")
			(net "FPGA_PEX0_MODE_SEL1")
		)
		(pad "AB16" smd circle
			(at 3.599942 8.400034)
			(size 0.4064 0.4064)
			(layers "F.Cu" "F.Mask" "F.Paste")
			(net "SSD2_PWRDIS_BIC_R")
		)
		(pad "AB17" smd circle
			(at 4.400042 8.400034)
			(size 0.4064 0.4064)
			(layers "F.Cu" "F.Mask" "F.Paste")
			(net "RST_PEX_SSD3_PERST_R_N")
		)
		(pad "AB18" smd circle
			(at 5.199888 8.400034)
			(size 0.4064 0.4064)
			(layers "F.Cu" "F.Mask" "F.Paste")
			(net "SSD4_PEX_PWR_EN_R")
		)
		(pad "AB19" smd circle
			(at 5.999988 8.400034)
			(size 0.4064 0.4064)
			(layers "F.Cu" "F.Mask" "F.Paste")
			(net "PRSNT_SSD5_FPGA_N")
		)
		(pad "AB20" smd circle
			(at 6.800088 8.400034)
			(size 0.4064 0.4064)
			(layers "F.Cu" "F.Mask" "F.Paste")
			(net "FPGA_PEX2_MODE_SEL1")
		)
		(pad "AB21" smd circle
			(at 7.599934 8.400034)
			(size 0.4064 0.4064)
			(layers "F.Cu" "F.Mask" "F.Paste")
			(net "PU_FPGA_SN")
		)
		(pad "AB22" smd circle
			(at 8.400034 8.400034)
			(size 0.4064 0.4064)
			(layers "F.Cu" "F.Mask" "F.Paste")
			(net "GND")
		)
		(pad "B1" smd circle
			(at -8.400034 -7.599934)
			(size 0.4064 0.4064)
			(layers "F.Cu" "F.Mask" "F.Paste")
			(net "RST_MB_PERST_0_ISO_R_N")
		)
		(pad "B2" smd circle
			(at -7.599934 -7.599934)
			(size 0.4064 0.4064)
			(layers "F.Cu" "F.Mask" "F.Paste")
			(net "MB_SWB_PWRGD")
		)
		(pad "B3" smd circle
			(at -6.800088 -7.599934)
			(size 0.4064 0.4064)
			(layers "F.Cu" "F.Mask" "F.Paste")
			(net "PRSNT_GPU_ISO_R1_N")
		)
		(pad "B4" smd circle
			(at -5.999988 -7.599934)
			(size 0.4064 0.4064)
			(layers "F.Cu" "F.Mask" "F.Paste")
			(net "SSD2_PWR_EN")
		)
		(pad "B5" smd circle
			(at -5.199888 -7.599934)
			(size 0.4064 0.4064)
			(layers "F.Cu" "F.Mask" "F.Paste")
			(net "SYS_PWR_READY_N")
		)
		(pad "B6" smd circle
			(at -4.400042 -7.599934)
			(size 0.4064 0.4064)
			(layers "F.Cu" "F.Mask" "F.Paste")
			(net "FPGA_HEARTBEAT_N")
		)
		(pad "B7" smd circle
			(at -3.599942 -7.599934)
			(size 0.4064 0.4064)
			(layers "F.Cu" "F.Mask" "F.Paste")
			(net "GND")
		)
		(pad "B8" smd circle
			(at -2.800096 -7.599934)
			(size 0.4064 0.4064)
			(layers "F.Cu" "F.Mask" "F.Paste")
			(net "SMB_PEX2_FPGA_SCL")
		)
		(pad "B9" smd circle
			(at -1.999996 -7.599934)
			(size 0.4064 0.4064)
			(layers "F.Cu" "F.Mask" "F.Paste")
			(net "PRSNT_SSD0_R_N")
		)
		(pad "B10" smd circle
			(at -1.199896 -7.599934)
			(size 0.4064 0.4064)
			(layers "F.Cu" "F.Mask" "F.Paste")
			(net "SSD0_CLK_EN_N")
		)
		(pad "B11" smd circle
			(at -0.40005 -7.599934)
			(size 0.4064 0.4064)
			(layers "F.Cu" "F.Mask" "F.Paste")
			(net "SSD1_PWR_EN")
		)
		(pad "B12" smd circle
			(at 0.40005 -7.599934)
			(size 0.4064 0.4064)
			(layers "F.Cu" "F.Mask" "F.Paste")
			(net "SMB_BIC_FPGA_R_SCL")
		)
		(pad "B13" smd circle
			(at 1.199896 -7.599934)
			(size 0.4064 0.4064)
			(layers "F.Cu" "F.Mask" "F.Paste")
			(net "PWRGD_P3V3_SSD3_R")
		)
		(pad "B14" smd circle
			(at 1.999996 -7.599934)
			(size 0.4064 0.4064)
			(layers "F.Cu" "F.Mask" "F.Paste")
			(net "SSD3_CLK_EN_N")
		)
		(pad "B15" smd circle
			(at 2.800096 -7.599934)
			(size 0.4064 0.4064)
			(layers "F.Cu" "F.Mask" "F.Paste")
			(net "RST_SSD4_PERST_N")
		)
		(pad "B16" smd circle
			(at 3.599942 -7.599934)
			(size 0.4064 0.4064)
			(layers "F.Cu" "F.Mask" "F.Paste")
			(net "GND")
		)
		(pad "B17" smd circle
			(at 4.400042 -7.599934)
			(size 0.4064 0.4064)
			(layers "F.Cu" "F.Mask" "F.Paste")
			(net "PWRGD_P3V3_SSD5_R")
		)
		(pad "B18" smd circle
			(at 5.199888 -7.599934)
			(size 0.4064 0.4064)
			(layers "F.Cu" "F.Mask" "F.Paste")
			(net "SSD5_CLK_EN_N")
		)
		(pad "B19" smd circle
			(at 5.999988 -7.599934)
			(size 0.4064 0.4064)
			(layers "F.Cu" "F.Mask" "F.Paste")
			(net "SSD6_PWR_EN")
		)
		(pad "B20" smd circle
			(at 6.800088 -7.599934)
			(size 0.4064 0.4064)
			(layers "F.Cu" "F.Mask" "F.Paste")
			(net "PRSNT_SSD7_R_N")
		)
		(pad "B21" smd circle
			(at 7.599934 -7.599934)
			(size 0.4064 0.4064)
			(layers "F.Cu" "F.Mask" "F.Paste")
			(net "SSD7_PWRDIS")
		)
		(pad "B22" smd circle
			(at 8.400034 -7.599934)
			(size 0.4064 0.4064)
			(layers "F.Cu" "F.Mask" "F.Paste")
			(net "Net_8564")
		)
		(pad "C1" smd circle
			(at -8.400034 -6.800088)
			(size 0.4064 0.4064)
			(layers "F.Cu" "F.Mask" "F.Paste")
			(net "PWRGD_P0V8_PEX3_R")
		)
		(pad "C2" smd circle
			(at -7.599934 -6.800088)
			(size 0.4064 0.4064)
			(layers "F.Cu" "F.Mask" "F.Paste")
			(net "GND")
		)
		(pad "C3" smd circle
			(at -6.800088 -6.800088)
			(size 0.4064 0.4064)
			(layers "F.Cu" "F.Mask" "F.Paste")
			(net "RST_GPU_PERST_1_N")
		)
		(pad "C4" smd circle
			(at -5.999988 -6.800088)
			(size 0.4064 0.4064)
			(layers "F.Cu" "F.Mask" "F.Paste")
			(net "RST_GPU_PERST_2_N")
		)
		(pad "C5" smd circle
			(at -5.199888 -6.800088)
			(size 0.4064 0.4064)
			(layers "F.Cu" "F.Mask" "F.Paste")
			(net "SSD2_CLK_EN_N")
		)
		(pad "C6" smd circle
			(at -4.400042 -6.800088)
			(size 0.4064 0.4064)
			(layers "F.Cu" "F.Mask" "F.Paste")
			(net "SMB_PEX0_FPGA_SCL")
		)
		(pad "C7" smd circle
			(at -3.599942 -6.800088)
			(size 0.4064 0.4064)
			(layers "F.Cu" "F.Mask" "F.Paste")
			(net "P3V3_FPGA_VCCIO0")
		)
		(pad "C8" smd circle
			(at -2.800096 -6.800088)
			(size 0.4064 0.4064)
			(layers "F.Cu" "F.Mask" "F.Paste")
			(net "SMB_PEX1_FPGA_SCL")
		)
		(pad "C9" smd circle
			(at -1.999996 -6.800088)
			(size 0.4064 0.4064)
			(layers "F.Cu" "F.Mask" "F.Paste")
			(net "SMB_PEX3_FPGA_SCL")
		)
		(pad "C10" smd circle
			(at -1.199896 -6.800088)
			(size 0.4064 0.4064)
			(layers "F.Cu" "F.Mask" "F.Paste")
			(net "JTAG_FPGA_TMS")
		)
		(pad "C11" smd circle
			(at -0.40005 -6.800088)
			(size 0.4064 0.4064)
			(layers "F.Cu" "F.Mask" "F.Paste")
			(net "GND")
		)
		(pad "C12" smd circle
			(at 0.40005 -6.800088)
			(size 0.4064 0.4064)
			(layers "F.Cu" "F.Mask" "F.Paste")
			(net "P3V3_FPGA_VCCIO0")
		)
		(pad "C13" smd circle
			(at 1.199896 -6.800088)
			(size 0.4064 0.4064)
			(layers "F.Cu" "F.Mask" "F.Paste")
			(net "SSD3_PWR_EN")
		)
		(pad "C14" smd circle
			(at 1.999996 -6.800088)
			(size 0.4064 0.4064)
			(layers "F.Cu" "F.Mask" "F.Paste")
			(net "PRSNT_SSD4_R_N")
		)
		(pad "C15" smd circle
			(at 2.800096 -6.800088)
			(size 0.4064 0.4064)
			(layers "F.Cu" "F.Mask" "F.Paste")
			(net "SSD4_CLK_EN_N")
		)
		(pad "C16" smd circle
			(at 3.599942 -6.800088)
			(size 0.4064 0.4064)
			(layers "F.Cu" "F.Mask" "F.Paste")
			(net "P3V3_FPGA_VCCIO0")
		)
		(pad "C17" smd circle
			(at 4.400042 -6.800088)
			(size 0.4064 0.4064)
			(layers "F.Cu" "F.Mask" "F.Paste")
			(net "SSD5_PWR_EN")
		)
		(pad "C18" smd circle
			(at 5.199888 -6.800088)
			(size 0.4064 0.4064)
			(layers "F.Cu" "F.Mask" "F.Paste")
			(net "SSD6_PWRDIS")
		)
		(pad "C19" smd circle
			(at 5.999988 -6.800088)
			(size 0.4064 0.4064)
			(layers "F.Cu" "F.Mask" "F.Paste")
			(net "RST_SSD7_PERST_N")
		)
		(pad "C20" smd circle
			(at 6.800088 -6.800088)
			(size 0.4064 0.4064)
			(layers "F.Cu" "F.Mask" "F.Paste")
			(net "SSD7_CLK_EN_N")
		)
		(pad "C21" smd circle
			(at 7.599934 -6.800088)
			(size 0.4064 0.4064)
			(layers "F.Cu" "F.Mask" "F.Paste")
			(net "PRSNT_NIC0_R_N")
		)
		(pad "C22" smd circle
			(at 8.400034 -6.800088)
			(size 0.4064 0.4064)
			(layers "F.Cu" "F.Mask" "F.Paste")
			(net "PWRGD_P12V_NIC0_R")
		)
		(pad "D1" smd circle
			(at -8.400034 -5.999988)
			(size 0.4064 0.4064)
			(layers "F.Cu" "F.Mask" "F.Paste")
			(net "PWRGD_P1V25_PEX3_R")
		)
		(pad "D2" smd circle
			(at -7.599934 -5.999988)
			(size 0.4064 0.4064)
			(layers "F.Cu" "F.Mask" "F.Paste")
			(net "PWRGD_P1V25_PEX0_R")
		)
		(pad "D3" smd circle
			(at -6.800088 -5.999988)
			(size 0.4064 0.4064)
			(layers "F.Cu" "F.Mask" "F.Paste")
			(net "PWRGD_P12V_AUX_BUF_R")
		)
		(pad "D4" smd circle
			(at -5.999988 -5.999988)
			(size 0.4064 0.4064)
			(layers "F.Cu" "F.Mask" "F.Paste")
			(net "PWRGD_P5V_AUX_BUF_R")
		)
		(pad "D5" smd circle
			(at -5.199888 -5.999988)
			(size 0.4064 0.4064)
			(layers "F.Cu" "F.Mask" "F.Paste")
			(net "RST_SSD2_PERST_N")
		)
		(pad "D6" smd circle
			(at -4.400042 -5.999988)
			(size 0.4064 0.4064)
			(layers "F.Cu" "F.Mask" "F.Paste")
			(net "JP_FPGA_FRC_PWRON_N")
		)
		(pad "D7" smd circle
			(at -3.599942 -5.999988)
			(size 0.4064 0.4064)
			(layers "F.Cu" "F.Mask" "F.Paste")
			(net "SMB_PEX0_FPGA_SDA")
		)
		(pad "D8" smd circle
			(at -2.800096 -5.999988)
			(size 0.4064 0.4064)
			(layers "F.Cu" "F.Mask" "F.Paste")
			(net "SMB_PEX1_FPGA_SDA")
		)
		(pad "D9" smd circle
			(at -1.999996 -5.999988)
			(size 0.4064 0.4064)
			(layers "F.Cu" "F.Mask" "F.Paste")
			(net "SMB_PEX3_FPGA_SDA")
		)
		(pad "D10" smd circle
			(at -1.199896 -5.999988)
			(size 0.4064 0.4064)
			(layers "F.Cu" "F.Mask" "F.Paste")
			(net "JTAG_FPGA_TCK")
		)
		(pad "D11" smd circle
			(at -0.40005 -5.999988)
			(size 0.4064 0.4064)
			(layers "F.Cu" "F.Mask" "F.Paste")
			(net "SSD1_CLK_EN_N")
		)
		(pad "D12" smd circle
			(at 0.40005 -5.999988)
			(size 0.4064 0.4064)
			(layers "F.Cu" "F.Mask" "F.Paste")
			(net "SMB_MB_BMC_ISO_FPGA_SCL")
		)
		(pad "D13" smd circle
			(at 1.199896 -5.999988)
			(size 0.4064 0.4064)
			(layers "F.Cu" "F.Mask" "F.Paste")
			(net "SSD3_PWRDIS")
		)
		(pad "D14" smd circle
			(at 1.999996 -5.999988)
			(size 0.4064 0.4064)
			(layers "F.Cu" "F.Mask" "F.Paste")
			(net "PWRGD_P12V_SSD4_R")
		)
		(pad "D15" smd circle
			(at 2.800096 -5.999988)
			(size 0.4064 0.4064)
			(layers "F.Cu" "F.Mask" "F.Paste")
			(net "PRSNT_SSD5_R_N")
		)
		(pad "D16" smd circle
			(at 3.599942 -5.999988)
			(size 0.4064 0.4064)
			(layers "F.Cu" "F.Mask" "F.Paste")
			(net "SSD5_PWRDIS")
		)
		(pad "D17" smd circle
			(at 4.400042 -5.999988)
			(size 0.4064 0.4064)
			(layers "F.Cu" "F.Mask" "F.Paste")
			(net "PWRGD_P12V_SSD6_R")
		)
		(pad "D18" smd circle
			(at 5.199888 -5.999988)
			(size 0.4064 0.4064)
			(layers "F.Cu" "F.Mask" "F.Paste")
			(net "RST_SSD6_PERST_N")
		)
		(pad "D19" smd circle
			(at 5.999988 -5.999988)
			(size 0.4064 0.4064)
			(layers "F.Cu" "F.Mask" "F.Paste")
			(net "RST_NIC0_PERST_N")
		)
		(pad "D20" smd circle
			(at 6.800088 -5.999988)
			(size 0.4064 0.4064)
			(layers "F.Cu" "F.Mask" "F.Paste")
			(net "NIC0_CLK_EN_N")
		)
		(pad "D21" smd circle
			(at 7.599934 -5.999988)
			(size 0.4064 0.4064)
			(layers "F.Cu" "F.Mask" "F.Paste")
			(net "NIC0_MAIN_PWR_EN")
		)
		(pad "D22" smd circle
			(at 8.400034 -5.999988)
			(size 0.4064 0.4064)
			(layers "F.Cu" "F.Mask" "F.Paste")
			(net "PWRGD_NIC0_PWR_GOOD_R")
		)
		(pad "E1" smd circle
			(at -8.400034 -5.199888)
			(size 0.4064 0.4064)
			(layers "F.Cu" "F.Mask" "F.Paste")
			(net "PWR_EN_PEX")
		)
		(pad "E2" smd circle
			(at -7.599934 -5.199888)
			(size 0.4064 0.4064)
			(layers "F.Cu" "F.Mask" "F.Paste")
			(net "PWRGD_P1V8_PEX_R")
		)
		(pad "E3" smd circle
			(at -6.800088 -5.199888)
			(size 0.4064 0.4064)
			(layers "F.Cu" "F.Mask" "F.Paste")
			(net "PWR_EN_P1V2_AUX")
		)
		(pad "E4" smd circle
			(at -5.999988 -5.199888)
			(size 0.4064 0.4064)
			(layers "F.Cu" "F.Mask" "F.Paste")
			(net "PWRGD_P3V3_R")
		)
		(pad "E5" smd circle
			(at -5.199888 -5.199888)
			(size 0.4064 0.4064)
			(layers "F.Cu" "F.Mask" "F.Paste")
			(net "GND")
		)
		(pad "E6" smd circle
			(at -4.400042 -5.199888)
			(size 0.4064 0.4064)
			(layers "F.Cu" "F.Mask" "F.Paste")
			(net "RST_MB_PERST_2_ISO_R_N")
		)
		(pad "E7" smd circle
			(at -3.599942 -5.199888)
			(size 0.4064 0.4064)
			(layers "F.Cu" "F.Mask" "F.Paste")
			(net "JP_FPGA_LED")
		)
		(pad "E8" smd circle
			(at -2.800096 -5.199888)
			(size 0.4064 0.4064)
			(layers "F.Cu" "F.Mask" "F.Paste")
			(net "JTAG_FPGA_R_TDO")
		)
		(pad "E9" smd circle
			(at -1.999996 -5.199888)
			(size 0.4064 0.4064)
			(layers "F.Cu" "F.Mask" "F.Paste")
			(net "JTAG_FPGA_TDI")
		)
		(pad "E10" smd circle
			(at -1.199896 -5.199888)
			(size 0.4064 0.4064)
			(layers "F.Cu" "F.Mask" "F.Paste")
			(net "RST_SSD0_PERST_N")
		)
		(pad "E11" smd circle
			(at -0.40005 -5.199888)
			(size 0.4064 0.4064)
			(layers "F.Cu" "F.Mask" "F.Paste")
			(net "RST_SSD1_PERST_N")
		)
		(pad "E12" smd circle
			(at 0.40005 -5.199888)
			(size 0.4064 0.4064)
			(layers "F.Cu" "F.Mask" "F.Paste")
			(net "SMB_MB_BMC_ISO_FPGA_SDA")
		)
		(pad "E13" smd circle
			(at 1.199896 -5.199888)
			(size 0.4064 0.4064)
			(layers "F.Cu" "F.Mask" "F.Paste")
			(net "Net_404")
		)
		(pad "E14" smd circle
			(at 1.999996 -5.199888)
			(size 0.4064 0.4064)
			(layers "F.Cu" "F.Mask" "F.Paste")
			(net "FPGA_JTAGENB")
		)
		(pad "E15" smd circle
			(at 2.800096 -5.199888)
			(size 0.4064 0.4064)
			(layers "F.Cu" "F.Mask" "F.Paste")
			(net "PU_FPGA_PROGRAMN")
		)
		(pad "E16" smd circle
			(at 3.599942 -5.199888)
			(size 0.4064 0.4064)
			(layers "F.Cu" "F.Mask" "F.Paste")
			(net "PRSNT_SSD6_R_N")
		)
		(pad "E17" smd circle
			(at 4.400042 -5.199888)
			(size 0.4064 0.4064)
			(layers "F.Cu" "F.Mask" "F.Paste")
			(net "TP_DONE")
		)
		(pad "E18" smd circle
			(at 5.199888 -5.199888)
			(size 0.4064 0.4064)
			(layers "F.Cu" "F.Mask" "F.Paste")
			(net "GND")
		)
		(pad "E19" smd circle
			(at 5.999988 -5.199888)
			(size 0.4064 0.4064)
			(layers "F.Cu" "F.Mask" "F.Paste")
			(net "PWRGD_P3V3_NIC1_R")
		)
		(pad "E20" smd circle
			(at 6.800088 -5.199888)
			(size 0.4064 0.4064)
			(layers "F.Cu" "F.Mask" "F.Paste")
			(net "NIC1_AUX_PWR_EN")
		)
		(pad "E21" smd circle
			(at 7.599934 -5.199888)
			(size 0.4064 0.4064)
			(layers "F.Cu" "F.Mask" "F.Paste")
			(net "PWRGD_P12V_NIC1_R")
		)
		(pad "E22" smd circle
			(at 8.400034 -5.199888)
			(size 0.4064 0.4064)
			(layers "F.Cu" "F.Mask" "F.Paste")
			(net "PRSNT_NIC1_R_N")
		)
		(pad "F1" smd circle
			(at -8.400034 -4.400042)
			(size 0.4064 0.4064)
			(layers "F.Cu" "F.Mask" "F.Paste")
			(net "FM_CLK_EN")
		)
		(pad "F2" smd circle
			(at -7.599934 -4.400042)
			(size 0.4064 0.4064)
			(layers "F.Cu" "F.Mask" "F.Paste")
			(net "GND")
		)
		(pad "F3" smd circle
			(at -6.800088 -4.400042)
			(size 0.4064 0.4064)
			(layers "F.Cu" "F.Mask" "F.Paste")
			(net "P3V3_FPGA_VCCIO5")
		)
		(pad "F4" smd circle
			(at -5.999988 -4.400042)
			(size 0.4064 0.4064)
			(layers "F.Cu" "F.Mask" "F.Paste")
			(net "PWR_EN_P3V3")
		)
		(pad "F5" smd circle
			(at -5.199888 -4.400042)
			(size 0.4064 0.4064)
			(layers "F.Cu" "F.Mask" "F.Paste")
			(net "PWRGD_P0V8_PEX0_R")
		)
		(pad "F6" smd circle
			(at -4.400042 -4.400042)
			(size 0.4064 0.4064)
			(layers "F.Cu" "F.Mask" "F.Paste")
			(net "PWRGD_P3V3_AUX_BUF_R")
		)
		(pad "F7" smd circle
			(at -3.599942 -4.400042)
			(size 0.4064 0.4064)
			(layers "F.Cu" "F.Mask" "F.Paste")
			(net "MB_SWB_PWR_EN_ISO_R")
		)
		(pad "F8" smd circle
			(at -2.800096 -4.400042)
			(size 0.4064 0.4064)
			(layers "F.Cu" "F.Mask" "F.Paste")
			(net "PWRGD_P12V_SSD2_R")
		)
		(pad "F9" smd circle
			(at -1.999996 -4.400042)
			(size 0.4064 0.4064)
			(layers "F.Cu" "F.Mask" "F.Paste")
			(net "PWRGD_P3V3_SSD0_R")
		)
		(pad "F10" smd circle
			(at -1.199896 -4.400042)
			(size 0.4064 0.4064)
			(layers "F.Cu" "F.Mask" "F.Paste")
			(net "SSD0_PWRDIS")
		)
		(pad "F11" smd circle
			(at -0.40005 -4.400042)
			(size 0.4064 0.4064)
			(layers "F.Cu" "F.Mask" "F.Paste")
			(net "PWRGD_P3V3_SSD1_R")
		)
		(pad "F12" smd circle
			(at 0.40005 -4.400042)
			(size 0.4064 0.4064)
			(layers "F.Cu" "F.Mask" "F.Paste")
			(net "BIC_SYS_READY_R2_N")
		)
		(pad "F13" smd circle
			(at 1.199896 -4.400042)
			(size 0.4064 0.4064)
			(layers "F.Cu" "F.Mask" "F.Paste")
			(net "PRSNT_SSD3_R_N")
		)
		(pad "F14" smd circle
			(at 1.999996 -4.400042)
			(size 0.4064 0.4064)
			(layers "F.Cu" "F.Mask" "F.Paste")
			(net "SSD4_PWR_EN")
		)
		(pad "F15" smd circle
			(at 2.800096 -4.400042)
			(size 0.4064 0.4064)
			(layers "F.Cu" "F.Mask" "F.Paste")
			(net "PWRGD_P12V_SSD7_R")
		)
		(pad "F16" smd circle
			(at 3.599942 -4.400042)
			(size 0.4064 0.4064)
			(layers "F.Cu" "F.Mask" "F.Paste")
			(net "TP_INITN")
		)
		(pad "F17" smd circle
			(at 4.400042 -4.400042)
			(size 0.4064 0.4064)
			(layers "F.Cu" "F.Mask" "F.Paste")
			(net "PWRGD_P3V3_NIC0_R")
		)
		(pad "F18" smd circle
			(at 5.199888 -4.400042)
			(size 0.4064 0.4064)
			(layers "F.Cu" "F.Mask" "F.Paste")
			(net "RST_NIC1_PERST_N")
		)
		(pad "F19" smd circle
			(at 5.999988 -4.400042)
			(size 0.4064 0.4064)
			(layers "F.Cu" "F.Mask" "F.Paste")
			(net "NIC1_CLK_EN_N")
		)
		(pad "F20" smd circle
			(at 6.800088 -4.400042)
			(size 0.4064 0.4064)
			(layers "F.Cu" "F.Mask" "F.Paste")
			(net "P3V3_FPGA_VCCIO1")
		)
		(pad "F21" smd circle
			(at 7.599934 -4.400042)
			(size 0.4064 0.4064)
			(layers "F.Cu" "F.Mask" "F.Paste")
			(net "GND")
		)
		(pad "F22" smd circle
			(at 8.400034 -4.400042)
			(size 0.4064 0.4064)
			(layers "F.Cu" "F.Mask" "F.Paste")
			(net "PWRGD_NIC1_PWR_GOOD_R")
		)
		(pad "G1" smd circle
			(at -8.400034 -3.599942)
			(size 0.4064 0.4064)
			(layers "F.Cu" "F.Mask" "F.Paste")
			(net "RST_PEX1_PERST_N")
		)
		(pad "G2" smd circle
			(at -7.599934 -3.599942)
			(size 0.4064 0.4064)
			(layers "F.Cu" "F.Mask" "F.Paste")
			(net "RST_PEX0_PERST_N")
		)
		(pad "G3" smd circle
			(at -6.800088 -3.599942)
			(size 0.4064 0.4064)
			(layers "F.Cu" "F.Mask" "F.Paste")
			(net "RST_PEX_SYS_N")
		)
		(pad "G4" smd circle
			(at -5.999988 -3.599942)
			(size 0.4064 0.4064)
			(layers "F.Cu" "F.Mask" "F.Paste")
			(net "FM_SYS_THROTTLE")
		)
		(pad "G5" smd circle
			(at -5.199888 -3.599942)
			(size 0.4064 0.4064)
			(layers "F.Cu" "F.Mask" "F.Paste")
			(net "PWRGD_P1V25_PEX1_R")
		)
		(pad "G6" smd circle
			(at -4.400042 -3.599942)
			(size 0.4064 0.4064)
			(layers "F.Cu" "F.Mask" "F.Paste")
			(net "PWRGD_P0V8_PEX1_R")
		)
		(pad "G7" smd circle
			(at -3.599942 -3.599942)
			(size 0.4064 0.4064)
			(layers "F.Cu" "F.Mask" "F.Paste")
			(net "PWRGD_P1V2_AUX_R")
		)
		(pad "G8" smd circle
			(at -2.800096 -3.599942)
			(size 0.4064 0.4064)
			(layers "F.Cu" "F.Mask" "F.Paste")
			(net "PWRGD_P3V3_SSD2_R")
		)
		(pad "G9" smd circle
			(at -1.999996 -3.599942)
			(size 0.4064 0.4064)
			(layers "F.Cu" "F.Mask" "F.Paste")
			(net "SSD0_PWR_EN")
		)
		(pad "G10" smd circle
			(at -1.199896 -3.599942)
			(size 0.4064 0.4064)
			(layers "F.Cu" "F.Mask" "F.Paste")
			(net "P3V3_FPGA_VCCIO0")
		)
		(pad "G11" smd circle
			(at -0.40005 -3.599942)
			(size 0.4064 0.4064)
			(layers "F.Cu" "F.Mask" "F.Paste")
			(net "PWRGD_P12V_SSD1_R")
		)
		(pad "G12" smd circle
			(at 0.40005 -3.599942)
			(size 0.4064 0.4064)
			(layers "F.Cu" "F.Mask" "F.Paste")
			(net "SMB_FPGA_ALERT_N")
		)
		(pad "G13" smd circle
			(at 1.199896 -3.599942)
			(size 0.4064 0.4064)
			(layers "F.Cu" "F.Mask" "F.Paste")
			(net "P3V3_FPGA_VCCIO0")
		)
		(pad "G14" smd circle
			(at 1.999996 -3.599942)
			(size 0.4064 0.4064)
			(layers "F.Cu" "F.Mask" "F.Paste")
			(net "PWRGD_P3V3_SSD4_R")
		)
		(pad "G15" smd circle
			(at 2.800096 -3.599942)
			(size 0.4064 0.4064)
			(layers "F.Cu" "F.Mask" "F.Paste")
			(net "PWRGD_P3V3_SSD7_R")
		)
		(pad "G16" smd circle
			(at 3.599942 -3.599942)
			(size 0.4064 0.4064)
			(layers "F.Cu" "F.Mask" "F.Paste")
			(net "NIC0_AUX_PWR_EN")
		)
		(pad "G17" smd circle
			(at 4.400042 -3.599942)
			(size 0.4064 0.4064)
			(layers "F.Cu" "F.Mask" "F.Paste")
			(net "RST_NIC2_PERST_N")
		)
		(pad "G18" smd circle
			(at 5.199888 -3.599942)
			(size 0.4064 0.4064)
			(layers "F.Cu" "F.Mask" "F.Paste")
			(net "NIC2_AUX_PWR_EN")
		)
		(pad "G19" smd circle
			(at 5.999988 -3.599942)
			(size 0.4064 0.4064)
			(layers "F.Cu" "F.Mask" "F.Paste")
			(net "PWRGD_P3V3_NIC2_R")
		)
		(pad "G20" smd circle
			(at 6.800088 -3.599942)
			(size 0.4064 0.4064)
			(layers "F.Cu" "F.Mask" "F.Paste")
			(net "PWRGD_P12V_NIC2_R")
		)
		(pad "G21" smd circle
			(at 7.599934 -3.599942)
			(size 0.4064 0.4064)
			(layers "F.Cu" "F.Mask" "F.Paste")
			(net "PRSNT_NIC2_R_N")
		)
		(pad "G22" smd circle
			(at 8.400034 -3.599942)
			(size 0.4064 0.4064)
			(layers "F.Cu" "F.Mask" "F.Paste")
			(net "NIC1_MAIN_PWR_EN")
		)
		(pad "H1" smd circle
			(at -8.400034 -2.800096)
			(size 0.4064 0.4064)
			(layers "F.Cu" "F.Mask" "F.Paste")
			(net "PEX1_SYS_ERR_FPGA")
		)
		(pad "H2" smd circle
			(at -7.599934 -2.800096)
			(size 0.4064 0.4064)
			(layers "F.Cu" "F.Mask" "F.Paste")
			(net "PEX0_SYS_ERR_FPGA")
		)
		(pad "H3" smd circle
			(at -6.800088 -2.800096)
			(size 0.4064 0.4064)
			(layers "F.Cu" "F.Mask" "F.Paste")
			(net "RST_PEX3_PERST_N")
		)
		(pad "H4" smd circle
			(at -5.999988 -2.800096)
			(size 0.4064 0.4064)
			(layers "F.Cu" "F.Mask" "F.Paste")
			(net "RST_PEX2_PERST_N")
		)
		(pad "H5" smd circle
			(at -5.199888 -2.800096)
			(size 0.4064 0.4064)
			(layers "F.Cu" "F.Mask" "F.Paste")
			(net "LED_POSTCODE_0")
		)
		(pad "H6" smd circle
			(at -4.400042 -2.800096)
			(size 0.4064 0.4064)
			(layers "F.Cu" "F.Mask" "F.Paste")
			(net "PWRGD_P1V25_PEX2_R")
		)
		(pad "H7" smd circle
			(at -3.599942 -2.800096)
			(size 0.4064 0.4064)
			(layers "F.Cu" "F.Mask" "F.Paste")
			(net "PWRGD_P0V8_PEX2_R")
		)
		(pad "H8" smd circle
			(at -2.800096 -2.800096)
			(size 0.4064 0.4064)
			(layers "F.Cu" "F.Mask" "F.Paste")
			(net "GND")
		)
		(pad "H9" smd circle
			(at -1.999996 -2.800096)
			(size 0.4064 0.4064)
			(layers "F.Cu" "F.Mask" "F.Paste")
			(net "P3V3_FPGA_VCCIO0")
		)
		(pad "H10" smd circle
			(at -1.199896 -2.800096)
			(size 0.4064 0.4064)
			(layers "F.Cu" "F.Mask" "F.Paste")
			(net "GND")
		)
		(pad "H11" smd circle
			(at -0.40005 -2.800096)
			(size 0.4064 0.4064)
			(layers "F.Cu" "F.Mask" "F.Paste")
			(net "P3V3_FPGA_VCCIO0")
		)
		(pad "H12" smd circle
			(at 0.40005 -2.800096)
			(size 0.4064 0.4064)
			(layers "F.Cu" "F.Mask" "F.Paste")
			(net "P3V3_FPGA_VCCIO0")
		)
		(pad "H13" smd circle
			(at 1.199896 -2.800096)
			(size 0.4064 0.4064)
			(layers "F.Cu" "F.Mask" "F.Paste")
			(net "GND")
		)
		(pad "H14" smd circle
			(at 1.999996 -2.800096)
			(size 0.4064 0.4064)
			(layers "F.Cu" "F.Mask" "F.Paste")
			(net "P3V3_FPGA_VCCIO0")
		)
		(pad "H15" smd circle
			(at 2.800096 -2.800096)
			(size 0.4064 0.4064)
			(layers "F.Cu" "F.Mask" "F.Paste")
			(net "GND")
		)
		(pad "H16" smd circle
			(at 3.599942 -2.800096)
			(size 0.4064 0.4064)
			(layers "F.Cu" "F.Mask" "F.Paste")
			(net "NIC3_AUX_PWR_EN")
		)
		(pad "H17" smd circle
			(at 4.400042 -2.800096)
			(size 0.4064 0.4064)
			(layers "F.Cu" "F.Mask" "F.Paste")
			(net "PWRGD_P3V3_NIC3_R")
		)
		(pad "H18" smd circle
			(at 5.199888 -2.800096)
			(size 0.4064 0.4064)
			(layers "F.Cu" "F.Mask" "F.Paste")
			(net "PWRGD_P12V_NIC3_R")
		)
		(pad "H19" smd circle
			(at 5.999988 -2.800096)
			(size 0.4064 0.4064)
			(layers "F.Cu" "F.Mask" "F.Paste")
			(net "PRSNT_NIC3_R_N")
		)
		(pad "H20" smd circle
			(at 6.800088 -2.800096)
			(size 0.4064 0.4064)
			(layers "F.Cu" "F.Mask" "F.Paste")
			(net "NIC2_CLK_EN_N")
		)
		(pad "H21" smd circle
			(at 7.599934 -2.800096)
			(size 0.4064 0.4064)
			(layers "F.Cu" "F.Mask" "F.Paste")
			(net "NIC2_MAIN_PWR_EN")
		)
		(pad "H22" smd circle
			(at 8.400034 -2.800096)
			(size 0.4064 0.4064)
			(layers "F.Cu" "F.Mask" "F.Paste")
			(net "PWRGD_NIC2_PWR_GOOD_R")
		)
		(pad "J1" smd circle
			(at -8.400034 -1.999996)
			(size 0.4064 0.4064)
			(layers "F.Cu" "F.Mask" "F.Paste")
			(net "LED_POSTCODE_5")
		)
		(pad "J2" smd circle
			(at -7.599934 -1.999996)
			(size 0.4064 0.4064)
			(layers "F.Cu" "F.Mask" "F.Paste")
			(net "LED_POSTCODE_4")
		)
		(pad "J3" smd circle
			(at -6.800088 -1.999996)
			(size 0.4064 0.4064)
			(layers "F.Cu" "F.Mask" "F.Paste")
			(net "LED_POSTCODE_3")
		)
		(pad "J4" smd circle
			(at -5.999988 -1.999996)
			(size 0.4064 0.4064)
			(layers "F.Cu" "F.Mask" "F.Paste")
			(net "LED_POSTCODE_2")
		)
		(pad "J5" smd circle
			(at -5.199888 -1.999996)
			(size 0.4064 0.4064)
			(layers "F.Cu" "F.Mask" "F.Paste")
			(net "LED_POSTCODE_1")
		)
		(pad "J6" smd circle
			(at -4.400042 -1.999996)
			(size 0.4064 0.4064)
			(layers "F.Cu" "F.Mask" "F.Paste")
			(net "PEX3_SYS_ERR_FPGA")
		)
		(pad "J7" smd circle
			(at -3.599942 -1.999996)
			(size 0.4064 0.4064)
			(layers "F.Cu" "F.Mask" "F.Paste")
			(net "PEX2_SYS_ERR_FPGA")
		)
		(pad "J8" smd circle
			(at -2.800096 -1.999996)
			(size 0.4064 0.4064)
			(layers "F.Cu" "F.Mask" "F.Paste")
			(net "P3V3_FPGA_VCCIO5")
		)
		(pad "J9" smd circle
			(at -1.999996 -1.999996)
			(size 0.4064 0.4064)
			(layers "F.Cu" "F.Mask" "F.Paste")
			(net "GND")
		)
		(pad "J10" smd circle
			(at -1.199896 -1.999996)
			(size 0.4064 0.4064)
			(layers "F.Cu" "F.Mask" "F.Paste")
			(net "GND")
		)
		(pad "J11" smd circle
			(at -0.40005 -1.999996)
			(size 0.4064 0.4064)
			(layers "F.Cu" "F.Mask" "F.Paste")
			(net "GND")
		)
		(pad "J12" smd circle
			(at 0.40005 -1.999996)
			(size 0.4064 0.4064)
			(layers "F.Cu" "F.Mask" "F.Paste")
			(net "GND")
		)
		(pad "J13" smd circle
			(at 1.199896 -1.999996)
			(size 0.4064 0.4064)
			(layers "F.Cu" "F.Mask" "F.Paste")
			(net "GND")
		)
		(pad "J14" smd circle
			(at 1.999996 -1.999996)
			(size 0.4064 0.4064)
			(layers "F.Cu" "F.Mask" "F.Paste")
			(net "GND")
		)
		(pad "J15" smd circle
			(at 2.800096 -1.999996)
			(size 0.4064 0.4064)
			(layers "F.Cu" "F.Mask" "F.Paste")
			(net "P3V3_FPGA_VCCIO1")
		)
		(pad "J16" smd circle
			(at 3.599942 -1.999996)
			(size 0.4064 0.4064)
			(layers "F.Cu" "F.Mask" "F.Paste")
			(net "PWRGD_NIC3_PWR_GOOD_R")
		)
		(pad "J17" smd circle
			(at 4.400042 -1.999996)
			(size 0.4064 0.4064)
			(layers "F.Cu" "F.Mask" "F.Paste")
			(net "NIC3_MAIN_PWR_EN")
		)
		(pad "J18" smd circle
			(at 5.199888 -1.999996)
			(size 0.4064 0.4064)
			(layers "F.Cu" "F.Mask" "F.Paste")
			(net "RST_NIC3_PERST_N")
		)
		(pad "J19" smd circle
			(at 5.999988 -1.999996)
			(size 0.4064 0.4064)
			(layers "F.Cu" "F.Mask" "F.Paste")
			(net "NIC3_CLK_EN_N")
		)
		(pad "J20" smd circle
			(at 6.800088 -1.999996)
			(size 0.4064 0.4064)
			(layers "F.Cu" "F.Mask" "F.Paste")
			(net "PWRGD_P3V3_NIC4_R")
		)
		(pad "J21" smd circle
			(at 7.599934 -1.999996)
			(size 0.4064 0.4064)
			(layers "F.Cu" "F.Mask" "F.Paste")
			(net "PRSNT_NIC4_R_N")
		)
		(pad "J22" smd circle
			(at 8.400034 -1.999996)
			(size 0.4064 0.4064)
			(layers "F.Cu" "F.Mask" "F.Paste")
			(net "PWRGD_P12V_NIC4_R")
		)
		(pad "K1" smd circle
			(at -8.400034 -1.199896)
			(size 0.4064 0.4064)
			(layers "F.Cu" "F.Mask" "F.Paste")
			(net "PRSNT_SSD15_FPGA_N")
		)
		(pad "K2" smd circle
			(at -7.599934 -1.199896)
			(size 0.4064 0.4064)
			(layers "F.Cu" "F.Mask" "F.Paste")
			(net "SMB_BIC_FPGA_R1_SDA")
		)
		(pad "K3" smd circle
			(at -6.800088 -1.199896)
			(size 0.4064 0.4064)
			(layers "F.Cu" "F.Mask" "F.Paste")
			(net "SSD14_PWRDIS_BIC_R")
		)
		(pad "K4" smd circle
			(at -5.999988 -1.199896)
			(size 0.4064 0.4064)
			(layers "F.Cu" "F.Mask" "F.Paste")
			(net "RST_PEX_SSD14_PERST_R_N")
		)
		(pad "K5" smd circle
			(at -5.199888 -1.199896)
			(size 0.4064 0.4064)
			(layers "F.Cu" "F.Mask" "F.Paste")
			(net "SSD14_PEX_PWR_EN_R")
		)
		(pad "K6" smd circle
			(at -4.400042 -1.199896)
			(size 0.4064 0.4064)
			(layers "F.Cu" "F.Mask" "F.Paste")
			(net "LED_POSTCODE_7")
		)
		(pad "K7" smd circle
			(at -3.599942 -1.199896)
			(size 0.4064 0.4064)
			(layers "F.Cu" "F.Mask" "F.Paste")
			(net "LED_POSTCODE_6")
		)
		(pad "K8" smd circle
			(at -2.800096 -1.199896)
			(size 0.4064 0.4064)
			(layers "F.Cu" "F.Mask" "F.Paste")
			(net "P3V3_FPGA_VCCIO5")
		)
		(pad "K9" smd circle
			(at -1.999996 -1.199896)
			(size 0.4064 0.4064)
			(layers "F.Cu" "F.Mask" "F.Paste")
			(net "GND")
		)
		(pad "K10" smd circle
			(at -1.199896 -1.199896)
			(size 0.4064 0.4064)
			(layers "F.Cu" "F.Mask" "F.Paste")
			(net "P3V3_VCC_FPGA_CORE")
		)
		(pad "K11" smd circle
			(at -0.40005 -1.199896)
			(size 0.4064 0.4064)
			(layers "F.Cu" "F.Mask" "F.Paste")
			(net "P3V3_VCC_FPGA_CORE")
		)
		(pad "K12" smd circle
			(at 0.40005 -1.199896)
			(size 0.4064 0.4064)
			(layers "F.Cu" "F.Mask" "F.Paste")
			(net "P3V3_VCC_FPGA_CORE")
		)
		(pad "K13" smd circle
			(at 1.199896 -1.199896)
			(size 0.4064 0.4064)
			(layers "F.Cu" "F.Mask" "F.Paste")
			(net "P3V3_VCC_FPGA_CORE")
		)
		(pad "K14" smd circle
			(at 1.999996 -1.199896)
			(size 0.4064 0.4064)
			(layers "F.Cu" "F.Mask" "F.Paste")
			(net "GND")
		)
		(pad "K15" smd circle
			(at 2.800096 -1.199896)
			(size 0.4064 0.4064)
			(layers "F.Cu" "F.Mask" "F.Paste")
			(net "P3V3_FPGA_VCCIO1")
		)
		(pad "K16" smd circle
			(at 3.599942 -1.199896)
			(size 0.4064 0.4064)
			(layers "F.Cu" "F.Mask" "F.Paste")
			(net "NIC4_CLK_EN_N")
		)
		(pad "K17" smd circle
			(at 4.400042 -1.199896)
			(size 0.4064 0.4064)
			(layers "F.Cu" "F.Mask" "F.Paste")
			(net "RST_NIC4_PERST_N")
		)
		(pad "K18" smd circle
			(at 5.199888 -1.199896)
			(size 0.4064 0.4064)
			(layers "F.Cu" "F.Mask" "F.Paste")
			(net "NIC4_MAIN_PWR_EN")
		)
		(pad "K19" smd circle
			(at 5.999988 -1.199896)
			(size 0.4064 0.4064)
			(layers "F.Cu" "F.Mask" "F.Paste")
			(net "PWRGD_NIC4_PWR_GOOD_R")
		)
		(pad "K20" smd circle
			(at 6.800088 -1.199896)
			(size 0.4064 0.4064)
			(layers "F.Cu" "F.Mask" "F.Paste")
			(net "NIC4_AUX_PWR_EN")
		)
		(pad "K21" smd circle
			(at 7.599934 -1.199896)
			(size 0.4064 0.4064)
			(layers "F.Cu" "F.Mask" "F.Paste")
			(net "GND")
		)
		(pad "K22" smd circle
			(at 8.400034 -1.199896)
			(size 0.4064 0.4064)
			(layers "F.Cu" "F.Mask" "F.Paste")
			(net "PWRGD_NIC5_PWR_GOOD_R")
		)
		(pad "L1" smd circle
			(at -8.400034 -0.40005)
			(size 0.4064 0.4064)
			(layers "F.Cu" "F.Mask" "F.Paste")
			(net "SSD15_PWRDIS_BIC_R")
		)
		(pad "L2" smd circle
			(at -7.599934 -0.40005)
			(size 0.4064 0.4064)
			(layers "F.Cu" "F.Mask" "F.Paste")
			(net "GND")
		)
		(pad "L3" smd circle
			(at -6.800088 -0.40005)
			(size 0.4064 0.4064)
			(layers "F.Cu" "F.Mask" "F.Paste")
			(net "HSC_UV_R_N")
		)
		(pad "L4" smd circle
			(at -5.999988 -0.40005)
			(size 0.4064 0.4064)
			(layers "F.Cu" "F.Mask" "F.Paste")
			(net "HSC_D_OC_FPGA_N")
		)
		(pad "L5" smd circle
			(at -5.199888 -0.40005)
			(size 0.4064 0.4064)
			(layers "F.Cu" "F.Mask" "F.Paste")
			(net "RST_PEX_SSD15_PERST_R_N")
		)
		(pad "L6" smd circle
			(at -4.400042 -0.40005)
			(size 0.4064 0.4064)
			(layers "F.Cu" "F.Mask" "F.Paste")
			(net "SSD15_PEX_PWR_EN_R")
		)
		(pad "L7" smd circle
			(at -3.599942 -0.40005)
			(size 0.4064 0.4064)
			(layers "F.Cu" "F.Mask" "F.Paste")
			(net "PRSNT_SSD14_FPGA_N")
		)
		(pad "L8" smd circle
			(at -2.800096 -0.40005)
			(size 0.4064 0.4064)
			(layers "F.Cu" "F.Mask" "F.Paste")
			(net "P3V3_FPGA_VCCIO4")
		)
		(pad "L9" smd circle
			(at -1.999996 -0.40005)
			(size 0.4064 0.4064)
			(layers "F.Cu" "F.Mask" "F.Paste")
			(net "GND")
		)
		(pad "L10" smd circle
			(at -1.199896 -0.40005)
			(size 0.4064 0.4064)
			(layers "F.Cu" "F.Mask" "F.Paste")
			(net "GND")
		)
		(pad "L11" smd circle
			(at -0.40005 -0.40005)
			(size 0.4064 0.4064)
			(layers "F.Cu" "F.Mask" "F.Paste")
			(net "P3V3_VCC_FPGA_CORE")
		)
		(pad "L12" smd circle
			(at 0.40005 -0.40005)
			(size 0.4064 0.4064)
			(layers "F.Cu" "F.Mask" "F.Paste")
			(net "P3V3_VCC_FPGA_CORE")
		)
		(pad "L13" smd circle
			(at 1.199896 -0.40005)
			(size 0.4064 0.4064)
			(layers "F.Cu" "F.Mask" "F.Paste")
			(net "GND")
		)
		(pad "L14" smd circle
			(at 1.999996 -0.40005)
			(size 0.4064 0.4064)
			(layers "F.Cu" "F.Mask" "F.Paste")
			(net "GND")
		)
		(pad "L15" smd circle
			(at 2.800096 -0.40005)
			(size 0.4064 0.4064)
			(layers "F.Cu" "F.Mask" "F.Paste")
			(net "P3V3_FPGA_VCCIO1")
		)
		(pad "L16" smd circle
			(at 3.599942 -0.40005)
			(size 0.4064 0.4064)
			(layers "F.Cu" "F.Mask" "F.Paste")
			(net "PWRGD_P12V_NIC5_R")
		)
		(pad "L17" smd circle
			(at 4.400042 -0.40005)
			(size 0.4064 0.4064)
			(layers "F.Cu" "F.Mask" "F.Paste")
			(net "PRSNT_NIC5_R_N")
		)
		(pad "L18" smd circle
			(at 5.199888 -0.40005)
			(size 0.4064 0.4064)
			(layers "F.Cu" "F.Mask" "F.Paste")
			(net "GND")
		)
		(pad "L19" smd circle
			(at 5.999988 -0.40005)
			(size 0.4064 0.4064)
			(layers "F.Cu" "F.Mask" "F.Paste")
			(net "PWRGD_P3V3_NIC5_R")
		)
		(pad "L20" smd circle
			(at 6.800088 -0.40005)
			(size 0.4064 0.4064)
			(layers "F.Cu" "F.Mask" "F.Paste")
			(net "NIC5_AUX_PWR_EN")
		)
		(pad "L21" smd circle
			(at 7.599934 -0.40005)
			(size 0.4064 0.4064)
			(layers "F.Cu" "F.Mask" "F.Paste")
			(net "NIC5_MAIN_PWR_EN")
		)
		(pad "L22" smd circle
			(at 8.400034 -0.40005)
			(size 0.4064 0.4064)
			(layers "F.Cu" "F.Mask" "F.Paste")
			(net "RST_NIC5_PERST_N")
		)
		(pad "M1" smd circle
			(at -8.400034 0.40005)
			(size 0.4064 0.4064)
			(layers "F.Cu" "F.Mask" "F.Paste")
			(net "PRSNT_NIC6_FPGA_N")
		)
		(pad "M2" smd circle
			(at -7.599934 0.40005)
			(size 0.4064 0.4064)
			(layers "F.Cu" "F.Mask" "F.Paste")
			(net "SMB_BIC_FPGA_R1_SCL")
		)
		(pad "M3" smd circle
			(at -6.800088 0.40005)
			(size 0.4064 0.4064)
			(layers "F.Cu" "F.Mask" "F.Paste")
			(net "P3V3_FPGA_VCCIO4")
		)
		(pad "M4" smd circle
			(at -5.999988 0.40005)
			(size 0.4064 0.4064)
			(layers "F.Cu" "F.Mask" "F.Paste")
			(net "GND")
		)
		(pad "M5" smd circle
			(at -5.199888 0.40005)
			(size 0.4064 0.4064)
			(layers "F.Cu" "F.Mask" "F.Paste")
			(net "NIC6_MAIN_PWR_BIC_EN_R")
		)
		(pad "M6" smd circle
			(at -4.400042 0.40005)
			(size 0.4064 0.4064)
			(layers "F.Cu" "F.Mask" "F.Paste")
			(net "RST_PEX_NIC6_PERST_R_N")
		)
		(pad "M7" smd circle
			(at -3.599942 0.40005)
			(size 0.4064 0.4064)
			(layers "F.Cu" "F.Mask" "F.Paste")
			(net "SMB_ALERT_HSC_R_N")
		)
		(pad "M8" smd circle
			(at -2.800096 0.40005)
			(size 0.4064 0.4064)
			(layers "F.Cu" "F.Mask" "F.Paste")
			(net "P3V3_FPGA_VCCIO4")
		)
		(pad "M9" smd circle
			(at -1.999996 0.40005)
			(size 0.4064 0.4064)
			(layers "F.Cu" "F.Mask" "F.Paste")
			(net "GND")
		)
		(pad "M10" smd circle
			(at -1.199896 0.40005)
			(size 0.4064 0.4064)
			(layers "F.Cu" "F.Mask" "F.Paste")
			(net "GND")
		)
		(pad "M11" smd circle
			(at -0.40005 0.40005)
			(size 0.4064 0.4064)
			(layers "F.Cu" "F.Mask" "F.Paste")
			(net "P3V3_VCC_FPGA_CORE")
		)
		(pad "M12" smd circle
			(at 0.40005 0.40005)
			(size 0.4064 0.4064)
			(layers "F.Cu" "F.Mask" "F.Paste")
			(net "P3V3_VCC_FPGA_CORE")
		)
		(pad "M13" smd circle
			(at 1.199896 0.40005)
			(size 0.4064 0.4064)
			(layers "F.Cu" "F.Mask" "F.Paste")
			(net "GND")
		)
		(pad "M14" smd circle
			(at 1.999996 0.40005)
			(size 0.4064 0.4064)
			(layers "F.Cu" "F.Mask" "F.Paste")
			(net "GND")
		)
		(pad "M15" smd circle
			(at 2.800096 0.40005)
			(size 0.4064 0.4064)
			(layers "F.Cu" "F.Mask" "F.Paste")
			(net "P3V3_FPGA_VCCIO1")
		)
		(pad "M16" smd circle
			(at 3.599942 0.40005)
			(size 0.4064 0.4064)
			(layers "F.Cu" "F.Mask" "F.Paste")
			(net "PWRGD_NIC6_PWR_GOOD_R")
		)
		(pad "M17" smd circle
			(at 4.400042 0.40005)
			(size 0.4064 0.4064)
			(layers "F.Cu" "F.Mask" "F.Paste")
			(net "NIC5_CLK_EN_N")
		)
		(pad "M18" smd circle
			(at 5.199888 0.40005)
			(size 0.4064 0.4064)
			(layers "F.Cu" "F.Mask" "F.Paste")
			(net "P3V3_FPGA_VCCIO1")
		)
		(pad "M19" smd circle
			(at 5.999988 0.40005)
			(size 0.4064 0.4064)
			(layers "F.Cu" "F.Mask" "F.Paste")
			(net "NIC6_AUX_PWR_EN")
		)
		(pad "M20" smd circle
			(at 6.800088 0.40005)
			(size 0.4064 0.4064)
			(layers "F.Cu" "F.Mask" "F.Paste")
			(net "PWRGD_P3V3_NIC6_R")
		)
		(pad "M21" smd circle
			(at 7.599934 0.40005)
			(size 0.4064 0.4064)
			(layers "F.Cu" "F.Mask" "F.Paste")
			(net "PWRGD_P12V_NIC6_R")
		)
		(pad "M22" smd circle
			(at 8.400034 0.40005)
			(size 0.4064 0.4064)
			(layers "F.Cu" "F.Mask" "F.Paste")
			(net "PRSNT_NIC6_R_N")
		)
		(pad "N1" smd circle
			(at -8.400034 1.199896)
			(size 0.4064 0.4064)
			(layers "F.Cu" "F.Mask" "F.Paste")
			(net "NIC6_PEX_PWR_EN_R")
		)
		(pad "N2" smd circle
			(at -7.599934 1.199896)
			(size 0.4064 0.4064)
			(layers "F.Cu" "F.Mask" "F.Paste")
			(net "Net_1184")
		)
		(pad "N3" smd circle
			(at -6.800088 1.199896)
			(size 0.4064 0.4064)
			(layers "F.Cu" "F.Mask" "F.Paste")
			(net "NIC7_PEX_PWR_EN_R")
		)
		(pad "N4" smd circle
			(at -5.999988 1.199896)
			(size 0.4064 0.4064)
			(layers "F.Cu" "F.Mask" "F.Paste")
			(net "RST_PEX_NIC7_PERST_R_N")
		)
		(pad "N5" smd circle
			(at -5.199888 1.199896)
			(size 0.4064 0.4064)
			(layers "F.Cu" "F.Mask" "F.Paste")
			(net "SSD10_PWRDIS_BIC_R")
		)
		(pad "N6" smd circle
			(at -4.400042 1.199896)
			(size 0.4064 0.4064)
			(layers "F.Cu" "F.Mask" "F.Paste")
			(net "RST_PEX_SSD10_PERST_R_N")
		)
		(pad "N7" smd circle
			(at -3.599942 1.199896)
			(size 0.4064 0.4064)
			(layers "F.Cu" "F.Mask" "F.Paste")
			(net "SSD10_PEX_PWR_EN_R")
		)
		(pad "N8" smd circle
			(at -2.800096 1.199896)
			(size 0.4064 0.4064)
			(layers "F.Cu" "F.Mask" "F.Paste")
			(net "P3V3_FPGA_VCCIO3")
		)
		(pad "N9" smd circle
			(at -1.999996 1.199896)
			(size 0.4064 0.4064)
			(layers "F.Cu" "F.Mask" "F.Paste")
			(net "GND")
		)
		(pad "N10" smd circle
			(at -1.199896 1.199896)
			(size 0.4064 0.4064)
			(layers "F.Cu" "F.Mask" "F.Paste")
			(net "P3V3_VCC_FPGA_CORE")
		)
		(pad "N11" smd circle
			(at -0.40005 1.199896)
			(size 0.4064 0.4064)
			(layers "F.Cu" "F.Mask" "F.Paste")
			(net "P3V3_VCC_FPGA_CORE")
		)
		(pad "N12" smd circle
			(at 0.40005 1.199896)
			(size 0.4064 0.4064)
			(layers "F.Cu" "F.Mask" "F.Paste")
			(net "P3V3_VCC_FPGA_CORE")
		)
		(pad "N13" smd circle
			(at 1.199896 1.199896)
			(size 0.4064 0.4064)
			(layers "F.Cu" "F.Mask" "F.Paste")
			(net "P3V3_VCC_FPGA_CORE")
		)
		(pad "N14" smd circle
			(at 1.999996 1.199896)
			(size 0.4064 0.4064)
			(layers "F.Cu" "F.Mask" "F.Paste")
			(net "GND")
		)
		(pad "N15" smd circle
			(at 2.800096 1.199896)
			(size 0.4064 0.4064)
			(layers "F.Cu" "F.Mask" "F.Paste")
			(net "P3V3_FPGA_VCCIO1")
		)
		(pad "N16" smd circle
			(at 3.599942 1.199896)
			(size 0.4064 0.4064)
			(layers "F.Cu" "F.Mask" "F.Paste")
			(net "NIC6_MAIN_PWR_EN")
		)
		(pad "N17" smd circle
			(at 4.400042 1.199896)
			(size 0.4064 0.4064)
			(layers "F.Cu" "F.Mask" "F.Paste")
			(net "RST_NIC6_PERST_N")
		)
		(pad "N18" smd circle
			(at 5.199888 1.199896)
			(size 0.4064 0.4064)
			(layers "F.Cu" "F.Mask" "F.Paste")
			(net "NIC6_CLK_EN_N")
		)
		(pad "N19" smd circle
			(at 5.999988 1.199896)
			(size 0.4064 0.4064)
			(layers "F.Cu" "F.Mask" "F.Paste")
			(net "NIC7_AUX_PWR_EN")
		)
		(pad "N20" smd circle
			(at 6.800088 1.199896)
			(size 0.4064 0.4064)
			(layers "F.Cu" "F.Mask" "F.Paste")
			(net "PWRGD_P3V3_NIC7_R")
		)
		(pad "N21" smd circle
			(at 7.599934 1.199896)
			(size 0.4064 0.4064)
			(layers "F.Cu" "F.Mask" "F.Paste")
			(net "GND")
		)
		(pad "N22" smd circle
			(at 8.400034 1.199896)
			(size 0.4064 0.4064)
			(layers "F.Cu" "F.Mask" "F.Paste")
			(net "PRSNT_NIC7_R_N")
		)
		(pad "P1" smd circle
			(at -8.400034 1.999996)
			(size 0.4064 0.4064)
			(layers "F.Cu" "F.Mask" "F.Paste")
			(net "PRSNT_NIC7_FPGA_N")
		)
		(pad "P2" smd circle
			(at -7.599934 1.999996)
			(size 0.4064 0.4064)
			(layers "F.Cu" "F.Mask" "F.Paste")
			(net "NIC7_MAIN_PWR_BIC_EN_R")
		)
		(pad "P3" smd circle
			(at -6.800088 1.999996)
			(size 0.4064 0.4064)
			(layers "F.Cu" "F.Mask" "F.Paste")
			(net "HSC_TIMER_R_N")
		)
		(pad "P4" smd circle
			(at -5.999988 1.999996)
			(size 0.4064 0.4064)
			(layers "F.Cu" "F.Mask" "F.Paste")
			(net "Net_1180")
		)
		(pad "P5" smd circle
			(at -5.199888 1.999996)
			(size 0.4064 0.4064)
			(layers "F.Cu" "F.Mask" "F.Paste")
			(net "SSD9_PWRDIS_BIC_R")
		)
		(pad "P6" smd circle
			(at -4.400042 1.999996)
			(size 0.4064 0.4064)
			(layers "F.Cu" "F.Mask" "F.Paste")
			(net "RST_PEX_SSD9_PERST_R_N")
		)
		(pad "P7" smd circle
			(at -3.599942 1.999996)
			(size 0.4064 0.4064)
			(layers "F.Cu" "F.Mask" "F.Paste")
			(net "SSD8_PWRDIS_BIC_R")
		)
		(pad "P8" smd circle
			(at -2.800096 1.999996)
			(size 0.4064 0.4064)
			(layers "F.Cu" "F.Mask" "F.Paste")
			(net "P3V3_FPGA_VCCIO3")
		)
		(pad "P9" smd circle
			(at -1.999996 1.999996)
			(size 0.4064 0.4064)
			(layers "F.Cu" "F.Mask" "F.Paste")
			(net "GND")
		)
		(pad "P10" smd circle
			(at -1.199896 1.999996)
			(size 0.4064 0.4064)
			(layers "F.Cu" "F.Mask" "F.Paste")
			(net "GND")
		)
		(pad "P11" smd circle
			(at -0.40005 1.999996)
			(size 0.4064 0.4064)
			(layers "F.Cu" "F.Mask" "F.Paste")
			(net "GND")
		)
		(pad "P12" smd circle
			(at 0.40005 1.999996)
			(size 0.4064 0.4064)
			(layers "F.Cu" "F.Mask" "F.Paste")
			(net "GND")
		)
		(pad "P13" smd circle
			(at 1.199896 1.999996)
			(size 0.4064 0.4064)
			(layers "F.Cu" "F.Mask" "F.Paste")
			(net "GND")
		)
		(pad "P14" smd circle
			(at 1.999996 1.999996)
			(size 0.4064 0.4064)
			(layers "F.Cu" "F.Mask" "F.Paste")
			(net "GND")
		)
		(pad "P15" smd circle
			(at 2.800096 1.999996)
			(size 0.4064 0.4064)
			(layers "F.Cu" "F.Mask" "F.Paste")
			(net "P3V3_FPGA_VCCIO1")
		)
		(pad "P16" smd circle
			(at 3.599942 1.999996)
			(size 0.4064 0.4064)
			(layers "F.Cu" "F.Mask" "F.Paste")
			(net "PRSNT_NIC1_FPGA_N")
		)
		(pad "P17" smd circle
			(at 4.400042 1.999996)
			(size 0.4064 0.4064)
			(layers "F.Cu" "F.Mask" "F.Paste")
			(net "PWRGD_P1V2_AUX_FPGA")
		)
		(pad "P18" smd circle
			(at 5.199888 1.999996)
			(size 0.4064 0.4064)
			(layers "F.Cu" "F.Mask" "F.Paste")
			(net "NIC0_MAIN_PWR_BIC_EN_R")
		)
		(pad "P19" smd circle
			(at 5.999988 1.999996)
			(size 0.4064 0.4064)
			(layers "F.Cu" "F.Mask" "F.Paste")
			(net "RST_PEX_NIC0_PERST_R_N")
		)
		(pad "P20" smd circle
			(at 6.800088 1.999996)
			(size 0.4064 0.4064)
			(layers "F.Cu" "F.Mask" "F.Paste")
			(net "NIC7_CLK_EN_N")
		)
		(pad "P21" smd circle
			(at 7.599934 1.999996)
			(size 0.4064 0.4064)
			(layers "F.Cu" "F.Mask" "F.Paste")
			(net "PWRGD_P12V_NIC7_R")
		)
		(pad "P22" smd circle
			(at 8.400034 1.999996)
			(size 0.4064 0.4064)
			(layers "F.Cu" "F.Mask" "F.Paste")
			(net "RST_NIC7_PERST_N")
		)
		(pad "R1" smd circle
			(at -8.400034 2.800096)
			(size 0.4064 0.4064)
			(layers "F.Cu" "F.Mask" "F.Paste")
			(net "Net_1192")
		)
		(pad "R2" smd circle
			(at -7.599934 2.800096)
			(size 0.4064 0.4064)
			(layers "F.Cu" "F.Mask" "F.Paste")
			(net "PRSNT_SSD10_FPGA_N")
		)
		(pad "R3" smd circle
			(at -6.800088 2.800096)
			(size 0.4064 0.4064)
			(layers "F.Cu" "F.Mask" "F.Paste")
			(net "SSD9_PEX_PWR_EN_R")
		)
		(pad "R4" smd circle
			(at -5.999988 2.800096)
			(size 0.4064 0.4064)
			(layers "F.Cu" "F.Mask" "F.Paste")
			(net "PRSNT_SSD9_FPGA_N")
		)
		(pad "R5" smd circle
			(at -5.199888 2.800096)
			(size 0.4064 0.4064)
			(layers "F.Cu" "F.Mask" "F.Paste")
			(net "MB_3V3IO_RSVD3_ISO_R")
		)
		(pad "R6" smd circle
			(at -4.400042 2.800096)
			(size 0.4064 0.4064)
			(layers "F.Cu" "F.Mask" "F.Paste")
			(net "PRSNT_SSD8_FPGA_N")
		)
		(pad "R7" smd circle
			(at -3.599942 2.800096)
			(size 0.4064 0.4064)
			(layers "F.Cu" "F.Mask" "F.Paste")
			(net "MB_3V3IO_RSVD1_ISO_R")
		)
		(pad "R8" smd circle
			(at -2.800096 2.800096)
			(size 0.4064 0.4064)
			(layers "F.Cu" "F.Mask" "F.Paste")
			(net "GND")
		)
		(pad "R9" smd circle
			(at -1.999996 2.800096)
			(size 0.4064 0.4064)
			(layers "F.Cu" "F.Mask" "F.Paste")
			(net "P3V3_FPGA_VCCIO2")
		)
		(pad "R10" smd circle
			(at -1.199896 2.800096)
			(size 0.4064 0.4064)
			(layers "F.Cu" "F.Mask" "F.Paste")
			(net "P3V3_FPGA_VCCIO2")
		)
		(pad "R11" smd circle
			(at -0.40005 2.800096)
			(size 0.4064 0.4064)
			(layers "F.Cu" "F.Mask" "F.Paste")
			(net "P3V3_FPGA_VCCIO2")
		)
		(pad "R12" smd circle
			(at 0.40005 2.800096)
			(size 0.4064 0.4064)
			(layers "F.Cu" "F.Mask" "F.Paste")
			(net "P3V3_FPGA_VCCIO2")
		)
		(pad "R13" smd circle
			(at 1.199896 2.800096)
			(size 0.4064 0.4064)
			(layers "F.Cu" "F.Mask" "F.Paste")
			(net "P3V3_FPGA_VCCIO2")
		)
		(pad "R14" smd circle
			(at 1.999996 2.800096)
			(size 0.4064 0.4064)
			(layers "F.Cu" "F.Mask" "F.Paste")
			(net "P3V3_FPGA_VCCIO2")
		)
		(pad "R15" smd circle
			(at 2.800096 2.800096)
			(size 0.4064 0.4064)
			(layers "F.Cu" "F.Mask" "F.Paste")
			(net "GND")
		)
		(pad "R16" smd circle
			(at 3.599942 2.800096)
			(size 0.4064 0.4064)
			(layers "F.Cu" "F.Mask" "F.Paste")
			(net "RST_MB_BIC_ISO_R_N")
		)
		(pad "R17" smd circle
			(at 4.400042 2.800096)
			(size 0.4064 0.4064)
			(layers "F.Cu" "F.Mask" "F.Paste")
			(net "NIC2_MAIN_PWR_BIC_EN_R")
		)
		(pad "R18" smd circle
			(at 5.199888 2.800096)
			(size 0.4064 0.4064)
			(layers "F.Cu" "F.Mask" "F.Paste")
			(net "RST_PEX_NIC2_PERST_R_N")
		)
		(pad "R19" smd circle
			(at 5.999988 2.800096)
			(size 0.4064 0.4064)
			(layers "F.Cu" "F.Mask" "F.Paste")
			(net "NIC2_PEX_PWR_EN_R")
		)
		(pad "R20" smd circle
			(at 6.800088 2.800096)
			(size 0.4064 0.4064)
			(layers "F.Cu" "F.Mask" "F.Paste")
			(net "PRSNT_NIC2_FPGA_N")
		)
		(pad "R21" smd circle
			(at 7.599934 2.800096)
			(size 0.4064 0.4064)
			(layers "F.Cu" "F.Mask" "F.Paste")
			(net "NIC7_MAIN_PWR_EN")
		)
		(pad "R22" smd circle
			(at 8.400034 2.800096)
			(size 0.4064 0.4064)
			(layers "F.Cu" "F.Mask" "F.Paste")
			(net "PWRGD_NIC7_PWR_GOOD_R")
		)
		(pad "T1" smd circle
			(at -8.400034 3.599942)
			(size 0.4064 0.4064)
			(layers "F.Cu" "F.Mask" "F.Paste")
			(net "MB_3V3IO_RSVD4_ISO_R")
		)
		(pad "T2" smd circle
			(at -7.599934 3.599942)
			(size 0.4064 0.4064)
			(layers "F.Cu" "F.Mask" "F.Paste")
			(net "RST_PEX_SSD8_PERST_R_N")
		)
		(pad "T3" smd circle
			(at -6.800088 3.599942)
			(size 0.4064 0.4064)
			(layers "F.Cu" "F.Mask" "F.Paste")
			(net "SSD7_PWRDIS_BIC_R")
		)
		(pad "T4" smd circle
			(at -5.999988 3.599942)
			(size 0.4064 0.4064)
			(layers "F.Cu" "F.Mask" "F.Paste")
			(net "RST_PEX_SSD7_PERST_R_N")
		)
		(pad "T5" smd circle
			(at -5.199888 3.599942)
			(size 0.4064 0.4064)
			(layers "F.Cu" "F.Mask" "F.Paste")
			(net "SSD7_PEX_PWR_EN_R")
		)
		(pad "T6" smd circle
			(at -4.400042 3.599942)
			(size 0.4064 0.4064)
			(layers "F.Cu" "F.Mask" "F.Paste")
			(net "PRSNT_SSD7_FPGA_N")
		)
		(pad "T7" smd circle
			(at -3.599942 3.599942)
			(size 0.4064 0.4064)
			(layers "F.Cu" "F.Mask" "F.Paste")
			(net "PRSNT_SSD11_FPGA_N")
		)
		(pad "T8" smd circle
			(at -2.800096 3.599942)
			(size 0.4064 0.4064)
			(layers "F.Cu" "F.Mask" "F.Paste")
			(net "SSD9_PWRDIS")
		)
		(pad "T9" smd circle
			(at -1.999996 3.599942)
			(size 0.4064 0.4064)
			(layers "F.Cu" "F.Mask" "F.Paste")
			(net "SSD11_PWR_EN")
		)
		(pad "T10" smd circle
			(at -1.199896 3.599942)
			(size 0.4064 0.4064)
			(layers "F.Cu" "F.Mask" "F.Paste")
			(net "SSD12_CLK_EN_N")
		)
		(pad "T11" smd circle
			(at -0.40005 3.599942)
			(size 0.4064 0.4064)
			(layers "F.Cu" "F.Mask" "F.Paste")
			(net "PRSNT_SSD14_R_N")
		)
		(pad "T12" smd circle
			(at 0.40005 3.599942)
			(size 0.4064 0.4064)
			(layers "F.Cu" "F.Mask" "F.Paste")
			(net "FM_PFR_LED_AMBER")
		)
		(pad "T13" smd circle
			(at 1.199896 3.599942)
			(size 0.4064 0.4064)
			(layers "F.Cu" "F.Mask" "F.Paste")
			(net "SSD0_PEX_PWR_EN_R")
		)
		(pad "T14" smd circle
			(at 1.999996 3.599942)
			(size 0.4064 0.4064)
			(layers "F.Cu" "F.Mask" "F.Paste")
			(net "RST_PEX_SSD0_PERST_R_N")
		)
		(pad "T15" smd circle
			(at 2.800096 3.599942)
			(size 0.4064 0.4064)
			(layers "F.Cu" "F.Mask" "F.Paste")
			(net "RST_PEX_SSD5_PERST_R_N")
		)
		(pad "T16" smd circle
			(at 3.599942 3.599942)
			(size 0.4064 0.4064)
			(layers "F.Cu" "F.Mask" "F.Paste")
			(net "FPGA_PEX3_MODE_SEL1")
		)
		(pad "T17" smd circle
			(at 4.400042 3.599942)
			(size 0.4064 0.4064)
			(layers "F.Cu" "F.Mask" "F.Paste")
			(net "NIC3_MAIN_PWR_BIC_EN_R")
		)
		(pad "T18" smd circle
			(at 5.199888 3.599942)
			(size 0.4064 0.4064)
			(layers "F.Cu" "F.Mask" "F.Paste")
			(net "RST_PEX_NIC3_PERST_R_N")
		)
		(pad "T19" smd circle
			(at 5.999988 3.599942)
			(size 0.4064 0.4064)
			(layers "F.Cu" "F.Mask" "F.Paste")
			(net "NIC3_PEX_PWR_EN_R")
		)
		(pad "T20" smd circle
			(at 6.800088 3.599942)
			(size 0.4064 0.4064)
			(layers "F.Cu" "F.Mask" "F.Paste")
			(net "PRSNT_NIC3_FPGA_N")
		)
		(pad "T21" smd circle
			(at 7.599934 3.599942)
			(size 0.4064 0.4064)
			(layers "F.Cu" "F.Mask" "F.Paste")
			(net "NIC0_PEX_PWR_EN_R")
		)
		(pad "T22" smd circle
			(at 8.400034 3.599942)
			(size 0.4064 0.4064)
			(layers "F.Cu" "F.Mask" "F.Paste")
			(net "PRSNT_NIC0_FPGA_N")
		)
		(pad "U1" smd circle
			(at -8.400034 4.400042)
			(size 0.4064 0.4064)
			(layers "F.Cu" "F.Mask" "F.Paste")
			(net "SSD8_PEX_PWR_EN_R")
		)
		(pad "U2" smd circle
			(at -7.599934 4.400042)
			(size 0.4064 0.4064)
			(layers "F.Cu" "F.Mask" "F.Paste")
			(net "CLK_25M_FPGA_R")
		)
		(pad "U3" smd circle
			(at -6.800088 4.400042)
			(size 0.4064 0.4064)
			(layers "F.Cu" "F.Mask" "F.Paste")
			(net "SSD13_PWRDIS_BIC_R")
		)
		(pad "U4" smd circle
			(at -5.999988 4.400042)
			(size 0.4064 0.4064)
			(layers "F.Cu" "F.Mask" "F.Paste")
			(net "RST_PEX_SSD13_PERST_R_N")
		)
		(pad "U5" smd circle
			(at -5.199888 4.400042)
			(size 0.4064 0.4064)
			(layers "F.Cu" "F.Mask" "F.Paste")
			(net "SSD12_PWRDIS_BIC_R")
		)
		(pad "U6" smd circle
			(at -4.400042 4.400042)
			(size 0.4064 0.4064)
			(layers "F.Cu" "F.Mask" "F.Paste")
			(net "SSD8_PWR_EN")
		)
		(pad "U7" smd circle
			(at -3.599942 4.400042)
			(size 0.4064 0.4064)
			(layers "F.Cu" "F.Mask" "F.Paste")
			(net "SSD9_PWR_EN")
		)
		(pad "U8" smd circle
			(at -2.800096 4.400042)
			(size 0.4064 0.4064)
			(layers "F.Cu" "F.Mask" "F.Paste")
			(net "PWRGD_P3V3_SSD11_R")
		)
		(pad "U9" smd circle
			(at -1.999996 4.400042)
			(size 0.4064 0.4064)
			(layers "F.Cu" "F.Mask" "F.Paste")
			(net "SSD11_PWRDIS")
		)
		(pad "U10" smd circle
			(at -1.199896 4.400042)
			(size 0.4064 0.4064)
			(layers "F.Cu" "F.Mask" "F.Paste")
			(net "PRSNT_SSD13_R_N")
		)
		(pad "U11" smd circle
			(at -0.40005 4.400042)
			(size 0.4064 0.4064)
			(layers "F.Cu" "F.Mask" "F.Paste")
			(net "PWRGD_P12V_SSD14_R")
		)
		(pad "U12" smd circle
			(at 0.40005 4.400042)
			(size 0.4064 0.4064)
			(layers "F.Cu" "F.Mask" "F.Paste")
			(net "FM_PFR_LED_BLUE")
		)
		(pad "U13" smd circle
			(at 1.199896 4.400042)
			(size 0.4064 0.4064)
			(layers "F.Cu" "F.Mask" "F.Paste")
			(net "SSD15_PWR_EN")
		)
		(pad "U14" smd circle
			(at 1.999996 4.400042)
			(size 0.4064 0.4064)
			(layers "F.Cu" "F.Mask" "F.Paste")
			(net "SSD0_PWRDIS_BIC_R")
		)
		(pad "U15" smd circle
			(at 2.800096 4.400042)
			(size 0.4064 0.4064)
			(layers "F.Cu" "F.Mask" "F.Paste")
			(net "SSD3_PEX_PWR_EN_R")
		)
		(pad "U16" smd circle
			(at 3.599942 4.400042)
			(size 0.4064 0.4064)
			(layers "F.Cu" "F.Mask" "F.Paste")
			(net "SSD5_PWRDIS_BIC_R")
		)
		(pad "U17" smd circle
			(at 4.400042 4.400042)
			(size 0.4064 0.4064)
			(layers "F.Cu" "F.Mask" "F.Paste")
			(net "NIC5_PEX_PWR_EN_R")
		)
		(pad "U18" smd circle
			(at 5.199888 4.400042)
			(size 0.4064 0.4064)
			(layers "F.Cu" "F.Mask" "F.Paste")
			(net "NIC4_MAIN_PWR_BIC_EN_R")
		)
		(pad "U19" smd circle
			(at 5.999988 4.400042)
			(size 0.4064 0.4064)
			(layers "F.Cu" "F.Mask" "F.Paste")
			(net "RST_PEX_NIC4_PERST_R_N")
		)
		(pad "U20" smd circle
			(at 6.800088 4.400042)
			(size 0.4064 0.4064)
			(layers "F.Cu" "F.Mask" "F.Paste")
			(net "PWRGD_PEX1_P1V8_PLL_R")
		)
		(pad "U21" smd circle
			(at 7.599934 4.400042)
			(size 0.4064 0.4064)
			(layers "F.Cu" "F.Mask" "F.Paste")
			(net "RST_PEX_NIC1_PERST_R_N")
		)
		(pad "U22" smd circle
			(at 8.400034 4.400042)
			(size 0.4064 0.4064)
			(layers "F.Cu" "F.Mask" "F.Paste")
			(net "NIC1_PEX_PWR_EN_R")
		)
		(pad "V1" smd circle
			(at -8.400034 5.199888)
			(size 0.4064 0.4064)
			(layers "F.Cu" "F.Mask" "F.Paste")
			(net "GPU_3V3IO_RSVD4_ISO_R")
		)
		(pad "V2" smd circle
			(at -7.599934 5.199888)
			(size 0.4064 0.4064)
			(layers "F.Cu" "F.Mask" "F.Paste")
			(net "GND")
		)
		(pad "V3" smd circle
			(at -6.800088 5.199888)
			(size 0.4064 0.4064)
			(layers "F.Cu" "F.Mask" "F.Paste")
			(net "P3V3_FPGA_VCCIO3")
		)
		(pad "V4" smd circle
			(at -5.999988 5.199888)
			(size 0.4064 0.4064)
			(layers "F.Cu" "F.Mask" "F.Paste")
			(net "GPU_3V3IO_RSVD3_ISO_R")
		)
		(pad "V5" smd circle
			(at -5.199888 5.199888)
			(size 0.4064 0.4064)
			(layers "F.Cu" "F.Mask" "F.Paste")
			(net "SSD11_PEX_PWR_EN_R")
		)
		(pad "V6" smd circle
			(at -4.400042 5.199888)
			(size 0.4064 0.4064)
			(layers "F.Cu" "F.Mask" "F.Paste")
			(net "PWRGD_P3V3_SSD8_R")
		)
		(pad "V7" smd circle
			(at -3.599942 5.199888)
			(size 0.4064 0.4064)
			(layers "F.Cu" "F.Mask" "F.Paste")
			(net "RST_SSD10_PERST_N")
		)
		(pad "V8" smd circle
			(at -2.800096 5.199888)
			(size 0.4064 0.4064)
			(layers "F.Cu" "F.Mask" "F.Paste")
			(net "PWRGD_P12V_SSD11_R")
		)
		(pad "V9" smd circle
			(at -1.999996 5.199888)
			(size 0.4064 0.4064)
			(layers "F.Cu" "F.Mask" "F.Paste")
			(net "RST_SSD11_PERST_N")
		)
		(pad "V10" smd circle
			(at -1.199896 5.199888)
			(size 0.4064 0.4064)
			(layers "F.Cu" "F.Mask" "F.Paste")
			(net "PWRGD_P12V_SSD13_R")
		)
		(pad "V11" smd circle
			(at -0.40005 5.199888)
			(size 0.4064 0.4064)
			(layers "F.Cu" "F.Mask" "F.Paste")
			(net "SSD14_PWRDIS")
		)
		(pad "V12" smd circle
			(at 0.40005 5.199888)
			(size 0.4064 0.4064)
			(layers "F.Cu" "F.Mask" "F.Paste")
			(net "RST_SMB_FPGA_R_N")
		)
		(pad "V13" smd circle
			(at 1.199896 5.199888)
			(size 0.4064 0.4064)
			(layers "F.Cu" "F.Mask" "F.Paste")
			(net "PWRGD_P3V3_SSD15_R")
		)
		(pad "V14" smd circle
			(at 1.999996 5.199888)
			(size 0.4064 0.4064)
			(layers "F.Cu" "F.Mask" "F.Paste")
			(net "FPGA_PEX0_MODE_SEL2")
		)
		(pad "V15" smd circle
			(at 2.800096 5.199888)
			(size 0.4064 0.4064)
			(layers "F.Cu" "F.Mask" "F.Paste")
			(net "PRSNT_SSD3_FPGA_N")
		)
		(pad "V16" smd circle
			(at 3.599942 5.199888)
			(size 0.4064 0.4064)
			(layers "F.Cu" "F.Mask" "F.Paste")
			(net "PRSNT_SSD4_FPGA_N")
		)
		(pad "V17" smd circle
			(at 4.400042 5.199888)
			(size 0.4064 0.4064)
			(layers "F.Cu" "F.Mask" "F.Paste")
			(net "SSD6_PWRDIS_BIC_R")
		)
		(pad "V18" smd circle
			(at 5.199888 5.199888)
			(size 0.4064 0.4064)
			(layers "F.Cu" "F.Mask" "F.Paste")
			(net "NIC5_MAIN_PWR_BIC_EN_R")
		)
		(pad "V19" smd circle
			(at 5.999988 5.199888)
			(size 0.4064 0.4064)
			(layers "F.Cu" "F.Mask" "F.Paste")
			(net "RST_PEX_NIC5_PERST_R_N")
		)
		(pad "V20" smd circle
			(at 6.800088 5.199888)
			(size 0.4064 0.4064)
			(layers "F.Cu" "F.Mask" "F.Paste")
			(net "P3V3_FPGA_VCCIO1")
		)
		(pad "V21" smd circle
			(at 7.599934 5.199888)
			(size 0.4064 0.4064)
			(layers "F.Cu" "F.Mask" "F.Paste")
			(net "GND")
		)
		(pad "V22" smd circle
			(at 8.400034 5.199888)
			(size 0.4064 0.4064)
			(layers "F.Cu" "F.Mask" "F.Paste")
			(net "NIC1_MAIN_PWR_BIC_EN_R")
		)
		(pad "W1" smd circle
			(at -8.400034 5.999988)
			(size 0.4064 0.4064)
			(layers "F.Cu" "F.Mask" "F.Paste")
			(net "SSD13_PEX_PWR_EN_R")
		)
		(pad "W2" smd circle
			(at -7.599934 5.999988)
			(size 0.4064 0.4064)
			(layers "F.Cu" "F.Mask" "F.Paste")
			(net "PRSNT_SSD13_FPGA_N")
		)
		(pad "W3" smd circle
			(at -6.800088 5.999988)
			(size 0.4064 0.4064)
			(layers "F.Cu" "F.Mask" "F.Paste")
			(net "PRSNT_SSD12_FPGA_N")
		)
		(pad "W4" smd circle
			(at -5.999988 5.999988)
			(size 0.4064 0.4064)
			(layers "F.Cu" "F.Mask" "F.Paste")
			(net "RST_PEX_SSD11_PERST_R_N")
		)
		(pad "W5" smd circle
			(at -5.199888 5.999988)
			(size 0.4064 0.4064)
			(layers "F.Cu" "F.Mask" "F.Paste")
			(net "PRSNT_SSD9_R_N")
		)
		(pad "W6" smd circle
			(at -4.400042 5.999988)
			(size 0.4064 0.4064)
			(layers "F.Cu" "F.Mask" "F.Paste")
			(net "SSD10_PWRDIS")
		)
		(pad "W7" smd circle
			(at -3.599942 5.999988)
			(size 0.4064 0.4064)
			(layers "F.Cu" "F.Mask" "F.Paste")
			(net "P3V3_FPGA_VCCIO2")
		)
		(pad "W8" smd circle
			(at -2.800096 5.999988)
			(size 0.4064 0.4064)
			(layers "F.Cu" "F.Mask" "F.Paste")
			(net "SSD11_CLK_EN_N")
		)
		(pad "W9" smd circle
			(at -1.999996 5.999988)
			(size 0.4064 0.4064)
			(layers "F.Cu" "F.Mask" "F.Paste")
			(net "SSD12_PWR_EN")
		)
		(pad "W10" smd circle
			(at -1.199896 5.999988)
			(size 0.4064 0.4064)
			(layers "F.Cu" "F.Mask" "F.Paste")
			(net "PWRGD_P3V3_SSD13_R")
		)
		(pad "W11" smd circle
			(at -0.40005 5.999988)
			(size 0.4064 0.4064)
			(layers "F.Cu" "F.Mask" "F.Paste")
			(net "P3V3_FPGA_VCCIO2")
		)
		(pad "W12" smd circle
			(at 0.40005 5.999988)
			(size 0.4064 0.4064)
			(layers "F.Cu" "F.Mask" "F.Paste")
			(net "GND")
		)
		(pad "W13" smd circle
			(at 1.199896 5.999988)
			(size 0.4064 0.4064)
			(layers "F.Cu" "F.Mask" "F.Paste")
			(net "PRSNT_SSD0_FPGA_N")
		)
		(pad "W14" smd circle
			(at 1.999996 5.999988)
			(size 0.4064 0.4064)
			(layers "F.Cu" "F.Mask" "F.Paste")
			(net "SSD1_PWRDIS_BIC_R")
		)
		(pad "W15" smd circle
			(at 2.800096 5.999988)
			(size 0.4064 0.4064)
			(layers "F.Cu" "F.Mask" "F.Paste")
			(net "RST_PEX_SSD2_PERST_R_N")
		)
		(pad "W16" smd circle
			(at 3.599942 5.999988)
			(size 0.4064 0.4064)
			(layers "F.Cu" "F.Mask" "F.Paste")
			(net "P3V3_FPGA_VCCIO2")
		)
		(pad "W17" smd circle
			(at 4.400042 5.999988)
			(size 0.4064 0.4064)
			(layers "F.Cu" "F.Mask" "F.Paste")
			(net "FPGA_PEX2_MODE_SEL2")
		)
		(pad "W18" smd circle
			(at 5.199888 5.999988)
			(size 0.4064 0.4064)
			(layers "F.Cu" "F.Mask" "F.Paste")
			(net "RST_PEX_SSD6_PERST_R_N")
		)
		(pad "W19" smd circle
			(at 5.999988 5.999988)
			(size 0.4064 0.4064)
			(layers "F.Cu" "F.Mask" "F.Paste")
			(net "RST_FPGA_BIC_N")
		)
		(pad "W20" smd circle
			(at 6.800088 5.999988)
			(size 0.4064 0.4064)
			(layers "F.Cu" "F.Mask" "F.Paste")
			(net "PWRGD_PEX3_P1V8_PLL_R")
		)
		(pad "W21" smd circle
			(at 7.599934 5.999988)
			(size 0.4064 0.4064)
			(layers "F.Cu" "F.Mask" "F.Paste")
			(net "NIC4_PEX_PWR_EN_R")
		)
		(pad "W22" smd circle
			(at 8.400034 5.999988)
			(size 0.4064 0.4064)
			(layers "F.Cu" "F.Mask" "F.Paste")
			(net "PWRGD_PEX0_P1V8_PLL_R")
		)
		(pad "Y1" smd circle
			(at -8.400034 6.800088)
			(size 0.4064 0.4064)
			(layers "F.Cu" "F.Mask" "F.Paste")
			(net "RST_PEX_SSD12_PERST_R_N")
		)
		(pad "Y2" smd circle
			(at -7.599934 6.800088)
			(size 0.4064 0.4064)
			(layers "F.Cu" "F.Mask" "F.Paste")
			(net "GPU_3V3IO_RSVD1_ISO_R")
		)
		(pad "Y3" smd circle
			(at -6.800088 6.800088)
			(size 0.4064 0.4064)
			(layers "F.Cu" "F.Mask" "F.Paste")
			(net "SSD11_PWRDIS_BIC_R")
		)
		(pad "Y4" smd circle
			(at -5.999988 6.800088)
			(size 0.4064 0.4064)
			(layers "F.Cu" "F.Mask" "F.Paste")
			(net "SSD8_CLK_EN_N")
		)
		(pad "Y5" smd circle
			(at -5.199888 6.800088)
			(size 0.4064 0.4064)
			(layers "F.Cu" "F.Mask" "F.Paste")
			(net "PRSNT_SSD10_R_N")
		)
		(pad "Y6" smd circle
			(at -4.400042 6.800088)
			(size 0.4064 0.4064)
			(layers "F.Cu" "F.Mask" "F.Paste")
			(net "PWRGD_P12V_SSD10_R")
		)
		(pad "Y7" smd circle
			(at -3.599942 6.800088)
			(size 0.4064 0.4064)
			(layers "F.Cu" "F.Mask" "F.Paste")
			(net "GND")
		)
		(pad "Y8" smd circle
			(at -2.800096 6.800088)
			(size 0.4064 0.4064)
			(layers "F.Cu" "F.Mask" "F.Paste")
			(net "PWRGD_P3V3_SSD12_R")
		)
		(pad "Y9" smd circle
			(at -1.999996 6.800088)
			(size 0.4064 0.4064)
			(layers "F.Cu" "F.Mask" "F.Paste")
			(net "SSD13_PWR_EN")
		)
		(pad "Y10" smd circle
			(at -1.199896 6.800088)
			(size 0.4064 0.4064)
			(layers "F.Cu" "F.Mask" "F.Paste")
			(net "SSD13_PWRDIS")
		)
		(pad "Y11" smd circle
			(at -0.40005 6.800088)
			(size 0.4064 0.4064)
			(layers "F.Cu" "F.Mask" "F.Paste")
			(net "RST_SSD14_PERST_N")
		)
		(pad "Y12" smd circle
			(at 0.40005 6.800088)
			(size 0.4064 0.4064)
			(layers "F.Cu" "F.Mask" "F.Paste")
			(net "SSD14_CLK_EN_N")
		)
		(pad "Y13" smd circle
			(at 1.199896 6.800088)
			(size 0.4064 0.4064)
			(layers "F.Cu" "F.Mask" "F.Paste")
			(net "SSD15_CLK_EN_N")
		)
		(pad "Y14" smd circle
			(at 1.999996 6.800088)
			(size 0.4064 0.4064)
			(layers "F.Cu" "F.Mask" "F.Paste")
			(net "RST_PEX_SSD1_PERST_R_N")
		)
		(pad "Y15" smd circle
			(at 2.800096 6.800088)
			(size 0.4064 0.4064)
			(layers "F.Cu" "F.Mask" "F.Paste")
			(net "SSD2_PEX_PWR_EN_R")
		)
		(pad "Y16" smd circle
			(at 3.599942 6.800088)
			(size 0.4064 0.4064)
			(layers "F.Cu" "F.Mask" "F.Paste")
			(net "GND")
		)
		(pad "Y17" smd circle
			(at 4.400042 6.800088)
			(size 0.4064 0.4064)
			(layers "F.Cu" "F.Mask" "F.Paste")
			(net "FPGA_PEX1_MODE_SEL1")
		)
		(pad "Y18" smd circle
			(at 5.199888 6.800088)
			(size 0.4064 0.4064)
			(layers "F.Cu" "F.Mask" "F.Paste")
			(net "SSD4_PWRDIS_BIC_R")
		)
		(pad "Y19" smd circle
			(at 5.999988 6.800088)
			(size 0.4064 0.4064)
			(layers "F.Cu" "F.Mask" "F.Paste")
			(net "SSD6_PEX_PWR_EN_R")
		)
		(pad "Y20" smd circle
			(at 6.800088 6.800088)
			(size 0.4064 0.4064)
			(layers "F.Cu" "F.Mask" "F.Paste")
			(net "RST_FT4232_N")
		)
		(pad "Y21" smd circle
			(at 7.599934 6.800088)
			(size 0.4064 0.4064)
			(layers "F.Cu" "F.Mask" "F.Paste")
			(net "PRSNT_NIC5_FPGA_N")
		)
		(pad "Y22" smd circle
			(at 8.400034 6.800088)
			(size 0.4064 0.4064)
			(layers "F.Cu" "F.Mask" "F.Paste")
			(net "PRSNT_NIC4_FPGA_N")
		)
		(zone
			(layer "F.Cu")
			(hatch none 0.5)
			(connect_pads
				(clearance 0)
			)
			(min_thickness 0.25)
			(keepout
				(tracks allowed)
				(vias not_allowed)
				(pads allowed)
				(copperpour not_allowed)
				(footprints allowed)
			)
			(placement
				(enabled no)
				(sheetname "")
			)
			(fill
				(thermal_gap 0.5)
				(thermal_bridge_width 0.5)
				(island_removal_mode 0)
			)
			(polygon
				(pts
					(xy 342.347804 -210.17103) (xy 342.347804 -219.441014) (xy 333.07782 -219.441014) (xy 333.07782 -219.733114)
					(xy 342.347804 -219.733114) (xy 342.347804 -229.003098) (xy 342.639904 -229.003098) (xy 342.639904 -219.733114)
					(xy 351.909888 -219.733114) (xy 351.909888 -219.441014) (xy 342.639904 -219.441014) (xy 342.639904 -210.17103)
				)
			)
		)
	)
	(footprint ""
		(layer "F.Cu")
		(at 37.004752 -141.87297 180)
		(property "Reference" "R31"
			(at 0 0 180)
			(layer "F.SilkS")
			(hide yes)
			(effects
				(font
					(size 1.27 1.27)
				)
			)
		)
		(property "Value" ""
			(at 0 0 180)
			(layer "F.Fab")
			(effects
				(font
					(size 1.27 1.27)
				)
			)
		)
		(duplicate_pad_numbers_are_jumpers no)
		(fp_line
			(start 0.7874 0.4064)
			(end -0.7874 0.4064)
			(stroke
				(width 0.1524)
				(type default)
			)
			(layer "F.SilkS")
		)
		(fp_line
			(start 0.7874 -0.4064)
			(end 0.7874 0.4064)
			(stroke
				(width 0.1524)
				(type default)
			)
			(layer "F.SilkS")
		)
		(fp_line
			(start -0.7874 0.4064)
			(end -0.7874 -0.4064)
			(stroke
				(width 0.1524)
				(type default)
			)
			(layer "F.SilkS")
		)
		(fp_line
			(start -0.7874 -0.4064)
			(end 0.7874 -0.4064)
			(stroke
				(width 0.1524)
				(type default)
			)
			(layer "F.SilkS")
		)
		(fp_line
			(start 0.67945 0.3048)
			(end 0.120396 0.3048)
			(stroke
				(width 0.1)
				(type default)
			)
			(layer "F.Fab")
		)
		(fp_line
			(start 0.67945 -0.3048)
			(end 0.67945 0.3048)
			(stroke
				(width 0.1)
				(type default)
			)
			(layer "F.Fab")
		)
		(fp_line
			(start 0.12065 -0.2794)
			(end 0.12065 -0.3048)
			(stroke
				(width 0.1)
				(type default)
			)
			(layer "F.Fab")
		)
		(fp_line
			(start 0.12065 -0.3048)
			(end 0.67945 -0.3048)
			(stroke
				(width 0.1)
				(type default)
			)
			(layer "F.Fab")
		)
		(fp_line
			(start 0.120396 0.3048)
			(end 0.120396 0.2794)
			(stroke
				(width 0.1)
				(type default)
			)
			(layer "F.Fab")
		)
		(fp_line
			(start 0.120396 0.2794)
			(end -0.12065 0.2794)
			(stroke
				(width 0.1)
				(type default)
			)
			(layer "F.Fab")
		)
		(fp_line
			(start -0.12065 0.3048)
			(end -0.67945 0.3048)
			(stroke
				(width 0.1)
				(type default)
			)
			(layer "F.Fab")
		)
		(fp_line
			(start -0.12065 0.2794)
			(end -0.12065 0.3048)
			(stroke
				(width 0.1)
				(type default)
			)
			(layer "F.Fab")
		)
		(fp_line
			(start -0.12065 -0.2794)
			(end 0.12065 -0.2794)
			(stroke
				(width 0.1)
				(type default)
			)
			(layer "F.Fab")
		)
		(fp_line
			(start -0.12065 -0.305054)
			(end -0.12065 -0.2794)
			(stroke
				(width 0.1)
				(type default)
			)
			(layer "F.Fab")
		)
		(fp_line
			(start -0.67945 0.3048)
			(end -0.67945 -0.305054)
			(stroke
				(width 0.1)
				(type default)
			)
			(layer "F.Fab")
		)
		(fp_line
			(start -0.67945 -0.305054)
			(end -0.12065 -0.305054)
			(stroke
				(width 0.1)
				(type default)
			)
			(layer "F.Fab")
		)
		(pad "1" smd circle
			(at -0.40005 0 180)
			(size 0 0)
			(layers "F.Cu" "F.Mask" "F.Paste")
			(net "NIC0_BIF1_N")
		)
		(pad "2" smd circle
			(at 0.40005 0 180)
			(size 0 0)
			(layers "F.Cu" "F.Mask" "F.Paste")
			(net "P3V3_AUX")
		)
	)
	(footprint ""
		(layer "F.Cu")
		(at 180.814472 -350.098614 90)
		(property "Reference" "C2530"
			(at 0 0 90)
			(layer "F.SilkS")
			(hide yes)
			(effects
				(font
					(size 1.27 1.27)
				)
			)
		)
		(property "Value" ""
			(at 0 0 90)
			(layer "F.Fab")
			(effects
				(font
					(size 1.27 1.27)
				)
			)
		)
		(duplicate_pad_numbers_are_jumpers no)
		(fp_line
			(start 0.299974 -0.150114)
			(end 0.299974 0.150114)
			(stroke
				(width 0.1)
				(type default)
			)
			(layer "F.Fab")
		)
		(fp_line
			(start -0.299974 -0.150114)
			(end 0.299974 -0.150114)
			(stroke
				(width 0.1)
				(type default)
			)
			(layer "F.Fab")
		)
		(fp_line
			(start 0.299974 0.150114)
			(end -0.299974 0.150114)
			(stroke
				(width 0.1)
				(type default)
			)
			(layer "F.Fab")
		)
		(fp_line
			(start -0.299974 0.150114)
			(end -0.299974 -0.150114)
			(stroke
				(width 0.1)
				(type default)
			)
			(layer "F.Fab")
		)
		(pad "1" smd rect
			(at -0.2667 0 90)
			(size 0.3048 0.381)
			(layers "F.Cu" "F.Mask" "F.Paste")
			(net "P5E_PEX1_STN4_TX_DP<70>")
		)
		(pad "2" smd rect
			(at 0.2667 0 90)
			(size 0.3048 0.381)
			(layers "F.Cu" "F.Mask" "F.Paste")
			(net "P5E_PEX1_STN4_TX_C_DP<70>")
		)
	)
	(footprint ""
		(layer "F.Cu")
		(at 197.25513 -53.468524 90)
		(property "Reference" "PC497"
			(at 0 0 90)
			(layer "F.SilkS")
			(hide yes)
			(effects
				(font
					(size 1.27 1.27)
				)
			)
		)
		(property "Value" ""
			(at 0 0 90)
			(layer "F.Fab")
			(effects
				(font
					(size 1.27 1.27)
				)
			)
		)
		(duplicate_pad_numbers_are_jumpers no)
		(fp_line
			(start 1.524 -0.762)
			(end 1.524 0.762)
			(stroke
				(width 0.1524)
				(type default)
			)
			(layer "F.SilkS")
		)
		(fp_line
			(start -1.524 -0.762)
			(end 1.524 -0.762)
			(stroke
				(width 0.1524)
				(type default)
			)
			(layer "F.SilkS")
		)
		(fp_line
			(start 1.524 0.762)
			(end -1.524 0.762)
			(stroke
				(width 0.1524)
				(type default)
			)
			(layer "F.SilkS")
		)
		(fp_line
			(start -1.524 0.762)
			(end -1.524 -0.762)
			(stroke
				(width 0.1524)
				(type default)
			)
			(layer "F.SilkS")
		)
		(fp_line
			(start 1.1049 -0.724916)
			(end -1.1049 -0.724916)
			(stroke
				(width 0.1)
				(type default)
			)
			(layer "F.Fab")
		)
		(fp_line
			(start -1.1049 -0.724916)
			(end -1.1049 0.724916)
			(stroke
				(width 0.1)
				(type default)
			)
			(layer "F.Fab")
		)
		(fp_line
			(start 1.1049 0.724916)
			(end 1.1049 -0.724916)
			(stroke
				(width 0.1)
				(type default)
			)
			(layer "F.Fab")
		)
		(fp_line
			(start -1.1049 0.724916)
			(end 1.1049 0.724916)
			(stroke
				(width 0.1)
				(type default)
			)
			(layer "F.Fab")
		)
		(pad "1" smd rect
			(at -0.889 0 270)
			(size 1.016 1.27)
			(layers "F.Cu" "F.Mask" "F.Paste")
			(net "GND")
		)
		(pad "2" smd rect
			(at 0.889 0 270)
			(size 1.016 1.27)
			(layers "F.Cu" "F.Mask" "F.Paste")
			(net "P3V3_AUX")
		)
	)
	(footprint ""
		(layer "F.Cu")
		(at 404.172166 -32.848042 90)
		(property "Reference" "PC971"
			(at 0 0 90)
			(layer "F.SilkS")
			(hide yes)
			(effects
				(font
					(size 1.27 1.27)
				)
			)
		)
		(property "Value" ""
			(at 0 0 90)
			(layer "F.Fab")
			(effects
				(font
					(size 1.27 1.27)
				)
			)
		)
		(duplicate_pad_numbers_are_jumpers no)
		(fp_line
			(start 0.7874 -0.4064)
			(end 0.7874 0.4064)
			(stroke
				(width 0.1524)
				(type default)
			)
			(layer "F.SilkS")
		)
		(fp_line
			(start -0.7874 -0.4064)
			(end 0.7874 -0.4064)
			(stroke
				(width 0.1524)
				(type default)
			)
			(layer "F.SilkS")
		)
		(fp_line
			(start 0.7874 0.4064)
			(end -0.7874 0.4064)
			(stroke
				(width 0.1524)
				(type default)
			)
			(layer "F.SilkS")
		)
		(fp_line
			(start -0.7874 0.4064)
			(end -0.7874 -0.4064)
			(stroke
				(width 0.1524)
				(type default)
			)
			(layer "F.SilkS")
		)
		(fp_line
			(start -0.12065 -0.305054)
			(end -0.12065 -0.2794)
			(stroke
				(width 0.1)
				(type default)
			)
			(layer "F.Fab")
		)
		(fp_line
			(start -0.67945 -0.305054)
			(end -0.12065 -0.305054)
			(stroke
				(width 0.1)
				(type default)
			)
			(layer "F.Fab")
		)
		(fp_line
			(start 0.67945 -0.3048)
			(end 0.67945 0.3048)
			(stroke
				(width 0.1)
				(type default)
			)
			(layer "F.Fab")
		)
		(fp_line
			(start 0.12065 -0.3048)
			(end 0.67945 -0.3048)
			(stroke
				(width 0.1)
				(type default)
			)
			(layer "F.Fab")
		)
		(fp_line
			(start 0.12065 -0.2794)
			(end 0.12065 -0.3048)
			(stroke
				(width 0.1)
				(type default)
			)
			(layer "F.Fab")
		)
		(fp_line
			(start -0.12065 -0.2794)
			(end 0.12065 -0.2794)
			(stroke
				(width 0.1)
				(type default)
			)
			(layer "F.Fab")
		)
		(fp_line
			(start 0.120396 0.2794)
			(end -0.12065 0.2794)
			(stroke
				(width 0.1)
				(type default)
			)
			(layer "F.Fab")
		)
		(fp_line
			(start -0.12065 0.2794)
			(end -0.12065 0.3048)
			(stroke
				(width 0.1)
				(type default)
			)
			(layer "F.Fab")
		)
		(fp_line
			(start 0.67945 0.3048)
			(end 0.120396 0.3048)
			(stroke
				(width 0.1)
				(type default)
			)
			(layer "F.Fab")
		)
		(fp_line
			(start 0.120396 0.3048)
			(end 0.120396 0.2794)
			(stroke
				(width 0.1)
				(type default)
			)
			(layer "F.Fab")
		)
		(fp_line
			(start -0.12065 0.3048)
			(end -0.67945 0.3048)
			(stroke
				(width 0.1)
				(type default)
			)
			(layer "F.Fab")
		)
		(fp_line
			(start -0.67945 0.3048)
			(end -0.67945 -0.305054)
			(stroke
				(width 0.1)
				(type default)
			)
			(layer "F.Fab")
		)
		(pad "1" smd circle
			(at -0.40005 0 90)
			(size 0 0)
			(layers "F.Cu" "F.Mask" "F.Paste")
			(net "P3V3_SSD14_CO_GATE")
		)
		(pad "2" smd circle
			(at 0.40005 0 90)
			(size 0 0)
			(layers "F.Cu" "F.Mask" "F.Paste")
			(net "GND")
		)
	)
	(footprint ""
		(layer "F.Cu")
		(at 129.129282 -280.44902 -90)
		(property "Reference" "PC115"
			(at 0 0 270)
			(layer "F.SilkS")
			(hide yes)
			(effects
				(font
					(size 1.27 1.27)
				)
			)
		)
		(property "Value" ""
			(at 0 0 270)
			(layer "F.Fab")
			(effects
				(font
					(size 1.27 1.27)
				)
			)
		)
		(duplicate_pad_numbers_are_jumpers no)
		(fp_line
			(start -0.7874 0.4064)
			(end -0.7874 -0.4064)
			(stroke
				(width 0.1524)
				(type default)
			)
			(layer "F.SilkS")
		)
		(fp_line
			(start 0.7874 0.4064)
			(end -0.7874 0.4064)
			(stroke
				(width 0.1524)
				(type default)
			)
			(layer "F.SilkS")
		)
		(fp_line
			(start -0.7874 -0.4064)
			(end 0.7874 -0.4064)
			(stroke
				(width 0.1524)
				(type default)
			)
			(layer "F.SilkS")
		)
		(fp_line
			(start 0.7874 -0.4064)
			(end 0.7874 0.4064)
			(stroke
				(width 0.1524)
				(type default)
			)
			(layer "F.SilkS")
		)
		(fp_line
			(start -0.67945 0.3048)
			(end -0.67945 -0.305054)
			(stroke
				(width 0.1)
				(type default)
			)
			(layer "F.Fab")
		)
		(fp_line
			(start -0.12065 0.3048)
			(end -0.67945 0.3048)
			(stroke
				(width 0.1)
				(type default)
			)
			(layer "F.Fab")
		)
		(fp_line
			(start 0.120396 0.3048)
			(end 0.120396 0.2794)
			(stroke
				(width 0.1)
				(type default)
			)
			(layer "F.Fab")
		)
		(fp_line
			(start 0.67945 0.3048)
			(end 0.120396 0.3048)
			(stroke
				(width 0.1)
				(type default)
			)
			(layer "F.Fab")
		)
		(fp_line
			(start -0.12065 0.2794)
			(end -0.12065 0.3048)
			(stroke
				(width 0.1)
				(type default)
			)
			(layer "F.Fab")
		)
		(fp_line
			(start 0.120396 0.2794)
			(end -0.12065 0.2794)
			(stroke
				(width 0.1)
				(type default)
			)
			(layer "F.Fab")
		)
		(fp_line
			(start -0.12065 -0.2794)
			(end 0.12065 -0.2794)
			(stroke
				(width 0.1)
				(type default)
			)
			(layer "F.Fab")
		)
		(fp_line
			(start 0.12065 -0.2794)
			(end 0.12065 -0.3048)
			(stroke
				(width 0.1)
				(type default)
			)
			(layer "F.Fab")
		)
		(fp_line
			(start 0.12065 -0.3048)
			(end 0.67945 -0.3048)
			(stroke
				(width 0.1)
				(type default)
			)
			(layer "F.Fab")
		)
		(fp_line
			(start 0.67945 -0.3048)
			(end 0.67945 0.3048)
			(stroke
				(width 0.1)
				(type default)
			)
			(layer "F.Fab")
		)
		(fp_line
			(start -0.67945 -0.305054)
			(end -0.12065 -0.305054)
			(stroke
				(width 0.1)
				(type default)
			)
			(layer "F.Fab")
		)
		(fp_line
			(start -0.12065 -0.305054)
			(end -0.12065 -0.2794)
			(stroke
				(width 0.1)
				(type default)
			)
			(layer "F.Fab")
		)
		(pad "1" smd circle
			(at -0.40005 0 270)
			(size 0 0)
			(layers "F.Cu" "F.Mask" "F.Paste")
			(net "SW_P0V8_PEX1_PHASE2")
		)
		(pad "2" smd circle
			(at 0.40005 0 270)
			(size 0 0)
			(layers "F.Cu" "F.Mask" "F.Paste")
			(net "SW_P0V8_PEX1_BOOT2_R")
		)
	)
	(footprint ""
		(layer "F.Cu")
		(at 218.247468 -251.163836 -90)
		(property "Reference" "C4300"
			(at 0 0 270)
			(layer "F.SilkS")
			(hide yes)
			(effects
				(font
					(size 1.27 1.27)
				)
			)
		)
		(property "Value" ""
			(at 0 0 270)
			(layer "F.Fab")
			(effects
				(font
					(size 1.27 1.27)
				)
			)
		)
		(duplicate_pad_numbers_are_jumpers no)
		(fp_line
			(start -1.524 0.762)
			(end -1.524 -0.762)
			(stroke
				(width 0.1524)
				(type default)
			)
			(layer "F.SilkS")
		)
		(fp_line
			(start 1.524 0.762)
			(end -1.524 0.762)
			(stroke
				(width 0.1524)
				(type default)
			)
			(layer "F.SilkS")
		)
		(fp_line
			(start -1.524 -0.762)
			(end 1.524 -0.762)
			(stroke
				(width 0.1524)
				(type default)
			)
			(layer "F.SilkS")
		)
		(fp_line
			(start 1.524 -0.762)
			(end 1.524 0.762)
			(stroke
				(width 0.1524)
				(type default)
			)
			(layer "F.SilkS")
		)
		(fp_line
			(start -1.1049 0.724916)
			(end 1.1049 0.724916)
			(stroke
				(width 0.1)
				(type default)
			)
			(layer "F.Fab")
		)
		(fp_line
			(start 1.1049 0.724916)
			(end 1.1049 -0.724916)
			(stroke
				(width 0.1)
				(type default)
			)
			(layer "F.Fab")
		)
		(fp_line
			(start -1.1049 -0.724916)
			(end -1.1049 0.724916)
			(stroke
				(width 0.1)
				(type default)
			)
			(layer "F.Fab")
		)
		(fp_line
			(start 1.1049 -0.724916)
			(end -1.1049 -0.724916)
			(stroke
				(width 0.1)
				(type default)
			)
			(layer "F.Fab")
		)
		(pad "1" smd rect
			(at -0.889 0 90)
			(size 1.016 1.27)
			(layers "F.Cu" "F.Mask" "F.Paste")
			(net "P1V25_SERDES_VDDPLL_PEX1_C10")
		)
		(pad "2" smd rect
			(at 0.889 0 90)
			(size 1.016 1.27)
			(layers "F.Cu" "F.Mask" "F.Paste")
			(net "GND")
		)
		(zone
			(layer "F.Cu")
			(hatch none 0.5)
			(connect_pads
				(clearance 0)
			)
			(min_thickness 0.25)
			(keepout
				(tracks not_allowed)
				(vias allowed)
				(pads allowed)
				(copperpour not_allowed)
				(footprints allowed)
			)
			(placement
				(enabled no)
				(sheetname "")
			)
			(fill
				(thermal_gap 0.5)
				(thermal_bridge_width 0.5)
				(island_removal_mode 0)
			)
			(polygon
				(pts
					(xy 218.972384 -251.494036) (xy 217.522552 -251.494036) (xy 217.522552 -250.833636) (xy 218.972384 -250.833636)
				)
			)
		)
	)
	(footprint ""
		(layer "F.Cu")
		(at 381.254 -206.502 180)
		(property "Reference" "R4615"
			(at 0 0 180)
			(layer "F.SilkS")
			(hide yes)
			(effects
				(font
					(size 1.27 1.27)
				)
			)
		)
		(property "Value" ""
			(at 0 0 180)
			(layer "F.Fab")
			(effects
				(font
					(size 1.27 1.27)
				)
			)
		)
		(duplicate_pad_numbers_are_jumpers no)
		(fp_line
			(start 0.7874 0.4064)
			(end -0.7874 0.4064)
			(stroke
				(width 0.1524)
				(type default)
			)
			(layer "F.SilkS")
		)
		(fp_line
			(start 0.7874 -0.4064)
			(end 0.7874 0.4064)
			(stroke
				(width 0.1524)
				(type default)
			)
			(layer "F.SilkS")
		)
		(fp_line
			(start -0.7874 0.4064)
			(end -0.7874 -0.4064)
			(stroke
				(width 0.1524)
				(type default)
			)
			(layer "F.SilkS")
		)
		(fp_line
			(start -0.7874 -0.4064)
			(end 0.7874 -0.4064)
			(stroke
				(width 0.1524)
				(type default)
			)
			(layer "F.SilkS")
		)
		(fp_line
			(start 0.67945 0.3048)
			(end 0.120396 0.3048)
			(stroke
				(width 0.1)
				(type default)
			)
			(layer "F.Fab")
		)
		(fp_line
			(start 0.67945 -0.3048)
			(end 0.67945 0.3048)
			(stroke
				(width 0.1)
				(type default)
			)
			(layer "F.Fab")
		)
		(fp_line
			(start 0.12065 -0.2794)
			(end 0.12065 -0.3048)
			(stroke
				(width 0.1)
				(type default)
			)
			(layer "F.Fab")
		)
		(fp_line
			(start 0.12065 -0.3048)
			(end 0.67945 -0.3048)
			(stroke
				(width 0.1)
				(type default)
			)
			(layer "F.Fab")
		)
		(fp_line
			(start 0.120396 0.3048)
			(end 0.120396 0.2794)
			(stroke
				(width 0.1)
				(type default)
			)
			(layer "F.Fab")
		)
		(fp_line
			(start 0.120396 0.2794)
			(end -0.12065 0.2794)
			(stroke
				(width 0.1)
				(type default)
			)
			(layer "F.Fab")
		)
		(fp_line
			(start -0.12065 0.3048)
			(end -0.67945 0.3048)
			(stroke
				(width 0.1)
				(type default)
			)
			(layer "F.Fab")
		)
		(fp_line
			(start -0.12065 0.2794)
			(end -0.12065 0.3048)
			(stroke
				(width 0.1)
				(type default)
			)
			(layer "F.Fab")
		)
		(fp_line
			(start -0.12065 -0.2794)
			(end 0.12065 -0.2794)
			(stroke
				(width 0.1)
				(type default)
			)
			(layer "F.Fab")
		)
		(fp_line
			(start -0.12065 -0.305054)
			(end -0.12065 -0.2794)
			(stroke
				(width 0.1)
				(type default)
			)
			(layer "F.Fab")
		)
		(fp_line
			(start -0.67945 0.3048)
			(end -0.67945 -0.305054)
			(stroke
				(width 0.1)
				(type default)
			)
			(layer "F.Fab")
		)
		(fp_line
			(start -0.67945 -0.305054)
			(end -0.12065 -0.305054)
			(stroke
				(width 0.1)
				(type default)
			)
			(layer "F.Fab")
		)
		(pad "1" smd circle
			(at -0.40005 0 180)
			(size 0 0)
			(layers "F.Cu" "F.Mask" "F.Paste")
			(net "NIC0_PEX_PWR_EN_R")
		)
		(pad "2" smd circle
			(at 0.40005 0 180)
			(size 0 0)
			(layers "F.Cu" "F.Mask" "F.Paste")
			(net "GND")
		)
	)
	(footprint ""
		(layer "F.Cu")
		(at 350.14027 -32.848042 90)
		(property "Reference" "PC963"
			(at 0 0 90)
			(layer "F.SilkS")
			(hide yes)
			(effects
				(font
					(size 1.27 1.27)
				)
			)
		)
		(property "Value" ""
			(at 0 0 90)
			(layer "F.Fab")
			(effects
				(font
					(size 1.27 1.27)
				)
			)
		)
		(duplicate_pad_numbers_are_jumpers no)
		(fp_line
			(start 0.7874 -0.4064)
			(end 0.7874 0.4064)
			(stroke
				(width 0.1524)
				(type default)
			)
			(layer "F.SilkS")
		)
		(fp_line
			(start -0.7874 -0.4064)
			(end 0.7874 -0.4064)
			(stroke
				(width 0.1524)
				(type default)
			)
			(layer "F.SilkS")
		)
		(fp_line
			(start 0.7874 0.4064)
			(end -0.7874 0.4064)
			(stroke
				(width 0.1524)
				(type default)
			)
			(layer "F.SilkS")
		)
		(fp_line
			(start -0.7874 0.4064)
			(end -0.7874 -0.4064)
			(stroke
				(width 0.1524)
				(type default)
			)
			(layer "F.SilkS")
		)
		(fp_line
			(start -0.12065 -0.305054)
			(end -0.12065 -0.2794)
			(stroke
				(width 0.1)
				(type default)
			)
			(layer "F.Fab")
		)
		(fp_line
			(start -0.67945 -0.305054)
			(end -0.12065 -0.305054)
			(stroke
				(width 0.1)
				(type default)
			)
			(layer "F.Fab")
		)
		(fp_line
			(start 0.67945 -0.3048)
			(end 0.67945 0.3048)
			(stroke
				(width 0.1)
				(type default)
			)
			(layer "F.Fab")
		)
		(fp_line
			(start 0.12065 -0.3048)
			(end 0.67945 -0.3048)
			(stroke
				(width 0.1)
				(type default)
			)
			(layer "F.Fab")
		)
		(fp_line
			(start 0.12065 -0.2794)
			(end 0.12065 -0.3048)
			(stroke
				(width 0.1)
				(type default)
			)
			(layer "F.Fab")
		)
		(fp_line
			(start -0.12065 -0.2794)
			(end 0.12065 -0.2794)
			(stroke
				(width 0.1)
				(type default)
			)
			(layer "F.Fab")
		)
		(fp_line
			(start 0.120396 0.2794)
			(end -0.12065 0.2794)
			(stroke
				(width 0.1)
				(type default)
			)
			(layer "F.Fab")
		)
		(fp_line
			(start -0.12065 0.2794)
			(end -0.12065 0.3048)
			(stroke
				(width 0.1)
				(type default)
			)
			(layer "F.Fab")
		)
		(fp_line
			(start 0.67945 0.3048)
			(end 0.120396 0.3048)
			(stroke
				(width 0.1)
				(type default)
			)
			(layer "F.Fab")
		)
		(fp_line
			(start 0.120396 0.3048)
			(end 0.120396 0.2794)
			(stroke
				(width 0.1)
				(type default)
			)
			(layer "F.Fab")
		)
		(fp_line
			(start -0.12065 0.3048)
			(end -0.67945 0.3048)
			(stroke
				(width 0.1)
				(type default)
			)
			(layer "F.Fab")
		)
		(fp_line
			(start -0.67945 0.3048)
			(end -0.67945 -0.305054)
			(stroke
				(width 0.1)
				(type default)
			)
			(layer "F.Fab")
		)
		(pad "1" smd circle
			(at -0.40005 0 90)
			(size 0 0)
			(layers "F.Cu" "F.Mask" "F.Paste")
			(net "P3V3_SSD12_CO_DV_DT")
		)
		(pad "2" smd circle
			(at 0.40005 0 90)
			(size 0 0)
			(layers "F.Cu" "F.Mask" "F.Paste")
			(net "GND")
		)
	)
	(footprint ""
		(layer "F.Cu")
		(at 229.467664 -218.70416 180)
		(property "Reference" "U5"
			(at -4.517136 -8.03783 0)
			(unlocked yes)
			(layer "F.SilkS")
			(effects
				(font
					(size 0.7874 0.5842)
					(thickness 0.1524)
				)
				(justify left)
			)
		)
		(property "Value" ""
			(at 0 0 180)
			(layer "F.Fab")
			(effects
				(font
					(size 1.27 1.27)
				)
			)
		)
		(duplicate_pad_numbers_are_jumpers no)
		(fp_line
			(start 6.549898 6.549898)
			(end 6.549898 -6.549898)
			(stroke
				(width 0.1524)
				(type default)
			)
			(layer "F.SilkS")
		)
		(fp_line
			(start 6.549898 -6.549898)
			(end -6.549898 -6.549898)
			(stroke
				(width 0.1524)
				(type default)
			)
			(layer "F.SilkS")
		)
		(fp_line
			(start -6.549898 6.549898)
			(end 6.549898 6.549898)
			(stroke
				(width 0.1524)
				(type default)
			)
			(layer "F.SilkS")
		)
		(fp_line
			(start -6.549898 -6.549898)
			(end -6.549898 6.549898)
			(stroke
				(width 0.1524)
				(type default)
			)
			(layer "F.SilkS")
		)
		(fp_poly
			(pts
				(xy -7.311898 -5.199888) (xy -7.311898 -7.311898) (xy -5.199888 -7.311898) (xy -5.199888 -6.549898)
				(xy -6.549898 -6.549898) (xy -6.549898 -5.199888)
			)
			(stroke
				(width 0)
				(type default)
			)
			(fill yes)
			(layer "F.SilkS")
		)
		(fp_line
			(start 6.549898 6.549898)
			(end 6.549898 -6.549898)
			(stroke
				(width 0.1)
				(type default)
			)
			(layer "F.Fab")
		)
		(fp_line
			(start 6.549898 -6.549898)
			(end -6.549898 -6.549898)
			(stroke
				(width 0.1)
				(type default)
			)
			(layer "F.Fab")
		)
		(fp_line
			(start -6.549898 6.549898)
			(end 6.549898 6.549898)
			(stroke
				(width 0.1)
				(type default)
			)
			(layer "F.Fab")
		)
		(fp_line
			(start -6.549898 -6.549898)
			(end -6.549898 6.549898)
			(stroke
				(width 0.1)
				(type default)
			)
			(layer "F.Fab")
		)
		(fp_poly
			(pts
				(xy -7.311898 -5.199888) (xy -7.311898 -7.311898) (xy -5.199888 -7.311898) (xy -5.199888 -6.549898)
				(xy -6.549898 -6.549898) (xy -6.549898 -5.199888)
			)
			(stroke
				(width 0)
				(type default)
			)
			(fill yes)
			(layer "F.Fab")
		)
		(pad "A1" smd circle
			(at -5.999988 -5.999988 180)
			(size 0.4064 0.4064)
			(layers "F.Cu" "F.Mask" "F.Paste")
			(net "GND")
		)
		(pad "A2" smd circle
			(at -5.199888 -5.999988 180)
			(size 0.4064 0.4064)
			(layers "F.Cu" "F.Mask" "F.Paste")
			(net "BIC_HEARTBEAT_N")
		)
		(pad "A3" smd circle
			(at -4.400042 -5.999988 180)
			(size 0.4064 0.4064)
			(layers "F.Cu" "F.Mask" "F.Paste")
			(net "PD_BIC_ENTEST")
		)
		(pad "A4" smd circle
			(at -3.599942 -5.999988 180)
			(size 0.4064 0.4064)
			(layers "F.Cu" "F.Mask" "F.Paste")
			(net "BIC_SPI1DQ2")
		)
		(pad "A5" smd circle
			(at -2.800096 -5.999988 180)
			(size 0.4064 0.4064)
			(layers "F.Cu" "F.Mask" "F.Paste")
			(net "SPI_BIC1_CLK")
		)
		(pad "A6" smd circle
			(at -1.999996 -5.999988 180)
			(size 0.4064 0.4064)
			(layers "F.Cu" "F.Mask" "F.Paste")
			(net "SPI_BIC1_MOSI")
		)
		(pad "A7" smd circle
			(at -1.199896 -5.999988 180)
			(size 0.4064 0.4064)
			(layers "F.Cu" "F.Mask" "F.Paste")
			(net "SPI_BIC1_CS0_N")
		)
		(pad "A8" smd circle
			(at -0.40005 -5.999988 180)
			(size 0.4064 0.4064)
			(layers "F.Cu" "F.Mask" "F.Paste")
			(net "BIC_SEL_FLASH_SW3")
		)
		(pad "A9" smd circle
			(at 0.40005 -5.999988 180)
			(size 0.4064 0.4064)
			(layers "F.Cu" "F.Mask" "F.Paste")
			(net "SYS_PWR_READY_R_N")
		)
		(pad "A10" smd circle
			(at 1.199896 -5.999988 180)
			(size 0.4064 0.4064)
			(layers "F.Cu" "F.Mask" "F.Paste")
			(net "Net_587")
		)
		(pad "A11" smd circle
			(at 1.999996 -5.999988 180)
			(size 0.4064 0.4064)
			(layers "F.Cu" "F.Mask" "F.Paste")
			(net "JTAG_BIC_TDO_R1")
		)
		(pad "A12" smd circle
			(at 2.800096 -5.999988 180)
			(size 0.4064 0.4064)
			(layers "F.Cu" "F.Mask" "F.Paste")
			(net "JTAG_BIC_NTRST_N")
		)
		(pad "A13" smd circle
			(at 3.599942 -5.999988 180)
			(size 0.4064 0.4064)
			(layers "F.Cu" "F.Mask" "F.Paste")
			(net "RST_SMB_FPGA_N")
		)
		(pad "A14" smd circle
			(at 4.400042 -5.999988 180)
			(size 0.4064 0.4064)
			(layers "F.Cu" "F.Mask" "F.Paste")
			(net "UART_BIC_DEBUG_R_RX")
		)
		(pad "A15" smd circle
			(at 5.199888 -5.999988 180)
			(size 0.4064 0.4064)
			(layers "F.Cu" "F.Mask" "F.Paste")
			(net "MB_BMC_MON_ISO_R")
		)
		(pad "A16" smd circle
			(at 5.999988 -5.999988 180)
			(size 0.4064 0.4064)
			(layers "F.Cu" "F.Mask" "F.Paste")
			(net "PEX_ADC_ALERT_N")
		)
		(pad "B1" smd circle
			(at -5.999988 -5.199888 180)
			(size 0.4064 0.4064)
			(layers "F.Cu" "F.Mask" "F.Paste")
			(net "P5V_AUX_SCALED")
		)
		(pad "B2" smd circle
			(at -5.199888 -5.199888 180)
			(size 0.4064 0.4064)
			(layers "F.Cu" "F.Mask" "F.Paste")
			(net "P12V_AUX_SCALED")
		)
		(pad "B3" smd circle
			(at -4.400042 -5.199888 180)
			(size 0.4064 0.4064)
			(layers "F.Cu" "F.Mask" "F.Paste")
			(net "RST_BIC_EXTRST_N")
		)
		(pad "B4" smd circle
			(at -3.599942 -5.199888 180)
			(size 0.4064 0.4064)
			(layers "F.Cu" "F.Mask" "F.Paste")
			(net "BIC_SPI1DQ3")
		)
		(pad "B5" smd circle
			(at -2.800096 -5.199888 180)
			(size 0.4064 0.4064)
			(layers "F.Cu" "F.Mask" "F.Paste")
			(net "SPI_BIC1_MISO")
		)
		(pad "B6" smd circle
			(at -1.999996 -5.199888 180)
			(size 0.4064 0.4064)
			(layers "F.Cu" "F.Mask" "F.Paste")
			(net "SPI_BIC1_CS1_N")
		)
		(pad "B7" smd circle
			(at -1.199896 -5.199888 180)
			(size 0.4064 0.4064)
			(layers "F.Cu" "F.Mask" "F.Paste")
			(net "GND")
		)
		(pad "B8" smd circle
			(at -0.40005 -5.199888 180)
			(size 0.4064 0.4064)
			(layers "F.Cu" "F.Mask" "F.Paste")
			(net "P3V3_BIC_SPI")
		)
		(pad "B9" smd circle
			(at 0.40005 -5.199888 180)
			(size 0.4064 0.4064)
			(layers "F.Cu" "F.Mask" "F.Paste")
			(net "BIC_SEL_FLASH_SW0")
		)
		(pad "B10" smd circle
			(at 1.199896 -5.199888 180)
			(size 0.4064 0.4064)
			(layers "F.Cu" "F.Mask" "F.Paste")
			(net "BIC_SYS_READY_N")
		)
		(pad "B11" smd circle
			(at 1.999996 -5.199888 180)
			(size 0.4064 0.4064)
			(layers "F.Cu" "F.Mask" "F.Paste")
			(net "JTAG_BIC_TMS")
		)
		(pad "B12" smd circle
			(at 2.800096 -5.199888 180)
			(size 0.4064 0.4064)
			(layers "F.Cu" "F.Mask" "F.Paste")
			(net "RST_SMB_NIC_MUX_N")
		)
		(pad "B13" smd circle
			(at 3.599942 -5.199888 180)
			(size 0.4064 0.4064)
			(layers "F.Cu" "F.Mask" "F.Paste")
			(net "RST_SMB_SSD_N")
		)
		(pad "B14" smd circle
			(at 4.400042 -5.199888 180)
			(size 0.4064 0.4064)
			(layers "F.Cu" "F.Mask" "F.Paste")
			(net "SGPIO_BIC_CLK")
		)
		(pad "B15" smd circle
			(at 5.199888 -5.199888 180)
			(size 0.4064 0.4064)
			(layers "F.Cu" "F.Mask" "F.Paste")
			(net "RST_SSD_LED_IOEXP_N")
		)
		(pad "B16" smd circle
			(at 5.999988 -5.199888 180)
			(size 0.4064 0.4064)
			(layers "F.Cu" "F.Mask" "F.Paste")
			(net "RST_BIC_I2C9_SSD_MUX1_N")
		)
		(pad "C1" smd circle
			(at -5.999988 -4.400042 180)
			(size 0.4064 0.4064)
			(layers "F.Cu" "F.Mask" "F.Paste")
			(net "P3V3_AUX_SCALED")
		)
		(pad "C2" smd circle
			(at -5.199888 -4.400042 180)
			(size 0.4064 0.4064)
			(layers "F.Cu" "F.Mask" "F.Paste")
			(net "P3V3_SCALED")
		)
		(pad "C3" smd circle
			(at -4.400042 -4.400042 180)
			(size 0.4064 0.4064)
			(layers "F.Cu" "F.Mask" "F.Paste")
			(net "RST_BIC_SRST_BIC_N")
		)
		(pad "C4" smd circle
			(at -3.599942 -4.400042 180)
			(size 0.4064 0.4064)
			(layers "F.Cu" "F.Mask" "F.Paste")
			(net "Net_641")
		)
		(pad "C5" smd circle
			(at -2.800096 -4.400042 180)
			(size 0.4064 0.4064)
			(layers "F.Cu" "F.Mask" "F.Paste")
			(net "BIC_FWSPIMOSI")
		)
		(pad "C6" smd circle
			(at -1.999996 -4.400042 180)
			(size 0.4064 0.4064)
			(layers "F.Cu" "F.Mask" "F.Paste")
			(net "GND")
		)
		(pad "C7" smd circle
			(at -1.199896 -4.400042 180)
			(size 0.4064 0.4064)
			(layers "F.Cu" "F.Mask" "F.Paste")
			(net "GND")
		)
		(pad "C8" smd circle
			(at -0.40005 -4.400042 180)
			(size 0.4064 0.4064)
			(layers "F.Cu" "F.Mask" "F.Paste")
			(net "BIC_FWSPIMISO")
		)
		(pad "C9" smd circle
			(at 0.40005 -4.400042 180)
			(size 0.4064 0.4064)
			(layers "F.Cu" "F.Mask" "F.Paste")
			(net "BIC_SEL_FLASH_SW1")
		)
		(pad "C10" smd circle
			(at 1.199896 -4.400042 180)
			(size 0.4064 0.4064)
			(layers "F.Cu" "F.Mask" "F.Paste")
			(net "JTAG_BIC_TDI")
		)
		(pad "C11" smd circle
			(at 1.999996 -4.400042 180)
			(size 0.4064 0.4064)
			(layers "F.Cu" "F.Mask" "F.Paste")
			(net "RST_SMB_FIO_N")
		)
		(pad "C12" smd circle
			(at 2.800096 -4.400042 180)
			(size 0.4064 0.4064)
			(layers "F.Cu" "F.Mask" "F.Paste")
			(net "JTAG_BIC_EN")
		)
		(pad "C13" smd circle
			(at 3.599942 -4.400042 180)
			(size 0.4064 0.4064)
			(layers "F.Cu" "F.Mask" "F.Paste")
			(net "FM_SYS_THROTTLE_R1")
		)
		(pad "C14" smd circle
			(at 4.400042 -4.400042 180)
			(size 0.4064 0.4064)
			(layers "F.Cu" "F.Mask" "F.Paste")
			(net "IRQ_SSD_LED_IOEXP_R_N")
		)
		(pad "C15" smd circle
			(at 5.199888 -4.400042 180)
			(size 0.4064 0.4064)
			(layers "F.Cu" "F.Mask" "F.Paste")
			(net "RST_BIC_I2C9_SSD_MUX0_N")
		)
		(pad "C16" smd circle
			(at 5.999988 -4.400042 180)
			(size 0.4064 0.4064)
			(layers "F.Cu" "F.Mask" "F.Paste")
			(net "SSD_8_15_ADC_ALERT_N")
		)
		(pad "D1" smd circle
			(at -5.999988 -3.599942 180)
			(size 0.4064 0.4064)
			(layers "F.Cu" "F.Mask" "F.Paste")
			(net "P1V8_PLL0_PEX0_SCALED")
		)
		(pad "D2" smd circle
			(at -5.199888 -3.599942 180)
			(size 0.4064 0.4064)
			(layers "F.Cu" "F.Mask" "F.Paste")
			(net "P1V8_PLL0_PEX1_SCALED")
		)
		(pad "D3" smd circle
			(at -4.400042 -3.599942 180)
			(size 0.4064 0.4064)
			(layers "F.Cu" "F.Mask" "F.Paste")
			(net "P1V2_AUX_SCALED")
		)
		(pad "D4" smd circle
			(at -3.599942 -3.599942 180)
			(size 0.4064 0.4064)
			(layers "F.Cu" "F.Mask" "F.Paste")
			(net "CLK_25M_BIC_CLKIN")
		)
		(pad "D5" smd circle
			(at -2.800096 -3.599942 180)
			(size 0.4064 0.4064)
			(layers "F.Cu" "F.Mask" "F.Paste")
			(net "BIC_FWSPIDQ3")
		)
		(pad "D6" smd circle
			(at -1.999996 -3.599942 180)
			(size 0.4064 0.4064)
			(layers "F.Cu" "F.Mask" "F.Paste")
			(net "GND")
		)
		(pad "D7" smd circle
			(at -1.199896 -3.599942 180)
			(size 0.4064 0.4064)
			(layers "F.Cu" "F.Mask" "F.Paste")
			(net "GND")
		)
		(pad "D8" smd circle
			(at -0.40005 -3.599942 180)
			(size 0.4064 0.4064)
			(layers "F.Cu" "F.Mask" "F.Paste")
			(net "BIC_FWSPIDQ2")
		)
		(pad "D9" smd circle
			(at 0.40005 -3.599942 180)
			(size 0.4064 0.4064)
			(layers "F.Cu" "F.Mask" "F.Paste")
			(net "BIC_SEL_FLASH_SW2")
		)
		(pad "D10" smd circle
			(at 1.199896 -3.599942 180)
			(size 0.4064 0.4064)
			(layers "F.Cu" "F.Mask" "F.Paste")
			(net "JTAG_BIC_TCK")
		)
		(pad "D11" smd circle
			(at 1.999996 -3.599942 180)
			(size 0.4064 0.4064)
			(layers "F.Cu" "F.Mask" "F.Paste")
			(net "MB_BIC_MON")
		)
		(pad "D12" smd circle
			(at 2.800096 -3.599942 180)
			(size 0.4064 0.4064)
			(layers "F.Cu" "F.Mask" "F.Paste")
			(net "SGPIO_BIC_DOUT")
		)
		(pad "D13" smd circle
			(at 3.599942 -3.599942 180)
			(size 0.4064 0.4064)
			(layers "F.Cu" "F.Mask" "F.Paste")
			(net "UART_BIC_DEBUG_TX")
		)
		(pad "D14" smd circle
			(at 4.400042 -3.599942 180)
			(size 0.4064 0.4064)
			(layers "F.Cu" "F.Mask" "F.Paste")
			(net "RST_BIC_USB_HUB_N")
		)
		(pad "D15" smd circle
			(at 5.199888 -3.599942 180)
			(size 0.4064 0.4064)
			(layers "F.Cu" "F.Mask" "F.Paste")
			(net "NIC_ADC_ALERT_N")
		)
		(pad "D16" smd circle
			(at 5.999988 -3.599942 180)
			(size 0.4064 0.4064)
			(layers "F.Cu" "F.Mask" "F.Paste")
			(net "SSD_0_7_ADC_ALERT_N")
		)
		(pad "E1" smd circle
			(at -5.999988 -2.800096 180)
			(size 0.4064 0.4064)
			(layers "F.Cu" "F.Mask" "F.Paste")
			(net "BIC_ADCVREFN0")
		)
		(pad "E2" smd circle
			(at -5.199888 -2.800096 180)
			(size 0.4064 0.4064)
			(layers "F.Cu" "F.Mask" "F.Paste")
			(net "BIC_ADCVREFP0")
		)
		(pad "E3" smd circle
			(at -4.400042 -2.800096 180)
			(size 0.4064 0.4064)
			(layers "F.Cu" "F.Mask" "F.Paste")
			(net "GND")
		)
		(pad "E4" smd circle
			(at -3.599942 -2.800096 180)
			(size 0.4064 0.4064)
			(layers "F.Cu" "F.Mask" "F.Paste")
			(net "USB2_BIC_DP")
		)
		(pad "E5" smd circle
			(at -2.800096 -2.800096 180)
			(size 0.4064 0.4064)
			(layers "F.Cu" "F.Mask" "F.Paste")
			(net "P1V2_BIC_USB2AV12")
		)
		(pad "E6" smd circle
			(at -1.999996 -2.800096 180)
			(size 0.4064 0.4064)
			(layers "F.Cu" "F.Mask" "F.Paste")
			(net "GND")
		)
		(pad "E7" smd circle
			(at -1.199896 -2.800096 180)
			(size 0.4064 0.4064)
			(layers "F.Cu" "F.Mask" "F.Paste")
			(net "BIC_FWSPICK")
		)
		(pad "E8" smd circle
			(at -0.40005 -2.800096 180)
			(size 0.4064 0.4064)
			(layers "F.Cu" "F.Mask" "F.Paste")
			(net "P3V3_AUX")
		)
		(pad "E9" smd circle
			(at 0.40005 -2.800096 180)
			(size 0.4064 0.4064)
			(layers "F.Cu" "F.Mask" "F.Paste")
			(net "P3V3_AUX")
		)
		(pad "E10" smd circle
			(at 1.199896 -2.800096 180)
			(size 0.4064 0.4064)
			(layers "F.Cu" "F.Mask" "F.Paste")
			(net "P3V3_AUX")
		)
		(pad "E11" smd circle
			(at 1.999996 -2.800096 180)
			(size 0.4064 0.4064)
			(layers "F.Cu" "F.Mask" "F.Paste")
			(net "RST_PEX_USB_HUB_N")
		)
		(pad "E12" smd circle
			(at 2.800096 -2.800096 180)
			(size 0.4064 0.4064)
			(layers "F.Cu" "F.Mask" "F.Paste")
			(net "Net_589")
		)
		(pad "E13" smd circle
			(at 3.599942 -2.800096 180)
			(size 0.4064 0.4064)
			(layers "F.Cu" "F.Mask" "F.Paste")
			(net "RST_BIC_SELF_HW_RST_N")
		)
		(pad "E14" smd circle
			(at 4.400042 -2.800096 180)
			(size 0.4064 0.4064)
			(layers "F.Cu" "F.Mask" "F.Paste")
			(net "PRSNT_GPU_ISO_R_N")
		)
		(pad "E15" smd circle
			(at 5.199888 -2.800096 180)
			(size 0.4064 0.4064)
			(layers "F.Cu" "F.Mask" "F.Paste")
			(net "Net_640")
		)
		(pad "E16" smd circle
			(at 5.999988 -2.800096 180)
			(size 0.4064 0.4064)
			(layers "F.Cu" "F.Mask" "F.Paste")
			(net "RST_MB_BMC_N")
		)
		(pad "F1" smd circle
			(at -5.999988 -1.999996 180)
			(size 0.4064 0.4064)
			(layers "F.Cu" "F.Mask" "F.Paste")
			(net "PD_BIC_ADCREXT0")
		)
		(pad "F2" smd circle
			(at -5.199888 -1.999996 180)
			(size 0.4064 0.4064)
			(layers "F.Cu" "F.Mask" "F.Paste")
			(net "P1V2_BIC_ADCVREFREXT0")
		)
		(pad "F3" smd circle
			(at -4.400042 -1.999996 180)
			(size 0.4064 0.4064)
			(layers "F.Cu" "F.Mask" "F.Paste")
			(net "GND")
		)
		(pad "F4" smd circle
			(at -3.599942 -1.999996 180)
			(size 0.4064 0.4064)
			(layers "F.Cu" "F.Mask" "F.Paste")
			(net "USB2_BIC_DN")
		)
		(pad "F5" smd circle
			(at -2.800096 -1.999996 180)
			(size 0.4064 0.4064)
			(layers "F.Cu" "F.Mask" "F.Paste")
			(net "P3V3_BIC_USB2AV33")
		)
		(pad "F6" smd circle
			(at -1.999996 -1.999996 180)
			(size 0.4064 0.4064)
			(layers "F.Cu" "F.Mask" "F.Paste")
			(net "GND")
		)
		(pad "F7" smd circle
			(at -1.199896 -1.999996 180)
			(size 0.4064 0.4064)
			(layers "F.Cu" "F.Mask" "F.Paste")
			(net "BIC_FWSPICS1_N")
		)
		(pad "F8" smd circle
			(at -0.40005 -1.999996 180)
			(size 0.4064 0.4064)
			(layers "F.Cu" "F.Mask" "F.Paste")
			(net "P1V2_AUX")
		)
		(pad "F9" smd circle
			(at 0.40005 -1.999996 180)
			(size 0.4064 0.4064)
			(layers "F.Cu" "F.Mask" "F.Paste")
			(net "P1V2_AUX")
		)
		(pad "F10" smd circle
			(at 1.199896 -1.999996 180)
			(size 0.4064 0.4064)
			(layers "F.Cu" "F.Mask" "F.Paste")
			(net "P1V2_AUX")
		)
		(pad "F11" smd circle
			(at 1.999996 -1.999996 180)
			(size 0.4064 0.4064)
			(layers "F.Cu" "F.Mask" "F.Paste")
			(net "RST_BIC_I2C6_MUX_N")
		)
		(pad "F12" smd circle
			(at 2.800096 -1.999996 180)
			(size 0.4064 0.4064)
			(layers "F.Cu" "F.Mask" "F.Paste")
			(net "BIC_UART_BIC_SEL")
		)
		(pad "F13" smd circle
			(at 3.599942 -1.999996 180)
			(size 0.4064 0.4064)
			(layers "F.Cu" "F.Mask" "F.Paste")
			(net "P3V3_AUX")
		)
		(pad "F14" smd circle
			(at 4.400042 -1.999996 180)
			(size 0.4064 0.4064)
			(layers "F.Cu" "F.Mask" "F.Paste")
			(net "SMB_ALERT_HSC_R_N")
		)
		(pad "F15" smd circle
			(at 5.199888 -1.999996 180)
			(size 0.4064 0.4064)
			(layers "F.Cu" "F.Mask" "F.Paste")
			(net "USB_DEBUG_RST_BTN_R_N")
		)
		(pad "F16" smd circle
			(at 5.999988 -1.999996 180)
			(size 0.4064 0.4064)
			(layers "F.Cu" "F.Mask" "F.Paste")
			(net "SMB_ALERT_PMBUS_R_N")
		)
		(pad "G1" smd circle
			(at -5.999988 -1.199896 180)
			(size 0.4064 0.4064)
			(layers "F.Cu" "F.Mask" "F.Paste")
			(net "P1V2_BIC_ADCVREFREXT1")
		)
		(pad "G2" smd circle
			(at -5.199888 -1.199896 180)
			(size 0.4064 0.4064)
			(layers "F.Cu" "F.Mask" "F.Paste")
			(net "PD_BIC_ADCREXT1")
		)
		(pad "G3" smd circle
			(at -4.400042 -1.199896 180)
			(size 0.4064 0.4064)
			(layers "F.Cu" "F.Mask" "F.Paste")
			(net "P1V2_BIC_PLL")
		)
		(pad "G4" smd circle
			(at -3.599942 -1.199896 180)
			(size 0.4064 0.4064)
			(layers "F.Cu" "F.Mask" "F.Paste")
			(net "P3V3_AUX")
		)
		(pad "G5" smd circle
			(at -2.800096 -1.199896 180)
			(size 0.4064 0.4064)
			(layers "F.Cu" "F.Mask" "F.Paste")
			(net "P1V2_AUX")
		)
		(pad "G6" smd circle
			(at -1.999996 -1.199896 180)
			(size 0.4064 0.4064)
			(layers "F.Cu" "F.Mask" "F.Paste")
			(net "GND")
		)
		(pad "G7" smd circle
			(at -1.199896 -1.199896 180)
			(size 0.4064 0.4064)
			(layers "F.Cu" "F.Mask" "F.Paste")
			(net "GND")
		)
		(pad "G8" smd circle
			(at -0.40005 -1.199896 180)
			(size 0.4064 0.4064)
			(layers "F.Cu" "F.Mask" "F.Paste")
			(net "GND")
		)
		(pad "G9" smd circle
			(at 0.40005 -1.199896 180)
			(size 0.4064 0.4064)
			(layers "F.Cu" "F.Mask" "F.Paste")
			(net "GND")
		)
		(pad "G10" smd circle
			(at 1.199896 -1.199896 180)
			(size 0.4064 0.4064)
			(layers "F.Cu" "F.Mask" "F.Paste")
			(net "GND")
		)
		(pad "G11" smd circle
			(at 1.999996 -1.199896 180)
			(size 0.4064 0.4064)
			(layers "F.Cu" "F.Mask" "F.Paste")
			(net "GND")
		)
		(pad "G12" smd circle
			(at 2.800096 -1.199896 180)
			(size 0.4064 0.4064)
			(layers "F.Cu" "F.Mask" "F.Paste")
			(net "P3V3_AUX")
		)
		(pad "G13" smd circle
			(at 3.599942 -1.199896 180)
			(size 0.4064 0.4064)
			(layers "F.Cu" "F.Mask" "F.Paste")
			(net "P3V3_AUX")
		)
		(pad "G14" smd circle
			(at 4.400042 -1.199896 180)
			(size 0.4064 0.4064)
			(layers "F.Cu" "F.Mask" "F.Paste")
			(net "SMB_FPGA_ALERT_R_N")
		)
		(pad "G15" smd circle
			(at 5.199888 -1.199896 180)
			(size 0.4064 0.4064)
			(layers "F.Cu" "F.Mask" "F.Paste")
			(net "SMB_NIC6_SDA")
		)
		(pad "G16" smd circle
			(at 5.999988 -1.199896 180)
			(size 0.4064 0.4064)
			(layers "F.Cu" "F.Mask" "F.Paste")
			(net "SMB_NIC7_SDA")
		)
		(pad "H1" smd circle
			(at -5.999988 -0.40005 180)
			(size 0.4064 0.4064)
			(layers "F.Cu" "F.Mask" "F.Paste")
			(net "P1V8_PLL0_PEX3_SCALED")
		)
		(pad "H2" smd circle
			(at -5.199888 -0.40005 180)
			(size 0.4064 0.4064)
			(layers "F.Cu" "F.Mask" "F.Paste")
			(net "P1V8_PLL0_PEX2_SCALED")
		)
		(pad "H3" smd circle
			(at -4.400042 -0.40005 180)
			(size 0.4064 0.4064)
			(layers "F.Cu" "F.Mask" "F.Paste")
			(net "BIC_ADCVREFN1")
		)
		(pad "H4" smd circle
			(at -3.599942 -0.40005 180)
			(size 0.4064 0.4064)
			(layers "F.Cu" "F.Mask" "F.Paste")
			(net "P3V3_AUX")
		)
		(pad "H5" smd circle
			(at -2.800096 -0.40005 180)
			(size 0.4064 0.4064)
			(layers "F.Cu" "F.Mask" "F.Paste")
			(net "P1V2_AUX")
		)
		(pad "H6" smd circle
			(at -1.999996 -0.40005 180)
			(size 0.4064 0.4064)
			(layers "F.Cu" "F.Mask" "F.Paste")
			(net "GND")
		)
		(pad "H7" smd circle
			(at -1.199896 -0.40005 180)
			(size 0.4064 0.4064)
			(layers "F.Cu" "F.Mask" "F.Paste")
			(net "GND")
		)
		(pad "H8" smd circle
			(at -0.40005 -0.40005 180)
			(size 0.4064 0.4064)
			(layers "F.Cu" "F.Mask" "F.Paste")
			(net "GND")
		)
		(pad "H9" smd circle
			(at 0.40005 -0.40005 180)
			(size 0.4064 0.4064)
			(layers "F.Cu" "F.Mask" "F.Paste")
			(net "GND")
		)
		(pad "H10" smd circle
			(at 1.199896 -0.40005 180)
			(size 0.4064 0.4064)
			(layers "F.Cu" "F.Mask" "F.Paste")
			(net "GND")
		)
		(pad "H11" smd circle
			(at 1.999996 -0.40005 180)
			(size 0.4064 0.4064)
			(layers "F.Cu" "F.Mask" "F.Paste")
			(net "GND")
		)
		(pad "H12" smd circle
			(at 2.800096 -0.40005 180)
			(size 0.4064 0.4064)
			(layers "F.Cu" "F.Mask" "F.Paste")
			(net "P1V2_AUX")
		)
		(pad "H13" smd circle
			(at 3.599942 -0.40005 180)
			(size 0.4064 0.4064)
			(layers "F.Cu" "F.Mask" "F.Paste")
			(net "PECI_VDD")
		)
		(pad "H14" smd circle
			(at 4.400042 -0.40005 180)
			(size 0.4064 0.4064)
			(layers "F.Cu" "F.Mask" "F.Paste")
			(net "BIC_PECI")
		)
		(pad "H15" smd circle
			(at 5.199888 -0.40005 180)
			(size 0.4064 0.4064)
			(layers "F.Cu" "F.Mask" "F.Paste")
			(net "SMB_NIC6_SCL")
		)
		(pad "H16" smd circle
			(at 5.999988 -0.40005 180)
			(size 0.4064 0.4064)
			(layers "F.Cu" "F.Mask" "F.Paste")
			(net "SMB_NIC5_SDA")
		)
		(pad "J1" smd circle
			(at -5.999988 0.40005 180)
			(size 0.4064 0.4064)
			(layers "F.Cu" "F.Mask" "F.Paste")
			(net "HSC_TYPE_ADC_R")
		)
		(pad "J2" smd circle
			(at -5.199888 0.40005 180)
			(size 0.4064 0.4064)
			(layers "F.Cu" "F.Mask" "F.Paste")
			(net "VR_TYPE_ADC_R")
		)
		(pad "J3" smd circle
			(at -4.400042 0.40005 180)
			(size 0.4064 0.4064)
			(layers "F.Cu" "F.Mask" "F.Paste")
			(net "BIC_ADCVREFP1")
		)
		(pad "J4" smd circle
			(at -3.599942 0.40005 180)
			(size 0.4064 0.4064)
			(layers "F.Cu" "F.Mask" "F.Paste")
			(net "ADC_TYPE_ADC_R")
		)
		(pad "J5" smd circle
			(at -2.800096 0.40005 180)
			(size 0.4064 0.4064)
			(layers "F.Cu" "F.Mask" "F.Paste")
			(net "P3V3_BIC_ADCAV33")
		)
		(pad "J6" smd circle
			(at -1.999996 0.40005 180)
			(size 0.4064 0.4064)
			(layers "F.Cu" "F.Mask" "F.Paste")
			(net "GND")
		)
		(pad "J7" smd circle
			(at -1.199896 0.40005 180)
			(size 0.4064 0.4064)
			(layers "F.Cu" "F.Mask" "F.Paste")
			(net "GND")
		)
		(pad "J8" smd circle
			(at -0.40005 0.40005 180)
			(size 0.4064 0.4064)
			(layers "F.Cu" "F.Mask" "F.Paste")
			(net "GND")
		)
		(pad "J9" smd circle
			(at 0.40005 0.40005 180)
			(size 0.4064 0.4064)
			(layers "F.Cu" "F.Mask" "F.Paste")
			(net "GND")
		)
		(pad "J10" smd circle
			(at 1.199896 0.40005 180)
			(size 0.4064 0.4064)
			(layers "F.Cu" "F.Mask" "F.Paste")
			(net "GND")
		)
		(pad "J11" smd circle
			(at 1.999996 0.40005 180)
			(size 0.4064 0.4064)
			(layers "F.Cu" "F.Mask" "F.Paste")
			(net "GND")
		)
		(pad "J12" smd circle
			(at 2.800096 0.40005 180)
			(size 0.4064 0.4064)
			(layers "F.Cu" "F.Mask" "F.Paste")
			(net "P1V2_AUX")
		)
		(pad "J13" smd circle
			(at 3.599942 0.40005 180)
			(size 0.4064 0.4064)
			(layers "F.Cu" "F.Mask" "F.Paste")
			(net "SMB_NIC7_SCL")
		)
		(pad "J14" smd circle
			(at 4.400042 0.40005 180)
			(size 0.4064 0.4064)
			(layers "F.Cu" "F.Mask" "F.Paste")
			(net "SMB_NIC5_SCL")
		)
		(pad "J15" smd circle
			(at 5.199888 0.40005 180)
			(size 0.4064 0.4064)
			(layers "F.Cu" "F.Mask" "F.Paste")
			(net "SMB_NIC4_SDA")
		)
		(pad "J16" smd circle
			(at 5.999988 0.40005 180)
			(size 0.4064 0.4064)
			(layers "F.Cu" "F.Mask" "F.Paste")
			(net "SMB_NIC4_SCL")
		)
		(pad "K1" smd circle
			(at -5.999988 1.199896 180)
			(size 0.4064 0.4064)
			(layers "F.Cu" "F.Mask" "F.Paste")
			(net "SSD12_PWRDIS_BIC")
		)
		(pad "K2" smd circle
			(at -5.199888 1.199896 180)
			(size 0.4064 0.4064)
			(layers "F.Cu" "F.Mask" "F.Paste")
			(net "BOARD_TYPE_2_ADC_R")
		)
		(pad "K3" smd circle
			(at -4.400042 1.199896 180)
			(size 0.4064 0.4064)
			(layers "F.Cu" "F.Mask" "F.Paste")
			(net "BOARD_TYPE_0_ADC_R")
		)
		(pad "K4" smd circle
			(at -3.599942 1.199896 180)
			(size 0.4064 0.4064)
			(layers "F.Cu" "F.Mask" "F.Paste")
			(net "BOARD_TYPE_1_ADC_R")
		)
		(pad "K5" smd circle
			(at -2.800096 1.199896 180)
			(size 0.4064 0.4064)
			(layers "F.Cu" "F.Mask" "F.Paste")
			(net "P3V3_BIC_ADCAV33")
		)
		(pad "K6" smd circle
			(at -1.999996 1.199896 180)
			(size 0.4064 0.4064)
			(layers "F.Cu" "F.Mask" "F.Paste")
			(net "GND")
		)
		(pad "K7" smd circle
			(at -1.199896 1.199896 180)
			(size 0.4064 0.4064)
			(layers "F.Cu" "F.Mask" "F.Paste")
			(net "GND")
		)
		(pad "K8" smd circle
			(at -0.40005 1.199896 180)
			(size 0.4064 0.4064)
			(layers "F.Cu" "F.Mask" "F.Paste")
			(net "GND")
		)
		(pad "K9" smd circle
			(at 0.40005 1.199896 180)
			(size 0.4064 0.4064)
			(layers "F.Cu" "F.Mask" "F.Paste")
			(net "GND")
		)
		(pad "K10" smd circle
			(at 1.199896 1.199896 180)
			(size 0.4064 0.4064)
			(layers "F.Cu" "F.Mask" "F.Paste")
			(net "GND")
		)
		(pad "K11" smd circle
			(at 1.999996 1.199896 180)
			(size 0.4064 0.4064)
			(layers "F.Cu" "F.Mask" "F.Paste")
			(net "GND")
		)
		(pad "K12" smd circle
			(at 2.800096 1.199896 180)
			(size 0.4064 0.4064)
			(layers "F.Cu" "F.Mask" "F.Paste")
			(net "P1V2_AUX")
		)
		(pad "K13" smd circle
			(at 3.599942 1.199896 180)
			(size 0.4064 0.4064)
			(layers "F.Cu" "F.Mask" "F.Paste")
			(net "P3V3_AUX")
		)
		(pad "K14" smd circle
			(at 4.400042 1.199896 180)
			(size 0.4064 0.4064)
			(layers "F.Cu" "F.Mask" "F.Paste")
			(net "SMB_PEX_SCL")
		)
		(pad "K15" smd circle
			(at 5.199888 1.199896 180)
			(size 0.4064 0.4064)
			(layers "F.Cu" "F.Mask" "F.Paste")
			(net "SMB_PEX_SDA")
		)
		(pad "K16" smd circle
			(at 5.999988 1.199896 180)
			(size 0.4064 0.4064)
			(layers "F.Cu" "F.Mask" "F.Paste")
			(net "SMB_BIC_I2C9_SSD_MUX_SDA")
		)
		(pad "L1" smd circle
			(at -5.999988 1.999996 180)
			(size 0.4064 0.4064)
			(layers "F.Cu" "F.Mask" "F.Paste")
			(net "PRSNT_SSD9_R_N")
		)
		(pad "L2" smd circle
			(at -5.199888 1.999996 180)
			(size 0.4064 0.4064)
			(layers "F.Cu" "F.Mask" "F.Paste")
			(net "PRSNT_SSD8_R_N")
		)
		(pad "L3" smd circle
			(at -4.400042 1.999996 180)
			(size 0.4064 0.4064)
			(layers "F.Cu" "F.Mask" "F.Paste")
			(net "SSD13_PWRDIS_BIC")
		)
		(pad "L4" smd circle
			(at -3.599942 1.999996 180)
			(size 0.4064 0.4064)
			(layers "F.Cu" "F.Mask" "F.Paste")
			(net "SSD14_PWRDIS_BIC")
		)
		(pad "L5" smd circle
			(at -2.800096 1.999996 180)
			(size 0.4064 0.4064)
			(layers "F.Cu" "F.Mask" "F.Paste")
			(net "P3V3_AUX")
		)
		(pad "L6" smd circle
			(at -1.999996 1.999996 180)
			(size 0.4064 0.4064)
			(layers "F.Cu" "F.Mask" "F.Paste")
			(net "GND")
		)
		(pad "L7" smd circle
			(at -1.199896 1.999996 180)
			(size 0.4064 0.4064)
			(layers "F.Cu" "F.Mask" "F.Paste")
			(net "GND")
		)
		(pad "L8" smd circle
			(at -0.40005 1.999996 180)
			(size 0.4064 0.4064)
			(layers "F.Cu" "F.Mask" "F.Paste")
			(net "GND")
		)
		(pad "L9" smd circle
			(at 0.40005 1.999996 180)
			(size 0.4064 0.4064)
			(layers "F.Cu" "F.Mask" "F.Paste")
			(net "GND")
		)
		(pad "L10" smd circle
			(at 1.199896 1.999996 180)
			(size 0.4064 0.4064)
			(layers "F.Cu" "F.Mask" "F.Paste")
			(net "GND")
		)
		(pad "L11" smd circle
			(at 1.999996 1.999996 180)
			(size 0.4064 0.4064)
			(layers "F.Cu" "F.Mask" "F.Paste")
			(net "GND")
		)
		(pad "L12" smd circle
			(at 2.800096 1.999996 180)
			(size 0.4064 0.4064)
			(layers "F.Cu" "F.Mask" "F.Paste")
			(net "P3V3_AUX")
		)
		(pad "L13" smd circle
			(at 3.599942 1.999996 180)
			(size 0.4064 0.4064)
			(layers "F.Cu" "F.Mask" "F.Paste")
			(net "P3V3_AUX")
		)
		(pad "L14" smd circle
			(at 4.400042 1.999996 180)
			(size 0.4064 0.4064)
			(layers "F.Cu" "F.Mask" "F.Paste")
			(net "SMB_BIC_FPGA_R2_SCL")
		)
		(pad "L15" smd circle
			(at 5.199888 1.999996 180)
			(size 0.4064 0.4064)
			(layers "F.Cu" "F.Mask" "F.Paste")
			(net "SMB_BIC_FPGA_R2_SDA")
		)
		(pad "L16" smd circle
			(at 5.999988 1.999996 180)
			(size 0.4064 0.4064)
			(layers "F.Cu" "F.Mask" "F.Paste")
			(net "SMB_BIC_I2C9_SSD_MUX_SCL")
		)
		(pad "M1" smd circle
			(at -5.999988 2.800096 180)
			(size 0.4064 0.4064)
			(layers "F.Cu" "F.Mask" "F.Paste")
			(net "PRSNT_SSD12_R_N")
		)
		(pad "M2" smd circle
			(at -5.199888 2.800096 180)
			(size 0.4064 0.4064)
			(layers "F.Cu" "F.Mask" "F.Paste")
			(net "PRSNT_SSD11_R_N")
		)
		(pad "M3" smd circle
			(at -4.400042 2.800096 180)
			(size 0.4064 0.4064)
			(layers "F.Cu" "F.Mask" "F.Paste")
			(net "PRSNT_SSD10_R_N")
		)
		(pad "M4" smd circle
			(at -3.599942 2.800096 180)
			(size 0.4064 0.4064)
			(layers "F.Cu" "F.Mask" "F.Paste")
			(net "SSD15_PWRDIS_BIC")
		)
		(pad "M5" smd circle
			(at -2.800096 2.800096 180)
			(size 0.4064 0.4064)
			(layers "F.Cu" "F.Mask" "F.Paste")
			(net "PRSNT_SSD6_R_N")
		)
		(pad "M6" smd circle
			(at -1.999996 2.800096 180)
			(size 0.4064 0.4064)
			(layers "F.Cu" "F.Mask" "F.Paste")
			(net "P1V2_AUX")
		)
		(pad "M7" smd circle
			(at -1.199896 2.800096 180)
			(size 0.4064 0.4064)
			(layers "F.Cu" "F.Mask" "F.Paste")
			(net "GND")
		)
		(pad "M8" smd circle
			(at -0.40005 2.800096 180)
			(size 0.4064 0.4064)
			(layers "F.Cu" "F.Mask" "F.Paste")
			(net "GND")
		)
		(pad "M9" smd circle
			(at 0.40005 2.800096 180)
			(size 0.4064 0.4064)
			(layers "F.Cu" "F.Mask" "F.Paste")
			(net "GND")
		)
		(pad "M10" smd circle
			(at 1.199896 2.800096 180)
			(size 0.4064 0.4064)
			(layers "F.Cu" "F.Mask" "F.Paste")
			(net "GND")
		)
		(pad "M11" smd circle
			(at 1.999996 2.800096 180)
			(size 0.4064 0.4064)
			(layers "F.Cu" "F.Mask" "F.Paste")
			(net "GND")
		)
		(pad "M12" smd circle
			(at 2.800096 2.800096 180)
			(size 0.4064 0.4064)
			(layers "F.Cu" "F.Mask" "F.Paste")
			(net "BIC_FORCE_THROTTLE_N")
		)
		(pad "M13" smd circle
			(at 3.599942 2.800096 180)
			(size 0.4064 0.4064)
			(layers "F.Cu" "F.Mask" "F.Paste")
			(net "SMB_FIO_SCL")
		)
		(pad "M14" smd circle
			(at 4.400042 2.800096 180)
			(size 0.4064 0.4064)
			(layers "F.Cu" "F.Mask" "F.Paste")
			(net "SMB_BIC_I2C6_SDA")
		)
		(pad "M15" smd circle
			(at 5.199888 2.800096 180)
			(size 0.4064 0.4064)
			(layers "F.Cu" "F.Mask" "F.Paste")
			(net "I3C_MB_SCL")
		)
		(pad "M16" smd circle
			(at 5.999988 2.800096 180)
			(size 0.4064 0.4064)
			(layers "F.Cu" "F.Mask" "F.Paste")
			(net "I3C_MB_SDA")
		)
		(pad "N1" smd circle
			(at -5.999988 3.599942 180)
			(size 0.4064 0.4064)
			(layers "F.Cu" "F.Mask" "F.Paste")
			(net "PRSNT_SSD15_R_N")
		)
		(pad "N2" smd circle
			(at -5.199888 3.599942 180)
			(size 0.4064 0.4064)
			(layers "F.Cu" "F.Mask" "F.Paste")
			(net "PRSNT_SSD14_R_N")
		)
		(pad "N3" smd circle
			(at -4.400042 3.599942 180)
			(size 0.4064 0.4064)
			(layers "F.Cu" "F.Mask" "F.Paste")
			(net "PRSNT_SSD13_R_N")
		)
		(pad "N4" smd circle
			(at -3.599942 3.599942 180)
			(size 0.4064 0.4064)
			(layers "F.Cu" "F.Mask" "F.Paste")
			(net "PRSNT_NIC0_R_N")
		)
		(pad "N5" smd circle
			(at -2.800096 3.599942 180)
			(size 0.4064 0.4064)
			(layers "F.Cu" "F.Mask" "F.Paste")
			(net "PRSNT_SSD4_R_N")
		)
		(pad "N6" smd circle
			(at -1.999996 3.599942 180)
			(size 0.4064 0.4064)
			(layers "F.Cu" "F.Mask" "F.Paste")
			(net "SSD3_PWRDIS_BIC")
		)
		(pad "N7" smd circle
			(at -1.199896 3.599942 180)
			(size 0.4064 0.4064)
			(layers "F.Cu" "F.Mask" "F.Paste")
			(net "P3V3_AUX")
		)
		(pad "N8" smd circle
			(at -0.40005 3.599942 180)
			(size 0.4064 0.4064)
			(layers "F.Cu" "F.Mask" "F.Paste")
			(net "P1V2_AUX")
		)
		(pad "N9" smd circle
			(at 0.40005 3.599942 180)
			(size 0.4064 0.4064)
			(layers "F.Cu" "F.Mask" "F.Paste")
			(net "P1V2_AUX")
		)
		(pad "N10" smd circle
			(at 1.199896 3.599942 180)
			(size 0.4064 0.4064)
			(layers "F.Cu" "F.Mask" "F.Paste")
			(net "P3V3_AUX")
		)
		(pad "N11" smd circle
			(at 1.999996 3.599942 180)
			(size 0.4064 0.4064)
			(layers "F.Cu" "F.Mask" "F.Paste")
			(net "NIC7_MAIN_PWR_BIC_EN")
		)
		(pad "N12" smd circle
			(at 2.800096 3.599942 180)
			(size 0.4064 0.4064)
			(layers "F.Cu" "F.Mask" "F.Paste")
			(net "PRSNT_DBV2_SLIMSAS_R")
		)
		(pad "N13" smd circle
			(at 3.599942 3.599942 180)
			(size 0.4064 0.4064)
			(layers "F.Cu" "F.Mask" "F.Paste")
			(net "GND")
		)
		(pad "N14" smd circle
			(at 4.400042 3.599942 180)
			(size 0.4064 0.4064)
			(layers "F.Cu" "F.Mask" "F.Paste")
			(net "SMB_NIC1_SDA")
		)
		(pad "N15" smd circle
			(at 5.199888 3.599942 180)
			(size 0.4064 0.4064)
			(layers "F.Cu" "F.Mask" "F.Paste")
			(net "SMB_FIO_SDA")
		)
		(pad "N16" smd circle
			(at 5.999988 3.599942 180)
			(size 0.4064 0.4064)
			(layers "F.Cu" "F.Mask" "F.Paste")
			(net "SMB_BIC_I2C6_SCL")
		)
		(pad "P1" smd circle
			(at -5.999988 4.400042 180)
			(size 0.4064 0.4064)
			(layers "F.Cu" "F.Mask" "F.Paste")
			(net "PRSNT_NIC2_R_N")
		)
		(pad "P2" smd circle
			(at -5.199888 4.400042 180)
			(size 0.4064 0.4064)
			(layers "F.Cu" "F.Mask" "F.Paste")
			(net "PRSNT_NIC4_R_N")
		)
		(pad "P3" smd circle
			(at -4.400042 4.400042 180)
			(size 0.4064 0.4064)
			(layers "F.Cu" "F.Mask" "F.Paste")
			(net "PRSNT_NIC5_R_N")
		)
		(pad "P4" smd circle
			(at -3.599942 4.400042 180)
			(size 0.4064 0.4064)
			(layers "F.Cu" "F.Mask" "F.Paste")
			(net "PRSNT_NIC1_R_N")
		)
		(pad "P5" smd circle
			(at -2.800096 4.400042 180)
			(size 0.4064 0.4064)
			(layers "F.Cu" "F.Mask" "F.Paste")
			(net "PRSNT_NIC3_R_N")
		)
		(pad "P6" smd circle
			(at -1.999996 4.400042 180)
			(size 0.4064 0.4064)
			(layers "F.Cu" "F.Mask" "F.Paste")
			(net "PRSNT_SSD5_R_N")
		)
		(pad "P7" smd circle
			(at -1.199896 4.400042 180)
			(size 0.4064 0.4064)
			(layers "F.Cu" "F.Mask" "F.Paste")
			(net "SSD2_PWRDIS_BIC")
		)
		(pad "P8" smd circle
			(at -0.40005 4.400042 180)
			(size 0.4064 0.4064)
			(layers "F.Cu" "F.Mask" "F.Paste")
			(net "SSD4_PWRDIS_BIC")
		)
		(pad "P9" smd circle
			(at 0.40005 4.400042 180)
			(size 0.4064 0.4064)
			(layers "F.Cu" "F.Mask" "F.Paste")
			(net "NIC1_MAIN_PWR_BIC_EN")
		)
		(pad "P10" smd circle
			(at 1.199896 4.400042 180)
			(size 0.4064 0.4064)
			(layers "F.Cu" "F.Mask" "F.Paste")
			(net "NIC5_MAIN_PWR_BIC_EN")
		)
		(pad "P11" smd circle
			(at 1.999996 4.400042 180)
			(size 0.4064 0.4064)
			(layers "F.Cu" "F.Mask" "F.Paste")
			(net "BOARD_ID1")
		)
		(pad "P12" smd circle
			(at 2.800096 4.400042 180)
			(size 0.4064 0.4064)
			(layers "F.Cu" "F.Mask" "F.Paste")
			(net "SMB_NIC0_SDA")
		)
		(pad "P13" smd circle
			(at 3.599942 4.400042 180)
			(size 0.4064 0.4064)
			(layers "F.Cu" "F.Mask" "F.Paste")
			(net "SMB_NIC1_SCL")
		)
		(pad "P14" smd circle
			(at 4.400042 4.400042 180)
			(size 0.4064 0.4064)
			(layers "F.Cu" "F.Mask" "F.Paste")
			(net "RST_PEX_MUX_N")
		)
		(pad "P15" smd circle
			(at 5.199888 4.400042 180)
			(size 0.4064 0.4064)
			(layers "F.Cu" "F.Mask" "F.Paste")
			(net "SMB_NIC3_SCL")
		)
		(pad "P16" smd circle
			(at 5.999988 4.400042 180)
			(size 0.4064 0.4064)
			(layers "F.Cu" "F.Mask" "F.Paste")
			(net "SMB_NIC3_SDA")
		)
		(pad "R1" smd circle
			(at -5.999988 5.199888 180)
			(size 0.4064 0.4064)
			(layers "F.Cu" "F.Mask" "F.Paste")
			(net "PRSNT_NIC6_R_N")
		)
		(pad "R2" smd circle
			(at -5.199888 5.199888 180)
			(size 0.4064 0.4064)
			(layers "F.Cu" "F.Mask" "F.Paste")
			(net "PRSNT_NIC7_R_N")
		)
		(pad "R3" smd circle
			(at -4.400042 5.199888 180)
			(size 0.4064 0.4064)
			(layers "F.Cu" "F.Mask" "F.Paste")
			(net "PRSNT_SSD1_R_N")
		)
		(pad "R4" smd circle
			(at -3.599942 5.199888 180)
			(size 0.4064 0.4064)
			(layers "F.Cu" "F.Mask" "F.Paste")
			(net "PRSNT_SSD7_R_N")
		)
		(pad "R5" smd circle
			(at -2.800096 5.199888 180)
			(size 0.4064 0.4064)
			(layers "F.Cu" "F.Mask" "F.Paste")
			(net "SSD0_PWRDIS_BIC")
		)
		(pad "R6" smd circle
			(at -1.999996 5.199888 180)
			(size 0.4064 0.4064)
			(layers "F.Cu" "F.Mask" "F.Paste")
			(net "SSD6_PWRDIS_BIC")
		)
		(pad "R7" smd circle
			(at -1.199896 5.199888 180)
			(size 0.4064 0.4064)
			(layers "F.Cu" "F.Mask" "F.Paste")
			(net "SSD8_PWRDIS_BIC")
		)
		(pad "R8" smd circle
			(at -0.40005 5.199888 180)
			(size 0.4064 0.4064)
			(layers "F.Cu" "F.Mask" "F.Paste")
			(net "SSD10_PWRDIS_BIC")
		)
		(pad "R9" smd circle
			(at 0.40005 5.199888 180)
			(size 0.4064 0.4064)
			(layers "F.Cu" "F.Mask" "F.Paste")
			(net "NIC2_MAIN_PWR_BIC_EN")
		)
		(pad "R10" smd circle
			(at 1.199896 5.199888 180)
			(size 0.4064 0.4064)
			(layers "F.Cu" "F.Mask" "F.Paste")
			(net "NIC4_MAIN_PWR_BIC_EN")
		)
		(pad "R11" smd circle
			(at 1.999996 5.199888 180)
			(size 0.4064 0.4064)
			(layers "F.Cu" "F.Mask" "F.Paste")
			(net "REV_ID0")
		)
		(pad "R12" smd circle
			(at 2.800096 5.199888 180)
			(size 0.4064 0.4064)
			(layers "F.Cu" "F.Mask" "F.Paste")
			(net "REV_ID2")
		)
		(pad "R13" smd circle
			(at 3.599942 5.199888 180)
			(size 0.4064 0.4064)
			(layers "F.Cu" "F.Mask" "F.Paste")
			(net "BOARD_ID2")
		)
		(pad "R14" smd circle
			(at 4.400042 5.199888 180)
			(size 0.4064 0.4064)
			(layers "F.Cu" "F.Mask" "F.Paste")
			(net "HSC_UV_R_N")
		)
		(pad "R15" smd circle
			(at 5.199888 5.199888 180)
			(size 0.4064 0.4064)
			(layers "F.Cu" "F.Mask" "F.Paste")
			(net "SMB_NIC0_SCL")
		)
		(pad "R16" smd circle
			(at 5.999988 5.199888 180)
			(size 0.4064 0.4064)
			(layers "F.Cu" "F.Mask" "F.Paste")
			(net "SMB_NIC2_SDA")
		)
		(pad "T1" smd circle
			(at -5.999988 5.999988 180)
			(size 0.4064 0.4064)
			(layers "F.Cu" "F.Mask" "F.Paste")
			(net "PRSNT_SSD0_R_N")
		)
		(pad "T2" smd circle
			(at -5.199888 5.999988 180)
			(size 0.4064 0.4064)
			(layers "F.Cu" "F.Mask" "F.Paste")
			(net "PRSNT_SSD2_R_N")
		)
		(pad "T3" smd circle
			(at -4.400042 5.999988 180)
			(size 0.4064 0.4064)
			(layers "F.Cu" "F.Mask" "F.Paste")
			(net "PRSNT_SSD3_R_N")
		)
		(pad "T4" smd circle
			(at -3.599942 5.999988 180)
			(size 0.4064 0.4064)
			(layers "F.Cu" "F.Mask" "F.Paste")
			(net "SSD1_PWRDIS_BIC")
		)
		(pad "T5" smd circle
			(at -2.800096 5.999988 180)
			(size 0.4064 0.4064)
			(layers "F.Cu" "F.Mask" "F.Paste")
			(net "SSD5_PWRDIS_BIC")
		)
		(pad "T6" smd circle
			(at -1.999996 5.999988 180)
			(size 0.4064 0.4064)
			(layers "F.Cu" "F.Mask" "F.Paste")
			(net "SSD7_PWRDIS_BIC")
		)
		(pad "T7" smd circle
			(at -1.199896 5.999988 180)
			(size 0.4064 0.4064)
			(layers "F.Cu" "F.Mask" "F.Paste")
			(net "SSD9_PWRDIS_BIC")
		)
		(pad "T8" smd circle
			(at -0.40005 5.999988 180)
			(size 0.4064 0.4064)
			(layers "F.Cu" "F.Mask" "F.Paste")
			(net "SSD11_PWRDIS_BIC")
		)
		(pad "T9" smd circle
			(at 0.40005 5.999988 180)
			(size 0.4064 0.4064)
			(layers "F.Cu" "F.Mask" "F.Paste")
			(net "NIC0_MAIN_PWR_BIC_EN")
		)
		(pad "T10" smd circle
			(at 1.199896 5.999988 180)
			(size 0.4064 0.4064)
			(layers "F.Cu" "F.Mask" "F.Paste")
			(net "NIC3_MAIN_PWR_BIC_EN")
		)
		(pad "T11" smd circle
			(at 1.999996 5.999988 180)
			(size 0.4064 0.4064)
			(layers "F.Cu" "F.Mask" "F.Paste")
			(net "NIC6_MAIN_PWR_BIC_EN")
		)
		(pad "T12" smd circle
			(at 2.800096 5.999988 180)
			(size 0.4064 0.4064)
			(layers "F.Cu" "F.Mask" "F.Paste")
			(net "REV_ID1")
		)
		(pad "T13" smd circle
			(at 3.599942 5.999988 180)
			(size 0.4064 0.4064)
			(layers "F.Cu" "F.Mask" "F.Paste")
			(net "BOARD_ID0")
		)
		(pad "T14" smd circle
			(at 4.400042 5.999988 180)
			(size 0.4064 0.4064)
			(layers "F.Cu" "F.Mask" "F.Paste")
			(net "HSC_TIMER_N")
		)
		(pad "T15" smd circle
			(at 5.199888 5.999988 180)
			(size 0.4064 0.4064)
			(layers "F.Cu" "F.Mask" "F.Paste")
			(net "HSC_D_OC_BIC_N")
		)
		(pad "T16" smd circle
			(at 5.999988 5.999988 180)
			(size 0.4064 0.4064)
			(layers "F.Cu" "F.Mask" "F.Paste")
			(net "SMB_NIC2_SCL")
		)
		(zone
			(layer "F.Cu")
			(hatch none 0.5)
			(connect_pads
				(clearance 0)
			)
			(min_thickness 0.25)
			(keepout
				(tracks allowed)
				(vias not_allowed)
				(pads allowed)
				(copperpour not_allowed)
				(footprints allowed)
			)
			(placement
				(enabled no)
				(sheetname "")
			)
			(fill
				(thermal_gap 0.5)
				(thermal_bridge_width 0.5)
				(island_removal_mode 0)
			)
			(polygon
				(pts
					(xy 229.613714 -225.720148) (xy 229.613714 -218.85021) (xy 236.483652 -218.85021) (xy 236.483652 -218.55811)
					(xy 229.613714 -218.55811) (xy 229.613714 -211.688172) (xy 229.321614 -211.688172) (xy 229.321614 -218.55811)
					(xy 222.451676 -218.55811) (xy 222.451676 -218.85021) (xy 229.321614 -218.85021) (xy 229.321614 -225.720148)
				)
			)
		)
	)
	(footprint ""
		(layer "F.Cu")
		(at 210.054444 -122.889264 180)
		(property "Reference" "PC448"
			(at 0 0 180)
			(layer "F.SilkS")
			(hide yes)
			(effects
				(font
					(size 1.27 1.27)
				)
			)
		)
		(property "Value" ""
			(at 0 0 180)
			(layer "F.Fab")
			(effects
				(font
					(size 1.27 1.27)
				)
			)
		)
		(duplicate_pad_numbers_are_jumpers no)
		(fp_line
			(start 0.7874 0.4064)
			(end -0.7874 0.4064)
			(stroke
				(width 0.1524)
				(type default)
			)
			(layer "F.SilkS")
		)
		(fp_line
			(start 0.7874 -0.4064)
			(end 0.7874 0.4064)
			(stroke
				(width 0.1524)
				(type default)
			)
			(layer "F.SilkS")
		)
		(fp_line
			(start -0.7874 0.4064)
			(end -0.7874 -0.4064)
			(stroke
				(width 0.1524)
				(type default)
			)
			(layer "F.SilkS")
		)
		(fp_line
			(start -0.7874 -0.4064)
			(end 0.7874 -0.4064)
			(stroke
				(width 0.1524)
				(type default)
			)
			(layer "F.SilkS")
		)
		(fp_line
			(start 0.67945 0.3048)
			(end 0.120396 0.3048)
			(stroke
				(width 0.1)
				(type default)
			)
			(layer "F.Fab")
		)
		(fp_line
			(start 0.67945 -0.3048)
			(end 0.67945 0.3048)
			(stroke
				(width 0.1)
				(type default)
			)
			(layer "F.Fab")
		)
		(fp_line
			(start 0.12065 -0.2794)
			(end 0.12065 -0.3048)
			(stroke
				(width 0.1)
				(type default)
			)
			(layer "F.Fab")
		)
		(fp_line
			(start 0.12065 -0.3048)
			(end 0.67945 -0.3048)
			(stroke
				(width 0.1)
				(type default)
			)
			(layer "F.Fab")
		)
		(fp_line
			(start 0.120396 0.3048)
			(end 0.120396 0.2794)
			(stroke
				(width 0.1)
				(type default)
			)
			(layer "F.Fab")
		)
		(fp_line
			(start 0.120396 0.2794)
			(end -0.12065 0.2794)
			(stroke
				(width 0.1)
				(type default)
			)
			(layer "F.Fab")
		)
		(fp_line
			(start -0.12065 0.3048)
			(end -0.67945 0.3048)
			(stroke
				(width 0.1)
				(type default)
			)
			(layer "F.Fab")
		)
		(fp_line
			(start -0.12065 0.2794)
			(end -0.12065 0.3048)
			(stroke
				(width 0.1)
				(type default)
			)
			(layer "F.Fab")
		)
		(fp_line
			(start -0.12065 -0.2794)
			(end 0.12065 -0.2794)
			(stroke
				(width 0.1)
				(type default)
			)
			(layer "F.Fab")
		)
		(fp_line
			(start -0.12065 -0.305054)
			(end -0.12065 -0.2794)
			(stroke
				(width 0.1)
				(type default)
			)
			(layer "F.Fab")
		)
		(fp_line
			(start -0.67945 0.3048)
			(end -0.67945 -0.305054)
			(stroke
				(width 0.1)
				(type default)
			)
			(layer "F.Fab")
		)
		(fp_line
			(start -0.67945 -0.305054)
			(end -0.12065 -0.305054)
			(stroke
				(width 0.1)
				(type default)
			)
			(layer "F.Fab")
		)
		(pad "1" smd circle
			(at -0.40005 0 180)
			(size 0 0)
			(layers "F.Cu" "F.Mask" "F.Paste")
			(net "P3V3_AUX")
		)
		(pad "2" smd circle
			(at 0.40005 0 180)
			(size 0 0)
			(layers "F.Cu" "F.Mask" "F.Paste")
			(net "GND")
		)
	)
	(footprint ""
		(layer "F.Cu")
		(at 250.407678 -152.71115 90)
		(property "Reference" "R728"
			(at 0 0 90)
			(layer "F.SilkS")
			(hide yes)
			(effects
				(font
					(size 1.27 1.27)
				)
			)
		)
		(property "Value" ""
			(at 0 0 90)
			(layer "F.Fab")
			(effects
				(font
					(size 1.27 1.27)
				)
			)
		)
		(duplicate_pad_numbers_are_jumpers no)
		(fp_line
			(start 0.7874 -0.4064)
			(end 0.7874 0.4064)
			(stroke
				(width 0.1524)
				(type default)
			)
			(layer "F.SilkS")
		)
		(fp_line
			(start -0.7874 -0.4064)
			(end 0.7874 -0.4064)
			(stroke
				(width 0.1524)
				(type default)
			)
			(layer "F.SilkS")
		)
		(fp_line
			(start 0.7874 0.4064)
			(end -0.7874 0.4064)
			(stroke
				(width 0.1524)
				(type default)
			)
			(layer "F.SilkS")
		)
		(fp_line
			(start -0.7874 0.4064)
			(end -0.7874 -0.4064)
			(stroke
				(width 0.1524)
				(type default)
			)
			(layer "F.SilkS")
		)
		(fp_line
			(start -0.12065 -0.305054)
			(end -0.12065 -0.2794)
			(stroke
				(width 0.1)
				(type default)
			)
			(layer "F.Fab")
		)
		(fp_line
			(start -0.67945 -0.305054)
			(end -0.12065 -0.305054)
			(stroke
				(width 0.1)
				(type default)
			)
			(layer "F.Fab")
		)
		(fp_line
			(start 0.67945 -0.3048)
			(end 0.67945 0.3048)
			(stroke
				(width 0.1)
				(type default)
			)
			(layer "F.Fab")
		)
		(fp_line
			(start 0.12065 -0.3048)
			(end 0.67945 -0.3048)
			(stroke
				(width 0.1)
				(type default)
			)
			(layer "F.Fab")
		)
		(fp_line
			(start 0.12065 -0.2794)
			(end 0.12065 -0.3048)
			(stroke
				(width 0.1)
				(type default)
			)
			(layer "F.Fab")
		)
		(fp_line
			(start -0.12065 -0.2794)
			(end 0.12065 -0.2794)
			(stroke
				(width 0.1)
				(type default)
			)
			(layer "F.Fab")
		)
		(fp_line
			(start 0.120396 0.2794)
			(end -0.12065 0.2794)
			(stroke
				(width 0.1)
				(type default)
			)
			(layer "F.Fab")
		)
		(fp_line
			(start -0.12065 0.2794)
			(end -0.12065 0.3048)
			(stroke
				(width 0.1)
				(type default)
			)
			(layer "F.Fab")
		)
		(fp_line
			(start 0.67945 0.3048)
			(end 0.120396 0.3048)
			(stroke
				(width 0.1)
				(type default)
			)
			(layer "F.Fab")
		)
		(fp_line
			(start 0.120396 0.3048)
			(end 0.120396 0.2794)
			(stroke
				(width 0.1)
				(type default)
			)
			(layer "F.Fab")
		)
		(fp_line
			(start -0.12065 0.3048)
			(end -0.67945 0.3048)
			(stroke
				(width 0.1)
				(type default)
			)
			(layer "F.Fab")
		)
		(fp_line
			(start -0.67945 0.3048)
			(end -0.67945 -0.305054)
			(stroke
				(width 0.1)
				(type default)
			)
			(layer "F.Fab")
		)
		(pad "1" smd circle
			(at -0.40005 0 90)
			(size 0 0)
			(layers "F.Cu" "F.Mask" "F.Paste")
			(net "NIC4_ADC_ALERT_N")
		)
		(pad "2" smd circle
			(at 0.40005 0 90)
			(size 0 0)
			(layers "F.Cu" "F.Mask" "F.Paste")
			(net "NIC_ADC_ALERT_N")
		)
	)
	(footprint ""
		(layer "F.Cu")
		(at 335.509362 -93.152214 90)
		(property "Reference" "R3511"
			(at 0 0 90)
			(layer "F.SilkS")
			(hide yes)
			(effects
				(font
					(size 1.27 1.27)
				)
			)
		)
		(property "Value" ""
			(at 0 0 90)
			(layer "F.Fab")
			(effects
				(font
					(size 1.27 1.27)
				)
			)
		)
		(duplicate_pad_numbers_are_jumpers no)
		(fp_line
			(start 0.7874 -0.4064)
			(end 0.7874 0.4064)
			(stroke
				(width 0.1524)
				(type default)
			)
			(layer "F.SilkS")
		)
		(fp_line
			(start -0.7874 -0.4064)
			(end 0.7874 -0.4064)
			(stroke
				(width 0.1524)
				(type default)
			)
			(layer "F.SilkS")
		)
		(fp_line
			(start 0.7874 0.4064)
			(end -0.7874 0.4064)
			(stroke
				(width 0.1524)
				(type default)
			)
			(layer "F.SilkS")
		)
		(fp_line
			(start -0.7874 0.4064)
			(end -0.7874 -0.4064)
			(stroke
				(width 0.1524)
				(type default)
			)
			(layer "F.SilkS")
		)
		(fp_line
			(start -0.12065 -0.305054)
			(end -0.12065 -0.2794)
			(stroke
				(width 0.1)
				(type default)
			)
			(layer "F.Fab")
		)
		(fp_line
			(start -0.67945 -0.305054)
			(end -0.12065 -0.305054)
			(stroke
				(width 0.1)
				(type default)
			)
			(layer "F.Fab")
		)
		(fp_line
			(start 0.67945 -0.3048)
			(end 0.67945 0.3048)
			(stroke
				(width 0.1)
				(type default)
			)
			(layer "F.Fab")
		)
		(fp_line
			(start 0.12065 -0.3048)
			(end 0.67945 -0.3048)
			(stroke
				(width 0.1)
				(type default)
			)
			(layer "F.Fab")
		)
		(fp_line
			(start 0.12065 -0.2794)
			(end 0.12065 -0.3048)
			(stroke
				(width 0.1)
				(type default)
			)
			(layer "F.Fab")
		)
		(fp_line
			(start -0.12065 -0.2794)
			(end 0.12065 -0.2794)
			(stroke
				(width 0.1)
				(type default)
			)
			(layer "F.Fab")
		)
		(fp_line
			(start 0.120396 0.2794)
			(end -0.12065 0.2794)
			(stroke
				(width 0.1)
				(type default)
			)
			(layer "F.Fab")
		)
		(fp_line
			(start -0.12065 0.2794)
			(end -0.12065 0.3048)
			(stroke
				(width 0.1)
				(type default)
			)
			(layer "F.Fab")
		)
		(fp_line
			(start 0.67945 0.3048)
			(end 0.120396 0.3048)
			(stroke
				(width 0.1)
				(type default)
			)
			(layer "F.Fab")
		)
		(fp_line
			(start 0.120396 0.3048)
			(end 0.120396 0.2794)
			(stroke
				(width 0.1)
				(type default)
			)
			(layer "F.Fab")
		)
		(fp_line
			(start -0.12065 0.3048)
			(end -0.67945 0.3048)
			(stroke
				(width 0.1)
				(type default)
			)
			(layer "F.Fab")
		)
		(fp_line
			(start -0.67945 0.3048)
			(end -0.67945 -0.305054)
			(stroke
				(width 0.1)
				(type default)
			)
			(layer "F.Fab")
		)
		(pad "1" smd circle
			(at -0.40005 0 90)
			(size 0 0)
			(layers "F.Cu" "F.Mask" "F.Paste")
			(net "PU_9ZXL0851_8_15_HBW")
		)
		(pad "2" smd circle
			(at 0.40005 0 90)
			(size 0 0)
			(layers "F.Cu" "F.Mask" "F.Paste")
			(net "GND")
		)
	)
	(footprint ""
		(layer "F.Cu")
		(at 268.220698 -333.104744)
		(property "Reference" "R6793"
			(at 0 0 0)
			(layer "F.SilkS")
			(hide yes)
			(effects
				(font
					(size 1.27 1.27)
				)
			)
		)
		(property "Value" ""
			(at 0 0 0)
			(layer "F.Fab")
			(effects
				(font
					(size 1.27 1.27)
				)
			)
		)
		(duplicate_pad_numbers_are_jumpers no)
		(fp_line
			(start -0.7874 -0.4064)
			(end 0.7874 -0.4064)
			(stroke
				(width 0.1524)
				(type default)
			)
			(layer "F.SilkS")
		)
		(fp_line
			(start -0.7874 0.4064)
			(end -0.7874 -0.4064)
			(stroke
				(width 0.1524)
				(type default)
			)
			(layer "F.SilkS")
		)
		(fp_line
			(start 0.7874 -0.4064)
			(end 0.7874 0.4064)
			(stroke
				(width 0.1524)
				(type default)
			)
			(layer "F.SilkS")
		)
		(fp_line
			(start 0.7874 0.4064)
			(end -0.7874 0.4064)
			(stroke
				(width 0.1524)
				(type default)
			)
			(layer "F.SilkS")
		)
		(fp_line
			(start -0.67945 -0.305054)
			(end -0.12065 -0.305054)
			(stroke
				(width 0.1)
				(type default)
			)
			(layer "F.Fab")
		)
		(fp_line
			(start -0.67945 0.3048)
			(end -0.67945 -0.305054)
			(stroke
				(width 0.1)
				(type default)
			)
			(layer "F.Fab")
		)
		(fp_line
			(start -0.12065 -0.305054)
			(end -0.12065 -0.2794)
			(stroke
				(width 0.1)
				(type default)
			)
			(layer "F.Fab")
		)
		(fp_line
			(start -0.12065 -0.2794)
			(end 0.12065 -0.2794)
			(stroke
				(width 0.1)
				(type default)
			)
			(layer "F.Fab")
		)
		(fp_line
			(start -0.12065 0.2794)
			(end -0.12065 0.3048)
			(stroke
				(width 0.1)
				(type default)
			)
			(layer "F.Fab")
		)
		(fp_line
			(start -0.12065 0.3048)
			(end -0.67945 0.3048)
			(stroke
				(width 0.1)
				(type default)
			)
			(layer "F.Fab")
		)
		(fp_line
			(start 0.120396 0.2794)
			(end -0.12065 0.2794)
			(stroke
				(width 0.1)
				(type default)
			)
			(layer "F.Fab")
		)
		(fp_line
			(start 0.120396 0.3048)
			(end 0.120396 0.2794)
			(stroke
				(width 0.1)
				(type default)
			)
			(layer "F.Fab")
		)
		(fp_line
			(start 0.12065 -0.3048)
			(end 0.67945 -0.3048)
			(stroke
				(width 0.1)
				(type default)
			)
			(layer "F.Fab")
		)
		(fp_line
			(start 0.12065 -0.2794)
			(end 0.12065 -0.3048)
			(stroke
				(width 0.1)
				(type default)
			)
			(layer "F.Fab")
		)
		(fp_line
			(start 0.67945 -0.3048)
			(end 0.67945 0.3048)
			(stroke
				(width 0.1)
				(type default)
			)
			(layer "F.Fab")
		)
		(fp_line
			(start 0.67945 0.3048)
			(end 0.120396 0.3048)
			(stroke
				(width 0.1)
				(type default)
			)
			(layer "F.Fab")
		)
		(pad "1" smd circle
			(at -0.40005 0)
			(size 0 0)
			(layers "F.Cu" "F.Mask" "F.Paste")
			(net "P3V3_AUX")
		)
		(pad "2" smd circle
			(at 0.40005 0)
			(size 0 0)
			(layers "F.Cu" "F.Mask" "F.Paste")
			(net "A_HSC_LOW_GATE")
		)
	)
	(footprint ""
		(layer "F.Cu")
		(at 244.696996 -277.791926 180)
		(property "Reference" "U94"
			(at -0.799338 -4.270756 0)
			(unlocked yes)
			(layer "F.SilkS")
			(effects
				(font
					(size 0.7874 0.5842)
					(thickness 0.1524)
				)
			)
		)
		(property "Value" ""
			(at 0 0 180)
			(layer "F.Fab")
			(effects
				(font
					(size 1.27 1.27)
				)
			)
		)
		(duplicate_pad_numbers_are_jumpers no)
		(fp_line
			(start 1.500124 1.500124)
			(end 1.004062 1.500124)
			(stroke
				(width 0.1524)
				(type default)
			)
			(layer "F.SilkS")
		)
		(fp_line
			(start 1.500124 1.004062)
			(end 1.500124 1.500124)
			(stroke
				(width 0.1524)
				(type default)
			)
			(layer "F.SilkS")
		)
		(fp_line
			(start 1.500124 -1.500124)
			(end 1.500124 -1.004062)
			(stroke
				(width 0.1524)
				(type default)
			)
			(layer "F.SilkS")
		)
		(fp_line
			(start 1.004062 -1.500124)
			(end 1.500124 -1.500124)
			(stroke
				(width 0.1524)
				(type default)
			)
			(layer "F.SilkS")
		)
		(fp_line
			(start -1.004062 1.500124)
			(end -1.500124 1.500124)
			(stroke
				(width 0.1524)
				(type default)
			)
			(layer "F.SilkS")
		)
		(fp_line
			(start -1.500124 1.500124)
			(end -1.500124 1.004062)
			(stroke
				(width 0.1524)
				(type default)
			)
			(layer "F.SilkS")
		)
		(fp_line
			(start -1.500124 -1.004062)
			(end -1.500124 -1.500124)
			(stroke
				(width 0.1524)
				(type default)
			)
			(layer "F.SilkS")
		)
		(fp_line
			(start -1.500124 -1.500124)
			(end -1.004062 -1.500124)
			(stroke
				(width 0.1524)
				(type default)
			)
			(layer "F.SilkS")
		)
		(fp_poly
			(pts
				(xy -1.153414 -2.31267) (xy -2.169414 -2.31267) (xy -1.661414 -1.29667)
			)
			(stroke
				(width 0)
				(type default)
			)
			(fill yes)
			(layer "F.SilkS")
		)
		(fp_line
			(start 1.500124 1.500124)
			(end -1.500124 1.500124)
			(stroke
				(width 0.1)
				(type default)
			)
			(layer "F.Fab")
		)
		(fp_line
			(start 1.500124 -1.500124)
			(end 1.500124 1.500124)
			(stroke
				(width 0.1)
				(type default)
			)
			(layer "F.Fab")
		)
		(fp_line
			(start -1.500124 1.500124)
			(end -1.500124 -1.500124)
			(stroke
				(width 0.1)
				(type default)
			)
			(layer "F.Fab")
		)
		(fp_line
			(start -1.500124 -1.500124)
			(end 1.500124 -1.500124)
			(stroke
				(width 0.1)
				(type default)
			)
			(layer "F.Fab")
		)
		(fp_poly
			(pts
				(xy -2.847848 -1.258062) (xy -2.847848 -0.242062) (xy -1.831848 -0.750062)
			)
			(stroke
				(width 0)
				(type default)
			)
			(fill yes)
			(layer "F.Fab")
		)
		(pad "1" smd rect
			(at -1.400048 -0.750062 90)
			(size 0.2286 0.6096)
			(layers "F.Cu" "F.Mask" "F.Paste")
			(net "PEX2_P1V25_ADC_A1")
		)
		(pad "2" smd rect
			(at -1.400048 -0.249936 90)
			(size 0.2286 0.6096)
			(layers "F.Cu" "F.Mask" "F.Paste")
			(net "PEX2_P1V25_ADC_A0")
		)
		(pad "3" smd rect
			(at -1.400048 0.249936 90)
			(size 0.2286 0.6096)
			(layers "F.Cu" "F.Mask" "F.Paste")
			(net "PEX2_P1V25_ADC_ALERT_N")
		)
		(pad "4" smd rect
			(at -1.400048 0.750062 90)
			(size 0.2286 0.6096)
			(layers "F.Cu" "F.Mask" "F.Paste")
			(net "SMB_PEX2_P1V25_ADC_SDA")
		)
		(pad "5" smd rect
			(at -0.750062 1.400048 180)
			(size 0.2286 0.6096)
			(layers "F.Cu" "F.Mask" "F.Paste")
			(net "SMB_PEX2_P1V25_ADC_SCL")
		)
		(pad "6" smd rect
			(at -0.249936 1.400048 180)
			(size 0.2286 0.6096)
			(layers "F.Cu" "F.Mask" "F.Paste")
			(net "Net_8606")
		)
		(pad "7" smd rect
			(at 0.249936 1.400048 180)
			(size 0.2286 0.6096)
			(layers "F.Cu" "F.Mask" "F.Paste")
			(net "Net_8605")
		)
		(pad "8" smd rect
			(at 0.750062 1.400048 180)
			(size 0.2286 0.6096)
			(layers "F.Cu" "F.Mask" "F.Paste")
			(net "Net_8604")
		)
		(pad "9" smd rect
			(at 1.400048 0.750062 90)
			(size 0.2286 0.6096)
			(layers "F.Cu" "F.Mask" "F.Paste")
			(net "P3V3_AUX")
		)
		(pad "10" smd rect
			(at 1.400048 0.249936 90)
			(size 0.2286 0.6096)
			(layers "F.Cu" "F.Mask" "F.Paste")
			(net "GND")
		)
		(pad "11" smd rect
			(at 1.400048 -0.249936 90)
			(size 0.2286 0.6096)
			(layers "F.Cu" "F.Mask" "F.Paste")
			(net "P1V25_PEX2_R")
		)
		(pad "12" smd rect
			(at 1.400048 -0.750062 90)
			(size 0.2286 0.6096)
			(layers "F.Cu" "F.Mask" "F.Paste")
			(net "P12V_PEX2_P1V25_VIN_N")
		)
		(pad "13" smd rect
			(at 0.750062 -1.400048 180)
			(size 0.2286 0.6096)
			(layers "F.Cu" "F.Mask" "F.Paste")
			(net "P12V_PEX2_P1V25_VIN_P")
		)
		(pad "14" smd rect
			(at 0.249936 -1.400048 180)
			(size 0.2286 0.6096)
			(layers "F.Cu" "F.Mask" "F.Paste")
			(net "Net_8603")
		)
		(pad "15" smd rect
			(at -0.249936 -1.400048 180)
			(size 0.2286 0.6096)
			(layers "F.Cu" "F.Mask" "F.Paste")
			(net "Net_8602")
		)
		(pad "16" smd rect
			(at -0.750062 -1.400048 180)
			(size 0.2286 0.6096)
			(layers "F.Cu" "F.Mask" "F.Paste")
			(net "Net_8601")
		)
		(pad "TH" smd rect
			(at 0 0 180)
			(size 1.7018 1.7018)
			(layers "F.Cu" "F.Mask" "F.Paste")
			(net "GND")
		)
		(zone
			(layer "F.Cu")
			(hatch none 0.5)
			(connect_pads
				(clearance 0)
			)
			(min_thickness 0.25)
			(keepout
				(tracks not_allowed)
				(vias allowed)
				(pads allowed)
				(copperpour not_allowed)
				(footprints allowed)
			)
			(placement
				(enabled no)
				(sheetname "")
			)
			(fill
				(thermal_gap 0.5)
				(thermal_bridge_width 0.5)
				(island_removal_mode 0)
			)
			(polygon
				(pts
					(xy 245.741444 -277.766526) (xy 245.741444 -276.747478) (xy 243.652548 -276.747478) (xy 243.652548 -278.836374)
					(xy 245.741444 -278.836374) (xy 245.741444 -277.791926) (xy 245.598696 -277.791926) (xy 245.598696 -278.693626)
					(xy 243.795296 -278.693626) (xy 243.795296 -276.890226) (xy 245.598696 -276.890226) (xy 245.598696 -277.766526)
				)
			)
		)
	)
	(footprint ""
		(layer "F.Cu")
		(at 121.13514 -92.605606)
		(property "Reference" "R1555"
			(at 0 0 0)
			(layer "F.SilkS")
			(hide yes)
			(effects
				(font
					(size 1.27 1.27)
				)
			)
		)
		(property "Value" ""
			(at 0 0 0)
			(layer "F.Fab")
			(effects
				(font
					(size 1.27 1.27)
				)
			)
		)
		(duplicate_pad_numbers_are_jumpers no)
		(fp_line
			(start -0.7874 -0.4064)
			(end 0.7874 -0.4064)
			(stroke
				(width 0.1524)
				(type default)
			)
			(layer "F.SilkS")
		)
		(fp_line
			(start -0.7874 0.4064)
			(end -0.7874 -0.4064)
			(stroke
				(width 0.1524)
				(type default)
			)
			(layer "F.SilkS")
		)
		(fp_line
			(start 0.7874 -0.4064)
			(end 0.7874 0.4064)
			(stroke
				(width 0.1524)
				(type default)
			)
			(layer "F.SilkS")
		)
		(fp_line
			(start 0.7874 0.4064)
			(end -0.7874 0.4064)
			(stroke
				(width 0.1524)
				(type default)
			)
			(layer "F.SilkS")
		)
		(fp_line
			(start -0.67945 -0.305054)
			(end -0.12065 -0.305054)
			(stroke
				(width 0.1)
				(type default)
			)
			(layer "F.Fab")
		)
		(fp_line
			(start -0.67945 0.3048)
			(end -0.67945 -0.305054)
			(stroke
				(width 0.1)
				(type default)
			)
			(layer "F.Fab")
		)
		(fp_line
			(start -0.12065 -0.305054)
			(end -0.12065 -0.2794)
			(stroke
				(width 0.1)
				(type default)
			)
			(layer "F.Fab")
		)
		(fp_line
			(start -0.12065 -0.2794)
			(end 0.12065 -0.2794)
			(stroke
				(width 0.1)
				(type default)
			)
			(layer "F.Fab")
		)
		(fp_line
			(start -0.12065 0.2794)
			(end -0.12065 0.3048)
			(stroke
				(width 0.1)
				(type default)
			)
			(layer "F.Fab")
		)
		(fp_line
			(start -0.12065 0.3048)
			(end -0.67945 0.3048)
			(stroke
				(width 0.1)
				(type default)
			)
			(layer "F.Fab")
		)
		(fp_line
			(start 0.120396 0.2794)
			(end -0.12065 0.2794)
			(stroke
				(width 0.1)
				(type default)
			)
			(layer "F.Fab")
		)
		(fp_line
			(start 0.120396 0.3048)
			(end 0.120396 0.2794)
			(stroke
				(width 0.1)
				(type default)
			)
			(layer "F.Fab")
		)
		(fp_line
			(start 0.12065 -0.3048)
			(end 0.67945 -0.3048)
			(stroke
				(width 0.1)
				(type default)
			)
			(layer "F.Fab")
		)
		(fp_line
			(start 0.12065 -0.2794)
			(end 0.12065 -0.3048)
			(stroke
				(width 0.1)
				(type default)
			)
			(layer "F.Fab")
		)
		(fp_line
			(start 0.67945 -0.3048)
			(end 0.67945 0.3048)
			(stroke
				(width 0.1)
				(type default)
			)
			(layer "F.Fab")
		)
		(fp_line
			(start 0.67945 0.3048)
			(end 0.120396 0.3048)
			(stroke
				(width 0.1)
				(type default)
			)
			(layer "F.Fab")
		)
		(pad "1" smd circle
			(at -0.40005 0)
			(size 0 0)
			(layers "F.Cu" "F.Mask" "F.Paste")
			(net "P3V3_AUX")
		)
		(pad "2" smd circle
			(at 0.40005 0)
			(size 0 0)
			(layers "F.Cu" "F.Mask" "F.Paste")
			(net "SMB_BIC_I2C9_MUX0_SSD2_R_SDA")
		)
	)
	(footprint ""
		(layer "F.Cu")
		(at 7.849362 -251.312426 -90)
		(property "Reference" "C4226"
			(at 0 0 270)
			(layer "F.SilkS")
			(hide yes)
			(effects
				(font
					(size 1.27 1.27)
				)
			)
		)
		(property "Value" ""
			(at 0 0 270)
			(layer "F.Fab")
			(effects
				(font
					(size 1.27 1.27)
				)
			)
		)
		(duplicate_pad_numbers_are_jumpers no)
		(fp_line
			(start -1.2954 0.5842)
			(end -1.2954 -0.5842)
			(stroke
				(width 0.1524)
				(type default)
			)
			(layer "F.SilkS")
		)
		(fp_line
			(start 1.2954 0.5842)
			(end -1.2954 0.5842)
			(stroke
				(width 0.1524)
				(type default)
			)
			(layer "F.SilkS")
		)
		(fp_line
			(start -1.2954 -0.5842)
			(end 1.2954 -0.5842)
			(stroke
				(width 0.1524)
				(type default)
			)
			(layer "F.SilkS")
		)
		(fp_line
			(start 1.2954 -0.5842)
			(end 1.2954 0.5842)
			(stroke
				(width 0.1524)
				(type default)
			)
			(layer "F.SilkS")
		)
		(fp_line
			(start -0.8636 0.4572)
			(end -0.8636 0.4064)
			(stroke
				(width 0.1)
				(type default)
			)
			(layer "F.Fab")
		)
		(fp_line
			(start 0.8636 0.4572)
			(end -0.8636 0.4572)
			(stroke
				(width 0.1)
				(type default)
			)
			(layer "F.Fab")
		)
		(fp_line
			(start -1.1938 0.4064)
			(end -1.1938 -0.4064)
			(stroke
				(width 0.1)
				(type default)
			)
			(layer "F.Fab")
		)
		(fp_line
			(start -0.8636 0.4064)
			(end -1.1938 0.4064)
			(stroke
				(width 0.1)
				(type default)
			)
			(layer "F.Fab")
		)
		(fp_line
			(start 0.8636 0.4064)
			(end 0.8636 0.4572)
			(stroke
				(width 0.1)
				(type default)
			)
			(layer "F.Fab")
		)
		(fp_line
			(start 1.1938 0.4064)
			(end 0.8636 0.4064)
			(stroke
				(width 0.1)
				(type default)
			)
			(layer "F.Fab")
		)
		(fp_line
			(start -1.1938 -0.4064)
			(end -0.8636 -0.4064)
			(stroke
				(width 0.1)
				(type default)
			)
			(layer "F.Fab")
		)
		(fp_line
			(start -0.8636 -0.4064)
			(end -0.8636 -0.4572)
			(stroke
				(width 0.1)
				(type default)
			)
			(layer "F.Fab")
		)
		(fp_line
			(start 0.8636 -0.4064)
			(end 1.1938 -0.4064)
			(stroke
				(width 0.1)
				(type default)
			)
			(layer "F.Fab")
		)
		(fp_line
			(start 1.1938 -0.4064)
			(end 1.1938 0.4064)
			(stroke
				(width 0.1)
				(type default)
			)
			(layer "F.Fab")
		)
		(fp_line
			(start -0.8636 -0.4572)
			(end 0.8636 -0.4572)
			(stroke
				(width 0.1)
				(type default)
			)
			(layer "F.Fab")
		)
		(fp_line
			(start 0.8636 -0.4572)
			(end 0.8636 -0.4064)
			(stroke
				(width 0.1)
				(type default)
			)
			(layer "F.Fab")
		)
		(pad "1" smd rect
			(at -0.7366 0 180)
			(size 0.7112 0.8128)
			(layers "F.Cu" "F.Mask" "F.Paste")
			(net "P1V25_SERDES_VDDPLL_PEX0_C0")
		)
		(pad "2" smd rect
			(at 0.7366 0 180)
			(size 0.7112 0.8128)
			(layers "F.Cu" "F.Mask" "F.Paste")
			(net "GND")
		)
	)
	(footprint ""
		(layer "F.Cu")
		(at 420.746428 -58.323734)
		(property "Reference" "PC439"
			(at 0 0 0)
			(layer "F.SilkS")
			(hide yes)
			(effects
				(font
					(size 1.27 1.27)
				)
			)
		)
		(property "Value" ""
			(at 0 0 0)
			(layer "F.Fab")
			(effects
				(font
					(size 1.27 1.27)
				)
			)
		)
		(duplicate_pad_numbers_are_jumpers no)
		(fp_line
			(start -1.524 -0.762)
			(end 1.524 -0.762)
			(stroke
				(width 0.1524)
				(type default)
			)
			(layer "F.SilkS")
		)
		(fp_line
			(start -1.524 0.762)
			(end -1.524 -0.762)
			(stroke
				(width 0.1524)
				(type default)
			)
			(layer "F.SilkS")
		)
		(fp_line
			(start 1.524 -0.762)
			(end 1.524 0.762)
			(stroke
				(width 0.1524)
				(type default)
			)
			(layer "F.SilkS")
		)
		(fp_line
			(start 1.524 0.762)
			(end -1.524 0.762)
			(stroke
				(width 0.1524)
				(type default)
			)
			(layer "F.SilkS")
		)
		(fp_line
			(start -1.1049 -0.724916)
			(end -1.1049 0.724916)
			(stroke
				(width 0.1)
				(type default)
			)
			(layer "F.Fab")
		)
		(fp_line
			(start -1.1049 0.724916)
			(end 1.1049 0.724916)
			(stroke
				(width 0.1)
				(type default)
			)
			(layer "F.Fab")
		)
		(fp_line
			(start 1.1049 -0.724916)
			(end -1.1049 -0.724916)
			(stroke
				(width 0.1)
				(type default)
			)
			(layer "F.Fab")
		)
		(fp_line
			(start 1.1049 0.724916)
			(end 1.1049 -0.724916)
			(stroke
				(width 0.1)
				(type default)
			)
			(layer "F.Fab")
		)
		(pad "1" smd rect
			(at -0.889 0 180)
			(size 1.016 1.27)
			(layers "F.Cu" "F.Mask" "F.Paste")
			(net "GND")
		)
		(pad "2" smd rect
			(at 0.889 0 180)
			(size 1.016 1.27)
			(layers "F.Cu" "F.Mask" "F.Paste")
			(net "P12V_AUX")
		)
	)
	(footprint ""
		(layer "F.Cu")
		(at 145.988278 -260.84911 -90)
		(property "Reference" "C3193"
			(at 0 0 270)
			(layer "F.SilkS")
			(hide yes)
			(effects
				(font
					(size 1.27 1.27)
				)
			)
		)
		(property "Value" ""
			(at 0 0 270)
			(layer "F.Fab")
			(effects
				(font
					(size 1.27 1.27)
				)
			)
		)
		(duplicate_pad_numbers_are_jumpers no)
		(fp_line
			(start -1.2954 0.5842)
			(end -1.2954 -0.5842)
			(stroke
				(width 0.1524)
				(type default)
			)
			(layer "F.SilkS")
		)
		(fp_line
			(start 1.2954 0.5842)
			(end -1.2954 0.5842)
			(stroke
				(width 0.1524)
				(type default)
			)
			(layer "F.SilkS")
		)
		(fp_line
			(start -1.2954 -0.5842)
			(end 1.2954 -0.5842)
			(stroke
				(width 0.1524)
				(type default)
			)
			(layer "F.SilkS")
		)
		(fp_line
			(start 1.2954 -0.5842)
			(end 1.2954 0.5842)
			(stroke
				(width 0.1524)
				(type default)
			)
			(layer "F.SilkS")
		)
		(fp_line
			(start -0.8636 0.4572)
			(end -0.8636 0.4064)
			(stroke
				(width 0.1)
				(type default)
			)
			(layer "F.Fab")
		)
		(fp_line
			(start 0.8636 0.4572)
			(end -0.8636 0.4572)
			(stroke
				(width 0.1)
				(type default)
			)
			(layer "F.Fab")
		)
		(fp_line
			(start -1.1938 0.4064)
			(end -1.1938 -0.4064)
			(stroke
				(width 0.1)
				(type default)
			)
			(layer "F.Fab")
		)
		(fp_line
			(start -0.8636 0.4064)
			(end -1.1938 0.4064)
			(stroke
				(width 0.1)
				(type default)
			)
			(layer "F.Fab")
		)
		(fp_line
			(start 0.8636 0.4064)
			(end 0.8636 0.4572)
			(stroke
				(width 0.1)
				(type default)
			)
			(layer "F.Fab")
		)
		(fp_line
			(start 1.1938 0.4064)
			(end 0.8636 0.4064)
			(stroke
				(width 0.1)
				(type default)
			)
			(layer "F.Fab")
		)
		(fp_line
			(start -1.1938 -0.4064)
			(end -0.8636 -0.4064)
			(stroke
				(width 0.1)
				(type default)
			)
			(layer "F.Fab")
		)
		(fp_line
			(start -0.8636 -0.4064)
			(end -0.8636 -0.4572)
			(stroke
				(width 0.1)
				(type default)
			)
			(layer "F.Fab")
		)
		(fp_line
			(start 0.8636 -0.4064)
			(end 1.1938 -0.4064)
			(stroke
				(width 0.1)
				(type default)
			)
			(layer "F.Fab")
		)
		(fp_line
			(start 1.1938 -0.4064)
			(end 1.1938 0.4064)
			(stroke
				(width 0.1)
				(type default)
			)
			(layer "F.Fab")
		)
		(fp_line
			(start -0.8636 -0.4572)
			(end 0.8636 -0.4572)
			(stroke
				(width 0.1)
				(type default)
			)
			(layer "F.Fab")
		)
		(fp_line
			(start 0.8636 -0.4572)
			(end 0.8636 -0.4064)
			(stroke
				(width 0.1)
				(type default)
			)
			(layer "F.Fab")
		)
		(pad "1" smd rect
			(at -0.7366 0 180)
			(size 0.7112 0.8128)
			(layers "F.Cu" "F.Mask" "F.Paste")
			(net "P1V8_PLL0_PEX1")
		)
		(pad "2" smd rect
			(at 0.7366 0 180)
			(size 0.7112 0.8128)
			(layers "F.Cu" "F.Mask" "F.Paste")
			(net "GND")
		)
	)
	(footprint ""
		(layer "F.Cu")
		(at 327.533 -215.265 180)
		(property "Reference" "R4157"
			(at 0 0 180)
			(layer "F.SilkS")
			(hide yes)
			(effects
				(font
					(size 1.27 1.27)
				)
			)
		)
		(property "Value" ""
			(at 0 0 180)
			(layer "F.Fab")
			(effects
				(font
					(size 1.27 1.27)
				)
			)
		)
		(duplicate_pad_numbers_are_jumpers no)
		(fp_line
			(start 0.7874 0.4064)
			(end -0.7874 0.4064)
			(stroke
				(width 0.1524)
				(type default)
			)
			(layer "F.SilkS")
		)
		(fp_line
			(start 0.7874 -0.4064)
			(end 0.7874 0.4064)
			(stroke
				(width 0.1524)
				(type default)
			)
			(layer "F.SilkS")
		)
		(fp_line
			(start -0.7874 0.4064)
			(end -0.7874 -0.4064)
			(stroke
				(width 0.1524)
				(type default)
			)
			(layer "F.SilkS")
		)
		(fp_line
			(start -0.7874 -0.4064)
			(end 0.7874 -0.4064)
			(stroke
				(width 0.1524)
				(type default)
			)
			(layer "F.SilkS")
		)
		(fp_line
			(start 0.67945 0.3048)
			(end 0.120396 0.3048)
			(stroke
				(width 0.1)
				(type default)
			)
			(layer "F.Fab")
		)
		(fp_line
			(start 0.67945 -0.3048)
			(end 0.67945 0.3048)
			(stroke
				(width 0.1)
				(type default)
			)
			(layer "F.Fab")
		)
		(fp_line
			(start 0.12065 -0.2794)
			(end 0.12065 -0.3048)
			(stroke
				(width 0.1)
				(type default)
			)
			(layer "F.Fab")
		)
		(fp_line
			(start 0.12065 -0.3048)
			(end 0.67945 -0.3048)
			(stroke
				(width 0.1)
				(type default)
			)
			(layer "F.Fab")
		)
		(fp_line
			(start 0.120396 0.3048)
			(end 0.120396 0.2794)
			(stroke
				(width 0.1)
				(type default)
			)
			(layer "F.Fab")
		)
		(fp_line
			(start 0.120396 0.2794)
			(end -0.12065 0.2794)
			(stroke
				(width 0.1)
				(type default)
			)
			(layer "F.Fab")
		)
		(fp_line
			(start -0.12065 0.3048)
			(end -0.67945 0.3048)
			(stroke
				(width 0.1)
				(type default)
			)
			(layer "F.Fab")
		)
		(fp_line
			(start -0.12065 0.2794)
			(end -0.12065 0.3048)
			(stroke
				(width 0.1)
				(type default)
			)
			(layer "F.Fab")
		)
		(fp_line
			(start -0.12065 -0.2794)
			(end 0.12065 -0.2794)
			(stroke
				(width 0.1)
				(type default)
			)
			(layer "F.Fab")
		)
		(fp_line
			(start -0.12065 -0.305054)
			(end -0.12065 -0.2794)
			(stroke
				(width 0.1)
				(type default)
			)
			(layer "F.Fab")
		)
		(fp_line
			(start -0.67945 0.3048)
			(end -0.67945 -0.305054)
			(stroke
				(width 0.1)
				(type default)
			)
			(layer "F.Fab")
		)
		(fp_line
			(start -0.67945 -0.305054)
			(end -0.12065 -0.305054)
			(stroke
				(width 0.1)
				(type default)
			)
			(layer "F.Fab")
		)
		(pad "1" smd circle
			(at -0.40005 0 180)
			(size 0 0)
			(layers "F.Cu" "F.Mask" "F.Paste")
			(net "PRSNT_SSD10_FPGA_N")
		)
		(pad "2" smd circle
			(at 0.40005 0 180)
			(size 0 0)
			(layers "F.Cu" "F.Mask" "F.Paste")
			(net "PRSNT_SSD10_FPGA_R_N")
		)
	)
	(footprint ""
		(layer "F.Cu")
		(at 150.331932 -388.21741 90)
		(property "Reference" "C4097"
			(at 0 0 90)
			(layer "F.SilkS")
			(hide yes)
			(effects
				(font
					(size 1.27 1.27)
				)
			)
		)
		(property "Value" ""
			(at 0 0 90)
			(layer "F.Fab")
			(effects
				(font
					(size 1.27 1.27)
				)
			)
		)
		(duplicate_pad_numbers_are_jumpers no)
		(fp_line
			(start 0.7874 -0.4064)
			(end 0.7874 0.4064)
			(stroke
				(width 0.1524)
				(type default)
			)
			(layer "F.SilkS")
		)
		(fp_line
			(start -0.7874 -0.4064)
			(end 0.7874 -0.4064)
			(stroke
				(width 0.1524)
				(type default)
			)
			(layer "F.SilkS")
		)
		(fp_line
			(start 0.7874 0.4064)
			(end -0.7874 0.4064)
			(stroke
				(width 0.1524)
				(type default)
			)
			(layer "F.SilkS")
		)
		(fp_line
			(start -0.7874 0.4064)
			(end -0.7874 -0.4064)
			(stroke
				(width 0.1524)
				(type default)
			)
			(layer "F.SilkS")
		)
		(fp_line
			(start -0.12065 -0.305054)
			(end -0.12065 -0.2794)
			(stroke
				(width 0.1)
				(type default)
			)
			(layer "F.Fab")
		)
		(fp_line
			(start -0.67945 -0.305054)
			(end -0.12065 -0.305054)
			(stroke
				(width 0.1)
				(type default)
			)
			(layer "F.Fab")
		)
		(fp_line
			(start 0.67945 -0.3048)
			(end 0.67945 0.3048)
			(stroke
				(width 0.1)
				(type default)
			)
			(layer "F.Fab")
		)
		(fp_line
			(start 0.12065 -0.3048)
			(end 0.67945 -0.3048)
			(stroke
				(width 0.1)
				(type default)
			)
			(layer "F.Fab")
		)
		(fp_line
			(start 0.12065 -0.2794)
			(end 0.12065 -0.3048)
			(stroke
				(width 0.1)
				(type default)
			)
			(layer "F.Fab")
		)
		(fp_line
			(start -0.12065 -0.2794)
			(end 0.12065 -0.2794)
			(stroke
				(width 0.1)
				(type default)
			)
			(layer "F.Fab")
		)
		(fp_line
			(start 0.120396 0.2794)
			(end -0.12065 0.2794)
			(stroke
				(width 0.1)
				(type default)
			)
			(layer "F.Fab")
		)
		(fp_line
			(start -0.12065 0.2794)
			(end -0.12065 0.3048)
			(stroke
				(width 0.1)
				(type default)
			)
			(layer "F.Fab")
		)
		(fp_line
			(start 0.67945 0.3048)
			(end 0.120396 0.3048)
			(stroke
				(width 0.1)
				(type default)
			)
			(layer "F.Fab")
		)
		(fp_line
			(start 0.120396 0.3048)
			(end 0.120396 0.2794)
			(stroke
				(width 0.1)
				(type default)
			)
			(layer "F.Fab")
		)
		(fp_line
			(start -0.12065 0.3048)
			(end -0.67945 0.3048)
			(stroke
				(width 0.1)
				(type default)
			)
			(layer "F.Fab")
		)
		(fp_line
			(start -0.67945 0.3048)
			(end -0.67945 -0.305054)
			(stroke
				(width 0.1)
				(type default)
			)
			(layer "F.Fab")
		)
		(pad "1" smd circle
			(at -0.40005 0 90)
			(size 0 0)
			(layers "F.Cu" "F.Mask" "F.Paste")
			(net "GND")
		)
		(pad "2" smd circle
			(at 0.40005 0 90)
			(size 0 0)
			(layers "F.Cu" "F.Mask" "F.Paste")
			(net "PRSNT_GPU_HMC_N")
		)
	)
	(footprint ""
		(layer "F.Cu")
		(at 315.101732 -32.849312 90)
		(property "Reference" "R5690"
			(at 0 0 90)
			(layer "F.SilkS")
			(hide yes)
			(effects
				(font
					(size 1.27 1.27)
				)
			)
		)
		(property "Value" ""
			(at 0 0 90)
			(layer "F.Fab")
			(effects
				(font
					(size 1.27 1.27)
				)
			)
		)
		(duplicate_pad_numbers_are_jumpers no)
		(fp_line
			(start 0.7874 -0.4064)
			(end 0.7874 0.4064)
			(stroke
				(width 0.1524)
				(type default)
			)
			(layer "F.SilkS")
		)
		(fp_line
			(start -0.7874 -0.4064)
			(end 0.7874 -0.4064)
			(stroke
				(width 0.1524)
				(type default)
			)
			(layer "F.SilkS")
		)
		(fp_line
			(start 0.7874 0.4064)
			(end -0.7874 0.4064)
			(stroke
				(width 0.1524)
				(type default)
			)
			(layer "F.SilkS")
		)
		(fp_line
			(start -0.7874 0.4064)
			(end -0.7874 -0.4064)
			(stroke
				(width 0.1524)
				(type default)
			)
			(layer "F.SilkS")
		)
		(fp_line
			(start -0.12065 -0.305054)
			(end -0.12065 -0.2794)
			(stroke
				(width 0.1)
				(type default)
			)
			(layer "F.Fab")
		)
		(fp_line
			(start -0.67945 -0.305054)
			(end -0.12065 -0.305054)
			(stroke
				(width 0.1)
				(type default)
			)
			(layer "F.Fab")
		)
		(fp_line
			(start 0.67945 -0.3048)
			(end 0.67945 0.3048)
			(stroke
				(width 0.1)
				(type default)
			)
			(layer "F.Fab")
		)
		(fp_line
			(start 0.12065 -0.3048)
			(end 0.67945 -0.3048)
			(stroke
				(width 0.1)
				(type default)
			)
			(layer "F.Fab")
		)
		(fp_line
			(start 0.12065 -0.2794)
			(end 0.12065 -0.3048)
			(stroke
				(width 0.1)
				(type default)
			)
			(layer "F.Fab")
		)
		(fp_line
			(start -0.12065 -0.2794)
			(end 0.12065 -0.2794)
			(stroke
				(width 0.1)
				(type default)
			)
			(layer "F.Fab")
		)
		(fp_line
			(start 0.120396 0.2794)
			(end -0.12065 0.2794)
			(stroke
				(width 0.1)
				(type default)
			)
			(layer "F.Fab")
		)
		(fp_line
			(start -0.12065 0.2794)
			(end -0.12065 0.3048)
			(stroke
				(width 0.1)
				(type default)
			)
			(layer "F.Fab")
		)
		(fp_line
			(start 0.67945 0.3048)
			(end 0.120396 0.3048)
			(stroke
				(width 0.1)
				(type default)
			)
			(layer "F.Fab")
		)
		(fp_line
			(start 0.120396 0.3048)
			(end 0.120396 0.2794)
			(stroke
				(width 0.1)
				(type default)
			)
			(layer "F.Fab")
		)
		(fp_line
			(start -0.12065 0.3048)
			(end -0.67945 0.3048)
			(stroke
				(width 0.1)
				(type default)
			)
			(layer "F.Fab")
		)
		(fp_line
			(start -0.67945 0.3048)
			(end -0.67945 -0.305054)
			(stroke
				(width 0.1)
				(type default)
			)
			(layer "F.Fab")
		)
		(pad "1" smd circle
			(at -0.40005 0 90)
			(size 0 0)
			(layers "F.Cu" "F.Mask" "F.Paste")
			(net "RST_SMB_SSD11_ISO_R_N")
		)
		(pad "2" smd circle
			(at 0.40005 0 90)
			(size 0 0)
			(layers "F.Cu" "F.Mask" "F.Paste")
			(net "RST_SMB_SSD11_ISO_N")
		)
	)
	(footprint ""
		(layer "F.Cu")
		(at 470.416128 -521.354304 180)
		(property "Reference" "J60_12"
			(at -2.8448 -1.402334 0)
			(unlocked yes)
			(layer "B.SilkS")
			(effects
				(font
					(size 0.7874 0.5842)
					(thickness 0.1524)
				)
				(justify mirror)
			)
		)
		(property "Value" ""
			(at 0 0 180)
			(layer "F.Fab")
			(effects
				(font
					(size 1.27 1.27)
				)
			)
		)
		(duplicate_pad_numbers_are_jumpers no)
		(pad "1" thru_hole circle
			(at 0 0 180)
			(size 0.4572 0.4572)
			(drill 0.2032)
			(layers "*.Cu" "*.Mask")
			(remove_unused_layers no)
			(net "Net_584")
			(clearance 0.127)
			(thermal_gap 0.127)
			(padstack
				(mode front_inner_back)
				(layer "Inner"
					(shape circle)
					(size 0.4572 0.4572)
					(clearance 0.127)
				)
				(layer "B.Cu"
					(shape circle)
					(size 0.508 0.508)
					(clearance 0.1016)
				)
			)
		)
	)
	(footprint ""
		(layer "F.Cu")
		(at 80.454754 -22.961346 90)
		(property "Reference" "R1645"
			(at 0 0 90)
			(layer "F.SilkS")
			(hide yes)
			(effects
				(font
					(size 1.27 1.27)
				)
			)
		)
		(property "Value" ""
			(at 0 0 90)
			(layer "F.Fab")
			(effects
				(font
					(size 1.27 1.27)
				)
			)
		)
		(duplicate_pad_numbers_are_jumpers no)
		(fp_line
			(start 0.7874 -0.4064)
			(end 0.7874 0.4064)
			(stroke
				(width 0.1524)
				(type default)
			)
			(layer "F.SilkS")
		)
		(fp_line
			(start -0.7874 -0.4064)
			(end 0.7874 -0.4064)
			(stroke
				(width 0.1524)
				(type default)
			)
			(layer "F.SilkS")
		)
		(fp_line
			(start 0.7874 0.4064)
			(end -0.7874 0.4064)
			(stroke
				(width 0.1524)
				(type default)
			)
			(layer "F.SilkS")
		)
		(fp_line
			(start -0.7874 0.4064)
			(end -0.7874 -0.4064)
			(stroke
				(width 0.1524)
				(type default)
			)
			(layer "F.SilkS")
		)
		(fp_line
			(start -0.12065 -0.305054)
			(end -0.12065 -0.2794)
			(stroke
				(width 0.1)
				(type default)
			)
			(layer "F.Fab")
		)
		(fp_line
			(start -0.67945 -0.305054)
			(end -0.12065 -0.305054)
			(stroke
				(width 0.1)
				(type default)
			)
			(layer "F.Fab")
		)
		(fp_line
			(start 0.67945 -0.3048)
			(end 0.67945 0.3048)
			(stroke
				(width 0.1)
				(type default)
			)
			(layer "F.Fab")
		)
		(fp_line
			(start 0.12065 -0.3048)
			(end 0.67945 -0.3048)
			(stroke
				(width 0.1)
				(type default)
			)
			(layer "F.Fab")
		)
		(fp_line
			(start 0.12065 -0.2794)
			(end 0.12065 -0.3048)
			(stroke
				(width 0.1)
				(type default)
			)
			(layer "F.Fab")
		)
		(fp_line
			(start -0.12065 -0.2794)
			(end 0.12065 -0.2794)
			(stroke
				(width 0.1)
				(type default)
			)
			(layer "F.Fab")
		)
		(fp_line
			(start 0.120396 0.2794)
			(end -0.12065 0.2794)
			(stroke
				(width 0.1)
				(type default)
			)
			(layer "F.Fab")
		)
		(fp_line
			(start -0.12065 0.2794)
			(end -0.12065 0.3048)
			(stroke
				(width 0.1)
				(type default)
			)
			(layer "F.Fab")
		)
		(fp_line
			(start 0.67945 0.3048)
			(end 0.120396 0.3048)
			(stroke
				(width 0.1)
				(type default)
			)
			(layer "F.Fab")
		)
		(fp_line
			(start 0.120396 0.3048)
			(end 0.120396 0.2794)
			(stroke
				(width 0.1)
				(type default)
			)
			(layer "F.Fab")
		)
		(fp_line
			(start -0.12065 0.3048)
			(end -0.67945 0.3048)
			(stroke
				(width 0.1)
				(type default)
			)
			(layer "F.Fab")
		)
		(fp_line
			(start -0.67945 0.3048)
			(end -0.67945 -0.305054)
			(stroke
				(width 0.1)
				(type default)
			)
			(layer "F.Fab")
		)
		(pad "1" smd circle
			(at -0.40005 0 90)
			(size 0 0)
			(layers "F.Cu" "F.Mask" "F.Paste")
			(net "SMB_SSD2_ISO_EN")
		)
		(pad "2" smd circle
			(at 0.40005 0 90)
			(size 0 0)
			(layers "F.Cu" "F.Mask" "F.Paste")
			(net "P3V3_AUX")
		)
	)
	(footprint ""
		(layer "F.Cu")
		(at 47.287688 -356.244906 90)
		(property "Reference" "C163"
			(at 0 0 90)
			(layer "F.SilkS")
			(hide yes)
			(effects
				(font
					(size 1.27 1.27)
				)
			)
		)
		(property "Value" ""
			(at 0 0 90)
			(layer "F.Fab")
			(effects
				(font
					(size 1.27 1.27)
				)
			)
		)
		(duplicate_pad_numbers_are_jumpers no)
		(fp_line
			(start 0.299974 -0.150114)
			(end 0.299974 0.150114)
			(stroke
				(width 0.1)
				(type default)
			)
			(layer "F.Fab")
		)
		(fp_line
			(start -0.299974 -0.150114)
			(end 0.299974 -0.150114)
			(stroke
				(width 0.1)
				(type default)
			)
			(layer "F.Fab")
		)
		(fp_line
			(start 0.299974 0.150114)
			(end -0.299974 0.150114)
			(stroke
				(width 0.1)
				(type default)
			)
			(layer "F.Fab")
		)
		(fp_line
			(start -0.299974 0.150114)
			(end -0.299974 -0.150114)
			(stroke
				(width 0.1)
				(type default)
			)
			(layer "F.Fab")
		)
		(pad "1" smd rect
			(at -0.2667 0 90)
			(size 0.3048 0.381)
			(layers "F.Cu" "F.Mask" "F.Paste")
			(net "P5E_PEX0_STN7_TX_DP<126>")
		)
		(pad "2" smd rect
			(at 0.2667 0 90)
			(size 0.3048 0.381)
			(layers "F.Cu" "F.Mask" "F.Paste")
			(net "P5E_PEX0_STN7_TX_C_DP<126>")
		)
	)
	(footprint ""
		(layer "F.Cu")
		(at 367.022634 -44.341542 90)
		(property "Reference" "R646"
			(at 0 0 90)
			(layer "F.SilkS")
			(hide yes)
			(effects
				(font
					(size 1.27 1.27)
				)
			)
		)
		(property "Value" ""
			(at 0 0 90)
			(layer "F.Fab")
			(effects
				(font
					(size 1.27 1.27)
				)
			)
		)
		(duplicate_pad_numbers_are_jumpers no)
		(fp_line
			(start 0.7874 -0.4064)
			(end 0.7874 0.4064)
			(stroke
				(width 0.1524)
				(type default)
			)
			(layer "F.SilkS")
		)
		(fp_line
			(start -0.7874 -0.4064)
			(end 0.7874 -0.4064)
			(stroke
				(width 0.1524)
				(type default)
			)
			(layer "F.SilkS")
		)
		(fp_line
			(start 0.7874 0.4064)
			(end -0.7874 0.4064)
			(stroke
				(width 0.1524)
				(type default)
			)
			(layer "F.SilkS")
		)
		(fp_line
			(start -0.7874 0.4064)
			(end -0.7874 -0.4064)
			(stroke
				(width 0.1524)
				(type default)
			)
			(layer "F.SilkS")
		)
		(fp_line
			(start -0.12065 -0.305054)
			(end -0.12065 -0.2794)
			(stroke
				(width 0.1)
				(type default)
			)
			(layer "F.Fab")
		)
		(fp_line
			(start -0.67945 -0.305054)
			(end -0.12065 -0.305054)
			(stroke
				(width 0.1)
				(type default)
			)
			(layer "F.Fab")
		)
		(fp_line
			(start 0.67945 -0.3048)
			(end 0.67945 0.3048)
			(stroke
				(width 0.1)
				(type default)
			)
			(layer "F.Fab")
		)
		(fp_line
			(start 0.12065 -0.3048)
			(end 0.67945 -0.3048)
			(stroke
				(width 0.1)
				(type default)
			)
			(layer "F.Fab")
		)
		(fp_line
			(start 0.12065 -0.2794)
			(end 0.12065 -0.3048)
			(stroke
				(width 0.1)
				(type default)
			)
			(layer "F.Fab")
		)
		(fp_line
			(start -0.12065 -0.2794)
			(end 0.12065 -0.2794)
			(stroke
				(width 0.1)
				(type default)
			)
			(layer "F.Fab")
		)
		(fp_line
			(start 0.120396 0.2794)
			(end -0.12065 0.2794)
			(stroke
				(width 0.1)
				(type default)
			)
			(layer "F.Fab")
		)
		(fp_line
			(start -0.12065 0.2794)
			(end -0.12065 0.3048)
			(stroke
				(width 0.1)
				(type default)
			)
			(layer "F.Fab")
		)
		(fp_line
			(start 0.67945 0.3048)
			(end 0.120396 0.3048)
			(stroke
				(width 0.1)
				(type default)
			)
			(layer "F.Fab")
		)
		(fp_line
			(start 0.120396 0.3048)
			(end 0.120396 0.2794)
			(stroke
				(width 0.1)
				(type default)
			)
			(layer "F.Fab")
		)
		(fp_line
			(start -0.12065 0.3048)
			(end -0.67945 0.3048)
			(stroke
				(width 0.1)
				(type default)
			)
			(layer "F.Fab")
		)
		(fp_line
			(start -0.67945 0.3048)
			(end -0.67945 -0.305054)
			(stroke
				(width 0.1)
				(type default)
			)
			(layer "F.Fab")
		)
		(pad "1" smd circle
			(at -0.40005 0 90)
			(size 0 0)
			(layers "F.Cu" "F.Mask" "F.Paste")
			(net "P12V_SSD12")
		)
		(pad "2" smd circle
			(at 0.40005 0 90)
			(size 0 0)
			(layers "F.Cu" "F.Mask" "F.Paste")
			(net "P12V_SSD12_VIN_N")
		)
	)
	(footprint ""
		(layer "F.Cu")
		(at 420.555166 -35.876738)
		(property "Reference" "R6117"
			(at 0 0 0)
			(layer "F.SilkS")
			(hide yes)
			(effects
				(font
					(size 1.27 1.27)
				)
			)
		)
		(property "Value" ""
			(at 0 0 0)
			(layer "F.Fab")
			(effects
				(font
					(size 1.27 1.27)
				)
			)
		)
		(duplicate_pad_numbers_are_jumpers no)
		(fp_line
			(start -0.7874 -0.4064)
			(end 0.7874 -0.4064)
			(stroke
				(width 0.1524)
				(type default)
			)
			(layer "F.SilkS")
		)
		(fp_line
			(start -0.7874 0.4064)
			(end -0.7874 -0.4064)
			(stroke
				(width 0.1524)
				(type default)
			)
			(layer "F.SilkS")
		)
		(fp_line
			(start 0.7874 -0.4064)
			(end 0.7874 0.4064)
			(stroke
				(width 0.1524)
				(type default)
			)
			(layer "F.SilkS")
		)
		(fp_line
			(start 0.7874 0.4064)
			(end -0.7874 0.4064)
			(stroke
				(width 0.1524)
				(type default)
			)
			(layer "F.SilkS")
		)
		(fp_line
			(start -0.67945 -0.305054)
			(end -0.12065 -0.305054)
			(stroke
				(width 0.1)
				(type default)
			)
			(layer "F.Fab")
		)
		(fp_line
			(start -0.67945 0.3048)
			(end -0.67945 -0.305054)
			(stroke
				(width 0.1)
				(type default)
			)
			(layer "F.Fab")
		)
		(fp_line
			(start -0.12065 -0.305054)
			(end -0.12065 -0.2794)
			(stroke
				(width 0.1)
				(type default)
			)
			(layer "F.Fab")
		)
		(fp_line
			(start -0.12065 -0.2794)
			(end 0.12065 -0.2794)
			(stroke
				(width 0.1)
				(type default)
			)
			(layer "F.Fab")
		)
		(fp_line
			(start -0.12065 0.2794)
			(end -0.12065 0.3048)
			(stroke
				(width 0.1)
				(type default)
			)
			(layer "F.Fab")
		)
		(fp_line
			(start -0.12065 0.3048)
			(end -0.67945 0.3048)
			(stroke
				(width 0.1)
				(type default)
			)
			(layer "F.Fab")
		)
		(fp_line
			(start 0.120396 0.2794)
			(end -0.12065 0.2794)
			(stroke
				(width 0.1)
				(type default)
			)
			(layer "F.Fab")
		)
		(fp_line
			(start 0.120396 0.3048)
			(end 0.120396 0.2794)
			(stroke
				(width 0.1)
				(type default)
			)
			(layer "F.Fab")
		)
		(fp_line
			(start 0.12065 -0.3048)
			(end 0.67945 -0.3048)
			(stroke
				(width 0.1)
				(type default)
			)
			(layer "F.Fab")
		)
		(fp_line
			(start 0.12065 -0.2794)
			(end 0.12065 -0.3048)
			(stroke
				(width 0.1)
				(type default)
			)
			(layer "F.Fab")
		)
		(fp_line
			(start 0.67945 -0.3048)
			(end 0.67945 0.3048)
			(stroke
				(width 0.1)
				(type default)
			)
			(layer "F.Fab")
		)
		(fp_line
			(start 0.67945 0.3048)
			(end 0.120396 0.3048)
			(stroke
				(width 0.1)
				(type default)
			)
			(layer "F.Fab")
		)
		(pad "1" smd circle
			(at -0.40005 0)
			(size 0 0)
			(layers "F.Cu" "F.Mask" "F.Paste")
			(net "P3V3_AUX")
		)
		(pad "2" smd circle
			(at 0.40005 0)
			(size 0 0)
			(layers "F.Cu" "F.Mask" "F.Paste")
			(net "PWRGD_P3V3_SSD15_D")
		)
	)
	(footprint ""
		(layer "F.Cu")
		(at 39.280592 -107.403138)
		(property "Reference" "C56"
			(at 0 0 0)
			(layer "F.SilkS")
			(hide yes)
			(effects
				(font
					(size 1.27 1.27)
				)
			)
		)
		(property "Value" ""
			(at 0 0 0)
			(layer "F.Fab")
			(effects
				(font
					(size 1.27 1.27)
				)
			)
		)
		(duplicate_pad_numbers_are_jumpers no)
		(fp_line
			(start -0.299974 -0.150114)
			(end 0.299974 -0.150114)
			(stroke
				(width 0.1)
				(type default)
			)
			(layer "F.Fab")
		)
		(fp_line
			(start -0.299974 0.150114)
			(end -0.299974 -0.150114)
			(stroke
				(width 0.1)
				(type default)
			)
			(layer "F.Fab")
		)
		(fp_line
			(start 0.299974 -0.150114)
			(end 0.299974 0.150114)
			(stroke
				(width 0.1)
				(type default)
			)
			(layer "F.Fab")
		)
		(fp_line
			(start 0.299974 0.150114)
			(end -0.299974 0.150114)
			(stroke
				(width 0.1)
				(type default)
			)
			(layer "F.Fab")
		)
		(pad "1" smd rect
			(at -0.2667 0)
			(size 0.3048 0.381)
			(layers "F.Cu" "F.Mask" "F.Paste")
			(net "P5E_PEX0_STN1_TX_DN<20>")
		)
		(pad "2" smd rect
			(at 0.2667 0)
			(size 0.3048 0.381)
			(layers "F.Cu" "F.Mask" "F.Paste")
			(net "P5E_PEX0_STN1_TX_C_DN<20>")
		)
	)
	(footprint ""
		(layer "F.Cu")
		(at 303.726596 -55.418228 90)
		(property "Reference" "PC428"
			(at 0 0 90)
			(layer "F.SilkS")
			(hide yes)
			(effects
				(font
					(size 1.27 1.27)
				)
			)
		)
		(property "Value" ""
			(at 0 0 90)
			(layer "F.Fab")
			(effects
				(font
					(size 1.27 1.27)
				)
			)
		)
		(duplicate_pad_numbers_are_jumpers no)
		(fp_line
			(start 0.7874 -0.4064)
			(end 0.7874 0.4064)
			(stroke
				(width 0.1524)
				(type default)
			)
			(layer "F.SilkS")
		)
		(fp_line
			(start -0.7874 -0.4064)
			(end 0.7874 -0.4064)
			(stroke
				(width 0.1524)
				(type default)
			)
			(layer "F.SilkS")
		)
		(fp_line
			(start 0.7874 0.4064)
			(end -0.7874 0.4064)
			(stroke
				(width 0.1524)
				(type default)
			)
			(layer "F.SilkS")
		)
		(fp_line
			(start -0.7874 0.4064)
			(end -0.7874 -0.4064)
			(stroke
				(width 0.1524)
				(type default)
			)
			(layer "F.SilkS")
		)
		(fp_line
			(start -0.12065 -0.305054)
			(end -0.12065 -0.2794)
			(stroke
				(width 0.1)
				(type default)
			)
			(layer "F.Fab")
		)
		(fp_line
			(start -0.67945 -0.305054)
			(end -0.12065 -0.305054)
			(stroke
				(width 0.1)
				(type default)
			)
			(layer "F.Fab")
		)
		(fp_line
			(start 0.67945 -0.3048)
			(end 0.67945 0.3048)
			(stroke
				(width 0.1)
				(type default)
			)
			(layer "F.Fab")
		)
		(fp_line
			(start 0.12065 -0.3048)
			(end 0.67945 -0.3048)
			(stroke
				(width 0.1)
				(type default)
			)
			(layer "F.Fab")
		)
		(fp_line
			(start 0.12065 -0.2794)
			(end 0.12065 -0.3048)
			(stroke
				(width 0.1)
				(type default)
			)
			(layer "F.Fab")
		)
		(fp_line
			(start -0.12065 -0.2794)
			(end 0.12065 -0.2794)
			(stroke
				(width 0.1)
				(type default)
			)
			(layer "F.Fab")
		)
		(fp_line
			(start 0.120396 0.2794)
			(end -0.12065 0.2794)
			(stroke
				(width 0.1)
				(type default)
			)
			(layer "F.Fab")
		)
		(fp_line
			(start -0.12065 0.2794)
			(end -0.12065 0.3048)
			(stroke
				(width 0.1)
				(type default)
			)
			(layer "F.Fab")
		)
		(fp_line
			(start 0.67945 0.3048)
			(end 0.120396 0.3048)
			(stroke
				(width 0.1)
				(type default)
			)
			(layer "F.Fab")
		)
		(fp_line
			(start 0.120396 0.3048)
			(end 0.120396 0.2794)
			(stroke
				(width 0.1)
				(type default)
			)
			(layer "F.Fab")
		)
		(fp_line
			(start -0.12065 0.3048)
			(end -0.67945 0.3048)
			(stroke
				(width 0.1)
				(type default)
			)
			(layer "F.Fab")
		)
		(fp_line
			(start -0.67945 0.3048)
			(end -0.67945 -0.305054)
			(stroke
				(width 0.1)
				(type default)
			)
			(layer "F.Fab")
		)
		(pad "1" smd circle
			(at -0.40005 0 90)
			(size 0 0)
			(layers "F.Cu" "F.Mask" "F.Paste")
			(net "P12V_SSD10_R")
		)
		(pad "2" smd circle
			(at 0.40005 0 90)
			(size 0 0)
			(layers "F.Cu" "F.Mask" "F.Paste")
			(net "GND")
		)
	)
	(footprint ""
		(layer "F.Cu")
		(at 426.567854 -52.035456 180)
		(property "Reference" "R874"
			(at 0 0 180)
			(layer "F.SilkS")
			(hide yes)
			(effects
				(font
					(size 1.27 1.27)
				)
			)
		)
		(property "Value" ""
			(at 0 0 180)
			(layer "F.Fab")
			(effects
				(font
					(size 1.27 1.27)
				)
			)
		)
		(duplicate_pad_numbers_are_jumpers no)
		(fp_line
			(start 0.7874 0.4064)
			(end -0.7874 0.4064)
			(stroke
				(width 0.1524)
				(type default)
			)
			(layer "F.SilkS")
		)
		(fp_line
			(start 0.7874 -0.4064)
			(end 0.7874 0.4064)
			(stroke
				(width 0.1524)
				(type default)
			)
			(layer "F.SilkS")
		)
		(fp_line
			(start -0.7874 0.4064)
			(end -0.7874 -0.4064)
			(stroke
				(width 0.1524)
				(type default)
			)
			(layer "F.SilkS")
		)
		(fp_line
			(start -0.7874 -0.4064)
			(end 0.7874 -0.4064)
			(stroke
				(width 0.1524)
				(type default)
			)
			(layer "F.SilkS")
		)
		(fp_line
			(start 0.67945 0.3048)
			(end 0.120396 0.3048)
			(stroke
				(width 0.1)
				(type default)
			)
			(layer "F.Fab")
		)
		(fp_line
			(start 0.67945 -0.3048)
			(end 0.67945 0.3048)
			(stroke
				(width 0.1)
				(type default)
			)
			(layer "F.Fab")
		)
		(fp_line
			(start 0.12065 -0.2794)
			(end 0.12065 -0.3048)
			(stroke
				(width 0.1)
				(type default)
			)
			(layer "F.Fab")
		)
		(fp_line
			(start 0.12065 -0.3048)
			(end 0.67945 -0.3048)
			(stroke
				(width 0.1)
				(type default)
			)
			(layer "F.Fab")
		)
		(fp_line
			(start 0.120396 0.3048)
			(end 0.120396 0.2794)
			(stroke
				(width 0.1)
				(type default)
			)
			(layer "F.Fab")
		)
		(fp_line
			(start 0.120396 0.2794)
			(end -0.12065 0.2794)
			(stroke
				(width 0.1)
				(type default)
			)
			(layer "F.Fab")
		)
		(fp_line
			(start -0.12065 0.3048)
			(end -0.67945 0.3048)
			(stroke
				(width 0.1)
				(type default)
			)
			(layer "F.Fab")
		)
		(fp_line
			(start -0.12065 0.2794)
			(end -0.12065 0.3048)
			(stroke
				(width 0.1)
				(type default)
			)
			(layer "F.Fab")
		)
		(fp_line
			(start -0.12065 -0.2794)
			(end 0.12065 -0.2794)
			(stroke
				(width 0.1)
				(type default)
			)
			(layer "F.Fab")
		)
		(fp_line
			(start -0.12065 -0.305054)
			(end -0.12065 -0.2794)
			(stroke
				(width 0.1)
				(type default)
			)
			(layer "F.Fab")
		)
		(fp_line
			(start -0.67945 0.3048)
			(end -0.67945 -0.305054)
			(stroke
				(width 0.1)
				(type default)
			)
			(layer "F.Fab")
		)
		(fp_line
			(start -0.67945 -0.305054)
			(end -0.12065 -0.305054)
			(stroke
				(width 0.1)
				(type default)
			)
			(layer "F.Fab")
		)
		(pad "1" smd circle
			(at -0.40005 0 180)
			(size 0 0)
			(layers "F.Cu" "F.Mask" "F.Paste")
			(net "P3V3_AUX")
		)
		(pad "2" smd circle
			(at 0.40005 0 180)
			(size 0 0)
			(layers "F.Cu" "F.Mask" "F.Paste")
			(net "PWRGD_P12V_SSD14")
		)
	)
	(footprint ""
		(layer "F.Cu")
		(at 124.32919 -110.722918 -90)
		(property "Reference" "R5828"
			(at 0 0 270)
			(layer "F.SilkS")
			(hide yes)
			(effects
				(font
					(size 1.27 1.27)
				)
			)
		)
		(property "Value" ""
			(at 0 0 270)
			(layer "F.Fab")
			(effects
				(font
					(size 1.27 1.27)
				)
			)
		)
		(duplicate_pad_numbers_are_jumpers no)
		(fp_line
			(start -0.7874 0.4064)
			(end -0.7874 -0.4064)
			(stroke
				(width 0.1524)
				(type default)
			)
			(layer "F.SilkS")
		)
		(fp_line
			(start 0.7874 0.4064)
			(end -0.7874 0.4064)
			(stroke
				(width 0.1524)
				(type default)
			)
			(layer "F.SilkS")
		)
		(fp_line
			(start -0.7874 -0.4064)
			(end 0.7874 -0.4064)
			(stroke
				(width 0.1524)
				(type default)
			)
			(layer "F.SilkS")
		)
		(fp_line
			(start 0.7874 -0.4064)
			(end 0.7874 0.4064)
			(stroke
				(width 0.1524)
				(type default)
			)
			(layer "F.SilkS")
		)
		(fp_line
			(start -0.67945 0.3048)
			(end -0.67945 -0.305054)
			(stroke
				(width 0.1)
				(type default)
			)
			(layer "F.Fab")
		)
		(fp_line
			(start -0.12065 0.3048)
			(end -0.67945 0.3048)
			(stroke
				(width 0.1)
				(type default)
			)
			(layer "F.Fab")
		)
		(fp_line
			(start 0.120396 0.3048)
			(end 0.120396 0.2794)
			(stroke
				(width 0.1)
				(type default)
			)
			(layer "F.Fab")
		)
		(fp_line
			(start 0.67945 0.3048)
			(end 0.120396 0.3048)
			(stroke
				(width 0.1)
				(type default)
			)
			(layer "F.Fab")
		)
		(fp_line
			(start -0.12065 0.2794)
			(end -0.12065 0.3048)
			(stroke
				(width 0.1)
				(type default)
			)
			(layer "F.Fab")
		)
		(fp_line
			(start 0.120396 0.2794)
			(end -0.12065 0.2794)
			(stroke
				(width 0.1)
				(type default)
			)
			(layer "F.Fab")
		)
		(fp_line
			(start -0.12065 -0.2794)
			(end 0.12065 -0.2794)
			(stroke
				(width 0.1)
				(type default)
			)
			(layer "F.Fab")
		)
		(fp_line
			(start 0.12065 -0.2794)
			(end 0.12065 -0.3048)
			(stroke
				(width 0.1)
				(type default)
			)
			(layer "F.Fab")
		)
		(fp_line
			(start 0.12065 -0.3048)
			(end 0.67945 -0.3048)
			(stroke
				(width 0.1)
				(type default)
			)
			(layer "F.Fab")
		)
		(fp_line
			(start 0.67945 -0.3048)
			(end 0.67945 0.3048)
			(stroke
				(width 0.1)
				(type default)
			)
			(layer "F.Fab")
		)
		(fp_line
			(start -0.67945 -0.305054)
			(end -0.12065 -0.305054)
			(stroke
				(width 0.1)
				(type default)
			)
			(layer "F.Fab")
		)
		(fp_line
			(start -0.12065 -0.305054)
			(end -0.12065 -0.2794)
			(stroke
				(width 0.1)
				(type default)
			)
			(layer "F.Fab")
		)
		(pad "1" smd circle
			(at -0.40005 0 270)
			(size 0 0)
			(layers "F.Cu" "F.Mask" "F.Paste")
			(net "P3V3")
		)
		(pad "2" smd circle
			(at 0.40005 0 270)
			(size 0 0)
			(layers "F.Cu" "F.Mask" "F.Paste")
			(net "P3V3_PG_G1")
		)
	)
	(footprint ""
		(layer "F.Cu")
		(at 208.300066 -98.700082)
		(property "Reference" "H79"
			(at -6.217666 -7.419848 0)
			(unlocked yes)
			(layer "F.SilkS")
			(effects
				(font
					(size 0.7874 0.5842)
					(thickness 0.1524)
				)
				(justify left)
			)
		)
		(property "Value" ""
			(at 0 0 0)
			(layer "F.Fab")
			(effects
				(font
					(size 1.27 1.27)
				)
			)
		)
		(duplicate_pad_numbers_are_jumpers no)
		(fp_circle
			(center 0 0)
			(end 7.999984 0)
			(stroke
				(width 0.1524)
				(type default)
			)
			(fill no)
			(layer "F.SilkS")
		)
		(fp_circle
			(center 0 0)
			(end 7.999984 0)
			(stroke
				(width 0.1524)
				(type default)
			)
			(fill no)
			(layer "B.SilkS")
		)
		(fp_circle
			(center 0 0)
			(end 7.999984 0)
			(stroke
				(width 0.1)
				(type default)
			)
			(fill no)
			(layer "B.Fab")
		)
		(fp_circle
			(center 0 0)
			(end 7.999984 0)
			(stroke
				(width 0.1)
				(type default)
			)
			(fill no)
			(layer "F.Fab")
		)
		(pad "" np_thru_hole circle
			(at 0 0)
			(size 3.4036 3.4036)
			(drill 3.4036)
			(layers "*.Cu" "*.Mask")
			(clearance 0.381)
			(thermal_gap 0.381)
		)
		(pad "2" thru_hole circle
			(at 3.606292 0)
			(size 0.762 0.762)
			(drill 0.5588)
			(layers "*.Cu" "*.Mask")
			(remove_unused_layers no)
			(net "GND")
			(clearance 0.1524)
			(thermal_gap 0.1524)
		)
		(pad "3" thru_hole circle
			(at 2.549906 -2.549906)
			(size 0.762 0.762)
			(drill 0.5588)
			(layers "*.Cu" "*.Mask")
			(remove_unused_layers no)
			(net "GND")
			(clearance 0.1524)
			(thermal_gap 0.1524)
		)
		(pad "4" thru_hole circle
			(at 0 -3.606292)
			(size 0.762 0.762)
			(drill 0.5588)
			(layers "*.Cu" "*.Mask")
			(remove_unused_layers no)
			(net "GND")
			(clearance 0.1524)
			(thermal_gap 0.1524)
		)
		(pad "5" thru_hole circle
			(at -2.549906 -2.549906)
			(size 0.762 0.762)
			(drill 0.5588)
			(layers "*.Cu" "*.Mask")
			(remove_unused_layers no)
			(net "GND")
			(clearance 0.1524)
			(thermal_gap 0.1524)
		)
		(pad "6" thru_hole circle
			(at -3.606292 0)
			(size 0.762 0.762)
			(drill 0.5588)
			(layers "*.Cu" "*.Mask")
			(remove_unused_layers no)
			(net "GND")
			(clearance 0.1524)
			(thermal_gap 0.1524)
		)
		(pad "7" thru_hole circle
			(at -2.549906 2.549906)
			(size 0.762 0.762)
			(drill 0.5588)
			(layers "*.Cu" "*.Mask")
			(remove_unused_layers no)
			(net "GND")
			(clearance 0.1524)
			(thermal_gap 0.1524)
		)
		(pad "8" thru_hole circle
			(at 0 3.606292)
			(size 0.762 0.762)
			(drill 0.5588)
			(layers "*.Cu" "*.Mask")
			(remove_unused_layers no)
			(net "GND")
			(clearance 0.1524)
			(thermal_gap 0.1524)
		)
		(pad "9" thru_hole circle
			(at 2.549906 2.549906)
			(size 0.762 0.762)
			(drill 0.5588)
			(layers "*.Cu" "*.Mask")
			(remove_unused_layers no)
			(net "GND")
			(clearance 0.1524)
			(thermal_gap 0.1524)
		)
		(zone
			(layer "F.Cu")
			(hatch none 0.5)
			(connect_pads
				(clearance 0)
			)
			(min_thickness 0.25)
			(keepout
				(tracks not_allowed)
				(vias allowed)
				(pads allowed)
				(copperpour not_allowed)
				(footprints allowed)
			)
			(placement
				(enabled no)
				(sheetname "")
			)
			(fill
				(thermal_gap 0.5)
				(thermal_bridge_width 0.5)
				(island_removal_mode 0)
			)
			(polygon
				(pts
					(arc
						(start 208.300066 -90.700098)
						(mid 200.300082 -98.700082)
						(end 208.300066 -106.700066)
					)
					(arc
						(start 208.300066 -103.954072)
						(mid 203.046076 -98.700082)
						(end 208.300066 -93.446092)
					)
				)
			)
		)
		(zone
			(layer "F.Cu")
			(hatch none 0.5)
			(connect_pads
				(clearance 0)
			)
			(min_thickness 0.25)
			(keepout
				(tracks not_allowed)
				(vias allowed)
				(pads allowed)
				(copperpour not_allowed)
				(footprints allowed)
			)
			(placement
				(enabled no)
				(sheetname "")
			)
			(fill
				(thermal_gap 0.5)
				(thermal_bridge_width 0.5)
				(island_removal_mode 0)
			)
			(polygon
				(pts
					(arc
						(start 208.300066 -90.700098)
						(mid 216.30005 -98.700082)
						(end 208.300066 -106.700066)
					)
					(arc
						(start 208.300066 -103.954072)
						(mid 213.554056 -98.700082)
						(end 208.300066 -93.446092)
					)
				)
			)
		)
		(zone
			(layers "F.Cu" "B.Cu" "In1.Cu" "In2.Cu" "In3.Cu" "In4.Cu" "In5.Cu" "In6.Cu"
				"In7.Cu" "In8.Cu" "In9.Cu" "In10.Cu" "In11.Cu" "In12.Cu" "In13.Cu" "In14.Cu"
				"In15.Cu" "In16.Cu"
			)
			(hatch none 0.5)
			(connect_pads
				(clearance 0)
			)
			(min_thickness 0.25)
			(keepout
				(tracks not_allowed)
				(vias allowed)
				(pads allowed)
				(copperpour not_allowed)
				(footprints allowed)
			)
			(placement
				(enabled no)
				(sheetname "")
			)
			(fill
				(thermal_gap 0.5)
				(thermal_bridge_width 0.5)
				(island_removal_mode 0)
			)
			(polygon
				(pts
					(arc
						(start 210.509866 -98.700082)
						(mid 206.090266 -98.700082)
						(end 210.509866 -98.700082)
					)
				)
			)
		)
		(zone
			(layer "B.Cu")
			(hatch none 0.5)
			(connect_pads
				(clearance 0)
			)
			(min_thickness 0.25)
			(keepout
				(tracks not_allowed)
				(vias allowed)
				(pads allowed)
				(copperpour not_allowed)
				(footprints allowed)
			)
			(placement
				(enabled no)
				(sheetname "")
			)
			(fill
				(thermal_gap 0.5)
				(thermal_bridge_width 0.5)
				(island_removal_mode 0)
			)
			(polygon
				(pts
					(arc
						(start 208.300066 -93.192092)
						(mid 202.792076 -98.700082)
						(end 208.300066 -104.208072)
					)
					(arc
						(start 208.300066 -103.725472)
						(mid 203.274676 -98.700082)
						(end 208.300066 -93.674692)
					)
				)
			)
		)
		(zone
			(layer "B.Cu")
			(hatch none 0.5)
			(connect_pads
				(clearance 0)
			)
			(min_thickness 0.25)
			(keepout
				(tracks not_allowed)
				(vias allowed)
				(pads allowed)
				(copperpour not_allowed)
				(footprints allowed)
			)
			(placement
				(enabled no)
				(sheetname "")
			)
			(fill
				(thermal_gap 0.5)
				(thermal_bridge_width 0.5)
				(island_removal_mode 0)
			)
			(polygon
				(pts
					(arc
						(start 208.300066 -93.192092)
						(mid 213.808056 -98.700082)
						(end 208.300066 -104.208072)
					)
					(arc
						(start 208.300066 -103.725472)
						(mid 213.325456 -98.700082)
						(end 208.300066 -93.674692)
					)
				)
			)
		)
	)
	(footprint ""
		(layer "F.Cu")
		(at 95.79229 -28.225242 180)
		(property "Reference" "C96"
			(at 0 0 180)
			(layer "F.SilkS")
			(hide yes)
			(effects
				(font
					(size 1.27 1.27)
				)
			)
		)
		(property "Value" ""
			(at 0 0 180)
			(layer "F.Fab")
			(effects
				(font
					(size 1.27 1.27)
				)
			)
		)
		(duplicate_pad_numbers_are_jumpers no)
		(fp_line
			(start 0.299974 0.150114)
			(end -0.299974 0.150114)
			(stroke
				(width 0.1)
				(type default)
			)
			(layer "F.Fab")
		)
		(fp_line
			(start 0.299974 -0.150114)
			(end 0.299974 0.150114)
			(stroke
				(width 0.1)
				(type default)
			)
			(layer "F.Fab")
		)
		(fp_line
			(start -0.299974 0.150114)
			(end -0.299974 -0.150114)
			(stroke
				(width 0.1)
				(type default)
			)
			(layer "F.Fab")
		)
		(fp_line
			(start -0.299974 -0.150114)
			(end 0.299974 -0.150114)
			(stroke
				(width 0.1)
				(type default)
			)
			(layer "F.Fab")
		)
		(pad "1" smd rect
			(at -0.2667 0 180)
			(size 0.3048 0.381)
			(layers "F.Cu" "F.Mask" "F.Paste")
			(net "P5E_PEX0_STN2_TX_DN<32>")
		)
		(pad "2" smd rect
			(at 0.2667 0 180)
			(size 0.3048 0.381)
			(layers "F.Cu" "F.Mask" "F.Paste")
			(net "P5E_PEX0_STN2_TX_C_DN<32>")
		)
	)
	(footprint ""
		(layer "F.Cu")
		(at 151.335486 -390.398254 90)
		(property "Reference" "R1837"
			(at 0 0 90)
			(layer "F.SilkS")
			(hide yes)
			(effects
				(font
					(size 1.27 1.27)
				)
			)
		)
		(property "Value" ""
			(at 0 0 90)
			(layer "F.Fab")
			(effects
				(font
					(size 1.27 1.27)
				)
			)
		)
		(duplicate_pad_numbers_are_jumpers no)
		(fp_line
			(start 0.7874 -0.4064)
			(end 0.7874 0.4064)
			(stroke
				(width 0.1524)
				(type default)
			)
			(layer "F.SilkS")
		)
		(fp_line
			(start -0.7874 -0.4064)
			(end 0.7874 -0.4064)
			(stroke
				(width 0.1524)
				(type default)
			)
			(layer "F.SilkS")
		)
		(fp_line
			(start 0.7874 0.4064)
			(end -0.7874 0.4064)
			(stroke
				(width 0.1524)
				(type default)
			)
			(layer "F.SilkS")
		)
		(fp_line
			(start -0.7874 0.4064)
			(end -0.7874 -0.4064)
			(stroke
				(width 0.1524)
				(type default)
			)
			(layer "F.SilkS")
		)
		(fp_line
			(start -0.12065 -0.305054)
			(end -0.12065 -0.2794)
			(stroke
				(width 0.1)
				(type default)
			)
			(layer "F.Fab")
		)
		(fp_line
			(start -0.67945 -0.305054)
			(end -0.12065 -0.305054)
			(stroke
				(width 0.1)
				(type default)
			)
			(layer "F.Fab")
		)
		(fp_line
			(start 0.67945 -0.3048)
			(end 0.67945 0.3048)
			(stroke
				(width 0.1)
				(type default)
			)
			(layer "F.Fab")
		)
		(fp_line
			(start 0.12065 -0.3048)
			(end 0.67945 -0.3048)
			(stroke
				(width 0.1)
				(type default)
			)
			(layer "F.Fab")
		)
		(fp_line
			(start 0.12065 -0.2794)
			(end 0.12065 -0.3048)
			(stroke
				(width 0.1)
				(type default)
			)
			(layer "F.Fab")
		)
		(fp_line
			(start -0.12065 -0.2794)
			(end 0.12065 -0.2794)
			(stroke
				(width 0.1)
				(type default)
			)
			(layer "F.Fab")
		)
		(fp_line
			(start 0.120396 0.2794)
			(end -0.12065 0.2794)
			(stroke
				(width 0.1)
				(type default)
			)
			(layer "F.Fab")
		)
		(fp_line
			(start -0.12065 0.2794)
			(end -0.12065 0.3048)
			(stroke
				(width 0.1)
				(type default)
			)
			(layer "F.Fab")
		)
		(fp_line
			(start 0.67945 0.3048)
			(end 0.120396 0.3048)
			(stroke
				(width 0.1)
				(type default)
			)
			(layer "F.Fab")
		)
		(fp_line
			(start 0.120396 0.3048)
			(end 0.120396 0.2794)
			(stroke
				(width 0.1)
				(type default)
			)
			(layer "F.Fab")
		)
		(fp_line
			(start -0.12065 0.3048)
			(end -0.67945 0.3048)
			(stroke
				(width 0.1)
				(type default)
			)
			(layer "F.Fab")
		)
		(fp_line
			(start -0.67945 0.3048)
			(end -0.67945 -0.305054)
			(stroke
				(width 0.1)
				(type default)
			)
			(layer "F.Fab")
		)
		(pad "1" smd circle
			(at -0.40005 0 90)
			(size 0 0)
			(layers "F.Cu" "F.Mask" "F.Paste")
			(net "GPU_FPGA_EROT_RECOV_R_N")
		)
		(pad "2" smd circle
			(at 0.40005 0 90)
			(size 0 0)
			(layers "F.Cu" "F.Mask" "F.Paste")
			(net "GPU_FPGA_EROT_RECOV_N")
		)
	)
	(footprint ""
		(layer "F.Cu")
		(at 173.689518 -63.56223)
		(property "Reference" "Q202"
			(at -0.004318 -1.8669 0)
			(unlocked yes)
			(layer "F.SilkS")
			(effects
				(font
					(size 0.7874 0.5842)
					(thickness 0.1524)
				)
			)
		)
		(property "Value" ""
			(at 0 0 0)
			(layer "F.Fab")
			(effects
				(font
					(size 1.27 1.27)
				)
			)
		)
		(duplicate_pad_numbers_are_jumpers no)
		(fp_line
			(start -1.376172 -1.199896)
			(end -0.508 -1.199896)
			(stroke
				(width 0.1524)
				(type default)
			)
			(layer "F.SilkS")
		)
		(fp_line
			(start -1.376172 1.199896)
			(end -1.376172 -1.199896)
			(stroke
				(width 0.1524)
				(type default)
			)
			(layer "F.SilkS")
		)
		(fp_line
			(start -0.508 -1.199896)
			(end 0 -0.762)
			(stroke
				(width 0.1524)
				(type default)
			)
			(layer "F.SilkS")
		)
		(fp_line
			(start 0 -0.762)
			(end 0.508 -1.199896)
			(stroke
				(width 0.1524)
				(type default)
			)
			(layer "F.SilkS")
		)
		(fp_line
			(start 0.508 -1.199896)
			(end 1.376172 -1.199896)
			(stroke
				(width 0.1524)
				(type default)
			)
			(layer "F.SilkS")
		)
		(fp_line
			(start 1.376172 -1.199896)
			(end 1.376172 1.199896)
			(stroke
				(width 0.1524)
				(type default)
			)
			(layer "F.SilkS")
		)
		(fp_line
			(start 1.376172 1.199896)
			(end -1.376172 1.199896)
			(stroke
				(width 0.1524)
				(type default)
			)
			(layer "F.SilkS")
		)
		(fp_poly
			(pts
				(xy -1.504696 -0.923544) (xy -1.773936 -1.731772) (xy -2.312924 -1.193038)
			)
			(stroke
				(width 0)
				(type default)
			)
			(fill yes)
			(layer "F.SilkS")
		)
		(fp_line
			(start -0.674878 -1.100074)
			(end 0.674878 -1.100074)
			(stroke
				(width 0.1)
				(type default)
			)
			(layer "F.Fab")
		)
		(fp_line
			(start -0.674878 1.100074)
			(end -0.674878 -1.100074)
			(stroke
				(width 0.1)
				(type default)
			)
			(layer "F.Fab")
		)
		(fp_line
			(start 0.674878 -1.100074)
			(end 0.674878 1.100074)
			(stroke
				(width 0.1)
				(type default)
			)
			(layer "F.Fab")
		)
		(fp_line
			(start 0.674878 1.100074)
			(end -0.674878 1.100074)
			(stroke
				(width 0.1)
				(type default)
			)
			(layer "F.Fab")
		)
		(fp_poly
			(pts
				(xy -1.4605 -0.7493) (xy -2.2225 -1.1303) (xy -2.2225 -0.3683)
			)
			(stroke
				(width 0)
				(type default)
			)
			(fill yes)
			(layer "F.Fab")
		)
		(pad "1" smd rect
			(at -0.899922 -0.750062 270)
			(size 0.6096 0.6096)
			(layers "F.Cu" "F.Mask" "F.Paste")
			(net "GND")
		)
		(pad "2" smd rect
			(at -0.899922 0 270)
			(size 0.4064 0.6096)
			(layers "F.Cu" "F.Mask" "F.Paste")
			(net "P12V_SSD6_PG_G1")
		)
		(pad "3" smd rect
			(at -0.899922 0.750062 270)
			(size 0.6096 0.6096)
			(layers "F.Cu" "F.Mask" "F.Paste")
			(net "PWRGD_P12V_SSD6_D")
		)
		(pad "4" smd rect
			(at 0.899922 0.750062 270)
			(size 0.6096 0.6096)
			(layers "F.Cu" "F.Mask" "F.Paste")
			(net "GND")
		)
		(pad "5" smd rect
			(at 0.899922 0 270)
			(size 0.4064 0.6096)
			(layers "F.Cu" "F.Mask" "F.Paste")
			(net "P12V_SSD6_PG_G2")
		)
		(pad "6" smd rect
			(at 0.899922 -0.750062 270)
			(size 0.6096 0.6096)
			(layers "F.Cu" "F.Mask" "F.Paste")
			(net "P12V_SSD6_PG_G2")
		)
	)
	(footprint ""
		(layer "F.Cu")
		(at 403.16658 -343.952322 90)
		(property "Reference" "C733"
			(at 0 0 90)
			(layer "F.SilkS")
			(hide yes)
			(effects
				(font
					(size 1.27 1.27)
				)
			)
		)
		(property "Value" ""
			(at 0 0 90)
			(layer "F.Fab")
			(effects
				(font
					(size 1.27 1.27)
				)
			)
		)
		(duplicate_pad_numbers_are_jumpers no)
		(fp_line
			(start 0.299974 -0.150114)
			(end 0.299974 0.150114)
			(stroke
				(width 0.1)
				(type default)
			)
			(layer "F.Fab")
		)
		(fp_line
			(start -0.299974 -0.150114)
			(end 0.299974 -0.150114)
			(stroke
				(width 0.1)
				(type default)
			)
			(layer "F.Fab")
		)
		(fp_line
			(start 0.299974 0.150114)
			(end -0.299974 0.150114)
			(stroke
				(width 0.1)
				(type default)
			)
			(layer "F.Fab")
		)
		(fp_line
			(start -0.299974 0.150114)
			(end -0.299974 -0.150114)
			(stroke
				(width 0.1)
				(type default)
			)
			(layer "F.Fab")
		)
		(pad "1" smd rect
			(at -0.2667 0 90)
			(size 0.3048 0.381)
			(layers "F.Cu" "F.Mask" "F.Paste")
			(net "P5E_PEX3_STN5_TX_DN<94>")
		)
		(pad "2" smd rect
			(at 0.2667 0 90)
			(size 0.3048 0.381)
			(layers "F.Cu" "F.Mask" "F.Paste")
			(net "P5E_PEX3_STN5_TX_C_DN<94>")
		)
	)
	(footprint ""
		(layer "F.Cu")
		(at 199.854312 -48.21809)
		(property "Reference" "PD67"
			(at 0 0 0)
			(layer "F.SilkS")
			(hide yes)
			(effects
				(font
					(size 1.27 1.27)
				)
			)
		)
		(property "Value" ""
			(at 0 0 0)
			(layer "F.Fab")
			(effects
				(font
					(size 1.27 1.27)
				)
			)
		)
		(duplicate_pad_numbers_are_jumpers no)
		(fp_line
			(start -3.400044 -1.459992)
			(end 4.107942 -1.459992)
			(stroke
				(width 0.1524)
				(type default)
			)
			(layer "F.SilkS")
		)
		(fp_line
			(start -3.400044 1.459992)
			(end -3.400044 -1.459992)
			(stroke
				(width 0.1524)
				(type default)
			)
			(layer "F.SilkS")
		)
		(fp_line
			(start 4.107942 -1.459992)
			(end 4.107942 1.459992)
			(stroke
				(width 0.1524)
				(type default)
			)
			(layer "F.SilkS")
		)
		(fp_line
			(start 4.107942 1.459992)
			(end -3.400044 1.459992)
			(stroke
				(width 0.1524)
				(type default)
			)
			(layer "F.SilkS")
		)
		(fp_poly
			(pts
				(xy 4.107942 -1.459992) (xy 4.107942 1.459992) (xy 3.308096 1.459992) (xy 3.308096 -1.459992)
			)
			(stroke
				(width 0)
				(type default)
			)
			(fill yes)
			(layer "F.SilkS")
		)
		(fp_line
			(start -2.29997 -1.459992)
			(end 2.29997 -1.459992)
			(stroke
				(width 0.1)
				(type default)
			)
			(layer "F.Fab")
		)
		(fp_line
			(start -2.29997 1.459992)
			(end -2.29997 -1.459992)
			(stroke
				(width 0.1)
				(type default)
			)
			(layer "F.Fab")
		)
		(fp_line
			(start 2.29997 -1.459992)
			(end 2.29997 1.459992)
			(stroke
				(width 0.1)
				(type default)
			)
			(layer "F.Fab")
		)
		(fp_line
			(start 2.29997 1.459992)
			(end -2.29997 1.459992)
			(stroke
				(width 0.1)
				(type default)
			)
			(layer "F.Fab")
		)
		(fp_text user "+"
			(at -4.7752 -0.12065 0)
			(unlocked yes)
			(layer "F.SilkS")
			(effects
				(font
					(size 1.905 1.4224)
					(thickness 0.1524)
				)
				(justify left)
			)
		)
		(fp_text user "-"
			(at 5.4102 0.29845 180)
			(unlocked yes)
			(layer "F.SilkS")
			(effects
				(font
					(size 1.905 1.4224)
					(thickness 0.1524)
				)
				(justify left)
			)
		)
		(fp_text user "+"
			(at -4.7752 -0.12065 0)
			(unlocked yes)
			(layer "F.Fab")
			(effects
				(font
					(size 1.905 1.4224)
					(thickness 0.1524)
				)
				(justify left)
			)
		)
		(fp_text user "-"
			(at 5.4102 0.29845 180)
			(unlocked yes)
			(layer "F.Fab")
			(effects
				(font
					(size 1.905 1.4224)
					(thickness 0.1524)
				)
				(justify left)
			)
		)
		(pad "A" smd rect
			(at -1.999996 0 90)
			(size 1.7018 2.5146)
			(layers "F.Cu" "F.Mask" "F.Paste")
			(net "GND")
		)
		(pad "C" smd rect
			(at 1.999996 0 90)
			(size 1.7018 2.5146)
			(layers "F.Cu" "F.Mask" "F.Paste")
			(net "P3V3_SSD7")
		)
	)
	(footprint ""
		(layer "F.Cu")
		(at 374.759474 -22.955504 90)
		(property "Reference" "R1727"
			(at 0 0 90)
			(layer "F.SilkS")
			(hide yes)
			(effects
				(font
					(size 1.27 1.27)
				)
			)
		)
		(property "Value" ""
			(at 0 0 90)
			(layer "F.Fab")
			(effects
				(font
					(size 1.27 1.27)
				)
			)
		)
		(duplicate_pad_numbers_are_jumpers no)
		(fp_line
			(start 0.7874 -0.4064)
			(end 0.7874 0.4064)
			(stroke
				(width 0.1524)
				(type default)
			)
			(layer "F.SilkS")
		)
		(fp_line
			(start -0.7874 -0.4064)
			(end 0.7874 -0.4064)
			(stroke
				(width 0.1524)
				(type default)
			)
			(layer "F.SilkS")
		)
		(fp_line
			(start 0.7874 0.4064)
			(end -0.7874 0.4064)
			(stroke
				(width 0.1524)
				(type default)
			)
			(layer "F.SilkS")
		)
		(fp_line
			(start -0.7874 0.4064)
			(end -0.7874 -0.4064)
			(stroke
				(width 0.1524)
				(type default)
			)
			(layer "F.SilkS")
		)
		(fp_line
			(start -0.12065 -0.305054)
			(end -0.12065 -0.2794)
			(stroke
				(width 0.1)
				(type default)
			)
			(layer "F.Fab")
		)
		(fp_line
			(start -0.67945 -0.305054)
			(end -0.12065 -0.305054)
			(stroke
				(width 0.1)
				(type default)
			)
			(layer "F.Fab")
		)
		(fp_line
			(start 0.67945 -0.3048)
			(end 0.67945 0.3048)
			(stroke
				(width 0.1)
				(type default)
			)
			(layer "F.Fab")
		)
		(fp_line
			(start 0.12065 -0.3048)
			(end 0.67945 -0.3048)
			(stroke
				(width 0.1)
				(type default)
			)
			(layer "F.Fab")
		)
		(fp_line
			(start 0.12065 -0.2794)
			(end 0.12065 -0.3048)
			(stroke
				(width 0.1)
				(type default)
			)
			(layer "F.Fab")
		)
		(fp_line
			(start -0.12065 -0.2794)
			(end 0.12065 -0.2794)
			(stroke
				(width 0.1)
				(type default)
			)
			(layer "F.Fab")
		)
		(fp_line
			(start 0.120396 0.2794)
			(end -0.12065 0.2794)
			(stroke
				(width 0.1)
				(type default)
			)
			(layer "F.Fab")
		)
		(fp_line
			(start -0.12065 0.2794)
			(end -0.12065 0.3048)
			(stroke
				(width 0.1)
				(type default)
			)
			(layer "F.Fab")
		)
		(fp_line
			(start 0.67945 0.3048)
			(end 0.120396 0.3048)
			(stroke
				(width 0.1)
				(type default)
			)
			(layer "F.Fab")
		)
		(fp_line
			(start 0.120396 0.3048)
			(end 0.120396 0.2794)
			(stroke
				(width 0.1)
				(type default)
			)
			(layer "F.Fab")
		)
		(fp_line
			(start -0.12065 0.3048)
			(end -0.67945 0.3048)
			(stroke
				(width 0.1)
				(type default)
			)
			(layer "F.Fab")
		)
		(fp_line
			(start -0.67945 0.3048)
			(end -0.67945 -0.305054)
			(stroke
				(width 0.1)
				(type default)
			)
			(layer "F.Fab")
		)
		(pad "1" smd circle
			(at -0.40005 0 90)
			(size 0 0)
			(layers "F.Cu" "F.Mask" "F.Paste")
			(net "SMB_BIC_I2C9_MUX1_SSD12_R_SCL")
		)
		(pad "2" smd circle
			(at 0.40005 0 90)
			(size 0 0)
			(layers "F.Cu" "F.Mask" "F.Paste")
			(net "SMB_ISO_SSD12_SCL")
		)
	)
	(footprint ""
		(layer "F.Cu")
		(at 250.651264 -114.914426 -90)
		(property "Reference" "PC901"
			(at 0 0 270)
			(layer "F.SilkS")
			(hide yes)
			(effects
				(font
					(size 1.27 1.27)
				)
			)
		)
		(property "Value" ""
			(at 0 0 270)
			(layer "F.Fab")
			(effects
				(font
					(size 1.27 1.27)
				)
			)
		)
		(duplicate_pad_numbers_are_jumpers no)
		(fp_line
			(start -1.524 0.762)
			(end -1.524 -0.762)
			(stroke
				(width 0.1524)
				(type default)
			)
			(layer "F.SilkS")
		)
		(fp_line
			(start 1.524 0.762)
			(end -1.524 0.762)
			(stroke
				(width 0.1524)
				(type default)
			)
			(layer "F.SilkS")
		)
		(fp_line
			(start -1.524 -0.762)
			(end 1.524 -0.762)
			(stroke
				(width 0.1524)
				(type default)
			)
			(layer "F.SilkS")
		)
		(fp_line
			(start 1.524 -0.762)
			(end 1.524 0.762)
			(stroke
				(width 0.1524)
				(type default)
			)
			(layer "F.SilkS")
		)
		(fp_line
			(start -1.1049 0.724916)
			(end 1.1049 0.724916)
			(stroke
				(width 0.1)
				(type default)
			)
			(layer "F.Fab")
		)
		(fp_line
			(start 1.1049 0.724916)
			(end 1.1049 -0.724916)
			(stroke
				(width 0.1)
				(type default)
			)
			(layer "F.Fab")
		)
		(fp_line
			(start -1.1049 -0.724916)
			(end -1.1049 0.724916)
			(stroke
				(width 0.1)
				(type default)
			)
			(layer "F.Fab")
		)
		(fp_line
			(start 1.1049 -0.724916)
			(end -1.1049 -0.724916)
			(stroke
				(width 0.1)
				(type default)
			)
			(layer "F.Fab")
		)
		(pad "1" smd rect
			(at -0.889 0 90)
			(size 1.016 1.27)
			(layers "F.Cu" "F.Mask" "F.Paste")
			(net "P3V3_NIC4")
		)
		(pad "2" smd rect
			(at 0.889 0 90)
			(size 1.016 1.27)
			(layers "F.Cu" "F.Mask" "F.Paste")
			(net "GND")
		)
	)
	(footprint ""
		(layer "F.Cu")
		(at 81.155032 -53.468524 90)
		(property "Reference" "PC499"
			(at 0 0 90)
			(layer "F.SilkS")
			(hide yes)
			(effects
				(font
					(size 1.27 1.27)
				)
			)
		)
		(property "Value" ""
			(at 0 0 90)
			(layer "F.Fab")
			(effects
				(font
					(size 1.27 1.27)
				)
			)
		)
		(duplicate_pad_numbers_are_jumpers no)
		(fp_line
			(start 1.524 -0.762)
			(end 1.524 0.762)
			(stroke
				(width 0.1524)
				(type default)
			)
			(layer "F.SilkS")
		)
		(fp_line
			(start -1.524 -0.762)
			(end 1.524 -0.762)
			(stroke
				(width 0.1524)
				(type default)
			)
			(layer "F.SilkS")
		)
		(fp_line
			(start 1.524 0.762)
			(end -1.524 0.762)
			(stroke
				(width 0.1524)
				(type default)
			)
			(layer "F.SilkS")
		)
		(fp_line
			(start -1.524 0.762)
			(end -1.524 -0.762)
			(stroke
				(width 0.1524)
				(type default)
			)
			(layer "F.SilkS")
		)
		(fp_line
			(start 1.1049 -0.724916)
			(end -1.1049 -0.724916)
			(stroke
				(width 0.1)
				(type default)
			)
			(layer "F.Fab")
		)
		(fp_line
			(start -1.1049 -0.724916)
			(end -1.1049 0.724916)
			(stroke
				(width 0.1)
				(type default)
			)
			(layer "F.Fab")
		)
		(fp_line
			(start 1.1049 0.724916)
			(end 1.1049 -0.724916)
			(stroke
				(width 0.1)
				(type default)
			)
			(layer "F.Fab")
		)
		(fp_line
			(start -1.1049 0.724916)
			(end 1.1049 0.724916)
			(stroke
				(width 0.1)
				(type default)
			)
			(layer "F.Fab")
		)
		(pad "1" smd rect
			(at -0.889 0 270)
			(size 1.016 1.27)
			(layers "F.Cu" "F.Mask" "F.Paste")
			(net "GND")
		)
		(pad "2" smd rect
			(at 0.889 0 270)
			(size 1.016 1.27)
			(layers "F.Cu" "F.Mask" "F.Paste")
			(net "P3V3_AUX")
		)
	)
	(footprint ""
		(layer "F.Cu")
		(at 133.63448 -308.648862 -90)
		(property "Reference" "C4263"
			(at 0 0 270)
			(layer "F.SilkS")
			(hide yes)
			(effects
				(font
					(size 1.27 1.27)
				)
			)
		)
		(property "Value" ""
			(at 0 0 270)
			(layer "F.Fab")
			(effects
				(font
					(size 1.27 1.27)
				)
			)
		)
		(duplicate_pad_numbers_are_jumpers no)
		(fp_line
			(start -1.2954 0.5842)
			(end -1.2954 -0.5842)
			(stroke
				(width 0.1524)
				(type default)
			)
			(layer "F.SilkS")
		)
		(fp_line
			(start 1.2954 0.5842)
			(end -1.2954 0.5842)
			(stroke
				(width 0.1524)
				(type default)
			)
			(layer "F.SilkS")
		)
		(fp_line
			(start -1.2954 -0.5842)
			(end 1.2954 -0.5842)
			(stroke
				(width 0.1524)
				(type default)
			)
			(layer "F.SilkS")
		)
		(fp_line
			(start 1.2954 -0.5842)
			(end 1.2954 0.5842)
			(stroke
				(width 0.1524)
				(type default)
			)
			(layer "F.SilkS")
		)
		(fp_line
			(start -0.8636 0.4572)
			(end -0.8636 0.4064)
			(stroke
				(width 0.1)
				(type default)
			)
			(layer "F.Fab")
		)
		(fp_line
			(start 0.8636 0.4572)
			(end -0.8636 0.4572)
			(stroke
				(width 0.1)
				(type default)
			)
			(layer "F.Fab")
		)
		(fp_line
			(start -1.1938 0.4064)
			(end -1.1938 -0.4064)
			(stroke
				(width 0.1)
				(type default)
			)
			(layer "F.Fab")
		)
		(fp_line
			(start -0.8636 0.4064)
			(end -1.1938 0.4064)
			(stroke
				(width 0.1)
				(type default)
			)
			(layer "F.Fab")
		)
		(fp_line
			(start 0.8636 0.4064)
			(end 0.8636 0.4572)
			(stroke
				(width 0.1)
				(type default)
			)
			(layer "F.Fab")
		)
		(fp_line
			(start 1.1938 0.4064)
			(end 0.8636 0.4064)
			(stroke
				(width 0.1)
				(type default)
			)
			(layer "F.Fab")
		)
		(fp_line
			(start -1.1938 -0.4064)
			(end -0.8636 -0.4064)
			(stroke
				(width 0.1)
				(type default)
			)
			(layer "F.Fab")
		)
		(fp_line
			(start -0.8636 -0.4064)
			(end -0.8636 -0.4572)
			(stroke
				(width 0.1)
				(type default)
			)
			(layer "F.Fab")
		)
		(fp_line
			(start 0.8636 -0.4064)
			(end 1.1938 -0.4064)
			(stroke
				(width 0.1)
				(type default)
			)
			(layer "F.Fab")
		)
		(fp_line
			(start 1.1938 -0.4064)
			(end 1.1938 0.4064)
			(stroke
				(width 0.1)
				(type default)
			)
			(layer "F.Fab")
		)
		(fp_line
			(start -0.8636 -0.4572)
			(end 0.8636 -0.4572)
			(stroke
				(width 0.1)
				(type default)
			)
			(layer "F.Fab")
		)
		(fp_line
			(start 0.8636 -0.4572)
			(end 0.8636 -0.4064)
			(stroke
				(width 0.1)
				(type default)
			)
			(layer "F.Fab")
		)
		(pad "1" smd rect
			(at -0.7366 0 180)
			(size 0.7112 0.8128)
			(layers "F.Cu" "F.Mask" "F.Paste")
			(net "P0V8_PEX1")
		)
		(pad "2" smd rect
			(at 0.7366 0 180)
			(size 0.7112 0.8128)
			(layers "F.Cu" "F.Mask" "F.Paste")
			(net "GND")
		)
	)
	(footprint ""
		(layer "F.Cu")
		(at 264.611358 -293.245032 -90)
		(property "Reference" "R4580"
			(at 0 0 270)
			(layer "F.SilkS")
			(hide yes)
			(effects
				(font
					(size 1.27 1.27)
				)
			)
		)
		(property "Value" ""
			(at 0 0 270)
			(layer "F.Fab")
			(effects
				(font
					(size 1.27 1.27)
				)
			)
		)
		(duplicate_pad_numbers_are_jumpers no)
		(fp_line
			(start -0.7874 0.4064)
			(end -0.7874 -0.4064)
			(stroke
				(width 0.1524)
				(type default)
			)
			(layer "F.SilkS")
		)
		(fp_line
			(start 0.7874 0.4064)
			(end -0.7874 0.4064)
			(stroke
				(width 0.1524)
				(type default)
			)
			(layer "F.SilkS")
		)
		(fp_line
			(start -0.7874 -0.4064)
			(end 0.7874 -0.4064)
			(stroke
				(width 0.1524)
				(type default)
			)
			(layer "F.SilkS")
		)
		(fp_line
			(start 0.7874 -0.4064)
			(end 0.7874 0.4064)
			(stroke
				(width 0.1524)
				(type default)
			)
			(layer "F.SilkS")
		)
		(fp_line
			(start -0.67945 0.3048)
			(end -0.67945 -0.305054)
			(stroke
				(width 0.1)
				(type default)
			)
			(layer "F.Fab")
		)
		(fp_line
			(start -0.12065 0.3048)
			(end -0.67945 0.3048)
			(stroke
				(width 0.1)
				(type default)
			)
			(layer "F.Fab")
		)
		(fp_line
			(start 0.120396 0.3048)
			(end 0.120396 0.2794)
			(stroke
				(width 0.1)
				(type default)
			)
			(layer "F.Fab")
		)
		(fp_line
			(start 0.67945 0.3048)
			(end 0.120396 0.3048)
			(stroke
				(width 0.1)
				(type default)
			)
			(layer "F.Fab")
		)
		(fp_line
			(start -0.12065 0.2794)
			(end -0.12065 0.3048)
			(stroke
				(width 0.1)
				(type default)
			)
			(layer "F.Fab")
		)
		(fp_line
			(start 0.120396 0.2794)
			(end -0.12065 0.2794)
			(stroke
				(width 0.1)
				(type default)
			)
			(layer "F.Fab")
		)
		(fp_line
			(start -0.12065 -0.2794)
			(end 0.12065 -0.2794)
			(stroke
				(width 0.1)
				(type default)
			)
			(layer "F.Fab")
		)
		(fp_line
			(start 0.12065 -0.2794)
			(end 0.12065 -0.3048)
			(stroke
				(width 0.1)
				(type default)
			)
			(layer "F.Fab")
		)
		(fp_line
			(start 0.12065 -0.3048)
			(end 0.67945 -0.3048)
			(stroke
				(width 0.1)
				(type default)
			)
			(layer "F.Fab")
		)
		(fp_line
			(start 0.67945 -0.3048)
			(end 0.67945 0.3048)
			(stroke
				(width 0.1)
				(type default)
			)
			(layer "F.Fab")
		)
		(fp_line
			(start -0.67945 -0.305054)
			(end -0.12065 -0.305054)
			(stroke
				(width 0.1)
				(type default)
			)
			(layer "F.Fab")
		)
		(fp_line
			(start -0.12065 -0.305054)
			(end -0.12065 -0.2794)
			(stroke
				(width 0.1)
				(type default)
			)
			(layer "F.Fab")
		)
		(pad "1" smd circle
			(at -0.40005 0 270)
			(size 0 0)
			(layers "F.Cu" "F.Mask" "F.Paste")
			(net "PCEPLL2_VDDA18_PEX2")
		)
		(pad "2" smd circle
			(at 0.40005 0 270)
			(size 0 0)
			(layers "F.Cu" "F.Mask" "F.Paste")
			(net "PCEPLL2_VDDA18_PEX2_R")
		)
	)
	(footprint ""
		(layer "F.Cu")
		(at 268.786102 -343.952322 90)
		(property "Reference" "C2342"
			(at 0 0 90)
			(layer "F.SilkS")
			(hide yes)
			(effects
				(font
					(size 1.27 1.27)
				)
			)
		)
		(property "Value" ""
			(at 0 0 90)
			(layer "F.Fab")
			(effects
				(font
					(size 1.27 1.27)
				)
			)
		)
		(duplicate_pad_numbers_are_jumpers no)
		(fp_line
			(start 0.299974 -0.150114)
			(end 0.299974 0.150114)
			(stroke
				(width 0.1)
				(type default)
			)
			(layer "F.Fab")
		)
		(fp_line
			(start -0.299974 -0.150114)
			(end 0.299974 -0.150114)
			(stroke
				(width 0.1)
				(type default)
			)
			(layer "F.Fab")
		)
		(fp_line
			(start 0.299974 0.150114)
			(end -0.299974 0.150114)
			(stroke
				(width 0.1)
				(type default)
			)
			(layer "F.Fab")
		)
		(fp_line
			(start -0.299974 0.150114)
			(end -0.299974 -0.150114)
			(stroke
				(width 0.1)
				(type default)
			)
			(layer "F.Fab")
		)
		(pad "1" smd rect
			(at -0.2667 0 90)
			(size 0.3048 0.381)
			(layers "F.Cu" "F.Mask" "F.Paste")
			(net "P5E_PEX2_STN4_TX_DN<79>")
		)
		(pad "2" smd rect
			(at 0.2667 0 90)
			(size 0.3048 0.381)
			(layers "F.Cu" "F.Mask" "F.Paste")
			(net "P5E_PEX2_STN4_TX_C_DN<79>")
		)
	)
	(footprint ""
		(layer "F.Cu")
		(at 189.630558 -66.32194 -90)
		(property "Reference" "PC850"
			(at 0 0 270)
			(layer "F.SilkS")
			(hide yes)
			(effects
				(font
					(size 1.27 1.27)
				)
			)
		)
		(property "Value" ""
			(at 0 0 270)
			(layer "F.Fab")
			(effects
				(font
					(size 1.27 1.27)
				)
			)
		)
		(duplicate_pad_numbers_are_jumpers no)
		(fp_line
			(start -0.7874 0.4064)
			(end -0.7874 -0.4064)
			(stroke
				(width 0.1524)
				(type default)
			)
			(layer "F.SilkS")
		)
		(fp_line
			(start 0.7874 0.4064)
			(end -0.7874 0.4064)
			(stroke
				(width 0.1524)
				(type default)
			)
			(layer "F.SilkS")
		)
		(fp_line
			(start -0.7874 -0.4064)
			(end 0.7874 -0.4064)
			(stroke
				(width 0.1524)
				(type default)
			)
			(layer "F.SilkS")
		)
		(fp_line
			(start 0.7874 -0.4064)
			(end 0.7874 0.4064)
			(stroke
				(width 0.1524)
				(type default)
			)
			(layer "F.SilkS")
		)
		(fp_line
			(start -0.67945 0.3048)
			(end -0.67945 -0.305054)
			(stroke
				(width 0.1)
				(type default)
			)
			(layer "F.Fab")
		)
		(fp_line
			(start -0.12065 0.3048)
			(end -0.67945 0.3048)
			(stroke
				(width 0.1)
				(type default)
			)
			(layer "F.Fab")
		)
		(fp_line
			(start 0.120396 0.3048)
			(end 0.120396 0.2794)
			(stroke
				(width 0.1)
				(type default)
			)
			(layer "F.Fab")
		)
		(fp_line
			(start 0.67945 0.3048)
			(end 0.120396 0.3048)
			(stroke
				(width 0.1)
				(type default)
			)
			(layer "F.Fab")
		)
		(fp_line
			(start -0.12065 0.2794)
			(end -0.12065 0.3048)
			(stroke
				(width 0.1)
				(type default)
			)
			(layer "F.Fab")
		)
		(fp_line
			(start 0.120396 0.2794)
			(end -0.12065 0.2794)
			(stroke
				(width 0.1)
				(type default)
			)
			(layer "F.Fab")
		)
		(fp_line
			(start -0.12065 -0.2794)
			(end 0.12065 -0.2794)
			(stroke
				(width 0.1)
				(type default)
			)
			(layer "F.Fab")
		)
		(fp_line
			(start 0.12065 -0.2794)
			(end 0.12065 -0.3048)
			(stroke
				(width 0.1)
				(type default)
			)
			(layer "F.Fab")
		)
		(fp_line
			(start 0.12065 -0.3048)
			(end 0.67945 -0.3048)
			(stroke
				(width 0.1)
				(type default)
			)
			(layer "F.Fab")
		)
		(fp_line
			(start 0.67945 -0.3048)
			(end 0.67945 0.3048)
			(stroke
				(width 0.1)
				(type default)
			)
			(layer "F.Fab")
		)
		(fp_line
			(start -0.67945 -0.305054)
			(end -0.12065 -0.305054)
			(stroke
				(width 0.1)
				(type default)
			)
			(layer "F.Fab")
		)
		(fp_line
			(start -0.12065 -0.305054)
			(end -0.12065 -0.2794)
			(stroke
				(width 0.1)
				(type default)
			)
			(layer "F.Fab")
		)
		(pad "1" smd circle
			(at -0.40005 0 270)
			(size 0 0)
			(layers "F.Cu" "F.Mask" "F.Paste")
			(net "P12V_SSD6_CO_DV_DT")
		)
		(pad "2" smd circle
			(at 0.40005 0 270)
			(size 0 0)
			(layers "F.Cu" "F.Mask" "F.Paste")
			(net "GND")
		)
	)
	(footprint ""
		(layer "F.Cu")
		(at 338.328 -245.237 -90)
		(property "Reference" "R1790"
			(at 0 0 270)
			(layer "F.SilkS")
			(hide yes)
			(effects
				(font
					(size 1.27 1.27)
				)
			)
		)
		(property "Value" ""
			(at 0 0 270)
			(layer "F.Fab")
			(effects
				(font
					(size 1.27 1.27)
				)
			)
		)
		(duplicate_pad_numbers_are_jumpers no)
		(fp_line
			(start -0.7874 0.4064)
			(end -0.7874 -0.4064)
			(stroke
				(width 0.1524)
				(type default)
			)
			(layer "F.SilkS")
		)
		(fp_line
			(start 0.7874 0.4064)
			(end -0.7874 0.4064)
			(stroke
				(width 0.1524)
				(type default)
			)
			(layer "F.SilkS")
		)
		(fp_line
			(start -0.7874 -0.4064)
			(end 0.7874 -0.4064)
			(stroke
				(width 0.1524)
				(type default)
			)
			(layer "F.SilkS")
		)
		(fp_line
			(start 0.7874 -0.4064)
			(end 0.7874 0.4064)
			(stroke
				(width 0.1524)
				(type default)
			)
			(layer "F.SilkS")
		)
		(fp_line
			(start -0.67945 0.3048)
			(end -0.67945 -0.305054)
			(stroke
				(width 0.1)
				(type default)
			)
			(layer "F.Fab")
		)
		(fp_line
			(start -0.12065 0.3048)
			(end -0.67945 0.3048)
			(stroke
				(width 0.1)
				(type default)
			)
			(layer "F.Fab")
		)
		(fp_line
			(start 0.120396 0.3048)
			(end 0.120396 0.2794)
			(stroke
				(width 0.1)
				(type default)
			)
			(layer "F.Fab")
		)
		(fp_line
			(start 0.67945 0.3048)
			(end 0.120396 0.3048)
			(stroke
				(width 0.1)
				(type default)
			)
			(layer "F.Fab")
		)
		(fp_line
			(start -0.12065 0.2794)
			(end -0.12065 0.3048)
			(stroke
				(width 0.1)
				(type default)
			)
			(layer "F.Fab")
		)
		(fp_line
			(start 0.120396 0.2794)
			(end -0.12065 0.2794)
			(stroke
				(width 0.1)
				(type default)
			)
			(layer "F.Fab")
		)
		(fp_line
			(start -0.12065 -0.2794)
			(end 0.12065 -0.2794)
			(stroke
				(width 0.1)
				(type default)
			)
			(layer "F.Fab")
		)
		(fp_line
			(start 0.12065 -0.2794)
			(end 0.12065 -0.3048)
			(stroke
				(width 0.1)
				(type default)
			)
			(layer "F.Fab")
		)
		(fp_line
			(start 0.12065 -0.3048)
			(end 0.67945 -0.3048)
			(stroke
				(width 0.1)
				(type default)
			)
			(layer "F.Fab")
		)
		(fp_line
			(start 0.67945 -0.3048)
			(end 0.67945 0.3048)
			(stroke
				(width 0.1)
				(type default)
			)
			(layer "F.Fab")
		)
		(fp_line
			(start -0.67945 -0.305054)
			(end -0.12065 -0.305054)
			(stroke
				(width 0.1)
				(type default)
			)
			(layer "F.Fab")
		)
		(fp_line
			(start -0.12065 -0.305054)
			(end -0.12065 -0.2794)
			(stroke
				(width 0.1)
				(type default)
			)
			(layer "F.Fab")
		)
		(pad "1" smd circle
			(at -0.40005 0 270)
			(size 0 0)
			(layers "F.Cu" "F.Mask" "F.Paste")
			(net "P3V3_AUX")
		)
		(pad "2" smd circle
			(at 0.40005 0 270)
			(size 0 0)
			(layers "F.Cu" "F.Mask" "F.Paste")
			(net "RST_MB_PERST_2_N")
		)
	)
	(footprint ""
		(layer "F.Cu")
		(at 376.809 -175.16602)
		(property "Reference" "R4714"
			(at 0 0 0)
			(layer "F.SilkS")
			(hide yes)
			(effects
				(font
					(size 1.27 1.27)
				)
			)
		)
		(property "Value" ""
			(at 0 0 0)
			(layer "F.Fab")
			(effects
				(font
					(size 1.27 1.27)
				)
			)
		)
		(duplicate_pad_numbers_are_jumpers no)
		(fp_line
			(start -0.7874 -0.4064)
			(end 0.7874 -0.4064)
			(stroke
				(width 0.1524)
				(type default)
			)
			(layer "F.SilkS")
		)
		(fp_line
			(start -0.7874 0.4064)
			(end -0.7874 -0.4064)
			(stroke
				(width 0.1524)
				(type default)
			)
			(layer "F.SilkS")
		)
		(fp_line
			(start 0.7874 -0.4064)
			(end 0.7874 0.4064)
			(stroke
				(width 0.1524)
				(type default)
			)
			(layer "F.SilkS")
		)
		(fp_line
			(start 0.7874 0.4064)
			(end -0.7874 0.4064)
			(stroke
				(width 0.1524)
				(type default)
			)
			(layer "F.SilkS")
		)
		(fp_line
			(start -0.67945 -0.305054)
			(end -0.12065 -0.305054)
			(stroke
				(width 0.1)
				(type default)
			)
			(layer "F.Fab")
		)
		(fp_line
			(start -0.67945 0.3048)
			(end -0.67945 -0.305054)
			(stroke
				(width 0.1)
				(type default)
			)
			(layer "F.Fab")
		)
		(fp_line
			(start -0.12065 -0.305054)
			(end -0.12065 -0.2794)
			(stroke
				(width 0.1)
				(type default)
			)
			(layer "F.Fab")
		)
		(fp_line
			(start -0.12065 -0.2794)
			(end 0.12065 -0.2794)
			(stroke
				(width 0.1)
				(type default)
			)
			(layer "F.Fab")
		)
		(fp_line
			(start -0.12065 0.2794)
			(end -0.12065 0.3048)
			(stroke
				(width 0.1)
				(type default)
			)
			(layer "F.Fab")
		)
		(fp_line
			(start -0.12065 0.3048)
			(end -0.67945 0.3048)
			(stroke
				(width 0.1)
				(type default)
			)
			(layer "F.Fab")
		)
		(fp_line
			(start 0.120396 0.2794)
			(end -0.12065 0.2794)
			(stroke
				(width 0.1)
				(type default)
			)
			(layer "F.Fab")
		)
		(fp_line
			(start 0.120396 0.3048)
			(end 0.120396 0.2794)
			(stroke
				(width 0.1)
				(type default)
			)
			(layer "F.Fab")
		)
		(fp_line
			(start 0.12065 -0.3048)
			(end 0.67945 -0.3048)
			(stroke
				(width 0.1)
				(type default)
			)
			(layer "F.Fab")
		)
		(fp_line
			(start 0.12065 -0.2794)
			(end 0.12065 -0.3048)
			(stroke
				(width 0.1)
				(type default)
			)
			(layer "F.Fab")
		)
		(fp_line
			(start 0.67945 -0.3048)
			(end 0.67945 0.3048)
			(stroke
				(width 0.1)
				(type default)
			)
			(layer "F.Fab")
		)
		(fp_line
			(start 0.67945 0.3048)
			(end 0.120396 0.3048)
			(stroke
				(width 0.1)
				(type default)
			)
			(layer "F.Fab")
		)
		(pad "1" smd circle
			(at -0.40005 0)
			(size 0 0)
			(layers "F.Cu" "F.Mask" "F.Paste")
			(net "NIC3_PEX_PWR_EN")
		)
		(pad "2" smd circle
			(at 0.40005 0)
			(size 0 0)
			(layers "F.Cu" "F.Mask" "F.Paste")
			(net "NIC3_PEX_PWR_EN_R")
		)
	)
	(footprint ""
		(layer "F.Cu")
		(at 143.030194 -281.203908 -90)
		(property "Reference" "C3237"
			(at 0 0 270)
			(layer "F.SilkS")
			(hide yes)
			(effects
				(font
					(size 1.27 1.27)
				)
			)
		)
		(property "Value" ""
			(at 0 0 270)
			(layer "F.Fab")
			(effects
				(font
					(size 1.27 1.27)
				)
			)
		)
		(duplicate_pad_numbers_are_jumpers no)
		(fp_line
			(start -1.2954 0.5842)
			(end -1.2954 -0.5842)
			(stroke
				(width 0.1524)
				(type default)
			)
			(layer "F.SilkS")
		)
		(fp_line
			(start 1.2954 0.5842)
			(end -1.2954 0.5842)
			(stroke
				(width 0.1524)
				(type default)
			)
			(layer "F.SilkS")
		)
		(fp_line
			(start -1.2954 -0.5842)
			(end 1.2954 -0.5842)
			(stroke
				(width 0.1524)
				(type default)
			)
			(layer "F.SilkS")
		)
		(fp_line
			(start 1.2954 -0.5842)
			(end 1.2954 0.5842)
			(stroke
				(width 0.1524)
				(type default)
			)
			(layer "F.SilkS")
		)
		(fp_line
			(start -0.8636 0.4572)
			(end -0.8636 0.4064)
			(stroke
				(width 0.1)
				(type default)
			)
			(layer "F.Fab")
		)
		(fp_line
			(start 0.8636 0.4572)
			(end -0.8636 0.4572)
			(stroke
				(width 0.1)
				(type default)
			)
			(layer "F.Fab")
		)
		(fp_line
			(start -1.1938 0.4064)
			(end -1.1938 -0.4064)
			(stroke
				(width 0.1)
				(type default)
			)
			(layer "F.Fab")
		)
		(fp_line
			(start -0.8636 0.4064)
			(end -1.1938 0.4064)
			(stroke
				(width 0.1)
				(type default)
			)
			(layer "F.Fab")
		)
		(fp_line
			(start 0.8636 0.4064)
			(end 0.8636 0.4572)
			(stroke
				(width 0.1)
				(type default)
			)
			(layer "F.Fab")
		)
		(fp_line
			(start 1.1938 0.4064)
			(end 0.8636 0.4064)
			(stroke
				(width 0.1)
				(type default)
			)
			(layer "F.Fab")
		)
		(fp_line
			(start -1.1938 -0.4064)
			(end -0.8636 -0.4064)
			(stroke
				(width 0.1)
				(type default)
			)
			(layer "F.Fab")
		)
		(fp_line
			(start -0.8636 -0.4064)
			(end -0.8636 -0.4572)
			(stroke
				(width 0.1)
				(type default)
			)
			(layer "F.Fab")
		)
		(fp_line
			(start 0.8636 -0.4064)
			(end 1.1938 -0.4064)
			(stroke
				(width 0.1)
				(type default)
			)
			(layer "F.Fab")
		)
		(fp_line
			(start 1.1938 -0.4064)
			(end 1.1938 0.4064)
			(stroke
				(width 0.1)
				(type default)
			)
			(layer "F.Fab")
		)
		(fp_line
			(start -0.8636 -0.4572)
			(end 0.8636 -0.4572)
			(stroke
				(width 0.1)
				(type default)
			)
			(layer "F.Fab")
		)
		(fp_line
			(start 0.8636 -0.4572)
			(end 0.8636 -0.4064)
			(stroke
				(width 0.1)
				(type default)
			)
			(layer "F.Fab")
		)
		(pad "1" smd rect
			(at -0.7366 0 180)
			(size 0.7112 0.8128)
			(layers "F.Cu" "F.Mask" "F.Paste")
			(net "P1V8_PLL0_PEX1")
		)
		(pad "2" smd rect
			(at 0.7366 0 180)
			(size 0.7112 0.8128)
			(layers "F.Cu" "F.Mask" "F.Paste")
			(net "GND")
		)
	)
	(footprint ""
		(layer "F.Cu")
		(at 454.961752 -49.918874)
		(property "Reference" "R1768"
			(at 0 0 0)
			(layer "F.SilkS")
			(hide yes)
			(effects
				(font
					(size 1.27 1.27)
				)
			)
		)
		(property "Value" ""
			(at 0 0 0)
			(layer "F.Fab")
			(effects
				(font
					(size 1.27 1.27)
				)
			)
		)
		(duplicate_pad_numbers_are_jumpers no)
		(fp_line
			(start -0.7874 -0.4064)
			(end 0.7874 -0.4064)
			(stroke
				(width 0.1524)
				(type default)
			)
			(layer "F.SilkS")
		)
		(fp_line
			(start -0.7874 0.4064)
			(end -0.7874 -0.4064)
			(stroke
				(width 0.1524)
				(type default)
			)
			(layer "F.SilkS")
		)
		(fp_line
			(start 0.7874 -0.4064)
			(end 0.7874 0.4064)
			(stroke
				(width 0.1524)
				(type default)
			)
			(layer "F.SilkS")
		)
		(fp_line
			(start 0.7874 0.4064)
			(end -0.7874 0.4064)
			(stroke
				(width 0.1524)
				(type default)
			)
			(layer "F.SilkS")
		)
		(fp_line
			(start -0.67945 -0.305054)
			(end -0.12065 -0.305054)
			(stroke
				(width 0.1)
				(type default)
			)
			(layer "F.Fab")
		)
		(fp_line
			(start -0.67945 0.3048)
			(end -0.67945 -0.305054)
			(stroke
				(width 0.1)
				(type default)
			)
			(layer "F.Fab")
		)
		(fp_line
			(start -0.12065 -0.305054)
			(end -0.12065 -0.2794)
			(stroke
				(width 0.1)
				(type default)
			)
			(layer "F.Fab")
		)
		(fp_line
			(start -0.12065 -0.2794)
			(end 0.12065 -0.2794)
			(stroke
				(width 0.1)
				(type default)
			)
			(layer "F.Fab")
		)
		(fp_line
			(start -0.12065 0.2794)
			(end -0.12065 0.3048)
			(stroke
				(width 0.1)
				(type default)
			)
			(layer "F.Fab")
		)
		(fp_line
			(start -0.12065 0.3048)
			(end -0.67945 0.3048)
			(stroke
				(width 0.1)
				(type default)
			)
			(layer "F.Fab")
		)
		(fp_line
			(start 0.120396 0.2794)
			(end -0.12065 0.2794)
			(stroke
				(width 0.1)
				(type default)
			)
			(layer "F.Fab")
		)
		(fp_line
			(start 0.120396 0.3048)
			(end 0.120396 0.2794)
			(stroke
				(width 0.1)
				(type default)
			)
			(layer "F.Fab")
		)
		(fp_line
			(start 0.12065 -0.3048)
			(end 0.67945 -0.3048)
			(stroke
				(width 0.1)
				(type default)
			)
			(layer "F.Fab")
		)
		(fp_line
			(start 0.12065 -0.2794)
			(end 0.12065 -0.3048)
			(stroke
				(width 0.1)
				(type default)
			)
			(layer "F.Fab")
		)
		(fp_line
			(start 0.67945 -0.3048)
			(end 0.67945 0.3048)
			(stroke
				(width 0.1)
				(type default)
			)
			(layer "F.Fab")
		)
		(fp_line
			(start 0.67945 0.3048)
			(end 0.120396 0.3048)
			(stroke
				(width 0.1)
				(type default)
			)
			(layer "F.Fab")
		)
		(pad "1" smd circle
			(at -0.40005 0)
			(size 0 0)
			(layers "F.Cu" "F.Mask" "F.Paste")
			(net "SMB_BIC_I2C6_MUX_SSD_8_15_ADC_R_SCL")
		)
		(pad "2" smd circle
			(at 0.40005 0)
			(size 0 0)
			(layers "F.Cu" "F.Mask" "F.Paste")
			(net "SMB_BIC_I2C6_MUX_SSD_8_15_ADC_SCL")
		)
	)
	(footprint ""
		(layer "F.Cu")
		(at 32.575754 -36.915598 -90)
		(property "Reference" "R5544"
			(at 0 0 270)
			(layer "F.SilkS")
			(hide yes)
			(effects
				(font
					(size 1.27 1.27)
				)
			)
		)
		(property "Value" ""
			(at 0 0 270)
			(layer "F.Fab")
			(effects
				(font
					(size 1.27 1.27)
				)
			)
		)
		(duplicate_pad_numbers_are_jumpers no)
		(fp_line
			(start -0.7874 0.4064)
			(end -0.7874 -0.4064)
			(stroke
				(width 0.1524)
				(type default)
			)
			(layer "F.SilkS")
		)
		(fp_line
			(start 0.7874 0.4064)
			(end -0.7874 0.4064)
			(stroke
				(width 0.1524)
				(type default)
			)
			(layer "F.SilkS")
		)
		(fp_line
			(start -0.7874 -0.4064)
			(end 0.7874 -0.4064)
			(stroke
				(width 0.1524)
				(type default)
			)
			(layer "F.SilkS")
		)
		(fp_line
			(start 0.7874 -0.4064)
			(end 0.7874 0.4064)
			(stroke
				(width 0.1524)
				(type default)
			)
			(layer "F.SilkS")
		)
		(fp_line
			(start -0.67945 0.3048)
			(end -0.67945 -0.305054)
			(stroke
				(width 0.1)
				(type default)
			)
			(layer "F.Fab")
		)
		(fp_line
			(start -0.12065 0.3048)
			(end -0.67945 0.3048)
			(stroke
				(width 0.1)
				(type default)
			)
			(layer "F.Fab")
		)
		(fp_line
			(start 0.120396 0.3048)
			(end 0.120396 0.2794)
			(stroke
				(width 0.1)
				(type default)
			)
			(layer "F.Fab")
		)
		(fp_line
			(start 0.67945 0.3048)
			(end 0.120396 0.3048)
			(stroke
				(width 0.1)
				(type default)
			)
			(layer "F.Fab")
		)
		(fp_line
			(start -0.12065 0.2794)
			(end -0.12065 0.3048)
			(stroke
				(width 0.1)
				(type default)
			)
			(layer "F.Fab")
		)
		(fp_line
			(start 0.120396 0.2794)
			(end -0.12065 0.2794)
			(stroke
				(width 0.1)
				(type default)
			)
			(layer "F.Fab")
		)
		(fp_line
			(start -0.12065 -0.2794)
			(end 0.12065 -0.2794)
			(stroke
				(width 0.1)
				(type default)
			)
			(layer "F.Fab")
		)
		(fp_line
			(start 0.12065 -0.2794)
			(end 0.12065 -0.3048)
			(stroke
				(width 0.1)
				(type default)
			)
			(layer "F.Fab")
		)
		(fp_line
			(start 0.12065 -0.3048)
			(end 0.67945 -0.3048)
			(stroke
				(width 0.1)
				(type default)
			)
			(layer "F.Fab")
		)
		(fp_line
			(start 0.67945 -0.3048)
			(end 0.67945 0.3048)
			(stroke
				(width 0.1)
				(type default)
			)
			(layer "F.Fab")
		)
		(fp_line
			(start -0.67945 -0.305054)
			(end -0.12065 -0.305054)
			(stroke
				(width 0.1)
				(type default)
			)
			(layer "F.Fab")
		)
		(fp_line
			(start -0.12065 -0.305054)
			(end -0.12065 -0.2794)
			(stroke
				(width 0.1)
				(type default)
			)
			(layer "F.Fab")
		)
		(pad "1" smd circle
			(at -0.40005 0 270)
			(size 0 0)
			(layers "F.Cu" "F.Mask" "F.Paste")
			(net "PRSNT_SSD1_R1_N")
		)
		(pad "2" smd circle
			(at 0.40005 0 270)
			(size 0 0)
			(layers "F.Cu" "F.Mask" "F.Paste")
			(net "PRSNT_SSD1_R_N")
		)
	)
	(footprint ""
		(layer "F.Cu")
		(at 2.87528 -64.102234)
		(property "Reference" "R5842"
			(at 0 0 0)
			(layer "F.SilkS")
			(hide yes)
			(effects
				(font
					(size 1.27 1.27)
				)
			)
		)
		(property "Value" ""
			(at 0 0 0)
			(layer "F.Fab")
			(effects
				(font
					(size 1.27 1.27)
				)
			)
		)
		(duplicate_pad_numbers_are_jumpers no)
		(fp_line
			(start -0.7874 -0.4064)
			(end 0.7874 -0.4064)
			(stroke
				(width 0.1524)
				(type default)
			)
			(layer "F.SilkS")
		)
		(fp_line
			(start -0.7874 0.4064)
			(end -0.7874 -0.4064)
			(stroke
				(width 0.1524)
				(type default)
			)
			(layer "F.SilkS")
		)
		(fp_line
			(start 0.7874 -0.4064)
			(end 0.7874 0.4064)
			(stroke
				(width 0.1524)
				(type default)
			)
			(layer "F.SilkS")
		)
		(fp_line
			(start 0.7874 0.4064)
			(end -0.7874 0.4064)
			(stroke
				(width 0.1524)
				(type default)
			)
			(layer "F.SilkS")
		)
		(fp_line
			(start -0.67945 -0.305054)
			(end -0.12065 -0.305054)
			(stroke
				(width 0.1)
				(type default)
			)
			(layer "F.Fab")
		)
		(fp_line
			(start -0.67945 0.3048)
			(end -0.67945 -0.305054)
			(stroke
				(width 0.1)
				(type default)
			)
			(layer "F.Fab")
		)
		(fp_line
			(start -0.12065 -0.305054)
			(end -0.12065 -0.2794)
			(stroke
				(width 0.1)
				(type default)
			)
			(layer "F.Fab")
		)
		(fp_line
			(start -0.12065 -0.2794)
			(end 0.12065 -0.2794)
			(stroke
				(width 0.1)
				(type default)
			)
			(layer "F.Fab")
		)
		(fp_line
			(start -0.12065 0.2794)
			(end -0.12065 0.3048)
			(stroke
				(width 0.1)
				(type default)
			)
			(layer "F.Fab")
		)
		(fp_line
			(start -0.12065 0.3048)
			(end -0.67945 0.3048)
			(stroke
				(width 0.1)
				(type default)
			)
			(layer "F.Fab")
		)
		(fp_line
			(start 0.120396 0.2794)
			(end -0.12065 0.2794)
			(stroke
				(width 0.1)
				(type default)
			)
			(layer "F.Fab")
		)
		(fp_line
			(start 0.120396 0.3048)
			(end 0.120396 0.2794)
			(stroke
				(width 0.1)
				(type default)
			)
			(layer "F.Fab")
		)
		(fp_line
			(start 0.12065 -0.3048)
			(end 0.67945 -0.3048)
			(stroke
				(width 0.1)
				(type default)
			)
			(layer "F.Fab")
		)
		(fp_line
			(start 0.12065 -0.2794)
			(end 0.12065 -0.3048)
			(stroke
				(width 0.1)
				(type default)
			)
			(layer "F.Fab")
		)
		(fp_line
			(start 0.67945 -0.3048)
			(end 0.67945 0.3048)
			(stroke
				(width 0.1)
				(type default)
			)
			(layer "F.Fab")
		)
		(fp_line
			(start 0.67945 0.3048)
			(end 0.120396 0.3048)
			(stroke
				(width 0.1)
				(type default)
			)
			(layer "F.Fab")
		)
		(pad "1" smd circle
			(at -0.40005 0)
			(size 0 0)
			(layers "F.Cu" "F.Mask" "F.Paste")
			(net "P12V_SSD0_R")
		)
		(pad "2" smd circle
			(at 0.40005 0)
			(size 0 0)
			(layers "F.Cu" "F.Mask" "F.Paste")
			(net "P12V_SSD0_PG_G1")
		)
	)
	(footprint ""
		(layer "F.Cu")
		(at 431.147728 -40.037258 90)
		(property "Reference" "U378"
			(at 0.247142 2.431542 90)
			(unlocked yes)
			(layer "F.SilkS")
			(effects
				(font
					(size 0.7874 0.5842)
					(thickness 0.1524)
				)
			)
		)
		(property "Value" ""
			(at 0 0 90)
			(layer "F.Fab")
			(effects
				(font
					(size 1.27 1.27)
				)
			)
		)
		(duplicate_pad_numbers_are_jumpers no)
		(fp_line
			(start -1.949958 -1.610106)
			(end 1.949958 -1.610106)
			(stroke
				(width 0.1524)
				(type default)
			)
			(layer "F.SilkS")
		)
		(fp_line
			(start 1.949958 -1.560068)
			(end 1.949958 1.610106)
			(stroke
				(width 0.1524)
				(type default)
			)
			(layer "F.SilkS")
		)
		(fp_line
			(start 1.949958 1.610106)
			(end -1.949958 1.610106)
			(stroke
				(width 0.1524)
				(type default)
			)
			(layer "F.SilkS")
		)
		(fp_line
			(start -1.949958 1.610106)
			(end -1.949958 -1.610106)
			(stroke
				(width 0.1524)
				(type default)
			)
			(layer "F.SilkS")
		)
		(fp_line
			(start 0.750062 -1.560068)
			(end 0.750062 1.560068)
			(stroke
				(width 0.1)
				(type default)
			)
			(layer "F.Fab")
		)
		(fp_line
			(start -0.750062 -1.560068)
			(end 0.750062 -1.560068)
			(stroke
				(width 0.1)
				(type default)
			)
			(layer "F.Fab")
		)
		(fp_line
			(start 0.750062 1.560068)
			(end -0.750062 1.560068)
			(stroke
				(width 0.1)
				(type default)
			)
			(layer "F.Fab")
		)
		(fp_line
			(start -0.750062 1.560068)
			(end -0.750062 -1.560068)
			(stroke
				(width 0.1)
				(type default)
			)
			(layer "F.Fab")
		)
		(pad "D" smd rect
			(at 1.100074 0)
			(size 1.016 1.4224)
			(layers "F.Cu" "F.Mask" "F.Paste")
			(net "SSD15_AUX_P3V3_EN")
		)
		(pad "G" smd rect
			(at -1.100074 -0.94996)
			(size 1.016 1.4224)
			(layers "F.Cu" "F.Mask" "F.Paste")
			(net "PRSNT_SSD15_R1_N")
		)
		(pad "S" smd rect
			(at -1.100074 0.94996)
			(size 1.016 1.4224)
			(layers "F.Cu" "F.Mask" "F.Paste")
			(net "GND")
		)
	)
	(footprint ""
		(layer "F.Cu")
		(at 335.534 -201.168 -90)
		(property "Reference" "R4125"
			(at 0 0 270)
			(layer "F.SilkS")
			(hide yes)
			(effects
				(font
					(size 1.27 1.27)
				)
			)
		)
		(property "Value" ""
			(at 0 0 270)
			(layer "F.Fab")
			(effects
				(font
					(size 1.27 1.27)
				)
			)
		)
		(duplicate_pad_numbers_are_jumpers no)
		(fp_line
			(start -0.7874 0.4064)
			(end -0.7874 -0.4064)
			(stroke
				(width 0.1524)
				(type default)
			)
			(layer "F.SilkS")
		)
		(fp_line
			(start 0.7874 0.4064)
			(end -0.7874 0.4064)
			(stroke
				(width 0.1524)
				(type default)
			)
			(layer "F.SilkS")
		)
		(fp_line
			(start -0.7874 -0.4064)
			(end 0.7874 -0.4064)
			(stroke
				(width 0.1524)
				(type default)
			)
			(layer "F.SilkS")
		)
		(fp_line
			(start 0.7874 -0.4064)
			(end 0.7874 0.4064)
			(stroke
				(width 0.1524)
				(type default)
			)
			(layer "F.SilkS")
		)
		(fp_line
			(start -0.67945 0.3048)
			(end -0.67945 -0.305054)
			(stroke
				(width 0.1)
				(type default)
			)
			(layer "F.Fab")
		)
		(fp_line
			(start -0.12065 0.3048)
			(end -0.67945 0.3048)
			(stroke
				(width 0.1)
				(type default)
			)
			(layer "F.Fab")
		)
		(fp_line
			(start 0.120396 0.3048)
			(end 0.120396 0.2794)
			(stroke
				(width 0.1)
				(type default)
			)
			(layer "F.Fab")
		)
		(fp_line
			(start 0.67945 0.3048)
			(end 0.120396 0.3048)
			(stroke
				(width 0.1)
				(type default)
			)
			(layer "F.Fab")
		)
		(fp_line
			(start -0.12065 0.2794)
			(end -0.12065 0.3048)
			(stroke
				(width 0.1)
				(type default)
			)
			(layer "F.Fab")
		)
		(fp_line
			(start 0.120396 0.2794)
			(end -0.12065 0.2794)
			(stroke
				(width 0.1)
				(type default)
			)
			(layer "F.Fab")
		)
		(fp_line
			(start -0.12065 -0.2794)
			(end 0.12065 -0.2794)
			(stroke
				(width 0.1)
				(type default)
			)
			(layer "F.Fab")
		)
		(fp_line
			(start 0.12065 -0.2794)
			(end 0.12065 -0.3048)
			(stroke
				(width 0.1)
				(type default)
			)
			(layer "F.Fab")
		)
		(fp_line
			(start 0.12065 -0.3048)
			(end 0.67945 -0.3048)
			(stroke
				(width 0.1)
				(type default)
			)
			(layer "F.Fab")
		)
		(fp_line
			(start 0.67945 -0.3048)
			(end 0.67945 0.3048)
			(stroke
				(width 0.1)
				(type default)
			)
			(layer "F.Fab")
		)
		(fp_line
			(start -0.67945 -0.305054)
			(end -0.12065 -0.305054)
			(stroke
				(width 0.1)
				(type default)
			)
			(layer "F.Fab")
		)
		(fp_line
			(start -0.12065 -0.305054)
			(end -0.12065 -0.2794)
			(stroke
				(width 0.1)
				(type default)
			)
			(layer "F.Fab")
		)
		(pad "1" smd circle
			(at -0.40005 0 270)
			(size 0 0)
			(layers "F.Cu" "F.Mask" "F.Paste")
			(net "RST_SSD10_PERST_N")
		)
		(pad "2" smd circle
			(at 0.40005 0 270)
			(size 0 0)
			(layers "F.Cu" "F.Mask" "F.Paste")
			(net "RST_SSD10_PERST_R_N")
		)
	)
	(footprint ""
		(layer "F.Cu")
		(at 271.782286 -252.356874 -90)
		(property "Reference" "R3963"
			(at 0 0 270)
			(layer "F.SilkS")
			(hide yes)
			(effects
				(font
					(size 1.27 1.27)
				)
			)
		)
		(property "Value" ""
			(at 0 0 270)
			(layer "F.Fab")
			(effects
				(font
					(size 1.27 1.27)
				)
			)
		)
		(duplicate_pad_numbers_are_jumpers no)
		(fp_line
			(start -0.7874 0.4064)
			(end -0.7874 -0.4064)
			(stroke
				(width 0.1524)
				(type default)
			)
			(layer "F.SilkS")
		)
		(fp_line
			(start 0.7874 0.4064)
			(end -0.7874 0.4064)
			(stroke
				(width 0.1524)
				(type default)
			)
			(layer "F.SilkS")
		)
		(fp_line
			(start -0.7874 -0.4064)
			(end 0.7874 -0.4064)
			(stroke
				(width 0.1524)
				(type default)
			)
			(layer "F.SilkS")
		)
		(fp_line
			(start 0.7874 -0.4064)
			(end 0.7874 0.4064)
			(stroke
				(width 0.1524)
				(type default)
			)
			(layer "F.SilkS")
		)
		(fp_line
			(start -0.67945 0.3048)
			(end -0.67945 -0.305054)
			(stroke
				(width 0.1)
				(type default)
			)
			(layer "F.Fab")
		)
		(fp_line
			(start -0.12065 0.3048)
			(end -0.67945 0.3048)
			(stroke
				(width 0.1)
				(type default)
			)
			(layer "F.Fab")
		)
		(fp_line
			(start 0.120396 0.3048)
			(end 0.120396 0.2794)
			(stroke
				(width 0.1)
				(type default)
			)
			(layer "F.Fab")
		)
		(fp_line
			(start 0.67945 0.3048)
			(end 0.120396 0.3048)
			(stroke
				(width 0.1)
				(type default)
			)
			(layer "F.Fab")
		)
		(fp_line
			(start -0.12065 0.2794)
			(end -0.12065 0.3048)
			(stroke
				(width 0.1)
				(type default)
			)
			(layer "F.Fab")
		)
		(fp_line
			(start 0.120396 0.2794)
			(end -0.12065 0.2794)
			(stroke
				(width 0.1)
				(type default)
			)
			(layer "F.Fab")
		)
		(fp_line
			(start -0.12065 -0.2794)
			(end 0.12065 -0.2794)
			(stroke
				(width 0.1)
				(type default)
			)
			(layer "F.Fab")
		)
		(fp_line
			(start 0.12065 -0.2794)
			(end 0.12065 -0.3048)
			(stroke
				(width 0.1)
				(type default)
			)
			(layer "F.Fab")
		)
		(fp_line
			(start 0.12065 -0.3048)
			(end 0.67945 -0.3048)
			(stroke
				(width 0.1)
				(type default)
			)
			(layer "F.Fab")
		)
		(fp_line
			(start 0.67945 -0.3048)
			(end 0.67945 0.3048)
			(stroke
				(width 0.1)
				(type default)
			)
			(layer "F.Fab")
		)
		(fp_line
			(start -0.67945 -0.305054)
			(end -0.12065 -0.305054)
			(stroke
				(width 0.1)
				(type default)
			)
			(layer "F.Fab")
		)
		(fp_line
			(start -0.12065 -0.305054)
			(end -0.12065 -0.2794)
			(stroke
				(width 0.1)
				(type default)
			)
			(layer "F.Fab")
		)
		(pad "1" smd circle
			(at -0.40005 0 270)
			(size 0 0)
			(layers "F.Cu" "F.Mask" "F.Paste")
			(net "PEX2_PCA9555_INT_R_N")
		)
		(pad "2" smd circle
			(at 0.40005 0 270)
			(size 0 0)
			(layers "F.Cu" "F.Mask" "F.Paste")
			(net "P1V8_PEX")
		)
	)
	(footprint ""
		(layer "F.Cu")
		(at 146.18208 -286.590232 180)
		(property "Reference" "C3235"
			(at 0 0 180)
			(layer "F.SilkS")
			(hide yes)
			(effects
				(font
					(size 1.27 1.27)
				)
			)
		)
		(property "Value" ""
			(at 0 0 180)
			(layer "F.Fab")
			(effects
				(font
					(size 1.27 1.27)
				)
			)
		)
		(duplicate_pad_numbers_are_jumpers no)
		(fp_line
			(start 1.2954 0.5842)
			(end -1.2954 0.5842)
			(stroke
				(width 0.1524)
				(type default)
			)
			(layer "F.SilkS")
		)
		(fp_line
			(start 1.2954 -0.5842)
			(end 1.2954 0.5842)
			(stroke
				(width 0.1524)
				(type default)
			)
			(layer "F.SilkS")
		)
		(fp_line
			(start -1.2954 0.5842)
			(end -1.2954 -0.5842)
			(stroke
				(width 0.1524)
				(type default)
			)
			(layer "F.SilkS")
		)
		(fp_line
			(start -1.2954 -0.5842)
			(end 1.2954 -0.5842)
			(stroke
				(width 0.1524)
				(type default)
			)
			(layer "F.SilkS")
		)
		(fp_line
			(start 1.1938 0.4064)
			(end 0.8636 0.4064)
			(stroke
				(width 0.1)
				(type default)
			)
			(layer "F.Fab")
		)
		(fp_line
			(start 1.1938 -0.4064)
			(end 1.1938 0.4064)
			(stroke
				(width 0.1)
				(type default)
			)
			(layer "F.Fab")
		)
		(fp_line
			(start 0.8636 0.4572)
			(end -0.8636 0.4572)
			(stroke
				(width 0.1)
				(type default)
			)
			(layer "F.Fab")
		)
		(fp_line
			(start 0.8636 0.4064)
			(end 0.8636 0.4572)
			(stroke
				(width 0.1)
				(type default)
			)
			(layer "F.Fab")
		)
		(fp_line
			(start 0.8636 -0.4064)
			(end 1.1938 -0.4064)
			(stroke
				(width 0.1)
				(type default)
			)
			(layer "F.Fab")
		)
		(fp_line
			(start 0.8636 -0.4572)
			(end 0.8636 -0.4064)
			(stroke
				(width 0.1)
				(type default)
			)
			(layer "F.Fab")
		)
		(fp_line
			(start -0.8636 0.4572)
			(end -0.8636 0.4064)
			(stroke
				(width 0.1)
				(type default)
			)
			(layer "F.Fab")
		)
		(fp_line
			(start -0.8636 0.4064)
			(end -1.1938 0.4064)
			(stroke
				(width 0.1)
				(type default)
			)
			(layer "F.Fab")
		)
		(fp_line
			(start -0.8636 -0.4064)
			(end -0.8636 -0.4572)
			(stroke
				(width 0.1)
				(type default)
			)
			(layer "F.Fab")
		)
		(fp_line
			(start -0.8636 -0.4572)
			(end 0.8636 -0.4572)
			(stroke
				(width 0.1)
				(type default)
			)
			(layer "F.Fab")
		)
		(fp_line
			(start -1.1938 0.4064)
			(end -1.1938 -0.4064)
			(stroke
				(width 0.1)
				(type default)
			)
			(layer "F.Fab")
		)
		(fp_line
			(start -1.1938 -0.4064)
			(end -0.8636 -0.4064)
			(stroke
				(width 0.1)
				(type default)
			)
			(layer "F.Fab")
		)
		(pad "1" smd rect
			(at -0.7366 0 90)
			(size 0.7112 0.8128)
			(layers "F.Cu" "F.Mask" "F.Paste")
			(net "PCEPLL6_VDDA18_PEX1_R")
		)
		(pad "2" smd rect
			(at 0.7366 0 90)
			(size 0.7112 0.8128)
			(layers "F.Cu" "F.Mask" "F.Paste")
			(net "GND")
		)
	)
	(footprint ""
		(layer "F.Cu")
		(at 78.243684 -47.92091)
		(property "Reference" "R526"
			(at 0 0 0)
			(layer "F.SilkS")
			(hide yes)
			(effects
				(font
					(size 1.27 1.27)
				)
			)
		)
		(property "Value" ""
			(at 0 0 0)
			(layer "F.Fab")
			(effects
				(font
					(size 1.27 1.27)
				)
			)
		)
		(duplicate_pad_numbers_are_jumpers no)
		(fp_line
			(start -0.7874 -0.4064)
			(end 0.7874 -0.4064)
			(stroke
				(width 0.1524)
				(type default)
			)
			(layer "F.SilkS")
		)
		(fp_line
			(start -0.7874 0.4064)
			(end -0.7874 -0.4064)
			(stroke
				(width 0.1524)
				(type default)
			)
			(layer "F.SilkS")
		)
		(fp_line
			(start 0.7874 -0.4064)
			(end 0.7874 0.4064)
			(stroke
				(width 0.1524)
				(type default)
			)
			(layer "F.SilkS")
		)
		(fp_line
			(start 0.7874 0.4064)
			(end -0.7874 0.4064)
			(stroke
				(width 0.1524)
				(type default)
			)
			(layer "F.SilkS")
		)
		(fp_line
			(start -0.67945 -0.305054)
			(end -0.12065 -0.305054)
			(stroke
				(width 0.1)
				(type default)
			)
			(layer "F.Fab")
		)
		(fp_line
			(start -0.67945 0.3048)
			(end -0.67945 -0.305054)
			(stroke
				(width 0.1)
				(type default)
			)
			(layer "F.Fab")
		)
		(fp_line
			(start -0.12065 -0.305054)
			(end -0.12065 -0.2794)
			(stroke
				(width 0.1)
				(type default)
			)
			(layer "F.Fab")
		)
		(fp_line
			(start -0.12065 -0.2794)
			(end 0.12065 -0.2794)
			(stroke
				(width 0.1)
				(type default)
			)
			(layer "F.Fab")
		)
		(fp_line
			(start -0.12065 0.2794)
			(end -0.12065 0.3048)
			(stroke
				(width 0.1)
				(type default)
			)
			(layer "F.Fab")
		)
		(fp_line
			(start -0.12065 0.3048)
			(end -0.67945 0.3048)
			(stroke
				(width 0.1)
				(type default)
			)
			(layer "F.Fab")
		)
		(fp_line
			(start 0.120396 0.2794)
			(end -0.12065 0.2794)
			(stroke
				(width 0.1)
				(type default)
			)
			(layer "F.Fab")
		)
		(fp_line
			(start 0.120396 0.3048)
			(end 0.120396 0.2794)
			(stroke
				(width 0.1)
				(type default)
			)
			(layer "F.Fab")
		)
		(fp_line
			(start 0.12065 -0.3048)
			(end 0.67945 -0.3048)
			(stroke
				(width 0.1)
				(type default)
			)
			(layer "F.Fab")
		)
		(fp_line
			(start 0.12065 -0.2794)
			(end 0.12065 -0.3048)
			(stroke
				(width 0.1)
				(type default)
			)
			(layer "F.Fab")
		)
		(fp_line
			(start 0.67945 -0.3048)
			(end 0.67945 0.3048)
			(stroke
				(width 0.1)
				(type default)
			)
			(layer "F.Fab")
		)
		(fp_line
			(start 0.67945 0.3048)
			(end 0.120396 0.3048)
			(stroke
				(width 0.1)
				(type default)
			)
			(layer "F.Fab")
		)
		(pad "1" smd circle
			(at -0.40005 0)
			(size 0 0)
			(layers "F.Cu" "F.Mask" "F.Paste")
			(net "P3V3_AUX")
		)
		(pad "2" smd circle
			(at 0.40005 0)
			(size 0 0)
			(layers "F.Cu" "F.Mask" "F.Paste")
			(net "SSD_0_7_ADC_ALERT_N")
		)
	)
	(footprint ""
		(layer "F.Cu")
		(at 280.160984 -37.951156)
		(property "Reference" "Q226"
			(at -0.049784 -1.823974 0)
			(unlocked yes)
			(layer "F.SilkS")
			(effects
				(font
					(size 0.7874 0.5842)
					(thickness 0.1524)
				)
			)
		)
		(property "Value" ""
			(at 0 0 0)
			(layer "F.Fab")
			(effects
				(font
					(size 1.27 1.27)
				)
			)
		)
		(duplicate_pad_numbers_are_jumpers no)
		(fp_line
			(start -1.376172 -1.199896)
			(end -0.508 -1.199896)
			(stroke
				(width 0.1524)
				(type default)
			)
			(layer "F.SilkS")
		)
		(fp_line
			(start -1.376172 1.199896)
			(end -1.376172 -1.199896)
			(stroke
				(width 0.1524)
				(type default)
			)
			(layer "F.SilkS")
		)
		(fp_line
			(start -0.508 -1.199896)
			(end 0 -0.762)
			(stroke
				(width 0.1524)
				(type default)
			)
			(layer "F.SilkS")
		)
		(fp_line
			(start 0 -0.762)
			(end 0.508 -1.199896)
			(stroke
				(width 0.1524)
				(type default)
			)
			(layer "F.SilkS")
		)
		(fp_line
			(start 0.508 -1.199896)
			(end 1.376172 -1.199896)
			(stroke
				(width 0.1524)
				(type default)
			)
			(layer "F.SilkS")
		)
		(fp_line
			(start 1.376172 -1.199896)
			(end 1.376172 1.199896)
			(stroke
				(width 0.1524)
				(type default)
			)
			(layer "F.SilkS")
		)
		(fp_line
			(start 1.376172 1.199896)
			(end -1.376172 1.199896)
			(stroke
				(width 0.1524)
				(type default)
			)
			(layer "F.SilkS")
		)
		(fp_poly
			(pts
				(xy -1.506982 -0.950468) (xy -1.776476 -1.758696) (xy -2.31521 -1.219708)
			)
			(stroke
				(width 0)
				(type default)
			)
			(fill yes)
			(layer "F.SilkS")
		)
		(fp_line
			(start -0.674878 -1.100074)
			(end 0.674878 -1.100074)
			(stroke
				(width 0.1)
				(type default)
			)
			(layer "F.Fab")
		)
		(fp_line
			(start -0.674878 1.100074)
			(end -0.674878 -1.100074)
			(stroke
				(width 0.1)
				(type default)
			)
			(layer "F.Fab")
		)
		(fp_line
			(start 0.674878 -1.100074)
			(end 0.674878 1.100074)
			(stroke
				(width 0.1)
				(type default)
			)
			(layer "F.Fab")
		)
		(fp_line
			(start 0.674878 1.100074)
			(end -0.674878 1.100074)
			(stroke
				(width 0.1)
				(type default)
			)
			(layer "F.Fab")
		)
		(fp_poly
			(pts
				(xy -1.4605 -0.7493) (xy -2.2225 -1.1303) (xy -2.2225 -0.3683)
			)
			(stroke
				(width 0)
				(type default)
			)
			(fill yes)
			(layer "F.Fab")
		)
		(pad "1" smd rect
			(at -0.899922 -0.750062 270)
			(size 0.6096 0.6096)
			(layers "F.Cu" "F.Mask" "F.Paste")
			(net "GND")
		)
		(pad "2" smd rect
			(at -0.899922 0 270)
			(size 0.4064 0.6096)
			(layers "F.Cu" "F.Mask" "F.Paste")
			(net "P3V3_SSD10_PG_G1")
		)
		(pad "3" smd rect
			(at -0.899922 0.750062 270)
			(size 0.6096 0.6096)
			(layers "F.Cu" "F.Mask" "F.Paste")
			(net "PWRGD_P3V3_SSD10_D")
		)
		(pad "4" smd rect
			(at 0.899922 0.750062 270)
			(size 0.6096 0.6096)
			(layers "F.Cu" "F.Mask" "F.Paste")
			(net "GND")
		)
		(pad "5" smd rect
			(at 0.899922 0 270)
			(size 0.4064 0.6096)
			(layers "F.Cu" "F.Mask" "F.Paste")
			(net "P3V3_SSD10_PG_G2")
		)
		(pad "6" smd rect
			(at 0.899922 -0.750062 270)
			(size 0.6096 0.6096)
			(layers "F.Cu" "F.Mask" "F.Paste")
			(net "P3V3_SSD10_PG_G2")
		)
	)
	(footprint ""
		(layer "F.Cu")
		(at 213.809072 -221.350586 180)
		(property "Reference" "R4886"
			(at 0 0 180)
			(layer "F.SilkS")
			(hide yes)
			(effects
				(font
					(size 1.27 1.27)
				)
			)
		)
		(property "Value" ""
			(at 0 0 180)
			(layer "F.Fab")
			(effects
				(font
					(size 1.27 1.27)
				)
			)
		)
		(duplicate_pad_numbers_are_jumpers no)
		(fp_line
			(start 0.7874 0.4064)
			(end -0.7874 0.4064)
			(stroke
				(width 0.1524)
				(type default)
			)
			(layer "F.SilkS")
		)
		(fp_line
			(start 0.7874 -0.4064)
			(end 0.7874 0.4064)
			(stroke
				(width 0.1524)
				(type default)
			)
			(layer "F.SilkS")
		)
		(fp_line
			(start -0.7874 0.4064)
			(end -0.7874 -0.4064)
			(stroke
				(width 0.1524)
				(type default)
			)
			(layer "F.SilkS")
		)
		(fp_line
			(start -0.7874 -0.4064)
			(end 0.7874 -0.4064)
			(stroke
				(width 0.1524)
				(type default)
			)
			(layer "F.SilkS")
		)
		(fp_line
			(start 0.67945 0.3048)
			(end 0.120396 0.3048)
			(stroke
				(width 0.1)
				(type default)
			)
			(layer "F.Fab")
		)
		(fp_line
			(start 0.67945 -0.3048)
			(end 0.67945 0.3048)
			(stroke
				(width 0.1)
				(type default)
			)
			(layer "F.Fab")
		)
		(fp_line
			(start 0.12065 -0.2794)
			(end 0.12065 -0.3048)
			(stroke
				(width 0.1)
				(type default)
			)
			(layer "F.Fab")
		)
		(fp_line
			(start 0.12065 -0.3048)
			(end 0.67945 -0.3048)
			(stroke
				(width 0.1)
				(type default)
			)
			(layer "F.Fab")
		)
		(fp_line
			(start 0.120396 0.3048)
			(end 0.120396 0.2794)
			(stroke
				(width 0.1)
				(type default)
			)
			(layer "F.Fab")
		)
		(fp_line
			(start 0.120396 0.2794)
			(end -0.12065 0.2794)
			(stroke
				(width 0.1)
				(type default)
			)
			(layer "F.Fab")
		)
		(fp_line
			(start -0.12065 0.3048)
			(end -0.67945 0.3048)
			(stroke
				(width 0.1)
				(type default)
			)
			(layer "F.Fab")
		)
		(fp_line
			(start -0.12065 0.2794)
			(end -0.12065 0.3048)
			(stroke
				(width 0.1)
				(type default)
			)
			(layer "F.Fab")
		)
		(fp_line
			(start -0.12065 -0.2794)
			(end 0.12065 -0.2794)
			(stroke
				(width 0.1)
				(type default)
			)
			(layer "F.Fab")
		)
		(fp_line
			(start -0.12065 -0.305054)
			(end -0.12065 -0.2794)
			(stroke
				(width 0.1)
				(type default)
			)
			(layer "F.Fab")
		)
		(fp_line
			(start -0.67945 0.3048)
			(end -0.67945 -0.305054)
			(stroke
				(width 0.1)
				(type default)
			)
			(layer "F.Fab")
		)
		(fp_line
			(start -0.67945 -0.305054)
			(end -0.12065 -0.305054)
			(stroke
				(width 0.1)
				(type default)
			)
			(layer "F.Fab")
		)
		(pad "1" smd circle
			(at -0.40005 0 180)
			(size 0 0)
			(layers "F.Cu" "F.Mask" "F.Paste")
			(net "SMB_BIC_I2C9_SSD_MUX_R_SDA")
		)
		(pad "2" smd circle
			(at 0.40005 0 180)
			(size 0 0)
			(layers "F.Cu" "F.Mask" "F.Paste")
			(net "P3V3_AUX")
		)
	)
	(footprint ""
		(layer "F.Cu")
		(at 19.740118 -225.49993 180)
		(property "Reference" "U317"
			(at 1.629918 -8.386064 0)
			(unlocked yes)
			(layer "F.SilkS")
			(effects
				(font
					(size 0.7874 0.5842)
					(thickness 0.1524)
				)
				(justify left)
			)
		)
		(property "Value" ""
			(at 0 0 180)
			(layer "F.Fab")
			(effects
				(font
					(size 1.27 1.27)
				)
			)
		)
		(duplicate_pad_numbers_are_jumpers no)
		(fp_line
			(start 3.795014 5.2451)
			(end 3.795014 -5.2451)
			(stroke
				(width 0.1524)
				(type default)
			)
			(layer "F.SilkS")
		)
		(fp_line
			(start 3.795014 -5.2451)
			(end 1.9431 -5.2451)
			(stroke
				(width 0.1524)
				(type default)
			)
			(layer "F.SilkS")
		)
		(fp_line
			(start 1.9431 -5.2451)
			(end 0 -3.302)
			(stroke
				(width 0.1524)
				(type default)
			)
			(layer "F.SilkS")
		)
		(fp_line
			(start 0 -3.302)
			(end -1.9431 -5.2451)
			(stroke
				(width 0.1524)
				(type default)
			)
			(layer "F.SilkS")
		)
		(fp_line
			(start -1.9431 -5.2451)
			(end -3.795014 -5.2451)
			(stroke
				(width 0.1524)
				(type default)
			)
			(layer "F.SilkS")
		)
		(fp_line
			(start -3.795014 5.2451)
			(end 3.795014 5.2451)
			(stroke
				(width 0.1524)
				(type default)
			)
			(layer "F.SilkS")
		)
		(fp_line
			(start -3.795014 -5.2451)
			(end -3.795014 5.2451)
			(stroke
				(width 0.1524)
				(type default)
			)
			(layer "F.SilkS")
		)
		(fp_poly
			(pts
				(xy -5.976366 -4.445) (xy -7.239 -3.81381) (xy -7.239 -5.07619)
			)
			(stroke
				(width 0)
				(type default)
			)
			(fill yes)
			(layer "F.SilkS")
		)
		(fp_line
			(start 3.795014 5.2451)
			(end 3.795014 -5.2451)
			(stroke
				(width 0.1)
				(type default)
			)
			(layer "F.Fab")
		)
		(fp_line
			(start 3.795014 -5.2451)
			(end -3.795014 -5.2451)
			(stroke
				(width 0.1)
				(type default)
			)
			(layer "F.Fab")
		)
		(fp_line
			(start -3.795014 5.2451)
			(end 3.795014 5.2451)
			(stroke
				(width 0.1)
				(type default)
			)
			(layer "F.Fab")
		)
		(fp_line
			(start -3.795014 -5.2451)
			(end -3.795014 5.2451)
			(stroke
				(width 0.1)
				(type default)
			)
			(layer "F.Fab")
		)
		(fp_poly
			(pts
				(xy -5.976366 -4.445) (xy -7.239 -3.81381) (xy -7.239 -5.07619)
			)
			(stroke
				(width 0)
				(type default)
			)
			(fill yes)
			(layer "F.Fab")
		)
		(pad "1" smd rect
			(at -4.880102 -4.445 90)
			(size 0.8128 1.905)
			(layers "F.Cu" "F.Mask" "F.Paste")
			(net "SPI_PEX0_SDIO3_R1")
		)
		(pad "2" smd rect
			(at -4.880102 -3.175 90)
			(size 0.8128 1.905)
			(layers "F.Cu" "F.Mask" "F.Paste")
			(net "P1V8_PEX")
		)
		(pad "3" smd rect
			(at -4.880102 -1.905 90)
			(size 0.8128 1.905)
			(layers "F.Cu" "F.Mask" "F.Paste")
			(net "SPI_PEX0_RST_R_N")
		)
		(pad "4" smd rect
			(at -4.880102 -0.635 90)
			(size 0.8128 1.905)
			(layers "F.Cu" "F.Mask" "F.Paste")
			(net "Net_9021")
		)
		(pad "5" smd rect
			(at -4.880102 0.635 90)
			(size 0.8128 1.905)
			(layers "F.Cu" "F.Mask" "F.Paste")
			(net "Net_9020")
		)
		(pad "6" smd rect
			(at -4.880102 1.905 90)
			(size 0.8128 1.905)
			(layers "F.Cu" "F.Mask" "F.Paste")
			(net "Net_9019")
		)
		(pad "7" smd rect
			(at -4.880102 3.175 90)
			(size 0.8128 1.905)
			(layers "F.Cu" "F.Mask" "F.Paste")
			(net "SPI_PEX0_CS_MUX_R_N")
		)
		(pad "8" smd rect
			(at -4.880102 4.445 90)
			(size 0.8128 1.905)
			(layers "F.Cu" "F.Mask" "F.Paste")
			(net "SPI_PEX0_SDIO1_MUX_R")
		)
		(pad "9" smd rect
			(at 4.880102 4.445 270)
			(size 0.8128 1.905)
			(layers "F.Cu" "F.Mask" "F.Paste")
			(net "SPI_PEX0_SDIO2_R1")
		)
		(pad "10" smd rect
			(at 4.880102 3.175 270)
			(size 0.8128 1.905)
			(layers "F.Cu" "F.Mask" "F.Paste")
			(net "GND")
		)
		(pad "11" smd rect
			(at 4.880102 1.905 270)
			(size 0.8128 1.905)
			(layers "F.Cu" "F.Mask" "F.Paste")
			(net "Net_9018")
		)
		(pad "12" smd rect
			(at 4.880102 0.635 270)
			(size 0.8128 1.905)
			(layers "F.Cu" "F.Mask" "F.Paste")
			(net "Net_9017")
		)
		(pad "13" smd rect
			(at 4.880102 -0.635 270)
			(size 0.8128 1.905)
			(layers "F.Cu" "F.Mask" "F.Paste")
			(net "Net_9016")
		)
		(pad "14" smd rect
			(at 4.880102 -1.905 270)
			(size 0.8128 1.905)
			(layers "F.Cu" "F.Mask" "F.Paste")
			(net "Net_9015")
		)
		(pad "15" smd rect
			(at 4.880102 -3.175 270)
			(size 0.8128 1.905)
			(layers "F.Cu" "F.Mask" "F.Paste")
			(net "SPI_PEX0_SDIO0_MUX_R")
		)
		(pad "16" smd rect
			(at 4.880102 -4.445 270)
			(size 0.8128 1.905)
			(layers "F.Cu" "F.Mask" "F.Paste")
			(net "SPI_PEX0_CLK_MUX_R")
		)
	)
	(footprint ""
		(layer "F.Cu")
		(at 83.034124 -7.062724)
		(property "Reference" "R5805"
			(at 0 0 0)
			(layer "F.SilkS")
			(hide yes)
			(effects
				(font
					(size 1.27 1.27)
				)
			)
		)
		(property "Value" ""
			(at 0 0 0)
			(layer "F.Fab")
			(effects
				(font
					(size 1.27 1.27)
				)
			)
		)
		(duplicate_pad_numbers_are_jumpers no)
		(fp_line
			(start -0.7874 -0.4064)
			(end 0.7874 -0.4064)
			(stroke
				(width 0.1524)
				(type default)
			)
			(layer "F.SilkS")
		)
		(fp_line
			(start -0.7874 0.4064)
			(end -0.7874 -0.4064)
			(stroke
				(width 0.1524)
				(type default)
			)
			(layer "F.SilkS")
		)
		(fp_line
			(start 0.7874 -0.4064)
			(end 0.7874 0.4064)
			(stroke
				(width 0.1524)
				(type default)
			)
			(layer "F.SilkS")
		)
		(fp_line
			(start 0.7874 0.4064)
			(end -0.7874 0.4064)
			(stroke
				(width 0.1524)
				(type default)
			)
			(layer "F.SilkS")
		)
		(fp_line
			(start -0.67945 -0.305054)
			(end -0.12065 -0.305054)
			(stroke
				(width 0.1)
				(type default)
			)
			(layer "F.Fab")
		)
		(fp_line
			(start -0.67945 0.3048)
			(end -0.67945 -0.305054)
			(stroke
				(width 0.1)
				(type default)
			)
			(layer "F.Fab")
		)
		(fp_line
			(start -0.12065 -0.305054)
			(end -0.12065 -0.2794)
			(stroke
				(width 0.1)
				(type default)
			)
			(layer "F.Fab")
		)
		(fp_line
			(start -0.12065 -0.2794)
			(end 0.12065 -0.2794)
			(stroke
				(width 0.1)
				(type default)
			)
			(layer "F.Fab")
		)
		(fp_line
			(start -0.12065 0.2794)
			(end -0.12065 0.3048)
			(stroke
				(width 0.1)
				(type default)
			)
			(layer "F.Fab")
		)
		(fp_line
			(start -0.12065 0.3048)
			(end -0.67945 0.3048)
			(stroke
				(width 0.1)
				(type default)
			)
			(layer "F.Fab")
		)
		(fp_line
			(start 0.120396 0.2794)
			(end -0.12065 0.2794)
			(stroke
				(width 0.1)
				(type default)
			)
			(layer "F.Fab")
		)
		(fp_line
			(start 0.120396 0.3048)
			(end 0.120396 0.2794)
			(stroke
				(width 0.1)
				(type default)
			)
			(layer "F.Fab")
		)
		(fp_line
			(start 0.12065 -0.3048)
			(end 0.67945 -0.3048)
			(stroke
				(width 0.1)
				(type default)
			)
			(layer "F.Fab")
		)
		(fp_line
			(start 0.12065 -0.2794)
			(end 0.12065 -0.3048)
			(stroke
				(width 0.1)
				(type default)
			)
			(layer "F.Fab")
		)
		(fp_line
			(start 0.67945 -0.3048)
			(end 0.67945 0.3048)
			(stroke
				(width 0.1)
				(type default)
			)
			(layer "F.Fab")
		)
		(fp_line
			(start 0.67945 0.3048)
			(end 0.120396 0.3048)
			(stroke
				(width 0.1)
				(type default)
			)
			(layer "F.Fab")
		)
		(pad "1" smd circle
			(at -0.40005 0)
			(size 0 0)
			(layers "F.Cu" "F.Mask" "F.Paste")
			(net "LM75_2_A0")
		)
		(pad "2" smd circle
			(at 0.40005 0)
			(size 0 0)
			(layers "F.Cu" "F.Mask" "F.Paste")
			(net "P3V3_AUX")
		)
	)
	(footprint ""
		(layer "F.Cu")
		(at 242.8113 -185.429652 90)
		(property "Reference" "R4250"
			(at 0 0 90)
			(layer "F.SilkS")
			(hide yes)
			(effects
				(font
					(size 1.27 1.27)
				)
			)
		)
		(property "Value" ""
			(at 0 0 90)
			(layer "F.Fab")
			(effects
				(font
					(size 1.27 1.27)
				)
			)
		)
		(duplicate_pad_numbers_are_jumpers no)
		(fp_line
			(start 0.7874 -0.4064)
			(end 0.7874 0.4064)
			(stroke
				(width 0.1524)
				(type default)
			)
			(layer "F.SilkS")
		)
		(fp_line
			(start -0.7874 -0.4064)
			(end 0.7874 -0.4064)
			(stroke
				(width 0.1524)
				(type default)
			)
			(layer "F.SilkS")
		)
		(fp_line
			(start 0.7874 0.4064)
			(end -0.7874 0.4064)
			(stroke
				(width 0.1524)
				(type default)
			)
			(layer "F.SilkS")
		)
		(fp_line
			(start -0.7874 0.4064)
			(end -0.7874 -0.4064)
			(stroke
				(width 0.1524)
				(type default)
			)
			(layer "F.SilkS")
		)
		(fp_line
			(start -0.12065 -0.305054)
			(end -0.12065 -0.2794)
			(stroke
				(width 0.1)
				(type default)
			)
			(layer "F.Fab")
		)
		(fp_line
			(start -0.67945 -0.305054)
			(end -0.12065 -0.305054)
			(stroke
				(width 0.1)
				(type default)
			)
			(layer "F.Fab")
		)
		(fp_line
			(start 0.67945 -0.3048)
			(end 0.67945 0.3048)
			(stroke
				(width 0.1)
				(type default)
			)
			(layer "F.Fab")
		)
		(fp_line
			(start 0.12065 -0.3048)
			(end 0.67945 -0.3048)
			(stroke
				(width 0.1)
				(type default)
			)
			(layer "F.Fab")
		)
		(fp_line
			(start 0.12065 -0.2794)
			(end 0.12065 -0.3048)
			(stroke
				(width 0.1)
				(type default)
			)
			(layer "F.Fab")
		)
		(fp_line
			(start -0.12065 -0.2794)
			(end 0.12065 -0.2794)
			(stroke
				(width 0.1)
				(type default)
			)
			(layer "F.Fab")
		)
		(fp_line
			(start 0.120396 0.2794)
			(end -0.12065 0.2794)
			(stroke
				(width 0.1)
				(type default)
			)
			(layer "F.Fab")
		)
		(fp_line
			(start -0.12065 0.2794)
			(end -0.12065 0.3048)
			(stroke
				(width 0.1)
				(type default)
			)
			(layer "F.Fab")
		)
		(fp_line
			(start 0.67945 0.3048)
			(end 0.120396 0.3048)
			(stroke
				(width 0.1)
				(type default)
			)
			(layer "F.Fab")
		)
		(fp_line
			(start 0.120396 0.3048)
			(end 0.120396 0.2794)
			(stroke
				(width 0.1)
				(type default)
			)
			(layer "F.Fab")
		)
		(fp_line
			(start -0.12065 0.3048)
			(end -0.67945 0.3048)
			(stroke
				(width 0.1)
				(type default)
			)
			(layer "F.Fab")
		)
		(fp_line
			(start -0.67945 0.3048)
			(end -0.67945 -0.305054)
			(stroke
				(width 0.1)
				(type default)
			)
			(layer "F.Fab")
		)
		(pad "1" smd circle
			(at -0.40005 0 90)
			(size 0 0)
			(layers "F.Cu" "F.Mask" "F.Paste")
			(net "BIC_RST_RSMRST_R_N")
		)
		(pad "2" smd circle
			(at 0.40005 0 90)
			(size 0 0)
			(layers "F.Cu" "F.Mask" "F.Paste")
			(net "BIC_RST_RSMRST_N")
		)
	)
	(footprint ""
		(layer "F.Cu")
		(at 33.13557 -308.13375 -135)
		(property "Reference" "R1118"
			(at 0 0 225)
			(layer "F.SilkS")
			(hide yes)
			(effects
				(font
					(size 1.27 1.27)
				)
			)
		)
		(property "Value" ""
			(at 0 0 225)
			(layer "F.Fab")
			(effects
				(font
					(size 1.27 1.27)
				)
			)
		)
		(duplicate_pad_numbers_are_jumpers no)
		(fp_line
			(start 0.787389 0.406267)
			(end -0.787389 0.406267)
			(stroke
				(width 0.1524)
				(type default)
			)
			(layer "F.SilkS")
		)
		(fp_line
			(start 0.787389 -0.406267)
			(end 0.787389 0.406267)
			(stroke
				(width 0.1524)
				(type default)
			)
			(layer "F.SilkS")
		)
		(fp_line
			(start -0.787389 0.406267)
			(end -0.787389 -0.406267)
			(stroke
				(width 0.1524)
				(type default)
			)
			(layer "F.SilkS")
		)
		(fp_line
			(start -0.787389 -0.406267)
			(end 0.787389 -0.406267)
			(stroke
				(width 0.1524)
				(type default)
			)
			(layer "F.SilkS")
		)
		(fp_line
			(start 0.679446 0.30479)
			(end 0.120515 0.30479)
			(stroke
				(width 0.1)
				(type default)
			)
			(layer "F.Fab")
		)
		(fp_line
			(start 0.120515 0.30479)
			(end 0.120335 0.279466)
			(stroke
				(width 0.1)
				(type default)
			)
			(layer "F.Fab")
		)
		(fp_line
			(start 0.120335 0.279466)
			(end -0.120695 0.279466)
			(stroke
				(width 0.1)
				(type default)
			)
			(layer "F.Fab")
		)
		(fp_line
			(start 0.679446 -0.30479)
			(end 0.679446 0.30479)
			(stroke
				(width 0.1)
				(type default)
			)
			(layer "F.Fab")
		)
		(fp_line
			(start -0.120515 0.30479)
			(end -0.679446 0.30479)
			(stroke
				(width 0.1)
				(type default)
			)
			(layer "F.Fab")
		)
		(fp_line
			(start -0.120695 0.279466)
			(end -0.120515 0.30479)
			(stroke
				(width 0.1)
				(type default)
			)
			(layer "F.Fab")
		)
		(fp_line
			(start 0.120695 -0.279466)
			(end 0.120515 -0.30479)
			(stroke
				(width 0.1)
				(type default)
			)
			(layer "F.Fab")
		)
		(fp_line
			(start 0.120515 -0.30479)
			(end 0.679446 -0.30479)
			(stroke
				(width 0.1)
				(type default)
			)
			(layer "F.Fab")
		)
		(fp_line
			(start -0.679446 0.30479)
			(end -0.679446 -0.305149)
			(stroke
				(width 0.1)
				(type default)
			)
			(layer "F.Fab")
		)
		(fp_line
			(start -0.120695 -0.279466)
			(end 0.120695 -0.279466)
			(stroke
				(width 0.1)
				(type default)
			)
			(layer "F.Fab")
		)
		(fp_line
			(start -0.120695 -0.304969)
			(end -0.120695 -0.279466)
			(stroke
				(width 0.1)
				(type default)
			)
			(layer "F.Fab")
		)
		(fp_line
			(start -0.679446 -0.305149)
			(end -0.120695 -0.304969)
			(stroke
				(width 0.1)
				(type default)
			)
			(layer "F.Fab")
		)
		(pad "1" smd circle
			(at -0.40005 0 225)
			(size 0 0)
			(layers "F.Cu" "F.Mask" "F.Paste")
			(net "PEX0_DBG_MODE1")
		)
		(pad "2" smd circle
			(at 0.40005 0 225)
			(size 0 0)
			(layers "F.Cu" "F.Mask" "F.Paste")
			(net "P1V8_PEX")
		)
	)
	(footprint ""
		(layer "F.Cu")
		(at 265.09091 -55.663846 90)
		(property "Reference" "PU64"
			(at -1.083818 2.93878 90)
			(unlocked yes)
			(layer "F.SilkS")
			(effects
				(font
					(size 0.7874 0.5842)
					(thickness 0.1524)
				)
				(justify left)
			)
		)
		(property "Value" ""
			(at 0 0 90)
			(layer "F.Fab")
			(effects
				(font
					(size 1.27 1.27)
				)
			)
		)
		(duplicate_pad_numbers_are_jumpers no)
		(fp_line
			(start 1.943608 -1.549908)
			(end 1.943608 1.549908)
			(stroke
				(width 0.1524)
				(type default)
			)
			(layer "F.SilkS")
		)
		(fp_line
			(start -1.943608 -1.549908)
			(end 1.943608 -1.549908)
			(stroke
				(width 0.1524)
				(type default)
			)
			(layer "F.SilkS")
		)
		(fp_line
			(start 1.943608 1.549908)
			(end -1.943608 1.549908)
			(stroke
				(width 0.1524)
				(type default)
			)
			(layer "F.SilkS")
		)
		(fp_line
			(start -1.943608 1.549908)
			(end -1.943608 -1.549908)
			(stroke
				(width 0.1524)
				(type default)
			)
			(layer "F.SilkS")
		)
		(fp_poly
			(pts
				(xy -2.019808 -1.549908) (xy -1.257808 -1.549908) (xy -1.257808 -1.880108) (xy -2.019808 -1.880108)
			)
			(stroke
				(width 0)
				(type default)
			)
			(fill yes)
			(layer "F.SilkS")
		)
		(fp_line
			(start 1.549908 -1.549908)
			(end 1.549908 1.549908)
			(stroke
				(width 0.1)
				(type default)
			)
			(layer "F.Fab")
		)
		(fp_line
			(start -1.549908 -1.549908)
			(end 1.549908 -1.549908)
			(stroke
				(width 0.1)
				(type default)
			)
			(layer "F.Fab")
		)
		(fp_line
			(start 1.549908 1.549908)
			(end -1.549908 1.549908)
			(stroke
				(width 0.1)
				(type default)
			)
			(layer "F.Fab")
		)
		(fp_line
			(start -1.549908 1.549908)
			(end -1.549908 -1.549908)
			(stroke
				(width 0.1)
				(type default)
			)
			(layer "F.Fab")
		)
		(fp_poly
			(pts
				(xy -2.019808 -1.549908) (xy -1.257808 -1.549908) (xy -1.257808 -1.880108) (xy -2.019808 -1.880108)
			)
			(stroke
				(width 0)
				(type default)
			)
			(fill yes)
			(layer "F.Fab")
		)
		(pad "1" smd rect
			(at -1.500124 -1.249934)
			(size 0.2794 0.6096)
			(layers "F.Cu" "F.Mask" "F.Paste")
			(net "P3V3_SSD9")
		)
		(pad "2" smd rect
			(at -1.500124 -0.750062)
			(size 0.2794 0.6096)
			(layers "F.Cu" "F.Mask" "F.Paste")
			(net "P3V3_SSD9")
		)
		(pad "3" smd rect
			(at -1.500124 -0.249936)
			(size 0.2794 0.6096)
			(layers "F.Cu" "F.Mask" "F.Paste")
			(net "P3V3_SSD9")
		)
		(pad "4" smd rect
			(at -1.500124 0.249936)
			(size 0.2794 0.6096)
			(layers "F.Cu" "F.Mask" "F.Paste")
			(net "P3V3_SSD9")
		)
		(pad "5" smd rect
			(at -1.500124 0.750062)
			(size 0.2794 0.6096)
			(layers "F.Cu" "F.Mask" "F.Paste")
			(net "P3V3_SSD9")
		)
		(pad "6" smd rect
			(at -1.500124 1.249934)
			(size 0.2794 0.6096)
			(layers "F.Cu" "F.Mask" "F.Paste")
			(net "GND")
		)
		(pad "7" smd rect
			(at 1.500124 1.249934)
			(size 0.2794 0.6096)
			(layers "F.Cu" "F.Mask" "F.Paste")
			(net "P3V3_SSD9_SS")
		)
		(pad "8" smd rect
			(at 1.500124 0.750062)
			(size 0.2794 0.6096)
			(layers "F.Cu" "F.Mask" "F.Paste")
			(net "PWRGD_P3V3_SSD9")
		)
		(pad "9" smd rect
			(at 1.500124 0.249936)
			(size 0.2794 0.6096)
			(layers "F.Cu" "F.Mask" "F.Paste")
			(net "P3V3_SSD9_OCP")
		)
		(pad "10" smd rect
			(at 1.500124 -0.249936)
			(size 0.2794 0.6096)
			(layers "F.Cu" "F.Mask" "F.Paste")
			(net "P5V_AUX")
		)
		(pad "11" smd rect
			(at 1.500124 -0.750062)
			(size 0.2794 0.6096)
			(layers "F.Cu" "F.Mask" "F.Paste")
			(net "SSD9_AUX_P3V3_EN_R")
		)
		(pad "12" smd rect
			(at 1.500124 -1.249934)
			(size 0.2794 0.6096)
			(layers "F.Cu" "F.Mask" "F.Paste")
			(net "P3V3_AUX")
		)
		(pad "13" smd rect
			(at 0 0 90)
			(size 1.9812 2.7178)
			(layers "F.Cu" "F.Mask" "F.Paste")
			(net "P3V3_AUX")
		)
		(zone
			(layer "F.Cu")
			(hatch none 0.5)
			(connect_pads
				(clearance 0)
			)
			(min_thickness 0.25)
			(keepout
				(tracks not_allowed)
				(vias allowed)
				(pads allowed)
				(copperpour not_allowed)
				(footprints allowed)
			)
			(placement
				(enabled no)
				(sheetname "")
			)
			(fill
				(thermal_gap 0.5)
				(thermal_bridge_width 0.5)
				(island_removal_mode 0)
			)
			(polygon
				(pts
					(xy 263.54151 -56.806846) (xy 263.66851 -56.806846) (xy 266.64031 -56.806846) (xy 266.640818 -56.806846)
					(xy 266.640818 -54.520846) (xy 266.64031 -54.520846) (xy 266.51331 -54.520846) (xy 265.09091 -54.520846)
					(xy 265.09091 -54.622446) (xy 266.51331 -54.622446) (xy 266.51331 -56.705246) (xy 263.66851 -56.705246)
					(xy 263.66851 -54.622446) (xy 265.06551 -54.622446) (xy 265.06551 -54.520846) (xy 263.66851 -54.520846)
					(xy 263.54151 -54.520846) (xy 263.541002 -54.520846) (xy 263.541002 -56.806846)
				)
			)
		)
	)
	(footprint ""
		(layer "F.Cu")
		(at 227.076 -134.526782 180)
		(property "Reference" "R6302"
			(at 0 0 180)
			(layer "F.SilkS")
			(hide yes)
			(effects
				(font
					(size 1.27 1.27)
				)
			)
		)
		(property "Value" ""
			(at 0 0 180)
			(layer "F.Fab")
			(effects
				(font
					(size 1.27 1.27)
				)
			)
		)
		(duplicate_pad_numbers_are_jumpers no)
		(fp_line
			(start 0.7874 0.4064)
			(end -0.7874 0.4064)
			(stroke
				(width 0.1524)
				(type default)
			)
			(layer "F.SilkS")
		)
		(fp_line
			(start 0.7874 -0.4064)
			(end 0.7874 0.4064)
			(stroke
				(width 0.1524)
				(type default)
			)
			(layer "F.SilkS")
		)
		(fp_line
			(start -0.7874 0.4064)
			(end -0.7874 -0.4064)
			(stroke
				(width 0.1524)
				(type default)
			)
			(layer "F.SilkS")
		)
		(fp_line
			(start -0.7874 -0.4064)
			(end 0.7874 -0.4064)
			(stroke
				(width 0.1524)
				(type default)
			)
			(layer "F.SilkS")
		)
		(fp_line
			(start 0.67945 0.3048)
			(end 0.120396 0.3048)
			(stroke
				(width 0.1)
				(type default)
			)
			(layer "F.Fab")
		)
		(fp_line
			(start 0.67945 -0.3048)
			(end 0.67945 0.3048)
			(stroke
				(width 0.1)
				(type default)
			)
			(layer "F.Fab")
		)
		(fp_line
			(start 0.12065 -0.2794)
			(end 0.12065 -0.3048)
			(stroke
				(width 0.1)
				(type default)
			)
			(layer "F.Fab")
		)
		(fp_line
			(start 0.12065 -0.3048)
			(end 0.67945 -0.3048)
			(stroke
				(width 0.1)
				(type default)
			)
			(layer "F.Fab")
		)
		(fp_line
			(start 0.120396 0.3048)
			(end 0.120396 0.2794)
			(stroke
				(width 0.1)
				(type default)
			)
			(layer "F.Fab")
		)
		(fp_line
			(start 0.120396 0.2794)
			(end -0.12065 0.2794)
			(stroke
				(width 0.1)
				(type default)
			)
			(layer "F.Fab")
		)
		(fp_line
			(start -0.12065 0.3048)
			(end -0.67945 0.3048)
			(stroke
				(width 0.1)
				(type default)
			)
			(layer "F.Fab")
		)
		(fp_line
			(start -0.12065 0.2794)
			(end -0.12065 0.3048)
			(stroke
				(width 0.1)
				(type default)
			)
			(layer "F.Fab")
		)
		(fp_line
			(start -0.12065 -0.2794)
			(end 0.12065 -0.2794)
			(stroke
				(width 0.1)
				(type default)
			)
			(layer "F.Fab")
		)
		(fp_line
			(start -0.12065 -0.305054)
			(end -0.12065 -0.2794)
			(stroke
				(width 0.1)
				(type default)
			)
			(layer "F.Fab")
		)
		(fp_line
			(start -0.67945 0.3048)
			(end -0.67945 -0.305054)
			(stroke
				(width 0.1)
				(type default)
			)
			(layer "F.Fab")
		)
		(fp_line
			(start -0.67945 -0.305054)
			(end -0.12065 -0.305054)
			(stroke
				(width 0.1)
				(type default)
			)
			(layer "F.Fab")
		)
		(pad "1" smd circle
			(at -0.40005 0 180)
			(size 0 0)
			(layers "F.Cu" "F.Mask" "F.Paste")
			(net "SMB_CLK_ISO_R_SCL_R1")
		)
		(pad "2" smd circle
			(at 0.40005 0 180)
			(size 0 0)
			(layers "F.Cu" "F.Mask" "F.Paste")
			(net "SMB_CLK_ISO_R_SCL")
		)
	)
	(footprint ""
		(layer "F.Cu")
		(at 258.44373 -49.95291 180)
		(property "Reference" "R599"
			(at 0 0 180)
			(layer "F.SilkS")
			(hide yes)
			(effects
				(font
					(size 1.27 1.27)
				)
			)
		)
		(property "Value" ""
			(at 0 0 180)
			(layer "F.Fab")
			(effects
				(font
					(size 1.27 1.27)
				)
			)
		)
		(duplicate_pad_numbers_are_jumpers no)
		(fp_line
			(start 0.7874 0.4064)
			(end -0.7874 0.4064)
			(stroke
				(width 0.1524)
				(type default)
			)
			(layer "F.SilkS")
		)
		(fp_line
			(start 0.7874 -0.4064)
			(end 0.7874 0.4064)
			(stroke
				(width 0.1524)
				(type default)
			)
			(layer "F.SilkS")
		)
		(fp_line
			(start -0.7874 0.4064)
			(end -0.7874 -0.4064)
			(stroke
				(width 0.1524)
				(type default)
			)
			(layer "F.SilkS")
		)
		(fp_line
			(start -0.7874 -0.4064)
			(end 0.7874 -0.4064)
			(stroke
				(width 0.1524)
				(type default)
			)
			(layer "F.SilkS")
		)
		(fp_line
			(start 0.67945 0.3048)
			(end 0.120396 0.3048)
			(stroke
				(width 0.1)
				(type default)
			)
			(layer "F.Fab")
		)
		(fp_line
			(start 0.67945 -0.3048)
			(end 0.67945 0.3048)
			(stroke
				(width 0.1)
				(type default)
			)
			(layer "F.Fab")
		)
		(fp_line
			(start 0.12065 -0.2794)
			(end 0.12065 -0.3048)
			(stroke
				(width 0.1)
				(type default)
			)
			(layer "F.Fab")
		)
		(fp_line
			(start 0.12065 -0.3048)
			(end 0.67945 -0.3048)
			(stroke
				(width 0.1)
				(type default)
			)
			(layer "F.Fab")
		)
		(fp_line
			(start 0.120396 0.3048)
			(end 0.120396 0.2794)
			(stroke
				(width 0.1)
				(type default)
			)
			(layer "F.Fab")
		)
		(fp_line
			(start 0.120396 0.2794)
			(end -0.12065 0.2794)
			(stroke
				(width 0.1)
				(type default)
			)
			(layer "F.Fab")
		)
		(fp_line
			(start -0.12065 0.3048)
			(end -0.67945 0.3048)
			(stroke
				(width 0.1)
				(type default)
			)
			(layer "F.Fab")
		)
		(fp_line
			(start -0.12065 0.2794)
			(end -0.12065 0.3048)
			(stroke
				(width 0.1)
				(type default)
			)
			(layer "F.Fab")
		)
		(fp_line
			(start -0.12065 -0.2794)
			(end 0.12065 -0.2794)
			(stroke
				(width 0.1)
				(type default)
			)
			(layer "F.Fab")
		)
		(fp_line
			(start -0.12065 -0.305054)
			(end -0.12065 -0.2794)
			(stroke
				(width 0.1)
				(type default)
			)
			(layer "F.Fab")
		)
		(fp_line
			(start -0.67945 0.3048)
			(end -0.67945 -0.305054)
			(stroke
				(width 0.1)
				(type default)
			)
			(layer "F.Fab")
		)
		(fp_line
			(start -0.67945 -0.305054)
			(end -0.12065 -0.305054)
			(stroke
				(width 0.1)
				(type default)
			)
			(layer "F.Fab")
		)
		(pad "1" smd circle
			(at -0.40005 0 180)
			(size 0 0)
			(layers "F.Cu" "F.Mask" "F.Paste")
			(net "SMB_BIC_I2C6_MUX_SSD_8_15_ADC_R_SCL")
		)
		(pad "2" smd circle
			(at 0.40005 0 180)
			(size 0 0)
			(layers "F.Cu" "F.Mask" "F.Paste")
			(net "SMB_SSD8_ADC_SCL")
		)
	)
	(footprint ""
		(layer "F.Cu")
		(at 129.306066 -134.434326)
		(property "Reference" "PC328"
			(at 0 0 0)
			(layer "F.SilkS")
			(hide yes)
			(effects
				(font
					(size 1.27 1.27)
				)
			)
		)
		(property "Value" ""
			(at 0 0 0)
			(layer "F.Fab")
			(effects
				(font
					(size 1.27 1.27)
				)
			)
		)
		(duplicate_pad_numbers_are_jumpers no)
		(fp_line
			(start -0.7874 -0.4064)
			(end 0.7874 -0.4064)
			(stroke
				(width 0.1524)
				(type default)
			)
			(layer "F.SilkS")
		)
		(fp_line
			(start -0.7874 0.4064)
			(end -0.7874 -0.4064)
			(stroke
				(width 0.1524)
				(type default)
			)
			(layer "F.SilkS")
		)
		(fp_line
			(start 0.7874 -0.4064)
			(end 0.7874 0.4064)
			(stroke
				(width 0.1524)
				(type default)
			)
			(layer "F.SilkS")
		)
		(fp_line
			(start 0.7874 0.4064)
			(end -0.7874 0.4064)
			(stroke
				(width 0.1524)
				(type default)
			)
			(layer "F.SilkS")
		)
		(fp_line
			(start -0.67945 -0.305054)
			(end -0.12065 -0.305054)
			(stroke
				(width 0.1)
				(type default)
			)
			(layer "F.Fab")
		)
		(fp_line
			(start -0.67945 0.3048)
			(end -0.67945 -0.305054)
			(stroke
				(width 0.1)
				(type default)
			)
			(layer "F.Fab")
		)
		(fp_line
			(start -0.12065 -0.305054)
			(end -0.12065 -0.2794)
			(stroke
				(width 0.1)
				(type default)
			)
			(layer "F.Fab")
		)
		(fp_line
			(start -0.12065 -0.2794)
			(end 0.12065 -0.2794)
			(stroke
				(width 0.1)
				(type default)
			)
			(layer "F.Fab")
		)
		(fp_line
			(start -0.12065 0.2794)
			(end -0.12065 0.3048)
			(stroke
				(width 0.1)
				(type default)
			)
			(layer "F.Fab")
		)
		(fp_line
			(start -0.12065 0.3048)
			(end -0.67945 0.3048)
			(stroke
				(width 0.1)
				(type default)
			)
			(layer "F.Fab")
		)
		(fp_line
			(start 0.120396 0.2794)
			(end -0.12065 0.2794)
			(stroke
				(width 0.1)
				(type default)
			)
			(layer "F.Fab")
		)
		(fp_line
			(start 0.120396 0.3048)
			(end 0.120396 0.2794)
			(stroke
				(width 0.1)
				(type default)
			)
			(layer "F.Fab")
		)
		(fp_line
			(start 0.12065 -0.3048)
			(end 0.67945 -0.3048)
			(stroke
				(width 0.1)
				(type default)
			)
			(layer "F.Fab")
		)
		(fp_line
			(start 0.12065 -0.2794)
			(end 0.12065 -0.3048)
			(stroke
				(width 0.1)
				(type default)
			)
			(layer "F.Fab")
		)
		(fp_line
			(start 0.67945 -0.3048)
			(end 0.67945 0.3048)
			(stroke
				(width 0.1)
				(type default)
			)
			(layer "F.Fab")
		)
		(fp_line
			(start 0.67945 0.3048)
			(end 0.120396 0.3048)
			(stroke
				(width 0.1)
				(type default)
			)
			(layer "F.Fab")
		)
		(pad "1" smd circle
			(at -0.40005 0)
			(size 0 0)
			(layers "F.Cu" "F.Mask" "F.Paste")
			(net "P12V_AUX")
		)
		(pad "2" smd circle
			(at 0.40005 0)
			(size 0 0)
			(layers "F.Cu" "F.Mask" "F.Paste")
			(net "GND")
		)
	)
	(footprint ""
		(layer "F.Cu")
		(at 16.252952 -159.173418 90)
		(property "Reference" "PC598"
			(at 0 0 90)
			(layer "F.SilkS")
			(hide yes)
			(effects
				(font
					(size 1.27 1.27)
				)
			)
		)
		(property "Value" ""
			(at 0 0 90)
			(layer "F.Fab")
			(effects
				(font
					(size 1.27 1.27)
				)
			)
		)
		(duplicate_pad_numbers_are_jumpers no)
		(fp_line
			(start 0.7874 -0.4064)
			(end 0.7874 0.4064)
			(stroke
				(width 0.1524)
				(type default)
			)
			(layer "F.SilkS")
		)
		(fp_line
			(start -0.7874 -0.4064)
			(end 0.7874 -0.4064)
			(stroke
				(width 0.1524)
				(type default)
			)
			(layer "F.SilkS")
		)
		(fp_line
			(start 0.7874 0.4064)
			(end -0.7874 0.4064)
			(stroke
				(width 0.1524)
				(type default)
			)
			(layer "F.SilkS")
		)
		(fp_line
			(start -0.7874 0.4064)
			(end -0.7874 -0.4064)
			(stroke
				(width 0.1524)
				(type default)
			)
			(layer "F.SilkS")
		)
		(fp_line
			(start -0.12065 -0.305054)
			(end -0.12065 -0.2794)
			(stroke
				(width 0.1)
				(type default)
			)
			(layer "F.Fab")
		)
		(fp_line
			(start -0.67945 -0.305054)
			(end -0.12065 -0.305054)
			(stroke
				(width 0.1)
				(type default)
			)
			(layer "F.Fab")
		)
		(fp_line
			(start 0.67945 -0.3048)
			(end 0.67945 0.3048)
			(stroke
				(width 0.1)
				(type default)
			)
			(layer "F.Fab")
		)
		(fp_line
			(start 0.12065 -0.3048)
			(end 0.67945 -0.3048)
			(stroke
				(width 0.1)
				(type default)
			)
			(layer "F.Fab")
		)
		(fp_line
			(start 0.12065 -0.2794)
			(end 0.12065 -0.3048)
			(stroke
				(width 0.1)
				(type default)
			)
			(layer "F.Fab")
		)
		(fp_line
			(start -0.12065 -0.2794)
			(end 0.12065 -0.2794)
			(stroke
				(width 0.1)
				(type default)
			)
			(layer "F.Fab")
		)
		(fp_line
			(start 0.120396 0.2794)
			(end -0.12065 0.2794)
			(stroke
				(width 0.1)
				(type default)
			)
			(layer "F.Fab")
		)
		(fp_line
			(start -0.12065 0.2794)
			(end -0.12065 0.3048)
			(stroke
				(width 0.1)
				(type default)
			)
			(layer "F.Fab")
		)
		(fp_line
			(start 0.67945 0.3048)
			(end 0.120396 0.3048)
			(stroke
				(width 0.1)
				(type default)
			)
			(layer "F.Fab")
		)
		(fp_line
			(start 0.120396 0.3048)
			(end 0.120396 0.2794)
			(stroke
				(width 0.1)
				(type default)
			)
			(layer "F.Fab")
		)
		(fp_line
			(start -0.12065 0.3048)
			(end -0.67945 0.3048)
			(stroke
				(width 0.1)
				(type default)
			)
			(layer "F.Fab")
		)
		(fp_line
			(start -0.67945 0.3048)
			(end -0.67945 -0.305054)
			(stroke
				(width 0.1)
				(type default)
			)
			(layer "F.Fab")
		)
		(pad "1" smd circle
			(at -0.40005 0 90)
			(size 0 0)
			(layers "F.Cu" "F.Mask" "F.Paste")
			(net "P12V_AUX")
		)
		(pad "2" smd circle
			(at 0.40005 0 90)
			(size 0 0)
			(layers "F.Cu" "F.Mask" "F.Paste")
			(net "GND")
		)
	)
	(footprint ""
		(layer "F.Cu")
		(at 26.243788 -44.87291)
		(property "Reference" "R507"
			(at 0 0 0)
			(layer "F.SilkS")
			(hide yes)
			(effects
				(font
					(size 1.27 1.27)
				)
			)
		)
		(property "Value" ""
			(at 0 0 0)
			(layer "F.Fab")
			(effects
				(font
					(size 1.27 1.27)
				)
			)
		)
		(duplicate_pad_numbers_are_jumpers no)
		(fp_line
			(start -0.7874 -0.4064)
			(end 0.7874 -0.4064)
			(stroke
				(width 0.1524)
				(type default)
			)
			(layer "F.SilkS")
		)
		(fp_line
			(start -0.7874 0.4064)
			(end -0.7874 -0.4064)
			(stroke
				(width 0.1524)
				(type default)
			)
			(layer "F.SilkS")
		)
		(fp_line
			(start 0.7874 -0.4064)
			(end 0.7874 0.4064)
			(stroke
				(width 0.1524)
				(type default)
			)
			(layer "F.SilkS")
		)
		(fp_line
			(start 0.7874 0.4064)
			(end -0.7874 0.4064)
			(stroke
				(width 0.1524)
				(type default)
			)
			(layer "F.SilkS")
		)
		(fp_line
			(start -0.67945 -0.305054)
			(end -0.12065 -0.305054)
			(stroke
				(width 0.1)
				(type default)
			)
			(layer "F.Fab")
		)
		(fp_line
			(start -0.67945 0.3048)
			(end -0.67945 -0.305054)
			(stroke
				(width 0.1)
				(type default)
			)
			(layer "F.Fab")
		)
		(fp_line
			(start -0.12065 -0.305054)
			(end -0.12065 -0.2794)
			(stroke
				(width 0.1)
				(type default)
			)
			(layer "F.Fab")
		)
		(fp_line
			(start -0.12065 -0.2794)
			(end 0.12065 -0.2794)
			(stroke
				(width 0.1)
				(type default)
			)
			(layer "F.Fab")
		)
		(fp_line
			(start -0.12065 0.2794)
			(end -0.12065 0.3048)
			(stroke
				(width 0.1)
				(type default)
			)
			(layer "F.Fab")
		)
		(fp_line
			(start -0.12065 0.3048)
			(end -0.67945 0.3048)
			(stroke
				(width 0.1)
				(type default)
			)
			(layer "F.Fab")
		)
		(fp_line
			(start 0.120396 0.2794)
			(end -0.12065 0.2794)
			(stroke
				(width 0.1)
				(type default)
			)
			(layer "F.Fab")
		)
		(fp_line
			(start 0.120396 0.3048)
			(end 0.120396 0.2794)
			(stroke
				(width 0.1)
				(type default)
			)
			(layer "F.Fab")
		)
		(fp_line
			(start 0.12065 -0.3048)
			(end 0.67945 -0.3048)
			(stroke
				(width 0.1)
				(type default)
			)
			(layer "F.Fab")
		)
		(fp_line
			(start 0.12065 -0.2794)
			(end 0.12065 -0.3048)
			(stroke
				(width 0.1)
				(type default)
			)
			(layer "F.Fab")
		)
		(fp_line
			(start 0.67945 -0.3048)
			(end 0.67945 0.3048)
			(stroke
				(width 0.1)
				(type default)
			)
			(layer "F.Fab")
		)
		(fp_line
			(start 0.67945 0.3048)
			(end 0.120396 0.3048)
			(stroke
				(width 0.1)
				(type default)
			)
			(layer "F.Fab")
		)
		(pad "1" smd circle
			(at -0.40005 0)
			(size 0 0)
			(layers "F.Cu" "F.Mask" "F.Paste")
			(net "SSD0_ADC_A0")
		)
		(pad "2" smd circle
			(at 0.40005 0)
			(size 0 0)
			(layers "F.Cu" "F.Mask" "F.Paste")
			(net "P3V3_AUX")
		)
	)
	(footprint ""
		(layer "F.Cu")
		(at 375.489978 -412.090108)
		(property "Reference" "J14"
			(at 26.41727 7.51459 90)
			(unlocked yes)
			(layer "F.SilkS")
			(effects
				(font
					(size 2.032 1.524)
					(thickness 0.1524)
				)
				(justify left)
			)
		)
		(property "Value" ""
			(at 0 0 0)
			(layer "F.Fab")
			(effects
				(font
					(size 1.27 1.27)
				)
			)
		)
		(duplicate_pad_numbers_are_jumpers no)
		(fp_line
			(start -4.249928 -16.999966)
			(end 24.45004 -16.999966)
			(stroke
				(width 0.1524)
				(type default)
			)
			(layer "F.SilkS")
		)
		(fp_line
			(start -4.249928 50.099976)
			(end -4.249928 -16.999966)
			(stroke
				(width 0.1524)
				(type default)
			)
			(layer "F.SilkS")
		)
		(fp_line
			(start -1.249934 -13.999972)
			(end -1.249934 47.099982)
			(stroke
				(width 0.1524)
				(type default)
			)
			(layer "F.SilkS")
		)
		(fp_line
			(start -1.249934 -6.500114)
			(end 21.450046 -6.500114)
			(stroke
				(width 0.1524)
				(type default)
			)
			(layer "F.SilkS")
		)
		(fp_line
			(start -1.249934 47.099982)
			(end 21.450046 47.099982)
			(stroke
				(width 0.1524)
				(type default)
			)
			(layer "F.SilkS")
		)
		(fp_line
			(start 21.450046 -13.999972)
			(end -1.249934 -13.999972)
			(stroke
				(width 0.1524)
				(type default)
			)
			(layer "F.SilkS")
		)
		(fp_line
			(start 21.450046 47.099982)
			(end 21.450046 -13.999972)
			(stroke
				(width 0.1524)
				(type default)
			)
			(layer "F.SilkS")
		)
		(fp_line
			(start 24.45004 -16.999966)
			(end 24.45004 50.099976)
			(stroke
				(width 0.1524)
				(type default)
			)
			(layer "F.SilkS")
		)
		(fp_line
			(start 24.45004 50.099976)
			(end -4.249928 50.099976)
			(stroke
				(width 0.1524)
				(type default)
			)
			(layer "F.SilkS")
		)
		(fp_poly
			(pts
				(xy -2.413 -0.508) (xy -2.413 0.508) (xy -1.397 0)
			)
			(stroke
				(width 0)
				(type default)
			)
			(fill yes)
			(layer "F.SilkS")
		)
		(fp_line
			(start -4.249928 -16.999966)
			(end 24.45004 -16.999966)
			(stroke
				(width 0.1524)
				(type default)
			)
			(layer "B.SilkS")
		)
		(fp_line
			(start -4.249928 50.099976)
			(end -4.249928 -16.999966)
			(stroke
				(width 0.1524)
				(type default)
			)
			(layer "B.SilkS")
		)
		(fp_line
			(start 24.45004 -16.999966)
			(end 24.45004 50.099976)
			(stroke
				(width 0.1524)
				(type default)
			)
			(layer "B.SilkS")
		)
		(fp_line
			(start 24.45004 50.099976)
			(end -4.249928 50.099976)
			(stroke
				(width 0.1524)
				(type default)
			)
			(layer "B.SilkS")
		)
		(fp_line
			(start -4.249928 -16.999966)
			(end 24.45004 -16.999966)
			(stroke
				(width 0.1)
				(type default)
			)
			(layer "B.Fab")
		)
		(fp_line
			(start -4.249928 50.099976)
			(end -4.249928 -16.999966)
			(stroke
				(width 0.1)
				(type default)
			)
			(layer "B.Fab")
		)
		(fp_line
			(start 24.45004 -16.999966)
			(end 24.45004 50.099976)
			(stroke
				(width 0.1)
				(type default)
			)
			(layer "B.Fab")
		)
		(fp_line
			(start 24.45004 50.099976)
			(end -4.249928 50.099976)
			(stroke
				(width 0.1)
				(type default)
			)
			(layer "B.Fab")
		)
		(fp_line
			(start -1.249934 -13.999972)
			(end -1.249934 47.099982)
			(stroke
				(width 0.1)
				(type default)
			)
			(layer "F.Fab")
		)
		(fp_line
			(start -1.249934 47.099982)
			(end 21.450046 47.099982)
			(stroke
				(width 0.1)
				(type default)
			)
			(layer "F.Fab")
		)
		(fp_line
			(start 21.450046 -13.999972)
			(end -1.249934 -13.999972)
			(stroke
				(width 0.1)
				(type default)
			)
			(layer "F.Fab")
		)
		(fp_line
			(start 21.450046 47.099982)
			(end 21.450046 -13.999972)
			(stroke
				(width 0.1)
				(type default)
			)
			(layer "F.Fab")
		)
		(fp_poly
			(pts
				(xy -2.413 -0.508) (xy -2.413 0.508) (xy -1.397 0)
			)
			(stroke
				(width 0)
				(type default)
			)
			(fill yes)
			(layer "F.Fab")
		)
		(fp_text user "PRESS-FIT"
			(at 23.167848 40.965374 90)
			(unlocked yes)
			(layer "F.SilkS")
			(effects
				(font
					(size 1.905 1.4224)
					(thickness 0.1524)
				)
				(justify left)
			)
		)
		(fp_text user "PRESS-FIT"
			(at -6.201918 31.739332 90)
			(unlocked yes)
			(layer "B.SilkS")
			(effects
				(font
					(size 1.905 1.4224)
					(thickness 0.1524)
				)
				(justify left mirror)
			)
		)
		(fp_text user "PRESS-FIT"
			(at 18.326862 48.74895 0)
			(unlocked yes)
			(layer "B.Fab")
			(effects
				(font
					(size 1.905 1.4224)
					(thickness 0.1524)
				)
				(justify left mirror)
			)
		)
		(fp_text user "PRESS-FIT"
			(at 1.5875 48.73625 0)
			(unlocked yes)
			(layer "F.Fab")
			(effects
				(font
					(size 1.905 1.4224)
					(thickness 0.1524)
				)
				(justify left)
			)
		)
		(pad "A1" thru_hole rect
			(at 0 0 180)
			(size 0.71628 0.71628)
			(drill 0.30988)
			(layers "*.Cu" "*.Mask")
			(remove_unused_layers no)
			(net "PRSNT_SWB_B1_N")
			(clearance 0.0508)
			(thermal_gap 0.0508)
			(padstack
				(mode front_inner_back)
				(layer "Inner"
					(shape circle)
					(size 0.71628 0.71628)
					(clearance 0.0508)
				)
				(layer "B.Cu"
					(shape rect)
					(size 0.71628 0.71628)
					(clearance 0.0508)
				)
			)
		)
		(pad "A2" thru_hole circle
			(at 2.199894 0.199898 180)
			(size 0.906272 0.906272)
			(drill 0.499872)
			(layers "*.Cu" "*.Mask")
			(remove_unused_layers no)
			(net "GND")
			(clearance 0.0508)
			(thermal_gap 0.0508)
		)
		(pad "A3" thru_hole circle
			(at 4.400042 0 180)
			(size 0.71628 0.71628)
			(drill 0.30988)
			(layers "*.Cu" "*.Mask")
			(remove_unused_layers no)
			(net "MB_SWB_PWRGD_BUF_R")
			(clearance 0.0508)
			(thermal_gap 0.0508)
		)
		(pad "A4" thru_hole circle
			(at 6.599936 0.199898 180)
			(size 0.906272 0.906272)
			(drill 0.499872)
			(layers "*.Cu" "*.Mask")
			(remove_unused_layers no)
			(net "GND")
			(clearance 0.0508)
			(thermal_gap 0.0508)
		)
		(pad "A5" thru_hole circle
			(at 8.800084 0 180)
			(size 0.71628 0.71628)
			(drill 0.30988)
			(layers "*.Cu" "*.Mask")
			(remove_unused_layers no)
			(net "Net_8872")
			(clearance 0.0508)
			(thermal_gap 0.0508)
		)
		(pad "A6" thru_hole circle
			(at 10.999978 0.199898 180)
			(size 0.906272 0.906272)
			(drill 0.499872)
			(layers "*.Cu" "*.Mask")
			(remove_unused_layers no)
			(net "GND")
			(clearance 0.0508)
			(thermal_gap 0.0508)
		)
		(pad "A7" thru_hole circle
			(at 13.199872 0 180)
			(size 0.71628 0.71628)
			(drill 0.30988)
			(layers "*.Cu" "*.Mask")
			(remove_unused_layers no)
			(net "PRSNT_GPU_A1_R_N")
			(clearance 0.0508)
			(thermal_gap 0.0508)
		)
		(pad "A8" thru_hole circle
			(at 15.40002 0.199898 180)
			(size 0.906272 0.906272)
			(drill 0.499872)
			(layers "*.Cu" "*.Mask")
			(remove_unused_layers no)
			(net "GND")
			(clearance 0.0508)
			(thermal_gap 0.0508)
		)
		(pad "A9" thru_hole circle
			(at 17.599914 0 180)
			(size 0.71628 0.71628)
			(drill 0.30988)
			(layers "*.Cu" "*.Mask")
			(remove_unused_layers no)
			(net "MB_3V3IO_RSVD1")
			(clearance 0.0508)
			(thermal_gap 0.0508)
		)
		(pad "A10" thru_hole circle
			(at 19.800062 0.199898 180)
			(size 0.906272 0.906272)
			(drill 0.499872)
			(layers "*.Cu" "*.Mask")
			(remove_unused_layers no)
			(net "GND")
			(clearance 0.0508)
			(thermal_gap 0.0508)
		)
		(pad "B1" thru_hole circle
			(at 0 1.299972 180)
			(size 0.906272 0.906272)
			(drill 0.499872)
			(layers "*.Cu" "*.Mask")
			(remove_unused_layers no)
			(net "GND")
			(clearance 0.0508)
			(thermal_gap 0.0508)
		)
		(pad "B3" thru_hole circle
			(at 4.400042 1.299972 180)
			(size 0.906272 0.906272)
			(drill 0.499872)
			(layers "*.Cu" "*.Mask")
			(remove_unused_layers no)
			(net "GND")
			(clearance 0.0508)
			(thermal_gap 0.0508)
		)
		(pad "B5" thru_hole circle
			(at 8.800084 1.299972 180)
			(size 0.906272 0.906272)
			(drill 0.499872)
			(layers "*.Cu" "*.Mask")
			(remove_unused_layers no)
			(net "GND")
			(clearance 0.0508)
			(thermal_gap 0.0508)
		)
		(pad "B7" thru_hole circle
			(at 13.199872 1.299972 180)
			(size 0.906272 0.906272)
			(drill 0.499872)
			(layers "*.Cu" "*.Mask")
			(remove_unused_layers no)
			(net "GND")
			(clearance 0.0508)
			(thermal_gap 0.0508)
		)
		(pad "B9" thru_hole circle
			(at 17.599914 1.299972 180)
			(size 0.906272 0.906272)
			(drill 0.499872)
			(layers "*.Cu" "*.Mask")
			(remove_unused_layers no)
			(net "GND")
			(clearance 0.0508)
			(thermal_gap 0.0508)
		)
		(pad "B10" thru_hole circle
			(at 19.800062 1.500124 180)
			(size 0.71628 0.71628)
			(drill 0.30988)
			(layers "*.Cu" "*.Mask")
			(remove_unused_layers no)
			(net "Net_8871")
			(clearance 0.0508)
			(thermal_gap 0.0508)
		)
		(pad "C9" thru_hole circle
			(at 17.599914 2.599944 180)
			(size 0.71628 0.71628)
			(drill 0.30988)
			(layers "*.Cu" "*.Mask")
			(remove_unused_layers no)
			(net "UART_MB_BIC_TX_BUF_R")
			(clearance 0.0508)
			(thermal_gap 0.0508)
		)
		(pad "C10" thru_hole circle
			(at 19.800062 2.800096 180)
			(size 0.71628 0.71628)
			(drill 0.30988)
			(layers "*.Cu" "*.Mask")
			(remove_unused_layers no)
			(net "Net_8870")
			(clearance 0.0508)
			(thermal_gap 0.0508)
		)
		(pad "D2" thru_hole circle
			(at 2.199894 4.100068 180)
			(size 0.906272 0.906272)
			(drill 0.499872)
			(layers "*.Cu" "*.Mask")
			(remove_unused_layers no)
			(net "GND")
			(clearance 0.0508)
			(thermal_gap 0.0508)
		)
		(pad "D4" thru_hole circle
			(at 6.599936 4.100068 180)
			(size 0.906272 0.906272)
			(drill 0.499872)
			(layers "*.Cu" "*.Mask")
			(remove_unused_layers no)
			(net "GND")
			(clearance 0.0508)
			(thermal_gap 0.0508)
		)
		(pad "D6" thru_hole circle
			(at 10.999978 4.100068 180)
			(size 0.906272 0.906272)
			(drill 0.499872)
			(layers "*.Cu" "*.Mask")
			(remove_unused_layers no)
			(net "GND")
			(clearance 0.0508)
			(thermal_gap 0.0508)
		)
		(pad "D8" thru_hole circle
			(at 15.40002 4.100068 180)
			(size 0.906272 0.906272)
			(drill 0.499872)
			(layers "*.Cu" "*.Mask")
			(remove_unused_layers no)
			(net "GND")
			(clearance 0.0508)
			(thermal_gap 0.0508)
		)
		(pad "D9" thru_hole circle
			(at 17.599914 3.899916 180)
			(size 0.71628 0.71628)
			(drill 0.30988)
			(layers "*.Cu" "*.Mask")
			(remove_unused_layers no)
			(net "MB_3V3IO_RSVD3")
			(clearance 0.0508)
			(thermal_gap 0.0508)
		)
		(pad "D10" thru_hole circle
			(at 19.800062 4.100068 180)
			(size 0.906272 0.906272)
			(drill 0.499872)
			(layers "*.Cu" "*.Mask")
			(remove_unused_layers no)
			(net "GND")
			(clearance 0.0508)
			(thermal_gap 0.0508)
		)
		(pad "E1" thru_hole circle
			(at 0 5.199888 180)
			(size 0.906272 0.906272)
			(drill 0.499872)
			(layers "*.Cu" "*.Mask")
			(remove_unused_layers no)
			(net "GND")
			(clearance 0.0508)
			(thermal_gap 0.0508)
		)
		(pad "E3" thru_hole circle
			(at 4.400042 5.199888 180)
			(size 0.906272 0.906272)
			(drill 0.499872)
			(layers "*.Cu" "*.Mask")
			(remove_unused_layers no)
			(net "GND")
			(clearance 0.0508)
			(thermal_gap 0.0508)
		)
		(pad "E5" thru_hole circle
			(at 8.800084 5.199888 180)
			(size 0.906272 0.906272)
			(drill 0.499872)
			(layers "*.Cu" "*.Mask")
			(remove_unused_layers no)
			(net "GND")
			(clearance 0.0508)
			(thermal_gap 0.0508)
		)
		(pad "E7" thru_hole circle
			(at 13.199872 5.199888 180)
			(size 0.906272 0.906272)
			(drill 0.499872)
			(layers "*.Cu" "*.Mask")
			(remove_unused_layers no)
			(net "GND")
			(clearance 0.0508)
			(thermal_gap 0.0508)
		)
		(pad "E9" thru_hole circle
			(at 17.599914 5.199888 180)
			(size 0.906272 0.906272)
			(drill 0.499872)
			(layers "*.Cu" "*.Mask")
			(remove_unused_layers no)
			(net "GND")
			(clearance 0.0508)
			(thermal_gap 0.0508)
		)
		(pad "E10" thru_hole circle
			(at 19.800062 5.40004 180)
			(size 0.71628 0.71628)
			(drill 0.30988)
			(layers "*.Cu" "*.Mask")
			(remove_unused_layers no)
			(net "Net_8869")
			(clearance 0.0508)
			(thermal_gap 0.0508)
		)
		(pad "F9" thru_hole circle
			(at 17.599914 6.500114 180)
			(size 0.71628 0.71628)
			(drill 0.30988)
			(layers "*.Cu" "*.Mask")
			(remove_unused_layers no)
			(net "I3C_MB_BMC_SCL")
			(clearance 0.0508)
			(thermal_gap 0.0508)
		)
		(pad "F10" thru_hole circle
			(at 19.800062 6.700012 180)
			(size 0.71628 0.71628)
			(drill 0.30988)
			(layers "*.Cu" "*.Mask")
			(remove_unused_layers no)
			(net "Net_8868")
			(clearance 0.0508)
			(thermal_gap 0.0508)
		)
		(pad "G2" thru_hole circle
			(at 2.199894 7.999984 180)
			(size 0.906272 0.906272)
			(drill 0.499872)
			(layers "*.Cu" "*.Mask")
			(remove_unused_layers no)
			(net "GND")
			(clearance 0.0508)
			(thermal_gap 0.0508)
		)
		(pad "G4" thru_hole circle
			(at 6.599936 7.999984 180)
			(size 0.906272 0.906272)
			(drill 0.499872)
			(layers "*.Cu" "*.Mask")
			(remove_unused_layers no)
			(net "GND")
			(clearance 0.0508)
			(thermal_gap 0.0508)
		)
		(pad "G6" thru_hole circle
			(at 10.999978 7.999984 180)
			(size 0.906272 0.906272)
			(drill 0.499872)
			(layers "*.Cu" "*.Mask")
			(remove_unused_layers no)
			(net "GND")
			(clearance 0.0508)
			(thermal_gap 0.0508)
		)
		(pad "G8" thru_hole circle
			(at 15.40002 7.999984 180)
			(size 0.906272 0.906272)
			(drill 0.499872)
			(layers "*.Cu" "*.Mask")
			(remove_unused_layers no)
			(net "GND")
			(clearance 0.0508)
			(thermal_gap 0.0508)
		)
		(pad "G9" thru_hole circle
			(at 17.599914 7.800086 180)
			(size 0.71628 0.71628)
			(drill 0.30988)
			(layers "*.Cu" "*.Mask")
			(remove_unused_layers no)
			(net "GPU_WP_HW_CTRL_N")
			(clearance 0.0508)
			(thermal_gap 0.0508)
		)
		(pad "G10" thru_hole circle
			(at 19.800062 7.999984 180)
			(size 0.906272 0.906272)
			(drill 0.499872)
			(layers "*.Cu" "*.Mask")
			(remove_unused_layers no)
			(net "GND")
			(clearance 0.0508)
			(thermal_gap 0.0508)
		)
		(pad "H1" thru_hole circle
			(at 0 9.100058 180)
			(size 0.906272 0.906272)
			(drill 0.499872)
			(layers "*.Cu" "*.Mask")
			(remove_unused_layers no)
			(net "GND")
			(clearance 0.0508)
			(thermal_gap 0.0508)
		)
		(pad "H3" thru_hole circle
			(at 4.400042 9.100058 180)
			(size 0.906272 0.906272)
			(drill 0.499872)
			(layers "*.Cu" "*.Mask")
			(remove_unused_layers no)
			(net "GND")
			(clearance 0.0508)
			(thermal_gap 0.0508)
		)
		(pad "H5" thru_hole circle
			(at 8.800084 9.100058 180)
			(size 0.906272 0.906272)
			(drill 0.499872)
			(layers "*.Cu" "*.Mask")
			(remove_unused_layers no)
			(net "GND")
			(clearance 0.0508)
			(thermal_gap 0.0508)
		)
		(pad "H7" thru_hole circle
			(at 13.199872 9.100058 180)
			(size 0.906272 0.906272)
			(drill 0.499872)
			(layers "*.Cu" "*.Mask")
			(remove_unused_layers no)
			(net "GND")
			(clearance 0.0508)
			(thermal_gap 0.0508)
		)
		(pad "H9" thru_hole circle
			(at 17.599914 9.100058 180)
			(size 0.906272 0.906272)
			(drill 0.499872)
			(layers "*.Cu" "*.Mask")
			(remove_unused_layers no)
			(net "GND")
			(clearance 0.0508)
			(thermal_gap 0.0508)
		)
		(pad "H10" thru_hole circle
			(at 19.800062 9.299956 180)
			(size 0.71628 0.71628)
			(drill 0.30988)
			(layers "*.Cu" "*.Mask")
			(remove_unused_layers no)
			(net "I3C_MB_BMC_SDA")
			(clearance 0.0508)
			(thermal_gap 0.0508)
		)
		(pad "I9" thru_hole circle
			(at 17.599914 10.40003 180)
			(size 0.71628 0.71628)
			(drill 0.30988)
			(layers "*.Cu" "*.Mask")
			(remove_unused_layers no)
			(net "Net_8867")
			(clearance 0.0508)
			(thermal_gap 0.0508)
		)
		(pad "I10" thru_hole circle
			(at 19.800062 10.599928 180)
			(size 0.71628 0.71628)
			(drill 0.30988)
			(layers "*.Cu" "*.Mask")
			(remove_unused_layers no)
			(net "MB_3V3IO_RSVD4")
			(clearance 0.0508)
			(thermal_gap 0.0508)
		)
		(pad "J2" thru_hole circle
			(at 2.199894 11.8999 180)
			(size 0.906272 0.906272)
			(drill 0.499872)
			(layers "*.Cu" "*.Mask")
			(remove_unused_layers no)
			(net "GND")
			(clearance 0.0508)
			(thermal_gap 0.0508)
		)
		(pad "J4" thru_hole circle
			(at 6.599936 11.8999 180)
			(size 0.906272 0.906272)
			(drill 0.499872)
			(layers "*.Cu" "*.Mask")
			(remove_unused_layers no)
			(net "GND")
			(clearance 0.0508)
			(thermal_gap 0.0508)
		)
		(pad "J6" thru_hole circle
			(at 10.999978 11.8999 180)
			(size 0.906272 0.906272)
			(drill 0.499872)
			(layers "*.Cu" "*.Mask")
			(remove_unused_layers no)
			(net "GND")
			(clearance 0.0508)
			(thermal_gap 0.0508)
		)
		(pad "J8" thru_hole circle
			(at 15.40002 11.8999 180)
			(size 0.906272 0.906272)
			(drill 0.499872)
			(layers "*.Cu" "*.Mask")
			(remove_unused_layers no)
			(net "GND")
			(clearance 0.0508)
			(thermal_gap 0.0508)
		)
		(pad "J9" thru_hole circle
			(at 17.599914 11.700002 180)
			(size 0.71628 0.71628)
			(drill 0.30988)
			(layers "*.Cu" "*.Mask")
			(remove_unused_layers no)
			(net "Net_8866")
			(clearance 0.0508)
			(thermal_gap 0.0508)
		)
		(pad "J10" thru_hole circle
			(at 19.800062 11.8999 180)
			(size 0.906272 0.906272)
			(drill 0.499872)
			(layers "*.Cu" "*.Mask")
			(remove_unused_layers no)
			(net "GND")
			(clearance 0.0508)
			(thermal_gap 0.0508)
		)
		(pad "K1" thru_hole circle
			(at 0 12.999974 180)
			(size 0.906272 0.906272)
			(drill 0.499872)
			(layers "*.Cu" "*.Mask")
			(remove_unused_layers no)
			(net "GND")
			(clearance 0.0508)
			(thermal_gap 0.0508)
		)
		(pad "K3" thru_hole circle
			(at 4.400042 12.999974 180)
			(size 0.906272 0.906272)
			(drill 0.499872)
			(layers "*.Cu" "*.Mask")
			(remove_unused_layers no)
			(net "GND")
			(clearance 0.0508)
			(thermal_gap 0.0508)
		)
		(pad "K5" thru_hole circle
			(at 8.800084 12.999974 180)
			(size 0.906272 0.906272)
			(drill 0.499872)
			(layers "*.Cu" "*.Mask")
			(remove_unused_layers no)
			(net "GND")
			(clearance 0.0508)
			(thermal_gap 0.0508)
		)
		(pad "K7" thru_hole circle
			(at 13.199872 12.999974 180)
			(size 0.906272 0.906272)
			(drill 0.499872)
			(layers "*.Cu" "*.Mask")
			(remove_unused_layers no)
			(net "GND")
			(clearance 0.0508)
			(thermal_gap 0.0508)
		)
		(pad "K9" thru_hole circle
			(at 17.599914 12.999974 180)
			(size 0.906272 0.906272)
			(drill 0.499872)
			(layers "*.Cu" "*.Mask")
			(remove_unused_layers no)
			(net "GND")
			(clearance 0.0508)
			(thermal_gap 0.0508)
		)
		(pad "K10" thru_hole circle
			(at 19.800062 13.199872 180)
			(size 0.71628 0.71628)
			(drill 0.30988)
			(layers "*.Cu" "*.Mask")
			(remove_unused_layers no)
			(net "Net_8865")
			(clearance 0.0508)
			(thermal_gap 0.0508)
		)
		(pad "L9" thru_hole circle
			(at 17.599914 14.299946 180)
			(size 0.71628 0.71628)
			(drill 0.30988)
			(layers "*.Cu" "*.Mask")
			(remove_unused_layers no)
			(net "Net_8863")
			(clearance 0.0508)
			(thermal_gap 0.0508)
		)
		(pad "L10" thru_hole circle
			(at 19.800062 14.500098 180)
			(size 0.71628 0.71628)
			(drill 0.30988)
			(layers "*.Cu" "*.Mask")
			(remove_unused_layers no)
			(net "Net_8864")
			(clearance 0.0508)
			(thermal_gap 0.0508)
		)
		(pad "M1_2" thru_hole circle
			(at 2.199894 15.80007 180)
			(size 0.906272 0.906272)
			(drill 0.499872)
			(layers "*.Cu" "*.Mask")
			(remove_unused_layers no)
			(net "GND")
			(clearance 0.0508)
			(thermal_gap 0.0508)
		)
		(pad "M1_4" thru_hole circle
			(at 6.599936 15.80007 180)
			(size 0.906272 0.906272)
			(drill 0.499872)
			(layers "*.Cu" "*.Mask")
			(remove_unused_layers no)
			(net "GND")
			(clearance 0.0508)
			(thermal_gap 0.0508)
		)
		(pad "M1_6" thru_hole circle
			(at 10.999978 15.80007 180)
			(size 0.906272 0.906272)
			(drill 0.499872)
			(layers "*.Cu" "*.Mask")
			(remove_unused_layers no)
			(net "GND")
			(clearance 0.0508)
			(thermal_gap 0.0508)
		)
		(pad "M1_8" thru_hole circle
			(at 15.40002 15.80007 180)
			(size 0.906272 0.906272)
			(drill 0.499872)
			(layers "*.Cu" "*.Mask")
			(remove_unused_layers no)
			(net "GND")
			(clearance 0.0508)
			(thermal_gap 0.0508)
		)
		(pad "M1_10" thru_hole circle
			(at 19.800062 15.80007 180)
			(size 0.906272 0.906272)
			(drill 0.499872)
			(layers "*.Cu" "*.Mask")
			(remove_unused_layers no)
			(net "GND")
			(clearance 0.0508)
			(thermal_gap 0.0508)
		)
		(pad "M2_2" thru_hole circle
			(at 2.199894 26.2001 180)
			(size 0.906272 0.906272)
			(drill 0.499872)
			(layers "*.Cu" "*.Mask")
			(remove_unused_layers no)
			(net "GND")
			(clearance 0.0508)
			(thermal_gap 0.0508)
		)
		(pad "M2_4" thru_hole circle
			(at 6.599936 26.2001 180)
			(size 0.906272 0.906272)
			(drill 0.499872)
			(layers "*.Cu" "*.Mask")
			(remove_unused_layers no)
			(net "GND")
			(clearance 0.0508)
			(thermal_gap 0.0508)
		)
		(pad "M2_6" thru_hole circle
			(at 10.999978 26.2001 180)
			(size 0.906272 0.906272)
			(drill 0.499872)
			(layers "*.Cu" "*.Mask")
			(remove_unused_layers no)
			(net "GND")
			(clearance 0.0508)
			(thermal_gap 0.0508)
		)
		(pad "M2_8" thru_hole circle
			(at 15.40002 26.2001 180)
			(size 0.906272 0.906272)
			(drill 0.499872)
			(layers "*.Cu" "*.Mask")
			(remove_unused_layers no)
			(net "GND")
			(clearance 0.0508)
			(thermal_gap 0.0508)
		)
		(pad "M2_10" thru_hole circle
			(at 19.800062 26.2001 180)
			(size 0.906272 0.906272)
			(drill 0.499872)
			(layers "*.Cu" "*.Mask")
			(remove_unused_layers no)
			(net "GND")
			(clearance 0.0508)
			(thermal_gap 0.0508)
		)
		(pad "M9" thru_hole circle
			(at 17.599914 15.599918 180)
			(size 0.71628 0.71628)
			(drill 0.30988)
			(layers "*.Cu" "*.Mask")
			(remove_unused_layers no)
			(net "Net_8862")
			(clearance 0.0508)
			(thermal_gap 0.0508)
		)
		(pad "N1_1" thru_hole circle
			(at 0 16.89989 180)
			(size 0.906272 0.906272)
			(drill 0.499872)
			(layers "*.Cu" "*.Mask")
			(remove_unused_layers no)
			(net "GND")
			(clearance 0.0508)
			(thermal_gap 0.0508)
		)
		(pad "N1_3" thru_hole circle
			(at 4.400042 16.89989 180)
			(size 0.906272 0.906272)
			(drill 0.499872)
			(layers "*.Cu" "*.Mask")
			(remove_unused_layers no)
			(net "GND")
			(clearance 0.0508)
			(thermal_gap 0.0508)
		)
		(pad "N1_5" thru_hole circle
			(at 8.800084 16.89989 180)
			(size 0.906272 0.906272)
			(drill 0.499872)
			(layers "*.Cu" "*.Mask")
			(remove_unused_layers no)
			(net "GND")
			(clearance 0.0508)
			(thermal_gap 0.0508)
		)
		(pad "N1_7" thru_hole circle
			(at 13.199872 16.89989 180)
			(size 0.906272 0.906272)
			(drill 0.499872)
			(layers "*.Cu" "*.Mask")
			(remove_unused_layers no)
			(net "GND")
			(clearance 0.0508)
			(thermal_gap 0.0508)
		)
		(pad "N1_9" thru_hole circle
			(at 17.599914 16.89989 180)
			(size 0.906272 0.906272)
			(drill 0.499872)
			(layers "*.Cu" "*.Mask")
			(remove_unused_layers no)
			(net "GND")
			(clearance 0.0508)
			(thermal_gap 0.0508)
		)
		(pad "N2_1" thru_hole circle
			(at 0 27.29992 180)
			(size 0.906272 0.906272)
			(drill 0.499872)
			(layers "*.Cu" "*.Mask")
			(remove_unused_layers no)
			(net "GND")
			(clearance 0.0508)
			(thermal_gap 0.0508)
		)
		(pad "N2_3" thru_hole circle
			(at 4.400042 27.29992 180)
			(size 0.906272 0.906272)
			(drill 0.499872)
			(layers "*.Cu" "*.Mask")
			(remove_unused_layers no)
			(net "GND")
			(clearance 0.0508)
			(thermal_gap 0.0508)
		)
		(pad "N2_5" thru_hole circle
			(at 8.800084 27.29992 180)
			(size 0.906272 0.906272)
			(drill 0.499872)
			(layers "*.Cu" "*.Mask")
			(remove_unused_layers no)
			(net "GND")
			(clearance 0.0508)
			(thermal_gap 0.0508)
		)
		(pad "N2_7" thru_hole circle
			(at 13.199872 27.29992 180)
			(size 0.906272 0.906272)
			(drill 0.499872)
			(layers "*.Cu" "*.Mask")
			(remove_unused_layers no)
			(net "GND")
			(clearance 0.0508)
			(thermal_gap 0.0508)
		)
		(pad "N2_9" thru_hole circle
			(at 17.599914 27.29992 180)
			(size 0.906272 0.906272)
			(drill 0.499872)
			(layers "*.Cu" "*.Mask")
			(remove_unused_layers no)
			(net "GND")
			(clearance 0.0508)
			(thermal_gap 0.0508)
		)
		(pad "N10" thru_hole circle
			(at 19.800062 27.500072 180)
			(size 0.71628 0.71628)
			(drill 0.30988)
			(layers "*.Cu" "*.Mask")
			(remove_unused_layers no)
			(net "Net_8861")
			(clearance 0.0508)
			(thermal_gap 0.0508)
		)
		(pad "O9" thru_hole circle
			(at 17.599914 28.599892 180)
			(size 0.71628 0.71628)
			(drill 0.30988)
			(layers "*.Cu" "*.Mask")
			(remove_unused_layers no)
			(net "Net_8859")
			(clearance 0.0508)
			(thermal_gap 0.0508)
		)
		(pad "O10" thru_hole circle
			(at 19.800062 28.800044 180)
			(size 0.71628 0.71628)
			(drill 0.30988)
			(layers "*.Cu" "*.Mask")
			(remove_unused_layers no)
			(net "Net_8860")
			(clearance 0.0508)
			(thermal_gap 0.0508)
		)
		(pad "P2" thru_hole circle
			(at 2.199894 30.100016 180)
			(size 0.906272 0.906272)
			(drill 0.499872)
			(layers "*.Cu" "*.Mask")
			(remove_unused_layers no)
			(net "GND")
			(clearance 0.0508)
			(thermal_gap 0.0508)
		)
		(pad "P4" thru_hole circle
			(at 6.599936 30.100016 180)
			(size 0.906272 0.906272)
			(drill 0.499872)
			(layers "*.Cu" "*.Mask")
			(remove_unused_layers no)
			(net "GND")
			(clearance 0.0508)
			(thermal_gap 0.0508)
		)
		(pad "P6" thru_hole circle
			(at 10.999978 30.100016 180)
			(size 0.906272 0.906272)
			(drill 0.499872)
			(layers "*.Cu" "*.Mask")
			(remove_unused_layers no)
			(net "GND")
			(clearance 0.0508)
			(thermal_gap 0.0508)
		)
		(pad "P8" thru_hole circle
			(at 15.40002 30.100016 180)
			(size 0.906272 0.906272)
			(drill 0.499872)
			(layers "*.Cu" "*.Mask")
			(remove_unused_layers no)
			(net "GND")
			(clearance 0.0508)
			(thermal_gap 0.0508)
		)
		(pad "P9" thru_hole circle
			(at 17.599914 29.900118 180)
			(size 0.71628 0.71628)
			(drill 0.30988)
			(layers "*.Cu" "*.Mask")
			(remove_unused_layers no)
			(net "Net_8858")
			(clearance 0.0508)
			(thermal_gap 0.0508)
		)
		(pad "P10" thru_hole circle
			(at 19.800062 30.100016 180)
			(size 0.906272 0.906272)
			(drill 0.499872)
			(layers "*.Cu" "*.Mask")
			(remove_unused_layers no)
			(net "GND")
			(clearance 0.0508)
			(thermal_gap 0.0508)
		)
		(pad "Q1" thru_hole circle
			(at 0 31.20009 180)
			(size 0.906272 0.906272)
			(drill 0.499872)
			(layers "*.Cu" "*.Mask")
			(remove_unused_layers no)
			(net "GND")
			(clearance 0.0508)
			(thermal_gap 0.0508)
		)
		(pad "Q3" thru_hole circle
			(at 4.400042 31.20009 180)
			(size 0.906272 0.906272)
			(drill 0.499872)
			(layers "*.Cu" "*.Mask")
			(remove_unused_layers no)
			(net "GND")
			(clearance 0.0508)
			(thermal_gap 0.0508)
		)
		(pad "Q5" thru_hole circle
			(at 8.800084 31.20009 180)
			(size 0.906272 0.906272)
			(drill 0.499872)
			(layers "*.Cu" "*.Mask")
			(remove_unused_layers no)
			(net "GND")
			(clearance 0.0508)
			(thermal_gap 0.0508)
		)
		(pad "Q7" thru_hole circle
			(at 13.199872 31.20009 180)
			(size 0.906272 0.906272)
			(drill 0.499872)
			(layers "*.Cu" "*.Mask")
			(remove_unused_layers no)
			(net "GND")
			(clearance 0.0508)
			(thermal_gap 0.0508)
		)
		(pad "Q9" thru_hole circle
			(at 17.599914 31.20009 180)
			(size 0.906272 0.906272)
			(drill 0.499872)
			(layers "*.Cu" "*.Mask")
			(remove_unused_layers no)
			(net "GND")
			(clearance 0.0508)
			(thermal_gap 0.0508)
		)
		(pad "Q10" thru_hole circle
			(at 19.800062 31.399988 180)
			(size 0.71628 0.71628)
			(drill 0.30988)
			(layers "*.Cu" "*.Mask")
			(remove_unused_layers no)
			(net "Net_8857")
			(clearance 0.0508)
			(thermal_gap 0.0508)
		)
		(pad "R9" thru_hole circle
			(at 17.599914 32.500062 180)
			(size 0.71628 0.71628)
			(drill 0.30988)
			(layers "*.Cu" "*.Mask")
			(remove_unused_layers no)
			(net "Net_8855")
			(clearance 0.0508)
			(thermal_gap 0.0508)
		)
		(pad "R10" thru_hole circle
			(at 19.800062 32.69996 180)
			(size 0.71628 0.71628)
			(drill 0.30988)
			(layers "*.Cu" "*.Mask")
			(remove_unused_layers no)
			(net "Net_8856")
			(clearance 0.0508)
			(thermal_gap 0.0508)
		)
		(pad "S2" thru_hole circle
			(at 2.199894 33.999932 180)
			(size 0.906272 0.906272)
			(drill 0.499872)
			(layers "*.Cu" "*.Mask")
			(remove_unused_layers no)
			(net "GND")
			(clearance 0.0508)
			(thermal_gap 0.0508)
		)
		(pad "S4" thru_hole circle
			(at 6.599936 33.999932 180)
			(size 0.906272 0.906272)
			(drill 0.499872)
			(layers "*.Cu" "*.Mask")
			(remove_unused_layers no)
			(net "GND")
			(clearance 0.0508)
			(thermal_gap 0.0508)
		)
		(pad "S6" thru_hole circle
			(at 10.999978 33.999932 180)
			(size 0.906272 0.906272)
			(drill 0.499872)
			(layers "*.Cu" "*.Mask")
			(remove_unused_layers no)
			(net "GND")
			(clearance 0.0508)
			(thermal_gap 0.0508)
		)
		(pad "S8" thru_hole circle
			(at 15.40002 33.999932 180)
			(size 0.906272 0.906272)
			(drill 0.499872)
			(layers "*.Cu" "*.Mask")
			(remove_unused_layers no)
			(net "GND")
			(clearance 0.0508)
			(thermal_gap 0.0508)
		)
		(pad "S9" thru_hole circle
			(at 17.599914 33.800034 180)
			(size 0.71628 0.71628)
			(drill 0.30988)
			(layers "*.Cu" "*.Mask")
			(remove_unused_layers no)
			(net "Net_8854")
			(clearance 0.0508)
			(thermal_gap 0.0508)
		)
		(pad "S10" thru_hole circle
			(at 19.800062 33.999932 180)
			(size 0.906272 0.906272)
			(drill 0.499872)
			(layers "*.Cu" "*.Mask")
			(remove_unused_layers no)
			(net "GND")
			(clearance 0.0508)
			(thermal_gap 0.0508)
		)
		(pad "T1" thru_hole circle
			(at 0 35.100006 180)
			(size 0.906272 0.906272)
			(drill 0.499872)
			(layers "*.Cu" "*.Mask")
			(remove_unused_layers no)
			(net "GND")
			(clearance 0.0508)
			(thermal_gap 0.0508)
		)
		(pad "T3" thru_hole circle
			(at 4.400042 35.100006 180)
			(size 0.906272 0.906272)
			(drill 0.499872)
			(layers "*.Cu" "*.Mask")
			(remove_unused_layers no)
			(net "GND")
			(clearance 0.0508)
			(thermal_gap 0.0508)
		)
		(pad "T5" thru_hole circle
			(at 8.800084 35.100006 180)
			(size 0.906272 0.906272)
			(drill 0.499872)
			(layers "*.Cu" "*.Mask")
			(remove_unused_layers no)
			(net "GND")
			(clearance 0.0508)
			(thermal_gap 0.0508)
		)
		(pad "T7" thru_hole circle
			(at 13.199872 35.100006 180)
			(size 0.906272 0.906272)
			(drill 0.499872)
			(layers "*.Cu" "*.Mask")
			(remove_unused_layers no)
			(net "GND")
			(clearance 0.0508)
			(thermal_gap 0.0508)
		)
		(pad "T9" thru_hole circle
			(at 17.599914 35.100006 180)
			(size 0.906272 0.906272)
			(drill 0.499872)
			(layers "*.Cu" "*.Mask")
			(remove_unused_layers no)
			(net "GND")
			(clearance 0.0508)
			(thermal_gap 0.0508)
		)
		(pad "T10" thru_hole circle
			(at 19.800062 35.299904 180)
			(size 0.71628 0.71628)
			(drill 0.30988)
			(layers "*.Cu" "*.Mask")
			(remove_unused_layers no)
			(net "Net_8853")
			(clearance 0.0508)
			(thermal_gap 0.0508)
		)
		(pad "U9" thru_hole circle
			(at 17.599914 36.399978 180)
			(size 0.71628 0.71628)
			(drill 0.30988)
			(layers "*.Cu" "*.Mask")
			(remove_unused_layers no)
			(net "Net_8851")
			(clearance 0.0508)
			(thermal_gap 0.0508)
		)
		(pad "U10" thru_hole circle
			(at 19.800062 36.599876 180)
			(size 0.71628 0.71628)
			(drill 0.30988)
			(layers "*.Cu" "*.Mask")
			(remove_unused_layers no)
			(net "Net_8852")
			(clearance 0.0508)
			(thermal_gap 0.0508)
		)
		(pad "V2" thru_hole circle
			(at 2.199894 37.900102 180)
			(size 0.906272 0.906272)
			(drill 0.499872)
			(layers "*.Cu" "*.Mask")
			(remove_unused_layers no)
			(net "GND")
			(clearance 0.0508)
			(thermal_gap 0.0508)
		)
		(pad "V4" thru_hole circle
			(at 6.599936 37.900102 180)
			(size 0.906272 0.906272)
			(drill 0.499872)
			(layers "*.Cu" "*.Mask")
			(remove_unused_layers no)
			(net "GND")
			(clearance 0.0508)
			(thermal_gap 0.0508)
		)
		(pad "V6" thru_hole circle
			(at 10.999978 37.900102 180)
			(size 0.906272 0.906272)
			(drill 0.499872)
			(layers "*.Cu" "*.Mask")
			(remove_unused_layers no)
			(net "GND")
			(clearance 0.0508)
			(thermal_gap 0.0508)
		)
		(pad "V8" thru_hole circle
			(at 15.40002 37.900102 180)
			(size 0.906272 0.906272)
			(drill 0.499872)
			(layers "*.Cu" "*.Mask")
			(remove_unused_layers no)
			(net "GND")
			(clearance 0.0508)
			(thermal_gap 0.0508)
		)
		(pad "V9" thru_hole circle
			(at 17.599914 37.69995 180)
			(size 0.71628 0.71628)
			(drill 0.30988)
			(layers "*.Cu" "*.Mask")
			(remove_unused_layers no)
			(net "Net_8850")
			(clearance 0.0508)
			(thermal_gap 0.0508)
		)
		(pad "V10" thru_hole circle
			(at 19.800062 37.900102 180)
			(size 0.906272 0.906272)
			(drill 0.499872)
			(layers "*.Cu" "*.Mask")
			(remove_unused_layers no)
			(net "GND")
			(clearance 0.0508)
			(thermal_gap 0.0508)
		)
		(pad "W1" thru_hole circle
			(at 0 38.999922 180)
			(size 0.906272 0.906272)
			(drill 0.499872)
			(layers "*.Cu" "*.Mask")
			(remove_unused_layers no)
			(net "GND")
			(clearance 0.0508)
			(thermal_gap 0.0508)
		)
		(pad "W3" thru_hole circle
			(at 4.400042 38.999922 180)
			(size 0.906272 0.906272)
			(drill 0.499872)
			(layers "*.Cu" "*.Mask")
			(remove_unused_layers no)
			(net "GND")
			(clearance 0.0508)
			(thermal_gap 0.0508)
		)
		(pad "W5" thru_hole circle
			(at 8.800084 38.999922 180)
			(size 0.906272 0.906272)
			(drill 0.499872)
			(layers "*.Cu" "*.Mask")
			(remove_unused_layers no)
			(net "GND")
			(clearance 0.0508)
			(thermal_gap 0.0508)
		)
		(pad "W7" thru_hole circle
			(at 13.199872 38.999922 180)
			(size 0.906272 0.906272)
			(drill 0.499872)
			(layers "*.Cu" "*.Mask")
			(remove_unused_layers no)
			(net "GND")
			(clearance 0.0508)
			(thermal_gap 0.0508)
		)
		(pad "W9" thru_hole circle
			(at 17.599914 38.999922 180)
			(size 0.906272 0.906272)
			(drill 0.499872)
			(layers "*.Cu" "*.Mask")
			(remove_unused_layers no)
			(net "GND")
			(clearance 0.0508)
			(thermal_gap 0.0508)
		)
		(pad "W10" thru_hole circle
			(at 19.800062 39.200074 180)
			(size 0.71628 0.71628)
			(drill 0.30988)
			(layers "*.Cu" "*.Mask")
			(remove_unused_layers no)
			(net "Net_8849")
			(clearance 0.0508)
			(thermal_gap 0.0508)
		)
		(pad "X9" thru_hole circle
			(at 17.599914 40.299894 180)
			(size 0.71628 0.71628)
			(drill 0.30988)
			(layers "*.Cu" "*.Mask")
			(remove_unused_layers no)
			(net "Net_8847")
			(clearance 0.0508)
			(thermal_gap 0.0508)
		)
		(pad "X10" thru_hole circle
			(at 19.800062 40.500046 180)
			(size 0.71628 0.71628)
			(drill 0.30988)
			(layers "*.Cu" "*.Mask")
			(remove_unused_layers no)
			(net "Net_8848")
			(clearance 0.0508)
			(thermal_gap 0.0508)
		)
		(pad "Y2" thru_hole circle
			(at 2.199894 41.800018 180)
			(size 0.906272 0.906272)
			(drill 0.499872)
			(layers "*.Cu" "*.Mask")
			(remove_unused_layers no)
			(net "GND")
			(clearance 0.0508)
			(thermal_gap 0.0508)
		)
		(pad "Y4" thru_hole circle
			(at 6.599936 41.800018 180)
			(size 0.906272 0.906272)
			(drill 0.499872)
			(layers "*.Cu" "*.Mask")
			(remove_unused_layers no)
			(net "GND")
			(clearance 0.0508)
			(thermal_gap 0.0508)
		)
		(pad "Y6" thru_hole circle
			(at 10.999978 41.800018 180)
			(size 0.906272 0.906272)
			(drill 0.499872)
			(layers "*.Cu" "*.Mask")
			(remove_unused_layers no)
			(net "GND")
			(clearance 0.0508)
			(thermal_gap 0.0508)
		)
		(pad "Y8" thru_hole circle
			(at 15.40002 41.800018 180)
			(size 0.906272 0.906272)
			(drill 0.499872)
			(layers "*.Cu" "*.Mask")
			(remove_unused_layers no)
			(net "GND")
			(clearance 0.0508)
			(thermal_gap 0.0508)
		)
		(pad "Y9" thru_hole circle
			(at 17.599914 41.60012 180)
			(size 0.71628 0.71628)
			(drill 0.30988)
			(layers "*.Cu" "*.Mask")
			(remove_unused_layers no)
			(net "Net_8846")
			(clearance 0.0508)
			(thermal_gap 0.0508)
		)
		(pad "Y10" thru_hole circle
			(at 19.800062 41.800018 180)
			(size 0.906272 0.906272)
			(drill 0.499872)
			(layers "*.Cu" "*.Mask")
			(remove_unused_layers no)
			(net "GND")
			(clearance 0.0508)
			(thermal_gap 0.0508)
		)
		(pad "Z1" thru_hole circle
			(at 0 42.900092 180)
			(size 0.906272 0.906272)
			(drill 0.499872)
			(layers "*.Cu" "*.Mask")
			(remove_unused_layers no)
			(net "GND")
			(clearance 0.0508)
			(thermal_gap 0.0508)
		)
		(pad "Z2" thru_hole circle
			(at 2.199894 43.09999 180)
			(size 0.71628 0.71628)
			(drill 0.30988)
			(layers "*.Cu" "*.Mask")
			(remove_unused_layers no)
			(net "MB_SWB_PWR_EN")
			(clearance 0.0508)
			(thermal_gap 0.0508)
		)
		(pad "Z3" thru_hole circle
			(at 4.400042 42.900092 180)
			(size 0.906272 0.906272)
			(drill 0.499872)
			(layers "*.Cu" "*.Mask")
			(remove_unused_layers no)
			(net "GND")
			(clearance 0.0508)
			(thermal_gap 0.0508)
		)
		(pad "Z4" thru_hole circle
			(at 6.599936 43.09999 180)
			(size 0.71628 0.71628)
			(drill 0.30988)
			(layers "*.Cu" "*.Mask")
			(remove_unused_layers no)
			(net "MB_BIC_READY_BUF_R_N")
			(clearance 0.0508)
			(thermal_gap 0.0508)
		)
		(pad "Z5" thru_hole circle
			(at 8.800084 42.900092 180)
			(size 0.906272 0.906272)
			(drill 0.499872)
			(layers "*.Cu" "*.Mask")
			(remove_unused_layers no)
			(net "GND")
			(clearance 0.0508)
			(thermal_gap 0.0508)
		)
		(pad "Z6" thru_hole circle
			(at 10.999978 43.09999 180)
			(size 0.71628 0.71628)
			(drill 0.30988)
			(layers "*.Cu" "*.Mask")
			(remove_unused_layers no)
			(net "RST_MB_BIC_N")
			(clearance 0.0508)
			(thermal_gap 0.0508)
		)
		(pad "Z7" thru_hole circle
			(at 13.199872 42.900092 180)
			(size 0.906272 0.906272)
			(drill 0.499872)
			(layers "*.Cu" "*.Mask")
			(remove_unused_layers no)
			(net "GND")
			(clearance 0.0508)
			(thermal_gap 0.0508)
		)
		(pad "Z8" thru_hole circle
			(at 15.40002 43.09999 180)
			(size 0.71628 0.71628)
			(drill 0.30988)
			(layers "*.Cu" "*.Mask")
			(remove_unused_layers no)
			(net "RST_MB_BMC_BUF_R_N")
			(clearance 0.0508)
			(thermal_gap 0.0508)
		)
		(pad "Z9" thru_hole circle
			(at 17.599914 42.900092 180)
			(size 0.906272 0.906272)
			(drill 0.499872)
			(layers "*.Cu" "*.Mask")
			(remove_unused_layers no)
			(net "GND")
			(clearance 0.0508)
			(thermal_gap 0.0508)
		)
		(pad "Z10" thru_hole circle
			(at 19.800062 43.09999 180)
			(size 0.71628 0.71628)
			(drill 0.30988)
			(layers "*.Cu" "*.Mask")
			(remove_unused_layers no)
			(net "UART_MB_BIC_RX")
			(clearance 0.0508)
			(thermal_gap 0.0508)
		)
		(zone
			(layer "B.Cu")
			(hatch none 0.5)
			(connect_pads
				(clearance 0)
			)
			(min_thickness 0.25)
			(keepout
				(tracks allowed)
				(vias not_allowed)
				(pads allowed)
				(copperpour not_allowed)
				(footprints allowed)
			)
			(placement
				(enabled no)
				(sheetname "")
			)
			(fill
				(thermal_gap 0.5)
				(thermal_bridge_width 0.5)
				(island_removal_mode 0)
			)
			(polygon
				(pts
					(xy 374.972834 -394.665708) (xy 395.800834 -394.665708) (xy 395.800834 -412.50743) (xy 374.972834 -412.50743)
				)
			)
		)
		(zone
			(layer "B.Cu")
			(hatch none 0.5)
			(connect_pads
				(clearance 0)
			)
			(min_thickness 0.25)
			(keepout
				(tracks allowed)
				(vias not_allowed)
				(pads allowed)
				(copperpour not_allowed)
				(footprints allowed)
			)
			(placement
				(enabled no)
				(sheetname "")
			)
			(fill
				(thermal_gap 0.5)
				(thermal_bridge_width 0.5)
				(island_removal_mode 0)
			)
			(polygon
				(pts
					(xy 374.972834 -368.572796) (xy 395.800834 -368.572796) (xy 395.800834 -386.414518) (xy 374.972834 -386.414518)
				)
			)
		)
	)
	(footprint ""
		(layer "F.Cu")
		(at 221.695518 -307.137308 90)
		(property "Reference" "PC237"
			(at 0 0 90)
			(layer "F.SilkS")
			(hide yes)
			(effects
				(font
					(size 1.27 1.27)
				)
			)
		)
		(property "Value" ""
			(at 0 0 90)
			(layer "F.Fab")
			(effects
				(font
					(size 1.27 1.27)
				)
			)
		)
		(duplicate_pad_numbers_are_jumpers no)
		(fp_line
			(start 0.7874 -0.4064)
			(end 0.7874 0.4064)
			(stroke
				(width 0.1524)
				(type default)
			)
			(layer "F.SilkS")
		)
		(fp_line
			(start -0.7874 -0.4064)
			(end 0.7874 -0.4064)
			(stroke
				(width 0.1524)
				(type default)
			)
			(layer "F.SilkS")
		)
		(fp_line
			(start 0.7874 0.4064)
			(end -0.7874 0.4064)
			(stroke
				(width 0.1524)
				(type default)
			)
			(layer "F.SilkS")
		)
		(fp_line
			(start -0.7874 0.4064)
			(end -0.7874 -0.4064)
			(stroke
				(width 0.1524)
				(type default)
			)
			(layer "F.SilkS")
		)
		(fp_line
			(start -0.12065 -0.305054)
			(end -0.12065 -0.2794)
			(stroke
				(width 0.1)
				(type default)
			)
			(layer "F.Fab")
		)
		(fp_line
			(start -0.67945 -0.305054)
			(end -0.12065 -0.305054)
			(stroke
				(width 0.1)
				(type default)
			)
			(layer "F.Fab")
		)
		(fp_line
			(start 0.67945 -0.3048)
			(end 0.67945 0.3048)
			(stroke
				(width 0.1)
				(type default)
			)
			(layer "F.Fab")
		)
		(fp_line
			(start 0.12065 -0.3048)
			(end 0.67945 -0.3048)
			(stroke
				(width 0.1)
				(type default)
			)
			(layer "F.Fab")
		)
		(fp_line
			(start 0.12065 -0.2794)
			(end 0.12065 -0.3048)
			(stroke
				(width 0.1)
				(type default)
			)
			(layer "F.Fab")
		)
		(fp_line
			(start -0.12065 -0.2794)
			(end 0.12065 -0.2794)
			(stroke
				(width 0.1)
				(type default)
			)
			(layer "F.Fab")
		)
		(fp_line
			(start 0.120396 0.2794)
			(end -0.12065 0.2794)
			(stroke
				(width 0.1)
				(type default)
			)
			(layer "F.Fab")
		)
		(fp_line
			(start -0.12065 0.2794)
			(end -0.12065 0.3048)
			(stroke
				(width 0.1)
				(type default)
			)
			(layer "F.Fab")
		)
		(fp_line
			(start 0.67945 0.3048)
			(end 0.120396 0.3048)
			(stroke
				(width 0.1)
				(type default)
			)
			(layer "F.Fab")
		)
		(fp_line
			(start 0.120396 0.3048)
			(end 0.120396 0.2794)
			(stroke
				(width 0.1)
				(type default)
			)
			(layer "F.Fab")
		)
		(fp_line
			(start -0.12065 0.3048)
			(end -0.67945 0.3048)
			(stroke
				(width 0.1)
				(type default)
			)
			(layer "F.Fab")
		)
		(fp_line
			(start -0.67945 0.3048)
			(end -0.67945 -0.305054)
			(stroke
				(width 0.1)
				(type default)
			)
			(layer "F.Fab")
		)
		(pad "1" smd circle
			(at -0.40005 0 90)
			(size 0 0)
			(layers "F.Cu" "F.Mask" "F.Paste")
			(net "P1V25_PEX1_VCC")
		)
		(pad "2" smd circle
			(at 0.40005 0 90)
			(size 0 0)
			(layers "F.Cu" "F.Mask" "F.Paste")
			(net "GND")
		)
	)
	(footprint ""
		(layer "F.Cu")
		(at 76.891642 -356.244906 90)
		(property "Reference" "C111"
			(at 0 0 90)
			(layer "F.SilkS")
			(hide yes)
			(effects
				(font
					(size 1.27 1.27)
				)
			)
		)
		(property "Value" ""
			(at 0 0 90)
			(layer "F.Fab")
			(effects
				(font
					(size 1.27 1.27)
				)
			)
		)
		(duplicate_pad_numbers_are_jumpers no)
		(fp_line
			(start 0.299974 -0.150114)
			(end 0.299974 0.150114)
			(stroke
				(width 0.1)
				(type default)
			)
			(layer "F.Fab")
		)
		(fp_line
			(start -0.299974 -0.150114)
			(end 0.299974 -0.150114)
			(stroke
				(width 0.1)
				(type default)
			)
			(layer "F.Fab")
		)
		(fp_line
			(start 0.299974 0.150114)
			(end -0.299974 0.150114)
			(stroke
				(width 0.1)
				(type default)
			)
			(layer "F.Fab")
		)
		(fp_line
			(start -0.299974 0.150114)
			(end -0.299974 -0.150114)
			(stroke
				(width 0.1)
				(type default)
			)
			(layer "F.Fab")
		)
		(pad "1" smd rect
			(at -0.2667 0 90)
			(size 0.3048 0.381)
			(layers "F.Cu" "F.Mask" "F.Paste")
			(net "P5E_PEX0_STN5_TX_DP<88>")
		)
		(pad "2" smd rect
			(at 0.2667 0 90)
			(size 0.3048 0.381)
			(layers "F.Cu" "F.Mask" "F.Paste")
			(net "P5E_PEX0_STN5_TX_C_DP<88>")
		)
	)
	(footprint ""
		(layer "F.Cu")
		(at 361.44327 -277.644352)
		(property "Reference" "PC175"
			(at 0 0 0)
			(layer "F.SilkS")
			(hide yes)
			(effects
				(font
					(size 1.27 1.27)
				)
			)
		)
		(property "Value" ""
			(at 0 0 0)
			(layer "F.Fab")
			(effects
				(font
					(size 1.27 1.27)
				)
			)
		)
		(duplicate_pad_numbers_are_jumpers no)
		(fp_line
			(start -1.524 -0.762)
			(end 1.524 -0.762)
			(stroke
				(width 0.1524)
				(type default)
			)
			(layer "F.SilkS")
		)
		(fp_line
			(start -1.524 0.762)
			(end -1.524 -0.762)
			(stroke
				(width 0.1524)
				(type default)
			)
			(layer "F.SilkS")
		)
		(fp_line
			(start 1.524 -0.762)
			(end 1.524 0.762)
			(stroke
				(width 0.1524)
				(type default)
			)
			(layer "F.SilkS")
		)
		(fp_line
			(start 1.524 0.762)
			(end -1.524 0.762)
			(stroke
				(width 0.1524)
				(type default)
			)
			(layer "F.SilkS")
		)
		(fp_line
			(start -1.1049 -0.724916)
			(end -1.1049 0.724916)
			(stroke
				(width 0.1)
				(type default)
			)
			(layer "F.Fab")
		)
		(fp_line
			(start -1.1049 0.724916)
			(end 1.1049 0.724916)
			(stroke
				(width 0.1)
				(type default)
			)
			(layer "F.Fab")
		)
		(fp_line
			(start 1.1049 -0.724916)
			(end -1.1049 -0.724916)
			(stroke
				(width 0.1)
				(type default)
			)
			(layer "F.Fab")
		)
		(fp_line
			(start 1.1049 0.724916)
			(end 1.1049 -0.724916)
			(stroke
				(width 0.1)
				(type default)
			)
			(layer "F.Fab")
		)
		(pad "1" smd rect
			(at -0.889 0 180)
			(size 1.016 1.27)
			(layers "F.Cu" "F.Mask" "F.Paste")
			(net "SW_P12V_P0V8_PEX3_FLT")
		)
		(pad "2" smd rect
			(at 0.889 0 180)
			(size 1.016 1.27)
			(layers "F.Cu" "F.Mask" "F.Paste")
			(net "GND")
		)
	)
	(footprint ""
		(layer "F.Cu")
		(at 162.374072 -72.766682 90)
		(property "Reference" "PR7065"
			(at 0 0 90)
			(layer "F.SilkS")
			(hide yes)
			(effects
				(font
					(size 1.27 1.27)
				)
			)
		)
		(property "Value" ""
			(at 0 0 90)
			(layer "F.Fab")
			(effects
				(font
					(size 1.27 1.27)
				)
			)
		)
		(duplicate_pad_numbers_are_jumpers no)
		(fp_line
			(start 0.7874 -0.4064)
			(end 0.7874 0.4064)
			(stroke
				(width 0.1524)
				(type default)
			)
			(layer "F.SilkS")
		)
		(fp_line
			(start -0.7874 -0.4064)
			(end 0.7874 -0.4064)
			(stroke
				(width 0.1524)
				(type default)
			)
			(layer "F.SilkS")
		)
		(fp_line
			(start 0.7874 0.4064)
			(end -0.7874 0.4064)
			(stroke
				(width 0.1524)
				(type default)
			)
			(layer "F.SilkS")
		)
		(fp_line
			(start -0.7874 0.4064)
			(end -0.7874 -0.4064)
			(stroke
				(width 0.1524)
				(type default)
			)
			(layer "F.SilkS")
		)
		(fp_line
			(start -0.12065 -0.305054)
			(end -0.12065 -0.2794)
			(stroke
				(width 0.1)
				(type default)
			)
			(layer "F.Fab")
		)
		(fp_line
			(start -0.67945 -0.305054)
			(end -0.12065 -0.305054)
			(stroke
				(width 0.1)
				(type default)
			)
			(layer "F.Fab")
		)
		(fp_line
			(start 0.67945 -0.3048)
			(end 0.67945 0.3048)
			(stroke
				(width 0.1)
				(type default)
			)
			(layer "F.Fab")
		)
		(fp_line
			(start 0.12065 -0.3048)
			(end 0.67945 -0.3048)
			(stroke
				(width 0.1)
				(type default)
			)
			(layer "F.Fab")
		)
		(fp_line
			(start 0.12065 -0.2794)
			(end 0.12065 -0.3048)
			(stroke
				(width 0.1)
				(type default)
			)
			(layer "F.Fab")
		)
		(fp_line
			(start -0.12065 -0.2794)
			(end 0.12065 -0.2794)
			(stroke
				(width 0.1)
				(type default)
			)
			(layer "F.Fab")
		)
		(fp_line
			(start 0.120396 0.2794)
			(end -0.12065 0.2794)
			(stroke
				(width 0.1)
				(type default)
			)
			(layer "F.Fab")
		)
		(fp_line
			(start -0.12065 0.2794)
			(end -0.12065 0.3048)
			(stroke
				(width 0.1)
				(type default)
			)
			(layer "F.Fab")
		)
		(fp_line
			(start 0.67945 0.3048)
			(end 0.120396 0.3048)
			(stroke
				(width 0.1)
				(type default)
			)
			(layer "F.Fab")
		)
		(fp_line
			(start 0.120396 0.3048)
			(end 0.120396 0.2794)
			(stroke
				(width 0.1)
				(type default)
			)
			(layer "F.Fab")
		)
		(fp_line
			(start -0.12065 0.3048)
			(end -0.67945 0.3048)
			(stroke
				(width 0.1)
				(type default)
			)
			(layer "F.Fab")
		)
		(fp_line
			(start -0.67945 0.3048)
			(end -0.67945 -0.305054)
			(stroke
				(width 0.1)
				(type default)
			)
			(layer "F.Fab")
		)
		(pad "1" smd circle
			(at -0.40005 0 90)
			(size 0 0)
			(layers "F.Cu" "F.Mask" "F.Paste")
			(net "P12V_SSD5_CO_MODE")
		)
		(pad "2" smd circle
			(at 0.40005 0 90)
			(size 0 0)
			(layers "F.Cu" "F.Mask" "F.Paste")
			(net "GND")
		)
	)
	(footprint ""
		(layer "F.Cu")
		(at 2.756408 -391.190988 90)
		(property "Reference" "R6757"
			(at 0 0 90)
			(layer "F.SilkS")
			(hide yes)
			(effects
				(font
					(size 1.27 1.27)
				)
			)
		)
		(property "Value" ""
			(at 0 0 90)
			(layer "F.Fab")
			(effects
				(font
					(size 1.27 1.27)
				)
			)
		)
		(duplicate_pad_numbers_are_jumpers no)
		(fp_line
			(start 0.7874 -0.4064)
			(end 0.7874 0.4064)
			(stroke
				(width 0.1524)
				(type default)
			)
			(layer "F.SilkS")
		)
		(fp_line
			(start -0.7874 -0.4064)
			(end 0.7874 -0.4064)
			(stroke
				(width 0.1524)
				(type default)
			)
			(layer "F.SilkS")
		)
		(fp_line
			(start 0.7874 0.4064)
			(end -0.7874 0.4064)
			(stroke
				(width 0.1524)
				(type default)
			)
			(layer "F.SilkS")
		)
		(fp_line
			(start -0.7874 0.4064)
			(end -0.7874 -0.4064)
			(stroke
				(width 0.1524)
				(type default)
			)
			(layer "F.SilkS")
		)
		(fp_line
			(start -0.12065 -0.305054)
			(end -0.12065 -0.2794)
			(stroke
				(width 0.1)
				(type default)
			)
			(layer "F.Fab")
		)
		(fp_line
			(start -0.67945 -0.305054)
			(end -0.12065 -0.305054)
			(stroke
				(width 0.1)
				(type default)
			)
			(layer "F.Fab")
		)
		(fp_line
			(start 0.67945 -0.3048)
			(end 0.67945 0.3048)
			(stroke
				(width 0.1)
				(type default)
			)
			(layer "F.Fab")
		)
		(fp_line
			(start 0.12065 -0.3048)
			(end 0.67945 -0.3048)
			(stroke
				(width 0.1)
				(type default)
			)
			(layer "F.Fab")
		)
		(fp_line
			(start 0.12065 -0.2794)
			(end 0.12065 -0.3048)
			(stroke
				(width 0.1)
				(type default)
			)
			(layer "F.Fab")
		)
		(fp_line
			(start -0.12065 -0.2794)
			(end 0.12065 -0.2794)
			(stroke
				(width 0.1)
				(type default)
			)
			(layer "F.Fab")
		)
		(fp_line
			(start 0.120396 0.2794)
			(end -0.12065 0.2794)
			(stroke
				(width 0.1)
				(type default)
			)
			(layer "F.Fab")
		)
		(fp_line
			(start -0.12065 0.2794)
			(end -0.12065 0.3048)
			(stroke
				(width 0.1)
				(type default)
			)
			(layer "F.Fab")
		)
		(fp_line
			(start 0.67945 0.3048)
			(end 0.120396 0.3048)
			(stroke
				(width 0.1)
				(type default)
			)
			(layer "F.Fab")
		)
		(fp_line
			(start 0.120396 0.3048)
			(end 0.120396 0.2794)
			(stroke
				(width 0.1)
				(type default)
			)
			(layer "F.Fab")
		)
		(fp_line
			(start -0.12065 0.3048)
			(end -0.67945 0.3048)
			(stroke
				(width 0.1)
				(type default)
			)
			(layer "F.Fab")
		)
		(fp_line
			(start -0.67945 0.3048)
			(end -0.67945 -0.305054)
			(stroke
				(width 0.1)
				(type default)
			)
			(layer "F.Fab")
		)
		(pad "1" smd circle
			(at -0.40005 0 90)
			(size 0 0)
			(layers "F.Cu" "F.Mask" "F.Paste")
			(net "RST_BIC_USB_HUB_R_N")
		)
		(pad "2" smd circle
			(at 0.40005 0 90)
			(size 0 0)
			(layers "F.Cu" "F.Mask" "F.Paste")
			(net "BIC_USB_8042_HUB_GRSTZ")
		)
	)
	(footprint ""
		(layer "F.Cu")
		(at 187.35802 -72.766682 90)
		(property "Reference" "PC852"
			(at 0 0 90)
			(layer "F.SilkS")
			(hide yes)
			(effects
				(font
					(size 1.27 1.27)
				)
			)
		)
		(property "Value" ""
			(at 0 0 90)
			(layer "F.Fab")
			(effects
				(font
					(size 1.27 1.27)
				)
			)
		)
		(duplicate_pad_numbers_are_jumpers no)
		(fp_line
			(start 0.7874 -0.4064)
			(end 0.7874 0.4064)
			(stroke
				(width 0.1524)
				(type default)
			)
			(layer "F.SilkS")
		)
		(fp_line
			(start -0.7874 -0.4064)
			(end 0.7874 -0.4064)
			(stroke
				(width 0.1524)
				(type default)
			)
			(layer "F.SilkS")
		)
		(fp_line
			(start 0.7874 0.4064)
			(end -0.7874 0.4064)
			(stroke
				(width 0.1524)
				(type default)
			)
			(layer "F.SilkS")
		)
		(fp_line
			(start -0.7874 0.4064)
			(end -0.7874 -0.4064)
			(stroke
				(width 0.1524)
				(type default)
			)
			(layer "F.SilkS")
		)
		(fp_line
			(start -0.12065 -0.305054)
			(end -0.12065 -0.2794)
			(stroke
				(width 0.1)
				(type default)
			)
			(layer "F.Fab")
		)
		(fp_line
			(start -0.67945 -0.305054)
			(end -0.12065 -0.305054)
			(stroke
				(width 0.1)
				(type default)
			)
			(layer "F.Fab")
		)
		(fp_line
			(start 0.67945 -0.3048)
			(end 0.67945 0.3048)
			(stroke
				(width 0.1)
				(type default)
			)
			(layer "F.Fab")
		)
		(fp_line
			(start 0.12065 -0.3048)
			(end 0.67945 -0.3048)
			(stroke
				(width 0.1)
				(type default)
			)
			(layer "F.Fab")
		)
		(fp_line
			(start 0.12065 -0.2794)
			(end 0.12065 -0.3048)
			(stroke
				(width 0.1)
				(type default)
			)
			(layer "F.Fab")
		)
		(fp_line
			(start -0.12065 -0.2794)
			(end 0.12065 -0.2794)
			(stroke
				(width 0.1)
				(type default)
			)
			(layer "F.Fab")
		)
		(fp_line
			(start 0.120396 0.2794)
			(end -0.12065 0.2794)
			(stroke
				(width 0.1)
				(type default)
			)
			(layer "F.Fab")
		)
		(fp_line
			(start -0.12065 0.2794)
			(end -0.12065 0.3048)
			(stroke
				(width 0.1)
				(type default)
			)
			(layer "F.Fab")
		)
		(fp_line
			(start 0.67945 0.3048)
			(end 0.120396 0.3048)
			(stroke
				(width 0.1)
				(type default)
			)
			(layer "F.Fab")
		)
		(fp_line
			(start 0.120396 0.3048)
			(end 0.120396 0.2794)
			(stroke
				(width 0.1)
				(type default)
			)
			(layer "F.Fab")
		)
		(fp_line
			(start -0.12065 0.3048)
			(end -0.67945 0.3048)
			(stroke
				(width 0.1)
				(type default)
			)
			(layer "F.Fab")
		)
		(fp_line
			(start -0.67945 0.3048)
			(end -0.67945 -0.305054)
			(stroke
				(width 0.1)
				(type default)
			)
			(layer "F.Fab")
		)
		(pad "1" smd circle
			(at -0.40005 0 90)
			(size 0 0)
			(layers "F.Cu" "F.Mask" "F.Paste")
			(net "P12V_SSD6_CO_MODE")
		)
		(pad "2" smd circle
			(at 0.40005 0 90)
			(size 0 0)
			(layers "F.Cu" "F.Mask" "F.Paste")
			(net "GND")
		)
	)
	(footprint ""
		(layer "F.Cu")
		(at 144.149318 -290.595812 -90)
		(property "Reference" "C3238"
			(at 0 0 270)
			(layer "F.SilkS")
			(hide yes)
			(effects
				(font
					(size 1.27 1.27)
				)
			)
		)
		(property "Value" ""
			(at 0 0 270)
			(layer "F.Fab")
			(effects
				(font
					(size 1.27 1.27)
				)
			)
		)
		(duplicate_pad_numbers_are_jumpers no)
		(fp_line
			(start -0.299974 0.150114)
			(end -0.299974 -0.150114)
			(stroke
				(width 0.1)
				(type default)
			)
			(layer "F.Fab")
		)
		(fp_line
			(start 0.299974 0.150114)
			(end -0.299974 0.150114)
			(stroke
				(width 0.1)
				(type default)
			)
			(layer "F.Fab")
		)
		(fp_line
			(start -0.299974 -0.150114)
			(end 0.299974 -0.150114)
			(stroke
				(width 0.1)
				(type default)
			)
			(layer "F.Fab")
		)
		(fp_line
			(start 0.299974 -0.150114)
			(end 0.299974 0.150114)
			(stroke
				(width 0.1)
				(type default)
			)
			(layer "F.Fab")
		)
		(pad "1" smd rect
			(at -0.2667 0 270)
			(size 0.3048 0.381)
			(layers "F.Cu" "F.Mask" "F.Paste")
			(net "P1V8_PLL0_PEX1")
		)
		(pad "2" smd rect
			(at 0.2667 0 270)
			(size 0.3048 0.381)
			(layers "F.Cu" "F.Mask" "F.Paste")
			(net "GND")
		)
	)
	(footprint ""
		(layer "F.Cu")
		(at 404.826724 -53.697124 -90)
		(property "Reference" "PC570"
			(at 0 0 270)
			(layer "F.SilkS")
			(hide yes)
			(effects
				(font
					(size 1.27 1.27)
				)
			)
		)
		(property "Value" ""
			(at 0 0 270)
			(layer "F.Fab")
			(effects
				(font
					(size 1.27 1.27)
				)
			)
		)
		(duplicate_pad_numbers_are_jumpers no)
		(fp_line
			(start -0.7874 0.4064)
			(end -0.7874 -0.4064)
			(stroke
				(width 0.1524)
				(type default)
			)
			(layer "F.SilkS")
		)
		(fp_line
			(start 0.7874 0.4064)
			(end -0.7874 0.4064)
			(stroke
				(width 0.1524)
				(type default)
			)
			(layer "F.SilkS")
		)
		(fp_line
			(start -0.7874 -0.4064)
			(end 0.7874 -0.4064)
			(stroke
				(width 0.1524)
				(type default)
			)
			(layer "F.SilkS")
		)
		(fp_line
			(start 0.7874 -0.4064)
			(end 0.7874 0.4064)
			(stroke
				(width 0.1524)
				(type default)
			)
			(layer "F.SilkS")
		)
		(fp_line
			(start -0.67945 0.3048)
			(end -0.67945 -0.305054)
			(stroke
				(width 0.1)
				(type default)
			)
			(layer "F.Fab")
		)
		(fp_line
			(start -0.12065 0.3048)
			(end -0.67945 0.3048)
			(stroke
				(width 0.1)
				(type default)
			)
			(layer "F.Fab")
		)
		(fp_line
			(start 0.120396 0.3048)
			(end 0.120396 0.2794)
			(stroke
				(width 0.1)
				(type default)
			)
			(layer "F.Fab")
		)
		(fp_line
			(start 0.67945 0.3048)
			(end 0.120396 0.3048)
			(stroke
				(width 0.1)
				(type default)
			)
			(layer "F.Fab")
		)
		(fp_line
			(start -0.12065 0.2794)
			(end -0.12065 0.3048)
			(stroke
				(width 0.1)
				(type default)
			)
			(layer "F.Fab")
		)
		(fp_line
			(start 0.120396 0.2794)
			(end -0.12065 0.2794)
			(stroke
				(width 0.1)
				(type default)
			)
			(layer "F.Fab")
		)
		(fp_line
			(start -0.12065 -0.2794)
			(end 0.12065 -0.2794)
			(stroke
				(width 0.1)
				(type default)
			)
			(layer "F.Fab")
		)
		(fp_line
			(start 0.12065 -0.2794)
			(end 0.12065 -0.3048)
			(stroke
				(width 0.1)
				(type default)
			)
			(layer "F.Fab")
		)
		(fp_line
			(start 0.12065 -0.3048)
			(end 0.67945 -0.3048)
			(stroke
				(width 0.1)
				(type default)
			)
			(layer "F.Fab")
		)
		(fp_line
			(start 0.67945 -0.3048)
			(end 0.67945 0.3048)
			(stroke
				(width 0.1)
				(type default)
			)
			(layer "F.Fab")
		)
		(fp_line
			(start -0.67945 -0.305054)
			(end -0.12065 -0.305054)
			(stroke
				(width 0.1)
				(type default)
			)
			(layer "F.Fab")
		)
		(fp_line
			(start -0.12065 -0.305054)
			(end -0.12065 -0.2794)
			(stroke
				(width 0.1)
				(type default)
			)
			(layer "F.Fab")
		)
		(pad "1" smd circle
			(at -0.40005 0 270)
			(size 0 0)
			(layers "F.Cu" "F.Mask" "F.Paste")
			(net "P3V3_AUX")
		)
		(pad "2" smd circle
			(at 0.40005 0 270)
			(size 0 0)
			(layers "F.Cu" "F.Mask" "F.Paste")
			(net "GND")
		)
	)
	(footprint ""
		(layer "F.Cu")
		(at 242.777264 -119.105426 90)
		(property "Reference" "R6034"
			(at 0 0 90)
			(layer "F.SilkS")
			(hide yes)
			(effects
				(font
					(size 1.27 1.27)
				)
			)
		)
		(property "Value" ""
			(at 0 0 90)
			(layer "F.Fab")
			(effects
				(font
					(size 1.27 1.27)
				)
			)
		)
		(duplicate_pad_numbers_are_jumpers no)
		(fp_line
			(start 0.7874 -0.4064)
			(end 0.7874 0.4064)
			(stroke
				(width 0.1524)
				(type default)
			)
			(layer "F.SilkS")
		)
		(fp_line
			(start -0.7874 -0.4064)
			(end 0.7874 -0.4064)
			(stroke
				(width 0.1524)
				(type default)
			)
			(layer "F.SilkS")
		)
		(fp_line
			(start 0.7874 0.4064)
			(end -0.7874 0.4064)
			(stroke
				(width 0.1524)
				(type default)
			)
			(layer "F.SilkS")
		)
		(fp_line
			(start -0.7874 0.4064)
			(end -0.7874 -0.4064)
			(stroke
				(width 0.1524)
				(type default)
			)
			(layer "F.SilkS")
		)
		(fp_line
			(start -0.12065 -0.305054)
			(end -0.12065 -0.2794)
			(stroke
				(width 0.1)
				(type default)
			)
			(layer "F.Fab")
		)
		(fp_line
			(start -0.67945 -0.305054)
			(end -0.12065 -0.305054)
			(stroke
				(width 0.1)
				(type default)
			)
			(layer "F.Fab")
		)
		(fp_line
			(start 0.67945 -0.3048)
			(end 0.67945 0.3048)
			(stroke
				(width 0.1)
				(type default)
			)
			(layer "F.Fab")
		)
		(fp_line
			(start 0.12065 -0.3048)
			(end 0.67945 -0.3048)
			(stroke
				(width 0.1)
				(type default)
			)
			(layer "F.Fab")
		)
		(fp_line
			(start 0.12065 -0.2794)
			(end 0.12065 -0.3048)
			(stroke
				(width 0.1)
				(type default)
			)
			(layer "F.Fab")
		)
		(fp_line
			(start -0.12065 -0.2794)
			(end 0.12065 -0.2794)
			(stroke
				(width 0.1)
				(type default)
			)
			(layer "F.Fab")
		)
		(fp_line
			(start 0.120396 0.2794)
			(end -0.12065 0.2794)
			(stroke
				(width 0.1)
				(type default)
			)
			(layer "F.Fab")
		)
		(fp_line
			(start -0.12065 0.2794)
			(end -0.12065 0.3048)
			(stroke
				(width 0.1)
				(type default)
			)
			(layer "F.Fab")
		)
		(fp_line
			(start 0.67945 0.3048)
			(end 0.120396 0.3048)
			(stroke
				(width 0.1)
				(type default)
			)
			(layer "F.Fab")
		)
		(fp_line
			(start 0.120396 0.3048)
			(end 0.120396 0.2794)
			(stroke
				(width 0.1)
				(type default)
			)
			(layer "F.Fab")
		)
		(fp_line
			(start -0.12065 0.3048)
			(end -0.67945 0.3048)
			(stroke
				(width 0.1)
				(type default)
			)
			(layer "F.Fab")
		)
		(fp_line
			(start -0.67945 0.3048)
			(end -0.67945 -0.305054)
			(stroke
				(width 0.1)
				(type default)
			)
			(layer "F.Fab")
		)
		(pad "1" smd circle
			(at -0.40005 0 90)
			(size 0 0)
			(layers "F.Cu" "F.Mask" "F.Paste")
			(net "PWRGD_P3V3_NIC4_D")
		)
		(pad "2" smd circle
			(at 0.40005 0 90)
			(size 0 0)
			(layers "F.Cu" "F.Mask" "F.Paste")
			(net "PWRGD_P3V3_NIC4_R")
		)
	)
	(footprint ""
		(layer "F.Cu")
		(at 229.16515 -258.375912 -90)
		(property "Reference" "R6502"
			(at 0 0 270)
			(layer "F.SilkS")
			(hide yes)
			(effects
				(font
					(size 1.27 1.27)
				)
			)
		)
		(property "Value" ""
			(at 0 0 270)
			(layer "F.Fab")
			(effects
				(font
					(size 1.27 1.27)
				)
			)
		)
		(duplicate_pad_numbers_are_jumpers no)
		(fp_line
			(start -0.7874 0.4064)
			(end -0.7874 -0.4064)
			(stroke
				(width 0.1524)
				(type default)
			)
			(layer "F.SilkS")
		)
		(fp_line
			(start 0.7874 0.4064)
			(end -0.7874 0.4064)
			(stroke
				(width 0.1524)
				(type default)
			)
			(layer "F.SilkS")
		)
		(fp_line
			(start -0.7874 -0.4064)
			(end 0.7874 -0.4064)
			(stroke
				(width 0.1524)
				(type default)
			)
			(layer "F.SilkS")
		)
		(fp_line
			(start 0.7874 -0.4064)
			(end 0.7874 0.4064)
			(stroke
				(width 0.1524)
				(type default)
			)
			(layer "F.SilkS")
		)
		(fp_line
			(start -0.67945 0.3048)
			(end -0.67945 -0.305054)
			(stroke
				(width 0.1)
				(type default)
			)
			(layer "F.Fab")
		)
		(fp_line
			(start -0.12065 0.3048)
			(end -0.67945 0.3048)
			(stroke
				(width 0.1)
				(type default)
			)
			(layer "F.Fab")
		)
		(fp_line
			(start 0.120396 0.3048)
			(end 0.120396 0.2794)
			(stroke
				(width 0.1)
				(type default)
			)
			(layer "F.Fab")
		)
		(fp_line
			(start 0.67945 0.3048)
			(end 0.120396 0.3048)
			(stroke
				(width 0.1)
				(type default)
			)
			(layer "F.Fab")
		)
		(fp_line
			(start -0.12065 0.2794)
			(end -0.12065 0.3048)
			(stroke
				(width 0.1)
				(type default)
			)
			(layer "F.Fab")
		)
		(fp_line
			(start 0.120396 0.2794)
			(end -0.12065 0.2794)
			(stroke
				(width 0.1)
				(type default)
			)
			(layer "F.Fab")
		)
		(fp_line
			(start -0.12065 -0.2794)
			(end 0.12065 -0.2794)
			(stroke
				(width 0.1)
				(type default)
			)
			(layer "F.Fab")
		)
		(fp_line
			(start 0.12065 -0.2794)
			(end 0.12065 -0.3048)
			(stroke
				(width 0.1)
				(type default)
			)
			(layer "F.Fab")
		)
		(fp_line
			(start 0.12065 -0.3048)
			(end 0.67945 -0.3048)
			(stroke
				(width 0.1)
				(type default)
			)
			(layer "F.Fab")
		)
		(fp_line
			(start 0.67945 -0.3048)
			(end 0.67945 0.3048)
			(stroke
				(width 0.1)
				(type default)
			)
			(layer "F.Fab")
		)
		(fp_line
			(start -0.67945 -0.305054)
			(end -0.12065 -0.305054)
			(stroke
				(width 0.1)
				(type default)
			)
			(layer "F.Fab")
		)
		(fp_line
			(start -0.12065 -0.305054)
			(end -0.12065 -0.2794)
			(stroke
				(width 0.1)
				(type default)
			)
			(layer "F.Fab")
		)
		(pad "1" smd circle
			(at -0.40005 0 270)
			(size 0 0)
			(layers "F.Cu" "F.Mask" "F.Paste")
			(net "P1V25_SERDES_VDDPLL_PEX1")
		)
		(pad "2" smd circle
			(at 0.40005 0 270)
			(size 0 0)
			(layers "F.Cu" "F.Mask" "F.Paste")
			(net "P1V25_SERDES_VDDPLL_PEX1_C9")
		)
	)
	(footprint ""
		(layer "F.Cu")
		(at 408.47899 -59.577986 -90)
		(property "Reference" "R899"
			(at 0 0 270)
			(layer "F.SilkS")
			(hide yes)
			(effects
				(font
					(size 1.27 1.27)
				)
			)
		)
		(property "Value" ""
			(at 0 0 270)
			(layer "F.Fab")
			(effects
				(font
					(size 1.27 1.27)
				)
			)
		)
		(duplicate_pad_numbers_are_jumpers no)
		(fp_line
			(start -0.7874 0.4064)
			(end -0.7874 -0.4064)
			(stroke
				(width 0.1524)
				(type default)
			)
			(layer "F.SilkS")
		)
		(fp_line
			(start 0.7874 0.4064)
			(end -0.7874 0.4064)
			(stroke
				(width 0.1524)
				(type default)
			)
			(layer "F.SilkS")
		)
		(fp_line
			(start -0.7874 -0.4064)
			(end 0.7874 -0.4064)
			(stroke
				(width 0.1524)
				(type default)
			)
			(layer "F.SilkS")
		)
		(fp_line
			(start 0.7874 -0.4064)
			(end 0.7874 0.4064)
			(stroke
				(width 0.1524)
				(type default)
			)
			(layer "F.SilkS")
		)
		(fp_line
			(start -0.67945 0.3048)
			(end -0.67945 -0.305054)
			(stroke
				(width 0.1)
				(type default)
			)
			(layer "F.Fab")
		)
		(fp_line
			(start -0.12065 0.3048)
			(end -0.67945 0.3048)
			(stroke
				(width 0.1)
				(type default)
			)
			(layer "F.Fab")
		)
		(fp_line
			(start 0.120396 0.3048)
			(end 0.120396 0.2794)
			(stroke
				(width 0.1)
				(type default)
			)
			(layer "F.Fab")
		)
		(fp_line
			(start 0.67945 0.3048)
			(end 0.120396 0.3048)
			(stroke
				(width 0.1)
				(type default)
			)
			(layer "F.Fab")
		)
		(fp_line
			(start -0.12065 0.2794)
			(end -0.12065 0.3048)
			(stroke
				(width 0.1)
				(type default)
			)
			(layer "F.Fab")
		)
		(fp_line
			(start 0.120396 0.2794)
			(end -0.12065 0.2794)
			(stroke
				(width 0.1)
				(type default)
			)
			(layer "F.Fab")
		)
		(fp_line
			(start -0.12065 -0.2794)
			(end 0.12065 -0.2794)
			(stroke
				(width 0.1)
				(type default)
			)
			(layer "F.Fab")
		)
		(fp_line
			(start 0.12065 -0.2794)
			(end 0.12065 -0.3048)
			(stroke
				(width 0.1)
				(type default)
			)
			(layer "F.Fab")
		)
		(fp_line
			(start 0.12065 -0.3048)
			(end 0.67945 -0.3048)
			(stroke
				(width 0.1)
				(type default)
			)
			(layer "F.Fab")
		)
		(fp_line
			(start 0.67945 -0.3048)
			(end 0.67945 0.3048)
			(stroke
				(width 0.1)
				(type default)
			)
			(layer "F.Fab")
		)
		(fp_line
			(start -0.67945 -0.305054)
			(end -0.12065 -0.305054)
			(stroke
				(width 0.1)
				(type default)
			)
			(layer "F.Fab")
		)
		(fp_line
			(start -0.12065 -0.305054)
			(end -0.12065 -0.2794)
			(stroke
				(width 0.1)
				(type default)
			)
			(layer "F.Fab")
		)
		(pad "1" smd circle
			(at -0.40005 0 270)
			(size 0 0)
			(layers "F.Cu" "F.Mask" "F.Paste")
			(net "P3V3_SSD14")
		)
		(pad "2" smd circle
			(at 0.40005 0 270)
			(size 0 0)
			(layers "F.Cu" "F.Mask" "F.Paste")
			(net "PWRGD_P3V3_SSD14")
		)
	)
	(footprint ""
		(layer "F.Cu")
		(at 225.915474 -136.669272 -90)
		(property "Reference" "R4217"
			(at 0 0 270)
			(layer "F.SilkS")
			(hide yes)
			(effects
				(font
					(size 1.27 1.27)
				)
			)
		)
		(property "Value" ""
			(at 0 0 270)
			(layer "F.Fab")
			(effects
				(font
					(size 1.27 1.27)
				)
			)
		)
		(duplicate_pad_numbers_are_jumpers no)
		(fp_line
			(start -0.7874 0.4064)
			(end -0.7874 -0.4064)
			(stroke
				(width 0.1524)
				(type default)
			)
			(layer "F.SilkS")
		)
		(fp_line
			(start 0.7874 0.4064)
			(end -0.7874 0.4064)
			(stroke
				(width 0.1524)
				(type default)
			)
			(layer "F.SilkS")
		)
		(fp_line
			(start -0.7874 -0.4064)
			(end 0.7874 -0.4064)
			(stroke
				(width 0.1524)
				(type default)
			)
			(layer "F.SilkS")
		)
		(fp_line
			(start 0.7874 -0.4064)
			(end 0.7874 0.4064)
			(stroke
				(width 0.1524)
				(type default)
			)
			(layer "F.SilkS")
		)
		(fp_line
			(start -0.67945 0.3048)
			(end -0.67945 -0.305054)
			(stroke
				(width 0.1)
				(type default)
			)
			(layer "F.Fab")
		)
		(fp_line
			(start -0.12065 0.3048)
			(end -0.67945 0.3048)
			(stroke
				(width 0.1)
				(type default)
			)
			(layer "F.Fab")
		)
		(fp_line
			(start 0.120396 0.3048)
			(end 0.120396 0.2794)
			(stroke
				(width 0.1)
				(type default)
			)
			(layer "F.Fab")
		)
		(fp_line
			(start 0.67945 0.3048)
			(end 0.120396 0.3048)
			(stroke
				(width 0.1)
				(type default)
			)
			(layer "F.Fab")
		)
		(fp_line
			(start -0.12065 0.2794)
			(end -0.12065 0.3048)
			(stroke
				(width 0.1)
				(type default)
			)
			(layer "F.Fab")
		)
		(fp_line
			(start 0.120396 0.2794)
			(end -0.12065 0.2794)
			(stroke
				(width 0.1)
				(type default)
			)
			(layer "F.Fab")
		)
		(fp_line
			(start -0.12065 -0.2794)
			(end 0.12065 -0.2794)
			(stroke
				(width 0.1)
				(type default)
			)
			(layer "F.Fab")
		)
		(fp_line
			(start 0.12065 -0.2794)
			(end 0.12065 -0.3048)
			(stroke
				(width 0.1)
				(type default)
			)
			(layer "F.Fab")
		)
		(fp_line
			(start 0.12065 -0.3048)
			(end 0.67945 -0.3048)
			(stroke
				(width 0.1)
				(type default)
			)
			(layer "F.Fab")
		)
		(fp_line
			(start 0.67945 -0.3048)
			(end 0.67945 0.3048)
			(stroke
				(width 0.1)
				(type default)
			)
			(layer "F.Fab")
		)
		(fp_line
			(start -0.67945 -0.305054)
			(end -0.12065 -0.305054)
			(stroke
				(width 0.1)
				(type default)
			)
			(layer "F.Fab")
		)
		(fp_line
			(start -0.12065 -0.305054)
			(end -0.12065 -0.2794)
			(stroke
				(width 0.1)
				(type default)
			)
			(layer "F.Fab")
		)
		(pad "1" smd circle
			(at -0.40005 0 270)
			(size 0 0)
			(layers "F.Cu" "F.Mask" "F.Paste")
			(net "SMB_CK440_PEX_CLK_SCL")
		)
		(pad "2" smd circle
			(at 0.40005 0 270)
			(size 0 0)
			(layers "F.Cu" "F.Mask" "F.Paste")
			(net "SMB_CLK_ISO_R_SCL")
		)
	)
	(footprint ""
		(layer "F.Cu")
		(at 72.174862 -48.753014 180)
		(property "Reference" "C3668"
			(at 0 0 180)
			(layer "F.SilkS")
			(hide yes)
			(effects
				(font
					(size 1.27 1.27)
				)
			)
		)
		(property "Value" ""
			(at 0 0 180)
			(layer "F.Fab")
			(effects
				(font
					(size 1.27 1.27)
				)
			)
		)
		(duplicate_pad_numbers_are_jumpers no)
		(fp_line
			(start 0.7874 0.4064)
			(end -0.7874 0.4064)
			(stroke
				(width 0.1524)
				(type default)
			)
			(layer "F.SilkS")
		)
		(fp_line
			(start 0.7874 -0.4064)
			(end 0.7874 0.4064)
			(stroke
				(width 0.1524)
				(type default)
			)
			(layer "F.SilkS")
		)
		(fp_line
			(start -0.7874 0.4064)
			(end -0.7874 -0.4064)
			(stroke
				(width 0.1524)
				(type default)
			)
			(layer "F.SilkS")
		)
		(fp_line
			(start -0.7874 -0.4064)
			(end 0.7874 -0.4064)
			(stroke
				(width 0.1524)
				(type default)
			)
			(layer "F.SilkS")
		)
		(fp_line
			(start 0.67945 0.3048)
			(end 0.120396 0.3048)
			(stroke
				(width 0.1)
				(type default)
			)
			(layer "F.Fab")
		)
		(fp_line
			(start 0.67945 -0.3048)
			(end 0.67945 0.3048)
			(stroke
				(width 0.1)
				(type default)
			)
			(layer "F.Fab")
		)
		(fp_line
			(start 0.12065 -0.2794)
			(end 0.12065 -0.3048)
			(stroke
				(width 0.1)
				(type default)
			)
			(layer "F.Fab")
		)
		(fp_line
			(start 0.12065 -0.3048)
			(end 0.67945 -0.3048)
			(stroke
				(width 0.1)
				(type default)
			)
			(layer "F.Fab")
		)
		(fp_line
			(start 0.120396 0.3048)
			(end 0.120396 0.2794)
			(stroke
				(width 0.1)
				(type default)
			)
			(layer "F.Fab")
		)
		(fp_line
			(start 0.120396 0.2794)
			(end -0.12065 0.2794)
			(stroke
				(width 0.1)
				(type default)
			)
			(layer "F.Fab")
		)
		(fp_line
			(start -0.12065 0.3048)
			(end -0.67945 0.3048)
			(stroke
				(width 0.1)
				(type default)
			)
			(layer "F.Fab")
		)
		(fp_line
			(start -0.12065 0.2794)
			(end -0.12065 0.3048)
			(stroke
				(width 0.1)
				(type default)
			)
			(layer "F.Fab")
		)
		(fp_line
			(start -0.12065 -0.2794)
			(end 0.12065 -0.2794)
			(stroke
				(width 0.1)
				(type default)
			)
			(layer "F.Fab")
		)
		(fp_line
			(start -0.12065 -0.305054)
			(end -0.12065 -0.2794)
			(stroke
				(width 0.1)
				(type default)
			)
			(layer "F.Fab")
		)
		(fp_line
			(start -0.67945 0.3048)
			(end -0.67945 -0.305054)
			(stroke
				(width 0.1)
				(type default)
			)
			(layer "F.Fab")
		)
		(fp_line
			(start -0.67945 -0.305054)
			(end -0.12065 -0.305054)
			(stroke
				(width 0.1)
				(type default)
			)
			(layer "F.Fab")
		)
		(pad "1" smd circle
			(at -0.40005 0 180)
			(size 0 0)
			(layers "F.Cu" "F.Mask" "F.Paste")
			(net "P3V3_AUX")
		)
		(pad "2" smd circle
			(at 0.40005 0 180)
			(size 0 0)
			(layers "F.Cu" "F.Mask" "F.Paste")
			(net "GND")
		)
	)
	(footprint ""
		(layer "F.Cu")
		(at 18.679922 -135.62711 90)
		(property "Reference" "PD6"
			(at -1.87071 2.403348 90)
			(unlocked yes)
			(layer "F.SilkS")
			(effects
				(font
					(size 0.7874 0.5842)
					(thickness 0.1524)
				)
				(justify left)
			)
		)
		(property "Value" ""
			(at 0 0 90)
			(layer "F.Fab")
			(effects
				(font
					(size 1.27 1.27)
				)
			)
		)
		(duplicate_pad_numbers_are_jumpers no)
		(fp_line
			(start 4.107942 -1.459992)
			(end 4.107942 1.459992)
			(stroke
				(width 0.1524)
				(type default)
			)
			(layer "F.SilkS")
		)
		(fp_line
			(start -3.400044 -1.459992)
			(end 4.107942 -1.459992)
			(stroke
				(width 0.1524)
				(type default)
			)
			(layer "F.SilkS")
		)
		(fp_line
			(start 4.107942 1.459992)
			(end -3.400044 1.459992)
			(stroke
				(width 0.1524)
				(type default)
			)
			(layer "F.SilkS")
		)
		(fp_line
			(start -3.400044 1.459992)
			(end -3.400044 -1.459992)
			(stroke
				(width 0.1524)
				(type default)
			)
			(layer "F.SilkS")
		)
		(fp_poly
			(pts
				(xy 4.107942 -1.459992) (xy 4.107942 1.459992) (xy 3.308096 1.459992) (xy 3.308096 -1.459992)
			)
			(stroke
				(width 0)
				(type default)
			)
			(fill yes)
			(layer "F.SilkS")
		)
		(fp_line
			(start 2.29997 -1.459992)
			(end 2.29997 1.459992)
			(stroke
				(width 0.1)
				(type default)
			)
			(layer "F.Fab")
		)
		(fp_line
			(start -2.29997 -1.459992)
			(end 2.29997 -1.459992)
			(stroke
				(width 0.1)
				(type default)
			)
			(layer "F.Fab")
		)
		(fp_line
			(start 2.29997 1.459992)
			(end -2.29997 1.459992)
			(stroke
				(width 0.1)
				(type default)
			)
			(layer "F.Fab")
		)
		(fp_line
			(start -2.29997 1.459992)
			(end -2.29997 -1.459992)
			(stroke
				(width 0.1)
				(type default)
			)
			(layer "F.Fab")
		)
		(fp_text user "-"
			(at 3.98272 -2.073148 270)
			(unlocked yes)
			(layer "F.SilkS")
			(effects
				(font
					(size 1.905 1.4224)
					(thickness 0.1524)
				)
				(justify left)
			)
		)
		(fp_text user "+"
			(at -4.7752 -0.12065 90)
			(unlocked yes)
			(layer "F.SilkS")
			(effects
				(font
					(size 1.905 1.4224)
					(thickness 0.1524)
				)
				(justify left)
			)
		)
		(fp_text user "+"
			(at -4.7752 -0.12065 90)
			(unlocked yes)
			(layer "F.Fab")
			(effects
				(font
					(size 1.905 1.4224)
					(thickness 0.1524)
				)
				(justify left)
			)
		)
		(fp_text user "-"
			(at 5.4102 0.29845 270)
			(unlocked yes)
			(layer "F.Fab")
			(effects
				(font
					(size 1.905 1.4224)
					(thickness 0.1524)
				)
				(justify left)
			)
		)
		(pad "A" smd rect
			(at -1.999996 0 180)
			(size 1.7018 2.5146)
			(layers "F.Cu" "F.Mask" "F.Paste")
			(net "GND")
		)
		(pad "C" smd rect
			(at 1.999996 0 180)
			(size 1.7018 2.5146)
			(layers "F.Cu" "F.Mask" "F.Paste")
			(net "P12V_NIC0_R")
		)
	)
	(footprint ""
		(layer "F.Cu")
		(at 136.445244 -92.385642 180)
		(property "Reference" "R1584"
			(at 0 0 180)
			(layer "F.SilkS")
			(hide yes)
			(effects
				(font
					(size 1.27 1.27)
				)
			)
		)
		(property "Value" ""
			(at 0 0 180)
			(layer "F.Fab")
			(effects
				(font
					(size 1.27 1.27)
				)
			)
		)
		(duplicate_pad_numbers_are_jumpers no)
		(fp_line
			(start 0.7874 0.4064)
			(end -0.7874 0.4064)
			(stroke
				(width 0.1524)
				(type default)
			)
			(layer "F.SilkS")
		)
		(fp_line
			(start 0.7874 -0.4064)
			(end 0.7874 0.4064)
			(stroke
				(width 0.1524)
				(type default)
			)
			(layer "F.SilkS")
		)
		(fp_line
			(start -0.7874 0.4064)
			(end -0.7874 -0.4064)
			(stroke
				(width 0.1524)
				(type default)
			)
			(layer "F.SilkS")
		)
		(fp_line
			(start -0.7874 -0.4064)
			(end 0.7874 -0.4064)
			(stroke
				(width 0.1524)
				(type default)
			)
			(layer "F.SilkS")
		)
		(fp_line
			(start 0.67945 0.3048)
			(end 0.120396 0.3048)
			(stroke
				(width 0.1)
				(type default)
			)
			(layer "F.Fab")
		)
		(fp_line
			(start 0.67945 -0.3048)
			(end 0.67945 0.3048)
			(stroke
				(width 0.1)
				(type default)
			)
			(layer "F.Fab")
		)
		(fp_line
			(start 0.12065 -0.2794)
			(end 0.12065 -0.3048)
			(stroke
				(width 0.1)
				(type default)
			)
			(layer "F.Fab")
		)
		(fp_line
			(start 0.12065 -0.3048)
			(end 0.67945 -0.3048)
			(stroke
				(width 0.1)
				(type default)
			)
			(layer "F.Fab")
		)
		(fp_line
			(start 0.120396 0.3048)
			(end 0.120396 0.2794)
			(stroke
				(width 0.1)
				(type default)
			)
			(layer "F.Fab")
		)
		(fp_line
			(start 0.120396 0.2794)
			(end -0.12065 0.2794)
			(stroke
				(width 0.1)
				(type default)
			)
			(layer "F.Fab")
		)
		(fp_line
			(start -0.12065 0.3048)
			(end -0.67945 0.3048)
			(stroke
				(width 0.1)
				(type default)
			)
			(layer "F.Fab")
		)
		(fp_line
			(start -0.12065 0.2794)
			(end -0.12065 0.3048)
			(stroke
				(width 0.1)
				(type default)
			)
			(layer "F.Fab")
		)
		(fp_line
			(start -0.12065 -0.2794)
			(end 0.12065 -0.2794)
			(stroke
				(width 0.1)
				(type default)
			)
			(layer "F.Fab")
		)
		(fp_line
			(start -0.12065 -0.305054)
			(end -0.12065 -0.2794)
			(stroke
				(width 0.1)
				(type default)
			)
			(layer "F.Fab")
		)
		(fp_line
			(start -0.67945 0.3048)
			(end -0.67945 -0.305054)
			(stroke
				(width 0.1)
				(type default)
			)
			(layer "F.Fab")
		)
		(fp_line
			(start -0.67945 -0.305054)
			(end -0.12065 -0.305054)
			(stroke
				(width 0.1)
				(type default)
			)
			(layer "F.Fab")
		)
		(pad "1" smd circle
			(at -0.40005 0 180)
			(size 0 0)
			(layers "F.Cu" "F.Mask" "F.Paste")
			(net "SMB_BIC_I2C9_MUX0_SSD6_R_SDA")
		)
		(pad "2" smd circle
			(at 0.40005 0 180)
			(size 0 0)
			(layers "F.Cu" "F.Mask" "F.Paste")
			(net "SMB_BIC_I2C9_MUX0_SSD6_SDA")
		)
	)
	(footprint ""
		(layer "F.Cu")
		(at 288.083498 -61.487812 180)
		(property "Reference" "R6004"
			(at 0 0 180)
			(layer "F.SilkS")
			(hide yes)
			(effects
				(font
					(size 1.27 1.27)
				)
			)
		)
		(property "Value" ""
			(at 0 0 180)
			(layer "F.Fab")
			(effects
				(font
					(size 1.27 1.27)
				)
			)
		)
		(duplicate_pad_numbers_are_jumpers no)
		(fp_line
			(start 0.7874 0.4064)
			(end -0.7874 0.4064)
			(stroke
				(width 0.1524)
				(type default)
			)
			(layer "F.SilkS")
		)
		(fp_line
			(start 0.7874 -0.4064)
			(end 0.7874 0.4064)
			(stroke
				(width 0.1524)
				(type default)
			)
			(layer "F.SilkS")
		)
		(fp_line
			(start -0.7874 0.4064)
			(end -0.7874 -0.4064)
			(stroke
				(width 0.1524)
				(type default)
			)
			(layer "F.SilkS")
		)
		(fp_line
			(start -0.7874 -0.4064)
			(end 0.7874 -0.4064)
			(stroke
				(width 0.1524)
				(type default)
			)
			(layer "F.SilkS")
		)
		(fp_line
			(start 0.67945 0.3048)
			(end 0.120396 0.3048)
			(stroke
				(width 0.1)
				(type default)
			)
			(layer "F.Fab")
		)
		(fp_line
			(start 0.67945 -0.3048)
			(end 0.67945 0.3048)
			(stroke
				(width 0.1)
				(type default)
			)
			(layer "F.Fab")
		)
		(fp_line
			(start 0.12065 -0.2794)
			(end 0.12065 -0.3048)
			(stroke
				(width 0.1)
				(type default)
			)
			(layer "F.Fab")
		)
		(fp_line
			(start 0.12065 -0.3048)
			(end 0.67945 -0.3048)
			(stroke
				(width 0.1)
				(type default)
			)
			(layer "F.Fab")
		)
		(fp_line
			(start 0.120396 0.3048)
			(end 0.120396 0.2794)
			(stroke
				(width 0.1)
				(type default)
			)
			(layer "F.Fab")
		)
		(fp_line
			(start 0.120396 0.2794)
			(end -0.12065 0.2794)
			(stroke
				(width 0.1)
				(type default)
			)
			(layer "F.Fab")
		)
		(fp_line
			(start -0.12065 0.3048)
			(end -0.67945 0.3048)
			(stroke
				(width 0.1)
				(type default)
			)
			(layer "F.Fab")
		)
		(fp_line
			(start -0.12065 0.2794)
			(end -0.12065 0.3048)
			(stroke
				(width 0.1)
				(type default)
			)
			(layer "F.Fab")
		)
		(fp_line
			(start -0.12065 -0.2794)
			(end 0.12065 -0.2794)
			(stroke
				(width 0.1)
				(type default)
			)
			(layer "F.Fab")
		)
		(fp_line
			(start -0.12065 -0.305054)
			(end -0.12065 -0.2794)
			(stroke
				(width 0.1)
				(type default)
			)
			(layer "F.Fab")
		)
		(fp_line
			(start -0.67945 0.3048)
			(end -0.67945 -0.305054)
			(stroke
				(width 0.1)
				(type default)
			)
			(layer "F.Fab")
		)
		(fp_line
			(start -0.67945 -0.305054)
			(end -0.12065 -0.305054)
			(stroke
				(width 0.1)
				(type default)
			)
			(layer "F.Fab")
		)
		(pad "1" smd circle
			(at -0.40005 0 180)
			(size 0 0)
			(layers "F.Cu" "F.Mask" "F.Paste")
			(net "PWRGD_P12V_SSD10_D")
		)
		(pad "2" smd circle
			(at 0.40005 0 180)
			(size 0 0)
			(layers "F.Cu" "F.Mask" "F.Paste")
			(net "PWRGD_P12V_SSD10_R")
		)
	)
	(footprint ""
		(layer "F.Cu")
		(at 354.166932 -52.543456 180)
		(property "Reference" "PC550"
			(at 0 0 180)
			(layer "F.SilkS")
			(hide yes)
			(effects
				(font
					(size 1.27 1.27)
				)
			)
		)
		(property "Value" ""
			(at 0 0 180)
			(layer "F.Fab")
			(effects
				(font
					(size 1.27 1.27)
				)
			)
		)
		(duplicate_pad_numbers_are_jumpers no)
		(fp_line
			(start 0.7874 0.4064)
			(end -0.7874 0.4064)
			(stroke
				(width 0.1524)
				(type default)
			)
			(layer "F.SilkS")
		)
		(fp_line
			(start 0.7874 -0.4064)
			(end 0.7874 0.4064)
			(stroke
				(width 0.1524)
				(type default)
			)
			(layer "F.SilkS")
		)
		(fp_line
			(start -0.7874 0.4064)
			(end -0.7874 -0.4064)
			(stroke
				(width 0.1524)
				(type default)
			)
			(layer "F.SilkS")
		)
		(fp_line
			(start -0.7874 -0.4064)
			(end 0.7874 -0.4064)
			(stroke
				(width 0.1524)
				(type default)
			)
			(layer "F.SilkS")
		)
		(fp_line
			(start 0.67945 0.3048)
			(end 0.120396 0.3048)
			(stroke
				(width 0.1)
				(type default)
			)
			(layer "F.Fab")
		)
		(fp_line
			(start 0.67945 -0.3048)
			(end 0.67945 0.3048)
			(stroke
				(width 0.1)
				(type default)
			)
			(layer "F.Fab")
		)
		(fp_line
			(start 0.12065 -0.2794)
			(end 0.12065 -0.3048)
			(stroke
				(width 0.1)
				(type default)
			)
			(layer "F.Fab")
		)
		(fp_line
			(start 0.12065 -0.3048)
			(end 0.67945 -0.3048)
			(stroke
				(width 0.1)
				(type default)
			)
			(layer "F.Fab")
		)
		(fp_line
			(start 0.120396 0.3048)
			(end 0.120396 0.2794)
			(stroke
				(width 0.1)
				(type default)
			)
			(layer "F.Fab")
		)
		(fp_line
			(start 0.120396 0.2794)
			(end -0.12065 0.2794)
			(stroke
				(width 0.1)
				(type default)
			)
			(layer "F.Fab")
		)
		(fp_line
			(start -0.12065 0.3048)
			(end -0.67945 0.3048)
			(stroke
				(width 0.1)
				(type default)
			)
			(layer "F.Fab")
		)
		(fp_line
			(start -0.12065 0.2794)
			(end -0.12065 0.3048)
			(stroke
				(width 0.1)
				(type default)
			)
			(layer "F.Fab")
		)
		(fp_line
			(start -0.12065 -0.2794)
			(end 0.12065 -0.2794)
			(stroke
				(width 0.1)
				(type default)
			)
			(layer "F.Fab")
		)
		(fp_line
			(start -0.12065 -0.305054)
			(end -0.12065 -0.2794)
			(stroke
				(width 0.1)
				(type default)
			)
			(layer "F.Fab")
		)
		(fp_line
			(start -0.67945 0.3048)
			(end -0.67945 -0.305054)
			(stroke
				(width 0.1)
				(type default)
			)
			(layer "F.Fab")
		)
		(fp_line
			(start -0.67945 -0.305054)
			(end -0.12065 -0.305054)
			(stroke
				(width 0.1)
				(type default)
			)
			(layer "F.Fab")
		)
		(pad "1" smd circle
			(at -0.40005 0 180)
			(size 0 0)
			(layers "F.Cu" "F.Mask" "F.Paste")
			(net "P3V3_SSD12")
		)
		(pad "2" smd circle
			(at 0.40005 0 180)
			(size 0 0)
			(layers "F.Cu" "F.Mask" "F.Paste")
			(net "GND")
		)
	)
	(footprint ""
		(layer "F.Cu")
		(at 418.596572 -350.098614 90)
		(property "Reference" "C816"
			(at 0 0 90)
			(layer "F.SilkS")
			(hide yes)
			(effects
				(font
					(size 1.27 1.27)
				)
			)
		)
		(property "Value" ""
			(at 0 0 90)
			(layer "F.Fab")
			(effects
				(font
					(size 1.27 1.27)
				)
			)
		)
		(duplicate_pad_numbers_are_jumpers no)
		(fp_line
			(start 0.299974 -0.150114)
			(end 0.299974 0.150114)
			(stroke
				(width 0.1)
				(type default)
			)
			(layer "F.Fab")
		)
		(fp_line
			(start -0.299974 -0.150114)
			(end 0.299974 -0.150114)
			(stroke
				(width 0.1)
				(type default)
			)
			(layer "F.Fab")
		)
		(fp_line
			(start 0.299974 0.150114)
			(end -0.299974 0.150114)
			(stroke
				(width 0.1)
				(type default)
			)
			(layer "F.Fab")
		)
		(fp_line
			(start -0.299974 0.150114)
			(end -0.299974 -0.150114)
			(stroke
				(width 0.1)
				(type default)
			)
			(layer "F.Fab")
		)
		(pad "1" smd rect
			(at -0.2667 0 90)
			(size 0.3048 0.381)
			(layers "F.Cu" "F.Mask" "F.Paste")
			(net "P5E_PEX3_STN7_TX_DP<116>")
		)
		(pad "2" smd rect
			(at 0.2667 0 90)
			(size 0.3048 0.381)
			(layers "F.Cu" "F.Mask" "F.Paste")
			(net "P5E_PEX3_STN7_TX_C_DP<116>")
		)
	)
	(footprint ""
		(layer "F.Cu")
		(at 141.164564 -29.079952 180)
		(property "Reference" "R6202"
			(at 0 0 180)
			(layer "F.SilkS")
			(hide yes)
			(effects
				(font
					(size 1.27 1.27)
				)
			)
		)
		(property "Value" ""
			(at 0 0 180)
			(layer "F.Fab")
			(effects
				(font
					(size 1.27 1.27)
				)
			)
		)
		(duplicate_pad_numbers_are_jumpers no)
		(fp_line
			(start 0.7874 0.4064)
			(end -0.7874 0.4064)
			(stroke
				(width 0.1524)
				(type default)
			)
			(layer "F.SilkS")
		)
		(fp_line
			(start 0.7874 -0.4064)
			(end 0.7874 0.4064)
			(stroke
				(width 0.1524)
				(type default)
			)
			(layer "F.SilkS")
		)
		(fp_line
			(start -0.7874 0.4064)
			(end -0.7874 -0.4064)
			(stroke
				(width 0.1524)
				(type default)
			)
			(layer "F.SilkS")
		)
		(fp_line
			(start -0.7874 -0.4064)
			(end 0.7874 -0.4064)
			(stroke
				(width 0.1524)
				(type default)
			)
			(layer "F.SilkS")
		)
		(fp_line
			(start 0.67945 0.3048)
			(end 0.120396 0.3048)
			(stroke
				(width 0.1)
				(type default)
			)
			(layer "F.Fab")
		)
		(fp_line
			(start 0.67945 -0.3048)
			(end 0.67945 0.3048)
			(stroke
				(width 0.1)
				(type default)
			)
			(layer "F.Fab")
		)
		(fp_line
			(start 0.12065 -0.2794)
			(end 0.12065 -0.3048)
			(stroke
				(width 0.1)
				(type default)
			)
			(layer "F.Fab")
		)
		(fp_line
			(start 0.12065 -0.3048)
			(end 0.67945 -0.3048)
			(stroke
				(width 0.1)
				(type default)
			)
			(layer "F.Fab")
		)
		(fp_line
			(start 0.120396 0.3048)
			(end 0.120396 0.2794)
			(stroke
				(width 0.1)
				(type default)
			)
			(layer "F.Fab")
		)
		(fp_line
			(start 0.120396 0.2794)
			(end -0.12065 0.2794)
			(stroke
				(width 0.1)
				(type default)
			)
			(layer "F.Fab")
		)
		(fp_line
			(start -0.12065 0.3048)
			(end -0.67945 0.3048)
			(stroke
				(width 0.1)
				(type default)
			)
			(layer "F.Fab")
		)
		(fp_line
			(start -0.12065 0.2794)
			(end -0.12065 0.3048)
			(stroke
				(width 0.1)
				(type default)
			)
			(layer "F.Fab")
		)
		(fp_line
			(start -0.12065 -0.2794)
			(end 0.12065 -0.2794)
			(stroke
				(width 0.1)
				(type default)
			)
			(layer "F.Fab")
		)
		(fp_line
			(start -0.12065 -0.305054)
			(end -0.12065 -0.2794)
			(stroke
				(width 0.1)
				(type default)
			)
			(layer "F.Fab")
		)
		(fp_line
			(start -0.67945 0.3048)
			(end -0.67945 -0.305054)
			(stroke
				(width 0.1)
				(type default)
			)
			(layer "F.Fab")
		)
		(fp_line
			(start -0.67945 -0.305054)
			(end -0.12065 -0.305054)
			(stroke
				(width 0.1)
				(type default)
			)
			(layer "F.Fab")
		)
		(pad "1" smd circle
			(at -0.40005 0 180)
			(size 0 0)
			(layers "F.Cu" "F.Mask" "F.Paste")
			(net "GND")
		)
		(pad "2" smd circle
			(at 0.40005 0 180)
			(size 0 0)
			(layers "F.Cu" "F.Mask" "F.Paste")
			(net "SSD4_PWRDIS_R")
		)
	)
	(footprint ""
		(layer "F.Cu")
		(at 321.205098 -298.87291 -90)
		(property "Reference" "R3971"
			(at 0 0 270)
			(layer "F.SilkS")
			(hide yes)
			(effects
				(font
					(size 1.27 1.27)
				)
			)
		)
		(property "Value" ""
			(at 0 0 270)
			(layer "F.Fab")
			(effects
				(font
					(size 1.27 1.27)
				)
			)
		)
		(duplicate_pad_numbers_are_jumpers no)
		(fp_line
			(start -0.7874 0.4064)
			(end -0.7874 -0.4064)
			(stroke
				(width 0.1524)
				(type default)
			)
			(layer "F.SilkS")
		)
		(fp_line
			(start 0.7874 0.4064)
			(end -0.7874 0.4064)
			(stroke
				(width 0.1524)
				(type default)
			)
			(layer "F.SilkS")
		)
		(fp_line
			(start -0.7874 -0.4064)
			(end 0.7874 -0.4064)
			(stroke
				(width 0.1524)
				(type default)
			)
			(layer "F.SilkS")
		)
		(fp_line
			(start 0.7874 -0.4064)
			(end 0.7874 0.4064)
			(stroke
				(width 0.1524)
				(type default)
			)
			(layer "F.SilkS")
		)
		(fp_line
			(start -0.67945 0.3048)
			(end -0.67945 -0.305054)
			(stroke
				(width 0.1)
				(type default)
			)
			(layer "F.Fab")
		)
		(fp_line
			(start -0.12065 0.3048)
			(end -0.67945 0.3048)
			(stroke
				(width 0.1)
				(type default)
			)
			(layer "F.Fab")
		)
		(fp_line
			(start 0.120396 0.3048)
			(end 0.120396 0.2794)
			(stroke
				(width 0.1)
				(type default)
			)
			(layer "F.Fab")
		)
		(fp_line
			(start 0.67945 0.3048)
			(end 0.120396 0.3048)
			(stroke
				(width 0.1)
				(type default)
			)
			(layer "F.Fab")
		)
		(fp_line
			(start -0.12065 0.2794)
			(end -0.12065 0.3048)
			(stroke
				(width 0.1)
				(type default)
			)
			(layer "F.Fab")
		)
		(fp_line
			(start 0.120396 0.2794)
			(end -0.12065 0.2794)
			(stroke
				(width 0.1)
				(type default)
			)
			(layer "F.Fab")
		)
		(fp_line
			(start -0.12065 -0.2794)
			(end 0.12065 -0.2794)
			(stroke
				(width 0.1)
				(type default)
			)
			(layer "F.Fab")
		)
		(fp_line
			(start 0.12065 -0.2794)
			(end 0.12065 -0.3048)
			(stroke
				(width 0.1)
				(type default)
			)
			(layer "F.Fab")
		)
		(fp_line
			(start 0.12065 -0.3048)
			(end 0.67945 -0.3048)
			(stroke
				(width 0.1)
				(type default)
			)
			(layer "F.Fab")
		)
		(fp_line
			(start 0.67945 -0.3048)
			(end 0.67945 0.3048)
			(stroke
				(width 0.1)
				(type default)
			)
			(layer "F.Fab")
		)
		(fp_line
			(start -0.67945 -0.305054)
			(end -0.12065 -0.305054)
			(stroke
				(width 0.1)
				(type default)
			)
			(layer "F.Fab")
		)
		(fp_line
			(start -0.12065 -0.305054)
			(end -0.12065 -0.2794)
			(stroke
				(width 0.1)
				(type default)
			)
			(layer "F.Fab")
		)
		(pad "1" smd circle
			(at -0.40005 0 270)
			(size 0 0)
			(layers "F.Cu" "F.Mask" "F.Paste")
			(net "I2C_PEX2_HOST_SDA")
		)
		(pad "2" smd circle
			(at 0.40005 0 270)
			(size 0 0)
			(layers "F.Cu" "F.Mask" "F.Paste")
			(net "I2C_PEX2_HOST_R_SDA")
		)
	)
	(footprint ""
		(layer "F.Cu")
		(at 169.22623 -37.929566 90)
		(property "Reference" "R5558"
			(at 0 0 90)
			(layer "F.SilkS")
			(hide yes)
			(effects
				(font
					(size 1.27 1.27)
				)
			)
		)
		(property "Value" ""
			(at 0 0 90)
			(layer "F.Fab")
			(effects
				(font
					(size 1.27 1.27)
				)
			)
		)
		(duplicate_pad_numbers_are_jumpers no)
		(fp_line
			(start 0.7874 -0.4064)
			(end 0.7874 0.4064)
			(stroke
				(width 0.1524)
				(type default)
			)
			(layer "F.SilkS")
		)
		(fp_line
			(start -0.7874 -0.4064)
			(end 0.7874 -0.4064)
			(stroke
				(width 0.1524)
				(type default)
			)
			(layer "F.SilkS")
		)
		(fp_line
			(start 0.7874 0.4064)
			(end -0.7874 0.4064)
			(stroke
				(width 0.1524)
				(type default)
			)
			(layer "F.SilkS")
		)
		(fp_line
			(start -0.7874 0.4064)
			(end -0.7874 -0.4064)
			(stroke
				(width 0.1524)
				(type default)
			)
			(layer "F.SilkS")
		)
		(fp_line
			(start -0.12065 -0.305054)
			(end -0.12065 -0.2794)
			(stroke
				(width 0.1)
				(type default)
			)
			(layer "F.Fab")
		)
		(fp_line
			(start -0.67945 -0.305054)
			(end -0.12065 -0.305054)
			(stroke
				(width 0.1)
				(type default)
			)
			(layer "F.Fab")
		)
		(fp_line
			(start 0.67945 -0.3048)
			(end 0.67945 0.3048)
			(stroke
				(width 0.1)
				(type default)
			)
			(layer "F.Fab")
		)
		(fp_line
			(start 0.12065 -0.3048)
			(end 0.67945 -0.3048)
			(stroke
				(width 0.1)
				(type default)
			)
			(layer "F.Fab")
		)
		(fp_line
			(start 0.12065 -0.2794)
			(end 0.12065 -0.3048)
			(stroke
				(width 0.1)
				(type default)
			)
			(layer "F.Fab")
		)
		(fp_line
			(start -0.12065 -0.2794)
			(end 0.12065 -0.2794)
			(stroke
				(width 0.1)
				(type default)
			)
			(layer "F.Fab")
		)
		(fp_line
			(start 0.120396 0.2794)
			(end -0.12065 0.2794)
			(stroke
				(width 0.1)
				(type default)
			)
			(layer "F.Fab")
		)
		(fp_line
			(start -0.12065 0.2794)
			(end -0.12065 0.3048)
			(stroke
				(width 0.1)
				(type default)
			)
			(layer "F.Fab")
		)
		(fp_line
			(start 0.67945 0.3048)
			(end 0.120396 0.3048)
			(stroke
				(width 0.1)
				(type default)
			)
			(layer "F.Fab")
		)
		(fp_line
			(start 0.120396 0.3048)
			(end 0.120396 0.2794)
			(stroke
				(width 0.1)
				(type default)
			)
			(layer "F.Fab")
		)
		(fp_line
			(start -0.12065 0.3048)
			(end -0.67945 0.3048)
			(stroke
				(width 0.1)
				(type default)
			)
			(layer "F.Fab")
		)
		(fp_line
			(start -0.67945 0.3048)
			(end -0.67945 -0.305054)
			(stroke
				(width 0.1)
				(type default)
			)
			(layer "F.Fab")
		)
		(pad "1" smd circle
			(at -0.40005 0 90)
			(size 0 0)
			(layers "F.Cu" "F.Mask" "F.Paste")
			(net "SSD6_AUX_P3V3_EN_R")
		)
		(pad "2" smd circle
			(at 0.40005 0 90)
			(size 0 0)
			(layers "F.Cu" "F.Mask" "F.Paste")
			(net "SSD6_AUX_P3V3_EN")
		)
	)
	(footprint ""
		(layer "F.Cu")
		(at 338.074 -151.003)
		(property "Reference" "R4830"
			(at 0 0 0)
			(layer "F.SilkS")
			(hide yes)
			(effects
				(font
					(size 1.27 1.27)
				)
			)
		)
		(property "Value" ""
			(at 0 0 0)
			(layer "F.Fab")
			(effects
				(font
					(size 1.27 1.27)
				)
			)
		)
		(duplicate_pad_numbers_are_jumpers no)
		(fp_line
			(start -0.7874 -0.4064)
			(end 0.7874 -0.4064)
			(stroke
				(width 0.1524)
				(type default)
			)
			(layer "F.SilkS")
		)
		(fp_line
			(start -0.7874 0.4064)
			(end -0.7874 -0.4064)
			(stroke
				(width 0.1524)
				(type default)
			)
			(layer "F.SilkS")
		)
		(fp_line
			(start 0.7874 -0.4064)
			(end 0.7874 0.4064)
			(stroke
				(width 0.1524)
				(type default)
			)
			(layer "F.SilkS")
		)
		(fp_line
			(start 0.7874 0.4064)
			(end -0.7874 0.4064)
			(stroke
				(width 0.1524)
				(type default)
			)
			(layer "F.SilkS")
		)
		(fp_line
			(start -0.67945 -0.305054)
			(end -0.12065 -0.305054)
			(stroke
				(width 0.1)
				(type default)
			)
			(layer "F.Fab")
		)
		(fp_line
			(start -0.67945 0.3048)
			(end -0.67945 -0.305054)
			(stroke
				(width 0.1)
				(type default)
			)
			(layer "F.Fab")
		)
		(fp_line
			(start -0.12065 -0.305054)
			(end -0.12065 -0.2794)
			(stroke
				(width 0.1)
				(type default)
			)
			(layer "F.Fab")
		)
		(fp_line
			(start -0.12065 -0.2794)
			(end 0.12065 -0.2794)
			(stroke
				(width 0.1)
				(type default)
			)
			(layer "F.Fab")
		)
		(fp_line
			(start -0.12065 0.2794)
			(end -0.12065 0.3048)
			(stroke
				(width 0.1)
				(type default)
			)
			(layer "F.Fab")
		)
		(fp_line
			(start -0.12065 0.3048)
			(end -0.67945 0.3048)
			(stroke
				(width 0.1)
				(type default)
			)
			(layer "F.Fab")
		)
		(fp_line
			(start 0.120396 0.2794)
			(end -0.12065 0.2794)
			(stroke
				(width 0.1)
				(type default)
			)
			(layer "F.Fab")
		)
		(fp_line
			(start 0.120396 0.3048)
			(end 0.120396 0.2794)
			(stroke
				(width 0.1)
				(type default)
			)
			(layer "F.Fab")
		)
		(fp_line
			(start 0.12065 -0.3048)
			(end 0.67945 -0.3048)
			(stroke
				(width 0.1)
				(type default)
			)
			(layer "F.Fab")
		)
		(fp_line
			(start 0.12065 -0.2794)
			(end 0.12065 -0.3048)
			(stroke
				(width 0.1)
				(type default)
			)
			(layer "F.Fab")
		)
		(fp_line
			(start 0.67945 -0.3048)
			(end 0.67945 0.3048)
			(stroke
				(width 0.1)
				(type default)
			)
			(layer "F.Fab")
		)
		(fp_line
			(start 0.67945 0.3048)
			(end 0.120396 0.3048)
			(stroke
				(width 0.1)
				(type default)
			)
			(layer "F.Fab")
		)
		(pad "1" smd circle
			(at -0.40005 0)
			(size 0 0)
			(layers "F.Cu" "F.Mask" "F.Paste")
			(net "PEX3_PCA9555_1_INT_N")
		)
		(pad "2" smd circle
			(at 0.40005 0)
			(size 0 0)
			(layers "F.Cu" "F.Mask" "F.Paste")
			(net "P1V8_PEX")
		)
	)
	(footprint ""
		(layer "F.Cu")
		(at 179.777644 -117.566186)
		(property "Reference" "R194"
			(at 0 0 0)
			(layer "F.SilkS")
			(hide yes)
			(effects
				(font
					(size 1.27 1.27)
				)
			)
		)
		(property "Value" ""
			(at 0 0 0)
			(layer "F.Fab")
			(effects
				(font
					(size 1.27 1.27)
				)
			)
		)
		(duplicate_pad_numbers_are_jumpers no)
		(fp_line
			(start -0.7874 -0.4064)
			(end 0.7874 -0.4064)
			(stroke
				(width 0.1524)
				(type default)
			)
			(layer "F.SilkS")
		)
		(fp_line
			(start -0.7874 0.4064)
			(end -0.7874 -0.4064)
			(stroke
				(width 0.1524)
				(type default)
			)
			(layer "F.SilkS")
		)
		(fp_line
			(start 0.7874 -0.4064)
			(end 0.7874 0.4064)
			(stroke
				(width 0.1524)
				(type default)
			)
			(layer "F.SilkS")
		)
		(fp_line
			(start 0.7874 0.4064)
			(end -0.7874 0.4064)
			(stroke
				(width 0.1524)
				(type default)
			)
			(layer "F.SilkS")
		)
		(fp_line
			(start -0.67945 -0.305054)
			(end -0.12065 -0.305054)
			(stroke
				(width 0.1)
				(type default)
			)
			(layer "F.Fab")
		)
		(fp_line
			(start -0.67945 0.3048)
			(end -0.67945 -0.305054)
			(stroke
				(width 0.1)
				(type default)
			)
			(layer "F.Fab")
		)
		(fp_line
			(start -0.12065 -0.305054)
			(end -0.12065 -0.2794)
			(stroke
				(width 0.1)
				(type default)
			)
			(layer "F.Fab")
		)
		(fp_line
			(start -0.12065 -0.2794)
			(end 0.12065 -0.2794)
			(stroke
				(width 0.1)
				(type default)
			)
			(layer "F.Fab")
		)
		(fp_line
			(start -0.12065 0.2794)
			(end -0.12065 0.3048)
			(stroke
				(width 0.1)
				(type default)
			)
			(layer "F.Fab")
		)
		(fp_line
			(start -0.12065 0.3048)
			(end -0.67945 0.3048)
			(stroke
				(width 0.1)
				(type default)
			)
			(layer "F.Fab")
		)
		(fp_line
			(start 0.120396 0.2794)
			(end -0.12065 0.2794)
			(stroke
				(width 0.1)
				(type default)
			)
			(layer "F.Fab")
		)
		(fp_line
			(start 0.120396 0.3048)
			(end 0.120396 0.2794)
			(stroke
				(width 0.1)
				(type default)
			)
			(layer "F.Fab")
		)
		(fp_line
			(start 0.12065 -0.3048)
			(end 0.67945 -0.3048)
			(stroke
				(width 0.1)
				(type default)
			)
			(layer "F.Fab")
		)
		(fp_line
			(start 0.12065 -0.2794)
			(end 0.12065 -0.3048)
			(stroke
				(width 0.1)
				(type default)
			)
			(layer "F.Fab")
		)
		(fp_line
			(start 0.67945 -0.3048)
			(end 0.67945 0.3048)
			(stroke
				(width 0.1)
				(type default)
			)
			(layer "F.Fab")
		)
		(fp_line
			(start 0.67945 0.3048)
			(end 0.120396 0.3048)
			(stroke
				(width 0.1)
				(type default)
			)
			(layer "F.Fab")
		)
		(pad "1" smd circle
			(at -0.40005 0)
			(size 0 0)
			(layers "F.Cu" "F.Mask" "F.Paste")
			(net "PRSNT_NIC3_N")
		)
		(pad "2" smd circle
			(at 0.40005 0)
			(size 0 0)
			(layers "F.Cu" "F.Mask" "F.Paste")
			(net "PRSNTB2_NIC3_N")
		)
	)
	(footprint ""
		(layer "F.Cu")
		(at 104.243632 -44.87291)
		(property "Reference" "R540"
			(at 0 0 0)
			(layer "F.SilkS")
			(hide yes)
			(effects
				(font
					(size 1.27 1.27)
				)
			)
		)
		(property "Value" ""
			(at 0 0 0)
			(layer "F.Fab")
			(effects
				(font
					(size 1.27 1.27)
				)
			)
		)
		(duplicate_pad_numbers_are_jumpers no)
		(fp_line
			(start -0.7874 -0.4064)
			(end 0.7874 -0.4064)
			(stroke
				(width 0.1524)
				(type default)
			)
			(layer "F.SilkS")
		)
		(fp_line
			(start -0.7874 0.4064)
			(end -0.7874 -0.4064)
			(stroke
				(width 0.1524)
				(type default)
			)
			(layer "F.SilkS")
		)
		(fp_line
			(start 0.7874 -0.4064)
			(end 0.7874 0.4064)
			(stroke
				(width 0.1524)
				(type default)
			)
			(layer "F.SilkS")
		)
		(fp_line
			(start 0.7874 0.4064)
			(end -0.7874 0.4064)
			(stroke
				(width 0.1524)
				(type default)
			)
			(layer "F.SilkS")
		)
		(fp_line
			(start -0.67945 -0.305054)
			(end -0.12065 -0.305054)
			(stroke
				(width 0.1)
				(type default)
			)
			(layer "F.Fab")
		)
		(fp_line
			(start -0.67945 0.3048)
			(end -0.67945 -0.305054)
			(stroke
				(width 0.1)
				(type default)
			)
			(layer "F.Fab")
		)
		(fp_line
			(start -0.12065 -0.305054)
			(end -0.12065 -0.2794)
			(stroke
				(width 0.1)
				(type default)
			)
			(layer "F.Fab")
		)
		(fp_line
			(start -0.12065 -0.2794)
			(end 0.12065 -0.2794)
			(stroke
				(width 0.1)
				(type default)
			)
			(layer "F.Fab")
		)
		(fp_line
			(start -0.12065 0.2794)
			(end -0.12065 0.3048)
			(stroke
				(width 0.1)
				(type default)
			)
			(layer "F.Fab")
		)
		(fp_line
			(start -0.12065 0.3048)
			(end -0.67945 0.3048)
			(stroke
				(width 0.1)
				(type default)
			)
			(layer "F.Fab")
		)
		(fp_line
			(start 0.120396 0.2794)
			(end -0.12065 0.2794)
			(stroke
				(width 0.1)
				(type default)
			)
			(layer "F.Fab")
		)
		(fp_line
			(start 0.120396 0.3048)
			(end 0.120396 0.2794)
			(stroke
				(width 0.1)
				(type default)
			)
			(layer "F.Fab")
		)
		(fp_line
			(start 0.12065 -0.3048)
			(end 0.67945 -0.3048)
			(stroke
				(width 0.1)
				(type default)
			)
			(layer "F.Fab")
		)
		(fp_line
			(start 0.12065 -0.2794)
			(end 0.12065 -0.3048)
			(stroke
				(width 0.1)
				(type default)
			)
			(layer "F.Fab")
		)
		(fp_line
			(start 0.67945 -0.3048)
			(end 0.67945 0.3048)
			(stroke
				(width 0.1)
				(type default)
			)
			(layer "F.Fab")
		)
		(fp_line
			(start 0.67945 0.3048)
			(end 0.120396 0.3048)
			(stroke
				(width 0.1)
				(type default)
			)
			(layer "F.Fab")
		)
		(pad "1" smd circle
			(at -0.40005 0)
			(size 0 0)
			(layers "F.Cu" "F.Mask" "F.Paste")
			(net "SSD3_ADC_A0")
		)
		(pad "2" smd circle
			(at 0.40005 0)
			(size 0 0)
			(layers "F.Cu" "F.Mask" "F.Paste")
			(net "P3V3_AUX")
		)
	)
	(footprint ""
		(layer "F.Cu")
		(at 223.50476 -312.316114 180)
		(property "Reference" "PC229"
			(at 0 0 180)
			(layer "F.SilkS")
			(hide yes)
			(effects
				(font
					(size 1.27 1.27)
				)
			)
		)
		(property "Value" ""
			(at 0 0 180)
			(layer "F.Fab")
			(effects
				(font
					(size 1.27 1.27)
				)
			)
		)
		(duplicate_pad_numbers_are_jumpers no)
		(fp_line
			(start 1.524 0.762)
			(end -1.524 0.762)
			(stroke
				(width 0.1524)
				(type default)
			)
			(layer "F.SilkS")
		)
		(fp_line
			(start 1.524 -0.762)
			(end 1.524 0.762)
			(stroke
				(width 0.1524)
				(type default)
			)
			(layer "F.SilkS")
		)
		(fp_line
			(start -1.524 0.762)
			(end -1.524 -0.762)
			(stroke
				(width 0.1524)
				(type default)
			)
			(layer "F.SilkS")
		)
		(fp_line
			(start -1.524 -0.762)
			(end 1.524 -0.762)
			(stroke
				(width 0.1524)
				(type default)
			)
			(layer "F.SilkS")
		)
		(fp_line
			(start 1.1049 0.724916)
			(end 1.1049 -0.724916)
			(stroke
				(width 0.1)
				(type default)
			)
			(layer "F.Fab")
		)
		(fp_line
			(start 1.1049 -0.724916)
			(end -1.1049 -0.724916)
			(stroke
				(width 0.1)
				(type default)
			)
			(layer "F.Fab")
		)
		(fp_line
			(start -1.1049 0.724916)
			(end 1.1049 0.724916)
			(stroke
				(width 0.1)
				(type default)
			)
			(layer "F.Fab")
		)
		(fp_line
			(start -1.1049 -0.724916)
			(end -1.1049 0.724916)
			(stroke
				(width 0.1)
				(type default)
			)
			(layer "F.Fab")
		)
		(pad "1" smd rect
			(at -0.889 0)
			(size 1.016 1.27)
			(layers "F.Cu" "F.Mask" "F.Paste")
			(net "SW_P12V_P1V25_PEX1_FLT")
		)
		(pad "2" smd rect
			(at 0.889 0)
			(size 1.016 1.27)
			(layers "F.Cu" "F.Mask" "F.Paste")
			(net "GND")
		)
	)
	(footprint ""
		(layer "F.Cu")
		(at 295.670732 -137.848848 180)
		(property "Reference" "R261"
			(at 0 0 180)
			(layer "F.SilkS")
			(hide yes)
			(effects
				(font
					(size 1.27 1.27)
				)
			)
		)
		(property "Value" ""
			(at 0 0 180)
			(layer "F.Fab")
			(effects
				(font
					(size 1.27 1.27)
				)
			)
		)
		(duplicate_pad_numbers_are_jumpers no)
		(fp_line
			(start 0.7874 0.4064)
			(end -0.7874 0.4064)
			(stroke
				(width 0.1524)
				(type default)
			)
			(layer "F.SilkS")
		)
		(fp_line
			(start 0.7874 -0.4064)
			(end 0.7874 0.4064)
			(stroke
				(width 0.1524)
				(type default)
			)
			(layer "F.SilkS")
		)
		(fp_line
			(start -0.7874 0.4064)
			(end -0.7874 -0.4064)
			(stroke
				(width 0.1524)
				(type default)
			)
			(layer "F.SilkS")
		)
		(fp_line
			(start -0.7874 -0.4064)
			(end 0.7874 -0.4064)
			(stroke
				(width 0.1524)
				(type default)
			)
			(layer "F.SilkS")
		)
		(fp_line
			(start 0.67945 0.3048)
			(end 0.120396 0.3048)
			(stroke
				(width 0.1)
				(type default)
			)
			(layer "F.Fab")
		)
		(fp_line
			(start 0.67945 -0.3048)
			(end 0.67945 0.3048)
			(stroke
				(width 0.1)
				(type default)
			)
			(layer "F.Fab")
		)
		(fp_line
			(start 0.12065 -0.2794)
			(end 0.12065 -0.3048)
			(stroke
				(width 0.1)
				(type default)
			)
			(layer "F.Fab")
		)
		(fp_line
			(start 0.12065 -0.3048)
			(end 0.67945 -0.3048)
			(stroke
				(width 0.1)
				(type default)
			)
			(layer "F.Fab")
		)
		(fp_line
			(start 0.120396 0.3048)
			(end 0.120396 0.2794)
			(stroke
				(width 0.1)
				(type default)
			)
			(layer "F.Fab")
		)
		(fp_line
			(start 0.120396 0.2794)
			(end -0.12065 0.2794)
			(stroke
				(width 0.1)
				(type default)
			)
			(layer "F.Fab")
		)
		(fp_line
			(start -0.12065 0.3048)
			(end -0.67945 0.3048)
			(stroke
				(width 0.1)
				(type default)
			)
			(layer "F.Fab")
		)
		(fp_line
			(start -0.12065 0.2794)
			(end -0.12065 0.3048)
			(stroke
				(width 0.1)
				(type default)
			)
			(layer "F.Fab")
		)
		(fp_line
			(start -0.12065 -0.2794)
			(end 0.12065 -0.2794)
			(stroke
				(width 0.1)
				(type default)
			)
			(layer "F.Fab")
		)
		(fp_line
			(start -0.12065 -0.305054)
			(end -0.12065 -0.2794)
			(stroke
				(width 0.1)
				(type default)
			)
			(layer "F.Fab")
		)
		(fp_line
			(start -0.67945 0.3048)
			(end -0.67945 -0.305054)
			(stroke
				(width 0.1)
				(type default)
			)
			(layer "F.Fab")
		)
		(fp_line
			(start -0.67945 -0.305054)
			(end -0.12065 -0.305054)
			(stroke
				(width 0.1)
				(type default)
			)
			(layer "F.Fab")
		)
		(pad "1" smd circle
			(at -0.40005 0 180)
			(size 0 0)
			(layers "F.Cu" "F.Mask" "F.Paste")
			(net "PRSNTB1_NIC5_N")
		)
		(pad "2" smd circle
			(at 0.40005 0 180)
			(size 0 0)
			(layers "F.Cu" "F.Mask" "F.Paste")
			(net "P3V3_AUX")
		)
	)
	(footprint ""
		(layer "F.Cu")
		(at 55.88 -138.6332 180)
		(property "Reference" "R41"
			(at 0 0 180)
			(layer "F.SilkS")
			(hide yes)
			(effects
				(font
					(size 1.27 1.27)
				)
			)
		)
		(property "Value" ""
			(at 0 0 180)
			(layer "F.Fab")
			(effects
				(font
					(size 1.27 1.27)
				)
			)
		)
		(duplicate_pad_numbers_are_jumpers no)
		(fp_line
			(start 0.7874 0.4064)
			(end -0.7874 0.4064)
			(stroke
				(width 0.1524)
				(type default)
			)
			(layer "F.SilkS")
		)
		(fp_line
			(start 0.7874 -0.4064)
			(end 0.7874 0.4064)
			(stroke
				(width 0.1524)
				(type default)
			)
			(layer "F.SilkS")
		)
		(fp_line
			(start -0.7874 0.4064)
			(end -0.7874 -0.4064)
			(stroke
				(width 0.1524)
				(type default)
			)
			(layer "F.SilkS")
		)
		(fp_line
			(start -0.7874 -0.4064)
			(end 0.7874 -0.4064)
			(stroke
				(width 0.1524)
				(type default)
			)
			(layer "F.SilkS")
		)
		(fp_line
			(start 0.67945 0.3048)
			(end 0.120396 0.3048)
			(stroke
				(width 0.1)
				(type default)
			)
			(layer "F.Fab")
		)
		(fp_line
			(start 0.67945 -0.3048)
			(end 0.67945 0.3048)
			(stroke
				(width 0.1)
				(type default)
			)
			(layer "F.Fab")
		)
		(fp_line
			(start 0.12065 -0.2794)
			(end 0.12065 -0.3048)
			(stroke
				(width 0.1)
				(type default)
			)
			(layer "F.Fab")
		)
		(fp_line
			(start 0.12065 -0.3048)
			(end 0.67945 -0.3048)
			(stroke
				(width 0.1)
				(type default)
			)
			(layer "F.Fab")
		)
		(fp_line
			(start 0.120396 0.3048)
			(end 0.120396 0.2794)
			(stroke
				(width 0.1)
				(type default)
			)
			(layer "F.Fab")
		)
		(fp_line
			(start 0.120396 0.2794)
			(end -0.12065 0.2794)
			(stroke
				(width 0.1)
				(type default)
			)
			(layer "F.Fab")
		)
		(fp_line
			(start -0.12065 0.3048)
			(end -0.67945 0.3048)
			(stroke
				(width 0.1)
				(type default)
			)
			(layer "F.Fab")
		)
		(fp_line
			(start -0.12065 0.2794)
			(end -0.12065 0.3048)
			(stroke
				(width 0.1)
				(type default)
			)
			(layer "F.Fab")
		)
		(fp_line
			(start -0.12065 -0.2794)
			(end 0.12065 -0.2794)
			(stroke
				(width 0.1)
				(type default)
			)
			(layer "F.Fab")
		)
		(fp_line
			(start -0.12065 -0.305054)
			(end -0.12065 -0.2794)
			(stroke
				(width 0.1)
				(type default)
			)
			(layer "F.Fab")
		)
		(fp_line
			(start -0.67945 0.3048)
			(end -0.67945 -0.305054)
			(stroke
				(width 0.1)
				(type default)
			)
			(layer "F.Fab")
		)
		(fp_line
			(start -0.67945 -0.305054)
			(end -0.12065 -0.305054)
			(stroke
				(width 0.1)
				(type default)
			)
			(layer "F.Fab")
		)
		(pad "1" smd circle
			(at -0.40005 0 180)
			(size 0 0)
			(layers "F.Cu" "F.Mask" "F.Paste")
			(net "PRSNT_NIC0_N")
		)
		(pad "2" smd circle
			(at 0.40005 0 180)
			(size 0 0)
			(layers "F.Cu" "F.Mask" "F.Paste")
			(net "PRSNTB2_NIC0_N")
		)
	)
	(footprint ""
		(layer "F.Cu")
		(at 457.586334 -366.913922)
		(property "Reference" "R6690"
			(at 0 0 0)
			(layer "F.SilkS")
			(hide yes)
			(effects
				(font
					(size 1.27 1.27)
				)
			)
		)
		(property "Value" ""
			(at 0 0 0)
			(layer "F.Fab")
			(effects
				(font
					(size 1.27 1.27)
				)
			)
		)
		(duplicate_pad_numbers_are_jumpers no)
		(fp_line
			(start -0.7874 -0.4064)
			(end 0.7874 -0.4064)
			(stroke
				(width 0.1524)
				(type default)
			)
			(layer "F.SilkS")
		)
		(fp_line
			(start -0.7874 0.4064)
			(end -0.7874 -0.4064)
			(stroke
				(width 0.1524)
				(type default)
			)
			(layer "F.SilkS")
		)
		(fp_line
			(start 0.7874 -0.4064)
			(end 0.7874 0.4064)
			(stroke
				(width 0.1524)
				(type default)
			)
			(layer "F.SilkS")
		)
		(fp_line
			(start 0.7874 0.4064)
			(end -0.7874 0.4064)
			(stroke
				(width 0.1524)
				(type default)
			)
			(layer "F.SilkS")
		)
		(fp_line
			(start -0.67945 -0.305054)
			(end -0.12065 -0.305054)
			(stroke
				(width 0.1)
				(type default)
			)
			(layer "F.Fab")
		)
		(fp_line
			(start -0.67945 0.3048)
			(end -0.67945 -0.305054)
			(stroke
				(width 0.1)
				(type default)
			)
			(layer "F.Fab")
		)
		(fp_line
			(start -0.12065 -0.305054)
			(end -0.12065 -0.2794)
			(stroke
				(width 0.1)
				(type default)
			)
			(layer "F.Fab")
		)
		(fp_line
			(start -0.12065 -0.2794)
			(end 0.12065 -0.2794)
			(stroke
				(width 0.1)
				(type default)
			)
			(layer "F.Fab")
		)
		(fp_line
			(start -0.12065 0.2794)
			(end -0.12065 0.3048)
			(stroke
				(width 0.1)
				(type default)
			)
			(layer "F.Fab")
		)
		(fp_line
			(start -0.12065 0.3048)
			(end -0.67945 0.3048)
			(stroke
				(width 0.1)
				(type default)
			)
			(layer "F.Fab")
		)
		(fp_line
			(start 0.120396 0.2794)
			(end -0.12065 0.2794)
			(stroke
				(width 0.1)
				(type default)
			)
			(layer "F.Fab")
		)
		(fp_line
			(start 0.120396 0.3048)
			(end 0.120396 0.2794)
			(stroke
				(width 0.1)
				(type default)
			)
			(layer "F.Fab")
		)
		(fp_line
			(start 0.12065 -0.3048)
			(end 0.67945 -0.3048)
			(stroke
				(width 0.1)
				(type default)
			)
			(layer "F.Fab")
		)
		(fp_line
			(start 0.12065 -0.2794)
			(end 0.12065 -0.3048)
			(stroke
				(width 0.1)
				(type default)
			)
			(layer "F.Fab")
		)
		(fp_line
			(start 0.67945 -0.3048)
			(end 0.67945 0.3048)
			(stroke
				(width 0.1)
				(type default)
			)
			(layer "F.Fab")
		)
		(fp_line
			(start 0.67945 0.3048)
			(end 0.120396 0.3048)
			(stroke
				(width 0.1)
				(type default)
			)
			(layer "F.Fab")
		)
		(pad "1" smd circle
			(at -0.40005 0)
			(size 0 0)
			(layers "F.Cu" "F.Mask" "F.Paste")
			(net "GPU_3V3IO_RSVD4_N")
		)
		(pad "2" smd circle
			(at 0.40005 0)
			(size 0 0)
			(layers "F.Cu" "F.Mask" "F.Paste")
			(net "P3V3_AUX")
		)
	)
	(footprint ""
		(layer "F.Cu")
		(at 235.196126 -254.18542 -90)
		(property "Reference" "C4338"
			(at 0 0 270)
			(layer "F.SilkS")
			(hide yes)
			(effects
				(font
					(size 1.27 1.27)
				)
			)
		)
		(property "Value" ""
			(at 0 0 270)
			(layer "F.Fab")
			(effects
				(font
					(size 1.27 1.27)
				)
			)
		)
		(duplicate_pad_numbers_are_jumpers no)
		(fp_line
			(start -1.2954 0.5842)
			(end -1.2954 -0.5842)
			(stroke
				(width 0.1524)
				(type default)
			)
			(layer "F.SilkS")
		)
		(fp_line
			(start 1.2954 0.5842)
			(end -1.2954 0.5842)
			(stroke
				(width 0.1524)
				(type default)
			)
			(layer "F.SilkS")
		)
		(fp_line
			(start -1.2954 -0.5842)
			(end 1.2954 -0.5842)
			(stroke
				(width 0.1524)
				(type default)
			)
			(layer "F.SilkS")
		)
		(fp_line
			(start 1.2954 -0.5842)
			(end 1.2954 0.5842)
			(stroke
				(width 0.1524)
				(type default)
			)
			(layer "F.SilkS")
		)
		(fp_line
			(start -0.8636 0.4572)
			(end -0.8636 0.4064)
			(stroke
				(width 0.1)
				(type default)
			)
			(layer "F.Fab")
		)
		(fp_line
			(start 0.8636 0.4572)
			(end -0.8636 0.4572)
			(stroke
				(width 0.1)
				(type default)
			)
			(layer "F.Fab")
		)
		(fp_line
			(start -1.1938 0.4064)
			(end -1.1938 -0.4064)
			(stroke
				(width 0.1)
				(type default)
			)
			(layer "F.Fab")
		)
		(fp_line
			(start -0.8636 0.4064)
			(end -1.1938 0.4064)
			(stroke
				(width 0.1)
				(type default)
			)
			(layer "F.Fab")
		)
		(fp_line
			(start 0.8636 0.4064)
			(end 0.8636 0.4572)
			(stroke
				(width 0.1)
				(type default)
			)
			(layer "F.Fab")
		)
		(fp_line
			(start 1.1938 0.4064)
			(end 0.8636 0.4064)
			(stroke
				(width 0.1)
				(type default)
			)
			(layer "F.Fab")
		)
		(fp_line
			(start -1.1938 -0.4064)
			(end -0.8636 -0.4064)
			(stroke
				(width 0.1)
				(type default)
			)
			(layer "F.Fab")
		)
		(fp_line
			(start -0.8636 -0.4064)
			(end -0.8636 -0.4572)
			(stroke
				(width 0.1)
				(type default)
			)
			(layer "F.Fab")
		)
		(fp_line
			(start 0.8636 -0.4064)
			(end 1.1938 -0.4064)
			(stroke
				(width 0.1)
				(type default)
			)
			(layer "F.Fab")
		)
		(fp_line
			(start 1.1938 -0.4064)
			(end 1.1938 0.4064)
			(stroke
				(width 0.1)
				(type default)
			)
			(layer "F.Fab")
		)
		(fp_line
			(start -0.8636 -0.4572)
			(end 0.8636 -0.4572)
			(stroke
				(width 0.1)
				(type default)
			)
			(layer "F.Fab")
		)
		(fp_line
			(start 0.8636 -0.4572)
			(end 0.8636 -0.4064)
			(stroke
				(width 0.1)
				(type default)
			)
			(layer "F.Fab")
		)
		(pad "1" smd rect
			(at -0.7366 0 180)
			(size 0.7112 0.8128)
			(layers "F.Cu" "F.Mask" "F.Paste")
			(net "P1V25_SERDES_VDDPLL_PEX2_C0")
		)
		(pad "2" smd rect
			(at 0.7366 0 180)
			(size 0.7112 0.8128)
			(layers "F.Cu" "F.Mask" "F.Paste")
			(net "GND")
		)
	)
	(footprint ""
		(layer "F.Cu")
		(at 371.924834 -259.378958)
		(property "Reference" "R1464"
			(at 0 0 0)
			(layer "F.SilkS")
			(hide yes)
			(effects
				(font
					(size 1.27 1.27)
				)
			)
		)
		(property "Value" ""
			(at 0 0 0)
			(layer "F.Fab")
			(effects
				(font
					(size 1.27 1.27)
				)
			)
		)
		(duplicate_pad_numbers_are_jumpers no)
		(fp_line
			(start -0.7874 -0.4064)
			(end 0.7874 -0.4064)
			(stroke
				(width 0.1524)
				(type default)
			)
			(layer "F.SilkS")
		)
		(fp_line
			(start -0.7874 0.4064)
			(end -0.7874 -0.4064)
			(stroke
				(width 0.1524)
				(type default)
			)
			(layer "F.SilkS")
		)
		(fp_line
			(start 0.7874 -0.4064)
			(end 0.7874 0.4064)
			(stroke
				(width 0.1524)
				(type default)
			)
			(layer "F.SilkS")
		)
		(fp_line
			(start 0.7874 0.4064)
			(end -0.7874 0.4064)
			(stroke
				(width 0.1524)
				(type default)
			)
			(layer "F.SilkS")
		)
		(fp_line
			(start -0.67945 -0.305054)
			(end -0.12065 -0.305054)
			(stroke
				(width 0.1)
				(type default)
			)
			(layer "F.Fab")
		)
		(fp_line
			(start -0.67945 0.3048)
			(end -0.67945 -0.305054)
			(stroke
				(width 0.1)
				(type default)
			)
			(layer "F.Fab")
		)
		(fp_line
			(start -0.12065 -0.305054)
			(end -0.12065 -0.2794)
			(stroke
				(width 0.1)
				(type default)
			)
			(layer "F.Fab")
		)
		(fp_line
			(start -0.12065 -0.2794)
			(end 0.12065 -0.2794)
			(stroke
				(width 0.1)
				(type default)
			)
			(layer "F.Fab")
		)
		(fp_line
			(start -0.12065 0.2794)
			(end -0.12065 0.3048)
			(stroke
				(width 0.1)
				(type default)
			)
			(layer "F.Fab")
		)
		(fp_line
			(start -0.12065 0.3048)
			(end -0.67945 0.3048)
			(stroke
				(width 0.1)
				(type default)
			)
			(layer "F.Fab")
		)
		(fp_line
			(start 0.120396 0.2794)
			(end -0.12065 0.2794)
			(stroke
				(width 0.1)
				(type default)
			)
			(layer "F.Fab")
		)
		(fp_line
			(start 0.120396 0.3048)
			(end 0.120396 0.2794)
			(stroke
				(width 0.1)
				(type default)
			)
			(layer "F.Fab")
		)
		(fp_line
			(start 0.12065 -0.3048)
			(end 0.67945 -0.3048)
			(stroke
				(width 0.1)
				(type default)
			)
			(layer "F.Fab")
		)
		(fp_line
			(start 0.12065 -0.2794)
			(end 0.12065 -0.3048)
			(stroke
				(width 0.1)
				(type default)
			)
			(layer "F.Fab")
		)
		(fp_line
			(start 0.67945 -0.3048)
			(end 0.67945 0.3048)
			(stroke
				(width 0.1)
				(type default)
			)
			(layer "F.Fab")
		)
		(fp_line
			(start 0.67945 0.3048)
			(end 0.120396 0.3048)
			(stroke
				(width 0.1)
				(type default)
			)
			(layer "F.Fab")
		)
		(pad "1" smd circle
			(at -0.40005 0)
			(size 0 0)
			(layers "F.Cu" "F.Mask" "F.Paste")
			(net "PEX3_SYS_ERR_N_G")
		)
		(pad "2" smd circle
			(at 0.40005 0)
			(size 0 0)
			(layers "F.Cu" "F.Mask" "F.Paste")
			(net "P3V3_AUX")
		)
	)
	(footprint ""
		(layer "F.Cu")
		(at 126.816612 -162.003994 90)
		(property "Reference" "PC632"
			(at 0 0 90)
			(layer "F.SilkS")
			(hide yes)
			(effects
				(font
					(size 1.27 1.27)
				)
			)
		)
		(property "Value" ""
			(at 0 0 90)
			(layer "F.Fab")
			(effects
				(font
					(size 1.27 1.27)
				)
			)
		)
		(duplicate_pad_numbers_are_jumpers no)
		(fp_line
			(start 0.7874 -0.4064)
			(end 0.7874 0.4064)
			(stroke
				(width 0.1524)
				(type default)
			)
			(layer "F.SilkS")
		)
		(fp_line
			(start -0.7874 -0.4064)
			(end 0.7874 -0.4064)
			(stroke
				(width 0.1524)
				(type default)
			)
			(layer "F.SilkS")
		)
		(fp_line
			(start 0.7874 0.4064)
			(end -0.7874 0.4064)
			(stroke
				(width 0.1524)
				(type default)
			)
			(layer "F.SilkS")
		)
		(fp_line
			(start -0.7874 0.4064)
			(end -0.7874 -0.4064)
			(stroke
				(width 0.1524)
				(type default)
			)
			(layer "F.SilkS")
		)
		(fp_line
			(start -0.12065 -0.305054)
			(end -0.12065 -0.2794)
			(stroke
				(width 0.1)
				(type default)
			)
			(layer "F.Fab")
		)
		(fp_line
			(start -0.67945 -0.305054)
			(end -0.12065 -0.305054)
			(stroke
				(width 0.1)
				(type default)
			)
			(layer "F.Fab")
		)
		(fp_line
			(start 0.67945 -0.3048)
			(end 0.67945 0.3048)
			(stroke
				(width 0.1)
				(type default)
			)
			(layer "F.Fab")
		)
		(fp_line
			(start 0.12065 -0.3048)
			(end 0.67945 -0.3048)
			(stroke
				(width 0.1)
				(type default)
			)
			(layer "F.Fab")
		)
		(fp_line
			(start 0.12065 -0.2794)
			(end 0.12065 -0.3048)
			(stroke
				(width 0.1)
				(type default)
			)
			(layer "F.Fab")
		)
		(fp_line
			(start -0.12065 -0.2794)
			(end 0.12065 -0.2794)
			(stroke
				(width 0.1)
				(type default)
			)
			(layer "F.Fab")
		)
		(fp_line
			(start 0.120396 0.2794)
			(end -0.12065 0.2794)
			(stroke
				(width 0.1)
				(type default)
			)
			(layer "F.Fab")
		)
		(fp_line
			(start -0.12065 0.2794)
			(end -0.12065 0.3048)
			(stroke
				(width 0.1)
				(type default)
			)
			(layer "F.Fab")
		)
		(fp_line
			(start 0.67945 0.3048)
			(end 0.120396 0.3048)
			(stroke
				(width 0.1)
				(type default)
			)
			(layer "F.Fab")
		)
		(fp_line
			(start 0.120396 0.3048)
			(end 0.120396 0.2794)
			(stroke
				(width 0.1)
				(type default)
			)
			(layer "F.Fab")
		)
		(fp_line
			(start -0.12065 0.3048)
			(end -0.67945 0.3048)
			(stroke
				(width 0.1)
				(type default)
			)
			(layer "F.Fab")
		)
		(fp_line
			(start -0.67945 0.3048)
			(end -0.67945 -0.305054)
			(stroke
				(width 0.1)
				(type default)
			)
			(layer "F.Fab")
		)
		(pad "1" smd circle
			(at -0.40005 0 90)
			(size 0 0)
			(layers "F.Cu" "F.Mask" "F.Paste")
			(net "P12V_NIC2_CO_SS")
		)
		(pad "2" smd circle
			(at 0.40005 0 90)
			(size 0 0)
			(layers "F.Cu" "F.Mask" "F.Paste")
			(net "GND")
		)
	)
	(footprint ""
		(layer "F.Cu")
		(at 357.367586 -263.57072)
		(property "Reference" "PJ7"
			(at 0 0 0)
			(layer "F.SilkS")
			(hide yes)
			(effects
				(font
					(size 1.27 1.27)
				)
			)
		)
		(property "Value" ""
			(at 0 0 0)
			(layer "F.Fab")
			(effects
				(font
					(size 1.27 1.27)
				)
			)
		)
		(duplicate_pad_numbers_are_jumpers no)
		(pad "1" smd circle
			(at -0.7493 0 90)
			(size 0 0)
			(layers "F.Cu" "F.Mask" "F.Paste")
			(net "SH_P0V8_PEX2_VSEN2_L")
		)
		(pad "2" smd rect
			(at 0.7493 0 270)
			(size 0.7112 0.8128)
			(layers "F.Cu" "F.Mask" "F.Paste")
			(net "SH_P0V8_PEX2_VSEN2_R")
		)
		(zone
			(layer "F.Cu")
			(hatch none 0.5)
			(connect_pads
				(clearance 0)
			)
			(min_thickness 0.25)
			(keepout
				(tracks allowed)
				(vias not_allowed)
				(pads allowed)
				(copperpour not_allowed)
				(footprints allowed)
			)
			(placement
				(enabled no)
				(sheetname "")
			)
			(fill
				(thermal_gap 0.5)
				(thermal_bridge_width 0.5)
				(island_removal_mode 0)
			)
			(polygon
				(pts
					(xy 356.186486 -263.159494) (xy 358.574086 -263.159494) (xy 358.574086 -263.97712) (xy 356.186486 -263.97712)
				)
			)
		)
	)
	(footprint ""
		(layer "F.Cu")
		(at 277.089616 -405.074374 -90)
		(property "Reference" "R1811"
			(at 0 0 270)
			(layer "F.SilkS")
			(hide yes)
			(effects
				(font
					(size 1.27 1.27)
				)
			)
		)
		(property "Value" ""
			(at 0 0 270)
			(layer "F.Fab")
			(effects
				(font
					(size 1.27 1.27)
				)
			)
		)
		(duplicate_pad_numbers_are_jumpers no)
		(fp_line
			(start -0.7874 0.4064)
			(end -0.7874 -0.4064)
			(stroke
				(width 0.1524)
				(type default)
			)
			(layer "F.SilkS")
		)
		(fp_line
			(start 0.7874 0.4064)
			(end -0.7874 0.4064)
			(stroke
				(width 0.1524)
				(type default)
			)
			(layer "F.SilkS")
		)
		(fp_line
			(start -0.7874 -0.4064)
			(end 0.7874 -0.4064)
			(stroke
				(width 0.1524)
				(type default)
			)
			(layer "F.SilkS")
		)
		(fp_line
			(start 0.7874 -0.4064)
			(end 0.7874 0.4064)
			(stroke
				(width 0.1524)
				(type default)
			)
			(layer "F.SilkS")
		)
		(fp_line
			(start -0.67945 0.3048)
			(end -0.67945 -0.305054)
			(stroke
				(width 0.1)
				(type default)
			)
			(layer "F.Fab")
		)
		(fp_line
			(start -0.12065 0.3048)
			(end -0.67945 0.3048)
			(stroke
				(width 0.1)
				(type default)
			)
			(layer "F.Fab")
		)
		(fp_line
			(start 0.120396 0.3048)
			(end 0.120396 0.2794)
			(stroke
				(width 0.1)
				(type default)
			)
			(layer "F.Fab")
		)
		(fp_line
			(start 0.67945 0.3048)
			(end 0.120396 0.3048)
			(stroke
				(width 0.1)
				(type default)
			)
			(layer "F.Fab")
		)
		(fp_line
			(start -0.12065 0.2794)
			(end -0.12065 0.3048)
			(stroke
				(width 0.1)
				(type default)
			)
			(layer "F.Fab")
		)
		(fp_line
			(start 0.120396 0.2794)
			(end -0.12065 0.2794)
			(stroke
				(width 0.1)
				(type default)
			)
			(layer "F.Fab")
		)
		(fp_line
			(start -0.12065 -0.2794)
			(end 0.12065 -0.2794)
			(stroke
				(width 0.1)
				(type default)
			)
			(layer "F.Fab")
		)
		(fp_line
			(start 0.12065 -0.2794)
			(end 0.12065 -0.3048)
			(stroke
				(width 0.1)
				(type default)
			)
			(layer "F.Fab")
		)
		(fp_line
			(start 0.12065 -0.3048)
			(end 0.67945 -0.3048)
			(stroke
				(width 0.1)
				(type default)
			)
			(layer "F.Fab")
		)
		(fp_line
			(start 0.67945 -0.3048)
			(end 0.67945 0.3048)
			(stroke
				(width 0.1)
				(type default)
			)
			(layer "F.Fab")
		)
		(fp_line
			(start -0.67945 -0.305054)
			(end -0.12065 -0.305054)
			(stroke
				(width 0.1)
				(type default)
			)
			(layer "F.Fab")
		)
		(fp_line
			(start -0.12065 -0.305054)
			(end -0.12065 -0.2794)
			(stroke
				(width 0.1)
				(type default)
			)
			(layer "F.Fab")
		)
		(pad "1" smd circle
			(at -0.40005 0 270)
			(size 0 0)
			(layers "F.Cu" "F.Mask" "F.Paste")
			(net "P3V3_AUX")
		)
		(pad "2" smd circle
			(at 0.40005 0 270)
			(size 0 0)
			(layers "F.Cu" "F.Mask" "F.Paste")
			(net "BIC_SYS_READY_R_N")
		)
	)
	(footprint ""
		(layer "F.Cu")
		(at 224.851976 -365.978186 180)
		(property "Reference" "PR41"
			(at 0 0 180)
			(layer "F.SilkS")
			(hide yes)
			(effects
				(font
					(size 1.27 1.27)
				)
			)
		)
		(property "Value" ""
			(at 0 0 180)
			(layer "F.Fab")
			(effects
				(font
					(size 1.27 1.27)
				)
			)
		)
		(duplicate_pad_numbers_are_jumpers no)
		(fp_line
			(start 0.7874 0.4064)
			(end -0.7874 0.4064)
			(stroke
				(width 0.1524)
				(type default)
			)
			(layer "F.SilkS")
		)
		(fp_line
			(start 0.7874 -0.4064)
			(end 0.7874 0.4064)
			(stroke
				(width 0.1524)
				(type default)
			)
			(layer "F.SilkS")
		)
		(fp_line
			(start -0.7874 0.4064)
			(end -0.7874 -0.4064)
			(stroke
				(width 0.1524)
				(type default)
			)
			(layer "F.SilkS")
		)
		(fp_line
			(start -0.7874 -0.4064)
			(end 0.7874 -0.4064)
			(stroke
				(width 0.1524)
				(type default)
			)
			(layer "F.SilkS")
		)
		(fp_line
			(start 0.67945 0.3048)
			(end 0.120396 0.3048)
			(stroke
				(width 0.1)
				(type default)
			)
			(layer "F.Fab")
		)
		(fp_line
			(start 0.67945 -0.3048)
			(end 0.67945 0.3048)
			(stroke
				(width 0.1)
				(type default)
			)
			(layer "F.Fab")
		)
		(fp_line
			(start 0.12065 -0.2794)
			(end 0.12065 -0.3048)
			(stroke
				(width 0.1)
				(type default)
			)
			(layer "F.Fab")
		)
		(fp_line
			(start 0.12065 -0.3048)
			(end 0.67945 -0.3048)
			(stroke
				(width 0.1)
				(type default)
			)
			(layer "F.Fab")
		)
		(fp_line
			(start 0.120396 0.3048)
			(end 0.120396 0.2794)
			(stroke
				(width 0.1)
				(type default)
			)
			(layer "F.Fab")
		)
		(fp_line
			(start 0.120396 0.2794)
			(end -0.12065 0.2794)
			(stroke
				(width 0.1)
				(type default)
			)
			(layer "F.Fab")
		)
		(fp_line
			(start -0.12065 0.3048)
			(end -0.67945 0.3048)
			(stroke
				(width 0.1)
				(type default)
			)
			(layer "F.Fab")
		)
		(fp_line
			(start -0.12065 0.2794)
			(end -0.12065 0.3048)
			(stroke
				(width 0.1)
				(type default)
			)
			(layer "F.Fab")
		)
		(fp_line
			(start -0.12065 -0.2794)
			(end 0.12065 -0.2794)
			(stroke
				(width 0.1)
				(type default)
			)
			(layer "F.Fab")
		)
		(fp_line
			(start -0.12065 -0.305054)
			(end -0.12065 -0.2794)
			(stroke
				(width 0.1)
				(type default)
			)
			(layer "F.Fab")
		)
		(fp_line
			(start -0.67945 0.3048)
			(end -0.67945 -0.305054)
			(stroke
				(width 0.1)
				(type default)
			)
			(layer "F.Fab")
		)
		(fp_line
			(start -0.67945 -0.305054)
			(end -0.12065 -0.305054)
			(stroke
				(width 0.1)
				(type default)
			)
			(layer "F.Fab")
		)
		(pad "1" smd circle
			(at -0.40005 0 180)
			(size 0 0)
			(layers "F.Cu" "F.Mask" "F.Paste")
			(net "HSC_OCREF")
		)
		(pad "2" smd circle
			(at 0.40005 0 180)
			(size 0 0)
			(layers "F.Cu" "F.Mask" "F.Paste")
			(net "AGND_HSC")
		)
	)
	(footprint ""
		(layer "F.Cu")
		(at 211.610448 -212.11286 -90)
		(property "Reference" "R4891"
			(at 0 0 270)
			(layer "F.SilkS")
			(hide yes)
			(effects
				(font
					(size 1.27 1.27)
				)
			)
		)
		(property "Value" ""
			(at 0 0 270)
			(layer "F.Fab")
			(effects
				(font
					(size 1.27 1.27)
				)
			)
		)
		(duplicate_pad_numbers_are_jumpers no)
		(fp_line
			(start -0.7874 0.4064)
			(end -0.7874 -0.4064)
			(stroke
				(width 0.1524)
				(type default)
			)
			(layer "F.SilkS")
		)
		(fp_line
			(start 0.7874 0.4064)
			(end -0.7874 0.4064)
			(stroke
				(width 0.1524)
				(type default)
			)
			(layer "F.SilkS")
		)
		(fp_line
			(start -0.7874 -0.4064)
			(end 0.7874 -0.4064)
			(stroke
				(width 0.1524)
				(type default)
			)
			(layer "F.SilkS")
		)
		(fp_line
			(start 0.7874 -0.4064)
			(end 0.7874 0.4064)
			(stroke
				(width 0.1524)
				(type default)
			)
			(layer "F.SilkS")
		)
		(fp_line
			(start -0.67945 0.3048)
			(end -0.67945 -0.305054)
			(stroke
				(width 0.1)
				(type default)
			)
			(layer "F.Fab")
		)
		(fp_line
			(start -0.12065 0.3048)
			(end -0.67945 0.3048)
			(stroke
				(width 0.1)
				(type default)
			)
			(layer "F.Fab")
		)
		(fp_line
			(start 0.120396 0.3048)
			(end 0.120396 0.2794)
			(stroke
				(width 0.1)
				(type default)
			)
			(layer "F.Fab")
		)
		(fp_line
			(start 0.67945 0.3048)
			(end 0.120396 0.3048)
			(stroke
				(width 0.1)
				(type default)
			)
			(layer "F.Fab")
		)
		(fp_line
			(start -0.12065 0.2794)
			(end -0.12065 0.3048)
			(stroke
				(width 0.1)
				(type default)
			)
			(layer "F.Fab")
		)
		(fp_line
			(start 0.120396 0.2794)
			(end -0.12065 0.2794)
			(stroke
				(width 0.1)
				(type default)
			)
			(layer "F.Fab")
		)
		(fp_line
			(start -0.12065 -0.2794)
			(end 0.12065 -0.2794)
			(stroke
				(width 0.1)
				(type default)
			)
			(layer "F.Fab")
		)
		(fp_line
			(start 0.12065 -0.2794)
			(end 0.12065 -0.3048)
			(stroke
				(width 0.1)
				(type default)
			)
			(layer "F.Fab")
		)
		(fp_line
			(start 0.12065 -0.3048)
			(end 0.67945 -0.3048)
			(stroke
				(width 0.1)
				(type default)
			)
			(layer "F.Fab")
		)
		(fp_line
			(start 0.67945 -0.3048)
			(end 0.67945 0.3048)
			(stroke
				(width 0.1)
				(type default)
			)
			(layer "F.Fab")
		)
		(fp_line
			(start -0.67945 -0.305054)
			(end -0.12065 -0.305054)
			(stroke
				(width 0.1)
				(type default)
			)
			(layer "F.Fab")
		)
		(fp_line
			(start -0.12065 -0.305054)
			(end -0.12065 -0.2794)
			(stroke
				(width 0.1)
				(type default)
			)
			(layer "F.Fab")
		)
		(pad "1" smd circle
			(at -0.40005 0 270)
			(size 0 0)
			(layers "F.Cu" "F.Mask" "F.Paste")
			(net "UART_BIC_DEBUG_R_TX")
		)
		(pad "2" smd circle
			(at 0.40005 0 270)
			(size 0 0)
			(layers "F.Cu" "F.Mask" "F.Paste")
			(net "UART_BIC_DEBUG_TX")
		)
	)
	(footprint ""
		(layer "F.Cu")
		(at 393.8397 -356.244906 90)
		(property "Reference" "C755"
			(at 0 0 90)
			(layer "F.SilkS")
			(hide yes)
			(effects
				(font
					(size 1.27 1.27)
				)
			)
		)
		(property "Value" ""
			(at 0 0 90)
			(layer "F.Fab")
			(effects
				(font
					(size 1.27 1.27)
				)
			)
		)
		(duplicate_pad_numbers_are_jumpers no)
		(fp_line
			(start 0.299974 -0.150114)
			(end 0.299974 0.150114)
			(stroke
				(width 0.1)
				(type default)
			)
			(layer "F.Fab")
		)
		(fp_line
			(start -0.299974 -0.150114)
			(end 0.299974 -0.150114)
			(stroke
				(width 0.1)
				(type default)
			)
			(layer "F.Fab")
		)
		(fp_line
			(start 0.299974 0.150114)
			(end -0.299974 0.150114)
			(stroke
				(width 0.1)
				(type default)
			)
			(layer "F.Fab")
		)
		(fp_line
			(start -0.299974 0.150114)
			(end -0.299974 -0.150114)
			(stroke
				(width 0.1)
				(type default)
			)
			(layer "F.Fab")
		)
		(pad "1" smd rect
			(at -0.2667 0 90)
			(size 0.3048 0.381)
			(layers "F.Cu" "F.Mask" "F.Paste")
			(net "P5E_PEX3_STN5_TX_DN<83>")
		)
		(pad "2" smd rect
			(at 0.2667 0 90)
			(size 0.3048 0.381)
			(layers "F.Cu" "F.Mask" "F.Paste")
			(net "P5E_PEX3_STN5_TX_C_DN<83>")
		)
	)
	(footprint ""
		(layer "F.Cu")
		(at 255.867916 -18.437098)
		(property "Reference" "R1693"
			(at 0 0 0)
			(layer "F.SilkS")
			(hide yes)
			(effects
				(font
					(size 1.27 1.27)
				)
			)
		)
		(property "Value" ""
			(at 0 0 0)
			(layer "F.Fab")
			(effects
				(font
					(size 1.27 1.27)
				)
			)
		)
		(duplicate_pad_numbers_are_jumpers no)
		(fp_line
			(start -0.7874 -0.4064)
			(end 0.7874 -0.4064)
			(stroke
				(width 0.1524)
				(type default)
			)
			(layer "F.SilkS")
		)
		(fp_line
			(start -0.7874 0.4064)
			(end -0.7874 -0.4064)
			(stroke
				(width 0.1524)
				(type default)
			)
			(layer "F.SilkS")
		)
		(fp_line
			(start 0.7874 -0.4064)
			(end 0.7874 0.4064)
			(stroke
				(width 0.1524)
				(type default)
			)
			(layer "F.SilkS")
		)
		(fp_line
			(start 0.7874 0.4064)
			(end -0.7874 0.4064)
			(stroke
				(width 0.1524)
				(type default)
			)
			(layer "F.SilkS")
		)
		(fp_line
			(start -0.67945 -0.305054)
			(end -0.12065 -0.305054)
			(stroke
				(width 0.1)
				(type default)
			)
			(layer "F.Fab")
		)
		(fp_line
			(start -0.67945 0.3048)
			(end -0.67945 -0.305054)
			(stroke
				(width 0.1)
				(type default)
			)
			(layer "F.Fab")
		)
		(fp_line
			(start -0.12065 -0.305054)
			(end -0.12065 -0.2794)
			(stroke
				(width 0.1)
				(type default)
			)
			(layer "F.Fab")
		)
		(fp_line
			(start -0.12065 -0.2794)
			(end 0.12065 -0.2794)
			(stroke
				(width 0.1)
				(type default)
			)
			(layer "F.Fab")
		)
		(fp_line
			(start -0.12065 0.2794)
			(end -0.12065 0.3048)
			(stroke
				(width 0.1)
				(type default)
			)
			(layer "F.Fab")
		)
		(fp_line
			(start -0.12065 0.3048)
			(end -0.67945 0.3048)
			(stroke
				(width 0.1)
				(type default)
			)
			(layer "F.Fab")
		)
		(fp_line
			(start 0.120396 0.2794)
			(end -0.12065 0.2794)
			(stroke
				(width 0.1)
				(type default)
			)
			(layer "F.Fab")
		)
		(fp_line
			(start 0.120396 0.3048)
			(end 0.120396 0.2794)
			(stroke
				(width 0.1)
				(type default)
			)
			(layer "F.Fab")
		)
		(fp_line
			(start 0.12065 -0.3048)
			(end 0.67945 -0.3048)
			(stroke
				(width 0.1)
				(type default)
			)
			(layer "F.Fab")
		)
		(fp_line
			(start 0.12065 -0.2794)
			(end 0.12065 -0.3048)
			(stroke
				(width 0.1)
				(type default)
			)
			(layer "F.Fab")
		)
		(fp_line
			(start 0.67945 -0.3048)
			(end 0.67945 0.3048)
			(stroke
				(width 0.1)
				(type default)
			)
			(layer "F.Fab")
		)
		(fp_line
			(start 0.67945 0.3048)
			(end 0.120396 0.3048)
			(stroke
				(width 0.1)
				(type default)
			)
			(layer "F.Fab")
		)
		(pad "1" smd circle
			(at -0.40005 0)
			(size 0 0)
			(layers "F.Cu" "F.Mask" "F.Paste")
			(net "SMB_ISO_SSD8_R_SCL")
		)
		(pad "2" smd circle
			(at 0.40005 0)
			(size 0 0)
			(layers "F.Cu" "F.Mask" "F.Paste")
			(net "SMB_ISO_SSD8_SCL")
		)
	)
	(footprint ""
		(layer "F.Cu")
		(at 204.752194 -112.860836 180)
		(property "Reference" "PC797"
			(at 0 0 180)
			(layer "F.SilkS")
			(hide yes)
			(effects
				(font
					(size 1.27 1.27)
				)
			)
		)
		(property "Value" ""
			(at 0 0 180)
			(layer "F.Fab")
			(effects
				(font
					(size 1.27 1.27)
				)
			)
		)
		(duplicate_pad_numbers_are_jumpers no)
		(fp_line
			(start 0.7874 0.4064)
			(end -0.7874 0.4064)
			(stroke
				(width 0.1524)
				(type default)
			)
			(layer "F.SilkS")
		)
		(fp_line
			(start 0.7874 -0.4064)
			(end 0.7874 0.4064)
			(stroke
				(width 0.1524)
				(type default)
			)
			(layer "F.SilkS")
		)
		(fp_line
			(start -0.7874 0.4064)
			(end -0.7874 -0.4064)
			(stroke
				(width 0.1524)
				(type default)
			)
			(layer "F.SilkS")
		)
		(fp_line
			(start -0.7874 -0.4064)
			(end 0.7874 -0.4064)
			(stroke
				(width 0.1524)
				(type default)
			)
			(layer "F.SilkS")
		)
		(fp_line
			(start 0.67945 0.3048)
			(end 0.120396 0.3048)
			(stroke
				(width 0.1)
				(type default)
			)
			(layer "F.Fab")
		)
		(fp_line
			(start 0.67945 -0.3048)
			(end 0.67945 0.3048)
			(stroke
				(width 0.1)
				(type default)
			)
			(layer "F.Fab")
		)
		(fp_line
			(start 0.12065 -0.2794)
			(end 0.12065 -0.3048)
			(stroke
				(width 0.1)
				(type default)
			)
			(layer "F.Fab")
		)
		(fp_line
			(start 0.12065 -0.3048)
			(end 0.67945 -0.3048)
			(stroke
				(width 0.1)
				(type default)
			)
			(layer "F.Fab")
		)
		(fp_line
			(start 0.120396 0.3048)
			(end 0.120396 0.2794)
			(stroke
				(width 0.1)
				(type default)
			)
			(layer "F.Fab")
		)
		(fp_line
			(start 0.120396 0.2794)
			(end -0.12065 0.2794)
			(stroke
				(width 0.1)
				(type default)
			)
			(layer "F.Fab")
		)
		(fp_line
			(start -0.12065 0.3048)
			(end -0.67945 0.3048)
			(stroke
				(width 0.1)
				(type default)
			)
			(layer "F.Fab")
		)
		(fp_line
			(start -0.12065 0.2794)
			(end -0.12065 0.3048)
			(stroke
				(width 0.1)
				(type default)
			)
			(layer "F.Fab")
		)
		(fp_line
			(start -0.12065 -0.2794)
			(end 0.12065 -0.2794)
			(stroke
				(width 0.1)
				(type default)
			)
			(layer "F.Fab")
		)
		(fp_line
			(start -0.12065 -0.305054)
			(end -0.12065 -0.2794)
			(stroke
				(width 0.1)
				(type default)
			)
			(layer "F.Fab")
		)
		(fp_line
			(start -0.67945 0.3048)
			(end -0.67945 -0.305054)
			(stroke
				(width 0.1)
				(type default)
			)
			(layer "F.Fab")
		)
		(fp_line
			(start -0.67945 -0.305054)
			(end -0.12065 -0.305054)
			(stroke
				(width 0.1)
				(type default)
			)
			(layer "F.Fab")
		)
		(pad "1" smd circle
			(at -0.40005 0 180)
			(size 0 0)
			(layers "F.Cu" "F.Mask" "F.Paste")
			(net "P3V3_NIC3_CO_DV_DT")
		)
		(pad "2" smd circle
			(at 0.40005 0 180)
			(size 0 0)
			(layers "F.Cu" "F.Mask" "F.Paste")
			(net "GND")
		)
	)
	(footprint ""
		(layer "F.Cu")
		(at 65.370202 -343.952322 90)
		(property "Reference" "C126"
			(at 0 0 90)
			(layer "F.SilkS")
			(hide yes)
			(effects
				(font
					(size 1.27 1.27)
				)
			)
		)
		(property "Value" ""
			(at 0 0 90)
			(layer "F.Fab")
			(effects
				(font
					(size 1.27 1.27)
				)
			)
		)
		(duplicate_pad_numbers_are_jumpers no)
		(fp_line
			(start 0.299974 -0.150114)
			(end 0.299974 0.150114)
			(stroke
				(width 0.1)
				(type default)
			)
			(layer "F.Fab")
		)
		(fp_line
			(start -0.299974 -0.150114)
			(end 0.299974 -0.150114)
			(stroke
				(width 0.1)
				(type default)
			)
			(layer "F.Fab")
		)
		(fp_line
			(start 0.299974 0.150114)
			(end -0.299974 0.150114)
			(stroke
				(width 0.1)
				(type default)
			)
			(layer "F.Fab")
		)
		(fp_line
			(start -0.299974 0.150114)
			(end -0.299974 -0.150114)
			(stroke
				(width 0.1)
				(type default)
			)
			(layer "F.Fab")
		)
		(pad "1" smd rect
			(at -0.2667 0 90)
			(size 0.3048 0.381)
			(layers "F.Cu" "F.Mask" "F.Paste")
			(net "P5E_PEX0_STN5_TX_DN<81>")
		)
		(pad "2" smd rect
			(at 0.2667 0 90)
			(size 0.3048 0.381)
			(layers "F.Cu" "F.Mask" "F.Paste")
			(net "P5E_PEX0_STN5_TX_C_DN<81>")
		)
	)
	(footprint ""
		(layer "F.Cu")
		(at 318.410844 -61.386974)
		(property "Reference" "R4511"
			(at 0 0 0)
			(layer "F.SilkS")
			(hide yes)
			(effects
				(font
					(size 1.27 1.27)
				)
			)
		)
		(property "Value" ""
			(at 0 0 0)
			(layer "F.Fab")
			(effects
				(font
					(size 1.27 1.27)
				)
			)
		)
		(duplicate_pad_numbers_are_jumpers no)
		(fp_line
			(start -0.7874 -0.4064)
			(end 0.7874 -0.4064)
			(stroke
				(width 0.1524)
				(type default)
			)
			(layer "F.SilkS")
		)
		(fp_line
			(start -0.7874 0.4064)
			(end -0.7874 -0.4064)
			(stroke
				(width 0.1524)
				(type default)
			)
			(layer "F.SilkS")
		)
		(fp_line
			(start 0.7874 -0.4064)
			(end 0.7874 0.4064)
			(stroke
				(width 0.1524)
				(type default)
			)
			(layer "F.SilkS")
		)
		(fp_line
			(start 0.7874 0.4064)
			(end -0.7874 0.4064)
			(stroke
				(width 0.1524)
				(type default)
			)
			(layer "F.SilkS")
		)
		(fp_line
			(start -0.67945 -0.305054)
			(end -0.12065 -0.305054)
			(stroke
				(width 0.1)
				(type default)
			)
			(layer "F.Fab")
		)
		(fp_line
			(start -0.67945 0.3048)
			(end -0.67945 -0.305054)
			(stroke
				(width 0.1)
				(type default)
			)
			(layer "F.Fab")
		)
		(fp_line
			(start -0.12065 -0.305054)
			(end -0.12065 -0.2794)
			(stroke
				(width 0.1)
				(type default)
			)
			(layer "F.Fab")
		)
		(fp_line
			(start -0.12065 -0.2794)
			(end 0.12065 -0.2794)
			(stroke
				(width 0.1)
				(type default)
			)
			(layer "F.Fab")
		)
		(fp_line
			(start -0.12065 0.2794)
			(end -0.12065 0.3048)
			(stroke
				(width 0.1)
				(type default)
			)
			(layer "F.Fab")
		)
		(fp_line
			(start -0.12065 0.3048)
			(end -0.67945 0.3048)
			(stroke
				(width 0.1)
				(type default)
			)
			(layer "F.Fab")
		)
		(fp_line
			(start 0.120396 0.2794)
			(end -0.12065 0.2794)
			(stroke
				(width 0.1)
				(type default)
			)
			(layer "F.Fab")
		)
		(fp_line
			(start 0.120396 0.3048)
			(end 0.120396 0.2794)
			(stroke
				(width 0.1)
				(type default)
			)
			(layer "F.Fab")
		)
		(fp_line
			(start 0.12065 -0.3048)
			(end 0.67945 -0.3048)
			(stroke
				(width 0.1)
				(type default)
			)
			(layer "F.Fab")
		)
		(fp_line
			(start 0.12065 -0.2794)
			(end 0.12065 -0.3048)
			(stroke
				(width 0.1)
				(type default)
			)
			(layer "F.Fab")
		)
		(fp_line
			(start 0.67945 -0.3048)
			(end 0.67945 0.3048)
			(stroke
				(width 0.1)
				(type default)
			)
			(layer "F.Fab")
		)
		(fp_line
			(start 0.67945 0.3048)
			(end 0.120396 0.3048)
			(stroke
				(width 0.1)
				(type default)
			)
			(layer "F.Fab")
		)
		(pad "1" smd circle
			(at -0.40005 0)
			(size 0 0)
			(layers "F.Cu" "F.Mask" "F.Paste")
			(net "PWRGD_P3V3_SSD11")
		)
		(pad "2" smd circle
			(at 0.40005 0)
			(size 0 0)
			(layers "F.Cu" "F.Mask" "F.Paste")
			(net "PWRGD_P3V3_SSD11_R")
		)
	)
	(footprint ""
		(layer "F.Cu")
		(at 55.9816 -157.8356)
		(property "Reference" "R48"
			(at 0 0 0)
			(layer "F.SilkS")
			(hide yes)
			(effects
				(font
					(size 1.27 1.27)
				)
			)
		)
		(property "Value" ""
			(at 0 0 0)
			(layer "F.Fab")
			(effects
				(font
					(size 1.27 1.27)
				)
			)
		)
		(duplicate_pad_numbers_are_jumpers no)
		(fp_line
			(start -0.7874 -0.4064)
			(end 0.7874 -0.4064)
			(stroke
				(width 0.1524)
				(type default)
			)
			(layer "F.SilkS")
		)
		(fp_line
			(start -0.7874 0.4064)
			(end -0.7874 -0.4064)
			(stroke
				(width 0.1524)
				(type default)
			)
			(layer "F.SilkS")
		)
		(fp_line
			(start 0.7874 -0.4064)
			(end 0.7874 0.4064)
			(stroke
				(width 0.1524)
				(type default)
			)
			(layer "F.SilkS")
		)
		(fp_line
			(start 0.7874 0.4064)
			(end -0.7874 0.4064)
			(stroke
				(width 0.1524)
				(type default)
			)
			(layer "F.SilkS")
		)
		(fp_line
			(start -0.67945 -0.305054)
			(end -0.12065 -0.305054)
			(stroke
				(width 0.1)
				(type default)
			)
			(layer "F.Fab")
		)
		(fp_line
			(start -0.67945 0.3048)
			(end -0.67945 -0.305054)
			(stroke
				(width 0.1)
				(type default)
			)
			(layer "F.Fab")
		)
		(fp_line
			(start -0.12065 -0.305054)
			(end -0.12065 -0.2794)
			(stroke
				(width 0.1)
				(type default)
			)
			(layer "F.Fab")
		)
		(fp_line
			(start -0.12065 -0.2794)
			(end 0.12065 -0.2794)
			(stroke
				(width 0.1)
				(type default)
			)
			(layer "F.Fab")
		)
		(fp_line
			(start -0.12065 0.2794)
			(end -0.12065 0.3048)
			(stroke
				(width 0.1)
				(type default)
			)
			(layer "F.Fab")
		)
		(fp_line
			(start -0.12065 0.3048)
			(end -0.67945 0.3048)
			(stroke
				(width 0.1)
				(type default)
			)
			(layer "F.Fab")
		)
		(fp_line
			(start 0.120396 0.2794)
			(end -0.12065 0.2794)
			(stroke
				(width 0.1)
				(type default)
			)
			(layer "F.Fab")
		)
		(fp_line
			(start 0.120396 0.3048)
			(end 0.120396 0.2794)
			(stroke
				(width 0.1)
				(type default)
			)
			(layer "F.Fab")
		)
		(fp_line
			(start 0.12065 -0.3048)
			(end 0.67945 -0.3048)
			(stroke
				(width 0.1)
				(type default)
			)
			(layer "F.Fab")
		)
		(fp_line
			(start 0.12065 -0.2794)
			(end 0.12065 -0.3048)
			(stroke
				(width 0.1)
				(type default)
			)
			(layer "F.Fab")
		)
		(fp_line
			(start 0.67945 -0.3048)
			(end 0.67945 0.3048)
			(stroke
				(width 0.1)
				(type default)
			)
			(layer "F.Fab")
		)
		(fp_line
			(start 0.67945 0.3048)
			(end 0.120396 0.3048)
			(stroke
				(width 0.1)
				(type default)
			)
			(layer "F.Fab")
		)
		(pad "1" smd circle
			(at -0.40005 0)
			(size 0 0)
			(layers "F.Cu" "F.Mask" "F.Paste")
			(net "RST_NIC0_PERST3_R_N")
		)
		(pad "2" smd circle
			(at 0.40005 0)
			(size 0 0)
			(layers "F.Cu" "F.Mask" "F.Paste")
			(net "RST_HP_NIC0_BUF_N")
		)
	)
	(footprint ""
		(layer "F.Cu")
		(at 239.416844 -377.863608 -90)
		(property "Reference" "PR6001"
			(at 0.399288 2.541778 90)
			(unlocked yes)
			(layer "F.SilkS")
			(effects
				(font
					(size 0.7874 0.5842)
					(thickness 0.1524)
				)
				(justify left)
			)
		)
		(property "Value" ""
			(at 0 0 270)
			(layer "F.Fab")
			(effects
				(font
					(size 1.27 1.27)
				)
			)
		)
		(duplicate_pad_numbers_are_jumpers no)
		(fp_line
			(start -4.0386 1.7526)
			(end -4.0386 -1.7526)
			(stroke
				(width 0.1524)
				(type default)
			)
			(layer "F.SilkS")
		)
		(fp_line
			(start 4.0386 1.7526)
			(end -4.0386 1.7526)
			(stroke
				(width 0.1524)
				(type default)
			)
			(layer "F.SilkS")
		)
		(fp_line
			(start -4.0386 -1.7526)
			(end 4.0386 -1.7526)
			(stroke
				(width 0.1524)
				(type default)
			)
			(layer "F.SilkS")
		)
		(fp_line
			(start 4.0386 -1.7526)
			(end 4.0386 1.7526)
			(stroke
				(width 0.1524)
				(type default)
			)
			(layer "F.SilkS")
		)
		(fp_line
			(start -4.0386 1.7526)
			(end -4.0386 -1.7526)
			(stroke
				(width 0.1)
				(type default)
			)
			(layer "F.Fab")
		)
		(fp_line
			(start 4.0386 1.7526)
			(end -4.0386 1.7526)
			(stroke
				(width 0.1)
				(type default)
			)
			(layer "F.Fab")
		)
		(fp_line
			(start -4.0386 -1.7526)
			(end 4.0386 -1.7526)
			(stroke
				(width 0.1)
				(type default)
			)
			(layer "F.Fab")
		)
		(fp_line
			(start 4.0386 -1.7526)
			(end 4.0386 1.7526)
			(stroke
				(width 0.1)
				(type default)
			)
			(layer "F.Fab")
		)
		(pad "1" smd circle
			(at -3.700018 0 180)
			(size 0 0)
			(layers "F.Cu" "F.Mask" "F.Paste")
			(net "P12V_STBY")
		)
		(pad "2" smd circle
			(at 3.700018 0)
			(size 0 0)
			(layers "F.Cu" "F.Mask" "F.Paste")
			(net "P12V_STBY_R1")
		)
		(pad "3" smd rect
			(at -2.70002 0)
			(size 0.4064 1.1176)
			(layers "F.Cu" "F.Mask" "F.Paste")
			(net "P12V_HSC_SENSE1_P")
		)
		(pad "4" smd rect
			(at 2.70002 0)
			(size 0.4064 1.1176)
			(layers "F.Cu" "F.Mask" "F.Paste")
			(net "P12V_HSC_SENSE1_N")
		)
	)
	(footprint ""
		(layer "F.Cu")
		(at 406.41905 -59.574684 90)
		(property "Reference" "PC588"
			(at 0 0 90)
			(layer "F.SilkS")
			(hide yes)
			(effects
				(font
					(size 1.27 1.27)
				)
			)
		)
		(property "Value" ""
			(at 0 0 90)
			(layer "F.Fab")
			(effects
				(font
					(size 1.27 1.27)
				)
			)
		)
		(duplicate_pad_numbers_are_jumpers no)
		(fp_line
			(start 0.7874 -0.4064)
			(end 0.7874 0.4064)
			(stroke
				(width 0.1524)
				(type default)
			)
			(layer "F.SilkS")
		)
		(fp_line
			(start -0.7874 -0.4064)
			(end 0.7874 -0.4064)
			(stroke
				(width 0.1524)
				(type default)
			)
			(layer "F.SilkS")
		)
		(fp_line
			(start 0.7874 0.4064)
			(end -0.7874 0.4064)
			(stroke
				(width 0.1524)
				(type default)
			)
			(layer "F.SilkS")
		)
		(fp_line
			(start -0.7874 0.4064)
			(end -0.7874 -0.4064)
			(stroke
				(width 0.1524)
				(type default)
			)
			(layer "F.SilkS")
		)
		(fp_line
			(start -0.12065 -0.305054)
			(end -0.12065 -0.2794)
			(stroke
				(width 0.1)
				(type default)
			)
			(layer "F.Fab")
		)
		(fp_line
			(start -0.67945 -0.305054)
			(end -0.12065 -0.305054)
			(stroke
				(width 0.1)
				(type default)
			)
			(layer "F.Fab")
		)
		(fp_line
			(start 0.67945 -0.3048)
			(end 0.67945 0.3048)
			(stroke
				(width 0.1)
				(type default)
			)
			(layer "F.Fab")
		)
		(fp_line
			(start 0.12065 -0.3048)
			(end 0.67945 -0.3048)
			(stroke
				(width 0.1)
				(type default)
			)
			(layer "F.Fab")
		)
		(fp_line
			(start 0.12065 -0.2794)
			(end 0.12065 -0.3048)
			(stroke
				(width 0.1)
				(type default)
			)
			(layer "F.Fab")
		)
		(fp_line
			(start -0.12065 -0.2794)
			(end 0.12065 -0.2794)
			(stroke
				(width 0.1)
				(type default)
			)
			(layer "F.Fab")
		)
		(fp_line
			(start 0.120396 0.2794)
			(end -0.12065 0.2794)
			(stroke
				(width 0.1)
				(type default)
			)
			(layer "F.Fab")
		)
		(fp_line
			(start -0.12065 0.2794)
			(end -0.12065 0.3048)
			(stroke
				(width 0.1)
				(type default)
			)
			(layer "F.Fab")
		)
		(fp_line
			(start 0.67945 0.3048)
			(end 0.120396 0.3048)
			(stroke
				(width 0.1)
				(type default)
			)
			(layer "F.Fab")
		)
		(fp_line
			(start 0.120396 0.3048)
			(end 0.120396 0.2794)
			(stroke
				(width 0.1)
				(type default)
			)
			(layer "F.Fab")
		)
		(fp_line
			(start -0.12065 0.3048)
			(end -0.67945 0.3048)
			(stroke
				(width 0.1)
				(type default)
			)
			(layer "F.Fab")
		)
		(fp_line
			(start -0.67945 0.3048)
			(end -0.67945 -0.305054)
			(stroke
				(width 0.1)
				(type default)
			)
			(layer "F.Fab")
		)
		(pad "1" smd circle
			(at -0.40005 0 90)
			(size 0 0)
			(layers "F.Cu" "F.Mask" "F.Paste")
			(net "P5V_AUX")
		)
		(pad "2" smd circle
			(at 0.40005 0 90)
			(size 0 0)
			(layers "F.Cu" "F.Mask" "F.Paste")
			(net "GND")
		)
	)
	(footprint ""
		(layer "F.Cu")
		(at 210.439 -206.375 180)
		(property "Reference" "R1512"
			(at 0 0 180)
			(layer "F.SilkS")
			(hide yes)
			(effects
				(font
					(size 1.27 1.27)
				)
			)
		)
		(property "Value" ""
			(at 0 0 180)
			(layer "F.Fab")
			(effects
				(font
					(size 1.27 1.27)
				)
			)
		)
		(duplicate_pad_numbers_are_jumpers no)
		(fp_line
			(start 0.7874 0.4064)
			(end -0.7874 0.4064)
			(stroke
				(width 0.1524)
				(type default)
			)
			(layer "F.SilkS")
		)
		(fp_line
			(start 0.7874 -0.4064)
			(end 0.7874 0.4064)
			(stroke
				(width 0.1524)
				(type default)
			)
			(layer "F.SilkS")
		)
		(fp_line
			(start -0.7874 0.4064)
			(end -0.7874 -0.4064)
			(stroke
				(width 0.1524)
				(type default)
			)
			(layer "F.SilkS")
		)
		(fp_line
			(start -0.7874 -0.4064)
			(end 0.7874 -0.4064)
			(stroke
				(width 0.1524)
				(type default)
			)
			(layer "F.SilkS")
		)
		(fp_line
			(start 0.67945 0.3048)
			(end 0.120396 0.3048)
			(stroke
				(width 0.1)
				(type default)
			)
			(layer "F.Fab")
		)
		(fp_line
			(start 0.67945 -0.3048)
			(end 0.67945 0.3048)
			(stroke
				(width 0.1)
				(type default)
			)
			(layer "F.Fab")
		)
		(fp_line
			(start 0.12065 -0.2794)
			(end 0.12065 -0.3048)
			(stroke
				(width 0.1)
				(type default)
			)
			(layer "F.Fab")
		)
		(fp_line
			(start 0.12065 -0.3048)
			(end 0.67945 -0.3048)
			(stroke
				(width 0.1)
				(type default)
			)
			(layer "F.Fab")
		)
		(fp_line
			(start 0.120396 0.3048)
			(end 0.120396 0.2794)
			(stroke
				(width 0.1)
				(type default)
			)
			(layer "F.Fab")
		)
		(fp_line
			(start 0.120396 0.2794)
			(end -0.12065 0.2794)
			(stroke
				(width 0.1)
				(type default)
			)
			(layer "F.Fab")
		)
		(fp_line
			(start -0.12065 0.3048)
			(end -0.67945 0.3048)
			(stroke
				(width 0.1)
				(type default)
			)
			(layer "F.Fab")
		)
		(fp_line
			(start -0.12065 0.2794)
			(end -0.12065 0.3048)
			(stroke
				(width 0.1)
				(type default)
			)
			(layer "F.Fab")
		)
		(fp_line
			(start -0.12065 -0.2794)
			(end 0.12065 -0.2794)
			(stroke
				(width 0.1)
				(type default)
			)
			(layer "F.Fab")
		)
		(fp_line
			(start -0.12065 -0.305054)
			(end -0.12065 -0.2794)
			(stroke
				(width 0.1)
				(type default)
			)
			(layer "F.Fab")
		)
		(fp_line
			(start -0.67945 0.3048)
			(end -0.67945 -0.305054)
			(stroke
				(width 0.1)
				(type default)
			)
			(layer "F.Fab")
		)
		(fp_line
			(start -0.67945 -0.305054)
			(end -0.12065 -0.305054)
			(stroke
				(width 0.1)
				(type default)
			)
			(layer "F.Fab")
		)
		(pad "1" smd circle
			(at -0.40005 0 180)
			(size 0 0)
			(layers "F.Cu" "F.Mask" "F.Paste")
			(net "SMB_NIC4_R_SCL")
		)
		(pad "2" smd circle
			(at 0.40005 0 180)
			(size 0 0)
			(layers "F.Cu" "F.Mask" "F.Paste")
			(net "P1V2_AUX")
		)
	)
	(footprint ""
		(layer "F.Cu")
		(at 314.861448 -148.91131 180)
		(property "Reference" "C431"
			(at 0 0 180)
			(layer "F.SilkS")
			(hide yes)
			(effects
				(font
					(size 1.27 1.27)
				)
			)
		)
		(property "Value" ""
			(at 0 0 180)
			(layer "F.Fab")
			(effects
				(font
					(size 1.27 1.27)
				)
			)
		)
		(duplicate_pad_numbers_are_jumpers no)
		(fp_line
			(start 0.299974 0.150114)
			(end -0.299974 0.150114)
			(stroke
				(width 0.1)
				(type default)
			)
			(layer "F.Fab")
		)
		(fp_line
			(start 0.299974 -0.150114)
			(end 0.299974 0.150114)
			(stroke
				(width 0.1)
				(type default)
			)
			(layer "F.Fab")
		)
		(fp_line
			(start -0.299974 0.150114)
			(end -0.299974 -0.150114)
			(stroke
				(width 0.1)
				(type default)
			)
			(layer "F.Fab")
		)
		(fp_line
			(start -0.299974 -0.150114)
			(end 0.299974 -0.150114)
			(stroke
				(width 0.1)
				(type default)
			)
			(layer "F.Fab")
		)
		(pad "1" smd rect
			(at -0.2667 0 180)
			(size 0.3048 0.381)
			(layers "F.Cu" "F.Mask" "F.Paste")
			(net "P5E_PEX2_STN0_TX_DP<11>")
		)
		(pad "2" smd rect
			(at 0.2667 0 180)
			(size 0.3048 0.381)
			(layers "F.Cu" "F.Mask" "F.Paste")
			(net "P5E_PEX2_STN0_TX_C_DP<11>")
		)
	)
	(footprint ""
		(layer "F.Cu")
		(at 184.491884 -194.090798 180)
		(property "Reference" "R471"
			(at 0 0 180)
			(layer "F.SilkS")
			(hide yes)
			(effects
				(font
					(size 1.27 1.27)
				)
			)
		)
		(property "Value" ""
			(at 0 0 180)
			(layer "F.Fab")
			(effects
				(font
					(size 1.27 1.27)
				)
			)
		)
		(duplicate_pad_numbers_are_jumpers no)
		(fp_line
			(start 0.7874 0.4064)
			(end -0.7874 0.4064)
			(stroke
				(width 0.1524)
				(type default)
			)
			(layer "F.SilkS")
		)
		(fp_line
			(start 0.7874 -0.4064)
			(end 0.7874 0.4064)
			(stroke
				(width 0.1524)
				(type default)
			)
			(layer "F.SilkS")
		)
		(fp_line
			(start -0.7874 0.4064)
			(end -0.7874 -0.4064)
			(stroke
				(width 0.1524)
				(type default)
			)
			(layer "F.SilkS")
		)
		(fp_line
			(start -0.7874 -0.4064)
			(end 0.7874 -0.4064)
			(stroke
				(width 0.1524)
				(type default)
			)
			(layer "F.SilkS")
		)
		(fp_line
			(start 0.67945 0.3048)
			(end 0.120396 0.3048)
			(stroke
				(width 0.1)
				(type default)
			)
			(layer "F.Fab")
		)
		(fp_line
			(start 0.67945 -0.3048)
			(end 0.67945 0.3048)
			(stroke
				(width 0.1)
				(type default)
			)
			(layer "F.Fab")
		)
		(fp_line
			(start 0.12065 -0.2794)
			(end 0.12065 -0.3048)
			(stroke
				(width 0.1)
				(type default)
			)
			(layer "F.Fab")
		)
		(fp_line
			(start 0.12065 -0.3048)
			(end 0.67945 -0.3048)
			(stroke
				(width 0.1)
				(type default)
			)
			(layer "F.Fab")
		)
		(fp_line
			(start 0.120396 0.3048)
			(end 0.120396 0.2794)
			(stroke
				(width 0.1)
				(type default)
			)
			(layer "F.Fab")
		)
		(fp_line
			(start 0.120396 0.2794)
			(end -0.12065 0.2794)
			(stroke
				(width 0.1)
				(type default)
			)
			(layer "F.Fab")
		)
		(fp_line
			(start -0.12065 0.3048)
			(end -0.67945 0.3048)
			(stroke
				(width 0.1)
				(type default)
			)
			(layer "F.Fab")
		)
		(fp_line
			(start -0.12065 0.2794)
			(end -0.12065 0.3048)
			(stroke
				(width 0.1)
				(type default)
			)
			(layer "F.Fab")
		)
		(fp_line
			(start -0.12065 -0.2794)
			(end 0.12065 -0.2794)
			(stroke
				(width 0.1)
				(type default)
			)
			(layer "F.Fab")
		)
		(fp_line
			(start -0.12065 -0.305054)
			(end -0.12065 -0.2794)
			(stroke
				(width 0.1)
				(type default)
			)
			(layer "F.Fab")
		)
		(fp_line
			(start -0.67945 0.3048)
			(end -0.67945 -0.305054)
			(stroke
				(width 0.1)
				(type default)
			)
			(layer "F.Fab")
		)
		(fp_line
			(start -0.67945 -0.305054)
			(end -0.12065 -0.305054)
			(stroke
				(width 0.1)
				(type default)
			)
			(layer "F.Fab")
		)
		(pad "1" smd circle
			(at -0.40005 0 180)
			(size 0 0)
			(layers "F.Cu" "F.Mask" "F.Paste")
			(net "SPI_BIC1_MOSI_R2")
		)
		(pad "2" smd circle
			(at 0.40005 0 180)
			(size 0 0)
			(layers "F.Cu" "F.Mask" "F.Paste")
			(net "SPI_BIC1_MOSI_R3")
		)
	)
	(footprint ""
		(layer "F.Cu")
		(at 125.16739 -262.17372 180)
		(property "Reference" "PR77"
			(at 0 0 180)
			(layer "F.SilkS")
			(hide yes)
			(effects
				(font
					(size 1.27 1.27)
				)
			)
		)
		(property "Value" ""
			(at 0 0 180)
			(layer "F.Fab")
			(effects
				(font
					(size 1.27 1.27)
				)
			)
		)
		(duplicate_pad_numbers_are_jumpers no)
		(fp_line
			(start 0.7874 0.4064)
			(end -0.7874 0.4064)
			(stroke
				(width 0.1524)
				(type default)
			)
			(layer "F.SilkS")
		)
		(fp_line
			(start 0.7874 -0.4064)
			(end 0.7874 0.4064)
			(stroke
				(width 0.1524)
				(type default)
			)
			(layer "F.SilkS")
		)
		(fp_line
			(start -0.7874 0.4064)
			(end -0.7874 -0.4064)
			(stroke
				(width 0.1524)
				(type default)
			)
			(layer "F.SilkS")
		)
		(fp_line
			(start -0.7874 -0.4064)
			(end 0.7874 -0.4064)
			(stroke
				(width 0.1524)
				(type default)
			)
			(layer "F.SilkS")
		)
		(fp_line
			(start 0.67945 0.3048)
			(end 0.120396 0.3048)
			(stroke
				(width 0.1)
				(type default)
			)
			(layer "F.Fab")
		)
		(fp_line
			(start 0.67945 -0.3048)
			(end 0.67945 0.3048)
			(stroke
				(width 0.1)
				(type default)
			)
			(layer "F.Fab")
		)
		(fp_line
			(start 0.12065 -0.2794)
			(end 0.12065 -0.3048)
			(stroke
				(width 0.1)
				(type default)
			)
			(layer "F.Fab")
		)
		(fp_line
			(start 0.12065 -0.3048)
			(end 0.67945 -0.3048)
			(stroke
				(width 0.1)
				(type default)
			)
			(layer "F.Fab")
		)
		(fp_line
			(start 0.120396 0.3048)
			(end 0.120396 0.2794)
			(stroke
				(width 0.1)
				(type default)
			)
			(layer "F.Fab")
		)
		(fp_line
			(start 0.120396 0.2794)
			(end -0.12065 0.2794)
			(stroke
				(width 0.1)
				(type default)
			)
			(layer "F.Fab")
		)
		(fp_line
			(start -0.12065 0.3048)
			(end -0.67945 0.3048)
			(stroke
				(width 0.1)
				(type default)
			)
			(layer "F.Fab")
		)
		(fp_line
			(start -0.12065 0.2794)
			(end -0.12065 0.3048)
			(stroke
				(width 0.1)
				(type default)
			)
			(layer "F.Fab")
		)
		(fp_line
			(start -0.12065 -0.2794)
			(end 0.12065 -0.2794)
			(stroke
				(width 0.1)
				(type default)
			)
			(layer "F.Fab")
		)
		(fp_line
			(start -0.12065 -0.305054)
			(end -0.12065 -0.2794)
			(stroke
				(width 0.1)
				(type default)
			)
			(layer "F.Fab")
		)
		(fp_line
			(start -0.67945 0.3048)
			(end -0.67945 -0.305054)
			(stroke
				(width 0.1)
				(type default)
			)
			(layer "F.Fab")
		)
		(fp_line
			(start -0.67945 -0.305054)
			(end -0.12065 -0.305054)
			(stroke
				(width 0.1)
				(type default)
			)
			(layer "F.Fab")
		)
		(pad "1" smd circle
			(at -0.40005 0 180)
			(size 0 0)
			(layers "F.Cu" "F.Mask" "F.Paste")
			(net "SH_P0V8_PEX0_VSEN0_R")
		)
		(pad "2" smd circle
			(at 0.40005 0 180)
			(size 0 0)
			(layers "F.Cu" "F.Mask" "F.Paste")
			(net "P0V8_PEX0_VSEN0")
		)
	)
	(footprint ""
		(layer "F.Cu")
		(at 196.119242 -149.79015 180)
		(property "Reference" "C219"
			(at 0 0 180)
			(layer "F.SilkS")
			(hide yes)
			(effects
				(font
					(size 1.27 1.27)
				)
			)
		)
		(property "Value" ""
			(at 0 0 180)
			(layer "F.Fab")
			(effects
				(font
					(size 1.27 1.27)
				)
			)
		)
		(duplicate_pad_numbers_are_jumpers no)
		(fp_line
			(start 0.299974 0.150114)
			(end -0.299974 0.150114)
			(stroke
				(width 0.1)
				(type default)
			)
			(layer "F.Fab")
		)
		(fp_line
			(start 0.299974 -0.150114)
			(end 0.299974 0.150114)
			(stroke
				(width 0.1)
				(type default)
			)
			(layer "F.Fab")
		)
		(fp_line
			(start -0.299974 0.150114)
			(end -0.299974 -0.150114)
			(stroke
				(width 0.1)
				(type default)
			)
			(layer "F.Fab")
		)
		(fp_line
			(start -0.299974 -0.150114)
			(end 0.299974 -0.150114)
			(stroke
				(width 0.1)
				(type default)
			)
			(layer "F.Fab")
		)
		(pad "1" smd rect
			(at -0.2667 0 180)
			(size 0.3048 0.381)
			(layers "F.Cu" "F.Mask" "F.Paste")
			(net "P5E_PEX1_STN0_TX_DP<12>")
		)
		(pad "2" smd rect
			(at 0.2667 0 180)
			(size 0.3048 0.381)
			(layers "F.Cu" "F.Mask" "F.Paste")
			(net "P5E_PEX1_STN0_TX_C_DP<12>")
		)
	)
	(footprint ""
		(layer "F.Cu")
		(at 198.473822 -27.006296 -90)
		(property "Reference" "PC936"
			(at 0 0 270)
			(layer "F.SilkS")
			(hide yes)
			(effects
				(font
					(size 1.27 1.27)
				)
			)
		)
		(property "Value" ""
			(at 0 0 270)
			(layer "F.Fab")
			(effects
				(font
					(size 1.27 1.27)
				)
			)
		)
		(duplicate_pad_numbers_are_jumpers no)
		(fp_line
			(start -0.7874 0.4064)
			(end -0.7874 -0.4064)
			(stroke
				(width 0.1524)
				(type default)
			)
			(layer "F.SilkS")
		)
		(fp_line
			(start 0.7874 0.4064)
			(end -0.7874 0.4064)
			(stroke
				(width 0.1524)
				(type default)
			)
			(layer "F.SilkS")
		)
		(fp_line
			(start -0.7874 -0.4064)
			(end 0.7874 -0.4064)
			(stroke
				(width 0.1524)
				(type default)
			)
			(layer "F.SilkS")
		)
		(fp_line
			(start 0.7874 -0.4064)
			(end 0.7874 0.4064)
			(stroke
				(width 0.1524)
				(type default)
			)
			(layer "F.SilkS")
		)
		(fp_line
			(start -0.67945 0.3048)
			(end -0.67945 -0.305054)
			(stroke
				(width 0.1)
				(type default)
			)
			(layer "F.Fab")
		)
		(fp_line
			(start -0.12065 0.3048)
			(end -0.67945 0.3048)
			(stroke
				(width 0.1)
				(type default)
			)
			(layer "F.Fab")
		)
		(fp_line
			(start 0.120396 0.3048)
			(end 0.120396 0.2794)
			(stroke
				(width 0.1)
				(type default)
			)
			(layer "F.Fab")
		)
		(fp_line
			(start 0.67945 0.3048)
			(end 0.120396 0.3048)
			(stroke
				(width 0.1)
				(type default)
			)
			(layer "F.Fab")
		)
		(fp_line
			(start -0.12065 0.2794)
			(end -0.12065 0.3048)
			(stroke
				(width 0.1)
				(type default)
			)
			(layer "F.Fab")
		)
		(fp_line
			(start 0.120396 0.2794)
			(end -0.12065 0.2794)
			(stroke
				(width 0.1)
				(type default)
			)
			(layer "F.Fab")
		)
		(fp_line
			(start -0.12065 -0.2794)
			(end 0.12065 -0.2794)
			(stroke
				(width 0.1)
				(type default)
			)
			(layer "F.Fab")
		)
		(fp_line
			(start 0.12065 -0.2794)
			(end 0.12065 -0.3048)
			(stroke
				(width 0.1)
				(type default)
			)
			(layer "F.Fab")
		)
		(fp_line
			(start 0.12065 -0.3048)
			(end 0.67945 -0.3048)
			(stroke
				(width 0.1)
				(type default)
			)
			(layer "F.Fab")
		)
		(fp_line
			(start 0.67945 -0.3048)
			(end 0.67945 0.3048)
			(stroke
				(width 0.1)
				(type default)
			)
			(layer "F.Fab")
		)
		(fp_line
			(start -0.67945 -0.305054)
			(end -0.12065 -0.305054)
			(stroke
				(width 0.1)
				(type default)
			)
			(layer "F.Fab")
		)
		(fp_line
			(start -0.12065 -0.305054)
			(end -0.12065 -0.2794)
			(stroke
				(width 0.1)
				(type default)
			)
			(layer "F.Fab")
		)
		(pad "1" smd circle
			(at -0.40005 0 270)
			(size 0 0)
			(layers "F.Cu" "F.Mask" "F.Paste")
			(net "P3V3_SSD7_CO_MODE")
		)
		(pad "2" smd circle
			(at 0.40005 0 270)
			(size 0 0)
			(layers "F.Cu" "F.Mask" "F.Paste")
			(net "GND")
		)
	)
	(footprint ""
		(layer "F.Cu")
		(at 125.546612 -152.859994 180)
		(property "Reference" "PR6889"
			(at 0 0 180)
			(layer "F.SilkS")
			(hide yes)
			(effects
				(font
					(size 1.27 1.27)
				)
			)
		)
		(property "Value" ""
			(at 0 0 180)
			(layer "F.Fab")
			(effects
				(font
					(size 1.27 1.27)
				)
			)
		)
		(duplicate_pad_numbers_are_jumpers no)
		(fp_line
			(start 1.2954 0.5842)
			(end -1.2954 0.5842)
			(stroke
				(width 0.1524)
				(type default)
			)
			(layer "F.SilkS")
		)
		(fp_line
			(start 1.2954 -0.5842)
			(end 1.2954 0.5842)
			(stroke
				(width 0.1524)
				(type default)
			)
			(layer "F.SilkS")
		)
		(fp_line
			(start -1.2954 0.5842)
			(end -1.2954 -0.5842)
			(stroke
				(width 0.1524)
				(type default)
			)
			(layer "F.SilkS")
		)
		(fp_line
			(start -1.2954 -0.5842)
			(end 1.2954 -0.5842)
			(stroke
				(width 0.1524)
				(type default)
			)
			(layer "F.SilkS")
		)
		(fp_line
			(start 1.1938 0.4064)
			(end 0.8636 0.4064)
			(stroke
				(width 0.1)
				(type default)
			)
			(layer "F.Fab")
		)
		(fp_line
			(start 1.1938 -0.406654)
			(end 1.1938 0.4064)
			(stroke
				(width 0.1)
				(type default)
			)
			(layer "F.Fab")
		)
		(fp_line
			(start 0.8636 0.4572)
			(end -0.8636 0.4572)
			(stroke
				(width 0.1)
				(type default)
			)
			(layer "F.Fab")
		)
		(fp_line
			(start 0.8636 0.4064)
			(end 0.8636 0.4572)
			(stroke
				(width 0.1)
				(type default)
			)
			(layer "F.Fab")
		)
		(fp_line
			(start 0.8636 -0.406654)
			(end 1.1938 -0.406654)
			(stroke
				(width 0.1)
				(type default)
			)
			(layer "F.Fab")
		)
		(fp_line
			(start 0.8636 -0.4572)
			(end 0.8636 -0.406654)
			(stroke
				(width 0.1)
				(type default)
			)
			(layer "F.Fab")
		)
		(fp_line
			(start -0.8636 0.4572)
			(end -0.8636 0.4318)
			(stroke
				(width 0.1)
				(type default)
			)
			(layer "F.Fab")
		)
		(fp_line
			(start -0.8636 0.4318)
			(end -0.8636 0.4064)
			(stroke
				(width 0.1)
				(type default)
			)
			(layer "F.Fab")
		)
		(fp_line
			(start -0.8636 0.4064)
			(end -1.1938 0.4064)
			(stroke
				(width 0.1)
				(type default)
			)
			(layer "F.Fab")
		)
		(fp_line
			(start -0.8636 -0.406654)
			(end -0.8636 -0.4572)
			(stroke
				(width 0.1)
				(type default)
			)
			(layer "F.Fab")
		)
		(fp_line
			(start -0.8636 -0.4572)
			(end 0.8636 -0.4572)
			(stroke
				(width 0.1)
				(type default)
			)
			(layer "F.Fab")
		)
		(fp_line
			(start -1.1938 0.4064)
			(end -1.1938 -0.406654)
			(stroke
				(width 0.1)
				(type default)
			)
			(layer "F.Fab")
		)
		(fp_line
			(start -1.1938 -0.406654)
			(end -0.8636 -0.406654)
			(stroke
				(width 0.1)
				(type default)
			)
			(layer "F.Fab")
		)
		(pad "1" smd rect
			(at -0.7366 0 90)
			(size 0.7112 0.8128)
			(layers "F.Cu" "F.Mask" "F.Paste")
			(net "P12V_NIC2_CO_AVIN_PD")
		)
		(pad "2" smd rect
			(at 0.7366 0 90)
			(size 0.7112 0.8128)
			(layers "F.Cu" "F.Mask" "F.Paste")
			(net "P12V_AUX")
		)
	)
	(footprint ""
		(layer "F.Cu")
		(at 223.679512 -231.416606 -90)
		(property "Reference" "R4547"
			(at 0 0 270)
			(layer "F.SilkS")
			(hide yes)
			(effects
				(font
					(size 1.27 1.27)
				)
			)
		)
		(property "Value" ""
			(at 0 0 270)
			(layer "F.Fab")
			(effects
				(font
					(size 1.27 1.27)
				)
			)
		)
		(duplicate_pad_numbers_are_jumpers no)
		(fp_line
			(start -0.7874 0.4064)
			(end -0.7874 -0.4064)
			(stroke
				(width 0.1524)
				(type default)
			)
			(layer "F.SilkS")
		)
		(fp_line
			(start 0.7874 0.4064)
			(end -0.7874 0.4064)
			(stroke
				(width 0.1524)
				(type default)
			)
			(layer "F.SilkS")
		)
		(fp_line
			(start -0.7874 -0.4064)
			(end 0.7874 -0.4064)
			(stroke
				(width 0.1524)
				(type default)
			)
			(layer "F.SilkS")
		)
		(fp_line
			(start 0.7874 -0.4064)
			(end 0.7874 0.4064)
			(stroke
				(width 0.1524)
				(type default)
			)
			(layer "F.SilkS")
		)
		(fp_line
			(start -0.67945 0.3048)
			(end -0.67945 -0.305054)
			(stroke
				(width 0.1)
				(type default)
			)
			(layer "F.Fab")
		)
		(fp_line
			(start -0.12065 0.3048)
			(end -0.67945 0.3048)
			(stroke
				(width 0.1)
				(type default)
			)
			(layer "F.Fab")
		)
		(fp_line
			(start 0.120396 0.3048)
			(end 0.120396 0.2794)
			(stroke
				(width 0.1)
				(type default)
			)
			(layer "F.Fab")
		)
		(fp_line
			(start 0.67945 0.3048)
			(end 0.120396 0.3048)
			(stroke
				(width 0.1)
				(type default)
			)
			(layer "F.Fab")
		)
		(fp_line
			(start -0.12065 0.2794)
			(end -0.12065 0.3048)
			(stroke
				(width 0.1)
				(type default)
			)
			(layer "F.Fab")
		)
		(fp_line
			(start 0.120396 0.2794)
			(end -0.12065 0.2794)
			(stroke
				(width 0.1)
				(type default)
			)
			(layer "F.Fab")
		)
		(fp_line
			(start -0.12065 -0.2794)
			(end 0.12065 -0.2794)
			(stroke
				(width 0.1)
				(type default)
			)
			(layer "F.Fab")
		)
		(fp_line
			(start 0.12065 -0.2794)
			(end 0.12065 -0.3048)
			(stroke
				(width 0.1)
				(type default)
			)
			(layer "F.Fab")
		)
		(fp_line
			(start 0.12065 -0.3048)
			(end 0.67945 -0.3048)
			(stroke
				(width 0.1)
				(type default)
			)
			(layer "F.Fab")
		)
		(fp_line
			(start 0.67945 -0.3048)
			(end 0.67945 0.3048)
			(stroke
				(width 0.1)
				(type default)
			)
			(layer "F.Fab")
		)
		(fp_line
			(start -0.67945 -0.305054)
			(end -0.12065 -0.305054)
			(stroke
				(width 0.1)
				(type default)
			)
			(layer "F.Fab")
		)
		(fp_line
			(start -0.12065 -0.305054)
			(end -0.12065 -0.2794)
			(stroke
				(width 0.1)
				(type default)
			)
			(layer "F.Fab")
		)
		(pad "1" smd circle
			(at -0.40005 0 270)
			(size 0 0)
			(layers "F.Cu" "F.Mask" "F.Paste")
			(net "GND")
		)
		(pad "2" smd circle
			(at 0.40005 0 270)
			(size 0 0)
			(layers "F.Cu" "F.Mask" "F.Paste")
			(net "REV_ID0")
		)
	)
	(footprint ""
		(layer "F.Cu")
		(at 98.975672 -122.525028)
		(property "Reference" "PC348"
			(at 0 0 0)
			(layer "F.SilkS")
			(hide yes)
			(effects
				(font
					(size 1.27 1.27)
				)
			)
		)
		(property "Value" ""
			(at 0 0 0)
			(layer "F.Fab")
			(effects
				(font
					(size 1.27 1.27)
				)
			)
		)
		(duplicate_pad_numbers_are_jumpers no)
		(fp_line
			(start -0.7874 -0.4064)
			(end 0.7874 -0.4064)
			(stroke
				(width 0.1524)
				(type default)
			)
			(layer "F.SilkS")
		)
		(fp_line
			(start -0.7874 0.4064)
			(end -0.7874 -0.4064)
			(stroke
				(width 0.1524)
				(type default)
			)
			(layer "F.SilkS")
		)
		(fp_line
			(start 0.7874 -0.4064)
			(end 0.7874 0.4064)
			(stroke
				(width 0.1524)
				(type default)
			)
			(layer "F.SilkS")
		)
		(fp_line
			(start 0.7874 0.4064)
			(end -0.7874 0.4064)
			(stroke
				(width 0.1524)
				(type default)
			)
			(layer "F.SilkS")
		)
		(fp_line
			(start -0.67945 -0.305054)
			(end -0.12065 -0.305054)
			(stroke
				(width 0.1)
				(type default)
			)
			(layer "F.Fab")
		)
		(fp_line
			(start -0.67945 0.3048)
			(end -0.67945 -0.305054)
			(stroke
				(width 0.1)
				(type default)
			)
			(layer "F.Fab")
		)
		(fp_line
			(start -0.12065 -0.305054)
			(end -0.12065 -0.2794)
			(stroke
				(width 0.1)
				(type default)
			)
			(layer "F.Fab")
		)
		(fp_line
			(start -0.12065 -0.2794)
			(end 0.12065 -0.2794)
			(stroke
				(width 0.1)
				(type default)
			)
			(layer "F.Fab")
		)
		(fp_line
			(start -0.12065 0.2794)
			(end -0.12065 0.3048)
			(stroke
				(width 0.1)
				(type default)
			)
			(layer "F.Fab")
		)
		(fp_line
			(start -0.12065 0.3048)
			(end -0.67945 0.3048)
			(stroke
				(width 0.1)
				(type default)
			)
			(layer "F.Fab")
		)
		(fp_line
			(start 0.120396 0.2794)
			(end -0.12065 0.2794)
			(stroke
				(width 0.1)
				(type default)
			)
			(layer "F.Fab")
		)
		(fp_line
			(start 0.120396 0.3048)
			(end 0.120396 0.2794)
			(stroke
				(width 0.1)
				(type default)
			)
			(layer "F.Fab")
		)
		(fp_line
			(start 0.12065 -0.3048)
			(end 0.67945 -0.3048)
			(stroke
				(width 0.1)
				(type default)
			)
			(layer "F.Fab")
		)
		(fp_line
			(start 0.12065 -0.2794)
			(end 0.12065 -0.3048)
			(stroke
				(width 0.1)
				(type default)
			)
			(layer "F.Fab")
		)
		(fp_line
			(start 0.67945 -0.3048)
			(end 0.67945 0.3048)
			(stroke
				(width 0.1)
				(type default)
			)
			(layer "F.Fab")
		)
		(fp_line
			(start 0.67945 0.3048)
			(end 0.120396 0.3048)
			(stroke
				(width 0.1)
				(type default)
			)
			(layer "F.Fab")
		)
		(pad "1" smd circle
			(at -0.40005 0)
			(size 0 0)
			(layers "F.Cu" "F.Mask" "F.Paste")
			(net "P5V_AUX")
		)
		(pad "2" smd circle
			(at 0.40005 0)
			(size 0 0)
			(layers "F.Cu" "F.Mask" "F.Paste")
			(net "GND")
		)
	)
	(footprint ""
		(layer "F.Cu")
		(at 101.610922 -245.339616 -90)
		(property "Reference" "C831"
			(at 0 0 270)
			(layer "F.SilkS")
			(hide yes)
			(effects
				(font
					(size 1.27 1.27)
				)
			)
		)
		(property "Value" ""
			(at 0 0 270)
			(layer "F.Fab")
			(effects
				(font
					(size 1.27 1.27)
				)
			)
		)
		(duplicate_pad_numbers_are_jumpers no)
		(fp_line
			(start -0.7874 0.4064)
			(end -0.7874 -0.4064)
			(stroke
				(width 0.1524)
				(type default)
			)
			(layer "F.SilkS")
		)
		(fp_line
			(start 0.7874 0.4064)
			(end -0.7874 0.4064)
			(stroke
				(width 0.1524)
				(type default)
			)
			(layer "F.SilkS")
		)
		(fp_line
			(start -0.7874 -0.4064)
			(end 0.7874 -0.4064)
			(stroke
				(width 0.1524)
				(type default)
			)
			(layer "F.SilkS")
		)
		(fp_line
			(start 0.7874 -0.4064)
			(end 0.7874 0.4064)
			(stroke
				(width 0.1524)
				(type default)
			)
			(layer "F.SilkS")
		)
		(fp_line
			(start -0.67945 0.3048)
			(end -0.67945 -0.305054)
			(stroke
				(width 0.1)
				(type default)
			)
			(layer "F.Fab")
		)
		(fp_line
			(start -0.12065 0.3048)
			(end -0.67945 0.3048)
			(stroke
				(width 0.1)
				(type default)
			)
			(layer "F.Fab")
		)
		(fp_line
			(start 0.120396 0.3048)
			(end 0.120396 0.2794)
			(stroke
				(width 0.1)
				(type default)
			)
			(layer "F.Fab")
		)
		(fp_line
			(start 0.67945 0.3048)
			(end 0.120396 0.3048)
			(stroke
				(width 0.1)
				(type default)
			)
			(layer "F.Fab")
		)
		(fp_line
			(start -0.12065 0.2794)
			(end -0.12065 0.3048)
			(stroke
				(width 0.1)
				(type default)
			)
			(layer "F.Fab")
		)
		(fp_line
			(start 0.120396 0.2794)
			(end -0.12065 0.2794)
			(stroke
				(width 0.1)
				(type default)
			)
			(layer "F.Fab")
		)
		(fp_line
			(start -0.12065 -0.2794)
			(end 0.12065 -0.2794)
			(stroke
				(width 0.1)
				(type default)
			)
			(layer "F.Fab")
		)
		(fp_line
			(start 0.12065 -0.2794)
			(end 0.12065 -0.3048)
			(stroke
				(width 0.1)
				(type default)
			)
			(layer "F.Fab")
		)
		(fp_line
			(start 0.12065 -0.3048)
			(end 0.67945 -0.3048)
			(stroke
				(width 0.1)
				(type default)
			)
			(layer "F.Fab")
		)
		(fp_line
			(start 0.67945 -0.3048)
			(end 0.67945 0.3048)
			(stroke
				(width 0.1)
				(type default)
			)
			(layer "F.Fab")
		)
		(fp_line
			(start -0.67945 -0.305054)
			(end -0.12065 -0.305054)
			(stroke
				(width 0.1)
				(type default)
			)
			(layer "F.Fab")
		)
		(fp_line
			(start -0.12065 -0.305054)
			(end -0.12065 -0.2794)
			(stroke
				(width 0.1)
				(type default)
			)
			(layer "F.Fab")
		)
		(pad "1" smd circle
			(at -0.40005 0 270)
			(size 0 0)
			(layers "F.Cu" "F.Mask" "F.Paste")
			(net "P12V_PEX_P1V8_VIN_P")
		)
		(pad "2" smd circle
			(at 0.40005 0 270)
			(size 0 0)
			(layers "F.Cu" "F.Mask" "F.Paste")
			(net "P12V_PEX_P1V8_VIN_N")
		)
	)
	(footprint ""
		(layer "F.Cu")
		(at 24.342344 -250.070874 -90)
		(property "Reference" "R1161"
			(at 0 0 270)
			(layer "F.SilkS")
			(hide yes)
			(effects
				(font
					(size 1.27 1.27)
				)
			)
		)
		(property "Value" ""
			(at 0 0 270)
			(layer "F.Fab")
			(effects
				(font
					(size 1.27 1.27)
				)
			)
		)
		(duplicate_pad_numbers_are_jumpers no)
		(fp_line
			(start -0.7874 0.4064)
			(end -0.7874 -0.4064)
			(stroke
				(width 0.1524)
				(type default)
			)
			(layer "F.SilkS")
		)
		(fp_line
			(start 0.7874 0.4064)
			(end -0.7874 0.4064)
			(stroke
				(width 0.1524)
				(type default)
			)
			(layer "F.SilkS")
		)
		(fp_line
			(start -0.7874 -0.4064)
			(end 0.7874 -0.4064)
			(stroke
				(width 0.1524)
				(type default)
			)
			(layer "F.SilkS")
		)
		(fp_line
			(start 0.7874 -0.4064)
			(end 0.7874 0.4064)
			(stroke
				(width 0.1524)
				(type default)
			)
			(layer "F.SilkS")
		)
		(fp_line
			(start -0.67945 0.3048)
			(end -0.67945 -0.305054)
			(stroke
				(width 0.1)
				(type default)
			)
			(layer "F.Fab")
		)
		(fp_line
			(start -0.12065 0.3048)
			(end -0.67945 0.3048)
			(stroke
				(width 0.1)
				(type default)
			)
			(layer "F.Fab")
		)
		(fp_line
			(start 0.120396 0.3048)
			(end 0.120396 0.2794)
			(stroke
				(width 0.1)
				(type default)
			)
			(layer "F.Fab")
		)
		(fp_line
			(start 0.67945 0.3048)
			(end 0.120396 0.3048)
			(stroke
				(width 0.1)
				(type default)
			)
			(layer "F.Fab")
		)
		(fp_line
			(start -0.12065 0.2794)
			(end -0.12065 0.3048)
			(stroke
				(width 0.1)
				(type default)
			)
			(layer "F.Fab")
		)
		(fp_line
			(start 0.120396 0.2794)
			(end -0.12065 0.2794)
			(stroke
				(width 0.1)
				(type default)
			)
			(layer "F.Fab")
		)
		(fp_line
			(start -0.12065 -0.2794)
			(end 0.12065 -0.2794)
			(stroke
				(width 0.1)
				(type default)
			)
			(layer "F.Fab")
		)
		(fp_line
			(start 0.12065 -0.2794)
			(end 0.12065 -0.3048)
			(stroke
				(width 0.1)
				(type default)
			)
			(layer "F.Fab")
		)
		(fp_line
			(start 0.12065 -0.3048)
			(end 0.67945 -0.3048)
			(stroke
				(width 0.1)
				(type default)
			)
			(layer "F.Fab")
		)
		(fp_line
			(start 0.67945 -0.3048)
			(end 0.67945 0.3048)
			(stroke
				(width 0.1)
				(type default)
			)
			(layer "F.Fab")
		)
		(fp_line
			(start -0.67945 -0.305054)
			(end -0.12065 -0.305054)
			(stroke
				(width 0.1)
				(type default)
			)
			(layer "F.Fab")
		)
		(fp_line
			(start -0.12065 -0.305054)
			(end -0.12065 -0.2794)
			(stroke
				(width 0.1)
				(type default)
			)
			(layer "F.Fab")
		)
		(pad "1" smd circle
			(at -0.40005 0 270)
			(size 0 0)
			(layers "F.Cu" "F.Mask" "F.Paste")
			(net "PEX0_MODE_SEL9")
		)
		(pad "2" smd circle
			(at 0.40005 0 270)
			(size 0 0)
			(layers "F.Cu" "F.Mask" "F.Paste")
			(net "P1V8_PEX")
		)
	)
	(footprint ""
		(layer "F.Cu")
		(at 72.43445 -30.94609 180)
		(property "Reference" "C85"
			(at 0 0 180)
			(layer "F.SilkS")
			(hide yes)
			(effects
				(font
					(size 1.27 1.27)
				)
			)
		)
		(property "Value" ""
			(at 0 0 180)
			(layer "F.Fab")
			(effects
				(font
					(size 1.27 1.27)
				)
			)
		)
		(duplicate_pad_numbers_are_jumpers no)
		(fp_line
			(start 0.299974 0.150114)
			(end -0.299974 0.150114)
			(stroke
				(width 0.1)
				(type default)
			)
			(layer "F.Fab")
		)
		(fp_line
			(start 0.299974 -0.150114)
			(end 0.299974 0.150114)
			(stroke
				(width 0.1)
				(type default)
			)
			(layer "F.Fab")
		)
		(fp_line
			(start -0.299974 0.150114)
			(end -0.299974 -0.150114)
			(stroke
				(width 0.1)
				(type default)
			)
			(layer "F.Fab")
		)
		(fp_line
			(start -0.299974 -0.150114)
			(end 0.299974 -0.150114)
			(stroke
				(width 0.1)
				(type default)
			)
			(layer "F.Fab")
		)
		(pad "1" smd rect
			(at -0.2667 0 180)
			(size 0.3048 0.381)
			(layers "F.Cu" "F.Mask" "F.Paste")
			(net "P5E_PEX0_STN2_TX_DP<37>")
		)
		(pad "2" smd rect
			(at 0.2667 0 180)
			(size 0.3048 0.381)
			(layers "F.Cu" "F.Mask" "F.Paste")
			(net "P5E_PEX0_STN2_TX_C_DP<37>")
		)
	)
	(footprint ""
		(layer "F.Cu")
		(at 232.06964 -83.718908 180)
		(property "Reference" "R6287"
			(at 0 0 180)
			(layer "F.SilkS")
			(hide yes)
			(effects
				(font
					(size 1.27 1.27)
				)
			)
		)
		(property "Value" ""
			(at 0 0 180)
			(layer "F.Fab")
			(effects
				(font
					(size 1.27 1.27)
				)
			)
		)
		(duplicate_pad_numbers_are_jumpers no)
		(fp_line
			(start 0.7874 0.4064)
			(end -0.001016 0.4064)
			(stroke
				(width 0.1524)
				(type default)
			)
			(layer "F.SilkS")
		)
		(fp_line
			(start 0.7874 -0.4064)
			(end 0.7874 0.4064)
			(stroke
				(width 0.1524)
				(type default)
			)
			(layer "F.SilkS")
		)
		(fp_line
			(start -0.7874 0.4064)
			(end -0.7874 -0.4064)
			(stroke
				(width 0.1524)
				(type default)
			)
			(layer "F.SilkS")
		)
		(fp_line
			(start -0.7874 -0.4064)
			(end 0.7874 -0.4064)
			(stroke
				(width 0.1524)
				(type default)
			)
			(layer "F.SilkS")
		)
		(fp_line
			(start 0.67945 0.3048)
			(end 0.120396 0.3048)
			(stroke
				(width 0.1)
				(type default)
			)
			(layer "F.Fab")
		)
		(fp_line
			(start 0.67945 -0.3048)
			(end 0.67945 0.3048)
			(stroke
				(width 0.1)
				(type default)
			)
			(layer "F.Fab")
		)
		(fp_line
			(start 0.12065 -0.2794)
			(end 0.12065 -0.3048)
			(stroke
				(width 0.1)
				(type default)
			)
			(layer "F.Fab")
		)
		(fp_line
			(start 0.12065 -0.3048)
			(end 0.67945 -0.3048)
			(stroke
				(width 0.1)
				(type default)
			)
			(layer "F.Fab")
		)
		(fp_line
			(start 0.120396 0.3048)
			(end 0.120396 0.2794)
			(stroke
				(width 0.1)
				(type default)
			)
			(layer "F.Fab")
		)
		(fp_line
			(start 0.120396 0.2794)
			(end -0.12065 0.2794)
			(stroke
				(width 0.1)
				(type default)
			)
			(layer "F.Fab")
		)
		(fp_line
			(start -0.12065 0.3048)
			(end -0.67945 0.3048)
			(stroke
				(width 0.1)
				(type default)
			)
			(layer "F.Fab")
		)
		(fp_line
			(start -0.12065 0.2794)
			(end -0.12065 0.3048)
			(stroke
				(width 0.1)
				(type default)
			)
			(layer "F.Fab")
		)
		(fp_line
			(start -0.12065 -0.2794)
			(end 0.12065 -0.2794)
			(stroke
				(width 0.1)
				(type default)
			)
			(layer "F.Fab")
		)
		(fp_line
			(start -0.12065 -0.305054)
			(end -0.12065 -0.2794)
			(stroke
				(width 0.1)
				(type default)
			)
			(layer "F.Fab")
		)
		(fp_line
			(start -0.67945 0.3048)
			(end -0.67945 -0.305054)
			(stroke
				(width 0.1)
				(type default)
			)
			(layer "F.Fab")
		)
		(fp_line
			(start -0.67945 -0.305054)
			(end -0.12065 -0.305054)
			(stroke
				(width 0.1)
				(type default)
			)
			(layer "F.Fab")
		)
		(pad "1" smd rect
			(at -0.40005 0)
			(size 0.4572 0.508)
			(layers "F.Cu" "F.Mask" "F.Paste")
			(net "USB2_FT4232_SDB_DN")
		)
		(pad "2" smd rect
			(at 0.40005 0)
			(size 0.4572 0.508)
			(layers "F.Cu" "F.Mask" "F.Paste")
			(net "GND")
		)
	)
	(footprint ""
		(layer "F.Cu")
		(at 248.134124 -135.77697 -90)
		(property "Reference" "PC310"
			(at 0 0 270)
			(layer "F.SilkS")
			(hide yes)
			(effects
				(font
					(size 1.27 1.27)
				)
			)
		)
		(property "Value" ""
			(at 0 0 270)
			(layer "F.Fab")
			(effects
				(font
					(size 1.27 1.27)
				)
			)
		)
		(duplicate_pad_numbers_are_jumpers no)
		(fp_line
			(start -1.524 0.762)
			(end -1.524 -0.762)
			(stroke
				(width 0.1524)
				(type default)
			)
			(layer "F.SilkS")
		)
		(fp_line
			(start 1.524 0.762)
			(end -1.524 0.762)
			(stroke
				(width 0.1524)
				(type default)
			)
			(layer "F.SilkS")
		)
		(fp_line
			(start -1.524 -0.762)
			(end 1.524 -0.762)
			(stroke
				(width 0.1524)
				(type default)
			)
			(layer "F.SilkS")
		)
		(fp_line
			(start 1.524 -0.762)
			(end 1.524 0.762)
			(stroke
				(width 0.1524)
				(type default)
			)
			(layer "F.SilkS")
		)
		(fp_line
			(start -1.1049 0.724916)
			(end 1.1049 0.724916)
			(stroke
				(width 0.1)
				(type default)
			)
			(layer "F.Fab")
		)
		(fp_line
			(start 1.1049 0.724916)
			(end 1.1049 -0.724916)
			(stroke
				(width 0.1)
				(type default)
			)
			(layer "F.Fab")
		)
		(fp_line
			(start -1.1049 -0.724916)
			(end -1.1049 0.724916)
			(stroke
				(width 0.1)
				(type default)
			)
			(layer "F.Fab")
		)
		(fp_line
			(start 1.1049 -0.724916)
			(end -1.1049 -0.724916)
			(stroke
				(width 0.1)
				(type default)
			)
			(layer "F.Fab")
		)
		(pad "1" smd rect
			(at -0.889 0 90)
			(size 1.016 1.27)
			(layers "F.Cu" "F.Mask" "F.Paste")
			(net "P12V_NIC4_R")
		)
		(pad "2" smd rect
			(at 0.889 0 90)
			(size 1.016 1.27)
			(layers "F.Cu" "F.Mask" "F.Paste")
			(net "GND")
		)
	)
	(footprint ""
		(layer "F.Cu")
		(at 437.949848 -270.89989)
		(property "Reference" "H99"
			(at -4.097274 -9.201658 0)
			(unlocked yes)
			(layer "F.SilkS")
			(effects
				(font
					(size 0.7874 0.5842)
					(thickness 0.1524)
				)
				(justify left)
			)
		)
		(property "Value" ""
			(at 0 0 0)
			(layer "F.Fab")
			(effects
				(font
					(size 1.27 1.27)
				)
			)
		)
		(duplicate_pad_numbers_are_jumpers no)
		(fp_arc
			(start -5.147818 -6.123686)
			(mid 3.377705 -7.252005)
			(end 7.999984 0)
			(stroke
				(width 0.1524)
				(type default)
			)
			(layer "F.SilkS")
		)
		(fp_arc
			(start 7.999984 0)
			(mid -0.158601 7.998349)
			(end -7.993634 -0.317246)
			(stroke
				(width 0.1524)
				(type default)
			)
			(layer "F.SilkS")
		)
		(fp_arc
			(start -5.424424 -5.8801)
			(mid 3.209671 -7.327835)
			(end 7.999984 0)
			(stroke
				(width 0.1524)
				(type default)
			)
			(layer "B.SilkS")
		)
		(fp_arc
			(start 7.999984 0)
			(mid -0.421727 7.988869)
			(end -7.955534 -0.842264)
			(stroke
				(width 0.1524)
				(type default)
			)
			(layer "B.SilkS")
		)
		(fp_circle
			(center 0 0)
			(end 7.999984 0)
			(stroke
				(width 0.1)
				(type default)
			)
			(fill no)
			(layer "B.Fab")
		)
		(fp_circle
			(center 0 0)
			(end 7.999984 0)
			(stroke
				(width 0.1)
				(type default)
			)
			(fill no)
			(layer "F.Fab")
		)
		(pad "" np_thru_hole circle
			(at 0 0)
			(size 4.5212 4.5212)
			(drill 4.5212)
			(layers "*.Cu" "*.Mask")
			(clearance 0.381)
			(thermal_gap 0.381)
		)
		(pad "2" thru_hole circle
			(at 3.6322 0)
			(size 0.762 0.762)
			(drill 0.5588)
			(layers "*.Cu" "*.Mask")
			(remove_unused_layers no)
			(net "GND")
			(clearance 0.1524)
			(thermal_gap 0.1524)
		)
		(pad "3" thru_hole circle
			(at 2.568448 -2.568448)
			(size 0.762 0.762)
			(drill 0.5588)
			(layers "*.Cu" "*.Mask")
			(remove_unused_layers no)
			(net "GND")
			(clearance 0.1524)
			(thermal_gap 0.1524)
		)
		(pad "4" thru_hole circle
			(at 0 -3.6322)
			(size 0.762 0.762)
			(drill 0.5588)
			(layers "*.Cu" "*.Mask")
			(remove_unused_layers no)
			(net "GND")
			(clearance 0.1524)
			(thermal_gap 0.1524)
		)
		(pad "5" thru_hole circle
			(at -2.568448 -2.568448)
			(size 0.762 0.762)
			(drill 0.5588)
			(layers "*.Cu" "*.Mask")
			(remove_unused_layers no)
			(net "GND")
			(clearance 0.1524)
			(thermal_gap 0.1524)
		)
		(pad "6" thru_hole circle
			(at -3.6322 0)
			(size 0.762 0.762)
			(drill 0.5588)
			(layers "*.Cu" "*.Mask")
			(remove_unused_layers no)
			(net "GND")
			(clearance 0.1524)
			(thermal_gap 0.1524)
		)
		(pad "7" thru_hole circle
			(at -2.568448 2.568448)
			(size 0.762 0.762)
			(drill 0.5588)
			(layers "*.Cu" "*.Mask")
			(remove_unused_layers no)
			(net "GND")
			(clearance 0.1524)
			(thermal_gap 0.1524)
		)
		(pad "8" thru_hole circle
			(at 0 3.6322)
			(size 0.762 0.762)
			(drill 0.5588)
			(layers "*.Cu" "*.Mask")
			(remove_unused_layers no)
			(net "GND")
			(clearance 0.1524)
			(thermal_gap 0.1524)
		)
		(pad "9" thru_hole circle
			(at 2.568448 2.568448)
			(size 0.762 0.762)
			(drill 0.5588)
			(layers "*.Cu" "*.Mask")
			(remove_unused_layers no)
			(net "GND")
			(clearance 0.1524)
			(thermal_gap 0.1524)
		)
		(zone
			(layer "F.Cu")
			(hatch none 0.5)
			(connect_pads
				(clearance 0)
			)
			(min_thickness 0.25)
			(keepout
				(tracks not_allowed)
				(vias allowed)
				(pads allowed)
				(copperpour not_allowed)
				(footprints allowed)
			)
			(placement
				(enabled no)
				(sheetname "")
			)
			(fill
				(thermal_gap 0.5)
				(thermal_bridge_width 0.5)
				(island_removal_mode 0)
			)
			(polygon
				(pts
					(arc
						(start 437.949848 -262.899906)
						(mid 429.949864 -270.89989)
						(end 437.949848 -278.899874)
					)
					(arc
						(start 437.949848 -275.64969)
						(mid 433.200048 -270.89989)
						(end 437.949848 -266.15009)
					)
				)
			)
		)
		(zone
			(layer "F.Cu")
			(hatch none 0.5)
			(connect_pads
				(clearance 0)
			)
			(min_thickness 0.25)
			(keepout
				(tracks not_allowed)
				(vias allowed)
				(pads allowed)
				(copperpour not_allowed)
				(footprints allowed)
			)
			(placement
				(enabled no)
				(sheetname "")
			)
			(fill
				(thermal_gap 0.5)
				(thermal_bridge_width 0.5)
				(island_removal_mode 0)
			)
			(polygon
				(pts
					(arc
						(start 437.949848 -262.899906)
						(mid 445.949832 -270.89989)
						(end 437.949848 -278.899874)
					)
					(arc
						(start 437.949848 -275.64969)
						(mid 442.699648 -270.89989)
						(end 437.949848 -266.15009)
					)
				)
			)
		)
		(zone
			(layers "F.Cu" "B.Cu" "In1.Cu" "In2.Cu" "In3.Cu" "In4.Cu" "In5.Cu" "In6.Cu"
				"In7.Cu" "In8.Cu" "In9.Cu" "In10.Cu" "In11.Cu" "In12.Cu" "In13.Cu" "In14.Cu"
				"In15.Cu" "In16.Cu"
			)
			(hatch none 0.5)
			(connect_pads
				(clearance 0)
			)
			(min_thickness 0.25)
			(keepout
				(tracks not_allowed)
				(vias allowed)
				(pads allowed)
				(copperpour not_allowed)
				(footprints allowed)
			)
			(placement
				(enabled no)
				(sheetname "")
			)
			(fill
				(thermal_gap 0.5)
				(thermal_bridge_width 0.5)
				(island_removal_mode 0)
			)
			(polygon
				(pts
					(arc
						(start 440.715908 -270.89989)
						(mid 435.183788 -270.89989)
						(end 440.715908 -270.89989)
					)
				)
			)
		)
		(zone
			(layer "B.Cu")
			(hatch none 0.5)
			(connect_pads
				(clearance 0)
			)
			(min_thickness 0.25)
			(keepout
				(tracks not_allowed)
				(vias allowed)
				(pads allowed)
				(copperpour not_allowed)
				(footprints allowed)
			)
			(placement
				(enabled no)
				(sheetname "")
			)
			(fill
				(thermal_gap 0.5)
				(thermal_bridge_width 0.5)
				(island_removal_mode 0)
			)
			(polygon
				(pts
					(arc
						(start 437.949848 -265.89609)
						(mid 432.946048 -270.89989)
						(end 437.949848 -275.90369)
					)
					(arc
						(start 437.949848 -275.42109)
						(mid 433.428648 -270.89989)
						(end 437.949848 -266.37869)
					)
				)
			)
		)
		(zone
			(layer "B.Cu")
			(hatch none 0.5)
			(connect_pads
				(clearance 0)
			)
			(min_thickness 0.25)
			(keepout
				(tracks not_allowed)
				(vias allowed)
				(pads allowed)
				(copperpour not_allowed)
				(footprints allowed)
			)
			(placement
				(enabled no)
				(sheetname "")
			)
			(fill
				(thermal_gap 0.5)
				(thermal_bridge_width 0.5)
				(island_removal_mode 0)
			)
			(polygon
				(pts
					(arc
						(start 437.949848 -265.89609)
						(mid 442.953648 -270.89989)
						(end 437.949848 -275.90369)
					)
					(arc
						(start 437.949848 -275.42109)
						(mid 442.471048 -270.89989)
						(end 437.949848 -266.37869)
					)
				)
			)
		)
	)
	(footprint ""
		(layer "F.Cu")
		(at 214.040212 -226.711256 180)
		(property "Reference" "R1484"
			(at 0 0 180)
			(layer "F.SilkS")
			(hide yes)
			(effects
				(font
					(size 1.27 1.27)
				)
			)
		)
		(property "Value" ""
			(at 0 0 180)
			(layer "F.Fab")
			(effects
				(font
					(size 1.27 1.27)
				)
			)
		)
		(duplicate_pad_numbers_are_jumpers no)
		(fp_line
			(start 0.7874 0.4064)
			(end -0.7874 0.4064)
			(stroke
				(width 0.1524)
				(type default)
			)
			(layer "F.SilkS")
		)
		(fp_line
			(start 0.7874 -0.4064)
			(end 0.7874 0.4064)
			(stroke
				(width 0.1524)
				(type default)
			)
			(layer "F.SilkS")
		)
		(fp_line
			(start -0.7874 0.4064)
			(end -0.7874 -0.4064)
			(stroke
				(width 0.1524)
				(type default)
			)
			(layer "F.SilkS")
		)
		(fp_line
			(start -0.7874 -0.4064)
			(end 0.7874 -0.4064)
			(stroke
				(width 0.1524)
				(type default)
			)
			(layer "F.SilkS")
		)
		(fp_line
			(start 0.67945 0.3048)
			(end 0.120396 0.3048)
			(stroke
				(width 0.1)
				(type default)
			)
			(layer "F.Fab")
		)
		(fp_line
			(start 0.67945 -0.3048)
			(end 0.67945 0.3048)
			(stroke
				(width 0.1)
				(type default)
			)
			(layer "F.Fab")
		)
		(fp_line
			(start 0.12065 -0.2794)
			(end 0.12065 -0.3048)
			(stroke
				(width 0.1)
				(type default)
			)
			(layer "F.Fab")
		)
		(fp_line
			(start 0.12065 -0.3048)
			(end 0.67945 -0.3048)
			(stroke
				(width 0.1)
				(type default)
			)
			(layer "F.Fab")
		)
		(fp_line
			(start 0.120396 0.3048)
			(end 0.120396 0.2794)
			(stroke
				(width 0.1)
				(type default)
			)
			(layer "F.Fab")
		)
		(fp_line
			(start 0.120396 0.2794)
			(end -0.12065 0.2794)
			(stroke
				(width 0.1)
				(type default)
			)
			(layer "F.Fab")
		)
		(fp_line
			(start -0.12065 0.3048)
			(end -0.67945 0.3048)
			(stroke
				(width 0.1)
				(type default)
			)
			(layer "F.Fab")
		)
		(fp_line
			(start -0.12065 0.2794)
			(end -0.12065 0.3048)
			(stroke
				(width 0.1)
				(type default)
			)
			(layer "F.Fab")
		)
		(fp_line
			(start -0.12065 -0.2794)
			(end 0.12065 -0.2794)
			(stroke
				(width 0.1)
				(type default)
			)
			(layer "F.Fab")
		)
		(fp_line
			(start -0.12065 -0.305054)
			(end -0.12065 -0.2794)
			(stroke
				(width 0.1)
				(type default)
			)
			(layer "F.Fab")
		)
		(fp_line
			(start -0.67945 0.3048)
			(end -0.67945 -0.305054)
			(stroke
				(width 0.1)
				(type default)
			)
			(layer "F.Fab")
		)
		(fp_line
			(start -0.67945 -0.305054)
			(end -0.12065 -0.305054)
			(stroke
				(width 0.1)
				(type default)
			)
			(layer "F.Fab")
		)
		(pad "1" smd circle
			(at -0.40005 0 180)
			(size 0 0)
			(layers "F.Cu" "F.Mask" "F.Paste")
			(net "SMB_NIC2_SDA")
		)
		(pad "2" smd circle
			(at 0.40005 0 180)
			(size 0 0)
			(layers "F.Cu" "F.Mask" "F.Paste")
			(net "SMB_NIC2_R_SDA")
		)
	)
	(footprint ""
		(layer "F.Cu")
		(at 12.964922 -26.785062 180)
		(property "Reference" "J30"
			(at 3.802634 -11.22045 90)
			(unlocked yes)
			(layer "F.SilkS")
			(effects
				(font
					(size 0.7874 0.5842)
					(thickness 0.1524)
				)
			)
		)
		(property "Value" ""
			(at 0 0 180)
			(layer "F.Fab")
			(effects
				(font
					(size 1.27 1.27)
				)
			)
		)
		(duplicate_pad_numbers_are_jumpers no)
		(fp_line
			(start 3.150108 12.115038)
			(end 1.529334 12.115038)
			(stroke
				(width 0.1524)
				(type default)
			)
			(layer "F.SilkS")
		)
		(fp_line
			(start 3.074924 12.014962)
			(end 1.632204 12.014962)
			(stroke
				(width 0.1524)
				(type default)
			)
			(layer "F.SilkS")
		)
		(fp_line
			(start 1.632204 -12.014962)
			(end 3.074924 -12.014962)
			(stroke
				(width 0.1524)
				(type default)
			)
			(layer "F.SilkS")
		)
		(fp_line
			(start 1.529334 -12.115038)
			(end 3.150108 -12.115038)
			(stroke
				(width 0.1524)
				(type default)
			)
			(layer "F.SilkS")
		)
		(fp_line
			(start -1.529334 12.115038)
			(end -3.150108 12.115038)
			(stroke
				(width 0.1524)
				(type default)
			)
			(layer "F.SilkS")
		)
		(fp_line
			(start -1.632204 12.014962)
			(end -3.074924 12.014962)
			(stroke
				(width 0.1524)
				(type default)
			)
			(layer "F.SilkS")
		)
		(fp_line
			(start -3.074924 -12.014962)
			(end -1.632204 -12.014962)
			(stroke
				(width 0.1524)
				(type default)
			)
			(layer "F.SilkS")
		)
		(fp_line
			(start -3.150108 -12.115038)
			(end -1.529334 -12.115038)
			(stroke
				(width 0.1524)
				(type default)
			)
			(layer "F.SilkS")
		)
		(fp_poly
			(pts
				(xy 3.358642 -8.713216) (xy 3.781044 -9.980676) (xy 4.626102 -9.135618)
			)
			(stroke
				(width 0)
				(type default)
			)
			(fill yes)
			(layer "F.SilkS")
		)
		(fp_line
			(start 3.074924 12.014962)
			(end -3.074924 12.014962)
			(stroke
				(width 0.1)
				(type default)
			)
			(layer "F.Fab")
		)
		(fp_line
			(start 3.074924 -12.014962)
			(end 3.074924 12.014962)
			(stroke
				(width 0.1)
				(type default)
			)
			(layer "F.Fab")
		)
		(fp_line
			(start -3.074924 12.014962)
			(end -3.074924 -12.014962)
			(stroke
				(width 0.1)
				(type default)
			)
			(layer "F.Fab")
		)
		(fp_line
			(start -3.074924 -12.014962)
			(end 3.074924 -12.014962)
			(stroke
				(width 0.1)
				(type default)
			)
			(layer "F.Fab")
		)
		(fp_poly
			(pts
				(xy 3.348736 -7.994904) (xy 4.543806 -8.592566) (xy 4.543806 -7.397496)
			)
			(stroke
				(width 0)
				(type default)
			)
			(fill yes)
			(layer "F.Fab")
		)
		(pad "" np_thru_hole circle
			(at -1.75006 -9.815068 90)
			(size 1.1176 1.1176)
			(drill 1.1176)
			(layers "*.Cu" "*.Mask")
			(clearance 0.381)
			(thermal_gap 0.381)
		)
		(pad "" np_thru_hole circle
			(at 0 9.815068 90)
			(size 1.1176 1.1176)
			(drill 1.1176)
			(layers "*.Cu" "*.Mask")
			(clearance 0.381)
			(thermal_gap 0.381)
		)
		(pad "A1" smd rect
			(at 2.29997 -7.994904 90)
			(size 0.381 1.27)
			(layers "F.Cu" "F.Mask" "F.Paste")
			(net "GND")
		)
		(pad "A2" smd rect
			(at 2.29997 -7.394956 90)
			(size 0.381 1.27)
			(layers "F.Cu" "F.Mask" "F.Paste")
			(net "GND")
		)
		(pad "A3" smd rect
			(at 2.29997 -6.795008 90)
			(size 0.381 1.27)
			(layers "F.Cu" "F.Mask" "F.Paste")
			(net "GND")
		)
		(pad "A4" smd rect
			(at 2.29997 -6.19506 90)
			(size 0.381 1.27)
			(layers "F.Cu" "F.Mask" "F.Paste")
			(net "GND")
		)
		(pad "A5" smd rect
			(at 2.29997 -5.595112 90)
			(size 0.381 1.27)
			(layers "F.Cu" "F.Mask" "F.Paste")
			(net "GND")
		)
		(pad "A6" smd rect
			(at 2.29997 -4.99491 90)
			(size 0.381 1.27)
			(layers "F.Cu" "F.Mask" "F.Paste")
			(net "GND")
		)
		(pad "A7" smd rect
			(at 2.29997 -4.394962 90)
			(size 0.381 1.27)
			(layers "F.Cu" "F.Mask" "F.Paste")
			(net "SMB_ISO_SSD0_R_SCL")
		)
		(pad "A8" smd rect
			(at 2.29997 -3.795014 90)
			(size 0.381 1.27)
			(layers "F.Cu" "F.Mask" "F.Paste")
			(net "SMB_ISO_SSD0_R_SDA")
		)
		(pad "A9" smd rect
			(at 2.29997 -3.195066 90)
			(size 0.381 1.27)
			(layers "F.Cu" "F.Mask" "F.Paste")
			(net "RST_SMB_SSD0_ISO_R_N")
		)
		(pad "A10" smd rect
			(at 2.29997 -2.595118 90)
			(size 0.381 1.27)
			(layers "F.Cu" "F.Mask" "F.Paste")
			(net "SSD0_LED_ISO_R_N")
		)
		(pad "A11" smd rect
			(at 2.29997 -1.994916 90)
			(size 0.381 1.27)
			(layers "F.Cu" "F.Mask" "F.Paste")
			(net "PU_CLKREQ0")
		)
		(pad "A12" smd rect
			(at 2.29997 -1.394968 90)
			(size 0.381 1.27)
			(layers "F.Cu" "F.Mask" "F.Paste")
			(net "PRSNT_SSD0_N")
		)
		(pad "A13" smd rect
			(at 2.29997 -0.79502 90)
			(size 0.381 1.27)
			(layers "F.Cu" "F.Mask" "F.Paste")
			(net "GND")
		)
		(pad "A14" smd rect
			(at 2.29997 -0.195072 90)
			(size 0.381 1.27)
			(layers "F.Cu" "F.Mask" "F.Paste")
			(net "Net_8585")
		)
		(pad "A15" smd rect
			(at 2.29997 0.404876 90)
			(size 0.381 1.27)
			(layers "F.Cu" "F.Mask" "F.Paste")
			(net "Net_8584")
		)
		(pad "A16" smd rect
			(at 2.29997 1.005078 90)
			(size 0.381 1.27)
			(layers "F.Cu" "F.Mask" "F.Paste")
			(net "GND")
		)
		(pad "A17" smd rect
			(at 2.29997 1.605026 90)
			(size 0.381 1.27)
			(layers "F.Cu" "F.Mask" "F.Paste")
			(net "P5E_PEX0_STN2_RX_DN<44>")
		)
		(pad "A18" smd rect
			(at 2.29997 2.204974 90)
			(size 0.381 1.27)
			(layers "F.Cu" "F.Mask" "F.Paste")
			(net "P5E_PEX0_STN2_RX_DP<44>")
		)
		(pad "A19" smd rect
			(at 2.29997 2.804922 90)
			(size 0.381 1.27)
			(layers "F.Cu" "F.Mask" "F.Paste")
			(net "GND")
		)
		(pad "A20" smd rect
			(at 2.29997 3.405124 90)
			(size 0.381 1.27)
			(layers "F.Cu" "F.Mask" "F.Paste")
			(net "P5E_PEX0_STN2_RX_DN<45>")
		)
		(pad "A21" smd rect
			(at 2.29997 4.005072 90)
			(size 0.381 1.27)
			(layers "F.Cu" "F.Mask" "F.Paste")
			(net "P5E_PEX0_STN2_RX_DP<45>")
		)
		(pad "A22" smd rect
			(at 2.29997 4.60502 90)
			(size 0.381 1.27)
			(layers "F.Cu" "F.Mask" "F.Paste")
			(net "GND")
		)
		(pad "A23" smd rect
			(at 2.29997 5.204968 90)
			(size 0.381 1.27)
			(layers "F.Cu" "F.Mask" "F.Paste")
			(net "P5E_PEX0_STN2_RX_DN<46>")
		)
		(pad "A24" smd rect
			(at 2.29997 5.804916 90)
			(size 0.381 1.27)
			(layers "F.Cu" "F.Mask" "F.Paste")
			(net "P5E_PEX0_STN2_RX_DP<46>")
		)
		(pad "A25" smd rect
			(at 2.29997 6.405118 90)
			(size 0.381 1.27)
			(layers "F.Cu" "F.Mask" "F.Paste")
			(net "GND")
		)
		(pad "A26" smd rect
			(at 2.29997 7.005066 90)
			(size 0.381 1.27)
			(layers "F.Cu" "F.Mask" "F.Paste")
			(net "P5E_PEX0_STN2_RX_DN<47>")
		)
		(pad "A27" smd rect
			(at 2.29997 7.605014 90)
			(size 0.381 1.27)
			(layers "F.Cu" "F.Mask" "F.Paste")
			(net "P5E_PEX0_STN2_RX_DP<47>")
		)
		(pad "A28" smd rect
			(at 2.29997 8.204962 90)
			(size 0.381 1.27)
			(layers "F.Cu" "F.Mask" "F.Paste")
			(net "GND")
		)
		(pad "B1" smd rect
			(at -2.29997 -7.994904 90)
			(size 0.381 1.27)
			(layers "F.Cu" "F.Mask" "F.Paste")
			(net "P12V_SSD0")
		)
		(pad "B2" smd rect
			(at -2.29997 -7.394956 90)
			(size 0.381 1.27)
			(layers "F.Cu" "F.Mask" "F.Paste")
			(net "P12V_SSD0")
		)
		(pad "B3" smd rect
			(at -2.29997 -6.795008 90)
			(size 0.381 1.27)
			(layers "F.Cu" "F.Mask" "F.Paste")
			(net "P12V_SSD0")
		)
		(pad "B4" smd rect
			(at -2.29997 -6.19506 90)
			(size 0.381 1.27)
			(layers "F.Cu" "F.Mask" "F.Paste")
			(net "P12V_SSD0")
		)
		(pad "B5" smd rect
			(at -2.29997 -5.595112 90)
			(size 0.381 1.27)
			(layers "F.Cu" "F.Mask" "F.Paste")
			(net "P12V_SSD0")
		)
		(pad "B6" smd rect
			(at -2.29997 -4.99491 90)
			(size 0.381 1.27)
			(layers "F.Cu" "F.Mask" "F.Paste")
			(net "P12V_SSD0")
		)
		(pad "B7" smd rect
			(at -2.29997 -4.394962 90)
			(size 0.381 1.27)
			(layers "F.Cu" "F.Mask" "F.Paste")
			(net "Net_8586")
		)
		(pad "B8" smd rect
			(at -2.29997 -3.795014 90)
			(size 0.381 1.27)
			(layers "F.Cu" "F.Mask" "F.Paste")
			(net "Net_8583")
		)
		(pad "B9" smd rect
			(at -2.29997 -3.195066 90)
			(size 0.381 1.27)
			(layers "F.Cu" "F.Mask" "F.Paste")
			(net "DUALPORT_N_SSD0")
		)
		(pad "B10" smd rect
			(at -2.29997 -2.595118 90)
			(size 0.381 1.27)
			(layers "F.Cu" "F.Mask" "F.Paste")
			(net "RST_SSD0_PERST_R_N")
		)
		(pad "B11" smd rect
			(at -2.29997 -1.994916 90)
			(size 0.381 1.27)
			(layers "F.Cu" "F.Mask" "F.Paste")
			(net "P3V3_SSD0")
		)
		(pad "B12" smd rect
			(at -2.29997 -1.394968 90)
			(size 0.381 1.27)
			(layers "F.Cu" "F.Mask" "F.Paste")
			(net "SSD0_PWRDIS_R")
		)
		(pad "B13" smd rect
			(at -2.29997 -0.79502 90)
			(size 0.381 1.27)
			(layers "F.Cu" "F.Mask" "F.Paste")
			(net "GND")
		)
		(pad "B14" smd rect
			(at -2.29997 -0.195072 90)
			(size 0.381 1.27)
			(layers "F.Cu" "F.Mask" "F.Paste")
			(net "CLK_100M_DB800ZL_SSD0_R_DN")
		)
		(pad "B15" smd rect
			(at -2.29997 0.404876 90)
			(size 0.381 1.27)
			(layers "F.Cu" "F.Mask" "F.Paste")
			(net "CLK_100M_DB800ZL_SSD0_R_DP")
		)
		(pad "B16" smd rect
			(at -2.29997 1.005078 90)
			(size 0.381 1.27)
			(layers "F.Cu" "F.Mask" "F.Paste")
			(net "GND")
		)
		(pad "B17" smd rect
			(at -2.29997 1.605026 90)
			(size 0.381 1.27)
			(layers "F.Cu" "F.Mask" "F.Paste")
			(net "P5E_PEX0_STN2_TX_C_DN<44>")
		)
		(pad "B18" smd rect
			(at -2.29997 2.204974 90)
			(size 0.381 1.27)
			(layers "F.Cu" "F.Mask" "F.Paste")
			(net "P5E_PEX0_STN2_TX_C_DP<44>")
		)
		(pad "B19" smd rect
			(at -2.29997 2.804922 90)
			(size 0.381 1.27)
			(layers "F.Cu" "F.Mask" "F.Paste")
			(net "GND")
		)
		(pad "B20" smd rect
			(at -2.29997 3.405124 90)
			(size 0.381 1.27)
			(layers "F.Cu" "F.Mask" "F.Paste")
			(net "P5E_PEX0_STN2_TX_C_DN<45>")
		)
		(pad "B21" smd rect
			(at -2.29997 4.005072 90)
			(size 0.381 1.27)
			(layers "F.Cu" "F.Mask" "F.Paste")
			(net "P5E_PEX0_STN2_TX_C_DP<45>")
		)
		(pad "B22" smd rect
			(at -2.29997 4.60502 90)
			(size 0.381 1.27)
			(layers "F.Cu" "F.Mask" "F.Paste")
			(net "GND")
		)
		(pad "B23" smd rect
			(at -2.29997 5.204968 90)
			(size 0.381 1.27)
			(layers "F.Cu" "F.Mask" "F.Paste")
			(net "P5E_PEX0_STN2_TX_C_DN<46>")
		)
		(pad "B24" smd rect
			(at -2.29997 5.804916 90)
			(size 0.381 1.27)
			(layers "F.Cu" "F.Mask" "F.Paste")
			(net "P5E_PEX0_STN2_TX_C_DP<46>")
		)
		(pad "B25" smd rect
			(at -2.29997 6.405118 90)
			(size 0.381 1.27)
			(layers "F.Cu" "F.Mask" "F.Paste")
			(net "GND")
		)
		(pad "B26" smd rect
			(at -2.29997 7.005066 90)
			(size 0.381 1.27)
			(layers "F.Cu" "F.Mask" "F.Paste")
			(net "P5E_PEX0_STN2_TX_C_DN<47>")
		)
		(pad "B27" smd rect
			(at -2.29997 7.605014 90)
			(size 0.381 1.27)
			(layers "F.Cu" "F.Mask" "F.Paste")
			(net "P5E_PEX0_STN2_TX_C_DP<47>")
		)
		(pad "B28" smd rect
			(at -2.29997 8.204962 90)
			(size 0.381 1.27)
			(layers "F.Cu" "F.Mask" "F.Paste")
			(net "GND")
		)
		(pad "G1" thru_hole oval
			(at 0 -11.364976 90)
			(size 1.6256 3.4798)
			(drill oval 1.1176 2.4638)
			(layers "*.Cu" "*.Mask")
			(remove_unused_layers no)
			(net "GND")
			(clearance 0.127)
			(thermal_gap 0.127)
		)
		(pad "G2" thru_hole oval
			(at 0 11.364976 90)
			(size 1.6256 3.4798)
			(drill oval 1.1176 2.4638)
			(layers "*.Cu" "*.Mask")
			(remove_unused_layers no)
			(net "GND")
			(clearance 0.127)
			(thermal_gap 0.127)
		)
		(zone
			(layer "F.Cu")
			(hatch none 0.5)
			(connect_pads
				(clearance 0)
			)
			(min_thickness 0.25)
			(keepout
				(tracks not_allowed)
				(vias allowed)
				(pads allowed)
				(copperpour not_allowed)
				(footprints allowed)
			)
			(placement
				(enabled no)
				(sheetname "")
			)
			(fill
				(thermal_gap 0.5)
				(thermal_bridge_width 0.5)
				(island_removal_mode 0)
			)
			(polygon
				(pts
					(xy 14.344904 -38.850062) (xy 11.594846 -38.850062) (xy 11.594846 -35.900106) (xy 14.344904 -35.900106)
				)
			)
		)
		(zone
			(layer "F.Cu")
			(hatch none 0.5)
			(connect_pads
				(clearance 0)
			)
			(min_thickness 0.25)
			(keepout
				(tracks not_allowed)
				(vias allowed)
				(pads allowed)
				(copperpour not_allowed)
				(footprints allowed)
			)
			(placement
				(enabled no)
				(sheetname "")
			)
			(fill
				(thermal_gap 0.5)
				(thermal_bridge_width 0.5)
				(island_removal_mode 0)
			)
			(polygon
				(pts
					(xy 15.415006 -17.670018) (xy 11.58494 -17.670018) (xy 11.58494 -14.720062) (xy 15.415006 -14.720062)
				)
			)
		)
		(zone
			(layers "F.Cu" "B.Cu" "In1.Cu" "In2.Cu" "In3.Cu" "In4.Cu" "In5.Cu" "In6.Cu"
				"In7.Cu" "In8.Cu" "In9.Cu" "In10.Cu" "In11.Cu" "In12.Cu" "In13.Cu" "In14.Cu"
				"In15.Cu" "In16.Cu"
			)
			(hatch none 0.5)
			(connect_pads
				(clearance 0)
			)
			(min_thickness 0.25)
			(keepout
				(tracks not_allowed)
				(vias allowed)
				(pads allowed)
				(copperpour not_allowed)
				(footprints allowed)
			)
			(placement
				(enabled no)
				(sheetname "")
			)
			(fill
				(thermal_gap 0.5)
				(thermal_bridge_width 0.5)
				(island_removal_mode 0)
			)
			(polygon
				(pts
					(arc
						(start 13.930122 -36.60013)
						(mid 11.999722 -36.60013)
						(end 13.930122 -36.60013)
					)
				)
			)
		)
		(zone
			(layers "F.Cu" "B.Cu" "In1.Cu" "In2.Cu" "In3.Cu" "In4.Cu" "In5.Cu" "In6.Cu"
				"In7.Cu" "In8.Cu" "In9.Cu" "In10.Cu" "In11.Cu" "In12.Cu" "In13.Cu" "In14.Cu"
				"In15.Cu" "In16.Cu"
			)
			(hatch none 0.5)
			(connect_pads
				(clearance 0)
			)
			(min_thickness 0.25)
			(keepout
				(tracks not_allowed)
				(vias allowed)
				(pads allowed)
				(copperpour not_allowed)
				(footprints allowed)
			)
			(placement
				(enabled no)
				(sheetname "")
			)
			(fill
				(thermal_gap 0.5)
				(thermal_bridge_width 0.5)
				(island_removal_mode 0)
			)
			(polygon
				(pts
					(arc
						(start 15.680182 -16.969994)
						(mid 13.749782 -16.969994)
						(end 15.680182 -16.969994)
					)
				)
			)
		)
	)
	(footprint ""
		(layer "F.Cu")
		(at 312.21934 -146.190208 180)
		(property "Reference" "C434"
			(at 0 0 180)
			(layer "F.SilkS")
			(hide yes)
			(effects
				(font
					(size 1.27 1.27)
				)
			)
		)
		(property "Value" ""
			(at 0 0 180)
			(layer "F.Fab")
			(effects
				(font
					(size 1.27 1.27)
				)
			)
		)
		(duplicate_pad_numbers_are_jumpers no)
		(fp_line
			(start 0.299974 0.150114)
			(end -0.299974 0.150114)
			(stroke
				(width 0.1)
				(type default)
			)
			(layer "F.Fab")
		)
		(fp_line
			(start 0.299974 -0.150114)
			(end 0.299974 0.150114)
			(stroke
				(width 0.1)
				(type default)
			)
			(layer "F.Fab")
		)
		(fp_line
			(start -0.299974 0.150114)
			(end -0.299974 -0.150114)
			(stroke
				(width 0.1)
				(type default)
			)
			(layer "F.Fab")
		)
		(fp_line
			(start -0.299974 -0.150114)
			(end 0.299974 -0.150114)
			(stroke
				(width 0.1)
				(type default)
			)
			(layer "F.Fab")
		)
		(pad "1" smd rect
			(at -0.2667 0 180)
			(size 0.3048 0.381)
			(layers "F.Cu" "F.Mask" "F.Paste")
			(net "P5E_PEX2_STN0_TX_DN<10>")
		)
		(pad "2" smd rect
			(at 0.2667 0 180)
			(size 0.3048 0.381)
			(layers "F.Cu" "F.Mask" "F.Paste")
			(net "P5E_PEX2_STN0_TX_C_DN<10>")
		)
	)
	(footprint ""
		(layer "F.Cu")
		(at 98.947224 -19.33956)
		(property "Reference" "C3899"
			(at 0 0 0)
			(layer "F.SilkS")
			(hide yes)
			(effects
				(font
					(size 1.27 1.27)
				)
			)
		)
		(property "Value" ""
			(at 0 0 0)
			(layer "F.Fab")
			(effects
				(font
					(size 1.27 1.27)
				)
			)
		)
		(duplicate_pad_numbers_are_jumpers no)
		(fp_line
			(start -0.7874 -0.4064)
			(end 0.7874 -0.4064)
			(stroke
				(width 0.1524)
				(type default)
			)
			(layer "F.SilkS")
		)
		(fp_line
			(start -0.7874 0.4064)
			(end -0.7874 -0.4064)
			(stroke
				(width 0.1524)
				(type default)
			)
			(layer "F.SilkS")
		)
		(fp_line
			(start 0.7874 -0.4064)
			(end 0.7874 0.4064)
			(stroke
				(width 0.1524)
				(type default)
			)
			(layer "F.SilkS")
		)
		(fp_line
			(start 0.7874 0.4064)
			(end -0.7874 0.4064)
			(stroke
				(width 0.1524)
				(type default)
			)
			(layer "F.SilkS")
		)
		(fp_line
			(start -0.67945 -0.305054)
			(end -0.12065 -0.305054)
			(stroke
				(width 0.1)
				(type default)
			)
			(layer "F.Fab")
		)
		(fp_line
			(start -0.67945 0.3048)
			(end -0.67945 -0.305054)
			(stroke
				(width 0.1)
				(type default)
			)
			(layer "F.Fab")
		)
		(fp_line
			(start -0.12065 -0.305054)
			(end -0.12065 -0.2794)
			(stroke
				(width 0.1)
				(type default)
			)
			(layer "F.Fab")
		)
		(fp_line
			(start -0.12065 -0.2794)
			(end 0.12065 -0.2794)
			(stroke
				(width 0.1)
				(type default)
			)
			(layer "F.Fab")
		)
		(fp_line
			(start -0.12065 0.2794)
			(end -0.12065 0.3048)
			(stroke
				(width 0.1)
				(type default)
			)
			(layer "F.Fab")
		)
		(fp_line
			(start -0.12065 0.3048)
			(end -0.67945 0.3048)
			(stroke
				(width 0.1)
				(type default)
			)
			(layer "F.Fab")
		)
		(fp_line
			(start 0.120396 0.2794)
			(end -0.12065 0.2794)
			(stroke
				(width 0.1)
				(type default)
			)
			(layer "F.Fab")
		)
		(fp_line
			(start 0.120396 0.3048)
			(end 0.120396 0.2794)
			(stroke
				(width 0.1)
				(type default)
			)
			(layer "F.Fab")
		)
		(fp_line
			(start 0.12065 -0.3048)
			(end 0.67945 -0.3048)
			(stroke
				(width 0.1)
				(type default)
			)
			(layer "F.Fab")
		)
		(fp_line
			(start 0.12065 -0.2794)
			(end 0.12065 -0.3048)
			(stroke
				(width 0.1)
				(type default)
			)
			(layer "F.Fab")
		)
		(fp_line
			(start 0.67945 -0.3048)
			(end 0.67945 0.3048)
			(stroke
				(width 0.1)
				(type default)
			)
			(layer "F.Fab")
		)
		(fp_line
			(start 0.67945 0.3048)
			(end 0.120396 0.3048)
			(stroke
				(width 0.1)
				(type default)
			)
			(layer "F.Fab")
		)
		(pad "1" smd circle
			(at -0.40005 0)
			(size 0 0)
			(layers "F.Cu" "F.Mask" "F.Paste")
			(net "P12V_SSD3")
		)
		(pad "2" smd circle
			(at 0.40005 0)
			(size 0 0)
			(layers "F.Cu" "F.Mask" "F.Paste")
			(net "GND")
		)
	)
	(footprint ""
		(layer "F.Cu")
		(at 95.105728 -242.776248 180)
		(property "Reference" "R817"
			(at 0 0 180)
			(layer "F.SilkS")
			(hide yes)
			(effects
				(font
					(size 1.27 1.27)
				)
			)
		)
		(property "Value" ""
			(at 0 0 180)
			(layer "F.Fab")
			(effects
				(font
					(size 1.27 1.27)
				)
			)
		)
		(duplicate_pad_numbers_are_jumpers no)
		(fp_line
			(start 0.7874 0.4064)
			(end -0.7874 0.4064)
			(stroke
				(width 0.1524)
				(type default)
			)
			(layer "F.SilkS")
		)
		(fp_line
			(start 0.7874 -0.4064)
			(end 0.7874 0.4064)
			(stroke
				(width 0.1524)
				(type default)
			)
			(layer "F.SilkS")
		)
		(fp_line
			(start -0.7874 0.4064)
			(end -0.7874 -0.4064)
			(stroke
				(width 0.1524)
				(type default)
			)
			(layer "F.SilkS")
		)
		(fp_line
			(start -0.7874 -0.4064)
			(end 0.7874 -0.4064)
			(stroke
				(width 0.1524)
				(type default)
			)
			(layer "F.SilkS")
		)
		(fp_line
			(start 0.67945 0.3048)
			(end 0.120396 0.3048)
			(stroke
				(width 0.1)
				(type default)
			)
			(layer "F.Fab")
		)
		(fp_line
			(start 0.67945 -0.3048)
			(end 0.67945 0.3048)
			(stroke
				(width 0.1)
				(type default)
			)
			(layer "F.Fab")
		)
		(fp_line
			(start 0.12065 -0.2794)
			(end 0.12065 -0.3048)
			(stroke
				(width 0.1)
				(type default)
			)
			(layer "F.Fab")
		)
		(fp_line
			(start 0.12065 -0.3048)
			(end 0.67945 -0.3048)
			(stroke
				(width 0.1)
				(type default)
			)
			(layer "F.Fab")
		)
		(fp_line
			(start 0.120396 0.3048)
			(end 0.120396 0.2794)
			(stroke
				(width 0.1)
				(type default)
			)
			(layer "F.Fab")
		)
		(fp_line
			(start 0.120396 0.2794)
			(end -0.12065 0.2794)
			(stroke
				(width 0.1)
				(type default)
			)
			(layer "F.Fab")
		)
		(fp_line
			(start -0.12065 0.3048)
			(end -0.67945 0.3048)
			(stroke
				(width 0.1)
				(type default)
			)
			(layer "F.Fab")
		)
		(fp_line
			(start -0.12065 0.2794)
			(end -0.12065 0.3048)
			(stroke
				(width 0.1)
				(type default)
			)
			(layer "F.Fab")
		)
		(fp_line
			(start -0.12065 -0.2794)
			(end 0.12065 -0.2794)
			(stroke
				(width 0.1)
				(type default)
			)
			(layer "F.Fab")
		)
		(fp_line
			(start -0.12065 -0.305054)
			(end -0.12065 -0.2794)
			(stroke
				(width 0.1)
				(type default)
			)
			(layer "F.Fab")
		)
		(fp_line
			(start -0.67945 0.3048)
			(end -0.67945 -0.305054)
			(stroke
				(width 0.1)
				(type default)
			)
			(layer "F.Fab")
		)
		(fp_line
			(start -0.67945 -0.305054)
			(end -0.12065 -0.305054)
			(stroke
				(width 0.1)
				(type default)
			)
			(layer "F.Fab")
		)
		(pad "1" smd circle
			(at -0.40005 0 180)
			(size 0 0)
			(layers "F.Cu" "F.Mask" "F.Paste")
			(net "PEX_P1V8_ADC_ALERT_N")
		)
		(pad "2" smd circle
			(at 0.40005 0 180)
			(size 0 0)
			(layers "F.Cu" "F.Mask" "F.Paste")
			(net "PEX_ADC_ALERT_N")
		)
	)
	(footprint ""
		(layer "F.Cu")
		(at 365.15167 -124.120656 -90)
		(property "Reference" "PC478"
			(at 0 0 270)
			(layer "F.SilkS")
			(hide yes)
			(effects
				(font
					(size 1.27 1.27)
				)
			)
		)
		(property "Value" ""
			(at 0 0 270)
			(layer "F.Fab")
			(effects
				(font
					(size 1.27 1.27)
				)
			)
		)
		(duplicate_pad_numbers_are_jumpers no)
		(fp_line
			(start -0.7874 0.4064)
			(end -0.7874 -0.4064)
			(stroke
				(width 0.1524)
				(type default)
			)
			(layer "F.SilkS")
		)
		(fp_line
			(start 0.7874 0.4064)
			(end -0.7874 0.4064)
			(stroke
				(width 0.1524)
				(type default)
			)
			(layer "F.SilkS")
		)
		(fp_line
			(start -0.7874 -0.4064)
			(end 0.7874 -0.4064)
			(stroke
				(width 0.1524)
				(type default)
			)
			(layer "F.SilkS")
		)
		(fp_line
			(start 0.7874 -0.4064)
			(end 0.7874 0.4064)
			(stroke
				(width 0.1524)
				(type default)
			)
			(layer "F.SilkS")
		)
		(fp_line
			(start -0.67945 0.3048)
			(end -0.67945 -0.305054)
			(stroke
				(width 0.1)
				(type default)
			)
			(layer "F.Fab")
		)
		(fp_line
			(start -0.12065 0.3048)
			(end -0.67945 0.3048)
			(stroke
				(width 0.1)
				(type default)
			)
			(layer "F.Fab")
		)
		(fp_line
			(start 0.120396 0.3048)
			(end 0.120396 0.2794)
			(stroke
				(width 0.1)
				(type default)
			)
			(layer "F.Fab")
		)
		(fp_line
			(start 0.67945 0.3048)
			(end 0.120396 0.3048)
			(stroke
				(width 0.1)
				(type default)
			)
			(layer "F.Fab")
		)
		(fp_line
			(start -0.12065 0.2794)
			(end -0.12065 0.3048)
			(stroke
				(width 0.1)
				(type default)
			)
			(layer "F.Fab")
		)
		(fp_line
			(start 0.120396 0.2794)
			(end -0.12065 0.2794)
			(stroke
				(width 0.1)
				(type default)
			)
			(layer "F.Fab")
		)
		(fp_line
			(start -0.12065 -0.2794)
			(end 0.12065 -0.2794)
			(stroke
				(width 0.1)
				(type default)
			)
			(layer "F.Fab")
		)
		(fp_line
			(start 0.12065 -0.2794)
			(end 0.12065 -0.3048)
			(stroke
				(width 0.1)
				(type default)
			)
			(layer "F.Fab")
		)
		(fp_line
			(start 0.12065 -0.3048)
			(end 0.67945 -0.3048)
			(stroke
				(width 0.1)
				(type default)
			)
			(layer "F.Fab")
		)
		(fp_line
			(start 0.67945 -0.3048)
			(end 0.67945 0.3048)
			(stroke
				(width 0.1)
				(type default)
			)
			(layer "F.Fab")
		)
		(fp_line
			(start -0.67945 -0.305054)
			(end -0.12065 -0.305054)
			(stroke
				(width 0.1)
				(type default)
			)
			(layer "F.Fab")
		)
		(fp_line
			(start -0.12065 -0.305054)
			(end -0.12065 -0.2794)
			(stroke
				(width 0.1)
				(type default)
			)
			(layer "F.Fab")
		)
		(pad "1" smd circle
			(at -0.40005 0 270)
			(size 0 0)
			(layers "F.Cu" "F.Mask" "F.Paste")
			(net "P3V3_NIC6")
		)
		(pad "2" smd circle
			(at 0.40005 0 270)
			(size 0 0)
			(layers "F.Cu" "F.Mask" "F.Paste")
			(net "GND")
		)
	)
	(footprint ""
		(layer "F.Cu")
		(at 288.029142 -117.5512)
		(property "Reference" "R210"
			(at 0 0 0)
			(layer "F.SilkS")
			(hide yes)
			(effects
				(font
					(size 1.27 1.27)
				)
			)
		)
		(property "Value" ""
			(at 0 0 0)
			(layer "F.Fab")
			(effects
				(font
					(size 1.27 1.27)
				)
			)
		)
		(duplicate_pad_numbers_are_jumpers no)
		(fp_line
			(start -0.7874 -0.4064)
			(end 0.7874 -0.4064)
			(stroke
				(width 0.1524)
				(type default)
			)
			(layer "F.SilkS")
		)
		(fp_line
			(start -0.7874 0.4064)
			(end -0.7874 -0.4064)
			(stroke
				(width 0.1524)
				(type default)
			)
			(layer "F.SilkS")
		)
		(fp_line
			(start 0.7874 -0.4064)
			(end 0.7874 0.4064)
			(stroke
				(width 0.1524)
				(type default)
			)
			(layer "F.SilkS")
		)
		(fp_line
			(start 0.7874 0.4064)
			(end -0.7874 0.4064)
			(stroke
				(width 0.1524)
				(type default)
			)
			(layer "F.SilkS")
		)
		(fp_line
			(start -0.67945 -0.305054)
			(end -0.12065 -0.305054)
			(stroke
				(width 0.1)
				(type default)
			)
			(layer "F.Fab")
		)
		(fp_line
			(start -0.67945 0.3048)
			(end -0.67945 -0.305054)
			(stroke
				(width 0.1)
				(type default)
			)
			(layer "F.Fab")
		)
		(fp_line
			(start -0.12065 -0.305054)
			(end -0.12065 -0.2794)
			(stroke
				(width 0.1)
				(type default)
			)
			(layer "F.Fab")
		)
		(fp_line
			(start -0.12065 -0.2794)
			(end 0.12065 -0.2794)
			(stroke
				(width 0.1)
				(type default)
			)
			(layer "F.Fab")
		)
		(fp_line
			(start -0.12065 0.2794)
			(end -0.12065 0.3048)
			(stroke
				(width 0.1)
				(type default)
			)
			(layer "F.Fab")
		)
		(fp_line
			(start -0.12065 0.3048)
			(end -0.67945 0.3048)
			(stroke
				(width 0.1)
				(type default)
			)
			(layer "F.Fab")
		)
		(fp_line
			(start 0.120396 0.2794)
			(end -0.12065 0.2794)
			(stroke
				(width 0.1)
				(type default)
			)
			(layer "F.Fab")
		)
		(fp_line
			(start 0.120396 0.3048)
			(end 0.120396 0.2794)
			(stroke
				(width 0.1)
				(type default)
			)
			(layer "F.Fab")
		)
		(fp_line
			(start 0.12065 -0.3048)
			(end 0.67945 -0.3048)
			(stroke
				(width 0.1)
				(type default)
			)
			(layer "F.Fab")
		)
		(fp_line
			(start 0.12065 -0.2794)
			(end 0.12065 -0.3048)
			(stroke
				(width 0.1)
				(type default)
			)
			(layer "F.Fab")
		)
		(fp_line
			(start 0.67945 -0.3048)
			(end 0.67945 0.3048)
			(stroke
				(width 0.1)
				(type default)
			)
			(layer "F.Fab")
		)
		(fp_line
			(start 0.67945 0.3048)
			(end 0.120396 0.3048)
			(stroke
				(width 0.1)
				(type default)
			)
			(layer "F.Fab")
		)
		(pad "1" smd circle
			(at -0.40005 0)
			(size 0 0)
			(layers "F.Cu" "F.Mask" "F.Paste")
			(net "PRSNTB1_NIC4_N")
		)
		(pad "2" smd circle
			(at 0.40005 0)
			(size 0 0)
			(layers "F.Cu" "F.Mask" "F.Paste")
			(net "P3V3_AUX")
		)
	)
	(footprint ""
		(layer "F.Cu")
		(at 384.51282 -356.244906 90)
		(property "Reference" "C775"
			(at 0 0 90)
			(layer "F.SilkS")
			(hide yes)
			(effects
				(font
					(size 1.27 1.27)
				)
			)
		)
		(property "Value" ""
			(at 0 0 90)
			(layer "F.Fab")
			(effects
				(font
					(size 1.27 1.27)
				)
			)
		)
		(duplicate_pad_numbers_are_jumpers no)
		(fp_line
			(start 0.299974 -0.150114)
			(end 0.299974 0.150114)
			(stroke
				(width 0.1)
				(type default)
			)
			(layer "F.Fab")
		)
		(fp_line
			(start -0.299974 -0.150114)
			(end 0.299974 -0.150114)
			(stroke
				(width 0.1)
				(type default)
			)
			(layer "F.Fab")
		)
		(fp_line
			(start 0.299974 0.150114)
			(end -0.299974 0.150114)
			(stroke
				(width 0.1)
				(type default)
			)
			(layer "F.Fab")
		)
		(fp_line
			(start -0.299974 0.150114)
			(end -0.299974 -0.150114)
			(stroke
				(width 0.1)
				(type default)
			)
			(layer "F.Fab")
		)
		(pad "1" smd rect
			(at -0.2667 0 90)
			(size 0.3048 0.381)
			(layers "F.Cu" "F.Mask" "F.Paste")
			(net "P5E_PEX3_STN6_TX_DN<105>")
		)
		(pad "2" smd rect
			(at 0.2667 0 90)
			(size 0.3048 0.381)
			(layers "F.Cu" "F.Mask" "F.Paste")
			(net "P5E_PEX3_STN6_TX_C_DN<105>")
		)
	)
	(footprint ""
		(layer "F.Cu")
		(at 238.124746 -115.682268)
		(property "Reference" "PR6900"
			(at 0 0 0)
			(layer "F.SilkS")
			(hide yes)
			(effects
				(font
					(size 1.27 1.27)
				)
			)
		)
		(property "Value" ""
			(at 0 0 0)
			(layer "F.Fab")
			(effects
				(font
					(size 1.27 1.27)
				)
			)
		)
		(duplicate_pad_numbers_are_jumpers no)
		(fp_line
			(start -0.7874 -0.4064)
			(end 0.7874 -0.4064)
			(stroke
				(width 0.1524)
				(type default)
			)
			(layer "F.SilkS")
		)
		(fp_line
			(start -0.7874 0.4064)
			(end -0.7874 -0.4064)
			(stroke
				(width 0.1524)
				(type default)
			)
			(layer "F.SilkS")
		)
		(fp_line
			(start 0.7874 -0.4064)
			(end 0.7874 0.4064)
			(stroke
				(width 0.1524)
				(type default)
			)
			(layer "F.SilkS")
		)
		(fp_line
			(start 0.7874 0.4064)
			(end -0.7874 0.4064)
			(stroke
				(width 0.1524)
				(type default)
			)
			(layer "F.SilkS")
		)
		(fp_line
			(start -0.67945 -0.305054)
			(end -0.12065 -0.305054)
			(stroke
				(width 0.1)
				(type default)
			)
			(layer "F.Fab")
		)
		(fp_line
			(start -0.67945 0.3048)
			(end -0.67945 -0.305054)
			(stroke
				(width 0.1)
				(type default)
			)
			(layer "F.Fab")
		)
		(fp_line
			(start -0.12065 -0.305054)
			(end -0.12065 -0.2794)
			(stroke
				(width 0.1)
				(type default)
			)
			(layer "F.Fab")
		)
		(fp_line
			(start -0.12065 -0.2794)
			(end 0.12065 -0.2794)
			(stroke
				(width 0.1)
				(type default)
			)
			(layer "F.Fab")
		)
		(fp_line
			(start -0.12065 0.2794)
			(end -0.12065 0.3048)
			(stroke
				(width 0.1)
				(type default)
			)
			(layer "F.Fab")
		)
		(fp_line
			(start -0.12065 0.3048)
			(end -0.67945 0.3048)
			(stroke
				(width 0.1)
				(type default)
			)
			(layer "F.Fab")
		)
		(fp_line
			(start 0.120396 0.2794)
			(end -0.12065 0.2794)
			(stroke
				(width 0.1)
				(type default)
			)
			(layer "F.Fab")
		)
		(fp_line
			(start 0.120396 0.3048)
			(end 0.120396 0.2794)
			(stroke
				(width 0.1)
				(type default)
			)
			(layer "F.Fab")
		)
		(fp_line
			(start 0.12065 -0.3048)
			(end 0.67945 -0.3048)
			(stroke
				(width 0.1)
				(type default)
			)
			(layer "F.Fab")
		)
		(fp_line
			(start 0.12065 -0.2794)
			(end 0.12065 -0.3048)
			(stroke
				(width 0.1)
				(type default)
			)
			(layer "F.Fab")
		)
		(fp_line
			(start 0.67945 -0.3048)
			(end 0.67945 0.3048)
			(stroke
				(width 0.1)
				(type default)
			)
			(layer "F.Fab")
		)
		(fp_line
			(start 0.67945 0.3048)
			(end 0.120396 0.3048)
			(stroke
				(width 0.1)
				(type default)
			)
			(layer "F.Fab")
		)
		(pad "1" smd circle
			(at -0.40005 0)
			(size 0 0)
			(layers "F.Cu" "F.Mask" "F.Paste")
			(net "P12V_NIC3_CO_ISET")
		)
		(pad "2" smd circle
			(at 0.40005 0)
			(size 0 0)
			(layers "F.Cu" "F.Mask" "F.Paste")
			(net "GND")
		)
	)
	(footprint ""
		(layer "F.Cu")
		(at 234.271058 -83.718908)
		(property "Reference" "R6288"
			(at 0 0 0)
			(layer "F.SilkS")
			(hide yes)
			(effects
				(font
					(size 1.27 1.27)
				)
			)
		)
		(property "Value" ""
			(at 0 0 0)
			(layer "F.Fab")
			(effects
				(font
					(size 1.27 1.27)
				)
			)
		)
		(duplicate_pad_numbers_are_jumpers no)
		(fp_line
			(start -0.7874 0.4064)
			(end -0.7874 -0.4064)
			(stroke
				(width 0.1524)
				(type default)
			)
			(layer "F.SilkS")
		)
		(fp_line
			(start -0.02286 -0.4064)
			(end 0.7874 -0.4064)
			(stroke
				(width 0.1524)
				(type default)
			)
			(layer "F.SilkS")
		)
		(fp_line
			(start 0.7874 -0.4064)
			(end 0.7874 0.4064)
			(stroke
				(width 0.1524)
				(type default)
			)
			(layer "F.SilkS")
		)
		(fp_line
			(start 0.7874 0.4064)
			(end -0.7874 0.4064)
			(stroke
				(width 0.1524)
				(type default)
			)
			(layer "F.SilkS")
		)
		(fp_line
			(start -0.67945 -0.305054)
			(end -0.12065 -0.305054)
			(stroke
				(width 0.1)
				(type default)
			)
			(layer "F.Fab")
		)
		(fp_line
			(start -0.67945 0.3048)
			(end -0.67945 -0.305054)
			(stroke
				(width 0.1)
				(type default)
			)
			(layer "F.Fab")
		)
		(fp_line
			(start -0.12065 -0.305054)
			(end -0.12065 -0.2794)
			(stroke
				(width 0.1)
				(type default)
			)
			(layer "F.Fab")
		)
		(fp_line
			(start -0.12065 -0.2794)
			(end 0.12065 -0.2794)
			(stroke
				(width 0.1)
				(type default)
			)
			(layer "F.Fab")
		)
		(fp_line
			(start -0.12065 0.2794)
			(end -0.12065 0.3048)
			(stroke
				(width 0.1)
				(type default)
			)
			(layer "F.Fab")
		)
		(fp_line
			(start -0.12065 0.3048)
			(end -0.67945 0.3048)
			(stroke
				(width 0.1)
				(type default)
			)
			(layer "F.Fab")
		)
		(fp_line
			(start 0.120396 0.2794)
			(end -0.12065 0.2794)
			(stroke
				(width 0.1)
				(type default)
			)
			(layer "F.Fab")
		)
		(fp_line
			(start 0.120396 0.3048)
			(end 0.120396 0.2794)
			(stroke
				(width 0.1)
				(type default)
			)
			(layer "F.Fab")
		)
		(fp_line
			(start 0.12065 -0.3048)
			(end 0.67945 -0.3048)
			(stroke
				(width 0.1)
				(type default)
			)
			(layer "F.Fab")
		)
		(fp_line
			(start 0.12065 -0.2794)
			(end 0.12065 -0.3048)
			(stroke
				(width 0.1)
				(type default)
			)
			(layer "F.Fab")
		)
		(fp_line
			(start 0.67945 -0.3048)
			(end 0.67945 0.3048)
			(stroke
				(width 0.1)
				(type default)
			)
			(layer "F.Fab")
		)
		(fp_line
			(start 0.67945 0.3048)
			(end 0.120396 0.3048)
			(stroke
				(width 0.1)
				(type default)
			)
			(layer "F.Fab")
		)
		(pad "1" smd rect
			(at -0.40005 0 180)
			(size 0.4572 0.508)
			(layers "F.Cu" "F.Mask" "F.Paste")
			(net "USB2_FT4232_SDB_DP")
		)
		(pad "2" smd rect
			(at 0.40005 0 180)
			(size 0.4572 0.508)
			(layers "F.Cu" "F.Mask" "F.Paste")
			(net "GND")
		)
	)
	(footprint ""
		(layer "F.Cu")
		(at 6.914388 -365.792258 90)
		(property "Reference" "R6758"
			(at 0 0 90)
			(layer "F.SilkS")
			(hide yes)
			(effects
				(font
					(size 1.27 1.27)
				)
			)
		)
		(property "Value" ""
			(at 0 0 90)
			(layer "F.Fab")
			(effects
				(font
					(size 1.27 1.27)
				)
			)
		)
		(duplicate_pad_numbers_are_jumpers no)
		(fp_line
			(start 0.7874 -0.4064)
			(end 0.7874 0.4064)
			(stroke
				(width 0.1524)
				(type default)
			)
			(layer "F.SilkS")
		)
		(fp_line
			(start -0.7874 -0.4064)
			(end 0.7874 -0.4064)
			(stroke
				(width 0.1524)
				(type default)
			)
			(layer "F.SilkS")
		)
		(fp_line
			(start 0.7874 0.4064)
			(end -0.7874 0.4064)
			(stroke
				(width 0.1524)
				(type default)
			)
			(layer "F.SilkS")
		)
		(fp_line
			(start -0.7874 0.4064)
			(end -0.7874 -0.4064)
			(stroke
				(width 0.1524)
				(type default)
			)
			(layer "F.SilkS")
		)
		(fp_line
			(start -0.12065 -0.305054)
			(end -0.12065 -0.2794)
			(stroke
				(width 0.1)
				(type default)
			)
			(layer "F.Fab")
		)
		(fp_line
			(start -0.67945 -0.305054)
			(end -0.12065 -0.305054)
			(stroke
				(width 0.1)
				(type default)
			)
			(layer "F.Fab")
		)
		(fp_line
			(start 0.67945 -0.3048)
			(end 0.67945 0.3048)
			(stroke
				(width 0.1)
				(type default)
			)
			(layer "F.Fab")
		)
		(fp_line
			(start 0.12065 -0.3048)
			(end 0.67945 -0.3048)
			(stroke
				(width 0.1)
				(type default)
			)
			(layer "F.Fab")
		)
		(fp_line
			(start 0.12065 -0.2794)
			(end 0.12065 -0.3048)
			(stroke
				(width 0.1)
				(type default)
			)
			(layer "F.Fab")
		)
		(fp_line
			(start -0.12065 -0.2794)
			(end 0.12065 -0.2794)
			(stroke
				(width 0.1)
				(type default)
			)
			(layer "F.Fab")
		)
		(fp_line
			(start 0.120396 0.2794)
			(end -0.12065 0.2794)
			(stroke
				(width 0.1)
				(type default)
			)
			(layer "F.Fab")
		)
		(fp_line
			(start -0.12065 0.2794)
			(end -0.12065 0.3048)
			(stroke
				(width 0.1)
				(type default)
			)
			(layer "F.Fab")
		)
		(fp_line
			(start 0.67945 0.3048)
			(end 0.120396 0.3048)
			(stroke
				(width 0.1)
				(type default)
			)
			(layer "F.Fab")
		)
		(fp_line
			(start 0.120396 0.3048)
			(end 0.120396 0.2794)
			(stroke
				(width 0.1)
				(type default)
			)
			(layer "F.Fab")
		)
		(fp_line
			(start -0.12065 0.3048)
			(end -0.67945 0.3048)
			(stroke
				(width 0.1)
				(type default)
			)
			(layer "F.Fab")
		)
		(fp_line
			(start -0.67945 0.3048)
			(end -0.67945 -0.305054)
			(stroke
				(width 0.1)
				(type default)
			)
			(layer "F.Fab")
		)
		(pad "1" smd circle
			(at -0.40005 0 90)
			(size 0 0)
			(layers "F.Cu" "F.Mask" "F.Paste")
			(net "P3V3_AUX")
		)
		(pad "2" smd circle
			(at 0.40005 0 90)
			(size 0 0)
			(layers "F.Cu" "F.Mask" "F.Paste")
			(net "PG12_USB_HUB_N")
		)
	)
	(footprint ""
		(layer "F.Cu")
		(at 325.20382 -291.722048 90)
		(property "Reference" "C2758"
			(at 0 0 90)
			(layer "F.SilkS")
			(hide yes)
			(effects
				(font
					(size 1.27 1.27)
				)
			)
		)
		(property "Value" ""
			(at 0 0 90)
			(layer "F.Fab")
			(effects
				(font
					(size 1.27 1.27)
				)
			)
		)
		(duplicate_pad_numbers_are_jumpers no)
		(fp_line
			(start 0.7874 -0.4064)
			(end 0.7874 0.4064)
			(stroke
				(width 0.1524)
				(type default)
			)
			(layer "F.SilkS")
		)
		(fp_line
			(start -0.7874 -0.4064)
			(end 0.7874 -0.4064)
			(stroke
				(width 0.1524)
				(type default)
			)
			(layer "F.SilkS")
		)
		(fp_line
			(start 0.7874 0.4064)
			(end -0.7874 0.4064)
			(stroke
				(width 0.1524)
				(type default)
			)
			(layer "F.SilkS")
		)
		(fp_line
			(start -0.7874 0.4064)
			(end -0.7874 -0.4064)
			(stroke
				(width 0.1524)
				(type default)
			)
			(layer "F.SilkS")
		)
		(fp_line
			(start -0.12065 -0.305054)
			(end -0.12065 -0.2794)
			(stroke
				(width 0.1)
				(type default)
			)
			(layer "F.Fab")
		)
		(fp_line
			(start -0.67945 -0.305054)
			(end -0.12065 -0.305054)
			(stroke
				(width 0.1)
				(type default)
			)
			(layer "F.Fab")
		)
		(fp_line
			(start 0.67945 -0.3048)
			(end 0.67945 0.3048)
			(stroke
				(width 0.1)
				(type default)
			)
			(layer "F.Fab")
		)
		(fp_line
			(start 0.12065 -0.3048)
			(end 0.67945 -0.3048)
			(stroke
				(width 0.1)
				(type default)
			)
			(layer "F.Fab")
		)
		(fp_line
			(start 0.12065 -0.2794)
			(end 0.12065 -0.3048)
			(stroke
				(width 0.1)
				(type default)
			)
			(layer "F.Fab")
		)
		(fp_line
			(start -0.12065 -0.2794)
			(end 0.12065 -0.2794)
			(stroke
				(width 0.1)
				(type default)
			)
			(layer "F.Fab")
		)
		(fp_line
			(start 0.120396 0.2794)
			(end -0.12065 0.2794)
			(stroke
				(width 0.1)
				(type default)
			)
			(layer "F.Fab")
		)
		(fp_line
			(start -0.12065 0.2794)
			(end -0.12065 0.3048)
			(stroke
				(width 0.1)
				(type default)
			)
			(layer "F.Fab")
		)
		(fp_line
			(start 0.67945 0.3048)
			(end 0.120396 0.3048)
			(stroke
				(width 0.1)
				(type default)
			)
			(layer "F.Fab")
		)
		(fp_line
			(start 0.120396 0.3048)
			(end 0.120396 0.2794)
			(stroke
				(width 0.1)
				(type default)
			)
			(layer "F.Fab")
		)
		(fp_line
			(start -0.12065 0.3048)
			(end -0.67945 0.3048)
			(stroke
				(width 0.1)
				(type default)
			)
			(layer "F.Fab")
		)
		(fp_line
			(start -0.67945 0.3048)
			(end -0.67945 -0.305054)
			(stroke
				(width 0.1)
				(type default)
			)
			(layer "F.Fab")
		)
		(pad "1" smd circle
			(at -0.40005 0 90)
			(size 0 0)
			(layers "F.Cu" "F.Mask" "F.Paste")
			(net "GND")
		)
		(pad "2" smd circle
			(at 0.40005 0 90)
			(size 0 0)
			(layers "F.Cu" "F.Mask" "F.Paste")
			(net "P3V3_AUX")
		)
	)
	(footprint ""
		(layer "F.Cu")
		(at 140.442442 -250.070874 -90)
		(property "Reference" "R1278"
			(at 0 0 270)
			(layer "F.SilkS")
			(hide yes)
			(effects
				(font
					(size 1.27 1.27)
				)
			)
		)
		(property "Value" ""
			(at 0 0 270)
			(layer "F.Fab")
			(effects
				(font
					(size 1.27 1.27)
				)
			)
		)
		(duplicate_pad_numbers_are_jumpers no)
		(fp_line
			(start -0.7874 0.4064)
			(end -0.7874 -0.4064)
			(stroke
				(width 0.1524)
				(type default)
			)
			(layer "F.SilkS")
		)
		(fp_line
			(start 0.7874 0.4064)
			(end -0.7874 0.4064)
			(stroke
				(width 0.1524)
				(type default)
			)
			(layer "F.SilkS")
		)
		(fp_line
			(start -0.7874 -0.4064)
			(end 0.7874 -0.4064)
			(stroke
				(width 0.1524)
				(type default)
			)
			(layer "F.SilkS")
		)
		(fp_line
			(start 0.7874 -0.4064)
			(end 0.7874 0.4064)
			(stroke
				(width 0.1524)
				(type default)
			)
			(layer "F.SilkS")
		)
		(fp_line
			(start -0.67945 0.3048)
			(end -0.67945 -0.305054)
			(stroke
				(width 0.1)
				(type default)
			)
			(layer "F.Fab")
		)
		(fp_line
			(start -0.12065 0.3048)
			(end -0.67945 0.3048)
			(stroke
				(width 0.1)
				(type default)
			)
			(layer "F.Fab")
		)
		(fp_line
			(start 0.120396 0.3048)
			(end 0.120396 0.2794)
			(stroke
				(width 0.1)
				(type default)
			)
			(layer "F.Fab")
		)
		(fp_line
			(start 0.67945 0.3048)
			(end 0.120396 0.3048)
			(stroke
				(width 0.1)
				(type default)
			)
			(layer "F.Fab")
		)
		(fp_line
			(start -0.12065 0.2794)
			(end -0.12065 0.3048)
			(stroke
				(width 0.1)
				(type default)
			)
			(layer "F.Fab")
		)
		(fp_line
			(start 0.120396 0.2794)
			(end -0.12065 0.2794)
			(stroke
				(width 0.1)
				(type default)
			)
			(layer "F.Fab")
		)
		(fp_line
			(start -0.12065 -0.2794)
			(end 0.12065 -0.2794)
			(stroke
				(width 0.1)
				(type default)
			)
			(layer "F.Fab")
		)
		(fp_line
			(start 0.12065 -0.2794)
			(end 0.12065 -0.3048)
			(stroke
				(width 0.1)
				(type default)
			)
			(layer "F.Fab")
		)
		(fp_line
			(start 0.12065 -0.3048)
			(end 0.67945 -0.3048)
			(stroke
				(width 0.1)
				(type default)
			)
			(layer "F.Fab")
		)
		(fp_line
			(start 0.67945 -0.3048)
			(end 0.67945 0.3048)
			(stroke
				(width 0.1)
				(type default)
			)
			(layer "F.Fab")
		)
		(fp_line
			(start -0.67945 -0.305054)
			(end -0.12065 -0.305054)
			(stroke
				(width 0.1)
				(type default)
			)
			(layer "F.Fab")
		)
		(fp_line
			(start -0.12065 -0.305054)
			(end -0.12065 -0.2794)
			(stroke
				(width 0.1)
				(type default)
			)
			(layer "F.Fab")
		)
		(pad "1" smd circle
			(at -0.40005 0 270)
			(size 0 0)
			(layers "F.Cu" "F.Mask" "F.Paste")
			(net "PEX1_MODE_SEL9")
		)
		(pad "2" smd circle
			(at 0.40005 0 270)
			(size 0 0)
			(layers "F.Cu" "F.Mask" "F.Paste")
			(net "P1V8_PEX")
		)
	)
	(footprint ""
		(layer "F.Cu")
		(at 327.533 -217.297)
		(property "Reference" "R4164"
			(at 0 0 0)
			(layer "F.SilkS")
			(hide yes)
			(effects
				(font
					(size 1.27 1.27)
				)
			)
		)
		(property "Value" ""
			(at 0 0 0)
			(layer "F.Fab")
			(effects
				(font
					(size 1.27 1.27)
				)
			)
		)
		(duplicate_pad_numbers_are_jumpers no)
		(fp_line
			(start -0.7874 -0.4064)
			(end 0.7874 -0.4064)
			(stroke
				(width 0.1524)
				(type default)
			)
			(layer "F.SilkS")
		)
		(fp_line
			(start -0.7874 0.4064)
			(end -0.7874 -0.4064)
			(stroke
				(width 0.1524)
				(type default)
			)
			(layer "F.SilkS")
		)
		(fp_line
			(start 0.7874 -0.4064)
			(end 0.7874 0.4064)
			(stroke
				(width 0.1524)
				(type default)
			)
			(layer "F.SilkS")
		)
		(fp_line
			(start 0.7874 0.4064)
			(end -0.7874 0.4064)
			(stroke
				(width 0.1524)
				(type default)
			)
			(layer "F.SilkS")
		)
		(fp_line
			(start -0.67945 -0.305054)
			(end -0.12065 -0.305054)
			(stroke
				(width 0.1)
				(type default)
			)
			(layer "F.Fab")
		)
		(fp_line
			(start -0.67945 0.3048)
			(end -0.67945 -0.305054)
			(stroke
				(width 0.1)
				(type default)
			)
			(layer "F.Fab")
		)
		(fp_line
			(start -0.12065 -0.305054)
			(end -0.12065 -0.2794)
			(stroke
				(width 0.1)
				(type default)
			)
			(layer "F.Fab")
		)
		(fp_line
			(start -0.12065 -0.2794)
			(end 0.12065 -0.2794)
			(stroke
				(width 0.1)
				(type default)
			)
			(layer "F.Fab")
		)
		(fp_line
			(start -0.12065 0.2794)
			(end -0.12065 0.3048)
			(stroke
				(width 0.1)
				(type default)
			)
			(layer "F.Fab")
		)
		(fp_line
			(start -0.12065 0.3048)
			(end -0.67945 0.3048)
			(stroke
				(width 0.1)
				(type default)
			)
			(layer "F.Fab")
		)
		(fp_line
			(start 0.120396 0.2794)
			(end -0.12065 0.2794)
			(stroke
				(width 0.1)
				(type default)
			)
			(layer "F.Fab")
		)
		(fp_line
			(start 0.120396 0.3048)
			(end 0.120396 0.2794)
			(stroke
				(width 0.1)
				(type default)
			)
			(layer "F.Fab")
		)
		(fp_line
			(start 0.12065 -0.3048)
			(end 0.67945 -0.3048)
			(stroke
				(width 0.1)
				(type default)
			)
			(layer "F.Fab")
		)
		(fp_line
			(start 0.12065 -0.2794)
			(end 0.12065 -0.3048)
			(stroke
				(width 0.1)
				(type default)
			)
			(layer "F.Fab")
		)
		(fp_line
			(start 0.67945 -0.3048)
			(end 0.67945 0.3048)
			(stroke
				(width 0.1)
				(type default)
			)
			(layer "F.Fab")
		)
		(fp_line
			(start 0.67945 0.3048)
			(end 0.120396 0.3048)
			(stroke
				(width 0.1)
				(type default)
			)
			(layer "F.Fab")
		)
		(pad "1" smd circle
			(at -0.40005 0)
			(size 0 0)
			(layers "F.Cu" "F.Mask" "F.Paste")
			(net "PRSNT_NIC7_FPGA_R_N")
		)
		(pad "2" smd circle
			(at 0.40005 0)
			(size 0 0)
			(layers "F.Cu" "F.Mask" "F.Paste")
			(net "PRSNT_NIC7_FPGA_N")
		)
	)
	(footprint ""
		(layer "F.Cu")
		(at 18.668746 -149.313392 -90)
		(property "Reference" "U79"
			(at -0.191008 -2.516124 90)
			(unlocked yes)
			(layer "F.SilkS")
			(effects
				(font
					(size 0.7874 0.5842)
					(thickness 0.1524)
				)
			)
		)
		(property "Value" ""
			(at 0 0 270)
			(layer "F.Fab")
			(effects
				(font
					(size 1.27 1.27)
				)
			)
		)
		(duplicate_pad_numbers_are_jumpers no)
		(fp_line
			(start -1.500124 1.500124)
			(end -1.500124 1.004062)
			(stroke
				(width 0.1524)
				(type default)
			)
			(layer "F.SilkS")
		)
		(fp_line
			(start -1.004062 1.500124)
			(end -1.500124 1.500124)
			(stroke
				(width 0.1524)
				(type default)
			)
			(layer "F.SilkS")
		)
		(fp_line
			(start 1.500124 1.500124)
			(end 1.004062 1.500124)
			(stroke
				(width 0.1524)
				(type default)
			)
			(layer "F.SilkS")
		)
		(fp_line
			(start 1.500124 1.004062)
			(end 1.500124 1.500124)
			(stroke
				(width 0.1524)
				(type default)
			)
			(layer "F.SilkS")
		)
		(fp_line
			(start -1.500124 -1.004062)
			(end -1.500124 -1.500124)
			(stroke
				(width 0.1524)
				(type default)
			)
			(layer "F.SilkS")
		)
		(fp_line
			(start -1.500124 -1.500124)
			(end -1.004062 -1.500124)
			(stroke
				(width 0.1524)
				(type default)
			)
			(layer "F.SilkS")
		)
		(fp_line
			(start 1.004062 -1.500124)
			(end 1.500124 -1.500124)
			(stroke
				(width 0.1524)
				(type default)
			)
			(layer "F.SilkS")
		)
		(fp_line
			(start 1.500124 -1.500124)
			(end 1.500124 -1.004062)
			(stroke
				(width 0.1524)
				(type default)
			)
			(layer "F.SilkS")
		)
		(fp_poly
			(pts
				(xy -1.976628 -2.091944) (xy -2.695194 -1.373378) (xy -1.617472 -1.014222)
			)
			(stroke
				(width 0)
				(type default)
			)
			(fill yes)
			(layer "F.SilkS")
		)
		(fp_line
			(start -1.500124 1.500124)
			(end -1.500124 -1.500124)
			(stroke
				(width 0.1)
				(type default)
			)
			(layer "F.Fab")
		)
		(fp_line
			(start 1.500124 1.500124)
			(end -1.500124 1.500124)
			(stroke
				(width 0.1)
				(type default)
			)
			(layer "F.Fab")
		)
		(fp_line
			(start -1.500124 -1.500124)
			(end 1.500124 -1.500124)
			(stroke
				(width 0.1)
				(type default)
			)
			(layer "F.Fab")
		)
		(fp_line
			(start 1.500124 -1.500124)
			(end 1.500124 1.500124)
			(stroke
				(width 0.1)
				(type default)
			)
			(layer "F.Fab")
		)
		(fp_poly
			(pts
				(xy -2.847848 -1.258062) (xy -2.847848 -0.242062) (xy -1.831848 -0.750062)
			)
			(stroke
				(width 0)
				(type default)
			)
			(fill yes)
			(layer "F.Fab")
		)
		(pad "1" smd rect
			(at -1.400048 -0.750062 180)
			(size 0.2286 0.6096)
			(layers "F.Cu" "F.Mask" "F.Paste")
			(net "NIC0_ADC_A1")
		)
		(pad "2" smd rect
			(at -1.400048 -0.249936 180)
			(size 0.2286 0.6096)
			(layers "F.Cu" "F.Mask" "F.Paste")
			(net "NIC0_ADC_A0")
		)
		(pad "3" smd rect
			(at -1.400048 0.249936 180)
			(size 0.2286 0.6096)
			(layers "F.Cu" "F.Mask" "F.Paste")
			(net "NIC0_ADC_ALERT_N")
		)
		(pad "4" smd rect
			(at -1.400048 0.750062 180)
			(size 0.2286 0.6096)
			(layers "F.Cu" "F.Mask" "F.Paste")
			(net "SMB_NIC0_ADC_SDA")
		)
		(pad "5" smd rect
			(at -0.750062 1.400048 270)
			(size 0.2286 0.6096)
			(layers "F.Cu" "F.Mask" "F.Paste")
			(net "SMB_NIC0_ADC_SCL")
		)
		(pad "6" smd rect
			(at -0.249936 1.400048 270)
			(size 0.2286 0.6096)
			(layers "F.Cu" "F.Mask" "F.Paste")
			(net "Net_8666")
		)
		(pad "7" smd rect
			(at 0.249936 1.400048 270)
			(size 0.2286 0.6096)
			(layers "F.Cu" "F.Mask" "F.Paste")
			(net "Net_8665")
		)
		(pad "8" smd rect
			(at 0.750062 1.400048 270)
			(size 0.2286 0.6096)
			(layers "F.Cu" "F.Mask" "F.Paste")
			(net "Net_8664")
		)
		(pad "9" smd rect
			(at 1.400048 0.750062 180)
			(size 0.2286 0.6096)
			(layers "F.Cu" "F.Mask" "F.Paste")
			(net "P3V3_AUX")
		)
		(pad "10" smd rect
			(at 1.400048 0.249936 180)
			(size 0.2286 0.6096)
			(layers "F.Cu" "F.Mask" "F.Paste")
			(net "GND")
		)
		(pad "11" smd rect
			(at 1.400048 -0.249936 180)
			(size 0.2286 0.6096)
			(layers "F.Cu" "F.Mask" "F.Paste")
			(net "P12V_NIC0_R")
		)
		(pad "12" smd rect
			(at 1.400048 -0.750062 180)
			(size 0.2286 0.6096)
			(layers "F.Cu" "F.Mask" "F.Paste")
			(net "P12V_NIC0_VIN_N")
		)
		(pad "13" smd rect
			(at 0.750062 -1.400048 270)
			(size 0.2286 0.6096)
			(layers "F.Cu" "F.Mask" "F.Paste")
			(net "P12V_NIC0_VIN_P")
		)
		(pad "14" smd rect
			(at 0.249936 -1.400048 270)
			(size 0.2286 0.6096)
			(layers "F.Cu" "F.Mask" "F.Paste")
			(net "Net_8663")
		)
		(pad "15" smd rect
			(at -0.249936 -1.400048 270)
			(size 0.2286 0.6096)
			(layers "F.Cu" "F.Mask" "F.Paste")
			(net "Net_8662")
		)
		(pad "16" smd rect
			(at -0.750062 -1.400048 270)
			(size 0.2286 0.6096)
			(layers "F.Cu" "F.Mask" "F.Paste")
			(net "Net_8661")
		)
		(pad "TH" smd rect
			(at 0 0 270)
			(size 1.7018 1.7018)
			(layers "F.Cu" "F.Mask" "F.Paste")
			(net "GND")
		)
		(zone
			(layer "F.Cu")
			(hatch none 0.5)
			(connect_pads
				(clearance 0)
			)
			(min_thickness 0.25)
			(keepout
				(tracks not_allowed)
				(vias allowed)
				(pads allowed)
				(copperpour not_allowed)
				(footprints allowed)
			)
			(placement
				(enabled no)
				(sheetname "")
			)
			(fill
				(thermal_gap 0.5)
				(thermal_bridge_width 0.5)
				(island_removal_mode 0)
			)
			(polygon
				(pts
					(xy 18.694146 -150.35784) (xy 19.713194 -150.35784) (xy 19.713194 -148.268944) (xy 17.624298 -148.268944)
					(xy 17.624298 -150.35784) (xy 18.668746 -150.35784) (xy 18.668746 -150.215092) (xy 17.767046 -150.215092)
					(xy 17.767046 -148.411692) (xy 19.570446 -148.411692) (xy 19.570446 -150.215092) (xy 18.694146 -150.215092)
				)
			)
		)
	)
	(footprint ""
		(layer "F.Cu")
		(at 262.281924 -283.389832 180)
		(property "Reference" "C3410"
			(at 0 0 180)
			(layer "F.SilkS")
			(hide yes)
			(effects
				(font
					(size 1.27 1.27)
				)
			)
		)
		(property "Value" ""
			(at 0 0 180)
			(layer "F.Fab")
			(effects
				(font
					(size 1.27 1.27)
				)
			)
		)
		(duplicate_pad_numbers_are_jumpers no)
		(fp_line
			(start 1.2954 0.5842)
			(end -1.2954 0.5842)
			(stroke
				(width 0.1524)
				(type default)
			)
			(layer "F.SilkS")
		)
		(fp_line
			(start 1.2954 -0.5842)
			(end 1.2954 0.5842)
			(stroke
				(width 0.1524)
				(type default)
			)
			(layer "F.SilkS")
		)
		(fp_line
			(start -1.2954 0.5842)
			(end -1.2954 -0.5842)
			(stroke
				(width 0.1524)
				(type default)
			)
			(layer "F.SilkS")
		)
		(fp_line
			(start -1.2954 -0.5842)
			(end 1.2954 -0.5842)
			(stroke
				(width 0.1524)
				(type default)
			)
			(layer "F.SilkS")
		)
		(fp_line
			(start 1.1938 0.4064)
			(end 0.8636 0.4064)
			(stroke
				(width 0.1)
				(type default)
			)
			(layer "F.Fab")
		)
		(fp_line
			(start 1.1938 -0.4064)
			(end 1.1938 0.4064)
			(stroke
				(width 0.1)
				(type default)
			)
			(layer "F.Fab")
		)
		(fp_line
			(start 0.8636 0.4572)
			(end -0.8636 0.4572)
			(stroke
				(width 0.1)
				(type default)
			)
			(layer "F.Fab")
		)
		(fp_line
			(start 0.8636 0.4064)
			(end 0.8636 0.4572)
			(stroke
				(width 0.1)
				(type default)
			)
			(layer "F.Fab")
		)
		(fp_line
			(start 0.8636 -0.4064)
			(end 1.1938 -0.4064)
			(stroke
				(width 0.1)
				(type default)
			)
			(layer "F.Fab")
		)
		(fp_line
			(start 0.8636 -0.4572)
			(end 0.8636 -0.4064)
			(stroke
				(width 0.1)
				(type default)
			)
			(layer "F.Fab")
		)
		(fp_line
			(start -0.8636 0.4572)
			(end -0.8636 0.4064)
			(stroke
				(width 0.1)
				(type default)
			)
			(layer "F.Fab")
		)
		(fp_line
			(start -0.8636 0.4064)
			(end -1.1938 0.4064)
			(stroke
				(width 0.1)
				(type default)
			)
			(layer "F.Fab")
		)
		(fp_line
			(start -0.8636 -0.4064)
			(end -0.8636 -0.4572)
			(stroke
				(width 0.1)
				(type default)
			)
			(layer "F.Fab")
		)
		(fp_line
			(start -0.8636 -0.4572)
			(end 0.8636 -0.4572)
			(stroke
				(width 0.1)
				(type default)
			)
			(layer "F.Fab")
		)
		(fp_line
			(start -1.1938 0.4064)
			(end -1.1938 -0.4064)
			(stroke
				(width 0.1)
				(type default)
			)
			(layer "F.Fab")
		)
		(fp_line
			(start -1.1938 -0.4064)
			(end -0.8636 -0.4064)
			(stroke
				(width 0.1)
				(type default)
			)
			(layer "F.Fab")
		)
		(pad "1" smd rect
			(at -0.7366 0 90)
			(size 0.7112 0.8128)
			(layers "F.Cu" "F.Mask" "F.Paste")
			(net "PCEPLL7_VDDA18_PEX2_R")
		)
		(pad "2" smd rect
			(at 0.7366 0 90)
			(size 0.7112 0.8128)
			(layers "F.Cu" "F.Mask" "F.Paste")
			(net "GND")
		)
	)
	(footprint ""
		(layer "F.Cu")
		(at 175.0949 -103.814372 180)
		(property "Reference" "R171"
			(at 0 0 180)
			(layer "F.SilkS")
			(hide yes)
			(effects
				(font
					(size 1.27 1.27)
				)
			)
		)
		(property "Value" ""
			(at 0 0 180)
			(layer "F.Fab")
			(effects
				(font
					(size 1.27 1.27)
				)
			)
		)
		(duplicate_pad_numbers_are_jumpers no)
		(fp_line
			(start 0.7874 0.4064)
			(end -0.7874 0.4064)
			(stroke
				(width 0.1524)
				(type default)
			)
			(layer "F.SilkS")
		)
		(fp_line
			(start 0.7874 -0.4064)
			(end 0.7874 0.4064)
			(stroke
				(width 0.1524)
				(type default)
			)
			(layer "F.SilkS")
		)
		(fp_line
			(start -0.7874 0.4064)
			(end -0.7874 -0.4064)
			(stroke
				(width 0.1524)
				(type default)
			)
			(layer "F.SilkS")
		)
		(fp_line
			(start -0.7874 -0.4064)
			(end 0.7874 -0.4064)
			(stroke
				(width 0.1524)
				(type default)
			)
			(layer "F.SilkS")
		)
		(fp_line
			(start 0.67945 0.3048)
			(end 0.120396 0.3048)
			(stroke
				(width 0.1)
				(type default)
			)
			(layer "F.Fab")
		)
		(fp_line
			(start 0.67945 -0.3048)
			(end 0.67945 0.3048)
			(stroke
				(width 0.1)
				(type default)
			)
			(layer "F.Fab")
		)
		(fp_line
			(start 0.12065 -0.2794)
			(end 0.12065 -0.3048)
			(stroke
				(width 0.1)
				(type default)
			)
			(layer "F.Fab")
		)
		(fp_line
			(start 0.12065 -0.3048)
			(end 0.67945 -0.3048)
			(stroke
				(width 0.1)
				(type default)
			)
			(layer "F.Fab")
		)
		(fp_line
			(start 0.120396 0.3048)
			(end 0.120396 0.2794)
			(stroke
				(width 0.1)
				(type default)
			)
			(layer "F.Fab")
		)
		(fp_line
			(start 0.120396 0.2794)
			(end -0.12065 0.2794)
			(stroke
				(width 0.1)
				(type default)
			)
			(layer "F.Fab")
		)
		(fp_line
			(start -0.12065 0.3048)
			(end -0.67945 0.3048)
			(stroke
				(width 0.1)
				(type default)
			)
			(layer "F.Fab")
		)
		(fp_line
			(start -0.12065 0.2794)
			(end -0.12065 0.3048)
			(stroke
				(width 0.1)
				(type default)
			)
			(layer "F.Fab")
		)
		(fp_line
			(start -0.12065 -0.2794)
			(end 0.12065 -0.2794)
			(stroke
				(width 0.1)
				(type default)
			)
			(layer "F.Fab")
		)
		(fp_line
			(start -0.12065 -0.305054)
			(end -0.12065 -0.2794)
			(stroke
				(width 0.1)
				(type default)
			)
			(layer "F.Fab")
		)
		(fp_line
			(start -0.67945 0.3048)
			(end -0.67945 -0.305054)
			(stroke
				(width 0.1)
				(type default)
			)
			(layer "F.Fab")
		)
		(fp_line
			(start -0.67945 -0.305054)
			(end -0.12065 -0.305054)
			(stroke
				(width 0.1)
				(type default)
			)
			(layer "F.Fab")
		)
		(pad "1" smd circle
			(at -0.40005 0 180)
			(size 0 0)
			(layers "F.Cu" "F.Mask" "F.Paste")
			(net "NCSI_NIC3_TXD0")
		)
		(pad "2" smd circle
			(at 0.40005 0 180)
			(size 0 0)
			(layers "F.Cu" "F.Mask" "F.Paste")
			(net "GND")
		)
	)
	(footprint ""
		(layer "F.Cu")
		(at 240.679224 -178.72075 90)
		(property "Reference" "R5479"
			(at 0 0 90)
			(layer "F.SilkS")
			(hide yes)
			(effects
				(font
					(size 1.27 1.27)
				)
			)
		)
		(property "Value" ""
			(at 0 0 90)
			(layer "F.Fab")
			(effects
				(font
					(size 1.27 1.27)
				)
			)
		)
		(duplicate_pad_numbers_are_jumpers no)
		(fp_line
			(start 0.7874 -0.4064)
			(end 0.7874 0.4064)
			(stroke
				(width 0.1524)
				(type default)
			)
			(layer "F.SilkS")
		)
		(fp_line
			(start -0.7874 -0.4064)
			(end 0.7874 -0.4064)
			(stroke
				(width 0.1524)
				(type default)
			)
			(layer "F.SilkS")
		)
		(fp_line
			(start 0.7874 0.4064)
			(end -0.7874 0.4064)
			(stroke
				(width 0.1524)
				(type default)
			)
			(layer "F.SilkS")
		)
		(fp_line
			(start -0.7874 0.4064)
			(end -0.7874 -0.4064)
			(stroke
				(width 0.1524)
				(type default)
			)
			(layer "F.SilkS")
		)
		(fp_line
			(start -0.12065 -0.305054)
			(end -0.12065 -0.2794)
			(stroke
				(width 0.1)
				(type default)
			)
			(layer "F.Fab")
		)
		(fp_line
			(start -0.67945 -0.305054)
			(end -0.12065 -0.305054)
			(stroke
				(width 0.1)
				(type default)
			)
			(layer "F.Fab")
		)
		(fp_line
			(start 0.67945 -0.3048)
			(end 0.67945 0.3048)
			(stroke
				(width 0.1)
				(type default)
			)
			(layer "F.Fab")
		)
		(fp_line
			(start 0.12065 -0.3048)
			(end 0.67945 -0.3048)
			(stroke
				(width 0.1)
				(type default)
			)
			(layer "F.Fab")
		)
		(fp_line
			(start 0.12065 -0.2794)
			(end 0.12065 -0.3048)
			(stroke
				(width 0.1)
				(type default)
			)
			(layer "F.Fab")
		)
		(fp_line
			(start -0.12065 -0.2794)
			(end 0.12065 -0.2794)
			(stroke
				(width 0.1)
				(type default)
			)
			(layer "F.Fab")
		)
		(fp_line
			(start 0.120396 0.2794)
			(end -0.12065 0.2794)
			(stroke
				(width 0.1)
				(type default)
			)
			(layer "F.Fab")
		)
		(fp_line
			(start -0.12065 0.2794)
			(end -0.12065 0.3048)
			(stroke
				(width 0.1)
				(type default)
			)
			(layer "F.Fab")
		)
		(fp_line
			(start 0.67945 0.3048)
			(end 0.120396 0.3048)
			(stroke
				(width 0.1)
				(type default)
			)
			(layer "F.Fab")
		)
		(fp_line
			(start 0.120396 0.3048)
			(end 0.120396 0.2794)
			(stroke
				(width 0.1)
				(type default)
			)
			(layer "F.Fab")
		)
		(fp_line
			(start -0.12065 0.3048)
			(end -0.67945 0.3048)
			(stroke
				(width 0.1)
				(type default)
			)
			(layer "F.Fab")
		)
		(fp_line
			(start -0.67945 0.3048)
			(end -0.67945 -0.305054)
			(stroke
				(width 0.1)
				(type default)
			)
			(layer "F.Fab")
		)
		(pad "1" smd circle
			(at -0.40005 0 90)
			(size 0 0)
			(layers "F.Cu" "F.Mask" "F.Paste")
			(net "P3V3_AUX")
		)
		(pad "2" smd circle
			(at 0.40005 0 90)
			(size 0 0)
			(layers "F.Cu" "F.Mask" "F.Paste")
			(net "BIC_RST_RSMRST_N")
		)
	)
	(footprint ""
		(layer "F.Cu")
		(at 187.946792 -343.952322 90)
		(property "Reference" "C379"
			(at 0 0 90)
			(layer "F.SilkS")
			(hide yes)
			(effects
				(font
					(size 1.27 1.27)
				)
			)
		)
		(property "Value" ""
			(at 0 0 90)
			(layer "F.Fab")
			(effects
				(font
					(size 1.27 1.27)
				)
			)
		)
		(duplicate_pad_numbers_are_jumpers no)
		(fp_line
			(start 0.299974 -0.150114)
			(end 0.299974 0.150114)
			(stroke
				(width 0.1)
				(type default)
			)
			(layer "F.Fab")
		)
		(fp_line
			(start -0.299974 -0.150114)
			(end 0.299974 -0.150114)
			(stroke
				(width 0.1)
				(type default)
			)
			(layer "F.Fab")
		)
		(fp_line
			(start 0.299974 0.150114)
			(end -0.299974 0.150114)
			(stroke
				(width 0.1)
				(type default)
			)
			(layer "F.Fab")
		)
		(fp_line
			(start -0.299974 0.150114)
			(end -0.299974 -0.150114)
			(stroke
				(width 0.1)
				(type default)
			)
			(layer "F.Fab")
		)
		(pad "1" smd rect
			(at -0.2667 0 90)
			(size 0.3048 0.381)
			(layers "F.Cu" "F.Mask" "F.Paste")
			(net "P5E_PEX1_STN7_TX_DN<124>")
		)
		(pad "2" smd rect
			(at 0.2667 0 90)
			(size 0.3048 0.381)
			(layers "F.Cu" "F.Mask" "F.Paste")
			(net "P5E_PEX1_STN7_TX_C_DN<124>")
		)
	)
	(footprint ""
		(layer "F.Cu")
		(at 368.975132 -56.977534 180)
		(property "Reference" "PC412"
			(at 0 0 180)
			(layer "F.SilkS")
			(hide yes)
			(effects
				(font
					(size 1.27 1.27)
				)
			)
		)
		(property "Value" ""
			(at 0 0 180)
			(layer "F.Fab")
			(effects
				(font
					(size 1.27 1.27)
				)
			)
		)
		(duplicate_pad_numbers_are_jumpers no)
		(fp_line
			(start 0.7874 0.4064)
			(end -0.7874 0.4064)
			(stroke
				(width 0.1524)
				(type default)
			)
			(layer "F.SilkS")
		)
		(fp_line
			(start 0.7874 -0.4064)
			(end 0.7874 0.4064)
			(stroke
				(width 0.1524)
				(type default)
			)
			(layer "F.SilkS")
		)
		(fp_line
			(start -0.7874 0.4064)
			(end -0.7874 -0.4064)
			(stroke
				(width 0.1524)
				(type default)
			)
			(layer "F.SilkS")
		)
		(fp_line
			(start -0.7874 -0.4064)
			(end 0.7874 -0.4064)
			(stroke
				(width 0.1524)
				(type default)
			)
			(layer "F.SilkS")
		)
		(fp_line
			(start 0.67945 0.3048)
			(end 0.120396 0.3048)
			(stroke
				(width 0.1)
				(type default)
			)
			(layer "F.Fab")
		)
		(fp_line
			(start 0.67945 -0.3048)
			(end 0.67945 0.3048)
			(stroke
				(width 0.1)
				(type default)
			)
			(layer "F.Fab")
		)
		(fp_line
			(start 0.12065 -0.2794)
			(end 0.12065 -0.3048)
			(stroke
				(width 0.1)
				(type default)
			)
			(layer "F.Fab")
		)
		(fp_line
			(start 0.12065 -0.3048)
			(end 0.67945 -0.3048)
			(stroke
				(width 0.1)
				(type default)
			)
			(layer "F.Fab")
		)
		(fp_line
			(start 0.120396 0.3048)
			(end 0.120396 0.2794)
			(stroke
				(width 0.1)
				(type default)
			)
			(layer "F.Fab")
		)
		(fp_line
			(start 0.120396 0.2794)
			(end -0.12065 0.2794)
			(stroke
				(width 0.1)
				(type default)
			)
			(layer "F.Fab")
		)
		(fp_line
			(start -0.12065 0.3048)
			(end -0.67945 0.3048)
			(stroke
				(width 0.1)
				(type default)
			)
			(layer "F.Fab")
		)
		(fp_line
			(start -0.12065 0.2794)
			(end -0.12065 0.3048)
			(stroke
				(width 0.1)
				(type default)
			)
			(layer "F.Fab")
		)
		(fp_line
			(start -0.12065 -0.2794)
			(end 0.12065 -0.2794)
			(stroke
				(width 0.1)
				(type default)
			)
			(layer "F.Fab")
		)
		(fp_line
			(start -0.12065 -0.305054)
			(end -0.12065 -0.2794)
			(stroke
				(width 0.1)
				(type default)
			)
			(layer "F.Fab")
		)
		(fp_line
			(start -0.67945 0.3048)
			(end -0.67945 -0.305054)
			(stroke
				(width 0.1)
				(type default)
			)
			(layer "F.Fab")
		)
		(fp_line
			(start -0.67945 -0.305054)
			(end -0.12065 -0.305054)
			(stroke
				(width 0.1)
				(type default)
			)
			(layer "F.Fab")
		)
		(pad "1" smd circle
			(at -0.40005 0 180)
			(size 0 0)
			(layers "F.Cu" "F.Mask" "F.Paste")
			(net "P12V_AUX")
		)
		(pad "2" smd circle
			(at 0.40005 0 180)
			(size 0 0)
			(layers "F.Cu" "F.Mask" "F.Paste")
			(net "GND")
		)
	)
	(footprint ""
		(layer "F.Cu")
		(at 124.149612 -159.844994 180)
		(property "Reference" "PR6893"
			(at 0 0 180)
			(layer "F.SilkS")
			(hide yes)
			(effects
				(font
					(size 1.27 1.27)
				)
			)
		)
		(property "Value" ""
			(at 0 0 180)
			(layer "F.Fab")
			(effects
				(font
					(size 1.27 1.27)
				)
			)
		)
		(duplicate_pad_numbers_are_jumpers no)
		(fp_line
			(start 0.7874 0.4064)
			(end -0.7874 0.4064)
			(stroke
				(width 0.1524)
				(type default)
			)
			(layer "F.SilkS")
		)
		(fp_line
			(start 0.7874 -0.4064)
			(end 0.7874 0.4064)
			(stroke
				(width 0.1524)
				(type default)
			)
			(layer "F.SilkS")
		)
		(fp_line
			(start -0.7874 0.4064)
			(end -0.7874 -0.4064)
			(stroke
				(width 0.1524)
				(type default)
			)
			(layer "F.SilkS")
		)
		(fp_line
			(start -0.7874 -0.4064)
			(end 0.7874 -0.4064)
			(stroke
				(width 0.1524)
				(type default)
			)
			(layer "F.SilkS")
		)
		(fp_line
			(start 0.67945 0.3048)
			(end 0.120396 0.3048)
			(stroke
				(width 0.1)
				(type default)
			)
			(layer "F.Fab")
		)
		(fp_line
			(start 0.67945 -0.3048)
			(end 0.67945 0.3048)
			(stroke
				(width 0.1)
				(type default)
			)
			(layer "F.Fab")
		)
		(fp_line
			(start 0.12065 -0.2794)
			(end 0.12065 -0.3048)
			(stroke
				(width 0.1)
				(type default)
			)
			(layer "F.Fab")
		)
		(fp_line
			(start 0.12065 -0.3048)
			(end 0.67945 -0.3048)
			(stroke
				(width 0.1)
				(type default)
			)
			(layer "F.Fab")
		)
		(fp_line
			(start 0.120396 0.3048)
			(end 0.120396 0.2794)
			(stroke
				(width 0.1)
				(type default)
			)
			(layer "F.Fab")
		)
		(fp_line
			(start 0.120396 0.2794)
			(end -0.12065 0.2794)
			(stroke
				(width 0.1)
				(type default)
			)
			(layer "F.Fab")
		)
		(fp_line
			(start -0.12065 0.3048)
			(end -0.67945 0.3048)
			(stroke
				(width 0.1)
				(type default)
			)
			(layer "F.Fab")
		)
		(fp_line
			(start -0.12065 0.2794)
			(end -0.12065 0.3048)
			(stroke
				(width 0.1)
				(type default)
			)
			(layer "F.Fab")
		)
		(fp_line
			(start -0.12065 -0.2794)
			(end 0.12065 -0.2794)
			(stroke
				(width 0.1)
				(type default)
			)
			(layer "F.Fab")
		)
		(fp_line
			(start -0.12065 -0.305054)
			(end -0.12065 -0.2794)
			(stroke
				(width 0.1)
				(type default)
			)
			(layer "F.Fab")
		)
		(fp_line
			(start -0.67945 0.3048)
			(end -0.67945 -0.305054)
			(stroke
				(width 0.1)
				(type default)
			)
			(layer "F.Fab")
		)
		(fp_line
			(start -0.67945 -0.305054)
			(end -0.12065 -0.305054)
			(stroke
				(width 0.1)
				(type default)
			)
			(layer "F.Fab")
		)
		(pad "1" smd circle
			(at -0.40005 0 180)
			(size 0 0)
			(layers "F.Cu" "F.Mask" "F.Paste")
			(net "P12V_NIC2_CO_FLTB")
		)
		(pad "2" smd circle
			(at 0.40005 0 180)
			(size 0 0)
			(layers "F.Cu" "F.Mask" "F.Paste")
			(net "P3V3_AUX")
		)
	)
	(footprint ""
		(layer "F.Cu")
		(at 265.46683 -208.039462 90)
		(property "Reference" "D24"
			(at -0.623062 -1.66116 90)
			(unlocked yes)
			(layer "F.SilkS")
			(effects
				(font
					(size 0.7874 0.5842)
					(thickness 0.1524)
				)
				(justify left)
			)
		)
		(property "Value" ""
			(at 0 0 90)
			(layer "F.Fab")
			(effects
				(font
					(size 1.27 1.27)
				)
			)
		)
		(duplicate_pad_numbers_are_jumpers no)
		(fp_line
			(start 2.7178 -1.0414)
			(end 2.7178 1.0414)
			(stroke
				(width 0.1524)
				(type default)
			)
			(layer "F.SilkS")
		)
		(fp_line
			(start 2.5908 -1.0414)
			(end 2.5908 1.0414)
			(stroke
				(width 0.1524)
				(type default)
			)
			(layer "F.SilkS")
		)
		(fp_line
			(start 2.4638 -1.0414)
			(end 2.4638 1.0414)
			(stroke
				(width 0.1524)
				(type default)
			)
			(layer "F.SilkS")
		)
		(fp_line
			(start -2.4638 -1.0414)
			(end 2.7178 -1.0414)
			(stroke
				(width 0.1524)
				(type default)
			)
			(layer "F.SilkS")
		)
		(fp_line
			(start 0.254 -0.508)
			(end 0.254 0.5334)
			(stroke
				(width 0.1524)
				(type default)
			)
			(layer "F.SilkS")
		)
		(fp_line
			(start -0.508 -0.508)
			(end -0.508 0.5334)
			(stroke
				(width 0.1524)
				(type default)
			)
			(layer "F.SilkS")
		)
		(fp_line
			(start 0.1778 -0.0254)
			(end -0.4826 -0.4826)
			(stroke
				(width 0.1524)
				(type default)
			)
			(layer "F.SilkS")
		)
		(fp_line
			(start -0.508 0.5334)
			(end 0.1778 -0.0254)
			(stroke
				(width 0.1524)
				(type default)
			)
			(layer "F.SilkS")
		)
		(fp_line
			(start 2.7178 1.0414)
			(end -2.4638 1.0414)
			(stroke
				(width 0.1524)
				(type default)
			)
			(layer "F.SilkS")
		)
		(fp_line
			(start -2.4638 1.0414)
			(end -2.4638 -1.0414)
			(stroke
				(width 0.1524)
				(type default)
			)
			(layer "F.SilkS")
		)
		(fp_line
			(start 2.7178 -1.0414)
			(end 2.7178 1.0414)
			(stroke
				(width 0.1)
				(type default)
			)
			(layer "F.Fab")
		)
		(fp_line
			(start -2.4638 -1.0414)
			(end 2.7178 -1.0414)
			(stroke
				(width 0.1)
				(type default)
			)
			(layer "F.Fab")
		)
		(fp_line
			(start 2.7178 1.0414)
			(end -2.4638 1.0414)
			(stroke
				(width 0.1)
				(type default)
			)
			(layer "F.Fab")
		)
		(fp_line
			(start -2.4638 1.0414)
			(end -2.4638 -1.0414)
			(stroke
				(width 0.1)
				(type default)
			)
			(layer "F.Fab")
		)
		(fp_text user "-"
			(at 2.9845 -0.366268 90)
			(unlocked yes)
			(layer "F.SilkS")
			(effects
				(font
					(size 1.905 1.4224)
					(thickness 0.1524)
				)
				(justify left)
			)
		)
		(fp_text user "+"
			(at -3.9624 -0.17145 90)
			(unlocked yes)
			(layer "F.SilkS")
			(effects
				(font
					(size 1.905 1.4224)
					(thickness 0.1524)
				)
				(justify left)
			)
		)
		(fp_text user "-"
			(at 2.9845 -0.366268 90)
			(unlocked yes)
			(layer "F.Fab")
			(effects
				(font
					(size 1.905 1.4224)
					(thickness 0.1524)
				)
				(justify left)
			)
		)
		(fp_text user "+"
			(at -3.9624 -0.17145 90)
			(unlocked yes)
			(layer "F.Fab")
			(effects
				(font
					(size 1.905 1.4224)
					(thickness 0.1524)
				)
				(justify left)
			)
		)
		(pad "1" smd rect
			(at -1.724914 0 90)
			(size 1.1684 1.7526)
			(layers "F.Cu" "F.Mask" "F.Paste")
			(net "P3V3_AUX")
		)
		(pad "2" smd rect
			(at 1.724914 0 90)
			(size 1.1684 1.7526)
			(layers "F.Cu" "F.Mask" "F.Paste")
			(net "P3V3_AUX_JTAG")
		)
	)
	(footprint ""
		(layer "F.Cu")
		(at 357.965756 -231.428798)
		(property "Reference" "R2622"
			(at 0 0 0)
			(layer "F.SilkS")
			(hide yes)
			(effects
				(font
					(size 1.27 1.27)
				)
			)
		)
		(property "Value" ""
			(at 0 0 0)
			(layer "F.Fab")
			(effects
				(font
					(size 1.27 1.27)
				)
			)
		)
		(duplicate_pad_numbers_are_jumpers no)
		(fp_line
			(start -0.7874 -0.4064)
			(end 0.7874 -0.4064)
			(stroke
				(width 0.1524)
				(type default)
			)
			(layer "F.SilkS")
		)
		(fp_line
			(start -0.7874 0.4064)
			(end -0.7874 -0.4064)
			(stroke
				(width 0.1524)
				(type default)
			)
			(layer "F.SilkS")
		)
		(fp_line
			(start 0.7874 -0.4064)
			(end 0.7874 0.4064)
			(stroke
				(width 0.1524)
				(type default)
			)
			(layer "F.SilkS")
		)
		(fp_line
			(start 0.7874 0.4064)
			(end -0.7874 0.4064)
			(stroke
				(width 0.1524)
				(type default)
			)
			(layer "F.SilkS")
		)
		(fp_line
			(start -0.67945 -0.305054)
			(end -0.12065 -0.305054)
			(stroke
				(width 0.1)
				(type default)
			)
			(layer "F.Fab")
		)
		(fp_line
			(start -0.67945 0.3048)
			(end -0.67945 -0.305054)
			(stroke
				(width 0.1)
				(type default)
			)
			(layer "F.Fab")
		)
		(fp_line
			(start -0.12065 -0.305054)
			(end -0.12065 -0.2794)
			(stroke
				(width 0.1)
				(type default)
			)
			(layer "F.Fab")
		)
		(fp_line
			(start -0.12065 -0.2794)
			(end 0.12065 -0.2794)
			(stroke
				(width 0.1)
				(type default)
			)
			(layer "F.Fab")
		)
		(fp_line
			(start -0.12065 0.2794)
			(end -0.12065 0.3048)
			(stroke
				(width 0.1)
				(type default)
			)
			(layer "F.Fab")
		)
		(fp_line
			(start -0.12065 0.3048)
			(end -0.67945 0.3048)
			(stroke
				(width 0.1)
				(type default)
			)
			(layer "F.Fab")
		)
		(fp_line
			(start 0.120396 0.2794)
			(end -0.12065 0.2794)
			(stroke
				(width 0.1)
				(type default)
			)
			(layer "F.Fab")
		)
		(fp_line
			(start 0.120396 0.3048)
			(end 0.120396 0.2794)
			(stroke
				(width 0.1)
				(type default)
			)
			(layer "F.Fab")
		)
		(fp_line
			(start 0.12065 -0.3048)
			(end 0.67945 -0.3048)
			(stroke
				(width 0.1)
				(type default)
			)
			(layer "F.Fab")
		)
		(fp_line
			(start 0.12065 -0.2794)
			(end 0.12065 -0.3048)
			(stroke
				(width 0.1)
				(type default)
			)
			(layer "F.Fab")
		)
		(fp_line
			(start 0.67945 -0.3048)
			(end 0.67945 0.3048)
			(stroke
				(width 0.1)
				(type default)
			)
			(layer "F.Fab")
		)
		(fp_line
			(start 0.67945 0.3048)
			(end 0.120396 0.3048)
			(stroke
				(width 0.1)
				(type default)
			)
			(layer "F.Fab")
		)
		(pad "1" smd circle
			(at -0.40005 0)
			(size 0 0)
			(layers "F.Cu" "F.Mask" "F.Paste")
			(net "FPGA_JTAGENB")
		)
		(pad "2" smd circle
			(at 0.40005 0)
			(size 0 0)
			(layers "F.Cu" "F.Mask" "F.Paste")
			(net "P3V3_AUX")
		)
	)
	(footprint ""
		(layer "F.Cu")
		(at 359.156 -184.15)
		(property "Reference" "R4607"
			(at 0 0 0)
			(layer "F.SilkS")
			(hide yes)
			(effects
				(font
					(size 1.27 1.27)
				)
			)
		)
		(property "Value" ""
			(at 0 0 0)
			(layer "F.Fab")
			(effects
				(font
					(size 1.27 1.27)
				)
			)
		)
		(duplicate_pad_numbers_are_jumpers no)
		(fp_line
			(start -0.7874 -0.4064)
			(end 0.7874 -0.4064)
			(stroke
				(width 0.1524)
				(type default)
			)
			(layer "F.SilkS")
		)
		(fp_line
			(start -0.7874 0.4064)
			(end -0.7874 -0.4064)
			(stroke
				(width 0.1524)
				(type default)
			)
			(layer "F.SilkS")
		)
		(fp_line
			(start 0.7874 -0.4064)
			(end 0.7874 0.4064)
			(stroke
				(width 0.1524)
				(type default)
			)
			(layer "F.SilkS")
		)
		(fp_line
			(start 0.7874 0.4064)
			(end -0.7874 0.4064)
			(stroke
				(width 0.1524)
				(type default)
			)
			(layer "F.SilkS")
		)
		(fp_line
			(start -0.67945 -0.305054)
			(end -0.12065 -0.305054)
			(stroke
				(width 0.1)
				(type default)
			)
			(layer "F.Fab")
		)
		(fp_line
			(start -0.67945 0.3048)
			(end -0.67945 -0.305054)
			(stroke
				(width 0.1)
				(type default)
			)
			(layer "F.Fab")
		)
		(fp_line
			(start -0.12065 -0.305054)
			(end -0.12065 -0.2794)
			(stroke
				(width 0.1)
				(type default)
			)
			(layer "F.Fab")
		)
		(fp_line
			(start -0.12065 -0.2794)
			(end 0.12065 -0.2794)
			(stroke
				(width 0.1)
				(type default)
			)
			(layer "F.Fab")
		)
		(fp_line
			(start -0.12065 0.2794)
			(end -0.12065 0.3048)
			(stroke
				(width 0.1)
				(type default)
			)
			(layer "F.Fab")
		)
		(fp_line
			(start -0.12065 0.3048)
			(end -0.67945 0.3048)
			(stroke
				(width 0.1)
				(type default)
			)
			(layer "F.Fab")
		)
		(fp_line
			(start 0.120396 0.2794)
			(end -0.12065 0.2794)
			(stroke
				(width 0.1)
				(type default)
			)
			(layer "F.Fab")
		)
		(fp_line
			(start 0.120396 0.3048)
			(end 0.120396 0.2794)
			(stroke
				(width 0.1)
				(type default)
			)
			(layer "F.Fab")
		)
		(fp_line
			(start 0.12065 -0.3048)
			(end 0.67945 -0.3048)
			(stroke
				(width 0.1)
				(type default)
			)
			(layer "F.Fab")
		)
		(fp_line
			(start 0.12065 -0.2794)
			(end 0.12065 -0.3048)
			(stroke
				(width 0.1)
				(type default)
			)
			(layer "F.Fab")
		)
		(fp_line
			(start 0.67945 -0.3048)
			(end 0.67945 0.3048)
			(stroke
				(width 0.1)
				(type default)
			)
			(layer "F.Fab")
		)
		(fp_line
			(start 0.67945 0.3048)
			(end 0.120396 0.3048)
			(stroke
				(width 0.1)
				(type default)
			)
			(layer "F.Fab")
		)
		(pad "1" smd circle
			(at -0.40005 0)
			(size 0 0)
			(layers "F.Cu" "F.Mask" "F.Paste")
			(net "P3V3_AUX")
		)
		(pad "2" smd circle
			(at 0.40005 0)
			(size 0 0)
			(layers "F.Cu" "F.Mask" "F.Paste")
			(net "RST_PEX_SSD3_PERST_R_N")
		)
	)
	(footprint ""
		(layer "F.Cu")
		(at 419.510972 -356.244906 90)
		(property "Reference" "C2450"
			(at 0 0 90)
			(layer "F.SilkS")
			(hide yes)
			(effects
				(font
					(size 1.27 1.27)
				)
			)
		)
		(property "Value" ""
			(at 0 0 90)
			(layer "F.Fab")
			(effects
				(font
					(size 1.27 1.27)
				)
			)
		)
		(duplicate_pad_numbers_are_jumpers no)
		(fp_line
			(start 0.299974 -0.150114)
			(end 0.299974 0.150114)
			(stroke
				(width 0.1)
				(type default)
			)
			(layer "F.Fab")
		)
		(fp_line
			(start -0.299974 -0.150114)
			(end 0.299974 -0.150114)
			(stroke
				(width 0.1)
				(type default)
			)
			(layer "F.Fab")
		)
		(fp_line
			(start 0.299974 0.150114)
			(end -0.299974 0.150114)
			(stroke
				(width 0.1)
				(type default)
			)
			(layer "F.Fab")
		)
		(fp_line
			(start -0.299974 0.150114)
			(end -0.299974 -0.150114)
			(stroke
				(width 0.1)
				(type default)
			)
			(layer "F.Fab")
		)
		(pad "1" smd rect
			(at -0.2667 0 90)
			(size 0.3048 0.381)
			(layers "F.Cu" "F.Mask" "F.Paste")
			(net "P5E_PEX3_STN4_TX_DN<74>")
		)
		(pad "2" smd rect
			(at 0.2667 0 90)
			(size 0.3048 0.381)
			(layers "F.Cu" "F.Mask" "F.Paste")
			(net "P5E_PEX3_STN4_TX_C_DN<74>")
		)
	)
	(footprint ""
		(layer "F.Cu")
		(at 150.602442 -252.356874 -90)
		(property "Reference" "R1300"
			(at 0 0 270)
			(layer "F.SilkS")
			(hide yes)
			(effects
				(font
					(size 1.27 1.27)
				)
			)
		)
		(property "Value" ""
			(at 0 0 270)
			(layer "F.Fab")
			(effects
				(font
					(size 1.27 1.27)
				)
			)
		)
		(duplicate_pad_numbers_are_jumpers no)
		(fp_line
			(start -0.7874 0.4064)
			(end -0.7874 -0.4064)
			(stroke
				(width 0.1524)
				(type default)
			)
			(layer "F.SilkS")
		)
		(fp_line
			(start 0.7874 0.4064)
			(end -0.7874 0.4064)
			(stroke
				(width 0.1524)
				(type default)
			)
			(layer "F.SilkS")
		)
		(fp_line
			(start -0.7874 -0.4064)
			(end 0.7874 -0.4064)
			(stroke
				(width 0.1524)
				(type default)
			)
			(layer "F.SilkS")
		)
		(fp_line
			(start 0.7874 -0.4064)
			(end 0.7874 0.4064)
			(stroke
				(width 0.1524)
				(type default)
			)
			(layer "F.SilkS")
		)
		(fp_line
			(start -0.67945 0.3048)
			(end -0.67945 -0.305054)
			(stroke
				(width 0.1)
				(type default)
			)
			(layer "F.Fab")
		)
		(fp_line
			(start -0.12065 0.3048)
			(end -0.67945 0.3048)
			(stroke
				(width 0.1)
				(type default)
			)
			(layer "F.Fab")
		)
		(fp_line
			(start 0.120396 0.3048)
			(end 0.120396 0.2794)
			(stroke
				(width 0.1)
				(type default)
			)
			(layer "F.Fab")
		)
		(fp_line
			(start 0.67945 0.3048)
			(end 0.120396 0.3048)
			(stroke
				(width 0.1)
				(type default)
			)
			(layer "F.Fab")
		)
		(fp_line
			(start -0.12065 0.2794)
			(end -0.12065 0.3048)
			(stroke
				(width 0.1)
				(type default)
			)
			(layer "F.Fab")
		)
		(fp_line
			(start 0.120396 0.2794)
			(end -0.12065 0.2794)
			(stroke
				(width 0.1)
				(type default)
			)
			(layer "F.Fab")
		)
		(fp_line
			(start -0.12065 -0.2794)
			(end 0.12065 -0.2794)
			(stroke
				(width 0.1)
				(type default)
			)
			(layer "F.Fab")
		)
		(fp_line
			(start 0.12065 -0.2794)
			(end 0.12065 -0.3048)
			(stroke
				(width 0.1)
				(type default)
			)
			(layer "F.Fab")
		)
		(fp_line
			(start 0.12065 -0.3048)
			(end 0.67945 -0.3048)
			(stroke
				(width 0.1)
				(type default)
			)
			(layer "F.Fab")
		)
		(fp_line
			(start 0.67945 -0.3048)
			(end 0.67945 0.3048)
			(stroke
				(width 0.1)
				(type default)
			)
			(layer "F.Fab")
		)
		(fp_line
			(start -0.67945 -0.305054)
			(end -0.12065 -0.305054)
			(stroke
				(width 0.1)
				(type default)
			)
			(layer "F.Fab")
		)
		(fp_line
			(start -0.12065 -0.305054)
			(end -0.12065 -0.2794)
			(stroke
				(width 0.1)
				(type default)
			)
			(layer "F.Fab")
		)
		(pad "1" smd circle
			(at -0.40005 0 270)
			(size 0 0)
			(layers "F.Cu" "F.Mask" "F.Paste")
			(net "GND")
		)
		(pad "2" smd circle
			(at 0.40005 0 270)
			(size 0 0)
			(layers "F.Cu" "F.Mask" "F.Paste")
			(net "PEX1_MODE_SEL11")
		)
	)
	(footprint ""
		(layer "F.Cu")
		(at 31.742888 -350.098614 90)
		(property "Reference" "C179"
			(at 0 0 90)
			(layer "F.SilkS")
			(hide yes)
			(effects
				(font
					(size 1.27 1.27)
				)
			)
		)
		(property "Value" ""
			(at 0 0 90)
			(layer "F.Fab")
			(effects
				(font
					(size 1.27 1.27)
				)
			)
		)
		(duplicate_pad_numbers_are_jumpers no)
		(fp_line
			(start 0.299974 -0.150114)
			(end 0.299974 0.150114)
			(stroke
				(width 0.1)
				(type default)
			)
			(layer "F.Fab")
		)
		(fp_line
			(start -0.299974 -0.150114)
			(end 0.299974 -0.150114)
			(stroke
				(width 0.1)
				(type default)
			)
			(layer "F.Fab")
		)
		(fp_line
			(start 0.299974 0.150114)
			(end -0.299974 0.150114)
			(stroke
				(width 0.1)
				(type default)
			)
			(layer "F.Fab")
		)
		(fp_line
			(start -0.299974 0.150114)
			(end -0.299974 -0.150114)
			(stroke
				(width 0.1)
				(type default)
			)
			(layer "F.Fab")
		)
		(pad "1" smd rect
			(at -0.2667 0 90)
			(size 0.3048 0.381)
			(layers "F.Cu" "F.Mask" "F.Paste")
			(net "P5E_PEX0_STN7_TX_DP<118>")
		)
		(pad "2" smd rect
			(at 0.2667 0 90)
			(size 0.3048 0.381)
			(layers "F.Cu" "F.Mask" "F.Paste")
			(net "P5E_PEX0_STN7_TX_C_DP<118>")
		)
	)
	(footprint ""
		(layer "F.Cu")
		(at 239.70869 -214.923878 90)
		(property "Reference" "C194"
			(at 0 0 90)
			(layer "F.SilkS")
			(hide yes)
			(effects
				(font
					(size 1.27 1.27)
				)
			)
		)
		(property "Value" ""
			(at 0 0 90)
			(layer "F.Fab")
			(effects
				(font
					(size 1.27 1.27)
				)
			)
		)
		(duplicate_pad_numbers_are_jumpers no)
		(fp_line
			(start 0.7874 -0.4064)
			(end 0.7874 0.4064)
			(stroke
				(width 0.1524)
				(type default)
			)
			(layer "F.SilkS")
		)
		(fp_line
			(start -0.7874 -0.4064)
			(end 0.7874 -0.4064)
			(stroke
				(width 0.1524)
				(type default)
			)
			(layer "F.SilkS")
		)
		(fp_line
			(start 0.7874 0.4064)
			(end -0.7874 0.4064)
			(stroke
				(width 0.1524)
				(type default)
			)
			(layer "F.SilkS")
		)
		(fp_line
			(start -0.7874 0.4064)
			(end -0.7874 -0.4064)
			(stroke
				(width 0.1524)
				(type default)
			)
			(layer "F.SilkS")
		)
		(fp_line
			(start -0.12065 -0.305054)
			(end -0.12065 -0.2794)
			(stroke
				(width 0.1)
				(type default)
			)
			(layer "F.Fab")
		)
		(fp_line
			(start -0.67945 -0.305054)
			(end -0.12065 -0.305054)
			(stroke
				(width 0.1)
				(type default)
			)
			(layer "F.Fab")
		)
		(fp_line
			(start 0.67945 -0.3048)
			(end 0.67945 0.3048)
			(stroke
				(width 0.1)
				(type default)
			)
			(layer "F.Fab")
		)
		(fp_line
			(start 0.12065 -0.3048)
			(end 0.67945 -0.3048)
			(stroke
				(width 0.1)
				(type default)
			)
			(layer "F.Fab")
		)
		(fp_line
			(start 0.12065 -0.2794)
			(end 0.12065 -0.3048)
			(stroke
				(width 0.1)
				(type default)
			)
			(layer "F.Fab")
		)
		(fp_line
			(start -0.12065 -0.2794)
			(end 0.12065 -0.2794)
			(stroke
				(width 0.1)
				(type default)
			)
			(layer "F.Fab")
		)
		(fp_line
			(start 0.120396 0.2794)
			(end -0.12065 0.2794)
			(stroke
				(width 0.1)
				(type default)
			)
			(layer "F.Fab")
		)
		(fp_line
			(start -0.12065 0.2794)
			(end -0.12065 0.3048)
			(stroke
				(width 0.1)
				(type default)
			)
			(layer "F.Fab")
		)
		(fp_line
			(start 0.67945 0.3048)
			(end 0.120396 0.3048)
			(stroke
				(width 0.1)
				(type default)
			)
			(layer "F.Fab")
		)
		(fp_line
			(start 0.120396 0.3048)
			(end 0.120396 0.2794)
			(stroke
				(width 0.1)
				(type default)
			)
			(layer "F.Fab")
		)
		(fp_line
			(start -0.12065 0.3048)
			(end -0.67945 0.3048)
			(stroke
				(width 0.1)
				(type default)
			)
			(layer "F.Fab")
		)
		(fp_line
			(start -0.67945 0.3048)
			(end -0.67945 -0.305054)
			(stroke
				(width 0.1)
				(type default)
			)
			(layer "F.Fab")
		)
		(pad "1" smd circle
			(at -0.40005 0 90)
			(size 0 0)
			(layers "F.Cu" "F.Mask" "F.Paste")
			(net "P3V3_AUX_SCALED")
		)
		(pad "2" smd circle
			(at 0.40005 0 90)
			(size 0 0)
			(layers "F.Cu" "F.Mask" "F.Paste")
			(net "GND")
		)
	)
	(footprint ""
		(layer "F.Cu")
		(at 301.992284 -31.825184 180)
		(property "Reference" "C506"
			(at 0 0 180)
			(layer "F.SilkS")
			(hide yes)
			(effects
				(font
					(size 1.27 1.27)
				)
			)
		)
		(property "Value" ""
			(at 0 0 180)
			(layer "F.Fab")
			(effects
				(font
					(size 1.27 1.27)
				)
			)
		)
		(duplicate_pad_numbers_are_jumpers no)
		(fp_line
			(start 0.299974 0.150114)
			(end -0.299974 0.150114)
			(stroke
				(width 0.1)
				(type default)
			)
			(layer "F.Fab")
		)
		(fp_line
			(start 0.299974 -0.150114)
			(end 0.299974 0.150114)
			(stroke
				(width 0.1)
				(type default)
			)
			(layer "F.Fab")
		)
		(fp_line
			(start -0.299974 0.150114)
			(end -0.299974 -0.150114)
			(stroke
				(width 0.1)
				(type default)
			)
			(layer "F.Fab")
		)
		(fp_line
			(start -0.299974 -0.150114)
			(end 0.299974 -0.150114)
			(stroke
				(width 0.1)
				(type default)
			)
			(layer "F.Fab")
		)
		(pad "1" smd rect
			(at -0.2667 0 180)
			(size 0.3048 0.381)
			(layers "F.Cu" "F.Mask" "F.Paste")
			(net "P5E_PEX2_STN2_TX_DN<38>")
		)
		(pad "2" smd rect
			(at 0.2667 0 180)
			(size 0.3048 0.381)
			(layers "F.Cu" "F.Mask" "F.Paste")
			(net "P5E_PEX2_STN2_TX_C_DN<38>")
		)
	)
	(footprint ""
		(layer "F.Cu")
		(at 455.542396 -235.200444 -90)
		(property "Reference" "R6608"
			(at 0 0 270)
			(layer "F.SilkS")
			(hide yes)
			(effects
				(font
					(size 1.27 1.27)
				)
			)
		)
		(property "Value" ""
			(at 0 0 270)
			(layer "F.Fab")
			(effects
				(font
					(size 1.27 1.27)
				)
			)
		)
		(duplicate_pad_numbers_are_jumpers no)
		(fp_line
			(start -0.7874 0.4064)
			(end -0.7874 -0.4064)
			(stroke
				(width 0.1524)
				(type default)
			)
			(layer "F.SilkS")
		)
		(fp_line
			(start 0.7874 0.4064)
			(end -0.7874 0.4064)
			(stroke
				(width 0.1524)
				(type default)
			)
			(layer "F.SilkS")
		)
		(fp_line
			(start -0.7874 -0.4064)
			(end 0.7874 -0.4064)
			(stroke
				(width 0.1524)
				(type default)
			)
			(layer "F.SilkS")
		)
		(fp_line
			(start 0.7874 -0.4064)
			(end 0.7874 0.4064)
			(stroke
				(width 0.1524)
				(type default)
			)
			(layer "F.SilkS")
		)
		(fp_line
			(start -0.67945 0.3048)
			(end -0.67945 -0.305054)
			(stroke
				(width 0.1)
				(type default)
			)
			(layer "F.Fab")
		)
		(fp_line
			(start -0.12065 0.3048)
			(end -0.67945 0.3048)
			(stroke
				(width 0.1)
				(type default)
			)
			(layer "F.Fab")
		)
		(fp_line
			(start 0.120396 0.3048)
			(end 0.120396 0.2794)
			(stroke
				(width 0.1)
				(type default)
			)
			(layer "F.Fab")
		)
		(fp_line
			(start 0.67945 0.3048)
			(end 0.120396 0.3048)
			(stroke
				(width 0.1)
				(type default)
			)
			(layer "F.Fab")
		)
		(fp_line
			(start -0.12065 0.2794)
			(end -0.12065 0.3048)
			(stroke
				(width 0.1)
				(type default)
			)
			(layer "F.Fab")
		)
		(fp_line
			(start 0.120396 0.2794)
			(end -0.12065 0.2794)
			(stroke
				(width 0.1)
				(type default)
			)
			(layer "F.Fab")
		)
		(fp_line
			(start -0.12065 -0.2794)
			(end 0.12065 -0.2794)
			(stroke
				(width 0.1)
				(type default)
			)
			(layer "F.Fab")
		)
		(fp_line
			(start 0.12065 -0.2794)
			(end 0.12065 -0.3048)
			(stroke
				(width 0.1)
				(type default)
			)
			(layer "F.Fab")
		)
		(fp_line
			(start 0.12065 -0.3048)
			(end 0.67945 -0.3048)
			(stroke
				(width 0.1)
				(type default)
			)
			(layer "F.Fab")
		)
		(fp_line
			(start 0.67945 -0.3048)
			(end 0.67945 0.3048)
			(stroke
				(width 0.1)
				(type default)
			)
			(layer "F.Fab")
		)
		(fp_line
			(start -0.67945 -0.305054)
			(end -0.12065 -0.305054)
			(stroke
				(width 0.1)
				(type default)
			)
			(layer "F.Fab")
		)
		(fp_line
			(start -0.12065 -0.305054)
			(end -0.12065 -0.2794)
			(stroke
				(width 0.1)
				(type default)
			)
			(layer "F.Fab")
		)
		(pad "1" smd circle
			(at -0.40005 0 270)
			(size 0 0)
			(layers "F.Cu" "F.Mask" "F.Paste")
			(net "UART_PEX0_SDB_BUF_R_TX")
		)
		(pad "2" smd circle
			(at 0.40005 0 270)
			(size 0 0)
			(layers "F.Cu" "F.Mask" "F.Paste")
			(net "UART_PEX0_SDB_CP2108_TX")
		)
	)
	(footprint ""
		(layer "F.Cu")
		(at 428.641764 -27.006296 -90)
		(property "Reference" "PR7130"
			(at 0 0 270)
			(layer "F.SilkS")
			(hide yes)
			(effects
				(font
					(size 1.27 1.27)
				)
			)
		)
		(property "Value" ""
			(at 0 0 270)
			(layer "F.Fab")
			(effects
				(font
					(size 1.27 1.27)
				)
			)
		)
		(duplicate_pad_numbers_are_jumpers no)
		(fp_line
			(start -0.7874 0.4064)
			(end -0.7874 -0.4064)
			(stroke
				(width 0.1524)
				(type default)
			)
			(layer "F.SilkS")
		)
		(fp_line
			(start 0.7874 0.4064)
			(end -0.7874 0.4064)
			(stroke
				(width 0.1524)
				(type default)
			)
			(layer "F.SilkS")
		)
		(fp_line
			(start -0.7874 -0.4064)
			(end 0.7874 -0.4064)
			(stroke
				(width 0.1524)
				(type default)
			)
			(layer "F.SilkS")
		)
		(fp_line
			(start 0.7874 -0.4064)
			(end 0.7874 0.4064)
			(stroke
				(width 0.1524)
				(type default)
			)
			(layer "F.SilkS")
		)
		(fp_line
			(start -0.67945 0.3048)
			(end -0.67945 -0.305054)
			(stroke
				(width 0.1)
				(type default)
			)
			(layer "F.Fab")
		)
		(fp_line
			(start -0.12065 0.3048)
			(end -0.67945 0.3048)
			(stroke
				(width 0.1)
				(type default)
			)
			(layer "F.Fab")
		)
		(fp_line
			(start 0.120396 0.3048)
			(end 0.120396 0.2794)
			(stroke
				(width 0.1)
				(type default)
			)
			(layer "F.Fab")
		)
		(fp_line
			(start 0.67945 0.3048)
			(end 0.120396 0.3048)
			(stroke
				(width 0.1)
				(type default)
			)
			(layer "F.Fab")
		)
		(fp_line
			(start -0.12065 0.2794)
			(end -0.12065 0.3048)
			(stroke
				(width 0.1)
				(type default)
			)
			(layer "F.Fab")
		)
		(fp_line
			(start 0.120396 0.2794)
			(end -0.12065 0.2794)
			(stroke
				(width 0.1)
				(type default)
			)
			(layer "F.Fab")
		)
		(fp_line
			(start -0.12065 -0.2794)
			(end 0.12065 -0.2794)
			(stroke
				(width 0.1)
				(type default)
			)
			(layer "F.Fab")
		)
		(fp_line
			(start 0.12065 -0.2794)
			(end 0.12065 -0.3048)
			(stroke
				(width 0.1)
				(type default)
			)
			(layer "F.Fab")
		)
		(fp_line
			(start 0.12065 -0.3048)
			(end 0.67945 -0.3048)
			(stroke
				(width 0.1)
				(type default)
			)
			(layer "F.Fab")
		)
		(fp_line
			(start 0.67945 -0.3048)
			(end 0.67945 0.3048)
			(stroke
				(width 0.1)
				(type default)
			)
			(layer "F.Fab")
		)
		(fp_line
			(start -0.67945 -0.305054)
			(end -0.12065 -0.305054)
			(stroke
				(width 0.1)
				(type default)
			)
			(layer "F.Fab")
		)
		(fp_line
			(start -0.12065 -0.305054)
			(end -0.12065 -0.2794)
			(stroke
				(width 0.1)
				(type default)
			)
			(layer "F.Fab")
		)
		(pad "1" smd circle
			(at -0.40005 0 270)
			(size 0 0)
			(layers "F.Cu" "F.Mask" "F.Paste")
			(net "P3V3_SSD15_CO_ILIMIT")
		)
		(pad "2" smd circle
			(at 0.40005 0 270)
			(size 0 0)
			(layers "F.Cu" "F.Mask" "F.Paste")
			(net "GND")
		)
	)
	(footprint ""
		(layer "F.Cu")
		(at 179.777644 -116.550186 180)
		(property "Reference" "R160"
			(at 0 0 180)
			(layer "F.SilkS")
			(hide yes)
			(effects
				(font
					(size 1.27 1.27)
				)
			)
		)
		(property "Value" ""
			(at 0 0 180)
			(layer "F.Fab")
			(effects
				(font
					(size 1.27 1.27)
				)
			)
		)
		(duplicate_pad_numbers_are_jumpers no)
		(fp_line
			(start 0.7874 0.4064)
			(end -0.7874 0.4064)
			(stroke
				(width 0.1524)
				(type default)
			)
			(layer "F.SilkS")
		)
		(fp_line
			(start 0.7874 -0.4064)
			(end 0.7874 0.4064)
			(stroke
				(width 0.1524)
				(type default)
			)
			(layer "F.SilkS")
		)
		(fp_line
			(start -0.7874 0.4064)
			(end -0.7874 -0.4064)
			(stroke
				(width 0.1524)
				(type default)
			)
			(layer "F.SilkS")
		)
		(fp_line
			(start -0.7874 -0.4064)
			(end 0.7874 -0.4064)
			(stroke
				(width 0.1524)
				(type default)
			)
			(layer "F.SilkS")
		)
		(fp_line
			(start 0.67945 0.3048)
			(end 0.120396 0.3048)
			(stroke
				(width 0.1)
				(type default)
			)
			(layer "F.Fab")
		)
		(fp_line
			(start 0.67945 -0.3048)
			(end 0.67945 0.3048)
			(stroke
				(width 0.1)
				(type default)
			)
			(layer "F.Fab")
		)
		(fp_line
			(start 0.12065 -0.2794)
			(end 0.12065 -0.3048)
			(stroke
				(width 0.1)
				(type default)
			)
			(layer "F.Fab")
		)
		(fp_line
			(start 0.12065 -0.3048)
			(end 0.67945 -0.3048)
			(stroke
				(width 0.1)
				(type default)
			)
			(layer "F.Fab")
		)
		(fp_line
			(start 0.120396 0.3048)
			(end 0.120396 0.2794)
			(stroke
				(width 0.1)
				(type default)
			)
			(layer "F.Fab")
		)
		(fp_line
			(start 0.120396 0.2794)
			(end -0.12065 0.2794)
			(stroke
				(width 0.1)
				(type default)
			)
			(layer "F.Fab")
		)
		(fp_line
			(start -0.12065 0.3048)
			(end -0.67945 0.3048)
			(stroke
				(width 0.1)
				(type default)
			)
			(layer "F.Fab")
		)
		(fp_line
			(start -0.12065 0.2794)
			(end -0.12065 0.3048)
			(stroke
				(width 0.1)
				(type default)
			)
			(layer "F.Fab")
		)
		(fp_line
			(start -0.12065 -0.2794)
			(end 0.12065 -0.2794)
			(stroke
				(width 0.1)
				(type default)
			)
			(layer "F.Fab")
		)
		(fp_line
			(start -0.12065 -0.305054)
			(end -0.12065 -0.2794)
			(stroke
				(width 0.1)
				(type default)
			)
			(layer "F.Fab")
		)
		(fp_line
			(start -0.67945 0.3048)
			(end -0.67945 -0.305054)
			(stroke
				(width 0.1)
				(type default)
			)
			(layer "F.Fab")
		)
		(fp_line
			(start -0.67945 -0.305054)
			(end -0.12065 -0.305054)
			(stroke
				(width 0.1)
				(type default)
			)
			(layer "F.Fab")
		)
		(pad "1" smd circle
			(at -0.40005 0 180)
			(size 0 0)
			(layers "F.Cu" "F.Mask" "F.Paste")
			(net "PRSNTB2_NIC3_N")
		)
		(pad "2" smd circle
			(at 0.40005 0 180)
			(size 0 0)
			(layers "F.Cu" "F.Mask" "F.Paste")
			(net "P3V3_AUX")
		)
	)
	(footprint ""
		(layer "F.Cu")
		(at 184.491884 -192.058798 180)
		(property "Reference" "R3291"
			(at 0 0 180)
			(layer "F.SilkS")
			(hide yes)
			(effects
				(font
					(size 1.27 1.27)
				)
			)
		)
		(property "Value" ""
			(at 0 0 180)
			(layer "F.Fab")
			(effects
				(font
					(size 1.27 1.27)
				)
			)
		)
		(duplicate_pad_numbers_are_jumpers no)
		(fp_line
			(start 0.7874 0.4064)
			(end -0.7874 0.4064)
			(stroke
				(width 0.1524)
				(type default)
			)
			(layer "F.SilkS")
		)
		(fp_line
			(start 0.7874 -0.4064)
			(end 0.7874 0.4064)
			(stroke
				(width 0.1524)
				(type default)
			)
			(layer "F.SilkS")
		)
		(fp_line
			(start -0.7874 0.4064)
			(end -0.7874 -0.4064)
			(stroke
				(width 0.1524)
				(type default)
			)
			(layer "F.SilkS")
		)
		(fp_line
			(start -0.7874 -0.4064)
			(end 0.7874 -0.4064)
			(stroke
				(width 0.1524)
				(type default)
			)
			(layer "F.SilkS")
		)
		(fp_line
			(start 0.67945 0.3048)
			(end 0.120396 0.3048)
			(stroke
				(width 0.1)
				(type default)
			)
			(layer "F.Fab")
		)
		(fp_line
			(start 0.67945 -0.3048)
			(end 0.67945 0.3048)
			(stroke
				(width 0.1)
				(type default)
			)
			(layer "F.Fab")
		)
		(fp_line
			(start 0.12065 -0.2794)
			(end 0.12065 -0.3048)
			(stroke
				(width 0.1)
				(type default)
			)
			(layer "F.Fab")
		)
		(fp_line
			(start 0.12065 -0.3048)
			(end 0.67945 -0.3048)
			(stroke
				(width 0.1)
				(type default)
			)
			(layer "F.Fab")
		)
		(fp_line
			(start 0.120396 0.3048)
			(end 0.120396 0.2794)
			(stroke
				(width 0.1)
				(type default)
			)
			(layer "F.Fab")
		)
		(fp_line
			(start 0.120396 0.2794)
			(end -0.12065 0.2794)
			(stroke
				(width 0.1)
				(type default)
			)
			(layer "F.Fab")
		)
		(fp_line
			(start -0.12065 0.3048)
			(end -0.67945 0.3048)
			(stroke
				(width 0.1)
				(type default)
			)
			(layer "F.Fab")
		)
		(fp_line
			(start -0.12065 0.2794)
			(end -0.12065 0.3048)
			(stroke
				(width 0.1)
				(type default)
			)
			(layer "F.Fab")
		)
		(fp_line
			(start -0.12065 -0.2794)
			(end 0.12065 -0.2794)
			(stroke
				(width 0.1)
				(type default)
			)
			(layer "F.Fab")
		)
		(fp_line
			(start -0.12065 -0.305054)
			(end -0.12065 -0.2794)
			(stroke
				(width 0.1)
				(type default)
			)
			(layer "F.Fab")
		)
		(fp_line
			(start -0.67945 0.3048)
			(end -0.67945 -0.305054)
			(stroke
				(width 0.1)
				(type default)
			)
			(layer "F.Fab")
		)
		(fp_line
			(start -0.67945 -0.305054)
			(end -0.12065 -0.305054)
			(stroke
				(width 0.1)
				(type default)
			)
			(layer "F.Fab")
		)
		(pad "1" smd circle
			(at -0.40005 0 180)
			(size 0 0)
			(layers "F.Cu" "F.Mask" "F.Paste")
			(net "SPI_BIC1_LS01_EN_N")
		)
		(pad "2" smd circle
			(at 0.40005 0 180)
			(size 0 0)
			(layers "F.Cu" "F.Mask" "F.Paste")
			(net "SPI_BIC1_LS01_EN_R_N")
		)
	)
	(footprint ""
		(layer "F.Cu")
		(at 338.151724 -108.054902 180)
		(property "Reference" "PC818"
			(at 0 0 180)
			(layer "F.SilkS")
			(hide yes)
			(effects
				(font
					(size 1.27 1.27)
				)
			)
		)
		(property "Value" ""
			(at 0 0 180)
			(layer "F.Fab")
			(effects
				(font
					(size 1.27 1.27)
				)
			)
		)
		(duplicate_pad_numbers_are_jumpers no)
		(fp_line
			(start 0.7874 0.4064)
			(end -0.7874 0.4064)
			(stroke
				(width 0.1524)
				(type default)
			)
			(layer "F.SilkS")
		)
		(fp_line
			(start 0.7874 -0.4064)
			(end 0.7874 0.4064)
			(stroke
				(width 0.1524)
				(type default)
			)
			(layer "F.SilkS")
		)
		(fp_line
			(start -0.7874 0.4064)
			(end -0.7874 -0.4064)
			(stroke
				(width 0.1524)
				(type default)
			)
			(layer "F.SilkS")
		)
		(fp_line
			(start -0.7874 -0.4064)
			(end 0.7874 -0.4064)
			(stroke
				(width 0.1524)
				(type default)
			)
			(layer "F.SilkS")
		)
		(fp_line
			(start 0.67945 0.3048)
			(end 0.120396 0.3048)
			(stroke
				(width 0.1)
				(type default)
			)
			(layer "F.Fab")
		)
		(fp_line
			(start 0.67945 -0.3048)
			(end 0.67945 0.3048)
			(stroke
				(width 0.1)
				(type default)
			)
			(layer "F.Fab")
		)
		(fp_line
			(start 0.12065 -0.2794)
			(end 0.12065 -0.3048)
			(stroke
				(width 0.1)
				(type default)
			)
			(layer "F.Fab")
		)
		(fp_line
			(start 0.12065 -0.3048)
			(end 0.67945 -0.3048)
			(stroke
				(width 0.1)
				(type default)
			)
			(layer "F.Fab")
		)
		(fp_line
			(start 0.120396 0.3048)
			(end 0.120396 0.2794)
			(stroke
				(width 0.1)
				(type default)
			)
			(layer "F.Fab")
		)
		(fp_line
			(start 0.120396 0.2794)
			(end -0.12065 0.2794)
			(stroke
				(width 0.1)
				(type default)
			)
			(layer "F.Fab")
		)
		(fp_line
			(start -0.12065 0.3048)
			(end -0.67945 0.3048)
			(stroke
				(width 0.1)
				(type default)
			)
			(layer "F.Fab")
		)
		(fp_line
			(start -0.12065 0.2794)
			(end -0.12065 0.3048)
			(stroke
				(width 0.1)
				(type default)
			)
			(layer "F.Fab")
		)
		(fp_line
			(start -0.12065 -0.2794)
			(end 0.12065 -0.2794)
			(stroke
				(width 0.1)
				(type default)
			)
			(layer "F.Fab")
		)
		(fp_line
			(start -0.12065 -0.305054)
			(end -0.12065 -0.2794)
			(stroke
				(width 0.1)
				(type default)
			)
			(layer "F.Fab")
		)
		(fp_line
			(start -0.67945 0.3048)
			(end -0.67945 -0.305054)
			(stroke
				(width 0.1)
				(type default)
			)
			(layer "F.Fab")
		)
		(fp_line
			(start -0.67945 -0.305054)
			(end -0.12065 -0.305054)
			(stroke
				(width 0.1)
				(type default)
			)
			(layer "F.Fab")
		)
		(pad "1" smd circle
			(at -0.40005 0 180)
			(size 0 0)
			(layers "F.Cu" "F.Mask" "F.Paste")
			(net "P12V_AUX")
		)
		(pad "2" smd circle
			(at 0.40005 0 180)
			(size 0 0)
			(layers "F.Cu" "F.Mask" "F.Paste")
			(net "GND")
		)
	)
	(footprint ""
		(layer "F.Cu")
		(at 221.990158 -79.595472)
		(property "Reference" "R5764"
			(at 0 0 0)
			(layer "F.SilkS")
			(hide yes)
			(effects
				(font
					(size 1.27 1.27)
				)
			)
		)
		(property "Value" ""
			(at 0 0 0)
			(layer "F.Fab")
			(effects
				(font
					(size 1.27 1.27)
				)
			)
		)
		(duplicate_pad_numbers_are_jumpers no)
		(fp_line
			(start -0.7874 -0.4064)
			(end 0.7874 -0.4064)
			(stroke
				(width 0.1524)
				(type default)
			)
			(layer "F.SilkS")
		)
		(fp_line
			(start -0.7874 0.4064)
			(end -0.7874 -0.4064)
			(stroke
				(width 0.1524)
				(type default)
			)
			(layer "F.SilkS")
		)
		(fp_line
			(start 0.7874 -0.4064)
			(end 0.7874 0.4064)
			(stroke
				(width 0.1524)
				(type default)
			)
			(layer "F.SilkS")
		)
		(fp_line
			(start 0.7874 0.4064)
			(end -0.7874 0.4064)
			(stroke
				(width 0.1524)
				(type default)
			)
			(layer "F.SilkS")
		)
		(fp_line
			(start -0.67945 -0.305054)
			(end -0.12065 -0.305054)
			(stroke
				(width 0.1)
				(type default)
			)
			(layer "F.Fab")
		)
		(fp_line
			(start -0.67945 0.3048)
			(end -0.67945 -0.305054)
			(stroke
				(width 0.1)
				(type default)
			)
			(layer "F.Fab")
		)
		(fp_line
			(start -0.12065 -0.305054)
			(end -0.12065 -0.2794)
			(stroke
				(width 0.1)
				(type default)
			)
			(layer "F.Fab")
		)
		(fp_line
			(start -0.12065 -0.2794)
			(end 0.12065 -0.2794)
			(stroke
				(width 0.1)
				(type default)
			)
			(layer "F.Fab")
		)
		(fp_line
			(start -0.12065 0.2794)
			(end -0.12065 0.3048)
			(stroke
				(width 0.1)
				(type default)
			)
			(layer "F.Fab")
		)
		(fp_line
			(start -0.12065 0.3048)
			(end -0.67945 0.3048)
			(stroke
				(width 0.1)
				(type default)
			)
			(layer "F.Fab")
		)
		(fp_line
			(start 0.120396 0.2794)
			(end -0.12065 0.2794)
			(stroke
				(width 0.1)
				(type default)
			)
			(layer "F.Fab")
		)
		(fp_line
			(start 0.120396 0.3048)
			(end 0.120396 0.2794)
			(stroke
				(width 0.1)
				(type default)
			)
			(layer "F.Fab")
		)
		(fp_line
			(start 0.12065 -0.3048)
			(end 0.67945 -0.3048)
			(stroke
				(width 0.1)
				(type default)
			)
			(layer "F.Fab")
		)
		(fp_line
			(start 0.12065 -0.2794)
			(end 0.12065 -0.3048)
			(stroke
				(width 0.1)
				(type default)
			)
			(layer "F.Fab")
		)
		(fp_line
			(start 0.67945 -0.3048)
			(end 0.67945 0.3048)
			(stroke
				(width 0.1)
				(type default)
			)
			(layer "F.Fab")
		)
		(fp_line
			(start 0.67945 0.3048)
			(end 0.120396 0.3048)
			(stroke
				(width 0.1)
				(type default)
			)
			(layer "F.Fab")
		)
		(pad "1" smd circle
			(at -0.40005 0)
			(size 0 0)
			(layers "F.Cu" "F.Mask" "F.Paste")
			(net "SSD10_LED")
		)
		(pad "2" smd circle
			(at 0.40005 0)
			(size 0 0)
			(layers "F.Cu" "F.Mask" "F.Paste")
			(net "SSD10_LED_R")
		)
	)
	(footprint ""
		(layer "F.Cu")
		(at 7.189216 -16.135858 180)
		(property "Reference" "C3873"
			(at 0 0 180)
			(layer "F.SilkS")
			(hide yes)
			(effects
				(font
					(size 1.27 1.27)
				)
			)
		)
		(property "Value" ""
			(at 0 0 180)
			(layer "F.Fab")
			(effects
				(font
					(size 1.27 1.27)
				)
			)
		)
		(duplicate_pad_numbers_are_jumpers no)
		(fp_line
			(start 0.7874 0.4064)
			(end -0.7874 0.4064)
			(stroke
				(width 0.1524)
				(type default)
			)
			(layer "F.SilkS")
		)
		(fp_line
			(start 0.7874 -0.4064)
			(end 0.7874 0.4064)
			(stroke
				(width 0.1524)
				(type default)
			)
			(layer "F.SilkS")
		)
		(fp_line
			(start -0.7874 0.4064)
			(end -0.7874 -0.4064)
			(stroke
				(width 0.1524)
				(type default)
			)
			(layer "F.SilkS")
		)
		(fp_line
			(start -0.7874 -0.4064)
			(end 0.7874 -0.4064)
			(stroke
				(width 0.1524)
				(type default)
			)
			(layer "F.SilkS")
		)
		(fp_line
			(start 0.67945 0.3048)
			(end 0.120396 0.3048)
			(stroke
				(width 0.1)
				(type default)
			)
			(layer "F.Fab")
		)
		(fp_line
			(start 0.67945 -0.3048)
			(end 0.67945 0.3048)
			(stroke
				(width 0.1)
				(type default)
			)
			(layer "F.Fab")
		)
		(fp_line
			(start 0.12065 -0.2794)
			(end 0.12065 -0.3048)
			(stroke
				(width 0.1)
				(type default)
			)
			(layer "F.Fab")
		)
		(fp_line
			(start 0.12065 -0.3048)
			(end 0.67945 -0.3048)
			(stroke
				(width 0.1)
				(type default)
			)
			(layer "F.Fab")
		)
		(fp_line
			(start 0.120396 0.3048)
			(end 0.120396 0.2794)
			(stroke
				(width 0.1)
				(type default)
			)
			(layer "F.Fab")
		)
		(fp_line
			(start 0.120396 0.2794)
			(end -0.12065 0.2794)
			(stroke
				(width 0.1)
				(type default)
			)
			(layer "F.Fab")
		)
		(fp_line
			(start -0.12065 0.3048)
			(end -0.67945 0.3048)
			(stroke
				(width 0.1)
				(type default)
			)
			(layer "F.Fab")
		)
		(fp_line
			(start -0.12065 0.2794)
			(end -0.12065 0.3048)
			(stroke
				(width 0.1)
				(type default)
			)
			(layer "F.Fab")
		)
		(fp_line
			(start -0.12065 -0.2794)
			(end 0.12065 -0.2794)
			(stroke
				(width 0.1)
				(type default)
			)
			(layer "F.Fab")
		)
		(fp_line
			(start -0.12065 -0.305054)
			(end -0.12065 -0.2794)
			(stroke
				(width 0.1)
				(type default)
			)
			(layer "F.Fab")
		)
		(fp_line
			(start -0.67945 0.3048)
			(end -0.67945 -0.305054)
			(stroke
				(width 0.1)
				(type default)
			)
			(layer "F.Fab")
		)
		(fp_line
			(start -0.67945 -0.305054)
			(end -0.12065 -0.305054)
			(stroke
				(width 0.1)
				(type default)
			)
			(layer "F.Fab")
		)
		(pad "1" smd circle
			(at -0.40005 0 180)
			(size 0 0)
			(layers "F.Cu" "F.Mask" "F.Paste")
			(net "P12V_SSD0")
		)
		(pad "2" smd circle
			(at 0.40005 0 180)
			(size 0 0)
			(layers "F.Cu" "F.Mask" "F.Paste")
			(net "GND")
		)
	)
	(footprint ""
		(layer "F.Cu")
		(at 224.686622 -107.056682)
		(property "Reference" "PC626"
			(at 0 0 0)
			(layer "F.SilkS")
			(hide yes)
			(effects
				(font
					(size 1.27 1.27)
				)
			)
		)
		(property "Value" ""
			(at 0 0 0)
			(layer "F.Fab")
			(effects
				(font
					(size 1.27 1.27)
				)
			)
		)
		(duplicate_pad_numbers_are_jumpers no)
		(fp_line
			(start -1.524 -0.762)
			(end 1.524 -0.762)
			(stroke
				(width 0.1524)
				(type default)
			)
			(layer "F.SilkS")
		)
		(fp_line
			(start -1.524 0.762)
			(end -1.524 -0.762)
			(stroke
				(width 0.1524)
				(type default)
			)
			(layer "F.SilkS")
		)
		(fp_line
			(start 1.524 -0.762)
			(end 1.524 0.762)
			(stroke
				(width 0.1524)
				(type default)
			)
			(layer "F.SilkS")
		)
		(fp_line
			(start 1.524 0.762)
			(end -1.524 0.762)
			(stroke
				(width 0.1524)
				(type default)
			)
			(layer "F.SilkS")
		)
		(fp_line
			(start -1.1049 -0.724916)
			(end -1.1049 0.724916)
			(stroke
				(width 0.1)
				(type default)
			)
			(layer "F.Fab")
		)
		(fp_line
			(start -1.1049 0.724916)
			(end 1.1049 0.724916)
			(stroke
				(width 0.1)
				(type default)
			)
			(layer "F.Fab")
		)
		(fp_line
			(start 1.1049 -0.724916)
			(end -1.1049 -0.724916)
			(stroke
				(width 0.1)
				(type default)
			)
			(layer "F.Fab")
		)
		(fp_line
			(start 1.1049 0.724916)
			(end 1.1049 -0.724916)
			(stroke
				(width 0.1)
				(type default)
			)
			(layer "F.Fab")
		)
		(pad "1" smd rect
			(at -0.889 0 180)
			(size 1.016 1.27)
			(layers "F.Cu" "F.Mask" "F.Paste")
			(net "P12V_NIC3_R")
		)
		(pad "2" smd rect
			(at 0.889 0 180)
			(size 1.016 1.27)
			(layers "F.Cu" "F.Mask" "F.Paste")
			(net "GND")
		)
	)
	(footprint ""
		(layer "F.Cu")
		(at 366.507776 -152.71115 90)
		(property "Reference" "R750"
			(at 0 0 90)
			(layer "F.SilkS")
			(hide yes)
			(effects
				(font
					(size 1.27 1.27)
				)
			)
		)
		(property "Value" ""
			(at 0 0 90)
			(layer "F.Fab")
			(effects
				(font
					(size 1.27 1.27)
				)
			)
		)
		(duplicate_pad_numbers_are_jumpers no)
		(fp_line
			(start 0.7874 -0.4064)
			(end 0.7874 0.4064)
			(stroke
				(width 0.1524)
				(type default)
			)
			(layer "F.SilkS")
		)
		(fp_line
			(start -0.7874 -0.4064)
			(end 0.7874 -0.4064)
			(stroke
				(width 0.1524)
				(type default)
			)
			(layer "F.SilkS")
		)
		(fp_line
			(start 0.7874 0.4064)
			(end -0.7874 0.4064)
			(stroke
				(width 0.1524)
				(type default)
			)
			(layer "F.SilkS")
		)
		(fp_line
			(start -0.7874 0.4064)
			(end -0.7874 -0.4064)
			(stroke
				(width 0.1524)
				(type default)
			)
			(layer "F.SilkS")
		)
		(fp_line
			(start -0.12065 -0.305054)
			(end -0.12065 -0.2794)
			(stroke
				(width 0.1)
				(type default)
			)
			(layer "F.Fab")
		)
		(fp_line
			(start -0.67945 -0.305054)
			(end -0.12065 -0.305054)
			(stroke
				(width 0.1)
				(type default)
			)
			(layer "F.Fab")
		)
		(fp_line
			(start 0.67945 -0.3048)
			(end 0.67945 0.3048)
			(stroke
				(width 0.1)
				(type default)
			)
			(layer "F.Fab")
		)
		(fp_line
			(start 0.12065 -0.3048)
			(end 0.67945 -0.3048)
			(stroke
				(width 0.1)
				(type default)
			)
			(layer "F.Fab")
		)
		(fp_line
			(start 0.12065 -0.2794)
			(end 0.12065 -0.3048)
			(stroke
				(width 0.1)
				(type default)
			)
			(layer "F.Fab")
		)
		(fp_line
			(start -0.12065 -0.2794)
			(end 0.12065 -0.2794)
			(stroke
				(width 0.1)
				(type default)
			)
			(layer "F.Fab")
		)
		(fp_line
			(start 0.120396 0.2794)
			(end -0.12065 0.2794)
			(stroke
				(width 0.1)
				(type default)
			)
			(layer "F.Fab")
		)
		(fp_line
			(start -0.12065 0.2794)
			(end -0.12065 0.3048)
			(stroke
				(width 0.1)
				(type default)
			)
			(layer "F.Fab")
		)
		(fp_line
			(start 0.67945 0.3048)
			(end 0.120396 0.3048)
			(stroke
				(width 0.1)
				(type default)
			)
			(layer "F.Fab")
		)
		(fp_line
			(start 0.120396 0.3048)
			(end 0.120396 0.2794)
			(stroke
				(width 0.1)
				(type default)
			)
			(layer "F.Fab")
		)
		(fp_line
			(start -0.12065 0.3048)
			(end -0.67945 0.3048)
			(stroke
				(width 0.1)
				(type default)
			)
			(layer "F.Fab")
		)
		(fp_line
			(start -0.67945 0.3048)
			(end -0.67945 -0.305054)
			(stroke
				(width 0.1)
				(type default)
			)
			(layer "F.Fab")
		)
		(pad "1" smd circle
			(at -0.40005 0 90)
			(size 0 0)
			(layers "F.Cu" "F.Mask" "F.Paste")
			(net "NIC6_ADC_ALERT_N")
		)
		(pad "2" smd circle
			(at 0.40005 0 90)
			(size 0 0)
			(layers "F.Cu" "F.Mask" "F.Paste")
			(net "NIC_ADC_ALERT_N")
		)
	)
	(footprint ""
		(layer "F.Cu")
		(at 179.570634 -137.848848 180)
		(property "Reference" "R159"
			(at 0 0 180)
			(layer "F.SilkS")
			(hide yes)
			(effects
				(font
					(size 1.27 1.27)
				)
			)
		)
		(property "Value" ""
			(at 0 0 180)
			(layer "F.Fab")
			(effects
				(font
					(size 1.27 1.27)
				)
			)
		)
		(duplicate_pad_numbers_are_jumpers no)
		(fp_line
			(start 0.7874 0.4064)
			(end -0.7874 0.4064)
			(stroke
				(width 0.1524)
				(type default)
			)
			(layer "F.SilkS")
		)
		(fp_line
			(start 0.7874 -0.4064)
			(end 0.7874 0.4064)
			(stroke
				(width 0.1524)
				(type default)
			)
			(layer "F.SilkS")
		)
		(fp_line
			(start -0.7874 0.4064)
			(end -0.7874 -0.4064)
			(stroke
				(width 0.1524)
				(type default)
			)
			(layer "F.SilkS")
		)
		(fp_line
			(start -0.7874 -0.4064)
			(end 0.7874 -0.4064)
			(stroke
				(width 0.1524)
				(type default)
			)
			(layer "F.SilkS")
		)
		(fp_line
			(start 0.67945 0.3048)
			(end 0.120396 0.3048)
			(stroke
				(width 0.1)
				(type default)
			)
			(layer "F.Fab")
		)
		(fp_line
			(start 0.67945 -0.3048)
			(end 0.67945 0.3048)
			(stroke
				(width 0.1)
				(type default)
			)
			(layer "F.Fab")
		)
		(fp_line
			(start 0.12065 -0.2794)
			(end 0.12065 -0.3048)
			(stroke
				(width 0.1)
				(type default)
			)
			(layer "F.Fab")
		)
		(fp_line
			(start 0.12065 -0.3048)
			(end 0.67945 -0.3048)
			(stroke
				(width 0.1)
				(type default)
			)
			(layer "F.Fab")
		)
		(fp_line
			(start 0.120396 0.3048)
			(end 0.120396 0.2794)
			(stroke
				(width 0.1)
				(type default)
			)
			(layer "F.Fab")
		)
		(fp_line
			(start 0.120396 0.2794)
			(end -0.12065 0.2794)
			(stroke
				(width 0.1)
				(type default)
			)
			(layer "F.Fab")
		)
		(fp_line
			(start -0.12065 0.3048)
			(end -0.67945 0.3048)
			(stroke
				(width 0.1)
				(type default)
			)
			(layer "F.Fab")
		)
		(fp_line
			(start -0.12065 0.2794)
			(end -0.12065 0.3048)
			(stroke
				(width 0.1)
				(type default)
			)
			(layer "F.Fab")
		)
		(fp_line
			(start -0.12065 -0.2794)
			(end 0.12065 -0.2794)
			(stroke
				(width 0.1)
				(type default)
			)
			(layer "F.Fab")
		)
		(fp_line
			(start -0.12065 -0.305054)
			(end -0.12065 -0.2794)
			(stroke
				(width 0.1)
				(type default)
			)
			(layer "F.Fab")
		)
		(fp_line
			(start -0.67945 0.3048)
			(end -0.67945 -0.305054)
			(stroke
				(width 0.1)
				(type default)
			)
			(layer "F.Fab")
		)
		(fp_line
			(start -0.67945 -0.305054)
			(end -0.12065 -0.305054)
			(stroke
				(width 0.1)
				(type default)
			)
			(layer "F.Fab")
		)
		(pad "1" smd circle
			(at -0.40005 0 180)
			(size 0 0)
			(layers "F.Cu" "F.Mask" "F.Paste")
			(net "PRSNTB1_NIC3_N")
		)
		(pad "2" smd circle
			(at 0.40005 0 180)
			(size 0 0)
			(layers "F.Cu" "F.Mask" "F.Paste")
			(net "P3V3_AUX")
		)
	)
	(footprint ""
		(layer "F.Cu")
		(at 80.53959 -138.661648 180)
		(property "Reference" "R90"
			(at 0 0 180)
			(layer "F.SilkS")
			(hide yes)
			(effects
				(font
					(size 1.27 1.27)
				)
			)
		)
		(property "Value" ""
			(at 0 0 180)
			(layer "F.Fab")
			(effects
				(font
					(size 1.27 1.27)
				)
			)
		)
		(duplicate_pad_numbers_are_jumpers no)
		(fp_line
			(start 0.7874 0.4064)
			(end -0.7874 0.4064)
			(stroke
				(width 0.1524)
				(type default)
			)
			(layer "F.SilkS")
		)
		(fp_line
			(start 0.7874 -0.4064)
			(end 0.7874 0.4064)
			(stroke
				(width 0.1524)
				(type default)
			)
			(layer "F.SilkS")
		)
		(fp_line
			(start -0.7874 0.4064)
			(end -0.7874 -0.4064)
			(stroke
				(width 0.1524)
				(type default)
			)
			(layer "F.SilkS")
		)
		(fp_line
			(start -0.7874 -0.4064)
			(end 0.7874 -0.4064)
			(stroke
				(width 0.1524)
				(type default)
			)
			(layer "F.SilkS")
		)
		(fp_line
			(start 0.67945 0.3048)
			(end 0.120396 0.3048)
			(stroke
				(width 0.1)
				(type default)
			)
			(layer "F.Fab")
		)
		(fp_line
			(start 0.67945 -0.3048)
			(end 0.67945 0.3048)
			(stroke
				(width 0.1)
				(type default)
			)
			(layer "F.Fab")
		)
		(fp_line
			(start 0.12065 -0.2794)
			(end 0.12065 -0.3048)
			(stroke
				(width 0.1)
				(type default)
			)
			(layer "F.Fab")
		)
		(fp_line
			(start 0.12065 -0.3048)
			(end 0.67945 -0.3048)
			(stroke
				(width 0.1)
				(type default)
			)
			(layer "F.Fab")
		)
		(fp_line
			(start 0.120396 0.3048)
			(end 0.120396 0.2794)
			(stroke
				(width 0.1)
				(type default)
			)
			(layer "F.Fab")
		)
		(fp_line
			(start 0.120396 0.2794)
			(end -0.12065 0.2794)
			(stroke
				(width 0.1)
				(type default)
			)
			(layer "F.Fab")
		)
		(fp_line
			(start -0.12065 0.3048)
			(end -0.67945 0.3048)
			(stroke
				(width 0.1)
				(type default)
			)
			(layer "F.Fab")
		)
		(fp_line
			(start -0.12065 0.2794)
			(end -0.12065 0.3048)
			(stroke
				(width 0.1)
				(type default)
			)
			(layer "F.Fab")
		)
		(fp_line
			(start -0.12065 -0.2794)
			(end 0.12065 -0.2794)
			(stroke
				(width 0.1)
				(type default)
			)
			(layer "F.Fab")
		)
		(fp_line
			(start -0.12065 -0.305054)
			(end -0.12065 -0.2794)
			(stroke
				(width 0.1)
				(type default)
			)
			(layer "F.Fab")
		)
		(fp_line
			(start -0.67945 0.3048)
			(end -0.67945 -0.305054)
			(stroke
				(width 0.1)
				(type default)
			)
			(layer "F.Fab")
		)
		(fp_line
			(start -0.67945 -0.305054)
			(end -0.12065 -0.305054)
			(stroke
				(width 0.1)
				(type default)
			)
			(layer "F.Fab")
		)
		(pad "1" smd circle
			(at -0.40005 0 180)
			(size 0 0)
			(layers "F.Cu" "F.Mask" "F.Paste")
			(net "PRSNT_NIC1_N")
		)
		(pad "2" smd circle
			(at 0.40005 0 180)
			(size 0 0)
			(layers "F.Cu" "F.Mask" "F.Paste")
			(net "PRSNTB0_NIC1_N")
		)
	)
	(footprint ""
		(layer "F.Cu")
		(at 143.0528 -262.649208 90)
		(property "Reference" "C3228"
			(at 0 0 90)
			(layer "F.SilkS")
			(hide yes)
			(effects
				(font
					(size 1.27 1.27)
				)
			)
		)
		(property "Value" ""
			(at 0 0 90)
			(layer "F.Fab")
			(effects
				(font
					(size 1.27 1.27)
				)
			)
		)
		(duplicate_pad_numbers_are_jumpers no)
		(fp_line
			(start 0.299974 -0.150114)
			(end 0.299974 0.150114)
			(stroke
				(width 0.1)
				(type default)
			)
			(layer "F.Fab")
		)
		(fp_line
			(start -0.299974 -0.150114)
			(end 0.299974 -0.150114)
			(stroke
				(width 0.1)
				(type default)
			)
			(layer "F.Fab")
		)
		(fp_line
			(start 0.299974 0.150114)
			(end -0.299974 0.150114)
			(stroke
				(width 0.1)
				(type default)
			)
			(layer "F.Fab")
		)
		(fp_line
			(start -0.299974 0.150114)
			(end -0.299974 -0.150114)
			(stroke
				(width 0.1)
				(type default)
			)
			(layer "F.Fab")
		)
		(pad "1" smd rect
			(at -0.2667 0 90)
			(size 0.3048 0.381)
			(layers "F.Cu" "F.Mask" "F.Paste")
			(net "P1V8_PLL0_PEX1")
		)
		(pad "2" smd rect
			(at 0.2667 0 90)
			(size 0.3048 0.381)
			(layers "F.Cu" "F.Mask" "F.Paste")
			(net "GND")
		)
	)
	(footprint ""
		(layer "F.Cu")
		(at 101.829362 -385.605274 -90)
		(property "Reference" "R5444"
			(at 0 0 270)
			(layer "F.SilkS")
			(hide yes)
			(effects
				(font
					(size 1.27 1.27)
				)
			)
		)
		(property "Value" ""
			(at 0 0 270)
			(layer "F.Fab")
			(effects
				(font
					(size 1.27 1.27)
				)
			)
		)
		(duplicate_pad_numbers_are_jumpers no)
		(fp_line
			(start -0.007874 0.4064)
			(end -0.7874 0.4064)
			(stroke
				(width 0.1524)
				(type default)
			)
			(layer "F.SilkS")
		)
		(fp_line
			(start -0.7874 -0.4064)
			(end 0.7874 -0.4064)
			(stroke
				(width 0.1524)
				(type default)
			)
			(layer "F.SilkS")
		)
		(fp_line
			(start 0.7874 -0.4064)
			(end 0.7874 0.4064)
			(stroke
				(width 0.1524)
				(type default)
			)
			(layer "F.SilkS")
		)
		(fp_line
			(start -0.67945 0.3048)
			(end -0.67945 -0.305054)
			(stroke
				(width 0.1)
				(type default)
			)
			(layer "F.Fab")
		)
		(fp_line
			(start -0.12065 0.3048)
			(end -0.67945 0.3048)
			(stroke
				(width 0.1)
				(type default)
			)
			(layer "F.Fab")
		)
		(fp_line
			(start 0.120396 0.3048)
			(end 0.120396 0.2794)
			(stroke
				(width 0.1)
				(type default)
			)
			(layer "F.Fab")
		)
		(fp_line
			(start 0.67945 0.3048)
			(end 0.120396 0.3048)
			(stroke
				(width 0.1)
				(type default)
			)
			(layer "F.Fab")
		)
		(fp_line
			(start -0.12065 0.2794)
			(end -0.12065 0.3048)
			(stroke
				(width 0.1)
				(type default)
			)
			(layer "F.Fab")
		)
		(fp_line
			(start 0.120396 0.2794)
			(end -0.12065 0.2794)
			(stroke
				(width 0.1)
				(type default)
			)
			(layer "F.Fab")
		)
		(fp_line
			(start -0.12065 -0.2794)
			(end 0.12065 -0.2794)
			(stroke
				(width 0.1)
				(type default)
			)
			(layer "F.Fab")
		)
		(fp_line
			(start 0.12065 -0.2794)
			(end 0.12065 -0.3048)
			(stroke
				(width 0.1)
				(type default)
			)
			(layer "F.Fab")
		)
		(fp_line
			(start 0.12065 -0.3048)
			(end 0.67945 -0.3048)
			(stroke
				(width 0.1)
				(type default)
			)
			(layer "F.Fab")
		)
		(fp_line
			(start 0.67945 -0.3048)
			(end 0.67945 0.3048)
			(stroke
				(width 0.1)
				(type default)
			)
			(layer "F.Fab")
		)
		(fp_line
			(start -0.67945 -0.305054)
			(end -0.12065 -0.305054)
			(stroke
				(width 0.1)
				(type default)
			)
			(layer "F.Fab")
		)
		(fp_line
			(start -0.12065 -0.305054)
			(end -0.12065 -0.2794)
			(stroke
				(width 0.1)
				(type default)
			)
			(layer "F.Fab")
		)
		(pad "1" smd rect
			(at -0.40005 0 90)
			(size 0.4572 0.508)
			(layers "F.Cu" "F.Mask" "F.Paste")
			(net "USB2_MB_BMC_R_DP")
		)
		(pad "2" smd rect
			(at 0.40005 0 90)
			(size 0.4572 0.508)
			(layers "F.Cu" "F.Mask" "F.Paste")
			(net "USB2_MB_BMC_DP")
		)
	)
	(footprint ""
		(layer "F.Cu")
		(at 382.468882 -230.43896)
		(property "Reference" "C2579"
			(at 0 0 0)
			(layer "F.SilkS")
			(hide yes)
			(effects
				(font
					(size 1.27 1.27)
				)
			)
		)
		(property "Value" ""
			(at 0 0 0)
			(layer "F.Fab")
			(effects
				(font
					(size 1.27 1.27)
				)
			)
		)
		(duplicate_pad_numbers_are_jumpers no)
		(fp_line
			(start -0.7874 -0.4064)
			(end 0.7874 -0.4064)
			(stroke
				(width 0.1524)
				(type default)
			)
			(layer "F.SilkS")
		)
		(fp_line
			(start -0.7874 0.4064)
			(end -0.7874 -0.4064)
			(stroke
				(width 0.1524)
				(type default)
			)
			(layer "F.SilkS")
		)
		(fp_line
			(start 0.7874 -0.4064)
			(end 0.7874 0.4064)
			(stroke
				(width 0.1524)
				(type default)
			)
			(layer "F.SilkS")
		)
		(fp_line
			(start 0.7874 0.4064)
			(end -0.7874 0.4064)
			(stroke
				(width 0.1524)
				(type default)
			)
			(layer "F.SilkS")
		)
		(fp_line
			(start -0.67945 -0.305054)
			(end -0.12065 -0.305054)
			(stroke
				(width 0.1)
				(type default)
			)
			(layer "F.Fab")
		)
		(fp_line
			(start -0.67945 0.3048)
			(end -0.67945 -0.305054)
			(stroke
				(width 0.1)
				(type default)
			)
			(layer "F.Fab")
		)
		(fp_line
			(start -0.12065 -0.305054)
			(end -0.12065 -0.2794)
			(stroke
				(width 0.1)
				(type default)
			)
			(layer "F.Fab")
		)
		(fp_line
			(start -0.12065 -0.2794)
			(end 0.12065 -0.2794)
			(stroke
				(width 0.1)
				(type default)
			)
			(layer "F.Fab")
		)
		(fp_line
			(start -0.12065 0.2794)
			(end -0.12065 0.3048)
			(stroke
				(width 0.1)
				(type default)
			)
			(layer "F.Fab")
		)
		(fp_line
			(start -0.12065 0.3048)
			(end -0.67945 0.3048)
			(stroke
				(width 0.1)
				(type default)
			)
			(layer "F.Fab")
		)
		(fp_line
			(start 0.120396 0.2794)
			(end -0.12065 0.2794)
			(stroke
				(width 0.1)
				(type default)
			)
			(layer "F.Fab")
		)
		(fp_line
			(start 0.120396 0.3048)
			(end 0.120396 0.2794)
			(stroke
				(width 0.1)
				(type default)
			)
			(layer "F.Fab")
		)
		(fp_line
			(start 0.12065 -0.3048)
			(end 0.67945 -0.3048)
			(stroke
				(width 0.1)
				(type default)
			)
			(layer "F.Fab")
		)
		(fp_line
			(start 0.12065 -0.2794)
			(end 0.12065 -0.3048)
			(stroke
				(width 0.1)
				(type default)
			)
			(layer "F.Fab")
		)
		(fp_line
			(start 0.67945 -0.3048)
			(end 0.67945 0.3048)
			(stroke
				(width 0.1)
				(type default)
			)
			(layer "F.Fab")
		)
		(fp_line
			(start 0.67945 0.3048)
			(end 0.120396 0.3048)
			(stroke
				(width 0.1)
				(type default)
			)
			(layer "F.Fab")
		)
		(pad "1" smd circle
			(at -0.40005 0)
			(size 0 0)
			(layers "F.Cu" "F.Mask" "F.Paste")
			(net "OSC_SDB_OUT")
		)
		(pad "2" smd circle
			(at 0.40005 0)
			(size 0 0)
			(layers "F.Cu" "F.Mask" "F.Paste")
			(net "GND")
		)
	)
	(footprint ""
		(layer "F.Cu")
		(at 103.11511 -367.488978 180)
		(property "Reference" "R6299"
			(at 0 0 180)
			(layer "F.SilkS")
			(hide yes)
			(effects
				(font
					(size 1.27 1.27)
				)
			)
		)
		(property "Value" ""
			(at 0 0 180)
			(layer "F.Fab")
			(effects
				(font
					(size 1.27 1.27)
				)
			)
		)
		(duplicate_pad_numbers_are_jumpers no)
		(fp_line
			(start 0.7874 0.4064)
			(end -0.7874 0.4064)
			(stroke
				(width 0.1524)
				(type default)
			)
			(layer "F.SilkS")
		)
		(fp_line
			(start 0.7874 -0.4064)
			(end 0.7874 0.4064)
			(stroke
				(width 0.1524)
				(type default)
			)
			(layer "F.SilkS")
		)
		(fp_line
			(start -0.7874 0.4064)
			(end -0.7874 -0.4064)
			(stroke
				(width 0.1524)
				(type default)
			)
			(layer "F.SilkS")
		)
		(fp_line
			(start -0.7874 -0.4064)
			(end 0.7874 -0.4064)
			(stroke
				(width 0.1524)
				(type default)
			)
			(layer "F.SilkS")
		)
		(fp_line
			(start 0.67945 0.3048)
			(end 0.120396 0.3048)
			(stroke
				(width 0.1)
				(type default)
			)
			(layer "F.Fab")
		)
		(fp_line
			(start 0.67945 -0.3048)
			(end 0.67945 0.3048)
			(stroke
				(width 0.1)
				(type default)
			)
			(layer "F.Fab")
		)
		(fp_line
			(start 0.12065 -0.2794)
			(end 0.12065 -0.3048)
			(stroke
				(width 0.1)
				(type default)
			)
			(layer "F.Fab")
		)
		(fp_line
			(start 0.12065 -0.3048)
			(end 0.67945 -0.3048)
			(stroke
				(width 0.1)
				(type default)
			)
			(layer "F.Fab")
		)
		(fp_line
			(start 0.120396 0.3048)
			(end 0.120396 0.2794)
			(stroke
				(width 0.1)
				(type default)
			)
			(layer "F.Fab")
		)
		(fp_line
			(start 0.120396 0.2794)
			(end -0.12065 0.2794)
			(stroke
				(width 0.1)
				(type default)
			)
			(layer "F.Fab")
		)
		(fp_line
			(start -0.12065 0.3048)
			(end -0.67945 0.3048)
			(stroke
				(width 0.1)
				(type default)
			)
			(layer "F.Fab")
		)
		(fp_line
			(start -0.12065 0.2794)
			(end -0.12065 0.3048)
			(stroke
				(width 0.1)
				(type default)
			)
			(layer "F.Fab")
		)
		(fp_line
			(start -0.12065 -0.2794)
			(end 0.12065 -0.2794)
			(stroke
				(width 0.1)
				(type default)
			)
			(layer "F.Fab")
		)
		(fp_line
			(start -0.12065 -0.305054)
			(end -0.12065 -0.2794)
			(stroke
				(width 0.1)
				(type default)
			)
			(layer "F.Fab")
		)
		(fp_line
			(start -0.67945 0.3048)
			(end -0.67945 -0.305054)
			(stroke
				(width 0.1)
				(type default)
			)
			(layer "F.Fab")
		)
		(fp_line
			(start -0.67945 -0.305054)
			(end -0.12065 -0.305054)
			(stroke
				(width 0.1)
				(type default)
			)
			(layer "F.Fab")
		)
		(pad "1" smd circle
			(at -0.40005 0 180)
			(size 0 0)
			(layers "F.Cu" "F.Mask" "F.Paste")
			(net "RST_MB_PERST_0_N")
		)
		(pad "2" smd circle
			(at 0.40005 0 180)
			(size 0 0)
			(layers "F.Cu" "F.Mask" "F.Paste")
			(net "GND")
		)
	)
	(footprint ""
		(layer "F.Cu")
		(at 229.471474 -136.669272 90)
		(property "Reference" "R4202"
			(at 0 0 90)
			(layer "F.SilkS")
			(hide yes)
			(effects
				(font
					(size 1.27 1.27)
				)
			)
		)
		(property "Value" ""
			(at 0 0 90)
			(layer "F.Fab")
			(effects
				(font
					(size 1.27 1.27)
				)
			)
		)
		(duplicate_pad_numbers_are_jumpers no)
		(fp_line
			(start 0.7874 -0.4064)
			(end 0.7874 0.4064)
			(stroke
				(width 0.1524)
				(type default)
			)
			(layer "F.SilkS")
		)
		(fp_line
			(start -0.7874 -0.4064)
			(end 0.7874 -0.4064)
			(stroke
				(width 0.1524)
				(type default)
			)
			(layer "F.SilkS")
		)
		(fp_line
			(start 0.7874 0.4064)
			(end -0.7874 0.4064)
			(stroke
				(width 0.1524)
				(type default)
			)
			(layer "F.SilkS")
		)
		(fp_line
			(start -0.7874 0.4064)
			(end -0.7874 -0.4064)
			(stroke
				(width 0.1524)
				(type default)
			)
			(layer "F.SilkS")
		)
		(fp_line
			(start -0.12065 -0.305054)
			(end -0.12065 -0.2794)
			(stroke
				(width 0.1)
				(type default)
			)
			(layer "F.Fab")
		)
		(fp_line
			(start -0.67945 -0.305054)
			(end -0.12065 -0.305054)
			(stroke
				(width 0.1)
				(type default)
			)
			(layer "F.Fab")
		)
		(fp_line
			(start 0.67945 -0.3048)
			(end 0.67945 0.3048)
			(stroke
				(width 0.1)
				(type default)
			)
			(layer "F.Fab")
		)
		(fp_line
			(start 0.12065 -0.3048)
			(end 0.67945 -0.3048)
			(stroke
				(width 0.1)
				(type default)
			)
			(layer "F.Fab")
		)
		(fp_line
			(start 0.12065 -0.2794)
			(end 0.12065 -0.3048)
			(stroke
				(width 0.1)
				(type default)
			)
			(layer "F.Fab")
		)
		(fp_line
			(start -0.12065 -0.2794)
			(end 0.12065 -0.2794)
			(stroke
				(width 0.1)
				(type default)
			)
			(layer "F.Fab")
		)
		(fp_line
			(start 0.120396 0.2794)
			(end -0.12065 0.2794)
			(stroke
				(width 0.1)
				(type default)
			)
			(layer "F.Fab")
		)
		(fp_line
			(start -0.12065 0.2794)
			(end -0.12065 0.3048)
			(stroke
				(width 0.1)
				(type default)
			)
			(layer "F.Fab")
		)
		(fp_line
			(start 0.67945 0.3048)
			(end 0.120396 0.3048)
			(stroke
				(width 0.1)
				(type default)
			)
			(layer "F.Fab")
		)
		(fp_line
			(start 0.120396 0.3048)
			(end 0.120396 0.2794)
			(stroke
				(width 0.1)
				(type default)
			)
			(layer "F.Fab")
		)
		(fp_line
			(start -0.12065 0.3048)
			(end -0.67945 0.3048)
			(stroke
				(width 0.1)
				(type default)
			)
			(layer "F.Fab")
		)
		(fp_line
			(start -0.67945 0.3048)
			(end -0.67945 -0.305054)
			(stroke
				(width 0.1)
				(type default)
			)
			(layer "F.Fab")
		)
		(pad "1" smd circle
			(at -0.40005 0 90)
			(size 0 0)
			(layers "F.Cu" "F.Mask" "F.Paste")
			(net "GND")
		)
		(pad "2" smd circle
			(at 0.40005 0 90)
			(size 0 0)
			(layers "F.Cu" "F.Mask" "F.Paste")
			(net "CLK_CK440_PEX_SMB_ADDR0")
		)
	)
	(footprint ""
		(layer "F.Cu")
		(at 122.809254 -26.03373)
		(property "Reference" "R4060"
			(at 0 0 0)
			(layer "F.SilkS")
			(hide yes)
			(effects
				(font
					(size 1.27 1.27)
				)
			)
		)
		(property "Value" ""
			(at 0 0 0)
			(layer "F.Fab")
			(effects
				(font
					(size 1.27 1.27)
				)
			)
		)
		(duplicate_pad_numbers_are_jumpers no)
		(fp_line
			(start -0.7874 -0.4064)
			(end 0.7874 -0.4064)
			(stroke
				(width 0.1524)
				(type default)
			)
			(layer "F.SilkS")
		)
		(fp_line
			(start -0.7874 0.4064)
			(end -0.7874 -0.4064)
			(stroke
				(width 0.1524)
				(type default)
			)
			(layer "F.SilkS")
		)
		(fp_line
			(start 0.7874 -0.4064)
			(end 0.7874 0.4064)
			(stroke
				(width 0.1524)
				(type default)
			)
			(layer "F.SilkS")
		)
		(fp_line
			(start 0.7874 0.4064)
			(end -0.7874 0.4064)
			(stroke
				(width 0.1524)
				(type default)
			)
			(layer "F.SilkS")
		)
		(fp_line
			(start -0.67945 -0.305054)
			(end -0.12065 -0.305054)
			(stroke
				(width 0.1)
				(type default)
			)
			(layer "F.Fab")
		)
		(fp_line
			(start -0.67945 0.3048)
			(end -0.67945 -0.305054)
			(stroke
				(width 0.1)
				(type default)
			)
			(layer "F.Fab")
		)
		(fp_line
			(start -0.12065 -0.305054)
			(end -0.12065 -0.2794)
			(stroke
				(width 0.1)
				(type default)
			)
			(layer "F.Fab")
		)
		(fp_line
			(start -0.12065 -0.2794)
			(end 0.12065 -0.2794)
			(stroke
				(width 0.1)
				(type default)
			)
			(layer "F.Fab")
		)
		(fp_line
			(start -0.12065 0.2794)
			(end -0.12065 0.3048)
			(stroke
				(width 0.1)
				(type default)
			)
			(layer "F.Fab")
		)
		(fp_line
			(start -0.12065 0.3048)
			(end -0.67945 0.3048)
			(stroke
				(width 0.1)
				(type default)
			)
			(layer "F.Fab")
		)
		(fp_line
			(start 0.120396 0.2794)
			(end -0.12065 0.2794)
			(stroke
				(width 0.1)
				(type default)
			)
			(layer "F.Fab")
		)
		(fp_line
			(start 0.120396 0.3048)
			(end 0.120396 0.2794)
			(stroke
				(width 0.1)
				(type default)
			)
			(layer "F.Fab")
		)
		(fp_line
			(start 0.12065 -0.3048)
			(end 0.67945 -0.3048)
			(stroke
				(width 0.1)
				(type default)
			)
			(layer "F.Fab")
		)
		(fp_line
			(start 0.12065 -0.2794)
			(end 0.12065 -0.3048)
			(stroke
				(width 0.1)
				(type default)
			)
			(layer "F.Fab")
		)
		(fp_line
			(start 0.67945 -0.3048)
			(end 0.67945 0.3048)
			(stroke
				(width 0.1)
				(type default)
			)
			(layer "F.Fab")
		)
		(fp_line
			(start 0.67945 0.3048)
			(end 0.120396 0.3048)
			(stroke
				(width 0.1)
				(type default)
			)
			(layer "F.Fab")
		)
		(pad "1" smd circle
			(at -0.40005 0)
			(size 0 0)
			(layers "F.Cu" "F.Mask" "F.Paste")
			(net "P3V3_AUX")
		)
		(pad "2" smd circle
			(at 0.40005 0)
			(size 0 0)
			(layers "F.Cu" "F.Mask" "F.Paste")
			(net "PRSNT_SSD4_R_N")
		)
	)
	(footprint ""
		(layer "F.Cu")
		(at 15.18539 -308.28488 180)
		(property "Reference" "PR166"
			(at 0 0 180)
			(layer "F.SilkS")
			(hide yes)
			(effects
				(font
					(size 1.27 1.27)
				)
			)
		)
		(property "Value" ""
			(at 0 0 180)
			(layer "F.Fab")
			(effects
				(font
					(size 1.27 1.27)
				)
			)
		)
		(duplicate_pad_numbers_are_jumpers no)
		(fp_line
			(start 0.7874 0.4064)
			(end -0.7874 0.4064)
			(stroke
				(width 0.1524)
				(type default)
			)
			(layer "F.SilkS")
		)
		(fp_line
			(start 0.7874 -0.4064)
			(end 0.7874 0.4064)
			(stroke
				(width 0.1524)
				(type default)
			)
			(layer "F.SilkS")
		)
		(fp_line
			(start -0.7874 0.4064)
			(end -0.7874 -0.4064)
			(stroke
				(width 0.1524)
				(type default)
			)
			(layer "F.SilkS")
		)
		(fp_line
			(start -0.7874 -0.4064)
			(end 0.7874 -0.4064)
			(stroke
				(width 0.1524)
				(type default)
			)
			(layer "F.SilkS")
		)
		(fp_line
			(start 0.67945 0.3048)
			(end 0.120396 0.3048)
			(stroke
				(width 0.1)
				(type default)
			)
			(layer "F.Fab")
		)
		(fp_line
			(start 0.67945 -0.3048)
			(end 0.67945 0.3048)
			(stroke
				(width 0.1)
				(type default)
			)
			(layer "F.Fab")
		)
		(fp_line
			(start 0.12065 -0.2794)
			(end 0.12065 -0.3048)
			(stroke
				(width 0.1)
				(type default)
			)
			(layer "F.Fab")
		)
		(fp_line
			(start 0.12065 -0.3048)
			(end 0.67945 -0.3048)
			(stroke
				(width 0.1)
				(type default)
			)
			(layer "F.Fab")
		)
		(fp_line
			(start 0.120396 0.3048)
			(end 0.120396 0.2794)
			(stroke
				(width 0.1)
				(type default)
			)
			(layer "F.Fab")
		)
		(fp_line
			(start 0.120396 0.2794)
			(end -0.12065 0.2794)
			(stroke
				(width 0.1)
				(type default)
			)
			(layer "F.Fab")
		)
		(fp_line
			(start -0.12065 0.3048)
			(end -0.67945 0.3048)
			(stroke
				(width 0.1)
				(type default)
			)
			(layer "F.Fab")
		)
		(fp_line
			(start -0.12065 0.2794)
			(end -0.12065 0.3048)
			(stroke
				(width 0.1)
				(type default)
			)
			(layer "F.Fab")
		)
		(fp_line
			(start -0.12065 -0.2794)
			(end 0.12065 -0.2794)
			(stroke
				(width 0.1)
				(type default)
			)
			(layer "F.Fab")
		)
		(fp_line
			(start -0.12065 -0.305054)
			(end -0.12065 -0.2794)
			(stroke
				(width 0.1)
				(type default)
			)
			(layer "F.Fab")
		)
		(fp_line
			(start -0.67945 0.3048)
			(end -0.67945 -0.305054)
			(stroke
				(width 0.1)
				(type default)
			)
			(layer "F.Fab")
		)
		(fp_line
			(start -0.67945 -0.305054)
			(end -0.12065 -0.305054)
			(stroke
				(width 0.1)
				(type default)
			)
			(layer "F.Fab")
		)
		(pad "1" smd circle
			(at -0.40005 0 180)
			(size 0 0)
			(layers "F.Cu" "F.Mask" "F.Paste")
			(net "SH_P1V25_PEX0_FB_P")
		)
		(pad "2" smd circle
			(at 0.40005 0 180)
			(size 0 0)
			(layers "F.Cu" "F.Mask" "F.Paste")
			(net "P1V25_PEX0_FB")
		)
	)
	(footprint ""
		(layer "F.Cu")
		(at 260.451346 -334.010254 90)
		(property "Reference" "R6798"
			(at 0 0 90)
			(layer "F.SilkS")
			(hide yes)
			(effects
				(font
					(size 1.27 1.27)
				)
			)
		)
		(property "Value" ""
			(at 0 0 90)
			(layer "F.Fab")
			(effects
				(font
					(size 1.27 1.27)
				)
			)
		)
		(duplicate_pad_numbers_are_jumpers no)
		(fp_line
			(start 0.7874 -0.4064)
			(end 0.7874 0.4064)
			(stroke
				(width 0.1524)
				(type default)
			)
			(layer "F.SilkS")
		)
		(fp_line
			(start -0.7874 -0.4064)
			(end 0.7874 -0.4064)
			(stroke
				(width 0.1524)
				(type default)
			)
			(layer "F.SilkS")
		)
		(fp_line
			(start 0.7874 0.4064)
			(end -0.7874 0.4064)
			(stroke
				(width 0.1524)
				(type default)
			)
			(layer "F.SilkS")
		)
		(fp_line
			(start -0.7874 0.4064)
			(end -0.7874 -0.4064)
			(stroke
				(width 0.1524)
				(type default)
			)
			(layer "F.SilkS")
		)
		(fp_line
			(start -0.12065 -0.305054)
			(end -0.12065 -0.2794)
			(stroke
				(width 0.1)
				(type default)
			)
			(layer "F.Fab")
		)
		(fp_line
			(start -0.67945 -0.305054)
			(end -0.12065 -0.305054)
			(stroke
				(width 0.1)
				(type default)
			)
			(layer "F.Fab")
		)
		(fp_line
			(start 0.67945 -0.3048)
			(end 0.67945 0.3048)
			(stroke
				(width 0.1)
				(type default)
			)
			(layer "F.Fab")
		)
		(fp_line
			(start 0.12065 -0.3048)
			(end 0.67945 -0.3048)
			(stroke
				(width 0.1)
				(type default)
			)
			(layer "F.Fab")
		)
		(fp_line
			(start 0.12065 -0.2794)
			(end 0.12065 -0.3048)
			(stroke
				(width 0.1)
				(type default)
			)
			(layer "F.Fab")
		)
		(fp_line
			(start -0.12065 -0.2794)
			(end 0.12065 -0.2794)
			(stroke
				(width 0.1)
				(type default)
			)
			(layer "F.Fab")
		)
		(fp_line
			(start 0.120396 0.2794)
			(end -0.12065 0.2794)
			(stroke
				(width 0.1)
				(type default)
			)
			(layer "F.Fab")
		)
		(fp_line
			(start -0.12065 0.2794)
			(end -0.12065 0.3048)
			(stroke
				(width 0.1)
				(type default)
			)
			(layer "F.Fab")
		)
		(fp_line
			(start 0.67945 0.3048)
			(end 0.120396 0.3048)
			(stroke
				(width 0.1)
				(type default)
			)
			(layer "F.Fab")
		)
		(fp_line
			(start 0.120396 0.3048)
			(end 0.120396 0.2794)
			(stroke
				(width 0.1)
				(type default)
			)
			(layer "F.Fab")
		)
		(fp_line
			(start -0.12065 0.3048)
			(end -0.67945 0.3048)
			(stroke
				(width 0.1)
				(type default)
			)
			(layer "F.Fab")
		)
		(fp_line
			(start -0.67945 0.3048)
			(end -0.67945 -0.305054)
			(stroke
				(width 0.1)
				(type default)
			)
			(layer "F.Fab")
		)
		(pad "1" smd rect
			(at -0.40005 0 270)
			(size 0.4572 0.508)
			(layers "F.Cu" "F.Mask" "F.Paste")
			(net "HSC_OC_VOL")
		)
		(pad "2" smd rect
			(at 0.40005 0 270)
			(size 0.4572 0.508)
			(layers "F.Cu" "F.Mask" "F.Paste")
			(net "GND")
		)
	)
	(footprint ""
		(layer "F.Cu")
		(at 387.580632 -121.919746)
		(property "Reference" "C679"
			(at 0 0 0)
			(layer "F.SilkS")
			(hide yes)
			(effects
				(font
					(size 1.27 1.27)
				)
			)
		)
		(property "Value" ""
			(at 0 0 0)
			(layer "F.Fab")
			(effects
				(font
					(size 1.27 1.27)
				)
			)
		)
		(duplicate_pad_numbers_are_jumpers no)
		(fp_line
			(start -0.299974 -0.150114)
			(end 0.299974 -0.150114)
			(stroke
				(width 0.1)
				(type default)
			)
			(layer "F.Fab")
		)
		(fp_line
			(start -0.299974 0.150114)
			(end -0.299974 -0.150114)
			(stroke
				(width 0.1)
				(type default)
			)
			(layer "F.Fab")
		)
		(fp_line
			(start 0.299974 -0.150114)
			(end 0.299974 0.150114)
			(stroke
				(width 0.1)
				(type default)
			)
			(layer "F.Fab")
		)
		(fp_line
			(start 0.299974 0.150114)
			(end -0.299974 0.150114)
			(stroke
				(width 0.1)
				(type default)
			)
			(layer "F.Fab")
		)
		(pad "1" smd rect
			(at -0.2667 0)
			(size 0.3048 0.381)
			(layers "F.Cu" "F.Mask" "F.Paste")
			(net "P5E_PEX3_STN1_TX_DP<25>")
		)
		(pad "2" smd rect
			(at 0.2667 0)
			(size 0.3048 0.381)
			(layers "F.Cu" "F.Mask" "F.Paste")
			(net "P5E_PEX3_STN1_TX_C_DP<25>")
		)
	)
	(footprint ""
		(layer "F.Cu")
		(at 198.214234 -140.134848 -90)
		(property "Reference" "R197"
			(at 0 0 270)
			(layer "F.SilkS")
			(hide yes)
			(effects
				(font
					(size 1.27 1.27)
				)
			)
		)
		(property "Value" ""
			(at 0 0 270)
			(layer "F.Fab")
			(effects
				(font
					(size 1.27 1.27)
				)
			)
		)
		(duplicate_pad_numbers_are_jumpers no)
		(fp_line
			(start -0.7874 0.4064)
			(end -0.7874 -0.4064)
			(stroke
				(width 0.1524)
				(type default)
			)
			(layer "F.SilkS")
		)
		(fp_line
			(start 0.7874 0.4064)
			(end -0.7874 0.4064)
			(stroke
				(width 0.1524)
				(type default)
			)
			(layer "F.SilkS")
		)
		(fp_line
			(start -0.7874 -0.4064)
			(end 0.7874 -0.4064)
			(stroke
				(width 0.1524)
				(type default)
			)
			(layer "F.SilkS")
		)
		(fp_line
			(start 0.7874 -0.4064)
			(end 0.7874 0.4064)
			(stroke
				(width 0.1524)
				(type default)
			)
			(layer "F.SilkS")
		)
		(fp_line
			(start -0.67945 0.3048)
			(end -0.67945 -0.305054)
			(stroke
				(width 0.1)
				(type default)
			)
			(layer "F.Fab")
		)
		(fp_line
			(start -0.12065 0.3048)
			(end -0.67945 0.3048)
			(stroke
				(width 0.1)
				(type default)
			)
			(layer "F.Fab")
		)
		(fp_line
			(start 0.120396 0.3048)
			(end 0.120396 0.2794)
			(stroke
				(width 0.1)
				(type default)
			)
			(layer "F.Fab")
		)
		(fp_line
			(start 0.67945 0.3048)
			(end 0.120396 0.3048)
			(stroke
				(width 0.1)
				(type default)
			)
			(layer "F.Fab")
		)
		(fp_line
			(start -0.12065 0.2794)
			(end -0.12065 0.3048)
			(stroke
				(width 0.1)
				(type default)
			)
			(layer "F.Fab")
		)
		(fp_line
			(start 0.120396 0.2794)
			(end -0.12065 0.2794)
			(stroke
				(width 0.1)
				(type default)
			)
			(layer "F.Fab")
		)
		(fp_line
			(start -0.12065 -0.2794)
			(end 0.12065 -0.2794)
			(stroke
				(width 0.1)
				(type default)
			)
			(layer "F.Fab")
		)
		(fp_line
			(start 0.12065 -0.2794)
			(end 0.12065 -0.3048)
			(stroke
				(width 0.1)
				(type default)
			)
			(layer "F.Fab")
		)
		(fp_line
			(start 0.12065 -0.3048)
			(end 0.67945 -0.3048)
			(stroke
				(width 0.1)
				(type default)
			)
			(layer "F.Fab")
		)
		(fp_line
			(start 0.67945 -0.3048)
			(end 0.67945 0.3048)
			(stroke
				(width 0.1)
				(type default)
			)
			(layer "F.Fab")
		)
		(fp_line
			(start -0.67945 -0.305054)
			(end -0.12065 -0.305054)
			(stroke
				(width 0.1)
				(type default)
			)
			(layer "F.Fab")
		)
		(fp_line
			(start -0.12065 -0.305054)
			(end -0.12065 -0.2794)
			(stroke
				(width 0.1)
				(type default)
			)
			(layer "F.Fab")
		)
		(pad "1" smd circle
			(at -0.40005 0 270)
			(size 0 0)
			(layers "F.Cu" "F.Mask" "F.Paste")
			(net "P3V3_AUX")
		)
		(pad "2" smd circle
			(at 0.40005 0 270)
			(size 0 0)
			(layers "F.Cu" "F.Mask" "F.Paste")
			(net "HP_NIC3_EN")
		)
	)
	(footprint ""
		(layer "F.Cu")
		(at 149.387814 -288.419032)
		(property "Reference" "C3229"
			(at 0 0 0)
			(layer "F.SilkS")
			(hide yes)
			(effects
				(font
					(size 1.27 1.27)
				)
			)
		)
		(property "Value" ""
			(at 0 0 0)
			(layer "F.Fab")
			(effects
				(font
					(size 1.27 1.27)
				)
			)
		)
		(duplicate_pad_numbers_are_jumpers no)
		(fp_line
			(start -1.2954 -0.5842)
			(end 1.2954 -0.5842)
			(stroke
				(width 0.1524)
				(type default)
			)
			(layer "F.SilkS")
		)
		(fp_line
			(start -1.2954 0.5842)
			(end -1.2954 -0.5842)
			(stroke
				(width 0.1524)
				(type default)
			)
			(layer "F.SilkS")
		)
		(fp_line
			(start 1.2954 -0.5842)
			(end 1.2954 0.5842)
			(stroke
				(width 0.1524)
				(type default)
			)
			(layer "F.SilkS")
		)
		(fp_line
			(start 1.2954 0.5842)
			(end -1.2954 0.5842)
			(stroke
				(width 0.1524)
				(type default)
			)
			(layer "F.SilkS")
		)
		(fp_line
			(start -1.1938 -0.4064)
			(end -0.8636 -0.4064)
			(stroke
				(width 0.1)
				(type default)
			)
			(layer "F.Fab")
		)
		(fp_line
			(start -1.1938 0.4064)
			(end -1.1938 -0.4064)
			(stroke
				(width 0.1)
				(type default)
			)
			(layer "F.Fab")
		)
		(fp_line
			(start -0.8636 -0.4572)
			(end 0.8636 -0.4572)
			(stroke
				(width 0.1)
				(type default)
			)
			(layer "F.Fab")
		)
		(fp_line
			(start -0.8636 -0.4064)
			(end -0.8636 -0.4572)
			(stroke
				(width 0.1)
				(type default)
			)
			(layer "F.Fab")
		)
		(fp_line
			(start -0.8636 0.4064)
			(end -1.1938 0.4064)
			(stroke
				(width 0.1)
				(type default)
			)
			(layer "F.Fab")
		)
		(fp_line
			(start -0.8636 0.4572)
			(end -0.8636 0.4064)
			(stroke
				(width 0.1)
				(type default)
			)
			(layer "F.Fab")
		)
		(fp_line
			(start 0.8636 -0.4572)
			(end 0.8636 -0.4064)
			(stroke
				(width 0.1)
				(type default)
			)
			(layer "F.Fab")
		)
		(fp_line
			(start 0.8636 -0.4064)
			(end 1.1938 -0.4064)
			(stroke
				(width 0.1)
				(type default)
			)
			(layer "F.Fab")
		)
		(fp_line
			(start 0.8636 0.4064)
			(end 0.8636 0.4572)
			(stroke
				(width 0.1)
				(type default)
			)
			(layer "F.Fab")
		)
		(fp_line
			(start 0.8636 0.4572)
			(end -0.8636 0.4572)
			(stroke
				(width 0.1)
				(type default)
			)
			(layer "F.Fab")
		)
		(fp_line
			(start 1.1938 -0.4064)
			(end 1.1938 0.4064)
			(stroke
				(width 0.1)
				(type default)
			)
			(layer "F.Fab")
		)
		(fp_line
			(start 1.1938 0.4064)
			(end 0.8636 0.4064)
			(stroke
				(width 0.1)
				(type default)
			)
			(layer "F.Fab")
		)
		(pad "1" smd rect
			(at -0.7366 0 270)
			(size 0.7112 0.8128)
			(layers "F.Cu" "F.Mask" "F.Paste")
			(net "PCEPLL6_VDDA18_PEX1")
		)
		(pad "2" smd rect
			(at 0.7366 0 270)
			(size 0.7112 0.8128)
			(layers "F.Cu" "F.Mask" "F.Paste")
			(net "GND")
		)
	)
	(footprint ""
		(layer "F.Cu")
		(at 194.710558 -18.61439 90)
		(property "Reference" "U132"
			(at -1.29159 2.445512 90)
			(unlocked yes)
			(layer "F.SilkS")
			(effects
				(font
					(size 0.7874 0.5842)
					(thickness 0.1524)
				)
				(justify left)
			)
		)
		(property "Value" ""
			(at 0 0 90)
			(layer "F.Fab")
			(effects
				(font
					(size 1.27 1.27)
				)
			)
		)
		(duplicate_pad_numbers_are_jumpers no)
		(fp_line
			(start 1.463548 -1.549908)
			(end 1.463548 1.549908)
			(stroke
				(width 0.1524)
				(type default)
			)
			(layer "F.SilkS")
		)
		(fp_line
			(start 0.762 -1.549908)
			(end 1.463548 -1.549908)
			(stroke
				(width 0.1524)
				(type default)
			)
			(layer "F.SilkS")
		)
		(fp_line
			(start -0.787908 -1.549908)
			(end 0 -0.762)
			(stroke
				(width 0.1524)
				(type default)
			)
			(layer "F.SilkS")
		)
		(fp_line
			(start -1.463548 -1.549908)
			(end -0.787908 -1.549908)
			(stroke
				(width 0.1524)
				(type default)
			)
			(layer "F.SilkS")
		)
		(fp_line
			(start 0 -0.762)
			(end 0.762 -1.549908)
			(stroke
				(width 0.1524)
				(type default)
			)
			(layer "F.SilkS")
		)
		(fp_line
			(start 1.463548 1.549908)
			(end -1.463548 1.549908)
			(stroke
				(width 0.1524)
				(type default)
			)
			(layer "F.SilkS")
		)
		(fp_line
			(start -1.463548 1.549908)
			(end -1.463548 -1.549908)
			(stroke
				(width 0.1524)
				(type default)
			)
			(layer "F.SilkS")
		)
		(fp_poly
			(pts
				(xy -2.98069 -2.223516) (xy -2.761488 -1.566164) (xy -3.41884 -1.785366)
			)
			(stroke
				(width 0)
				(type default)
			)
			(fill yes)
			(layer "F.SilkS")
		)
		(fp_line
			(start 1.549908 -1.549908)
			(end 1.549908 1.549908)
			(stroke
				(width 0.1)
				(type default)
			)
			(layer "F.Fab")
		)
		(fp_line
			(start -1.549908 -1.549908)
			(end 1.549908 -1.549908)
			(stroke
				(width 0.1)
				(type default)
			)
			(layer "F.Fab")
		)
		(fp_line
			(start 1.549908 1.549908)
			(end -1.549908 1.549908)
			(stroke
				(width 0.1)
				(type default)
			)
			(layer "F.Fab")
		)
		(fp_line
			(start -1.549908 1.549908)
			(end -1.549908 -1.549908)
			(stroke
				(width 0.1)
				(type default)
			)
			(layer "F.Fab")
		)
		(fp_poly
			(pts
				(xy -3.4798 -1.359916) (xy -2.86004 -1.050036) (xy -3.4798 -0.740156)
			)
			(stroke
				(width 0)
				(type default)
			)
			(fill yes)
			(layer "F.Fab")
		)
		(pad "1" smd rect
			(at -2.175002 -1.050036 180)
			(size 0.6096 1.1684)
			(layers "F.Cu" "F.Mask" "F.Paste")
			(net "P3V3_SSD6")
		)
		(pad "2" smd rect
			(at -2.175002 -0.32512 180)
			(size 0.4318 1.1684)
			(layers "F.Cu" "F.Mask" "F.Paste")
			(net "SMB_ISO_SSD6_SCL")
		)
		(pad "3" smd rect
			(at -2.175002 0.32512 180)
			(size 0.4318 1.1684)
			(layers "F.Cu" "F.Mask" "F.Paste")
			(net "SMB_ISO_SSD6_SDA")
		)
		(pad "4" smd rect
			(at -2.175002 1.050036 180)
			(size 0.6096 1.1684)
			(layers "F.Cu" "F.Mask" "F.Paste")
			(net "GND")
		)
		(pad "5" smd rect
			(at 2.175002 1.050036 180)
			(size 0.6096 1.1684)
			(layers "F.Cu" "F.Mask" "F.Paste")
			(net "SMB_SSD6_ISO_EN")
		)
		(pad "6" smd rect
			(at 2.175002 0.32512 180)
			(size 0.4318 1.1684)
			(layers "F.Cu" "F.Mask" "F.Paste")
			(net "SMB_BIC_I2C9_MUX0_SSD6_R_SDA")
		)
		(pad "7" smd rect
			(at 2.175002 -0.32512 180)
			(size 0.4318 1.1684)
			(layers "F.Cu" "F.Mask" "F.Paste")
			(net "SMB_BIC_I2C9_MUX0_SSD6_R_SCL")
		)
		(pad "8" smd rect
			(at 2.175002 -1.050036 180)
			(size 0.6096 1.1684)
			(layers "F.Cu" "F.Mask" "F.Paste")
			(net "P3V3_AUX")
		)
	)
	(footprint ""
		(layer "F.Cu")
		(at 62.261242 -350.098614 90)
		(property "Reference" "C128"
			(at 0 0 90)
			(layer "F.SilkS")
			(hide yes)
			(effects
				(font
					(size 1.27 1.27)
				)
			)
		)
		(property "Value" ""
			(at 0 0 90)
			(layer "F.Fab")
			(effects
				(font
					(size 1.27 1.27)
				)
			)
		)
		(duplicate_pad_numbers_are_jumpers no)
		(fp_line
			(start 0.299974 -0.150114)
			(end 0.299974 0.150114)
			(stroke
				(width 0.1)
				(type default)
			)
			(layer "F.Fab")
		)
		(fp_line
			(start -0.299974 -0.150114)
			(end 0.299974 -0.150114)
			(stroke
				(width 0.1)
				(type default)
			)
			(layer "F.Fab")
		)
		(fp_line
			(start 0.299974 0.150114)
			(end -0.299974 0.150114)
			(stroke
				(width 0.1)
				(type default)
			)
			(layer "F.Fab")
		)
		(fp_line
			(start -0.299974 0.150114)
			(end -0.299974 -0.150114)
			(stroke
				(width 0.1)
				(type default)
			)
			(layer "F.Fab")
		)
		(pad "1" smd rect
			(at -0.2667 0 90)
			(size 0.3048 0.381)
			(layers "F.Cu" "F.Mask" "F.Paste")
			(net "P5E_PEX0_STN5_TX_DN<80>")
		)
		(pad "2" smd rect
			(at 0.2667 0 90)
			(size 0.3048 0.381)
			(layers "F.Cu" "F.Mask" "F.Paste")
			(net "P5E_PEX0_STN5_TX_C_DN<80>")
		)
	)
	(footprint ""
		(layer "F.Cu")
		(at 5.260086 -43.637708 90)
		(property "Reference" "PC670"
			(at 0 0 90)
			(layer "F.SilkS")
			(hide yes)
			(effects
				(font
					(size 1.27 1.27)
				)
			)
		)
		(property "Value" ""
			(at 0 0 90)
			(layer "F.Fab")
			(effects
				(font
					(size 1.27 1.27)
				)
			)
		)
		(duplicate_pad_numbers_are_jumpers no)
		(fp_line
			(start 0.7874 -0.4064)
			(end 0.7874 0.4064)
			(stroke
				(width 0.1524)
				(type default)
			)
			(layer "F.SilkS")
		)
		(fp_line
			(start -0.7874 -0.4064)
			(end 0.7874 -0.4064)
			(stroke
				(width 0.1524)
				(type default)
			)
			(layer "F.SilkS")
		)
		(fp_line
			(start 0.7874 0.4064)
			(end -0.7874 0.4064)
			(stroke
				(width 0.1524)
				(type default)
			)
			(layer "F.SilkS")
		)
		(fp_line
			(start -0.7874 0.4064)
			(end -0.7874 -0.4064)
			(stroke
				(width 0.1524)
				(type default)
			)
			(layer "F.SilkS")
		)
		(fp_line
			(start -0.12065 -0.305054)
			(end -0.12065 -0.2794)
			(stroke
				(width 0.1)
				(type default)
			)
			(layer "F.Fab")
		)
		(fp_line
			(start -0.67945 -0.305054)
			(end -0.12065 -0.305054)
			(stroke
				(width 0.1)
				(type default)
			)
			(layer "F.Fab")
		)
		(fp_line
			(start 0.67945 -0.3048)
			(end 0.67945 0.3048)
			(stroke
				(width 0.1)
				(type default)
			)
			(layer "F.Fab")
		)
		(fp_line
			(start 0.12065 -0.3048)
			(end 0.67945 -0.3048)
			(stroke
				(width 0.1)
				(type default)
			)
			(layer "F.Fab")
		)
		(fp_line
			(start 0.12065 -0.2794)
			(end 0.12065 -0.3048)
			(stroke
				(width 0.1)
				(type default)
			)
			(layer "F.Fab")
		)
		(fp_line
			(start -0.12065 -0.2794)
			(end 0.12065 -0.2794)
			(stroke
				(width 0.1)
				(type default)
			)
			(layer "F.Fab")
		)
		(fp_line
			(start 0.120396 0.2794)
			(end -0.12065 0.2794)
			(stroke
				(width 0.1)
				(type default)
			)
			(layer "F.Fab")
		)
		(fp_line
			(start -0.12065 0.2794)
			(end -0.12065 0.3048)
			(stroke
				(width 0.1)
				(type default)
			)
			(layer "F.Fab")
		)
		(fp_line
			(start 0.67945 0.3048)
			(end 0.120396 0.3048)
			(stroke
				(width 0.1)
				(type default)
			)
			(layer "F.Fab")
		)
		(fp_line
			(start 0.120396 0.3048)
			(end 0.120396 0.2794)
			(stroke
				(width 0.1)
				(type default)
			)
			(layer "F.Fab")
		)
		(fp_line
			(start -0.12065 0.3048)
			(end -0.67945 0.3048)
			(stroke
				(width 0.1)
				(type default)
			)
			(layer "F.Fab")
		)
		(fp_line
			(start -0.67945 0.3048)
			(end -0.67945 -0.305054)
			(stroke
				(width 0.1)
				(type default)
			)
			(layer "F.Fab")
		)
		(pad "1" smd circle
			(at -0.40005 0 90)
			(size 0 0)
			(layers "F.Cu" "F.Mask" "F.Paste")
			(net "P3V3_SSD0_CO_GATE")
		)
		(pad "2" smd circle
			(at 0.40005 0 90)
			(size 0 0)
			(layers "F.Cu" "F.Mask" "F.Paste")
			(net "GND")
		)
	)
	(footprint ""
		(layer "F.Cu")
		(at 196.639434 -138.661648 180)
		(property "Reference" "R192"
			(at 0 0 180)
			(layer "F.SilkS")
			(hide yes)
			(effects
				(font
					(size 1.27 1.27)
				)
			)
		)
		(property "Value" ""
			(at 0 0 180)
			(layer "F.Fab")
			(effects
				(font
					(size 1.27 1.27)
				)
			)
		)
		(duplicate_pad_numbers_are_jumpers no)
		(fp_line
			(start 0.7874 0.4064)
			(end -0.7874 0.4064)
			(stroke
				(width 0.1524)
				(type default)
			)
			(layer "F.SilkS")
		)
		(fp_line
			(start 0.7874 -0.4064)
			(end 0.7874 0.4064)
			(stroke
				(width 0.1524)
				(type default)
			)
			(layer "F.SilkS")
		)
		(fp_line
			(start -0.7874 0.4064)
			(end -0.7874 -0.4064)
			(stroke
				(width 0.1524)
				(type default)
			)
			(layer "F.SilkS")
		)
		(fp_line
			(start -0.7874 -0.4064)
			(end 0.7874 -0.4064)
			(stroke
				(width 0.1524)
				(type default)
			)
			(layer "F.SilkS")
		)
		(fp_line
			(start 0.67945 0.3048)
			(end 0.120396 0.3048)
			(stroke
				(width 0.1)
				(type default)
			)
			(layer "F.Fab")
		)
		(fp_line
			(start 0.67945 -0.3048)
			(end 0.67945 0.3048)
			(stroke
				(width 0.1)
				(type default)
			)
			(layer "F.Fab")
		)
		(fp_line
			(start 0.12065 -0.2794)
			(end 0.12065 -0.3048)
			(stroke
				(width 0.1)
				(type default)
			)
			(layer "F.Fab")
		)
		(fp_line
			(start 0.12065 -0.3048)
			(end 0.67945 -0.3048)
			(stroke
				(width 0.1)
				(type default)
			)
			(layer "F.Fab")
		)
		(fp_line
			(start 0.120396 0.3048)
			(end 0.120396 0.2794)
			(stroke
				(width 0.1)
				(type default)
			)
			(layer "F.Fab")
		)
		(fp_line
			(start 0.120396 0.2794)
			(end -0.12065 0.2794)
			(stroke
				(width 0.1)
				(type default)
			)
			(layer "F.Fab")
		)
		(fp_line
			(start -0.12065 0.3048)
			(end -0.67945 0.3048)
			(stroke
				(width 0.1)
				(type default)
			)
			(layer "F.Fab")
		)
		(fp_line
			(start -0.12065 0.2794)
			(end -0.12065 0.3048)
			(stroke
				(width 0.1)
				(type default)
			)
			(layer "F.Fab")
		)
		(fp_line
			(start -0.12065 -0.2794)
			(end 0.12065 -0.2794)
			(stroke
				(width 0.1)
				(type default)
			)
			(layer "F.Fab")
		)
		(fp_line
			(start -0.12065 -0.305054)
			(end -0.12065 -0.2794)
			(stroke
				(width 0.1)
				(type default)
			)
			(layer "F.Fab")
		)
		(fp_line
			(start -0.67945 0.3048)
			(end -0.67945 -0.305054)
			(stroke
				(width 0.1)
				(type default)
			)
			(layer "F.Fab")
		)
		(fp_line
			(start -0.67945 -0.305054)
			(end -0.12065 -0.305054)
			(stroke
				(width 0.1)
				(type default)
			)
			(layer "F.Fab")
		)
		(pad "1" smd circle
			(at -0.40005 0 180)
			(size 0 0)
			(layers "F.Cu" "F.Mask" "F.Paste")
			(net "PRSNT_NIC3_N")
		)
		(pad "2" smd circle
			(at 0.40005 0 180)
			(size 0 0)
			(layers "F.Cu" "F.Mask" "F.Paste")
			(net "PRSNTB0_NIC3_N")
		)
	)
	(footprint ""
		(layer "F.Cu")
		(at 234.040172 -32.848042 90)
		(property "Reference" "PC945"
			(at 0 0 90)
			(layer "F.SilkS")
			(hide yes)
			(effects
				(font
					(size 1.27 1.27)
				)
			)
		)
		(property "Value" ""
			(at 0 0 90)
			(layer "F.Fab")
			(effects
				(font
					(size 1.27 1.27)
				)
			)
		)
		(duplicate_pad_numbers_are_jumpers no)
		(fp_line
			(start 0.7874 -0.4064)
			(end 0.7874 0.4064)
			(stroke
				(width 0.1524)
				(type default)
			)
			(layer "F.SilkS")
		)
		(fp_line
			(start -0.7874 -0.4064)
			(end 0.7874 -0.4064)
			(stroke
				(width 0.1524)
				(type default)
			)
			(layer "F.SilkS")
		)
		(fp_line
			(start 0.7874 0.4064)
			(end -0.7874 0.4064)
			(stroke
				(width 0.1524)
				(type default)
			)
			(layer "F.SilkS")
		)
		(fp_line
			(start -0.7874 0.4064)
			(end -0.7874 -0.4064)
			(stroke
				(width 0.1524)
				(type default)
			)
			(layer "F.SilkS")
		)
		(fp_line
			(start -0.12065 -0.305054)
			(end -0.12065 -0.2794)
			(stroke
				(width 0.1)
				(type default)
			)
			(layer "F.Fab")
		)
		(fp_line
			(start -0.67945 -0.305054)
			(end -0.12065 -0.305054)
			(stroke
				(width 0.1)
				(type default)
			)
			(layer "F.Fab")
		)
		(fp_line
			(start 0.67945 -0.3048)
			(end 0.67945 0.3048)
			(stroke
				(width 0.1)
				(type default)
			)
			(layer "F.Fab")
		)
		(fp_line
			(start 0.12065 -0.3048)
			(end 0.67945 -0.3048)
			(stroke
				(width 0.1)
				(type default)
			)
			(layer "F.Fab")
		)
		(fp_line
			(start 0.12065 -0.2794)
			(end 0.12065 -0.3048)
			(stroke
				(width 0.1)
				(type default)
			)
			(layer "F.Fab")
		)
		(fp_line
			(start -0.12065 -0.2794)
			(end 0.12065 -0.2794)
			(stroke
				(width 0.1)
				(type default)
			)
			(layer "F.Fab")
		)
		(fp_line
			(start 0.120396 0.2794)
			(end -0.12065 0.2794)
			(stroke
				(width 0.1)
				(type default)
			)
			(layer "F.Fab")
		)
		(fp_line
			(start -0.12065 0.2794)
			(end -0.12065 0.3048)
			(stroke
				(width 0.1)
				(type default)
			)
			(layer "F.Fab")
		)
		(fp_line
			(start 0.67945 0.3048)
			(end 0.120396 0.3048)
			(stroke
				(width 0.1)
				(type default)
			)
			(layer "F.Fab")
		)
		(fp_line
			(start 0.120396 0.3048)
			(end 0.120396 0.2794)
			(stroke
				(width 0.1)
				(type default)
			)
			(layer "F.Fab")
		)
		(fp_line
			(start -0.12065 0.3048)
			(end -0.67945 0.3048)
			(stroke
				(width 0.1)
				(type default)
			)
			(layer "F.Fab")
		)
		(fp_line
			(start -0.67945 0.3048)
			(end -0.67945 -0.305054)
			(stroke
				(width 0.1)
				(type default)
			)
			(layer "F.Fab")
		)
		(pad "1" smd circle
			(at -0.40005 0 90)
			(size 0 0)
			(layers "F.Cu" "F.Mask" "F.Paste")
			(net "P3V3_SSD8_CO_DV_DT")
		)
		(pad "2" smd circle
			(at 0.40005 0 90)
			(size 0 0)
			(layers "F.Cu" "F.Mask" "F.Paste")
			(net "GND")
		)
	)
	(footprint ""
		(layer "F.Cu")
		(at 71.980044 -127.700024 180)
		(property "Reference" "J21"
			(at 5.278374 -34.786824 90)
			(unlocked yes)
			(layer "F.SilkS")
			(effects
				(font
					(size 0.7874 0.5842)
					(thickness 0.1524)
				)
				(justify left)
			)
		)
		(property "Value" ""
			(at 0 0 180)
			(layer "F.Fab")
			(effects
				(font
					(size 1.27 1.27)
				)
			)
		)
		(duplicate_pad_numbers_are_jumpers no)
		(fp_line
			(start 4.507484 -21.5265)
			(end 4.507484 -34.720022)
			(stroke
				(width 0.1524)
				(type default)
			)
			(layer "F.SilkS")
		)
		(fp_line
			(start 4.507484 -34.720022)
			(end 2.6162 -34.720022)
			(stroke
				(width 0.1524)
				(type default)
			)
			(layer "F.SilkS")
		)
		(fp_line
			(start 2.6035 34.720022)
			(end 4.507484 34.720022)
			(stroke
				(width 0.1524)
				(type default)
			)
			(layer "F.SilkS")
		)
		(fp_line
			(start -0.57658 -34.720022)
			(end -4.507484 -34.720022)
			(stroke
				(width 0.1524)
				(type default)
			)
			(layer "F.SilkS")
		)
		(fp_line
			(start -4.507484 34.720022)
			(end -0.5588 34.720022)
			(stroke
				(width 0.1524)
				(type default)
			)
			(layer "F.SilkS")
		)
		(fp_poly
			(pts
				(xy 5.735574 -17.957038) (xy 5.735574 -18.973038) (xy 4.719574 -18.465038)
			)
			(stroke
				(width 0)
				(type default)
			)
			(fill yes)
			(layer "F.SilkS")
		)
		(fp_line
			(start 4.507484 34.720022)
			(end 4.507484 -34.720022)
			(stroke
				(width 0.1)
				(type default)
			)
			(layer "F.Fab")
		)
		(fp_line
			(start 4.507484 -34.720022)
			(end -4.507484 -34.720022)
			(stroke
				(width 0.1)
				(type default)
			)
			(layer "F.Fab")
		)
		(fp_line
			(start -4.507484 34.720022)
			(end 4.507484 34.720022)
			(stroke
				(width 0.1)
				(type default)
			)
			(layer "F.Fab")
		)
		(fp_line
			(start -4.507484 -34.720022)
			(end -4.507484 34.720022)
			(stroke
				(width 0.1)
				(type default)
			)
			(layer "F.Fab")
		)
		(fp_poly
			(pts
				(xy 5.735574 -17.957038) (xy 5.735574 -18.973038) (xy 4.719574 -18.465038)
			)
			(stroke
				(width 0)
				(type default)
			)
			(fill yes)
			(layer "F.Fab")
		)
		(pad "" np_thru_hole circle
			(at -0.727456 -32.485076 180)
			(size 1.1176 1.1176)
			(drill 1.1176)
			(layers "*.Cu" "*.Mask")
			(clearance 0.381)
			(thermal_gap 0.381)
		)
		(pad "" np_thru_hole circle
			(at 1.022604 32.485076 180)
			(size 1.1176 1.1176)
			(drill 1.1176)
			(layers "*.Cu" "*.Mask")
			(clearance 0.381)
			(thermal_gap 0.381)
		)
		(pad "A1" smd rect
			(at 3.322574 -18.465038 90)
			(size 0.3556 1.2192)
			(layers "F.Cu" "F.Mask" "F.Paste")
			(net "GND")
		)
		(pad "A2" smd rect
			(at 3.322574 -17.86509 90)
			(size 0.3556 1.2192)
			(layers "F.Cu" "F.Mask" "F.Paste")
			(net "GND")
		)
		(pad "A3" smd rect
			(at 3.322574 -17.264888 90)
			(size 0.3556 1.2192)
			(layers "F.Cu" "F.Mask" "F.Paste")
			(net "GND")
		)
		(pad "A4" smd rect
			(at 3.322574 -16.66494 90)
			(size 0.3556 1.2192)
			(layers "F.Cu" "F.Mask" "F.Paste")
			(net "GND")
		)
		(pad "A5" smd rect
			(at 3.322574 -16.064992 90)
			(size 0.3556 1.2192)
			(layers "F.Cu" "F.Mask" "F.Paste")
			(net "GND")
		)
		(pad "A6" smd rect
			(at 3.322574 -15.465044 90)
			(size 0.3556 1.2192)
			(layers "F.Cu" "F.Mask" "F.Paste")
			(net "GND")
		)
		(pad "A7" smd rect
			(at 3.322574 -14.865096 90)
			(size 0.3556 1.2192)
			(layers "F.Cu" "F.Mask" "F.Paste")
			(net "SMB_NIC1_R_SCL")
		)
		(pad "A8" smd rect
			(at 3.322574 -14.264894 90)
			(size 0.3556 1.2192)
			(layers "F.Cu" "F.Mask" "F.Paste")
			(net "SMB_NIC1_R_SDA")
		)
		(pad "A9" smd rect
			(at 3.322574 -13.664946 90)
			(size 0.3556 1.2192)
			(layers "F.Cu" "F.Mask" "F.Paste")
			(net "RST_SMB_NIC1_MUX_ISO_R_N")
		)
		(pad "A10" smd rect
			(at 3.322574 -13.064998 90)
			(size 0.3556 1.2192)
			(layers "F.Cu" "F.Mask" "F.Paste")
			(net "GND")
		)
		(pad "A11" smd rect
			(at 3.322574 -12.46505 90)
			(size 0.3556 1.2192)
			(layers "F.Cu" "F.Mask" "F.Paste")
			(net "RST_NIC1_PERST1_R_N")
		)
		(pad "A12" smd rect
			(at 3.322574 -11.865102 90)
			(size 0.3556 1.2192)
			(layers "F.Cu" "F.Mask" "F.Paste")
			(net "PRSNTB2_NIC1_N")
		)
		(pad "A13" smd rect
			(at 3.322574 -11.2649 90)
			(size 0.3556 1.2192)
			(layers "F.Cu" "F.Mask" "F.Paste")
			(net "GND")
		)
		(pad "A14" smd rect
			(at 3.322574 -10.664952 90)
			(size 0.3556 1.2192)
			(layers "F.Cu" "F.Mask" "F.Paste")
			(net "Net_2588")
		)
		(pad "A15" smd rect
			(at 3.322574 -10.065004 90)
			(size 0.3556 1.2192)
			(layers "F.Cu" "F.Mask" "F.Paste")
			(net "Net_2591")
		)
		(pad "A16" smd rect
			(at 3.322574 -9.465056 90)
			(size 0.3556 1.2192)
			(layers "F.Cu" "F.Mask" "F.Paste")
			(net "GND")
		)
		(pad "A17" smd rect
			(at 3.322574 -8.865108 90)
			(size 0.3556 1.2192)
			(layers "F.Cu" "F.Mask" "F.Paste")
			(net "P5E_PEX0_STN0_RX_DN<0>")
		)
		(pad "A18" smd rect
			(at 3.322574 -8.264906 90)
			(size 0.3556 1.2192)
			(layers "F.Cu" "F.Mask" "F.Paste")
			(net "P5E_PEX0_STN0_RX_DP<0>")
		)
		(pad "A19" smd rect
			(at 3.322574 -7.664958 90)
			(size 0.3556 1.2192)
			(layers "F.Cu" "F.Mask" "F.Paste")
			(net "GND")
		)
		(pad "A20" smd rect
			(at 3.322574 -7.06501 90)
			(size 0.3556 1.2192)
			(layers "F.Cu" "F.Mask" "F.Paste")
			(net "P5E_PEX0_STN0_RX_DN<1>")
		)
		(pad "A21" smd rect
			(at 3.322574 -6.465062 90)
			(size 0.3556 1.2192)
			(layers "F.Cu" "F.Mask" "F.Paste")
			(net "P5E_PEX0_STN0_RX_DP<1>")
		)
		(pad "A22" smd rect
			(at 3.322574 -5.865114 90)
			(size 0.3556 1.2192)
			(layers "F.Cu" "F.Mask" "F.Paste")
			(net "GND")
		)
		(pad "A23" smd rect
			(at 3.322574 -5.264912 90)
			(size 0.3556 1.2192)
			(layers "F.Cu" "F.Mask" "F.Paste")
			(net "P5E_PEX0_STN0_RX_DN<2>")
		)
		(pad "A24" smd rect
			(at 3.322574 -4.664964 90)
			(size 0.3556 1.2192)
			(layers "F.Cu" "F.Mask" "F.Paste")
			(net "P5E_PEX0_STN0_RX_DP<2>")
		)
		(pad "A25" smd rect
			(at 3.322574 -4.065016 90)
			(size 0.3556 1.2192)
			(layers "F.Cu" "F.Mask" "F.Paste")
			(net "GND")
		)
		(pad "A26" smd rect
			(at 3.322574 -3.465068 90)
			(size 0.3556 1.2192)
			(layers "F.Cu" "F.Mask" "F.Paste")
			(net "P5E_PEX0_STN0_RX_DN<3>")
		)
		(pad "A27" smd rect
			(at 3.322574 -2.86512 90)
			(size 0.3556 1.2192)
			(layers "F.Cu" "F.Mask" "F.Paste")
			(net "P5E_PEX0_STN0_RX_DP<3>")
		)
		(pad "A28" smd rect
			(at 3.322574 -2.264918 90)
			(size 0.3556 1.2192)
			(layers "F.Cu" "F.Mask" "F.Paste")
			(net "GND")
		)
		(pad "A29" smd rect
			(at 3.322574 1.74498 90)
			(size 0.3556 1.2192)
			(layers "F.Cu" "F.Mask" "F.Paste")
			(net "GND")
		)
		(pad "A30" smd rect
			(at 3.322574 2.344928 90)
			(size 0.3556 1.2192)
			(layers "F.Cu" "F.Mask" "F.Paste")
			(net "P5E_PEX0_STN0_RX_DN<4>")
		)
		(pad "A31" smd rect
			(at 3.322574 2.944876 90)
			(size 0.3556 1.2192)
			(layers "F.Cu" "F.Mask" "F.Paste")
			(net "P5E_PEX0_STN0_RX_DP<4>")
		)
		(pad "A32" smd rect
			(at 3.322574 3.545078 90)
			(size 0.3556 1.2192)
			(layers "F.Cu" "F.Mask" "F.Paste")
			(net "GND")
		)
		(pad "A33" smd rect
			(at 3.322574 4.145026 90)
			(size 0.3556 1.2192)
			(layers "F.Cu" "F.Mask" "F.Paste")
			(net "P5E_PEX0_STN0_RX_DN<5>")
		)
		(pad "A34" smd rect
			(at 3.322574 4.744974 90)
			(size 0.3556 1.2192)
			(layers "F.Cu" "F.Mask" "F.Paste")
			(net "P5E_PEX0_STN0_RX_DP<5>")
		)
		(pad "A35" smd rect
			(at 3.322574 5.344922 90)
			(size 0.3556 1.2192)
			(layers "F.Cu" "F.Mask" "F.Paste")
			(net "GND")
		)
		(pad "A36" smd rect
			(at 3.322574 5.945124 90)
			(size 0.3556 1.2192)
			(layers "F.Cu" "F.Mask" "F.Paste")
			(net "P5E_PEX0_STN0_RX_DN<6>")
		)
		(pad "A37" smd rect
			(at 3.322574 6.545072 90)
			(size 0.3556 1.2192)
			(layers "F.Cu" "F.Mask" "F.Paste")
			(net "P5E_PEX0_STN0_RX_DP<6>")
		)
		(pad "A38" smd rect
			(at 3.322574 7.14502 90)
			(size 0.3556 1.2192)
			(layers "F.Cu" "F.Mask" "F.Paste")
			(net "GND")
		)
		(pad "A39" smd rect
			(at 3.322574 7.744968 90)
			(size 0.3556 1.2192)
			(layers "F.Cu" "F.Mask" "F.Paste")
			(net "P5E_PEX0_STN0_RX_DN<7>")
		)
		(pad "A40" smd rect
			(at 3.322574 8.344916 90)
			(size 0.3556 1.2192)
			(layers "F.Cu" "F.Mask" "F.Paste")
			(net "P5E_PEX0_STN0_RX_DP<7>")
		)
		(pad "A41" smd rect
			(at 3.322574 8.945118 90)
			(size 0.3556 1.2192)
			(layers "F.Cu" "F.Mask" "F.Paste")
			(net "GND")
		)
		(pad "A42" smd rect
			(at 3.322574 9.545066 90)
			(size 0.3556 1.2192)
			(layers "F.Cu" "F.Mask" "F.Paste")
			(net "PRSNTB1_NIC1_N")
		)
		(pad "A43" smd rect
			(at 3.322574 14.454886 90)
			(size 0.3556 1.2192)
			(layers "F.Cu" "F.Mask" "F.Paste")
			(net "GND")
		)
		(pad "A44" smd rect
			(at 3.322574 15.055088 90)
			(size 0.3556 1.2192)
			(layers "F.Cu" "F.Mask" "F.Paste")
			(net "P5E_PEX0_STN0_RX_DN<8>")
		)
		(pad "A45" smd rect
			(at 3.322574 15.655036 90)
			(size 0.3556 1.2192)
			(layers "F.Cu" "F.Mask" "F.Paste")
			(net "P5E_PEX0_STN0_RX_DP<8>")
		)
		(pad "A46" smd rect
			(at 3.322574 16.254984 90)
			(size 0.3556 1.2192)
			(layers "F.Cu" "F.Mask" "F.Paste")
			(net "GND")
		)
		(pad "A47" smd rect
			(at 3.322574 16.854932 90)
			(size 0.3556 1.2192)
			(layers "F.Cu" "F.Mask" "F.Paste")
			(net "P5E_PEX0_STN0_RX_DN<9>")
		)
		(pad "A48" smd rect
			(at 3.322574 17.45488 90)
			(size 0.3556 1.2192)
			(layers "F.Cu" "F.Mask" "F.Paste")
			(net "P5E_PEX0_STN0_RX_DP<9>")
		)
		(pad "A49" smd rect
			(at 3.322574 18.055082 90)
			(size 0.3556 1.2192)
			(layers "F.Cu" "F.Mask" "F.Paste")
			(net "GND")
		)
		(pad "A50" smd rect
			(at 3.322574 18.65503 90)
			(size 0.3556 1.2192)
			(layers "F.Cu" "F.Mask" "F.Paste")
			(net "P5E_PEX0_STN0_RX_DN<10>")
		)
		(pad "A51" smd rect
			(at 3.322574 19.254978 90)
			(size 0.3556 1.2192)
			(layers "F.Cu" "F.Mask" "F.Paste")
			(net "P5E_PEX0_STN0_RX_DP<10>")
		)
		(pad "A52" smd rect
			(at 3.322574 19.854926 90)
			(size 0.3556 1.2192)
			(layers "F.Cu" "F.Mask" "F.Paste")
			(net "GND")
		)
		(pad "A53" smd rect
			(at 3.322574 20.455128 90)
			(size 0.3556 1.2192)
			(layers "F.Cu" "F.Mask" "F.Paste")
			(net "P5E_PEX0_STN0_RX_DN<11>")
		)
		(pad "A54" smd rect
			(at 3.322574 21.055076 90)
			(size 0.3556 1.2192)
			(layers "F.Cu" "F.Mask" "F.Paste")
			(net "P5E_PEX0_STN0_RX_DP<11>")
		)
		(pad "A55" smd rect
			(at 3.322574 21.655024 90)
			(size 0.3556 1.2192)
			(layers "F.Cu" "F.Mask" "F.Paste")
			(net "GND")
		)
		(pad "A56" smd rect
			(at 3.322574 22.254972 90)
			(size 0.3556 1.2192)
			(layers "F.Cu" "F.Mask" "F.Paste")
			(net "P5E_PEX0_STN0_RX_DN<12>")
		)
		(pad "A57" smd rect
			(at 3.322574 22.85492 90)
			(size 0.3556 1.2192)
			(layers "F.Cu" "F.Mask" "F.Paste")
			(net "P5E_PEX0_STN0_RX_DP<12>")
		)
		(pad "A58" smd rect
			(at 3.322574 23.455122 90)
			(size 0.3556 1.2192)
			(layers "F.Cu" "F.Mask" "F.Paste")
			(net "GND")
		)
		(pad "A59" smd rect
			(at 3.322574 24.05507 90)
			(size 0.3556 1.2192)
			(layers "F.Cu" "F.Mask" "F.Paste")
			(net "P5E_PEX0_STN0_RX_DN<13>")
		)
		(pad "A60" smd rect
			(at 3.322574 24.655018 90)
			(size 0.3556 1.2192)
			(layers "F.Cu" "F.Mask" "F.Paste")
			(net "P5E_PEX0_STN0_RX_DP<13>")
		)
		(pad "A61" smd rect
			(at 3.322574 25.254966 90)
			(size 0.3556 1.2192)
			(layers "F.Cu" "F.Mask" "F.Paste")
			(net "GND")
		)
		(pad "A62" smd rect
			(at 3.322574 25.854914 90)
			(size 0.3556 1.2192)
			(layers "F.Cu" "F.Mask" "F.Paste")
			(net "P5E_PEX0_STN0_RX_DN<14>")
		)
		(pad "A63" smd rect
			(at 3.322574 26.455116 90)
			(size 0.3556 1.2192)
			(layers "F.Cu" "F.Mask" "F.Paste")
			(net "P5E_PEX0_STN0_RX_DP<14>")
		)
		(pad "A64" smd rect
			(at 3.322574 27.055064 90)
			(size 0.3556 1.2192)
			(layers "F.Cu" "F.Mask" "F.Paste")
			(net "GND")
		)
		(pad "A65" smd rect
			(at 3.322574 27.655012 90)
			(size 0.3556 1.2192)
			(layers "F.Cu" "F.Mask" "F.Paste")
			(net "P5E_PEX0_STN0_RX_DN<15>")
		)
		(pad "A66" smd rect
			(at 3.322574 28.25496 90)
			(size 0.3556 1.2192)
			(layers "F.Cu" "F.Mask" "F.Paste")
			(net "P5E_PEX0_STN0_RX_DP<15>")
		)
		(pad "A67" smd rect
			(at 3.322574 28.854908 90)
			(size 0.3556 1.2192)
			(layers "F.Cu" "F.Mask" "F.Paste")
			(net "GND")
		)
		(pad "A68" smd rect
			(at 3.322574 29.45511 90)
			(size 0.3556 1.2192)
			(layers "F.Cu" "F.Mask" "F.Paste")
			(net "Net_2596")
		)
		(pad "A69" smd rect
			(at 3.322574 30.055058 90)
			(size 0.3556 1.2192)
			(layers "F.Cu" "F.Mask" "F.Paste")
			(net "Net_2597")
		)
		(pad "A70" smd rect
			(at 3.322574 30.655006 90)
			(size 0.3556 1.2192)
			(layers "F.Cu" "F.Mask" "F.Paste")
			(net "NIC1_PWRBRK_R_N")
		)
		(pad "B1" smd rect
			(at -1.27762 -18.465038 90)
			(size 0.3556 1.2192)
			(layers "F.Cu" "F.Mask" "F.Paste")
			(net "P12V_NIC1")
		)
		(pad "B2" smd rect
			(at -1.27762 -17.86509 90)
			(size 0.3556 1.2192)
			(layers "F.Cu" "F.Mask" "F.Paste")
			(net "P12V_NIC1")
		)
		(pad "B3" smd rect
			(at -1.27762 -17.264888 90)
			(size 0.3556 1.2192)
			(layers "F.Cu" "F.Mask" "F.Paste")
			(net "P12V_NIC1")
		)
		(pad "B4" smd rect
			(at -1.27762 -16.66494 90)
			(size 0.3556 1.2192)
			(layers "F.Cu" "F.Mask" "F.Paste")
			(net "P12V_NIC1")
		)
		(pad "B5" smd rect
			(at -1.27762 -16.064992 90)
			(size 0.3556 1.2192)
			(layers "F.Cu" "F.Mask" "F.Paste")
			(net "P12V_NIC1")
		)
		(pad "B6" smd rect
			(at -1.27762 -15.465044 90)
			(size 0.3556 1.2192)
			(layers "F.Cu" "F.Mask" "F.Paste")
			(net "P12V_NIC1")
		)
		(pad "B7" smd rect
			(at -1.27762 -14.865096 90)
			(size 0.3556 1.2192)
			(layers "F.Cu" "F.Mask" "F.Paste")
			(net "NIC1_BIF0_N")
		)
		(pad "B8" smd rect
			(at -1.27762 -14.264894 90)
			(size 0.3556 1.2192)
			(layers "F.Cu" "F.Mask" "F.Paste")
			(net "NIC1_BIF1_N")
		)
		(pad "B9" smd rect
			(at -1.27762 -13.664946 90)
			(size 0.3556 1.2192)
			(layers "F.Cu" "F.Mask" "F.Paste")
			(net "NIC1_BIF2_N")
		)
		(pad "B10" smd rect
			(at -1.27762 -13.064998 90)
			(size 0.3556 1.2192)
			(layers "F.Cu" "F.Mask" "F.Paste")
			(net "RST_NIC1_PERST0_R_N")
		)
		(pad "B11" smd rect
			(at -1.27762 -12.46505 90)
			(size 0.3556 1.2192)
			(layers "F.Cu" "F.Mask" "F.Paste")
			(net "P3V3_NIC1")
		)
		(pad "B12" smd rect
			(at -1.27762 -11.865102 90)
			(size 0.3556 1.2192)
			(layers "F.Cu" "F.Mask" "F.Paste")
			(net "NIC1_AUX_PWR_EN_R")
		)
		(pad "B13" smd rect
			(at -1.27762 -11.2649 90)
			(size 0.3556 1.2192)
			(layers "F.Cu" "F.Mask" "F.Paste")
			(net "GND")
		)
		(pad "B14" smd rect
			(at -1.27762 -10.664952 90)
			(size 0.3556 1.2192)
			(layers "F.Cu" "F.Mask" "F.Paste")
			(net "CLK_100M_DB2000QL_NIC1_R_DN")
		)
		(pad "B15" smd rect
			(at -1.27762 -10.065004 90)
			(size 0.3556 1.2192)
			(layers "F.Cu" "F.Mask" "F.Paste")
			(net "CLK_100M_DB2000QL_NIC1_R_DP")
		)
		(pad "B16" smd rect
			(at -1.27762 -9.465056 90)
			(size 0.3556 1.2192)
			(layers "F.Cu" "F.Mask" "F.Paste")
			(net "GND")
		)
		(pad "B17" smd rect
			(at -1.27762 -8.865108 90)
			(size 0.3556 1.2192)
			(layers "F.Cu" "F.Mask" "F.Paste")
			(net "P5E_PEX0_STN0_TX_C_DN<0>")
		)
		(pad "B18" smd rect
			(at -1.27762 -8.264906 90)
			(size 0.3556 1.2192)
			(layers "F.Cu" "F.Mask" "F.Paste")
			(net "P5E_PEX0_STN0_TX_C_DP<0>")
		)
		(pad "B19" smd rect
			(at -1.27762 -7.664958 90)
			(size 0.3556 1.2192)
			(layers "F.Cu" "F.Mask" "F.Paste")
			(net "GND")
		)
		(pad "B20" smd rect
			(at -1.27762 -7.06501 90)
			(size 0.3556 1.2192)
			(layers "F.Cu" "F.Mask" "F.Paste")
			(net "P5E_PEX0_STN0_TX_C_DN<1>")
		)
		(pad "B21" smd rect
			(at -1.27762 -6.465062 90)
			(size 0.3556 1.2192)
			(layers "F.Cu" "F.Mask" "F.Paste")
			(net "P5E_PEX0_STN0_TX_C_DP<1>")
		)
		(pad "B22" smd rect
			(at -1.27762 -5.865114 90)
			(size 0.3556 1.2192)
			(layers "F.Cu" "F.Mask" "F.Paste")
			(net "GND")
		)
		(pad "B23" smd rect
			(at -1.27762 -5.264912 90)
			(size 0.3556 1.2192)
			(layers "F.Cu" "F.Mask" "F.Paste")
			(net "P5E_PEX0_STN0_TX_C_DN<2>")
		)
		(pad "B24" smd rect
			(at -1.27762 -4.664964 90)
			(size 0.3556 1.2192)
			(layers "F.Cu" "F.Mask" "F.Paste")
			(net "P5E_PEX0_STN0_TX_C_DP<2>")
		)
		(pad "B25" smd rect
			(at -1.27762 -4.065016 90)
			(size 0.3556 1.2192)
			(layers "F.Cu" "F.Mask" "F.Paste")
			(net "GND")
		)
		(pad "B26" smd rect
			(at -1.27762 -3.465068 90)
			(size 0.3556 1.2192)
			(layers "F.Cu" "F.Mask" "F.Paste")
			(net "P5E_PEX0_STN0_TX_C_DN<3>")
		)
		(pad "B27" smd rect
			(at -1.27762 -2.86512 90)
			(size 0.3556 1.2192)
			(layers "F.Cu" "F.Mask" "F.Paste")
			(net "P5E_PEX0_STN0_TX_C_DP<3>")
		)
		(pad "B28" smd rect
			(at -1.27762 -2.264918 90)
			(size 0.3556 1.2192)
			(layers "F.Cu" "F.Mask" "F.Paste")
			(net "GND")
		)
		(pad "B29" smd rect
			(at -1.27762 1.74498 90)
			(size 0.3556 1.2192)
			(layers "F.Cu" "F.Mask" "F.Paste")
			(net "GND")
		)
		(pad "B30" smd rect
			(at -1.27762 2.344928 90)
			(size 0.3556 1.2192)
			(layers "F.Cu" "F.Mask" "F.Paste")
			(net "P5E_PEX0_STN0_TX_C_DN<4>")
		)
		(pad "B31" smd rect
			(at -1.27762 2.944876 90)
			(size 0.3556 1.2192)
			(layers "F.Cu" "F.Mask" "F.Paste")
			(net "P5E_PEX0_STN0_TX_C_DP<4>")
		)
		(pad "B32" smd rect
			(at -1.27762 3.545078 90)
			(size 0.3556 1.2192)
			(layers "F.Cu" "F.Mask" "F.Paste")
			(net "GND")
		)
		(pad "B33" smd rect
			(at -1.27762 4.145026 90)
			(size 0.3556 1.2192)
			(layers "F.Cu" "F.Mask" "F.Paste")
			(net "P5E_PEX0_STN0_TX_C_DN<5>")
		)
		(pad "B34" smd rect
			(at -1.27762 4.744974 90)
			(size 0.3556 1.2192)
			(layers "F.Cu" "F.Mask" "F.Paste")
			(net "P5E_PEX0_STN0_TX_C_DP<5>")
		)
		(pad "B35" smd rect
			(at -1.27762 5.344922 90)
			(size 0.3556 1.2192)
			(layers "F.Cu" "F.Mask" "F.Paste")
			(net "GND")
		)
		(pad "B36" smd rect
			(at -1.27762 5.945124 90)
			(size 0.3556 1.2192)
			(layers "F.Cu" "F.Mask" "F.Paste")
			(net "P5E_PEX0_STN0_TX_C_DN<6>")
		)
		(pad "B37" smd rect
			(at -1.27762 6.545072 90)
			(size 0.3556 1.2192)
			(layers "F.Cu" "F.Mask" "F.Paste")
			(net "P5E_PEX0_STN0_TX_C_DP<6>")
		)
		(pad "B38" smd rect
			(at -1.27762 7.14502 90)
			(size 0.3556 1.2192)
			(layers "F.Cu" "F.Mask" "F.Paste")
			(net "GND")
		)
		(pad "B39" smd rect
			(at -1.27762 7.744968 90)
			(size 0.3556 1.2192)
			(layers "F.Cu" "F.Mask" "F.Paste")
			(net "P5E_PEX0_STN0_TX_C_DN<7>")
		)
		(pad "B40" smd rect
			(at -1.27762 8.344916 90)
			(size 0.3556 1.2192)
			(layers "F.Cu" "F.Mask" "F.Paste")
			(net "P5E_PEX0_STN0_TX_C_DP<7>")
		)
		(pad "B41" smd rect
			(at -1.27762 8.945118 90)
			(size 0.3556 1.2192)
			(layers "F.Cu" "F.Mask" "F.Paste")
			(net "GND")
		)
		(pad "B42" smd rect
			(at -1.27762 9.545066 90)
			(size 0.3556 1.2192)
			(layers "F.Cu" "F.Mask" "F.Paste")
			(net "PRSNTB0_NIC1_N")
		)
		(pad "B43" smd rect
			(at -1.27762 14.454886 90)
			(size 0.3556 1.2192)
			(layers "F.Cu" "F.Mask" "F.Paste")
			(net "GND")
		)
		(pad "B44" smd rect
			(at -1.27762 15.055088 90)
			(size 0.3556 1.2192)
			(layers "F.Cu" "F.Mask" "F.Paste")
			(net "P5E_PEX0_STN0_TX_C_DN<8>")
		)
		(pad "B45" smd rect
			(at -1.27762 15.655036 90)
			(size 0.3556 1.2192)
			(layers "F.Cu" "F.Mask" "F.Paste")
			(net "P5E_PEX0_STN0_TX_C_DP<8>")
		)
		(pad "B46" smd rect
			(at -1.27762 16.254984 90)
			(size 0.3556 1.2192)
			(layers "F.Cu" "F.Mask" "F.Paste")
			(net "GND")
		)
		(pad "B47" smd rect
			(at -1.27762 16.854932 90)
			(size 0.3556 1.2192)
			(layers "F.Cu" "F.Mask" "F.Paste")
			(net "P5E_PEX0_STN0_TX_C_DN<9>")
		)
		(pad "B48" smd rect
			(at -1.27762 17.45488 90)
			(size 0.3556 1.2192)
			(layers "F.Cu" "F.Mask" "F.Paste")
			(net "P5E_PEX0_STN0_TX_C_DP<9>")
		)
		(pad "B49" smd rect
			(at -1.27762 18.055082 90)
			(size 0.3556 1.2192)
			(layers "F.Cu" "F.Mask" "F.Paste")
			(net "GND")
		)
		(pad "B50" smd rect
			(at -1.27762 18.65503 90)
			(size 0.3556 1.2192)
			(layers "F.Cu" "F.Mask" "F.Paste")
			(net "P5E_PEX0_STN0_TX_C_DN<10>")
		)
		(pad "B51" smd rect
			(at -1.27762 19.254978 90)
			(size 0.3556 1.2192)
			(layers "F.Cu" "F.Mask" "F.Paste")
			(net "P5E_PEX0_STN0_TX_C_DP<10>")
		)
		(pad "B52" smd rect
			(at -1.27762 19.854926 90)
			(size 0.3556 1.2192)
			(layers "F.Cu" "F.Mask" "F.Paste")
			(net "GND")
		)
		(pad "B53" smd rect
			(at -1.27762 20.455128 90)
			(size 0.3556 1.2192)
			(layers "F.Cu" "F.Mask" "F.Paste")
			(net "P5E_PEX0_STN0_TX_C_DN<11>")
		)
		(pad "B54" smd rect
			(at -1.27762 21.055076 90)
			(size 0.3556 1.2192)
			(layers "F.Cu" "F.Mask" "F.Paste")
			(net "P5E_PEX0_STN0_TX_C_DP<11>")
		)
		(pad "B55" smd rect
			(at -1.27762 21.655024 90)
			(size 0.3556 1.2192)
			(layers "F.Cu" "F.Mask" "F.Paste")
			(net "GND")
		)
		(pad "B56" smd rect
			(at -1.27762 22.254972 90)
			(size 0.3556 1.2192)
			(layers "F.Cu" "F.Mask" "F.Paste")
			(net "P5E_PEX0_STN0_TX_C_DP<12>")
		)
		(pad "B57" smd rect
			(at -1.27762 22.85492 90)
			(size 0.3556 1.2192)
			(layers "F.Cu" "F.Mask" "F.Paste")
			(net "P5E_PEX0_STN0_TX_C_DN<12>")
		)
		(pad "B58" smd rect
			(at -1.27762 23.455122 90)
			(size 0.3556 1.2192)
			(layers "F.Cu" "F.Mask" "F.Paste")
			(net "GND")
		)
		(pad "B59" smd rect
			(at -1.27762 24.05507 90)
			(size 0.3556 1.2192)
			(layers "F.Cu" "F.Mask" "F.Paste")
			(net "P5E_PEX0_STN0_TX_C_DN<13>")
		)
		(pad "B60" smd rect
			(at -1.27762 24.655018 90)
			(size 0.3556 1.2192)
			(layers "F.Cu" "F.Mask" "F.Paste")
			(net "P5E_PEX0_STN0_TX_C_DP<13>")
		)
		(pad "B61" smd rect
			(at -1.27762 25.254966 90)
			(size 0.3556 1.2192)
			(layers "F.Cu" "F.Mask" "F.Paste")
			(net "GND")
		)
		(pad "B62" smd rect
			(at -1.27762 25.854914 90)
			(size 0.3556 1.2192)
			(layers "F.Cu" "F.Mask" "F.Paste")
			(net "P5E_PEX0_STN0_TX_C_DP<14>")
		)
		(pad "B63" smd rect
			(at -1.27762 26.455116 90)
			(size 0.3556 1.2192)
			(layers "F.Cu" "F.Mask" "F.Paste")
			(net "P5E_PEX0_STN0_TX_C_DN<14>")
		)
		(pad "B64" smd rect
			(at -1.27762 27.055064 90)
			(size 0.3556 1.2192)
			(layers "F.Cu" "F.Mask" "F.Paste")
			(net "GND")
		)
		(pad "B65" smd rect
			(at -1.27762 27.655012 90)
			(size 0.3556 1.2192)
			(layers "F.Cu" "F.Mask" "F.Paste")
			(net "P5E_PEX0_STN0_TX_C_DN<15>")
		)
		(pad "B66" smd rect
			(at -1.27762 28.25496 90)
			(size 0.3556 1.2192)
			(layers "F.Cu" "F.Mask" "F.Paste")
			(net "P5E_PEX0_STN0_TX_C_DP<15>")
		)
		(pad "B67" smd rect
			(at -1.27762 28.854908 90)
			(size 0.3556 1.2192)
			(layers "F.Cu" "F.Mask" "F.Paste")
			(net "GND")
		)
		(pad "B68" smd rect
			(at -1.27762 29.45511 90)
			(size 0.3556 1.2192)
			(layers "F.Cu" "F.Mask" "F.Paste")
			(net "Net_2594")
		)
		(pad "B69" smd rect
			(at -1.27762 30.055058 90)
			(size 0.3556 1.2192)
			(layers "F.Cu" "F.Mask" "F.Paste")
			(net "Net_2595")
		)
		(pad "B70" smd rect
			(at -1.27762 30.655006 90)
			(size 0.3556 1.2192)
			(layers "F.Cu" "F.Mask" "F.Paste")
			(net "PRSNTB3_NIC1_N")
		)
		(pad "G1" thru_hole oval
			(at 1.022604 -34.034984 90)
			(size 1.6256 3.4798)
			(drill oval 1.1176 2.4638)
			(layers "*.Cu" "*.Mask")
			(remove_unused_layers no)
			(net "GND")
			(clearance 0.127)
			(thermal_gap 0.127)
		)
		(pad "G2" thru_hole oval
			(at 1.022604 -20.625054 90)
			(size 1.6256 3.4798)
			(drill oval 1.1176 2.4638)
			(layers "*.Cu" "*.Mask")
			(remove_unused_layers no)
			(net "GND")
			(clearance 0.127)
			(thermal_gap 0.127)
		)
		(pad "G3" thru_hole oval
			(at 1.022604 -0.255016 90)
			(size 1.6256 3.4798)
			(drill oval 1.1176 2.4638)
			(layers "*.Cu" "*.Mask")
			(remove_unused_layers no)
			(net "GND")
			(clearance 0.127)
			(thermal_gap 0.127)
		)
		(pad "G4" thru_hole oval
			(at 1.022604 12.005056 90)
			(size 1.6256 3.4798)
			(drill oval 1.1176 2.4638)
			(layers "*.Cu" "*.Mask")
			(remove_unused_layers no)
			(net "GND")
			(clearance 0.127)
			(thermal_gap 0.127)
		)
		(pad "G5" thru_hole oval
			(at 1.022604 34.034984 90)
			(size 1.5748 3.4798)
			(drill oval 1.1176 2.4638)
			(layers "*.Cu" "*.Mask")
			(remove_unused_layers no)
			(net "GND")
			(clearance 0.1524)
			(thermal_gap 0.1524)
		)
		(pad "G6" thru_hole circle
			(at -3.16738 -20.625054 180)
			(size 1.6256 1.6256)
			(drill 1.1176)
			(layers "*.Cu" "*.Mask")
			(remove_unused_layers no)
			(net "GND")
			(clearance 0)
		)
		(pad "G7" thru_hole circle
			(at -3.16738 12.005056 180)
			(size 1.6256 1.6256)
			(drill 1.1176)
			(layers "*.Cu" "*.Mask")
			(remove_unused_layers no)
			(net "GND")
			(clearance 0)
		)
		(pad "G8" thru_hole circle
			(at 4.20243 -20.625054 180)
			(size 1.6256 1.6256)
			(drill 1.1176)
			(layers "*.Cu" "*.Mask")
			(remove_unused_layers no)
			(net "GND")
			(clearance 0)
		)
		(pad "G9" thru_hole circle
			(at 4.20243 12.005056 180)
			(size 1.6256 1.6256)
			(drill 1.1176)
			(layers "*.Cu" "*.Mask")
			(remove_unused_layers no)
			(net "GND")
			(clearance 0)
		)
		(pad "OA1" smd rect
			(at 3.322574 -30.660086 90)
			(size 0.3556 1.2192)
			(layers "F.Cu" "F.Mask" "F.Paste")
			(net "RST_NIC1_PERST2_R_N")
		)
		(pad "OA2" smd rect
			(at 3.322574 -30.059884 90)
			(size 0.3556 1.2192)
			(layers "F.Cu" "F.Mask" "F.Paste")
			(net "RST_NIC1_PERST3_R_N")
		)
		(pad "OA3" smd rect
			(at 3.322574 -29.459936 90)
			(size 0.3556 1.2192)
			(layers "F.Cu" "F.Mask" "F.Paste")
			(net "Net_2598")
		)
		(pad "OA4" smd rect
			(at 3.322574 -28.859988 90)
			(size 0.3556 1.2192)
			(layers "F.Cu" "F.Mask" "F.Paste")
			(net "NIC1_RBT_ARB_IN")
		)
		(pad "OA5" smd rect
			(at 3.322574 -28.26004 90)
			(size 0.3556 1.2192)
			(layers "F.Cu" "F.Mask" "F.Paste")
			(net "NIC1_RBT_ARB_OUT")
		)
		(pad "OA6" smd rect
			(at 3.322574 -27.660092 90)
			(size 0.3556 1.2192)
			(layers "F.Cu" "F.Mask" "F.Paste")
			(net "NIC1_SLOT_ID1")
		)
		(pad "OA7" smd rect
			(at 3.322574 -27.05989 90)
			(size 0.3556 1.2192)
			(layers "F.Cu" "F.Mask" "F.Paste")
			(net "NCSI_NIC1_TX_EN")
		)
		(pad "OA8" smd rect
			(at 3.322574 -26.459942 90)
			(size 0.3556 1.2192)
			(layers "F.Cu" "F.Mask" "F.Paste")
			(net "NCSI_NIC1_TXD1")
		)
		(pad "OA9" smd rect
			(at 3.322574 -25.859994 90)
			(size 0.3556 1.2192)
			(layers "F.Cu" "F.Mask" "F.Paste")
			(net "NCSI_NIC1_TXD0")
		)
		(pad "OA10" smd rect
			(at 3.322574 -25.260046 90)
			(size 0.3556 1.2192)
			(layers "F.Cu" "F.Mask" "F.Paste")
			(net "GND")
		)
		(pad "OA11" smd rect
			(at 3.322574 -24.660098 90)
			(size 0.3556 1.2192)
			(layers "F.Cu" "F.Mask" "F.Paste")
			(net "Net_2590")
		)
		(pad "OA12" smd rect
			(at 3.322574 -24.059896 90)
			(size 0.3556 1.2192)
			(layers "F.Cu" "F.Mask" "F.Paste")
			(net "Net_2593")
		)
		(pad "OA13" smd rect
			(at 3.322574 -23.459948 90)
			(size 0.3556 1.2192)
			(layers "F.Cu" "F.Mask" "F.Paste")
			(net "GND")
		)
		(pad "OA14" smd rect
			(at 3.322574 -22.86 90)
			(size 0.3556 1.2192)
			(layers "F.Cu" "F.Mask" "F.Paste")
			(net "CLK_50M_NIC1_RBT_REF")
		)
		(pad "OB1" smd rect
			(at -1.27762 -30.660086 90)
			(size 0.3556 1.2192)
			(layers "F.Cu" "F.Mask" "F.Paste")
			(net "PWRGD_NIC1_PWR_GOOD")
		)
		(pad "OB2" smd rect
			(at -1.27762 -30.059884 90)
			(size 0.3556 1.2192)
			(layers "F.Cu" "F.Mask" "F.Paste")
			(net "NIC1_MAIN_PWR_EN_R")
		)
		(pad "OB3" smd rect
			(at -1.27762 -29.459936 90)
			(size 0.3556 1.2192)
			(layers "F.Cu" "F.Mask" "F.Paste")
			(net "NIC1_LD_N")
		)
		(pad "OB4" smd rect
			(at -1.27762 -28.859988 90)
			(size 0.3556 1.2192)
			(layers "F.Cu" "F.Mask" "F.Paste")
			(net "NIC1_DATA_IN")
		)
		(pad "OB5" smd rect
			(at -1.27762 -28.26004 90)
			(size 0.3556 1.2192)
			(layers "F.Cu" "F.Mask" "F.Paste")
			(net "NIC1_DATA_OUT")
		)
		(pad "OB6" smd rect
			(at -1.27762 -27.660092 90)
			(size 0.3556 1.2192)
			(layers "F.Cu" "F.Mask" "F.Paste")
			(net "NIC1_CLK")
		)
		(pad "OB7" smd rect
			(at -1.27762 -27.05989 90)
			(size 0.3556 1.2192)
			(layers "F.Cu" "F.Mask" "F.Paste")
			(net "NIC1_SLOT_ID0")
		)
		(pad "OB8" smd rect
			(at -1.27762 -26.459942 90)
			(size 0.3556 1.2192)
			(layers "F.Cu" "F.Mask" "F.Paste")
			(net "NCSI_NIC1_RXD1")
		)
		(pad "OB9" smd rect
			(at -1.27762 -25.859994 90)
			(size 0.3556 1.2192)
			(layers "F.Cu" "F.Mask" "F.Paste")
			(net "NCSI_NIC1_RXD0")
		)
		(pad "OB10" smd rect
			(at -1.27762 -25.260046 90)
			(size 0.3556 1.2192)
			(layers "F.Cu" "F.Mask" "F.Paste")
			(net "GND")
		)
		(pad "OB11" smd rect
			(at -1.27762 -24.660098 90)
			(size 0.3556 1.2192)
			(layers "F.Cu" "F.Mask" "F.Paste")
			(net "Net_2589")
		)
		(pad "OB12" smd rect
			(at -1.27762 -24.059896 90)
			(size 0.3556 1.2192)
			(layers "F.Cu" "F.Mask" "F.Paste")
			(net "Net_2592")
		)
		(pad "OB13" smd rect
			(at -1.27762 -23.459948 90)
			(size 0.3556 1.2192)
			(layers "F.Cu" "F.Mask" "F.Paste")
			(net "GND")
		)
		(pad "OB14" smd rect
			(at -1.27762 -22.86 90)
			(size 0.3556 1.2192)
			(layers "F.Cu" "F.Mask" "F.Paste")
			(net "NCSI_NIC1_CRS_DV")
		)
		(zone
			(layers "F.Cu" "B.Cu" "In1.Cu" "In2.Cu" "In3.Cu" "In4.Cu" "In5.Cu" "In6.Cu"
				"In7.Cu" "In8.Cu" "In9.Cu" "In10.Cu" "In11.Cu" "In12.Cu" "In13.Cu" "In14.Cu"
				"In15.Cu" "In16.Cu"
			)
			(hatch none 0.5)
			(connect_pads
				(clearance 0)
			)
			(min_thickness 0.25)
			(keepout
				(tracks not_allowed)
				(vias allowed)
				(pads allowed)
				(copperpour not_allowed)
				(footprints allowed)
			)
			(placement
				(enabled no)
				(sheetname "")
			)
			(fill
				(thermal_gap 0.5)
				(thermal_bridge_width 0.5)
				(island_removal_mode 0)
			)
			(polygon
				(pts
					(arc
						(start 72.024494 -160.1851)
						(mid 69.890386 -160.1851)
						(end 72.024494 -160.1851)
					)
				)
			)
		)
		(zone
			(layers "F.Cu" "B.Cu" "In1.Cu" "In2.Cu" "In3.Cu" "In4.Cu" "In5.Cu" "In6.Cu"
				"In7.Cu" "In8.Cu" "In9.Cu" "In10.Cu" "In11.Cu" "In12.Cu" "In13.Cu" "In14.Cu"
				"In15.Cu" "In16.Cu"
			)
			(hatch none 0.5)
			(connect_pads
				(clearance 0)
			)
			(min_thickness 0.25)
			(keepout
				(tracks not_allowed)
				(vias allowed)
				(pads allowed)
				(copperpour not_allowed)
				(footprints allowed)
			)
			(placement
				(enabled no)
				(sheetname "")
			)
			(fill
				(thermal_gap 0.5)
				(thermal_bridge_width 0.5)
				(island_removal_mode 0)
			)
			(polygon
				(pts
					(arc
						(start 73.7743 -95.214948)
						(mid 71.6407 -95.214948)
						(end 73.7743 -95.214948)
					)
				)
			)
		)
	)
	(footprint ""
		(layer "F.Cu")
		(at 222.663512 -231.416606 90)
		(property "Reference" "R4545"
			(at 0 0 90)
			(layer "F.SilkS")
			(hide yes)
			(effects
				(font
					(size 1.27 1.27)
				)
			)
		)
		(property "Value" ""
			(at 0 0 90)
			(layer "F.Fab")
			(effects
				(font
					(size 1.27 1.27)
				)
			)
		)
		(duplicate_pad_numbers_are_jumpers no)
		(fp_line
			(start 0.7874 -0.4064)
			(end 0.7874 0.4064)
			(stroke
				(width 0.1524)
				(type default)
			)
			(layer "F.SilkS")
		)
		(fp_line
			(start -0.7874 -0.4064)
			(end 0.7874 -0.4064)
			(stroke
				(width 0.1524)
				(type default)
			)
			(layer "F.SilkS")
		)
		(fp_line
			(start 0.7874 0.4064)
			(end -0.7874 0.4064)
			(stroke
				(width 0.1524)
				(type default)
			)
			(layer "F.SilkS")
		)
		(fp_line
			(start -0.7874 0.4064)
			(end -0.7874 -0.4064)
			(stroke
				(width 0.1524)
				(type default)
			)
			(layer "F.SilkS")
		)
		(fp_line
			(start -0.12065 -0.305054)
			(end -0.12065 -0.2794)
			(stroke
				(width 0.1)
				(type default)
			)
			(layer "F.Fab")
		)
		(fp_line
			(start -0.67945 -0.305054)
			(end -0.12065 -0.305054)
			(stroke
				(width 0.1)
				(type default)
			)
			(layer "F.Fab")
		)
		(fp_line
			(start 0.67945 -0.3048)
			(end 0.67945 0.3048)
			(stroke
				(width 0.1)
				(type default)
			)
			(layer "F.Fab")
		)
		(fp_line
			(start 0.12065 -0.3048)
			(end 0.67945 -0.3048)
			(stroke
				(width 0.1)
				(type default)
			)
			(layer "F.Fab")
		)
		(fp_line
			(start 0.12065 -0.2794)
			(end 0.12065 -0.3048)
			(stroke
				(width 0.1)
				(type default)
			)
			(layer "F.Fab")
		)
		(fp_line
			(start -0.12065 -0.2794)
			(end 0.12065 -0.2794)
			(stroke
				(width 0.1)
				(type default)
			)
			(layer "F.Fab")
		)
		(fp_line
			(start 0.120396 0.2794)
			(end -0.12065 0.2794)
			(stroke
				(width 0.1)
				(type default)
			)
			(layer "F.Fab")
		)
		(fp_line
			(start -0.12065 0.2794)
			(end -0.12065 0.3048)
			(stroke
				(width 0.1)
				(type default)
			)
			(layer "F.Fab")
		)
		(fp_line
			(start 0.67945 0.3048)
			(end 0.120396 0.3048)
			(stroke
				(width 0.1)
				(type default)
			)
			(layer "F.Fab")
		)
		(fp_line
			(start 0.120396 0.3048)
			(end 0.120396 0.2794)
			(stroke
				(width 0.1)
				(type default)
			)
			(layer "F.Fab")
		)
		(fp_line
			(start -0.12065 0.3048)
			(end -0.67945 0.3048)
			(stroke
				(width 0.1)
				(type default)
			)
			(layer "F.Fab")
		)
		(fp_line
			(start -0.67945 0.3048)
			(end -0.67945 -0.305054)
			(stroke
				(width 0.1)
				(type default)
			)
			(layer "F.Fab")
		)
		(pad "1" smd circle
			(at -0.40005 0 90)
			(size 0 0)
			(layers "F.Cu" "F.Mask" "F.Paste")
			(net "REV_ID1")
		)
		(pad "2" smd circle
			(at 0.40005 0 90)
			(size 0 0)
			(layers "F.Cu" "F.Mask" "F.Paste")
			(net "P3V3_AUX")
		)
	)
	(footprint ""
		(layer "F.Cu")
		(at 98.048318 -396.1638)
		(property "Reference" "R5459"
			(at 0 0 0)
			(layer "F.SilkS")
			(hide yes)
			(effects
				(font
					(size 1.27 1.27)
				)
			)
		)
		(property "Value" ""
			(at 0 0 0)
			(layer "F.Fab")
			(effects
				(font
					(size 1.27 1.27)
				)
			)
		)
		(duplicate_pad_numbers_are_jumpers no)
		(fp_line
			(start -0.7874 -0.4064)
			(end 0.7874 -0.4064)
			(stroke
				(width 0.1524)
				(type default)
			)
			(layer "F.SilkS")
		)
		(fp_line
			(start -0.7874 0.4064)
			(end -0.7874 -0.4064)
			(stroke
				(width 0.1524)
				(type default)
			)
			(layer "F.SilkS")
		)
		(fp_line
			(start 0.7874 -0.4064)
			(end 0.7874 0.4064)
			(stroke
				(width 0.1524)
				(type default)
			)
			(layer "F.SilkS")
		)
		(fp_line
			(start 0.7874 0.4064)
			(end -0.7874 0.4064)
			(stroke
				(width 0.1524)
				(type default)
			)
			(layer "F.SilkS")
		)
		(fp_line
			(start -0.67945 -0.305054)
			(end -0.12065 -0.305054)
			(stroke
				(width 0.1)
				(type default)
			)
			(layer "F.Fab")
		)
		(fp_line
			(start -0.67945 0.3048)
			(end -0.67945 -0.305054)
			(stroke
				(width 0.1)
				(type default)
			)
			(layer "F.Fab")
		)
		(fp_line
			(start -0.12065 -0.305054)
			(end -0.12065 -0.2794)
			(stroke
				(width 0.1)
				(type default)
			)
			(layer "F.Fab")
		)
		(fp_line
			(start -0.12065 -0.2794)
			(end 0.12065 -0.2794)
			(stroke
				(width 0.1)
				(type default)
			)
			(layer "F.Fab")
		)
		(fp_line
			(start -0.12065 0.2794)
			(end -0.12065 0.3048)
			(stroke
				(width 0.1)
				(type default)
			)
			(layer "F.Fab")
		)
		(fp_line
			(start -0.12065 0.3048)
			(end -0.67945 0.3048)
			(stroke
				(width 0.1)
				(type default)
			)
			(layer "F.Fab")
		)
		(fp_line
			(start 0.120396 0.2794)
			(end -0.12065 0.2794)
			(stroke
				(width 0.1)
				(type default)
			)
			(layer "F.Fab")
		)
		(fp_line
			(start 0.120396 0.3048)
			(end 0.120396 0.2794)
			(stroke
				(width 0.1)
				(type default)
			)
			(layer "F.Fab")
		)
		(fp_line
			(start 0.12065 -0.3048)
			(end 0.67945 -0.3048)
			(stroke
				(width 0.1)
				(type default)
			)
			(layer "F.Fab")
		)
		(fp_line
			(start 0.12065 -0.2794)
			(end 0.12065 -0.3048)
			(stroke
				(width 0.1)
				(type default)
			)
			(layer "F.Fab")
		)
		(fp_line
			(start 0.67945 -0.3048)
			(end 0.67945 0.3048)
			(stroke
				(width 0.1)
				(type default)
			)
			(layer "F.Fab")
		)
		(fp_line
			(start 0.67945 0.3048)
			(end 0.120396 0.3048)
			(stroke
				(width 0.1)
				(type default)
			)
			(layer "F.Fab")
		)
		(pad "1" smd circle
			(at -0.40005 0)
			(size 0 0)
			(layers "F.Cu" "F.Mask" "F.Paste")
			(net "P3V3_AUX")
		)
		(pad "2" smd circle
			(at 0.40005 0)
			(size 0 0)
			(layers "F.Cu" "F.Mask" "F.Paste")
			(net "BIC_USB_HUB_PSELF")
		)
	)
	(footprint ""
		(layer "F.Cu")
		(at 146.18208 -283.389832 180)
		(property "Reference" "C3236"
			(at 0 0 180)
			(layer "F.SilkS")
			(hide yes)
			(effects
				(font
					(size 1.27 1.27)
				)
			)
		)
		(property "Value" ""
			(at 0 0 180)
			(layer "F.Fab")
			(effects
				(font
					(size 1.27 1.27)
				)
			)
		)
		(duplicate_pad_numbers_are_jumpers no)
		(fp_line
			(start 1.2954 0.5842)
			(end -1.2954 0.5842)
			(stroke
				(width 0.1524)
				(type default)
			)
			(layer "F.SilkS")
		)
		(fp_line
			(start 1.2954 -0.5842)
			(end 1.2954 0.5842)
			(stroke
				(width 0.1524)
				(type default)
			)
			(layer "F.SilkS")
		)
		(fp_line
			(start -1.2954 0.5842)
			(end -1.2954 -0.5842)
			(stroke
				(width 0.1524)
				(type default)
			)
			(layer "F.SilkS")
		)
		(fp_line
			(start -1.2954 -0.5842)
			(end 1.2954 -0.5842)
			(stroke
				(width 0.1524)
				(type default)
			)
			(layer "F.SilkS")
		)
		(fp_line
			(start 1.1938 0.4064)
			(end 0.8636 0.4064)
			(stroke
				(width 0.1)
				(type default)
			)
			(layer "F.Fab")
		)
		(fp_line
			(start 1.1938 -0.4064)
			(end 1.1938 0.4064)
			(stroke
				(width 0.1)
				(type default)
			)
			(layer "F.Fab")
		)
		(fp_line
			(start 0.8636 0.4572)
			(end -0.8636 0.4572)
			(stroke
				(width 0.1)
				(type default)
			)
			(layer "F.Fab")
		)
		(fp_line
			(start 0.8636 0.4064)
			(end 0.8636 0.4572)
			(stroke
				(width 0.1)
				(type default)
			)
			(layer "F.Fab")
		)
		(fp_line
			(start 0.8636 -0.4064)
			(end 1.1938 -0.4064)
			(stroke
				(width 0.1)
				(type default)
			)
			(layer "F.Fab")
		)
		(fp_line
			(start 0.8636 -0.4572)
			(end 0.8636 -0.4064)
			(stroke
				(width 0.1)
				(type default)
			)
			(layer "F.Fab")
		)
		(fp_line
			(start -0.8636 0.4572)
			(end -0.8636 0.4064)
			(stroke
				(width 0.1)
				(type default)
			)
			(layer "F.Fab")
		)
		(fp_line
			(start -0.8636 0.4064)
			(end -1.1938 0.4064)
			(stroke
				(width 0.1)
				(type default)
			)
			(layer "F.Fab")
		)
		(fp_line
			(start -0.8636 -0.4064)
			(end -0.8636 -0.4572)
			(stroke
				(width 0.1)
				(type default)
			)
			(layer "F.Fab")
		)
		(fp_line
			(start -0.8636 -0.4572)
			(end 0.8636 -0.4572)
			(stroke
				(width 0.1)
				(type default)
			)
			(layer "F.Fab")
		)
		(fp_line
			(start -1.1938 0.4064)
			(end -1.1938 -0.4064)
			(stroke
				(width 0.1)
				(type default)
			)
			(layer "F.Fab")
		)
		(fp_line
			(start -1.1938 -0.4064)
			(end -0.8636 -0.4064)
			(stroke
				(width 0.1)
				(type default)
			)
			(layer "F.Fab")
		)
		(pad "1" smd rect
			(at -0.7366 0 90)
			(size 0.7112 0.8128)
			(layers "F.Cu" "F.Mask" "F.Paste")
			(net "PCEPLL7_VDDA18_PEX1_R")
		)
		(pad "2" smd rect
			(at 0.7366 0 90)
			(size 0.7112 0.8128)
			(layers "F.Cu" "F.Mask" "F.Paste")
			(net "GND")
		)
	)
	(footprint ""
		(layer "F.Cu")
		(at 143.030194 -287.604708 -90)
		(property "Reference" "C3211"
			(at 0 0 270)
			(layer "F.SilkS")
			(hide yes)
			(effects
				(font
					(size 1.27 1.27)
				)
			)
		)
		(property "Value" ""
			(at 0 0 270)
			(layer "F.Fab")
			(effects
				(font
					(size 1.27 1.27)
				)
			)
		)
		(duplicate_pad_numbers_are_jumpers no)
		(fp_line
			(start -1.2954 0.5842)
			(end -1.2954 -0.5842)
			(stroke
				(width 0.1524)
				(type default)
			)
			(layer "F.SilkS")
		)
		(fp_line
			(start 1.2954 0.5842)
			(end -1.2954 0.5842)
			(stroke
				(width 0.1524)
				(type default)
			)
			(layer "F.SilkS")
		)
		(fp_line
			(start -1.2954 -0.5842)
			(end 1.2954 -0.5842)
			(stroke
				(width 0.1524)
				(type default)
			)
			(layer "F.SilkS")
		)
		(fp_line
			(start 1.2954 -0.5842)
			(end 1.2954 0.5842)
			(stroke
				(width 0.1524)
				(type default)
			)
			(layer "F.SilkS")
		)
		(fp_line
			(start -0.8636 0.4572)
			(end -0.8636 0.4064)
			(stroke
				(width 0.1)
				(type default)
			)
			(layer "F.Fab")
		)
		(fp_line
			(start 0.8636 0.4572)
			(end -0.8636 0.4572)
			(stroke
				(width 0.1)
				(type default)
			)
			(layer "F.Fab")
		)
		(fp_line
			(start -1.1938 0.4064)
			(end -1.1938 -0.4064)
			(stroke
				(width 0.1)
				(type default)
			)
			(layer "F.Fab")
		)
		(fp_line
			(start -0.8636 0.4064)
			(end -1.1938 0.4064)
			(stroke
				(width 0.1)
				(type default)
			)
			(layer "F.Fab")
		)
		(fp_line
			(start 0.8636 0.4064)
			(end 0.8636 0.4572)
			(stroke
				(width 0.1)
				(type default)
			)
			(layer "F.Fab")
		)
		(fp_line
			(start 1.1938 0.4064)
			(end 0.8636 0.4064)
			(stroke
				(width 0.1)
				(type default)
			)
			(layer "F.Fab")
		)
		(fp_line
			(start -1.1938 -0.4064)
			(end -0.8636 -0.4064)
			(stroke
				(width 0.1)
				(type default)
			)
			(layer "F.Fab")
		)
		(fp_line
			(start -0.8636 -0.4064)
			(end -0.8636 -0.4572)
			(stroke
				(width 0.1)
				(type default)
			)
			(layer "F.Fab")
		)
		(fp_line
			(start 0.8636 -0.4064)
			(end 1.1938 -0.4064)
			(stroke
				(width 0.1)
				(type default)
			)
			(layer "F.Fab")
		)
		(fp_line
			(start 1.1938 -0.4064)
			(end 1.1938 0.4064)
			(stroke
				(width 0.1)
				(type default)
			)
			(layer "F.Fab")
		)
		(fp_line
			(start -0.8636 -0.4572)
			(end 0.8636 -0.4572)
			(stroke
				(width 0.1)
				(type default)
			)
			(layer "F.Fab")
		)
		(fp_line
			(start 0.8636 -0.4572)
			(end 0.8636 -0.4064)
			(stroke
				(width 0.1)
				(type default)
			)
			(layer "F.Fab")
		)
		(pad "1" smd rect
			(at -0.7366 0 180)
			(size 0.7112 0.8128)
			(layers "F.Cu" "F.Mask" "F.Paste")
			(net "P1V8_PLL0_PEX1")
		)
		(pad "2" smd rect
			(at 0.7366 0 180)
			(size 0.7112 0.8128)
			(layers "F.Cu" "F.Mask" "F.Paste")
			(net "GND")
		)
	)
	(footprint ""
		(layer "F.Cu")
		(at 259.299964 -98.700082)
		(property "Reference" "H81"
			(at -6.874764 -7.013448 0)
			(unlocked yes)
			(layer "F.SilkS")
			(effects
				(font
					(size 0.7874 0.5842)
					(thickness 0.1524)
				)
				(justify left)
			)
		)
		(property "Value" ""
			(at 0 0 0)
			(layer "F.Fab")
			(effects
				(font
					(size 1.27 1.27)
				)
			)
		)
		(duplicate_pad_numbers_are_jumpers no)
		(fp_circle
			(center 0 0)
			(end 7.999984 0)
			(stroke
				(width 0.1524)
				(type default)
			)
			(fill no)
			(layer "F.SilkS")
		)
		(fp_circle
			(center 0 0)
			(end 7.999984 0)
			(stroke
				(width 0.1524)
				(type default)
			)
			(fill no)
			(layer "B.SilkS")
		)
		(fp_circle
			(center 0 0)
			(end 7.999984 0)
			(stroke
				(width 0.1)
				(type default)
			)
			(fill no)
			(layer "B.Fab")
		)
		(fp_circle
			(center 0 0)
			(end 7.999984 0)
			(stroke
				(width 0.1)
				(type default)
			)
			(fill no)
			(layer "F.Fab")
		)
		(pad "" np_thru_hole circle
			(at 0 0)
			(size 3.4036 3.4036)
			(drill 3.4036)
			(layers "*.Cu" "*.Mask")
			(clearance 0.381)
			(thermal_gap 0.381)
		)
		(pad "2" thru_hole circle
			(at 3.606292 0)
			(size 0.762 0.762)
			(drill 0.5588)
			(layers "*.Cu" "*.Mask")
			(remove_unused_layers no)
			(net "GND")
			(clearance 0.1524)
			(thermal_gap 0.1524)
		)
		(pad "3" thru_hole circle
			(at 2.549906 -2.549906)
			(size 0.762 0.762)
			(drill 0.5588)
			(layers "*.Cu" "*.Mask")
			(remove_unused_layers no)
			(net "GND")
			(clearance 0.1524)
			(thermal_gap 0.1524)
		)
		(pad "4" thru_hole circle
			(at 0 -3.606292)
			(size 0.762 0.762)
			(drill 0.5588)
			(layers "*.Cu" "*.Mask")
			(remove_unused_layers no)
			(net "GND")
			(clearance 0.1524)
			(thermal_gap 0.1524)
		)
		(pad "5" thru_hole circle
			(at -2.549906 -2.549906)
			(size 0.762 0.762)
			(drill 0.5588)
			(layers "*.Cu" "*.Mask")
			(remove_unused_layers no)
			(net "GND")
			(clearance 0.1524)
			(thermal_gap 0.1524)
		)
		(pad "6" thru_hole circle
			(at -3.606292 0)
			(size 0.762 0.762)
			(drill 0.5588)
			(layers "*.Cu" "*.Mask")
			(remove_unused_layers no)
			(net "GND")
			(clearance 0.1524)
			(thermal_gap 0.1524)
		)
		(pad "7" thru_hole circle
			(at -2.549906 2.549906)
			(size 0.762 0.762)
			(drill 0.5588)
			(layers "*.Cu" "*.Mask")
			(remove_unused_layers no)
			(net "GND")
			(clearance 0.1524)
			(thermal_gap 0.1524)
		)
		(pad "8" thru_hole circle
			(at 0 3.606292)
			(size 0.762 0.762)
			(drill 0.5588)
			(layers "*.Cu" "*.Mask")
			(remove_unused_layers no)
			(net "GND")
			(clearance 0.1524)
			(thermal_gap 0.1524)
		)
		(pad "9" thru_hole circle
			(at 2.549906 2.549906)
			(size 0.762 0.762)
			(drill 0.5588)
			(layers "*.Cu" "*.Mask")
			(remove_unused_layers no)
			(net "GND")
			(clearance 0.1524)
			(thermal_gap 0.1524)
		)
		(zone
			(layer "F.Cu")
			(hatch none 0.5)
			(connect_pads
				(clearance 0)
			)
			(min_thickness 0.25)
			(keepout
				(tracks not_allowed)
				(vias allowed)
				(pads allowed)
				(copperpour not_allowed)
				(footprints allowed)
			)
			(placement
				(enabled no)
				(sheetname "")
			)
			(fill
				(thermal_gap 0.5)
				(thermal_bridge_width 0.5)
				(island_removal_mode 0)
			)
			(polygon
				(pts
					(arc
						(start 259.299964 -90.700098)
						(mid 251.29998 -98.700082)
						(end 259.299964 -106.700066)
					)
					(arc
						(start 259.299964 -103.954072)
						(mid 254.045974 -98.700082)
						(end 259.299964 -93.446092)
					)
				)
			)
		)
		(zone
			(layer "F.Cu")
			(hatch none 0.5)
			(connect_pads
				(clearance 0)
			)
			(min_thickness 0.25)
			(keepout
				(tracks not_allowed)
				(vias allowed)
				(pads allowed)
				(copperpour not_allowed)
				(footprints allowed)
			)
			(placement
				(enabled no)
				(sheetname "")
			)
			(fill
				(thermal_gap 0.5)
				(thermal_bridge_width 0.5)
				(island_removal_mode 0)
			)
			(polygon
				(pts
					(arc
						(start 259.299964 -90.700098)
						(mid 267.299948 -98.700082)
						(end 259.299964 -106.700066)
					)
					(arc
						(start 259.299964 -103.954072)
						(mid 264.553954 -98.700082)
						(end 259.299964 -93.446092)
					)
				)
			)
		)
		(zone
			(layers "F.Cu" "B.Cu" "In1.Cu" "In2.Cu" "In3.Cu" "In4.Cu" "In5.Cu" "In6.Cu"
				"In7.Cu" "In8.Cu" "In9.Cu" "In10.Cu" "In11.Cu" "In12.Cu" "In13.Cu" "In14.Cu"
				"In15.Cu" "In16.Cu"
			)
			(hatch none 0.5)
			(connect_pads
				(clearance 0)
			)
			(min_thickness 0.25)
			(keepout
				(tracks not_allowed)
				(vias allowed)
				(pads allowed)
				(copperpour not_allowed)
				(footprints allowed)
			)
			(placement
				(enabled no)
				(sheetname "")
			)
			(fill
				(thermal_gap 0.5)
				(thermal_bridge_width 0.5)
				(island_removal_mode 0)
			)
			(polygon
				(pts
					(arc
						(start 261.509764 -98.700082)
						(mid 257.090164 -98.700082)
						(end 261.509764 -98.700082)
					)
				)
			)
		)
		(zone
			(layer "B.Cu")
			(hatch none 0.5)
			(connect_pads
				(clearance 0)
			)
			(min_thickness 0.25)
			(keepout
				(tracks not_allowed)
				(vias allowed)
				(pads allowed)
				(copperpour not_allowed)
				(footprints allowed)
			)
			(placement
				(enabled no)
				(sheetname "")
			)
			(fill
				(thermal_gap 0.5)
				(thermal_bridge_width 0.5)
				(island_removal_mode 0)
			)
			(polygon
				(pts
					(arc
						(start 259.299964 -93.192092)
						(mid 253.791974 -98.700082)
						(end 259.299964 -104.208072)
					)
					(arc
						(start 259.299964 -103.725472)
						(mid 254.274574 -98.700082)
						(end 259.299964 -93.674692)
					)
				)
			)
		)
		(zone
			(layer "B.Cu")
			(hatch none 0.5)
			(connect_pads
				(clearance 0)
			)
			(min_thickness 0.25)
			(keepout
				(tracks not_allowed)
				(vias allowed)
				(pads allowed)
				(copperpour not_allowed)
				(footprints allowed)
			)
			(placement
				(enabled no)
				(sheetname "")
			)
			(fill
				(thermal_gap 0.5)
				(thermal_bridge_width 0.5)
				(island_removal_mode 0)
			)
			(polygon
				(pts
					(arc
						(start 259.299964 -93.192092)
						(mid 264.807954 -98.700082)
						(end 259.299964 -104.208072)
					)
					(arc
						(start 259.299964 -103.725472)
						(mid 264.325354 -98.700082)
						(end 259.299964 -93.674692)
					)
				)
			)
		)
	)
	(footprint ""
		(layer "F.Cu")
		(at 362.077762 -378.764292 180)
		(property "Reference" "C4457"
			(at 0 0 180)
			(layer "F.SilkS")
			(hide yes)
			(effects
				(font
					(size 1.27 1.27)
				)
			)
		)
		(property "Value" ""
			(at 0 0 180)
			(layer "F.Fab")
			(effects
				(font
					(size 1.27 1.27)
				)
			)
		)
		(duplicate_pad_numbers_are_jumpers no)
		(fp_line
			(start 0.299974 0.150114)
			(end -0.299974 0.150114)
			(stroke
				(width 0.1)
				(type default)
			)
			(layer "F.Fab")
		)
		(fp_line
			(start 0.299974 -0.150114)
			(end 0.299974 0.150114)
			(stroke
				(width 0.1)
				(type default)
			)
			(layer "F.Fab")
		)
		(fp_line
			(start -0.299974 0.150114)
			(end -0.299974 -0.150114)
			(stroke
				(width 0.1)
				(type default)
			)
			(layer "F.Fab")
		)
		(fp_line
			(start -0.299974 -0.150114)
			(end 0.299974 -0.150114)
			(stroke
				(width 0.1)
				(type default)
			)
			(layer "F.Fab")
		)
		(pad "1" smd rect
			(at -0.2667 0 180)
			(size 0.3048 0.381)
			(layers "F.Cu" "F.Mask" "F.Paste")
			(net "MB_3V3IO_RSVD4_ISO")
		)
		(pad "2" smd rect
			(at 0.2667 0 180)
			(size 0.3048 0.381)
			(layers "F.Cu" "F.Mask" "F.Paste")
			(net "GND")
		)
	)
	(footprint ""
		(layer "F.Cu")
		(at 15.18539 -307.26888)
		(property "Reference" "PC219"
			(at 0 0 0)
			(layer "F.SilkS")
			(hide yes)
			(effects
				(font
					(size 1.27 1.27)
				)
			)
		)
		(property "Value" ""
			(at 0 0 0)
			(layer "F.Fab")
			(effects
				(font
					(size 1.27 1.27)
				)
			)
		)
		(duplicate_pad_numbers_are_jumpers no)
		(fp_line
			(start -0.7874 -0.4064)
			(end 0.7874 -0.4064)
			(stroke
				(width 0.1524)
				(type default)
			)
			(layer "F.SilkS")
		)
		(fp_line
			(start -0.7874 0.4064)
			(end -0.7874 -0.4064)
			(stroke
				(width 0.1524)
				(type default)
			)
			(layer "F.SilkS")
		)
		(fp_line
			(start 0.7874 -0.4064)
			(end 0.7874 0.4064)
			(stroke
				(width 0.1524)
				(type default)
			)
			(layer "F.SilkS")
		)
		(fp_line
			(start 0.7874 0.4064)
			(end -0.7874 0.4064)
			(stroke
				(width 0.1524)
				(type default)
			)
			(layer "F.SilkS")
		)
		(fp_line
			(start -0.67945 -0.305054)
			(end -0.12065 -0.305054)
			(stroke
				(width 0.1)
				(type default)
			)
			(layer "F.Fab")
		)
		(fp_line
			(start -0.67945 0.3048)
			(end -0.67945 -0.305054)
			(stroke
				(width 0.1)
				(type default)
			)
			(layer "F.Fab")
		)
		(fp_line
			(start -0.12065 -0.305054)
			(end -0.12065 -0.2794)
			(stroke
				(width 0.1)
				(type default)
			)
			(layer "F.Fab")
		)
		(fp_line
			(start -0.12065 -0.2794)
			(end 0.12065 -0.2794)
			(stroke
				(width 0.1)
				(type default)
			)
			(layer "F.Fab")
		)
		(fp_line
			(start -0.12065 0.2794)
			(end -0.12065 0.3048)
			(stroke
				(width 0.1)
				(type default)
			)
			(layer "F.Fab")
		)
		(fp_line
			(start -0.12065 0.3048)
			(end -0.67945 0.3048)
			(stroke
				(width 0.1)
				(type default)
			)
			(layer "F.Fab")
		)
		(fp_line
			(start 0.120396 0.2794)
			(end -0.12065 0.2794)
			(stroke
				(width 0.1)
				(type default)
			)
			(layer "F.Fab")
		)
		(fp_line
			(start 0.120396 0.3048)
			(end 0.120396 0.2794)
			(stroke
				(width 0.1)
				(type default)
			)
			(layer "F.Fab")
		)
		(fp_line
			(start 0.12065 -0.3048)
			(end 0.67945 -0.3048)
			(stroke
				(width 0.1)
				(type default)
			)
			(layer "F.Fab")
		)
		(fp_line
			(start 0.12065 -0.2794)
			(end 0.12065 -0.3048)
			(stroke
				(width 0.1)
				(type default)
			)
			(layer "F.Fab")
		)
		(fp_line
			(start 0.67945 -0.3048)
			(end 0.67945 0.3048)
			(stroke
				(width 0.1)
				(type default)
			)
			(layer "F.Fab")
		)
		(fp_line
			(start 0.67945 0.3048)
			(end 0.120396 0.3048)
			(stroke
				(width 0.1)
				(type default)
			)
			(layer "F.Fab")
		)
		(pad "1" smd circle
			(at -0.40005 0)
			(size 0 0)
			(layers "F.Cu" "F.Mask" "F.Paste")
			(net "P1V25_PEX0_FB")
		)
		(pad "2" smd circle
			(at 0.40005 0)
			(size 0 0)
			(layers "F.Cu" "F.Mask" "F.Paste")
			(net "SH_P1V25_PEX0_FB_P")
		)
	)
	(footprint ""
		(layer "F.Cu")
		(at 344.612976 -85.255354 180)
		(property "Reference" "R1178"
			(at 0 0 180)
			(layer "F.SilkS")
			(hide yes)
			(effects
				(font
					(size 1.27 1.27)
				)
			)
		)
		(property "Value" ""
			(at 0 0 180)
			(layer "F.Fab")
			(effects
				(font
					(size 1.27 1.27)
				)
			)
		)
		(duplicate_pad_numbers_are_jumpers no)
		(fp_line
			(start -0.7874 -0.4064)
			(end 0.7874 -0.4064)
			(stroke
				(width 0.1524)
				(type default)
			)
			(layer "F.SilkS")
		)
		(fp_line
			(start 0.67945 0.3048)
			(end 0.120396 0.3048)
			(stroke
				(width 0.1)
				(type default)
			)
			(layer "F.Fab")
		)
		(fp_line
			(start 0.67945 -0.3048)
			(end 0.67945 0.3048)
			(stroke
				(width 0.1)
				(type default)
			)
			(layer "F.Fab")
		)
		(fp_line
			(start 0.12065 -0.2794)
			(end 0.12065 -0.3048)
			(stroke
				(width 0.1)
				(type default)
			)
			(layer "F.Fab")
		)
		(fp_line
			(start 0.12065 -0.3048)
			(end 0.67945 -0.3048)
			(stroke
				(width 0.1)
				(type default)
			)
			(layer "F.Fab")
		)
		(fp_line
			(start 0.120396 0.3048)
			(end 0.120396 0.2794)
			(stroke
				(width 0.1)
				(type default)
			)
			(layer "F.Fab")
		)
		(fp_line
			(start 0.120396 0.2794)
			(end -0.12065 0.2794)
			(stroke
				(width 0.1)
				(type default)
			)
			(layer "F.Fab")
		)
		(fp_line
			(start -0.12065 0.3048)
			(end -0.67945 0.3048)
			(stroke
				(width 0.1)
				(type default)
			)
			(layer "F.Fab")
		)
		(fp_line
			(start -0.12065 0.2794)
			(end -0.12065 0.3048)
			(stroke
				(width 0.1)
				(type default)
			)
			(layer "F.Fab")
		)
		(fp_line
			(start -0.12065 -0.2794)
			(end 0.12065 -0.2794)
			(stroke
				(width 0.1)
				(type default)
			)
			(layer "F.Fab")
		)
		(fp_line
			(start -0.12065 -0.305054)
			(end -0.12065 -0.2794)
			(stroke
				(width 0.1)
				(type default)
			)
			(layer "F.Fab")
		)
		(fp_line
			(start -0.67945 0.3048)
			(end -0.67945 -0.305054)
			(stroke
				(width 0.1)
				(type default)
			)
			(layer "F.Fab")
		)
		(fp_line
			(start -0.67945 -0.305054)
			(end -0.12065 -0.305054)
			(stroke
				(width 0.1)
				(type default)
			)
			(layer "F.Fab")
		)
		(pad "1" smd circle
			(at -0.40005 0 180)
			(size 0 0)
			(layers "F.Cu" "F.Mask" "F.Paste")
			(net "CLK_100M_DB800ZL_SSD12_R_DP")
		)
		(pad "2" smd circle
			(at 0.40005 0 180)
			(size 0 0)
			(layers "F.Cu" "F.Mask" "F.Paste")
			(net "CLK_100M_DB800ZL_SSD12_DP")
		)
	)
	(footprint ""
		(layer "F.Cu")
		(at 446.42532 -42.849038 180)
		(property "Reference" "R678"
			(at 0 0 180)
			(layer "F.SilkS")
			(hide yes)
			(effects
				(font
					(size 1.27 1.27)
				)
			)
		)
		(property "Value" ""
			(at 0 0 180)
			(layer "F.Fab")
			(effects
				(font
					(size 1.27 1.27)
				)
			)
		)
		(duplicate_pad_numbers_are_jumpers no)
		(fp_line
			(start 0.7874 0.4064)
			(end -0.7874 0.4064)
			(stroke
				(width 0.1524)
				(type default)
			)
			(layer "F.SilkS")
		)
		(fp_line
			(start 0.7874 -0.4064)
			(end 0.7874 0.4064)
			(stroke
				(width 0.1524)
				(type default)
			)
			(layer "F.SilkS")
		)
		(fp_line
			(start -0.7874 0.4064)
			(end -0.7874 -0.4064)
			(stroke
				(width 0.1524)
				(type default)
			)
			(layer "F.SilkS")
		)
		(fp_line
			(start -0.7874 -0.4064)
			(end 0.7874 -0.4064)
			(stroke
				(width 0.1524)
				(type default)
			)
			(layer "F.SilkS")
		)
		(fp_line
			(start 0.67945 0.3048)
			(end 0.120396 0.3048)
			(stroke
				(width 0.1)
				(type default)
			)
			(layer "F.Fab")
		)
		(fp_line
			(start 0.67945 -0.3048)
			(end 0.67945 0.3048)
			(stroke
				(width 0.1)
				(type default)
			)
			(layer "F.Fab")
		)
		(fp_line
			(start 0.12065 -0.2794)
			(end 0.12065 -0.3048)
			(stroke
				(width 0.1)
				(type default)
			)
			(layer "F.Fab")
		)
		(fp_line
			(start 0.12065 -0.3048)
			(end 0.67945 -0.3048)
			(stroke
				(width 0.1)
				(type default)
			)
			(layer "F.Fab")
		)
		(fp_line
			(start 0.120396 0.3048)
			(end 0.120396 0.2794)
			(stroke
				(width 0.1)
				(type default)
			)
			(layer "F.Fab")
		)
		(fp_line
			(start 0.120396 0.2794)
			(end -0.12065 0.2794)
			(stroke
				(width 0.1)
				(type default)
			)
			(layer "F.Fab")
		)
		(fp_line
			(start -0.12065 0.3048)
			(end -0.67945 0.3048)
			(stroke
				(width 0.1)
				(type default)
			)
			(layer "F.Fab")
		)
		(fp_line
			(start -0.12065 0.2794)
			(end -0.12065 0.3048)
			(stroke
				(width 0.1)
				(type default)
			)
			(layer "F.Fab")
		)
		(fp_line
			(start -0.12065 -0.2794)
			(end 0.12065 -0.2794)
			(stroke
				(width 0.1)
				(type default)
			)
			(layer "F.Fab")
		)
		(fp_line
			(start -0.12065 -0.305054)
			(end -0.12065 -0.2794)
			(stroke
				(width 0.1)
				(type default)
			)
			(layer "F.Fab")
		)
		(fp_line
			(start -0.67945 0.3048)
			(end -0.67945 -0.305054)
			(stroke
				(width 0.1)
				(type default)
			)
			(layer "F.Fab")
		)
		(fp_line
			(start -0.67945 -0.305054)
			(end -0.12065 -0.305054)
			(stroke
				(width 0.1)
				(type default)
			)
			(layer "F.Fab")
		)
		(pad "1" smd circle
			(at -0.40005 0 180)
			(size 0 0)
			(layers "F.Cu" "F.Mask" "F.Paste")
			(net "P12V_SSD15_R")
		)
		(pad "2" smd circle
			(at 0.40005 0 180)
			(size 0 0)
			(layers "F.Cu" "F.Mask" "F.Paste")
			(net "P12V_SSD15_VIN_P")
		)
	)
	(footprint ""
		(layer "F.Cu")
		(at 309.264304 -29.079952 180)
		(property "Reference" "R6208"
			(at 0 0 180)
			(layer "F.SilkS")
			(hide yes)
			(effects
				(font
					(size 1.27 1.27)
				)
			)
		)
		(property "Value" ""
			(at 0 0 180)
			(layer "F.Fab")
			(effects
				(font
					(size 1.27 1.27)
				)
			)
		)
		(duplicate_pad_numbers_are_jumpers no)
		(fp_line
			(start 0.7874 0.4064)
			(end -0.7874 0.4064)
			(stroke
				(width 0.1524)
				(type default)
			)
			(layer "F.SilkS")
		)
		(fp_line
			(start 0.7874 -0.4064)
			(end 0.7874 0.4064)
			(stroke
				(width 0.1524)
				(type default)
			)
			(layer "F.SilkS")
		)
		(fp_line
			(start -0.7874 0.4064)
			(end -0.7874 -0.4064)
			(stroke
				(width 0.1524)
				(type default)
			)
			(layer "F.SilkS")
		)
		(fp_line
			(start -0.7874 -0.4064)
			(end 0.7874 -0.4064)
			(stroke
				(width 0.1524)
				(type default)
			)
			(layer "F.SilkS")
		)
		(fp_line
			(start 0.67945 0.3048)
			(end 0.120396 0.3048)
			(stroke
				(width 0.1)
				(type default)
			)
			(layer "F.Fab")
		)
		(fp_line
			(start 0.67945 -0.3048)
			(end 0.67945 0.3048)
			(stroke
				(width 0.1)
				(type default)
			)
			(layer "F.Fab")
		)
		(fp_line
			(start 0.12065 -0.2794)
			(end 0.12065 -0.3048)
			(stroke
				(width 0.1)
				(type default)
			)
			(layer "F.Fab")
		)
		(fp_line
			(start 0.12065 -0.3048)
			(end 0.67945 -0.3048)
			(stroke
				(width 0.1)
				(type default)
			)
			(layer "F.Fab")
		)
		(fp_line
			(start 0.120396 0.3048)
			(end 0.120396 0.2794)
			(stroke
				(width 0.1)
				(type default)
			)
			(layer "F.Fab")
		)
		(fp_line
			(start 0.120396 0.2794)
			(end -0.12065 0.2794)
			(stroke
				(width 0.1)
				(type default)
			)
			(layer "F.Fab")
		)
		(fp_line
			(start -0.12065 0.3048)
			(end -0.67945 0.3048)
			(stroke
				(width 0.1)
				(type default)
			)
			(layer "F.Fab")
		)
		(fp_line
			(start -0.12065 0.2794)
			(end -0.12065 0.3048)
			(stroke
				(width 0.1)
				(type default)
			)
			(layer "F.Fab")
		)
		(fp_line
			(start -0.12065 -0.2794)
			(end 0.12065 -0.2794)
			(stroke
				(width 0.1)
				(type default)
			)
			(layer "F.Fab")
		)
		(fp_line
			(start -0.12065 -0.305054)
			(end -0.12065 -0.2794)
			(stroke
				(width 0.1)
				(type default)
			)
			(layer "F.Fab")
		)
		(fp_line
			(start -0.67945 0.3048)
			(end -0.67945 -0.305054)
			(stroke
				(width 0.1)
				(type default)
			)
			(layer "F.Fab")
		)
		(fp_line
			(start -0.67945 -0.305054)
			(end -0.12065 -0.305054)
			(stroke
				(width 0.1)
				(type default)
			)
			(layer "F.Fab")
		)
		(pad "1" smd circle
			(at -0.40005 0 180)
			(size 0 0)
			(layers "F.Cu" "F.Mask" "F.Paste")
			(net "GND")
		)
		(pad "2" smd circle
			(at 0.40005 0 180)
			(size 0 0)
			(layers "F.Cu" "F.Mask" "F.Paste")
			(net "SSD10_PWRDIS_R")
		)
	)
	(footprint ""
		(layer "F.Cu")
		(at 85.933788 -302.88738 90)
		(property "Reference" "R6660"
			(at 0 0 90)
			(layer "F.SilkS")
			(hide yes)
			(effects
				(font
					(size 1.27 1.27)
				)
			)
		)
		(property "Value" ""
			(at 0 0 90)
			(layer "F.Fab")
			(effects
				(font
					(size 1.27 1.27)
				)
			)
		)
		(duplicate_pad_numbers_are_jumpers no)
		(fp_line
			(start 0.7874 -0.4064)
			(end 0.7874 0.4064)
			(stroke
				(width 0.1524)
				(type default)
			)
			(layer "F.SilkS")
		)
		(fp_line
			(start -0.7874 -0.4064)
			(end 0.7874 -0.4064)
			(stroke
				(width 0.1524)
				(type default)
			)
			(layer "F.SilkS")
		)
		(fp_line
			(start 0.7874 0.4064)
			(end -0.7874 0.4064)
			(stroke
				(width 0.1524)
				(type default)
			)
			(layer "F.SilkS")
		)
		(fp_line
			(start -0.7874 0.4064)
			(end -0.7874 -0.4064)
			(stroke
				(width 0.1524)
				(type default)
			)
			(layer "F.SilkS")
		)
		(fp_line
			(start -0.12065 -0.305054)
			(end -0.12065 -0.2794)
			(stroke
				(width 0.1)
				(type default)
			)
			(layer "F.Fab")
		)
		(fp_line
			(start -0.67945 -0.305054)
			(end -0.12065 -0.305054)
			(stroke
				(width 0.1)
				(type default)
			)
			(layer "F.Fab")
		)
		(fp_line
			(start 0.67945 -0.3048)
			(end 0.67945 0.3048)
			(stroke
				(width 0.1)
				(type default)
			)
			(layer "F.Fab")
		)
		(fp_line
			(start 0.12065 -0.3048)
			(end 0.67945 -0.3048)
			(stroke
				(width 0.1)
				(type default)
			)
			(layer "F.Fab")
		)
		(fp_line
			(start 0.12065 -0.2794)
			(end 0.12065 -0.3048)
			(stroke
				(width 0.1)
				(type default)
			)
			(layer "F.Fab")
		)
		(fp_line
			(start -0.12065 -0.2794)
			(end 0.12065 -0.2794)
			(stroke
				(width 0.1)
				(type default)
			)
			(layer "F.Fab")
		)
		(fp_line
			(start 0.120396 0.2794)
			(end -0.12065 0.2794)
			(stroke
				(width 0.1)
				(type default)
			)
			(layer "F.Fab")
		)
		(fp_line
			(start -0.12065 0.2794)
			(end -0.12065 0.3048)
			(stroke
				(width 0.1)
				(type default)
			)
			(layer "F.Fab")
		)
		(fp_line
			(start 0.67945 0.3048)
			(end 0.120396 0.3048)
			(stroke
				(width 0.1)
				(type default)
			)
			(layer "F.Fab")
		)
		(fp_line
			(start 0.120396 0.3048)
			(end 0.120396 0.2794)
			(stroke
				(width 0.1)
				(type default)
			)
			(layer "F.Fab")
		)
		(fp_line
			(start -0.12065 0.3048)
			(end -0.67945 0.3048)
			(stroke
				(width 0.1)
				(type default)
			)
			(layer "F.Fab")
		)
		(fp_line
			(start -0.67945 0.3048)
			(end -0.67945 -0.305054)
			(stroke
				(width 0.1)
				(type default)
			)
			(layer "F.Fab")
		)
		(pad "1" smd circle
			(at -0.40005 0 90)
			(size 0 0)
			(layers "F.Cu" "F.Mask" "F.Paste")
			(net "SMB_PEX0_SLAVE1_SCL")
		)
		(pad "2" smd circle
			(at 0.40005 0 90)
			(size 0 0)
			(layers "F.Cu" "F.Mask" "F.Paste")
			(net "SMB_PEX0_R_SCL")
		)
	)
	(footprint ""
		(layer "F.Cu")
		(at 440.652662 -311.197244 135)
		(property "Reference" "R1449"
			(at 0 0 135)
			(layer "F.SilkS")
			(hide yes)
			(effects
				(font
					(size 1.27 1.27)
				)
			)
		)
		(property "Value" ""
			(at 0 0 135)
			(layer "F.Fab")
			(effects
				(font
					(size 1.27 1.27)
				)
			)
		)
		(duplicate_pad_numbers_are_jumpers no)
		(fp_line
			(start 0.787389 -0.406267)
			(end 0.787389 0.406267)
			(stroke
				(width 0.1524)
				(type default)
			)
			(layer "F.SilkS")
		)
		(fp_line
			(start 0.787389 0.406267)
			(end -0.787389 0.406267)
			(stroke
				(width 0.1524)
				(type default)
			)
			(layer "F.SilkS")
		)
		(fp_line
			(start -0.787389 -0.406267)
			(end 0.787389 -0.406267)
			(stroke
				(width 0.1524)
				(type default)
			)
			(layer "F.SilkS")
		)
		(fp_line
			(start -0.787389 0.406267)
			(end -0.787389 -0.406267)
			(stroke
				(width 0.1524)
				(type default)
			)
			(layer "F.SilkS")
		)
		(fp_line
			(start 0.679446 -0.30479)
			(end 0.679446 0.30479)
			(stroke
				(width 0.1)
				(type default)
			)
			(layer "F.Fab")
		)
		(fp_line
			(start 0.120515 -0.30479)
			(end 0.679446 -0.30479)
			(stroke
				(width 0.1)
				(type default)
			)
			(layer "F.Fab")
		)
		(fp_line
			(start 0.120695 -0.279466)
			(end 0.120515 -0.30479)
			(stroke
				(width 0.1)
				(type default)
			)
			(layer "F.Fab")
		)
		(fp_line
			(start 0.679446 0.30479)
			(end 0.120515 0.30479)
			(stroke
				(width 0.1)
				(type default)
			)
			(layer "F.Fab")
		)
		(fp_line
			(start -0.120695 -0.304969)
			(end -0.120695 -0.279466)
			(stroke
				(width 0.1)
				(type default)
			)
			(layer "F.Fab")
		)
		(fp_line
			(start -0.120695 -0.279466)
			(end 0.120695 -0.279466)
			(stroke
				(width 0.1)
				(type default)
			)
			(layer "F.Fab")
		)
		(fp_line
			(start 0.120335 0.279466)
			(end -0.120695 0.279466)
			(stroke
				(width 0.1)
				(type default)
			)
			(layer "F.Fab")
		)
		(fp_line
			(start 0.120515 0.30479)
			(end 0.120335 0.279466)
			(stroke
				(width 0.1)
				(type default)
			)
			(layer "F.Fab")
		)
		(fp_line
			(start -0.679446 -0.305149)
			(end -0.120695 -0.304969)
			(stroke
				(width 0.1)
				(type default)
			)
			(layer "F.Fab")
		)
		(fp_line
			(start -0.120695 0.279466)
			(end -0.120515 0.30479)
			(stroke
				(width 0.1)
				(type default)
			)
			(layer "F.Fab")
		)
		(fp_line
			(start -0.120515 0.30479)
			(end -0.679446 0.30479)
			(stroke
				(width 0.1)
				(type default)
			)
			(layer "F.Fab")
		)
		(fp_line
			(start -0.679446 0.30479)
			(end -0.679446 -0.305149)
			(stroke
				(width 0.1)
				(type default)
			)
			(layer "F.Fab")
		)
		(pad "1" smd circle
			(at -0.40005 0 135)
			(size 0 0)
			(layers "F.Cu" "F.Mask" "F.Paste")
			(net "GND")
		)
		(pad "2" smd circle
			(at 0.40005 0 135)
			(size 0 0)
			(layers "F.Cu" "F.Mask" "F.Paste")
			(net "PEX3_SPARE5")
		)
	)
	(footprint ""
		(layer "F.Cu")
		(at 208.150206 -306.074572 90)
		(property "Reference" "R1309"
			(at 0 0 90)
			(layer "F.SilkS")
			(hide yes)
			(effects
				(font
					(size 1.27 1.27)
				)
			)
		)
		(property "Value" ""
			(at 0 0 90)
			(layer "F.Fab")
			(effects
				(font
					(size 1.27 1.27)
				)
			)
		)
		(duplicate_pad_numbers_are_jumpers no)
		(fp_line
			(start 0.7874 -0.4064)
			(end 0.7874 0.4064)
			(stroke
				(width 0.1524)
				(type default)
			)
			(layer "F.SilkS")
		)
		(fp_line
			(start -0.7874 -0.4064)
			(end 0.7874 -0.4064)
			(stroke
				(width 0.1524)
				(type default)
			)
			(layer "F.SilkS")
		)
		(fp_line
			(start 0.7874 0.4064)
			(end -0.7874 0.4064)
			(stroke
				(width 0.1524)
				(type default)
			)
			(layer "F.SilkS")
		)
		(fp_line
			(start -0.7874 0.4064)
			(end -0.7874 -0.4064)
			(stroke
				(width 0.1524)
				(type default)
			)
			(layer "F.SilkS")
		)
		(fp_line
			(start -0.12065 -0.305054)
			(end -0.12065 -0.2794)
			(stroke
				(width 0.1)
				(type default)
			)
			(layer "F.Fab")
		)
		(fp_line
			(start -0.67945 -0.305054)
			(end -0.12065 -0.305054)
			(stroke
				(width 0.1)
				(type default)
			)
			(layer "F.Fab")
		)
		(fp_line
			(start 0.67945 -0.3048)
			(end 0.67945 0.3048)
			(stroke
				(width 0.1)
				(type default)
			)
			(layer "F.Fab")
		)
		(fp_line
			(start 0.12065 -0.3048)
			(end 0.67945 -0.3048)
			(stroke
				(width 0.1)
				(type default)
			)
			(layer "F.Fab")
		)
		(fp_line
			(start 0.12065 -0.2794)
			(end 0.12065 -0.3048)
			(stroke
				(width 0.1)
				(type default)
			)
			(layer "F.Fab")
		)
		(fp_line
			(start -0.12065 -0.2794)
			(end 0.12065 -0.2794)
			(stroke
				(width 0.1)
				(type default)
			)
			(layer "F.Fab")
		)
		(fp_line
			(start 0.120396 0.2794)
			(end -0.12065 0.2794)
			(stroke
				(width 0.1)
				(type default)
			)
			(layer "F.Fab")
		)
		(fp_line
			(start -0.12065 0.2794)
			(end -0.12065 0.3048)
			(stroke
				(width 0.1)
				(type default)
			)
			(layer "F.Fab")
		)
		(fp_line
			(start 0.67945 0.3048)
			(end 0.120396 0.3048)
			(stroke
				(width 0.1)
				(type default)
			)
			(layer "F.Fab")
		)
		(fp_line
			(start 0.120396 0.3048)
			(end 0.120396 0.2794)
			(stroke
				(width 0.1)
				(type default)
			)
			(layer "F.Fab")
		)
		(fp_line
			(start -0.12065 0.3048)
			(end -0.67945 0.3048)
			(stroke
				(width 0.1)
				(type default)
			)
			(layer "F.Fab")
		)
		(fp_line
			(start -0.67945 0.3048)
			(end -0.67945 -0.305054)
			(stroke
				(width 0.1)
				(type default)
			)
			(layer "F.Fab")
		)
		(pad "1" smd circle
			(at -0.40005 0 90)
			(size 0 0)
			(layers "F.Cu" "F.Mask" "F.Paste")
			(net "PEX1_SPARE6")
		)
		(pad "2" smd circle
			(at 0.40005 0 90)
			(size 0 0)
			(layers "F.Cu" "F.Mask" "F.Paste")
			(net "P1V8_PEX")
		)
	)
	(footprint ""
		(layer "F.Cu")
		(at 101.601016 -303.649634 90)
		(property "Reference" "PC68"
			(at 0 0 90)
			(layer "F.SilkS")
			(hide yes)
			(effects
				(font
					(size 1.27 1.27)
				)
			)
		)
		(property "Value" ""
			(at 0 0 90)
			(layer "F.Fab")
			(effects
				(font
					(size 1.27 1.27)
				)
			)
		)
		(duplicate_pad_numbers_are_jumpers no)
		(fp_line
			(start 1.524 -0.762)
			(end 1.524 0.762)
			(stroke
				(width 0.1524)
				(type default)
			)
			(layer "F.SilkS")
		)
		(fp_line
			(start -1.524 -0.762)
			(end 1.524 -0.762)
			(stroke
				(width 0.1524)
				(type default)
			)
			(layer "F.SilkS")
		)
		(fp_line
			(start 1.524 0.762)
			(end -1.524 0.762)
			(stroke
				(width 0.1524)
				(type default)
			)
			(layer "F.SilkS")
		)
		(fp_line
			(start -1.524 0.762)
			(end -1.524 -0.762)
			(stroke
				(width 0.1524)
				(type default)
			)
			(layer "F.SilkS")
		)
		(fp_line
			(start 1.1049 -0.724916)
			(end -1.1049 -0.724916)
			(stroke
				(width 0.1)
				(type default)
			)
			(layer "F.Fab")
		)
		(fp_line
			(start -1.1049 -0.724916)
			(end -1.1049 0.724916)
			(stroke
				(width 0.1)
				(type default)
			)
			(layer "F.Fab")
		)
		(fp_line
			(start 1.1049 0.724916)
			(end 1.1049 -0.724916)
			(stroke
				(width 0.1)
				(type default)
			)
			(layer "F.Fab")
		)
		(fp_line
			(start -1.1049 0.724916)
			(end 1.1049 0.724916)
			(stroke
				(width 0.1)
				(type default)
			)
			(layer "F.Fab")
		)
		(pad "1" smd rect
			(at -0.889 0 270)
			(size 1.016 1.27)
			(layers "F.Cu" "F.Mask" "F.Paste")
			(net "P0V8_PEX0")
		)
		(pad "2" smd rect
			(at 0.889 0 270)
			(size 1.016 1.27)
			(layers "F.Cu" "F.Mask" "F.Paste")
			(net "GND")
		)
	)
	(footprint ""
		(layer "F.Cu")
		(at 118.969028 -350.098614 90)
		(property "Reference" "C363"
			(at 0 0 90)
			(layer "F.SilkS")
			(hide yes)
			(effects
				(font
					(size 1.27 1.27)
				)
			)
		)
		(property "Value" ""
			(at 0 0 90)
			(layer "F.Fab")
			(effects
				(font
					(size 1.27 1.27)
				)
			)
		)
		(duplicate_pad_numbers_are_jumpers no)
		(fp_line
			(start 0.299974 -0.150114)
			(end 0.299974 0.150114)
			(stroke
				(width 0.1)
				(type default)
			)
			(layer "F.Fab")
		)
		(fp_line
			(start -0.299974 -0.150114)
			(end 0.299974 -0.150114)
			(stroke
				(width 0.1)
				(type default)
			)
			(layer "F.Fab")
		)
		(fp_line
			(start 0.299974 0.150114)
			(end -0.299974 0.150114)
			(stroke
				(width 0.1)
				(type default)
			)
			(layer "F.Fab")
		)
		(fp_line
			(start -0.299974 0.150114)
			(end -0.299974 -0.150114)
			(stroke
				(width 0.1)
				(type default)
			)
			(layer "F.Fab")
		)
		(pad "1" smd rect
			(at -0.2667 0 90)
			(size 0.3048 0.381)
			(layers "F.Cu" "F.Mask" "F.Paste")
			(net "P5E_PEX1_STN6_TX_DN<100>")
		)
		(pad "2" smd rect
			(at 0.2667 0 90)
			(size 0.3048 0.381)
			(layers "F.Cu" "F.Mask" "F.Paste")
			(net "P5E_PEX1_STN6_TX_C_DN<100>")
		)
	)
	(footprint ""
		(layer "F.Cu")
		(at 329.438 -82.931 180)
		(property "Reference" "R6259"
			(at 0 0 180)
			(layer "F.SilkS")
			(hide yes)
			(effects
				(font
					(size 1.27 1.27)
				)
			)
		)
		(property "Value" ""
			(at 0 0 180)
			(layer "F.Fab")
			(effects
				(font
					(size 1.27 1.27)
				)
			)
		)
		(duplicate_pad_numbers_are_jumpers no)
		(fp_line
			(start 0.7874 0.4064)
			(end -0.7874 0.4064)
			(stroke
				(width 0.1524)
				(type default)
			)
			(layer "F.SilkS")
		)
		(fp_line
			(start 0.7874 -0.4064)
			(end 0.7874 0.4064)
			(stroke
				(width 0.1524)
				(type default)
			)
			(layer "F.SilkS")
		)
		(fp_line
			(start -0.7874 0.4064)
			(end -0.7874 -0.4064)
			(stroke
				(width 0.1524)
				(type default)
			)
			(layer "F.SilkS")
		)
		(fp_line
			(start -0.7874 -0.4064)
			(end 0.7874 -0.4064)
			(stroke
				(width 0.1524)
				(type default)
			)
			(layer "F.SilkS")
		)
		(fp_line
			(start 0.67945 0.3048)
			(end 0.120396 0.3048)
			(stroke
				(width 0.1)
				(type default)
			)
			(layer "F.Fab")
		)
		(fp_line
			(start 0.67945 -0.3048)
			(end 0.67945 0.3048)
			(stroke
				(width 0.1)
				(type default)
			)
			(layer "F.Fab")
		)
		(fp_line
			(start 0.12065 -0.2794)
			(end 0.12065 -0.3048)
			(stroke
				(width 0.1)
				(type default)
			)
			(layer "F.Fab")
		)
		(fp_line
			(start 0.12065 -0.3048)
			(end 0.67945 -0.3048)
			(stroke
				(width 0.1)
				(type default)
			)
			(layer "F.Fab")
		)
		(fp_line
			(start 0.120396 0.3048)
			(end 0.120396 0.2794)
			(stroke
				(width 0.1)
				(type default)
			)
			(layer "F.Fab")
		)
		(fp_line
			(start 0.120396 0.2794)
			(end -0.12065 0.2794)
			(stroke
				(width 0.1)
				(type default)
			)
			(layer "F.Fab")
		)
		(fp_line
			(start -0.12065 0.3048)
			(end -0.67945 0.3048)
			(stroke
				(width 0.1)
				(type default)
			)
			(layer "F.Fab")
		)
		(fp_line
			(start -0.12065 0.2794)
			(end -0.12065 0.3048)
			(stroke
				(width 0.1)
				(type default)
			)
			(layer "F.Fab")
		)
		(fp_line
			(start -0.12065 -0.2794)
			(end 0.12065 -0.2794)
			(stroke
				(width 0.1)
				(type default)
			)
			(layer "F.Fab")
		)
		(fp_line
			(start -0.12065 -0.305054)
			(end -0.12065 -0.2794)
			(stroke
				(width 0.1)
				(type default)
			)
			(layer "F.Fab")
		)
		(fp_line
			(start -0.67945 0.3048)
			(end -0.67945 -0.305054)
			(stroke
				(width 0.1)
				(type default)
			)
			(layer "F.Fab")
		)
		(fp_line
			(start -0.67945 -0.305054)
			(end -0.12065 -0.305054)
			(stroke
				(width 0.1)
				(type default)
			)
			(layer "F.Fab")
		)
		(pad "1" smd circle
			(at -0.40005 0 180)
			(size 0 0)
			(layers "F.Cu" "F.Mask" "F.Paste")
			(net "SMB_ISO_CB_SCL")
		)
		(pad "2" smd circle
			(at 0.40005 0 180)
			(size 0 0)
			(layers "F.Cu" "F.Mask" "F.Paste")
			(net "P3V3")
		)
	)
	(footprint ""
		(layer "F.Cu")
		(at 269.448026 -101.095302)
		(property "Reference" "C483"
			(at 0 0 0)
			(layer "F.SilkS")
			(hide yes)
			(effects
				(font
					(size 1.27 1.27)
				)
			)
		)
		(property "Value" ""
			(at 0 0 0)
			(layer "F.Fab")
			(effects
				(font
					(size 1.27 1.27)
				)
			)
		)
		(duplicate_pad_numbers_are_jumpers no)
		(fp_line
			(start -0.299974 -0.150114)
			(end 0.299974 -0.150114)
			(stroke
				(width 0.1)
				(type default)
			)
			(layer "F.Fab")
		)
		(fp_line
			(start -0.299974 0.150114)
			(end -0.299974 -0.150114)
			(stroke
				(width 0.1)
				(type default)
			)
			(layer "F.Fab")
		)
		(fp_line
			(start 0.299974 -0.150114)
			(end 0.299974 0.150114)
			(stroke
				(width 0.1)
				(type default)
			)
			(layer "F.Fab")
		)
		(fp_line
			(start 0.299974 0.150114)
			(end -0.299974 0.150114)
			(stroke
				(width 0.1)
				(type default)
			)
			(layer "F.Fab")
		)
		(pad "1" smd rect
			(at -0.2667 0)
			(size 0.3048 0.381)
			(layers "F.Cu" "F.Mask" "F.Paste")
			(net "P5E_PEX2_STN1_TX_DN<17>")
		)
		(pad "2" smd rect
			(at 0.2667 0)
			(size 0.3048 0.381)
			(layers "F.Cu" "F.Mask" "F.Paste")
			(net "P5E_PEX2_STN1_TX_C_DN<17>")
		)
	)
	(footprint ""
		(layer "F.Cu")
		(at 323.8246 -115.835176 90)
		(property "Reference" "PU120"
			(at 1.613154 -3.429 0)
			(unlocked yes)
			(layer "F.SilkS")
			(effects
				(font
					(size 0.7874 0.5842)
					(thickness 0.1524)
				)
			)
		)
		(property "Value" ""
			(at 0 0 90)
			(layer "F.Fab")
			(effects
				(font
					(size 1.27 1.27)
				)
			)
		)
		(duplicate_pad_numbers_are_jumpers no)
		(fp_line
			(start 1.239774 -1.495298)
			(end 1.239774 1.495298)
			(stroke
				(width 0.1524)
				(type default)
			)
			(layer "F.SilkS")
		)
		(fp_line
			(start -1.239774 -1.495298)
			(end 1.239774 -1.495298)
			(stroke
				(width 0.1524)
				(type default)
			)
			(layer "F.SilkS")
		)
		(fp_line
			(start 1.239774 1.495298)
			(end -1.239774 1.495298)
			(stroke
				(width 0.1524)
				(type default)
			)
			(layer "F.SilkS")
		)
		(fp_line
			(start -1.239774 1.495298)
			(end -1.239774 -1.495298)
			(stroke
				(width 0.1524)
				(type default)
			)
			(layer "F.SilkS")
		)
		(fp_poly
			(pts
				(xy -2.164588 -1.709928) (xy -2.8829 -0.991616) (xy -1.805432 -0.63246)
			)
			(stroke
				(width 0)
				(type default)
			)
			(fill yes)
			(layer "F.SilkS")
		)
		(fp_line
			(start 0.8001 -1.050036)
			(end 0.8001 1.050036)
			(stroke
				(width 0.1)
				(type default)
			)
			(layer "F.Fab")
		)
		(fp_line
			(start -0.8001 -1.050036)
			(end 0.8001 -1.050036)
			(stroke
				(width 0.1)
				(type default)
			)
			(layer "F.Fab")
		)
		(fp_line
			(start 0.8001 1.050036)
			(end -0.8001 1.050036)
			(stroke
				(width 0.1)
				(type default)
			)
			(layer "F.Fab")
		)
		(fp_line
			(start -0.8001 1.050036)
			(end -0.8001 -1.050036)
			(stroke
				(width 0.1)
				(type default)
			)
			(layer "F.Fab")
		)
		(fp_poly
			(pts
				(xy -2.458974 -0.508) (xy -2.458974 0.508) (xy -1.442974 0)
			)
			(stroke
				(width 0)
				(type default)
			)
			(fill yes)
			(layer "F.Fab")
		)
		(pad "1_2" smd circle
			(at -0.374904 0 180)
			(size 0 0)
			(layers "F.Cu" "F.Mask" "F.Paste")
			(net "P3V3_AUX")
		)
		(pad "3" smd rect
			(at -0.499872 0.999998 90)
			(size 0.254 0.7112)
			(layers "F.Cu" "F.Mask" "F.Paste")
			(net "GND")
		)
		(pad "4" smd rect
			(at 0 0.999998 90)
			(size 0.254 0.7112)
			(layers "F.Cu" "F.Mask" "F.Paste")
			(net "P3V3_NIC5_CO_ILIMIT")
		)
		(pad "5" smd rect
			(at 0.499872 0.999998 90)
			(size 0.254 0.7112)
			(layers "F.Cu" "F.Mask" "F.Paste")
			(net "P3V3_NIC5_CO_MODE")
		)
		(pad "6_7" smd circle
			(at 0.374904 0)
			(size 0 0)
			(layers "F.Cu" "F.Mask" "F.Paste")
			(net "P3V3_NIC5")
		)
		(pad "8" smd rect
			(at 0.499872 -0.999998 90)
			(size 0.254 0.7112)
			(layers "F.Cu" "F.Mask" "F.Paste")
			(net "P3V3_NIC5_CO_GATE")
		)
		(pad "9" smd rect
			(at 0 -0.999998 90)
			(size 0.254 0.7112)
			(layers "F.Cu" "F.Mask" "F.Paste")
			(net "P3V3_NIC5_CO_EN")
		)
		(pad "10" smd rect
			(at -0.499872 -0.999998 90)
			(size 0.254 0.7112)
			(layers "F.Cu" "F.Mask" "F.Paste")
			(net "P3V3_NIC5_CO_DV_DT")
		)
	)
	(footprint ""
		(layer "F.Cu")
		(at 38.566344 -252.356874 -90)
		(property "Reference" "R1189"
			(at 0 0 270)
			(layer "F.SilkS")
			(hide yes)
			(effects
				(font
					(size 1.27 1.27)
				)
			)
		)
		(property "Value" ""
			(at 0 0 270)
			(layer "F.Fab")
			(effects
				(font
					(size 1.27 1.27)
				)
			)
		)
		(duplicate_pad_numbers_are_jumpers no)
		(fp_line
			(start -0.7874 0.4064)
			(end -0.7874 -0.4064)
			(stroke
				(width 0.1524)
				(type default)
			)
			(layer "F.SilkS")
		)
		(fp_line
			(start 0.7874 0.4064)
			(end -0.7874 0.4064)
			(stroke
				(width 0.1524)
				(type default)
			)
			(layer "F.SilkS")
		)
		(fp_line
			(start -0.7874 -0.4064)
			(end 0.7874 -0.4064)
			(stroke
				(width 0.1524)
				(type default)
			)
			(layer "F.SilkS")
		)
		(fp_line
			(start 0.7874 -0.4064)
			(end 0.7874 0.4064)
			(stroke
				(width 0.1524)
				(type default)
			)
			(layer "F.SilkS")
		)
		(fp_line
			(start -0.67945 0.3048)
			(end -0.67945 -0.305054)
			(stroke
				(width 0.1)
				(type default)
			)
			(layer "F.Fab")
		)
		(fp_line
			(start -0.12065 0.3048)
			(end -0.67945 0.3048)
			(stroke
				(width 0.1)
				(type default)
			)
			(layer "F.Fab")
		)
		(fp_line
			(start 0.120396 0.3048)
			(end 0.120396 0.2794)
			(stroke
				(width 0.1)
				(type default)
			)
			(layer "F.Fab")
		)
		(fp_line
			(start 0.67945 0.3048)
			(end 0.120396 0.3048)
			(stroke
				(width 0.1)
				(type default)
			)
			(layer "F.Fab")
		)
		(fp_line
			(start -0.12065 0.2794)
			(end -0.12065 0.3048)
			(stroke
				(width 0.1)
				(type default)
			)
			(layer "F.Fab")
		)
		(fp_line
			(start 0.120396 0.2794)
			(end -0.12065 0.2794)
			(stroke
				(width 0.1)
				(type default)
			)
			(layer "F.Fab")
		)
		(fp_line
			(start -0.12065 -0.2794)
			(end 0.12065 -0.2794)
			(stroke
				(width 0.1)
				(type default)
			)
			(layer "F.Fab")
		)
		(fp_line
			(start 0.12065 -0.2794)
			(end 0.12065 -0.3048)
			(stroke
				(width 0.1)
				(type default)
			)
			(layer "F.Fab")
		)
		(fp_line
			(start 0.12065 -0.3048)
			(end 0.67945 -0.3048)
			(stroke
				(width 0.1)
				(type default)
			)
			(layer "F.Fab")
		)
		(fp_line
			(start 0.67945 -0.3048)
			(end 0.67945 0.3048)
			(stroke
				(width 0.1)
				(type default)
			)
			(layer "F.Fab")
		)
		(fp_line
			(start -0.67945 -0.305054)
			(end -0.12065 -0.305054)
			(stroke
				(width 0.1)
				(type default)
			)
			(layer "F.Fab")
		)
		(fp_line
			(start -0.12065 -0.305054)
			(end -0.12065 -0.2794)
			(stroke
				(width 0.1)
				(type default)
			)
			(layer "F.Fab")
		)
		(pad "1" smd circle
			(at -0.40005 0 270)
			(size 0 0)
			(layers "F.Cu" "F.Mask" "F.Paste")
			(net "GND")
		)
		(pad "2" smd circle
			(at 0.40005 0 270)
			(size 0 0)
			(layers "F.Cu" "F.Mask" "F.Paste")
			(net "PEX0_DBG_MODE4")
		)
	)
	(footprint ""
		(layer "F.Cu")
		(at 377.949714 -270.89989)
		(property "Reference" "H97"
			(at -8.582152 5.53339 0)
			(unlocked yes)
			(layer "F.SilkS")
			(effects
				(font
					(size 0.7874 0.5842)
					(thickness 0.1524)
				)
				(justify left)
			)
		)
		(property "Value" ""
			(at 0 0 0)
			(layer "F.Fab")
			(effects
				(font
					(size 1.27 1.27)
				)
			)
		)
		(duplicate_pad_numbers_are_jumpers no)
		(fp_arc
			(start -6.13156 -5.138166)
			(mid -0.38317 -7.990754)
			(end 5.611876 -5.701538)
			(stroke
				(width 0.1524)
				(type default)
			)
			(layer "F.SilkS")
		)
		(fp_arc
			(start 7.957058 -0.828294)
			(mid 7.989266 -0.414704)
			(end 7.999984 0)
			(stroke
				(width 0.1524)
				(type default)
			)
			(layer "F.SilkS")
		)
		(fp_arc
			(start 7.999984 0)
			(mid -1.072494 7.927345)
			(end -7.711948 -2.12598)
			(stroke
				(width 0.1524)
				(type default)
			)
			(layer "F.SilkS")
		)
		(fp_arc
			(start -5.678932 -5.634482)
			(mid -4.30144 -6.745127)
			(end -2.713482 -7.525766)
			(stroke
				(width 0.1524)
				(type default)
			)
			(layer "B.SilkS")
		)
		(fp_arc
			(start 1.398016 -7.877048)
			(mid 3.669224 -7.10905)
			(end 5.61086 -5.702554)
			(stroke
				(width 0.1524)
				(type default)
			)
			(layer "B.SilkS")
		)
		(fp_arc
			(start 7.933182 -1.032256)
			(mid 7.983281 -0.517209)
			(end 7.999984 0)
			(stroke
				(width 0.1524)
				(type default)
			)
			(layer "B.SilkS")
		)
		(fp_arc
			(start 7.999984 0)
			(mid 0.652631 7.97313)
			(end -7.893304 1.300734)
			(stroke
				(width 0.1524)
				(type default)
			)
			(layer "B.SilkS")
		)
		(fp_circle
			(center 0 0)
			(end 7.999984 0)
			(stroke
				(width 0.1)
				(type default)
			)
			(fill no)
			(layer "B.Fab")
		)
		(fp_circle
			(center 0 0)
			(end 7.999984 0)
			(stroke
				(width 0.1)
				(type default)
			)
			(fill no)
			(layer "F.Fab")
		)
		(pad "" np_thru_hole circle
			(at 0 0)
			(size 4.5212 4.5212)
			(drill 4.5212)
			(layers "*.Cu" "*.Mask")
			(clearance 0.381)
			(thermal_gap 0.381)
		)
		(pad "2" thru_hole circle
			(at 3.6322 0)
			(size 0.762 0.762)
			(drill 0.5588)
			(layers "*.Cu" "*.Mask")
			(remove_unused_layers no)
			(net "GND")
			(clearance 0.1524)
			(thermal_gap 0.1524)
		)
		(pad "3" thru_hole circle
			(at 2.568448 -2.568448)
			(size 0.762 0.762)
			(drill 0.5588)
			(layers "*.Cu" "*.Mask")
			(remove_unused_layers no)
			(net "GND")
			(clearance 0.1524)
			(thermal_gap 0.1524)
		)
		(pad "4" thru_hole circle
			(at 0 -3.6322)
			(size 0.762 0.762)
			(drill 0.5588)
			(layers "*.Cu" "*.Mask")
			(remove_unused_layers no)
			(net "GND")
			(clearance 0.1524)
			(thermal_gap 0.1524)
		)
		(pad "5" thru_hole circle
			(at -2.568448 -2.568448)
			(size 0.762 0.762)
			(drill 0.5588)
			(layers "*.Cu" "*.Mask")
			(remove_unused_layers no)
			(net "GND")
			(clearance 0.1524)
			(thermal_gap 0.1524)
		)
		(pad "6" thru_hole circle
			(at -3.6322 0)
			(size 0.762 0.762)
			(drill 0.5588)
			(layers "*.Cu" "*.Mask")
			(remove_unused_layers no)
			(net "GND")
			(clearance 0.1524)
			(thermal_gap 0.1524)
		)
		(pad "7" thru_hole circle
			(at -2.568448 2.568448)
			(size 0.762 0.762)
			(drill 0.5588)
			(layers "*.Cu" "*.Mask")
			(remove_unused_layers no)
			(net "GND")
			(clearance 0.1524)
			(thermal_gap 0.1524)
		)
		(pad "8" thru_hole circle
			(at 0 3.6322)
			(size 0.762 0.762)
			(drill 0.5588)
			(layers "*.Cu" "*.Mask")
			(remove_unused_layers no)
			(net "GND")
			(clearance 0.1524)
			(thermal_gap 0.1524)
		)
		(pad "9" thru_hole circle
			(at 2.568448 2.568448)
			(size 0.762 0.762)
			(drill 0.5588)
			(layers "*.Cu" "*.Mask")
			(remove_unused_layers no)
			(net "GND")
			(clearance 0.1524)
			(thermal_gap 0.1524)
		)
		(zone
			(layer "F.Cu")
			(hatch none 0.5)
			(connect_pads
				(clearance 0)
			)
			(min_thickness 0.25)
			(keepout
				(tracks not_allowed)
				(vias allowed)
				(pads allowed)
				(copperpour not_allowed)
				(footprints allowed)
			)
			(placement
				(enabled no)
				(sheetname "")
			)
			(fill
				(thermal_gap 0.5)
				(thermal_bridge_width 0.5)
				(island_removal_mode 0)
			)
			(polygon
				(pts
					(arc
						(start 377.949714 -262.899906)
						(mid 369.94973 -270.89989)
						(end 377.949714 -278.899874)
					)
					(arc
						(start 377.949714 -275.64969)
						(mid 373.199914 -270.89989)
						(end 377.949714 -266.15009)
					)
				)
			)
		)
		(zone
			(layer "F.Cu")
			(hatch none 0.5)
			(connect_pads
				(clearance 0)
			)
			(min_thickness 0.25)
			(keepout
				(tracks not_allowed)
				(vias allowed)
				(pads allowed)
				(copperpour not_allowed)
				(footprints allowed)
			)
			(placement
				(enabled no)
				(sheetname "")
			)
			(fill
				(thermal_gap 0.5)
				(thermal_bridge_width 0.5)
				(island_removal_mode 0)
			)
			(polygon
				(pts
					(arc
						(start 377.949714 -262.899906)
						(mid 385.949698 -270.89989)
						(end 377.949714 -278.899874)
					)
					(arc
						(start 377.949714 -275.64969)
						(mid 382.699514 -270.89989)
						(end 377.949714 -266.15009)
					)
				)
			)
		)
		(zone
			(layers "F.Cu" "B.Cu" "In1.Cu" "In2.Cu" "In3.Cu" "In4.Cu" "In5.Cu" "In6.Cu"
				"In7.Cu" "In8.Cu" "In9.Cu" "In10.Cu" "In11.Cu" "In12.Cu" "In13.Cu" "In14.Cu"
				"In15.Cu" "In16.Cu"
			)
			(hatch none 0.5)
			(connect_pads
				(clearance 0)
			)
			(min_thickness 0.25)
			(keepout
				(tracks not_allowed)
				(vias allowed)
				(pads allowed)
				(copperpour not_allowed)
				(footprints allowed)
			)
			(placement
				(enabled no)
				(sheetname "")
			)
			(fill
				(thermal_gap 0.5)
				(thermal_bridge_width 0.5)
				(island_removal_mode 0)
			)
			(polygon
				(pts
					(arc
						(start 380.715774 -270.89989)
						(mid 375.183654 -270.89989)
						(end 380.715774 -270.89989)
					)
				)
			)
		)
		(zone
			(layer "B.Cu")
			(hatch none 0.5)
			(connect_pads
				(clearance 0)
			)
			(min_thickness 0.25)
			(keepout
				(tracks not_allowed)
				(vias allowed)
				(pads allowed)
				(copperpour not_allowed)
				(footprints allowed)
			)
			(placement
				(enabled no)
				(sheetname "")
			)
			(fill
				(thermal_gap 0.5)
				(thermal_bridge_width 0.5)
				(island_removal_mode 0)
			)
			(polygon
				(pts
					(arc
						(start 377.949714 -265.89609)
						(mid 372.945914 -270.89989)
						(end 377.949714 -275.90369)
					)
					(arc
						(start 377.949714 -275.42109)
						(mid 373.428514 -270.89989)
						(end 377.949714 -266.37869)
					)
				)
			)
		)
		(zone
			(layer "B.Cu")
			(hatch none 0.5)
			(connect_pads
				(clearance 0)
			)
			(min_thickness 0.25)
			(keepout
				(tracks not_allowed)
				(vias allowed)
				(pads allowed)
				(copperpour not_allowed)
				(footprints allowed)
			)
			(placement
				(enabled no)
				(sheetname "")
			)
			(fill
				(thermal_gap 0.5)
				(thermal_bridge_width 0.5)
				(island_removal_mode 0)
			)
			(polygon
				(pts
					(arc
						(start 377.949714 -265.89609)
						(mid 382.953514 -270.89989)
						(end 377.949714 -275.90369)
					)
					(arc
						(start 377.949714 -275.42109)
						(mid 382.470914 -270.89989)
						(end 377.949714 -266.37869)
					)
				)
			)
		)
	)
	(footprint ""
		(layer "F.Cu")
		(at 203.106782 -294.77335 90)
		(property "Reference" "U426"
			(at -1.0922 -2.174748 90)
			(unlocked yes)
			(layer "F.SilkS")
			(effects
				(font
					(size 0.7874 0.5842)
					(thickness 0.1524)
				)
				(justify left)
			)
		)
		(property "Value" ""
			(at 0 0 90)
			(layer "F.Fab")
			(effects
				(font
					(size 1.27 1.27)
				)
			)
		)
		(duplicate_pad_numbers_are_jumpers no)
		(fp_line
			(start 1.0414 -1.575054)
			(end 1.0414 1.575054)
			(stroke
				(width 0.1524)
				(type default)
			)
			(layer "F.SilkS")
		)
		(fp_line
			(start 0.254 -1.575054)
			(end 1.0414 -1.575054)
			(stroke
				(width 0.1524)
				(type default)
			)
			(layer "F.SilkS")
		)
		(fp_line
			(start 0.2286 -1.575054)
			(end 0 -1.272032)
			(stroke
				(width 0.1524)
				(type default)
			)
			(layer "F.SilkS")
		)
		(fp_line
			(start -1.0414 -1.575054)
			(end -0.254 -1.575054)
			(stroke
				(width 0.1524)
				(type default)
			)
			(layer "F.SilkS")
		)
		(fp_line
			(start 0 -1.272032)
			(end -0.254 -1.575054)
			(stroke
				(width 0.1524)
				(type default)
			)
			(layer "F.SilkS")
		)
		(fp_line
			(start 1.0414 1.575054)
			(end -1.0414 1.575054)
			(stroke
				(width 0.1524)
				(type default)
			)
			(layer "F.SilkS")
		)
		(fp_line
			(start -1.0414 1.575054)
			(end -1.0414 -1.575054)
			(stroke
				(width 0.1524)
				(type default)
			)
			(layer "F.SilkS")
		)
		(fp_poly
			(pts
				(xy -2.710688 -0.975106) (xy -3.726688 -1.483106) (xy -3.726688 -0.467106)
			)
			(stroke
				(width 0)
				(type default)
			)
			(fill yes)
			(layer "F.SilkS")
		)
		(fp_line
			(start 1.4478 -1.5748)
			(end 1.4478 -1.2192)
			(stroke
				(width 0.1)
				(type default)
			)
			(layer "F.Fab")
		)
		(fp_line
			(start -1.4478 -1.5748)
			(end 1.4478 -1.5748)
			(stroke
				(width 0.1)
				(type default)
			)
			(layer "F.Fab")
		)
		(fp_line
			(start 2.5654 -1.2192)
			(end 2.5654 1.2192)
			(stroke
				(width 0.1)
				(type default)
			)
			(layer "F.Fab")
		)
		(fp_line
			(start 1.4478 -1.2192)
			(end 2.5654 -1.2192)
			(stroke
				(width 0.1)
				(type default)
			)
			(layer "F.Fab")
		)
		(fp_line
			(start -1.4478 -1.2192)
			(end -1.4478 -1.5748)
			(stroke
				(width 0.1)
				(type default)
			)
			(layer "F.Fab")
		)
		(fp_line
			(start -2.5654 -1.2192)
			(end -1.4478 -1.2192)
			(stroke
				(width 0.1)
				(type default)
			)
			(layer "F.Fab")
		)
		(fp_line
			(start 2.5654 1.2192)
			(end 1.4478 1.2192)
			(stroke
				(width 0.1)
				(type default)
			)
			(layer "F.Fab")
		)
		(fp_line
			(start 1.4478 1.2192)
			(end 1.4478 1.5748)
			(stroke
				(width 0.1)
				(type default)
			)
			(layer "F.Fab")
		)
		(fp_line
			(start -1.4478 1.2192)
			(end -2.5654 1.2192)
			(stroke
				(width 0.1)
				(type default)
			)
			(layer "F.Fab")
		)
		(fp_line
			(start -2.5654 1.2192)
			(end -2.5654 -1.2192)
			(stroke
				(width 0.1)
				(type default)
			)
			(layer "F.Fab")
		)
		(fp_line
			(start 1.4478 1.5748)
			(end -1.4478 1.5748)
			(stroke
				(width 0.1)
				(type default)
			)
			(layer "F.Fab")
		)
		(fp_line
			(start -1.4478 1.5748)
			(end -1.4478 1.2192)
			(stroke
				(width 0.1)
				(type default)
			)
			(layer "F.Fab")
		)
		(fp_poly
			(pts
				(xy -2.710688 -0.975106) (xy -3.726688 -1.483106) (xy -3.726688 -0.467106)
			)
			(stroke
				(width 0)
				(type default)
			)
			(fill yes)
			(layer "F.Fab")
		)
		(pad "1" smd rect
			(at -1.849882 -0.975106)
			(size 0.3556 1.3208)
			(layers "F.Cu" "F.Mask" "F.Paste")
			(net "RST_PEX1_PERST_R_N")
		)
		(pad "2" smd rect
			(at -1.849882 -0.32512)
			(size 0.3556 1.3208)
			(layers "F.Cu" "F.Mask" "F.Paste")
			(net "RST_PEX1_S0_PERST_N")
		)
		(pad "3" smd rect
			(at -1.849882 0.32512)
			(size 0.3556 1.3208)
			(layers "F.Cu" "F.Mask" "F.Paste")
			(net "RST_PEX1_PERST_R_N")
		)
		(pad "4" smd rect
			(at -1.849882 0.975106)
			(size 0.3556 1.3208)
			(layers "F.Cu" "F.Mask" "F.Paste")
			(net "GND")
		)
		(pad "5" smd rect
			(at 1.849882 0.975106)
			(size 0.3556 1.3208)
			(layers "F.Cu" "F.Mask" "F.Paste")
			(net "RST_PEX1_S1_PERST_N")
		)
		(pad "6" smd rect
			(at 1.849882 0.32512)
			(size 0.3556 1.3208)
			(layers "F.Cu" "F.Mask" "F.Paste")
			(net "RST_PEX1_PERST_R_N")
		)
		(pad "7" smd rect
			(at 1.849882 -0.32512)
			(size 0.3556 1.3208)
			(layers "F.Cu" "F.Mask" "F.Paste")
			(net "RST_PEX1_S3_PERST_N")
		)
		(pad "8" smd rect
			(at 1.849882 -0.975106)
			(size 0.3556 1.3208)
			(layers "F.Cu" "F.Mask" "F.Paste")
			(net "P1V8_PEX")
		)
	)
	(footprint ""
		(layer "F.Cu")
		(at 258.659376 -22.955504 90)
		(property "Reference" "R1699"
			(at 0 0 90)
			(layer "F.SilkS")
			(hide yes)
			(effects
				(font
					(size 1.27 1.27)
				)
			)
		)
		(property "Value" ""
			(at 0 0 90)
			(layer "F.Fab")
			(effects
				(font
					(size 1.27 1.27)
				)
			)
		)
		(duplicate_pad_numbers_are_jumpers no)
		(fp_line
			(start 0.7874 -0.4064)
			(end 0.7874 0.4064)
			(stroke
				(width 0.1524)
				(type default)
			)
			(layer "F.SilkS")
		)
		(fp_line
			(start -0.7874 -0.4064)
			(end 0.7874 -0.4064)
			(stroke
				(width 0.1524)
				(type default)
			)
			(layer "F.SilkS")
		)
		(fp_line
			(start 0.7874 0.4064)
			(end -0.7874 0.4064)
			(stroke
				(width 0.1524)
				(type default)
			)
			(layer "F.SilkS")
		)
		(fp_line
			(start -0.7874 0.4064)
			(end -0.7874 -0.4064)
			(stroke
				(width 0.1524)
				(type default)
			)
			(layer "F.SilkS")
		)
		(fp_line
			(start -0.12065 -0.305054)
			(end -0.12065 -0.2794)
			(stroke
				(width 0.1)
				(type default)
			)
			(layer "F.Fab")
		)
		(fp_line
			(start -0.67945 -0.305054)
			(end -0.12065 -0.305054)
			(stroke
				(width 0.1)
				(type default)
			)
			(layer "F.Fab")
		)
		(fp_line
			(start 0.67945 -0.3048)
			(end 0.67945 0.3048)
			(stroke
				(width 0.1)
				(type default)
			)
			(layer "F.Fab")
		)
		(fp_line
			(start 0.12065 -0.3048)
			(end 0.67945 -0.3048)
			(stroke
				(width 0.1)
				(type default)
			)
			(layer "F.Fab")
		)
		(fp_line
			(start 0.12065 -0.2794)
			(end 0.12065 -0.3048)
			(stroke
				(width 0.1)
				(type default)
			)
			(layer "F.Fab")
		)
		(fp_line
			(start -0.12065 -0.2794)
			(end 0.12065 -0.2794)
			(stroke
				(width 0.1)
				(type default)
			)
			(layer "F.Fab")
		)
		(fp_line
			(start 0.120396 0.2794)
			(end -0.12065 0.2794)
			(stroke
				(width 0.1)
				(type default)
			)
			(layer "F.Fab")
		)
		(fp_line
			(start -0.12065 0.2794)
			(end -0.12065 0.3048)
			(stroke
				(width 0.1)
				(type default)
			)
			(layer "F.Fab")
		)
		(fp_line
			(start 0.67945 0.3048)
			(end 0.120396 0.3048)
			(stroke
				(width 0.1)
				(type default)
			)
			(layer "F.Fab")
		)
		(fp_line
			(start 0.120396 0.3048)
			(end 0.120396 0.2794)
			(stroke
				(width 0.1)
				(type default)
			)
			(layer "F.Fab")
		)
		(fp_line
			(start -0.12065 0.3048)
			(end -0.67945 0.3048)
			(stroke
				(width 0.1)
				(type default)
			)
			(layer "F.Fab")
		)
		(fp_line
			(start -0.67945 0.3048)
			(end -0.67945 -0.305054)
			(stroke
				(width 0.1)
				(type default)
			)
			(layer "F.Fab")
		)
		(pad "1" smd circle
			(at -0.40005 0 90)
			(size 0 0)
			(layers "F.Cu" "F.Mask" "F.Paste")
			(net "SMB_BIC_I2C9_MUX1_SSD8_R_SCL")
		)
		(pad "2" smd circle
			(at 0.40005 0 90)
			(size 0 0)
			(layers "F.Cu" "F.Mask" "F.Paste")
			(net "SMB_ISO_SSD8_SCL")
		)
	)
	(footprint ""
		(layer "F.Cu")
		(at 431.95621 -61.487812 180)
		(property "Reference" "R6023"
			(at 0 0 180)
			(layer "F.SilkS")
			(hide yes)
			(effects
				(font
					(size 1.27 1.27)
				)
			)
		)
		(property "Value" ""
			(at 0 0 180)
			(layer "F.Fab")
			(effects
				(font
					(size 1.27 1.27)
				)
			)
		)
		(duplicate_pad_numbers_are_jumpers no)
		(fp_line
			(start 0.7874 0.4064)
			(end -0.7874 0.4064)
			(stroke
				(width 0.1524)
				(type default)
			)
			(layer "F.SilkS")
		)
		(fp_line
			(start 0.7874 -0.4064)
			(end 0.7874 0.4064)
			(stroke
				(width 0.1524)
				(type default)
			)
			(layer "F.SilkS")
		)
		(fp_line
			(start -0.7874 0.4064)
			(end -0.7874 -0.4064)
			(stroke
				(width 0.1524)
				(type default)
			)
			(layer "F.SilkS")
		)
		(fp_line
			(start -0.7874 -0.4064)
			(end 0.7874 -0.4064)
			(stroke
				(width 0.1524)
				(type default)
			)
			(layer "F.SilkS")
		)
		(fp_line
			(start 0.67945 0.3048)
			(end 0.120396 0.3048)
			(stroke
				(width 0.1)
				(type default)
			)
			(layer "F.Fab")
		)
		(fp_line
			(start 0.67945 -0.3048)
			(end 0.67945 0.3048)
			(stroke
				(width 0.1)
				(type default)
			)
			(layer "F.Fab")
		)
		(fp_line
			(start 0.12065 -0.2794)
			(end 0.12065 -0.3048)
			(stroke
				(width 0.1)
				(type default)
			)
			(layer "F.Fab")
		)
		(fp_line
			(start 0.12065 -0.3048)
			(end 0.67945 -0.3048)
			(stroke
				(width 0.1)
				(type default)
			)
			(layer "F.Fab")
		)
		(fp_line
			(start 0.120396 0.3048)
			(end 0.120396 0.2794)
			(stroke
				(width 0.1)
				(type default)
			)
			(layer "F.Fab")
		)
		(fp_line
			(start 0.120396 0.2794)
			(end -0.12065 0.2794)
			(stroke
				(width 0.1)
				(type default)
			)
			(layer "F.Fab")
		)
		(fp_line
			(start -0.12065 0.3048)
			(end -0.67945 0.3048)
			(stroke
				(width 0.1)
				(type default)
			)
			(layer "F.Fab")
		)
		(fp_line
			(start -0.12065 0.2794)
			(end -0.12065 0.3048)
			(stroke
				(width 0.1)
				(type default)
			)
			(layer "F.Fab")
		)
		(fp_line
			(start -0.12065 -0.2794)
			(end 0.12065 -0.2794)
			(stroke
				(width 0.1)
				(type default)
			)
			(layer "F.Fab")
		)
		(fp_line
			(start -0.12065 -0.305054)
			(end -0.12065 -0.2794)
			(stroke
				(width 0.1)
				(type default)
			)
			(layer "F.Fab")
		)
		(fp_line
			(start -0.67945 0.3048)
			(end -0.67945 -0.305054)
			(stroke
				(width 0.1)
				(type default)
			)
			(layer "F.Fab")
		)
		(fp_line
			(start -0.67945 -0.305054)
			(end -0.12065 -0.305054)
			(stroke
				(width 0.1)
				(type default)
			)
			(layer "F.Fab")
		)
		(pad "1" smd circle
			(at -0.40005 0 180)
			(size 0 0)
			(layers "F.Cu" "F.Mask" "F.Paste")
			(net "P3V3_AUX")
		)
		(pad "2" smd circle
			(at 0.40005 0 180)
			(size 0 0)
			(layers "F.Cu" "F.Mask" "F.Paste")
			(net "PWRGD_P12V_SSD15_D")
		)
	)
	(footprint ""
		(layer "F.Cu")
		(at 337.058 -245.237 -90)
		(property "Reference" "R1791"
			(at 0 0 270)
			(layer "F.SilkS")
			(hide yes)
			(effects
				(font
					(size 1.27 1.27)
				)
			)
		)
		(property "Value" ""
			(at 0 0 270)
			(layer "F.Fab")
			(effects
				(font
					(size 1.27 1.27)
				)
			)
		)
		(duplicate_pad_numbers_are_jumpers no)
		(fp_line
			(start -0.7874 0.4064)
			(end -0.7874 -0.4064)
			(stroke
				(width 0.1524)
				(type default)
			)
			(layer "F.SilkS")
		)
		(fp_line
			(start 0.7874 0.4064)
			(end -0.7874 0.4064)
			(stroke
				(width 0.1524)
				(type default)
			)
			(layer "F.SilkS")
		)
		(fp_line
			(start -0.7874 -0.4064)
			(end 0.7874 -0.4064)
			(stroke
				(width 0.1524)
				(type default)
			)
			(layer "F.SilkS")
		)
		(fp_line
			(start 0.7874 -0.4064)
			(end 0.7874 0.4064)
			(stroke
				(width 0.1524)
				(type default)
			)
			(layer "F.SilkS")
		)
		(fp_line
			(start -0.67945 0.3048)
			(end -0.67945 -0.305054)
			(stroke
				(width 0.1)
				(type default)
			)
			(layer "F.Fab")
		)
		(fp_line
			(start -0.12065 0.3048)
			(end -0.67945 0.3048)
			(stroke
				(width 0.1)
				(type default)
			)
			(layer "F.Fab")
		)
		(fp_line
			(start 0.120396 0.3048)
			(end 0.120396 0.2794)
			(stroke
				(width 0.1)
				(type default)
			)
			(layer "F.Fab")
		)
		(fp_line
			(start 0.67945 0.3048)
			(end 0.120396 0.3048)
			(stroke
				(width 0.1)
				(type default)
			)
			(layer "F.Fab")
		)
		(fp_line
			(start -0.12065 0.2794)
			(end -0.12065 0.3048)
			(stroke
				(width 0.1)
				(type default)
			)
			(layer "F.Fab")
		)
		(fp_line
			(start 0.120396 0.2794)
			(end -0.12065 0.2794)
			(stroke
				(width 0.1)
				(type default)
			)
			(layer "F.Fab")
		)
		(fp_line
			(start -0.12065 -0.2794)
			(end 0.12065 -0.2794)
			(stroke
				(width 0.1)
				(type default)
			)
			(layer "F.Fab")
		)
		(fp_line
			(start 0.12065 -0.2794)
			(end 0.12065 -0.3048)
			(stroke
				(width 0.1)
				(type default)
			)
			(layer "F.Fab")
		)
		(fp_line
			(start 0.12065 -0.3048)
			(end 0.67945 -0.3048)
			(stroke
				(width 0.1)
				(type default)
			)
			(layer "F.Fab")
		)
		(fp_line
			(start 0.67945 -0.3048)
			(end 0.67945 0.3048)
			(stroke
				(width 0.1)
				(type default)
			)
			(layer "F.Fab")
		)
		(fp_line
			(start -0.67945 -0.305054)
			(end -0.12065 -0.305054)
			(stroke
				(width 0.1)
				(type default)
			)
			(layer "F.Fab")
		)
		(fp_line
			(start -0.12065 -0.305054)
			(end -0.12065 -0.2794)
			(stroke
				(width 0.1)
				(type default)
			)
			(layer "F.Fab")
		)
		(pad "1" smd circle
			(at -0.40005 0 270)
			(size 0 0)
			(layers "F.Cu" "F.Mask" "F.Paste")
			(net "P3V3_AUX")
		)
		(pad "2" smd circle
			(at 0.40005 0 270)
			(size 0 0)
			(layers "F.Cu" "F.Mask" "F.Paste")
			(net "MB_SWB_PWR_EN")
		)
	)
	(footprint ""
		(layer "F.Cu")
		(at 150.311104 -61.386974)
		(property "Reference" "R4487"
			(at 0 0 0)
			(layer "F.SilkS")
			(hide yes)
			(effects
				(font
					(size 1.27 1.27)
				)
			)
		)
		(property "Value" ""
			(at 0 0 0)
			(layer "F.Fab")
			(effects
				(font
					(size 1.27 1.27)
				)
			)
		)
		(duplicate_pad_numbers_are_jumpers no)
		(fp_line
			(start -0.7874 -0.4064)
			(end 0.7874 -0.4064)
			(stroke
				(width 0.1524)
				(type default)
			)
			(layer "F.SilkS")
		)
		(fp_line
			(start -0.7874 0.4064)
			(end -0.7874 -0.4064)
			(stroke
				(width 0.1524)
				(type default)
			)
			(layer "F.SilkS")
		)
		(fp_line
			(start 0.7874 -0.4064)
			(end 0.7874 0.4064)
			(stroke
				(width 0.1524)
				(type default)
			)
			(layer "F.SilkS")
		)
		(fp_line
			(start 0.7874 0.4064)
			(end -0.7874 0.4064)
			(stroke
				(width 0.1524)
				(type default)
			)
			(layer "F.SilkS")
		)
		(fp_line
			(start -0.67945 -0.305054)
			(end -0.12065 -0.305054)
			(stroke
				(width 0.1)
				(type default)
			)
			(layer "F.Fab")
		)
		(fp_line
			(start -0.67945 0.3048)
			(end -0.67945 -0.305054)
			(stroke
				(width 0.1)
				(type default)
			)
			(layer "F.Fab")
		)
		(fp_line
			(start -0.12065 -0.305054)
			(end -0.12065 -0.2794)
			(stroke
				(width 0.1)
				(type default)
			)
			(layer "F.Fab")
		)
		(fp_line
			(start -0.12065 -0.2794)
			(end 0.12065 -0.2794)
			(stroke
				(width 0.1)
				(type default)
			)
			(layer "F.Fab")
		)
		(fp_line
			(start -0.12065 0.2794)
			(end -0.12065 0.3048)
			(stroke
				(width 0.1)
				(type default)
			)
			(layer "F.Fab")
		)
		(fp_line
			(start -0.12065 0.3048)
			(end -0.67945 0.3048)
			(stroke
				(width 0.1)
				(type default)
			)
			(layer "F.Fab")
		)
		(fp_line
			(start 0.120396 0.2794)
			(end -0.12065 0.2794)
			(stroke
				(width 0.1)
				(type default)
			)
			(layer "F.Fab")
		)
		(fp_line
			(start 0.120396 0.3048)
			(end 0.120396 0.2794)
			(stroke
				(width 0.1)
				(type default)
			)
			(layer "F.Fab")
		)
		(fp_line
			(start 0.12065 -0.3048)
			(end 0.67945 -0.3048)
			(stroke
				(width 0.1)
				(type default)
			)
			(layer "F.Fab")
		)
		(fp_line
			(start 0.12065 -0.2794)
			(end 0.12065 -0.3048)
			(stroke
				(width 0.1)
				(type default)
			)
			(layer "F.Fab")
		)
		(fp_line
			(start 0.67945 -0.3048)
			(end 0.67945 0.3048)
			(stroke
				(width 0.1)
				(type default)
			)
			(layer "F.Fab")
		)
		(fp_line
			(start 0.67945 0.3048)
			(end 0.120396 0.3048)
			(stroke
				(width 0.1)
				(type default)
			)
			(layer "F.Fab")
		)
		(pad "1" smd circle
			(at -0.40005 0)
			(size 0 0)
			(layers "F.Cu" "F.Mask" "F.Paste")
			(net "PWRGD_P3V3_SSD5")
		)
		(pad "2" smd circle
			(at 0.40005 0)
			(size 0 0)
			(layers "F.Cu" "F.Mask" "F.Paste")
			(net "PWRGD_P3V3_SSD5_R")
		)
	)
	(footprint ""
		(layer "F.Cu")
		(at 4.244086 -43.637708 -90)
		(property "Reference" "R5866"
			(at 0 0 270)
			(layer "F.SilkS")
			(hide yes)
			(effects
				(font
					(size 1.27 1.27)
				)
			)
		)
		(property "Value" ""
			(at 0 0 270)
			(layer "F.Fab")
			(effects
				(font
					(size 1.27 1.27)
				)
			)
		)
		(duplicate_pad_numbers_are_jumpers no)
		(fp_line
			(start -0.7874 0.4064)
			(end -0.7874 -0.4064)
			(stroke
				(width 0.1524)
				(type default)
			)
			(layer "F.SilkS")
		)
		(fp_line
			(start 0.7874 0.4064)
			(end -0.7874 0.4064)
			(stroke
				(width 0.1524)
				(type default)
			)
			(layer "F.SilkS")
		)
		(fp_line
			(start -0.7874 -0.4064)
			(end 0.7874 -0.4064)
			(stroke
				(width 0.1524)
				(type default)
			)
			(layer "F.SilkS")
		)
		(fp_line
			(start 0.7874 -0.4064)
			(end 0.7874 0.4064)
			(stroke
				(width 0.1524)
				(type default)
			)
			(layer "F.SilkS")
		)
		(fp_line
			(start -0.67945 0.3048)
			(end -0.67945 -0.305054)
			(stroke
				(width 0.1)
				(type default)
			)
			(layer "F.Fab")
		)
		(fp_line
			(start -0.12065 0.3048)
			(end -0.67945 0.3048)
			(stroke
				(width 0.1)
				(type default)
			)
			(layer "F.Fab")
		)
		(fp_line
			(start 0.120396 0.3048)
			(end 0.120396 0.2794)
			(stroke
				(width 0.1)
				(type default)
			)
			(layer "F.Fab")
		)
		(fp_line
			(start 0.67945 0.3048)
			(end 0.120396 0.3048)
			(stroke
				(width 0.1)
				(type default)
			)
			(layer "F.Fab")
		)
		(fp_line
			(start -0.12065 0.2794)
			(end -0.12065 0.3048)
			(stroke
				(width 0.1)
				(type default)
			)
			(layer "F.Fab")
		)
		(fp_line
			(start 0.120396 0.2794)
			(end -0.12065 0.2794)
			(stroke
				(width 0.1)
				(type default)
			)
			(layer "F.Fab")
		)
		(fp_line
			(start -0.12065 -0.2794)
			(end 0.12065 -0.2794)
			(stroke
				(width 0.1)
				(type default)
			)
			(layer "F.Fab")
		)
		(fp_line
			(start 0.12065 -0.2794)
			(end 0.12065 -0.3048)
			(stroke
				(width 0.1)
				(type default)
			)
			(layer "F.Fab")
		)
		(fp_line
			(start 0.12065 -0.3048)
			(end 0.67945 -0.3048)
			(stroke
				(width 0.1)
				(type default)
			)
			(layer "F.Fab")
		)
		(fp_line
			(start 0.67945 -0.3048)
			(end 0.67945 0.3048)
			(stroke
				(width 0.1)
				(type default)
			)
			(layer "F.Fab")
		)
		(fp_line
			(start -0.67945 -0.305054)
			(end -0.12065 -0.305054)
			(stroke
				(width 0.1)
				(type default)
			)
			(layer "F.Fab")
		)
		(fp_line
			(start -0.12065 -0.305054)
			(end -0.12065 -0.2794)
			(stroke
				(width 0.1)
				(type default)
			)
			(layer "F.Fab")
		)
		(pad "1" smd circle
			(at -0.40005 0 270)
			(size 0 0)
			(layers "F.Cu" "F.Mask" "F.Paste")
			(net "SSD0_AUX_P3V3_EN_R")
		)
		(pad "2" smd circle
			(at 0.40005 0 270)
			(size 0 0)
			(layers "F.Cu" "F.Mask" "F.Paste")
			(net "P3V3_SSD0_CO_EN")
		)
	)
	(footprint ""
		(layer "F.Cu")
		(at 101.89591 -113.547398 90)
		(property "Reference" "PR6863"
			(at 0 0 90)
			(layer "F.SilkS")
			(hide yes)
			(effects
				(font
					(size 1.27 1.27)
				)
			)
		)
		(property "Value" ""
			(at 0 0 90)
			(layer "F.Fab")
			(effects
				(font
					(size 1.27 1.27)
				)
			)
		)
		(duplicate_pad_numbers_are_jumpers no)
		(fp_line
			(start 0.7874 -0.4064)
			(end 0.7874 0.4064)
			(stroke
				(width 0.1524)
				(type default)
			)
			(layer "F.SilkS")
		)
		(fp_line
			(start -0.7874 -0.4064)
			(end 0.7874 -0.4064)
			(stroke
				(width 0.1524)
				(type default)
			)
			(layer "F.SilkS")
		)
		(fp_line
			(start 0.7874 0.4064)
			(end -0.7874 0.4064)
			(stroke
				(width 0.1524)
				(type default)
			)
			(layer "F.SilkS")
		)
		(fp_line
			(start -0.7874 0.4064)
			(end -0.7874 -0.4064)
			(stroke
				(width 0.1524)
				(type default)
			)
			(layer "F.SilkS")
		)
		(fp_line
			(start -0.12065 -0.305054)
			(end -0.12065 -0.2794)
			(stroke
				(width 0.1)
				(type default)
			)
			(layer "F.Fab")
		)
		(fp_line
			(start -0.67945 -0.305054)
			(end -0.12065 -0.305054)
			(stroke
				(width 0.1)
				(type default)
			)
			(layer "F.Fab")
		)
		(fp_line
			(start 0.67945 -0.3048)
			(end 0.67945 0.3048)
			(stroke
				(width 0.1)
				(type default)
			)
			(layer "F.Fab")
		)
		(fp_line
			(start 0.12065 -0.3048)
			(end 0.67945 -0.3048)
			(stroke
				(width 0.1)
				(type default)
			)
			(layer "F.Fab")
		)
		(fp_line
			(start 0.12065 -0.2794)
			(end 0.12065 -0.3048)
			(stroke
				(width 0.1)
				(type default)
			)
			(layer "F.Fab")
		)
		(fp_line
			(start -0.12065 -0.2794)
			(end 0.12065 -0.2794)
			(stroke
				(width 0.1)
				(type default)
			)
			(layer "F.Fab")
		)
		(fp_line
			(start 0.120396 0.2794)
			(end -0.12065 0.2794)
			(stroke
				(width 0.1)
				(type default)
			)
			(layer "F.Fab")
		)
		(fp_line
			(start -0.12065 0.2794)
			(end -0.12065 0.3048)
			(stroke
				(width 0.1)
				(type default)
			)
			(layer "F.Fab")
		)
		(fp_line
			(start 0.67945 0.3048)
			(end 0.120396 0.3048)
			(stroke
				(width 0.1)
				(type default)
			)
			(layer "F.Fab")
		)
		(fp_line
			(start 0.120396 0.3048)
			(end 0.120396 0.2794)
			(stroke
				(width 0.1)
				(type default)
			)
			(layer "F.Fab")
		)
		(fp_line
			(start -0.12065 0.3048)
			(end -0.67945 0.3048)
			(stroke
				(width 0.1)
				(type default)
			)
			(layer "F.Fab")
		)
		(fp_line
			(start -0.67945 0.3048)
			(end -0.67945 -0.305054)
			(stroke
				(width 0.1)
				(type default)
			)
			(layer "F.Fab")
		)
		(pad "1" smd circle
			(at -0.40005 0 90)
			(size 0 0)
			(layers "F.Cu" "F.Mask" "F.Paste")
			(net "P12V_NIC1_R")
		)
		(pad "2" smd circle
			(at 0.40005 0 90)
			(size 0 0)
			(layers "F.Cu" "F.Mask" "F.Paste")
			(net "P12V_NIC1_CO_AVIN_PD")
		)
	)
	(footprint ""
		(layer "F.Cu")
		(at 384.54584 -261.663434)
		(property "Reference" "C3561"
			(at 0 0 0)
			(layer "F.SilkS")
			(hide yes)
			(effects
				(font
					(size 1.27 1.27)
				)
			)
		)
		(property "Value" ""
			(at 0 0 0)
			(layer "F.Fab")
			(effects
				(font
					(size 1.27 1.27)
				)
			)
		)
		(duplicate_pad_numbers_are_jumpers no)
		(fp_line
			(start -1.2954 -0.5842)
			(end 1.2954 -0.5842)
			(stroke
				(width 0.1524)
				(type default)
			)
			(layer "F.SilkS")
		)
		(fp_line
			(start -1.2954 0.5842)
			(end -1.2954 -0.5842)
			(stroke
				(width 0.1524)
				(type default)
			)
			(layer "F.SilkS")
		)
		(fp_line
			(start 1.2954 -0.5842)
			(end 1.2954 0.5842)
			(stroke
				(width 0.1524)
				(type default)
			)
			(layer "F.SilkS")
		)
		(fp_line
			(start 1.2954 0.5842)
			(end -1.2954 0.5842)
			(stroke
				(width 0.1524)
				(type default)
			)
			(layer "F.SilkS")
		)
		(fp_line
			(start -1.1938 -0.4064)
			(end -0.8636 -0.4064)
			(stroke
				(width 0.1)
				(type default)
			)
			(layer "F.Fab")
		)
		(fp_line
			(start -1.1938 0.4064)
			(end -1.1938 -0.4064)
			(stroke
				(width 0.1)
				(type default)
			)
			(layer "F.Fab")
		)
		(fp_line
			(start -0.8636 -0.4572)
			(end 0.8636 -0.4572)
			(stroke
				(width 0.1)
				(type default)
			)
			(layer "F.Fab")
		)
		(fp_line
			(start -0.8636 -0.4064)
			(end -0.8636 -0.4572)
			(stroke
				(width 0.1)
				(type default)
			)
			(layer "F.Fab")
		)
		(fp_line
			(start -0.8636 0.4064)
			(end -1.1938 0.4064)
			(stroke
				(width 0.1)
				(type default)
			)
			(layer "F.Fab")
		)
		(fp_line
			(start -0.8636 0.4572)
			(end -0.8636 0.4064)
			(stroke
				(width 0.1)
				(type default)
			)
			(layer "F.Fab")
		)
		(fp_line
			(start 0.8636 -0.4572)
			(end 0.8636 -0.4064)
			(stroke
				(width 0.1)
				(type default)
			)
			(layer "F.Fab")
		)
		(fp_line
			(start 0.8636 -0.4064)
			(end 1.1938 -0.4064)
			(stroke
				(width 0.1)
				(type default)
			)
			(layer "F.Fab")
		)
		(fp_line
			(start 0.8636 0.4064)
			(end 0.8636 0.4572)
			(stroke
				(width 0.1)
				(type default)
			)
			(layer "F.Fab")
		)
		(fp_line
			(start 0.8636 0.4572)
			(end -0.8636 0.4572)
			(stroke
				(width 0.1)
				(type default)
			)
			(layer "F.Fab")
		)
		(fp_line
			(start 1.1938 -0.4064)
			(end 1.1938 0.4064)
			(stroke
				(width 0.1)
				(type default)
			)
			(layer "F.Fab")
		)
		(fp_line
			(start 1.1938 0.4064)
			(end 0.8636 0.4064)
			(stroke
				(width 0.1)
				(type default)
			)
			(layer "F.Fab")
		)
		(pad "1" smd rect
			(at -0.7366 0 270)
			(size 0.7112 0.8128)
			(layers "F.Cu" "F.Mask" "F.Paste")
			(net "PCEPLL3_VDDA18_PEX3")
		)
		(pad "2" smd rect
			(at 0.7366 0 270)
			(size 0.7112 0.8128)
			(layers "F.Cu" "F.Mask" "F.Paste")
			(net "GND")
		)
	)
	(footprint ""
		(layer "F.Cu")
		(at 361.188 -186.182 180)
		(property "Reference" "R4646"
			(at 0 0 180)
			(layer "F.SilkS")
			(hide yes)
			(effects
				(font
					(size 1.27 1.27)
				)
			)
		)
		(property "Value" ""
			(at 0 0 180)
			(layer "F.Fab")
			(effects
				(font
					(size 1.27 1.27)
				)
			)
		)
		(duplicate_pad_numbers_are_jumpers no)
		(fp_line
			(start 0.7874 0.4064)
			(end -0.7874 0.4064)
			(stroke
				(width 0.1524)
				(type default)
			)
			(layer "F.SilkS")
		)
		(fp_line
			(start 0.7874 -0.4064)
			(end 0.7874 0.4064)
			(stroke
				(width 0.1524)
				(type default)
			)
			(layer "F.SilkS")
		)
		(fp_line
			(start -0.7874 0.4064)
			(end -0.7874 -0.4064)
			(stroke
				(width 0.1524)
				(type default)
			)
			(layer "F.SilkS")
		)
		(fp_line
			(start -0.7874 -0.4064)
			(end 0.7874 -0.4064)
			(stroke
				(width 0.1524)
				(type default)
			)
			(layer "F.SilkS")
		)
		(fp_line
			(start 0.67945 0.3048)
			(end 0.120396 0.3048)
			(stroke
				(width 0.1)
				(type default)
			)
			(layer "F.Fab")
		)
		(fp_line
			(start 0.67945 -0.3048)
			(end 0.67945 0.3048)
			(stroke
				(width 0.1)
				(type default)
			)
			(layer "F.Fab")
		)
		(fp_line
			(start 0.12065 -0.2794)
			(end 0.12065 -0.3048)
			(stroke
				(width 0.1)
				(type default)
			)
			(layer "F.Fab")
		)
		(fp_line
			(start 0.12065 -0.3048)
			(end 0.67945 -0.3048)
			(stroke
				(width 0.1)
				(type default)
			)
			(layer "F.Fab")
		)
		(fp_line
			(start 0.120396 0.3048)
			(end 0.120396 0.2794)
			(stroke
				(width 0.1)
				(type default)
			)
			(layer "F.Fab")
		)
		(fp_line
			(start 0.120396 0.2794)
			(end -0.12065 0.2794)
			(stroke
				(width 0.1)
				(type default)
			)
			(layer "F.Fab")
		)
		(fp_line
			(start -0.12065 0.3048)
			(end -0.67945 0.3048)
			(stroke
				(width 0.1)
				(type default)
			)
			(layer "F.Fab")
		)
		(fp_line
			(start -0.12065 0.2794)
			(end -0.12065 0.3048)
			(stroke
				(width 0.1)
				(type default)
			)
			(layer "F.Fab")
		)
		(fp_line
			(start -0.12065 -0.2794)
			(end 0.12065 -0.2794)
			(stroke
				(width 0.1)
				(type default)
			)
			(layer "F.Fab")
		)
		(fp_line
			(start -0.12065 -0.305054)
			(end -0.12065 -0.2794)
			(stroke
				(width 0.1)
				(type default)
			)
			(layer "F.Fab")
		)
		(fp_line
			(start -0.67945 0.3048)
			(end -0.67945 -0.305054)
			(stroke
				(width 0.1)
				(type default)
			)
			(layer "F.Fab")
		)
		(fp_line
			(start -0.67945 -0.305054)
			(end -0.12065 -0.305054)
			(stroke
				(width 0.1)
				(type default)
			)
			(layer "F.Fab")
		)
		(pad "1" smd circle
			(at -0.40005 0 180)
			(size 0 0)
			(layers "F.Cu" "F.Mask" "F.Paste")
			(net "PRSNT_SSD3_FPGA_PCA9555_N")
		)
		(pad "2" smd circle
			(at 0.40005 0 180)
			(size 0 0)
			(layers "F.Cu" "F.Mask" "F.Paste")
			(net "PRSNT_SSD3_FPGA_R_N")
		)
	)
	(footprint ""
		(layer "F.Cu")
		(at 140.582142 -38.041072 180)
		(property "Reference" "R6061"
			(at 0 0 180)
			(layer "F.SilkS")
			(hide yes)
			(effects
				(font
					(size 1.27 1.27)
				)
			)
		)
		(property "Value" ""
			(at 0 0 180)
			(layer "F.Fab")
			(effects
				(font
					(size 1.27 1.27)
				)
			)
		)
		(duplicate_pad_numbers_are_jumpers no)
		(fp_line
			(start 0.7874 0.4064)
			(end -0.7874 0.4064)
			(stroke
				(width 0.1524)
				(type default)
			)
			(layer "F.SilkS")
		)
		(fp_line
			(start 0.7874 -0.4064)
			(end 0.7874 0.4064)
			(stroke
				(width 0.1524)
				(type default)
			)
			(layer "F.SilkS")
		)
		(fp_line
			(start -0.7874 0.4064)
			(end -0.7874 -0.4064)
			(stroke
				(width 0.1524)
				(type default)
			)
			(layer "F.SilkS")
		)
		(fp_line
			(start -0.7874 -0.4064)
			(end 0.7874 -0.4064)
			(stroke
				(width 0.1524)
				(type default)
			)
			(layer "F.SilkS")
		)
		(fp_line
			(start 0.67945 0.3048)
			(end 0.120396 0.3048)
			(stroke
				(width 0.1)
				(type default)
			)
			(layer "F.Fab")
		)
		(fp_line
			(start 0.67945 -0.3048)
			(end 0.67945 0.3048)
			(stroke
				(width 0.1)
				(type default)
			)
			(layer "F.Fab")
		)
		(fp_line
			(start 0.12065 -0.2794)
			(end 0.12065 -0.3048)
			(stroke
				(width 0.1)
				(type default)
			)
			(layer "F.Fab")
		)
		(fp_line
			(start 0.12065 -0.3048)
			(end 0.67945 -0.3048)
			(stroke
				(width 0.1)
				(type default)
			)
			(layer "F.Fab")
		)
		(fp_line
			(start 0.120396 0.3048)
			(end 0.120396 0.2794)
			(stroke
				(width 0.1)
				(type default)
			)
			(layer "F.Fab")
		)
		(fp_line
			(start 0.120396 0.2794)
			(end -0.12065 0.2794)
			(stroke
				(width 0.1)
				(type default)
			)
			(layer "F.Fab")
		)
		(fp_line
			(start -0.12065 0.3048)
			(end -0.67945 0.3048)
			(stroke
				(width 0.1)
				(type default)
			)
			(layer "F.Fab")
		)
		(fp_line
			(start -0.12065 0.2794)
			(end -0.12065 0.3048)
			(stroke
				(width 0.1)
				(type default)
			)
			(layer "F.Fab")
		)
		(fp_line
			(start -0.12065 -0.2794)
			(end 0.12065 -0.2794)
			(stroke
				(width 0.1)
				(type default)
			)
			(layer "F.Fab")
		)
		(fp_line
			(start -0.12065 -0.305054)
			(end -0.12065 -0.2794)
			(stroke
				(width 0.1)
				(type default)
			)
			(layer "F.Fab")
		)
		(fp_line
			(start -0.67945 0.3048)
			(end -0.67945 -0.305054)
			(stroke
				(width 0.1)
				(type default)
			)
			(layer "F.Fab")
		)
		(fp_line
			(start -0.67945 -0.305054)
			(end -0.12065 -0.305054)
			(stroke
				(width 0.1)
				(type default)
			)
			(layer "F.Fab")
		)
		(pad "1" smd circle
			(at -0.40005 0 180)
			(size 0 0)
			(layers "F.Cu" "F.Mask" "F.Paste")
			(net "P5V_AUX")
		)
		(pad "2" smd circle
			(at 0.40005 0 180)
			(size 0 0)
			(layers "F.Cu" "F.Mask" "F.Paste")
			(net "P3V3_SSD5_PG_G2")
		)
	)
	(footprint ""
		(layer "F.Cu")
		(at 149.414992 -20.724876)
		(property "Reference" "H110"
			(at 1.500886 -2.63398 0)
			(unlocked yes)
			(layer "B.SilkS")
			(effects
				(font
					(size 0.7874 0.5842)
					(thickness 0.1524)
				)
				(justify left mirror)
			)
		)
		(property "Value" ""
			(at 0 0 0)
			(layer "F.Fab")
			(effects
				(font
					(size 1.27 1.27)
				)
			)
		)
		(duplicate_pad_numbers_are_jumpers no)
		(pad "1" thru_hole rect
			(at 0 0)
			(size 4.2164 5.0038)
			(drill 2.0066
				(offset 0.099822 0)
			)
			(layers "*.Cu" "*.Mask")
			(remove_unused_layers no)
			(net "Net_8553")
			(clearance -0.8509)
			(padstack
				(mode front_inner_back)
				(layer "Inner"
					(shape circle)
					(size 4.0132 4.0132)
					(clearance -0.7493)
				)
				(layer "B.Cu"
					(shape circle)
					(size 4.0132 4.0132)
					(clearance -0.7493)
				)
			)
		)
	)
	(footprint ""
		(layer "F.Cu")
		(at 495.57813 -547.603172 180)
		(property "Reference" "J38_OTH"
			(at -3.2385 -1.402334 0)
			(unlocked yes)
			(layer "B.SilkS")
			(effects
				(font
					(size 0.7874 0.5842)
					(thickness 0.1524)
				)
				(justify mirror)
			)
		)
		(property "Value" ""
			(at 0 0 180)
			(layer "F.Fab")
			(effects
				(font
					(size 1.27 1.27)
				)
			)
		)
		(duplicate_pad_numbers_are_jumpers no)
		(pad "1" thru_hole circle
			(at 0 0 180)
			(size 0.4572 0.4572)
			(drill 0.2032)
			(layers "*.Cu" "*.Mask")
			(remove_unused_layers no)
			(net "Net_9098")
			(clearance 0.127)
			(thermal_gap 0.127)
			(padstack
				(mode front_inner_back)
				(layer "Inner"
					(shape circle)
					(size 0.4572 0.4572)
					(clearance 0.127)
				)
				(layer "B.Cu"
					(shape circle)
					(size 0.508 0.508)
					(clearance 0.1016)
				)
			)
		)
	)
	(footprint ""
		(layer "F.Cu")
		(at 185.89244 -31.825184 180)
		(property "Reference" "C295"
			(at 0 0 180)
			(layer "F.SilkS")
			(hide yes)
			(effects
				(font
					(size 1.27 1.27)
				)
			)
		)
		(property "Value" ""
			(at 0 0 180)
			(layer "F.Fab")
			(effects
				(font
					(size 1.27 1.27)
				)
			)
		)
		(duplicate_pad_numbers_are_jumpers no)
		(fp_line
			(start 0.299974 0.150114)
			(end -0.299974 0.150114)
			(stroke
				(width 0.1)
				(type default)
			)
			(layer "F.Fab")
		)
		(fp_line
			(start 0.299974 -0.150114)
			(end 0.299974 0.150114)
			(stroke
				(width 0.1)
				(type default)
			)
			(layer "F.Fab")
		)
		(fp_line
			(start -0.299974 0.150114)
			(end -0.299974 -0.150114)
			(stroke
				(width 0.1)
				(type default)
			)
			(layer "F.Fab")
		)
		(fp_line
			(start -0.299974 -0.150114)
			(end 0.299974 -0.150114)
			(stroke
				(width 0.1)
				(type default)
			)
			(layer "F.Fab")
		)
		(pad "1" smd rect
			(at -0.2667 0 180)
			(size 0.3048 0.381)
			(layers "F.Cu" "F.Mask" "F.Paste")
			(net "P5E_PEX1_STN2_TX_DN<38>")
		)
		(pad "2" smd rect
			(at 0.2667 0 180)
			(size 0.3048 0.381)
			(layers "F.Cu" "F.Mask" "F.Paste")
			(net "P5E_PEX1_STN2_TX_C_DN<38>")
		)
	)
	(footprint ""
		(layer "F.Cu")
		(at 133.722872 -22.867366 90)
		(property "Reference" "C3904"
			(at 0 0 90)
			(layer "F.SilkS")
			(hide yes)
			(effects
				(font
					(size 1.27 1.27)
				)
			)
		)
		(property "Value" ""
			(at 0 0 90)
			(layer "F.Fab")
			(effects
				(font
					(size 1.27 1.27)
				)
			)
		)
		(duplicate_pad_numbers_are_jumpers no)
		(fp_line
			(start 0.7874 -0.4064)
			(end 0.7874 0.4064)
			(stroke
				(width 0.1524)
				(type default)
			)
			(layer "F.SilkS")
		)
		(fp_line
			(start -0.7874 -0.4064)
			(end 0.7874 -0.4064)
			(stroke
				(width 0.1524)
				(type default)
			)
			(layer "F.SilkS")
		)
		(fp_line
			(start 0.7874 0.4064)
			(end -0.7874 0.4064)
			(stroke
				(width 0.1524)
				(type default)
			)
			(layer "F.SilkS")
		)
		(fp_line
			(start -0.7874 0.4064)
			(end -0.7874 -0.4064)
			(stroke
				(width 0.1524)
				(type default)
			)
			(layer "F.SilkS")
		)
		(fp_line
			(start -0.12065 -0.305054)
			(end -0.12065 -0.2794)
			(stroke
				(width 0.1)
				(type default)
			)
			(layer "F.Fab")
		)
		(fp_line
			(start -0.67945 -0.305054)
			(end -0.12065 -0.305054)
			(stroke
				(width 0.1)
				(type default)
			)
			(layer "F.Fab")
		)
		(fp_line
			(start 0.67945 -0.3048)
			(end 0.67945 0.3048)
			(stroke
				(width 0.1)
				(type default)
			)
			(layer "F.Fab")
		)
		(fp_line
			(start 0.12065 -0.3048)
			(end 0.67945 -0.3048)
			(stroke
				(width 0.1)
				(type default)
			)
			(layer "F.Fab")
		)
		(fp_line
			(start 0.12065 -0.2794)
			(end 0.12065 -0.3048)
			(stroke
				(width 0.1)
				(type default)
			)
			(layer "F.Fab")
		)
		(fp_line
			(start -0.12065 -0.2794)
			(end 0.12065 -0.2794)
			(stroke
				(width 0.1)
				(type default)
			)
			(layer "F.Fab")
		)
		(fp_line
			(start 0.120396 0.2794)
			(end -0.12065 0.2794)
			(stroke
				(width 0.1)
				(type default)
			)
			(layer "F.Fab")
		)
		(fp_line
			(start -0.12065 0.2794)
			(end -0.12065 0.3048)
			(stroke
				(width 0.1)
				(type default)
			)
			(layer "F.Fab")
		)
		(fp_line
			(start 0.67945 0.3048)
			(end 0.120396 0.3048)
			(stroke
				(width 0.1)
				(type default)
			)
			(layer "F.Fab")
		)
		(fp_line
			(start 0.120396 0.3048)
			(end 0.120396 0.2794)
			(stroke
				(width 0.1)
				(type default)
			)
			(layer "F.Fab")
		)
		(fp_line
			(start -0.12065 0.3048)
			(end -0.67945 0.3048)
			(stroke
				(width 0.1)
				(type default)
			)
			(layer "F.Fab")
		)
		(fp_line
			(start -0.67945 0.3048)
			(end -0.67945 -0.305054)
			(stroke
				(width 0.1)
				(type default)
			)
			(layer "F.Fab")
		)
		(pad "1" smd circle
			(at -0.40005 0 90)
			(size 0 0)
			(layers "F.Cu" "F.Mask" "F.Paste")
			(net "P12V_SSD4")
		)
		(pad "2" smd circle
			(at 0.40005 0 90)
			(size 0 0)
			(layers "F.Cu" "F.Mask" "F.Paste")
			(net "GND")
		)
	)
	(footprint ""
		(layer "F.Cu")
		(at 313.839606 -87.349076 -90)
		(property "Reference" "R300"
			(at 0 0 270)
			(layer "F.SilkS")
			(hide yes)
			(effects
				(font
					(size 1.27 1.27)
				)
			)
		)
		(property "Value" ""
			(at 0 0 270)
			(layer "F.Fab")
			(effects
				(font
					(size 1.27 1.27)
				)
			)
		)
		(duplicate_pad_numbers_are_jumpers no)
		(fp_line
			(start -0.7874 0.4064)
			(end -0.7874 -0.4064)
			(stroke
				(width 0.1524)
				(type default)
			)
			(layer "F.SilkS")
		)
		(fp_line
			(start 0.7874 0.4064)
			(end -0.7874 0.4064)
			(stroke
				(width 0.1524)
				(type default)
			)
			(layer "F.SilkS")
		)
		(fp_line
			(start -0.7874 -0.4064)
			(end 0.7874 -0.4064)
			(stroke
				(width 0.1524)
				(type default)
			)
			(layer "F.SilkS")
		)
		(fp_line
			(start 0.7874 -0.4064)
			(end 0.7874 0.4064)
			(stroke
				(width 0.1524)
				(type default)
			)
			(layer "F.SilkS")
		)
		(fp_line
			(start -0.67945 0.3048)
			(end -0.67945 -0.305054)
			(stroke
				(width 0.1)
				(type default)
			)
			(layer "F.Fab")
		)
		(fp_line
			(start -0.12065 0.3048)
			(end -0.67945 0.3048)
			(stroke
				(width 0.1)
				(type default)
			)
			(layer "F.Fab")
		)
		(fp_line
			(start 0.120396 0.3048)
			(end 0.120396 0.2794)
			(stroke
				(width 0.1)
				(type default)
			)
			(layer "F.Fab")
		)
		(fp_line
			(start 0.67945 0.3048)
			(end 0.120396 0.3048)
			(stroke
				(width 0.1)
				(type default)
			)
			(layer "F.Fab")
		)
		(fp_line
			(start -0.12065 0.2794)
			(end -0.12065 0.3048)
			(stroke
				(width 0.1)
				(type default)
			)
			(layer "F.Fab")
		)
		(fp_line
			(start 0.120396 0.2794)
			(end -0.12065 0.2794)
			(stroke
				(width 0.1)
				(type default)
			)
			(layer "F.Fab")
		)
		(fp_line
			(start -0.12065 -0.2794)
			(end 0.12065 -0.2794)
			(stroke
				(width 0.1)
				(type default)
			)
			(layer "F.Fab")
		)
		(fp_line
			(start 0.12065 -0.2794)
			(end 0.12065 -0.3048)
			(stroke
				(width 0.1)
				(type default)
			)
			(layer "F.Fab")
		)
		(fp_line
			(start 0.12065 -0.3048)
			(end 0.67945 -0.3048)
			(stroke
				(width 0.1)
				(type default)
			)
			(layer "F.Fab")
		)
		(fp_line
			(start 0.67945 -0.3048)
			(end 0.67945 0.3048)
			(stroke
				(width 0.1)
				(type default)
			)
			(layer "F.Fab")
		)
		(fp_line
			(start -0.67945 -0.305054)
			(end -0.12065 -0.305054)
			(stroke
				(width 0.1)
				(type default)
			)
			(layer "F.Fab")
		)
		(fp_line
			(start -0.12065 -0.305054)
			(end -0.12065 -0.2794)
			(stroke
				(width 0.1)
				(type default)
			)
			(layer "F.Fab")
		)
		(pad "1" smd circle
			(at -0.40005 0 270)
			(size 0 0)
			(layers "F.Cu" "F.Mask" "F.Paste")
			(net "RST_NIC5_PERST0_R_N")
		)
		(pad "2" smd circle
			(at 0.40005 0 270)
			(size 0 0)
			(layers "F.Cu" "F.Mask" "F.Paste")
			(net "RST_HP_NIC5_BUF_N")
		)
	)
	(footprint ""
		(layer "F.Cu")
		(at 263.207246 -260.639814 -90)
		(property "Reference" "C3366"
			(at 0 0 270)
			(layer "F.SilkS")
			(hide yes)
			(effects
				(font
					(size 1.27 1.27)
				)
			)
		)
		(property "Value" ""
			(at 0 0 270)
			(layer "F.Fab")
			(effects
				(font
					(size 1.27 1.27)
				)
			)
		)
		(duplicate_pad_numbers_are_jumpers no)
		(fp_line
			(start -0.299974 0.150114)
			(end -0.299974 -0.150114)
			(stroke
				(width 0.1)
				(type default)
			)
			(layer "F.Fab")
		)
		(fp_line
			(start 0.299974 0.150114)
			(end -0.299974 0.150114)
			(stroke
				(width 0.1)
				(type default)
			)
			(layer "F.Fab")
		)
		(fp_line
			(start -0.299974 -0.150114)
			(end 0.299974 -0.150114)
			(stroke
				(width 0.1)
				(type default)
			)
			(layer "F.Fab")
		)
		(fp_line
			(start 0.299974 -0.150114)
			(end 0.299974 0.150114)
			(stroke
				(width 0.1)
				(type default)
			)
			(layer "F.Fab")
		)
		(pad "1" smd rect
			(at -0.2667 0 270)
			(size 0.3048 0.381)
			(layers "F.Cu" "F.Mask" "F.Paste")
			(net "P1V8_PLL0_PEX2")
		)
		(pad "2" smd rect
			(at 0.2667 0 270)
			(size 0.3048 0.381)
			(layers "F.Cu" "F.Mask" "F.Paste")
			(net "GND")
		)
	)
	(footprint ""
		(layer "F.Cu")
		(at 3.247644 -21.317712 90)
		(property "Reference" "R5732"
			(at 0 0 90)
			(layer "F.SilkS")
			(hide yes)
			(effects
				(font
					(size 1.27 1.27)
				)
			)
		)
		(property "Value" ""
			(at 0 0 90)
			(layer "F.Fab")
			(effects
				(font
					(size 1.27 1.27)
				)
			)
		)
		(duplicate_pad_numbers_are_jumpers no)
		(fp_line
			(start 0.7874 -0.4064)
			(end 0.7874 0.4064)
			(stroke
				(width 0.1524)
				(type default)
			)
			(layer "F.SilkS")
		)
		(fp_line
			(start -0.7874 -0.4064)
			(end 0.7874 -0.4064)
			(stroke
				(width 0.1524)
				(type default)
			)
			(layer "F.SilkS")
		)
		(fp_line
			(start 0.7874 0.4064)
			(end -0.7874 0.4064)
			(stroke
				(width 0.1524)
				(type default)
			)
			(layer "F.SilkS")
		)
		(fp_line
			(start -0.7874 0.4064)
			(end -0.7874 -0.4064)
			(stroke
				(width 0.1524)
				(type default)
			)
			(layer "F.SilkS")
		)
		(fp_line
			(start -0.12065 -0.305054)
			(end -0.12065 -0.2794)
			(stroke
				(width 0.1)
				(type default)
			)
			(layer "F.Fab")
		)
		(fp_line
			(start -0.67945 -0.305054)
			(end -0.12065 -0.305054)
			(stroke
				(width 0.1)
				(type default)
			)
			(layer "F.Fab")
		)
		(fp_line
			(start 0.67945 -0.3048)
			(end 0.67945 0.3048)
			(stroke
				(width 0.1)
				(type default)
			)
			(layer "F.Fab")
		)
		(fp_line
			(start 0.12065 -0.3048)
			(end 0.67945 -0.3048)
			(stroke
				(width 0.1)
				(type default)
			)
			(layer "F.Fab")
		)
		(fp_line
			(start 0.12065 -0.2794)
			(end 0.12065 -0.3048)
			(stroke
				(width 0.1)
				(type default)
			)
			(layer "F.Fab")
		)
		(fp_line
			(start -0.12065 -0.2794)
			(end 0.12065 -0.2794)
			(stroke
				(width 0.1)
				(type default)
			)
			(layer "F.Fab")
		)
		(fp_line
			(start 0.120396 0.2794)
			(end -0.12065 0.2794)
			(stroke
				(width 0.1)
				(type default)
			)
			(layer "F.Fab")
		)
		(fp_line
			(start -0.12065 0.2794)
			(end -0.12065 0.3048)
			(stroke
				(width 0.1)
				(type default)
			)
			(layer "F.Fab")
		)
		(fp_line
			(start 0.67945 0.3048)
			(end 0.120396 0.3048)
			(stroke
				(width 0.1)
				(type default)
			)
			(layer "F.Fab")
		)
		(fp_line
			(start 0.120396 0.3048)
			(end 0.120396 0.2794)
			(stroke
				(width 0.1)
				(type default)
			)
			(layer "F.Fab")
		)
		(fp_line
			(start -0.12065 0.3048)
			(end -0.67945 0.3048)
			(stroke
				(width 0.1)
				(type default)
			)
			(layer "F.Fab")
		)
		(fp_line
			(start -0.67945 0.3048)
			(end -0.67945 -0.305054)
			(stroke
				(width 0.1)
				(type default)
			)
			(layer "F.Fab")
		)
		(pad "1" smd circle
			(at -0.40005 0 90)
			(size 0 0)
			(layers "F.Cu" "F.Mask" "F.Paste")
			(net "SSD0_LED_ISO_N")
		)
		(pad "2" smd circle
			(at 0.40005 0 90)
			(size 0 0)
			(layers "F.Cu" "F.Mask" "F.Paste")
			(net "SSD0_LED_ISO_R_N")
		)
	)
	(footprint ""
		(layer "F.Cu")
		(at 181.199028 -178.749198 -90)
		(property "Reference" "R6671"
			(at 0 0 270)
			(layer "F.SilkS")
			(hide yes)
			(effects
				(font
					(size 1.27 1.27)
				)
			)
		)
		(property "Value" ""
			(at 0 0 270)
			(layer "F.Fab")
			(effects
				(font
					(size 1.27 1.27)
				)
			)
		)
		(duplicate_pad_numbers_are_jumpers no)
		(fp_line
			(start -0.7874 0.4064)
			(end -0.7874 -0.4064)
			(stroke
				(width 0.1524)
				(type default)
			)
			(layer "F.SilkS")
		)
		(fp_line
			(start 0.7874 0.4064)
			(end -0.7874 0.4064)
			(stroke
				(width 0.1524)
				(type default)
			)
			(layer "F.SilkS")
		)
		(fp_line
			(start -0.7874 -0.4064)
			(end 0.7874 -0.4064)
			(stroke
				(width 0.1524)
				(type default)
			)
			(layer "F.SilkS")
		)
		(fp_line
			(start 0.7874 -0.4064)
			(end 0.7874 0.4064)
			(stroke
				(width 0.1524)
				(type default)
			)
			(layer "F.SilkS")
		)
		(fp_line
			(start -0.67945 0.3048)
			(end -0.67945 -0.305054)
			(stroke
				(width 0.1)
				(type default)
			)
			(layer "F.Fab")
		)
		(fp_line
			(start -0.12065 0.3048)
			(end -0.67945 0.3048)
			(stroke
				(width 0.1)
				(type default)
			)
			(layer "F.Fab")
		)
		(fp_line
			(start 0.120396 0.3048)
			(end 0.120396 0.2794)
			(stroke
				(width 0.1)
				(type default)
			)
			(layer "F.Fab")
		)
		(fp_line
			(start 0.67945 0.3048)
			(end 0.120396 0.3048)
			(stroke
				(width 0.1)
				(type default)
			)
			(layer "F.Fab")
		)
		(fp_line
			(start -0.12065 0.2794)
			(end -0.12065 0.3048)
			(stroke
				(width 0.1)
				(type default)
			)
			(layer "F.Fab")
		)
		(fp_line
			(start 0.120396 0.2794)
			(end -0.12065 0.2794)
			(stroke
				(width 0.1)
				(type default)
			)
			(layer "F.Fab")
		)
		(fp_line
			(start -0.12065 -0.2794)
			(end 0.12065 -0.2794)
			(stroke
				(width 0.1)
				(type default)
			)
			(layer "F.Fab")
		)
		(fp_line
			(start 0.12065 -0.2794)
			(end 0.12065 -0.3048)
			(stroke
				(width 0.1)
				(type default)
			)
			(layer "F.Fab")
		)
		(fp_line
			(start 0.12065 -0.3048)
			(end 0.67945 -0.3048)
			(stroke
				(width 0.1)
				(type default)
			)
			(layer "F.Fab")
		)
		(fp_line
			(start 0.67945 -0.3048)
			(end 0.67945 0.3048)
			(stroke
				(width 0.1)
				(type default)
			)
			(layer "F.Fab")
		)
		(fp_line
			(start -0.67945 -0.305054)
			(end -0.12065 -0.305054)
			(stroke
				(width 0.1)
				(type default)
			)
			(layer "F.Fab")
		)
		(fp_line
			(start -0.12065 -0.305054)
			(end -0.12065 -0.2794)
			(stroke
				(width 0.1)
				(type default)
			)
			(layer "F.Fab")
		)
		(pad "1" smd circle
			(at -0.40005 0 270)
			(size 0 0)
			(layers "F.Cu" "F.Mask" "F.Paste")
			(net "NIC2_CLK_EN_BUF_R_N")
		)
		(pad "2" smd circle
			(at 0.40005 0 270)
			(size 0 0)
			(layers "F.Cu" "F.Mask" "F.Paste")
			(net "P3V3")
		)
	)
	(footprint ""
		(layer "F.Cu")
		(at 53.840126 -32.848042 90)
		(property "Reference" "PC685"
			(at 0 0 90)
			(layer "F.SilkS")
			(hide yes)
			(effects
				(font
					(size 1.27 1.27)
				)
			)
		)
		(property "Value" ""
			(at 0 0 90)
			(layer "F.Fab")
			(effects
				(font
					(size 1.27 1.27)
				)
			)
		)
		(duplicate_pad_numbers_are_jumpers no)
		(fp_line
			(start 0.7874 -0.4064)
			(end 0.7874 0.4064)
			(stroke
				(width 0.1524)
				(type default)
			)
			(layer "F.SilkS")
		)
		(fp_line
			(start -0.7874 -0.4064)
			(end 0.7874 -0.4064)
			(stroke
				(width 0.1524)
				(type default)
			)
			(layer "F.SilkS")
		)
		(fp_line
			(start 0.7874 0.4064)
			(end -0.7874 0.4064)
			(stroke
				(width 0.1524)
				(type default)
			)
			(layer "F.SilkS")
		)
		(fp_line
			(start -0.7874 0.4064)
			(end -0.7874 -0.4064)
			(stroke
				(width 0.1524)
				(type default)
			)
			(layer "F.SilkS")
		)
		(fp_line
			(start -0.12065 -0.305054)
			(end -0.12065 -0.2794)
			(stroke
				(width 0.1)
				(type default)
			)
			(layer "F.Fab")
		)
		(fp_line
			(start -0.67945 -0.305054)
			(end -0.12065 -0.305054)
			(stroke
				(width 0.1)
				(type default)
			)
			(layer "F.Fab")
		)
		(fp_line
			(start 0.67945 -0.3048)
			(end 0.67945 0.3048)
			(stroke
				(width 0.1)
				(type default)
			)
			(layer "F.Fab")
		)
		(fp_line
			(start 0.12065 -0.3048)
			(end 0.67945 -0.3048)
			(stroke
				(width 0.1)
				(type default)
			)
			(layer "F.Fab")
		)
		(fp_line
			(start 0.12065 -0.2794)
			(end 0.12065 -0.3048)
			(stroke
				(width 0.1)
				(type default)
			)
			(layer "F.Fab")
		)
		(fp_line
			(start -0.12065 -0.2794)
			(end 0.12065 -0.2794)
			(stroke
				(width 0.1)
				(type default)
			)
			(layer "F.Fab")
		)
		(fp_line
			(start 0.120396 0.2794)
			(end -0.12065 0.2794)
			(stroke
				(width 0.1)
				(type default)
			)
			(layer "F.Fab")
		)
		(fp_line
			(start -0.12065 0.2794)
			(end -0.12065 0.3048)
			(stroke
				(width 0.1)
				(type default)
			)
			(layer "F.Fab")
		)
		(fp_line
			(start 0.67945 0.3048)
			(end 0.120396 0.3048)
			(stroke
				(width 0.1)
				(type default)
			)
			(layer "F.Fab")
		)
		(fp_line
			(start 0.120396 0.3048)
			(end 0.120396 0.2794)
			(stroke
				(width 0.1)
				(type default)
			)
			(layer "F.Fab")
		)
		(fp_line
			(start -0.12065 0.3048)
			(end -0.67945 0.3048)
			(stroke
				(width 0.1)
				(type default)
			)
			(layer "F.Fab")
		)
		(fp_line
			(start -0.67945 0.3048)
			(end -0.67945 -0.305054)
			(stroke
				(width 0.1)
				(type default)
			)
			(layer "F.Fab")
		)
		(pad "1" smd circle
			(at -0.40005 0 90)
			(size 0 0)
			(layers "F.Cu" "F.Mask" "F.Paste")
			(net "P3V3_SSD2_CO_DV_DT")
		)
		(pad "2" smd circle
			(at 0.40005 0 90)
			(size 0 0)
			(layers "F.Cu" "F.Mask" "F.Paste")
			(net "GND")
		)
	)
	(footprint ""
		(layer "F.Cu")
		(at 8.049768 -157.812994)
		(property "Reference" "R902"
			(at 0 0 0)
			(layer "F.SilkS")
			(hide yes)
			(effects
				(font
					(size 1.27 1.27)
				)
			)
		)
		(property "Value" ""
			(at 0 0 0)
			(layer "F.Fab")
			(effects
				(font
					(size 1.27 1.27)
				)
			)
		)
		(duplicate_pad_numbers_are_jumpers no)
		(fp_line
			(start -0.7874 -0.4064)
			(end 0.7874 -0.4064)
			(stroke
				(width 0.1524)
				(type default)
			)
			(layer "F.SilkS")
		)
		(fp_line
			(start -0.7874 0.4064)
			(end -0.7874 -0.4064)
			(stroke
				(width 0.1524)
				(type default)
			)
			(layer "F.SilkS")
		)
		(fp_line
			(start 0.7874 -0.4064)
			(end 0.7874 0.4064)
			(stroke
				(width 0.1524)
				(type default)
			)
			(layer "F.SilkS")
		)
		(fp_line
			(start 0.7874 0.4064)
			(end -0.7874 0.4064)
			(stroke
				(width 0.1524)
				(type default)
			)
			(layer "F.SilkS")
		)
		(fp_line
			(start -0.67945 -0.305054)
			(end -0.12065 -0.305054)
			(stroke
				(width 0.1)
				(type default)
			)
			(layer "F.Fab")
		)
		(fp_line
			(start -0.67945 0.3048)
			(end -0.67945 -0.305054)
			(stroke
				(width 0.1)
				(type default)
			)
			(layer "F.Fab")
		)
		(fp_line
			(start -0.12065 -0.305054)
			(end -0.12065 -0.2794)
			(stroke
				(width 0.1)
				(type default)
			)
			(layer "F.Fab")
		)
		(fp_line
			(start -0.12065 -0.2794)
			(end 0.12065 -0.2794)
			(stroke
				(width 0.1)
				(type default)
			)
			(layer "F.Fab")
		)
		(fp_line
			(start -0.12065 0.2794)
			(end -0.12065 0.3048)
			(stroke
				(width 0.1)
				(type default)
			)
			(layer "F.Fab")
		)
		(fp_line
			(start -0.12065 0.3048)
			(end -0.67945 0.3048)
			(stroke
				(width 0.1)
				(type default)
			)
			(layer "F.Fab")
		)
		(fp_line
			(start 0.120396 0.2794)
			(end -0.12065 0.2794)
			(stroke
				(width 0.1)
				(type default)
			)
			(layer "F.Fab")
		)
		(fp_line
			(start 0.120396 0.3048)
			(end 0.120396 0.2794)
			(stroke
				(width 0.1)
				(type default)
			)
			(layer "F.Fab")
		)
		(fp_line
			(start 0.12065 -0.3048)
			(end 0.67945 -0.3048)
			(stroke
				(width 0.1)
				(type default)
			)
			(layer "F.Fab")
		)
		(fp_line
			(start 0.12065 -0.2794)
			(end 0.12065 -0.3048)
			(stroke
				(width 0.1)
				(type default)
			)
			(layer "F.Fab")
		)
		(fp_line
			(start 0.67945 -0.3048)
			(end 0.67945 0.3048)
			(stroke
				(width 0.1)
				(type default)
			)
			(layer "F.Fab")
		)
		(fp_line
			(start 0.67945 0.3048)
			(end 0.120396 0.3048)
			(stroke
				(width 0.1)
				(type default)
			)
			(layer "F.Fab")
		)
		(pad "1" smd circle
			(at -0.40005 0)
			(size 0 0)
			(layers "F.Cu" "F.Mask" "F.Paste")
			(net "P3V3_AUX")
		)
		(pad "2" smd circle
			(at 0.40005 0)
			(size 0 0)
			(layers "F.Cu" "F.Mask" "F.Paste")
			(net "PWRGD_P12V_NIC0_CO")
		)
	)
	(footprint ""
		(layer "F.Cu")
		(at 380.419102 -59.574684 90)
		(property "Reference" "PC564"
			(at 0 0 90)
			(layer "F.SilkS")
			(hide yes)
			(effects
				(font
					(size 1.27 1.27)
				)
			)
		)
		(property "Value" ""
			(at 0 0 90)
			(layer "F.Fab")
			(effects
				(font
					(size 1.27 1.27)
				)
			)
		)
		(duplicate_pad_numbers_are_jumpers no)
		(fp_line
			(start 0.7874 -0.4064)
			(end 0.7874 0.4064)
			(stroke
				(width 0.1524)
				(type default)
			)
			(layer "F.SilkS")
		)
		(fp_line
			(start -0.7874 -0.4064)
			(end 0.7874 -0.4064)
			(stroke
				(width 0.1524)
				(type default)
			)
			(layer "F.SilkS")
		)
		(fp_line
			(start 0.7874 0.4064)
			(end -0.7874 0.4064)
			(stroke
				(width 0.1524)
				(type default)
			)
			(layer "F.SilkS")
		)
		(fp_line
			(start -0.7874 0.4064)
			(end -0.7874 -0.4064)
			(stroke
				(width 0.1524)
				(type default)
			)
			(layer "F.SilkS")
		)
		(fp_line
			(start -0.12065 -0.305054)
			(end -0.12065 -0.2794)
			(stroke
				(width 0.1)
				(type default)
			)
			(layer "F.Fab")
		)
		(fp_line
			(start -0.67945 -0.305054)
			(end -0.12065 -0.305054)
			(stroke
				(width 0.1)
				(type default)
			)
			(layer "F.Fab")
		)
		(fp_line
			(start 0.67945 -0.3048)
			(end 0.67945 0.3048)
			(stroke
				(width 0.1)
				(type default)
			)
			(layer "F.Fab")
		)
		(fp_line
			(start 0.12065 -0.3048)
			(end 0.67945 -0.3048)
			(stroke
				(width 0.1)
				(type default)
			)
			(layer "F.Fab")
		)
		(fp_line
			(start 0.12065 -0.2794)
			(end 0.12065 -0.3048)
			(stroke
				(width 0.1)
				(type default)
			)
			(layer "F.Fab")
		)
		(fp_line
			(start -0.12065 -0.2794)
			(end 0.12065 -0.2794)
			(stroke
				(width 0.1)
				(type default)
			)
			(layer "F.Fab")
		)
		(fp_line
			(start 0.120396 0.2794)
			(end -0.12065 0.2794)
			(stroke
				(width 0.1)
				(type default)
			)
			(layer "F.Fab")
		)
		(fp_line
			(start -0.12065 0.2794)
			(end -0.12065 0.3048)
			(stroke
				(width 0.1)
				(type default)
			)
			(layer "F.Fab")
		)
		(fp_line
			(start 0.67945 0.3048)
			(end 0.120396 0.3048)
			(stroke
				(width 0.1)
				(type default)
			)
			(layer "F.Fab")
		)
		(fp_line
			(start 0.120396 0.3048)
			(end 0.120396 0.2794)
			(stroke
				(width 0.1)
				(type default)
			)
			(layer "F.Fab")
		)
		(fp_line
			(start -0.12065 0.3048)
			(end -0.67945 0.3048)
			(stroke
				(width 0.1)
				(type default)
			)
			(layer "F.Fab")
		)
		(fp_line
			(start -0.67945 0.3048)
			(end -0.67945 -0.305054)
			(stroke
				(width 0.1)
				(type default)
			)
			(layer "F.Fab")
		)
		(pad "1" smd circle
			(at -0.40005 0 90)
			(size 0 0)
			(layers "F.Cu" "F.Mask" "F.Paste")
			(net "P5V_AUX")
		)
		(pad "2" smd circle
			(at 0.40005 0 90)
			(size 0 0)
			(layers "F.Cu" "F.Mask" "F.Paste")
			(net "GND")
		)
	)
	(footprint ""
		(layer "F.Cu")
		(at 267.871702 -343.952322 90)
		(property "Reference" "C2341"
			(at 0 0 90)
			(layer "F.SilkS")
			(hide yes)
			(effects
				(font
					(size 1.27 1.27)
				)
			)
		)
		(property "Value" ""
			(at 0 0 90)
			(layer "F.Fab")
			(effects
				(font
					(size 1.27 1.27)
				)
			)
		)
		(duplicate_pad_numbers_are_jumpers no)
		(fp_line
			(start 0.299974 -0.150114)
			(end 0.299974 0.150114)
			(stroke
				(width 0.1)
				(type default)
			)
			(layer "F.Fab")
		)
		(fp_line
			(start -0.299974 -0.150114)
			(end 0.299974 -0.150114)
			(stroke
				(width 0.1)
				(type default)
			)
			(layer "F.Fab")
		)
		(fp_line
			(start 0.299974 0.150114)
			(end -0.299974 0.150114)
			(stroke
				(width 0.1)
				(type default)
			)
			(layer "F.Fab")
		)
		(fp_line
			(start -0.299974 0.150114)
			(end -0.299974 -0.150114)
			(stroke
				(width 0.1)
				(type default)
			)
			(layer "F.Fab")
		)
		(pad "1" smd rect
			(at -0.2667 0 90)
			(size 0.3048 0.381)
			(layers "F.Cu" "F.Mask" "F.Paste")
			(net "P5E_PEX2_STN4_TX_DP<79>")
		)
		(pad "2" smd rect
			(at 0.2667 0 90)
			(size 0.3048 0.381)
			(layers "F.Cu" "F.Mask" "F.Paste")
			(net "P5E_PEX2_STN4_TX_C_DP<79>")
		)
	)
	(footprint ""
		(layer "F.Cu")
		(at 110.767114 -157.595824)
		(property "Reference" "PC30"
			(at 0 0 0)
			(layer "F.SilkS")
			(hide yes)
			(effects
				(font
					(size 1.27 1.27)
				)
			)
		)
		(property "Value" ""
			(at 0 0 0)
			(layer "F.Fab")
			(effects
				(font
					(size 1.27 1.27)
				)
			)
		)
		(duplicate_pad_numbers_are_jumpers no)
		(fp_line
			(start -0.7874 -0.4064)
			(end 0.7874 -0.4064)
			(stroke
				(width 0.1524)
				(type default)
			)
			(layer "F.SilkS")
		)
		(fp_line
			(start -0.7874 0.4064)
			(end -0.7874 -0.4064)
			(stroke
				(width 0.1524)
				(type default)
			)
			(layer "F.SilkS")
		)
		(fp_line
			(start 0.7874 -0.4064)
			(end 0.7874 0.4064)
			(stroke
				(width 0.1524)
				(type default)
			)
			(layer "F.SilkS")
		)
		(fp_line
			(start 0.7874 0.4064)
			(end -0.7874 0.4064)
			(stroke
				(width 0.1524)
				(type default)
			)
			(layer "F.SilkS")
		)
		(fp_line
			(start -0.67945 -0.305054)
			(end -0.12065 -0.305054)
			(stroke
				(width 0.1)
				(type default)
			)
			(layer "F.Fab")
		)
		(fp_line
			(start -0.67945 0.3048)
			(end -0.67945 -0.305054)
			(stroke
				(width 0.1)
				(type default)
			)
			(layer "F.Fab")
		)
		(fp_line
			(start -0.12065 -0.305054)
			(end -0.12065 -0.2794)
			(stroke
				(width 0.1)
				(type default)
			)
			(layer "F.Fab")
		)
		(fp_line
			(start -0.12065 -0.2794)
			(end 0.12065 -0.2794)
			(stroke
				(width 0.1)
				(type default)
			)
			(layer "F.Fab")
		)
		(fp_line
			(start -0.12065 0.2794)
			(end -0.12065 0.3048)
			(stroke
				(width 0.1)
				(type default)
			)
			(layer "F.Fab")
		)
		(fp_line
			(start -0.12065 0.3048)
			(end -0.67945 0.3048)
			(stroke
				(width 0.1)
				(type default)
			)
			(layer "F.Fab")
		)
		(fp_line
			(start 0.120396 0.2794)
			(end -0.12065 0.2794)
			(stroke
				(width 0.1)
				(type default)
			)
			(layer "F.Fab")
		)
		(fp_line
			(start 0.120396 0.3048)
			(end 0.120396 0.2794)
			(stroke
				(width 0.1)
				(type default)
			)
			(layer "F.Fab")
		)
		(fp_line
			(start 0.12065 -0.3048)
			(end 0.67945 -0.3048)
			(stroke
				(width 0.1)
				(type default)
			)
			(layer "F.Fab")
		)
		(fp_line
			(start 0.12065 -0.2794)
			(end 0.12065 -0.3048)
			(stroke
				(width 0.1)
				(type default)
			)
			(layer "F.Fab")
		)
		(fp_line
			(start 0.67945 -0.3048)
			(end 0.67945 0.3048)
			(stroke
				(width 0.1)
				(type default)
			)
			(layer "F.Fab")
		)
		(fp_line
			(start 0.67945 0.3048)
			(end 0.120396 0.3048)
			(stroke
				(width 0.1)
				(type default)
			)
			(layer "F.Fab")
		)
		(pad "1" smd circle
			(at -0.40005 0)
			(size 0 0)
			(layers "F.Cu" "F.Mask" "F.Paste")
			(net "SW_P12V_P3V3_AUX_FLT")
		)
		(pad "2" smd circle
			(at 0.40005 0)
			(size 0 0)
			(layers "F.Cu" "F.Mask" "F.Paste")
			(net "GND")
		)
	)
	(footprint ""
		(layer "F.Cu")
		(at 251.42571 -159.082994 -90)
		(property "Reference" "PD93"
			(at 4.142994 -2.72796 90)
			(unlocked yes)
			(layer "F.SilkS")
			(effects
				(font
					(size 0.7874 0.5842)
					(thickness 0.1524)
				)
				(justify left)
			)
		)
		(property "Value" ""
			(at 0 0 270)
			(layer "F.Fab")
			(effects
				(font
					(size 1.27 1.27)
				)
			)
		)
		(duplicate_pad_numbers_are_jumpers no)
		(fp_line
			(start -3.656584 1.970024)
			(end 4.240784 1.970024)
			(stroke
				(width 0.1524)
				(type default)
			)
			(layer "F.SilkS")
		)
		(fp_line
			(start 4.240784 1.970024)
			(end 4.240784 -1.970024)
			(stroke
				(width 0.1524)
				(type default)
			)
			(layer "F.SilkS")
		)
		(fp_line
			(start -3.656584 -1.970024)
			(end -3.656584 1.970024)
			(stroke
				(width 0.1524)
				(type default)
			)
			(layer "F.SilkS")
		)
		(fp_line
			(start 4.240784 -1.970024)
			(end -3.656584 -1.970024)
			(stroke
				(width 0.1524)
				(type default)
			)
			(layer "F.SilkS")
		)
		(fp_poly
			(pts
				(xy 3.580384 1.970024) (xy 3.580384 -1.970024) (xy 4.240784 -1.970024) (xy 4.240784 1.970024)
			)
			(stroke
				(width 0)
				(type default)
			)
			(fill yes)
			(layer "F.SilkS")
		)
		(fp_line
			(start -2.3749 1.970024)
			(end 2.3749 1.970024)
			(stroke
				(width 0.1)
				(type default)
			)
			(layer "F.Fab")
		)
		(fp_line
			(start 2.3749 1.970024)
			(end 2.3749 -1.970024)
			(stroke
				(width 0.1)
				(type default)
			)
			(layer "F.Fab")
		)
		(fp_line
			(start -2.3749 -1.970024)
			(end -2.3749 1.970024)
			(stroke
				(width 0.1)
				(type default)
			)
			(layer "F.Fab")
		)
		(fp_line
			(start 2.3749 -1.970024)
			(end -2.3749 -1.970024)
			(stroke
				(width 0.1)
				(type default)
			)
			(layer "F.Fab")
		)
		(fp_text user "+"
			(at -4.9784 -0.23495 270)
			(unlocked yes)
			(layer "F.Fab")
			(effects
				(font
					(size 1.905 1.4224)
					(thickness 0.1524)
				)
				(justify left)
			)
		)
		(fp_text user "-"
			(at 4.1656 -0.23495 270)
			(unlocked yes)
			(layer "F.Fab")
			(effects
				(font
					(size 1.905 1.4224)
					(thickness 0.1524)
				)
				(justify left)
			)
		)
		(pad "A" smd rect
			(at -2.450084 0 270)
			(size 2.159 2.2606)
			(layers "F.Cu" "F.Mask" "F.Paste")
			(net "GND")
		)
		(pad "C" smd rect
			(at 2.450084 0 270)
			(size 2.159 2.2606)
			(layers "F.Cu" "F.Mask" "F.Paste")
			(net "P12V_AUX")
		)
	)
	(footprint ""
		(layer "F.Cu")
		(at 368.00282 -225.49993 180)
		(property "Reference" "U321"
			(at 1.299972 8.679942 0)
			(unlocked yes)
			(layer "F.SilkS")
			(effects
				(font
					(size 0.7874 0.5842)
					(thickness 0.1524)
				)
				(justify left)
			)
		)
		(property "Value" ""
			(at 0 0 180)
			(layer "F.Fab")
			(effects
				(font
					(size 1.27 1.27)
				)
			)
		)
		(duplicate_pad_numbers_are_jumpers no)
		(fp_line
			(start 3.795014 5.2451)
			(end 3.795014 -5.2451)
			(stroke
				(width 0.1524)
				(type default)
			)
			(layer "F.SilkS")
		)
		(fp_line
			(start 3.795014 -5.2451)
			(end 1.9431 -5.2451)
			(stroke
				(width 0.1524)
				(type default)
			)
			(layer "F.SilkS")
		)
		(fp_line
			(start 1.9431 -5.2451)
			(end 0 -3.302)
			(stroke
				(width 0.1524)
				(type default)
			)
			(layer "F.SilkS")
		)
		(fp_line
			(start 0 -3.302)
			(end -1.9431 -5.2451)
			(stroke
				(width 0.1524)
				(type default)
			)
			(layer "F.SilkS")
		)
		(fp_line
			(start -1.9431 -5.2451)
			(end -3.795014 -5.2451)
			(stroke
				(width 0.1524)
				(type default)
			)
			(layer "F.SilkS")
		)
		(fp_line
			(start -3.795014 5.2451)
			(end 3.795014 5.2451)
			(stroke
				(width 0.1524)
				(type default)
			)
			(layer "F.SilkS")
		)
		(fp_line
			(start -3.795014 -5.2451)
			(end -3.795014 5.2451)
			(stroke
				(width 0.1524)
				(type default)
			)
			(layer "F.SilkS")
		)
		(fp_poly
			(pts
				(xy -5.976366 -4.445) (xy -7.239 -3.81381) (xy -7.239 -5.07619)
			)
			(stroke
				(width 0)
				(type default)
			)
			(fill yes)
			(layer "F.SilkS")
		)
		(fp_line
			(start 3.795014 5.2451)
			(end 3.795014 -5.2451)
			(stroke
				(width 0.1)
				(type default)
			)
			(layer "F.Fab")
		)
		(fp_line
			(start 3.795014 -5.2451)
			(end -3.795014 -5.2451)
			(stroke
				(width 0.1)
				(type default)
			)
			(layer "F.Fab")
		)
		(fp_line
			(start -3.795014 5.2451)
			(end 3.795014 5.2451)
			(stroke
				(width 0.1)
				(type default)
			)
			(layer "F.Fab")
		)
		(fp_line
			(start -3.795014 -5.2451)
			(end -3.795014 5.2451)
			(stroke
				(width 0.1)
				(type default)
			)
			(layer "F.Fab")
		)
		(fp_poly
			(pts
				(xy -5.976366 -4.445) (xy -7.239 -3.81381) (xy -7.239 -5.07619)
			)
			(stroke
				(width 0)
				(type default)
			)
			(fill yes)
			(layer "F.Fab")
		)
		(pad "1" smd rect
			(at -4.880102 -4.445 90)
			(size 0.8128 1.905)
			(layers "F.Cu" "F.Mask" "F.Paste")
			(net "SPI_PEX3_SDIO3_R1")
		)
		(pad "2" smd rect
			(at -4.880102 -3.175 90)
			(size 0.8128 1.905)
			(layers "F.Cu" "F.Mask" "F.Paste")
			(net "P1V8_PEX")
		)
		(pad "3" smd rect
			(at -4.880102 -1.905 90)
			(size 0.8128 1.905)
			(layers "F.Cu" "F.Mask" "F.Paste")
			(net "SPI_PEX3_RST_R_N")
		)
		(pad "4" smd rect
			(at -4.880102 -0.635 90)
			(size 0.8128 1.905)
			(layers "F.Cu" "F.Mask" "F.Paste")
			(net "Net_9000")
		)
		(pad "5" smd rect
			(at -4.880102 0.635 90)
			(size 0.8128 1.905)
			(layers "F.Cu" "F.Mask" "F.Paste")
			(net "Net_8999")
		)
		(pad "6" smd rect
			(at -4.880102 1.905 90)
			(size 0.8128 1.905)
			(layers "F.Cu" "F.Mask" "F.Paste")
			(net "Net_8998")
		)
		(pad "7" smd rect
			(at -4.880102 3.175 90)
			(size 0.8128 1.905)
			(layers "F.Cu" "F.Mask" "F.Paste")
			(net "SPI_PEX3_CS_MUX_R_N")
		)
		(pad "8" smd rect
			(at -4.880102 4.445 90)
			(size 0.8128 1.905)
			(layers "F.Cu" "F.Mask" "F.Paste")
			(net "SPI_PEX3_SDIO1_MUX_R")
		)
		(pad "9" smd rect
			(at 4.880102 4.445 270)
			(size 0.8128 1.905)
			(layers "F.Cu" "F.Mask" "F.Paste")
			(net "SPI_PEX3_SDIO2_R1")
		)
		(pad "10" smd rect
			(at 4.880102 3.175 270)
			(size 0.8128 1.905)
			(layers "F.Cu" "F.Mask" "F.Paste")
			(net "GND")
		)
		(pad "11" smd rect
			(at 4.880102 1.905 270)
			(size 0.8128 1.905)
			(layers "F.Cu" "F.Mask" "F.Paste")
			(net "Net_8997")
		)
		(pad "12" smd rect
			(at 4.880102 0.635 270)
			(size 0.8128 1.905)
			(layers "F.Cu" "F.Mask" "F.Paste")
			(net "Net_8996")
		)
		(pad "13" smd rect
			(at 4.880102 -0.635 270)
			(size 0.8128 1.905)
			(layers "F.Cu" "F.Mask" "F.Paste")
			(net "Net_8995")
		)
		(pad "14" smd rect
			(at 4.880102 -1.905 270)
			(size 0.8128 1.905)
			(layers "F.Cu" "F.Mask" "F.Paste")
			(net "Net_8994")
		)
		(pad "15" smd rect
			(at 4.880102 -3.175 270)
			(size 0.8128 1.905)
			(layers "F.Cu" "F.Mask" "F.Paste")
			(net "SPI_PEX3_SDIO0_MUX_R")
		)
		(pad "16" smd rect
			(at 4.880102 -4.445 270)
			(size 0.8128 1.905)
			(layers "F.Cu" "F.Mask" "F.Paste")
			(net "SPI_PEX3_CLK_MUX_R")
		)
	)
	(footprint ""
		(layer "F.Cu")
		(at 268.53515 -79.892906 180)
		(property "Reference" "R1060"
			(at 0 0 180)
			(layer "F.SilkS")
			(hide yes)
			(effects
				(font
					(size 1.27 1.27)
				)
			)
		)
		(property "Value" ""
			(at 0 0 180)
			(layer "F.Fab")
			(effects
				(font
					(size 1.27 1.27)
				)
			)
		)
		(duplicate_pad_numbers_are_jumpers no)
		(fp_line
			(start 0.7874 0.4064)
			(end -0.7874 0.4064)
			(stroke
				(width 0.1524)
				(type default)
			)
			(layer "F.SilkS")
		)
		(fp_line
			(start 0.7874 -0.4064)
			(end 0.7874 0.4064)
			(stroke
				(width 0.1524)
				(type default)
			)
			(layer "F.SilkS")
		)
		(fp_line
			(start -0.7874 0.4064)
			(end -0.7874 -0.4064)
			(stroke
				(width 0.1524)
				(type default)
			)
			(layer "F.SilkS")
		)
		(fp_line
			(start -0.7874 -0.4064)
			(end 0.7874 -0.4064)
			(stroke
				(width 0.1524)
				(type default)
			)
			(layer "F.SilkS")
		)
		(fp_line
			(start 0.67945 0.3048)
			(end 0.120396 0.3048)
			(stroke
				(width 0.1)
				(type default)
			)
			(layer "F.Fab")
		)
		(fp_line
			(start 0.67945 -0.3048)
			(end 0.67945 0.3048)
			(stroke
				(width 0.1)
				(type default)
			)
			(layer "F.Fab")
		)
		(fp_line
			(start 0.12065 -0.2794)
			(end 0.12065 -0.3048)
			(stroke
				(width 0.1)
				(type default)
			)
			(layer "F.Fab")
		)
		(fp_line
			(start 0.12065 -0.3048)
			(end 0.67945 -0.3048)
			(stroke
				(width 0.1)
				(type default)
			)
			(layer "F.Fab")
		)
		(fp_line
			(start 0.120396 0.3048)
			(end 0.120396 0.2794)
			(stroke
				(width 0.1)
				(type default)
			)
			(layer "F.Fab")
		)
		(fp_line
			(start 0.120396 0.2794)
			(end -0.12065 0.2794)
			(stroke
				(width 0.1)
				(type default)
			)
			(layer "F.Fab")
		)
		(fp_line
			(start -0.12065 0.3048)
			(end -0.67945 0.3048)
			(stroke
				(width 0.1)
				(type default)
			)
			(layer "F.Fab")
		)
		(fp_line
			(start -0.12065 0.2794)
			(end -0.12065 0.3048)
			(stroke
				(width 0.1)
				(type default)
			)
			(layer "F.Fab")
		)
		(fp_line
			(start -0.12065 -0.2794)
			(end 0.12065 -0.2794)
			(stroke
				(width 0.1)
				(type default)
			)
			(layer "F.Fab")
		)
		(fp_line
			(start -0.12065 -0.305054)
			(end -0.12065 -0.2794)
			(stroke
				(width 0.1)
				(type default)
			)
			(layer "F.Fab")
		)
		(fp_line
			(start -0.67945 0.3048)
			(end -0.67945 -0.305054)
			(stroke
				(width 0.1)
				(type default)
			)
			(layer "F.Fab")
		)
		(fp_line
			(start -0.67945 -0.305054)
			(end -0.12065 -0.305054)
			(stroke
				(width 0.1)
				(type default)
			)
			(layer "F.Fab")
		)
		(pad "1" smd circle
			(at -0.40005 0 180)
			(size 0 0)
			(layers "F.Cu" "F.Mask" "F.Paste")
			(net "GND")
		)
		(pad "2" smd circle
			(at 0.40005 0 180)
			(size 0 0)
			(layers "F.Cu" "F.Mask" "F.Paste")
			(net "CLK_BUFFER_9ZXL0851E_0_7_OE1_N")
		)
	)
	(footprint ""
		(layer "F.Cu")
		(at 150.855934 -115.590574 90)
		(property "Reference" "U19"
			(at 2.518156 -0.183134 0)
			(unlocked yes)
			(layer "F.SilkS")
			(effects
				(font
					(size 0.7874 0.5842)
					(thickness 0.1524)
				)
			)
		)
		(property "Value" ""
			(at 0 0 90)
			(layer "F.Fab")
			(effects
				(font
					(size 1.27 1.27)
				)
			)
		)
		(duplicate_pad_numbers_are_jumpers no)
		(fp_line
			(start -1.949958 -1.610106)
			(end 1.949958 -1.610106)
			(stroke
				(width 0.1524)
				(type default)
			)
			(layer "F.SilkS")
		)
		(fp_line
			(start 1.949958 -1.560068)
			(end 1.949958 1.610106)
			(stroke
				(width 0.1524)
				(type default)
			)
			(layer "F.SilkS")
		)
		(fp_line
			(start 1.949958 1.610106)
			(end -1.949958 1.610106)
			(stroke
				(width 0.1524)
				(type default)
			)
			(layer "F.SilkS")
		)
		(fp_line
			(start -1.949958 1.610106)
			(end -1.949958 -1.610106)
			(stroke
				(width 0.1524)
				(type default)
			)
			(layer "F.SilkS")
		)
		(fp_line
			(start 0.750062 -1.560068)
			(end 0.750062 1.560068)
			(stroke
				(width 0.1)
				(type default)
			)
			(layer "F.Fab")
		)
		(fp_line
			(start -0.750062 -1.560068)
			(end 0.750062 -1.560068)
			(stroke
				(width 0.1)
				(type default)
			)
			(layer "F.Fab")
		)
		(fp_line
			(start 0.750062 1.560068)
			(end -0.750062 1.560068)
			(stroke
				(width 0.1)
				(type default)
			)
			(layer "F.Fab")
		)
		(fp_line
			(start -0.750062 1.560068)
			(end -0.750062 -1.560068)
			(stroke
				(width 0.1)
				(type default)
			)
			(layer "F.Fab")
		)
		(pad "D" smd rect
			(at 1.100074 0)
			(size 1.016 1.4224)
			(layers "F.Cu" "F.Mask" "F.Paste")
			(net "HP_NIC2_EN")
		)
		(pad "G" smd rect
			(at -1.100074 -0.94996)
			(size 1.016 1.4224)
			(layers "F.Cu" "F.Mask" "F.Paste")
			(net "PRSNT_NIC2_R_N")
		)
		(pad "S" smd rect
			(at -1.100074 0.94996)
			(size 1.016 1.4224)
			(layers "F.Cu" "F.Mask" "F.Paste")
			(net "GND")
		)
	)
	(footprint ""
		(layer "F.Cu")
		(at 281.04592 -46.4439 180)
		(property "Reference" "U72"
			(at 0.52832 -2.40157 0)
			(unlocked yes)
			(layer "F.SilkS")
			(effects
				(font
					(size 0.7874 0.5842)
					(thickness 0.1524)
				)
			)
		)
		(property "Value" ""
			(at 0 0 180)
			(layer "F.Fab")
			(effects
				(font
					(size 1.27 1.27)
				)
			)
		)
		(duplicate_pad_numbers_are_jumpers no)
		(fp_line
			(start 1.500124 1.500124)
			(end 1.004062 1.500124)
			(stroke
				(width 0.1524)
				(type default)
			)
			(layer "F.SilkS")
		)
		(fp_line
			(start 1.500124 1.004062)
			(end 1.500124 1.500124)
			(stroke
				(width 0.1524)
				(type default)
			)
			(layer "F.SilkS")
		)
		(fp_line
			(start 1.500124 -1.500124)
			(end 1.500124 -1.004062)
			(stroke
				(width 0.1524)
				(type default)
			)
			(layer "F.SilkS")
		)
		(fp_line
			(start 1.004062 -1.500124)
			(end 1.500124 -1.500124)
			(stroke
				(width 0.1524)
				(type default)
			)
			(layer "F.SilkS")
		)
		(fp_line
			(start -1.004062 1.500124)
			(end -1.500124 1.500124)
			(stroke
				(width 0.1524)
				(type default)
			)
			(layer "F.SilkS")
		)
		(fp_line
			(start -1.500124 1.500124)
			(end -1.500124 1.004062)
			(stroke
				(width 0.1524)
				(type default)
			)
			(layer "F.SilkS")
		)
		(fp_line
			(start -1.500124 -1.004062)
			(end -1.500124 -1.500124)
			(stroke
				(width 0.1524)
				(type default)
			)
			(layer "F.SilkS")
		)
		(fp_line
			(start -1.500124 -1.500124)
			(end -1.004062 -1.500124)
			(stroke
				(width 0.1524)
				(type default)
			)
			(layer "F.SilkS")
		)
		(fp_poly
			(pts
				(xy -1.6764 -2.789428) (xy -2.394966 -2.071116) (xy -1.317244 -1.71196)
			)
			(stroke
				(width 0)
				(type default)
			)
			(fill yes)
			(layer "F.SilkS")
		)
		(fp_line
			(start 1.500124 1.500124)
			(end -1.500124 1.500124)
			(stroke
				(width 0.1)
				(type default)
			)
			(layer "F.Fab")
		)
		(fp_line
			(start 1.500124 -1.500124)
			(end 1.500124 1.500124)
			(stroke
				(width 0.1)
				(type default)
			)
			(layer "F.Fab")
		)
		(fp_line
			(start -1.500124 1.500124)
			(end -1.500124 -1.500124)
			(stroke
				(width 0.1)
				(type default)
			)
			(layer "F.Fab")
		)
		(fp_line
			(start -1.500124 -1.500124)
			(end 1.500124 -1.500124)
			(stroke
				(width 0.1)
				(type default)
			)
			(layer "F.Fab")
		)
		(fp_poly
			(pts
				(xy -2.847848 -1.258062) (xy -2.847848 -0.242062) (xy -1.831848 -0.750062)
			)
			(stroke
				(width 0)
				(type default)
			)
			(fill yes)
			(layer "F.Fab")
		)
		(pad "1" smd rect
			(at -1.400048 -0.750062 90)
			(size 0.2286 0.6096)
			(layers "F.Cu" "F.Mask" "F.Paste")
			(net "SSD9_ADC_A1")
		)
		(pad "2" smd rect
			(at -1.400048 -0.249936 90)
			(size 0.2286 0.6096)
			(layers "F.Cu" "F.Mask" "F.Paste")
			(net "SSD9_ADC_A0")
		)
		(pad "3" smd rect
			(at -1.400048 0.249936 90)
			(size 0.2286 0.6096)
			(layers "F.Cu" "F.Mask" "F.Paste")
			(net "SSD9_ADC_ALERT_N")
		)
		(pad "4" smd rect
			(at -1.400048 0.750062 90)
			(size 0.2286 0.6096)
			(layers "F.Cu" "F.Mask" "F.Paste")
			(net "SMB_SSD9_ADC_SDA")
		)
		(pad "5" smd rect
			(at -0.750062 1.400048 180)
			(size 0.2286 0.6096)
			(layers "F.Cu" "F.Mask" "F.Paste")
			(net "SMB_SSD9_ADC_SCL")
		)
		(pad "6" smd rect
			(at -0.249936 1.400048 180)
			(size 0.2286 0.6096)
			(layers "F.Cu" "F.Mask" "F.Paste")
			(net "Net_8708")
		)
		(pad "7" smd rect
			(at 0.249936 1.400048 180)
			(size 0.2286 0.6096)
			(layers "F.Cu" "F.Mask" "F.Paste")
			(net "Net_8707")
		)
		(pad "8" smd rect
			(at 0.750062 1.400048 180)
			(size 0.2286 0.6096)
			(layers "F.Cu" "F.Mask" "F.Paste")
			(net "Net_8706")
		)
		(pad "9" smd rect
			(at 1.400048 0.750062 90)
			(size 0.2286 0.6096)
			(layers "F.Cu" "F.Mask" "F.Paste")
			(net "P3V3_AUX")
		)
		(pad "10" smd rect
			(at 1.400048 0.249936 90)
			(size 0.2286 0.6096)
			(layers "F.Cu" "F.Mask" "F.Paste")
			(net "GND")
		)
		(pad "11" smd rect
			(at 1.400048 -0.249936 90)
			(size 0.2286 0.6096)
			(layers "F.Cu" "F.Mask" "F.Paste")
			(net "P12V_SSD9_R")
		)
		(pad "12" smd rect
			(at 1.400048 -0.750062 90)
			(size 0.2286 0.6096)
			(layers "F.Cu" "F.Mask" "F.Paste")
			(net "P12V_SSD9_VIN_N")
		)
		(pad "13" smd rect
			(at 0.750062 -1.400048 180)
			(size 0.2286 0.6096)
			(layers "F.Cu" "F.Mask" "F.Paste")
			(net "P12V_SSD9_VIN_P")
		)
		(pad "14" smd rect
			(at 0.249936 -1.400048 180)
			(size 0.2286 0.6096)
			(layers "F.Cu" "F.Mask" "F.Paste")
			(net "Net_8705")
		)
		(pad "15" smd rect
			(at -0.249936 -1.400048 180)
			(size 0.2286 0.6096)
			(layers "F.Cu" "F.Mask" "F.Paste")
			(net "Net_8704")
		)
		(pad "16" smd rect
			(at -0.750062 -1.400048 180)
			(size 0.2286 0.6096)
			(layers "F.Cu" "F.Mask" "F.Paste")
			(net "Net_8703")
		)
		(pad "TH" smd rect
			(at 0 0 180)
			(size 1.7018 1.7018)
			(layers "F.Cu" "F.Mask" "F.Paste")
			(net "GND")
		)
		(zone
			(layer "F.Cu")
			(hatch none 0.5)
			(connect_pads
				(clearance 0)
			)
			(min_thickness 0.25)
			(keepout
				(tracks not_allowed)
				(vias allowed)
				(pads allowed)
				(copperpour not_allowed)
				(footprints allowed)
			)
			(placement
				(enabled no)
				(sheetname "")
			)
			(fill
				(thermal_gap 0.5)
				(thermal_bridge_width 0.5)
				(island_removal_mode 0)
			)
			(polygon
				(pts
					(xy 282.090368 -46.4185) (xy 282.090368 -45.399452) (xy 280.001472 -45.399452) (xy 280.001472 -47.488348)
					(xy 282.090368 -47.488348) (xy 282.090368 -46.4439) (xy 281.94762 -46.4439) (xy 281.94762 -47.3456)
					(xy 280.14422 -47.3456) (xy 280.14422 -45.5422) (xy 281.94762 -45.5422) (xy 281.94762 -46.4185)
				)
			)
		)
	)
	(footprint ""
		(layer "F.Cu")
		(at 374.27154 -350.098614 90)
		(property "Reference" "C764"
			(at 0 0 90)
			(layer "F.SilkS")
			(hide yes)
			(effects
				(font
					(size 1.27 1.27)
				)
			)
		)
		(property "Value" ""
			(at 0 0 90)
			(layer "F.Fab")
			(effects
				(font
					(size 1.27 1.27)
				)
			)
		)
		(duplicate_pad_numbers_are_jumpers no)
		(fp_line
			(start 0.299974 -0.150114)
			(end 0.299974 0.150114)
			(stroke
				(width 0.1)
				(type default)
			)
			(layer "F.Fab")
		)
		(fp_line
			(start -0.299974 -0.150114)
			(end 0.299974 -0.150114)
			(stroke
				(width 0.1)
				(type default)
			)
			(layer "F.Fab")
		)
		(fp_line
			(start 0.299974 0.150114)
			(end -0.299974 0.150114)
			(stroke
				(width 0.1)
				(type default)
			)
			(layer "F.Fab")
		)
		(fp_line
			(start -0.299974 0.150114)
			(end -0.299974 -0.150114)
			(stroke
				(width 0.1)
				(type default)
			)
			(layer "F.Fab")
		)
		(pad "1" smd rect
			(at -0.2667 0 90)
			(size 0.3048 0.381)
			(layers "F.Cu" "F.Mask" "F.Paste")
			(net "P5E_PEX3_STN6_TX_DP<110>")
		)
		(pad "2" smd rect
			(at 0.2667 0 90)
			(size 0.3048 0.381)
			(layers "F.Cu" "F.Mask" "F.Paste")
			(net "P5E_PEX3_STN6_TX_C_DP<110>")
		)
	)
	(footprint ""
		(layer "F.Cu")
		(at 130.490468 -343.952322 90)
		(property "Reference" "C2257"
			(at 0 0 90)
			(layer "F.SilkS")
			(hide yes)
			(effects
				(font
					(size 1.27 1.27)
				)
			)
		)
		(property "Value" ""
			(at 0 0 90)
			(layer "F.Fab")
			(effects
				(font
					(size 1.27 1.27)
				)
			)
		)
		(duplicate_pad_numbers_are_jumpers no)
		(fp_line
			(start 0.299974 -0.150114)
			(end 0.299974 0.150114)
			(stroke
				(width 0.1)
				(type default)
			)
			(layer "F.Fab")
		)
		(fp_line
			(start -0.299974 -0.150114)
			(end 0.299974 -0.150114)
			(stroke
				(width 0.1)
				(type default)
			)
			(layer "F.Fab")
		)
		(fp_line
			(start 0.299974 0.150114)
			(end -0.299974 0.150114)
			(stroke
				(width 0.1)
				(type default)
			)
			(layer "F.Fab")
		)
		(fp_line
			(start -0.299974 0.150114)
			(end -0.299974 -0.150114)
			(stroke
				(width 0.1)
				(type default)
			)
			(layer "F.Fab")
		)
		(pad "1" smd rect
			(at -0.2667 0 90)
			(size 0.3048 0.381)
			(layers "F.Cu" "F.Mask" "F.Paste")
			(net "P5E_PEX1_STN5_TX_DP<88>")
		)
		(pad "2" smd rect
			(at 0.2667 0 90)
			(size 0.3048 0.381)
			(layers "F.Cu" "F.Mask" "F.Paste")
			(net "P5E_PEX1_STN5_TX_C_DP<88>")
		)
	)
	(footprint ""
		(layer "F.Cu")
		(at 374.169432 -6.38683)
		(property "Reference" "U417"
			(at -1.246632 3.3401 0)
			(unlocked yes)
			(layer "F.SilkS")
			(effects
				(font
					(size 0.7874 0.5842)
					(thickness 0.1524)
				)
				(justify left)
			)
		)
		(property "Value" ""
			(at 0 0 0)
			(layer "F.Fab")
			(effects
				(font
					(size 1.27 1.27)
				)
			)
		)
		(duplicate_pad_numbers_are_jumpers no)
		(fp_line
			(start -3.447796 -2.500122)
			(end -3.447796 2.500122)
			(stroke
				(width 0.1524)
				(type default)
			)
			(layer "F.SilkS")
		)
		(fp_line
			(start -3.447796 2.500122)
			(end 3.447796 2.500122)
			(stroke
				(width 0.1524)
				(type default)
			)
			(layer "F.SilkS")
		)
		(fp_line
			(start -1.484122 -2.500122)
			(end -3.447796 -2.500122)
			(stroke
				(width 0.1524)
				(type default)
			)
			(layer "F.SilkS")
		)
		(fp_line
			(start 0 -1.016)
			(end -1.484122 -2.500122)
			(stroke
				(width 0.1524)
				(type default)
			)
			(layer "F.SilkS")
		)
		(fp_line
			(start 1.484122 -2.500122)
			(end 0 -1.016)
			(stroke
				(width 0.1524)
				(type default)
			)
			(layer "F.SilkS")
		)
		(fp_line
			(start 3.447796 -2.500122)
			(end 1.484122 -2.500122)
			(stroke
				(width 0.1524)
				(type default)
			)
			(layer "F.SilkS")
		)
		(fp_line
			(start 3.447796 2.500122)
			(end 3.447796 -2.500122)
			(stroke
				(width 0.1524)
				(type default)
			)
			(layer "F.SilkS")
		)
		(fp_poly
			(pts
				(xy -3.991356 -3.090672) (xy -4.709922 -2.372106) (xy -3.6322 -2.01295)
			)
			(stroke
				(width 0)
				(type default)
			)
			(fill yes)
			(layer "F.SilkS")
		)
		(fp_line
			(start -1.999996 -2.500122)
			(end -1.999996 2.500122)
			(stroke
				(width 0.1)
				(type default)
			)
			(layer "F.Fab")
		)
		(fp_line
			(start -1.999996 2.500122)
			(end 1.999996 2.500122)
			(stroke
				(width 0.1)
				(type default)
			)
			(layer "F.Fab")
		)
		(fp_line
			(start 1.999996 -2.500122)
			(end -1.999996 -2.500122)
			(stroke
				(width 0.1)
				(type default)
			)
			(layer "F.Fab")
		)
		(fp_line
			(start 1.999996 2.500122)
			(end 1.999996 -2.500122)
			(stroke
				(width 0.1)
				(type default)
			)
			(layer "F.Fab")
		)
		(fp_poly
			(pts
				(xy -4.5974 -2.413) (xy -4.5974 -1.397) (xy -3.5814 -1.905)
			)
			(stroke
				(width 0)
				(type default)
			)
			(fill yes)
			(layer "F.Fab")
		)
		(pad "1" smd rect
			(at -2.649982 -1.905 270)
			(size 0.6096 1.3208)
			(layers "F.Cu" "F.Mask" "F.Paste")
			(net "SMB_LM75_3_SDA")
		)
		(pad "2" smd rect
			(at -2.649982 -0.635 270)
			(size 0.6096 1.3208)
			(layers "F.Cu" "F.Mask" "F.Paste")
			(net "SMB_LM75_3_SCL")
		)
		(pad "3" smd rect
			(at -2.649982 0.635 270)
			(size 0.6096 1.3208)
			(layers "F.Cu" "F.Mask" "F.Paste")
			(net "Net_407")
		)
		(pad "4" smd rect
			(at -2.649982 1.905 270)
			(size 0.6096 1.3208)
			(layers "F.Cu" "F.Mask" "F.Paste")
			(net "GND")
		)
		(pad "5" smd rect
			(at 2.649982 1.905 270)
			(size 0.6096 1.3208)
			(layers "F.Cu" "F.Mask" "F.Paste")
			(net "LM75_3_A2")
		)
		(pad "6" smd rect
			(at 2.649982 0.635 270)
			(size 0.6096 1.3208)
			(layers "F.Cu" "F.Mask" "F.Paste")
			(net "LM75_3_A1")
		)
		(pad "7" smd rect
			(at 2.649982 -0.635 270)
			(size 0.6096 1.3208)
			(layers "F.Cu" "F.Mask" "F.Paste")
			(net "LM75_3_A0")
		)
		(pad "8" smd rect
			(at 2.649982 -1.905 270)
			(size 0.6096 1.3208)
			(layers "F.Cu" "F.Mask" "F.Paste")
			(net "P3V3_AUX")
		)
	)
	(footprint ""
		(layer "F.Cu")
		(at 126.897892 -308.470554 -90)
		(property "Reference" "C4247"
			(at 0 0 270)
			(layer "F.SilkS")
			(hide yes)
			(effects
				(font
					(size 1.27 1.27)
				)
			)
		)
		(property "Value" ""
			(at 0 0 270)
			(layer "F.Fab")
			(effects
				(font
					(size 1.27 1.27)
				)
			)
		)
		(duplicate_pad_numbers_are_jumpers no)
		(fp_line
			(start -1.2954 0.5842)
			(end -1.2954 -0.5842)
			(stroke
				(width 0.1524)
				(type default)
			)
			(layer "F.SilkS")
		)
		(fp_line
			(start 1.2954 0.5842)
			(end -1.2954 0.5842)
			(stroke
				(width 0.1524)
				(type default)
			)
			(layer "F.SilkS")
		)
		(fp_line
			(start -1.2954 -0.5842)
			(end 1.2954 -0.5842)
			(stroke
				(width 0.1524)
				(type default)
			)
			(layer "F.SilkS")
		)
		(fp_line
			(start 1.2954 -0.5842)
			(end 1.2954 0.5842)
			(stroke
				(width 0.1524)
				(type default)
			)
			(layer "F.SilkS")
		)
		(fp_line
			(start -0.8636 0.4572)
			(end -0.8636 0.4064)
			(stroke
				(width 0.1)
				(type default)
			)
			(layer "F.Fab")
		)
		(fp_line
			(start 0.8636 0.4572)
			(end -0.8636 0.4572)
			(stroke
				(width 0.1)
				(type default)
			)
			(layer "F.Fab")
		)
		(fp_line
			(start -1.1938 0.4064)
			(end -1.1938 -0.4064)
			(stroke
				(width 0.1)
				(type default)
			)
			(layer "F.Fab")
		)
		(fp_line
			(start -0.8636 0.4064)
			(end -1.1938 0.4064)
			(stroke
				(width 0.1)
				(type default)
			)
			(layer "F.Fab")
		)
		(fp_line
			(start 0.8636 0.4064)
			(end 0.8636 0.4572)
			(stroke
				(width 0.1)
				(type default)
			)
			(layer "F.Fab")
		)
		(fp_line
			(start 1.1938 0.4064)
			(end 0.8636 0.4064)
			(stroke
				(width 0.1)
				(type default)
			)
			(layer "F.Fab")
		)
		(fp_line
			(start -1.1938 -0.4064)
			(end -0.8636 -0.4064)
			(stroke
				(width 0.1)
				(type default)
			)
			(layer "F.Fab")
		)
		(fp_line
			(start -0.8636 -0.4064)
			(end -0.8636 -0.4572)
			(stroke
				(width 0.1)
				(type default)
			)
			(layer "F.Fab")
		)
		(fp_line
			(start 0.8636 -0.4064)
			(end 1.1938 -0.4064)
			(stroke
				(width 0.1)
				(type default)
			)
			(layer "F.Fab")
		)
		(fp_line
			(start 1.1938 -0.4064)
			(end 1.1938 0.4064)
			(stroke
				(width 0.1)
				(type default)
			)
			(layer "F.Fab")
		)
		(fp_line
			(start -0.8636 -0.4572)
			(end 0.8636 -0.4572)
			(stroke
				(width 0.1)
				(type default)
			)
			(layer "F.Fab")
		)
		(fp_line
			(start 0.8636 -0.4572)
			(end 0.8636 -0.4064)
			(stroke
				(width 0.1)
				(type default)
			)
			(layer "F.Fab")
		)
		(pad "1" smd rect
			(at -0.7366 0 180)
			(size 0.7112 0.8128)
			(layers "F.Cu" "F.Mask" "F.Paste")
			(net "P0V8_PEX1")
		)
		(pad "2" smd rect
			(at 0.7366 0 180)
			(size 0.7112 0.8128)
			(layers "F.Cu" "F.Mask" "F.Paste")
			(net "GND")
		)
	)
	(footprint ""
		(layer "F.Cu")
		(at 28.875228 -63.086234)
		(property "Reference" "R5843"
			(at 0 0 0)
			(layer "F.SilkS")
			(hide yes)
			(effects
				(font
					(size 1.27 1.27)
				)
			)
		)
		(property "Value" ""
			(at 0 0 0)
			(layer "F.Fab")
			(effects
				(font
					(size 1.27 1.27)
				)
			)
		)
		(duplicate_pad_numbers_are_jumpers no)
		(fp_line
			(start -0.7874 -0.4064)
			(end 0.7874 -0.4064)
			(stroke
				(width 0.1524)
				(type default)
			)
			(layer "F.SilkS")
		)
		(fp_line
			(start -0.7874 0.4064)
			(end -0.7874 -0.4064)
			(stroke
				(width 0.1524)
				(type default)
			)
			(layer "F.SilkS")
		)
		(fp_line
			(start 0.7874 -0.4064)
			(end 0.7874 0.4064)
			(stroke
				(width 0.1524)
				(type default)
			)
			(layer "F.SilkS")
		)
		(fp_line
			(start 0.7874 0.4064)
			(end -0.7874 0.4064)
			(stroke
				(width 0.1524)
				(type default)
			)
			(layer "F.SilkS")
		)
		(fp_line
			(start -0.67945 -0.305054)
			(end -0.12065 -0.305054)
			(stroke
				(width 0.1)
				(type default)
			)
			(layer "F.Fab")
		)
		(fp_line
			(start -0.67945 0.3048)
			(end -0.67945 -0.305054)
			(stroke
				(width 0.1)
				(type default)
			)
			(layer "F.Fab")
		)
		(fp_line
			(start -0.12065 -0.305054)
			(end -0.12065 -0.2794)
			(stroke
				(width 0.1)
				(type default)
			)
			(layer "F.Fab")
		)
		(fp_line
			(start -0.12065 -0.2794)
			(end 0.12065 -0.2794)
			(stroke
				(width 0.1)
				(type default)
			)
			(layer "F.Fab")
		)
		(fp_line
			(start -0.12065 0.2794)
			(end -0.12065 0.3048)
			(stroke
				(width 0.1)
				(type default)
			)
			(layer "F.Fab")
		)
		(fp_line
			(start -0.12065 0.3048)
			(end -0.67945 0.3048)
			(stroke
				(width 0.1)
				(type default)
			)
			(layer "F.Fab")
		)
		(fp_line
			(start 0.120396 0.2794)
			(end -0.12065 0.2794)
			(stroke
				(width 0.1)
				(type default)
			)
			(layer "F.Fab")
		)
		(fp_line
			(start 0.120396 0.3048)
			(end 0.120396 0.2794)
			(stroke
				(width 0.1)
				(type default)
			)
			(layer "F.Fab")
		)
		(fp_line
			(start 0.12065 -0.3048)
			(end 0.67945 -0.3048)
			(stroke
				(width 0.1)
				(type default)
			)
			(layer "F.Fab")
		)
		(fp_line
			(start 0.12065 -0.2794)
			(end 0.12065 -0.3048)
			(stroke
				(width 0.1)
				(type default)
			)
			(layer "F.Fab")
		)
		(fp_line
			(start 0.67945 -0.3048)
			(end 0.67945 0.3048)
			(stroke
				(width 0.1)
				(type default)
			)
			(layer "F.Fab")
		)
		(fp_line
			(start 0.67945 0.3048)
			(end 0.120396 0.3048)
			(stroke
				(width 0.1)
				(type default)
			)
			(layer "F.Fab")
		)
		(pad "1" smd circle
			(at -0.40005 0)
			(size 0 0)
			(layers "F.Cu" "F.Mask" "F.Paste")
			(net "P12V_SSD1_R")
		)
		(pad "2" smd circle
			(at 0.40005 0)
			(size 0 0)
			(layers "F.Cu" "F.Mask" "F.Paste")
			(net "P12V_SSD1_PG_G1")
		)
	)
	(footprint ""
		(layer "F.Cu")
		(at 280.759154 -166.55288)
		(property "Reference" "U30"
			(at -1.8034 -1.819148 0)
			(unlocked yes)
			(layer "F.SilkS")
			(effects
				(font
					(size 0.7874 0.5842)
					(thickness 0.1524)
				)
				(justify left)
			)
		)
		(property "Value" ""
			(at 0 0 0)
			(layer "F.Fab")
			(effects
				(font
					(size 1.27 1.27)
				)
			)
		)
		(duplicate_pad_numbers_are_jumpers no)
		(fp_line
			(start -1.684274 -1.074928)
			(end -0.381 -1.074928)
			(stroke
				(width 0.1524)
				(type default)
			)
			(layer "F.SilkS")
		)
		(fp_line
			(start -1.684274 1.074928)
			(end -1.684274 -1.074928)
			(stroke
				(width 0.1524)
				(type default)
			)
			(layer "F.SilkS")
		)
		(fp_line
			(start -0.381 -1.074928)
			(end 0 -0.625094)
			(stroke
				(width 0.1524)
				(type default)
			)
			(layer "F.SilkS")
		)
		(fp_line
			(start 0 -0.625094)
			(end 0.381 -1.074928)
			(stroke
				(width 0.1524)
				(type default)
			)
			(layer "F.SilkS")
		)
		(fp_line
			(start 0.381 -1.074928)
			(end 1.684274 -1.074928)
			(stroke
				(width 0.1524)
				(type default)
			)
			(layer "F.SilkS")
		)
		(fp_line
			(start 1.684274 -1.074928)
			(end 1.684274 1.074928)
			(stroke
				(width 0.1524)
				(type default)
			)
			(layer "F.SilkS")
		)
		(fp_line
			(start 1.684274 1.074928)
			(end -1.684274 1.074928)
			(stroke
				(width 0.1524)
				(type default)
			)
			(layer "F.SilkS")
		)
		(fp_poly
			(pts
				(xy -2.637282 -0.903986) (xy -2.637282 -0.395986) (xy -1.875282 -0.649986)
			)
			(stroke
				(width 0)
				(type default)
			)
			(fill yes)
			(layer "F.SilkS")
		)
		(fp_line
			(start -0.700024 -1.074928)
			(end -0.700024 1.074928)
			(stroke
				(width 0.1)
				(type default)
			)
			(layer "F.Fab")
		)
		(fp_line
			(start -0.700024 1.074928)
			(end 0.700024 1.074928)
			(stroke
				(width 0.1)
				(type default)
			)
			(layer "F.Fab")
		)
		(fp_line
			(start 0.700024 -1.074928)
			(end -0.700024 -1.074928)
			(stroke
				(width 0.1)
				(type default)
			)
			(layer "F.Fab")
		)
		(fp_line
			(start 0.700024 1.074928)
			(end 0.700024 -1.074928)
			(stroke
				(width 0.1)
				(type default)
			)
			(layer "F.Fab")
		)
		(fp_poly
			(pts
				(xy -2.637282 -0.903986) (xy -2.637282 -0.395986) (xy -1.875282 -0.649986)
			)
			(stroke
				(width 0)
				(type default)
			)
			(fill yes)
			(layer "F.Fab")
		)
		(pad "1" smd rect
			(at -1.100074 -0.649986 270)
			(size 0.4064 0.9144)
			(layers "F.Cu" "F.Mask" "F.Paste")
			(net "Net_8452")
		)
		(pad "2" smd rect
			(at -1.100074 0 270)
			(size 0.4064 0.9144)
			(layers "F.Cu" "F.Mask" "F.Paste")
			(net "RST_HP_NIC4_N")
		)
		(pad "3" smd rect
			(at -1.100074 0.649986 270)
			(size 0.4064 0.9144)
			(layers "F.Cu" "F.Mask" "F.Paste")
			(net "GND")
		)
		(pad "4" smd rect
			(at 1.100074 0.649986 270)
			(size 0.4064 0.9144)
			(layers "F.Cu" "F.Mask" "F.Paste")
			(net "RST_HP_NIC4_BUF_N")
		)
		(pad "5" smd rect
			(at 1.100074 -0.649986 270)
			(size 0.4064 0.9144)
			(layers "F.Cu" "F.Mask" "F.Paste")
			(net "P3V3_AUX")
		)
	)
	(footprint ""
		(layer "F.Cu")
		(at 28.856178 -32.848042 -90)
		(property "Reference" "R5867"
			(at 0 0 270)
			(layer "F.SilkS")
			(hide yes)
			(effects
				(font
					(size 1.27 1.27)
				)
			)
		)
		(property "Value" ""
			(at 0 0 270)
			(layer "F.Fab")
			(effects
				(font
					(size 1.27 1.27)
				)
			)
		)
		(duplicate_pad_numbers_are_jumpers no)
		(fp_line
			(start -0.7874 0.4064)
			(end -0.7874 -0.4064)
			(stroke
				(width 0.1524)
				(type default)
			)
			(layer "F.SilkS")
		)
		(fp_line
			(start 0.7874 0.4064)
			(end -0.7874 0.4064)
			(stroke
				(width 0.1524)
				(type default)
			)
			(layer "F.SilkS")
		)
		(fp_line
			(start -0.7874 -0.4064)
			(end 0.7874 -0.4064)
			(stroke
				(width 0.1524)
				(type default)
			)
			(layer "F.SilkS")
		)
		(fp_line
			(start 0.7874 -0.4064)
			(end 0.7874 0.4064)
			(stroke
				(width 0.1524)
				(type default)
			)
			(layer "F.SilkS")
		)
		(fp_line
			(start -0.67945 0.3048)
			(end -0.67945 -0.305054)
			(stroke
				(width 0.1)
				(type default)
			)
			(layer "F.Fab")
		)
		(fp_line
			(start -0.12065 0.3048)
			(end -0.67945 0.3048)
			(stroke
				(width 0.1)
				(type default)
			)
			(layer "F.Fab")
		)
		(fp_line
			(start 0.120396 0.3048)
			(end 0.120396 0.2794)
			(stroke
				(width 0.1)
				(type default)
			)
			(layer "F.Fab")
		)
		(fp_line
			(start 0.67945 0.3048)
			(end 0.120396 0.3048)
			(stroke
				(width 0.1)
				(type default)
			)
			(layer "F.Fab")
		)
		(fp_line
			(start -0.12065 0.2794)
			(end -0.12065 0.3048)
			(stroke
				(width 0.1)
				(type default)
			)
			(layer "F.Fab")
		)
		(fp_line
			(start 0.120396 0.2794)
			(end -0.12065 0.2794)
			(stroke
				(width 0.1)
				(type default)
			)
			(layer "F.Fab")
		)
		(fp_line
			(start -0.12065 -0.2794)
			(end 0.12065 -0.2794)
			(stroke
				(width 0.1)
				(type default)
			)
			(layer "F.Fab")
		)
		(fp_line
			(start 0.12065 -0.2794)
			(end 0.12065 -0.3048)
			(stroke
				(width 0.1)
				(type default)
			)
			(layer "F.Fab")
		)
		(fp_line
			(start 0.12065 -0.3048)
			(end 0.67945 -0.3048)
			(stroke
				(width 0.1)
				(type default)
			)
			(layer "F.Fab")
		)
		(fp_line
			(start 0.67945 -0.3048)
			(end 0.67945 0.3048)
			(stroke
				(width 0.1)
				(type default)
			)
			(layer "F.Fab")
		)
		(fp_line
			(start -0.67945 -0.305054)
			(end -0.12065 -0.305054)
			(stroke
				(width 0.1)
				(type default)
			)
			(layer "F.Fab")
		)
		(fp_line
			(start -0.12065 -0.305054)
			(end -0.12065 -0.2794)
			(stroke
				(width 0.1)
				(type default)
			)
			(layer "F.Fab")
		)
		(pad "1" smd circle
			(at -0.40005 0 270)
			(size 0 0)
			(layers "F.Cu" "F.Mask" "F.Paste")
			(net "SSD1_AUX_P3V3_EN_R")
		)
		(pad "2" smd circle
			(at 0.40005 0 270)
			(size 0 0)
			(layers "F.Cu" "F.Mask" "F.Paste")
			(net "P3V3_SSD1_CO_EN")
		)
	)
	(footprint ""
		(layer "F.Cu")
		(at 241.756692 -92.244164 90)
		(property "Reference" "Y5"
			(at 2.140966 -0.761492 0)
			(unlocked yes)
			(layer "F.SilkS")
			(effects
				(font
					(size 0.7874 0.5842)
					(thickness 0.1524)
				)
				(justify left)
			)
		)
		(property "Value" ""
			(at 0 0 90)
			(layer "F.Fab")
			(effects
				(font
					(size 1.27 1.27)
				)
			)
		)
		(duplicate_pad_numbers_are_jumpers no)
		(fp_line
			(start 1.2446 -1.4986)
			(end -1.2446 -1.4986)
			(stroke
				(width 0.1524)
				(type default)
			)
			(layer "F.SilkS")
		)
		(fp_line
			(start -1.2446 -1.4986)
			(end -1.2446 1.4986)
			(stroke
				(width 0.1524)
				(type default)
			)
			(layer "F.SilkS")
		)
		(fp_line
			(start 1.2446 1.4986)
			(end 1.2446 -1.4986)
			(stroke
				(width 0.1524)
				(type default)
			)
			(layer "F.SilkS")
		)
		(fp_line
			(start -1.2446 1.4986)
			(end 1.2446 1.4986)
			(stroke
				(width 0.1524)
				(type default)
			)
			(layer "F.SilkS")
		)
		(fp_poly
			(pts
				(xy -2.4638 -1.357884) (xy -2.4638 -0.341884) (xy -1.4478 -0.849884)
			)
			(stroke
				(width 0)
				(type default)
			)
			(fill yes)
			(layer "F.SilkS")
		)
		(fp_line
			(start 1.050036 -1.299972)
			(end -1.050036 -1.299972)
			(stroke
				(width 0.1)
				(type default)
			)
			(layer "F.Fab")
		)
		(fp_line
			(start -1.050036 -1.299972)
			(end -1.050036 1.299972)
			(stroke
				(width 0.1)
				(type default)
			)
			(layer "F.Fab")
		)
		(fp_line
			(start 1.050036 1.299972)
			(end 1.050036 -1.299972)
			(stroke
				(width 0.1)
				(type default)
			)
			(layer "F.Fab")
		)
		(fp_line
			(start -1.050036 1.299972)
			(end 1.050036 1.299972)
			(stroke
				(width 0.1)
				(type default)
			)
			(layer "F.Fab")
		)
		(fp_poly
			(pts
				(xy -2.4638 -1.357884) (xy -2.4638 -0.341884) (xy -1.4478 -0.849884)
			)
			(stroke
				(width 0)
				(type default)
			)
			(fill yes)
			(layer "F.Fab")
		)
		(pad "1" smd rect
			(at -0.649986 -0.849884 270)
			(size 0.9144 1.016)
			(layers "F.Cu" "F.Mask" "F.Paste")
			(net "PEX_USB_HUB_XIN")
		)
		(pad "2" smd rect
			(at -0.649986 0.849884 270)
			(size 0.9144 1.016)
			(layers "F.Cu" "F.Mask" "F.Paste")
			(net "GND")
		)
		(pad "3" smd rect
			(at 0.649986 0.849884 270)
			(size 0.9144 1.016)
			(layers "F.Cu" "F.Mask" "F.Paste")
			(net "PEX_USB_HUB_XOUT_R")
		)
		(pad "4" smd rect
			(at 0.649986 -0.849884 270)
			(size 0.9144 1.016)
			(layers "F.Cu" "F.Mask" "F.Paste")
			(net "GND")
		)
	)
	(footprint ""
		(layer "F.Cu")
		(at 135.802878 -225.49993 180)
		(property "Reference" "U320"
			(at 1.589278 -8.367268 0)
			(unlocked yes)
			(layer "F.SilkS")
			(effects
				(font
					(size 0.7874 0.5842)
					(thickness 0.1524)
				)
				(justify left)
			)
		)
		(property "Value" ""
			(at 0 0 180)
			(layer "F.Fab")
			(effects
				(font
					(size 1.27 1.27)
				)
			)
		)
		(duplicate_pad_numbers_are_jumpers no)
		(fp_line
			(start 3.795014 5.2451)
			(end 3.795014 -5.2451)
			(stroke
				(width 0.1524)
				(type default)
			)
			(layer "F.SilkS")
		)
		(fp_line
			(start 3.795014 -5.2451)
			(end 1.9431 -5.2451)
			(stroke
				(width 0.1524)
				(type default)
			)
			(layer "F.SilkS")
		)
		(fp_line
			(start 1.9431 -5.2451)
			(end 0 -3.302)
			(stroke
				(width 0.1524)
				(type default)
			)
			(layer "F.SilkS")
		)
		(fp_line
			(start 0 -3.302)
			(end -1.9431 -5.2451)
			(stroke
				(width 0.1524)
				(type default)
			)
			(layer "F.SilkS")
		)
		(fp_line
			(start -1.9431 -5.2451)
			(end -3.795014 -5.2451)
			(stroke
				(width 0.1524)
				(type default)
			)
			(layer "F.SilkS")
		)
		(fp_line
			(start -3.795014 5.2451)
			(end 3.795014 5.2451)
			(stroke
				(width 0.1524)
				(type default)
			)
			(layer "F.SilkS")
		)
		(fp_line
			(start -3.795014 -5.2451)
			(end -3.795014 5.2451)
			(stroke
				(width 0.1524)
				(type default)
			)
			(layer "F.SilkS")
		)
		(fp_poly
			(pts
				(xy -5.976366 -4.445) (xy -7.239 -3.81381) (xy -7.239 -5.07619)
			)
			(stroke
				(width 0)
				(type default)
			)
			(fill yes)
			(layer "F.SilkS")
		)
		(fp_line
			(start 3.795014 5.2451)
			(end 3.795014 -5.2451)
			(stroke
				(width 0.1)
				(type default)
			)
			(layer "F.Fab")
		)
		(fp_line
			(start 3.795014 -5.2451)
			(end -3.795014 -5.2451)
			(stroke
				(width 0.1)
				(type default)
			)
			(layer "F.Fab")
		)
		(fp_line
			(start -3.795014 5.2451)
			(end 3.795014 5.2451)
			(stroke
				(width 0.1)
				(type default)
			)
			(layer "F.Fab")
		)
		(fp_line
			(start -3.795014 -5.2451)
			(end -3.795014 5.2451)
			(stroke
				(width 0.1)
				(type default)
			)
			(layer "F.Fab")
		)
		(fp_poly
			(pts
				(xy -5.976366 -4.445) (xy -7.239 -3.81381) (xy -7.239 -5.07619)
			)
			(stroke
				(width 0)
				(type default)
			)
			(fill yes)
			(layer "F.Fab")
		)
		(pad "1" smd rect
			(at -4.880102 -4.445 90)
			(size 0.8128 1.905)
			(layers "F.Cu" "F.Mask" "F.Paste")
			(net "SPI_PEX1_SDIO3_R1")
		)
		(pad "2" smd rect
			(at -4.880102 -3.175 90)
			(size 0.8128 1.905)
			(layers "F.Cu" "F.Mask" "F.Paste")
			(net "P1V8_PEX")
		)
		(pad "3" smd rect
			(at -4.880102 -1.905 90)
			(size 0.8128 1.905)
			(layers "F.Cu" "F.Mask" "F.Paste")
			(net "SPI_PEX1_RST_R_N")
		)
		(pad "4" smd rect
			(at -4.880102 -0.635 90)
			(size 0.8128 1.905)
			(layers "F.Cu" "F.Mask" "F.Paste")
			(net "Net_9007")
		)
		(pad "5" smd rect
			(at -4.880102 0.635 90)
			(size 0.8128 1.905)
			(layers "F.Cu" "F.Mask" "F.Paste")
			(net "Net_9006")
		)
		(pad "6" smd rect
			(at -4.880102 1.905 90)
			(size 0.8128 1.905)
			(layers "F.Cu" "F.Mask" "F.Paste")
			(net "Net_9005")
		)
		(pad "7" smd rect
			(at -4.880102 3.175 90)
			(size 0.8128 1.905)
			(layers "F.Cu" "F.Mask" "F.Paste")
			(net "SPI_PEX1_CS_MUX_R_N")
		)
		(pad "8" smd rect
			(at -4.880102 4.445 90)
			(size 0.8128 1.905)
			(layers "F.Cu" "F.Mask" "F.Paste")
			(net "SPI_PEX1_SDIO1_MUX_R")
		)
		(pad "9" smd rect
			(at 4.880102 4.445 270)
			(size 0.8128 1.905)
			(layers "F.Cu" "F.Mask" "F.Paste")
			(net "SPI_PEX1_SDIO2_R1")
		)
		(pad "10" smd rect
			(at 4.880102 3.175 270)
			(size 0.8128 1.905)
			(layers "F.Cu" "F.Mask" "F.Paste")
			(net "GND")
		)
		(pad "11" smd rect
			(at 4.880102 1.905 270)
			(size 0.8128 1.905)
			(layers "F.Cu" "F.Mask" "F.Paste")
			(net "Net_9004")
		)
		(pad "12" smd rect
			(at 4.880102 0.635 270)
			(size 0.8128 1.905)
			(layers "F.Cu" "F.Mask" "F.Paste")
			(net "Net_9003")
		)
		(pad "13" smd rect
			(at 4.880102 -0.635 270)
			(size 0.8128 1.905)
			(layers "F.Cu" "F.Mask" "F.Paste")
			(net "Net_9002")
		)
		(pad "14" smd rect
			(at 4.880102 -1.905 270)
			(size 0.8128 1.905)
			(layers "F.Cu" "F.Mask" "F.Paste")
			(net "Net_9001")
		)
		(pad "15" smd rect
			(at 4.880102 -3.175 270)
			(size 0.8128 1.905)
			(layers "F.Cu" "F.Mask" "F.Paste")
			(net "SPI_PEX1_SDIO0_MUX_R")
		)
		(pad "16" smd rect
			(at 4.880102 -4.445 270)
			(size 0.8128 1.905)
			(layers "F.Cu" "F.Mask" "F.Paste")
			(net "SPI_PEX1_CLK_MUX_R")
		)
	)
	(footprint ""
		(layer "F.Cu")
		(at 241.5794 -213.3854 -90)
		(property "Reference" "C4435"
			(at 0 0 270)
			(layer "F.SilkS")
			(hide yes)
			(effects
				(font
					(size 1.27 1.27)
				)
			)
		)
		(property "Value" ""
			(at 0 0 270)
			(layer "F.Fab")
			(effects
				(font
					(size 1.27 1.27)
				)
			)
		)
		(duplicate_pad_numbers_are_jumpers no)
		(fp_line
			(start -0.7874 0.4064)
			(end -0.7874 -0.4064)
			(stroke
				(width 0.1524)
				(type default)
			)
			(layer "F.SilkS")
		)
		(fp_line
			(start 0.7874 0.4064)
			(end -0.7874 0.4064)
			(stroke
				(width 0.1524)
				(type default)
			)
			(layer "F.SilkS")
		)
		(fp_line
			(start -0.7874 -0.4064)
			(end 0.7874 -0.4064)
			(stroke
				(width 0.1524)
				(type default)
			)
			(layer "F.SilkS")
		)
		(fp_line
			(start 0.7874 -0.4064)
			(end 0.7874 0.4064)
			(stroke
				(width 0.1524)
				(type default)
			)
			(layer "F.SilkS")
		)
		(fp_line
			(start -0.67945 0.3048)
			(end -0.67945 -0.305054)
			(stroke
				(width 0.1)
				(type default)
			)
			(layer "F.Fab")
		)
		(fp_line
			(start -0.12065 0.3048)
			(end -0.67945 0.3048)
			(stroke
				(width 0.1)
				(type default)
			)
			(layer "F.Fab")
		)
		(fp_line
			(start 0.120396 0.3048)
			(end 0.120396 0.2794)
			(stroke
				(width 0.1)
				(type default)
			)
			(layer "F.Fab")
		)
		(fp_line
			(start 0.67945 0.3048)
			(end 0.120396 0.3048)
			(stroke
				(width 0.1)
				(type default)
			)
			(layer "F.Fab")
		)
		(fp_line
			(start -0.12065 0.2794)
			(end -0.12065 0.3048)
			(stroke
				(width 0.1)
				(type default)
			)
			(layer "F.Fab")
		)
		(fp_line
			(start 0.120396 0.2794)
			(end -0.12065 0.2794)
			(stroke
				(width 0.1)
				(type default)
			)
			(layer "F.Fab")
		)
		(fp_line
			(start -0.12065 -0.2794)
			(end 0.12065 -0.2794)
			(stroke
				(width 0.1)
				(type default)
			)
			(layer "F.Fab")
		)
		(fp_line
			(start 0.12065 -0.2794)
			(end 0.12065 -0.3048)
			(stroke
				(width 0.1)
				(type default)
			)
			(layer "F.Fab")
		)
		(fp_line
			(start 0.12065 -0.3048)
			(end 0.67945 -0.3048)
			(stroke
				(width 0.1)
				(type default)
			)
			(layer "F.Fab")
		)
		(fp_line
			(start 0.67945 -0.3048)
			(end 0.67945 0.3048)
			(stroke
				(width 0.1)
				(type default)
			)
			(layer "F.Fab")
		)
		(fp_line
			(start -0.67945 -0.305054)
			(end -0.12065 -0.305054)
			(stroke
				(width 0.1)
				(type default)
			)
			(layer "F.Fab")
		)
		(fp_line
			(start -0.12065 -0.305054)
			(end -0.12065 -0.2794)
			(stroke
				(width 0.1)
				(type default)
			)
			(layer "F.Fab")
		)
		(pad "1" smd circle
			(at -0.40005 0 270)
			(size 0 0)
			(layers "F.Cu" "F.Mask" "F.Paste")
			(net "P1V8_PLL0_PEX1_SCALED")
		)
		(pad "2" smd circle
			(at 0.40005 0 270)
			(size 0 0)
			(layers "F.Cu" "F.Mask" "F.Paste")
			(net "GND")
		)
	)
	(footprint ""
		(layer "F.Cu")
		(at 275.26869 -409.736036 90)
		(property "Reference" "R1818"
			(at 0 0 90)
			(layer "F.SilkS")
			(hide yes)
			(effects
				(font
					(size 1.27 1.27)
				)
			)
		)
		(property "Value" ""
			(at 0 0 90)
			(layer "F.Fab")
			(effects
				(font
					(size 1.27 1.27)
				)
			)
		)
		(duplicate_pad_numbers_are_jumpers no)
		(fp_line
			(start 0.7874 -0.4064)
			(end 0.7874 0.4064)
			(stroke
				(width 0.1524)
				(type default)
			)
			(layer "F.SilkS")
		)
		(fp_line
			(start -0.7874 -0.4064)
			(end 0.7874 -0.4064)
			(stroke
				(width 0.1524)
				(type default)
			)
			(layer "F.SilkS")
		)
		(fp_line
			(start 0.7874 0.4064)
			(end -0.7874 0.4064)
			(stroke
				(width 0.1524)
				(type default)
			)
			(layer "F.SilkS")
		)
		(fp_line
			(start -0.7874 0.4064)
			(end -0.7874 -0.4064)
			(stroke
				(width 0.1524)
				(type default)
			)
			(layer "F.SilkS")
		)
		(fp_line
			(start -0.12065 -0.305054)
			(end -0.12065 -0.2794)
			(stroke
				(width 0.1)
				(type default)
			)
			(layer "F.Fab")
		)
		(fp_line
			(start -0.67945 -0.305054)
			(end -0.12065 -0.305054)
			(stroke
				(width 0.1)
				(type default)
			)
			(layer "F.Fab")
		)
		(fp_line
			(start 0.67945 -0.3048)
			(end 0.67945 0.3048)
			(stroke
				(width 0.1)
				(type default)
			)
			(layer "F.Fab")
		)
		(fp_line
			(start 0.12065 -0.3048)
			(end 0.67945 -0.3048)
			(stroke
				(width 0.1)
				(type default)
			)
			(layer "F.Fab")
		)
		(fp_line
			(start 0.12065 -0.2794)
			(end 0.12065 -0.3048)
			(stroke
				(width 0.1)
				(type default)
			)
			(layer "F.Fab")
		)
		(fp_line
			(start -0.12065 -0.2794)
			(end 0.12065 -0.2794)
			(stroke
				(width 0.1)
				(type default)
			)
			(layer "F.Fab")
		)
		(fp_line
			(start 0.120396 0.2794)
			(end -0.12065 0.2794)
			(stroke
				(width 0.1)
				(type default)
			)
			(layer "F.Fab")
		)
		(fp_line
			(start -0.12065 0.2794)
			(end -0.12065 0.3048)
			(stroke
				(width 0.1)
				(type default)
			)
			(layer "F.Fab")
		)
		(fp_line
			(start 0.67945 0.3048)
			(end 0.120396 0.3048)
			(stroke
				(width 0.1)
				(type default)
			)
			(layer "F.Fab")
		)
		(fp_line
			(start 0.120396 0.3048)
			(end 0.120396 0.2794)
			(stroke
				(width 0.1)
				(type default)
			)
			(layer "F.Fab")
		)
		(fp_line
			(start -0.12065 0.3048)
			(end -0.67945 0.3048)
			(stroke
				(width 0.1)
				(type default)
			)
			(layer "F.Fab")
		)
		(fp_line
			(start -0.67945 0.3048)
			(end -0.67945 -0.305054)
			(stroke
				(width 0.1)
				(type default)
			)
			(layer "F.Fab")
		)
		(pad "1" smd circle
			(at -0.40005 0 90)
			(size 0 0)
			(layers "F.Cu" "F.Mask" "F.Paste")
			(net "RST_MB_BMC_BUF_N")
		)
		(pad "2" smd circle
			(at 0.40005 0 90)
			(size 0 0)
			(layers "F.Cu" "F.Mask" "F.Paste")
			(net "RST_MB_BMC_BUF_R_N")
		)
	)
	(footprint ""
		(layer "F.Cu")
		(at 231.844596 -275.503386)
		(property "Reference" "R782"
			(at 0 0 0)
			(layer "F.SilkS")
			(hide yes)
			(effects
				(font
					(size 1.27 1.27)
				)
			)
		)
		(property "Value" ""
			(at 0 0 0)
			(layer "F.Fab")
			(effects
				(font
					(size 1.27 1.27)
				)
			)
		)
		(duplicate_pad_numbers_are_jumpers no)
		(fp_line
			(start -0.7874 -0.4064)
			(end 0.7874 -0.4064)
			(stroke
				(width 0.1524)
				(type default)
			)
			(layer "F.SilkS")
		)
		(fp_line
			(start -0.7874 0.4064)
			(end -0.7874 -0.4064)
			(stroke
				(width 0.1524)
				(type default)
			)
			(layer "F.SilkS")
		)
		(fp_line
			(start 0.7874 -0.4064)
			(end 0.7874 0.4064)
			(stroke
				(width 0.1524)
				(type default)
			)
			(layer "F.SilkS")
		)
		(fp_line
			(start 0.7874 0.4064)
			(end -0.7874 0.4064)
			(stroke
				(width 0.1524)
				(type default)
			)
			(layer "F.SilkS")
		)
		(fp_line
			(start -0.67945 -0.305054)
			(end -0.12065 -0.305054)
			(stroke
				(width 0.1)
				(type default)
			)
			(layer "F.Fab")
		)
		(fp_line
			(start -0.67945 0.3048)
			(end -0.67945 -0.305054)
			(stroke
				(width 0.1)
				(type default)
			)
			(layer "F.Fab")
		)
		(fp_line
			(start -0.12065 -0.305054)
			(end -0.12065 -0.2794)
			(stroke
				(width 0.1)
				(type default)
			)
			(layer "F.Fab")
		)
		(fp_line
			(start -0.12065 -0.2794)
			(end 0.12065 -0.2794)
			(stroke
				(width 0.1)
				(type default)
			)
			(layer "F.Fab")
		)
		(fp_line
			(start -0.12065 0.2794)
			(end -0.12065 0.3048)
			(stroke
				(width 0.1)
				(type default)
			)
			(layer "F.Fab")
		)
		(fp_line
			(start -0.12065 0.3048)
			(end -0.67945 0.3048)
			(stroke
				(width 0.1)
				(type default)
			)
			(layer "F.Fab")
		)
		(fp_line
			(start 0.120396 0.2794)
			(end -0.12065 0.2794)
			(stroke
				(width 0.1)
				(type default)
			)
			(layer "F.Fab")
		)
		(fp_line
			(start 0.120396 0.3048)
			(end 0.120396 0.2794)
			(stroke
				(width 0.1)
				(type default)
			)
			(layer "F.Fab")
		)
		(fp_line
			(start 0.12065 -0.3048)
			(end 0.67945 -0.3048)
			(stroke
				(width 0.1)
				(type default)
			)
			(layer "F.Fab")
		)
		(fp_line
			(start 0.12065 -0.2794)
			(end 0.12065 -0.3048)
			(stroke
				(width 0.1)
				(type default)
			)
			(layer "F.Fab")
		)
		(fp_line
			(start 0.67945 -0.3048)
			(end 0.67945 0.3048)
			(stroke
				(width 0.1)
				(type default)
			)
			(layer "F.Fab")
		)
		(fp_line
			(start 0.67945 0.3048)
			(end 0.120396 0.3048)
			(stroke
				(width 0.1)
				(type default)
			)
			(layer "F.Fab")
		)
		(pad "1" smd circle
			(at -0.40005 0)
			(size 0 0)
			(layers "F.Cu" "F.Mask" "F.Paste")
			(net "PEX1_P1V25_ADC_A0")
		)
		(pad "2" smd circle
			(at 0.40005 0)
			(size 0 0)
			(layers "F.Cu" "F.Mask" "F.Paste")
			(net "P3V3_AUX")
		)
	)
	(footprint ""
		(layer "F.Cu")
		(at 206.623158 -87.977472)
		(property "Reference" "R4267"
			(at 0 0 0)
			(layer "F.SilkS")
			(hide yes)
			(effects
				(font
					(size 1.27 1.27)
				)
			)
		)
		(property "Value" ""
			(at 0 0 0)
			(layer "F.Fab")
			(effects
				(font
					(size 1.27 1.27)
				)
			)
		)
		(duplicate_pad_numbers_are_jumpers no)
		(fp_line
			(start -0.7874 -0.4064)
			(end 0.7874 -0.4064)
			(stroke
				(width 0.1524)
				(type default)
			)
			(layer "F.SilkS")
		)
		(fp_line
			(start -0.7874 0.4064)
			(end -0.7874 -0.4064)
			(stroke
				(width 0.1524)
				(type default)
			)
			(layer "F.SilkS")
		)
		(fp_line
			(start 0.7874 -0.4064)
			(end 0.7874 0.4064)
			(stroke
				(width 0.1524)
				(type default)
			)
			(layer "F.SilkS")
		)
		(fp_line
			(start 0.7874 0.4064)
			(end -0.7874 0.4064)
			(stroke
				(width 0.1524)
				(type default)
			)
			(layer "F.SilkS")
		)
		(fp_line
			(start -0.67945 -0.305054)
			(end -0.12065 -0.305054)
			(stroke
				(width 0.1)
				(type default)
			)
			(layer "F.Fab")
		)
		(fp_line
			(start -0.67945 0.3048)
			(end -0.67945 -0.305054)
			(stroke
				(width 0.1)
				(type default)
			)
			(layer "F.Fab")
		)
		(fp_line
			(start -0.12065 -0.305054)
			(end -0.12065 -0.2794)
			(stroke
				(width 0.1)
				(type default)
			)
			(layer "F.Fab")
		)
		(fp_line
			(start -0.12065 -0.2794)
			(end 0.12065 -0.2794)
			(stroke
				(width 0.1)
				(type default)
			)
			(layer "F.Fab")
		)
		(fp_line
			(start -0.12065 0.2794)
			(end -0.12065 0.3048)
			(stroke
				(width 0.1)
				(type default)
			)
			(layer "F.Fab")
		)
		(fp_line
			(start -0.12065 0.3048)
			(end -0.67945 0.3048)
			(stroke
				(width 0.1)
				(type default)
			)
			(layer "F.Fab")
		)
		(fp_line
			(start 0.120396 0.2794)
			(end -0.12065 0.2794)
			(stroke
				(width 0.1)
				(type default)
			)
			(layer "F.Fab")
		)
		(fp_line
			(start 0.120396 0.3048)
			(end 0.120396 0.2794)
			(stroke
				(width 0.1)
				(type default)
			)
			(layer "F.Fab")
		)
		(fp_line
			(start 0.12065 -0.3048)
			(end 0.67945 -0.3048)
			(stroke
				(width 0.1)
				(type default)
			)
			(layer "F.Fab")
		)
		(fp_line
			(start 0.12065 -0.2794)
			(end 0.12065 -0.3048)
			(stroke
				(width 0.1)
				(type default)
			)
			(layer "F.Fab")
		)
		(fp_line
			(start 0.67945 -0.3048)
			(end 0.67945 0.3048)
			(stroke
				(width 0.1)
				(type default)
			)
			(layer "F.Fab")
		)
		(fp_line
			(start 0.67945 0.3048)
			(end 0.120396 0.3048)
			(stroke
				(width 0.1)
				(type default)
			)
			(layer "F.Fab")
		)
		(pad "1" smd circle
			(at -0.40005 0)
			(size 0 0)
			(layers "F.Cu" "F.Mask" "F.Paste")
			(net "SSD_LED_IOEXP_A1")
		)
		(pad "2" smd circle
			(at 0.40005 0)
			(size 0 0)
			(layers "F.Cu" "F.Mask" "F.Paste")
			(net "GND")
		)
	)
	(footprint ""
		(layer "F.Cu")
		(at 198.947786 -40.037258 90)
		(property "Reference" "U370"
			(at 0.399542 2.373884 90)
			(unlocked yes)
			(layer "F.SilkS")
			(effects
				(font
					(size 0.7874 0.5842)
					(thickness 0.1524)
				)
			)
		)
		(property "Value" ""
			(at 0 0 90)
			(layer "F.Fab")
			(effects
				(font
					(size 1.27 1.27)
				)
			)
		)
		(duplicate_pad_numbers_are_jumpers no)
		(fp_line
			(start -1.949958 -1.610106)
			(end 1.949958 -1.610106)
			(stroke
				(width 0.1524)
				(type default)
			)
			(layer "F.SilkS")
		)
		(fp_line
			(start 1.949958 -1.560068)
			(end 1.949958 1.610106)
			(stroke
				(width 0.1524)
				(type default)
			)
			(layer "F.SilkS")
		)
		(fp_line
			(start 1.949958 1.610106)
			(end -1.949958 1.610106)
			(stroke
				(width 0.1524)
				(type default)
			)
			(layer "F.SilkS")
		)
		(fp_line
			(start -1.949958 1.610106)
			(end -1.949958 -1.610106)
			(stroke
				(width 0.1524)
				(type default)
			)
			(layer "F.SilkS")
		)
		(fp_line
			(start 0.750062 -1.560068)
			(end 0.750062 1.560068)
			(stroke
				(width 0.1)
				(type default)
			)
			(layer "F.Fab")
		)
		(fp_line
			(start -0.750062 -1.560068)
			(end 0.750062 -1.560068)
			(stroke
				(width 0.1)
				(type default)
			)
			(layer "F.Fab")
		)
		(fp_line
			(start 0.750062 1.560068)
			(end -0.750062 1.560068)
			(stroke
				(width 0.1)
				(type default)
			)
			(layer "F.Fab")
		)
		(fp_line
			(start -0.750062 1.560068)
			(end -0.750062 -1.560068)
			(stroke
				(width 0.1)
				(type default)
			)
			(layer "F.Fab")
		)
		(pad "D" smd rect
			(at 1.100074 0)
			(size 1.016 1.4224)
			(layers "F.Cu" "F.Mask" "F.Paste")
			(net "SSD7_AUX_P3V3_EN")
		)
		(pad "G" smd rect
			(at -1.100074 -0.94996)
			(size 1.016 1.4224)
			(layers "F.Cu" "F.Mask" "F.Paste")
			(net "PRSNT_SSD7_R1_N")
		)
		(pad "S" smd rect
			(at -1.100074 0.94996)
			(size 1.016 1.4224)
			(layers "F.Cu" "F.Mask" "F.Paste")
			(net "GND")
		)
	)
	(footprint ""
		(layer "F.Cu")
		(at 262.915146 -59.546236 90)
		(property "Reference" "C2895"
			(at 0 0 90)
			(layer "F.SilkS")
			(hide yes)
			(effects
				(font
					(size 1.27 1.27)
				)
			)
		)
		(property "Value" ""
			(at 0 0 90)
			(layer "F.Fab")
			(effects
				(font
					(size 1.27 1.27)
				)
			)
		)
		(duplicate_pad_numbers_are_jumpers no)
		(fp_line
			(start 0.7874 -0.4064)
			(end 0.7874 0.4064)
			(stroke
				(width 0.1524)
				(type default)
			)
			(layer "F.SilkS")
		)
		(fp_line
			(start -0.7874 -0.4064)
			(end 0.7874 -0.4064)
			(stroke
				(width 0.1524)
				(type default)
			)
			(layer "F.SilkS")
		)
		(fp_line
			(start 0.7874 0.4064)
			(end -0.7874 0.4064)
			(stroke
				(width 0.1524)
				(type default)
			)
			(layer "F.SilkS")
		)
		(fp_line
			(start -0.7874 0.4064)
			(end -0.7874 -0.4064)
			(stroke
				(width 0.1524)
				(type default)
			)
			(layer "F.SilkS")
		)
		(fp_line
			(start -0.12065 -0.305054)
			(end -0.12065 -0.2794)
			(stroke
				(width 0.1)
				(type default)
			)
			(layer "F.Fab")
		)
		(fp_line
			(start -0.67945 -0.305054)
			(end -0.12065 -0.305054)
			(stroke
				(width 0.1)
				(type default)
			)
			(layer "F.Fab")
		)
		(fp_line
			(start 0.67945 -0.3048)
			(end 0.67945 0.3048)
			(stroke
				(width 0.1)
				(type default)
			)
			(layer "F.Fab")
		)
		(fp_line
			(start 0.12065 -0.3048)
			(end 0.67945 -0.3048)
			(stroke
				(width 0.1)
				(type default)
			)
			(layer "F.Fab")
		)
		(fp_line
			(start 0.12065 -0.2794)
			(end 0.12065 -0.3048)
			(stroke
				(width 0.1)
				(type default)
			)
			(layer "F.Fab")
		)
		(fp_line
			(start -0.12065 -0.2794)
			(end 0.12065 -0.2794)
			(stroke
				(width 0.1)
				(type default)
			)
			(layer "F.Fab")
		)
		(fp_line
			(start 0.120396 0.2794)
			(end -0.12065 0.2794)
			(stroke
				(width 0.1)
				(type default)
			)
			(layer "F.Fab")
		)
		(fp_line
			(start -0.12065 0.2794)
			(end -0.12065 0.3048)
			(stroke
				(width 0.1)
				(type default)
			)
			(layer "F.Fab")
		)
		(fp_line
			(start 0.67945 0.3048)
			(end 0.120396 0.3048)
			(stroke
				(width 0.1)
				(type default)
			)
			(layer "F.Fab")
		)
		(fp_line
			(start 0.120396 0.3048)
			(end 0.120396 0.2794)
			(stroke
				(width 0.1)
				(type default)
			)
			(layer "F.Fab")
		)
		(fp_line
			(start -0.12065 0.3048)
			(end -0.67945 0.3048)
			(stroke
				(width 0.1)
				(type default)
			)
			(layer "F.Fab")
		)
		(fp_line
			(start -0.67945 0.3048)
			(end -0.67945 -0.305054)
			(stroke
				(width 0.1)
				(type default)
			)
			(layer "F.Fab")
		)
		(pad "1" smd circle
			(at -0.40005 0 90)
			(size 0 0)
			(layers "F.Cu" "F.Mask" "F.Paste")
			(net "SSD9_AUX_P3V3_EN_R")
		)
		(pad "2" smd circle
			(at 0.40005 0 90)
			(size 0 0)
			(layers "F.Cu" "F.Mask" "F.Paste")
			(net "GND")
		)
	)
	(footprint ""
		(layer "F.Cu")
		(at 12.960096 -174.872142)
		(property "Reference" "PC22"
			(at 0 0 0)
			(layer "F.SilkS")
			(hide yes)
			(effects
				(font
					(size 1.27 1.27)
				)
			)
		)
		(property "Value" ""
			(at 0 0 0)
			(layer "F.Fab")
			(effects
				(font
					(size 1.27 1.27)
				)
			)
		)
		(duplicate_pad_numbers_are_jumpers no)
		(fp_line
			(start -0.7874 -0.4064)
			(end 0.7874 -0.4064)
			(stroke
				(width 0.1524)
				(type default)
			)
			(layer "F.SilkS")
		)
		(fp_line
			(start -0.7874 0.4064)
			(end -0.7874 -0.4064)
			(stroke
				(width 0.1524)
				(type default)
			)
			(layer "F.SilkS")
		)
		(fp_line
			(start 0.7874 -0.4064)
			(end 0.7874 0.4064)
			(stroke
				(width 0.1524)
				(type default)
			)
			(layer "F.SilkS")
		)
		(fp_line
			(start 0.7874 0.4064)
			(end -0.7874 0.4064)
			(stroke
				(width 0.1524)
				(type default)
			)
			(layer "F.SilkS")
		)
		(fp_line
			(start -0.67945 -0.305054)
			(end -0.12065 -0.305054)
			(stroke
				(width 0.1)
				(type default)
			)
			(layer "F.Fab")
		)
		(fp_line
			(start -0.67945 0.3048)
			(end -0.67945 -0.305054)
			(stroke
				(width 0.1)
				(type default)
			)
			(layer "F.Fab")
		)
		(fp_line
			(start -0.12065 -0.305054)
			(end -0.12065 -0.2794)
			(stroke
				(width 0.1)
				(type default)
			)
			(layer "F.Fab")
		)
		(fp_line
			(start -0.12065 -0.2794)
			(end 0.12065 -0.2794)
			(stroke
				(width 0.1)
				(type default)
			)
			(layer "F.Fab")
		)
		(fp_line
			(start -0.12065 0.2794)
			(end -0.12065 0.3048)
			(stroke
				(width 0.1)
				(type default)
			)
			(layer "F.Fab")
		)
		(fp_line
			(start -0.12065 0.3048)
			(end -0.67945 0.3048)
			(stroke
				(width 0.1)
				(type default)
			)
			(layer "F.Fab")
		)
		(fp_line
			(start 0.120396 0.2794)
			(end -0.12065 0.2794)
			(stroke
				(width 0.1)
				(type default)
			)
			(layer "F.Fab")
		)
		(fp_line
			(start 0.120396 0.3048)
			(end 0.120396 0.2794)
			(stroke
				(width 0.1)
				(type default)
			)
			(layer "F.Fab")
		)
		(fp_line
			(start 0.12065 -0.3048)
			(end 0.67945 -0.3048)
			(stroke
				(width 0.1)
				(type default)
			)
			(layer "F.Fab")
		)
		(fp_line
			(start 0.12065 -0.2794)
			(end 0.12065 -0.3048)
			(stroke
				(width 0.1)
				(type default)
			)
			(layer "F.Fab")
		)
		(fp_line
			(start 0.67945 -0.3048)
			(end 0.67945 0.3048)
			(stroke
				(width 0.1)
				(type default)
			)
			(layer "F.Fab")
		)
		(fp_line
			(start 0.67945 0.3048)
			(end 0.120396 0.3048)
			(stroke
				(width 0.1)
				(type default)
			)
			(layer "F.Fab")
		)
		(pad "1" smd circle
			(at -0.40005 0)
			(size 0 0)
			(layers "F.Cu" "F.Mask" "F.Paste")
			(net "P5V_AUX")
		)
		(pad "2" smd circle
			(at 0.40005 0)
			(size 0 0)
			(layers "F.Cu" "F.Mask" "F.Paste")
			(net "GND")
		)
	)
	(footprint ""
		(layer "F.Cu")
		(at 252.687582 -25.342342 -90)
		(property "Reference" "R434"
			(at 0 0 270)
			(layer "F.SilkS")
			(hide yes)
			(effects
				(font
					(size 1.27 1.27)
				)
			)
		)
		(property "Value" ""
			(at 0 0 270)
			(layer "F.Fab")
			(effects
				(font
					(size 1.27 1.27)
				)
			)
		)
		(duplicate_pad_numbers_are_jumpers no)
		(fp_line
			(start -0.7874 0.4064)
			(end -0.7874 -0.4064)
			(stroke
				(width 0.1524)
				(type default)
			)
			(layer "F.SilkS")
		)
		(fp_line
			(start 0.7874 0.4064)
			(end -0.7874 0.4064)
			(stroke
				(width 0.1524)
				(type default)
			)
			(layer "F.SilkS")
		)
		(fp_line
			(start -0.7874 -0.4064)
			(end 0.7874 -0.4064)
			(stroke
				(width 0.1524)
				(type default)
			)
			(layer "F.SilkS")
		)
		(fp_line
			(start 0.7874 -0.4064)
			(end 0.7874 0.4064)
			(stroke
				(width 0.1524)
				(type default)
			)
			(layer "F.SilkS")
		)
		(fp_line
			(start -0.67945 0.3048)
			(end -0.67945 -0.305054)
			(stroke
				(width 0.1)
				(type default)
			)
			(layer "F.Fab")
		)
		(fp_line
			(start -0.12065 0.3048)
			(end -0.67945 0.3048)
			(stroke
				(width 0.1)
				(type default)
			)
			(layer "F.Fab")
		)
		(fp_line
			(start 0.120396 0.3048)
			(end 0.120396 0.2794)
			(stroke
				(width 0.1)
				(type default)
			)
			(layer "F.Fab")
		)
		(fp_line
			(start 0.67945 0.3048)
			(end 0.120396 0.3048)
			(stroke
				(width 0.1)
				(type default)
			)
			(layer "F.Fab")
		)
		(fp_line
			(start -0.12065 0.2794)
			(end -0.12065 0.3048)
			(stroke
				(width 0.1)
				(type default)
			)
			(layer "F.Fab")
		)
		(fp_line
			(start 0.120396 0.2794)
			(end -0.12065 0.2794)
			(stroke
				(width 0.1)
				(type default)
			)
			(layer "F.Fab")
		)
		(fp_line
			(start -0.12065 -0.2794)
			(end 0.12065 -0.2794)
			(stroke
				(width 0.1)
				(type default)
			)
			(layer "F.Fab")
		)
		(fp_line
			(start 0.12065 -0.2794)
			(end 0.12065 -0.3048)
			(stroke
				(width 0.1)
				(type default)
			)
			(layer "F.Fab")
		)
		(fp_line
			(start 0.12065 -0.3048)
			(end 0.67945 -0.3048)
			(stroke
				(width 0.1)
				(type default)
			)
			(layer "F.Fab")
		)
		(fp_line
			(start 0.67945 -0.3048)
			(end 0.67945 0.3048)
			(stroke
				(width 0.1)
				(type default)
			)
			(layer "F.Fab")
		)
		(fp_line
			(start -0.67945 -0.305054)
			(end -0.12065 -0.305054)
			(stroke
				(width 0.1)
				(type default)
			)
			(layer "F.Fab")
		)
		(fp_line
			(start -0.12065 -0.305054)
			(end -0.12065 -0.2794)
			(stroke
				(width 0.1)
				(type default)
			)
			(layer "F.Fab")
		)
		(pad "1" smd circle
			(at -0.40005 0 270)
			(size 0 0)
			(layers "F.Cu" "F.Mask" "F.Paste")
			(net "GND")
		)
		(pad "2" smd circle
			(at 0.40005 0 270)
			(size 0 0)
			(layers "F.Cu" "F.Mask" "F.Paste")
			(net "DUALPORT_N_SSD8")
		)
	)
	(footprint ""
		(layer "F.Cu")
		(at 154.699716 -151.279352 180)
		(property "Reference" "R118"
			(at 0 0 180)
			(layer "F.SilkS")
			(hide yes)
			(effects
				(font
					(size 1.27 1.27)
				)
			)
		)
		(property "Value" ""
			(at 0 0 180)
			(layer "F.Fab")
			(effects
				(font
					(size 1.27 1.27)
				)
			)
		)
		(duplicate_pad_numbers_are_jumpers no)
		(fp_line
			(start 0.7874 0.4064)
			(end -0.7874 0.4064)
			(stroke
				(width 0.1524)
				(type default)
			)
			(layer "F.SilkS")
		)
		(fp_line
			(start 0.7874 -0.4064)
			(end 0.7874 0.4064)
			(stroke
				(width 0.1524)
				(type default)
			)
			(layer "F.SilkS")
		)
		(fp_line
			(start -0.7874 0.4064)
			(end -0.7874 -0.4064)
			(stroke
				(width 0.1524)
				(type default)
			)
			(layer "F.SilkS")
		)
		(fp_line
			(start -0.7874 -0.4064)
			(end 0.7874 -0.4064)
			(stroke
				(width 0.1524)
				(type default)
			)
			(layer "F.SilkS")
		)
		(fp_line
			(start 0.67945 0.3048)
			(end 0.120396 0.3048)
			(stroke
				(width 0.1)
				(type default)
			)
			(layer "F.Fab")
		)
		(fp_line
			(start 0.67945 -0.3048)
			(end 0.67945 0.3048)
			(stroke
				(width 0.1)
				(type default)
			)
			(layer "F.Fab")
		)
		(fp_line
			(start 0.12065 -0.2794)
			(end 0.12065 -0.3048)
			(stroke
				(width 0.1)
				(type default)
			)
			(layer "F.Fab")
		)
		(fp_line
			(start 0.12065 -0.3048)
			(end 0.67945 -0.3048)
			(stroke
				(width 0.1)
				(type default)
			)
			(layer "F.Fab")
		)
		(fp_line
			(start 0.120396 0.3048)
			(end 0.120396 0.2794)
			(stroke
				(width 0.1)
				(type default)
			)
			(layer "F.Fab")
		)
		(fp_line
			(start 0.120396 0.2794)
			(end -0.12065 0.2794)
			(stroke
				(width 0.1)
				(type default)
			)
			(layer "F.Fab")
		)
		(fp_line
			(start -0.12065 0.3048)
			(end -0.67945 0.3048)
			(stroke
				(width 0.1)
				(type default)
			)
			(layer "F.Fab")
		)
		(fp_line
			(start -0.12065 0.2794)
			(end -0.12065 0.3048)
			(stroke
				(width 0.1)
				(type default)
			)
			(layer "F.Fab")
		)
		(fp_line
			(start -0.12065 -0.2794)
			(end 0.12065 -0.2794)
			(stroke
				(width 0.1)
				(type default)
			)
			(layer "F.Fab")
		)
		(fp_line
			(start -0.12065 -0.305054)
			(end -0.12065 -0.2794)
			(stroke
				(width 0.1)
				(type default)
			)
			(layer "F.Fab")
		)
		(fp_line
			(start -0.67945 0.3048)
			(end -0.67945 -0.305054)
			(stroke
				(width 0.1)
				(type default)
			)
			(layer "F.Fab")
		)
		(fp_line
			(start -0.67945 -0.305054)
			(end -0.12065 -0.305054)
			(stroke
				(width 0.1)
				(type default)
			)
			(layer "F.Fab")
		)
		(pad "1" smd circle
			(at -0.40005 0 180)
			(size 0 0)
			(layers "F.Cu" "F.Mask" "F.Paste")
			(net "NCSI_NIC2_RXD0")
		)
		(pad "2" smd circle
			(at 0.40005 0 180)
			(size 0 0)
			(layers "F.Cu" "F.Mask" "F.Paste")
			(net "GND")
		)
	)
	(footprint ""
		(layer "F.Cu")
		(at 73.885552 -25.1587 -90)
		(property "Reference" "R5736"
			(at 0 0 270)
			(layer "F.SilkS")
			(hide yes)
			(effects
				(font
					(size 1.27 1.27)
				)
			)
		)
		(property "Value" ""
			(at 0 0 270)
			(layer "F.Fab")
			(effects
				(font
					(size 1.27 1.27)
				)
			)
		)
		(duplicate_pad_numbers_are_jumpers no)
		(fp_line
			(start -0.7874 0.4064)
			(end -0.7874 -0.4064)
			(stroke
				(width 0.1524)
				(type default)
			)
			(layer "F.SilkS")
		)
		(fp_line
			(start 0.7874 0.4064)
			(end -0.7874 0.4064)
			(stroke
				(width 0.1524)
				(type default)
			)
			(layer "F.SilkS")
		)
		(fp_line
			(start -0.7874 -0.4064)
			(end 0.7874 -0.4064)
			(stroke
				(width 0.1524)
				(type default)
			)
			(layer "F.SilkS")
		)
		(fp_line
			(start 0.7874 -0.4064)
			(end 0.7874 0.4064)
			(stroke
				(width 0.1524)
				(type default)
			)
			(layer "F.SilkS")
		)
		(fp_line
			(start -0.67945 0.3048)
			(end -0.67945 -0.305054)
			(stroke
				(width 0.1)
				(type default)
			)
			(layer "F.Fab")
		)
		(fp_line
			(start -0.12065 0.3048)
			(end -0.67945 0.3048)
			(stroke
				(width 0.1)
				(type default)
			)
			(layer "F.Fab")
		)
		(fp_line
			(start 0.120396 0.3048)
			(end 0.120396 0.2794)
			(stroke
				(width 0.1)
				(type default)
			)
			(layer "F.Fab")
		)
		(fp_line
			(start 0.67945 0.3048)
			(end 0.120396 0.3048)
			(stroke
				(width 0.1)
				(type default)
			)
			(layer "F.Fab")
		)
		(fp_line
			(start -0.12065 0.2794)
			(end -0.12065 0.3048)
			(stroke
				(width 0.1)
				(type default)
			)
			(layer "F.Fab")
		)
		(fp_line
			(start 0.120396 0.2794)
			(end -0.12065 0.2794)
			(stroke
				(width 0.1)
				(type default)
			)
			(layer "F.Fab")
		)
		(fp_line
			(start -0.12065 -0.2794)
			(end 0.12065 -0.2794)
			(stroke
				(width 0.1)
				(type default)
			)
			(layer "F.Fab")
		)
		(fp_line
			(start 0.12065 -0.2794)
			(end 0.12065 -0.3048)
			(stroke
				(width 0.1)
				(type default)
			)
			(layer "F.Fab")
		)
		(fp_line
			(start 0.12065 -0.3048)
			(end 0.67945 -0.3048)
			(stroke
				(width 0.1)
				(type default)
			)
			(layer "F.Fab")
		)
		(fp_line
			(start 0.67945 -0.3048)
			(end 0.67945 0.3048)
			(stroke
				(width 0.1)
				(type default)
			)
			(layer "F.Fab")
		)
		(fp_line
			(start -0.67945 -0.305054)
			(end -0.12065 -0.305054)
			(stroke
				(width 0.1)
				(type default)
			)
			(layer "F.Fab")
		)
		(fp_line
			(start -0.12065 -0.305054)
			(end -0.12065 -0.2794)
			(stroke
				(width 0.1)
				(type default)
			)
			(layer "F.Fab")
		)
		(pad "1" smd circle
			(at -0.40005 0 270)
			(size 0 0)
			(layers "F.Cu" "F.Mask" "F.Paste")
			(net "SSD2_LED_ISO_N")
		)
		(pad "2" smd circle
			(at 0.40005 0 270)
			(size 0 0)
			(layers "F.Cu" "F.Mask" "F.Paste")
			(net "SSD2_LED_ISO_R_N")
		)
	)
	(footprint ""
		(layer "F.Cu")
		(at 140.582142 -37.025072)
		(property "Reference" "R5665"
			(at 0 0 0)
			(layer "F.SilkS")
			(hide yes)
			(effects
				(font
					(size 1.27 1.27)
				)
			)
		)
		(property "Value" ""
			(at 0 0 0)
			(layer "F.Fab")
			(effects
				(font
					(size 1.27 1.27)
				)
			)
		)
		(duplicate_pad_numbers_are_jumpers no)
		(fp_line
			(start -0.7874 -0.4064)
			(end 0.7874 -0.4064)
			(stroke
				(width 0.1524)
				(type default)
			)
			(layer "F.SilkS")
		)
		(fp_line
			(start -0.7874 0.4064)
			(end -0.7874 -0.4064)
			(stroke
				(width 0.1524)
				(type default)
			)
			(layer "F.SilkS")
		)
		(fp_line
			(start 0.7874 -0.4064)
			(end 0.7874 0.4064)
			(stroke
				(width 0.1524)
				(type default)
			)
			(layer "F.SilkS")
		)
		(fp_line
			(start 0.7874 0.4064)
			(end -0.7874 0.4064)
			(stroke
				(width 0.1524)
				(type default)
			)
			(layer "F.SilkS")
		)
		(fp_line
			(start -0.67945 -0.305054)
			(end -0.12065 -0.305054)
			(stroke
				(width 0.1)
				(type default)
			)
			(layer "F.Fab")
		)
		(fp_line
			(start -0.67945 0.3048)
			(end -0.67945 -0.305054)
			(stroke
				(width 0.1)
				(type default)
			)
			(layer "F.Fab")
		)
		(fp_line
			(start -0.12065 -0.305054)
			(end -0.12065 -0.2794)
			(stroke
				(width 0.1)
				(type default)
			)
			(layer "F.Fab")
		)
		(fp_line
			(start -0.12065 -0.2794)
			(end 0.12065 -0.2794)
			(stroke
				(width 0.1)
				(type default)
			)
			(layer "F.Fab")
		)
		(fp_line
			(start -0.12065 0.2794)
			(end -0.12065 0.3048)
			(stroke
				(width 0.1)
				(type default)
			)
			(layer "F.Fab")
		)
		(fp_line
			(start -0.12065 0.3048)
			(end -0.67945 0.3048)
			(stroke
				(width 0.1)
				(type default)
			)
			(layer "F.Fab")
		)
		(fp_line
			(start 0.120396 0.2794)
			(end -0.12065 0.2794)
			(stroke
				(width 0.1)
				(type default)
			)
			(layer "F.Fab")
		)
		(fp_line
			(start 0.120396 0.3048)
			(end 0.120396 0.2794)
			(stroke
				(width 0.1)
				(type default)
			)
			(layer "F.Fab")
		)
		(fp_line
			(start 0.12065 -0.3048)
			(end 0.67945 -0.3048)
			(stroke
				(width 0.1)
				(type default)
			)
			(layer "F.Fab")
		)
		(fp_line
			(start 0.12065 -0.2794)
			(end 0.12065 -0.3048)
			(stroke
				(width 0.1)
				(type default)
			)
			(layer "F.Fab")
		)
		(fp_line
			(start 0.67945 -0.3048)
			(end 0.67945 0.3048)
			(stroke
				(width 0.1)
				(type default)
			)
			(layer "F.Fab")
		)
		(fp_line
			(start 0.67945 0.3048)
			(end 0.120396 0.3048)
			(stroke
				(width 0.1)
				(type default)
			)
			(layer "F.Fab")
		)
		(pad "1" smd circle
			(at -0.40005 0)
			(size 0 0)
			(layers "F.Cu" "F.Mask" "F.Paste")
			(net "RST_SMB_SSD_R_N")
		)
		(pad "2" smd circle
			(at 0.40005 0)
			(size 0 0)
			(layers "F.Cu" "F.Mask" "F.Paste")
			(net "RST_SMB_SSD5_N")
		)
	)
	(footprint ""
		(layer "F.Cu")
		(at 138.985244 -93.528642 180)
		(property "Reference" "R1570"
			(at 0 0 180)
			(layer "F.SilkS")
			(hide yes)
			(effects
				(font
					(size 1.27 1.27)
				)
			)
		)
		(property "Value" ""
			(at 0 0 180)
			(layer "F.Fab")
			(effects
				(font
					(size 1.27 1.27)
				)
			)
		)
		(duplicate_pad_numbers_are_jumpers no)
		(fp_line
			(start 0.7874 0.4064)
			(end -0.7874 0.4064)
			(stroke
				(width 0.1524)
				(type default)
			)
			(layer "F.SilkS")
		)
		(fp_line
			(start 0.7874 -0.4064)
			(end 0.7874 0.4064)
			(stroke
				(width 0.1524)
				(type default)
			)
			(layer "F.SilkS")
		)
		(fp_line
			(start -0.7874 0.4064)
			(end -0.7874 -0.4064)
			(stroke
				(width 0.1524)
				(type default)
			)
			(layer "F.SilkS")
		)
		(fp_line
			(start -0.7874 -0.4064)
			(end 0.7874 -0.4064)
			(stroke
				(width 0.1524)
				(type default)
			)
			(layer "F.SilkS")
		)
		(fp_line
			(start 0.67945 0.3048)
			(end 0.120396 0.3048)
			(stroke
				(width 0.1)
				(type default)
			)
			(layer "F.Fab")
		)
		(fp_line
			(start 0.67945 -0.3048)
			(end 0.67945 0.3048)
			(stroke
				(width 0.1)
				(type default)
			)
			(layer "F.Fab")
		)
		(fp_line
			(start 0.12065 -0.2794)
			(end 0.12065 -0.3048)
			(stroke
				(width 0.1)
				(type default)
			)
			(layer "F.Fab")
		)
		(fp_line
			(start 0.12065 -0.3048)
			(end 0.67945 -0.3048)
			(stroke
				(width 0.1)
				(type default)
			)
			(layer "F.Fab")
		)
		(fp_line
			(start 0.120396 0.3048)
			(end 0.120396 0.2794)
			(stroke
				(width 0.1)
				(type default)
			)
			(layer "F.Fab")
		)
		(fp_line
			(start 0.120396 0.2794)
			(end -0.12065 0.2794)
			(stroke
				(width 0.1)
				(type default)
			)
			(layer "F.Fab")
		)
		(fp_line
			(start -0.12065 0.3048)
			(end -0.67945 0.3048)
			(stroke
				(width 0.1)
				(type default)
			)
			(layer "F.Fab")
		)
		(fp_line
			(start -0.12065 0.2794)
			(end -0.12065 0.3048)
			(stroke
				(width 0.1)
				(type default)
			)
			(layer "F.Fab")
		)
		(fp_line
			(start -0.12065 -0.2794)
			(end 0.12065 -0.2794)
			(stroke
				(width 0.1)
				(type default)
			)
			(layer "F.Fab")
		)
		(fp_line
			(start -0.12065 -0.305054)
			(end -0.12065 -0.2794)
			(stroke
				(width 0.1)
				(type default)
			)
			(layer "F.Fab")
		)
		(fp_line
			(start -0.67945 0.3048)
			(end -0.67945 -0.305054)
			(stroke
				(width 0.1)
				(type default)
			)
			(layer "F.Fab")
		)
		(fp_line
			(start -0.67945 -0.305054)
			(end -0.12065 -0.305054)
			(stroke
				(width 0.1)
				(type default)
			)
			(layer "F.Fab")
		)
		(pad "1" smd circle
			(at -0.40005 0 180)
			(size 0 0)
			(layers "F.Cu" "F.Mask" "F.Paste")
			(net "P3V3_AUX")
		)
		(pad "2" smd circle
			(at 0.40005 0 180)
			(size 0 0)
			(layers "F.Cu" "F.Mask" "F.Paste")
			(net "SMB_BIC_I2C9_MUX0_SSD6_R_SCL")
		)
	)
	(footprint ""
		(layer "F.Cu")
		(at 450.230494 -119.77624 180)
		(property "Reference" "R6047"
			(at 0 0 180)
			(layer "F.SilkS")
			(hide yes)
			(effects
				(font
					(size 1.27 1.27)
				)
			)
		)
		(property "Value" ""
			(at 0 0 180)
			(layer "F.Fab")
			(effects
				(font
					(size 1.27 1.27)
				)
			)
		)
		(duplicate_pad_numbers_are_jumpers no)
		(fp_line
			(start 0.7874 0.4064)
			(end -0.7874 0.4064)
			(stroke
				(width 0.1524)
				(type default)
			)
			(layer "F.SilkS")
		)
		(fp_line
			(start 0.7874 -0.4064)
			(end 0.7874 0.4064)
			(stroke
				(width 0.1524)
				(type default)
			)
			(layer "F.SilkS")
		)
		(fp_line
			(start -0.7874 0.4064)
			(end -0.7874 -0.4064)
			(stroke
				(width 0.1524)
				(type default)
			)
			(layer "F.SilkS")
		)
		(fp_line
			(start -0.7874 -0.4064)
			(end 0.7874 -0.4064)
			(stroke
				(width 0.1524)
				(type default)
			)
			(layer "F.SilkS")
		)
		(fp_line
			(start 0.67945 0.3048)
			(end 0.120396 0.3048)
			(stroke
				(width 0.1)
				(type default)
			)
			(layer "F.Fab")
		)
		(fp_line
			(start 0.67945 -0.3048)
			(end 0.67945 0.3048)
			(stroke
				(width 0.1)
				(type default)
			)
			(layer "F.Fab")
		)
		(fp_line
			(start 0.12065 -0.2794)
			(end 0.12065 -0.3048)
			(stroke
				(width 0.1)
				(type default)
			)
			(layer "F.Fab")
		)
		(fp_line
			(start 0.12065 -0.3048)
			(end 0.67945 -0.3048)
			(stroke
				(width 0.1)
				(type default)
			)
			(layer "F.Fab")
		)
		(fp_line
			(start 0.120396 0.3048)
			(end 0.120396 0.2794)
			(stroke
				(width 0.1)
				(type default)
			)
			(layer "F.Fab")
		)
		(fp_line
			(start 0.120396 0.2794)
			(end -0.12065 0.2794)
			(stroke
				(width 0.1)
				(type default)
			)
			(layer "F.Fab")
		)
		(fp_line
			(start -0.12065 0.3048)
			(end -0.67945 0.3048)
			(stroke
				(width 0.1)
				(type default)
			)
			(layer "F.Fab")
		)
		(fp_line
			(start -0.12065 0.2794)
			(end -0.12065 0.3048)
			(stroke
				(width 0.1)
				(type default)
			)
			(layer "F.Fab")
		)
		(fp_line
			(start -0.12065 -0.2794)
			(end 0.12065 -0.2794)
			(stroke
				(width 0.1)
				(type default)
			)
			(layer "F.Fab")
		)
		(fp_line
			(start -0.12065 -0.305054)
			(end -0.12065 -0.2794)
			(stroke
				(width 0.1)
				(type default)
			)
			(layer "F.Fab")
		)
		(fp_line
			(start -0.67945 0.3048)
			(end -0.67945 -0.305054)
			(stroke
				(width 0.1)
				(type default)
			)
			(layer "F.Fab")
		)
		(fp_line
			(start -0.67945 -0.305054)
			(end -0.12065 -0.305054)
			(stroke
				(width 0.1)
				(type default)
			)
			(layer "F.Fab")
		)
		(pad "1" smd circle
			(at -0.40005 0 180)
			(size 0 0)
			(layers "F.Cu" "F.Mask" "F.Paste")
			(net "PWRGD_P3V3_NIC7_D")
		)
		(pad "2" smd circle
			(at 0.40005 0 180)
			(size 0 0)
			(layers "F.Cu" "F.Mask" "F.Paste")
			(net "PWRGD_P3V3_NIC7_R")
		)
	)
	(footprint ""
		(layer "F.Cu")
		(at 50.396648 -343.952322 90)
		(property "Reference" "C2180"
			(at 0 0 90)
			(layer "F.SilkS")
			(hide yes)
			(effects
				(font
					(size 1.27 1.27)
				)
			)
		)
		(property "Value" ""
			(at 0 0 90)
			(layer "F.Fab")
			(effects
				(font
					(size 1.27 1.27)
				)
			)
		)
		(duplicate_pad_numbers_are_jumpers no)
		(fp_line
			(start 0.299974 -0.150114)
			(end 0.299974 0.150114)
			(stroke
				(width 0.1)
				(type default)
			)
			(layer "F.Fab")
		)
		(fp_line
			(start -0.299974 -0.150114)
			(end 0.299974 -0.150114)
			(stroke
				(width 0.1)
				(type default)
			)
			(layer "F.Fab")
		)
		(fp_line
			(start 0.299974 0.150114)
			(end -0.299974 0.150114)
			(stroke
				(width 0.1)
				(type default)
			)
			(layer "F.Fab")
		)
		(fp_line
			(start -0.299974 0.150114)
			(end -0.299974 -0.150114)
			(stroke
				(width 0.1)
				(type default)
			)
			(layer "F.Fab")
		)
		(pad "1" smd rect
			(at -0.2667 0 90)
			(size 0.3048 0.381)
			(layers "F.Cu" "F.Mask" "F.Paste")
			(net "P5E_PEX0_STN4_TX_DP<65>")
		)
		(pad "2" smd rect
			(at 0.2667 0 90)
			(size 0.3048 0.381)
			(layers "F.Cu" "F.Mask" "F.Paste")
			(net "P5E_PEX0_STN4_TX_C_DP<65>")
		)
	)
	(footprint ""
		(layer "F.Cu")
		(at 236.573822 -27.006296 -90)
		(property "Reference" "PC944"
			(at 0 0 270)
			(layer "F.SilkS")
			(hide yes)
			(effects
				(font
					(size 1.27 1.27)
				)
			)
		)
		(property "Value" ""
			(at 0 0 270)
			(layer "F.Fab")
			(effects
				(font
					(size 1.27 1.27)
				)
			)
		)
		(duplicate_pad_numbers_are_jumpers no)
		(fp_line
			(start -0.7874 0.4064)
			(end -0.7874 -0.4064)
			(stroke
				(width 0.1524)
				(type default)
			)
			(layer "F.SilkS")
		)
		(fp_line
			(start 0.7874 0.4064)
			(end -0.7874 0.4064)
			(stroke
				(width 0.1524)
				(type default)
			)
			(layer "F.SilkS")
		)
		(fp_line
			(start -0.7874 -0.4064)
			(end 0.7874 -0.4064)
			(stroke
				(width 0.1524)
				(type default)
			)
			(layer "F.SilkS")
		)
		(fp_line
			(start 0.7874 -0.4064)
			(end 0.7874 0.4064)
			(stroke
				(width 0.1524)
				(type default)
			)
			(layer "F.SilkS")
		)
		(fp_line
			(start -0.67945 0.3048)
			(end -0.67945 -0.305054)
			(stroke
				(width 0.1)
				(type default)
			)
			(layer "F.Fab")
		)
		(fp_line
			(start -0.12065 0.3048)
			(end -0.67945 0.3048)
			(stroke
				(width 0.1)
				(type default)
			)
			(layer "F.Fab")
		)
		(fp_line
			(start 0.120396 0.3048)
			(end 0.120396 0.2794)
			(stroke
				(width 0.1)
				(type default)
			)
			(layer "F.Fab")
		)
		(fp_line
			(start 0.67945 0.3048)
			(end 0.120396 0.3048)
			(stroke
				(width 0.1)
				(type default)
			)
			(layer "F.Fab")
		)
		(fp_line
			(start -0.12065 0.2794)
			(end -0.12065 0.3048)
			(stroke
				(width 0.1)
				(type default)
			)
			(layer "F.Fab")
		)
		(fp_line
			(start 0.120396 0.2794)
			(end -0.12065 0.2794)
			(stroke
				(width 0.1)
				(type default)
			)
			(layer "F.Fab")
		)
		(fp_line
			(start -0.12065 -0.2794)
			(end 0.12065 -0.2794)
			(stroke
				(width 0.1)
				(type default)
			)
			(layer "F.Fab")
		)
		(fp_line
			(start 0.12065 -0.2794)
			(end 0.12065 -0.3048)
			(stroke
				(width 0.1)
				(type default)
			)
			(layer "F.Fab")
		)
		(fp_line
			(start 0.12065 -0.3048)
			(end 0.67945 -0.3048)
			(stroke
				(width 0.1)
				(type default)
			)
			(layer "F.Fab")
		)
		(fp_line
			(start 0.67945 -0.3048)
			(end 0.67945 0.3048)
			(stroke
				(width 0.1)
				(type default)
			)
			(layer "F.Fab")
		)
		(fp_line
			(start -0.67945 -0.305054)
			(end -0.12065 -0.305054)
			(stroke
				(width 0.1)
				(type default)
			)
			(layer "F.Fab")
		)
		(fp_line
			(start -0.12065 -0.305054)
			(end -0.12065 -0.2794)
			(stroke
				(width 0.1)
				(type default)
			)
			(layer "F.Fab")
		)
		(pad "1" smd circle
			(at -0.40005 0 270)
			(size 0 0)
			(layers "F.Cu" "F.Mask" "F.Paste")
			(net "P3V3_SSD8_CO_MODE")
		)
		(pad "2" smd circle
			(at 0.40005 0 270)
			(size 0 0)
			(layers "F.Cu" "F.Mask" "F.Paste")
			(net "GND")
		)
	)
	(footprint ""
		(layer "F.Cu")
		(at 350.139762 -237.69828 90)
		(property "Reference" "R6835"
			(at 0 0 90)
			(layer "F.SilkS")
			(hide yes)
			(effects
				(font
					(size 1.27 1.27)
				)
			)
		)
		(property "Value" ""
			(at 0 0 90)
			(layer "F.Fab")
			(effects
				(font
					(size 1.27 1.27)
				)
			)
		)
		(duplicate_pad_numbers_are_jumpers no)
		(fp_line
			(start 0.7874 -0.4064)
			(end 0.7874 0.4064)
			(stroke
				(width 0.1524)
				(type default)
			)
			(layer "F.SilkS")
		)
		(fp_line
			(start -0.7874 -0.4064)
			(end 0.7874 -0.4064)
			(stroke
				(width 0.1524)
				(type default)
			)
			(layer "F.SilkS")
		)
		(fp_line
			(start 0.7874 0.4064)
			(end -0.7874 0.4064)
			(stroke
				(width 0.1524)
				(type default)
			)
			(layer "F.SilkS")
		)
		(fp_line
			(start -0.7874 0.4064)
			(end -0.7874 -0.4064)
			(stroke
				(width 0.1524)
				(type default)
			)
			(layer "F.SilkS")
		)
		(fp_line
			(start -0.12065 -0.305054)
			(end -0.12065 -0.2794)
			(stroke
				(width 0.1)
				(type default)
			)
			(layer "F.Fab")
		)
		(fp_line
			(start -0.67945 -0.305054)
			(end -0.12065 -0.305054)
			(stroke
				(width 0.1)
				(type default)
			)
			(layer "F.Fab")
		)
		(fp_line
			(start 0.67945 -0.3048)
			(end 0.67945 0.3048)
			(stroke
				(width 0.1)
				(type default)
			)
			(layer "F.Fab")
		)
		(fp_line
			(start 0.12065 -0.3048)
			(end 0.67945 -0.3048)
			(stroke
				(width 0.1)
				(type default)
			)
			(layer "F.Fab")
		)
		(fp_line
			(start 0.12065 -0.2794)
			(end 0.12065 -0.3048)
			(stroke
				(width 0.1)
				(type default)
			)
			(layer "F.Fab")
		)
		(fp_line
			(start -0.12065 -0.2794)
			(end 0.12065 -0.2794)
			(stroke
				(width 0.1)
				(type default)
			)
			(layer "F.Fab")
		)
		(fp_line
			(start 0.120396 0.2794)
			(end -0.12065 0.2794)
			(stroke
				(width 0.1)
				(type default)
			)
			(layer "F.Fab")
		)
		(fp_line
			(start -0.12065 0.2794)
			(end -0.12065 0.3048)
			(stroke
				(width 0.1)
				(type default)
			)
			(layer "F.Fab")
		)
		(fp_line
			(start 0.67945 0.3048)
			(end 0.120396 0.3048)
			(stroke
				(width 0.1)
				(type default)
			)
			(layer "F.Fab")
		)
		(fp_line
			(start 0.120396 0.3048)
			(end 0.120396 0.2794)
			(stroke
				(width 0.1)
				(type default)
			)
			(layer "F.Fab")
		)
		(fp_line
			(start -0.12065 0.3048)
			(end -0.67945 0.3048)
			(stroke
				(width 0.1)
				(type default)
			)
			(layer "F.Fab")
		)
		(fp_line
			(start -0.67945 0.3048)
			(end -0.67945 -0.305054)
			(stroke
				(width 0.1)
				(type default)
			)
			(layer "F.Fab")
		)
		(pad "1" smd circle
			(at -0.40005 0 90)
			(size 0 0)
			(layers "F.Cu" "F.Mask" "F.Paste")
			(net "SSD6_PWR_EN_R")
		)
		(pad "2" smd circle
			(at 0.40005 0 90)
			(size 0 0)
			(layers "F.Cu" "F.Mask" "F.Paste")
			(net "GND")
		)
	)
	(footprint ""
		(layer "F.Cu")
		(at 102.734872 -215.055958 180)
		(property "Reference" "PC284"
			(at 0 0 180)
			(layer "F.SilkS")
			(hide yes)
			(effects
				(font
					(size 1.27 1.27)
				)
			)
		)
		(property "Value" ""
			(at 0 0 180)
			(layer "F.Fab")
			(effects
				(font
					(size 1.27 1.27)
				)
			)
		)
		(duplicate_pad_numbers_are_jumpers no)
		(fp_line
			(start 1.524 0.762)
			(end -1.524 0.762)
			(stroke
				(width 0.1524)
				(type default)
			)
			(layer "F.SilkS")
		)
		(fp_line
			(start 1.524 -0.762)
			(end 1.524 0.762)
			(stroke
				(width 0.1524)
				(type default)
			)
			(layer "F.SilkS")
		)
		(fp_line
			(start -1.524 0.762)
			(end -1.524 -0.762)
			(stroke
				(width 0.1524)
				(type default)
			)
			(layer "F.SilkS")
		)
		(fp_line
			(start -1.524 -0.762)
			(end 1.524 -0.762)
			(stroke
				(width 0.1524)
				(type default)
			)
			(layer "F.SilkS")
		)
		(fp_line
			(start 1.1049 0.724916)
			(end 1.1049 -0.724916)
			(stroke
				(width 0.1)
				(type default)
			)
			(layer "F.Fab")
		)
		(fp_line
			(start 1.1049 -0.724916)
			(end -1.1049 -0.724916)
			(stroke
				(width 0.1)
				(type default)
			)
			(layer "F.Fab")
		)
		(fp_line
			(start -1.1049 0.724916)
			(end 1.1049 0.724916)
			(stroke
				(width 0.1)
				(type default)
			)
			(layer "F.Fab")
		)
		(fp_line
			(start -1.1049 -0.724916)
			(end -1.1049 0.724916)
			(stroke
				(width 0.1)
				(type default)
			)
			(layer "F.Fab")
		)
		(pad "1" smd rect
			(at -0.889 0)
			(size 1.016 1.27)
			(layers "F.Cu" "F.Mask" "F.Paste")
			(net "SW_P12V_P1V8_PEX_FLT")
		)
		(pad "2" smd rect
			(at 0.889 0)
			(size 1.016 1.27)
			(layers "F.Cu" "F.Mask" "F.Paste")
			(net "GND")
		)
	)
	(footprint ""
		(layer "F.Cu")
		(at 36.638484 -120.113298)
		(property "Reference" "C48"
			(at 0 0 0)
			(layer "F.SilkS")
			(hide yes)
			(effects
				(font
					(size 1.27 1.27)
				)
			)
		)
		(property "Value" ""
			(at 0 0 0)
			(layer "F.Fab")
			(effects
				(font
					(size 1.27 1.27)
				)
			)
		)
		(duplicate_pad_numbers_are_jumpers no)
		(fp_line
			(start -0.299974 -0.150114)
			(end 0.299974 -0.150114)
			(stroke
				(width 0.1)
				(type default)
			)
			(layer "F.Fab")
		)
		(fp_line
			(start -0.299974 0.150114)
			(end -0.299974 -0.150114)
			(stroke
				(width 0.1)
				(type default)
			)
			(layer "F.Fab")
		)
		(fp_line
			(start 0.299974 -0.150114)
			(end 0.299974 0.150114)
			(stroke
				(width 0.1)
				(type default)
			)
			(layer "F.Fab")
		)
		(fp_line
			(start 0.299974 0.150114)
			(end -0.299974 0.150114)
			(stroke
				(width 0.1)
				(type default)
			)
			(layer "F.Fab")
		)
		(pad "1" smd rect
			(at -0.2667 0)
			(size 0.3048 0.381)
			(layers "F.Cu" "F.Mask" "F.Paste")
			(net "P5E_PEX0_STN1_TX_DN<24>")
		)
		(pad "2" smd rect
			(at 0.2667 0)
			(size 0.3048 0.381)
			(layers "F.Cu" "F.Mask" "F.Paste")
			(net "P5E_PEX0_STN1_TX_C_DN<24>")
		)
	)
	(footprint ""
		(layer "F.Cu")
		(at 439.612024 -100.20935 90)
		(property "Reference" "U86"
			(at 0.42545 2.450846 90)
			(unlocked yes)
			(layer "F.SilkS")
			(effects
				(font
					(size 0.7874 0.5842)
					(thickness 0.1524)
				)
			)
		)
		(property "Value" ""
			(at 0 0 90)
			(layer "F.Fab")
			(effects
				(font
					(size 1.27 1.27)
				)
			)
		)
		(duplicate_pad_numbers_are_jumpers no)
		(fp_line
			(start 1.500124 -1.500124)
			(end 1.500124 -1.004062)
			(stroke
				(width 0.1524)
				(type default)
			)
			(layer "F.SilkS")
		)
		(fp_line
			(start 1.004062 -1.500124)
			(end 1.500124 -1.500124)
			(stroke
				(width 0.1524)
				(type default)
			)
			(layer "F.SilkS")
		)
		(fp_line
			(start -1.500124 -1.500124)
			(end -1.004062 -1.500124)
			(stroke
				(width 0.1524)
				(type default)
			)
			(layer "F.SilkS")
		)
		(fp_line
			(start -1.500124 -1.004062)
			(end -1.500124 -1.500124)
			(stroke
				(width 0.1524)
				(type default)
			)
			(layer "F.SilkS")
		)
		(fp_line
			(start 1.500124 1.004062)
			(end 1.500124 1.500124)
			(stroke
				(width 0.1524)
				(type default)
			)
			(layer "F.SilkS")
		)
		(fp_line
			(start 1.500124 1.500124)
			(end 1.004062 1.500124)
			(stroke
				(width 0.1524)
				(type default)
			)
			(layer "F.SilkS")
		)
		(fp_line
			(start -1.004062 1.500124)
			(end -1.500124 1.500124)
			(stroke
				(width 0.1524)
				(type default)
			)
			(layer "F.SilkS")
		)
		(fp_line
			(start -1.500124 1.500124)
			(end -1.500124 1.004062)
			(stroke
				(width 0.1524)
				(type default)
			)
			(layer "F.SilkS")
		)
		(fp_poly
			(pts
				(xy -1.956562 -2.173478) (xy -2.675128 -1.454912) (xy -1.597406 -1.095756)
			)
			(stroke
				(width 0)
				(type default)
			)
			(fill yes)
			(layer "F.SilkS")
		)
		(fp_line
			(start 1.500124 -1.500124)
			(end 1.500124 1.500124)
			(stroke
				(width 0.1)
				(type default)
			)
			(layer "F.Fab")
		)
		(fp_line
			(start -1.500124 -1.500124)
			(end 1.500124 -1.500124)
			(stroke
				(width 0.1)
				(type default)
			)
			(layer "F.Fab")
		)
		(fp_line
			(start 1.500124 1.500124)
			(end -1.500124 1.500124)
			(stroke
				(width 0.1)
				(type default)
			)
			(layer "F.Fab")
		)
		(fp_line
			(start -1.500124 1.500124)
			(end -1.500124 -1.500124)
			(stroke
				(width 0.1)
				(type default)
			)
			(layer "F.Fab")
		)
		(fp_poly
			(pts
				(xy -2.847848 -1.258062) (xy -2.847848 -0.242062) (xy -1.831848 -0.750062)
			)
			(stroke
				(width 0)
				(type default)
			)
			(fill yes)
			(layer "F.Fab")
		)
		(pad "1" smd rect
			(at -1.400048 -0.750062)
			(size 0.2286 0.6096)
			(layers "F.Cu" "F.Mask" "F.Paste")
			(net "NIC7_ADC_A1")
		)
		(pad "2" smd rect
			(at -1.400048 -0.249936)
			(size 0.2286 0.6096)
			(layers "F.Cu" "F.Mask" "F.Paste")
			(net "NIC7_ADC_A0")
		)
		(pad "3" smd rect
			(at -1.400048 0.249936)
			(size 0.2286 0.6096)
			(layers "F.Cu" "F.Mask" "F.Paste")
			(net "NIC7_ADC_ALERT_N")
		)
		(pad "4" smd rect
			(at -1.400048 0.750062)
			(size 0.2286 0.6096)
			(layers "F.Cu" "F.Mask" "F.Paste")
			(net "SMB_NIC7_ADC_SDA")
		)
		(pad "5" smd rect
			(at -0.750062 1.400048 90)
			(size 0.2286 0.6096)
			(layers "F.Cu" "F.Mask" "F.Paste")
			(net "SMB_NIC7_ADC_SCL")
		)
		(pad "6" smd rect
			(at -0.249936 1.400048 90)
			(size 0.2286 0.6096)
			(layers "F.Cu" "F.Mask" "F.Paste")
			(net "Net_8624")
		)
		(pad "7" smd rect
			(at 0.249936 1.400048 90)
			(size 0.2286 0.6096)
			(layers "F.Cu" "F.Mask" "F.Paste")
			(net "Net_8623")
		)
		(pad "8" smd rect
			(at 0.750062 1.400048 90)
			(size 0.2286 0.6096)
			(layers "F.Cu" "F.Mask" "F.Paste")
			(net "Net_8622")
		)
		(pad "9" smd rect
			(at 1.400048 0.750062)
			(size 0.2286 0.6096)
			(layers "F.Cu" "F.Mask" "F.Paste")
			(net "P3V3_AUX")
		)
		(pad "10" smd rect
			(at 1.400048 0.249936)
			(size 0.2286 0.6096)
			(layers "F.Cu" "F.Mask" "F.Paste")
			(net "GND")
		)
		(pad "11" smd rect
			(at 1.400048 -0.249936)
			(size 0.2286 0.6096)
			(layers "F.Cu" "F.Mask" "F.Paste")
			(net "P12V_NIC7_R")
		)
		(pad "12" smd rect
			(at 1.400048 -0.750062)
			(size 0.2286 0.6096)
			(layers "F.Cu" "F.Mask" "F.Paste")
			(net "P12V_NIC7_VIN_N")
		)
		(pad "13" smd rect
			(at 0.750062 -1.400048 90)
			(size 0.2286 0.6096)
			(layers "F.Cu" "F.Mask" "F.Paste")
			(net "P12V_NIC7_VIN_P")
		)
		(pad "14" smd rect
			(at 0.249936 -1.400048 90)
			(size 0.2286 0.6096)
			(layers "F.Cu" "F.Mask" "F.Paste")
			(net "Net_8621")
		)
		(pad "15" smd rect
			(at -0.249936 -1.400048 90)
			(size 0.2286 0.6096)
			(layers "F.Cu" "F.Mask" "F.Paste")
			(net "Net_8620")
		)
		(pad "16" smd rect
			(at -0.750062 -1.400048 90)
			(size 0.2286 0.6096)
			(layers "F.Cu" "F.Mask" "F.Paste")
			(net "Net_8619")
		)
		(pad "TH" smd rect
			(at 0 0 90)
			(size 1.7018 1.7018)
			(layers "F.Cu" "F.Mask" "F.Paste")
			(net "GND")
		)
		(zone
			(layer "F.Cu")
			(hatch none 0.5)
			(connect_pads
				(clearance 0)
			)
			(min_thickness 0.25)
			(keepout
				(tracks not_allowed)
				(vias allowed)
				(pads allowed)
				(copperpour not_allowed)
				(footprints allowed)
			)
			(placement
				(enabled no)
				(sheetname "")
			)
			(fill
				(thermal_gap 0.5)
				(thermal_bridge_width 0.5)
				(island_removal_mode 0)
			)
			(polygon
				(pts
					(xy 439.586624 -99.164902) (xy 438.567576 -99.164902) (xy 438.567576 -101.253798) (xy 440.656472 -101.253798)
					(xy 440.656472 -99.164902) (xy 439.612024 -99.164902) (xy 439.612024 -99.30765) (xy 440.513724 -99.30765)
					(xy 440.513724 -101.11105) (xy 438.710324 -101.11105) (xy 438.710324 -99.30765) (xy 439.586624 -99.30765)
				)
			)
		)
	)
	(footprint ""
		(layer "F.Cu")
		(at 46.659546 -61.612526)
		(property "Reference" "PD25"
			(at -3.682746 -2.648204 0)
			(unlocked yes)
			(layer "F.SilkS")
			(effects
				(font
					(size 0.7874 0.5842)
					(thickness 0.1524)
				)
				(justify left)
			)
		)
		(property "Value" ""
			(at 0 0 0)
			(layer "F.Fab")
			(effects
				(font
					(size 1.27 1.27)
				)
			)
		)
		(duplicate_pad_numbers_are_jumpers no)
		(fp_line
			(start -3.656584 -1.970024)
			(end -3.656584 1.970024)
			(stroke
				(width 0.1524)
				(type default)
			)
			(layer "F.SilkS")
		)
		(fp_line
			(start -3.656584 1.970024)
			(end 4.240784 1.970024)
			(stroke
				(width 0.1524)
				(type default)
			)
			(layer "F.SilkS")
		)
		(fp_line
			(start 4.240784 -1.970024)
			(end -3.656584 -1.970024)
			(stroke
				(width 0.1524)
				(type default)
			)
			(layer "F.SilkS")
		)
		(fp_line
			(start 4.240784 1.970024)
			(end 4.240784 -1.970024)
			(stroke
				(width 0.1524)
				(type default)
			)
			(layer "F.SilkS")
		)
		(fp_poly
			(pts
				(xy 3.580384 1.970024) (xy 3.580384 -1.970024) (xy 4.240784 -1.970024) (xy 4.240784 1.970024)
			)
			(stroke
				(width 0)
				(type default)
			)
			(fill yes)
			(layer "F.SilkS")
		)
		(fp_line
			(start -2.3749 -1.970024)
			(end -2.3749 1.970024)
			(stroke
				(width 0.1)
				(type default)
			)
			(layer "F.Fab")
		)
		(fp_line
			(start -2.3749 1.970024)
			(end 2.3749 1.970024)
			(stroke
				(width 0.1)
				(type default)
			)
			(layer "F.Fab")
		)
		(fp_line
			(start 2.3749 -1.970024)
			(end -2.3749 -1.970024)
			(stroke
				(width 0.1)
				(type default)
			)
			(layer "F.Fab")
		)
		(fp_line
			(start 2.3749 1.970024)
			(end 2.3749 -1.970024)
			(stroke
				(width 0.1)
				(type default)
			)
			(layer "F.Fab")
		)
		(fp_text user "+"
			(at -4.9784 -0.23495 0)
			(unlocked yes)
			(layer "F.Fab")
			(effects
				(font
					(size 1.905 1.4224)
					(thickness 0.1524)
				)
				(justify left)
			)
		)
		(fp_text user "-"
			(at 4.1656 -0.23495 0)
			(unlocked yes)
			(layer "F.Fab")
			(effects
				(font
					(size 1.905 1.4224)
					(thickness 0.1524)
				)
				(justify left)
			)
		)
		(pad "A" smd rect
			(at -2.450084 0)
			(size 2.159 2.2606)
			(layers "F.Cu" "F.Mask" "F.Paste")
			(net "GND")
		)
		(pad "C" smd rect
			(at 2.450084 0)
			(size 2.159 2.2606)
			(layers "F.Cu" "F.Mask" "F.Paste")
			(net "P12V_AUX")
		)
	)
	(footprint ""
		(layer "F.Cu")
		(at 359.156 -189.23)
		(property "Reference" "R4600"
			(at 0 0 0)
			(layer "F.SilkS")
			(hide yes)
			(effects
				(font
					(size 1.27 1.27)
				)
			)
		)
		(property "Value" ""
			(at 0 0 0)
			(layer "F.Fab")
			(effects
				(font
					(size 1.27 1.27)
				)
			)
		)
		(duplicate_pad_numbers_are_jumpers no)
		(fp_line
			(start -0.7874 -0.4064)
			(end 0.7874 -0.4064)
			(stroke
				(width 0.1524)
				(type default)
			)
			(layer "F.SilkS")
		)
		(fp_line
			(start -0.7874 0.4064)
			(end -0.7874 -0.4064)
			(stroke
				(width 0.1524)
				(type default)
			)
			(layer "F.SilkS")
		)
		(fp_line
			(start 0.7874 -0.4064)
			(end 0.7874 0.4064)
			(stroke
				(width 0.1524)
				(type default)
			)
			(layer "F.SilkS")
		)
		(fp_line
			(start 0.7874 0.4064)
			(end -0.7874 0.4064)
			(stroke
				(width 0.1524)
				(type default)
			)
			(layer "F.SilkS")
		)
		(fp_line
			(start -0.67945 -0.305054)
			(end -0.12065 -0.305054)
			(stroke
				(width 0.1)
				(type default)
			)
			(layer "F.Fab")
		)
		(fp_line
			(start -0.67945 0.3048)
			(end -0.67945 -0.305054)
			(stroke
				(width 0.1)
				(type default)
			)
			(layer "F.Fab")
		)
		(fp_line
			(start -0.12065 -0.305054)
			(end -0.12065 -0.2794)
			(stroke
				(width 0.1)
				(type default)
			)
			(layer "F.Fab")
		)
		(fp_line
			(start -0.12065 -0.2794)
			(end 0.12065 -0.2794)
			(stroke
				(width 0.1)
				(type default)
			)
			(layer "F.Fab")
		)
		(fp_line
			(start -0.12065 0.2794)
			(end -0.12065 0.3048)
			(stroke
				(width 0.1)
				(type default)
			)
			(layer "F.Fab")
		)
		(fp_line
			(start -0.12065 0.3048)
			(end -0.67945 0.3048)
			(stroke
				(width 0.1)
				(type default)
			)
			(layer "F.Fab")
		)
		(fp_line
			(start 0.120396 0.2794)
			(end -0.12065 0.2794)
			(stroke
				(width 0.1)
				(type default)
			)
			(layer "F.Fab")
		)
		(fp_line
			(start 0.120396 0.3048)
			(end 0.120396 0.2794)
			(stroke
				(width 0.1)
				(type default)
			)
			(layer "F.Fab")
		)
		(fp_line
			(start 0.12065 -0.3048)
			(end 0.67945 -0.3048)
			(stroke
				(width 0.1)
				(type default)
			)
			(layer "F.Fab")
		)
		(fp_line
			(start 0.12065 -0.2794)
			(end 0.12065 -0.3048)
			(stroke
				(width 0.1)
				(type default)
			)
			(layer "F.Fab")
		)
		(fp_line
			(start 0.67945 -0.3048)
			(end 0.67945 0.3048)
			(stroke
				(width 0.1)
				(type default)
			)
			(layer "F.Fab")
		)
		(fp_line
			(start 0.67945 0.3048)
			(end 0.120396 0.3048)
			(stroke
				(width 0.1)
				(type default)
			)
			(layer "F.Fab")
		)
		(pad "1" smd circle
			(at -0.40005 0)
			(size 0 0)
			(layers "F.Cu" "F.Mask" "F.Paste")
			(net "P3V3_AUX")
		)
		(pad "2" smd circle
			(at 0.40005 0)
			(size 0 0)
			(layers "F.Cu" "F.Mask" "F.Paste")
			(net "SSD2_PEX_PWR_EN_R")
		)
	)
	(footprint ""
		(layer "F.Cu")
		(at 233.524044 -139.026392)
		(property "Reference" "C2791"
			(at 0 0 0)
			(layer "F.SilkS")
			(hide yes)
			(effects
				(font
					(size 1.27 1.27)
				)
			)
		)
		(property "Value" ""
			(at 0 0 0)
			(layer "F.Fab")
			(effects
				(font
					(size 1.27 1.27)
				)
			)
		)
		(duplicate_pad_numbers_are_jumpers no)
		(fp_line
			(start -0.7874 -0.4064)
			(end 0.7874 -0.4064)
			(stroke
				(width 0.1524)
				(type default)
			)
			(layer "F.SilkS")
		)
		(fp_line
			(start -0.7874 0.4064)
			(end -0.7874 -0.4064)
			(stroke
				(width 0.1524)
				(type default)
			)
			(layer "F.SilkS")
		)
		(fp_line
			(start 0.7874 -0.4064)
			(end 0.7874 0.4064)
			(stroke
				(width 0.1524)
				(type default)
			)
			(layer "F.SilkS")
		)
		(fp_line
			(start 0.7874 0.4064)
			(end -0.7874 0.4064)
			(stroke
				(width 0.1524)
				(type default)
			)
			(layer "F.SilkS")
		)
		(fp_line
			(start -0.67945 -0.305054)
			(end -0.12065 -0.305054)
			(stroke
				(width 0.1)
				(type default)
			)
			(layer "F.Fab")
		)
		(fp_line
			(start -0.67945 0.3048)
			(end -0.67945 -0.305054)
			(stroke
				(width 0.1)
				(type default)
			)
			(layer "F.Fab")
		)
		(fp_line
			(start -0.12065 -0.305054)
			(end -0.12065 -0.2794)
			(stroke
				(width 0.1)
				(type default)
			)
			(layer "F.Fab")
		)
		(fp_line
			(start -0.12065 -0.2794)
			(end 0.12065 -0.2794)
			(stroke
				(width 0.1)
				(type default)
			)
			(layer "F.Fab")
		)
		(fp_line
			(start -0.12065 0.2794)
			(end -0.12065 0.3048)
			(stroke
				(width 0.1)
				(type default)
			)
			(layer "F.Fab")
		)
		(fp_line
			(start -0.12065 0.3048)
			(end -0.67945 0.3048)
			(stroke
				(width 0.1)
				(type default)
			)
			(layer "F.Fab")
		)
		(fp_line
			(start 0.120396 0.2794)
			(end -0.12065 0.2794)
			(stroke
				(width 0.1)
				(type default)
			)
			(layer "F.Fab")
		)
		(fp_line
			(start 0.120396 0.3048)
			(end 0.120396 0.2794)
			(stroke
				(width 0.1)
				(type default)
			)
			(layer "F.Fab")
		)
		(fp_line
			(start 0.12065 -0.3048)
			(end 0.67945 -0.3048)
			(stroke
				(width 0.1)
				(type default)
			)
			(layer "F.Fab")
		)
		(fp_line
			(start 0.12065 -0.2794)
			(end 0.12065 -0.3048)
			(stroke
				(width 0.1)
				(type default)
			)
			(layer "F.Fab")
		)
		(fp_line
			(start 0.67945 -0.3048)
			(end 0.67945 0.3048)
			(stroke
				(width 0.1)
				(type default)
			)
			(layer "F.Fab")
		)
		(fp_line
			(start 0.67945 0.3048)
			(end 0.120396 0.3048)
			(stroke
				(width 0.1)
				(type default)
			)
			(layer "F.Fab")
		)
		(pad "1" smd circle
			(at -0.40005 0)
			(size 0 0)
			(layers "F.Cu" "F.Mask" "F.Paste")
			(net "XTAL_CK440_PEX_25M_R_XIN")
		)
		(pad "2" smd circle
			(at 0.40005 0)
			(size 0 0)
			(layers "F.Cu" "F.Mask" "F.Paste")
			(net "GND")
		)
	)
	(footprint ""
		(layer "F.Cu")
		(at 90.241882 -350.098614 90)
		(property "Reference" "C156"
			(at 0 0 90)
			(layer "F.SilkS")
			(hide yes)
			(effects
				(font
					(size 1.27 1.27)
				)
			)
		)
		(property "Value" ""
			(at 0 0 90)
			(layer "F.Fab")
			(effects
				(font
					(size 1.27 1.27)
				)
			)
		)
		(duplicate_pad_numbers_are_jumpers no)
		(fp_line
			(start 0.299974 -0.150114)
			(end 0.299974 0.150114)
			(stroke
				(width 0.1)
				(type default)
			)
			(layer "F.Fab")
		)
		(fp_line
			(start -0.299974 -0.150114)
			(end 0.299974 -0.150114)
			(stroke
				(width 0.1)
				(type default)
			)
			(layer "F.Fab")
		)
		(fp_line
			(start 0.299974 0.150114)
			(end -0.299974 0.150114)
			(stroke
				(width 0.1)
				(type default)
			)
			(layer "F.Fab")
		)
		(fp_line
			(start -0.299974 0.150114)
			(end -0.299974 -0.150114)
			(stroke
				(width 0.1)
				(type default)
			)
			(layer "F.Fab")
		)
		(pad "1" smd rect
			(at -0.2667 0 90)
			(size 0.3048 0.381)
			(layers "F.Cu" "F.Mask" "F.Paste")
			(net "P5E_PEX0_STN6_TX_DN<98>")
		)
		(pad "2" smd rect
			(at 0.2667 0 90)
			(size 0.3048 0.381)
			(layers "F.Cu" "F.Mask" "F.Paste")
			(net "P5E_PEX0_STN6_TX_C_DN<98>")
		)
	)
	(footprint ""
		(layer "F.Cu")
		(at 143.030194 -297.205908 -90)
		(property "Reference" "C3225"
			(at 0 0 270)
			(layer "F.SilkS")
			(hide yes)
			(effects
				(font
					(size 1.27 1.27)
				)
			)
		)
		(property "Value" ""
			(at 0 0 270)
			(layer "F.Fab")
			(effects
				(font
					(size 1.27 1.27)
				)
			)
		)
		(duplicate_pad_numbers_are_jumpers no)
		(fp_line
			(start -1.2954 0.5842)
			(end -1.2954 -0.5842)
			(stroke
				(width 0.1524)
				(type default)
			)
			(layer "F.SilkS")
		)
		(fp_line
			(start 1.2954 0.5842)
			(end -1.2954 0.5842)
			(stroke
				(width 0.1524)
				(type default)
			)
			(layer "F.SilkS")
		)
		(fp_line
			(start -1.2954 -0.5842)
			(end 1.2954 -0.5842)
			(stroke
				(width 0.1524)
				(type default)
			)
			(layer "F.SilkS")
		)
		(fp_line
			(start 1.2954 -0.5842)
			(end 1.2954 0.5842)
			(stroke
				(width 0.1524)
				(type default)
			)
			(layer "F.SilkS")
		)
		(fp_line
			(start -0.8636 0.4572)
			(end -0.8636 0.4064)
			(stroke
				(width 0.1)
				(type default)
			)
			(layer "F.Fab")
		)
		(fp_line
			(start 0.8636 0.4572)
			(end -0.8636 0.4572)
			(stroke
				(width 0.1)
				(type default)
			)
			(layer "F.Fab")
		)
		(fp_line
			(start -1.1938 0.4064)
			(end -1.1938 -0.4064)
			(stroke
				(width 0.1)
				(type default)
			)
			(layer "F.Fab")
		)
		(fp_line
			(start -0.8636 0.4064)
			(end -1.1938 0.4064)
			(stroke
				(width 0.1)
				(type default)
			)
			(layer "F.Fab")
		)
		(fp_line
			(start 0.8636 0.4064)
			(end 0.8636 0.4572)
			(stroke
				(width 0.1)
				(type default)
			)
			(layer "F.Fab")
		)
		(fp_line
			(start 1.1938 0.4064)
			(end 0.8636 0.4064)
			(stroke
				(width 0.1)
				(type default)
			)
			(layer "F.Fab")
		)
		(fp_line
			(start -1.1938 -0.4064)
			(end -0.8636 -0.4064)
			(stroke
				(width 0.1)
				(type default)
			)
			(layer "F.Fab")
		)
		(fp_line
			(start -0.8636 -0.4064)
			(end -0.8636 -0.4572)
			(stroke
				(width 0.1)
				(type default)
			)
			(layer "F.Fab")
		)
		(fp_line
			(start 0.8636 -0.4064)
			(end 1.1938 -0.4064)
			(stroke
				(width 0.1)
				(type default)
			)
			(layer "F.Fab")
		)
		(fp_line
			(start 1.1938 -0.4064)
			(end 1.1938 0.4064)
			(stroke
				(width 0.1)
				(type default)
			)
			(layer "F.Fab")
		)
		(fp_line
			(start -0.8636 -0.4572)
			(end 0.8636 -0.4572)
			(stroke
				(width 0.1)
				(type default)
			)
			(layer "F.Fab")
		)
		(fp_line
			(start 0.8636 -0.4572)
			(end 0.8636 -0.4064)
			(stroke
				(width 0.1)
				(type default)
			)
			(layer "F.Fab")
		)
		(pad "1" smd rect
			(at -0.7366 0 180)
			(size 0.7112 0.8128)
			(layers "F.Cu" "F.Mask" "F.Paste")
			(net "P1V8_PLL0_PEX1")
		)
		(pad "2" smd rect
			(at 0.7366 0 180)
			(size 0.7112 0.8128)
			(layers "F.Cu" "F.Mask" "F.Paste")
			(net "GND")
		)
	)
	(footprint ""
		(layer "F.Cu")
		(at 252.775466 -69.47916 180)
		(property "Reference" "PU111"
			(at -1.835404 3.92684 90)
			(unlocked yes)
			(layer "F.SilkS")
			(effects
				(font
					(size 0.7874 0.5842)
					(thickness 0.1524)
				)
			)
		)
		(property "Value" ""
			(at 0 0 180)
			(layer "F.Fab")
			(effects
				(font
					(size 1.27 1.27)
				)
			)
		)
		(duplicate_pad_numbers_are_jumpers no)
		(fp_line
			(start 1.239774 1.495298)
			(end -1.239774 1.495298)
			(stroke
				(width 0.1524)
				(type default)
			)
			(layer "F.SilkS")
		)
		(fp_line
			(start 1.239774 -1.495298)
			(end 1.239774 1.495298)
			(stroke
				(width 0.1524)
				(type default)
			)
			(layer "F.SilkS")
		)
		(fp_line
			(start -1.239774 1.495298)
			(end -1.239774 -1.495298)
			(stroke
				(width 0.1524)
				(type default)
			)
			(layer "F.SilkS")
		)
		(fp_line
			(start -1.239774 -1.495298)
			(end 1.239774 -1.495298)
			(stroke
				(width 0.1524)
				(type default)
			)
			(layer "F.SilkS")
		)
		(fp_poly
			(pts
				(xy -1.68021 -2.025904) (xy -2.398522 -1.307338) (xy -1.3208 -0.948182)
			)
			(stroke
				(width 0)
				(type default)
			)
			(fill yes)
			(layer "F.SilkS")
		)
		(fp_line
			(start 0.8001 1.050036)
			(end -0.8001 1.050036)
			(stroke
				(width 0.1)
				(type default)
			)
			(layer "F.Fab")
		)
		(fp_line
			(start 0.8001 -1.050036)
			(end 0.8001 1.050036)
			(stroke
				(width 0.1)
				(type default)
			)
			(layer "F.Fab")
		)
		(fp_line
			(start -0.8001 1.050036)
			(end -0.8001 -1.050036)
			(stroke
				(width 0.1)
				(type default)
			)
			(layer "F.Fab")
		)
		(fp_line
			(start -0.8001 -1.050036)
			(end 0.8001 -1.050036)
			(stroke
				(width 0.1)
				(type default)
			)
			(layer "F.Fab")
		)
		(fp_poly
			(pts
				(xy -2.458974 -0.508) (xy -2.458974 0.508) (xy -1.442974 0)
			)
			(stroke
				(width 0)
				(type default)
			)
			(fill yes)
			(layer "F.Fab")
		)
		(pad "1_2" smd circle
			(at -0.374904 0 270)
			(size 0 0)
			(layers "F.Cu" "F.Mask" "F.Paste")
			(net "P12V_AUX")
		)
		(pad "3" smd rect
			(at -0.499872 0.999998 180)
			(size 0.254 0.7112)
			(layers "F.Cu" "F.Mask" "F.Paste")
			(net "GND")
		)
		(pad "4" smd rect
			(at 0 0.999998 180)
			(size 0.254 0.7112)
			(layers "F.Cu" "F.Mask" "F.Paste")
			(net "P12V_SSD8_CO_ILIMIT")
		)
		(pad "5" smd rect
			(at 0.499872 0.999998 180)
			(size 0.254 0.7112)
			(layers "F.Cu" "F.Mask" "F.Paste")
			(net "P12V_SSD8_CO_MODE")
		)
		(pad "6_7" smd circle
			(at 0.374904 0 90)
			(size 0 0)
			(layers "F.Cu" "F.Mask" "F.Paste")
			(net "P12V_SSD8_R")
		)
		(pad "8" smd rect
			(at 0.499872 -0.999998 180)
			(size 0.254 0.7112)
			(layers "F.Cu" "F.Mask" "F.Paste")
			(net "P12V_SSD8_CO_GATE")
		)
		(pad "9" smd rect
			(at 0 -0.999998 180)
			(size 0.254 0.7112)
			(layers "F.Cu" "F.Mask" "F.Paste")
			(net "P12V_SSD8_CO_EN")
		)
		(pad "10" smd rect
			(at -0.499872 -0.999998 180)
			(size 0.254 0.7112)
			(layers "F.Cu" "F.Mask" "F.Paste")
			(net "P12V_SSD8_CO_DV_DT")
		)
	)
	(footprint ""
		(layer "F.Cu")
		(at 406.484582 -367.02619 -90)
		(property "Reference" "R6677"
			(at 0 0 270)
			(layer "F.SilkS")
			(hide yes)
			(effects
				(font
					(size 1.27 1.27)
				)
			)
		)
		(property "Value" ""
			(at 0 0 270)
			(layer "F.Fab")
			(effects
				(font
					(size 1.27 1.27)
				)
			)
		)
		(duplicate_pad_numbers_are_jumpers no)
		(fp_line
			(start -0.7874 0.4064)
			(end -0.7874 -0.4064)
			(stroke
				(width 0.1524)
				(type default)
			)
			(layer "F.SilkS")
		)
		(fp_line
			(start 0.7874 0.4064)
			(end -0.7874 0.4064)
			(stroke
				(width 0.1524)
				(type default)
			)
			(layer "F.SilkS")
		)
		(fp_line
			(start -0.7874 -0.4064)
			(end 0.7874 -0.4064)
			(stroke
				(width 0.1524)
				(type default)
			)
			(layer "F.SilkS")
		)
		(fp_line
			(start 0.7874 -0.4064)
			(end 0.7874 0.4064)
			(stroke
				(width 0.1524)
				(type default)
			)
			(layer "F.SilkS")
		)
		(fp_line
			(start -0.67945 0.3048)
			(end -0.67945 -0.305054)
			(stroke
				(width 0.1)
				(type default)
			)
			(layer "F.Fab")
		)
		(fp_line
			(start -0.12065 0.3048)
			(end -0.67945 0.3048)
			(stroke
				(width 0.1)
				(type default)
			)
			(layer "F.Fab")
		)
		(fp_line
			(start 0.120396 0.3048)
			(end 0.120396 0.2794)
			(stroke
				(width 0.1)
				(type default)
			)
			(layer "F.Fab")
		)
		(fp_line
			(start 0.67945 0.3048)
			(end 0.120396 0.3048)
			(stroke
				(width 0.1)
				(type default)
			)
			(layer "F.Fab")
		)
		(fp_line
			(start -0.12065 0.2794)
			(end -0.12065 0.3048)
			(stroke
				(width 0.1)
				(type default)
			)
			(layer "F.Fab")
		)
		(fp_line
			(start 0.120396 0.2794)
			(end -0.12065 0.2794)
			(stroke
				(width 0.1)
				(type default)
			)
			(layer "F.Fab")
		)
		(fp_line
			(start -0.12065 -0.2794)
			(end 0.12065 -0.2794)
			(stroke
				(width 0.1)
				(type default)
			)
			(layer "F.Fab")
		)
		(fp_line
			(start 0.12065 -0.2794)
			(end 0.12065 -0.3048)
			(stroke
				(width 0.1)
				(type default)
			)
			(layer "F.Fab")
		)
		(fp_line
			(start 0.12065 -0.3048)
			(end 0.67945 -0.3048)
			(stroke
				(width 0.1)
				(type default)
			)
			(layer "F.Fab")
		)
		(fp_line
			(start 0.67945 -0.3048)
			(end 0.67945 0.3048)
			(stroke
				(width 0.1)
				(type default)
			)
			(layer "F.Fab")
		)
		(fp_line
			(start -0.67945 -0.305054)
			(end -0.12065 -0.305054)
			(stroke
				(width 0.1)
				(type default)
			)
			(layer "F.Fab")
		)
		(fp_line
			(start -0.12065 -0.305054)
			(end -0.12065 -0.2794)
			(stroke
				(width 0.1)
				(type default)
			)
			(layer "F.Fab")
		)
		(pad "1" smd circle
			(at -0.40005 0 270)
			(size 0 0)
			(layers "F.Cu" "F.Mask" "F.Paste")
			(net "GPU_3V3IO_RSVD1_N")
		)
		(pad "2" smd circle
			(at 0.40005 0 270)
			(size 0 0)
			(layers "F.Cu" "F.Mask" "F.Paste")
			(net "P3V3_AUX")
		)
	)
	(footprint ""
		(layer "F.Cu")
		(at 322.611242 -107.29976)
		(property "Reference" "R738"
			(at 0 0 0)
			(layer "F.SilkS")
			(hide yes)
			(effects
				(font
					(size 1.27 1.27)
				)
			)
		)
		(property "Value" ""
			(at 0 0 0)
			(layer "F.Fab")
			(effects
				(font
					(size 1.27 1.27)
				)
			)
		)
		(duplicate_pad_numbers_are_jumpers no)
		(fp_line
			(start -3.937508 -1.8796)
			(end -3.937508 1.8796)
			(stroke
				(width 0.1524)
				(type default)
			)
			(layer "F.SilkS")
		)
		(fp_line
			(start -3.937508 1.8796)
			(end 3.937508 1.8796)
			(stroke
				(width 0.1524)
				(type default)
			)
			(layer "F.SilkS")
		)
		(fp_line
			(start 3.937508 -1.8796)
			(end -3.937508 -1.8796)
			(stroke
				(width 0.1524)
				(type default)
			)
			(layer "F.SilkS")
		)
		(fp_line
			(start 3.937508 1.8796)
			(end 3.937508 -1.8796)
			(stroke
				(width 0.1524)
				(type default)
			)
			(layer "F.SilkS")
		)
		(fp_line
			(start -3.275076 -1.674876)
			(end -3.275076 1.674876)
			(stroke
				(width 0.1)
				(type default)
			)
			(layer "F.Fab")
		)
		(fp_line
			(start -3.275076 1.674876)
			(end 3.275076 1.674876)
			(stroke
				(width 0.1)
				(type default)
			)
			(layer "F.Fab")
		)
		(fp_line
			(start 3.275076 -1.674876)
			(end -3.275076 -1.674876)
			(stroke
				(width 0.1)
				(type default)
			)
			(layer "F.Fab")
		)
		(fp_line
			(start 3.275076 1.674876)
			(end 3.275076 -1.674876)
			(stroke
				(width 0.1)
				(type default)
			)
			(layer "F.Fab")
		)
		(pad "1" smd rect
			(at -2.350008 0)
			(size 2.921 3.5052)
			(layers "F.Cu" "F.Mask" "F.Paste")
			(net "P12V_NIC5")
		)
		(pad "2" smd rect
			(at 2.350008 0)
			(size 2.921 3.5052)
			(layers "F.Cu" "F.Mask" "F.Paste")
			(net "P12V_NIC5_R")
		)
	)
	(footprint ""
		(layer "F.Cu")
		(at 210.475322 -227.225606 -90)
		(property "Reference" "C2569"
			(at 0 0 270)
			(layer "F.SilkS")
			(hide yes)
			(effects
				(font
					(size 1.27 1.27)
				)
			)
		)
		(property "Value" ""
			(at 0 0 270)
			(layer "F.Fab")
			(effects
				(font
					(size 1.27 1.27)
				)
			)
		)
		(duplicate_pad_numbers_are_jumpers no)
		(fp_line
			(start -0.7874 0.4064)
			(end -0.7874 -0.4064)
			(stroke
				(width 0.1524)
				(type default)
			)
			(layer "F.SilkS")
		)
		(fp_line
			(start 0.7874 0.4064)
			(end -0.7874 0.4064)
			(stroke
				(width 0.1524)
				(type default)
			)
			(layer "F.SilkS")
		)
		(fp_line
			(start -0.7874 -0.4064)
			(end 0.7874 -0.4064)
			(stroke
				(width 0.1524)
				(type default)
			)
			(layer "F.SilkS")
		)
		(fp_line
			(start 0.7874 -0.4064)
			(end 0.7874 0.4064)
			(stroke
				(width 0.1524)
				(type default)
			)
			(layer "F.SilkS")
		)
		(fp_line
			(start -0.67945 0.3048)
			(end -0.67945 -0.305054)
			(stroke
				(width 0.1)
				(type default)
			)
			(layer "F.Fab")
		)
		(fp_line
			(start -0.12065 0.3048)
			(end -0.67945 0.3048)
			(stroke
				(width 0.1)
				(type default)
			)
			(layer "F.Fab")
		)
		(fp_line
			(start 0.120396 0.3048)
			(end 0.120396 0.2794)
			(stroke
				(width 0.1)
				(type default)
			)
			(layer "F.Fab")
		)
		(fp_line
			(start 0.67945 0.3048)
			(end 0.120396 0.3048)
			(stroke
				(width 0.1)
				(type default)
			)
			(layer "F.Fab")
		)
		(fp_line
			(start -0.12065 0.2794)
			(end -0.12065 0.3048)
			(stroke
				(width 0.1)
				(type default)
			)
			(layer "F.Fab")
		)
		(fp_line
			(start 0.120396 0.2794)
			(end -0.12065 0.2794)
			(stroke
				(width 0.1)
				(type default)
			)
			(layer "F.Fab")
		)
		(fp_line
			(start -0.12065 -0.2794)
			(end 0.12065 -0.2794)
			(stroke
				(width 0.1)
				(type default)
			)
			(layer "F.Fab")
		)
		(fp_line
			(start 0.12065 -0.2794)
			(end 0.12065 -0.3048)
			(stroke
				(width 0.1)
				(type default)
			)
			(layer "F.Fab")
		)
		(fp_line
			(start 0.12065 -0.3048)
			(end 0.67945 -0.3048)
			(stroke
				(width 0.1)
				(type default)
			)
			(layer "F.Fab")
		)
		(fp_line
			(start 0.67945 -0.3048)
			(end 0.67945 0.3048)
			(stroke
				(width 0.1)
				(type default)
			)
			(layer "F.Fab")
		)
		(fp_line
			(start -0.67945 -0.305054)
			(end -0.12065 -0.305054)
			(stroke
				(width 0.1)
				(type default)
			)
			(layer "F.Fab")
		)
		(fp_line
			(start -0.12065 -0.305054)
			(end -0.12065 -0.2794)
			(stroke
				(width 0.1)
				(type default)
			)
			(layer "F.Fab")
		)
		(pad "1" smd circle
			(at -0.40005 0 270)
			(size 0 0)
			(layers "F.Cu" "F.Mask" "F.Paste")
			(net "GND")
		)
		(pad "2" smd circle
			(at 0.40005 0 270)
			(size 0 0)
			(layers "F.Cu" "F.Mask" "F.Paste")
			(net "P3V3_AUX")
		)
	)
	(footprint ""
		(layer "F.Cu")
		(at 312.739532 -137.645648)
		(property "Reference" "R260"
			(at 0 0 0)
			(layer "F.SilkS")
			(hide yes)
			(effects
				(font
					(size 1.27 1.27)
				)
			)
		)
		(property "Value" ""
			(at 0 0 0)
			(layer "F.Fab")
			(effects
				(font
					(size 1.27 1.27)
				)
			)
		)
		(duplicate_pad_numbers_are_jumpers no)
		(fp_line
			(start -0.7874 -0.4064)
			(end 0.7874 -0.4064)
			(stroke
				(width 0.1524)
				(type default)
			)
			(layer "F.SilkS")
		)
		(fp_line
			(start -0.7874 0.4064)
			(end -0.7874 -0.4064)
			(stroke
				(width 0.1524)
				(type default)
			)
			(layer "F.SilkS")
		)
		(fp_line
			(start 0.7874 -0.4064)
			(end 0.7874 0.4064)
			(stroke
				(width 0.1524)
				(type default)
			)
			(layer "F.SilkS")
		)
		(fp_line
			(start 0.7874 0.4064)
			(end -0.7874 0.4064)
			(stroke
				(width 0.1524)
				(type default)
			)
			(layer "F.SilkS")
		)
		(fp_line
			(start -0.67945 -0.305054)
			(end -0.12065 -0.305054)
			(stroke
				(width 0.1)
				(type default)
			)
			(layer "F.Fab")
		)
		(fp_line
			(start -0.67945 0.3048)
			(end -0.67945 -0.305054)
			(stroke
				(width 0.1)
				(type default)
			)
			(layer "F.Fab")
		)
		(fp_line
			(start -0.12065 -0.305054)
			(end -0.12065 -0.2794)
			(stroke
				(width 0.1)
				(type default)
			)
			(layer "F.Fab")
		)
		(fp_line
			(start -0.12065 -0.2794)
			(end 0.12065 -0.2794)
			(stroke
				(width 0.1)
				(type default)
			)
			(layer "F.Fab")
		)
		(fp_line
			(start -0.12065 0.2794)
			(end -0.12065 0.3048)
			(stroke
				(width 0.1)
				(type default)
			)
			(layer "F.Fab")
		)
		(fp_line
			(start -0.12065 0.3048)
			(end -0.67945 0.3048)
			(stroke
				(width 0.1)
				(type default)
			)
			(layer "F.Fab")
		)
		(fp_line
			(start 0.120396 0.2794)
			(end -0.12065 0.2794)
			(stroke
				(width 0.1)
				(type default)
			)
			(layer "F.Fab")
		)
		(fp_line
			(start 0.120396 0.3048)
			(end 0.120396 0.2794)
			(stroke
				(width 0.1)
				(type default)
			)
			(layer "F.Fab")
		)
		(fp_line
			(start 0.12065 -0.3048)
			(end 0.67945 -0.3048)
			(stroke
				(width 0.1)
				(type default)
			)
			(layer "F.Fab")
		)
		(fp_line
			(start 0.12065 -0.2794)
			(end 0.12065 -0.3048)
			(stroke
				(width 0.1)
				(type default)
			)
			(layer "F.Fab")
		)
		(fp_line
			(start 0.67945 -0.3048)
			(end 0.67945 0.3048)
			(stroke
				(width 0.1)
				(type default)
			)
			(layer "F.Fab")
		)
		(fp_line
			(start 0.67945 0.3048)
			(end 0.120396 0.3048)
			(stroke
				(width 0.1)
				(type default)
			)
			(layer "F.Fab")
		)
		(pad "1" smd circle
			(at -0.40005 0)
			(size 0 0)
			(layers "F.Cu" "F.Mask" "F.Paste")
			(net "PRSNTB0_NIC5_N")
		)
		(pad "2" smd circle
			(at 0.40005 0)
			(size 0 0)
			(layers "F.Cu" "F.Mask" "F.Paste")
			(net "P3V3_AUX")
		)
	)
	(footprint ""
		(layer "F.Cu")
		(at 334.130396 -121.80824 180)
		(property "Reference" "R6041"
			(at 0 0 180)
			(layer "F.SilkS")
			(hide yes)
			(effects
				(font
					(size 1.27 1.27)
				)
			)
		)
		(property "Value" ""
			(at 0 0 180)
			(layer "F.Fab")
			(effects
				(font
					(size 1.27 1.27)
				)
			)
		)
		(duplicate_pad_numbers_are_jumpers no)
		(fp_line
			(start 0.7874 0.4064)
			(end -0.7874 0.4064)
			(stroke
				(width 0.1524)
				(type default)
			)
			(layer "F.SilkS")
		)
		(fp_line
			(start 0.7874 -0.4064)
			(end 0.7874 0.4064)
			(stroke
				(width 0.1524)
				(type default)
			)
			(layer "F.SilkS")
		)
		(fp_line
			(start -0.7874 0.4064)
			(end -0.7874 -0.4064)
			(stroke
				(width 0.1524)
				(type default)
			)
			(layer "F.SilkS")
		)
		(fp_line
			(start -0.7874 -0.4064)
			(end 0.7874 -0.4064)
			(stroke
				(width 0.1524)
				(type default)
			)
			(layer "F.SilkS")
		)
		(fp_line
			(start 0.67945 0.3048)
			(end 0.120396 0.3048)
			(stroke
				(width 0.1)
				(type default)
			)
			(layer "F.Fab")
		)
		(fp_line
			(start 0.67945 -0.3048)
			(end 0.67945 0.3048)
			(stroke
				(width 0.1)
				(type default)
			)
			(layer "F.Fab")
		)
		(fp_line
			(start 0.12065 -0.2794)
			(end 0.12065 -0.3048)
			(stroke
				(width 0.1)
				(type default)
			)
			(layer "F.Fab")
		)
		(fp_line
			(start 0.12065 -0.3048)
			(end 0.67945 -0.3048)
			(stroke
				(width 0.1)
				(type default)
			)
			(layer "F.Fab")
		)
		(fp_line
			(start 0.120396 0.3048)
			(end 0.120396 0.2794)
			(stroke
				(width 0.1)
				(type default)
			)
			(layer "F.Fab")
		)
		(fp_line
			(start 0.120396 0.2794)
			(end -0.12065 0.2794)
			(stroke
				(width 0.1)
				(type default)
			)
			(layer "F.Fab")
		)
		(fp_line
			(start -0.12065 0.3048)
			(end -0.67945 0.3048)
			(stroke
				(width 0.1)
				(type default)
			)
			(layer "F.Fab")
		)
		(fp_line
			(start -0.12065 0.2794)
			(end -0.12065 0.3048)
			(stroke
				(width 0.1)
				(type default)
			)
			(layer "F.Fab")
		)
		(fp_line
			(start -0.12065 -0.2794)
			(end 0.12065 -0.2794)
			(stroke
				(width 0.1)
				(type default)
			)
			(layer "F.Fab")
		)
		(fp_line
			(start -0.12065 -0.305054)
			(end -0.12065 -0.2794)
			(stroke
				(width 0.1)
				(type default)
			)
			(layer "F.Fab")
		)
		(fp_line
			(start -0.67945 0.3048)
			(end -0.67945 -0.305054)
			(stroke
				(width 0.1)
				(type default)
			)
			(layer "F.Fab")
		)
		(fp_line
			(start -0.67945 -0.305054)
			(end -0.12065 -0.305054)
			(stroke
				(width 0.1)
				(type default)
			)
			(layer "F.Fab")
		)
		(pad "1" smd circle
			(at -0.40005 0 180)
			(size 0 0)
			(layers "F.Cu" "F.Mask" "F.Paste")
			(net "P3V3_NIC5_PG_G1")
		)
		(pad "2" smd circle
			(at 0.40005 0 180)
			(size 0 0)
			(layers "F.Cu" "F.Mask" "F.Paste")
			(net "GND")
		)
	)
	(footprint ""
		(layer "F.Cu")
		(at 26.374344 -252.356874 -90)
		(property "Reference" "R1192"
			(at 0 0 270)
			(layer "F.SilkS")
			(hide yes)
			(effects
				(font
					(size 1.27 1.27)
				)
			)
		)
		(property "Value" ""
			(at 0 0 270)
			(layer "F.Fab")
			(effects
				(font
					(size 1.27 1.27)
				)
			)
		)
		(duplicate_pad_numbers_are_jumpers no)
		(fp_line
			(start -0.7874 0.4064)
			(end -0.7874 -0.4064)
			(stroke
				(width 0.1524)
				(type default)
			)
			(layer "F.SilkS")
		)
		(fp_line
			(start 0.7874 0.4064)
			(end -0.7874 0.4064)
			(stroke
				(width 0.1524)
				(type default)
			)
			(layer "F.SilkS")
		)
		(fp_line
			(start -0.7874 -0.4064)
			(end 0.7874 -0.4064)
			(stroke
				(width 0.1524)
				(type default)
			)
			(layer "F.SilkS")
		)
		(fp_line
			(start 0.7874 -0.4064)
			(end 0.7874 0.4064)
			(stroke
				(width 0.1524)
				(type default)
			)
			(layer "F.SilkS")
		)
		(fp_line
			(start -0.67945 0.3048)
			(end -0.67945 -0.305054)
			(stroke
				(width 0.1)
				(type default)
			)
			(layer "F.Fab")
		)
		(fp_line
			(start -0.12065 0.3048)
			(end -0.67945 0.3048)
			(stroke
				(width 0.1)
				(type default)
			)
			(layer "F.Fab")
		)
		(fp_line
			(start 0.120396 0.3048)
			(end 0.120396 0.2794)
			(stroke
				(width 0.1)
				(type default)
			)
			(layer "F.Fab")
		)
		(fp_line
			(start 0.67945 0.3048)
			(end 0.120396 0.3048)
			(stroke
				(width 0.1)
				(type default)
			)
			(layer "F.Fab")
		)
		(fp_line
			(start -0.12065 0.2794)
			(end -0.12065 0.3048)
			(stroke
				(width 0.1)
				(type default)
			)
			(layer "F.Fab")
		)
		(fp_line
			(start 0.120396 0.2794)
			(end -0.12065 0.2794)
			(stroke
				(width 0.1)
				(type default)
			)
			(layer "F.Fab")
		)
		(fp_line
			(start -0.12065 -0.2794)
			(end 0.12065 -0.2794)
			(stroke
				(width 0.1)
				(type default)
			)
			(layer "F.Fab")
		)
		(fp_line
			(start 0.12065 -0.2794)
			(end 0.12065 -0.3048)
			(stroke
				(width 0.1)
				(type default)
			)
			(layer "F.Fab")
		)
		(fp_line
			(start 0.12065 -0.3048)
			(end 0.67945 -0.3048)
			(stroke
				(width 0.1)
				(type default)
			)
			(layer "F.Fab")
		)
		(fp_line
			(start 0.67945 -0.3048)
			(end 0.67945 0.3048)
			(stroke
				(width 0.1)
				(type default)
			)
			(layer "F.Fab")
		)
		(fp_line
			(start -0.67945 -0.305054)
			(end -0.12065 -0.305054)
			(stroke
				(width 0.1)
				(type default)
			)
			(layer "F.Fab")
		)
		(fp_line
			(start -0.12065 -0.305054)
			(end -0.12065 -0.2794)
			(stroke
				(width 0.1)
				(type default)
			)
			(layer "F.Fab")
		)
		(pad "1" smd circle
			(at -0.40005 0 270)
			(size 0 0)
			(layers "F.Cu" "F.Mask" "F.Paste")
			(net "GND")
		)
		(pad "2" smd circle
			(at 0.40005 0 270)
			(size 0 0)
			(layers "F.Cu" "F.Mask" "F.Paste")
			(net "PEX0_MODE_SEL2")
		)
	)
	(footprint ""
		(layer "F.Cu")
		(at 327.533 -211.201)
		(property "Reference" "R4160"
			(at 0 0 0)
			(layer "F.SilkS")
			(hide yes)
			(effects
				(font
					(size 1.27 1.27)
				)
			)
		)
		(property "Value" ""
			(at 0 0 0)
			(layer "F.Fab")
			(effects
				(font
					(size 1.27 1.27)
				)
			)
		)
		(duplicate_pad_numbers_are_jumpers no)
		(fp_line
			(start -0.7874 -0.4064)
			(end 0.7874 -0.4064)
			(stroke
				(width 0.1524)
				(type default)
			)
			(layer "F.SilkS")
		)
		(fp_line
			(start -0.7874 0.4064)
			(end -0.7874 -0.4064)
			(stroke
				(width 0.1524)
				(type default)
			)
			(layer "F.SilkS")
		)
		(fp_line
			(start 0.7874 -0.4064)
			(end 0.7874 0.4064)
			(stroke
				(width 0.1524)
				(type default)
			)
			(layer "F.SilkS")
		)
		(fp_line
			(start 0.7874 0.4064)
			(end -0.7874 0.4064)
			(stroke
				(width 0.1524)
				(type default)
			)
			(layer "F.SilkS")
		)
		(fp_line
			(start -0.67945 -0.305054)
			(end -0.12065 -0.305054)
			(stroke
				(width 0.1)
				(type default)
			)
			(layer "F.Fab")
		)
		(fp_line
			(start -0.67945 0.3048)
			(end -0.67945 -0.305054)
			(stroke
				(width 0.1)
				(type default)
			)
			(layer "F.Fab")
		)
		(fp_line
			(start -0.12065 -0.305054)
			(end -0.12065 -0.2794)
			(stroke
				(width 0.1)
				(type default)
			)
			(layer "F.Fab")
		)
		(fp_line
			(start -0.12065 -0.2794)
			(end 0.12065 -0.2794)
			(stroke
				(width 0.1)
				(type default)
			)
			(layer "F.Fab")
		)
		(fp_line
			(start -0.12065 0.2794)
			(end -0.12065 0.3048)
			(stroke
				(width 0.1)
				(type default)
			)
			(layer "F.Fab")
		)
		(fp_line
			(start -0.12065 0.3048)
			(end -0.67945 0.3048)
			(stroke
				(width 0.1)
				(type default)
			)
			(layer "F.Fab")
		)
		(fp_line
			(start 0.120396 0.2794)
			(end -0.12065 0.2794)
			(stroke
				(width 0.1)
				(type default)
			)
			(layer "F.Fab")
		)
		(fp_line
			(start 0.120396 0.3048)
			(end 0.120396 0.2794)
			(stroke
				(width 0.1)
				(type default)
			)
			(layer "F.Fab")
		)
		(fp_line
			(start 0.12065 -0.3048)
			(end 0.67945 -0.3048)
			(stroke
				(width 0.1)
				(type default)
			)
			(layer "F.Fab")
		)
		(fp_line
			(start 0.12065 -0.2794)
			(end 0.12065 -0.3048)
			(stroke
				(width 0.1)
				(type default)
			)
			(layer "F.Fab")
		)
		(fp_line
			(start 0.67945 -0.3048)
			(end 0.67945 0.3048)
			(stroke
				(width 0.1)
				(type default)
			)
			(layer "F.Fab")
		)
		(fp_line
			(start 0.67945 0.3048)
			(end 0.120396 0.3048)
			(stroke
				(width 0.1)
				(type default)
			)
			(layer "F.Fab")
		)
		(pad "1" smd circle
			(at -0.40005 0)
			(size 0 0)
			(layers "F.Cu" "F.Mask" "F.Paste")
			(net "PRSNT_SSD13_FPGA_R_N")
		)
		(pad "2" smd circle
			(at 0.40005 0)
			(size 0 0)
			(layers "F.Cu" "F.Mask" "F.Paste")
			(net "PRSNT_SSD13_FPGA_N")
		)
	)
	(footprint ""
		(layer "F.Cu")
		(at 364.612936 -118.378986 90)
		(property "Reference" "PC910"
			(at 0 0 90)
			(layer "F.SilkS")
			(hide yes)
			(effects
				(font
					(size 1.27 1.27)
				)
			)
		)
		(property "Value" ""
			(at 0 0 90)
			(layer "F.Fab")
			(effects
				(font
					(size 1.27 1.27)
				)
			)
		)
		(duplicate_pad_numbers_are_jumpers no)
		(fp_line
			(start 0.7874 -0.4064)
			(end 0.7874 0.4064)
			(stroke
				(width 0.1524)
				(type default)
			)
			(layer "F.SilkS")
		)
		(fp_line
			(start -0.7874 -0.4064)
			(end 0.7874 -0.4064)
			(stroke
				(width 0.1524)
				(type default)
			)
			(layer "F.SilkS")
		)
		(fp_line
			(start 0.7874 0.4064)
			(end -0.7874 0.4064)
			(stroke
				(width 0.1524)
				(type default)
			)
			(layer "F.SilkS")
		)
		(fp_line
			(start -0.7874 0.4064)
			(end -0.7874 -0.4064)
			(stroke
				(width 0.1524)
				(type default)
			)
			(layer "F.SilkS")
		)
		(fp_line
			(start -0.12065 -0.305054)
			(end -0.12065 -0.2794)
			(stroke
				(width 0.1)
				(type default)
			)
			(layer "F.Fab")
		)
		(fp_line
			(start -0.67945 -0.305054)
			(end -0.12065 -0.305054)
			(stroke
				(width 0.1)
				(type default)
			)
			(layer "F.Fab")
		)
		(fp_line
			(start 0.67945 -0.3048)
			(end 0.67945 0.3048)
			(stroke
				(width 0.1)
				(type default)
			)
			(layer "F.Fab")
		)
		(fp_line
			(start 0.12065 -0.3048)
			(end 0.67945 -0.3048)
			(stroke
				(width 0.1)
				(type default)
			)
			(layer "F.Fab")
		)
		(fp_line
			(start 0.12065 -0.2794)
			(end 0.12065 -0.3048)
			(stroke
				(width 0.1)
				(type default)
			)
			(layer "F.Fab")
		)
		(fp_line
			(start -0.12065 -0.2794)
			(end 0.12065 -0.2794)
			(stroke
				(width 0.1)
				(type default)
			)
			(layer "F.Fab")
		)
		(fp_line
			(start 0.120396 0.2794)
			(end -0.12065 0.2794)
			(stroke
				(width 0.1)
				(type default)
			)
			(layer "F.Fab")
		)
		(fp_line
			(start -0.12065 0.2794)
			(end -0.12065 0.3048)
			(stroke
				(width 0.1)
				(type default)
			)
			(layer "F.Fab")
		)
		(fp_line
			(start 0.67945 0.3048)
			(end 0.120396 0.3048)
			(stroke
				(width 0.1)
				(type default)
			)
			(layer "F.Fab")
		)
		(fp_line
			(start 0.120396 0.3048)
			(end 0.120396 0.2794)
			(stroke
				(width 0.1)
				(type default)
			)
			(layer "F.Fab")
		)
		(fp_line
			(start -0.12065 0.3048)
			(end -0.67945 0.3048)
			(stroke
				(width 0.1)
				(type default)
			)
			(layer "F.Fab")
		)
		(fp_line
			(start -0.67945 0.3048)
			(end -0.67945 -0.305054)
			(stroke
				(width 0.1)
				(type default)
			)
			(layer "F.Fab")
		)
		(pad "1" smd circle
			(at -0.40005 0 90)
			(size 0 0)
			(layers "F.Cu" "F.Mask" "F.Paste")
			(net "P3V3_NIC6_CO_GATE")
		)
		(pad "2" smd circle
			(at 0.40005 0 90)
			(size 0 0)
			(layers "F.Cu" "F.Mask" "F.Paste")
			(net "GND")
		)
	)
	(footprint ""
		(layer "F.Cu")
		(at 82.661506 -148.91131 180)
		(property "Reference" "C9"
			(at 0 0 180)
			(layer "F.SilkS")
			(hide yes)
			(effects
				(font
					(size 1.27 1.27)
				)
			)
		)
		(property "Value" ""
			(at 0 0 180)
			(layer "F.Fab")
			(effects
				(font
					(size 1.27 1.27)
				)
			)
		)
		(duplicate_pad_numbers_are_jumpers no)
		(fp_line
			(start 0.299974 0.150114)
			(end -0.299974 0.150114)
			(stroke
				(width 0.1)
				(type default)
			)
			(layer "F.Fab")
		)
		(fp_line
			(start 0.299974 -0.150114)
			(end 0.299974 0.150114)
			(stroke
				(width 0.1)
				(type default)
			)
			(layer "F.Fab")
		)
		(fp_line
			(start -0.299974 0.150114)
			(end -0.299974 -0.150114)
			(stroke
				(width 0.1)
				(type default)
			)
			(layer "F.Fab")
		)
		(fp_line
			(start -0.299974 -0.150114)
			(end 0.299974 -0.150114)
			(stroke
				(width 0.1)
				(type default)
			)
			(layer "F.Fab")
		)
		(pad "1" smd rect
			(at -0.2667 0 180)
			(size 0.3048 0.381)
			(layers "F.Cu" "F.Mask" "F.Paste")
			(net "P5E_PEX0_STN0_TX_DP<11>")
		)
		(pad "2" smd rect
			(at 0.2667 0 180)
			(size 0.3048 0.381)
			(layers "F.Cu" "F.Mask" "F.Paste")
			(net "P5E_PEX0_STN0_TX_C_DP<11>")
		)
	)
	(footprint ""
		(layer "F.Cu")
		(at 239.754664 -206.51216 90)
		(property "Reference" "R4850"
			(at 0 0 90)
			(layer "F.SilkS")
			(hide yes)
			(effects
				(font
					(size 1.27 1.27)
				)
			)
		)
		(property "Value" ""
			(at 0 0 90)
			(layer "F.Fab")
			(effects
				(font
					(size 1.27 1.27)
				)
			)
		)
		(duplicate_pad_numbers_are_jumpers no)
		(fp_line
			(start 0.7874 -0.4064)
			(end 0.7874 0.4064)
			(stroke
				(width 0.1524)
				(type default)
			)
			(layer "F.SilkS")
		)
		(fp_line
			(start -0.7874 -0.4064)
			(end 0.7874 -0.4064)
			(stroke
				(width 0.1524)
				(type default)
			)
			(layer "F.SilkS")
		)
		(fp_line
			(start 0.7874 0.4064)
			(end -0.7874 0.4064)
			(stroke
				(width 0.1524)
				(type default)
			)
			(layer "F.SilkS")
		)
		(fp_line
			(start -0.7874 0.4064)
			(end -0.7874 -0.4064)
			(stroke
				(width 0.1524)
				(type default)
			)
			(layer "F.SilkS")
		)
		(fp_line
			(start -0.12065 -0.305054)
			(end -0.12065 -0.2794)
			(stroke
				(width 0.1)
				(type default)
			)
			(layer "F.Fab")
		)
		(fp_line
			(start -0.67945 -0.305054)
			(end -0.12065 -0.305054)
			(stroke
				(width 0.1)
				(type default)
			)
			(layer "F.Fab")
		)
		(fp_line
			(start 0.67945 -0.3048)
			(end 0.67945 0.3048)
			(stroke
				(width 0.1)
				(type default)
			)
			(layer "F.Fab")
		)
		(fp_line
			(start 0.12065 -0.3048)
			(end 0.67945 -0.3048)
			(stroke
				(width 0.1)
				(type default)
			)
			(layer "F.Fab")
		)
		(fp_line
			(start 0.12065 -0.2794)
			(end 0.12065 -0.3048)
			(stroke
				(width 0.1)
				(type default)
			)
			(layer "F.Fab")
		)
		(fp_line
			(start -0.12065 -0.2794)
			(end 0.12065 -0.2794)
			(stroke
				(width 0.1)
				(type default)
			)
			(layer "F.Fab")
		)
		(fp_line
			(start 0.120396 0.2794)
			(end -0.12065 0.2794)
			(stroke
				(width 0.1)
				(type default)
			)
			(layer "F.Fab")
		)
		(fp_line
			(start -0.12065 0.2794)
			(end -0.12065 0.3048)
			(stroke
				(width 0.1)
				(type default)
			)
			(layer "F.Fab")
		)
		(fp_line
			(start 0.67945 0.3048)
			(end 0.120396 0.3048)
			(stroke
				(width 0.1)
				(type default)
			)
			(layer "F.Fab")
		)
		(fp_line
			(start 0.120396 0.3048)
			(end 0.120396 0.2794)
			(stroke
				(width 0.1)
				(type default)
			)
			(layer "F.Fab")
		)
		(fp_line
			(start -0.12065 0.3048)
			(end -0.67945 0.3048)
			(stroke
				(width 0.1)
				(type default)
			)
			(layer "F.Fab")
		)
		(fp_line
			(start -0.67945 0.3048)
			(end -0.67945 -0.305054)
			(stroke
				(width 0.1)
				(type default)
			)
			(layer "F.Fab")
		)
		(pad "1" smd circle
			(at -0.40005 0 90)
			(size 0 0)
			(layers "F.Cu" "F.Mask" "F.Paste")
			(net "P12V_AUX")
		)
		(pad "2" smd circle
			(at 0.40005 0 90)
			(size 0 0)
			(layers "F.Cu" "F.Mask" "F.Paste")
			(net "P12V_AUX_SCALED")
		)
	)
	(footprint ""
		(layer "F.Cu")
		(at 358.013 -216.408 180)
		(property "Reference" "R4092"
			(at 0 0 180)
			(layer "F.SilkS")
			(hide yes)
			(effects
				(font
					(size 1.27 1.27)
				)
			)
		)
		(property "Value" ""
			(at 0 0 180)
			(layer "F.Fab")
			(effects
				(font
					(size 1.27 1.27)
				)
			)
		)
		(duplicate_pad_numbers_are_jumpers no)
		(fp_line
			(start 0.7874 0.4064)
			(end -0.7874 0.4064)
			(stroke
				(width 0.1524)
				(type default)
			)
			(layer "F.SilkS")
		)
		(fp_line
			(start 0.7874 -0.4064)
			(end 0.7874 0.4064)
			(stroke
				(width 0.1524)
				(type default)
			)
			(layer "F.SilkS")
		)
		(fp_line
			(start -0.7874 0.4064)
			(end -0.7874 -0.4064)
			(stroke
				(width 0.1524)
				(type default)
			)
			(layer "F.SilkS")
		)
		(fp_line
			(start -0.7874 -0.4064)
			(end 0.7874 -0.4064)
			(stroke
				(width 0.1524)
				(type default)
			)
			(layer "F.SilkS")
		)
		(fp_line
			(start 0.67945 0.3048)
			(end 0.120396 0.3048)
			(stroke
				(width 0.1)
				(type default)
			)
			(layer "F.Fab")
		)
		(fp_line
			(start 0.67945 -0.3048)
			(end 0.67945 0.3048)
			(stroke
				(width 0.1)
				(type default)
			)
			(layer "F.Fab")
		)
		(fp_line
			(start 0.12065 -0.2794)
			(end 0.12065 -0.3048)
			(stroke
				(width 0.1)
				(type default)
			)
			(layer "F.Fab")
		)
		(fp_line
			(start 0.12065 -0.3048)
			(end 0.67945 -0.3048)
			(stroke
				(width 0.1)
				(type default)
			)
			(layer "F.Fab")
		)
		(fp_line
			(start 0.120396 0.3048)
			(end 0.120396 0.2794)
			(stroke
				(width 0.1)
				(type default)
			)
			(layer "F.Fab")
		)
		(fp_line
			(start 0.120396 0.2794)
			(end -0.12065 0.2794)
			(stroke
				(width 0.1)
				(type default)
			)
			(layer "F.Fab")
		)
		(fp_line
			(start -0.12065 0.3048)
			(end -0.67945 0.3048)
			(stroke
				(width 0.1)
				(type default)
			)
			(layer "F.Fab")
		)
		(fp_line
			(start -0.12065 0.2794)
			(end -0.12065 0.3048)
			(stroke
				(width 0.1)
				(type default)
			)
			(layer "F.Fab")
		)
		(fp_line
			(start -0.12065 -0.2794)
			(end 0.12065 -0.2794)
			(stroke
				(width 0.1)
				(type default)
			)
			(layer "F.Fab")
		)
		(fp_line
			(start -0.12065 -0.305054)
			(end -0.12065 -0.2794)
			(stroke
				(width 0.1)
				(type default)
			)
			(layer "F.Fab")
		)
		(fp_line
			(start -0.67945 0.3048)
			(end -0.67945 -0.305054)
			(stroke
				(width 0.1)
				(type default)
			)
			(layer "F.Fab")
		)
		(fp_line
			(start -0.67945 -0.305054)
			(end -0.12065 -0.305054)
			(stroke
				(width 0.1)
				(type default)
			)
			(layer "F.Fab")
		)
		(pad "1" smd circle
			(at -0.40005 0 180)
			(size 0 0)
			(layers "F.Cu" "F.Mask" "F.Paste")
			(net "PRSNT_NIC0_FPGA_R_N")
		)
		(pad "2" smd circle
			(at 0.40005 0 180)
			(size 0 0)
			(layers "F.Cu" "F.Mask" "F.Paste")
			(net "PRSNT_NIC0_FPGA_N")
		)
	)
	(footprint ""
		(layer "F.Cu")
		(at 28.495244 -35.48253)
		(property "Reference" "U382"
			(at -2.535174 1.29413 90)
			(unlocked yes)
			(layer "F.SilkS")
			(effects
				(font
					(size 0.7874 0.5842)
					(thickness 0.1524)
				)
				(justify left)
			)
		)
		(property "Value" ""
			(at 0 0 0)
			(layer "F.Fab")
			(effects
				(font
					(size 1.27 1.27)
				)
			)
		)
		(duplicate_pad_numbers_are_jumpers no)
		(fp_line
			(start -1.3462 -1.1938)
			(end -1.3462 1.1684)
			(stroke
				(width 0.1524)
				(type default)
			)
			(layer "F.SilkS")
		)
		(fp_line
			(start -1.3462 1.1938)
			(end 1.3462 1.1938)
			(stroke
				(width 0.1524)
				(type default)
			)
			(layer "F.SilkS")
		)
		(fp_line
			(start 1.3462 -1.1938)
			(end -1.3462 -1.1938)
			(stroke
				(width 0.1524)
				(type default)
			)
			(layer "F.SilkS")
		)
		(fp_line
			(start 1.3462 1.1938)
			(end 1.3462 -1.1938)
			(stroke
				(width 0.1524)
				(type default)
			)
			(layer "F.SilkS")
		)
		(fp_poly
			(pts
				(xy -1.447038 -0.760476) (xy -2.052066 -0.457962) (xy -2.052066 -1.06299)
			)
			(stroke
				(width 0)
				(type default)
			)
			(fill yes)
			(layer "F.SilkS")
		)
		(fp_line
			(start -0.674878 -1.124966)
			(end -0.674878 1.124966)
			(stroke
				(width 0.1)
				(type default)
			)
			(layer "F.Fab")
		)
		(fp_line
			(start -0.674878 1.124966)
			(end 0.674878 1.124966)
			(stroke
				(width 0.1)
				(type default)
			)
			(layer "F.Fab")
		)
		(fp_line
			(start 0.674878 -1.124966)
			(end -0.674878 -1.124966)
			(stroke
				(width 0.1)
				(type default)
			)
			(layer "F.Fab")
		)
		(fp_line
			(start 0.674878 1.124966)
			(end 0.674878 -1.124966)
			(stroke
				(width 0.1)
				(type default)
			)
			(layer "F.Fab")
		)
		(fp_poly
			(pts
				(xy -1.447038 -0.760476) (xy -2.052066 -0.457962) (xy -2.052066 -1.06299)
			)
			(stroke
				(width 0)
				(type default)
			)
			(fill yes)
			(layer "F.Fab")
		)
		(pad "1" smd rect
			(at -0.899922 -0.750062)
			(size 0.6096 0.6096)
			(layers "F.Cu" "F.Mask" "F.Paste")
			(net "PWRGD_P3V3_SSD1_R")
		)
		(pad "2" smd rect
			(at -0.899922 0 90)
			(size 0.4064 0.6096)
			(layers "F.Cu" "F.Mask" "F.Paste")
			(net "RST_SMB_SSD1_N")
		)
		(pad "3" smd rect
			(at -0.899922 0.750062)
			(size 0.6096 0.6096)
			(layers "F.Cu" "F.Mask" "F.Paste")
			(net "GND")
		)
		(pad "4" smd rect
			(at 0.899922 0.750062)
			(size 0.6096 0.6096)
			(layers "F.Cu" "F.Mask" "F.Paste")
			(net "RST_SMB_SSD1_ISO_N")
		)
		(pad "5" smd rect
			(at 0.899922 -0.750062)
			(size 0.6096 0.6096)
			(layers "F.Cu" "F.Mask" "F.Paste")
			(net "P3V3_AUX")
		)
	)
	(footprint ""
		(layer "F.Cu")
		(at 72.57542 -69.47916 180)
		(property "Reference" "PU78"
			(at -2.135124 -3.185922 90)
			(unlocked yes)
			(layer "F.SilkS")
			(effects
				(font
					(size 0.7874 0.5842)
					(thickness 0.1524)
				)
			)
		)
		(property "Value" ""
			(at 0 0 180)
			(layer "F.Fab")
			(effects
				(font
					(size 1.27 1.27)
				)
			)
		)
		(duplicate_pad_numbers_are_jumpers no)
		(fp_line
			(start 1.239774 1.495298)
			(end -1.239774 1.495298)
			(stroke
				(width 0.1524)
				(type default)
			)
			(layer "F.SilkS")
		)
		(fp_line
			(start 1.239774 -1.495298)
			(end 1.239774 1.495298)
			(stroke
				(width 0.1524)
				(type default)
			)
			(layer "F.SilkS")
		)
		(fp_line
			(start -1.239774 1.495298)
			(end -1.239774 -1.495298)
			(stroke
				(width 0.1524)
				(type default)
			)
			(layer "F.SilkS")
		)
		(fp_line
			(start -1.239774 -1.495298)
			(end 1.239774 -1.495298)
			(stroke
				(width 0.1524)
				(type default)
			)
			(layer "F.SilkS")
		)
		(fp_poly
			(pts
				(xy -1.830578 -1.378458) (xy -2.549144 -0.659892) (xy -1.471422 -0.300736)
			)
			(stroke
				(width 0)
				(type default)
			)
			(fill yes)
			(layer "F.SilkS")
		)
		(fp_line
			(start 0.8001 1.050036)
			(end -0.8001 1.050036)
			(stroke
				(width 0.1)
				(type default)
			)
			(layer "F.Fab")
		)
		(fp_line
			(start 0.8001 -1.050036)
			(end 0.8001 1.050036)
			(stroke
				(width 0.1)
				(type default)
			)
			(layer "F.Fab")
		)
		(fp_line
			(start -0.8001 1.050036)
			(end -0.8001 -1.050036)
			(stroke
				(width 0.1)
				(type default)
			)
			(layer "F.Fab")
		)
		(fp_line
			(start -0.8001 -1.050036)
			(end 0.8001 -1.050036)
			(stroke
				(width 0.1)
				(type default)
			)
			(layer "F.Fab")
		)
		(fp_poly
			(pts
				(xy -2.458974 -0.508) (xy -2.458974 0.508) (xy -1.442974 0)
			)
			(stroke
				(width 0)
				(type default)
			)
			(fill yes)
			(layer "F.Fab")
		)
		(pad "1_2" smd circle
			(at -0.374904 0 270)
			(size 0 0)
			(layers "F.Cu" "F.Mask" "F.Paste")
			(net "P12V_AUX")
		)
		(pad "3" smd rect
			(at -0.499872 0.999998 180)
			(size 0.254 0.7112)
			(layers "F.Cu" "F.Mask" "F.Paste")
			(net "GND")
		)
		(pad "4" smd rect
			(at 0 0.999998 180)
			(size 0.254 0.7112)
			(layers "F.Cu" "F.Mask" "F.Paste")
			(net "P12V_SSD2_CO_ILIMIT")
		)
		(pad "5" smd rect
			(at 0.499872 0.999998 180)
			(size 0.254 0.7112)
			(layers "F.Cu" "F.Mask" "F.Paste")
			(net "P12V_SSD2_CO_MODE")
		)
		(pad "6_7" smd circle
			(at 0.374904 0 90)
			(size 0 0)
			(layers "F.Cu" "F.Mask" "F.Paste")
			(net "P12V_SSD2_R")
		)
		(pad "8" smd rect
			(at 0.499872 -0.999998 180)
			(size 0.254 0.7112)
			(layers "F.Cu" "F.Mask" "F.Paste")
			(net "P12V_SSD2_CO_GATE")
		)
		(pad "9" smd rect
			(at 0 -0.999998 180)
			(size 0.254 0.7112)
			(layers "F.Cu" "F.Mask" "F.Paste")
			(net "P12V_SSD2_CO_EN")
		)
		(pad "10" smd rect
			(at -0.499872 -0.999998 180)
			(size 0.254 0.7112)
			(layers "F.Cu" "F.Mask" "F.Paste")
			(net "P12V_SSD2_CO_DV_DT")
		)
	)
	(footprint ""
		(layer "F.Cu")
		(at 3.686302 -251.312426 -90)
		(property "Reference" "C4241"
			(at 0 0 270)
			(layer "F.SilkS")
			(hide yes)
			(effects
				(font
					(size 1.27 1.27)
				)
			)
		)
		(property "Value" ""
			(at 0 0 270)
			(layer "F.Fab")
			(effects
				(font
					(size 1.27 1.27)
				)
			)
		)
		(duplicate_pad_numbers_are_jumpers no)
		(fp_line
			(start -1.2954 0.5842)
			(end -1.2954 -0.5842)
			(stroke
				(width 0.1524)
				(type default)
			)
			(layer "F.SilkS")
		)
		(fp_line
			(start 1.2954 0.5842)
			(end -1.2954 0.5842)
			(stroke
				(width 0.1524)
				(type default)
			)
			(layer "F.SilkS")
		)
		(fp_line
			(start -1.2954 -0.5842)
			(end 1.2954 -0.5842)
			(stroke
				(width 0.1524)
				(type default)
			)
			(layer "F.SilkS")
		)
		(fp_line
			(start 1.2954 -0.5842)
			(end 1.2954 0.5842)
			(stroke
				(width 0.1524)
				(type default)
			)
			(layer "F.SilkS")
		)
		(fp_line
			(start -0.8636 0.4572)
			(end -0.8636 0.4064)
			(stroke
				(width 0.1)
				(type default)
			)
			(layer "F.Fab")
		)
		(fp_line
			(start 0.8636 0.4572)
			(end -0.8636 0.4572)
			(stroke
				(width 0.1)
				(type default)
			)
			(layer "F.Fab")
		)
		(fp_line
			(start -1.1938 0.4064)
			(end -1.1938 -0.4064)
			(stroke
				(width 0.1)
				(type default)
			)
			(layer "F.Fab")
		)
		(fp_line
			(start -0.8636 0.4064)
			(end -1.1938 0.4064)
			(stroke
				(width 0.1)
				(type default)
			)
			(layer "F.Fab")
		)
		(fp_line
			(start 0.8636 0.4064)
			(end 0.8636 0.4572)
			(stroke
				(width 0.1)
				(type default)
			)
			(layer "F.Fab")
		)
		(fp_line
			(start 1.1938 0.4064)
			(end 0.8636 0.4064)
			(stroke
				(width 0.1)
				(type default)
			)
			(layer "F.Fab")
		)
		(fp_line
			(start -1.1938 -0.4064)
			(end -0.8636 -0.4064)
			(stroke
				(width 0.1)
				(type default)
			)
			(layer "F.Fab")
		)
		(fp_line
			(start -0.8636 -0.4064)
			(end -0.8636 -0.4572)
			(stroke
				(width 0.1)
				(type default)
			)
			(layer "F.Fab")
		)
		(fp_line
			(start 0.8636 -0.4064)
			(end 1.1938 -0.4064)
			(stroke
				(width 0.1)
				(type default)
			)
			(layer "F.Fab")
		)
		(fp_line
			(start 1.1938 -0.4064)
			(end 1.1938 0.4064)
			(stroke
				(width 0.1)
				(type default)
			)
			(layer "F.Fab")
		)
		(fp_line
			(start -0.8636 -0.4572)
			(end 0.8636 -0.4572)
			(stroke
				(width 0.1)
				(type default)
			)
			(layer "F.Fab")
		)
		(fp_line
			(start 0.8636 -0.4572)
			(end 0.8636 -0.4064)
			(stroke
				(width 0.1)
				(type default)
			)
			(layer "F.Fab")
		)
		(pad "1" smd rect
			(at -0.7366 0 180)
			(size 0.7112 0.8128)
			(layers "F.Cu" "F.Mask" "F.Paste")
			(net "P1V25_SERDES_VDDPLL_PEX0_C7")
		)
		(pad "2" smd rect
			(at 0.7366 0 180)
			(size 0.7112 0.8128)
			(layers "F.Cu" "F.Mask" "F.Paste")
			(net "GND")
		)
	)
	(footprint ""
		(layer "F.Cu")
		(at 126.221236 -177.039524)
		(property "Reference" "R1087"
			(at 0 0 0)
			(layer "F.SilkS")
			(hide yes)
			(effects
				(font
					(size 1.27 1.27)
				)
			)
		)
		(property "Value" ""
			(at 0 0 0)
			(layer "F.Fab")
			(effects
				(font
					(size 1.27 1.27)
				)
			)
		)
		(duplicate_pad_numbers_are_jumpers no)
		(fp_line
			(start -0.7874 -0.4064)
			(end 0.7874 -0.4064)
			(stroke
				(width 0.1524)
				(type default)
			)
			(layer "F.SilkS")
		)
		(fp_line
			(start -0.67945 -0.305054)
			(end -0.12065 -0.305054)
			(stroke
				(width 0.1)
				(type default)
			)
			(layer "F.Fab")
		)
		(fp_line
			(start -0.67945 0.3048)
			(end -0.67945 -0.305054)
			(stroke
				(width 0.1)
				(type default)
			)
			(layer "F.Fab")
		)
		(fp_line
			(start -0.12065 -0.305054)
			(end -0.12065 -0.2794)
			(stroke
				(width 0.1)
				(type default)
			)
			(layer "F.Fab")
		)
		(fp_line
			(start -0.12065 -0.2794)
			(end 0.12065 -0.2794)
			(stroke
				(width 0.1)
				(type default)
			)
			(layer "F.Fab")
		)
		(fp_line
			(start -0.12065 0.2794)
			(end -0.12065 0.3048)
			(stroke
				(width 0.1)
				(type default)
			)
			(layer "F.Fab")
		)
		(fp_line
			(start -0.12065 0.3048)
			(end -0.67945 0.3048)
			(stroke
				(width 0.1)
				(type default)
			)
			(layer "F.Fab")
		)
		(fp_line
			(start 0.120396 0.2794)
			(end -0.12065 0.2794)
			(stroke
				(width 0.1)
				(type default)
			)
			(layer "F.Fab")
		)
		(fp_line
			(start 0.120396 0.3048)
			(end 0.120396 0.2794)
			(stroke
				(width 0.1)
				(type default)
			)
			(layer "F.Fab")
		)
		(fp_line
			(start 0.12065 -0.3048)
			(end 0.67945 -0.3048)
			(stroke
				(width 0.1)
				(type default)
			)
			(layer "F.Fab")
		)
		(fp_line
			(start 0.12065 -0.2794)
			(end 0.12065 -0.3048)
			(stroke
				(width 0.1)
				(type default)
			)
			(layer "F.Fab")
		)
		(fp_line
			(start 0.67945 -0.3048)
			(end 0.67945 0.3048)
			(stroke
				(width 0.1)
				(type default)
			)
			(layer "F.Fab")
		)
		(fp_line
			(start 0.67945 0.3048)
			(end 0.120396 0.3048)
			(stroke
				(width 0.1)
				(type default)
			)
			(layer "F.Fab")
		)
		(pad "1" smd circle
			(at -0.40005 0)
			(size 0 0)
			(layers "F.Cu" "F.Mask" "F.Paste")
			(net "CLK_100M_DB2000QL_PEX0_S1_R_DP")
		)
		(pad "2" smd circle
			(at 0.40005 0)
			(size 0 0)
			(layers "F.Cu" "F.Mask" "F.Paste")
			(net "CLK_100M_DB2000QL_PEX0_S1_DP")
		)
	)
	(footprint ""
		(layer "F.Cu")
		(at 322.718684 -343.952322 90)
		(property "Reference" "C542"
			(at 0 0 90)
			(layer "F.SilkS")
			(hide yes)
			(effects
				(font
					(size 1.27 1.27)
				)
			)
		)
		(property "Value" ""
			(at 0 0 90)
			(layer "F.Fab")
			(effects
				(font
					(size 1.27 1.27)
				)
			)
		)
		(duplicate_pad_numbers_are_jumpers no)
		(fp_line
			(start 0.299974 -0.150114)
			(end 0.299974 0.150114)
			(stroke
				(width 0.1)
				(type default)
			)
			(layer "F.Fab")
		)
		(fp_line
			(start -0.299974 -0.150114)
			(end 0.299974 -0.150114)
			(stroke
				(width 0.1)
				(type default)
			)
			(layer "F.Fab")
		)
		(fp_line
			(start 0.299974 0.150114)
			(end -0.299974 0.150114)
			(stroke
				(width 0.1)
				(type default)
			)
			(layer "F.Fab")
		)
		(fp_line
			(start -0.299974 0.150114)
			(end -0.299974 -0.150114)
			(stroke
				(width 0.1)
				(type default)
			)
			(layer "F.Fab")
		)
		(pad "1" smd rect
			(at -0.2667 0 90)
			(size 0.3048 0.381)
			(layers "F.Cu" "F.Mask" "F.Paste")
			(net "P5E_PEX2_STN5_TX_DN<84>")
		)
		(pad "2" smd rect
			(at 0.2667 0 90)
			(size 0.3048 0.381)
			(layers "F.Cu" "F.Mask" "F.Paste")
			(net "P5E_PEX2_STN5_TX_C_DN<84>")
		)
	)
	(footprint ""
		(layer "F.Cu")
		(at 106.496358 -79.822294 90)
		(property "Reference" "R1137"
			(at 0 0 90)
			(layer "F.SilkS")
			(hide yes)
			(effects
				(font
					(size 1.27 1.27)
				)
			)
		)
		(property "Value" ""
			(at 0 0 90)
			(layer "F.Fab")
			(effects
				(font
					(size 1.27 1.27)
				)
			)
		)
		(duplicate_pad_numbers_are_jumpers no)
		(fp_line
			(start 0.7874 0.4064)
			(end -0.7874 0.4064)
			(stroke
				(width 0.1524)
				(type default)
			)
			(layer "F.SilkS")
		)
		(fp_line
			(start -0.12065 -0.305054)
			(end -0.12065 -0.2794)
			(stroke
				(width 0.1)
				(type default)
			)
			(layer "F.Fab")
		)
		(fp_line
			(start -0.67945 -0.305054)
			(end -0.12065 -0.305054)
			(stroke
				(width 0.1)
				(type default)
			)
			(layer "F.Fab")
		)
		(fp_line
			(start 0.67945 -0.3048)
			(end 0.67945 0.3048)
			(stroke
				(width 0.1)
				(type default)
			)
			(layer "F.Fab")
		)
		(fp_line
			(start 0.12065 -0.3048)
			(end 0.67945 -0.3048)
			(stroke
				(width 0.1)
				(type default)
			)
			(layer "F.Fab")
		)
		(fp_line
			(start 0.12065 -0.2794)
			(end 0.12065 -0.3048)
			(stroke
				(width 0.1)
				(type default)
			)
			(layer "F.Fab")
		)
		(fp_line
			(start -0.12065 -0.2794)
			(end 0.12065 -0.2794)
			(stroke
				(width 0.1)
				(type default)
			)
			(layer "F.Fab")
		)
		(fp_line
			(start 0.120396 0.2794)
			(end -0.12065 0.2794)
			(stroke
				(width 0.1)
				(type default)
			)
			(layer "F.Fab")
		)
		(fp_line
			(start -0.12065 0.2794)
			(end -0.12065 0.3048)
			(stroke
				(width 0.1)
				(type default)
			)
			(layer "F.Fab")
		)
		(fp_line
			(start 0.67945 0.3048)
			(end 0.120396 0.3048)
			(stroke
				(width 0.1)
				(type default)
			)
			(layer "F.Fab")
		)
		(fp_line
			(start 0.120396 0.3048)
			(end 0.120396 0.2794)
			(stroke
				(width 0.1)
				(type default)
			)
			(layer "F.Fab")
		)
		(fp_line
			(start -0.12065 0.3048)
			(end -0.67945 0.3048)
			(stroke
				(width 0.1)
				(type default)
			)
			(layer "F.Fab")
		)
		(fp_line
			(start -0.67945 0.3048)
			(end -0.67945 -0.305054)
			(stroke
				(width 0.1)
				(type default)
			)
			(layer "F.Fab")
		)
		(pad "1" smd circle
			(at -0.40005 0 90)
			(size 0 0)
			(layers "F.Cu" "F.Mask" "F.Paste")
			(net "CLK_100M_DB800ZL_SSD0_R_DN")
		)
		(pad "2" smd circle
			(at 0.40005 0 90)
			(size 0 0)
			(layers "F.Cu" "F.Mask" "F.Paste")
			(net "CLK_100M_DB800ZL_SSD0_DN")
		)
	)
	(footprint ""
		(layer "F.Cu")
		(at 435.24043 -141.404848 -90)
		(property "Reference" "R400"
			(at 0 0 270)
			(layer "F.SilkS")
			(hide yes)
			(effects
				(font
					(size 1.27 1.27)
				)
			)
		)
		(property "Value" ""
			(at 0 0 270)
			(layer "F.Fab")
			(effects
				(font
					(size 1.27 1.27)
				)
			)
		)
		(duplicate_pad_numbers_are_jumpers no)
		(fp_line
			(start -0.7874 0.4064)
			(end -0.7874 -0.4064)
			(stroke
				(width 0.1524)
				(type default)
			)
			(layer "F.SilkS")
		)
		(fp_line
			(start 0.7874 0.4064)
			(end -0.7874 0.4064)
			(stroke
				(width 0.1524)
				(type default)
			)
			(layer "F.SilkS")
		)
		(fp_line
			(start -0.7874 -0.4064)
			(end 0.7874 -0.4064)
			(stroke
				(width 0.1524)
				(type default)
			)
			(layer "F.SilkS")
		)
		(fp_line
			(start 0.7874 -0.4064)
			(end 0.7874 0.4064)
			(stroke
				(width 0.1524)
				(type default)
			)
			(layer "F.SilkS")
		)
		(fp_line
			(start -0.67945 0.3048)
			(end -0.67945 -0.305054)
			(stroke
				(width 0.1)
				(type default)
			)
			(layer "F.Fab")
		)
		(fp_line
			(start -0.12065 0.3048)
			(end -0.67945 0.3048)
			(stroke
				(width 0.1)
				(type default)
			)
			(layer "F.Fab")
		)
		(fp_line
			(start 0.120396 0.3048)
			(end 0.120396 0.2794)
			(stroke
				(width 0.1)
				(type default)
			)
			(layer "F.Fab")
		)
		(fp_line
			(start 0.67945 0.3048)
			(end 0.120396 0.3048)
			(stroke
				(width 0.1)
				(type default)
			)
			(layer "F.Fab")
		)
		(fp_line
			(start -0.12065 0.2794)
			(end -0.12065 0.3048)
			(stroke
				(width 0.1)
				(type default)
			)
			(layer "F.Fab")
		)
		(fp_line
			(start 0.120396 0.2794)
			(end -0.12065 0.2794)
			(stroke
				(width 0.1)
				(type default)
			)
			(layer "F.Fab")
		)
		(fp_line
			(start -0.12065 -0.2794)
			(end 0.12065 -0.2794)
			(stroke
				(width 0.1)
				(type default)
			)
			(layer "F.Fab")
		)
		(fp_line
			(start 0.12065 -0.2794)
			(end 0.12065 -0.3048)
			(stroke
				(width 0.1)
				(type default)
			)
			(layer "F.Fab")
		)
		(fp_line
			(start 0.12065 -0.3048)
			(end 0.67945 -0.3048)
			(stroke
				(width 0.1)
				(type default)
			)
			(layer "F.Fab")
		)
		(fp_line
			(start 0.67945 -0.3048)
			(end 0.67945 0.3048)
			(stroke
				(width 0.1)
				(type default)
			)
			(layer "F.Fab")
		)
		(fp_line
			(start -0.67945 -0.305054)
			(end -0.12065 -0.305054)
			(stroke
				(width 0.1)
				(type default)
			)
			(layer "F.Fab")
		)
		(fp_line
			(start -0.12065 -0.305054)
			(end -0.12065 -0.2794)
			(stroke
				(width 0.1)
				(type default)
			)
			(layer "F.Fab")
		)
		(pad "1" smd circle
			(at -0.40005 0 270)
			(size 0 0)
			(layers "F.Cu" "F.Mask" "F.Paste")
			(net "PRSNT_NIC7_R_N")
		)
		(pad "2" smd circle
			(at 0.40005 0 270)
			(size 0 0)
			(layers "F.Cu" "F.Mask" "F.Paste")
			(net "PRSNT_NIC7_N")
		)
	)
	(footprint ""
		(layer "F.Cu")
		(at 338.582 -201.168 -90)
		(property "Reference" "R4134"
			(at 0 0 270)
			(layer "F.SilkS")
			(hide yes)
			(effects
				(font
					(size 1.27 1.27)
				)
			)
		)
		(property "Value" ""
			(at 0 0 270)
			(layer "F.Fab")
			(effects
				(font
					(size 1.27 1.27)
				)
			)
		)
		(duplicate_pad_numbers_are_jumpers no)
		(fp_line
			(start -0.7874 0.4064)
			(end -0.7874 -0.4064)
			(stroke
				(width 0.1524)
				(type default)
			)
			(layer "F.SilkS")
		)
		(fp_line
			(start 0.7874 0.4064)
			(end -0.7874 0.4064)
			(stroke
				(width 0.1524)
				(type default)
			)
			(layer "F.SilkS")
		)
		(fp_line
			(start -0.7874 -0.4064)
			(end 0.7874 -0.4064)
			(stroke
				(width 0.1524)
				(type default)
			)
			(layer "F.SilkS")
		)
		(fp_line
			(start 0.7874 -0.4064)
			(end 0.7874 0.4064)
			(stroke
				(width 0.1524)
				(type default)
			)
			(layer "F.SilkS")
		)
		(fp_line
			(start -0.67945 0.3048)
			(end -0.67945 -0.305054)
			(stroke
				(width 0.1)
				(type default)
			)
			(layer "F.Fab")
		)
		(fp_line
			(start -0.12065 0.3048)
			(end -0.67945 0.3048)
			(stroke
				(width 0.1)
				(type default)
			)
			(layer "F.Fab")
		)
		(fp_line
			(start 0.120396 0.3048)
			(end 0.120396 0.2794)
			(stroke
				(width 0.1)
				(type default)
			)
			(layer "F.Fab")
		)
		(fp_line
			(start 0.67945 0.3048)
			(end 0.120396 0.3048)
			(stroke
				(width 0.1)
				(type default)
			)
			(layer "F.Fab")
		)
		(fp_line
			(start -0.12065 0.2794)
			(end -0.12065 0.3048)
			(stroke
				(width 0.1)
				(type default)
			)
			(layer "F.Fab")
		)
		(fp_line
			(start 0.120396 0.2794)
			(end -0.12065 0.2794)
			(stroke
				(width 0.1)
				(type default)
			)
			(layer "F.Fab")
		)
		(fp_line
			(start -0.12065 -0.2794)
			(end 0.12065 -0.2794)
			(stroke
				(width 0.1)
				(type default)
			)
			(layer "F.Fab")
		)
		(fp_line
			(start 0.12065 -0.2794)
			(end 0.12065 -0.3048)
			(stroke
				(width 0.1)
				(type default)
			)
			(layer "F.Fab")
		)
		(fp_line
			(start 0.12065 -0.3048)
			(end 0.67945 -0.3048)
			(stroke
				(width 0.1)
				(type default)
			)
			(layer "F.Fab")
		)
		(fp_line
			(start 0.67945 -0.3048)
			(end 0.67945 0.3048)
			(stroke
				(width 0.1)
				(type default)
			)
			(layer "F.Fab")
		)
		(fp_line
			(start -0.67945 -0.305054)
			(end -0.12065 -0.305054)
			(stroke
				(width 0.1)
				(type default)
			)
			(layer "F.Fab")
		)
		(fp_line
			(start -0.12065 -0.305054)
			(end -0.12065 -0.2794)
			(stroke
				(width 0.1)
				(type default)
			)
			(layer "F.Fab")
		)
		(pad "1" smd circle
			(at -0.40005 0 270)
			(size 0 0)
			(layers "F.Cu" "F.Mask" "F.Paste")
			(net "SSD12_CLK_EN_N")
		)
		(pad "2" smd circle
			(at 0.40005 0 270)
			(size 0 0)
			(layers "F.Cu" "F.Mask" "F.Paste")
			(net "SSD12_CLK_EN_R_N")
		)
	)
	(footprint ""
		(layer "F.Cu")
		(at 245.203726 -306.386992 -90)
		(property "Reference" "PC261"
			(at 0 0 270)
			(layer "F.SilkS")
			(hide yes)
			(effects
				(font
					(size 1.27 1.27)
				)
			)
		)
		(property "Value" ""
			(at 0 0 270)
			(layer "F.Fab")
			(effects
				(font
					(size 1.27 1.27)
				)
			)
		)
		(duplicate_pad_numbers_are_jumpers no)
		(fp_line
			(start -0.7874 0.4064)
			(end -0.7874 -0.4064)
			(stroke
				(width 0.1524)
				(type default)
			)
			(layer "F.SilkS")
		)
		(fp_line
			(start 0.7874 0.4064)
			(end -0.7874 0.4064)
			(stroke
				(width 0.1524)
				(type default)
			)
			(layer "F.SilkS")
		)
		(fp_line
			(start -0.7874 -0.4064)
			(end 0.7874 -0.4064)
			(stroke
				(width 0.1524)
				(type default)
			)
			(layer "F.SilkS")
		)
		(fp_line
			(start 0.7874 -0.4064)
			(end 0.7874 0.4064)
			(stroke
				(width 0.1524)
				(type default)
			)
			(layer "F.SilkS")
		)
		(fp_line
			(start -0.67945 0.3048)
			(end -0.67945 -0.305054)
			(stroke
				(width 0.1)
				(type default)
			)
			(layer "F.Fab")
		)
		(fp_line
			(start -0.12065 0.3048)
			(end -0.67945 0.3048)
			(stroke
				(width 0.1)
				(type default)
			)
			(layer "F.Fab")
		)
		(fp_line
			(start 0.120396 0.3048)
			(end 0.120396 0.2794)
			(stroke
				(width 0.1)
				(type default)
			)
			(layer "F.Fab")
		)
		(fp_line
			(start 0.67945 0.3048)
			(end 0.120396 0.3048)
			(stroke
				(width 0.1)
				(type default)
			)
			(layer "F.Fab")
		)
		(fp_line
			(start -0.12065 0.2794)
			(end -0.12065 0.3048)
			(stroke
				(width 0.1)
				(type default)
			)
			(layer "F.Fab")
		)
		(fp_line
			(start 0.120396 0.2794)
			(end -0.12065 0.2794)
			(stroke
				(width 0.1)
				(type default)
			)
			(layer "F.Fab")
		)
		(fp_line
			(start -0.12065 -0.2794)
			(end 0.12065 -0.2794)
			(stroke
				(width 0.1)
				(type default)
			)
			(layer "F.Fab")
		)
		(fp_line
			(start 0.12065 -0.2794)
			(end 0.12065 -0.3048)
			(stroke
				(width 0.1)
				(type default)
			)
			(layer "F.Fab")
		)
		(fp_line
			(start 0.12065 -0.3048)
			(end 0.67945 -0.3048)
			(stroke
				(width 0.1)
				(type default)
			)
			(layer "F.Fab")
		)
		(fp_line
			(start 0.67945 -0.3048)
			(end 0.67945 0.3048)
			(stroke
				(width 0.1)
				(type default)
			)
			(layer "F.Fab")
		)
		(fp_line
			(start -0.67945 -0.305054)
			(end -0.12065 -0.305054)
			(stroke
				(width 0.1)
				(type default)
			)
			(layer "F.Fab")
		)
		(fp_line
			(start -0.12065 -0.305054)
			(end -0.12065 -0.2794)
			(stroke
				(width 0.1)
				(type default)
			)
			(layer "F.Fab")
		)
		(pad "1" smd circle
			(at -0.40005 0 270)
			(size 0 0)
			(layers "F.Cu" "F.Mask" "F.Paste")
			(net "P1V25_PEX2_REF")
		)
		(pad "2" smd circle
			(at 0.40005 0 270)
			(size 0 0)
			(layers "F.Cu" "F.Mask" "F.Paste")
			(net "GND")
		)
	)
	(footprint ""
		(layer "F.Cu")
		(at 340.561422 -189.40145 180)
		(property "Reference" "R4242"
			(at 0 0 180)
			(layer "F.SilkS")
			(hide yes)
			(effects
				(font
					(size 1.27 1.27)
				)
			)
		)
		(property "Value" ""
			(at 0 0 180)
			(layer "F.Fab")
			(effects
				(font
					(size 1.27 1.27)
				)
			)
		)
		(duplicate_pad_numbers_are_jumpers no)
		(fp_line
			(start 0.7874 0.4064)
			(end -0.7874 0.4064)
			(stroke
				(width 0.1524)
				(type default)
			)
			(layer "F.SilkS")
		)
		(fp_line
			(start 0.7874 -0.4064)
			(end 0.7874 0.4064)
			(stroke
				(width 0.1524)
				(type default)
			)
			(layer "F.SilkS")
		)
		(fp_line
			(start -0.7874 0.4064)
			(end -0.7874 -0.4064)
			(stroke
				(width 0.1524)
				(type default)
			)
			(layer "F.SilkS")
		)
		(fp_line
			(start -0.7874 -0.4064)
			(end 0.7874 -0.4064)
			(stroke
				(width 0.1524)
				(type default)
			)
			(layer "F.SilkS")
		)
		(fp_line
			(start 0.67945 0.3048)
			(end 0.120396 0.3048)
			(stroke
				(width 0.1)
				(type default)
			)
			(layer "F.Fab")
		)
		(fp_line
			(start 0.67945 -0.3048)
			(end 0.67945 0.3048)
			(stroke
				(width 0.1)
				(type default)
			)
			(layer "F.Fab")
		)
		(fp_line
			(start 0.12065 -0.2794)
			(end 0.12065 -0.3048)
			(stroke
				(width 0.1)
				(type default)
			)
			(layer "F.Fab")
		)
		(fp_line
			(start 0.12065 -0.3048)
			(end 0.67945 -0.3048)
			(stroke
				(width 0.1)
				(type default)
			)
			(layer "F.Fab")
		)
		(fp_line
			(start 0.120396 0.3048)
			(end 0.120396 0.2794)
			(stroke
				(width 0.1)
				(type default)
			)
			(layer "F.Fab")
		)
		(fp_line
			(start 0.120396 0.2794)
			(end -0.12065 0.2794)
			(stroke
				(width 0.1)
				(type default)
			)
			(layer "F.Fab")
		)
		(fp_line
			(start -0.12065 0.3048)
			(end -0.67945 0.3048)
			(stroke
				(width 0.1)
				(type default)
			)
			(layer "F.Fab")
		)
		(fp_line
			(start -0.12065 0.2794)
			(end -0.12065 0.3048)
			(stroke
				(width 0.1)
				(type default)
			)
			(layer "F.Fab")
		)
		(fp_line
			(start -0.12065 -0.2794)
			(end 0.12065 -0.2794)
			(stroke
				(width 0.1)
				(type default)
			)
			(layer "F.Fab")
		)
		(fp_line
			(start -0.12065 -0.305054)
			(end -0.12065 -0.2794)
			(stroke
				(width 0.1)
				(type default)
			)
			(layer "F.Fab")
		)
		(fp_line
			(start -0.67945 0.3048)
			(end -0.67945 -0.305054)
			(stroke
				(width 0.1)
				(type default)
			)
			(layer "F.Fab")
		)
		(fp_line
			(start -0.67945 -0.305054)
			(end -0.12065 -0.305054)
			(stroke
				(width 0.1)
				(type default)
			)
			(layer "F.Fab")
		)
		(pad "1" smd circle
			(at -0.40005 0 180)
			(size 0 0)
			(layers "F.Cu" "F.Mask" "F.Paste")
			(net "P3V3_AUX")
		)
		(pad "2" smd circle
			(at 0.40005 0 180)
			(size 0 0)
			(layers "F.Cu" "F.Mask" "F.Paste")
			(net "PWRGD_SYS_PWROK")
		)
	)
	(footprint ""
		(layer "F.Cu")
		(at 383.159 -201.168)
		(property "Reference" "R4684"
			(at 0 0 0)
			(layer "F.SilkS")
			(hide yes)
			(effects
				(font
					(size 1.27 1.27)
				)
			)
		)
		(property "Value" ""
			(at 0 0 0)
			(layer "F.Fab")
			(effects
				(font
					(size 1.27 1.27)
				)
			)
		)
		(duplicate_pad_numbers_are_jumpers no)
		(fp_line
			(start -0.7874 -0.4064)
			(end 0.7874 -0.4064)
			(stroke
				(width 0.1524)
				(type default)
			)
			(layer "F.SilkS")
		)
		(fp_line
			(start -0.7874 0.4064)
			(end -0.7874 -0.4064)
			(stroke
				(width 0.1524)
				(type default)
			)
			(layer "F.SilkS")
		)
		(fp_line
			(start 0.7874 -0.4064)
			(end 0.7874 0.4064)
			(stroke
				(width 0.1524)
				(type default)
			)
			(layer "F.SilkS")
		)
		(fp_line
			(start 0.7874 0.4064)
			(end -0.7874 0.4064)
			(stroke
				(width 0.1524)
				(type default)
			)
			(layer "F.SilkS")
		)
		(fp_line
			(start -0.67945 -0.305054)
			(end -0.12065 -0.305054)
			(stroke
				(width 0.1)
				(type default)
			)
			(layer "F.Fab")
		)
		(fp_line
			(start -0.67945 0.3048)
			(end -0.67945 -0.305054)
			(stroke
				(width 0.1)
				(type default)
			)
			(layer "F.Fab")
		)
		(fp_line
			(start -0.12065 -0.305054)
			(end -0.12065 -0.2794)
			(stroke
				(width 0.1)
				(type default)
			)
			(layer "F.Fab")
		)
		(fp_line
			(start -0.12065 -0.2794)
			(end 0.12065 -0.2794)
			(stroke
				(width 0.1)
				(type default)
			)
			(layer "F.Fab")
		)
		(fp_line
			(start -0.12065 0.2794)
			(end -0.12065 0.3048)
			(stroke
				(width 0.1)
				(type default)
			)
			(layer "F.Fab")
		)
		(fp_line
			(start -0.12065 0.3048)
			(end -0.67945 0.3048)
			(stroke
				(width 0.1)
				(type default)
			)
			(layer "F.Fab")
		)
		(fp_line
			(start 0.120396 0.2794)
			(end -0.12065 0.2794)
			(stroke
				(width 0.1)
				(type default)
			)
			(layer "F.Fab")
		)
		(fp_line
			(start 0.120396 0.3048)
			(end 0.120396 0.2794)
			(stroke
				(width 0.1)
				(type default)
			)
			(layer "F.Fab")
		)
		(fp_line
			(start 0.12065 -0.3048)
			(end 0.67945 -0.3048)
			(stroke
				(width 0.1)
				(type default)
			)
			(layer "F.Fab")
		)
		(fp_line
			(start 0.12065 -0.2794)
			(end 0.12065 -0.3048)
			(stroke
				(width 0.1)
				(type default)
			)
			(layer "F.Fab")
		)
		(fp_line
			(start 0.67945 -0.3048)
			(end 0.67945 0.3048)
			(stroke
				(width 0.1)
				(type default)
			)
			(layer "F.Fab")
		)
		(fp_line
			(start 0.67945 0.3048)
			(end 0.120396 0.3048)
			(stroke
				(width 0.1)
				(type default)
			)
			(layer "F.Fab")
		)
		(pad "1" smd circle
			(at -0.40005 0)
			(size 0 0)
			(layers "F.Cu" "F.Mask" "F.Paste")
			(net "PCA9555_0_PEX1_A0")
		)
		(pad "2" smd circle
			(at 0.40005 0)
			(size 0 0)
			(layers "F.Cu" "F.Mask" "F.Paste")
			(net "P3V3_AUX")
		)
	)
	(footprint ""
		(layer "F.Cu")
		(at 26.930096 -287.604708 -90)
		(property "Reference" "C3051"
			(at 0 0 270)
			(layer "F.SilkS")
			(hide yes)
			(effects
				(font
					(size 1.27 1.27)
				)
			)
		)
		(property "Value" ""
			(at 0 0 270)
			(layer "F.Fab")
			(effects
				(font
					(size 1.27 1.27)
				)
			)
		)
		(duplicate_pad_numbers_are_jumpers no)
		(fp_line
			(start -1.2954 0.5842)
			(end -1.2954 -0.5842)
			(stroke
				(width 0.1524)
				(type default)
			)
			(layer "F.SilkS")
		)
		(fp_line
			(start 1.2954 0.5842)
			(end -1.2954 0.5842)
			(stroke
				(width 0.1524)
				(type default)
			)
			(layer "F.SilkS")
		)
		(fp_line
			(start -1.2954 -0.5842)
			(end 1.2954 -0.5842)
			(stroke
				(width 0.1524)
				(type default)
			)
			(layer "F.SilkS")
		)
		(fp_line
			(start 1.2954 -0.5842)
			(end 1.2954 0.5842)
			(stroke
				(width 0.1524)
				(type default)
			)
			(layer "F.SilkS")
		)
		(fp_line
			(start -0.8636 0.4572)
			(end -0.8636 0.4064)
			(stroke
				(width 0.1)
				(type default)
			)
			(layer "F.Fab")
		)
		(fp_line
			(start 0.8636 0.4572)
			(end -0.8636 0.4572)
			(stroke
				(width 0.1)
				(type default)
			)
			(layer "F.Fab")
		)
		(fp_line
			(start -1.1938 0.4064)
			(end -1.1938 -0.4064)
			(stroke
				(width 0.1)
				(type default)
			)
			(layer "F.Fab")
		)
		(fp_line
			(start -0.8636 0.4064)
			(end -1.1938 0.4064)
			(stroke
				(width 0.1)
				(type default)
			)
			(layer "F.Fab")
		)
		(fp_line
			(start 0.8636 0.4064)
			(end 0.8636 0.4572)
			(stroke
				(width 0.1)
				(type default)
			)
			(layer "F.Fab")
		)
		(fp_line
			(start 1.1938 0.4064)
			(end 0.8636 0.4064)
			(stroke
				(width 0.1)
				(type default)
			)
			(layer "F.Fab")
		)
		(fp_line
			(start -1.1938 -0.4064)
			(end -0.8636 -0.4064)
			(stroke
				(width 0.1)
				(type default)
			)
			(layer "F.Fab")
		)
		(fp_line
			(start -0.8636 -0.4064)
			(end -0.8636 -0.4572)
			(stroke
				(width 0.1)
				(type default)
			)
			(layer "F.Fab")
		)
		(fp_line
			(start 0.8636 -0.4064)
			(end 1.1938 -0.4064)
			(stroke
				(width 0.1)
				(type default)
			)
			(layer "F.Fab")
		)
		(fp_line
			(start 1.1938 -0.4064)
			(end 1.1938 0.4064)
			(stroke
				(width 0.1)
				(type default)
			)
			(layer "F.Fab")
		)
		(fp_line
			(start -0.8636 -0.4572)
			(end 0.8636 -0.4572)
			(stroke
				(width 0.1)
				(type default)
			)
			(layer "F.Fab")
		)
		(fp_line
			(start 0.8636 -0.4572)
			(end 0.8636 -0.4064)
			(stroke
				(width 0.1)
				(type default)
			)
			(layer "F.Fab")
		)
		(pad "1" smd rect
			(at -0.7366 0 180)
			(size 0.7112 0.8128)
			(layers "F.Cu" "F.Mask" "F.Paste")
			(net "P1V8_PLL0_PEX0")
		)
		(pad "2" smd rect
			(at 0.7366 0 180)
			(size 0.7112 0.8128)
			(layers "F.Cu" "F.Mask" "F.Paste")
			(net "GND")
		)
	)
	(footprint ""
		(layer "F.Cu")
		(at 382.802384 -252.356874 -90)
		(property "Reference" "R1436"
			(at 0 0 270)
			(layer "F.SilkS")
			(hide yes)
			(effects
				(font
					(size 1.27 1.27)
				)
			)
		)
		(property "Value" ""
			(at 0 0 270)
			(layer "F.Fab")
			(effects
				(font
					(size 1.27 1.27)
				)
			)
		)
		(duplicate_pad_numbers_are_jumpers no)
		(fp_line
			(start -0.7874 0.4064)
			(end -0.7874 -0.4064)
			(stroke
				(width 0.1524)
				(type default)
			)
			(layer "F.SilkS")
		)
		(fp_line
			(start 0.7874 0.4064)
			(end -0.7874 0.4064)
			(stroke
				(width 0.1524)
				(type default)
			)
			(layer "F.SilkS")
		)
		(fp_line
			(start -0.7874 -0.4064)
			(end 0.7874 -0.4064)
			(stroke
				(width 0.1524)
				(type default)
			)
			(layer "F.SilkS")
		)
		(fp_line
			(start 0.7874 -0.4064)
			(end 0.7874 0.4064)
			(stroke
				(width 0.1524)
				(type default)
			)
			(layer "F.SilkS")
		)
		(fp_line
			(start -0.67945 0.3048)
			(end -0.67945 -0.305054)
			(stroke
				(width 0.1)
				(type default)
			)
			(layer "F.Fab")
		)
		(fp_line
			(start -0.12065 0.3048)
			(end -0.67945 0.3048)
			(stroke
				(width 0.1)
				(type default)
			)
			(layer "F.Fab")
		)
		(fp_line
			(start 0.120396 0.3048)
			(end 0.120396 0.2794)
			(stroke
				(width 0.1)
				(type default)
			)
			(layer "F.Fab")
		)
		(fp_line
			(start 0.67945 0.3048)
			(end 0.120396 0.3048)
			(stroke
				(width 0.1)
				(type default)
			)
			(layer "F.Fab")
		)
		(fp_line
			(start -0.12065 0.2794)
			(end -0.12065 0.3048)
			(stroke
				(width 0.1)
				(type default)
			)
			(layer "F.Fab")
		)
		(fp_line
			(start 0.120396 0.2794)
			(end -0.12065 0.2794)
			(stroke
				(width 0.1)
				(type default)
			)
			(layer "F.Fab")
		)
		(fp_line
			(start -0.12065 -0.2794)
			(end 0.12065 -0.2794)
			(stroke
				(width 0.1)
				(type default)
			)
			(layer "F.Fab")
		)
		(fp_line
			(start 0.12065 -0.2794)
			(end 0.12065 -0.3048)
			(stroke
				(width 0.1)
				(type default)
			)
			(layer "F.Fab")
		)
		(fp_line
			(start 0.12065 -0.3048)
			(end 0.67945 -0.3048)
			(stroke
				(width 0.1)
				(type default)
			)
			(layer "F.Fab")
		)
		(fp_line
			(start 0.67945 -0.3048)
			(end 0.67945 0.3048)
			(stroke
				(width 0.1)
				(type default)
			)
			(layer "F.Fab")
		)
		(fp_line
			(start -0.67945 -0.305054)
			(end -0.12065 -0.305054)
			(stroke
				(width 0.1)
				(type default)
			)
			(layer "F.Fab")
		)
		(fp_line
			(start -0.12065 -0.305054)
			(end -0.12065 -0.2794)
			(stroke
				(width 0.1)
				(type default)
			)
			(layer "F.Fab")
		)
		(pad "1" smd circle
			(at -0.40005 0 270)
			(size 0 0)
			(layers "F.Cu" "F.Mask" "F.Paste")
			(net "GND")
		)
		(pad "2" smd circle
			(at 0.40005 0 270)
			(size 0 0)
			(layers "F.Cu" "F.Mask" "F.Paste")
			(net "PEX3_MODE_SEL11")
		)
	)
	(footprint ""
		(layer "F.Cu")
		(at 370.261134 -37.951156)
		(property "Reference" "Q229"
			(at 2.132838 -1.805686 0)
			(unlocked yes)
			(layer "F.SilkS")
			(effects
				(font
					(size 0.7874 0.5842)
					(thickness 0.1524)
				)
			)
		)
		(property "Value" ""
			(at 0 0 0)
			(layer "F.Fab")
			(effects
				(font
					(size 1.27 1.27)
				)
			)
		)
		(duplicate_pad_numbers_are_jumpers no)
		(fp_line
			(start -1.376172 -1.199896)
			(end -0.508 -1.199896)
			(stroke
				(width 0.1524)
				(type default)
			)
			(layer "F.SilkS")
		)
		(fp_line
			(start -1.376172 1.199896)
			(end -1.376172 -1.199896)
			(stroke
				(width 0.1524)
				(type default)
			)
			(layer "F.SilkS")
		)
		(fp_line
			(start -0.508 -1.199896)
			(end 0 -0.762)
			(stroke
				(width 0.1524)
				(type default)
			)
			(layer "F.SilkS")
		)
		(fp_line
			(start 0 -0.762)
			(end 0.508 -1.199896)
			(stroke
				(width 0.1524)
				(type default)
			)
			(layer "F.SilkS")
		)
		(fp_line
			(start 0.508 -1.199896)
			(end 1.376172 -1.199896)
			(stroke
				(width 0.1524)
				(type default)
			)
			(layer "F.SilkS")
		)
		(fp_line
			(start 1.376172 -1.199896)
			(end 1.376172 1.199896)
			(stroke
				(width 0.1524)
				(type default)
			)
			(layer "F.SilkS")
		)
		(fp_line
			(start 1.376172 1.199896)
			(end -1.376172 1.199896)
			(stroke
				(width 0.1524)
				(type default)
			)
			(layer "F.SilkS")
		)
		(fp_poly
			(pts
				(xy -1.461262 -1.05156) (xy -1.730756 -1.859788) (xy -2.26949 -1.321054)
			)
			(stroke
				(width 0)
				(type default)
			)
			(fill yes)
			(layer "F.SilkS")
		)
		(fp_line
			(start -0.674878 -1.100074)
			(end 0.674878 -1.100074)
			(stroke
				(width 0.1)
				(type default)
			)
			(layer "F.Fab")
		)
		(fp_line
			(start -0.674878 1.100074)
			(end -0.674878 -1.100074)
			(stroke
				(width 0.1)
				(type default)
			)
			(layer "F.Fab")
		)
		(fp_line
			(start 0.674878 -1.100074)
			(end 0.674878 1.100074)
			(stroke
				(width 0.1)
				(type default)
			)
			(layer "F.Fab")
		)
		(fp_line
			(start 0.674878 1.100074)
			(end -0.674878 1.100074)
			(stroke
				(width 0.1)
				(type default)
			)
			(layer "F.Fab")
		)
		(fp_poly
			(pts
				(xy -1.4605 -0.7493) (xy -2.2225 -1.1303) (xy -2.2225 -0.3683)
			)
			(stroke
				(width 0)
				(type default)
			)
			(fill yes)
			(layer "F.Fab")
		)
		(pad "1" smd rect
			(at -0.899922 -0.750062 270)
			(size 0.6096 0.6096)
			(layers "F.Cu" "F.Mask" "F.Paste")
			(net "GND")
		)
		(pad "2" smd rect
			(at -0.899922 0 270)
			(size 0.4064 0.6096)
			(layers "F.Cu" "F.Mask" "F.Paste")
			(net "P3V3_SSD13_PG_G1")
		)
		(pad "3" smd rect
			(at -0.899922 0.750062 270)
			(size 0.6096 0.6096)
			(layers "F.Cu" "F.Mask" "F.Paste")
			(net "PWRGD_P3V3_SSD13_D")
		)
		(pad "4" smd rect
			(at 0.899922 0.750062 270)
			(size 0.6096 0.6096)
			(layers "F.Cu" "F.Mask" "F.Paste")
			(net "GND")
		)
		(pad "5" smd rect
			(at 0.899922 0 270)
			(size 0.4064 0.6096)
			(layers "F.Cu" "F.Mask" "F.Paste")
			(net "P3V3_SSD13_PG_G2")
		)
		(pad "6" smd rect
			(at 0.899922 -0.750062 270)
			(size 0.6096 0.6096)
			(layers "F.Cu" "F.Mask" "F.Paste")
			(net "P3V3_SSD13_PG_G2")
		)
	)
	(footprint ""
		(layer "F.Cu")
		(at 425.911518 -71.458074 -90)
		(property "Reference" "PD37"
			(at 4.351274 -2.790952 90)
			(unlocked yes)
			(layer "F.SilkS")
			(effects
				(font
					(size 0.7874 0.5842)
					(thickness 0.1524)
				)
				(justify left)
			)
		)
		(property "Value" ""
			(at 0 0 270)
			(layer "F.Fab")
			(effects
				(font
					(size 1.27 1.27)
				)
			)
		)
		(duplicate_pad_numbers_are_jumpers no)
		(fp_line
			(start -3.656584 1.970024)
			(end 4.240784 1.970024)
			(stroke
				(width 0.1524)
				(type default)
			)
			(layer "F.SilkS")
		)
		(fp_line
			(start 4.240784 1.970024)
			(end 4.240784 -1.970024)
			(stroke
				(width 0.1524)
				(type default)
			)
			(layer "F.SilkS")
		)
		(fp_line
			(start -3.656584 -1.970024)
			(end -3.656584 1.970024)
			(stroke
				(width 0.1524)
				(type default)
			)
			(layer "F.SilkS")
		)
		(fp_line
			(start 4.240784 -1.970024)
			(end -3.656584 -1.970024)
			(stroke
				(width 0.1524)
				(type default)
			)
			(layer "F.SilkS")
		)
		(fp_poly
			(pts
				(xy 3.580384 1.970024) (xy 3.580384 -1.970024) (xy 4.240784 -1.970024) (xy 4.240784 1.970024)
			)
			(stroke
				(width 0)
				(type default)
			)
			(fill yes)
			(layer "F.SilkS")
		)
		(fp_line
			(start -2.3749 1.970024)
			(end 2.3749 1.970024)
			(stroke
				(width 0.1)
				(type default)
			)
			(layer "F.Fab")
		)
		(fp_line
			(start 2.3749 1.970024)
			(end 2.3749 -1.970024)
			(stroke
				(width 0.1)
				(type default)
			)
			(layer "F.Fab")
		)
		(fp_line
			(start -2.3749 -1.970024)
			(end -2.3749 1.970024)
			(stroke
				(width 0.1)
				(type default)
			)
			(layer "F.Fab")
		)
		(fp_line
			(start 2.3749 -1.970024)
			(end -2.3749 -1.970024)
			(stroke
				(width 0.1)
				(type default)
			)
			(layer "F.Fab")
		)
		(fp_text user "+"
			(at -4.9784 -0.23495 270)
			(unlocked yes)
			(layer "F.Fab")
			(effects
				(font
					(size 1.905 1.4224)
					(thickness 0.1524)
				)
				(justify left)
			)
		)
		(fp_text user "-"
			(at 4.1656 -0.23495 270)
			(unlocked yes)
			(layer "F.Fab")
			(effects
				(font
					(size 1.905 1.4224)
					(thickness 0.1524)
				)
				(justify left)
			)
		)
		(pad "A" smd rect
			(at -2.450084 0 270)
			(size 2.159 2.2606)
			(layers "F.Cu" "F.Mask" "F.Paste")
			(net "GND")
		)
		(pad "C" smd rect
			(at 2.450084 0 270)
			(size 2.159 2.2606)
			(layers "F.Cu" "F.Mask" "F.Paste")
			(net "P12V_AUX")
		)
	)
	(footprint ""
		(layer "F.Cu")
		(at 6.89102 -55.663846 90)
		(property "Reference" "PU54"
			(at -1.230376 2.791968 90)
			(unlocked yes)
			(layer "F.SilkS")
			(effects
				(font
					(size 0.7874 0.5842)
					(thickness 0.1524)
				)
				(justify left)
			)
		)
		(property "Value" ""
			(at 0 0 90)
			(layer "F.Fab")
			(effects
				(font
					(size 1.27 1.27)
				)
			)
		)
		(duplicate_pad_numbers_are_jumpers no)
		(fp_line
			(start 1.943608 -1.549908)
			(end 1.943608 1.549908)
			(stroke
				(width 0.1524)
				(type default)
			)
			(layer "F.SilkS")
		)
		(fp_line
			(start -1.943608 -1.549908)
			(end 1.943608 -1.549908)
			(stroke
				(width 0.1524)
				(type default)
			)
			(layer "F.SilkS")
		)
		(fp_line
			(start 1.943608 1.549908)
			(end -1.943608 1.549908)
			(stroke
				(width 0.1524)
				(type default)
			)
			(layer "F.SilkS")
		)
		(fp_line
			(start -1.943608 1.549908)
			(end -1.943608 -1.549908)
			(stroke
				(width 0.1524)
				(type default)
			)
			(layer "F.SilkS")
		)
		(fp_poly
			(pts
				(xy -2.019808 -1.549908) (xy -1.257808 -1.549908) (xy -1.257808 -1.880108) (xy -2.019808 -1.880108)
			)
			(stroke
				(width 0)
				(type default)
			)
			(fill yes)
			(layer "F.SilkS")
		)
		(fp_line
			(start 1.549908 -1.549908)
			(end 1.549908 1.549908)
			(stroke
				(width 0.1)
				(type default)
			)
			(layer "F.Fab")
		)
		(fp_line
			(start -1.549908 -1.549908)
			(end 1.549908 -1.549908)
			(stroke
				(width 0.1)
				(type default)
			)
			(layer "F.Fab")
		)
		(fp_line
			(start 1.549908 1.549908)
			(end -1.549908 1.549908)
			(stroke
				(width 0.1)
				(type default)
			)
			(layer "F.Fab")
		)
		(fp_line
			(start -1.549908 1.549908)
			(end -1.549908 -1.549908)
			(stroke
				(width 0.1)
				(type default)
			)
			(layer "F.Fab")
		)
		(fp_poly
			(pts
				(xy -2.019808 -1.549908) (xy -1.257808 -1.549908) (xy -1.257808 -1.880108) (xy -2.019808 -1.880108)
			)
			(stroke
				(width 0)
				(type default)
			)
			(fill yes)
			(layer "F.Fab")
		)
		(pad "1" smd rect
			(at -1.500124 -1.249934)
			(size 0.2794 0.6096)
			(layers "F.Cu" "F.Mask" "F.Paste")
			(net "P3V3_SSD0")
		)
		(pad "2" smd rect
			(at -1.500124 -0.750062)
			(size 0.2794 0.6096)
			(layers "F.Cu" "F.Mask" "F.Paste")
			(net "P3V3_SSD0")
		)
		(pad "3" smd rect
			(at -1.500124 -0.249936)
			(size 0.2794 0.6096)
			(layers "F.Cu" "F.Mask" "F.Paste")
			(net "P3V3_SSD0")
		)
		(pad "4" smd rect
			(at -1.500124 0.249936)
			(size 0.2794 0.6096)
			(layers "F.Cu" "F.Mask" "F.Paste")
			(net "P3V3_SSD0")
		)
		(pad "5" smd rect
			(at -1.500124 0.750062)
			(size 0.2794 0.6096)
			(layers "F.Cu" "F.Mask" "F.Paste")
			(net "P3V3_SSD0")
		)
		(pad "6" smd rect
			(at -1.500124 1.249934)
			(size 0.2794 0.6096)
			(layers "F.Cu" "F.Mask" "F.Paste")
			(net "GND")
		)
		(pad "7" smd rect
			(at 1.500124 1.249934)
			(size 0.2794 0.6096)
			(layers "F.Cu" "F.Mask" "F.Paste")
			(net "P3V3_SSD0_SS")
		)
		(pad "8" smd rect
			(at 1.500124 0.750062)
			(size 0.2794 0.6096)
			(layers "F.Cu" "F.Mask" "F.Paste")
			(net "PWRGD_P3V3_SSD0")
		)
		(pad "9" smd rect
			(at 1.500124 0.249936)
			(size 0.2794 0.6096)
			(layers "F.Cu" "F.Mask" "F.Paste")
			(net "P3V3_SSD0_OCP")
		)
		(pad "10" smd rect
			(at 1.500124 -0.249936)
			(size 0.2794 0.6096)
			(layers "F.Cu" "F.Mask" "F.Paste")
			(net "P5V_AUX")
		)
		(pad "11" smd rect
			(at 1.500124 -0.750062)
			(size 0.2794 0.6096)
			(layers "F.Cu" "F.Mask" "F.Paste")
			(net "SSD0_AUX_P3V3_EN_R")
		)
		(pad "12" smd rect
			(at 1.500124 -1.249934)
			(size 0.2794 0.6096)
			(layers "F.Cu" "F.Mask" "F.Paste")
			(net "P3V3_AUX")
		)
		(pad "13" smd rect
			(at 0 0 90)
			(size 1.9812 2.7178)
			(layers "F.Cu" "F.Mask" "F.Paste")
			(net "P3V3_AUX")
		)
		(zone
			(layer "F.Cu")
			(hatch none 0.5)
			(connect_pads
				(clearance 0)
			)
			(min_thickness 0.25)
			(keepout
				(tracks not_allowed)
				(vias allowed)
				(pads allowed)
				(copperpour not_allowed)
				(footprints allowed)
			)
			(placement
				(enabled no)
				(sheetname "")
			)
			(fill
				(thermal_gap 0.5)
				(thermal_bridge_width 0.5)
				(island_removal_mode 0)
			)
			(polygon
				(pts
					(xy 5.34162 -56.806846) (xy 5.46862 -56.806846) (xy 8.44042 -56.806846) (xy 8.440928 -56.806846)
					(xy 8.440928 -54.520846) (xy 8.44042 -54.520846) (xy 8.31342 -54.520846) (xy 6.89102 -54.520846)
					(xy 6.89102 -54.622446) (xy 8.31342 -54.622446) (xy 8.31342 -56.705246) (xy 5.46862 -56.705246)
					(xy 5.46862 -54.622446) (xy 6.86562 -54.622446) (xy 6.86562 -54.520846) (xy 5.46862 -54.520846)
					(xy 5.34162 -54.520846) (xy 5.341112 -54.520846) (xy 5.341112 -56.806846)
				)
			)
		)
	)
	(footprint ""
		(layer "F.Cu")
		(at 189.047374 -21.37156)
		(property "Reference" "C3918"
			(at 0 0 0)
			(layer "F.SilkS")
			(hide yes)
			(effects
				(font
					(size 1.27 1.27)
				)
			)
		)
		(property "Value" ""
			(at 0 0 0)
			(layer "F.Fab")
			(effects
				(font
					(size 1.27 1.27)
				)
			)
		)
		(duplicate_pad_numbers_are_jumpers no)
		(fp_line
			(start -0.7874 -0.4064)
			(end 0.7874 -0.4064)
			(stroke
				(width 0.1524)
				(type default)
			)
			(layer "F.SilkS")
		)
		(fp_line
			(start -0.7874 0.4064)
			(end -0.7874 -0.4064)
			(stroke
				(width 0.1524)
				(type default)
			)
			(layer "F.SilkS")
		)
		(fp_line
			(start 0.7874 -0.4064)
			(end 0.7874 0.4064)
			(stroke
				(width 0.1524)
				(type default)
			)
			(layer "F.SilkS")
		)
		(fp_line
			(start 0.7874 0.4064)
			(end -0.7874 0.4064)
			(stroke
				(width 0.1524)
				(type default)
			)
			(layer "F.SilkS")
		)
		(fp_line
			(start -0.67945 -0.305054)
			(end -0.12065 -0.305054)
			(stroke
				(width 0.1)
				(type default)
			)
			(layer "F.Fab")
		)
		(fp_line
			(start -0.67945 0.3048)
			(end -0.67945 -0.305054)
			(stroke
				(width 0.1)
				(type default)
			)
			(layer "F.Fab")
		)
		(fp_line
			(start -0.12065 -0.305054)
			(end -0.12065 -0.2794)
			(stroke
				(width 0.1)
				(type default)
			)
			(layer "F.Fab")
		)
		(fp_line
			(start -0.12065 -0.2794)
			(end 0.12065 -0.2794)
			(stroke
				(width 0.1)
				(type default)
			)
			(layer "F.Fab")
		)
		(fp_line
			(start -0.12065 0.2794)
			(end -0.12065 0.3048)
			(stroke
				(width 0.1)
				(type default)
			)
			(layer "F.Fab")
		)
		(fp_line
			(start -0.12065 0.3048)
			(end -0.67945 0.3048)
			(stroke
				(width 0.1)
				(type default)
			)
			(layer "F.Fab")
		)
		(fp_line
			(start 0.120396 0.2794)
			(end -0.12065 0.2794)
			(stroke
				(width 0.1)
				(type default)
			)
			(layer "F.Fab")
		)
		(fp_line
			(start 0.120396 0.3048)
			(end 0.120396 0.2794)
			(stroke
				(width 0.1)
				(type default)
			)
			(layer "F.Fab")
		)
		(fp_line
			(start 0.12065 -0.3048)
			(end 0.67945 -0.3048)
			(stroke
				(width 0.1)
				(type default)
			)
			(layer "F.Fab")
		)
		(fp_line
			(start 0.12065 -0.2794)
			(end 0.12065 -0.3048)
			(stroke
				(width 0.1)
				(type default)
			)
			(layer "F.Fab")
		)
		(fp_line
			(start 0.67945 -0.3048)
			(end 0.67945 0.3048)
			(stroke
				(width 0.1)
				(type default)
			)
			(layer "F.Fab")
		)
		(fp_line
			(start 0.67945 0.3048)
			(end 0.120396 0.3048)
			(stroke
				(width 0.1)
				(type default)
			)
			(layer "F.Fab")
		)
		(pad "1" smd circle
			(at -0.40005 0)
			(size 0 0)
			(layers "F.Cu" "F.Mask" "F.Paste")
			(net "P12V_SSD6")
		)
		(pad "2" smd circle
			(at 0.40005 0)
			(size 0 0)
			(layers "F.Cu" "F.Mask" "F.Paste")
			(net "GND")
		)
	)
	(footprint ""
		(layer "F.Cu")
		(at 119.255286 -53.468524 90)
		(property "Reference" "PC533"
			(at 0 0 90)
			(layer "F.SilkS")
			(hide yes)
			(effects
				(font
					(size 1.27 1.27)
				)
			)
		)
		(property "Value" ""
			(at 0 0 90)
			(layer "F.Fab")
			(effects
				(font
					(size 1.27 1.27)
				)
			)
		)
		(duplicate_pad_numbers_are_jumpers no)
		(fp_line
			(start 1.524 -0.762)
			(end 1.524 0.762)
			(stroke
				(width 0.1524)
				(type default)
			)
			(layer "F.SilkS")
		)
		(fp_line
			(start -1.524 -0.762)
			(end 1.524 -0.762)
			(stroke
				(width 0.1524)
				(type default)
			)
			(layer "F.SilkS")
		)
		(fp_line
			(start 1.524 0.762)
			(end -1.524 0.762)
			(stroke
				(width 0.1524)
				(type default)
			)
			(layer "F.SilkS")
		)
		(fp_line
			(start -1.524 0.762)
			(end -1.524 -0.762)
			(stroke
				(width 0.1524)
				(type default)
			)
			(layer "F.SilkS")
		)
		(fp_line
			(start 1.1049 -0.724916)
			(end -1.1049 -0.724916)
			(stroke
				(width 0.1)
				(type default)
			)
			(layer "F.Fab")
		)
		(fp_line
			(start -1.1049 -0.724916)
			(end -1.1049 0.724916)
			(stroke
				(width 0.1)
				(type default)
			)
			(layer "F.Fab")
		)
		(fp_line
			(start 1.1049 0.724916)
			(end 1.1049 -0.724916)
			(stroke
				(width 0.1)
				(type default)
			)
			(layer "F.Fab")
		)
		(fp_line
			(start -1.1049 0.724916)
			(end 1.1049 0.724916)
			(stroke
				(width 0.1)
				(type default)
			)
			(layer "F.Fab")
		)
		(pad "1" smd rect
			(at -0.889 0 270)
			(size 1.016 1.27)
			(layers "F.Cu" "F.Mask" "F.Paste")
			(net "GND")
		)
		(pad "2" smd rect
			(at 0.889 0 270)
			(size 1.016 1.27)
			(layers "F.Cu" "F.Mask" "F.Paste")
			(net "P3V3_AUX")
		)
	)
	(footprint ""
		(layer "F.Cu")
		(at 280.085546 -25.1587 -90)
		(property "Reference" "R5762"
			(at 0 0 270)
			(layer "F.SilkS")
			(hide yes)
			(effects
				(font
					(size 1.27 1.27)
				)
			)
		)
		(property "Value" ""
			(at 0 0 270)
			(layer "F.Fab")
			(effects
				(font
					(size 1.27 1.27)
				)
			)
		)
		(duplicate_pad_numbers_are_jumpers no)
		(fp_line
			(start -0.7874 0.4064)
			(end -0.7874 -0.4064)
			(stroke
				(width 0.1524)
				(type default)
			)
			(layer "F.SilkS")
		)
		(fp_line
			(start 0.7874 0.4064)
			(end -0.7874 0.4064)
			(stroke
				(width 0.1524)
				(type default)
			)
			(layer "F.SilkS")
		)
		(fp_line
			(start -0.7874 -0.4064)
			(end 0.7874 -0.4064)
			(stroke
				(width 0.1524)
				(type default)
			)
			(layer "F.SilkS")
		)
		(fp_line
			(start 0.7874 -0.4064)
			(end 0.7874 0.4064)
			(stroke
				(width 0.1524)
				(type default)
			)
			(layer "F.SilkS")
		)
		(fp_line
			(start -0.67945 0.3048)
			(end -0.67945 -0.305054)
			(stroke
				(width 0.1)
				(type default)
			)
			(layer "F.Fab")
		)
		(fp_line
			(start -0.12065 0.3048)
			(end -0.67945 0.3048)
			(stroke
				(width 0.1)
				(type default)
			)
			(layer "F.Fab")
		)
		(fp_line
			(start 0.120396 0.3048)
			(end 0.120396 0.2794)
			(stroke
				(width 0.1)
				(type default)
			)
			(layer "F.Fab")
		)
		(fp_line
			(start 0.67945 0.3048)
			(end 0.120396 0.3048)
			(stroke
				(width 0.1)
				(type default)
			)
			(layer "F.Fab")
		)
		(fp_line
			(start -0.12065 0.2794)
			(end -0.12065 0.3048)
			(stroke
				(width 0.1)
				(type default)
			)
			(layer "F.Fab")
		)
		(fp_line
			(start 0.120396 0.2794)
			(end -0.12065 0.2794)
			(stroke
				(width 0.1)
				(type default)
			)
			(layer "F.Fab")
		)
		(fp_line
			(start -0.12065 -0.2794)
			(end 0.12065 -0.2794)
			(stroke
				(width 0.1)
				(type default)
			)
			(layer "F.Fab")
		)
		(fp_line
			(start 0.12065 -0.2794)
			(end 0.12065 -0.3048)
			(stroke
				(width 0.1)
				(type default)
			)
			(layer "F.Fab")
		)
		(fp_line
			(start 0.12065 -0.3048)
			(end 0.67945 -0.3048)
			(stroke
				(width 0.1)
				(type default)
			)
			(layer "F.Fab")
		)
		(fp_line
			(start 0.67945 -0.3048)
			(end 0.67945 0.3048)
			(stroke
				(width 0.1)
				(type default)
			)
			(layer "F.Fab")
		)
		(fp_line
			(start -0.67945 -0.305054)
			(end -0.12065 -0.305054)
			(stroke
				(width 0.1)
				(type default)
			)
			(layer "F.Fab")
		)
		(fp_line
			(start -0.12065 -0.305054)
			(end -0.12065 -0.2794)
			(stroke
				(width 0.1)
				(type default)
			)
			(layer "F.Fab")
		)
		(pad "1" smd circle
			(at -0.40005 0 270)
			(size 0 0)
			(layers "F.Cu" "F.Mask" "F.Paste")
			(net "SSD9_LED_ISO_N")
		)
		(pad "2" smd circle
			(at 0.40005 0 270)
			(size 0 0)
			(layers "F.Cu" "F.Mask" "F.Paste")
			(net "SSD9_LED_ISO_R_N")
		)
	)
	(footprint ""
		(layer "F.Cu")
		(at 318.37884 -59.577986 -90)
		(property "Reference" "R901"
			(at 0 0 270)
			(layer "F.SilkS")
			(hide yes)
			(effects
				(font
					(size 1.27 1.27)
				)
			)
		)
		(property "Value" ""
			(at 0 0 270)
			(layer "F.Fab")
			(effects
				(font
					(size 1.27 1.27)
				)
			)
		)
		(duplicate_pad_numbers_are_jumpers no)
		(fp_line
			(start -0.7874 0.4064)
			(end -0.7874 -0.4064)
			(stroke
				(width 0.1524)
				(type default)
			)
			(layer "F.SilkS")
		)
		(fp_line
			(start 0.7874 0.4064)
			(end -0.7874 0.4064)
			(stroke
				(width 0.1524)
				(type default)
			)
			(layer "F.SilkS")
		)
		(fp_line
			(start -0.7874 -0.4064)
			(end 0.7874 -0.4064)
			(stroke
				(width 0.1524)
				(type default)
			)
			(layer "F.SilkS")
		)
		(fp_line
			(start 0.7874 -0.4064)
			(end 0.7874 0.4064)
			(stroke
				(width 0.1524)
				(type default)
			)
			(layer "F.SilkS")
		)
		(fp_line
			(start -0.67945 0.3048)
			(end -0.67945 -0.305054)
			(stroke
				(width 0.1)
				(type default)
			)
			(layer "F.Fab")
		)
		(fp_line
			(start -0.12065 0.3048)
			(end -0.67945 0.3048)
			(stroke
				(width 0.1)
				(type default)
			)
			(layer "F.Fab")
		)
		(fp_line
			(start 0.120396 0.3048)
			(end 0.120396 0.2794)
			(stroke
				(width 0.1)
				(type default)
			)
			(layer "F.Fab")
		)
		(fp_line
			(start 0.67945 0.3048)
			(end 0.120396 0.3048)
			(stroke
				(width 0.1)
				(type default)
			)
			(layer "F.Fab")
		)
		(fp_line
			(start -0.12065 0.2794)
			(end -0.12065 0.3048)
			(stroke
				(width 0.1)
				(type default)
			)
			(layer "F.Fab")
		)
		(fp_line
			(start 0.120396 0.2794)
			(end -0.12065 0.2794)
			(stroke
				(width 0.1)
				(type default)
			)
			(layer "F.Fab")
		)
		(fp_line
			(start -0.12065 -0.2794)
			(end 0.12065 -0.2794)
			(stroke
				(width 0.1)
				(type default)
			)
			(layer "F.Fab")
		)
		(fp_line
			(start 0.12065 -0.2794)
			(end 0.12065 -0.3048)
			(stroke
				(width 0.1)
				(type default)
			)
			(layer "F.Fab")
		)
		(fp_line
			(start 0.12065 -0.3048)
			(end 0.67945 -0.3048)
			(stroke
				(width 0.1)
				(type default)
			)
			(layer "F.Fab")
		)
		(fp_line
			(start 0.67945 -0.3048)
			(end 0.67945 0.3048)
			(stroke
				(width 0.1)
				(type default)
			)
			(layer "F.Fab")
		)
		(fp_line
			(start -0.67945 -0.305054)
			(end -0.12065 -0.305054)
			(stroke
				(width 0.1)
				(type default)
			)
			(layer "F.Fab")
		)
		(fp_line
			(start -0.12065 -0.305054)
			(end -0.12065 -0.2794)
			(stroke
				(width 0.1)
				(type default)
			)
			(layer "F.Fab")
		)
		(pad "1" smd circle
			(at -0.40005 0 270)
			(size 0 0)
			(layers "F.Cu" "F.Mask" "F.Paste")
			(net "P3V3_SSD11")
		)
		(pad "2" smd circle
			(at 0.40005 0 270)
			(size 0 0)
			(layers "F.Cu" "F.Mask" "F.Paste")
			(net "PWRGD_P3V3_SSD11")
		)
	)
	(footprint ""
		(layer "F.Cu")
		(at 323.067934 -289.230816 90)
		(property "Reference" "R3985"
			(at 0 0 90)
			(layer "F.SilkS")
			(hide yes)
			(effects
				(font
					(size 1.27 1.27)
				)
			)
		)
		(property "Value" ""
			(at 0 0 90)
			(layer "F.Fab")
			(effects
				(font
					(size 1.27 1.27)
				)
			)
		)
		(duplicate_pad_numbers_are_jumpers no)
		(fp_line
			(start 0.7874 -0.4064)
			(end 0.7874 0.4064)
			(stroke
				(width 0.1524)
				(type default)
			)
			(layer "F.SilkS")
		)
		(fp_line
			(start -0.7874 -0.4064)
			(end 0.7874 -0.4064)
			(stroke
				(width 0.1524)
				(type default)
			)
			(layer "F.SilkS")
		)
		(fp_line
			(start 0.7874 0.4064)
			(end -0.7874 0.4064)
			(stroke
				(width 0.1524)
				(type default)
			)
			(layer "F.SilkS")
		)
		(fp_line
			(start -0.7874 0.4064)
			(end -0.7874 -0.4064)
			(stroke
				(width 0.1524)
				(type default)
			)
			(layer "F.SilkS")
		)
		(fp_line
			(start -0.12065 -0.305054)
			(end -0.12065 -0.2794)
			(stroke
				(width 0.1)
				(type default)
			)
			(layer "F.Fab")
		)
		(fp_line
			(start -0.67945 -0.305054)
			(end -0.12065 -0.305054)
			(stroke
				(width 0.1)
				(type default)
			)
			(layer "F.Fab")
		)
		(fp_line
			(start 0.67945 -0.3048)
			(end 0.67945 0.3048)
			(stroke
				(width 0.1)
				(type default)
			)
			(layer "F.Fab")
		)
		(fp_line
			(start 0.12065 -0.3048)
			(end 0.67945 -0.3048)
			(stroke
				(width 0.1)
				(type default)
			)
			(layer "F.Fab")
		)
		(fp_line
			(start 0.12065 -0.2794)
			(end 0.12065 -0.3048)
			(stroke
				(width 0.1)
				(type default)
			)
			(layer "F.Fab")
		)
		(fp_line
			(start -0.12065 -0.2794)
			(end 0.12065 -0.2794)
			(stroke
				(width 0.1)
				(type default)
			)
			(layer "F.Fab")
		)
		(fp_line
			(start 0.120396 0.2794)
			(end -0.12065 0.2794)
			(stroke
				(width 0.1)
				(type default)
			)
			(layer "F.Fab")
		)
		(fp_line
			(start -0.12065 0.2794)
			(end -0.12065 0.3048)
			(stroke
				(width 0.1)
				(type default)
			)
			(layer "F.Fab")
		)
		(fp_line
			(start 0.67945 0.3048)
			(end 0.120396 0.3048)
			(stroke
				(width 0.1)
				(type default)
			)
			(layer "F.Fab")
		)
		(fp_line
			(start 0.120396 0.3048)
			(end 0.120396 0.2794)
			(stroke
				(width 0.1)
				(type default)
			)
			(layer "F.Fab")
		)
		(fp_line
			(start -0.12065 0.3048)
			(end -0.67945 0.3048)
			(stroke
				(width 0.1)
				(type default)
			)
			(layer "F.Fab")
		)
		(fp_line
			(start -0.67945 0.3048)
			(end -0.67945 -0.305054)
			(stroke
				(width 0.1)
				(type default)
			)
			(layer "F.Fab")
		)
		(pad "1" smd circle
			(at -0.40005 0 90)
			(size 0 0)
			(layers "F.Cu" "F.Mask" "F.Paste")
			(net "SMB_PEX2_FPGA_SCL")
		)
		(pad "2" smd circle
			(at 0.40005 0 90)
			(size 0 0)
			(layers "F.Cu" "F.Mask" "F.Paste")
			(net "SMB_PEX2_HOST_LS_SCL")
		)
	)
	(footprint ""
		(layer "F.Cu")
		(at 106.035094 -397.512286 -90)
		(property "Reference" "R5446"
			(at 0 0 270)
			(layer "F.SilkS")
			(hide yes)
			(effects
				(font
					(size 1.27 1.27)
				)
			)
		)
		(property "Value" ""
			(at 0 0 270)
			(layer "F.Fab")
			(effects
				(font
					(size 1.27 1.27)
				)
			)
		)
		(duplicate_pad_numbers_are_jumpers no)
		(fp_line
			(start -0.7874 0.4064)
			(end -0.7874 -0.4064)
			(stroke
				(width 0.1524)
				(type default)
			)
			(layer "F.SilkS")
		)
		(fp_line
			(start 0.7874 0.4064)
			(end -0.7874 0.4064)
			(stroke
				(width 0.1524)
				(type default)
			)
			(layer "F.SilkS")
		)
		(fp_line
			(start -0.7874 -0.4064)
			(end 0.7874 -0.4064)
			(stroke
				(width 0.1524)
				(type default)
			)
			(layer "F.SilkS")
		)
		(fp_line
			(start 0.7874 -0.4064)
			(end 0.7874 0.4064)
			(stroke
				(width 0.1524)
				(type default)
			)
			(layer "F.SilkS")
		)
		(fp_line
			(start -0.67945 0.3048)
			(end -0.67945 -0.305054)
			(stroke
				(width 0.1)
				(type default)
			)
			(layer "F.Fab")
		)
		(fp_line
			(start -0.12065 0.3048)
			(end -0.67945 0.3048)
			(stroke
				(width 0.1)
				(type default)
			)
			(layer "F.Fab")
		)
		(fp_line
			(start 0.120396 0.3048)
			(end 0.120396 0.2794)
			(stroke
				(width 0.1)
				(type default)
			)
			(layer "F.Fab")
		)
		(fp_line
			(start 0.67945 0.3048)
			(end 0.120396 0.3048)
			(stroke
				(width 0.1)
				(type default)
			)
			(layer "F.Fab")
		)
		(fp_line
			(start -0.12065 0.2794)
			(end -0.12065 0.3048)
			(stroke
				(width 0.1)
				(type default)
			)
			(layer "F.Fab")
		)
		(fp_line
			(start 0.120396 0.2794)
			(end -0.12065 0.2794)
			(stroke
				(width 0.1)
				(type default)
			)
			(layer "F.Fab")
		)
		(fp_line
			(start -0.12065 -0.2794)
			(end 0.12065 -0.2794)
			(stroke
				(width 0.1)
				(type default)
			)
			(layer "F.Fab")
		)
		(fp_line
			(start 0.12065 -0.2794)
			(end 0.12065 -0.3048)
			(stroke
				(width 0.1)
				(type default)
			)
			(layer "F.Fab")
		)
		(fp_line
			(start 0.12065 -0.3048)
			(end 0.67945 -0.3048)
			(stroke
				(width 0.1)
				(type default)
			)
			(layer "F.Fab")
		)
		(fp_line
			(start 0.67945 -0.3048)
			(end 0.67945 0.3048)
			(stroke
				(width 0.1)
				(type default)
			)
			(layer "F.Fab")
		)
		(fp_line
			(start -0.67945 -0.305054)
			(end -0.12065 -0.305054)
			(stroke
				(width 0.1)
				(type default)
			)
			(layer "F.Fab")
		)
		(fp_line
			(start -0.12065 -0.305054)
			(end -0.12065 -0.2794)
			(stroke
				(width 0.1)
				(type default)
			)
			(layer "F.Fab")
		)
		(pad "1" smd circle
			(at -0.40005 0 270)
			(size 0 0)
			(layers "F.Cu" "F.Mask" "F.Paste")
			(net "P3V3_AUX")
		)
		(pad "2" smd circle
			(at 0.40005 0 270)
			(size 0 0)
			(layers "F.Cu" "F.Mask" "F.Paste")
			(net "RST_BIC_USB_HUB_R1_N")
		)
	)
	(footprint ""
		(layer "F.Cu")
		(at 228.024944 -98.36912 90)
		(property "Reference" "R4456"
			(at 0 0 90)
			(layer "F.SilkS")
			(hide yes)
			(effects
				(font
					(size 1.27 1.27)
				)
			)
		)
		(property "Value" ""
			(at 0 0 90)
			(layer "F.Fab")
			(effects
				(font
					(size 1.27 1.27)
				)
			)
		)
		(duplicate_pad_numbers_are_jumpers no)
		(fp_line
			(start 0.7874 -0.4064)
			(end 0.7874 0.4064)
			(stroke
				(width 0.1524)
				(type default)
			)
			(layer "F.SilkS")
		)
		(fp_line
			(start -0.7874 -0.4064)
			(end 0.7874 -0.4064)
			(stroke
				(width 0.1524)
				(type default)
			)
			(layer "F.SilkS")
		)
		(fp_line
			(start 0.7874 0.4064)
			(end -0.7874 0.4064)
			(stroke
				(width 0.1524)
				(type default)
			)
			(layer "F.SilkS")
		)
		(fp_line
			(start -0.7874 0.4064)
			(end -0.7874 -0.4064)
			(stroke
				(width 0.1524)
				(type default)
			)
			(layer "F.SilkS")
		)
		(fp_line
			(start -0.12065 -0.305054)
			(end -0.12065 -0.2794)
			(stroke
				(width 0.1)
				(type default)
			)
			(layer "F.Fab")
		)
		(fp_line
			(start -0.67945 -0.305054)
			(end -0.12065 -0.305054)
			(stroke
				(width 0.1)
				(type default)
			)
			(layer "F.Fab")
		)
		(fp_line
			(start 0.67945 -0.3048)
			(end 0.67945 0.3048)
			(stroke
				(width 0.1)
				(type default)
			)
			(layer "F.Fab")
		)
		(fp_line
			(start 0.12065 -0.3048)
			(end 0.67945 -0.3048)
			(stroke
				(width 0.1)
				(type default)
			)
			(layer "F.Fab")
		)
		(fp_line
			(start 0.12065 -0.2794)
			(end 0.12065 -0.3048)
			(stroke
				(width 0.1)
				(type default)
			)
			(layer "F.Fab")
		)
		(fp_line
			(start -0.12065 -0.2794)
			(end 0.12065 -0.2794)
			(stroke
				(width 0.1)
				(type default)
			)
			(layer "F.Fab")
		)
		(fp_line
			(start 0.120396 0.2794)
			(end -0.12065 0.2794)
			(stroke
				(width 0.1)
				(type default)
			)
			(layer "F.Fab")
		)
		(fp_line
			(start -0.12065 0.2794)
			(end -0.12065 0.3048)
			(stroke
				(width 0.1)
				(type default)
			)
			(layer "F.Fab")
		)
		(fp_line
			(start 0.67945 0.3048)
			(end 0.120396 0.3048)
			(stroke
				(width 0.1)
				(type default)
			)
			(layer "F.Fab")
		)
		(fp_line
			(start 0.120396 0.3048)
			(end 0.120396 0.2794)
			(stroke
				(width 0.1)
				(type default)
			)
			(layer "F.Fab")
		)
		(fp_line
			(start -0.12065 0.3048)
			(end -0.67945 0.3048)
			(stroke
				(width 0.1)
				(type default)
			)
			(layer "F.Fab")
		)
		(fp_line
			(start -0.67945 0.3048)
			(end -0.67945 -0.305054)
			(stroke
				(width 0.1)
				(type default)
			)
			(layer "F.Fab")
		)
		(pad "1" smd circle
			(at -0.40005 0 90)
			(size 0 0)
			(layers "F.Cu" "F.Mask" "F.Paste")
			(net "HP_NIC3_EN")
		)
		(pad "2" smd circle
			(at 0.40005 0 90)
			(size 0 0)
			(layers "F.Cu" "F.Mask" "F.Paste")
			(net "P12V_NIC3_EN_R")
		)
	)
	(footprint ""
		(layer "F.Cu")
		(at 454.930002 -250.20524)
		(property "Reference" "C4433"
			(at 0 0 0)
			(layer "F.SilkS")
			(hide yes)
			(effects
				(font
					(size 1.27 1.27)
				)
			)
		)
		(property "Value" ""
			(at 0 0 0)
			(layer "F.Fab")
			(effects
				(font
					(size 1.27 1.27)
				)
			)
		)
		(duplicate_pad_numbers_are_jumpers no)
		(fp_line
			(start -0.7874 -0.4064)
			(end 0.7874 -0.4064)
			(stroke
				(width 0.1524)
				(type default)
			)
			(layer "F.SilkS")
		)
		(fp_line
			(start -0.7874 0.4064)
			(end -0.7874 -0.4064)
			(stroke
				(width 0.1524)
				(type default)
			)
			(layer "F.SilkS")
		)
		(fp_line
			(start 0.7874 -0.4064)
			(end 0.7874 0.4064)
			(stroke
				(width 0.1524)
				(type default)
			)
			(layer "F.SilkS")
		)
		(fp_line
			(start 0.7874 0.4064)
			(end -0.7874 0.4064)
			(stroke
				(width 0.1524)
				(type default)
			)
			(layer "F.SilkS")
		)
		(fp_line
			(start -0.67945 -0.305054)
			(end -0.12065 -0.305054)
			(stroke
				(width 0.1)
				(type default)
			)
			(layer "F.Fab")
		)
		(fp_line
			(start -0.67945 0.3048)
			(end -0.67945 -0.305054)
			(stroke
				(width 0.1)
				(type default)
			)
			(layer "F.Fab")
		)
		(fp_line
			(start -0.12065 -0.305054)
			(end -0.12065 -0.2794)
			(stroke
				(width 0.1)
				(type default)
			)
			(layer "F.Fab")
		)
		(fp_line
			(start -0.12065 -0.2794)
			(end 0.12065 -0.2794)
			(stroke
				(width 0.1)
				(type default)
			)
			(layer "F.Fab")
		)
		(fp_line
			(start -0.12065 0.2794)
			(end -0.12065 0.3048)
			(stroke
				(width 0.1)
				(type default)
			)
			(layer "F.Fab")
		)
		(fp_line
			(start -0.12065 0.3048)
			(end -0.67945 0.3048)
			(stroke
				(width 0.1)
				(type default)
			)
			(layer "F.Fab")
		)
		(fp_line
			(start 0.120396 0.2794)
			(end -0.12065 0.2794)
			(stroke
				(width 0.1)
				(type default)
			)
			(layer "F.Fab")
		)
		(fp_line
			(start 0.120396 0.3048)
			(end 0.120396 0.2794)
			(stroke
				(width 0.1)
				(type default)
			)
			(layer "F.Fab")
		)
		(fp_line
			(start 0.12065 -0.3048)
			(end 0.67945 -0.3048)
			(stroke
				(width 0.1)
				(type default)
			)
			(layer "F.Fab")
		)
		(fp_line
			(start 0.12065 -0.2794)
			(end 0.12065 -0.3048)
			(stroke
				(width 0.1)
				(type default)
			)
			(layer "F.Fab")
		)
		(fp_line
			(start 0.67945 -0.3048)
			(end 0.67945 0.3048)
			(stroke
				(width 0.1)
				(type default)
			)
			(layer "F.Fab")
		)
		(fp_line
			(start 0.67945 0.3048)
			(end 0.120396 0.3048)
			(stroke
				(width 0.1)
				(type default)
			)
			(layer "F.Fab")
		)
		(pad "1" smd circle
			(at -0.40005 0)
			(size 0 0)
			(layers "F.Cu" "F.Mask" "F.Paste")
			(net "PEX3_P1V8_PLL_EN")
		)
		(pad "2" smd circle
			(at 0.40005 0)
			(size 0 0)
			(layers "F.Cu" "F.Mask" "F.Paste")
			(net "GND")
		)
	)
	(footprint ""
		(layer "F.Cu")
		(at 123.71324 -139.376404)
		(property "Reference" "R857"
			(at 0 0 0)
			(layer "F.SilkS")
			(hide yes)
			(effects
				(font
					(size 1.27 1.27)
				)
			)
		)
		(property "Value" ""
			(at 0 0 0)
			(layer "F.Fab")
			(effects
				(font
					(size 1.27 1.27)
				)
			)
		)
		(duplicate_pad_numbers_are_jumpers no)
		(fp_line
			(start -0.7874 -0.4064)
			(end 0.7874 -0.4064)
			(stroke
				(width 0.1524)
				(type default)
			)
			(layer "F.SilkS")
		)
		(fp_line
			(start -0.7874 0.4064)
			(end -0.7874 -0.4064)
			(stroke
				(width 0.1524)
				(type default)
			)
			(layer "F.SilkS")
		)
		(fp_line
			(start 0.7874 -0.4064)
			(end 0.7874 0.4064)
			(stroke
				(width 0.1524)
				(type default)
			)
			(layer "F.SilkS")
		)
		(fp_line
			(start 0.7874 0.4064)
			(end -0.7874 0.4064)
			(stroke
				(width 0.1524)
				(type default)
			)
			(layer "F.SilkS")
		)
		(fp_line
			(start -0.67945 -0.305054)
			(end -0.12065 -0.305054)
			(stroke
				(width 0.1)
				(type default)
			)
			(layer "F.Fab")
		)
		(fp_line
			(start -0.67945 0.3048)
			(end -0.67945 -0.305054)
			(stroke
				(width 0.1)
				(type default)
			)
			(layer "F.Fab")
		)
		(fp_line
			(start -0.12065 -0.305054)
			(end -0.12065 -0.2794)
			(stroke
				(width 0.1)
				(type default)
			)
			(layer "F.Fab")
		)
		(fp_line
			(start -0.12065 -0.2794)
			(end 0.12065 -0.2794)
			(stroke
				(width 0.1)
				(type default)
			)
			(layer "F.Fab")
		)
		(fp_line
			(start -0.12065 0.2794)
			(end -0.12065 0.3048)
			(stroke
				(width 0.1)
				(type default)
			)
			(layer "F.Fab")
		)
		(fp_line
			(start -0.12065 0.3048)
			(end -0.67945 0.3048)
			(stroke
				(width 0.1)
				(type default)
			)
			(layer "F.Fab")
		)
		(fp_line
			(start 0.120396 0.2794)
			(end -0.12065 0.2794)
			(stroke
				(width 0.1)
				(type default)
			)
			(layer "F.Fab")
		)
		(fp_line
			(start 0.120396 0.3048)
			(end 0.120396 0.2794)
			(stroke
				(width 0.1)
				(type default)
			)
			(layer "F.Fab")
		)
		(fp_line
			(start 0.12065 -0.3048)
			(end 0.67945 -0.3048)
			(stroke
				(width 0.1)
				(type default)
			)
			(layer "F.Fab")
		)
		(fp_line
			(start 0.12065 -0.2794)
			(end 0.12065 -0.3048)
			(stroke
				(width 0.1)
				(type default)
			)
			(layer "F.Fab")
		)
		(fp_line
			(start 0.67945 -0.3048)
			(end 0.67945 0.3048)
			(stroke
				(width 0.1)
				(type default)
			)
			(layer "F.Fab")
		)
		(fp_line
			(start 0.67945 0.3048)
			(end 0.120396 0.3048)
			(stroke
				(width 0.1)
				(type default)
			)
			(layer "F.Fab")
		)
		(pad "1" smd circle
			(at -0.40005 0)
			(size 0 0)
			(layers "F.Cu" "F.Mask" "F.Paste")
			(net "P3V3_AUX")
		)
		(pad "2" smd circle
			(at 0.40005 0)
			(size 0 0)
			(layers "F.Cu" "F.Mask" "F.Paste")
			(net "PWRGD_P12V_NIC2")
		)
	)
	(footprint ""
		(layer "F.Cu")
		(at 102.1588 -201.6252)
		(property "Reference" "C4445"
			(at 0 0 0)
			(layer "F.SilkS")
			(hide yes)
			(effects
				(font
					(size 1.27 1.27)
				)
			)
		)
		(property "Value" ""
			(at 0 0 0)
			(layer "F.Fab")
			(effects
				(font
					(size 1.27 1.27)
				)
			)
		)
		(duplicate_pad_numbers_are_jumpers no)
		(fp_line
			(start -1.2954 -0.5842)
			(end 1.2954 -0.5842)
			(stroke
				(width 0.1524)
				(type default)
			)
			(layer "F.SilkS")
		)
		(fp_line
			(start -1.2954 0.5842)
			(end -1.2954 -0.5842)
			(stroke
				(width 0.1524)
				(type default)
			)
			(layer "F.SilkS")
		)
		(fp_line
			(start 1.2954 -0.5842)
			(end 1.2954 0.5842)
			(stroke
				(width 0.1524)
				(type default)
			)
			(layer "F.SilkS")
		)
		(fp_line
			(start 1.2954 0.5842)
			(end -1.2954 0.5842)
			(stroke
				(width 0.1524)
				(type default)
			)
			(layer "F.SilkS")
		)
		(fp_line
			(start -1.1938 -0.4064)
			(end -0.8636 -0.4064)
			(stroke
				(width 0.1)
				(type default)
			)
			(layer "F.Fab")
		)
		(fp_line
			(start -1.1938 0.4064)
			(end -1.1938 -0.4064)
			(stroke
				(width 0.1)
				(type default)
			)
			(layer "F.Fab")
		)
		(fp_line
			(start -0.8636 -0.4572)
			(end 0.8636 -0.4572)
			(stroke
				(width 0.1)
				(type default)
			)
			(layer "F.Fab")
		)
		(fp_line
			(start -0.8636 -0.4064)
			(end -0.8636 -0.4572)
			(stroke
				(width 0.1)
				(type default)
			)
			(layer "F.Fab")
		)
		(fp_line
			(start -0.8636 0.4064)
			(end -1.1938 0.4064)
			(stroke
				(width 0.1)
				(type default)
			)
			(layer "F.Fab")
		)
		(fp_line
			(start -0.8636 0.4572)
			(end -0.8636 0.4064)
			(stroke
				(width 0.1)
				(type default)
			)
			(layer "F.Fab")
		)
		(fp_line
			(start 0.8636 -0.4572)
			(end 0.8636 -0.4064)
			(stroke
				(width 0.1)
				(type default)
			)
			(layer "F.Fab")
		)
		(fp_line
			(start 0.8636 -0.4064)
			(end 1.1938 -0.4064)
			(stroke
				(width 0.1)
				(type default)
			)
			(layer "F.Fab")
		)
		(fp_line
			(start 0.8636 0.4064)
			(end 0.8636 0.4572)
			(stroke
				(width 0.1)
				(type default)
			)
			(layer "F.Fab")
		)
		(fp_line
			(start 0.8636 0.4572)
			(end -0.8636 0.4572)
			(stroke
				(width 0.1)
				(type default)
			)
			(layer "F.Fab")
		)
		(fp_line
			(start 1.1938 -0.4064)
			(end 1.1938 0.4064)
			(stroke
				(width 0.1)
				(type default)
			)
			(layer "F.Fab")
		)
		(fp_line
			(start 1.1938 0.4064)
			(end 0.8636 0.4064)
			(stroke
				(width 0.1)
				(type default)
			)
			(layer "F.Fab")
		)
		(pad "1" smd rect
			(at -0.7366 0 270)
			(size 0.7112 0.8128)
			(layers "F.Cu" "F.Mask" "F.Paste")
			(net "P3V3_AUX")
		)
		(pad "2" smd rect
			(at 0.7366 0 270)
			(size 0.7112 0.8128)
			(layers "F.Cu" "F.Mask" "F.Paste")
			(net "GND")
		)
	)
	(footprint ""
		(layer "F.Cu")
		(at 268.506448 -87.251286)
		(property "Reference" "R1057"
			(at 0 0 0)
			(layer "F.SilkS")
			(hide yes)
			(effects
				(font
					(size 1.27 1.27)
				)
			)
		)
		(property "Value" ""
			(at 0 0 0)
			(layer "F.Fab")
			(effects
				(font
					(size 1.27 1.27)
				)
			)
		)
		(duplicate_pad_numbers_are_jumpers no)
		(fp_line
			(start -0.7874 -0.4064)
			(end 0.7874 -0.4064)
			(stroke
				(width 0.1524)
				(type default)
			)
			(layer "F.SilkS")
		)
		(fp_line
			(start -0.7874 0.4064)
			(end -0.7874 -0.4064)
			(stroke
				(width 0.1524)
				(type default)
			)
			(layer "F.SilkS")
		)
		(fp_line
			(start 0.7874 -0.4064)
			(end 0.7874 0.4064)
			(stroke
				(width 0.1524)
				(type default)
			)
			(layer "F.SilkS")
		)
		(fp_line
			(start 0.7874 0.4064)
			(end -0.7874 0.4064)
			(stroke
				(width 0.1524)
				(type default)
			)
			(layer "F.SilkS")
		)
		(fp_line
			(start -0.67945 -0.305054)
			(end -0.12065 -0.305054)
			(stroke
				(width 0.1)
				(type default)
			)
			(layer "F.Fab")
		)
		(fp_line
			(start -0.67945 0.3048)
			(end -0.67945 -0.305054)
			(stroke
				(width 0.1)
				(type default)
			)
			(layer "F.Fab")
		)
		(fp_line
			(start -0.12065 -0.305054)
			(end -0.12065 -0.2794)
			(stroke
				(width 0.1)
				(type default)
			)
			(layer "F.Fab")
		)
		(fp_line
			(start -0.12065 -0.2794)
			(end 0.12065 -0.2794)
			(stroke
				(width 0.1)
				(type default)
			)
			(layer "F.Fab")
		)
		(fp_line
			(start -0.12065 0.2794)
			(end -0.12065 0.3048)
			(stroke
				(width 0.1)
				(type default)
			)
			(layer "F.Fab")
		)
		(fp_line
			(start -0.12065 0.3048)
			(end -0.67945 0.3048)
			(stroke
				(width 0.1)
				(type default)
			)
			(layer "F.Fab")
		)
		(fp_line
			(start 0.120396 0.2794)
			(end -0.12065 0.2794)
			(stroke
				(width 0.1)
				(type default)
			)
			(layer "F.Fab")
		)
		(fp_line
			(start 0.120396 0.3048)
			(end 0.120396 0.2794)
			(stroke
				(width 0.1)
				(type default)
			)
			(layer "F.Fab")
		)
		(fp_line
			(start 0.12065 -0.3048)
			(end 0.67945 -0.3048)
			(stroke
				(width 0.1)
				(type default)
			)
			(layer "F.Fab")
		)
		(fp_line
			(start 0.12065 -0.2794)
			(end 0.12065 -0.3048)
			(stroke
				(width 0.1)
				(type default)
			)
			(layer "F.Fab")
		)
		(fp_line
			(start 0.67945 -0.3048)
			(end 0.67945 0.3048)
			(stroke
				(width 0.1)
				(type default)
			)
			(layer "F.Fab")
		)
		(fp_line
			(start 0.67945 0.3048)
			(end 0.120396 0.3048)
			(stroke
				(width 0.1)
				(type default)
			)
			(layer "F.Fab")
		)
		(pad "1" smd circle
			(at -0.40005 0)
			(size 0 0)
			(layers "F.Cu" "F.Mask" "F.Paste")
			(net "CLK_BUFFER_DB2000QL_OE0_N")
		)
		(pad "2" smd circle
			(at 0.40005 0)
			(size 0 0)
			(layers "F.Cu" "F.Mask" "F.Paste")
			(net "P3V3")
		)
	)
	(footprint ""
		(layer "F.Cu")
		(at 375.230136 -300.406308 -90)
		(property "Reference" "C3539"
			(at 0 0 270)
			(layer "F.SilkS")
			(hide yes)
			(effects
				(font
					(size 1.27 1.27)
				)
			)
		)
		(property "Value" ""
			(at 0 0 270)
			(layer "F.Fab")
			(effects
				(font
					(size 1.27 1.27)
				)
			)
		)
		(duplicate_pad_numbers_are_jumpers no)
		(fp_line
			(start -1.2954 0.5842)
			(end -1.2954 -0.5842)
			(stroke
				(width 0.1524)
				(type default)
			)
			(layer "F.SilkS")
		)
		(fp_line
			(start 1.2954 0.5842)
			(end -1.2954 0.5842)
			(stroke
				(width 0.1524)
				(type default)
			)
			(layer "F.SilkS")
		)
		(fp_line
			(start -1.2954 -0.5842)
			(end 1.2954 -0.5842)
			(stroke
				(width 0.1524)
				(type default)
			)
			(layer "F.SilkS")
		)
		(fp_line
			(start 1.2954 -0.5842)
			(end 1.2954 0.5842)
			(stroke
				(width 0.1524)
				(type default)
			)
			(layer "F.SilkS")
		)
		(fp_line
			(start -0.8636 0.4572)
			(end -0.8636 0.4064)
			(stroke
				(width 0.1)
				(type default)
			)
			(layer "F.Fab")
		)
		(fp_line
			(start 0.8636 0.4572)
			(end -0.8636 0.4572)
			(stroke
				(width 0.1)
				(type default)
			)
			(layer "F.Fab")
		)
		(fp_line
			(start -1.1938 0.4064)
			(end -1.1938 -0.4064)
			(stroke
				(width 0.1)
				(type default)
			)
			(layer "F.Fab")
		)
		(fp_line
			(start -0.8636 0.4064)
			(end -1.1938 0.4064)
			(stroke
				(width 0.1)
				(type default)
			)
			(layer "F.Fab")
		)
		(fp_line
			(start 0.8636 0.4064)
			(end 0.8636 0.4572)
			(stroke
				(width 0.1)
				(type default)
			)
			(layer "F.Fab")
		)
		(fp_line
			(start 1.1938 0.4064)
			(end 0.8636 0.4064)
			(stroke
				(width 0.1)
				(type default)
			)
			(layer "F.Fab")
		)
		(fp_line
			(start -1.1938 -0.4064)
			(end -0.8636 -0.4064)
			(stroke
				(width 0.1)
				(type default)
			)
			(layer "F.Fab")
		)
		(fp_line
			(start -0.8636 -0.4064)
			(end -0.8636 -0.4572)
			(stroke
				(width 0.1)
				(type default)
			)
			(layer "F.Fab")
		)
		(fp_line
			(start 0.8636 -0.4064)
			(end 1.1938 -0.4064)
			(stroke
				(width 0.1)
				(type default)
			)
			(layer "F.Fab")
		)
		(fp_line
			(start 1.1938 -0.4064)
			(end 1.1938 0.4064)
			(stroke
				(width 0.1)
				(type default)
			)
			(layer "F.Fab")
		)
		(fp_line
			(start -0.8636 -0.4572)
			(end 0.8636 -0.4572)
			(stroke
				(width 0.1)
				(type default)
			)
			(layer "F.Fab")
		)
		(fp_line
			(start 0.8636 -0.4572)
			(end 0.8636 -0.4064)
			(stroke
				(width 0.1)
				(type default)
			)
			(layer "F.Fab")
		)
		(pad "1" smd rect
			(at -0.7366 0 180)
			(size 0.7112 0.8128)
			(layers "F.Cu" "F.Mask" "F.Paste")
			(net "P1V8_PLL0_PEX3")
		)
		(pad "2" smd rect
			(at 0.7366 0 180)
			(size 0.7112 0.8128)
			(layers "F.Cu" "F.Mask" "F.Paste")
			(net "GND")
		)
	)
	(footprint ""
		(layer "F.Cu")
		(at 460.354934 -284.375606)
		(property "Reference" "PC279"
			(at 0 0 0)
			(layer "F.SilkS")
			(hide yes)
			(effects
				(font
					(size 1.27 1.27)
				)
			)
		)
		(property "Value" ""
			(at 0 0 0)
			(layer "F.Fab")
			(effects
				(font
					(size 1.27 1.27)
				)
			)
		)
		(duplicate_pad_numbers_are_jumpers no)
		(fp_line
			(start -2.750058 -1.988058)
			(end -2.750058 -0.9398)
			(stroke
				(width 0.1524)
				(type default)
			)
			(layer "F.SilkS")
		)
		(fp_line
			(start -2.750058 0.9398)
			(end -2.750058 1.988058)
			(stroke
				(width 0.1524)
				(type default)
			)
			(layer "F.SilkS")
		)
		(fp_line
			(start -2.750058 1.988058)
			(end -1.988058 2.750058)
			(stroke
				(width 0.1524)
				(type default)
			)
			(layer "F.SilkS")
		)
		(fp_line
			(start -1.988058 -2.750058)
			(end -2.750058 -1.988058)
			(stroke
				(width 0.1524)
				(type default)
			)
			(layer "F.SilkS")
		)
		(fp_line
			(start -1.988058 2.750058)
			(end 2.750058 2.750058)
			(stroke
				(width 0.1524)
				(type default)
			)
			(layer "F.SilkS")
		)
		(fp_line
			(start 2.750058 -2.750058)
			(end -1.988058 -2.750058)
			(stroke
				(width 0.1524)
				(type default)
			)
			(layer "F.SilkS")
		)
		(fp_line
			(start 2.750058 -0.9398)
			(end 2.750058 -2.750058)
			(stroke
				(width 0.1524)
				(type default)
			)
			(layer "F.SilkS")
		)
		(fp_line
			(start 2.750058 2.750058)
			(end 2.750058 0.9398)
			(stroke
				(width 0.1524)
				(type default)
			)
			(layer "F.SilkS")
		)
		(fp_line
			(start -2.750058 -2.750058)
			(end -2.750058 2.750058)
			(stroke
				(width 0.1)
				(type default)
			)
			(layer "F.Fab")
		)
		(fp_line
			(start -2.750058 2.750058)
			(end 2.750058 2.750058)
			(stroke
				(width 0.1)
				(type default)
			)
			(layer "F.Fab")
		)
		(fp_line
			(start 2.750058 -2.750058)
			(end -2.750058 -2.750058)
			(stroke
				(width 0.1)
				(type default)
			)
			(layer "F.Fab")
		)
		(fp_line
			(start 2.750058 2.750058)
			(end 2.750058 -2.750058)
			(stroke
				(width 0.1)
				(type default)
			)
			(layer "F.Fab")
		)
		(pad "1" smd rect
			(at -2.199894 0 90)
			(size 1.6002 3.0226)
			(layers "F.Cu" "F.Mask" "F.Paste")
			(net "P1V25_PEX3_R")
		)
		(pad "2" smd rect
			(at 2.199894 0 90)
			(size 1.6002 3.0226)
			(layers "F.Cu" "F.Mask" "F.Paste")
			(net "GND")
		)
	)
	(footprint ""
		(layer "F.Cu")
		(at 414.371282 -203.962508 -90)
		(property "Reference" "R6439"
			(at 0 0 270)
			(layer "F.SilkS")
			(hide yes)
			(effects
				(font
					(size 1.27 1.27)
				)
			)
		)
		(property "Value" ""
			(at 0 0 270)
			(layer "F.Fab")
			(effects
				(font
					(size 1.27 1.27)
				)
			)
		)
		(duplicate_pad_numbers_are_jumpers no)
		(fp_line
			(start -0.7874 0.4064)
			(end -0.7874 -0.4064)
			(stroke
				(width 0.1524)
				(type default)
			)
			(layer "F.SilkS")
		)
		(fp_line
			(start 0.7874 0.4064)
			(end -0.7874 0.4064)
			(stroke
				(width 0.1524)
				(type default)
			)
			(layer "F.SilkS")
		)
		(fp_line
			(start -0.7874 -0.4064)
			(end 0.7874 -0.4064)
			(stroke
				(width 0.1524)
				(type default)
			)
			(layer "F.SilkS")
		)
		(fp_line
			(start 0.7874 -0.4064)
			(end 0.7874 0.4064)
			(stroke
				(width 0.1524)
				(type default)
			)
			(layer "F.SilkS")
		)
		(fp_line
			(start -0.67945 0.3048)
			(end -0.67945 -0.305054)
			(stroke
				(width 0.1)
				(type default)
			)
			(layer "F.Fab")
		)
		(fp_line
			(start -0.12065 0.3048)
			(end -0.67945 0.3048)
			(stroke
				(width 0.1)
				(type default)
			)
			(layer "F.Fab")
		)
		(fp_line
			(start 0.120396 0.3048)
			(end 0.120396 0.2794)
			(stroke
				(width 0.1)
				(type default)
			)
			(layer "F.Fab")
		)
		(fp_line
			(start 0.67945 0.3048)
			(end 0.120396 0.3048)
			(stroke
				(width 0.1)
				(type default)
			)
			(layer "F.Fab")
		)
		(fp_line
			(start -0.12065 0.2794)
			(end -0.12065 0.3048)
			(stroke
				(width 0.1)
				(type default)
			)
			(layer "F.Fab")
		)
		(fp_line
			(start 0.120396 0.2794)
			(end -0.12065 0.2794)
			(stroke
				(width 0.1)
				(type default)
			)
			(layer "F.Fab")
		)
		(fp_line
			(start -0.12065 -0.2794)
			(end 0.12065 -0.2794)
			(stroke
				(width 0.1)
				(type default)
			)
			(layer "F.Fab")
		)
		(fp_line
			(start 0.12065 -0.2794)
			(end 0.12065 -0.3048)
			(stroke
				(width 0.1)
				(type default)
			)
			(layer "F.Fab")
		)
		(fp_line
			(start 0.12065 -0.3048)
			(end 0.67945 -0.3048)
			(stroke
				(width 0.1)
				(type default)
			)
			(layer "F.Fab")
		)
		(fp_line
			(start 0.67945 -0.3048)
			(end 0.67945 0.3048)
			(stroke
				(width 0.1)
				(type default)
			)
			(layer "F.Fab")
		)
		(fp_line
			(start -0.67945 -0.305054)
			(end -0.12065 -0.305054)
			(stroke
				(width 0.1)
				(type default)
			)
			(layer "F.Fab")
		)
		(fp_line
			(start -0.12065 -0.305054)
			(end -0.12065 -0.2794)
			(stroke
				(width 0.1)
				(type default)
			)
			(layer "F.Fab")
		)
		(pad "1" smd circle
			(at -0.40005 0 270)
			(size 0 0)
			(layers "F.Cu" "F.Mask" "F.Paste")
			(net "FPGA_PEX2_MODE_SEL2_D_N")
		)
		(pad "2" smd circle
			(at 0.40005 0 270)
			(size 0 0)
			(layers "F.Cu" "F.Mask" "F.Paste")
			(net "P3V3_AUX")
		)
	)
	(footprint ""
		(layer "F.Cu")
		(at 244.555264 -113.517426 90)
		(property "Reference" "R6036"
			(at 0 0 90)
			(layer "F.SilkS")
			(hide yes)
			(effects
				(font
					(size 1.27 1.27)
				)
			)
		)
		(property "Value" ""
			(at 0 0 90)
			(layer "F.Fab")
			(effects
				(font
					(size 1.27 1.27)
				)
			)
		)
		(duplicate_pad_numbers_are_jumpers no)
		(fp_line
			(start 0.7874 -0.4064)
			(end 0.7874 0.4064)
			(stroke
				(width 0.1524)
				(type default)
			)
			(layer "F.SilkS")
		)
		(fp_line
			(start -0.7874 -0.4064)
			(end 0.7874 -0.4064)
			(stroke
				(width 0.1524)
				(type default)
			)
			(layer "F.SilkS")
		)
		(fp_line
			(start 0.7874 0.4064)
			(end -0.7874 0.4064)
			(stroke
				(width 0.1524)
				(type default)
			)
			(layer "F.SilkS")
		)
		(fp_line
			(start -0.7874 0.4064)
			(end -0.7874 -0.4064)
			(stroke
				(width 0.1524)
				(type default)
			)
			(layer "F.SilkS")
		)
		(fp_line
			(start -0.12065 -0.305054)
			(end -0.12065 -0.2794)
			(stroke
				(width 0.1)
				(type default)
			)
			(layer "F.Fab")
		)
		(fp_line
			(start -0.67945 -0.305054)
			(end -0.12065 -0.305054)
			(stroke
				(width 0.1)
				(type default)
			)
			(layer "F.Fab")
		)
		(fp_line
			(start 0.67945 -0.3048)
			(end 0.67945 0.3048)
			(stroke
				(width 0.1)
				(type default)
			)
			(layer "F.Fab")
		)
		(fp_line
			(start 0.12065 -0.3048)
			(end 0.67945 -0.3048)
			(stroke
				(width 0.1)
				(type default)
			)
			(layer "F.Fab")
		)
		(fp_line
			(start 0.12065 -0.2794)
			(end 0.12065 -0.3048)
			(stroke
				(width 0.1)
				(type default)
			)
			(layer "F.Fab")
		)
		(fp_line
			(start -0.12065 -0.2794)
			(end 0.12065 -0.2794)
			(stroke
				(width 0.1)
				(type default)
			)
			(layer "F.Fab")
		)
		(fp_line
			(start 0.120396 0.2794)
			(end -0.12065 0.2794)
			(stroke
				(width 0.1)
				(type default)
			)
			(layer "F.Fab")
		)
		(fp_line
			(start -0.12065 0.2794)
			(end -0.12065 0.3048)
			(stroke
				(width 0.1)
				(type default)
			)
			(layer "F.Fab")
		)
		(fp_line
			(start 0.67945 0.3048)
			(end 0.120396 0.3048)
			(stroke
				(width 0.1)
				(type default)
			)
			(layer "F.Fab")
		)
		(fp_line
			(start 0.120396 0.3048)
			(end 0.120396 0.2794)
			(stroke
				(width 0.1)
				(type default)
			)
			(layer "F.Fab")
		)
		(fp_line
			(start -0.12065 0.3048)
			(end -0.67945 0.3048)
			(stroke
				(width 0.1)
				(type default)
			)
			(layer "F.Fab")
		)
		(fp_line
			(start -0.67945 0.3048)
			(end -0.67945 -0.305054)
			(stroke
				(width 0.1)
				(type default)
			)
			(layer "F.Fab")
		)
		(pad "1" smd circle
			(at -0.40005 0 90)
			(size 0 0)
			(layers "F.Cu" "F.Mask" "F.Paste")
			(net "P5V_AUX")
		)
		(pad "2" smd circle
			(at 0.40005 0 90)
			(size 0 0)
			(layers "F.Cu" "F.Mask" "F.Paste")
			(net "P3V3_NIC4_PG_G2")
		)
	)
	(footprint ""
		(layer "F.Cu")
		(at 196.810376 -411.72638 90)
		(property "Reference" "C4479"
			(at 0 0 90)
			(layer "F.SilkS")
			(hide yes)
			(effects
				(font
					(size 1.27 1.27)
				)
			)
		)
		(property "Value" ""
			(at 0 0 90)
			(layer "F.Fab")
			(effects
				(font
					(size 1.27 1.27)
				)
			)
		)
		(duplicate_pad_numbers_are_jumpers no)
		(fp_line
			(start 0.7874 -0.4064)
			(end 0.7874 0.4064)
			(stroke
				(width 0.1524)
				(type default)
			)
			(layer "F.SilkS")
		)
		(fp_line
			(start -0.7874 -0.4064)
			(end 0.7874 -0.4064)
			(stroke
				(width 0.1524)
				(type default)
			)
			(layer "F.SilkS")
		)
		(fp_line
			(start 0.7874 0.4064)
			(end -0.7874 0.4064)
			(stroke
				(width 0.1524)
				(type default)
			)
			(layer "F.SilkS")
		)
		(fp_line
			(start -0.7874 0.4064)
			(end -0.7874 -0.4064)
			(stroke
				(width 0.1524)
				(type default)
			)
			(layer "F.SilkS")
		)
		(fp_line
			(start -0.12065 -0.305054)
			(end -0.12065 -0.2794)
			(stroke
				(width 0.1)
				(type default)
			)
			(layer "F.Fab")
		)
		(fp_line
			(start -0.67945 -0.305054)
			(end -0.12065 -0.305054)
			(stroke
				(width 0.1)
				(type default)
			)
			(layer "F.Fab")
		)
		(fp_line
			(start 0.67945 -0.3048)
			(end 0.67945 0.3048)
			(stroke
				(width 0.1)
				(type default)
			)
			(layer "F.Fab")
		)
		(fp_line
			(start 0.12065 -0.3048)
			(end 0.67945 -0.3048)
			(stroke
				(width 0.1)
				(type default)
			)
			(layer "F.Fab")
		)
		(fp_line
			(start 0.12065 -0.2794)
			(end 0.12065 -0.3048)
			(stroke
				(width 0.1)
				(type default)
			)
			(layer "F.Fab")
		)
		(fp_line
			(start -0.12065 -0.2794)
			(end 0.12065 -0.2794)
			(stroke
				(width 0.1)
				(type default)
			)
			(layer "F.Fab")
		)
		(fp_line
			(start 0.120396 0.2794)
			(end -0.12065 0.2794)
			(stroke
				(width 0.1)
				(type default)
			)
			(layer "F.Fab")
		)
		(fp_line
			(start -0.12065 0.2794)
			(end -0.12065 0.3048)
			(stroke
				(width 0.1)
				(type default)
			)
			(layer "F.Fab")
		)
		(fp_line
			(start 0.67945 0.3048)
			(end 0.120396 0.3048)
			(stroke
				(width 0.1)
				(type default)
			)
			(layer "F.Fab")
		)
		(fp_line
			(start 0.120396 0.3048)
			(end 0.120396 0.2794)
			(stroke
				(width 0.1)
				(type default)
			)
			(layer "F.Fab")
		)
		(fp_line
			(start -0.12065 0.3048)
			(end -0.67945 0.3048)
			(stroke
				(width 0.1)
				(type default)
			)
			(layer "F.Fab")
		)
		(fp_line
			(start -0.67945 0.3048)
			(end -0.67945 -0.305054)
			(stroke
				(width 0.1)
				(type default)
			)
			(layer "F.Fab")
		)
		(pad "1" smd circle
			(at -0.40005 0 90)
			(size 0 0)
			(layers "F.Cu" "F.Mask" "F.Paste")
			(net "P12V_AUX")
		)
		(pad "2" smd circle
			(at 0.40005 0 90)
			(size 0 0)
			(layers "F.Cu" "F.Mask" "F.Paste")
			(net "GND")
		)
	)
	(footprint ""
		(layer "F.Cu")
		(at 150.21052 -63.652146 180)
		(property "Reference" "R5977"
			(at 0 0 180)
			(layer "F.SilkS")
			(hide yes)
			(effects
				(font
					(size 1.27 1.27)
				)
			)
		)
		(property "Value" ""
			(at 0 0 180)
			(layer "F.Fab")
			(effects
				(font
					(size 1.27 1.27)
				)
			)
		)
		(duplicate_pad_numbers_are_jumpers no)
		(fp_line
			(start 0.7874 0.4064)
			(end -0.7874 0.4064)
			(stroke
				(width 0.1524)
				(type default)
			)
			(layer "F.SilkS")
		)
		(fp_line
			(start 0.7874 -0.4064)
			(end 0.7874 0.4064)
			(stroke
				(width 0.1524)
				(type default)
			)
			(layer "F.SilkS")
		)
		(fp_line
			(start -0.7874 0.4064)
			(end -0.7874 -0.4064)
			(stroke
				(width 0.1524)
				(type default)
			)
			(layer "F.SilkS")
		)
		(fp_line
			(start -0.7874 -0.4064)
			(end 0.7874 -0.4064)
			(stroke
				(width 0.1524)
				(type default)
			)
			(layer "F.SilkS")
		)
		(fp_line
			(start 0.67945 0.3048)
			(end 0.120396 0.3048)
			(stroke
				(width 0.1)
				(type default)
			)
			(layer "F.Fab")
		)
		(fp_line
			(start 0.67945 -0.3048)
			(end 0.67945 0.3048)
			(stroke
				(width 0.1)
				(type default)
			)
			(layer "F.Fab")
		)
		(fp_line
			(start 0.12065 -0.2794)
			(end 0.12065 -0.3048)
			(stroke
				(width 0.1)
				(type default)
			)
			(layer "F.Fab")
		)
		(fp_line
			(start 0.12065 -0.3048)
			(end 0.67945 -0.3048)
			(stroke
				(width 0.1)
				(type default)
			)
			(layer "F.Fab")
		)
		(fp_line
			(start 0.120396 0.3048)
			(end 0.120396 0.2794)
			(stroke
				(width 0.1)
				(type default)
			)
			(layer "F.Fab")
		)
		(fp_line
			(start 0.120396 0.2794)
			(end -0.12065 0.2794)
			(stroke
				(width 0.1)
				(type default)
			)
			(layer "F.Fab")
		)
		(fp_line
			(start -0.12065 0.3048)
			(end -0.67945 0.3048)
			(stroke
				(width 0.1)
				(type default)
			)
			(layer "F.Fab")
		)
		(fp_line
			(start -0.12065 0.2794)
			(end -0.12065 0.3048)
			(stroke
				(width 0.1)
				(type default)
			)
			(layer "F.Fab")
		)
		(fp_line
			(start -0.12065 -0.2794)
			(end 0.12065 -0.2794)
			(stroke
				(width 0.1)
				(type default)
			)
			(layer "F.Fab")
		)
		(fp_line
			(start -0.12065 -0.305054)
			(end -0.12065 -0.2794)
			(stroke
				(width 0.1)
				(type default)
			)
			(layer "F.Fab")
		)
		(fp_line
			(start -0.67945 0.3048)
			(end -0.67945 -0.305054)
			(stroke
				(width 0.1)
				(type default)
			)
			(layer "F.Fab")
		)
		(fp_line
			(start -0.67945 -0.305054)
			(end -0.12065 -0.305054)
			(stroke
				(width 0.1)
				(type default)
			)
			(layer "F.Fab")
		)
		(pad "1" smd circle
			(at -0.40005 0 180)
			(size 0 0)
			(layers "F.Cu" "F.Mask" "F.Paste")
			(net "P5V_AUX")
		)
		(pad "2" smd circle
			(at 0.40005 0 180)
			(size 0 0)
			(layers "F.Cu" "F.Mask" "F.Paste")
			(net "P12V_SSD5_PG_G2")
		)
	)
	(footprint ""
		(layer "F.Cu")
		(at 206.297276 -309.0418 135)
		(property "Reference" "R1316"
			(at 0 0 135)
			(layer "F.SilkS")
			(hide yes)
			(effects
				(font
					(size 1.27 1.27)
				)
			)
		)
		(property "Value" ""
			(at 0 0 135)
			(layer "F.Fab")
			(effects
				(font
					(size 1.27 1.27)
				)
			)
		)
		(duplicate_pad_numbers_are_jumpers no)
		(fp_line
			(start 0.787389 -0.406267)
			(end 0.787389 0.406267)
			(stroke
				(width 0.1524)
				(type default)
			)
			(layer "F.SilkS")
		)
		(fp_line
			(start 0.787389 0.406267)
			(end -0.787389 0.406267)
			(stroke
				(width 0.1524)
				(type default)
			)
			(layer "F.SilkS")
		)
		(fp_line
			(start -0.787389 -0.406267)
			(end 0.787389 -0.406267)
			(stroke
				(width 0.1524)
				(type default)
			)
			(layer "F.SilkS")
		)
		(fp_line
			(start -0.787389 0.406267)
			(end -0.787389 -0.406267)
			(stroke
				(width 0.1524)
				(type default)
			)
			(layer "F.SilkS")
		)
		(fp_line
			(start 0.679446 -0.30479)
			(end 0.679446 0.30479)
			(stroke
				(width 0.1)
				(type default)
			)
			(layer "F.Fab")
		)
		(fp_line
			(start 0.120515 -0.30479)
			(end 0.679446 -0.30479)
			(stroke
				(width 0.1)
				(type default)
			)
			(layer "F.Fab")
		)
		(fp_line
			(start 0.120695 -0.279466)
			(end 0.120515 -0.30479)
			(stroke
				(width 0.1)
				(type default)
			)
			(layer "F.Fab")
		)
		(fp_line
			(start 0.679446 0.30479)
			(end 0.120515 0.30479)
			(stroke
				(width 0.1)
				(type default)
			)
			(layer "F.Fab")
		)
		(fp_line
			(start -0.120695 -0.304969)
			(end -0.120695 -0.279466)
			(stroke
				(width 0.1)
				(type default)
			)
			(layer "F.Fab")
		)
		(fp_line
			(start -0.120695 -0.279466)
			(end 0.120695 -0.279466)
			(stroke
				(width 0.1)
				(type default)
			)
			(layer "F.Fab")
		)
		(fp_line
			(start 0.120335 0.279466)
			(end -0.120695 0.279466)
			(stroke
				(width 0.1)
				(type default)
			)
			(layer "F.Fab")
		)
		(fp_line
			(start 0.120515 0.30479)
			(end 0.120335 0.279466)
			(stroke
				(width 0.1)
				(type default)
			)
			(layer "F.Fab")
		)
		(fp_line
			(start -0.679446 -0.305149)
			(end -0.120695 -0.304969)
			(stroke
				(width 0.1)
				(type default)
			)
			(layer "F.Fab")
		)
		(fp_line
			(start -0.120695 0.279466)
			(end -0.120515 0.30479)
			(stroke
				(width 0.1)
				(type default)
			)
			(layer "F.Fab")
		)
		(fp_line
			(start -0.120515 0.30479)
			(end -0.679446 0.30479)
			(stroke
				(width 0.1)
				(type default)
			)
			(layer "F.Fab")
		)
		(fp_line
			(start -0.679446 0.30479)
			(end -0.679446 -0.305149)
			(stroke
				(width 0.1)
				(type default)
			)
			(layer "F.Fab")
		)
		(pad "1" smd circle
			(at -0.40005 0 135)
			(size 0 0)
			(layers "F.Cu" "F.Mask" "F.Paste")
			(net "GND")
		)
		(pad "2" smd circle
			(at 0.40005 0 135)
			(size 0 0)
			(layers "F.Cu" "F.Mask" "F.Paste")
			(net "PEX1_SPARE2")
		)
	)
	(footprint ""
		(layer "F.Cu")
		(at 136.445244 -93.528642 180)
		(property "Reference" "R1586"
			(at 0 0 180)
			(layer "F.SilkS")
			(hide yes)
			(effects
				(font
					(size 1.27 1.27)
				)
			)
		)
		(property "Value" ""
			(at 0 0 180)
			(layer "F.Fab")
			(effects
				(font
					(size 1.27 1.27)
				)
			)
		)
		(duplicate_pad_numbers_are_jumpers no)
		(fp_line
			(start 0.7874 0.4064)
			(end -0.7874 0.4064)
			(stroke
				(width 0.1524)
				(type default)
			)
			(layer "F.SilkS")
		)
		(fp_line
			(start 0.7874 -0.4064)
			(end 0.7874 0.4064)
			(stroke
				(width 0.1524)
				(type default)
			)
			(layer "F.SilkS")
		)
		(fp_line
			(start -0.7874 0.4064)
			(end -0.7874 -0.4064)
			(stroke
				(width 0.1524)
				(type default)
			)
			(layer "F.SilkS")
		)
		(fp_line
			(start -0.7874 -0.4064)
			(end 0.7874 -0.4064)
			(stroke
				(width 0.1524)
				(type default)
			)
			(layer "F.SilkS")
		)
		(fp_line
			(start 0.67945 0.3048)
			(end 0.120396 0.3048)
			(stroke
				(width 0.1)
				(type default)
			)
			(layer "F.Fab")
		)
		(fp_line
			(start 0.67945 -0.3048)
			(end 0.67945 0.3048)
			(stroke
				(width 0.1)
				(type default)
			)
			(layer "F.Fab")
		)
		(fp_line
			(start 0.12065 -0.2794)
			(end 0.12065 -0.3048)
			(stroke
				(width 0.1)
				(type default)
			)
			(layer "F.Fab")
		)
		(fp_line
			(start 0.12065 -0.3048)
			(end 0.67945 -0.3048)
			(stroke
				(width 0.1)
				(type default)
			)
			(layer "F.Fab")
		)
		(fp_line
			(start 0.120396 0.3048)
			(end 0.120396 0.2794)
			(stroke
				(width 0.1)
				(type default)
			)
			(layer "F.Fab")
		)
		(fp_line
			(start 0.120396 0.2794)
			(end -0.12065 0.2794)
			(stroke
				(width 0.1)
				(type default)
			)
			(layer "F.Fab")
		)
		(fp_line
			(start -0.12065 0.3048)
			(end -0.67945 0.3048)
			(stroke
				(width 0.1)
				(type default)
			)
			(layer "F.Fab")
		)
		(fp_line
			(start -0.12065 0.2794)
			(end -0.12065 0.3048)
			(stroke
				(width 0.1)
				(type default)
			)
			(layer "F.Fab")
		)
		(fp_line
			(start -0.12065 -0.2794)
			(end 0.12065 -0.2794)
			(stroke
				(width 0.1)
				(type default)
			)
			(layer "F.Fab")
		)
		(fp_line
			(start -0.12065 -0.305054)
			(end -0.12065 -0.2794)
			(stroke
				(width 0.1)
				(type default)
			)
			(layer "F.Fab")
		)
		(fp_line
			(start -0.67945 0.3048)
			(end -0.67945 -0.305054)
			(stroke
				(width 0.1)
				(type default)
			)
			(layer "F.Fab")
		)
		(fp_line
			(start -0.67945 -0.305054)
			(end -0.12065 -0.305054)
			(stroke
				(width 0.1)
				(type default)
			)
			(layer "F.Fab")
		)
		(pad "1" smd circle
			(at -0.40005 0 180)
			(size 0 0)
			(layers "F.Cu" "F.Mask" "F.Paste")
			(net "SMB_BIC_I2C9_MUX0_SSD6_R_SCL")
		)
		(pad "2" smd circle
			(at 0.40005 0 180)
			(size 0 0)
			(layers "F.Cu" "F.Mask" "F.Paste")
			(net "SMB_BIC_I2C9_MUX0_SSD6_SCL")
		)
	)
	(footprint ""
		(layer "F.Cu")
		(at 153.347928 -102.009702)
		(property "Reference" "C273"
			(at 0 0 0)
			(layer "F.SilkS")
			(hide yes)
			(effects
				(font
					(size 1.27 1.27)
				)
			)
		)
		(property "Value" ""
			(at 0 0 0)
			(layer "F.Fab")
			(effects
				(font
					(size 1.27 1.27)
				)
			)
		)
		(duplicate_pad_numbers_are_jumpers no)
		(fp_line
			(start -0.299974 -0.150114)
			(end 0.299974 -0.150114)
			(stroke
				(width 0.1)
				(type default)
			)
			(layer "F.Fab")
		)
		(fp_line
			(start -0.299974 0.150114)
			(end -0.299974 -0.150114)
			(stroke
				(width 0.1)
				(type default)
			)
			(layer "F.Fab")
		)
		(fp_line
			(start 0.299974 -0.150114)
			(end 0.299974 0.150114)
			(stroke
				(width 0.1)
				(type default)
			)
			(layer "F.Fab")
		)
		(fp_line
			(start 0.299974 0.150114)
			(end -0.299974 0.150114)
			(stroke
				(width 0.1)
				(type default)
			)
			(layer "F.Fab")
		)
		(pad "1" smd rect
			(at -0.2667 0)
			(size 0.3048 0.381)
			(layers "F.Cu" "F.Mask" "F.Paste")
			(net "P5E_PEX1_STN1_TX_DP<17>")
		)
		(pad "2" smd rect
			(at 0.2667 0)
			(size 0.3048 0.381)
			(layers "F.Cu" "F.Mask" "F.Paste")
			(net "P5E_PEX1_STN1_TX_C_DP<17>")
		)
	)
	(footprint ""
		(layer "F.Cu")
		(at 322.13296 -311.946544 135)
		(property "Reference" "R1369"
			(at 0 0 135)
			(layer "F.SilkS")
			(hide yes)
			(effects
				(font
					(size 1.27 1.27)
				)
			)
		)
		(property "Value" ""
			(at 0 0 135)
			(layer "F.Fab")
			(effects
				(font
					(size 1.27 1.27)
				)
			)
		)
		(duplicate_pad_numbers_are_jumpers no)
		(fp_line
			(start 0.787389 -0.406267)
			(end 0.787389 0.406267)
			(stroke
				(width 0.1524)
				(type default)
			)
			(layer "F.SilkS")
		)
		(fp_line
			(start 0.787389 0.406267)
			(end -0.787389 0.406267)
			(stroke
				(width 0.1524)
				(type default)
			)
			(layer "F.SilkS")
		)
		(fp_line
			(start -0.787389 -0.406267)
			(end 0.787389 -0.406267)
			(stroke
				(width 0.1524)
				(type default)
			)
			(layer "F.SilkS")
		)
		(fp_line
			(start -0.787389 0.406267)
			(end -0.787389 -0.406267)
			(stroke
				(width 0.1524)
				(type default)
			)
			(layer "F.SilkS")
		)
		(fp_line
			(start 0.679446 -0.30479)
			(end 0.679446 0.30479)
			(stroke
				(width 0.1)
				(type default)
			)
			(layer "F.Fab")
		)
		(fp_line
			(start 0.120515 -0.30479)
			(end 0.679446 -0.30479)
			(stroke
				(width 0.1)
				(type default)
			)
			(layer "F.Fab")
		)
		(fp_line
			(start 0.120695 -0.279466)
			(end 0.120515 -0.30479)
			(stroke
				(width 0.1)
				(type default)
			)
			(layer "F.Fab")
		)
		(fp_line
			(start 0.679446 0.30479)
			(end 0.120515 0.30479)
			(stroke
				(width 0.1)
				(type default)
			)
			(layer "F.Fab")
		)
		(fp_line
			(start -0.120695 -0.304969)
			(end -0.120695 -0.279466)
			(stroke
				(width 0.1)
				(type default)
			)
			(layer "F.Fab")
		)
		(fp_line
			(start -0.120695 -0.279466)
			(end 0.120695 -0.279466)
			(stroke
				(width 0.1)
				(type default)
			)
			(layer "F.Fab")
		)
		(fp_line
			(start 0.120335 0.279466)
			(end -0.120695 0.279466)
			(stroke
				(width 0.1)
				(type default)
			)
			(layer "F.Fab")
		)
		(fp_line
			(start 0.120515 0.30479)
			(end 0.120335 0.279466)
			(stroke
				(width 0.1)
				(type default)
			)
			(layer "F.Fab")
		)
		(fp_line
			(start -0.679446 -0.305149)
			(end -0.120695 -0.304969)
			(stroke
				(width 0.1)
				(type default)
			)
			(layer "F.Fab")
		)
		(fp_line
			(start -0.120695 0.279466)
			(end -0.120515 0.30479)
			(stroke
				(width 0.1)
				(type default)
			)
			(layer "F.Fab")
		)
		(fp_line
			(start -0.120515 0.30479)
			(end -0.679446 0.30479)
			(stroke
				(width 0.1)
				(type default)
			)
			(layer "F.Fab")
		)
		(fp_line
			(start -0.679446 0.30479)
			(end -0.679446 -0.305149)
			(stroke
				(width 0.1)
				(type default)
			)
			(layer "F.Fab")
		)
		(pad "1" smd circle
			(at -0.40005 0 135)
			(size 0 0)
			(layers "F.Cu" "F.Mask" "F.Paste")
			(net "PEX2_SPARE5")
		)
		(pad "2" smd circle
			(at 0.40005 0 135)
			(size 0 0)
			(layers "F.Cu" "F.Mask" "F.Paste")
			(net "P1V8_PEX")
		)
	)
	(footprint ""
		(layer "F.Cu")
		(at 268.53515 -81.087722 180)
		(property "Reference" "R1074"
			(at 0 0 180)
			(layer "F.SilkS")
			(hide yes)
			(effects
				(font
					(size 1.27 1.27)
				)
			)
		)
		(property "Value" ""
			(at 0 0 180)
			(layer "F.Fab")
			(effects
				(font
					(size 1.27 1.27)
				)
			)
		)
		(duplicate_pad_numbers_are_jumpers no)
		(fp_line
			(start -0.7874 -0.4064)
			(end 0.7874 -0.4064)
			(stroke
				(width 0.1524)
				(type default)
			)
			(layer "F.SilkS")
		)
		(fp_line
			(start 0.67945 0.3048)
			(end 0.120396 0.3048)
			(stroke
				(width 0.1)
				(type default)
			)
			(layer "F.Fab")
		)
		(fp_line
			(start 0.67945 -0.3048)
			(end 0.67945 0.3048)
			(stroke
				(width 0.1)
				(type default)
			)
			(layer "F.Fab")
		)
		(fp_line
			(start 0.12065 -0.2794)
			(end 0.12065 -0.3048)
			(stroke
				(width 0.1)
				(type default)
			)
			(layer "F.Fab")
		)
		(fp_line
			(start 0.12065 -0.3048)
			(end 0.67945 -0.3048)
			(stroke
				(width 0.1)
				(type default)
			)
			(layer "F.Fab")
		)
		(fp_line
			(start 0.120396 0.3048)
			(end 0.120396 0.2794)
			(stroke
				(width 0.1)
				(type default)
			)
			(layer "F.Fab")
		)
		(fp_line
			(start 0.120396 0.2794)
			(end -0.12065 0.2794)
			(stroke
				(width 0.1)
				(type default)
			)
			(layer "F.Fab")
		)
		(fp_line
			(start -0.12065 0.3048)
			(end -0.67945 0.3048)
			(stroke
				(width 0.1)
				(type default)
			)
			(layer "F.Fab")
		)
		(fp_line
			(start -0.12065 0.2794)
			(end -0.12065 0.3048)
			(stroke
				(width 0.1)
				(type default)
			)
			(layer "F.Fab")
		)
		(fp_line
			(start -0.12065 -0.2794)
			(end 0.12065 -0.2794)
			(stroke
				(width 0.1)
				(type default)
			)
			(layer "F.Fab")
		)
		(fp_line
			(start -0.12065 -0.305054)
			(end -0.12065 -0.2794)
			(stroke
				(width 0.1)
				(type default)
			)
			(layer "F.Fab")
		)
		(fp_line
			(start -0.67945 0.3048)
			(end -0.67945 -0.305054)
			(stroke
				(width 0.1)
				(type default)
			)
			(layer "F.Fab")
		)
		(fp_line
			(start -0.67945 -0.305054)
			(end -0.12065 -0.305054)
			(stroke
				(width 0.1)
				(type default)
			)
			(layer "F.Fab")
		)
		(pad "1" smd circle
			(at -0.40005 0 180)
			(size 0 0)
			(layers "F.Cu" "F.Mask" "F.Paste")
			(net "CLK_100M_CK440Q_1_DB800ZL_R_DN")
		)
		(pad "2" smd circle
			(at 0.40005 0 180)
			(size 0 0)
			(layers "F.Cu" "F.Mask" "F.Paste")
			(net "CLK_100M_CK440Q_1_DB800ZL_DN")
		)
	)
	(footprint ""
		(layer "F.Cu")
		(at 346.332302 -284.8991 180)
		(property "Reference" "PU13"
			(at -22.780498 -2.637536 90)
			(unlocked yes)
			(layer "F.SilkS")
			(effects
				(font
					(size 0.7874 0.5842)
					(thickness 0.1524)
				)
				(justify left)
			)
		)
		(property "Value" ""
			(at 0 0 180)
			(layer "F.Fab")
			(effects
				(font
					(size 1.27 1.27)
				)
			)
		)
		(duplicate_pad_numbers_are_jumpers no)
		(fp_line
			(start 2.500122 2.999994)
			(end 2.2987 2.999994)
			(stroke
				(width 0.1524)
				(type default)
			)
			(layer "F.SilkS")
		)
		(fp_line
			(start 2.500122 2.339594)
			(end 2.500122 2.999994)
			(stroke
				(width 0.1524)
				(type default)
			)
			(layer "F.SilkS")
		)
		(fp_line
			(start 2.500122 -2.999994)
			(end 2.500122 -2.44348)
			(stroke
				(width 0.1524)
				(type default)
			)
			(layer "F.SilkS")
		)
		(fp_line
			(start 2.31394 -2.999994)
			(end 2.500122 -2.999994)
			(stroke
				(width 0.1524)
				(type default)
			)
			(layer "F.SilkS")
		)
		(fp_line
			(start -2.2987 2.999994)
			(end -2.500122 2.999994)
			(stroke
				(width 0.1524)
				(type default)
			)
			(layer "F.SilkS")
		)
		(fp_line
			(start -2.500122 2.999994)
			(end -2.500122 2.339594)
			(stroke
				(width 0.1524)
				(type default)
			)
			(layer "F.SilkS")
		)
		(fp_line
			(start -2.500122 0.6604)
			(end -2.500122 0.229108)
			(stroke
				(width 0.1524)
				(type default)
			)
			(layer "F.SilkS")
		)
		(fp_line
			(start -2.500122 -2.529078)
			(end -2.500122 -2.999994)
			(stroke
				(width 0.1524)
				(type default)
			)
			(layer "F.SilkS")
		)
		(fp_line
			(start -2.500122 -2.999994)
			(end -2.24409 -2.999994)
			(stroke
				(width 0.1524)
				(type default)
			)
			(layer "F.SilkS")
		)
		(fp_poly
			(pts
				(xy -3.899916 -4.357116) (xy -4.618482 -3.63855) (xy -3.54076 -3.279394)
			)
			(stroke
				(width 0)
				(type default)
			)
			(fill yes)
			(layer "F.SilkS")
		)
		(fp_line
			(start 2.500122 2.999994)
			(end -2.500122 2.999994)
			(stroke
				(width 0.1)
				(type default)
			)
			(layer "F.Fab")
		)
		(fp_line
			(start 2.500122 -2.999994)
			(end 2.500122 2.999994)
			(stroke
				(width 0.1)
				(type default)
			)
			(layer "F.Fab")
		)
		(fp_line
			(start -2.500122 2.999994)
			(end -2.500122 -2.999994)
			(stroke
				(width 0.1)
				(type default)
			)
			(layer "F.Fab")
		)
		(fp_line
			(start -2.500122 -2.999994)
			(end 2.500122 -2.999994)
			(stroke
				(width 0.1)
				(type default)
			)
			(layer "F.Fab")
		)
		(fp_poly
			(pts
				(xy -4.218432 -2.783078) (xy -4.218432 -1.767078) (xy -3.202432 -2.275078)
			)
			(stroke
				(width 0)
				(type default)
			)
			(fill yes)
			(layer "F.Fab")
		)
		(pad "1" smd rect
			(at -2.400046 -2.275078 270)
			(size 0.2286 0.6096)
			(layers "F.Cu" "F.Mask" "F.Paste")
			(net "SW_P0V8_PEX2_VOS2")
		)
		(pad "2" smd rect
			(at -2.400046 -1.82499 270)
			(size 0.2286 0.6096)
			(layers "F.Cu" "F.Mask" "F.Paste")
			(net "GND")
		)
		(pad "3" smd rect
			(at -2.400046 -1.374902 270)
			(size 0.2286 0.6096)
			(layers "F.Cu" "F.Mask" "F.Paste")
			(net "P0V8_PEX2_VCC2")
		)
		(pad "4" smd rect
			(at -2.400046 -0.925068 270)
			(size 0.2286 0.6096)
			(layers "F.Cu" "F.Mask" "F.Paste")
			(net "P0V8_PEX2_PVCC")
		)
		(pad "5" smd rect
			(at -2.400046 -0.47498 270)
			(size 0.2286 0.6096)
			(layers "F.Cu" "F.Mask" "F.Paste")
			(net "GND")
		)
		(pad "6" smd rect
			(at -2.400046 -0.024892 270)
			(size 0.2286 0.6096)
			(layers "F.Cu" "F.Mask" "F.Paste")
			(net "NC_P0V8_PEX2_PH2_NC1")
		)
		(pad "7_9-20_24" smd circle
			(at 0 1.150112 270)
			(size 0 0)
			(layers "F.Cu" "F.Mask" "F.Paste")
			(net "GND")
		)
		(pad "10_19" smd rect
			(at 0 2.899918 270)
			(size 0.6096 4.318)
			(layers "F.Cu" "F.Mask" "F.Paste")
			(net "SW_P0V8_PEX2_PH2")
		)
		(pad "25_29" smd rect
			(at 1.549908 -1.279906 90)
			(size 2.0574 2.3114)
			(layers "F.Cu" "F.Mask" "F.Paste")
			(net "SW_P12V_P0V8_PEX2_FLT")
		)
		(pad "30" smd rect
			(at 2.05994 -2.899918 180)
			(size 0.2286 0.6096)
			(layers "F.Cu" "F.Mask" "F.Paste")
			(net "SW_P12V_P0V8_PEX2_FLT")
		)
		(pad "31" smd rect
			(at 1.610106 -2.899918 180)
			(size 0.2286 0.6096)
			(layers "F.Cu" "F.Mask" "F.Paste")
			(net "NC_P0V8_PEX2_PH2_NC3")
		)
		(pad "32" smd rect
			(at 1.160018 -2.899918 180)
			(size 0.2286 0.6096)
			(layers "F.Cu" "F.Mask" "F.Paste")
			(net "SW_P0V8_PEX2_PHASE2")
		)
		(pad "33" smd rect
			(at 0.70993 -2.899918 180)
			(size 0.2286 0.6096)
			(layers "F.Cu" "F.Mask" "F.Paste")
			(net "SW_P0V8_PEX2_BOOT2")
		)
		(pad "34" smd rect
			(at 0.260096 -2.899918 180)
			(size 0.2286 0.6096)
			(layers "F.Cu" "F.Mask" "F.Paste")
			(net "P0V8_PEX2_PWM2")
		)
		(pad "35" smd rect
			(at -0.189992 -2.899918 180)
			(size 0.2286 0.6096)
			(layers "F.Cu" "F.Mask" "F.Paste")
			(net "P0V8_PEX2_EN2")
		)
		(pad "36" smd rect
			(at -0.64008 -2.899918 180)
			(size 0.2286 0.6096)
			(layers "F.Cu" "F.Mask" "F.Paste")
			(net "P0V8_PEX2_TSEN")
		)
		(pad "37" smd rect
			(at -1.089914 -2.899918 180)
			(size 0.2286 0.6096)
			(layers "F.Cu" "F.Mask" "F.Paste")
			(net "P0V8_PEX2_LSET2")
		)
		(pad "38" smd rect
			(at -1.540002 -2.899918 180)
			(size 0.2286 0.6096)
			(layers "F.Cu" "F.Mask" "F.Paste")
			(net "P0V8_PEX2_ISEN2")
		)
		(pad "39" smd rect
			(at -1.99009 -2.899918 180)
			(size 0.2286 0.6096)
			(layers "F.Cu" "F.Mask" "F.Paste")
			(net "P0V8_PEX2_VREF")
		)
		(pad "40" smd rect
			(at -0.87503 -1.27508 180)
			(size 1.7526 1.9558)
			(layers "F.Cu" "F.Mask" "F.Paste")
			(net "GND")
		)
		(pad "41" smd rect
			(at -1.525016 0.249936 90)
			(size 0.3048 0.4572)
			(layers "F.Cu" "F.Mask" "F.Paste")
			(net "NC_P0V8_PEX2_PH2_NC2")
		)
		(zone
			(layer "F.Cu")
			(hatch none 0.5)
			(connect_pads
				(clearance 0)
			)
			(min_thickness 0.25)
			(keepout
				(tracks not_allowed)
				(vias allowed)
				(pads allowed)
				(copperpour not_allowed)
				(footprints allowed)
			)
			(placement
				(enabled no)
				(sheetname "")
			)
			(fill
				(thermal_gap 0.5)
				(thermal_bridge_width 0.5)
				(island_removal_mode 0)
			)
			(polygon
				(pts
					(xy 348.832424 -287.899094) (xy 348.832424 -287.149794) (xy 343.83218 -287.149794) (xy 343.83218 -287.899094)
					(xy 344.122502 -287.899094) (xy 344.122502 -287.443418) (xy 348.542102 -287.443418) (xy 348.542102 -287.899094)
				)
			)
		)
	)
	(footprint ""
		(layer "F.Cu")
		(at 458.101446 -250.20524 180)
		(property "Reference" "R6588"
			(at 0 0 180)
			(layer "F.SilkS")
			(hide yes)
			(effects
				(font
					(size 1.27 1.27)
				)
			)
		)
		(property "Value" ""
			(at 0 0 180)
			(layer "F.Fab")
			(effects
				(font
					(size 1.27 1.27)
				)
			)
		)
		(duplicate_pad_numbers_are_jumpers no)
		(fp_line
			(start 0.7874 0.4064)
			(end -0.7874 0.4064)
			(stroke
				(width 0.1524)
				(type default)
			)
			(layer "F.SilkS")
		)
		(fp_line
			(start 0.7874 -0.4064)
			(end 0.7874 0.4064)
			(stroke
				(width 0.1524)
				(type default)
			)
			(layer "F.SilkS")
		)
		(fp_line
			(start -0.7874 0.4064)
			(end -0.7874 -0.4064)
			(stroke
				(width 0.1524)
				(type default)
			)
			(layer "F.SilkS")
		)
		(fp_line
			(start -0.7874 -0.4064)
			(end 0.7874 -0.4064)
			(stroke
				(width 0.1524)
				(type default)
			)
			(layer "F.SilkS")
		)
		(fp_line
			(start 0.67945 0.3048)
			(end 0.120396 0.3048)
			(stroke
				(width 0.1)
				(type default)
			)
			(layer "F.Fab")
		)
		(fp_line
			(start 0.67945 -0.3048)
			(end 0.67945 0.3048)
			(stroke
				(width 0.1)
				(type default)
			)
			(layer "F.Fab")
		)
		(fp_line
			(start 0.12065 -0.2794)
			(end 0.12065 -0.3048)
			(stroke
				(width 0.1)
				(type default)
			)
			(layer "F.Fab")
		)
		(fp_line
			(start 0.12065 -0.3048)
			(end 0.67945 -0.3048)
			(stroke
				(width 0.1)
				(type default)
			)
			(layer "F.Fab")
		)
		(fp_line
			(start 0.120396 0.3048)
			(end 0.120396 0.2794)
			(stroke
				(width 0.1)
				(type default)
			)
			(layer "F.Fab")
		)
		(fp_line
			(start 0.120396 0.2794)
			(end -0.12065 0.2794)
			(stroke
				(width 0.1)
				(type default)
			)
			(layer "F.Fab")
		)
		(fp_line
			(start -0.12065 0.3048)
			(end -0.67945 0.3048)
			(stroke
				(width 0.1)
				(type default)
			)
			(layer "F.Fab")
		)
		(fp_line
			(start -0.12065 0.2794)
			(end -0.12065 0.3048)
			(stroke
				(width 0.1)
				(type default)
			)
			(layer "F.Fab")
		)
		(fp_line
			(start -0.12065 -0.2794)
			(end 0.12065 -0.2794)
			(stroke
				(width 0.1)
				(type default)
			)
			(layer "F.Fab")
		)
		(fp_line
			(start -0.12065 -0.305054)
			(end -0.12065 -0.2794)
			(stroke
				(width 0.1)
				(type default)
			)
			(layer "F.Fab")
		)
		(fp_line
			(start -0.67945 0.3048)
			(end -0.67945 -0.305054)
			(stroke
				(width 0.1)
				(type default)
			)
			(layer "F.Fab")
		)
		(fp_line
			(start -0.67945 -0.305054)
			(end -0.12065 -0.305054)
			(stroke
				(width 0.1)
				(type default)
			)
			(layer "F.Fab")
		)
		(pad "1" smd circle
			(at -0.40005 0 180)
			(size 0 0)
			(layers "F.Cu" "F.Mask" "F.Paste")
			(net "PWRGD_PEX3_P1V8_PLL_R")
		)
		(pad "2" smd circle
			(at 0.40005 0 180)
			(size 0 0)
			(layers "F.Cu" "F.Mask" "F.Paste")
			(net "PWRGD_PEX3_P1V8_PLL")
		)
	)
	(footprint ""
		(layer "F.Cu")
		(at 129.13487 -279.101804)
		(property "Reference" "PC108"
			(at 0 0 0)
			(layer "F.SilkS")
			(hide yes)
			(effects
				(font
					(size 1.27 1.27)
				)
			)
		)
		(property "Value" ""
			(at 0 0 0)
			(layer "F.Fab")
			(effects
				(font
					(size 1.27 1.27)
				)
			)
		)
		(duplicate_pad_numbers_are_jumpers no)
		(fp_line
			(start -0.7874 -0.4064)
			(end 0.7874 -0.4064)
			(stroke
				(width 0.1524)
				(type default)
			)
			(layer "F.SilkS")
		)
		(fp_line
			(start -0.7874 0.4064)
			(end -0.7874 -0.4064)
			(stroke
				(width 0.1524)
				(type default)
			)
			(layer "F.SilkS")
		)
		(fp_line
			(start 0.7874 -0.4064)
			(end 0.7874 0.4064)
			(stroke
				(width 0.1524)
				(type default)
			)
			(layer "F.SilkS")
		)
		(fp_line
			(start 0.7874 0.4064)
			(end -0.7874 0.4064)
			(stroke
				(width 0.1524)
				(type default)
			)
			(layer "F.SilkS")
		)
		(fp_line
			(start -0.67945 -0.305054)
			(end -0.12065 -0.305054)
			(stroke
				(width 0.1)
				(type default)
			)
			(layer "F.Fab")
		)
		(fp_line
			(start -0.67945 0.3048)
			(end -0.67945 -0.305054)
			(stroke
				(width 0.1)
				(type default)
			)
			(layer "F.Fab")
		)
		(fp_line
			(start -0.12065 -0.305054)
			(end -0.12065 -0.2794)
			(stroke
				(width 0.1)
				(type default)
			)
			(layer "F.Fab")
		)
		(fp_line
			(start -0.12065 -0.2794)
			(end 0.12065 -0.2794)
			(stroke
				(width 0.1)
				(type default)
			)
			(layer "F.Fab")
		)
		(fp_line
			(start -0.12065 0.2794)
			(end -0.12065 0.3048)
			(stroke
				(width 0.1)
				(type default)
			)
			(layer "F.Fab")
		)
		(fp_line
			(start -0.12065 0.3048)
			(end -0.67945 0.3048)
			(stroke
				(width 0.1)
				(type default)
			)
			(layer "F.Fab")
		)
		(fp_line
			(start 0.120396 0.2794)
			(end -0.12065 0.2794)
			(stroke
				(width 0.1)
				(type default)
			)
			(layer "F.Fab")
		)
		(fp_line
			(start 0.120396 0.3048)
			(end 0.120396 0.2794)
			(stroke
				(width 0.1)
				(type default)
			)
			(layer "F.Fab")
		)
		(fp_line
			(start 0.12065 -0.3048)
			(end 0.67945 -0.3048)
			(stroke
				(width 0.1)
				(type default)
			)
			(layer "F.Fab")
		)
		(fp_line
			(start 0.12065 -0.2794)
			(end 0.12065 -0.3048)
			(stroke
				(width 0.1)
				(type default)
			)
			(layer "F.Fab")
		)
		(fp_line
			(start 0.67945 -0.3048)
			(end 0.67945 0.3048)
			(stroke
				(width 0.1)
				(type default)
			)
			(layer "F.Fab")
		)
		(fp_line
			(start 0.67945 0.3048)
			(end 0.120396 0.3048)
			(stroke
				(width 0.1)
				(type default)
			)
			(layer "F.Fab")
		)
		(pad "1" smd circle
			(at -0.40005 0)
			(size 0 0)
			(layers "F.Cu" "F.Mask" "F.Paste")
			(net "SW_P12V_P0V8_PEX1_FLT")
		)
		(pad "2" smd circle
			(at 0.40005 0)
			(size 0 0)
			(layers "F.Cu" "F.Mask" "F.Paste")
			(net "GND")
		)
	)
	(footprint ""
		(layer "F.Cu")
		(at 427.923452 -350.098614 90)
		(property "Reference" "C2457"
			(at 0 0 90)
			(layer "F.SilkS")
			(hide yes)
			(effects
				(font
					(size 1.27 1.27)
				)
			)
		)
		(property "Value" ""
			(at 0 0 90)
			(layer "F.Fab")
			(effects
				(font
					(size 1.27 1.27)
				)
			)
		)
		(duplicate_pad_numbers_are_jumpers no)
		(fp_line
			(start 0.299974 -0.150114)
			(end 0.299974 0.150114)
			(stroke
				(width 0.1)
				(type default)
			)
			(layer "F.Fab")
		)
		(fp_line
			(start -0.299974 -0.150114)
			(end 0.299974 -0.150114)
			(stroke
				(width 0.1)
				(type default)
			)
			(layer "F.Fab")
		)
		(fp_line
			(start 0.299974 0.150114)
			(end -0.299974 0.150114)
			(stroke
				(width 0.1)
				(type default)
			)
			(layer "F.Fab")
		)
		(fp_line
			(start -0.299974 0.150114)
			(end -0.299974 -0.150114)
			(stroke
				(width 0.1)
				(type default)
			)
			(layer "F.Fab")
		)
		(pad "1" smd rect
			(at -0.2667 0 90)
			(size 0.3048 0.381)
			(layers "F.Cu" "F.Mask" "F.Paste")
			(net "P5E_PEX3_STN4_TX_DP<70>")
		)
		(pad "2" smd rect
			(at 0.2667 0 90)
			(size 0.3048 0.381)
			(layers "F.Cu" "F.Mask" "F.Paste")
			(net "P5E_PEX3_STN4_TX_C_DP<70>")
		)
	)
	(footprint ""
		(layer "F.Cu")
		(at 5.684774 -393.744958 -90)
		(property "Reference" "R6753"
			(at 0 0 270)
			(layer "F.SilkS")
			(hide yes)
			(effects
				(font
					(size 1.27 1.27)
				)
			)
		)
		(property "Value" ""
			(at 0 0 270)
			(layer "F.Fab")
			(effects
				(font
					(size 1.27 1.27)
				)
			)
		)
		(duplicate_pad_numbers_are_jumpers no)
		(fp_line
			(start -0.7874 0.4064)
			(end -0.7874 -0.4064)
			(stroke
				(width 0.1524)
				(type default)
			)
			(layer "F.SilkS")
		)
		(fp_line
			(start 0.7874 0.4064)
			(end -0.7874 0.4064)
			(stroke
				(width 0.1524)
				(type default)
			)
			(layer "F.SilkS")
		)
		(fp_line
			(start -0.7874 -0.4064)
			(end 0.7874 -0.4064)
			(stroke
				(width 0.1524)
				(type default)
			)
			(layer "F.SilkS")
		)
		(fp_line
			(start 0.7874 -0.4064)
			(end 0.7874 0.4064)
			(stroke
				(width 0.1524)
				(type default)
			)
			(layer "F.SilkS")
		)
		(fp_line
			(start -0.67945 0.3048)
			(end -0.67945 -0.305054)
			(stroke
				(width 0.1)
				(type default)
			)
			(layer "F.Fab")
		)
		(fp_line
			(start -0.12065 0.3048)
			(end -0.67945 0.3048)
			(stroke
				(width 0.1)
				(type default)
			)
			(layer "F.Fab")
		)
		(fp_line
			(start 0.120396 0.3048)
			(end 0.120396 0.2794)
			(stroke
				(width 0.1)
				(type default)
			)
			(layer "F.Fab")
		)
		(fp_line
			(start 0.67945 0.3048)
			(end 0.120396 0.3048)
			(stroke
				(width 0.1)
				(type default)
			)
			(layer "F.Fab")
		)
		(fp_line
			(start -0.12065 0.2794)
			(end -0.12065 0.3048)
			(stroke
				(width 0.1)
				(type default)
			)
			(layer "F.Fab")
		)
		(fp_line
			(start 0.120396 0.2794)
			(end -0.12065 0.2794)
			(stroke
				(width 0.1)
				(type default)
			)
			(layer "F.Fab")
		)
		(fp_line
			(start -0.12065 -0.2794)
			(end 0.12065 -0.2794)
			(stroke
				(width 0.1)
				(type default)
			)
			(layer "F.Fab")
		)
		(fp_line
			(start 0.12065 -0.2794)
			(end 0.12065 -0.3048)
			(stroke
				(width 0.1)
				(type default)
			)
			(layer "F.Fab")
		)
		(fp_line
			(start 0.12065 -0.3048)
			(end 0.67945 -0.3048)
			(stroke
				(width 0.1)
				(type default)
			)
			(layer "F.Fab")
		)
		(fp_line
			(start 0.67945 -0.3048)
			(end 0.67945 0.3048)
			(stroke
				(width 0.1)
				(type default)
			)
			(layer "F.Fab")
		)
		(fp_line
			(start -0.67945 -0.305054)
			(end -0.12065 -0.305054)
			(stroke
				(width 0.1)
				(type default)
			)
			(layer "F.Fab")
		)
		(fp_line
			(start -0.12065 -0.305054)
			(end -0.12065 -0.2794)
			(stroke
				(width 0.1)
				(type default)
			)
			(layer "F.Fab")
		)
		(pad "1" smd circle
			(at -0.40005 0 270)
			(size 0 0)
			(layers "F.Cu" "F.Mask" "F.Paste")
			(net "P5V_AUX")
		)
		(pad "2" smd circle
			(at 0.40005 0 270)
			(size 0 0)
			(layers "F.Cu" "F.Mask" "F.Paste")
			(net "BIC_USB_8042_HUB_VBUS")
		)
	)
	(footprint ""
		(layer "F.Cu")
		(at 242.025932 -280.10104 180)
		(property "Reference" "C628"
			(at 0 0 180)
			(layer "F.SilkS")
			(hide yes)
			(effects
				(font
					(size 1.27 1.27)
				)
			)
		)
		(property "Value" ""
			(at 0 0 180)
			(layer "F.Fab")
			(effects
				(font
					(size 1.27 1.27)
				)
			)
		)
		(duplicate_pad_numbers_are_jumpers no)
		(fp_line
			(start 0.7874 0.4064)
			(end -0.7874 0.4064)
			(stroke
				(width 0.1524)
				(type default)
			)
			(layer "F.SilkS")
		)
		(fp_line
			(start 0.7874 -0.4064)
			(end 0.7874 0.4064)
			(stroke
				(width 0.1524)
				(type default)
			)
			(layer "F.SilkS")
		)
		(fp_line
			(start -0.7874 0.4064)
			(end -0.7874 -0.4064)
			(stroke
				(width 0.1524)
				(type default)
			)
			(layer "F.SilkS")
		)
		(fp_line
			(start -0.7874 -0.4064)
			(end 0.7874 -0.4064)
			(stroke
				(width 0.1524)
				(type default)
			)
			(layer "F.SilkS")
		)
		(fp_line
			(start 0.67945 0.3048)
			(end 0.120396 0.3048)
			(stroke
				(width 0.1)
				(type default)
			)
			(layer "F.Fab")
		)
		(fp_line
			(start 0.67945 -0.3048)
			(end 0.67945 0.3048)
			(stroke
				(width 0.1)
				(type default)
			)
			(layer "F.Fab")
		)
		(fp_line
			(start 0.12065 -0.2794)
			(end 0.12065 -0.3048)
			(stroke
				(width 0.1)
				(type default)
			)
			(layer "F.Fab")
		)
		(fp_line
			(start 0.12065 -0.3048)
			(end 0.67945 -0.3048)
			(stroke
				(width 0.1)
				(type default)
			)
			(layer "F.Fab")
		)
		(fp_line
			(start 0.120396 0.3048)
			(end 0.120396 0.2794)
			(stroke
				(width 0.1)
				(type default)
			)
			(layer "F.Fab")
		)
		(fp_line
			(start 0.120396 0.2794)
			(end -0.12065 0.2794)
			(stroke
				(width 0.1)
				(type default)
			)
			(layer "F.Fab")
		)
		(fp_line
			(start -0.12065 0.3048)
			(end -0.67945 0.3048)
			(stroke
				(width 0.1)
				(type default)
			)
			(layer "F.Fab")
		)
		(fp_line
			(start -0.12065 0.2794)
			(end -0.12065 0.3048)
			(stroke
				(width 0.1)
				(type default)
			)
			(layer "F.Fab")
		)
		(fp_line
			(start -0.12065 -0.2794)
			(end 0.12065 -0.2794)
			(stroke
				(width 0.1)
				(type default)
			)
			(layer "F.Fab")
		)
		(fp_line
			(start -0.12065 -0.305054)
			(end -0.12065 -0.2794)
			(stroke
				(width 0.1)
				(type default)
			)
			(layer "F.Fab")
		)
		(fp_line
			(start -0.67945 0.3048)
			(end -0.67945 -0.305054)
			(stroke
				(width 0.1)
				(type default)
			)
			(layer "F.Fab")
		)
		(fp_line
			(start -0.67945 -0.305054)
			(end -0.12065 -0.305054)
			(stroke
				(width 0.1)
				(type default)
			)
			(layer "F.Fab")
		)
		(pad "1" smd circle
			(at -0.40005 0 180)
			(size 0 0)
			(layers "F.Cu" "F.Mask" "F.Paste")
			(net "P3V3_AUX")
		)
		(pad "2" smd circle
			(at 0.40005 0 180)
			(size 0 0)
			(layers "F.Cu" "F.Mask" "F.Paste")
			(net "GND")
		)
	)
	(footprint ""
		(layer "F.Cu")
		(at 192.900808 -410.296868 90)
		(property "Reference" "C2846"
			(at 0 0 90)
			(layer "F.SilkS")
			(hide yes)
			(effects
				(font
					(size 1.27 1.27)
				)
			)
		)
		(property "Value" ""
			(at 0 0 90)
			(layer "F.Fab")
			(effects
				(font
					(size 1.27 1.27)
				)
			)
		)
		(duplicate_pad_numbers_are_jumpers no)
		(fp_line
			(start 0.7874 -0.4064)
			(end 0.7874 0.4064)
			(stroke
				(width 0.1524)
				(type default)
			)
			(layer "F.SilkS")
		)
		(fp_line
			(start -0.7874 -0.4064)
			(end 0.7874 -0.4064)
			(stroke
				(width 0.1524)
				(type default)
			)
			(layer "F.SilkS")
		)
		(fp_line
			(start 0.7874 0.4064)
			(end -0.7874 0.4064)
			(stroke
				(width 0.1524)
				(type default)
			)
			(layer "F.SilkS")
		)
		(fp_line
			(start -0.7874 0.4064)
			(end -0.7874 -0.4064)
			(stroke
				(width 0.1524)
				(type default)
			)
			(layer "F.SilkS")
		)
		(fp_line
			(start -0.12065 -0.305054)
			(end -0.12065 -0.2794)
			(stroke
				(width 0.1)
				(type default)
			)
			(layer "F.Fab")
		)
		(fp_line
			(start -0.67945 -0.305054)
			(end -0.12065 -0.305054)
			(stroke
				(width 0.1)
				(type default)
			)
			(layer "F.Fab")
		)
		(fp_line
			(start 0.67945 -0.3048)
			(end 0.67945 0.3048)
			(stroke
				(width 0.1)
				(type default)
			)
			(layer "F.Fab")
		)
		(fp_line
			(start 0.12065 -0.3048)
			(end 0.67945 -0.3048)
			(stroke
				(width 0.1)
				(type default)
			)
			(layer "F.Fab")
		)
		(fp_line
			(start 0.12065 -0.2794)
			(end 0.12065 -0.3048)
			(stroke
				(width 0.1)
				(type default)
			)
			(layer "F.Fab")
		)
		(fp_line
			(start -0.12065 -0.2794)
			(end 0.12065 -0.2794)
			(stroke
				(width 0.1)
				(type default)
			)
			(layer "F.Fab")
		)
		(fp_line
			(start 0.120396 0.2794)
			(end -0.12065 0.2794)
			(stroke
				(width 0.1)
				(type default)
			)
			(layer "F.Fab")
		)
		(fp_line
			(start -0.12065 0.2794)
			(end -0.12065 0.3048)
			(stroke
				(width 0.1)
				(type default)
			)
			(layer "F.Fab")
		)
		(fp_line
			(start 0.67945 0.3048)
			(end 0.120396 0.3048)
			(stroke
				(width 0.1)
				(type default)
			)
			(layer "F.Fab")
		)
		(fp_line
			(start 0.120396 0.3048)
			(end 0.120396 0.2794)
			(stroke
				(width 0.1)
				(type default)
			)
			(layer "F.Fab")
		)
		(fp_line
			(start -0.12065 0.3048)
			(end -0.67945 0.3048)
			(stroke
				(width 0.1)
				(type default)
			)
			(layer "F.Fab")
		)
		(fp_line
			(start -0.67945 0.3048)
			(end -0.67945 -0.305054)
			(stroke
				(width 0.1)
				(type default)
			)
			(layer "F.Fab")
		)
		(pad "1" smd circle
			(at -0.40005 0 90)
			(size 0 0)
			(layers "F.Cu" "F.Mask" "F.Paste")
			(net "P3V3_AUX")
		)
		(pad "2" smd circle
			(at 0.40005 0 90)
			(size 0 0)
			(layers "F.Cu" "F.Mask" "F.Paste")
			(net "GND")
		)
	)
	(footprint ""
		(layer "F.Cu")
		(at 46.952154 -84.960968)
		(property "Reference" "H142"
			(at -1.551686 -3.452622 0)
			(unlocked yes)
			(layer "F.SilkS")
			(effects
				(font
					(size 0.7874 0.5842)
					(thickness 0.1524)
				)
				(justify left)
			)
		)
		(property "Value" ""
			(at 0 0 0)
			(layer "F.Fab")
			(effects
				(font
					(size 1.27 1.27)
				)
			)
		)
		(duplicate_pad_numbers_are_jumpers no)
		(fp_circle
			(center 0 0)
			(end 2.4003 0)
			(stroke
				(width 0.1524)
				(type default)
			)
			(fill no)
			(layer "F.SilkS")
		)
		(fp_circle
			(center 0 0)
			(end 6.5913 0)
			(stroke
				(width 0.1524)
				(type default)
			)
			(fill no)
			(layer "B.SilkS")
		)
		(fp_circle
			(center 0 0)
			(end 6.5913 0)
			(stroke
				(width 0.1)
				(type default)
			)
			(fill no)
			(layer "B.Fab")
		)
		(fp_circle
			(center 0 0)
			(end 2.4003 0)
			(stroke
				(width 0.1)
				(type default)
			)
			(fill no)
			(layer "F.Fab")
		)
		(pad "" np_thru_hole circle
			(at 0 0)
			(size 3.175 3.175)
			(drill 3.175)
			(layers "*.Cu" "*.Mask")
			(clearance 0.381)
			(thermal_gap 0.381)
		)
		(zone
			(layers "F.Cu" "B.Cu" "In1.Cu" "In2.Cu" "In3.Cu" "In4.Cu" "In5.Cu" "In6.Cu"
				"In7.Cu" "In8.Cu" "In9.Cu" "In10.Cu" "In11.Cu" "In12.Cu" "In13.Cu" "In14.Cu"
				"In15.Cu" "In16.Cu"
			)
			(hatch none 0.5)
			(connect_pads
				(clearance 0)
			)
			(min_thickness 0.25)
			(keepout
				(tracks not_allowed)
				(vias allowed)
				(pads allowed)
				(copperpour not_allowed)
				(footprints allowed)
			)
			(placement
				(enabled no)
				(sheetname "")
			)
			(fill
				(thermal_gap 0.5)
				(thermal_bridge_width 0.5)
				(island_removal_mode 0)
			)
			(polygon
				(pts
					(arc
						(start 49.047654 -84.960968)
						(mid 44.856654 -84.960968)
						(end 49.047654 -84.960968)
					)
				)
			)
		)
	)
	(footprint ""
		(layer "F.Cu")
		(at 305.489864 -72.766682 90)
		(property "Reference" "PR7082"
			(at 0 0 90)
			(layer "F.SilkS")
			(hide yes)
			(effects
				(font
					(size 1.27 1.27)
				)
			)
		)
		(property "Value" ""
			(at 0 0 90)
			(layer "F.Fab")
			(effects
				(font
					(size 1.27 1.27)
				)
			)
		)
		(duplicate_pad_numbers_are_jumpers no)
		(fp_line
			(start 0.7874 -0.4064)
			(end 0.7874 0.4064)
			(stroke
				(width 0.1524)
				(type default)
			)
			(layer "F.SilkS")
		)
		(fp_line
			(start -0.7874 -0.4064)
			(end 0.7874 -0.4064)
			(stroke
				(width 0.1524)
				(type default)
			)
			(layer "F.SilkS")
		)
		(fp_line
			(start 0.7874 0.4064)
			(end -0.7874 0.4064)
			(stroke
				(width 0.1524)
				(type default)
			)
			(layer "F.SilkS")
		)
		(fp_line
			(start -0.7874 0.4064)
			(end -0.7874 -0.4064)
			(stroke
				(width 0.1524)
				(type default)
			)
			(layer "F.SilkS")
		)
		(fp_line
			(start -0.12065 -0.305054)
			(end -0.12065 -0.2794)
			(stroke
				(width 0.1)
				(type default)
			)
			(layer "F.Fab")
		)
		(fp_line
			(start -0.67945 -0.305054)
			(end -0.12065 -0.305054)
			(stroke
				(width 0.1)
				(type default)
			)
			(layer "F.Fab")
		)
		(fp_line
			(start 0.67945 -0.3048)
			(end 0.67945 0.3048)
			(stroke
				(width 0.1)
				(type default)
			)
			(layer "F.Fab")
		)
		(fp_line
			(start 0.12065 -0.3048)
			(end 0.67945 -0.3048)
			(stroke
				(width 0.1)
				(type default)
			)
			(layer "F.Fab")
		)
		(fp_line
			(start 0.12065 -0.2794)
			(end 0.12065 -0.3048)
			(stroke
				(width 0.1)
				(type default)
			)
			(layer "F.Fab")
		)
		(fp_line
			(start -0.12065 -0.2794)
			(end 0.12065 -0.2794)
			(stroke
				(width 0.1)
				(type default)
			)
			(layer "F.Fab")
		)
		(fp_line
			(start 0.120396 0.2794)
			(end -0.12065 0.2794)
			(stroke
				(width 0.1)
				(type default)
			)
			(layer "F.Fab")
		)
		(fp_line
			(start -0.12065 0.2794)
			(end -0.12065 0.3048)
			(stroke
				(width 0.1)
				(type default)
			)
			(layer "F.Fab")
		)
		(fp_line
			(start 0.67945 0.3048)
			(end 0.120396 0.3048)
			(stroke
				(width 0.1)
				(type default)
			)
			(layer "F.Fab")
		)
		(fp_line
			(start 0.120396 0.3048)
			(end 0.120396 0.2794)
			(stroke
				(width 0.1)
				(type default)
			)
			(layer "F.Fab")
		)
		(fp_line
			(start -0.12065 0.3048)
			(end -0.67945 0.3048)
			(stroke
				(width 0.1)
				(type default)
			)
			(layer "F.Fab")
		)
		(fp_line
			(start -0.67945 0.3048)
			(end -0.67945 -0.305054)
			(stroke
				(width 0.1)
				(type default)
			)
			(layer "F.Fab")
		)
		(pad "1" smd circle
			(at -0.40005 0 90)
			(size 0 0)
			(layers "F.Cu" "F.Mask" "F.Paste")
			(net "P12V_SSD10_CO_ILIMIT")
		)
		(pad "2" smd circle
			(at 0.40005 0 90)
			(size 0 0)
			(layers "F.Cu" "F.Mask" "F.Paste")
			(net "GND")
		)
	)
	(footprint ""
		(layer "F.Cu")
		(at 373.507 -210.185)
		(property "Reference" "U343"
			(at -1.3462 -4.613148 0)
			(unlocked yes)
			(layer "F.SilkS")
			(effects
				(font
					(size 0.7874 0.5842)
					(thickness 0.1524)
				)
				(justify left)
			)
		)
		(property "Value" ""
			(at 0 0 0)
			(layer "F.Fab")
			(effects
				(font
					(size 1.27 1.27)
				)
			)
		)
		(duplicate_pad_numbers_are_jumpers no)
		(fp_line
			(start -2.097532 -3.949954)
			(end -2.097532 3.949954)
			(stroke
				(width 0.1524)
				(type default)
			)
			(layer "F.SilkS")
		)
		(fp_line
			(start -2.097532 3.949954)
			(end 2.097532 3.949954)
			(stroke
				(width 0.1524)
				(type default)
			)
			(layer "F.SilkS")
		)
		(fp_line
			(start -1.409954 -3.949954)
			(end -2.097532 -3.949954)
			(stroke
				(width 0.1524)
				(type default)
			)
			(layer "F.SilkS")
		)
		(fp_line
			(start 0 -2.54)
			(end -1.409954 -3.949954)
			(stroke
				(width 0.1524)
				(type default)
			)
			(layer "F.SilkS")
		)
		(fp_line
			(start 1.409954 -3.949954)
			(end 0 -2.54)
			(stroke
				(width 0.1524)
				(type default)
			)
			(layer "F.SilkS")
		)
		(fp_line
			(start 2.097532 -3.949954)
			(end 1.409954 -3.949954)
			(stroke
				(width 0.1524)
				(type default)
			)
			(layer "F.SilkS")
		)
		(fp_line
			(start 2.097532 3.949954)
			(end 2.097532 -3.949954)
			(stroke
				(width 0.1524)
				(type default)
			)
			(layer "F.SilkS")
		)
		(fp_poly
			(pts
				(xy -4.7498 -4.182872) (xy -4.7498 -3.166872) (xy -3.7338 -3.674872)
			)
			(stroke
				(width 0)
				(type default)
			)
			(fill yes)
			(layer "F.SilkS")
		)
		(fp_line
			(start -2.249932 -3.949954)
			(end -2.249932 3.949954)
			(stroke
				(width 0.1)
				(type default)
			)
			(layer "F.Fab")
		)
		(fp_line
			(start -2.249932 3.949954)
			(end 2.249932 3.949954)
			(stroke
				(width 0.1)
				(type default)
			)
			(layer "F.Fab")
		)
		(fp_line
			(start 2.249932 -3.949954)
			(end -2.249932 -3.949954)
			(stroke
				(width 0.1)
				(type default)
			)
			(layer "F.Fab")
		)
		(fp_line
			(start 2.249932 3.949954)
			(end 2.249932 -3.949954)
			(stroke
				(width 0.1)
				(type default)
			)
			(layer "F.Fab")
		)
		(fp_poly
			(pts
				(xy -4.7498 -4.182872) (xy -4.7498 -3.166872) (xy -3.7338 -3.674872)
			)
			(stroke
				(width 0)
				(type default)
			)
			(fill yes)
			(layer "F.Fab")
		)
		(pad "1" smd rect
			(at -2.925064 -3.674872 270)
			(size 0.6096 1.3716)
			(layers "F.Cu" "F.Mask" "F.Paste")
			(net "PEX0_PCA9555_0_INT_N")
		)
		(pad "2" smd rect
			(at -2.925064 -2.925064 270)
			(size 0.4064 1.3716)
			(layers "F.Cu" "F.Mask" "F.Paste")
			(net "PCA9555_0_PEX0_A1")
		)
		(pad "3" smd rect
			(at -2.925064 -2.275078 270)
			(size 0.4064 1.3716)
			(layers "F.Cu" "F.Mask" "F.Paste")
			(net "PCA9555_0_PEX0_A2")
		)
		(pad "4" smd rect
			(at -2.925064 -1.625092 270)
			(size 0.4064 1.3716)
			(layers "F.Cu" "F.Mask" "F.Paste")
			(net "PRSNT_SSD0_FPGA_PCA9555_N")
		)
		(pad "5" smd rect
			(at -2.925064 -0.975106 270)
			(size 0.4064 1.3716)
			(layers "F.Cu" "F.Mask" "F.Paste")
			(net "SSD0_PEX_PWR_EN")
		)
		(pad "6" smd rect
			(at -2.925064 -0.32512 270)
			(size 0.4064 1.3716)
			(layers "F.Cu" "F.Mask" "F.Paste")
			(net "RST_PEX_SSD0_PERST_N")
		)
		(pad "7" smd rect
			(at -2.925064 0.32512 270)
			(size 0.4064 1.3716)
			(layers "F.Cu" "F.Mask" "F.Paste")
			(net "Net_1186")
		)
		(pad "8" smd rect
			(at -2.925064 0.975106 270)
			(size 0.4064 1.3716)
			(layers "F.Cu" "F.Mask" "F.Paste")
			(net "PRSNT_SSD1_FPGA_PCA9555_N")
		)
		(pad "9" smd rect
			(at -2.925064 1.625092 270)
			(size 0.4064 1.3716)
			(layers "F.Cu" "F.Mask" "F.Paste")
			(net "SSD1_PEX_PWR_EN")
		)
		(pad "10" smd rect
			(at -2.925064 2.275078 270)
			(size 0.4064 1.3716)
			(layers "F.Cu" "F.Mask" "F.Paste")
			(net "RST_PEX_SSD1_PERST_N")
		)
		(pad "11" smd rect
			(at -2.925064 2.925064 270)
			(size 0.4064 1.3716)
			(layers "F.Cu" "F.Mask" "F.Paste")
			(net "Net_1187")
		)
		(pad "12" smd rect
			(at -2.925064 3.674872 270)
			(size 0.6096 1.3716)
			(layers "F.Cu" "F.Mask" "F.Paste")
			(net "GND")
		)
		(pad "13" smd rect
			(at 2.925064 3.674872 270)
			(size 0.6096 1.3716)
			(layers "F.Cu" "F.Mask" "F.Paste")
			(net "PRSNT_NIC0_FPGA_PCA9555_N")
		)
		(pad "14" smd rect
			(at 2.925064 2.925064 270)
			(size 0.4064 1.3716)
			(layers "F.Cu" "F.Mask" "F.Paste")
			(net "NIC0_PEX_PWR_EN")
		)
		(pad "15" smd rect
			(at 2.925064 2.275078 270)
			(size 0.4064 1.3716)
			(layers "F.Cu" "F.Mask" "F.Paste")
			(net "RST_PEX_NIC0_PERST_N")
		)
		(pad "16" smd rect
			(at 2.925064 1.625092 270)
			(size 0.4064 1.3716)
			(layers "F.Cu" "F.Mask" "F.Paste")
			(net "Net_1188")
		)
		(pad "17" smd rect
			(at 2.925064 0.975106 270)
			(size 0.4064 1.3716)
			(layers "F.Cu" "F.Mask" "F.Paste")
			(net "Net_8992")
		)
		(pad "18" smd rect
			(at 2.925064 0.32512 270)
			(size 0.4064 1.3716)
			(layers "F.Cu" "F.Mask" "F.Paste")
			(net "Net_8991")
		)
		(pad "19" smd rect
			(at 2.925064 -0.32512 270)
			(size 0.4064 1.3716)
			(layers "F.Cu" "F.Mask" "F.Paste")
			(net "Net_8990")
		)
		(pad "20" smd rect
			(at 2.925064 -0.975106 270)
			(size 0.4064 1.3716)
			(layers "F.Cu" "F.Mask" "F.Paste")
			(net "Net_8989")
		)
		(pad "21" smd rect
			(at 2.925064 -1.625092 270)
			(size 0.4064 1.3716)
			(layers "F.Cu" "F.Mask" "F.Paste")
			(net "PCA9555_0_PEX0_A0")
		)
		(pad "22" smd rect
			(at 2.925064 -2.275078 270)
			(size 0.4064 1.3716)
			(layers "F.Cu" "F.Mask" "F.Paste")
			(net "SMB_PEX0_PCA9555_SCL")
		)
		(pad "23" smd rect
			(at 2.925064 -2.925064 270)
			(size 0.4064 1.3716)
			(layers "F.Cu" "F.Mask" "F.Paste")
			(net "SMB_PEX0_PCA9555_SDA")
		)
		(pad "24" smd rect
			(at 2.925064 -3.674872 270)
			(size 0.6096 1.3716)
			(layers "F.Cu" "F.Mask" "F.Paste")
			(net "P3V3_AUX")
		)
	)
	(footprint ""
		(layer "F.Cu")
		(at 210.439 -208.407)
		(property "Reference" "C2706"
			(at 0 0 0)
			(layer "F.SilkS")
			(hide yes)
			(effects
				(font
					(size 1.27 1.27)
				)
			)
		)
		(property "Value" ""
			(at 0 0 0)
			(layer "F.Fab")
			(effects
				(font
					(size 1.27 1.27)
				)
			)
		)
		(duplicate_pad_numbers_are_jumpers no)
		(fp_line
			(start -0.7874 -0.4064)
			(end 0.7874 -0.4064)
			(stroke
				(width 0.1524)
				(type default)
			)
			(layer "F.SilkS")
		)
		(fp_line
			(start -0.7874 0.4064)
			(end -0.7874 -0.4064)
			(stroke
				(width 0.1524)
				(type default)
			)
			(layer "F.SilkS")
		)
		(fp_line
			(start 0.7874 -0.4064)
			(end 0.7874 0.4064)
			(stroke
				(width 0.1524)
				(type default)
			)
			(layer "F.SilkS")
		)
		(fp_line
			(start 0.7874 0.4064)
			(end -0.7874 0.4064)
			(stroke
				(width 0.1524)
				(type default)
			)
			(layer "F.SilkS")
		)
		(fp_line
			(start -0.67945 -0.305054)
			(end -0.12065 -0.305054)
			(stroke
				(width 0.1)
				(type default)
			)
			(layer "F.Fab")
		)
		(fp_line
			(start -0.67945 0.3048)
			(end -0.67945 -0.305054)
			(stroke
				(width 0.1)
				(type default)
			)
			(layer "F.Fab")
		)
		(fp_line
			(start -0.12065 -0.305054)
			(end -0.12065 -0.2794)
			(stroke
				(width 0.1)
				(type default)
			)
			(layer "F.Fab")
		)
		(fp_line
			(start -0.12065 -0.2794)
			(end 0.12065 -0.2794)
			(stroke
				(width 0.1)
				(type default)
			)
			(layer "F.Fab")
		)
		(fp_line
			(start -0.12065 0.2794)
			(end -0.12065 0.3048)
			(stroke
				(width 0.1)
				(type default)
			)
			(layer "F.Fab")
		)
		(fp_line
			(start -0.12065 0.3048)
			(end -0.67945 0.3048)
			(stroke
				(width 0.1)
				(type default)
			)
			(layer "F.Fab")
		)
		(fp_line
			(start 0.120396 0.2794)
			(end -0.12065 0.2794)
			(stroke
				(width 0.1)
				(type default)
			)
			(layer "F.Fab")
		)
		(fp_line
			(start 0.120396 0.3048)
			(end 0.120396 0.2794)
			(stroke
				(width 0.1)
				(type default)
			)
			(layer "F.Fab")
		)
		(fp_line
			(start 0.12065 -0.3048)
			(end 0.67945 -0.3048)
			(stroke
				(width 0.1)
				(type default)
			)
			(layer "F.Fab")
		)
		(fp_line
			(start 0.12065 -0.2794)
			(end 0.12065 -0.3048)
			(stroke
				(width 0.1)
				(type default)
			)
			(layer "F.Fab")
		)
		(fp_line
			(start 0.67945 -0.3048)
			(end 0.67945 0.3048)
			(stroke
				(width 0.1)
				(type default)
			)
			(layer "F.Fab")
		)
		(fp_line
			(start 0.67945 0.3048)
			(end 0.120396 0.3048)
			(stroke
				(width 0.1)
				(type default)
			)
			(layer "F.Fab")
		)
		(pad "1" smd circle
			(at -0.40005 0)
			(size 0 0)
			(layers "F.Cu" "F.Mask" "F.Paste")
			(net "GND")
		)
		(pad "2" smd circle
			(at 0.40005 0)
			(size 0 0)
			(layers "F.Cu" "F.Mask" "F.Paste")
			(net "P1V2_AUX")
		)
	)
	(footprint ""
		(layer "F.Cu")
		(at 208.489804 -298.885102 -90)
		(property "Reference" "R3928"
			(at 0 0 270)
			(layer "F.SilkS")
			(hide yes)
			(effects
				(font
					(size 1.27 1.27)
				)
			)
		)
		(property "Value" ""
			(at 0 0 270)
			(layer "F.Fab")
			(effects
				(font
					(size 1.27 1.27)
				)
			)
		)
		(duplicate_pad_numbers_are_jumpers no)
		(fp_line
			(start -0.7874 0.4064)
			(end -0.7874 -0.4064)
			(stroke
				(width 0.1524)
				(type default)
			)
			(layer "F.SilkS")
		)
		(fp_line
			(start 0.7874 0.4064)
			(end -0.7874 0.4064)
			(stroke
				(width 0.1524)
				(type default)
			)
			(layer "F.SilkS")
		)
		(fp_line
			(start -0.7874 -0.4064)
			(end 0.7874 -0.4064)
			(stroke
				(width 0.1524)
				(type default)
			)
			(layer "F.SilkS")
		)
		(fp_line
			(start 0.7874 -0.4064)
			(end 0.7874 0.4064)
			(stroke
				(width 0.1524)
				(type default)
			)
			(layer "F.SilkS")
		)
		(fp_line
			(start -0.67945 0.3048)
			(end -0.67945 -0.305054)
			(stroke
				(width 0.1)
				(type default)
			)
			(layer "F.Fab")
		)
		(fp_line
			(start -0.12065 0.3048)
			(end -0.67945 0.3048)
			(stroke
				(width 0.1)
				(type default)
			)
			(layer "F.Fab")
		)
		(fp_line
			(start 0.120396 0.3048)
			(end 0.120396 0.2794)
			(stroke
				(width 0.1)
				(type default)
			)
			(layer "F.Fab")
		)
		(fp_line
			(start 0.67945 0.3048)
			(end 0.120396 0.3048)
			(stroke
				(width 0.1)
				(type default)
			)
			(layer "F.Fab")
		)
		(fp_line
			(start -0.12065 0.2794)
			(end -0.12065 0.3048)
			(stroke
				(width 0.1)
				(type default)
			)
			(layer "F.Fab")
		)
		(fp_line
			(start 0.120396 0.2794)
			(end -0.12065 0.2794)
			(stroke
				(width 0.1)
				(type default)
			)
			(layer "F.Fab")
		)
		(fp_line
			(start -0.12065 -0.2794)
			(end 0.12065 -0.2794)
			(stroke
				(width 0.1)
				(type default)
			)
			(layer "F.Fab")
		)
		(fp_line
			(start 0.12065 -0.2794)
			(end 0.12065 -0.3048)
			(stroke
				(width 0.1)
				(type default)
			)
			(layer "F.Fab")
		)
		(fp_line
			(start 0.12065 -0.3048)
			(end 0.67945 -0.3048)
			(stroke
				(width 0.1)
				(type default)
			)
			(layer "F.Fab")
		)
		(fp_line
			(start 0.67945 -0.3048)
			(end 0.67945 0.3048)
			(stroke
				(width 0.1)
				(type default)
			)
			(layer "F.Fab")
		)
		(fp_line
			(start -0.67945 -0.305054)
			(end -0.12065 -0.305054)
			(stroke
				(width 0.1)
				(type default)
			)
			(layer "F.Fab")
		)
		(fp_line
			(start -0.12065 -0.305054)
			(end -0.12065 -0.2794)
			(stroke
				(width 0.1)
				(type default)
			)
			(layer "F.Fab")
		)
		(pad "1" smd circle
			(at -0.40005 0 270)
			(size 0 0)
			(layers "F.Cu" "F.Mask" "F.Paste")
			(net "I2C_PEX1_HOST_SCL")
		)
		(pad "2" smd circle
			(at 0.40005 0 270)
			(size 0 0)
			(layers "F.Cu" "F.Mask" "F.Paste")
			(net "I2C_PEX1_HOST_R_SCL")
		)
	)
	(footprint ""
		(layer "F.Cu")
		(at 253.147322 -20.35556)
		(property "Reference" "C3932"
			(at 0 0 0)
			(layer "F.SilkS")
			(hide yes)
			(effects
				(font
					(size 1.27 1.27)
				)
			)
		)
		(property "Value" ""
			(at 0 0 0)
			(layer "F.Fab")
			(effects
				(font
					(size 1.27 1.27)
				)
			)
		)
		(duplicate_pad_numbers_are_jumpers no)
		(fp_line
			(start -0.7874 -0.4064)
			(end 0.7874 -0.4064)
			(stroke
				(width 0.1524)
				(type default)
			)
			(layer "F.SilkS")
		)
		(fp_line
			(start -0.7874 0.4064)
			(end -0.7874 -0.4064)
			(stroke
				(width 0.1524)
				(type default)
			)
			(layer "F.SilkS")
		)
		(fp_line
			(start 0.7874 -0.4064)
			(end 0.7874 0.4064)
			(stroke
				(width 0.1524)
				(type default)
			)
			(layer "F.SilkS")
		)
		(fp_line
			(start 0.7874 0.4064)
			(end -0.7874 0.4064)
			(stroke
				(width 0.1524)
				(type default)
			)
			(layer "F.SilkS")
		)
		(fp_line
			(start -0.67945 -0.305054)
			(end -0.12065 -0.305054)
			(stroke
				(width 0.1)
				(type default)
			)
			(layer "F.Fab")
		)
		(fp_line
			(start -0.67945 0.3048)
			(end -0.67945 -0.305054)
			(stroke
				(width 0.1)
				(type default)
			)
			(layer "F.Fab")
		)
		(fp_line
			(start -0.12065 -0.305054)
			(end -0.12065 -0.2794)
			(stroke
				(width 0.1)
				(type default)
			)
			(layer "F.Fab")
		)
		(fp_line
			(start -0.12065 -0.2794)
			(end 0.12065 -0.2794)
			(stroke
				(width 0.1)
				(type default)
			)
			(layer "F.Fab")
		)
		(fp_line
			(start -0.12065 0.2794)
			(end -0.12065 0.3048)
			(stroke
				(width 0.1)
				(type default)
			)
			(layer "F.Fab")
		)
		(fp_line
			(start -0.12065 0.3048)
			(end -0.67945 0.3048)
			(stroke
				(width 0.1)
				(type default)
			)
			(layer "F.Fab")
		)
		(fp_line
			(start 0.120396 0.2794)
			(end -0.12065 0.2794)
			(stroke
				(width 0.1)
				(type default)
			)
			(layer "F.Fab")
		)
		(fp_line
			(start 0.120396 0.3048)
			(end 0.120396 0.2794)
			(stroke
				(width 0.1)
				(type default)
			)
			(layer "F.Fab")
		)
		(fp_line
			(start 0.12065 -0.3048)
			(end 0.67945 -0.3048)
			(stroke
				(width 0.1)
				(type default)
			)
			(layer "F.Fab")
		)
		(fp_line
			(start 0.12065 -0.2794)
			(end 0.12065 -0.3048)
			(stroke
				(width 0.1)
				(type default)
			)
			(layer "F.Fab")
		)
		(fp_line
			(start 0.67945 -0.3048)
			(end 0.67945 0.3048)
			(stroke
				(width 0.1)
				(type default)
			)
			(layer "F.Fab")
		)
		(fp_line
			(start 0.67945 0.3048)
			(end 0.120396 0.3048)
			(stroke
				(width 0.1)
				(type default)
			)
			(layer "F.Fab")
		)
		(pad "1" smd circle
			(at -0.40005 0)
			(size 0 0)
			(layers "F.Cu" "F.Mask" "F.Paste")
			(net "P12V_SSD8")
		)
		(pad "2" smd circle
			(at 0.40005 0)
			(size 0 0)
			(layers "F.Cu" "F.Mask" "F.Paste")
			(net "GND")
		)
	)
	(footprint ""
		(layer "F.Cu")
		(at 366.243362 -114.152426 -90)
		(property "Reference" "PC911"
			(at 0 0 270)
			(layer "F.SilkS")
			(hide yes)
			(effects
				(font
					(size 1.27 1.27)
				)
			)
		)
		(property "Value" ""
			(at 0 0 270)
			(layer "F.Fab")
			(effects
				(font
					(size 1.27 1.27)
				)
			)
		)
		(duplicate_pad_numbers_are_jumpers no)
		(fp_line
			(start -1.524 0.762)
			(end -1.524 -0.762)
			(stroke
				(width 0.1524)
				(type default)
			)
			(layer "F.SilkS")
		)
		(fp_line
			(start 1.524 0.762)
			(end -1.524 0.762)
			(stroke
				(width 0.1524)
				(type default)
			)
			(layer "F.SilkS")
		)
		(fp_line
			(start -1.524 -0.762)
			(end 1.524 -0.762)
			(stroke
				(width 0.1524)
				(type default)
			)
			(layer "F.SilkS")
		)
		(fp_line
			(start 1.524 -0.762)
			(end 1.524 0.762)
			(stroke
				(width 0.1524)
				(type default)
			)
			(layer "F.SilkS")
		)
		(fp_line
			(start -1.1049 0.724916)
			(end 1.1049 0.724916)
			(stroke
				(width 0.1)
				(type default)
			)
			(layer "F.Fab")
		)
		(fp_line
			(start 1.1049 0.724916)
			(end 1.1049 -0.724916)
			(stroke
				(width 0.1)
				(type default)
			)
			(layer "F.Fab")
		)
		(fp_line
			(start -1.1049 -0.724916)
			(end -1.1049 0.724916)
			(stroke
				(width 0.1)
				(type default)
			)
			(layer "F.Fab")
		)
		(fp_line
			(start 1.1049 -0.724916)
			(end -1.1049 -0.724916)
			(stroke
				(width 0.1)
				(type default)
			)
			(layer "F.Fab")
		)
		(pad "1" smd rect
			(at -0.889 0 90)
			(size 1.016 1.27)
			(layers "F.Cu" "F.Mask" "F.Paste")
			(net "P3V3_NIC6")
		)
		(pad "2" smd rect
			(at 0.889 0 90)
			(size 1.016 1.27)
			(layers "F.Cu" "F.Mask" "F.Paste")
			(net "GND")
		)
	)
	(footprint ""
		(layer "F.Cu")
		(at 236.927136 -266.873228 180)
		(property "Reference" "L116"
			(at 0 0 180)
			(layer "F.SilkS")
			(hide yes)
			(effects
				(font
					(size 1.27 1.27)
				)
			)
		)
		(property "Value" ""
			(at 0 0 180)
			(layer "F.Fab")
			(effects
				(font
					(size 1.27 1.27)
				)
			)
		)
		(duplicate_pad_numbers_are_jumpers no)
		(fp_line
			(start 2.248154 4.9911)
			(end 2.248154 1.672336)
			(stroke
				(width 0.1524)
				(type default)
			)
			(layer "F.SilkS")
		)
		(fp_line
			(start 2.248154 -1.687576)
			(end 2.248154 -4.9911)
			(stroke
				(width 0.1524)
				(type default)
			)
			(layer "F.SilkS")
		)
		(fp_line
			(start 2.248154 -4.9911)
			(end -2.248154 -4.9911)
			(stroke
				(width 0.1524)
				(type default)
			)
			(layer "F.SilkS")
		)
		(fp_line
			(start -2.248154 4.9911)
			(end 2.248154 4.9911)
			(stroke
				(width 0.1524)
				(type default)
			)
			(layer "F.SilkS")
		)
		(fp_line
			(start -2.248154 1.76022)
			(end -2.248154 4.9911)
			(stroke
				(width 0.1524)
				(type default)
			)
			(layer "F.SilkS")
		)
		(fp_line
			(start -2.248154 -4.9911)
			(end -2.248154 -1.665478)
			(stroke
				(width 0.1524)
				(type default)
			)
			(layer "F.SilkS")
		)
		(fp_line
			(start 1.700022 0.899922)
			(end 1.700022 -0.899922)
			(stroke
				(width 0.1)
				(type default)
			)
			(layer "F.Fab")
		)
		(fp_line
			(start 1.700022 -0.899922)
			(end -1.700022 -0.899922)
			(stroke
				(width 0.1)
				(type default)
			)
			(layer "F.Fab")
		)
		(fp_line
			(start -1.700022 0.899922)
			(end 1.700022 0.899922)
			(stroke
				(width 0.1)
				(type default)
			)
			(layer "F.Fab")
		)
		(fp_line
			(start -1.700022 -0.899922)
			(end -1.700022 0.899922)
			(stroke
				(width 0.1)
				(type default)
			)
			(layer "F.Fab")
		)
		(pad "1" smd rect
			(at -1.575054 0 180)
			(size 1.1684 9.8044)
			(layers "F.Cu" "F.Mask" "F.Paste")
			(net "P1V25_PEX2")
		)
		(pad "2" smd rect
			(at 1.575054 0 180)
			(size 1.1684 9.8044)
			(layers "F.Cu" "F.Mask" "F.Paste")
			(net "P1V25_SERDES_VDDPLL_PEX2")
		)
	)
	(footprint ""
		(layer "F.Cu")
		(at 336.042 -151.003)
		(property "Reference" "R4805"
			(at 0 0 0)
			(layer "F.SilkS")
			(hide yes)
			(effects
				(font
					(size 1.27 1.27)
				)
			)
		)
		(property "Value" ""
			(at 0 0 0)
			(layer "F.Fab")
			(effects
				(font
					(size 1.27 1.27)
				)
			)
		)
		(duplicate_pad_numbers_are_jumpers no)
		(fp_line
			(start -0.7874 -0.4064)
			(end 0.7874 -0.4064)
			(stroke
				(width 0.1524)
				(type default)
			)
			(layer "F.SilkS")
		)
		(fp_line
			(start -0.7874 0.4064)
			(end -0.7874 -0.4064)
			(stroke
				(width 0.1524)
				(type default)
			)
			(layer "F.SilkS")
		)
		(fp_line
			(start 0.7874 -0.4064)
			(end 0.7874 0.4064)
			(stroke
				(width 0.1524)
				(type default)
			)
			(layer "F.SilkS")
		)
		(fp_line
			(start 0.7874 0.4064)
			(end -0.7874 0.4064)
			(stroke
				(width 0.1524)
				(type default)
			)
			(layer "F.SilkS")
		)
		(fp_line
			(start -0.67945 -0.305054)
			(end -0.12065 -0.305054)
			(stroke
				(width 0.1)
				(type default)
			)
			(layer "F.Fab")
		)
		(fp_line
			(start -0.67945 0.3048)
			(end -0.67945 -0.305054)
			(stroke
				(width 0.1)
				(type default)
			)
			(layer "F.Fab")
		)
		(fp_line
			(start -0.12065 -0.305054)
			(end -0.12065 -0.2794)
			(stroke
				(width 0.1)
				(type default)
			)
			(layer "F.Fab")
		)
		(fp_line
			(start -0.12065 -0.2794)
			(end 0.12065 -0.2794)
			(stroke
				(width 0.1)
				(type default)
			)
			(layer "F.Fab")
		)
		(fp_line
			(start -0.12065 0.2794)
			(end -0.12065 0.3048)
			(stroke
				(width 0.1)
				(type default)
			)
			(layer "F.Fab")
		)
		(fp_line
			(start -0.12065 0.3048)
			(end -0.67945 0.3048)
			(stroke
				(width 0.1)
				(type default)
			)
			(layer "F.Fab")
		)
		(fp_line
			(start 0.120396 0.2794)
			(end -0.12065 0.2794)
			(stroke
				(width 0.1)
				(type default)
			)
			(layer "F.Fab")
		)
		(fp_line
			(start 0.120396 0.3048)
			(end 0.120396 0.2794)
			(stroke
				(width 0.1)
				(type default)
			)
			(layer "F.Fab")
		)
		(fp_line
			(start 0.12065 -0.3048)
			(end 0.67945 -0.3048)
			(stroke
				(width 0.1)
				(type default)
			)
			(layer "F.Fab")
		)
		(fp_line
			(start 0.12065 -0.2794)
			(end 0.12065 -0.3048)
			(stroke
				(width 0.1)
				(type default)
			)
			(layer "F.Fab")
		)
		(fp_line
			(start 0.67945 -0.3048)
			(end 0.67945 0.3048)
			(stroke
				(width 0.1)
				(type default)
			)
			(layer "F.Fab")
		)
		(fp_line
			(start 0.67945 0.3048)
			(end 0.120396 0.3048)
			(stroke
				(width 0.1)
				(type default)
			)
			(layer "F.Fab")
		)
		(pad "1" smd circle
			(at -0.40005 0)
			(size 0 0)
			(layers "F.Cu" "F.Mask" "F.Paste")
			(net "PEX3_PCA9555_INT_N")
		)
		(pad "2" smd circle
			(at 0.40005 0)
			(size 0 0)
			(layers "F.Cu" "F.Mask" "F.Paste")
			(net "PEX3_PCA9555_1_INT_N")
		)
	)
	(footprint ""
		(layer "F.Cu")
		(at 19.498564 -66.32194 -90)
		(property "Reference" "PC642"
			(at 0 0 270)
			(layer "F.SilkS")
			(hide yes)
			(effects
				(font
					(size 1.27 1.27)
				)
			)
		)
		(property "Value" ""
			(at 0 0 270)
			(layer "F.Fab")
			(effects
				(font
					(size 1.27 1.27)
				)
			)
		)
		(duplicate_pad_numbers_are_jumpers no)
		(fp_line
			(start -0.7874 0.4064)
			(end -0.7874 -0.4064)
			(stroke
				(width 0.1524)
				(type default)
			)
			(layer "F.SilkS")
		)
		(fp_line
			(start 0.7874 0.4064)
			(end -0.7874 0.4064)
			(stroke
				(width 0.1524)
				(type default)
			)
			(layer "F.SilkS")
		)
		(fp_line
			(start -0.7874 -0.4064)
			(end 0.7874 -0.4064)
			(stroke
				(width 0.1524)
				(type default)
			)
			(layer "F.SilkS")
		)
		(fp_line
			(start 0.7874 -0.4064)
			(end 0.7874 0.4064)
			(stroke
				(width 0.1524)
				(type default)
			)
			(layer "F.SilkS")
		)
		(fp_line
			(start -0.67945 0.3048)
			(end -0.67945 -0.305054)
			(stroke
				(width 0.1)
				(type default)
			)
			(layer "F.Fab")
		)
		(fp_line
			(start -0.12065 0.3048)
			(end -0.67945 0.3048)
			(stroke
				(width 0.1)
				(type default)
			)
			(layer "F.Fab")
		)
		(fp_line
			(start 0.120396 0.3048)
			(end 0.120396 0.2794)
			(stroke
				(width 0.1)
				(type default)
			)
			(layer "F.Fab")
		)
		(fp_line
			(start 0.67945 0.3048)
			(end 0.120396 0.3048)
			(stroke
				(width 0.1)
				(type default)
			)
			(layer "F.Fab")
		)
		(fp_line
			(start -0.12065 0.2794)
			(end -0.12065 0.3048)
			(stroke
				(width 0.1)
				(type default)
			)
			(layer "F.Fab")
		)
		(fp_line
			(start 0.120396 0.2794)
			(end -0.12065 0.2794)
			(stroke
				(width 0.1)
				(type default)
			)
			(layer "F.Fab")
		)
		(fp_line
			(start -0.12065 -0.2794)
			(end 0.12065 -0.2794)
			(stroke
				(width 0.1)
				(type default)
			)
			(layer "F.Fab")
		)
		(fp_line
			(start 0.12065 -0.2794)
			(end 0.12065 -0.3048)
			(stroke
				(width 0.1)
				(type default)
			)
			(layer "F.Fab")
		)
		(fp_line
			(start 0.12065 -0.3048)
			(end 0.67945 -0.3048)
			(stroke
				(width 0.1)
				(type default)
			)
			(layer "F.Fab")
		)
		(fp_line
			(start 0.67945 -0.3048)
			(end 0.67945 0.3048)
			(stroke
				(width 0.1)
				(type default)
			)
			(layer "F.Fab")
		)
		(fp_line
			(start -0.67945 -0.305054)
			(end -0.12065 -0.305054)
			(stroke
				(width 0.1)
				(type default)
			)
			(layer "F.Fab")
		)
		(fp_line
			(start -0.12065 -0.305054)
			(end -0.12065 -0.2794)
			(stroke
				(width 0.1)
				(type default)
			)
			(layer "F.Fab")
		)
		(pad "1" smd circle
			(at -0.40005 0 270)
			(size 0 0)
			(layers "F.Cu" "F.Mask" "F.Paste")
			(net "P12V_SSD0_CO_GATE")
		)
		(pad "2" smd circle
			(at 0.40005 0 270)
			(size 0 0)
			(layers "F.Cu" "F.Mask" "F.Paste")
			(net "GND")
		)
	)
	(footprint ""
		(layer "F.Cu")
		(at 132.951474 -124.120656 -90)
		(property "Reference" "PC476"
			(at 0 0 270)
			(layer "F.SilkS")
			(hide yes)
			(effects
				(font
					(size 1.27 1.27)
				)
			)
		)
		(property "Value" ""
			(at 0 0 270)
			(layer "F.Fab")
			(effects
				(font
					(size 1.27 1.27)
				)
			)
		)
		(duplicate_pad_numbers_are_jumpers no)
		(fp_line
			(start -0.7874 0.4064)
			(end -0.7874 -0.4064)
			(stroke
				(width 0.1524)
				(type default)
			)
			(layer "F.SilkS")
		)
		(fp_line
			(start 0.7874 0.4064)
			(end -0.7874 0.4064)
			(stroke
				(width 0.1524)
				(type default)
			)
			(layer "F.SilkS")
		)
		(fp_line
			(start -0.7874 -0.4064)
			(end 0.7874 -0.4064)
			(stroke
				(width 0.1524)
				(type default)
			)
			(layer "F.SilkS")
		)
		(fp_line
			(start 0.7874 -0.4064)
			(end 0.7874 0.4064)
			(stroke
				(width 0.1524)
				(type default)
			)
			(layer "F.SilkS")
		)
		(fp_line
			(start -0.67945 0.3048)
			(end -0.67945 -0.305054)
			(stroke
				(width 0.1)
				(type default)
			)
			(layer "F.Fab")
		)
		(fp_line
			(start -0.12065 0.3048)
			(end -0.67945 0.3048)
			(stroke
				(width 0.1)
				(type default)
			)
			(layer "F.Fab")
		)
		(fp_line
			(start 0.120396 0.3048)
			(end 0.120396 0.2794)
			(stroke
				(width 0.1)
				(type default)
			)
			(layer "F.Fab")
		)
		(fp_line
			(start 0.67945 0.3048)
			(end 0.120396 0.3048)
			(stroke
				(width 0.1)
				(type default)
			)
			(layer "F.Fab")
		)
		(fp_line
			(start -0.12065 0.2794)
			(end -0.12065 0.3048)
			(stroke
				(width 0.1)
				(type default)
			)
			(layer "F.Fab")
		)
		(fp_line
			(start 0.120396 0.2794)
			(end -0.12065 0.2794)
			(stroke
				(width 0.1)
				(type default)
			)
			(layer "F.Fab")
		)
		(fp_line
			(start -0.12065 -0.2794)
			(end 0.12065 -0.2794)
			(stroke
				(width 0.1)
				(type default)
			)
			(layer "F.Fab")
		)
		(fp_line
			(start 0.12065 -0.2794)
			(end 0.12065 -0.3048)
			(stroke
				(width 0.1)
				(type default)
			)
			(layer "F.Fab")
		)
		(fp_line
			(start 0.12065 -0.3048)
			(end 0.67945 -0.3048)
			(stroke
				(width 0.1)
				(type default)
			)
			(layer "F.Fab")
		)
		(fp_line
			(start 0.67945 -0.3048)
			(end 0.67945 0.3048)
			(stroke
				(width 0.1)
				(type default)
			)
			(layer "F.Fab")
		)
		(fp_line
			(start -0.67945 -0.305054)
			(end -0.12065 -0.305054)
			(stroke
				(width 0.1)
				(type default)
			)
			(layer "F.Fab")
		)
		(fp_line
			(start -0.12065 -0.305054)
			(end -0.12065 -0.2794)
			(stroke
				(width 0.1)
				(type default)
			)
			(layer "F.Fab")
		)
		(pad "1" smd circle
			(at -0.40005 0 270)
			(size 0 0)
			(layers "F.Cu" "F.Mask" "F.Paste")
			(net "P3V3_NIC2")
		)
		(pad "2" smd circle
			(at 0.40005 0 270)
			(size 0 0)
			(layers "F.Cu" "F.Mask" "F.Paste")
			(net "GND")
		)
	)
	(footprint ""
		(layer "F.Cu")
		(at 155.380436 -124.605542)
		(property "Reference" "C252"
			(at 0 0 0)
			(layer "F.SilkS")
			(hide yes)
			(effects
				(font
					(size 1.27 1.27)
				)
			)
		)
		(property "Value" ""
			(at 0 0 0)
			(layer "F.Fab")
			(effects
				(font
					(size 1.27 1.27)
				)
			)
		)
		(duplicate_pad_numbers_are_jumpers no)
		(fp_line
			(start -0.299974 -0.150114)
			(end 0.299974 -0.150114)
			(stroke
				(width 0.1)
				(type default)
			)
			(layer "F.Fab")
		)
		(fp_line
			(start -0.299974 0.150114)
			(end -0.299974 -0.150114)
			(stroke
				(width 0.1)
				(type default)
			)
			(layer "F.Fab")
		)
		(fp_line
			(start 0.299974 -0.150114)
			(end 0.299974 0.150114)
			(stroke
				(width 0.1)
				(type default)
			)
			(layer "F.Fab")
		)
		(fp_line
			(start 0.299974 0.150114)
			(end -0.299974 0.150114)
			(stroke
				(width 0.1)
				(type default)
			)
			(layer "F.Fab")
		)
		(pad "1" smd rect
			(at -0.2667 0)
			(size 0.3048 0.381)
			(layers "F.Cu" "F.Mask" "F.Paste")
			(net "P5E_PEX1_STN1_TX_DN<27>")
		)
		(pad "2" smd rect
			(at 0.2667 0)
			(size 0.3048 0.381)
			(layers "F.Cu" "F.Mask" "F.Paste")
			(net "P5E_PEX1_STN1_TX_C_DN<27>")
		)
	)
	(footprint ""
		(layer "F.Cu")
		(at 428.319438 -149.79015 180)
		(property "Reference" "C641"
			(at 0 0 180)
			(layer "F.SilkS")
			(hide yes)
			(effects
				(font
					(size 1.27 1.27)
				)
			)
		)
		(property "Value" ""
			(at 0 0 180)
			(layer "F.Fab")
			(effects
				(font
					(size 1.27 1.27)
				)
			)
		)
		(duplicate_pad_numbers_are_jumpers no)
		(fp_line
			(start 0.299974 0.150114)
			(end -0.299974 0.150114)
			(stroke
				(width 0.1)
				(type default)
			)
			(layer "F.Fab")
		)
		(fp_line
			(start 0.299974 -0.150114)
			(end 0.299974 0.150114)
			(stroke
				(width 0.1)
				(type default)
			)
			(layer "F.Fab")
		)
		(fp_line
			(start -0.299974 0.150114)
			(end -0.299974 -0.150114)
			(stroke
				(width 0.1)
				(type default)
			)
			(layer "F.Fab")
		)
		(fp_line
			(start -0.299974 -0.150114)
			(end 0.299974 -0.150114)
			(stroke
				(width 0.1)
				(type default)
			)
			(layer "F.Fab")
		)
		(pad "1" smd rect
			(at -0.2667 0 180)
			(size 0.3048 0.381)
			(layers "F.Cu" "F.Mask" "F.Paste")
			(net "P5E_PEX3_STN0_TX_DP<12>")
		)
		(pad "2" smd rect
			(at 0.2667 0 180)
			(size 0.3048 0.381)
			(layers "F.Cu" "F.Mask" "F.Paste")
			(net "P5E_PEX3_STN0_TX_C_DP<12>")
		)
	)
	(footprint ""
		(layer "F.Cu")
		(at 172.401992 -356.244906 90)
		(property "Reference" "C2523"
			(at 0 0 90)
			(layer "F.SilkS")
			(hide yes)
			(effects
				(font
					(size 1.27 1.27)
				)
			)
		)
		(property "Value" ""
			(at 0 0 90)
			(layer "F.Fab")
			(effects
				(font
					(size 1.27 1.27)
				)
			)
		)
		(duplicate_pad_numbers_are_jumpers no)
		(fp_line
			(start 0.299974 -0.150114)
			(end 0.299974 0.150114)
			(stroke
				(width 0.1)
				(type default)
			)
			(layer "F.Fab")
		)
		(fp_line
			(start -0.299974 -0.150114)
			(end 0.299974 -0.150114)
			(stroke
				(width 0.1)
				(type default)
			)
			(layer "F.Fab")
		)
		(fp_line
			(start 0.299974 0.150114)
			(end -0.299974 0.150114)
			(stroke
				(width 0.1)
				(type default)
			)
			(layer "F.Fab")
		)
		(fp_line
			(start -0.299974 0.150114)
			(end -0.299974 -0.150114)
			(stroke
				(width 0.1)
				(type default)
			)
			(layer "F.Fab")
		)
		(pad "1" smd rect
			(at -0.2667 0 90)
			(size 0.3048 0.381)
			(layers "F.Cu" "F.Mask" "F.Paste")
			(net "P5E_PEX1_STN4_TX_DN<74>")
		)
		(pad "2" smd rect
			(at 0.2667 0 90)
			(size 0.3048 0.381)
			(layers "F.Cu" "F.Mask" "F.Paste")
			(net "P5E_PEX1_STN4_TX_C_DN<74>")
		)
	)
	(footprint ""
		(layer "F.Cu")
		(at 22.271736 -152.71115 90)
		(property "Reference" "R681"
			(at 0 0 90)
			(layer "F.SilkS")
			(hide yes)
			(effects
				(font
					(size 1.27 1.27)
				)
			)
		)
		(property "Value" ""
			(at 0 0 90)
			(layer "F.Fab")
			(effects
				(font
					(size 1.27 1.27)
				)
			)
		)
		(duplicate_pad_numbers_are_jumpers no)
		(fp_line
			(start 0.7874 -0.4064)
			(end 0.7874 0.4064)
			(stroke
				(width 0.1524)
				(type default)
			)
			(layer "F.SilkS")
		)
		(fp_line
			(start -0.7874 -0.4064)
			(end 0.7874 -0.4064)
			(stroke
				(width 0.1524)
				(type default)
			)
			(layer "F.SilkS")
		)
		(fp_line
			(start 0.7874 0.4064)
			(end -0.7874 0.4064)
			(stroke
				(width 0.1524)
				(type default)
			)
			(layer "F.SilkS")
		)
		(fp_line
			(start -0.7874 0.4064)
			(end -0.7874 -0.4064)
			(stroke
				(width 0.1524)
				(type default)
			)
			(layer "F.SilkS")
		)
		(fp_line
			(start -0.12065 -0.305054)
			(end -0.12065 -0.2794)
			(stroke
				(width 0.1)
				(type default)
			)
			(layer "F.Fab")
		)
		(fp_line
			(start -0.67945 -0.305054)
			(end -0.12065 -0.305054)
			(stroke
				(width 0.1)
				(type default)
			)
			(layer "F.Fab")
		)
		(fp_line
			(start 0.67945 -0.3048)
			(end 0.67945 0.3048)
			(stroke
				(width 0.1)
				(type default)
			)
			(layer "F.Fab")
		)
		(fp_line
			(start 0.12065 -0.3048)
			(end 0.67945 -0.3048)
			(stroke
				(width 0.1)
				(type default)
			)
			(layer "F.Fab")
		)
		(fp_line
			(start 0.12065 -0.2794)
			(end 0.12065 -0.3048)
			(stroke
				(width 0.1)
				(type default)
			)
			(layer "F.Fab")
		)
		(fp_line
			(start -0.12065 -0.2794)
			(end 0.12065 -0.2794)
			(stroke
				(width 0.1)
				(type default)
			)
			(layer "F.Fab")
		)
		(fp_line
			(start 0.120396 0.2794)
			(end -0.12065 0.2794)
			(stroke
				(width 0.1)
				(type default)
			)
			(layer "F.Fab")
		)
		(fp_line
			(start -0.12065 0.2794)
			(end -0.12065 0.3048)
			(stroke
				(width 0.1)
				(type default)
			)
			(layer "F.Fab")
		)
		(fp_line
			(start 0.67945 0.3048)
			(end 0.120396 0.3048)
			(stroke
				(width 0.1)
				(type default)
			)
			(layer "F.Fab")
		)
		(fp_line
			(start 0.120396 0.3048)
			(end 0.120396 0.2794)
			(stroke
				(width 0.1)
				(type default)
			)
			(layer "F.Fab")
		)
		(fp_line
			(start -0.12065 0.3048)
			(end -0.67945 0.3048)
			(stroke
				(width 0.1)
				(type default)
			)
			(layer "F.Fab")
		)
		(fp_line
			(start -0.67945 0.3048)
			(end -0.67945 -0.305054)
			(stroke
				(width 0.1)
				(type default)
			)
			(layer "F.Fab")
		)
		(pad "1" smd circle
			(at -0.40005 0 90)
			(size 0 0)
			(layers "F.Cu" "F.Mask" "F.Paste")
			(net "NIC0_ADC_A1")
		)
		(pad "2" smd circle
			(at 0.40005 0 90)
			(size 0 0)
			(layers "F.Cu" "F.Mask" "F.Paste")
			(net "P3V3_AUX")
		)
	)
	(footprint ""
		(layer "F.Cu")
		(at 268.53515 -84.266024 180)
		(property "Reference" "R1071"
			(at 0 0 180)
			(layer "F.SilkS")
			(hide yes)
			(effects
				(font
					(size 1.27 1.27)
				)
			)
		)
		(property "Value" ""
			(at 0 0 180)
			(layer "F.Fab")
			(effects
				(font
					(size 1.27 1.27)
				)
			)
		)
		(duplicate_pad_numbers_are_jumpers no)
		(fp_line
			(start 0.7874 0.4064)
			(end -0.7874 0.4064)
			(stroke
				(width 0.1524)
				(type default)
			)
			(layer "F.SilkS")
		)
		(fp_line
			(start 0.67945 0.3048)
			(end 0.120396 0.3048)
			(stroke
				(width 0.1)
				(type default)
			)
			(layer "F.Fab")
		)
		(fp_line
			(start 0.67945 -0.3048)
			(end 0.67945 0.3048)
			(stroke
				(width 0.1)
				(type default)
			)
			(layer "F.Fab")
		)
		(fp_line
			(start 0.12065 -0.2794)
			(end 0.12065 -0.3048)
			(stroke
				(width 0.1)
				(type default)
			)
			(layer "F.Fab")
		)
		(fp_line
			(start 0.12065 -0.3048)
			(end 0.67945 -0.3048)
			(stroke
				(width 0.1)
				(type default)
			)
			(layer "F.Fab")
		)
		(fp_line
			(start 0.120396 0.3048)
			(end 0.120396 0.2794)
			(stroke
				(width 0.1)
				(type default)
			)
			(layer "F.Fab")
		)
		(fp_line
			(start 0.120396 0.2794)
			(end -0.12065 0.2794)
			(stroke
				(width 0.1)
				(type default)
			)
			(layer "F.Fab")
		)
		(fp_line
			(start -0.12065 0.3048)
			(end -0.67945 0.3048)
			(stroke
				(width 0.1)
				(type default)
			)
			(layer "F.Fab")
		)
		(fp_line
			(start -0.12065 0.2794)
			(end -0.12065 0.3048)
			(stroke
				(width 0.1)
				(type default)
			)
			(layer "F.Fab")
		)
		(fp_line
			(start -0.12065 -0.2794)
			(end 0.12065 -0.2794)
			(stroke
				(width 0.1)
				(type default)
			)
			(layer "F.Fab")
		)
		(fp_line
			(start -0.12065 -0.305054)
			(end -0.12065 -0.2794)
			(stroke
				(width 0.1)
				(type default)
			)
			(layer "F.Fab")
		)
		(fp_line
			(start -0.67945 0.3048)
			(end -0.67945 -0.305054)
			(stroke
				(width 0.1)
				(type default)
			)
			(layer "F.Fab")
		)
		(fp_line
			(start -0.67945 -0.305054)
			(end -0.12065 -0.305054)
			(stroke
				(width 0.1)
				(type default)
			)
			(layer "F.Fab")
		)
		(pad "1" smd circle
			(at -0.40005 0 180)
			(size 0 0)
			(layers "F.Cu" "F.Mask" "F.Paste")
			(net "CLK_100M_CK440Q_0_DB2000QL_R_DP")
		)
		(pad "2" smd circle
			(at 0.40005 0 180)
			(size 0 0)
			(layers "F.Cu" "F.Mask" "F.Paste")
			(net "CLK_100M_CK440Q_0_DB2000QL_DP")
		)
	)
	(footprint ""
		(layer "F.Cu")
		(at 264.319004 -59.574684 90)
		(property "Reference" "PC552"
			(at 0 0 90)
			(layer "F.SilkS")
			(hide yes)
			(effects
				(font
					(size 1.27 1.27)
				)
			)
		)
		(property "Value" ""
			(at 0 0 90)
			(layer "F.Fab")
			(effects
				(font
					(size 1.27 1.27)
				)
			)
		)
		(duplicate_pad_numbers_are_jumpers no)
		(fp_line
			(start 0.7874 -0.4064)
			(end 0.7874 0.4064)
			(stroke
				(width 0.1524)
				(type default)
			)
			(layer "F.SilkS")
		)
		(fp_line
			(start -0.7874 -0.4064)
			(end 0.7874 -0.4064)
			(stroke
				(width 0.1524)
				(type default)
			)
			(layer "F.SilkS")
		)
		(fp_line
			(start 0.7874 0.4064)
			(end -0.7874 0.4064)
			(stroke
				(width 0.1524)
				(type default)
			)
			(layer "F.SilkS")
		)
		(fp_line
			(start -0.7874 0.4064)
			(end -0.7874 -0.4064)
			(stroke
				(width 0.1524)
				(type default)
			)
			(layer "F.SilkS")
		)
		(fp_line
			(start -0.12065 -0.305054)
			(end -0.12065 -0.2794)
			(stroke
				(width 0.1)
				(type default)
			)
			(layer "F.Fab")
		)
		(fp_line
			(start -0.67945 -0.305054)
			(end -0.12065 -0.305054)
			(stroke
				(width 0.1)
				(type default)
			)
			(layer "F.Fab")
		)
		(fp_line
			(start 0.67945 -0.3048)
			(end 0.67945 0.3048)
			(stroke
				(width 0.1)
				(type default)
			)
			(layer "F.Fab")
		)
		(fp_line
			(start 0.12065 -0.3048)
			(end 0.67945 -0.3048)
			(stroke
				(width 0.1)
				(type default)
			)
			(layer "F.Fab")
		)
		(fp_line
			(start 0.12065 -0.2794)
			(end 0.12065 -0.3048)
			(stroke
				(width 0.1)
				(type default)
			)
			(layer "F.Fab")
		)
		(fp_line
			(start -0.12065 -0.2794)
			(end 0.12065 -0.2794)
			(stroke
				(width 0.1)
				(type default)
			)
			(layer "F.Fab")
		)
		(fp_line
			(start 0.120396 0.2794)
			(end -0.12065 0.2794)
			(stroke
				(width 0.1)
				(type default)
			)
			(layer "F.Fab")
		)
		(fp_line
			(start -0.12065 0.2794)
			(end -0.12065 0.3048)
			(stroke
				(width 0.1)
				(type default)
			)
			(layer "F.Fab")
		)
		(fp_line
			(start 0.67945 0.3048)
			(end 0.120396 0.3048)
			(stroke
				(width 0.1)
				(type default)
			)
			(layer "F.Fab")
		)
		(fp_line
			(start 0.120396 0.3048)
			(end 0.120396 0.2794)
			(stroke
				(width 0.1)
				(type default)
			)
			(layer "F.Fab")
		)
		(fp_line
			(start -0.12065 0.3048)
			(end -0.67945 0.3048)
			(stroke
				(width 0.1)
				(type default)
			)
			(layer "F.Fab")
		)
		(fp_line
			(start -0.67945 0.3048)
			(end -0.67945 -0.305054)
			(stroke
				(width 0.1)
				(type default)
			)
			(layer "F.Fab")
		)
		(pad "1" smd circle
			(at -0.40005 0 90)
			(size 0 0)
			(layers "F.Cu" "F.Mask" "F.Paste")
			(net "P5V_AUX")
		)
		(pad "2" smd circle
			(at 0.40005 0 90)
			(size 0 0)
			(layers "F.Cu" "F.Mask" "F.Paste")
			(net "GND")
		)
	)
	(footprint ""
		(layer "F.Cu")
		(at 258.810506 -18.61439 90)
		(property "Reference" "U134"
			(at -1.39319 2.251964 90)
			(unlocked yes)
			(layer "F.SilkS")
			(effects
				(font
					(size 0.7874 0.5842)
					(thickness 0.1524)
				)
				(justify left)
			)
		)
		(property "Value" ""
			(at 0 0 90)
			(layer "F.Fab")
			(effects
				(font
					(size 1.27 1.27)
				)
			)
		)
		(duplicate_pad_numbers_are_jumpers no)
		(fp_line
			(start 1.463548 -1.549908)
			(end 1.463548 1.549908)
			(stroke
				(width 0.1524)
				(type default)
			)
			(layer "F.SilkS")
		)
		(fp_line
			(start 0.762 -1.549908)
			(end 1.463548 -1.549908)
			(stroke
				(width 0.1524)
				(type default)
			)
			(layer "F.SilkS")
		)
		(fp_line
			(start -0.787908 -1.549908)
			(end 0 -0.762)
			(stroke
				(width 0.1524)
				(type default)
			)
			(layer "F.SilkS")
		)
		(fp_line
			(start -1.463548 -1.549908)
			(end -0.787908 -1.549908)
			(stroke
				(width 0.1524)
				(type default)
			)
			(layer "F.SilkS")
		)
		(fp_line
			(start 0 -0.762)
			(end 0.762 -1.549908)
			(stroke
				(width 0.1524)
				(type default)
			)
			(layer "F.SilkS")
		)
		(fp_line
			(start 1.463548 1.549908)
			(end -1.463548 1.549908)
			(stroke
				(width 0.1524)
				(type default)
			)
			(layer "F.SilkS")
		)
		(fp_line
			(start -1.463548 1.549908)
			(end -1.463548 -1.549908)
			(stroke
				(width 0.1524)
				(type default)
			)
			(layer "F.SilkS")
		)
		(fp_poly
			(pts
				(xy -3.11023 -2.04978) (xy -2.891282 -1.392428) (xy -3.548634 -1.61163)
			)
			(stroke
				(width 0)
				(type default)
			)
			(fill yes)
			(layer "F.SilkS")
		)
		(fp_line
			(start 1.549908 -1.549908)
			(end 1.549908 1.549908)
			(stroke
				(width 0.1)
				(type default)
			)
			(layer "F.Fab")
		)
		(fp_line
			(start -1.549908 -1.549908)
			(end 1.549908 -1.549908)
			(stroke
				(width 0.1)
				(type default)
			)
			(layer "F.Fab")
		)
		(fp_line
			(start 1.549908 1.549908)
			(end -1.549908 1.549908)
			(stroke
				(width 0.1)
				(type default)
			)
			(layer "F.Fab")
		)
		(fp_line
			(start -1.549908 1.549908)
			(end -1.549908 -1.549908)
			(stroke
				(width 0.1)
				(type default)
			)
			(layer "F.Fab")
		)
		(fp_poly
			(pts
				(xy -3.4798 -1.359916) (xy -2.86004 -1.050036) (xy -3.4798 -0.740156)
			)
			(stroke
				(width 0)
				(type default)
			)
			(fill yes)
			(layer "F.Fab")
		)
		(pad "1" smd rect
			(at -2.175002 -1.050036 180)
			(size 0.6096 1.1684)
			(layers "F.Cu" "F.Mask" "F.Paste")
			(net "P3V3_SSD8")
		)
		(pad "2" smd rect
			(at -2.175002 -0.32512 180)
			(size 0.4318 1.1684)
			(layers "F.Cu" "F.Mask" "F.Paste")
			(net "SMB_ISO_SSD8_SCL")
		)
		(pad "3" smd rect
			(at -2.175002 0.32512 180)
			(size 0.4318 1.1684)
			(layers "F.Cu" "F.Mask" "F.Paste")
			(net "SMB_ISO_SSD8_SDA")
		)
		(pad "4" smd rect
			(at -2.175002 1.050036 180)
			(size 0.6096 1.1684)
			(layers "F.Cu" "F.Mask" "F.Paste")
			(net "GND")
		)
		(pad "5" smd rect
			(at 2.175002 1.050036 180)
			(size 0.6096 1.1684)
			(layers "F.Cu" "F.Mask" "F.Paste")
			(net "SMB_SSD8_ISO_EN")
		)
		(pad "6" smd rect
			(at 2.175002 0.32512 180)
			(size 0.4318 1.1684)
			(layers "F.Cu" "F.Mask" "F.Paste")
			(net "SMB_BIC_I2C9_MUX1_SSD8_R_SDA")
		)
		(pad "7" smd rect
			(at 2.175002 -0.32512 180)
			(size 0.4318 1.1684)
			(layers "F.Cu" "F.Mask" "F.Paste")
			(net "SMB_BIC_I2C9_MUX1_SSD8_R_SCL")
		)
		(pad "8" smd rect
			(at 2.175002 -1.050036 180)
			(size 0.6096 1.1684)
			(layers "F.Cu" "F.Mask" "F.Paste")
			(net "P3V3_AUX")
		)
	)
	(footprint ""
		(layer "F.Cu")
		(at 179.777644 -115.283742 180)
		(property "Reference" "R190"
			(at 0 0 180)
			(layer "F.SilkS")
			(hide yes)
			(effects
				(font
					(size 1.27 1.27)
				)
			)
		)
		(property "Value" ""
			(at 0 0 180)
			(layer "F.Fab")
			(effects
				(font
					(size 1.27 1.27)
				)
			)
		)
		(duplicate_pad_numbers_are_jumpers no)
		(fp_line
			(start 0.7874 0.4064)
			(end -0.7874 0.4064)
			(stroke
				(width 0.1524)
				(type default)
			)
			(layer "F.SilkS")
		)
		(fp_line
			(start 0.7874 -0.4064)
			(end 0.7874 0.4064)
			(stroke
				(width 0.1524)
				(type default)
			)
			(layer "F.SilkS")
		)
		(fp_line
			(start -0.7874 0.4064)
			(end -0.7874 -0.4064)
			(stroke
				(width 0.1524)
				(type default)
			)
			(layer "F.SilkS")
		)
		(fp_line
			(start -0.7874 -0.4064)
			(end 0.7874 -0.4064)
			(stroke
				(width 0.1524)
				(type default)
			)
			(layer "F.SilkS")
		)
		(fp_line
			(start 0.67945 0.3048)
			(end 0.120396 0.3048)
			(stroke
				(width 0.1)
				(type default)
			)
			(layer "F.Fab")
		)
		(fp_line
			(start 0.67945 -0.3048)
			(end 0.67945 0.3048)
			(stroke
				(width 0.1)
				(type default)
			)
			(layer "F.Fab")
		)
		(fp_line
			(start 0.12065 -0.2794)
			(end 0.12065 -0.3048)
			(stroke
				(width 0.1)
				(type default)
			)
			(layer "F.Fab")
		)
		(fp_line
			(start 0.12065 -0.3048)
			(end 0.67945 -0.3048)
			(stroke
				(width 0.1)
				(type default)
			)
			(layer "F.Fab")
		)
		(fp_line
			(start 0.120396 0.3048)
			(end 0.120396 0.2794)
			(stroke
				(width 0.1)
				(type default)
			)
			(layer "F.Fab")
		)
		(fp_line
			(start 0.120396 0.2794)
			(end -0.12065 0.2794)
			(stroke
				(width 0.1)
				(type default)
			)
			(layer "F.Fab")
		)
		(fp_line
			(start -0.12065 0.3048)
			(end -0.67945 0.3048)
			(stroke
				(width 0.1)
				(type default)
			)
			(layer "F.Fab")
		)
		(fp_line
			(start -0.12065 0.2794)
			(end -0.12065 0.3048)
			(stroke
				(width 0.1)
				(type default)
			)
			(layer "F.Fab")
		)
		(fp_line
			(start -0.12065 -0.2794)
			(end 0.12065 -0.2794)
			(stroke
				(width 0.1)
				(type default)
			)
			(layer "F.Fab")
		)
		(fp_line
			(start -0.12065 -0.305054)
			(end -0.12065 -0.2794)
			(stroke
				(width 0.1)
				(type default)
			)
			(layer "F.Fab")
		)
		(fp_line
			(start -0.67945 0.3048)
			(end -0.67945 -0.305054)
			(stroke
				(width 0.1)
				(type default)
			)
			(layer "F.Fab")
		)
		(fp_line
			(start -0.67945 -0.305054)
			(end -0.12065 -0.305054)
			(stroke
				(width 0.1)
				(type default)
			)
			(layer "F.Fab")
		)
		(pad "1" smd circle
			(at -0.40005 0 180)
			(size 0 0)
			(layers "F.Cu" "F.Mask" "F.Paste")
			(net "RST_SMB_NIC3_MUX_ISO_R_N")
		)
		(pad "2" smd circle
			(at 0.40005 0 180)
			(size 0 0)
			(layers "F.Cu" "F.Mask" "F.Paste")
			(net "RST_SMB_NIC3_MUX_ISO_N")
		)
	)
	(footprint ""
		(layer "F.Cu")
		(at 303.671478 -25.342342 -90)
		(property "Reference" "R439"
			(at 0 0 270)
			(layer "F.SilkS")
			(hide yes)
			(effects
				(font
					(size 1.27 1.27)
				)
			)
		)
		(property "Value" ""
			(at 0 0 270)
			(layer "F.Fab")
			(effects
				(font
					(size 1.27 1.27)
				)
			)
		)
		(duplicate_pad_numbers_are_jumpers no)
		(fp_line
			(start -0.7874 0.4064)
			(end -0.7874 -0.4064)
			(stroke
				(width 0.1524)
				(type default)
			)
			(layer "F.SilkS")
		)
		(fp_line
			(start 0.7874 0.4064)
			(end -0.7874 0.4064)
			(stroke
				(width 0.1524)
				(type default)
			)
			(layer "F.SilkS")
		)
		(fp_line
			(start -0.7874 -0.4064)
			(end 0.7874 -0.4064)
			(stroke
				(width 0.1524)
				(type default)
			)
			(layer "F.SilkS")
		)
		(fp_line
			(start 0.7874 -0.4064)
			(end 0.7874 0.4064)
			(stroke
				(width 0.1524)
				(type default)
			)
			(layer "F.SilkS")
		)
		(fp_line
			(start -0.67945 0.3048)
			(end -0.67945 -0.305054)
			(stroke
				(width 0.1)
				(type default)
			)
			(layer "F.Fab")
		)
		(fp_line
			(start -0.12065 0.3048)
			(end -0.67945 0.3048)
			(stroke
				(width 0.1)
				(type default)
			)
			(layer "F.Fab")
		)
		(fp_line
			(start 0.120396 0.3048)
			(end 0.120396 0.2794)
			(stroke
				(width 0.1)
				(type default)
			)
			(layer "F.Fab")
		)
		(fp_line
			(start 0.67945 0.3048)
			(end 0.120396 0.3048)
			(stroke
				(width 0.1)
				(type default)
			)
			(layer "F.Fab")
		)
		(fp_line
			(start -0.12065 0.2794)
			(end -0.12065 0.3048)
			(stroke
				(width 0.1)
				(type default)
			)
			(layer "F.Fab")
		)
		(fp_line
			(start 0.120396 0.2794)
			(end -0.12065 0.2794)
			(stroke
				(width 0.1)
				(type default)
			)
			(layer "F.Fab")
		)
		(fp_line
			(start -0.12065 -0.2794)
			(end 0.12065 -0.2794)
			(stroke
				(width 0.1)
				(type default)
			)
			(layer "F.Fab")
		)
		(fp_line
			(start 0.12065 -0.2794)
			(end 0.12065 -0.3048)
			(stroke
				(width 0.1)
				(type default)
			)
			(layer "F.Fab")
		)
		(fp_line
			(start 0.12065 -0.3048)
			(end 0.67945 -0.3048)
			(stroke
				(width 0.1)
				(type default)
			)
			(layer "F.Fab")
		)
		(fp_line
			(start 0.67945 -0.3048)
			(end 0.67945 0.3048)
			(stroke
				(width 0.1)
				(type default)
			)
			(layer "F.Fab")
		)
		(fp_line
			(start -0.67945 -0.305054)
			(end -0.12065 -0.305054)
			(stroke
				(width 0.1)
				(type default)
			)
			(layer "F.Fab")
		)
		(fp_line
			(start -0.12065 -0.305054)
			(end -0.12065 -0.2794)
			(stroke
				(width 0.1)
				(type default)
			)
			(layer "F.Fab")
		)
		(pad "1" smd circle
			(at -0.40005 0 270)
			(size 0 0)
			(layers "F.Cu" "F.Mask" "F.Paste")
			(net "P3V3_SSD10")
		)
		(pad "2" smd circle
			(at 0.40005 0 270)
			(size 0 0)
			(layers "F.Cu" "F.Mask" "F.Paste")
			(net "DUALPORT_N_SSD10")
		)
	)
	(footprint ""
		(layer "F.Cu")
		(at 57.394094 -29.507688 -90)
		(property "Reference" "PC681"
			(at 0 0 270)
			(layer "F.SilkS")
			(hide yes)
			(effects
				(font
					(size 1.27 1.27)
				)
			)
		)
		(property "Value" ""
			(at 0 0 270)
			(layer "F.Fab")
			(effects
				(font
					(size 1.27 1.27)
				)
			)
		)
		(duplicate_pad_numbers_are_jumpers no)
		(fp_line
			(start -1.524 0.762)
			(end -1.524 -0.762)
			(stroke
				(width 0.1524)
				(type default)
			)
			(layer "F.SilkS")
		)
		(fp_line
			(start 1.524 0.762)
			(end -1.524 0.762)
			(stroke
				(width 0.1524)
				(type default)
			)
			(layer "F.SilkS")
		)
		(fp_line
			(start -1.524 -0.762)
			(end 1.524 -0.762)
			(stroke
				(width 0.1524)
				(type default)
			)
			(layer "F.SilkS")
		)
		(fp_line
			(start 1.524 -0.762)
			(end 1.524 0.762)
			(stroke
				(width 0.1524)
				(type default)
			)
			(layer "F.SilkS")
		)
		(fp_line
			(start -1.1049 0.724916)
			(end 1.1049 0.724916)
			(stroke
				(width 0.1)
				(type default)
			)
			(layer "F.Fab")
		)
		(fp_line
			(start 1.1049 0.724916)
			(end 1.1049 -0.724916)
			(stroke
				(width 0.1)
				(type default)
			)
			(layer "F.Fab")
		)
		(fp_line
			(start -1.1049 -0.724916)
			(end -1.1049 0.724916)
			(stroke
				(width 0.1)
				(type default)
			)
			(layer "F.Fab")
		)
		(fp_line
			(start 1.1049 -0.724916)
			(end -1.1049 -0.724916)
			(stroke
				(width 0.1)
				(type default)
			)
			(layer "F.Fab")
		)
		(pad "1" smd rect
			(at -0.889 0 90)
			(size 1.016 1.27)
			(layers "F.Cu" "F.Mask" "F.Paste")
			(net "P3V3_SSD2")
		)
		(pad "2" smd rect
			(at 0.889 0 90)
			(size 1.016 1.27)
			(layers "F.Cu" "F.Mask" "F.Paste")
			(net "GND")
		)
	)
	(footprint ""
		(layer "F.Cu")
		(at 103.15321 -366.507268)
		(property "Reference" "C4051"
			(at 0 0 0)
			(layer "F.SilkS")
			(hide yes)
			(effects
				(font
					(size 1.27 1.27)
				)
			)
		)
		(property "Value" ""
			(at 0 0 0)
			(layer "F.Fab")
			(effects
				(font
					(size 1.27 1.27)
				)
			)
		)
		(duplicate_pad_numbers_are_jumpers no)
		(fp_line
			(start -0.7874 -0.4064)
			(end 0.7874 -0.4064)
			(stroke
				(width 0.1524)
				(type default)
			)
			(layer "F.SilkS")
		)
		(fp_line
			(start -0.7874 0.4064)
			(end -0.7874 -0.4064)
			(stroke
				(width 0.1524)
				(type default)
			)
			(layer "F.SilkS")
		)
		(fp_line
			(start 0.7874 -0.4064)
			(end 0.7874 0.4064)
			(stroke
				(width 0.1524)
				(type default)
			)
			(layer "F.SilkS")
		)
		(fp_line
			(start 0.7874 0.4064)
			(end -0.7874 0.4064)
			(stroke
				(width 0.1524)
				(type default)
			)
			(layer "F.SilkS")
		)
		(fp_line
			(start -0.67945 -0.305054)
			(end -0.12065 -0.305054)
			(stroke
				(width 0.1)
				(type default)
			)
			(layer "F.Fab")
		)
		(fp_line
			(start -0.67945 0.3048)
			(end -0.67945 -0.305054)
			(stroke
				(width 0.1)
				(type default)
			)
			(layer "F.Fab")
		)
		(fp_line
			(start -0.12065 -0.305054)
			(end -0.12065 -0.2794)
			(stroke
				(width 0.1)
				(type default)
			)
			(layer "F.Fab")
		)
		(fp_line
			(start -0.12065 -0.2794)
			(end 0.12065 -0.2794)
			(stroke
				(width 0.1)
				(type default)
			)
			(layer "F.Fab")
		)
		(fp_line
			(start -0.12065 0.2794)
			(end -0.12065 0.3048)
			(stroke
				(width 0.1)
				(type default)
			)
			(layer "F.Fab")
		)
		(fp_line
			(start -0.12065 0.3048)
			(end -0.67945 0.3048)
			(stroke
				(width 0.1)
				(type default)
			)
			(layer "F.Fab")
		)
		(fp_line
			(start 0.120396 0.2794)
			(end -0.12065 0.2794)
			(stroke
				(width 0.1)
				(type default)
			)
			(layer "F.Fab")
		)
		(fp_line
			(start 0.120396 0.3048)
			(end 0.120396 0.2794)
			(stroke
				(width 0.1)
				(type default)
			)
			(layer "F.Fab")
		)
		(fp_line
			(start 0.12065 -0.3048)
			(end 0.67945 -0.3048)
			(stroke
				(width 0.1)
				(type default)
			)
			(layer "F.Fab")
		)
		(fp_line
			(start 0.12065 -0.2794)
			(end 0.12065 -0.3048)
			(stroke
				(width 0.1)
				(type default)
			)
			(layer "F.Fab")
		)
		(fp_line
			(start 0.67945 -0.3048)
			(end 0.67945 0.3048)
			(stroke
				(width 0.1)
				(type default)
			)
			(layer "F.Fab")
		)
		(fp_line
			(start 0.67945 0.3048)
			(end 0.120396 0.3048)
			(stroke
				(width 0.1)
				(type default)
			)
			(layer "F.Fab")
		)
		(pad "1" smd circle
			(at -0.40005 0)
			(size 0 0)
			(layers "F.Cu" "F.Mask" "F.Paste")
			(net "GND")
		)
		(pad "2" smd circle
			(at 0.40005 0)
			(size 0 0)
			(layers "F.Cu" "F.Mask" "F.Paste")
			(net "RST_MB_PERST_0_N")
		)
	)
	(footprint ""
		(layer "F.Cu")
		(at 338.263484 -343.952322 90)
		(property "Reference" "C574"
			(at 0 0 90)
			(layer "F.SilkS")
			(hide yes)
			(effects
				(font
					(size 1.27 1.27)
				)
			)
		)
		(property "Value" ""
			(at 0 0 90)
			(layer "F.Fab")
			(effects
				(font
					(size 1.27 1.27)
				)
			)
		)
		(duplicate_pad_numbers_are_jumpers no)
		(fp_line
			(start 0.299974 -0.150114)
			(end 0.299974 0.150114)
			(stroke
				(width 0.1)
				(type default)
			)
			(layer "F.Fab")
		)
		(fp_line
			(start -0.299974 -0.150114)
			(end 0.299974 -0.150114)
			(stroke
				(width 0.1)
				(type default)
			)
			(layer "F.Fab")
		)
		(fp_line
			(start 0.299974 0.150114)
			(end -0.299974 0.150114)
			(stroke
				(width 0.1)
				(type default)
			)
			(layer "F.Fab")
		)
		(fp_line
			(start -0.299974 0.150114)
			(end -0.299974 -0.150114)
			(stroke
				(width 0.1)
				(type default)
			)
			(layer "F.Fab")
		)
		(pad "1" smd rect
			(at -0.2667 0 90)
			(size 0.3048 0.381)
			(layers "F.Cu" "F.Mask" "F.Paste")
			(net "P5E_PEX2_STN6_TX_DN<100>")
		)
		(pad "2" smd rect
			(at 0.2667 0 90)
			(size 0.3048 0.381)
			(layers "F.Cu" "F.Mask" "F.Paste")
			(net "P5E_PEX2_STN6_TX_C_DN<100>")
		)
	)
	(footprint ""
		(layer "F.Cu")
		(at 292.310312 -63.652146 180)
		(property "Reference" "R6006"
			(at 0 0 180)
			(layer "F.SilkS")
			(hide yes)
			(effects
				(font
					(size 1.27 1.27)
				)
			)
		)
		(property "Value" ""
			(at 0 0 180)
			(layer "F.Fab")
			(effects
				(font
					(size 1.27 1.27)
				)
			)
		)
		(duplicate_pad_numbers_are_jumpers no)
		(fp_line
			(start 0.7874 0.4064)
			(end -0.7874 0.4064)
			(stroke
				(width 0.1524)
				(type default)
			)
			(layer "F.SilkS")
		)
		(fp_line
			(start 0.7874 -0.4064)
			(end 0.7874 0.4064)
			(stroke
				(width 0.1524)
				(type default)
			)
			(layer "F.SilkS")
		)
		(fp_line
			(start -0.7874 0.4064)
			(end -0.7874 -0.4064)
			(stroke
				(width 0.1524)
				(type default)
			)
			(layer "F.SilkS")
		)
		(fp_line
			(start -0.7874 -0.4064)
			(end 0.7874 -0.4064)
			(stroke
				(width 0.1524)
				(type default)
			)
			(layer "F.SilkS")
		)
		(fp_line
			(start 0.67945 0.3048)
			(end 0.120396 0.3048)
			(stroke
				(width 0.1)
				(type default)
			)
			(layer "F.Fab")
		)
		(fp_line
			(start 0.67945 -0.3048)
			(end 0.67945 0.3048)
			(stroke
				(width 0.1)
				(type default)
			)
			(layer "F.Fab")
		)
		(fp_line
			(start 0.12065 -0.2794)
			(end 0.12065 -0.3048)
			(stroke
				(width 0.1)
				(type default)
			)
			(layer "F.Fab")
		)
		(fp_line
			(start 0.12065 -0.3048)
			(end 0.67945 -0.3048)
			(stroke
				(width 0.1)
				(type default)
			)
			(layer "F.Fab")
		)
		(fp_line
			(start 0.120396 0.3048)
			(end 0.120396 0.2794)
			(stroke
				(width 0.1)
				(type default)
			)
			(layer "F.Fab")
		)
		(fp_line
			(start 0.120396 0.2794)
			(end -0.12065 0.2794)
			(stroke
				(width 0.1)
				(type default)
			)
			(layer "F.Fab")
		)
		(fp_line
			(start -0.12065 0.3048)
			(end -0.67945 0.3048)
			(stroke
				(width 0.1)
				(type default)
			)
			(layer "F.Fab")
		)
		(fp_line
			(start -0.12065 0.2794)
			(end -0.12065 0.3048)
			(stroke
				(width 0.1)
				(type default)
			)
			(layer "F.Fab")
		)
		(fp_line
			(start -0.12065 -0.2794)
			(end 0.12065 -0.2794)
			(stroke
				(width 0.1)
				(type default)
			)
			(layer "F.Fab")
		)
		(fp_line
			(start -0.12065 -0.305054)
			(end -0.12065 -0.2794)
			(stroke
				(width 0.1)
				(type default)
			)
			(layer "F.Fab")
		)
		(fp_line
			(start -0.67945 0.3048)
			(end -0.67945 -0.305054)
			(stroke
				(width 0.1)
				(type default)
			)
			(layer "F.Fab")
		)
		(fp_line
			(start -0.67945 -0.305054)
			(end -0.12065 -0.305054)
			(stroke
				(width 0.1)
				(type default)
			)
			(layer "F.Fab")
		)
		(pad "1" smd circle
			(at -0.40005 0 180)
			(size 0 0)
			(layers "F.Cu" "F.Mask" "F.Paste")
			(net "P5V_AUX")
		)
		(pad "2" smd circle
			(at 0.40005 0 180)
			(size 0 0)
			(layers "F.Cu" "F.Mask" "F.Paste")
			(net "P12V_SSD10_PG_G2")
		)
	)
	(footprint ""
		(layer "F.Cu")
		(at 444.7286 -230.2256 90)
		(property "Reference" "C4440"
			(at 0 0 90)
			(layer "F.SilkS")
			(hide yes)
			(effects
				(font
					(size 1.27 1.27)
				)
			)
		)
		(property "Value" ""
			(at 0 0 90)
			(layer "F.Fab")
			(effects
				(font
					(size 1.27 1.27)
				)
			)
		)
		(duplicate_pad_numbers_are_jumpers no)
		(fp_line
			(start 0.7874 -0.4064)
			(end 0.7874 0.4064)
			(stroke
				(width 0.1524)
				(type default)
			)
			(layer "F.SilkS")
		)
		(fp_line
			(start -0.7874 -0.4064)
			(end 0.7874 -0.4064)
			(stroke
				(width 0.1524)
				(type default)
			)
			(layer "F.SilkS")
		)
		(fp_line
			(start 0.7874 0.4064)
			(end -0.7874 0.4064)
			(stroke
				(width 0.1524)
				(type default)
			)
			(layer "F.SilkS")
		)
		(fp_line
			(start -0.7874 0.4064)
			(end -0.7874 -0.4064)
			(stroke
				(width 0.1524)
				(type default)
			)
			(layer "F.SilkS")
		)
		(fp_line
			(start -0.12065 -0.305054)
			(end -0.12065 -0.2794)
			(stroke
				(width 0.1)
				(type default)
			)
			(layer "F.Fab")
		)
		(fp_line
			(start -0.67945 -0.305054)
			(end -0.12065 -0.305054)
			(stroke
				(width 0.1)
				(type default)
			)
			(layer "F.Fab")
		)
		(fp_line
			(start 0.67945 -0.3048)
			(end 0.67945 0.3048)
			(stroke
				(width 0.1)
				(type default)
			)
			(layer "F.Fab")
		)
		(fp_line
			(start 0.12065 -0.3048)
			(end 0.67945 -0.3048)
			(stroke
				(width 0.1)
				(type default)
			)
			(layer "F.Fab")
		)
		(fp_line
			(start 0.12065 -0.2794)
			(end 0.12065 -0.3048)
			(stroke
				(width 0.1)
				(type default)
			)
			(layer "F.Fab")
		)
		(fp_line
			(start -0.12065 -0.2794)
			(end 0.12065 -0.2794)
			(stroke
				(width 0.1)
				(type default)
			)
			(layer "F.Fab")
		)
		(fp_line
			(start 0.120396 0.2794)
			(end -0.12065 0.2794)
			(stroke
				(width 0.1)
				(type default)
			)
			(layer "F.Fab")
		)
		(fp_line
			(start -0.12065 0.2794)
			(end -0.12065 0.3048)
			(stroke
				(width 0.1)
				(type default)
			)
			(layer "F.Fab")
		)
		(fp_line
			(start 0.67945 0.3048)
			(end 0.120396 0.3048)
			(stroke
				(width 0.1)
				(type default)
			)
			(layer "F.Fab")
		)
		(fp_line
			(start 0.120396 0.3048)
			(end 0.120396 0.2794)
			(stroke
				(width 0.1)
				(type default)
			)
			(layer "F.Fab")
		)
		(fp_line
			(start -0.12065 0.3048)
			(end -0.67945 0.3048)
			(stroke
				(width 0.1)
				(type default)
			)
			(layer "F.Fab")
		)
		(fp_line
			(start -0.67945 0.3048)
			(end -0.67945 -0.305054)
			(stroke
				(width 0.1)
				(type default)
			)
			(layer "F.Fab")
		)
		(pad "1" smd circle
			(at -0.40005 0 90)
			(size 0 0)
			(layers "F.Cu" "F.Mask" "F.Paste")
			(net "P3V3_AUX")
		)
		(pad "2" smd circle
			(at 0.40005 0 90)
			(size 0 0)
			(layers "F.Cu" "F.Mask" "F.Paste")
			(net "GND")
		)
	)
	(footprint ""
		(layer "F.Cu")
		(at 204.430376 -364.885986 180)
		(property "Reference" "R6600"
			(at 0 0 180)
			(layer "F.SilkS")
			(hide yes)
			(effects
				(font
					(size 1.27 1.27)
				)
			)
		)
		(property "Value" ""
			(at 0 0 180)
			(layer "F.Fab")
			(effects
				(font
					(size 1.27 1.27)
				)
			)
		)
		(duplicate_pad_numbers_are_jumpers no)
		(fp_line
			(start 0.7874 0.4064)
			(end -0.7874 0.4064)
			(stroke
				(width 0.1524)
				(type default)
			)
			(layer "F.SilkS")
		)
		(fp_line
			(start 0.7874 -0.4064)
			(end 0.7874 0.4064)
			(stroke
				(width 0.1524)
				(type default)
			)
			(layer "F.SilkS")
		)
		(fp_line
			(start -0.7874 0.4064)
			(end -0.7874 -0.4064)
			(stroke
				(width 0.1524)
				(type default)
			)
			(layer "F.SilkS")
		)
		(fp_line
			(start -0.7874 -0.4064)
			(end 0.7874 -0.4064)
			(stroke
				(width 0.1524)
				(type default)
			)
			(layer "F.SilkS")
		)
		(fp_line
			(start 0.67945 0.3048)
			(end 0.120396 0.3048)
			(stroke
				(width 0.1)
				(type default)
			)
			(layer "F.Fab")
		)
		(fp_line
			(start 0.67945 -0.3048)
			(end 0.67945 0.3048)
			(stroke
				(width 0.1)
				(type default)
			)
			(layer "F.Fab")
		)
		(fp_line
			(start 0.12065 -0.2794)
			(end 0.12065 -0.3048)
			(stroke
				(width 0.1)
				(type default)
			)
			(layer "F.Fab")
		)
		(fp_line
			(start 0.12065 -0.3048)
			(end 0.67945 -0.3048)
			(stroke
				(width 0.1)
				(type default)
			)
			(layer "F.Fab")
		)
		(fp_line
			(start 0.120396 0.3048)
			(end 0.120396 0.2794)
			(stroke
				(width 0.1)
				(type default)
			)
			(layer "F.Fab")
		)
		(fp_line
			(start 0.120396 0.2794)
			(end -0.12065 0.2794)
			(stroke
				(width 0.1)
				(type default)
			)
			(layer "F.Fab")
		)
		(fp_line
			(start -0.12065 0.3048)
			(end -0.67945 0.3048)
			(stroke
				(width 0.1)
				(type default)
			)
			(layer "F.Fab")
		)
		(fp_line
			(start -0.12065 0.2794)
			(end -0.12065 0.3048)
			(stroke
				(width 0.1)
				(type default)
			)
			(layer "F.Fab")
		)
		(fp_line
			(start -0.12065 -0.2794)
			(end 0.12065 -0.2794)
			(stroke
				(width 0.1)
				(type default)
			)
			(layer "F.Fab")
		)
		(fp_line
			(start -0.12065 -0.305054)
			(end -0.12065 -0.2794)
			(stroke
				(width 0.1)
				(type default)
			)
			(layer "F.Fab")
		)
		(fp_line
			(start -0.67945 0.3048)
			(end -0.67945 -0.305054)
			(stroke
				(width 0.1)
				(type default)
			)
			(layer "F.Fab")
		)
		(fp_line
			(start -0.67945 -0.305054)
			(end -0.12065 -0.305054)
			(stroke
				(width 0.1)
				(type default)
			)
			(layer "F.Fab")
		)
		(pad "1" smd circle
			(at -0.40005 0 180)
			(size 0 0)
			(layers "F.Cu" "F.Mask" "F.Paste")
			(net "HSC_P12V_EN")
		)
		(pad "2" smd circle
			(at 0.40005 0 180)
			(size 0 0)
			(layers "F.Cu" "F.Mask" "F.Paste")
			(net "HSC_P12V_MP5990_EN")
		)
	)
	(footprint ""
		(layer "F.Cu")
		(at 343.514172 -271.703546 -90)
		(property "Reference" "PC144"
			(at 0 0 270)
			(layer "F.SilkS")
			(hide yes)
			(effects
				(font
					(size 1.27 1.27)
				)
			)
		)
		(property "Value" ""
			(at 0 0 270)
			(layer "F.Fab")
			(effects
				(font
					(size 1.27 1.27)
				)
			)
		)
		(duplicate_pad_numbers_are_jumpers no)
		(fp_line
			(start -2.146046 3.400044)
			(end -3.400044 2.146046)
			(stroke
				(width 0.1524)
				(type default)
			)
			(layer "F.SilkS")
		)
		(fp_line
			(start 3.400044 3.400044)
			(end -2.146046 3.400044)
			(stroke
				(width 0.1524)
				(type default)
			)
			(layer "F.SilkS")
		)
		(fp_line
			(start -3.400044 2.146046)
			(end -3.400044 0.9398)
			(stroke
				(width 0.1524)
				(type default)
			)
			(layer "F.SilkS")
		)
		(fp_line
			(start 3.400044 0.9398)
			(end 3.400044 3.400044)
			(stroke
				(width 0.1524)
				(type default)
			)
			(layer "F.SilkS")
		)
		(fp_line
			(start 3.400044 -0.9398)
			(end 3.400044 -3.400044)
			(stroke
				(width 0.1524)
				(type default)
			)
			(layer "F.SilkS")
		)
		(fp_line
			(start -3.400044 -2.146046)
			(end -3.400044 -0.9398)
			(stroke
				(width 0.1524)
				(type default)
			)
			(layer "F.SilkS")
		)
		(fp_line
			(start -2.146046 -3.400044)
			(end -3.400044 -2.146046)
			(stroke
				(width 0.1524)
				(type default)
			)
			(layer "F.SilkS")
		)
		(fp_line
			(start 3.400044 -3.400044)
			(end -2.146046 -3.400044)
			(stroke
				(width 0.1524)
				(type default)
			)
			(layer "F.SilkS")
		)
		(fp_line
			(start -3.400044 3.400044)
			(end 3.400044 3.400044)
			(stroke
				(width 0.1)
				(type default)
			)
			(layer "F.Fab")
		)
		(fp_line
			(start 3.400044 3.400044)
			(end 3.400044 -3.400044)
			(stroke
				(width 0.1)
				(type default)
			)
			(layer "F.Fab")
		)
		(fp_line
			(start -3.400044 -3.400044)
			(end -3.400044 3.400044)
			(stroke
				(width 0.1)
				(type default)
			)
			(layer "F.Fab")
		)
		(fp_line
			(start 3.400044 -3.400044)
			(end -3.400044 -3.400044)
			(stroke
				(width 0.1)
				(type default)
			)
			(layer "F.Fab")
		)
		(pad "1" smd rect
			(at -2.70002 0 180)
			(size 1.6002 3.5052)
			(layers "F.Cu" "F.Mask" "F.Paste")
			(net "SW_P12V_P0V8_PEX2_FLT")
		)
		(pad "2" smd rect
			(at 2.70002 0 180)
			(size 1.6002 3.5052)
			(layers "F.Cu" "F.Mask" "F.Paste")
			(net "GND")
		)
	)
	(footprint ""
		(layer "F.Cu")
		(at 338.074 -162.814)
		(property "Reference" "R4810"
			(at 0 0 0)
			(layer "F.SilkS")
			(hide yes)
			(effects
				(font
					(size 1.27 1.27)
				)
			)
		)
		(property "Value" ""
			(at 0 0 0)
			(layer "F.Fab")
			(effects
				(font
					(size 1.27 1.27)
				)
			)
		)
		(duplicate_pad_numbers_are_jumpers no)
		(fp_line
			(start -0.7874 -0.4064)
			(end 0.7874 -0.4064)
			(stroke
				(width 0.1524)
				(type default)
			)
			(layer "F.SilkS")
		)
		(fp_line
			(start -0.7874 0.4064)
			(end -0.7874 -0.4064)
			(stroke
				(width 0.1524)
				(type default)
			)
			(layer "F.SilkS")
		)
		(fp_line
			(start 0.7874 -0.4064)
			(end 0.7874 0.4064)
			(stroke
				(width 0.1524)
				(type default)
			)
			(layer "F.SilkS")
		)
		(fp_line
			(start 0.7874 0.4064)
			(end -0.7874 0.4064)
			(stroke
				(width 0.1524)
				(type default)
			)
			(layer "F.SilkS")
		)
		(fp_line
			(start -0.67945 -0.305054)
			(end -0.12065 -0.305054)
			(stroke
				(width 0.1)
				(type default)
			)
			(layer "F.Fab")
		)
		(fp_line
			(start -0.67945 0.3048)
			(end -0.67945 -0.305054)
			(stroke
				(width 0.1)
				(type default)
			)
			(layer "F.Fab")
		)
		(fp_line
			(start -0.12065 -0.305054)
			(end -0.12065 -0.2794)
			(stroke
				(width 0.1)
				(type default)
			)
			(layer "F.Fab")
		)
		(fp_line
			(start -0.12065 -0.2794)
			(end 0.12065 -0.2794)
			(stroke
				(width 0.1)
				(type default)
			)
			(layer "F.Fab")
		)
		(fp_line
			(start -0.12065 0.2794)
			(end -0.12065 0.3048)
			(stroke
				(width 0.1)
				(type default)
			)
			(layer "F.Fab")
		)
		(fp_line
			(start -0.12065 0.3048)
			(end -0.67945 0.3048)
			(stroke
				(width 0.1)
				(type default)
			)
			(layer "F.Fab")
		)
		(fp_line
			(start 0.120396 0.2794)
			(end -0.12065 0.2794)
			(stroke
				(width 0.1)
				(type default)
			)
			(layer "F.Fab")
		)
		(fp_line
			(start 0.120396 0.3048)
			(end 0.120396 0.2794)
			(stroke
				(width 0.1)
				(type default)
			)
			(layer "F.Fab")
		)
		(fp_line
			(start 0.12065 -0.3048)
			(end 0.67945 -0.3048)
			(stroke
				(width 0.1)
				(type default)
			)
			(layer "F.Fab")
		)
		(fp_line
			(start 0.12065 -0.2794)
			(end 0.12065 -0.3048)
			(stroke
				(width 0.1)
				(type default)
			)
			(layer "F.Fab")
		)
		(fp_line
			(start 0.67945 -0.3048)
			(end 0.67945 0.3048)
			(stroke
				(width 0.1)
				(type default)
			)
			(layer "F.Fab")
		)
		(fp_line
			(start 0.67945 0.3048)
			(end 0.120396 0.3048)
			(stroke
				(width 0.1)
				(type default)
			)
			(layer "F.Fab")
		)
		(pad "1" smd circle
			(at -0.40005 0)
			(size 0 0)
			(layers "F.Cu" "F.Mask" "F.Paste")
			(net "PEX3_PCA9555_0_INT_N")
		)
		(pad "2" smd circle
			(at 0.40005 0)
			(size 0 0)
			(layers "F.Cu" "F.Mask" "F.Paste")
			(net "P1V8_PEX")
		)
	)
	(footprint ""
		(layer "F.Cu")
		(at 72.51446 -66.32194 90)
		(property "Reference" "R5844"
			(at 0 0 90)
			(layer "F.SilkS")
			(hide yes)
			(effects
				(font
					(size 1.27 1.27)
				)
			)
		)
		(property "Value" ""
			(at 0 0 90)
			(layer "F.Fab")
			(effects
				(font
					(size 1.27 1.27)
				)
			)
		)
		(duplicate_pad_numbers_are_jumpers no)
		(fp_line
			(start 0.7874 -0.4064)
			(end 0.7874 0.4064)
			(stroke
				(width 0.1524)
				(type default)
			)
			(layer "F.SilkS")
		)
		(fp_line
			(start -0.7874 -0.4064)
			(end 0.7874 -0.4064)
			(stroke
				(width 0.1524)
				(type default)
			)
			(layer "F.SilkS")
		)
		(fp_line
			(start 0.7874 0.4064)
			(end -0.7874 0.4064)
			(stroke
				(width 0.1524)
				(type default)
			)
			(layer "F.SilkS")
		)
		(fp_line
			(start -0.7874 0.4064)
			(end -0.7874 -0.4064)
			(stroke
				(width 0.1524)
				(type default)
			)
			(layer "F.SilkS")
		)
		(fp_line
			(start -0.12065 -0.305054)
			(end -0.12065 -0.2794)
			(stroke
				(width 0.1)
				(type default)
			)
			(layer "F.Fab")
		)
		(fp_line
			(start -0.67945 -0.305054)
			(end -0.12065 -0.305054)
			(stroke
				(width 0.1)
				(type default)
			)
			(layer "F.Fab")
		)
		(fp_line
			(start 0.67945 -0.3048)
			(end 0.67945 0.3048)
			(stroke
				(width 0.1)
				(type default)
			)
			(layer "F.Fab")
		)
		(fp_line
			(start 0.12065 -0.3048)
			(end 0.67945 -0.3048)
			(stroke
				(width 0.1)
				(type default)
			)
			(layer "F.Fab")
		)
		(fp_line
			(start 0.12065 -0.2794)
			(end 0.12065 -0.3048)
			(stroke
				(width 0.1)
				(type default)
			)
			(layer "F.Fab")
		)
		(fp_line
			(start -0.12065 -0.2794)
			(end 0.12065 -0.2794)
			(stroke
				(width 0.1)
				(type default)
			)
			(layer "F.Fab")
		)
		(fp_line
			(start 0.120396 0.2794)
			(end -0.12065 0.2794)
			(stroke
				(width 0.1)
				(type default)
			)
			(layer "F.Fab")
		)
		(fp_line
			(start -0.12065 0.2794)
			(end -0.12065 0.3048)
			(stroke
				(width 0.1)
				(type default)
			)
			(layer "F.Fab")
		)
		(fp_line
			(start 0.67945 0.3048)
			(end 0.120396 0.3048)
			(stroke
				(width 0.1)
				(type default)
			)
			(layer "F.Fab")
		)
		(fp_line
			(start 0.120396 0.3048)
			(end 0.120396 0.2794)
			(stroke
				(width 0.1)
				(type default)
			)
			(layer "F.Fab")
		)
		(fp_line
			(start -0.12065 0.3048)
			(end -0.67945 0.3048)
			(stroke
				(width 0.1)
				(type default)
			)
			(layer "F.Fab")
		)
		(fp_line
			(start -0.67945 0.3048)
			(end -0.67945 -0.305054)
			(stroke
				(width 0.1)
				(type default)
			)
			(layer "F.Fab")
		)
		(pad "1" smd circle
			(at -0.40005 0 90)
			(size 0 0)
			(layers "F.Cu" "F.Mask" "F.Paste")
			(net "SSD2_PWR_EN_R")
		)
		(pad "2" smd circle
			(at 0.40005 0 90)
			(size 0 0)
			(layers "F.Cu" "F.Mask" "F.Paste")
			(net "P12V_SSD2_CO_EN")
		)
	)
	(footprint ""
		(layer "F.Cu")
		(at 437.778906 -308.323488 135)
		(property "Reference" "R1457"
			(at 0 0 135)
			(layer "F.SilkS")
			(hide yes)
			(effects
				(font
					(size 1.27 1.27)
				)
			)
		)
		(property "Value" ""
			(at 0 0 135)
			(layer "F.Fab")
			(effects
				(font
					(size 1.27 1.27)
				)
			)
		)
		(duplicate_pad_numbers_are_jumpers no)
		(fp_line
			(start 0.787389 -0.406267)
			(end 0.787389 0.406267)
			(stroke
				(width 0.1524)
				(type default)
			)
			(layer "F.SilkS")
		)
		(fp_line
			(start 0.787389 0.406267)
			(end -0.787389 0.406267)
			(stroke
				(width 0.1524)
				(type default)
			)
			(layer "F.SilkS")
		)
		(fp_line
			(start -0.787389 -0.406267)
			(end 0.787389 -0.406267)
			(stroke
				(width 0.1524)
				(type default)
			)
			(layer "F.SilkS")
		)
		(fp_line
			(start -0.787389 0.406267)
			(end -0.787389 -0.406267)
			(stroke
				(width 0.1524)
				(type default)
			)
			(layer "F.SilkS")
		)
		(fp_line
			(start 0.679446 -0.30479)
			(end 0.679446 0.30479)
			(stroke
				(width 0.1)
				(type default)
			)
			(layer "F.Fab")
		)
		(fp_line
			(start 0.120515 -0.30479)
			(end 0.679446 -0.30479)
			(stroke
				(width 0.1)
				(type default)
			)
			(layer "F.Fab")
		)
		(fp_line
			(start 0.120695 -0.279466)
			(end 0.120515 -0.30479)
			(stroke
				(width 0.1)
				(type default)
			)
			(layer "F.Fab")
		)
		(fp_line
			(start 0.679446 0.30479)
			(end 0.120515 0.30479)
			(stroke
				(width 0.1)
				(type default)
			)
			(layer "F.Fab")
		)
		(fp_line
			(start -0.120695 -0.304969)
			(end -0.120695 -0.279466)
			(stroke
				(width 0.1)
				(type default)
			)
			(layer "F.Fab")
		)
		(fp_line
			(start -0.120695 -0.279466)
			(end 0.120695 -0.279466)
			(stroke
				(width 0.1)
				(type default)
			)
			(layer "F.Fab")
		)
		(fp_line
			(start 0.120335 0.279466)
			(end -0.120695 0.279466)
			(stroke
				(width 0.1)
				(type default)
			)
			(layer "F.Fab")
		)
		(fp_line
			(start 0.120515 0.30479)
			(end 0.120335 0.279466)
			(stroke
				(width 0.1)
				(type default)
			)
			(layer "F.Fab")
		)
		(fp_line
			(start -0.679446 -0.305149)
			(end -0.120695 -0.304969)
			(stroke
				(width 0.1)
				(type default)
			)
			(layer "F.Fab")
		)
		(fp_line
			(start -0.120695 0.279466)
			(end -0.120515 0.30479)
			(stroke
				(width 0.1)
				(type default)
			)
			(layer "F.Fab")
		)
		(fp_line
			(start -0.120515 0.30479)
			(end -0.679446 0.30479)
			(stroke
				(width 0.1)
				(type default)
			)
			(layer "F.Fab")
		)
		(fp_line
			(start -0.679446 0.30479)
			(end -0.679446 -0.305149)
			(stroke
				(width 0.1)
				(type default)
			)
			(layer "F.Fab")
		)
		(pad "1" smd circle
			(at -0.40005 0 135)
			(size 0 0)
			(layers "F.Cu" "F.Mask" "F.Paste")
			(net "GND")
		)
		(pad "2" smd circle
			(at 0.40005 0 135)
			(size 0 0)
			(layers "F.Cu" "F.Mask" "F.Paste")
			(net "PEX3_SPARE7")
		)
	)
	(footprint ""
		(layer "F.Cu")
		(at 434.141372 -343.952322 90)
		(property "Reference" "C802"
			(at 0 0 90)
			(layer "F.SilkS")
			(hide yes)
			(effects
				(font
					(size 1.27 1.27)
				)
			)
		)
		(property "Value" ""
			(at 0 0 90)
			(layer "F.Fab")
			(effects
				(font
					(size 1.27 1.27)
				)
			)
		)
		(duplicate_pad_numbers_are_jumpers no)
		(fp_line
			(start 0.299974 -0.150114)
			(end 0.299974 0.150114)
			(stroke
				(width 0.1)
				(type default)
			)
			(layer "F.Fab")
		)
		(fp_line
			(start -0.299974 -0.150114)
			(end 0.299974 -0.150114)
			(stroke
				(width 0.1)
				(type default)
			)
			(layer "F.Fab")
		)
		(fp_line
			(start 0.299974 0.150114)
			(end -0.299974 0.150114)
			(stroke
				(width 0.1)
				(type default)
			)
			(layer "F.Fab")
		)
		(fp_line
			(start -0.299974 0.150114)
			(end -0.299974 -0.150114)
			(stroke
				(width 0.1)
				(type default)
			)
			(layer "F.Fab")
		)
		(pad "1" smd rect
			(at -0.2667 0 90)
			(size 0.3048 0.381)
			(layers "F.Cu" "F.Mask" "F.Paste")
			(net "P5E_PEX3_STN7_TX_DP<123>")
		)
		(pad "2" smd rect
			(at 0.2667 0 90)
			(size 0.3048 0.381)
			(layers "F.Cu" "F.Mask" "F.Paste")
			(net "P5E_PEX3_STN7_TX_C_DP<123>")
		)
	)
	(footprint ""
		(layer "F.Cu")
		(at 287.439862 -356.244906 90)
		(property "Reference" "C2360"
			(at 0 0 90)
			(layer "F.SilkS")
			(hide yes)
			(effects
				(font
					(size 1.27 1.27)
				)
			)
		)
		(property "Value" ""
			(at 0 0 90)
			(layer "F.Fab")
			(effects
				(font
					(size 1.27 1.27)
				)
			)
		)
		(duplicate_pad_numbers_are_jumpers no)
		(fp_line
			(start 0.299974 -0.150114)
			(end 0.299974 0.150114)
			(stroke
				(width 0.1)
				(type default)
			)
			(layer "F.Fab")
		)
		(fp_line
			(start -0.299974 -0.150114)
			(end 0.299974 -0.150114)
			(stroke
				(width 0.1)
				(type default)
			)
			(layer "F.Fab")
		)
		(fp_line
			(start 0.299974 0.150114)
			(end -0.299974 0.150114)
			(stroke
				(width 0.1)
				(type default)
			)
			(layer "F.Fab")
		)
		(fp_line
			(start -0.299974 0.150114)
			(end -0.299974 -0.150114)
			(stroke
				(width 0.1)
				(type default)
			)
			(layer "F.Fab")
		)
		(pad "1" smd rect
			(at -0.2667 0 90)
			(size 0.3048 0.381)
			(layers "F.Cu" "F.Mask" "F.Paste")
			(net "P5E_PEX2_STN4_TX_DN<70>")
		)
		(pad "2" smd rect
			(at 0.2667 0 90)
			(size 0.3048 0.381)
			(layers "F.Cu" "F.Mask" "F.Paste")
			(net "P5E_PEX2_STN4_TX_C_DN<70>")
		)
	)
	(footprint ""
		(layer "F.Cu")
		(at 252.634496 -33.631886 180)
		(property "Reference" "C488"
			(at 0 0 180)
			(layer "F.SilkS")
			(hide yes)
			(effects
				(font
					(size 1.27 1.27)
				)
			)
		)
		(property "Value" ""
			(at 0 0 180)
			(layer "F.Fab")
			(effects
				(font
					(size 1.27 1.27)
				)
			)
		)
		(duplicate_pad_numbers_are_jumpers no)
		(fp_line
			(start 0.299974 0.150114)
			(end -0.299974 0.150114)
			(stroke
				(width 0.1)
				(type default)
			)
			(layer "F.Fab")
		)
		(fp_line
			(start 0.299974 -0.150114)
			(end 0.299974 0.150114)
			(stroke
				(width 0.1)
				(type default)
			)
			(layer "F.Fab")
		)
		(fp_line
			(start -0.299974 0.150114)
			(end -0.299974 -0.150114)
			(stroke
				(width 0.1)
				(type default)
			)
			(layer "F.Fab")
		)
		(fp_line
			(start -0.299974 -0.150114)
			(end 0.299974 -0.150114)
			(stroke
				(width 0.1)
				(type default)
			)
			(layer "F.Fab")
		)
		(pad "1" smd rect
			(at -0.2667 0 180)
			(size 0.3048 0.381)
			(layers "F.Cu" "F.Mask" "F.Paste")
			(net "P5E_PEX2_STN2_TX_DN<47>")
		)
		(pad "2" smd rect
			(at 0.2667 0 180)
			(size 0.3048 0.381)
			(layers "F.Cu" "F.Mask" "F.Paste")
			(net "P5E_PEX2_STN2_TX_C_DN<47>")
		)
	)
	(footprint ""
		(layer "F.Cu")
		(at 127.658114 -255.210564 180)
		(property "Reference" "C200"
			(at 0 0 180)
			(layer "F.SilkS")
			(hide yes)
			(effects
				(font
					(size 1.27 1.27)
				)
			)
		)
		(property "Value" ""
			(at 0 0 180)
			(layer "F.Fab")
			(effects
				(font
					(size 1.27 1.27)
				)
			)
		)
		(duplicate_pad_numbers_are_jumpers no)
		(fp_line
			(start 0.7874 0.4064)
			(end -0.7874 0.4064)
			(stroke
				(width 0.1524)
				(type default)
			)
			(layer "F.SilkS")
		)
		(fp_line
			(start 0.7874 -0.4064)
			(end 0.7874 0.4064)
			(stroke
				(width 0.1524)
				(type default)
			)
			(layer "F.SilkS")
		)
		(fp_line
			(start -0.7874 0.4064)
			(end -0.7874 -0.4064)
			(stroke
				(width 0.1524)
				(type default)
			)
			(layer "F.SilkS")
		)
		(fp_line
			(start -0.7874 -0.4064)
			(end 0.7874 -0.4064)
			(stroke
				(width 0.1524)
				(type default)
			)
			(layer "F.SilkS")
		)
		(fp_line
			(start 0.67945 0.3048)
			(end 0.120396 0.3048)
			(stroke
				(width 0.1)
				(type default)
			)
			(layer "F.Fab")
		)
		(fp_line
			(start 0.67945 -0.3048)
			(end 0.67945 0.3048)
			(stroke
				(width 0.1)
				(type default)
			)
			(layer "F.Fab")
		)
		(fp_line
			(start 0.12065 -0.2794)
			(end 0.12065 -0.3048)
			(stroke
				(width 0.1)
				(type default)
			)
			(layer "F.Fab")
		)
		(fp_line
			(start 0.12065 -0.3048)
			(end 0.67945 -0.3048)
			(stroke
				(width 0.1)
				(type default)
			)
			(layer "F.Fab")
		)
		(fp_line
			(start 0.120396 0.3048)
			(end 0.120396 0.2794)
			(stroke
				(width 0.1)
				(type default)
			)
			(layer "F.Fab")
		)
		(fp_line
			(start 0.120396 0.2794)
			(end -0.12065 0.2794)
			(stroke
				(width 0.1)
				(type default)
			)
			(layer "F.Fab")
		)
		(fp_line
			(start -0.12065 0.3048)
			(end -0.67945 0.3048)
			(stroke
				(width 0.1)
				(type default)
			)
			(layer "F.Fab")
		)
		(fp_line
			(start -0.12065 0.2794)
			(end -0.12065 0.3048)
			(stroke
				(width 0.1)
				(type default)
			)
			(layer "F.Fab")
		)
		(fp_line
			(start -0.12065 -0.2794)
			(end 0.12065 -0.2794)
			(stroke
				(width 0.1)
				(type default)
			)
			(layer "F.Fab")
		)
		(fp_line
			(start -0.12065 -0.305054)
			(end -0.12065 -0.2794)
			(stroke
				(width 0.1)
				(type default)
			)
			(layer "F.Fab")
		)
		(fp_line
			(start -0.67945 0.3048)
			(end -0.67945 -0.305054)
			(stroke
				(width 0.1)
				(type default)
			)
			(layer "F.Fab")
		)
		(fp_line
			(start -0.67945 -0.305054)
			(end -0.12065 -0.305054)
			(stroke
				(width 0.1)
				(type default)
			)
			(layer "F.Fab")
		)
		(pad "1" smd circle
			(at -0.40005 0 180)
			(size 0 0)
			(layers "F.Cu" "F.Mask" "F.Paste")
			(net "GND")
		)
		(pad "2" smd circle
			(at 0.40005 0 180)
			(size 0 0)
			(layers "F.Cu" "F.Mask" "F.Paste")
			(net "FM_P0V8_PEX0_EN_R")
		)
	)
	(footprint ""
		(layer "F.Cu")
		(at 243.3066 -216.408 -90)
		(property "Reference" "R6589"
			(at 0 0 270)
			(layer "F.SilkS")
			(hide yes)
			(effects
				(font
					(size 1.27 1.27)
				)
			)
		)
		(property "Value" ""
			(at 0 0 270)
			(layer "F.Fab")
			(effects
				(font
					(size 1.27 1.27)
				)
			)
		)
		(duplicate_pad_numbers_are_jumpers no)
		(fp_line
			(start -0.7874 0.4064)
			(end -0.7874 -0.4064)
			(stroke
				(width 0.1524)
				(type default)
			)
			(layer "F.SilkS")
		)
		(fp_line
			(start 0.7874 0.4064)
			(end -0.7874 0.4064)
			(stroke
				(width 0.1524)
				(type default)
			)
			(layer "F.SilkS")
		)
		(fp_line
			(start -0.7874 -0.4064)
			(end 0.7874 -0.4064)
			(stroke
				(width 0.1524)
				(type default)
			)
			(layer "F.SilkS")
		)
		(fp_line
			(start 0.7874 -0.4064)
			(end 0.7874 0.4064)
			(stroke
				(width 0.1524)
				(type default)
			)
			(layer "F.SilkS")
		)
		(fp_line
			(start -0.67945 0.3048)
			(end -0.67945 -0.305054)
			(stroke
				(width 0.1)
				(type default)
			)
			(layer "F.Fab")
		)
		(fp_line
			(start -0.12065 0.3048)
			(end -0.67945 0.3048)
			(stroke
				(width 0.1)
				(type default)
			)
			(layer "F.Fab")
		)
		(fp_line
			(start 0.120396 0.3048)
			(end 0.120396 0.2794)
			(stroke
				(width 0.1)
				(type default)
			)
			(layer "F.Fab")
		)
		(fp_line
			(start 0.67945 0.3048)
			(end 0.120396 0.3048)
			(stroke
				(width 0.1)
				(type default)
			)
			(layer "F.Fab")
		)
		(fp_line
			(start -0.12065 0.2794)
			(end -0.12065 0.3048)
			(stroke
				(width 0.1)
				(type default)
			)
			(layer "F.Fab")
		)
		(fp_line
			(start 0.120396 0.2794)
			(end -0.12065 0.2794)
			(stroke
				(width 0.1)
				(type default)
			)
			(layer "F.Fab")
		)
		(fp_line
			(start -0.12065 -0.2794)
			(end 0.12065 -0.2794)
			(stroke
				(width 0.1)
				(type default)
			)
			(layer "F.Fab")
		)
		(fp_line
			(start 0.12065 -0.2794)
			(end 0.12065 -0.3048)
			(stroke
				(width 0.1)
				(type default)
			)
			(layer "F.Fab")
		)
		(fp_line
			(start 0.12065 -0.3048)
			(end 0.67945 -0.3048)
			(stroke
				(width 0.1)
				(type default)
			)
			(layer "F.Fab")
		)
		(fp_line
			(start 0.67945 -0.3048)
			(end 0.67945 0.3048)
			(stroke
				(width 0.1)
				(type default)
			)
			(layer "F.Fab")
		)
		(fp_line
			(start -0.67945 -0.305054)
			(end -0.12065 -0.305054)
			(stroke
				(width 0.1)
				(type default)
			)
			(layer "F.Fab")
		)
		(fp_line
			(start -0.12065 -0.305054)
			(end -0.12065 -0.2794)
			(stroke
				(width 0.1)
				(type default)
			)
			(layer "F.Fab")
		)
		(pad "1" smd circle
			(at -0.40005 0 270)
			(size 0 0)
			(layers "F.Cu" "F.Mask" "F.Paste")
			(net "P1V8_PLL0_PEX0")
		)
		(pad "2" smd circle
			(at 0.40005 0 270)
			(size 0 0)
			(layers "F.Cu" "F.Mask" "F.Paste")
			(net "P1V8_PLL0_PEX0_SCALED")
		)
	)
	(footprint ""
		(layer "F.Cu")
		(at 404.12924 -117.5512)
		(property "Reference" "R311"
			(at 0 0 0)
			(layer "F.SilkS")
			(hide yes)
			(effects
				(font
					(size 1.27 1.27)
				)
			)
		)
		(property "Value" ""
			(at 0 0 0)
			(layer "F.Fab")
			(effects
				(font
					(size 1.27 1.27)
				)
			)
		)
		(duplicate_pad_numbers_are_jumpers no)
		(fp_line
			(start -0.7874 -0.4064)
			(end 0.7874 -0.4064)
			(stroke
				(width 0.1524)
				(type default)
			)
			(layer "F.SilkS")
		)
		(fp_line
			(start -0.7874 0.4064)
			(end -0.7874 -0.4064)
			(stroke
				(width 0.1524)
				(type default)
			)
			(layer "F.SilkS")
		)
		(fp_line
			(start 0.7874 -0.4064)
			(end 0.7874 0.4064)
			(stroke
				(width 0.1524)
				(type default)
			)
			(layer "F.SilkS")
		)
		(fp_line
			(start 0.7874 0.4064)
			(end -0.7874 0.4064)
			(stroke
				(width 0.1524)
				(type default)
			)
			(layer "F.SilkS")
		)
		(fp_line
			(start -0.67945 -0.305054)
			(end -0.12065 -0.305054)
			(stroke
				(width 0.1)
				(type default)
			)
			(layer "F.Fab")
		)
		(fp_line
			(start -0.67945 0.3048)
			(end -0.67945 -0.305054)
			(stroke
				(width 0.1)
				(type default)
			)
			(layer "F.Fab")
		)
		(fp_line
			(start -0.12065 -0.305054)
			(end -0.12065 -0.2794)
			(stroke
				(width 0.1)
				(type default)
			)
			(layer "F.Fab")
		)
		(fp_line
			(start -0.12065 -0.2794)
			(end 0.12065 -0.2794)
			(stroke
				(width 0.1)
				(type default)
			)
			(layer "F.Fab")
		)
		(fp_line
			(start -0.12065 0.2794)
			(end -0.12065 0.3048)
			(stroke
				(width 0.1)
				(type default)
			)
			(layer "F.Fab")
		)
		(fp_line
			(start -0.12065 0.3048)
			(end -0.67945 0.3048)
			(stroke
				(width 0.1)
				(type default)
			)
			(layer "F.Fab")
		)
		(fp_line
			(start 0.120396 0.2794)
			(end -0.12065 0.2794)
			(stroke
				(width 0.1)
				(type default)
			)
			(layer "F.Fab")
		)
		(fp_line
			(start 0.120396 0.3048)
			(end 0.120396 0.2794)
			(stroke
				(width 0.1)
				(type default)
			)
			(layer "F.Fab")
		)
		(fp_line
			(start 0.12065 -0.3048)
			(end 0.67945 -0.3048)
			(stroke
				(width 0.1)
				(type default)
			)
			(layer "F.Fab")
		)
		(fp_line
			(start 0.12065 -0.2794)
			(end 0.12065 -0.3048)
			(stroke
				(width 0.1)
				(type default)
			)
			(layer "F.Fab")
		)
		(fp_line
			(start 0.67945 -0.3048)
			(end 0.67945 0.3048)
			(stroke
				(width 0.1)
				(type default)
			)
			(layer "F.Fab")
		)
		(fp_line
			(start 0.67945 0.3048)
			(end 0.120396 0.3048)
			(stroke
				(width 0.1)
				(type default)
			)
			(layer "F.Fab")
		)
		(pad "1" smd circle
			(at -0.40005 0)
			(size 0 0)
			(layers "F.Cu" "F.Mask" "F.Paste")
			(net "PRSNTB1_NIC6_N")
		)
		(pad "2" smd circle
			(at 0.40005 0)
			(size 0 0)
			(layers "F.Cu" "F.Mask" "F.Paste")
			(net "P3V3_AUX")
		)
	)
	(footprint ""
		(layer "F.Cu")
		(at 323.368924 -123.067318 90)
		(property "Reference" "PC467"
			(at 0 0 90)
			(layer "F.SilkS")
			(hide yes)
			(effects
				(font
					(size 1.27 1.27)
				)
			)
		)
		(property "Value" ""
			(at 0 0 90)
			(layer "F.Fab")
			(effects
				(font
					(size 1.27 1.27)
				)
			)
		)
		(duplicate_pad_numbers_are_jumpers no)
		(fp_line
			(start 1.524 -0.762)
			(end 1.524 0.762)
			(stroke
				(width 0.1524)
				(type default)
			)
			(layer "F.SilkS")
		)
		(fp_line
			(start -1.524 -0.762)
			(end 1.524 -0.762)
			(stroke
				(width 0.1524)
				(type default)
			)
			(layer "F.SilkS")
		)
		(fp_line
			(start 1.524 0.762)
			(end -1.524 0.762)
			(stroke
				(width 0.1524)
				(type default)
			)
			(layer "F.SilkS")
		)
		(fp_line
			(start -1.524 0.762)
			(end -1.524 -0.762)
			(stroke
				(width 0.1524)
				(type default)
			)
			(layer "F.SilkS")
		)
		(fp_line
			(start 1.1049 -0.724916)
			(end -1.1049 -0.724916)
			(stroke
				(width 0.1)
				(type default)
			)
			(layer "F.Fab")
		)
		(fp_line
			(start -1.1049 -0.724916)
			(end -1.1049 0.724916)
			(stroke
				(width 0.1)
				(type default)
			)
			(layer "F.Fab")
		)
		(fp_line
			(start 1.1049 0.724916)
			(end 1.1049 -0.724916)
			(stroke
				(width 0.1)
				(type default)
			)
			(layer "F.Fab")
		)
		(fp_line
			(start -1.1049 0.724916)
			(end 1.1049 0.724916)
			(stroke
				(width 0.1)
				(type default)
			)
			(layer "F.Fab")
		)
		(pad "1" smd rect
			(at -0.889 0 270)
			(size 1.016 1.27)
			(layers "F.Cu" "F.Mask" "F.Paste")
			(net "P3V3_NIC5")
		)
		(pad "2" smd rect
			(at 0.889 0 270)
			(size 1.016 1.27)
			(layers "F.Cu" "F.Mask" "F.Paste")
			(net "GND")
		)
	)
	(footprint ""
		(layer "F.Cu")
		(at 245.625112 -254.00889 -90)
		(property "Reference" "C4342"
			(at 0 0 270)
			(layer "F.SilkS")
			(hide yes)
			(effects
				(font
					(size 1.27 1.27)
				)
			)
		)
		(property "Value" ""
			(at 0 0 270)
			(layer "F.Fab")
			(effects
				(font
					(size 1.27 1.27)
				)
			)
		)
		(duplicate_pad_numbers_are_jumpers no)
		(fp_line
			(start -1.524 0.762)
			(end -1.524 -0.762)
			(stroke
				(width 0.1524)
				(type default)
			)
			(layer "F.SilkS")
		)
		(fp_line
			(start 1.524 0.762)
			(end -1.524 0.762)
			(stroke
				(width 0.1524)
				(type default)
			)
			(layer "F.SilkS")
		)
		(fp_line
			(start -1.524 -0.762)
			(end 1.524 -0.762)
			(stroke
				(width 0.1524)
				(type default)
			)
			(layer "F.SilkS")
		)
		(fp_line
			(start 1.524 -0.762)
			(end 1.524 0.762)
			(stroke
				(width 0.1524)
				(type default)
			)
			(layer "F.SilkS")
		)
		(fp_line
			(start -1.1049 0.724916)
			(end 1.1049 0.724916)
			(stroke
				(width 0.1)
				(type default)
			)
			(layer "F.Fab")
		)
		(fp_line
			(start 1.1049 0.724916)
			(end 1.1049 -0.724916)
			(stroke
				(width 0.1)
				(type default)
			)
			(layer "F.Fab")
		)
		(fp_line
			(start -1.1049 -0.724916)
			(end -1.1049 0.724916)
			(stroke
				(width 0.1)
				(type default)
			)
			(layer "F.Fab")
		)
		(fp_line
			(start 1.1049 -0.724916)
			(end -1.1049 -0.724916)
			(stroke
				(width 0.1)
				(type default)
			)
			(layer "F.Fab")
		)
		(pad "1" smd rect
			(at -0.889 0 90)
			(size 1.016 1.27)
			(layers "F.Cu" "F.Mask" "F.Paste")
			(net "P1V25_SERDES_VDDPLL_PEX2_C4")
		)
		(pad "2" smd rect
			(at 0.889 0 90)
			(size 1.016 1.27)
			(layers "F.Cu" "F.Mask" "F.Paste")
			(net "GND")
		)
		(zone
			(layer "F.Cu")
			(hatch none 0.5)
			(connect_pads
				(clearance 0)
			)
			(min_thickness 0.25)
			(keepout
				(tracks not_allowed)
				(vias allowed)
				(pads allowed)
				(copperpour not_allowed)
				(footprints allowed)
			)
			(placement
				(enabled no)
				(sheetname "")
			)
			(fill
				(thermal_gap 0.5)
				(thermal_bridge_width 0.5)
				(island_removal_mode 0)
			)
			(polygon
				(pts
					(xy 246.350028 -254.33909) (xy 244.900196 -254.33909) (xy 244.900196 -253.67869) (xy 246.350028 -253.67869)
				)
			)
		)
	)
	(footprint ""
		(layer "F.Cu")
		(at 162.225482 -42.849038 180)
		(property "Reference" "R568"
			(at 0 0 180)
			(layer "F.SilkS")
			(hide yes)
			(effects
				(font
					(size 1.27 1.27)
				)
			)
		)
		(property "Value" ""
			(at 0 0 180)
			(layer "F.Fab")
			(effects
				(font
					(size 1.27 1.27)
				)
			)
		)
		(duplicate_pad_numbers_are_jumpers no)
		(fp_line
			(start 0.7874 0.4064)
			(end -0.7874 0.4064)
			(stroke
				(width 0.1524)
				(type default)
			)
			(layer "F.SilkS")
		)
		(fp_line
			(start 0.7874 -0.4064)
			(end 0.7874 0.4064)
			(stroke
				(width 0.1524)
				(type default)
			)
			(layer "F.SilkS")
		)
		(fp_line
			(start -0.7874 0.4064)
			(end -0.7874 -0.4064)
			(stroke
				(width 0.1524)
				(type default)
			)
			(layer "F.SilkS")
		)
		(fp_line
			(start -0.7874 -0.4064)
			(end 0.7874 -0.4064)
			(stroke
				(width 0.1524)
				(type default)
			)
			(layer "F.SilkS")
		)
		(fp_line
			(start 0.67945 0.3048)
			(end 0.120396 0.3048)
			(stroke
				(width 0.1)
				(type default)
			)
			(layer "F.Fab")
		)
		(fp_line
			(start 0.67945 -0.3048)
			(end 0.67945 0.3048)
			(stroke
				(width 0.1)
				(type default)
			)
			(layer "F.Fab")
		)
		(fp_line
			(start 0.12065 -0.2794)
			(end 0.12065 -0.3048)
			(stroke
				(width 0.1)
				(type default)
			)
			(layer "F.Fab")
		)
		(fp_line
			(start 0.12065 -0.3048)
			(end 0.67945 -0.3048)
			(stroke
				(width 0.1)
				(type default)
			)
			(layer "F.Fab")
		)
		(fp_line
			(start 0.120396 0.3048)
			(end 0.120396 0.2794)
			(stroke
				(width 0.1)
				(type default)
			)
			(layer "F.Fab")
		)
		(fp_line
			(start 0.120396 0.2794)
			(end -0.12065 0.2794)
			(stroke
				(width 0.1)
				(type default)
			)
			(layer "F.Fab")
		)
		(fp_line
			(start -0.12065 0.3048)
			(end -0.67945 0.3048)
			(stroke
				(width 0.1)
				(type default)
			)
			(layer "F.Fab")
		)
		(fp_line
			(start -0.12065 0.2794)
			(end -0.12065 0.3048)
			(stroke
				(width 0.1)
				(type default)
			)
			(layer "F.Fab")
		)
		(fp_line
			(start -0.12065 -0.2794)
			(end 0.12065 -0.2794)
			(stroke
				(width 0.1)
				(type default)
			)
			(layer "F.Fab")
		)
		(fp_line
			(start -0.12065 -0.305054)
			(end -0.12065 -0.2794)
			(stroke
				(width 0.1)
				(type default)
			)
			(layer "F.Fab")
		)
		(fp_line
			(start -0.67945 0.3048)
			(end -0.67945 -0.305054)
			(stroke
				(width 0.1)
				(type default)
			)
			(layer "F.Fab")
		)
		(fp_line
			(start -0.67945 -0.305054)
			(end -0.12065 -0.305054)
			(stroke
				(width 0.1)
				(type default)
			)
			(layer "F.Fab")
		)
		(pad "1" smd circle
			(at -0.40005 0 180)
			(size 0 0)
			(layers "F.Cu" "F.Mask" "F.Paste")
			(net "P12V_SSD5_R")
		)
		(pad "2" smd circle
			(at 0.40005 0 180)
			(size 0 0)
			(layers "F.Cu" "F.Mask" "F.Paste")
			(net "P12V_SSD5_VIN_P")
		)
	)
	(footprint ""
		(layer "F.Cu")
		(at 447.802 -402.209 -90)
		(property "Reference" "R5588"
			(at 0 0 270)
			(layer "F.SilkS")
			(hide yes)
			(effects
				(font
					(size 1.27 1.27)
				)
			)
		)
		(property "Value" ""
			(at 0 0 270)
			(layer "F.Fab")
			(effects
				(font
					(size 1.27 1.27)
				)
			)
		)
		(duplicate_pad_numbers_are_jumpers no)
		(fp_line
			(start -0.7874 0.4064)
			(end -0.7874 -0.4064)
			(stroke
				(width 0.1524)
				(type default)
			)
			(layer "F.SilkS")
		)
		(fp_line
			(start 0.7874 0.4064)
			(end -0.7874 0.4064)
			(stroke
				(width 0.1524)
				(type default)
			)
			(layer "F.SilkS")
		)
		(fp_line
			(start -0.7874 -0.4064)
			(end 0.7874 -0.4064)
			(stroke
				(width 0.1524)
				(type default)
			)
			(layer "F.SilkS")
		)
		(fp_line
			(start 0.7874 -0.4064)
			(end 0.7874 0.4064)
			(stroke
				(width 0.1524)
				(type default)
			)
			(layer "F.SilkS")
		)
		(fp_line
			(start -0.67945 0.3048)
			(end -0.67945 -0.305054)
			(stroke
				(width 0.1)
				(type default)
			)
			(layer "F.Fab")
		)
		(fp_line
			(start -0.12065 0.3048)
			(end -0.67945 0.3048)
			(stroke
				(width 0.1)
				(type default)
			)
			(layer "F.Fab")
		)
		(fp_line
			(start 0.120396 0.3048)
			(end 0.120396 0.2794)
			(stroke
				(width 0.1)
				(type default)
			)
			(layer "F.Fab")
		)
		(fp_line
			(start 0.67945 0.3048)
			(end 0.120396 0.3048)
			(stroke
				(width 0.1)
				(type default)
			)
			(layer "F.Fab")
		)
		(fp_line
			(start -0.12065 0.2794)
			(end -0.12065 0.3048)
			(stroke
				(width 0.1)
				(type default)
			)
			(layer "F.Fab")
		)
		(fp_line
			(start 0.120396 0.2794)
			(end -0.12065 0.2794)
			(stroke
				(width 0.1)
				(type default)
			)
			(layer "F.Fab")
		)
		(fp_line
			(start -0.12065 -0.2794)
			(end 0.12065 -0.2794)
			(stroke
				(width 0.1)
				(type default)
			)
			(layer "F.Fab")
		)
		(fp_line
			(start 0.12065 -0.2794)
			(end 0.12065 -0.3048)
			(stroke
				(width 0.1)
				(type default)
			)
			(layer "F.Fab")
		)
		(fp_line
			(start 0.12065 -0.3048)
			(end 0.67945 -0.3048)
			(stroke
				(width 0.1)
				(type default)
			)
			(layer "F.Fab")
		)
		(fp_line
			(start 0.67945 -0.3048)
			(end 0.67945 0.3048)
			(stroke
				(width 0.1)
				(type default)
			)
			(layer "F.Fab")
		)
		(fp_line
			(start -0.67945 -0.305054)
			(end -0.12065 -0.305054)
			(stroke
				(width 0.1)
				(type default)
			)
			(layer "F.Fab")
		)
		(fp_line
			(start -0.12065 -0.305054)
			(end -0.12065 -0.2794)
			(stroke
				(width 0.1)
				(type default)
			)
			(layer "F.Fab")
		)
		(pad "1" smd circle
			(at -0.40005 0 270)
			(size 0 0)
			(layers "F.Cu" "F.Mask" "F.Paste")
			(net "SMB_BIC_I2C6_MUX_THERMAL_R1_SCL")
		)
		(pad "2" smd circle
			(at 0.40005 0 270)
			(size 0 0)
			(layers "F.Cu" "F.Mask" "F.Paste")
			(net "SMB_LM75_0_SCL")
		)
	)
	(footprint ""
		(layer "F.Cu")
		(at 268.838426 -112.809782)
		(property "Reference" "C472"
			(at 0 0 0)
			(layer "F.SilkS")
			(hide yes)
			(effects
				(font
					(size 1.27 1.27)
				)
			)
		)
		(property "Value" ""
			(at 0 0 0)
			(layer "F.Fab")
			(effects
				(font
					(size 1.27 1.27)
				)
			)
		)
		(duplicate_pad_numbers_are_jumpers no)
		(fp_line
			(start -0.299974 -0.150114)
			(end 0.299974 -0.150114)
			(stroke
				(width 0.1)
				(type default)
			)
			(layer "F.Fab")
		)
		(fp_line
			(start -0.299974 0.150114)
			(end -0.299974 -0.150114)
			(stroke
				(width 0.1)
				(type default)
			)
			(layer "F.Fab")
		)
		(fp_line
			(start 0.299974 -0.150114)
			(end 0.299974 0.150114)
			(stroke
				(width 0.1)
				(type default)
			)
			(layer "F.Fab")
		)
		(fp_line
			(start 0.299974 0.150114)
			(end -0.299974 0.150114)
			(stroke
				(width 0.1)
				(type default)
			)
			(layer "F.Fab")
		)
		(pad "1" smd rect
			(at -0.2667 0)
			(size 0.3048 0.381)
			(layers "F.Cu" "F.Mask" "F.Paste")
			(net "P5E_PEX2_STN1_TX_DP<23>")
		)
		(pad "2" smd rect
			(at 0.2667 0)
			(size 0.3048 0.381)
			(layers "F.Cu" "F.Mask" "F.Paste")
			(net "P5E_PEX2_STN1_TX_C_DP<23>")
		)
	)
	(footprint ""
		(layer "F.Cu")
		(at 7.613396 -135.058404 180)
		(property "Reference" "C2853"
			(at 0 0 180)
			(layer "F.SilkS")
			(hide yes)
			(effects
				(font
					(size 1.27 1.27)
				)
			)
		)
		(property "Value" ""
			(at 0 0 180)
			(layer "F.Fab")
			(effects
				(font
					(size 1.27 1.27)
				)
			)
		)
		(duplicate_pad_numbers_are_jumpers no)
		(fp_line
			(start 0.7874 0.4064)
			(end -0.7874 0.4064)
			(stroke
				(width 0.1524)
				(type default)
			)
			(layer "F.SilkS")
		)
		(fp_line
			(start 0.7874 -0.4064)
			(end 0.7874 0.4064)
			(stroke
				(width 0.1524)
				(type default)
			)
			(layer "F.SilkS")
		)
		(fp_line
			(start -0.7874 0.4064)
			(end -0.7874 -0.4064)
			(stroke
				(width 0.1524)
				(type default)
			)
			(layer "F.SilkS")
		)
		(fp_line
			(start -0.7874 -0.4064)
			(end 0.7874 -0.4064)
			(stroke
				(width 0.1524)
				(type default)
			)
			(layer "F.SilkS")
		)
		(fp_line
			(start 0.67945 0.3048)
			(end 0.120396 0.3048)
			(stroke
				(width 0.1)
				(type default)
			)
			(layer "F.Fab")
		)
		(fp_line
			(start 0.67945 -0.3048)
			(end 0.67945 0.3048)
			(stroke
				(width 0.1)
				(type default)
			)
			(layer "F.Fab")
		)
		(fp_line
			(start 0.12065 -0.2794)
			(end 0.12065 -0.3048)
			(stroke
				(width 0.1)
				(type default)
			)
			(layer "F.Fab")
		)
		(fp_line
			(start 0.12065 -0.3048)
			(end 0.67945 -0.3048)
			(stroke
				(width 0.1)
				(type default)
			)
			(layer "F.Fab")
		)
		(fp_line
			(start 0.120396 0.3048)
			(end 0.120396 0.2794)
			(stroke
				(width 0.1)
				(type default)
			)
			(layer "F.Fab")
		)
		(fp_line
			(start 0.120396 0.2794)
			(end -0.12065 0.2794)
			(stroke
				(width 0.1)
				(type default)
			)
			(layer "F.Fab")
		)
		(fp_line
			(start -0.12065 0.3048)
			(end -0.67945 0.3048)
			(stroke
				(width 0.1)
				(type default)
			)
			(layer "F.Fab")
		)
		(fp_line
			(start -0.12065 0.2794)
			(end -0.12065 0.3048)
			(stroke
				(width 0.1)
				(type default)
			)
			(layer "F.Fab")
		)
		(fp_line
			(start -0.12065 -0.2794)
			(end 0.12065 -0.2794)
			(stroke
				(width 0.1)
				(type default)
			)
			(layer "F.Fab")
		)
		(fp_line
			(start -0.12065 -0.305054)
			(end -0.12065 -0.2794)
			(stroke
				(width 0.1)
				(type default)
			)
			(layer "F.Fab")
		)
		(fp_line
			(start -0.67945 0.3048)
			(end -0.67945 -0.305054)
			(stroke
				(width 0.1)
				(type default)
			)
			(layer "F.Fab")
		)
		(fp_line
			(start -0.67945 -0.305054)
			(end -0.12065 -0.305054)
			(stroke
				(width 0.1)
				(type default)
			)
			(layer "F.Fab")
		)
		(pad "1" smd circle
			(at -0.40005 0 180)
			(size 0 0)
			(layers "F.Cu" "F.Mask" "F.Paste")
			(net "P12V_NIC0_EN_R")
		)
		(pad "2" smd circle
			(at 0.40005 0 180)
			(size 0 0)
			(layers "F.Cu" "F.Mask" "F.Paste")
			(net "GND")
		)
	)
	(footprint ""
		(layer "F.Cu")
		(at 364.731808 -162.003994 -90)
		(property "Reference" "R958"
			(at 0 0 270)
			(layer "F.SilkS")
			(hide yes)
			(effects
				(font
					(size 1.27 1.27)
				)
			)
		)
		(property "Value" ""
			(at 0 0 270)
			(layer "F.Fab")
			(effects
				(font
					(size 1.27 1.27)
				)
			)
		)
		(duplicate_pad_numbers_are_jumpers no)
		(fp_line
			(start -0.7874 0.4064)
			(end -0.7874 -0.4064)
			(stroke
				(width 0.1524)
				(type default)
			)
			(layer "F.SilkS")
		)
		(fp_line
			(start 0.7874 0.4064)
			(end -0.7874 0.4064)
			(stroke
				(width 0.1524)
				(type default)
			)
			(layer "F.SilkS")
		)
		(fp_line
			(start -0.7874 -0.4064)
			(end 0.7874 -0.4064)
			(stroke
				(width 0.1524)
				(type default)
			)
			(layer "F.SilkS")
		)
		(fp_line
			(start 0.7874 -0.4064)
			(end 0.7874 0.4064)
			(stroke
				(width 0.1524)
				(type default)
			)
			(layer "F.SilkS")
		)
		(fp_line
			(start -0.67945 0.3048)
			(end -0.67945 -0.305054)
			(stroke
				(width 0.1)
				(type default)
			)
			(layer "F.Fab")
		)
		(fp_line
			(start -0.12065 0.3048)
			(end -0.67945 0.3048)
			(stroke
				(width 0.1)
				(type default)
			)
			(layer "F.Fab")
		)
		(fp_line
			(start 0.120396 0.3048)
			(end 0.120396 0.2794)
			(stroke
				(width 0.1)
				(type default)
			)
			(layer "F.Fab")
		)
		(fp_line
			(start 0.67945 0.3048)
			(end 0.120396 0.3048)
			(stroke
				(width 0.1)
				(type default)
			)
			(layer "F.Fab")
		)
		(fp_line
			(start -0.12065 0.2794)
			(end -0.12065 0.3048)
			(stroke
				(width 0.1)
				(type default)
			)
			(layer "F.Fab")
		)
		(fp_line
			(start 0.120396 0.2794)
			(end -0.12065 0.2794)
			(stroke
				(width 0.1)
				(type default)
			)
			(layer "F.Fab")
		)
		(fp_line
			(start -0.12065 -0.2794)
			(end 0.12065 -0.2794)
			(stroke
				(width 0.1)
				(type default)
			)
			(layer "F.Fab")
		)
		(fp_line
			(start 0.12065 -0.2794)
			(end 0.12065 -0.3048)
			(stroke
				(width 0.1)
				(type default)
			)
			(layer "F.Fab")
		)
		(fp_line
			(start 0.12065 -0.3048)
			(end 0.67945 -0.3048)
			(stroke
				(width 0.1)
				(type default)
			)
			(layer "F.Fab")
		)
		(fp_line
			(start 0.67945 -0.3048)
			(end 0.67945 0.3048)
			(stroke
				(width 0.1)
				(type default)
			)
			(layer "F.Fab")
		)
		(fp_line
			(start -0.67945 -0.305054)
			(end -0.12065 -0.305054)
			(stroke
				(width 0.1)
				(type default)
			)
			(layer "F.Fab")
		)
		(fp_line
			(start -0.12065 -0.305054)
			(end -0.12065 -0.2794)
			(stroke
				(width 0.1)
				(type default)
			)
			(layer "F.Fab")
		)
		(pad "1" smd circle
			(at -0.40005 0 270)
			(size 0 0)
			(layers "F.Cu" "F.Mask" "F.Paste")
			(net "HP_NIC6_EN")
		)
		(pad "2" smd circle
			(at 0.40005 0 270)
			(size 0 0)
			(layers "F.Cu" "F.Mask" "F.Paste")
			(net "P12V_NIC6_CO_EN")
		)
	)
	(footprint ""
		(layer "F.Cu")
		(at 367.54689 -37.47516)
		(property "Reference" "R6111"
			(at 0 0 0)
			(layer "F.SilkS")
			(hide yes)
			(effects
				(font
					(size 1.27 1.27)
				)
			)
		)
		(property "Value" ""
			(at 0 0 0)
			(layer "F.Fab")
			(effects
				(font
					(size 1.27 1.27)
				)
			)
		)
		(duplicate_pad_numbers_are_jumpers no)
		(fp_line
			(start -0.7874 -0.4064)
			(end 0.7874 -0.4064)
			(stroke
				(width 0.1524)
				(type default)
			)
			(layer "F.SilkS")
		)
		(fp_line
			(start -0.7874 0.4064)
			(end -0.7874 -0.4064)
			(stroke
				(width 0.1524)
				(type default)
			)
			(layer "F.SilkS")
		)
		(fp_line
			(start 0.7874 -0.4064)
			(end 0.7874 0.4064)
			(stroke
				(width 0.1524)
				(type default)
			)
			(layer "F.SilkS")
		)
		(fp_line
			(start 0.7874 0.4064)
			(end -0.7874 0.4064)
			(stroke
				(width 0.1524)
				(type default)
			)
			(layer "F.SilkS")
		)
		(fp_line
			(start -0.67945 -0.305054)
			(end -0.12065 -0.305054)
			(stroke
				(width 0.1)
				(type default)
			)
			(layer "F.Fab")
		)
		(fp_line
			(start -0.67945 0.3048)
			(end -0.67945 -0.305054)
			(stroke
				(width 0.1)
				(type default)
			)
			(layer "F.Fab")
		)
		(fp_line
			(start -0.12065 -0.305054)
			(end -0.12065 -0.2794)
			(stroke
				(width 0.1)
				(type default)
			)
			(layer "F.Fab")
		)
		(fp_line
			(start -0.12065 -0.2794)
			(end 0.12065 -0.2794)
			(stroke
				(width 0.1)
				(type default)
			)
			(layer "F.Fab")
		)
		(fp_line
			(start -0.12065 0.2794)
			(end -0.12065 0.3048)
			(stroke
				(width 0.1)
				(type default)
			)
			(layer "F.Fab")
		)
		(fp_line
			(start -0.12065 0.3048)
			(end -0.67945 0.3048)
			(stroke
				(width 0.1)
				(type default)
			)
			(layer "F.Fab")
		)
		(fp_line
			(start 0.120396 0.2794)
			(end -0.12065 0.2794)
			(stroke
				(width 0.1)
				(type default)
			)
			(layer "F.Fab")
		)
		(fp_line
			(start 0.120396 0.3048)
			(end 0.120396 0.2794)
			(stroke
				(width 0.1)
				(type default)
			)
			(layer "F.Fab")
		)
		(fp_line
			(start 0.12065 -0.3048)
			(end 0.67945 -0.3048)
			(stroke
				(width 0.1)
				(type default)
			)
			(layer "F.Fab")
		)
		(fp_line
			(start 0.12065 -0.2794)
			(end 0.12065 -0.3048)
			(stroke
				(width 0.1)
				(type default)
			)
			(layer "F.Fab")
		)
		(fp_line
			(start 0.67945 -0.3048)
			(end 0.67945 0.3048)
			(stroke
				(width 0.1)
				(type default)
			)
			(layer "F.Fab")
		)
		(fp_line
			(start 0.67945 0.3048)
			(end 0.120396 0.3048)
			(stroke
				(width 0.1)
				(type default)
			)
			(layer "F.Fab")
		)
		(pad "1" smd circle
			(at -0.40005 0)
			(size 0 0)
			(layers "F.Cu" "F.Mask" "F.Paste")
			(net "P3V3_SSD13")
		)
		(pad "2" smd circle
			(at 0.40005 0)
			(size 0 0)
			(layers "F.Cu" "F.Mask" "F.Paste")
			(net "P3V3_SSD13_PG_G1")
		)
	)
	(footprint ""
		(layer "F.Cu")
		(at 262.088122 -257.64871 -90)
		(property "Reference" "C3399"
			(at 0 0 270)
			(layer "F.SilkS")
			(hide yes)
			(effects
				(font
					(size 1.27 1.27)
				)
			)
		)
		(property "Value" ""
			(at 0 0 270)
			(layer "F.Fab")
			(effects
				(font
					(size 1.27 1.27)
				)
			)
		)
		(duplicate_pad_numbers_are_jumpers no)
		(fp_line
			(start -1.2954 0.5842)
			(end -1.2954 -0.5842)
			(stroke
				(width 0.1524)
				(type default)
			)
			(layer "F.SilkS")
		)
		(fp_line
			(start 1.2954 0.5842)
			(end -1.2954 0.5842)
			(stroke
				(width 0.1524)
				(type default)
			)
			(layer "F.SilkS")
		)
		(fp_line
			(start -1.2954 -0.5842)
			(end 1.2954 -0.5842)
			(stroke
				(width 0.1524)
				(type default)
			)
			(layer "F.SilkS")
		)
		(fp_line
			(start 1.2954 -0.5842)
			(end 1.2954 0.5842)
			(stroke
				(width 0.1524)
				(type default)
			)
			(layer "F.SilkS")
		)
		(fp_line
			(start -0.8636 0.4572)
			(end -0.8636 0.4064)
			(stroke
				(width 0.1)
				(type default)
			)
			(layer "F.Fab")
		)
		(fp_line
			(start 0.8636 0.4572)
			(end -0.8636 0.4572)
			(stroke
				(width 0.1)
				(type default)
			)
			(layer "F.Fab")
		)
		(fp_line
			(start -1.1938 0.4064)
			(end -1.1938 -0.4064)
			(stroke
				(width 0.1)
				(type default)
			)
			(layer "F.Fab")
		)
		(fp_line
			(start -0.8636 0.4064)
			(end -1.1938 0.4064)
			(stroke
				(width 0.1)
				(type default)
			)
			(layer "F.Fab")
		)
		(fp_line
			(start 0.8636 0.4064)
			(end 0.8636 0.4572)
			(stroke
				(width 0.1)
				(type default)
			)
			(layer "F.Fab")
		)
		(fp_line
			(start 1.1938 0.4064)
			(end 0.8636 0.4064)
			(stroke
				(width 0.1)
				(type default)
			)
			(layer "F.Fab")
		)
		(fp_line
			(start -1.1938 -0.4064)
			(end -0.8636 -0.4064)
			(stroke
				(width 0.1)
				(type default)
			)
			(layer "F.Fab")
		)
		(fp_line
			(start -0.8636 -0.4064)
			(end -0.8636 -0.4572)
			(stroke
				(width 0.1)
				(type default)
			)
			(layer "F.Fab")
		)
		(fp_line
			(start 0.8636 -0.4064)
			(end 1.1938 -0.4064)
			(stroke
				(width 0.1)
				(type default)
			)
			(layer "F.Fab")
		)
		(fp_line
			(start 1.1938 -0.4064)
			(end 1.1938 0.4064)
			(stroke
				(width 0.1)
				(type default)
			)
			(layer "F.Fab")
		)
		(fp_line
			(start -0.8636 -0.4572)
			(end 0.8636 -0.4572)
			(stroke
				(width 0.1)
				(type default)
			)
			(layer "F.Fab")
		)
		(fp_line
			(start 0.8636 -0.4572)
			(end 0.8636 -0.4064)
			(stroke
				(width 0.1)
				(type default)
			)
			(layer "F.Fab")
		)
		(pad "1" smd rect
			(at -0.7366 0 180)
			(size 0.7112 0.8128)
			(layers "F.Cu" "F.Mask" "F.Paste")
			(net "P1V8_PLL0_PEX2")
		)
		(pad "2" smd rect
			(at 0.7366 0 180)
			(size 0.7112 0.8128)
			(layers "F.Cu" "F.Mask" "F.Paste")
			(net "GND")
		)
	)
	(footprint ""
		(layer "F.Cu")
		(at 80.49514 -35.48253)
		(property "Reference" "U384"
			(at -2.46507 1.59893 90)
			(unlocked yes)
			(layer "F.SilkS")
			(effects
				(font
					(size 0.7874 0.5842)
					(thickness 0.1524)
				)
				(justify left)
			)
		)
		(property "Value" ""
			(at 0 0 0)
			(layer "F.Fab")
			(effects
				(font
					(size 1.27 1.27)
				)
			)
		)
		(duplicate_pad_numbers_are_jumpers no)
		(fp_line
			(start -1.3462 -1.1938)
			(end -1.3462 1.1684)
			(stroke
				(width 0.1524)
				(type default)
			)
			(layer "F.SilkS")
		)
		(fp_line
			(start -1.3462 1.1938)
			(end 1.3462 1.1938)
			(stroke
				(width 0.1524)
				(type default)
			)
			(layer "F.SilkS")
		)
		(fp_line
			(start 1.3462 -1.1938)
			(end -1.3462 -1.1938)
			(stroke
				(width 0.1524)
				(type default)
			)
			(layer "F.SilkS")
		)
		(fp_line
			(start 1.3462 1.1938)
			(end 1.3462 -1.1938)
			(stroke
				(width 0.1524)
				(type default)
			)
			(layer "F.SilkS")
		)
		(fp_poly
			(pts
				(xy -1.447038 -0.760476) (xy -2.052066 -0.457962) (xy -2.052066 -1.06299)
			)
			(stroke
				(width 0)
				(type default)
			)
			(fill yes)
			(layer "F.SilkS")
		)
		(fp_line
			(start -0.674878 -1.124966)
			(end -0.674878 1.124966)
			(stroke
				(width 0.1)
				(type default)
			)
			(layer "F.Fab")
		)
		(fp_line
			(start -0.674878 1.124966)
			(end 0.674878 1.124966)
			(stroke
				(width 0.1)
				(type default)
			)
			(layer "F.Fab")
		)
		(fp_line
			(start 0.674878 -1.124966)
			(end -0.674878 -1.124966)
			(stroke
				(width 0.1)
				(type default)
			)
			(layer "F.Fab")
		)
		(fp_line
			(start 0.674878 1.124966)
			(end 0.674878 -1.124966)
			(stroke
				(width 0.1)
				(type default)
			)
			(layer "F.Fab")
		)
		(fp_poly
			(pts
				(xy -1.447038 -0.760476) (xy -2.052066 -0.457962) (xy -2.052066 -1.06299)
			)
			(stroke
				(width 0)
				(type default)
			)
			(fill yes)
			(layer "F.Fab")
		)
		(pad "1" smd rect
			(at -0.899922 -0.750062)
			(size 0.6096 0.6096)
			(layers "F.Cu" "F.Mask" "F.Paste")
			(net "PWRGD_P3V3_SSD3_R")
		)
		(pad "2" smd rect
			(at -0.899922 0 90)
			(size 0.4064 0.6096)
			(layers "F.Cu" "F.Mask" "F.Paste")
			(net "RST_SMB_SSD3_N")
		)
		(pad "3" smd rect
			(at -0.899922 0.750062)
			(size 0.6096 0.6096)
			(layers "F.Cu" "F.Mask" "F.Paste")
			(net "GND")
		)
		(pad "4" smd rect
			(at 0.899922 0.750062)
			(size 0.6096 0.6096)
			(layers "F.Cu" "F.Mask" "F.Paste")
			(net "RST_SMB_SSD3_ISO_N")
		)
		(pad "5" smd rect
			(at 0.899922 -0.750062)
			(size 0.6096 0.6096)
			(layers "F.Cu" "F.Mask" "F.Paste")
			(net "P3V3_AUX")
		)
	)
	(footprint ""
		(layer "F.Cu")
		(at 386.866384 -250.070874 -90)
		(property "Reference" "R1404"
			(at 0 0 270)
			(layer "F.SilkS")
			(hide yes)
			(effects
				(font
					(size 1.27 1.27)
				)
			)
		)
		(property "Value" ""
			(at 0 0 270)
			(layer "F.Fab")
			(effects
				(font
					(size 1.27 1.27)
				)
			)
		)
		(duplicate_pad_numbers_are_jumpers no)
		(fp_line
			(start -0.7874 0.4064)
			(end -0.7874 -0.4064)
			(stroke
				(width 0.1524)
				(type default)
			)
			(layer "F.SilkS")
		)
		(fp_line
			(start 0.7874 0.4064)
			(end -0.7874 0.4064)
			(stroke
				(width 0.1524)
				(type default)
			)
			(layer "F.SilkS")
		)
		(fp_line
			(start -0.7874 -0.4064)
			(end 0.7874 -0.4064)
			(stroke
				(width 0.1524)
				(type default)
			)
			(layer "F.SilkS")
		)
		(fp_line
			(start 0.7874 -0.4064)
			(end 0.7874 0.4064)
			(stroke
				(width 0.1524)
				(type default)
			)
			(layer "F.SilkS")
		)
		(fp_line
			(start -0.67945 0.3048)
			(end -0.67945 -0.305054)
			(stroke
				(width 0.1)
				(type default)
			)
			(layer "F.Fab")
		)
		(fp_line
			(start -0.12065 0.3048)
			(end -0.67945 0.3048)
			(stroke
				(width 0.1)
				(type default)
			)
			(layer "F.Fab")
		)
		(fp_line
			(start 0.120396 0.3048)
			(end 0.120396 0.2794)
			(stroke
				(width 0.1)
				(type default)
			)
			(layer "F.Fab")
		)
		(fp_line
			(start 0.67945 0.3048)
			(end 0.120396 0.3048)
			(stroke
				(width 0.1)
				(type default)
			)
			(layer "F.Fab")
		)
		(fp_line
			(start -0.12065 0.2794)
			(end -0.12065 0.3048)
			(stroke
				(width 0.1)
				(type default)
			)
			(layer "F.Fab")
		)
		(fp_line
			(start 0.120396 0.2794)
			(end -0.12065 0.2794)
			(stroke
				(width 0.1)
				(type default)
			)
			(layer "F.Fab")
		)
		(fp_line
			(start -0.12065 -0.2794)
			(end 0.12065 -0.2794)
			(stroke
				(width 0.1)
				(type default)
			)
			(layer "F.Fab")
		)
		(fp_line
			(start 0.12065 -0.2794)
			(end 0.12065 -0.3048)
			(stroke
				(width 0.1)
				(type default)
			)
			(layer "F.Fab")
		)
		(fp_line
			(start 0.12065 -0.3048)
			(end 0.67945 -0.3048)
			(stroke
				(width 0.1)
				(type default)
			)
			(layer "F.Fab")
		)
		(fp_line
			(start 0.67945 -0.3048)
			(end 0.67945 0.3048)
			(stroke
				(width 0.1)
				(type default)
			)
			(layer "F.Fab")
		)
		(fp_line
			(start -0.67945 -0.305054)
			(end -0.12065 -0.305054)
			(stroke
				(width 0.1)
				(type default)
			)
			(layer "F.Fab")
		)
		(fp_line
			(start -0.12065 -0.305054)
			(end -0.12065 -0.2794)
			(stroke
				(width 0.1)
				(type default)
			)
			(layer "F.Fab")
		)
		(pad "1" smd circle
			(at -0.40005 0 270)
			(size 0 0)
			(layers "F.Cu" "F.Mask" "F.Paste")
			(net "PEX3_DBG_MODE4")
		)
		(pad "2" smd circle
			(at 0.40005 0 270)
			(size 0 0)
			(layers "F.Cu" "F.Mask" "F.Paste")
			(net "P1V8_PEX")
		)
	)
	(footprint ""
		(layer "F.Cu")
		(at 329.69835 -66.32194 -90)
		(property "Reference" "PC875"
			(at 0 0 270)
			(layer "F.SilkS")
			(hide yes)
			(effects
				(font
					(size 1.27 1.27)
				)
			)
		)
		(property "Value" ""
			(at 0 0 270)
			(layer "F.Fab")
			(effects
				(font
					(size 1.27 1.27)
				)
			)
		)
		(duplicate_pad_numbers_are_jumpers no)
		(fp_line
			(start -0.7874 0.4064)
			(end -0.7874 -0.4064)
			(stroke
				(width 0.1524)
				(type default)
			)
			(layer "F.SilkS")
		)
		(fp_line
			(start 0.7874 0.4064)
			(end -0.7874 0.4064)
			(stroke
				(width 0.1524)
				(type default)
			)
			(layer "F.SilkS")
		)
		(fp_line
			(start -0.7874 -0.4064)
			(end 0.7874 -0.4064)
			(stroke
				(width 0.1524)
				(type default)
			)
			(layer "F.SilkS")
		)
		(fp_line
			(start 0.7874 -0.4064)
			(end 0.7874 0.4064)
			(stroke
				(width 0.1524)
				(type default)
			)
			(layer "F.SilkS")
		)
		(fp_line
			(start -0.67945 0.3048)
			(end -0.67945 -0.305054)
			(stroke
				(width 0.1)
				(type default)
			)
			(layer "F.Fab")
		)
		(fp_line
			(start -0.12065 0.3048)
			(end -0.67945 0.3048)
			(stroke
				(width 0.1)
				(type default)
			)
			(layer "F.Fab")
		)
		(fp_line
			(start 0.120396 0.3048)
			(end 0.120396 0.2794)
			(stroke
				(width 0.1)
				(type default)
			)
			(layer "F.Fab")
		)
		(fp_line
			(start 0.67945 0.3048)
			(end 0.120396 0.3048)
			(stroke
				(width 0.1)
				(type default)
			)
			(layer "F.Fab")
		)
		(fp_line
			(start -0.12065 0.2794)
			(end -0.12065 0.3048)
			(stroke
				(width 0.1)
				(type default)
			)
			(layer "F.Fab")
		)
		(fp_line
			(start 0.120396 0.2794)
			(end -0.12065 0.2794)
			(stroke
				(width 0.1)
				(type default)
			)
			(layer "F.Fab")
		)
		(fp_line
			(start -0.12065 -0.2794)
			(end 0.12065 -0.2794)
			(stroke
				(width 0.1)
				(type default)
			)
			(layer "F.Fab")
		)
		(fp_line
			(start 0.12065 -0.2794)
			(end 0.12065 -0.3048)
			(stroke
				(width 0.1)
				(type default)
			)
			(layer "F.Fab")
		)
		(fp_line
			(start 0.12065 -0.3048)
			(end 0.67945 -0.3048)
			(stroke
				(width 0.1)
				(type default)
			)
			(layer "F.Fab")
		)
		(fp_line
			(start 0.67945 -0.3048)
			(end 0.67945 0.3048)
			(stroke
				(width 0.1)
				(type default)
			)
			(layer "F.Fab")
		)
		(fp_line
			(start -0.67945 -0.305054)
			(end -0.12065 -0.305054)
			(stroke
				(width 0.1)
				(type default)
			)
			(layer "F.Fab")
		)
		(fp_line
			(start -0.12065 -0.305054)
			(end -0.12065 -0.2794)
			(stroke
				(width 0.1)
				(type default)
			)
			(layer "F.Fab")
		)
		(pad "1" smd circle
			(at -0.40005 0 270)
			(size 0 0)
			(layers "F.Cu" "F.Mask" "F.Paste")
			(net "P12V_SSD11_CO_GATE")
		)
		(pad "2" smd circle
			(at 0.40005 0 270)
			(size 0 0)
			(layers "F.Cu" "F.Mask" "F.Paste")
			(net "GND")
		)
	)
	(footprint ""
		(layer "F.Cu")
		(at 260.249162 -287.395412 -90)
		(property "Reference" "C3402"
			(at 0 0 270)
			(layer "F.SilkS")
			(hide yes)
			(effects
				(font
					(size 1.27 1.27)
				)
			)
		)
		(property "Value" ""
			(at 0 0 270)
			(layer "F.Fab")
			(effects
				(font
					(size 1.27 1.27)
				)
			)
		)
		(duplicate_pad_numbers_are_jumpers no)
		(fp_line
			(start -0.299974 0.150114)
			(end -0.299974 -0.150114)
			(stroke
				(width 0.1)
				(type default)
			)
			(layer "F.Fab")
		)
		(fp_line
			(start 0.299974 0.150114)
			(end -0.299974 0.150114)
			(stroke
				(width 0.1)
				(type default)
			)
			(layer "F.Fab")
		)
		(fp_line
			(start -0.299974 -0.150114)
			(end 0.299974 -0.150114)
			(stroke
				(width 0.1)
				(type default)
			)
			(layer "F.Fab")
		)
		(fp_line
			(start 0.299974 -0.150114)
			(end 0.299974 0.150114)
			(stroke
				(width 0.1)
				(type default)
			)
			(layer "F.Fab")
		)
		(pad "1" smd rect
			(at -0.2667 0 270)
			(size 0.3048 0.381)
			(layers "F.Cu" "F.Mask" "F.Paste")
			(net "P1V8_PLL0_PEX2")
		)
		(pad "2" smd rect
			(at 0.2667 0 270)
			(size 0.3048 0.381)
			(layers "F.Cu" "F.Mask" "F.Paste")
			(net "GND")
		)
	)
	(footprint ""
		(layer "F.Cu")
		(at 329.438 -83.82 180)
		(property "Reference" "R1472"
			(at 0 0 180)
			(layer "F.SilkS")
			(hide yes)
			(effects
				(font
					(size 1.27 1.27)
				)
			)
		)
		(property "Value" ""
			(at 0 0 180)
			(layer "F.Fab")
			(effects
				(font
					(size 1.27 1.27)
				)
			)
		)
		(duplicate_pad_numbers_are_jumpers no)
		(fp_line
			(start 0.7874 0.4064)
			(end -0.7874 0.4064)
			(stroke
				(width 0.1524)
				(type default)
			)
			(layer "F.SilkS")
		)
		(fp_line
			(start 0.7874 -0.4064)
			(end 0.7874 0.4064)
			(stroke
				(width 0.1524)
				(type default)
			)
			(layer "F.SilkS")
		)
		(fp_line
			(start -0.7874 0.4064)
			(end -0.7874 -0.4064)
			(stroke
				(width 0.1524)
				(type default)
			)
			(layer "F.SilkS")
		)
		(fp_line
			(start -0.7874 -0.4064)
			(end 0.7874 -0.4064)
			(stroke
				(width 0.1524)
				(type default)
			)
			(layer "F.SilkS")
		)
		(fp_line
			(start 0.67945 0.3048)
			(end 0.120396 0.3048)
			(stroke
				(width 0.1)
				(type default)
			)
			(layer "F.Fab")
		)
		(fp_line
			(start 0.67945 -0.3048)
			(end 0.67945 0.3048)
			(stroke
				(width 0.1)
				(type default)
			)
			(layer "F.Fab")
		)
		(fp_line
			(start 0.12065 -0.2794)
			(end 0.12065 -0.3048)
			(stroke
				(width 0.1)
				(type default)
			)
			(layer "F.Fab")
		)
		(fp_line
			(start 0.12065 -0.3048)
			(end 0.67945 -0.3048)
			(stroke
				(width 0.1)
				(type default)
			)
			(layer "F.Fab")
		)
		(fp_line
			(start 0.120396 0.3048)
			(end 0.120396 0.2794)
			(stroke
				(width 0.1)
				(type default)
			)
			(layer "F.Fab")
		)
		(fp_line
			(start 0.120396 0.2794)
			(end -0.12065 0.2794)
			(stroke
				(width 0.1)
				(type default)
			)
			(layer "F.Fab")
		)
		(fp_line
			(start -0.12065 0.3048)
			(end -0.67945 0.3048)
			(stroke
				(width 0.1)
				(type default)
			)
			(layer "F.Fab")
		)
		(fp_line
			(start -0.12065 0.2794)
			(end -0.12065 0.3048)
			(stroke
				(width 0.1)
				(type default)
			)
			(layer "F.Fab")
		)
		(fp_line
			(start -0.12065 -0.2794)
			(end 0.12065 -0.2794)
			(stroke
				(width 0.1)
				(type default)
			)
			(layer "F.Fab")
		)
		(fp_line
			(start -0.12065 -0.305054)
			(end -0.12065 -0.2794)
			(stroke
				(width 0.1)
				(type default)
			)
			(layer "F.Fab")
		)
		(fp_line
			(start -0.67945 0.3048)
			(end -0.67945 -0.305054)
			(stroke
				(width 0.1)
				(type default)
			)
			(layer "F.Fab")
		)
		(fp_line
			(start -0.67945 -0.305054)
			(end -0.12065 -0.305054)
			(stroke
				(width 0.1)
				(type default)
			)
			(layer "F.Fab")
		)
		(pad "1" smd circle
			(at -0.40005 0 180)
			(size 0 0)
			(layers "F.Cu" "F.Mask" "F.Paste")
			(net "SMB_BMC_9ZXL0851_8_15_SCL")
		)
		(pad "2" smd circle
			(at 0.40005 0 180)
			(size 0 0)
			(layers "F.Cu" "F.Mask" "F.Paste")
			(net "SMB_ISO_CB_SCL")
		)
	)
	(footprint ""
		(layer "F.Cu")
		(at 434.02123 -311.3278 -90)
		(property "Reference" "R6722"
			(at 0 0 270)
			(layer "F.SilkS")
			(hide yes)
			(effects
				(font
					(size 1.27 1.27)
				)
			)
		)
		(property "Value" ""
			(at 0 0 270)
			(layer "F.Fab")
			(effects
				(font
					(size 1.27 1.27)
				)
			)
		)
		(duplicate_pad_numbers_are_jumpers no)
		(fp_line
			(start -0.7874 0.4064)
			(end -0.7874 -0.4064)
			(stroke
				(width 0.1524)
				(type default)
			)
			(layer "F.SilkS")
		)
		(fp_line
			(start 0.7874 0.4064)
			(end -0.7874 0.4064)
			(stroke
				(width 0.1524)
				(type default)
			)
			(layer "F.SilkS")
		)
		(fp_line
			(start -0.7874 -0.4064)
			(end 0.7874 -0.4064)
			(stroke
				(width 0.1524)
				(type default)
			)
			(layer "F.SilkS")
		)
		(fp_line
			(start 0.7874 -0.4064)
			(end 0.7874 0.4064)
			(stroke
				(width 0.1524)
				(type default)
			)
			(layer "F.SilkS")
		)
		(fp_line
			(start -0.67945 0.3048)
			(end -0.67945 -0.305054)
			(stroke
				(width 0.1)
				(type default)
			)
			(layer "F.Fab")
		)
		(fp_line
			(start -0.12065 0.3048)
			(end -0.67945 0.3048)
			(stroke
				(width 0.1)
				(type default)
			)
			(layer "F.Fab")
		)
		(fp_line
			(start 0.120396 0.3048)
			(end 0.120396 0.2794)
			(stroke
				(width 0.1)
				(type default)
			)
			(layer "F.Fab")
		)
		(fp_line
			(start 0.67945 0.3048)
			(end 0.120396 0.3048)
			(stroke
				(width 0.1)
				(type default)
			)
			(layer "F.Fab")
		)
		(fp_line
			(start -0.12065 0.2794)
			(end -0.12065 0.3048)
			(stroke
				(width 0.1)
				(type default)
			)
			(layer "F.Fab")
		)
		(fp_line
			(start 0.120396 0.2794)
			(end -0.12065 0.2794)
			(stroke
				(width 0.1)
				(type default)
			)
			(layer "F.Fab")
		)
		(fp_line
			(start -0.12065 -0.2794)
			(end 0.12065 -0.2794)
			(stroke
				(width 0.1)
				(type default)
			)
			(layer "F.Fab")
		)
		(fp_line
			(start 0.12065 -0.2794)
			(end 0.12065 -0.3048)
			(stroke
				(width 0.1)
				(type default)
			)
			(layer "F.Fab")
		)
		(fp_line
			(start 0.12065 -0.3048)
			(end 0.67945 -0.3048)
			(stroke
				(width 0.1)
				(type default)
			)
			(layer "F.Fab")
		)
		(fp_line
			(start 0.67945 -0.3048)
			(end 0.67945 0.3048)
			(stroke
				(width 0.1)
				(type default)
			)
			(layer "F.Fab")
		)
		(fp_line
			(start -0.67945 -0.305054)
			(end -0.12065 -0.305054)
			(stroke
				(width 0.1)
				(type default)
			)
			(layer "F.Fab")
		)
		(fp_line
			(start -0.12065 -0.305054)
			(end -0.12065 -0.2794)
			(stroke
				(width 0.1)
				(type default)
			)
			(layer "F.Fab")
		)
		(pad "1" smd circle
			(at -0.40005 0 270)
			(size 0 0)
			(layers "F.Cu" "F.Mask" "F.Paste")
			(net "SMB_PEX3_SLAVE1_SCL")
		)
		(pad "2" smd circle
			(at 0.40005 0 270)
			(size 0 0)
			(layers "F.Cu" "F.Mask" "F.Paste")
			(net "SMB_PEX3_R_SCL")
		)
	)
	(footprint ""
		(layer "F.Cu")
		(at 123.31319 -107.928918 -90)
		(property "Reference" "Q126"
			(at 0.423926 -1.964182 90)
			(unlocked yes)
			(layer "F.SilkS")
			(effects
				(font
					(size 0.7874 0.5842)
					(thickness 0.1524)
				)
			)
		)
		(property "Value" ""
			(at 0 0 270)
			(layer "F.Fab")
			(effects
				(font
					(size 1.27 1.27)
				)
			)
		)
		(duplicate_pad_numbers_are_jumpers no)
		(fp_line
			(start -1.376172 1.199896)
			(end -1.376172 -1.199896)
			(stroke
				(width 0.1524)
				(type default)
			)
			(layer "F.SilkS")
		)
		(fp_line
			(start 1.376172 1.199896)
			(end -1.376172 1.199896)
			(stroke
				(width 0.1524)
				(type default)
			)
			(layer "F.SilkS")
		)
		(fp_line
			(start 0 -0.762)
			(end 0.508 -1.199896)
			(stroke
				(width 0.1524)
				(type default)
			)
			(layer "F.SilkS")
		)
		(fp_line
			(start -1.376172 -1.199896)
			(end -0.508 -1.199896)
			(stroke
				(width 0.1524)
				(type default)
			)
			(layer "F.SilkS")
		)
		(fp_line
			(start -0.508 -1.199896)
			(end 0 -0.762)
			(stroke
				(width 0.1524)
				(type default)
			)
			(layer "F.SilkS")
		)
		(fp_line
			(start 0.508 -1.199896)
			(end 1.376172 -1.199896)
			(stroke
				(width 0.1524)
				(type default)
			)
			(layer "F.SilkS")
		)
		(fp_line
			(start 1.376172 -1.199896)
			(end 1.376172 1.199896)
			(stroke
				(width 0.1524)
				(type default)
			)
			(layer "F.SilkS")
		)
		(fp_poly
			(pts
				(xy -1.176274 -1.296924) (xy -1.445768 -2.105152) (xy -1.984502 -1.566418)
			)
			(stroke
				(width 0)
				(type default)
			)
			(fill yes)
			(layer "F.SilkS")
		)
		(fp_line
			(start -0.674878 1.100074)
			(end -0.674878 -1.100074)
			(stroke
				(width 0.1)
				(type default)
			)
			(layer "F.Fab")
		)
		(fp_line
			(start 0.674878 1.100074)
			(end -0.674878 1.100074)
			(stroke
				(width 0.1)
				(type default)
			)
			(layer "F.Fab")
		)
		(fp_line
			(start -0.674878 -1.100074)
			(end 0.674878 -1.100074)
			(stroke
				(width 0.1)
				(type default)
			)
			(layer "F.Fab")
		)
		(fp_line
			(start 0.674878 -1.100074)
			(end 0.674878 1.100074)
			(stroke
				(width 0.1)
				(type default)
			)
			(layer "F.Fab")
		)
		(fp_poly
			(pts
				(xy -1.4605 -0.7493) (xy -2.2225 -1.1303) (xy -2.2225 -0.3683)
			)
			(stroke
				(width 0)
				(type default)
			)
			(fill yes)
			(layer "F.Fab")
		)
		(pad "1" smd rect
			(at -0.899922 -0.750062 180)
			(size 0.6096 0.6096)
			(layers "F.Cu" "F.Mask" "F.Paste")
			(net "GND")
		)
		(pad "2" smd rect
			(at -0.899922 0 180)
			(size 0.4064 0.6096)
			(layers "F.Cu" "F.Mask" "F.Paste")
			(net "P3V3_PG_G1")
		)
		(pad "3" smd rect
			(at -0.899922 0.750062 180)
			(size 0.6096 0.6096)
			(layers "F.Cu" "F.Mask" "F.Paste")
			(net "PWRGD_P3V3_D")
		)
		(pad "4" smd rect
			(at 0.899922 0.750062 180)
			(size 0.6096 0.6096)
			(layers "F.Cu" "F.Mask" "F.Paste")
			(net "GND")
		)
		(pad "5" smd rect
			(at 0.899922 0 180)
			(size 0.4064 0.6096)
			(layers "F.Cu" "F.Mask" "F.Paste")
			(net "P3V3_PG_G2")
		)
		(pad "6" smd rect
			(at 0.899922 -0.750062 180)
			(size 0.6096 0.6096)
			(layers "F.Cu" "F.Mask" "F.Paste")
			(net "P3V3_PG_G2")
		)
	)
	(footprint ""
		(layer "F.Cu")
		(at 225.828606 -257.975862 -90)
		(property "Reference" "R6499"
			(at 0 0 270)
			(layer "F.SilkS")
			(hide yes)
			(effects
				(font
					(size 1.27 1.27)
				)
			)
		)
		(property "Value" ""
			(at 0 0 270)
			(layer "F.Fab")
			(effects
				(font
					(size 1.27 1.27)
				)
			)
		)
		(duplicate_pad_numbers_are_jumpers no)
		(fp_line
			(start -0.7874 0.4064)
			(end -0.7874 -0.4064)
			(stroke
				(width 0.1524)
				(type default)
			)
			(layer "F.SilkS")
		)
		(fp_line
			(start 0.7874 0.4064)
			(end -0.7874 0.4064)
			(stroke
				(width 0.1524)
				(type default)
			)
			(layer "F.SilkS")
		)
		(fp_line
			(start -0.7874 -0.4064)
			(end 0.7874 -0.4064)
			(stroke
				(width 0.1524)
				(type default)
			)
			(layer "F.SilkS")
		)
		(fp_line
			(start 0.7874 -0.4064)
			(end 0.7874 0.4064)
			(stroke
				(width 0.1524)
				(type default)
			)
			(layer "F.SilkS")
		)
		(fp_line
			(start -0.67945 0.3048)
			(end -0.67945 -0.305054)
			(stroke
				(width 0.1)
				(type default)
			)
			(layer "F.Fab")
		)
		(fp_line
			(start -0.12065 0.3048)
			(end -0.67945 0.3048)
			(stroke
				(width 0.1)
				(type default)
			)
			(layer "F.Fab")
		)
		(fp_line
			(start 0.120396 0.3048)
			(end 0.120396 0.2794)
			(stroke
				(width 0.1)
				(type default)
			)
			(layer "F.Fab")
		)
		(fp_line
			(start 0.67945 0.3048)
			(end 0.120396 0.3048)
			(stroke
				(width 0.1)
				(type default)
			)
			(layer "F.Fab")
		)
		(fp_line
			(start -0.12065 0.2794)
			(end -0.12065 0.3048)
			(stroke
				(width 0.1)
				(type default)
			)
			(layer "F.Fab")
		)
		(fp_line
			(start 0.120396 0.2794)
			(end -0.12065 0.2794)
			(stroke
				(width 0.1)
				(type default)
			)
			(layer "F.Fab")
		)
		(fp_line
			(start -0.12065 -0.2794)
			(end 0.12065 -0.2794)
			(stroke
				(width 0.1)
				(type default)
			)
			(layer "F.Fab")
		)
		(fp_line
			(start 0.12065 -0.2794)
			(end 0.12065 -0.3048)
			(stroke
				(width 0.1)
				(type default)
			)
			(layer "F.Fab")
		)
		(fp_line
			(start 0.12065 -0.3048)
			(end 0.67945 -0.3048)
			(stroke
				(width 0.1)
				(type default)
			)
			(layer "F.Fab")
		)
		(fp_line
			(start 0.67945 -0.3048)
			(end 0.67945 0.3048)
			(stroke
				(width 0.1)
				(type default)
			)
			(layer "F.Fab")
		)
		(fp_line
			(start -0.67945 -0.305054)
			(end -0.12065 -0.305054)
			(stroke
				(width 0.1)
				(type default)
			)
			(layer "F.Fab")
		)
		(fp_line
			(start -0.12065 -0.305054)
			(end -0.12065 -0.2794)
			(stroke
				(width 0.1)
				(type default)
			)
			(layer "F.Fab")
		)
		(pad "1" smd circle
			(at -0.40005 0 270)
			(size 0 0)
			(layers "F.Cu" "F.Mask" "F.Paste")
			(net "P1V25_SERDES_VDDPLL_PEX1")
		)
		(pad "2" smd circle
			(at 0.40005 0 270)
			(size 0 0)
			(layers "F.Cu" "F.Mask" "F.Paste")
			(net "P1V25_SERDES_VDDPLL_PEX1_C6")
		)
	)
	(footprint ""
		(layer "F.Cu")
		(at 80.019398 -134.394702 180)
		(property "Reference" "C19"
			(at 0 0 180)
			(layer "F.SilkS")
			(hide yes)
			(effects
				(font
					(size 1.27 1.27)
				)
			)
		)
		(property "Value" ""
			(at 0 0 180)
			(layer "F.Fab")
			(effects
				(font
					(size 1.27 1.27)
				)
			)
		)
		(duplicate_pad_numbers_are_jumpers no)
		(fp_line
			(start 0.299974 0.150114)
			(end -0.299974 0.150114)
			(stroke
				(width 0.1)
				(type default)
			)
			(layer "F.Fab")
		)
		(fp_line
			(start 0.299974 -0.150114)
			(end 0.299974 0.150114)
			(stroke
				(width 0.1)
				(type default)
			)
			(layer "F.Fab")
		)
		(fp_line
			(start -0.299974 0.150114)
			(end -0.299974 -0.150114)
			(stroke
				(width 0.1)
				(type default)
			)
			(layer "F.Fab")
		)
		(fp_line
			(start -0.299974 -0.150114)
			(end 0.299974 -0.150114)
			(stroke
				(width 0.1)
				(type default)
			)
			(layer "F.Fab")
		)
		(pad "1" smd rect
			(at -0.2667 0 180)
			(size 0.3048 0.381)
			(layers "F.Cu" "F.Mask" "F.Paste")
			(net "P5E_PEX0_STN0_TX_DP<6>")
		)
		(pad "2" smd rect
			(at 0.2667 0 180)
			(size 0.3048 0.381)
			(layers "F.Cu" "F.Mask" "F.Paste")
			(net "P5E_PEX0_STN0_TX_C_DP<6>")
		)
	)
	(footprint ""
		(layer "F.Cu")
		(at 368.574066 -72.766682 90)
		(property "Reference" "PR7087"
			(at 0 0 90)
			(layer "F.SilkS")
			(hide yes)
			(effects
				(font
					(size 1.27 1.27)
				)
			)
		)
		(property "Value" ""
			(at 0 0 90)
			(layer "F.Fab")
			(effects
				(font
					(size 1.27 1.27)
				)
			)
		)
		(duplicate_pad_numbers_are_jumpers no)
		(fp_line
			(start 0.7874 -0.4064)
			(end 0.7874 0.4064)
			(stroke
				(width 0.1524)
				(type default)
			)
			(layer "F.SilkS")
		)
		(fp_line
			(start -0.7874 -0.4064)
			(end 0.7874 -0.4064)
			(stroke
				(width 0.1524)
				(type default)
			)
			(layer "F.SilkS")
		)
		(fp_line
			(start 0.7874 0.4064)
			(end -0.7874 0.4064)
			(stroke
				(width 0.1524)
				(type default)
			)
			(layer "F.SilkS")
		)
		(fp_line
			(start -0.7874 0.4064)
			(end -0.7874 -0.4064)
			(stroke
				(width 0.1524)
				(type default)
			)
			(layer "F.SilkS")
		)
		(fp_line
			(start -0.12065 -0.305054)
			(end -0.12065 -0.2794)
			(stroke
				(width 0.1)
				(type default)
			)
			(layer "F.Fab")
		)
		(fp_line
			(start -0.67945 -0.305054)
			(end -0.12065 -0.305054)
			(stroke
				(width 0.1)
				(type default)
			)
			(layer "F.Fab")
		)
		(fp_line
			(start 0.67945 -0.3048)
			(end 0.67945 0.3048)
			(stroke
				(width 0.1)
				(type default)
			)
			(layer "F.Fab")
		)
		(fp_line
			(start 0.12065 -0.3048)
			(end 0.67945 -0.3048)
			(stroke
				(width 0.1)
				(type default)
			)
			(layer "F.Fab")
		)
		(fp_line
			(start 0.12065 -0.2794)
			(end 0.12065 -0.3048)
			(stroke
				(width 0.1)
				(type default)
			)
			(layer "F.Fab")
		)
		(fp_line
			(start -0.12065 -0.2794)
			(end 0.12065 -0.2794)
			(stroke
				(width 0.1)
				(type default)
			)
			(layer "F.Fab")
		)
		(fp_line
			(start 0.120396 0.2794)
			(end -0.12065 0.2794)
			(stroke
				(width 0.1)
				(type default)
			)
			(layer "F.Fab")
		)
		(fp_line
			(start -0.12065 0.2794)
			(end -0.12065 0.3048)
			(stroke
				(width 0.1)
				(type default)
			)
			(layer "F.Fab")
		)
		(fp_line
			(start 0.67945 0.3048)
			(end 0.120396 0.3048)
			(stroke
				(width 0.1)
				(type default)
			)
			(layer "F.Fab")
		)
		(fp_line
			(start 0.120396 0.3048)
			(end 0.120396 0.2794)
			(stroke
				(width 0.1)
				(type default)
			)
			(layer "F.Fab")
		)
		(fp_line
			(start -0.12065 0.3048)
			(end -0.67945 0.3048)
			(stroke
				(width 0.1)
				(type default)
			)
			(layer "F.Fab")
		)
		(fp_line
			(start -0.67945 0.3048)
			(end -0.67945 -0.305054)
			(stroke
				(width 0.1)
				(type default)
			)
			(layer "F.Fab")
		)
		(pad "1" smd circle
			(at -0.40005 0 90)
			(size 0 0)
			(layers "F.Cu" "F.Mask" "F.Paste")
			(net "P12V_SSD12_CO_MODE")
		)
		(pad "2" smd circle
			(at 0.40005 0 90)
			(size 0 0)
			(layers "F.Cu" "F.Mask" "F.Paste")
			(net "GND")
		)
	)
	(footprint ""
		(layer "F.Cu")
		(at 125.349 -279.486868 -90)
		(property "Reference" "PC89"
			(at 0 0 270)
			(layer "F.SilkS")
			(hide yes)
			(effects
				(font
					(size 1.27 1.27)
				)
			)
		)
		(property "Value" ""
			(at 0 0 270)
			(layer "F.Fab")
			(effects
				(font
					(size 1.27 1.27)
				)
			)
		)
		(duplicate_pad_numbers_are_jumpers no)
		(fp_line
			(start -0.7874 0.4064)
			(end -0.7874 -0.4064)
			(stroke
				(width 0.1524)
				(type default)
			)
			(layer "F.SilkS")
		)
		(fp_line
			(start 0.7874 0.4064)
			(end -0.7874 0.4064)
			(stroke
				(width 0.1524)
				(type default)
			)
			(layer "F.SilkS")
		)
		(fp_line
			(start -0.7874 -0.4064)
			(end 0.7874 -0.4064)
			(stroke
				(width 0.1524)
				(type default)
			)
			(layer "F.SilkS")
		)
		(fp_line
			(start 0.7874 -0.4064)
			(end 0.7874 0.4064)
			(stroke
				(width 0.1524)
				(type default)
			)
			(layer "F.SilkS")
		)
		(fp_line
			(start -0.67945 0.3048)
			(end -0.67945 -0.305054)
			(stroke
				(width 0.1)
				(type default)
			)
			(layer "F.Fab")
		)
		(fp_line
			(start -0.12065 0.3048)
			(end -0.67945 0.3048)
			(stroke
				(width 0.1)
				(type default)
			)
			(layer "F.Fab")
		)
		(fp_line
			(start 0.120396 0.3048)
			(end 0.120396 0.2794)
			(stroke
				(width 0.1)
				(type default)
			)
			(layer "F.Fab")
		)
		(fp_line
			(start 0.67945 0.3048)
			(end 0.120396 0.3048)
			(stroke
				(width 0.1)
				(type default)
			)
			(layer "F.Fab")
		)
		(fp_line
			(start -0.12065 0.2794)
			(end -0.12065 0.3048)
			(stroke
				(width 0.1)
				(type default)
			)
			(layer "F.Fab")
		)
		(fp_line
			(start 0.120396 0.2794)
			(end -0.12065 0.2794)
			(stroke
				(width 0.1)
				(type default)
			)
			(layer "F.Fab")
		)
		(fp_line
			(start -0.12065 -0.2794)
			(end 0.12065 -0.2794)
			(stroke
				(width 0.1)
				(type default)
			)
			(layer "F.Fab")
		)
		(fp_line
			(start 0.12065 -0.2794)
			(end 0.12065 -0.3048)
			(stroke
				(width 0.1)
				(type default)
			)
			(layer "F.Fab")
		)
		(fp_line
			(start 0.12065 -0.3048)
			(end 0.67945 -0.3048)
			(stroke
				(width 0.1)
				(type default)
			)
			(layer "F.Fab")
		)
		(fp_line
			(start 0.67945 -0.3048)
			(end 0.67945 0.3048)
			(stroke
				(width 0.1)
				(type default)
			)
			(layer "F.Fab")
		)
		(fp_line
			(start -0.67945 -0.305054)
			(end -0.12065 -0.305054)
			(stroke
				(width 0.1)
				(type default)
			)
			(layer "F.Fab")
		)
		(fp_line
			(start -0.12065 -0.305054)
			(end -0.12065 -0.2794)
			(stroke
				(width 0.1)
				(type default)
			)
			(layer "F.Fab")
		)
		(pad "1" smd circle
			(at -0.40005 0 270)
			(size 0 0)
			(layers "F.Cu" "F.Mask" "F.Paste")
			(net "P0V8_PEX0_VREF")
		)
		(pad "2" smd circle
			(at 0.40005 0 270)
			(size 0 0)
			(layers "F.Cu" "F.Mask" "F.Paste")
			(net "GND")
		)
	)
	(footprint ""
		(layer "F.Cu")
		(at 194.343782 -46.90491)
		(property "Reference" "R576"
			(at 0 0 0)
			(layer "F.SilkS")
			(hide yes)
			(effects
				(font
					(size 1.27 1.27)
				)
			)
		)
		(property "Value" ""
			(at 0 0 0)
			(layer "F.Fab")
			(effects
				(font
					(size 1.27 1.27)
				)
			)
		)
		(duplicate_pad_numbers_are_jumpers no)
		(fp_line
			(start -0.7874 -0.4064)
			(end 0.7874 -0.4064)
			(stroke
				(width 0.1524)
				(type default)
			)
			(layer "F.SilkS")
		)
		(fp_line
			(start -0.7874 0.4064)
			(end -0.7874 -0.4064)
			(stroke
				(width 0.1524)
				(type default)
			)
			(layer "F.SilkS")
		)
		(fp_line
			(start 0.7874 -0.4064)
			(end 0.7874 0.4064)
			(stroke
				(width 0.1524)
				(type default)
			)
			(layer "F.SilkS")
		)
		(fp_line
			(start 0.7874 0.4064)
			(end -0.7874 0.4064)
			(stroke
				(width 0.1524)
				(type default)
			)
			(layer "F.SilkS")
		)
		(fp_line
			(start -0.67945 -0.305054)
			(end -0.12065 -0.305054)
			(stroke
				(width 0.1)
				(type default)
			)
			(layer "F.Fab")
		)
		(fp_line
			(start -0.67945 0.3048)
			(end -0.67945 -0.305054)
			(stroke
				(width 0.1)
				(type default)
			)
			(layer "F.Fab")
		)
		(fp_line
			(start -0.12065 -0.305054)
			(end -0.12065 -0.2794)
			(stroke
				(width 0.1)
				(type default)
			)
			(layer "F.Fab")
		)
		(fp_line
			(start -0.12065 -0.2794)
			(end 0.12065 -0.2794)
			(stroke
				(width 0.1)
				(type default)
			)
			(layer "F.Fab")
		)
		(fp_line
			(start -0.12065 0.2794)
			(end -0.12065 0.3048)
			(stroke
				(width 0.1)
				(type default)
			)
			(layer "F.Fab")
		)
		(fp_line
			(start -0.12065 0.3048)
			(end -0.67945 0.3048)
			(stroke
				(width 0.1)
				(type default)
			)
			(layer "F.Fab")
		)
		(fp_line
			(start 0.120396 0.2794)
			(end -0.12065 0.2794)
			(stroke
				(width 0.1)
				(type default)
			)
			(layer "F.Fab")
		)
		(fp_line
			(start 0.120396 0.3048)
			(end 0.120396 0.2794)
			(stroke
				(width 0.1)
				(type default)
			)
			(layer "F.Fab")
		)
		(fp_line
			(start 0.12065 -0.3048)
			(end 0.67945 -0.3048)
			(stroke
				(width 0.1)
				(type default)
			)
			(layer "F.Fab")
		)
		(fp_line
			(start 0.12065 -0.2794)
			(end 0.12065 -0.3048)
			(stroke
				(width 0.1)
				(type default)
			)
			(layer "F.Fab")
		)
		(fp_line
			(start 0.67945 -0.3048)
			(end 0.67945 0.3048)
			(stroke
				(width 0.1)
				(type default)
			)
			(layer "F.Fab")
		)
		(fp_line
			(start 0.67945 0.3048)
			(end 0.120396 0.3048)
			(stroke
				(width 0.1)
				(type default)
			)
			(layer "F.Fab")
		)
		(pad "1" smd circle
			(at -0.40005 0)
			(size 0 0)
			(layers "F.Cu" "F.Mask" "F.Paste")
			(net "SSD6_ADC_ALERT_N")
		)
		(pad "2" smd circle
			(at 0.40005 0)
			(size 0 0)
			(layers "F.Cu" "F.Mask" "F.Paste")
			(net "SSD_0_7_ADC_ALERT_N")
		)
	)
	(footprint ""
		(layer "F.Cu")
		(at 332.846934 -54.3941)
		(property "Reference" "PU44"
			(at -1.964182 2.975356 0)
			(unlocked yes)
			(layer "F.SilkS")
			(effects
				(font
					(size 0.7874 0.5842)
					(thickness 0.1524)
				)
				(justify left)
			)
		)
		(property "Value" ""
			(at 0 0 0)
			(layer "F.Fab")
			(effects
				(font
					(size 1.27 1.27)
				)
			)
		)
		(duplicate_pad_numbers_are_jumpers no)
		(fp_line
			(start -1.943608 -1.549908)
			(end 1.943608 -1.549908)
			(stroke
				(width 0.1524)
				(type default)
			)
			(layer "F.SilkS")
		)
		(fp_line
			(start -1.943608 1.549908)
			(end -1.943608 -1.549908)
			(stroke
				(width 0.1524)
				(type default)
			)
			(layer "F.SilkS")
		)
		(fp_line
			(start 1.943608 -1.549908)
			(end 1.943608 1.549908)
			(stroke
				(width 0.1524)
				(type default)
			)
			(layer "F.SilkS")
		)
		(fp_line
			(start 1.943608 1.549908)
			(end -1.943608 1.549908)
			(stroke
				(width 0.1524)
				(type default)
			)
			(layer "F.SilkS")
		)
		(fp_poly
			(pts
				(xy -2.019808 -1.549908) (xy -1.257808 -1.549908) (xy -1.257808 -1.880108) (xy -2.019808 -1.880108)
			)
			(stroke
				(width 0)
				(type default)
			)
			(fill yes)
			(layer "F.SilkS")
		)
		(fp_line
			(start -1.549908 -1.549908)
			(end 1.549908 -1.549908)
			(stroke
				(width 0.1)
				(type default)
			)
			(layer "F.Fab")
		)
		(fp_line
			(start -1.549908 1.549908)
			(end -1.549908 -1.549908)
			(stroke
				(width 0.1)
				(type default)
			)
			(layer "F.Fab")
		)
		(fp_line
			(start 1.549908 -1.549908)
			(end 1.549908 1.549908)
			(stroke
				(width 0.1)
				(type default)
			)
			(layer "F.Fab")
		)
		(fp_line
			(start 1.549908 1.549908)
			(end -1.549908 1.549908)
			(stroke
				(width 0.1)
				(type default)
			)
			(layer "F.Fab")
		)
		(fp_poly
			(pts
				(xy -2.019808 -1.549908) (xy -1.257808 -1.549908) (xy -1.257808 -1.880108) (xy -2.019808 -1.880108)
			)
			(stroke
				(width 0)
				(type default)
			)
			(fill yes)
			(layer "F.Fab")
		)
		(pad "1" smd rect
			(at -1.500124 -1.249934 270)
			(size 0.2794 0.6096)
			(layers "F.Cu" "F.Mask" "F.Paste")
			(net "P12V_SSD11_R")
		)
		(pad "2" smd rect
			(at -1.500124 -0.750062 270)
			(size 0.2794 0.6096)
			(layers "F.Cu" "F.Mask" "F.Paste")
			(net "P12V_SSD11_R")
		)
		(pad "3" smd rect
			(at -1.500124 -0.249936 270)
			(size 0.2794 0.6096)
			(layers "F.Cu" "F.Mask" "F.Paste")
			(net "P12V_SSD11_R")
		)
		(pad "4" smd rect
			(at -1.500124 0.249936 270)
			(size 0.2794 0.6096)
			(layers "F.Cu" "F.Mask" "F.Paste")
			(net "P12V_SSD11_R")
		)
		(pad "5" smd rect
			(at -1.500124 0.750062 270)
			(size 0.2794 0.6096)
			(layers "F.Cu" "F.Mask" "F.Paste")
			(net "P12V_SSD11_R")
		)
		(pad "6" smd rect
			(at -1.500124 1.249934 270)
			(size 0.2794 0.6096)
			(layers "F.Cu" "F.Mask" "F.Paste")
			(net "GND")
		)
		(pad "7" smd rect
			(at 1.500124 1.249934 270)
			(size 0.2794 0.6096)
			(layers "F.Cu" "F.Mask" "F.Paste")
			(net "P12V_SSD11_SS")
		)
		(pad "8" smd rect
			(at 1.500124 0.750062 270)
			(size 0.2794 0.6096)
			(layers "F.Cu" "F.Mask" "F.Paste")
			(net "PWRGD_P12V_SSD11")
		)
		(pad "9" smd rect
			(at 1.500124 0.249936 270)
			(size 0.2794 0.6096)
			(layers "F.Cu" "F.Mask" "F.Paste")
			(net "P12V_SSD11_OCP")
		)
		(pad "10" smd rect
			(at 1.500124 -0.249936 270)
			(size 0.2794 0.6096)
			(layers "F.Cu" "F.Mask" "F.Paste")
			(net "P5V_AUX")
		)
		(pad "11" smd rect
			(at 1.500124 -0.750062 270)
			(size 0.2794 0.6096)
			(layers "F.Cu" "F.Mask" "F.Paste")
			(net "SSD11_PWR_EN_R")
		)
		(pad "12" smd rect
			(at 1.500124 -1.249934 270)
			(size 0.2794 0.6096)
			(layers "F.Cu" "F.Mask" "F.Paste")
			(net "P12V_AUX")
		)
		(pad "13" smd rect
			(at 0 0)
			(size 1.9812 2.7178)
			(layers "F.Cu" "F.Mask" "F.Paste")
			(net "P12V_AUX")
		)
		(zone
			(layer "F.Cu")
			(hatch none 0.5)
			(connect_pads
				(clearance 0)
			)
			(min_thickness 0.25)
			(keepout
				(tracks not_allowed)
				(vias allowed)
				(pads allowed)
				(copperpour not_allowed)
				(footprints allowed)
			)
			(placement
				(enabled no)
				(sheetname "")
			)
			(fill
				(thermal_gap 0.5)
				(thermal_bridge_width 0.5)
				(island_removal_mode 0)
			)
			(polygon
				(pts
					(xy 333.989934 -55.9435) (xy 333.989934 -55.8165) (xy 333.989934 -52.8447) (xy 333.989934 -52.844192)
					(xy 331.703934 -52.844192) (xy 331.703934 -52.8447) (xy 331.703934 -52.9717) (xy 331.703934 -54.3941)
					(xy 331.805534 -54.3941) (xy 331.805534 -52.9717) (xy 333.888334 -52.9717) (xy 333.888334 -55.8165)
					(xy 331.805534 -55.8165) (xy 331.805534 -54.4195) (xy 331.703934 -54.4195) (xy 331.703934 -55.8165)
					(xy 331.703934 -55.9435) (xy 331.703934 -55.944008) (xy 333.989934 -55.944008)
				)
			)
		)
	)
	(footprint ""
		(layer "F.Cu")
		(at 355.223318 -205.160118 90)
		(property "Reference" "R6418"
			(at 0 0 90)
			(layer "F.SilkS")
			(hide yes)
			(effects
				(font
					(size 1.27 1.27)
				)
			)
		)
		(property "Value" ""
			(at 0 0 90)
			(layer "F.Fab")
			(effects
				(font
					(size 1.27 1.27)
				)
			)
		)
		(duplicate_pad_numbers_are_jumpers no)
		(fp_line
			(start 0.7874 -0.4064)
			(end 0.7874 0.4064)
			(stroke
				(width 0.1524)
				(type default)
			)
			(layer "F.SilkS")
		)
		(fp_line
			(start -0.7874 -0.4064)
			(end 0.7874 -0.4064)
			(stroke
				(width 0.1524)
				(type default)
			)
			(layer "F.SilkS")
		)
		(fp_line
			(start 0.7874 0.4064)
			(end -0.7874 0.4064)
			(stroke
				(width 0.1524)
				(type default)
			)
			(layer "F.SilkS")
		)
		(fp_line
			(start -0.7874 0.4064)
			(end -0.7874 -0.4064)
			(stroke
				(width 0.1524)
				(type default)
			)
			(layer "F.SilkS")
		)
		(fp_line
			(start -0.12065 -0.305054)
			(end -0.12065 -0.2794)
			(stroke
				(width 0.1)
				(type default)
			)
			(layer "F.Fab")
		)
		(fp_line
			(start -0.67945 -0.305054)
			(end -0.12065 -0.305054)
			(stroke
				(width 0.1)
				(type default)
			)
			(layer "F.Fab")
		)
		(fp_line
			(start 0.67945 -0.3048)
			(end 0.67945 0.3048)
			(stroke
				(width 0.1)
				(type default)
			)
			(layer "F.Fab")
		)
		(fp_line
			(start 0.12065 -0.3048)
			(end 0.67945 -0.3048)
			(stroke
				(width 0.1)
				(type default)
			)
			(layer "F.Fab")
		)
		(fp_line
			(start 0.12065 -0.2794)
			(end 0.12065 -0.3048)
			(stroke
				(width 0.1)
				(type default)
			)
			(layer "F.Fab")
		)
		(fp_line
			(start -0.12065 -0.2794)
			(end 0.12065 -0.2794)
			(stroke
				(width 0.1)
				(type default)
			)
			(layer "F.Fab")
		)
		(fp_line
			(start 0.120396 0.2794)
			(end -0.12065 0.2794)
			(stroke
				(width 0.1)
				(type default)
			)
			(layer "F.Fab")
		)
		(fp_line
			(start -0.12065 0.2794)
			(end -0.12065 0.3048)
			(stroke
				(width 0.1)
				(type default)
			)
			(layer "F.Fab")
		)
		(fp_line
			(start 0.67945 0.3048)
			(end 0.120396 0.3048)
			(stroke
				(width 0.1)
				(type default)
			)
			(layer "F.Fab")
		)
		(fp_line
			(start 0.120396 0.3048)
			(end 0.120396 0.2794)
			(stroke
				(width 0.1)
				(type default)
			)
			(layer "F.Fab")
		)
		(fp_line
			(start -0.12065 0.3048)
			(end -0.67945 0.3048)
			(stroke
				(width 0.1)
				(type default)
			)
			(layer "F.Fab")
		)
		(fp_line
			(start -0.67945 0.3048)
			(end -0.67945 -0.305054)
			(stroke
				(width 0.1)
				(type default)
			)
			(layer "F.Fab")
		)
		(pad "1" smd circle
			(at -0.40005 0 90)
			(size 0 0)
			(layers "F.Cu" "F.Mask" "F.Paste")
			(net "FPGA_PEX1_MODE_SEL2_R")
		)
		(pad "2" smd circle
			(at 0.40005 0 90)
			(size 0 0)
			(layers "F.Cu" "F.Mask" "F.Paste")
			(net "FPGA_PEX1_MODE_SEL2")
		)
	)
	(footprint ""
		(layer "F.Cu")
		(at 196.452236 -107.552998 -90)
		(property "Reference" "C891"
			(at 0 0 270)
			(layer "F.SilkS")
			(hide yes)
			(effects
				(font
					(size 1.27 1.27)
				)
			)
		)
		(property "Value" ""
			(at 0 0 270)
			(layer "F.Fab")
			(effects
				(font
					(size 1.27 1.27)
				)
			)
		)
		(duplicate_pad_numbers_are_jumpers no)
		(fp_line
			(start -1.524 0.762)
			(end -1.524 -0.762)
			(stroke
				(width 0.1524)
				(type default)
			)
			(layer "F.SilkS")
		)
		(fp_line
			(start 1.524 0.762)
			(end -1.524 0.762)
			(stroke
				(width 0.1524)
				(type default)
			)
			(layer "F.SilkS")
		)
		(fp_line
			(start -1.524 -0.762)
			(end 1.524 -0.762)
			(stroke
				(width 0.1524)
				(type default)
			)
			(layer "F.SilkS")
		)
		(fp_line
			(start 1.524 -0.762)
			(end 1.524 0.762)
			(stroke
				(width 0.1524)
				(type default)
			)
			(layer "F.SilkS")
		)
		(fp_line
			(start -1.1049 0.724916)
			(end 1.1049 0.724916)
			(stroke
				(width 0.1)
				(type default)
			)
			(layer "F.Fab")
		)
		(fp_line
			(start 1.1049 0.724916)
			(end 1.1049 -0.724916)
			(stroke
				(width 0.1)
				(type default)
			)
			(layer "F.Fab")
		)
		(fp_line
			(start -1.1049 -0.724916)
			(end -1.1049 0.724916)
			(stroke
				(width 0.1)
				(type default)
			)
			(layer "F.Fab")
		)
		(fp_line
			(start 1.1049 -0.724916)
			(end -1.1049 -0.724916)
			(stroke
				(width 0.1)
				(type default)
			)
			(layer "F.Fab")
		)
		(pad "1" smd rect
			(at -0.889 0 90)
			(size 1.016 1.27)
			(layers "F.Cu" "F.Mask" "F.Paste")
			(net "P12V_NIC3")
		)
		(pad "2" smd rect
			(at 0.889 0 90)
			(size 1.016 1.27)
			(layers "F.Cu" "F.Mask" "F.Paste")
			(net "GND")
		)
	)
	(footprint ""
		(layer "F.Cu")
		(at 52.025042 -14.735302 180)
		(property "Reference" "C2714"
			(at 0 0 180)
			(layer "F.SilkS")
			(hide yes)
			(effects
				(font
					(size 1.27 1.27)
				)
			)
		)
		(property "Value" ""
			(at 0 0 180)
			(layer "F.Fab")
			(effects
				(font
					(size 1.27 1.27)
				)
			)
		)
		(duplicate_pad_numbers_are_jumpers no)
		(fp_line
			(start 0.7874 0.4064)
			(end -0.7874 0.4064)
			(stroke
				(width 0.1524)
				(type default)
			)
			(layer "F.SilkS")
		)
		(fp_line
			(start 0.7874 -0.4064)
			(end 0.7874 0.4064)
			(stroke
				(width 0.1524)
				(type default)
			)
			(layer "F.SilkS")
		)
		(fp_line
			(start -0.7874 0.4064)
			(end -0.7874 -0.4064)
			(stroke
				(width 0.1524)
				(type default)
			)
			(layer "F.SilkS")
		)
		(fp_line
			(start -0.7874 -0.4064)
			(end 0.7874 -0.4064)
			(stroke
				(width 0.1524)
				(type default)
			)
			(layer "F.SilkS")
		)
		(fp_line
			(start 0.67945 0.3048)
			(end 0.120396 0.3048)
			(stroke
				(width 0.1)
				(type default)
			)
			(layer "F.Fab")
		)
		(fp_line
			(start 0.67945 -0.3048)
			(end 0.67945 0.3048)
			(stroke
				(width 0.1)
				(type default)
			)
			(layer "F.Fab")
		)
		(fp_line
			(start 0.12065 -0.2794)
			(end 0.12065 -0.3048)
			(stroke
				(width 0.1)
				(type default)
			)
			(layer "F.Fab")
		)
		(fp_line
			(start 0.12065 -0.3048)
			(end 0.67945 -0.3048)
			(stroke
				(width 0.1)
				(type default)
			)
			(layer "F.Fab")
		)
		(fp_line
			(start 0.120396 0.3048)
			(end 0.120396 0.2794)
			(stroke
				(width 0.1)
				(type default)
			)
			(layer "F.Fab")
		)
		(fp_line
			(start 0.120396 0.2794)
			(end -0.12065 0.2794)
			(stroke
				(width 0.1)
				(type default)
			)
			(layer "F.Fab")
		)
		(fp_line
			(start -0.12065 0.3048)
			(end -0.67945 0.3048)
			(stroke
				(width 0.1)
				(type default)
			)
			(layer "F.Fab")
		)
		(fp_line
			(start -0.12065 0.2794)
			(end -0.12065 0.3048)
			(stroke
				(width 0.1)
				(type default)
			)
			(layer "F.Fab")
		)
		(fp_line
			(start -0.12065 -0.2794)
			(end 0.12065 -0.2794)
			(stroke
				(width 0.1)
				(type default)
			)
			(layer "F.Fab")
		)
		(fp_line
			(start -0.12065 -0.305054)
			(end -0.12065 -0.2794)
			(stroke
				(width 0.1)
				(type default)
			)
			(layer "F.Fab")
		)
		(fp_line
			(start -0.67945 0.3048)
			(end -0.67945 -0.305054)
			(stroke
				(width 0.1)
				(type default)
			)
			(layer "F.Fab")
		)
		(fp_line
			(start -0.67945 -0.305054)
			(end -0.12065 -0.305054)
			(stroke
				(width 0.1)
				(type default)
			)
			(layer "F.Fab")
		)
		(pad "1" smd circle
			(at -0.40005 0 180)
			(size 0 0)
			(layers "F.Cu" "F.Mask" "F.Paste")
			(net "GND")
		)
		(pad "2" smd circle
			(at 0.40005 0 180)
			(size 0 0)
			(layers "F.Cu" "F.Mask" "F.Paste")
			(net "P3V3_SSD1")
		)
	)
	(footprint ""
		(layer "F.Cu")
		(at 99.57943 -385.177792 180)
		(property "Reference" "R6293"
			(at 0 0 180)
			(layer "F.SilkS")
			(hide yes)
			(effects
				(font
					(size 1.27 1.27)
				)
			)
		)
		(property "Value" ""
			(at 0 0 180)
			(layer "F.Fab")
			(effects
				(font
					(size 1.27 1.27)
				)
			)
		)
		(duplicate_pad_numbers_are_jumpers no)
		(fp_line
			(start 0.7874 0.4064)
			(end -0.7874 0.4064)
			(stroke
				(width 0.1524)
				(type default)
			)
			(layer "F.SilkS")
		)
		(fp_line
			(start 0.7874 -0.4064)
			(end 0.7874 0.4064)
			(stroke
				(width 0.1524)
				(type default)
			)
			(layer "F.SilkS")
		)
		(fp_line
			(start -0.7874 -0.4064)
			(end 0.7874 -0.4064)
			(stroke
				(width 0.1524)
				(type default)
			)
			(layer "F.SilkS")
		)
		(fp_line
			(start 0.67945 0.3048)
			(end 0.120396 0.3048)
			(stroke
				(width 0.1)
				(type default)
			)
			(layer "F.Fab")
		)
		(fp_line
			(start 0.67945 -0.3048)
			(end 0.67945 0.3048)
			(stroke
				(width 0.1)
				(type default)
			)
			(layer "F.Fab")
		)
		(fp_line
			(start 0.12065 -0.2794)
			(end 0.12065 -0.3048)
			(stroke
				(width 0.1)
				(type default)
			)
			(layer "F.Fab")
		)
		(fp_line
			(start 0.12065 -0.3048)
			(end 0.67945 -0.3048)
			(stroke
				(width 0.1)
				(type default)
			)
			(layer "F.Fab")
		)
		(fp_line
			(start 0.120396 0.3048)
			(end 0.120396 0.2794)
			(stroke
				(width 0.1)
				(type default)
			)
			(layer "F.Fab")
		)
		(fp_line
			(start 0.120396 0.2794)
			(end -0.12065 0.2794)
			(stroke
				(width 0.1)
				(type default)
			)
			(layer "F.Fab")
		)
		(fp_line
			(start -0.12065 0.3048)
			(end -0.67945 0.3048)
			(stroke
				(width 0.1)
				(type default)
			)
			(layer "F.Fab")
		)
		(fp_line
			(start -0.12065 0.2794)
			(end -0.12065 0.3048)
			(stroke
				(width 0.1)
				(type default)
			)
			(layer "F.Fab")
		)
		(fp_line
			(start -0.12065 -0.2794)
			(end 0.12065 -0.2794)
			(stroke
				(width 0.1)
				(type default)
			)
			(layer "F.Fab")
		)
		(fp_line
			(start -0.12065 -0.305054)
			(end -0.12065 -0.2794)
			(stroke
				(width 0.1)
				(type default)
			)
			(layer "F.Fab")
		)
		(fp_line
			(start -0.67945 0.3048)
			(end -0.67945 -0.305054)
			(stroke
				(width 0.1)
				(type default)
			)
			(layer "F.Fab")
		)
		(fp_line
			(start -0.67945 -0.305054)
			(end -0.12065 -0.305054)
			(stroke
				(width 0.1)
				(type default)
			)
			(layer "F.Fab")
		)
		(pad "1" smd rect
			(at -0.40005 0)
			(size 0.4572 0.508)
			(layers "F.Cu" "F.Mask" "F.Paste")
			(net "USB2_MB_BMC_DN")
		)
		(pad "2" smd rect
			(at 0.40005 0)
			(size 0.4572 0.508)
			(layers "F.Cu" "F.Mask" "F.Paste")
			(net "GND")
		)
	)
	(footprint ""
		(layer "F.Cu")
		(at 267.394944 -59.577986 90)
		(property "Reference" "PC566"
			(at 0 0 90)
			(layer "F.SilkS")
			(hide yes)
			(effects
				(font
					(size 1.27 1.27)
				)
			)
		)
		(property "Value" ""
			(at 0 0 90)
			(layer "F.Fab")
			(effects
				(font
					(size 1.27 1.27)
				)
			)
		)
		(duplicate_pad_numbers_are_jumpers no)
		(fp_line
			(start 0.7874 -0.4064)
			(end 0.7874 0.4064)
			(stroke
				(width 0.1524)
				(type default)
			)
			(layer "F.SilkS")
		)
		(fp_line
			(start -0.7874 -0.4064)
			(end 0.7874 -0.4064)
			(stroke
				(width 0.1524)
				(type default)
			)
			(layer "F.SilkS")
		)
		(fp_line
			(start 0.7874 0.4064)
			(end -0.7874 0.4064)
			(stroke
				(width 0.1524)
				(type default)
			)
			(layer "F.SilkS")
		)
		(fp_line
			(start -0.7874 0.4064)
			(end -0.7874 -0.4064)
			(stroke
				(width 0.1524)
				(type default)
			)
			(layer "F.SilkS")
		)
		(fp_line
			(start -0.12065 -0.305054)
			(end -0.12065 -0.2794)
			(stroke
				(width 0.1)
				(type default)
			)
			(layer "F.Fab")
		)
		(fp_line
			(start -0.67945 -0.305054)
			(end -0.12065 -0.305054)
			(stroke
				(width 0.1)
				(type default)
			)
			(layer "F.Fab")
		)
		(fp_line
			(start 0.67945 -0.3048)
			(end 0.67945 0.3048)
			(stroke
				(width 0.1)
				(type default)
			)
			(layer "F.Fab")
		)
		(fp_line
			(start 0.12065 -0.3048)
			(end 0.67945 -0.3048)
			(stroke
				(width 0.1)
				(type default)
			)
			(layer "F.Fab")
		)
		(fp_line
			(start 0.12065 -0.2794)
			(end 0.12065 -0.3048)
			(stroke
				(width 0.1)
				(type default)
			)
			(layer "F.Fab")
		)
		(fp_line
			(start -0.12065 -0.2794)
			(end 0.12065 -0.2794)
			(stroke
				(width 0.1)
				(type default)
			)
			(layer "F.Fab")
		)
		(fp_line
			(start 0.120396 0.2794)
			(end -0.12065 0.2794)
			(stroke
				(width 0.1)
				(type default)
			)
			(layer "F.Fab")
		)
		(fp_line
			(start -0.12065 0.2794)
			(end -0.12065 0.3048)
			(stroke
				(width 0.1)
				(type default)
			)
			(layer "F.Fab")
		)
		(fp_line
			(start 0.67945 0.3048)
			(end 0.120396 0.3048)
			(stroke
				(width 0.1)
				(type default)
			)
			(layer "F.Fab")
		)
		(fp_line
			(start 0.120396 0.3048)
			(end 0.120396 0.2794)
			(stroke
				(width 0.1)
				(type default)
			)
			(layer "F.Fab")
		)
		(fp_line
			(start -0.12065 0.3048)
			(end -0.67945 0.3048)
			(stroke
				(width 0.1)
				(type default)
			)
			(layer "F.Fab")
		)
		(fp_line
			(start -0.67945 0.3048)
			(end -0.67945 -0.305054)
			(stroke
				(width 0.1)
				(type default)
			)
			(layer "F.Fab")
		)
		(pad "1" smd circle
			(at -0.40005 0 90)
			(size 0 0)
			(layers "F.Cu" "F.Mask" "F.Paste")
			(net "P3V3_SSD9_SS")
		)
		(pad "2" smd circle
			(at 0.40005 0 90)
			(size 0 0)
			(layers "F.Cu" "F.Mask" "F.Paste")
			(net "GND")
		)
	)
	(footprint ""
		(layer "F.Cu")
		(at 358.41051 -121.661428 180)
		(property "Reference" "C2882"
			(at 0 0 180)
			(layer "F.SilkS")
			(hide yes)
			(effects
				(font
					(size 1.27 1.27)
				)
			)
		)
		(property "Value" ""
			(at 0 0 180)
			(layer "F.Fab")
			(effects
				(font
					(size 1.27 1.27)
				)
			)
		)
		(duplicate_pad_numbers_are_jumpers no)
		(fp_line
			(start 0.7874 0.4064)
			(end -0.7874 0.4064)
			(stroke
				(width 0.1524)
				(type default)
			)
			(layer "F.SilkS")
		)
		(fp_line
			(start 0.7874 -0.4064)
			(end 0.7874 0.4064)
			(stroke
				(width 0.1524)
				(type default)
			)
			(layer "F.SilkS")
		)
		(fp_line
			(start -0.7874 0.4064)
			(end -0.7874 -0.4064)
			(stroke
				(width 0.1524)
				(type default)
			)
			(layer "F.SilkS")
		)
		(fp_line
			(start -0.7874 -0.4064)
			(end 0.7874 -0.4064)
			(stroke
				(width 0.1524)
				(type default)
			)
			(layer "F.SilkS")
		)
		(fp_line
			(start 0.67945 0.3048)
			(end 0.120396 0.3048)
			(stroke
				(width 0.1)
				(type default)
			)
			(layer "F.Fab")
		)
		(fp_line
			(start 0.67945 -0.3048)
			(end 0.67945 0.3048)
			(stroke
				(width 0.1)
				(type default)
			)
			(layer "F.Fab")
		)
		(fp_line
			(start 0.12065 -0.2794)
			(end 0.12065 -0.3048)
			(stroke
				(width 0.1)
				(type default)
			)
			(layer "F.Fab")
		)
		(fp_line
			(start 0.12065 -0.3048)
			(end 0.67945 -0.3048)
			(stroke
				(width 0.1)
				(type default)
			)
			(layer "F.Fab")
		)
		(fp_line
			(start 0.120396 0.3048)
			(end 0.120396 0.2794)
			(stroke
				(width 0.1)
				(type default)
			)
			(layer "F.Fab")
		)
		(fp_line
			(start 0.120396 0.2794)
			(end -0.12065 0.2794)
			(stroke
				(width 0.1)
				(type default)
			)
			(layer "F.Fab")
		)
		(fp_line
			(start -0.12065 0.3048)
			(end -0.67945 0.3048)
			(stroke
				(width 0.1)
				(type default)
			)
			(layer "F.Fab")
		)
		(fp_line
			(start -0.12065 0.2794)
			(end -0.12065 0.3048)
			(stroke
				(width 0.1)
				(type default)
			)
			(layer "F.Fab")
		)
		(fp_line
			(start -0.12065 -0.2794)
			(end 0.12065 -0.2794)
			(stroke
				(width 0.1)
				(type default)
			)
			(layer "F.Fab")
		)
		(fp_line
			(start -0.12065 -0.305054)
			(end -0.12065 -0.2794)
			(stroke
				(width 0.1)
				(type default)
			)
			(layer "F.Fab")
		)
		(fp_line
			(start -0.67945 0.3048)
			(end -0.67945 -0.305054)
			(stroke
				(width 0.1)
				(type default)
			)
			(layer "F.Fab")
		)
		(fp_line
			(start -0.67945 -0.305054)
			(end -0.12065 -0.305054)
			(stroke
				(width 0.1)
				(type default)
			)
			(layer "F.Fab")
		)
		(pad "1" smd circle
			(at -0.40005 0 180)
			(size 0 0)
			(layers "F.Cu" "F.Mask" "F.Paste")
			(net "HP_NIC6_EN")
		)
		(pad "2" smd circle
			(at 0.40005 0 180)
			(size 0 0)
			(layers "F.Cu" "F.Mask" "F.Paste")
			(net "GND")
		)
	)
	(footprint ""
		(layer "F.Cu")
		(at 407.67 -383.667 -90)
		(property "Reference" "R6282"
			(at 0 0 270)
			(layer "F.SilkS")
			(hide yes)
			(effects
				(font
					(size 1.27 1.27)
				)
			)
		)
		(property "Value" ""
			(at 0 0 270)
			(layer "F.Fab")
			(effects
				(font
					(size 1.27 1.27)
				)
			)
		)
		(duplicate_pad_numbers_are_jumpers no)
		(fp_line
			(start -0.7874 0.4064)
			(end -0.7874 -0.4064)
			(stroke
				(width 0.1524)
				(type default)
			)
			(layer "F.SilkS")
		)
		(fp_line
			(start 0.7874 0.4064)
			(end -0.7874 0.4064)
			(stroke
				(width 0.1524)
				(type default)
			)
			(layer "F.SilkS")
		)
		(fp_line
			(start -0.7874 -0.4064)
			(end 0.7874 -0.4064)
			(stroke
				(width 0.1524)
				(type default)
			)
			(layer "F.SilkS")
		)
		(fp_line
			(start 0.7874 -0.4064)
			(end 0.7874 0.4064)
			(stroke
				(width 0.1524)
				(type default)
			)
			(layer "F.SilkS")
		)
		(fp_line
			(start -0.67945 0.3048)
			(end -0.67945 -0.305054)
			(stroke
				(width 0.1)
				(type default)
			)
			(layer "F.Fab")
		)
		(fp_line
			(start -0.12065 0.3048)
			(end -0.67945 0.3048)
			(stroke
				(width 0.1)
				(type default)
			)
			(layer "F.Fab")
		)
		(fp_line
			(start 0.120396 0.3048)
			(end 0.120396 0.2794)
			(stroke
				(width 0.1)
				(type default)
			)
			(layer "F.Fab")
		)
		(fp_line
			(start 0.67945 0.3048)
			(end 0.120396 0.3048)
			(stroke
				(width 0.1)
				(type default)
			)
			(layer "F.Fab")
		)
		(fp_line
			(start -0.12065 0.2794)
			(end -0.12065 0.3048)
			(stroke
				(width 0.1)
				(type default)
			)
			(layer "F.Fab")
		)
		(fp_line
			(start 0.120396 0.2794)
			(end -0.12065 0.2794)
			(stroke
				(width 0.1)
				(type default)
			)
			(layer "F.Fab")
		)
		(fp_line
			(start -0.12065 -0.2794)
			(end 0.12065 -0.2794)
			(stroke
				(width 0.1)
				(type default)
			)
			(layer "F.Fab")
		)
		(fp_line
			(start 0.12065 -0.2794)
			(end 0.12065 -0.3048)
			(stroke
				(width 0.1)
				(type default)
			)
			(layer "F.Fab")
		)
		(fp_line
			(start 0.12065 -0.3048)
			(end 0.67945 -0.3048)
			(stroke
				(width 0.1)
				(type default)
			)
			(layer "F.Fab")
		)
		(fp_line
			(start 0.67945 -0.3048)
			(end 0.67945 0.3048)
			(stroke
				(width 0.1)
				(type default)
			)
			(layer "F.Fab")
		)
		(fp_line
			(start -0.67945 -0.305054)
			(end -0.12065 -0.305054)
			(stroke
				(width 0.1)
				(type default)
			)
			(layer "F.Fab")
		)
		(fp_line
			(start -0.12065 -0.305054)
			(end -0.12065 -0.2794)
			(stroke
				(width 0.1)
				(type default)
			)
			(layer "F.Fab")
		)
		(pad "1" smd circle
			(at -0.40005 0 270)
			(size 0 0)
			(layers "F.Cu" "F.Mask" "F.Paste")
			(net "P3V3_AUX")
		)
		(pad "2" smd circle
			(at 0.40005 0 270)
			(size 0 0)
			(layers "F.Cu" "F.Mask" "F.Paste")
			(net "I3C_MB_BMC_R_SDA")
		)
	)
	(footprint ""
		(layer "F.Cu")
		(at 440.359292 -343.952322 90)
		(property "Reference" "C796"
			(at 0 0 90)
			(layer "F.SilkS")
			(hide yes)
			(effects
				(font
					(size 1.27 1.27)
				)
			)
		)
		(property "Value" ""
			(at 0 0 90)
			(layer "F.Fab")
			(effects
				(font
					(size 1.27 1.27)
				)
			)
		)
		(duplicate_pad_numbers_are_jumpers no)
		(fp_line
			(start 0.299974 -0.150114)
			(end 0.299974 0.150114)
			(stroke
				(width 0.1)
				(type default)
			)
			(layer "F.Fab")
		)
		(fp_line
			(start -0.299974 -0.150114)
			(end 0.299974 -0.150114)
			(stroke
				(width 0.1)
				(type default)
			)
			(layer "F.Fab")
		)
		(fp_line
			(start 0.299974 0.150114)
			(end -0.299974 0.150114)
			(stroke
				(width 0.1)
				(type default)
			)
			(layer "F.Fab")
		)
		(fp_line
			(start -0.299974 0.150114)
			(end -0.299974 -0.150114)
			(stroke
				(width 0.1)
				(type default)
			)
			(layer "F.Fab")
		)
		(pad "1" smd rect
			(at -0.2667 0 90)
			(size 0.3048 0.381)
			(layers "F.Cu" "F.Mask" "F.Paste")
			(net "P5E_PEX3_STN7_TX_DP<126>")
		)
		(pad "2" smd rect
			(at 0.2667 0 90)
			(size 0.3048 0.381)
			(layers "F.Cu" "F.Mask" "F.Paste")
			(net "P5E_PEX3_STN7_TX_C_DP<126>")
		)
	)
	(footprint ""
		(layer "F.Cu")
		(at 428.319438 -146.190208 180)
		(property "Reference" "C645"
			(at 0 0 180)
			(layer "F.SilkS")
			(hide yes)
			(effects
				(font
					(size 1.27 1.27)
				)
			)
		)
		(property "Value" ""
			(at 0 0 180)
			(layer "F.Fab")
			(effects
				(font
					(size 1.27 1.27)
				)
			)
		)
		(duplicate_pad_numbers_are_jumpers no)
		(fp_line
			(start 0.299974 0.150114)
			(end -0.299974 0.150114)
			(stroke
				(width 0.1)
				(type default)
			)
			(layer "F.Fab")
		)
		(fp_line
			(start 0.299974 -0.150114)
			(end 0.299974 0.150114)
			(stroke
				(width 0.1)
				(type default)
			)
			(layer "F.Fab")
		)
		(fp_line
			(start -0.299974 0.150114)
			(end -0.299974 -0.150114)
			(stroke
				(width 0.1)
				(type default)
			)
			(layer "F.Fab")
		)
		(fp_line
			(start -0.299974 -0.150114)
			(end 0.299974 -0.150114)
			(stroke
				(width 0.1)
				(type default)
			)
			(layer "F.Fab")
		)
		(pad "1" smd rect
			(at -0.2667 0 180)
			(size 0.3048 0.381)
			(layers "F.Cu" "F.Mask" "F.Paste")
			(net "P5E_PEX3_STN0_TX_DN<10>")
		)
		(pad "2" smd rect
			(at 0.2667 0 180)
			(size 0.3048 0.381)
			(layers "F.Cu" "F.Mask" "F.Paste")
			(net "P5E_PEX3_STN0_TX_C_DN<10>")
		)
	)
	(footprint ""
		(layer "F.Cu")
		(at 235.623608 -144.672812)
		(property "Reference" "R4194"
			(at 0 0 0)
			(layer "F.SilkS")
			(hide yes)
			(effects
				(font
					(size 1.27 1.27)
				)
			)
		)
		(property "Value" ""
			(at 0 0 0)
			(layer "F.Fab")
			(effects
				(font
					(size 1.27 1.27)
				)
			)
		)
		(duplicate_pad_numbers_are_jumpers no)
		(fp_line
			(start -0.7874 -0.4064)
			(end 0.7874 -0.4064)
			(stroke
				(width 0.1524)
				(type default)
			)
			(layer "F.SilkS")
		)
		(fp_line
			(start -0.7874 0.4064)
			(end -0.7874 -0.4064)
			(stroke
				(width 0.1524)
				(type default)
			)
			(layer "F.SilkS")
		)
		(fp_line
			(start 0.7874 -0.4064)
			(end 0.7874 0.4064)
			(stroke
				(width 0.1524)
				(type default)
			)
			(layer "F.SilkS")
		)
		(fp_line
			(start 0.7874 0.4064)
			(end -0.7874 0.4064)
			(stroke
				(width 0.1524)
				(type default)
			)
			(layer "F.SilkS")
		)
		(fp_line
			(start -0.67945 -0.305054)
			(end -0.12065 -0.305054)
			(stroke
				(width 0.1)
				(type default)
			)
			(layer "F.Fab")
		)
		(fp_line
			(start -0.67945 0.3048)
			(end -0.67945 -0.305054)
			(stroke
				(width 0.1)
				(type default)
			)
			(layer "F.Fab")
		)
		(fp_line
			(start -0.12065 -0.305054)
			(end -0.12065 -0.2794)
			(stroke
				(width 0.1)
				(type default)
			)
			(layer "F.Fab")
		)
		(fp_line
			(start -0.12065 -0.2794)
			(end 0.12065 -0.2794)
			(stroke
				(width 0.1)
				(type default)
			)
			(layer "F.Fab")
		)
		(fp_line
			(start -0.12065 0.2794)
			(end -0.12065 0.3048)
			(stroke
				(width 0.1)
				(type default)
			)
			(layer "F.Fab")
		)
		(fp_line
			(start -0.12065 0.3048)
			(end -0.67945 0.3048)
			(stroke
				(width 0.1)
				(type default)
			)
			(layer "F.Fab")
		)
		(fp_line
			(start 0.120396 0.2794)
			(end -0.12065 0.2794)
			(stroke
				(width 0.1)
				(type default)
			)
			(layer "F.Fab")
		)
		(fp_line
			(start 0.120396 0.3048)
			(end 0.120396 0.2794)
			(stroke
				(width 0.1)
				(type default)
			)
			(layer "F.Fab")
		)
		(fp_line
			(start 0.12065 -0.3048)
			(end 0.67945 -0.3048)
			(stroke
				(width 0.1)
				(type default)
			)
			(layer "F.Fab")
		)
		(fp_line
			(start 0.12065 -0.2794)
			(end 0.12065 -0.3048)
			(stroke
				(width 0.1)
				(type default)
			)
			(layer "F.Fab")
		)
		(fp_line
			(start 0.67945 -0.3048)
			(end 0.67945 0.3048)
			(stroke
				(width 0.1)
				(type default)
			)
			(layer "F.Fab")
		)
		(fp_line
			(start 0.67945 0.3048)
			(end 0.120396 0.3048)
			(stroke
				(width 0.1)
				(type default)
			)
			(layer "F.Fab")
		)
		(pad "1" smd circle
			(at -0.40005 0)
			(size 0 0)
			(layers "F.Cu" "F.Mask" "F.Paste")
			(net "FM_CLK_EN_R")
		)
		(pad "2" smd circle
			(at 0.40005 0)
			(size 0 0)
			(layers "F.Cu" "F.Mask" "F.Paste")
			(net "P3V3")
		)
	)
	(footprint ""
		(layer "F.Cu")
		(at 331.978 -245.237 -90)
		(property "Reference" "R1784"
			(at 0 0 270)
			(layer "F.SilkS")
			(hide yes)
			(effects
				(font
					(size 1.27 1.27)
				)
			)
		)
		(property "Value" ""
			(at 0 0 270)
			(layer "F.Fab")
			(effects
				(font
					(size 1.27 1.27)
				)
			)
		)
		(duplicate_pad_numbers_are_jumpers no)
		(fp_line
			(start -0.7874 0.4064)
			(end -0.7874 -0.4064)
			(stroke
				(width 0.1524)
				(type default)
			)
			(layer "F.SilkS")
		)
		(fp_line
			(start 0.7874 0.4064)
			(end -0.7874 0.4064)
			(stroke
				(width 0.1524)
				(type default)
			)
			(layer "F.SilkS")
		)
		(fp_line
			(start -0.7874 -0.4064)
			(end 0.7874 -0.4064)
			(stroke
				(width 0.1524)
				(type default)
			)
			(layer "F.SilkS")
		)
		(fp_line
			(start 0.7874 -0.4064)
			(end 0.7874 0.4064)
			(stroke
				(width 0.1524)
				(type default)
			)
			(layer "F.SilkS")
		)
		(fp_line
			(start -0.67945 0.3048)
			(end -0.67945 -0.305054)
			(stroke
				(width 0.1)
				(type default)
			)
			(layer "F.Fab")
		)
		(fp_line
			(start -0.12065 0.3048)
			(end -0.67945 0.3048)
			(stroke
				(width 0.1)
				(type default)
			)
			(layer "F.Fab")
		)
		(fp_line
			(start 0.120396 0.3048)
			(end 0.120396 0.2794)
			(stroke
				(width 0.1)
				(type default)
			)
			(layer "F.Fab")
		)
		(fp_line
			(start 0.67945 0.3048)
			(end 0.120396 0.3048)
			(stroke
				(width 0.1)
				(type default)
			)
			(layer "F.Fab")
		)
		(fp_line
			(start -0.12065 0.2794)
			(end -0.12065 0.3048)
			(stroke
				(width 0.1)
				(type default)
			)
			(layer "F.Fab")
		)
		(fp_line
			(start 0.120396 0.2794)
			(end -0.12065 0.2794)
			(stroke
				(width 0.1)
				(type default)
			)
			(layer "F.Fab")
		)
		(fp_line
			(start -0.12065 -0.2794)
			(end 0.12065 -0.2794)
			(stroke
				(width 0.1)
				(type default)
			)
			(layer "F.Fab")
		)
		(fp_line
			(start 0.12065 -0.2794)
			(end 0.12065 -0.3048)
			(stroke
				(width 0.1)
				(type default)
			)
			(layer "F.Fab")
		)
		(fp_line
			(start 0.12065 -0.3048)
			(end 0.67945 -0.3048)
			(stroke
				(width 0.1)
				(type default)
			)
			(layer "F.Fab")
		)
		(fp_line
			(start 0.67945 -0.3048)
			(end 0.67945 0.3048)
			(stroke
				(width 0.1)
				(type default)
			)
			(layer "F.Fab")
		)
		(fp_line
			(start -0.67945 -0.305054)
			(end -0.12065 -0.305054)
			(stroke
				(width 0.1)
				(type default)
			)
			(layer "F.Fab")
		)
		(fp_line
			(start -0.12065 -0.305054)
			(end -0.12065 -0.2794)
			(stroke
				(width 0.1)
				(type default)
			)
			(layer "F.Fab")
		)
		(pad "1" smd circle
			(at -0.40005 0 270)
			(size 0 0)
			(layers "F.Cu" "F.Mask" "F.Paste")
			(net "P3V3_AUX")
		)
		(pad "2" smd circle
			(at 0.40005 0 270)
			(size 0 0)
			(layers "F.Cu" "F.Mask" "F.Paste")
			(net "RST_MB_PERST_0_N")
		)
	)
	(footprint ""
		(layer "F.Cu")
		(at 428.837852 -350.098614 90)
		(property "Reference" "C2458"
			(at 0 0 90)
			(layer "F.SilkS")
			(hide yes)
			(effects
				(font
					(size 1.27 1.27)
				)
			)
		)
		(property "Value" ""
			(at 0 0 90)
			(layer "F.Fab")
			(effects
				(font
					(size 1.27 1.27)
				)
			)
		)
		(duplicate_pad_numbers_are_jumpers no)
		(fp_line
			(start 0.299974 -0.150114)
			(end 0.299974 0.150114)
			(stroke
				(width 0.1)
				(type default)
			)
			(layer "F.Fab")
		)
		(fp_line
			(start -0.299974 -0.150114)
			(end 0.299974 -0.150114)
			(stroke
				(width 0.1)
				(type default)
			)
			(layer "F.Fab")
		)
		(fp_line
			(start 0.299974 0.150114)
			(end -0.299974 0.150114)
			(stroke
				(width 0.1)
				(type default)
			)
			(layer "F.Fab")
		)
		(fp_line
			(start -0.299974 0.150114)
			(end -0.299974 -0.150114)
			(stroke
				(width 0.1)
				(type default)
			)
			(layer "F.Fab")
		)
		(pad "1" smd rect
			(at -0.2667 0 90)
			(size 0.3048 0.381)
			(layers "F.Cu" "F.Mask" "F.Paste")
			(net "P5E_PEX3_STN4_TX_DN<70>")
		)
		(pad "2" smd rect
			(at 0.2667 0 90)
			(size 0.3048 0.381)
			(layers "F.Cu" "F.Mask" "F.Paste")
			(net "P5E_PEX3_STN4_TX_C_DN<70>")
		)
	)
	(footprint ""
		(layer "F.Cu")
		(at 168.367964 -51.019456)
		(property "Reference" "PC375"
			(at 0 0 0)
			(layer "F.SilkS")
			(hide yes)
			(effects
				(font
					(size 1.27 1.27)
				)
			)
		)
		(property "Value" ""
			(at 0 0 0)
			(layer "F.Fab")
			(effects
				(font
					(size 1.27 1.27)
				)
			)
		)
		(duplicate_pad_numbers_are_jumpers no)
		(fp_line
			(start -0.7874 -0.4064)
			(end 0.7874 -0.4064)
			(stroke
				(width 0.1524)
				(type default)
			)
			(layer "F.SilkS")
		)
		(fp_line
			(start -0.7874 0.4064)
			(end -0.7874 -0.4064)
			(stroke
				(width 0.1524)
				(type default)
			)
			(layer "F.SilkS")
		)
		(fp_line
			(start 0.7874 -0.4064)
			(end 0.7874 0.4064)
			(stroke
				(width 0.1524)
				(type default)
			)
			(layer "F.SilkS")
		)
		(fp_line
			(start 0.7874 0.4064)
			(end -0.7874 0.4064)
			(stroke
				(width 0.1524)
				(type default)
			)
			(layer "F.SilkS")
		)
		(fp_line
			(start -0.6858 -0.3048)
			(end -0.1016 -0.3048)
			(stroke
				(width 0.1)
				(type default)
			)
			(layer "F.Fab")
		)
		(fp_line
			(start -0.6858 0.3048)
			(end -0.6858 -0.3048)
			(stroke
				(width 0.1)
				(type default)
			)
			(layer "F.Fab")
		)
		(fp_line
			(start -0.1016 -0.3048)
			(end -0.1016 -0.2794)
			(stroke
				(width 0.1)
				(type default)
			)
			(layer "F.Fab")
		)
		(fp_line
			(start -0.1016 -0.2794)
			(end 0.1016 -0.2794)
			(stroke
				(width 0.1)
				(type default)
			)
			(layer "F.Fab")
		)
		(fp_line
			(start -0.1016 0.2794)
			(end -0.1016 0.3048)
			(stroke
				(width 0.1)
				(type default)
			)
			(layer "F.Fab")
		)
		(fp_line
			(start -0.1016 0.3048)
			(end -0.6858 0.3048)
			(stroke
				(width 0.1)
				(type default)
			)
			(layer "F.Fab")
		)
		(fp_line
			(start 0.1016 -0.3048)
			(end 0.6858 -0.3048)
			(stroke
				(width 0.1)
				(type default)
			)
			(layer "F.Fab")
		)
		(fp_line
			(start 0.1016 -0.2794)
			(end 0.1016 -0.3048)
			(stroke
				(width 0.1)
				(type default)
			)
			(layer "F.Fab")
		)
		(fp_line
			(start 0.1016 0.2794)
			(end -0.1016 0.2794)
			(stroke
				(width 0.1)
				(type default)
			)
			(layer "F.Fab")
		)
		(fp_line
			(start 0.1016 0.3048)
			(end 0.1016 0.2794)
			(stroke
				(width 0.1)
				(type default)
			)
			(layer "F.Fab")
		)
		(fp_line
			(start 0.6858 -0.3048)
			(end 0.6858 0.3048)
			(stroke
				(width 0.1)
				(type default)
			)
			(layer "F.Fab")
		)
		(fp_line
			(start 0.6858 0.3048)
			(end 0.1016 0.3048)
			(stroke
				(width 0.1)
				(type default)
			)
			(layer "F.Fab")
		)
		(pad "1" smd rect
			(at -0.40005 0 180)
			(size 0.4572 0.508)
			(layers "F.Cu" "F.Mask" "F.Paste")
			(net "P12V_SSD5_SS")
		)
		(pad "2" smd rect
			(at 0.40005 0 180)
			(size 0.4572 0.508)
			(layers "F.Cu" "F.Mask" "F.Paste")
			(net "GND")
		)
	)
	(footprint ""
		(layer "F.Cu")
		(at 201.970386 -302.308514 90)
		(property "Reference" "R6718"
			(at 0 0 90)
			(layer "F.SilkS")
			(hide yes)
			(effects
				(font
					(size 1.27 1.27)
				)
			)
		)
		(property "Value" ""
			(at 0 0 90)
			(layer "F.Fab")
			(effects
				(font
					(size 1.27 1.27)
				)
			)
		)
		(duplicate_pad_numbers_are_jumpers no)
		(fp_line
			(start 0.7874 -0.4064)
			(end 0.7874 0.4064)
			(stroke
				(width 0.1524)
				(type default)
			)
			(layer "F.SilkS")
		)
		(fp_line
			(start -0.7874 -0.4064)
			(end 0.7874 -0.4064)
			(stroke
				(width 0.1524)
				(type default)
			)
			(layer "F.SilkS")
		)
		(fp_line
			(start 0.7874 0.4064)
			(end -0.7874 0.4064)
			(stroke
				(width 0.1524)
				(type default)
			)
			(layer "F.SilkS")
		)
		(fp_line
			(start -0.7874 0.4064)
			(end -0.7874 -0.4064)
			(stroke
				(width 0.1524)
				(type default)
			)
			(layer "F.SilkS")
		)
		(fp_line
			(start -0.12065 -0.305054)
			(end -0.12065 -0.2794)
			(stroke
				(width 0.1)
				(type default)
			)
			(layer "F.Fab")
		)
		(fp_line
			(start -0.67945 -0.305054)
			(end -0.12065 -0.305054)
			(stroke
				(width 0.1)
				(type default)
			)
			(layer "F.Fab")
		)
		(fp_line
			(start 0.67945 -0.3048)
			(end 0.67945 0.3048)
			(stroke
				(width 0.1)
				(type default)
			)
			(layer "F.Fab")
		)
		(fp_line
			(start 0.12065 -0.3048)
			(end 0.67945 -0.3048)
			(stroke
				(width 0.1)
				(type default)
			)
			(layer "F.Fab")
		)
		(fp_line
			(start 0.12065 -0.2794)
			(end 0.12065 -0.3048)
			(stroke
				(width 0.1)
				(type default)
			)
			(layer "F.Fab")
		)
		(fp_line
			(start -0.12065 -0.2794)
			(end 0.12065 -0.2794)
			(stroke
				(width 0.1)
				(type default)
			)
			(layer "F.Fab")
		)
		(fp_line
			(start 0.120396 0.2794)
			(end -0.12065 0.2794)
			(stroke
				(width 0.1)
				(type default)
			)
			(layer "F.Fab")
		)
		(fp_line
			(start -0.12065 0.2794)
			(end -0.12065 0.3048)
			(stroke
				(width 0.1)
				(type default)
			)
			(layer "F.Fab")
		)
		(fp_line
			(start 0.67945 0.3048)
			(end 0.120396 0.3048)
			(stroke
				(width 0.1)
				(type default)
			)
			(layer "F.Fab")
		)
		(fp_line
			(start 0.120396 0.3048)
			(end 0.120396 0.2794)
			(stroke
				(width 0.1)
				(type default)
			)
			(layer "F.Fab")
		)
		(fp_line
			(start -0.12065 0.3048)
			(end -0.67945 0.3048)
			(stroke
				(width 0.1)
				(type default)
			)
			(layer "F.Fab")
		)
		(fp_line
			(start -0.67945 0.3048)
			(end -0.67945 -0.305054)
			(stroke
				(width 0.1)
				(type default)
			)
			(layer "F.Fab")
		)
		(pad "1" smd circle
			(at -0.40005 0 90)
			(size 0 0)
			(layers "F.Cu" "F.Mask" "F.Paste")
			(net "SMB_PEX1_SLAVE1_SCL")
		)
		(pad "2" smd circle
			(at 0.40005 0 90)
			(size 0 0)
			(layers "F.Cu" "F.Mask" "F.Paste")
			(net "SMB_PEX1_R_SCL")
		)
	)
	(footprint ""
		(layer "F.Cu")
		(at 243.793264 -116.311426 -90)
		(property "Reference" "Q216"
			(at 0.131826 1.933194 90)
			(unlocked yes)
			(layer "F.SilkS")
			(effects
				(font
					(size 0.7874 0.5842)
					(thickness 0.1524)
				)
			)
		)
		(property "Value" ""
			(at 0 0 270)
			(layer "F.Fab")
			(effects
				(font
					(size 1.27 1.27)
				)
			)
		)
		(duplicate_pad_numbers_are_jumpers no)
		(fp_line
			(start -1.376172 1.199896)
			(end -1.376172 -1.199896)
			(stroke
				(width 0.1524)
				(type default)
			)
			(layer "F.SilkS")
		)
		(fp_line
			(start 1.376172 1.199896)
			(end -1.376172 1.199896)
			(stroke
				(width 0.1524)
				(type default)
			)
			(layer "F.SilkS")
		)
		(fp_line
			(start 0 -0.762)
			(end 0.508 -1.199896)
			(stroke
				(width 0.1524)
				(type default)
			)
			(layer "F.SilkS")
		)
		(fp_line
			(start -1.376172 -1.199896)
			(end -0.508 -1.199896)
			(stroke
				(width 0.1524)
				(type default)
			)
			(layer "F.SilkS")
		)
		(fp_line
			(start -0.508 -1.199896)
			(end 0 -0.762)
			(stroke
				(width 0.1524)
				(type default)
			)
			(layer "F.SilkS")
		)
		(fp_line
			(start 0.508 -1.199896)
			(end 1.376172 -1.199896)
			(stroke
				(width 0.1524)
				(type default)
			)
			(layer "F.SilkS")
		)
		(fp_line
			(start 1.376172 -1.199896)
			(end 1.376172 1.199896)
			(stroke
				(width 0.1524)
				(type default)
			)
			(layer "F.SilkS")
		)
		(fp_poly
			(pts
				(xy -1.151636 -1.323086) (xy -1.42113 -2.131314) (xy -1.959864 -1.59258)
			)
			(stroke
				(width 0)
				(type default)
			)
			(fill yes)
			(layer "F.SilkS")
		)
		(fp_line
			(start -0.674878 1.100074)
			(end -0.674878 -1.100074)
			(stroke
				(width 0.1)
				(type default)
			)
			(layer "F.Fab")
		)
		(fp_line
			(start 0.674878 1.100074)
			(end -0.674878 1.100074)
			(stroke
				(width 0.1)
				(type default)
			)
			(layer "F.Fab")
		)
		(fp_line
			(start -0.674878 -1.100074)
			(end 0.674878 -1.100074)
			(stroke
				(width 0.1)
				(type default)
			)
			(layer "F.Fab")
		)
		(fp_line
			(start 0.674878 -1.100074)
			(end 0.674878 1.100074)
			(stroke
				(width 0.1)
				(type default)
			)
			(layer "F.Fab")
		)
		(fp_poly
			(pts
				(xy -1.4605 -0.7493) (xy -2.2225 -1.1303) (xy -2.2225 -0.3683)
			)
			(stroke
				(width 0)
				(type default)
			)
			(fill yes)
			(layer "F.Fab")
		)
		(pad "1" smd rect
			(at -0.899922 -0.750062 180)
			(size 0.6096 0.6096)
			(layers "F.Cu" "F.Mask" "F.Paste")
			(net "GND")
		)
		(pad "2" smd rect
			(at -0.899922 0 180)
			(size 0.4064 0.6096)
			(layers "F.Cu" "F.Mask" "F.Paste")
			(net "P3V3_NIC4_PG_G1")
		)
		(pad "3" smd rect
			(at -0.899922 0.750062 180)
			(size 0.6096 0.6096)
			(layers "F.Cu" "F.Mask" "F.Paste")
			(net "PWRGD_P3V3_NIC4_D")
		)
		(pad "4" smd rect
			(at 0.899922 0.750062 180)
			(size 0.6096 0.6096)
			(layers "F.Cu" "F.Mask" "F.Paste")
			(net "GND")
		)
		(pad "5" smd rect
			(at 0.899922 0 180)
			(size 0.4064 0.6096)
			(layers "F.Cu" "F.Mask" "F.Paste")
			(net "P3V3_NIC4_PG_G2")
		)
		(pad "6" smd rect
			(at 0.899922 -0.750062 180)
			(size 0.6096 0.6096)
			(layers "F.Cu" "F.Mask" "F.Paste")
			(net "P3V3_NIC4_PG_G2")
		)
	)
	(footprint ""
		(layer "F.Cu")
		(at 194.343782 -47.92091)
		(property "Reference" "R570"
			(at 0 0 0)
			(layer "F.SilkS")
			(hide yes)
			(effects
				(font
					(size 1.27 1.27)
				)
			)
		)
		(property "Value" ""
			(at 0 0 0)
			(layer "F.Fab")
			(effects
				(font
					(size 1.27 1.27)
				)
			)
		)
		(duplicate_pad_numbers_are_jumpers no)
		(fp_line
			(start -0.7874 -0.4064)
			(end 0.7874 -0.4064)
			(stroke
				(width 0.1524)
				(type default)
			)
			(layer "F.SilkS")
		)
		(fp_line
			(start -0.7874 0.4064)
			(end -0.7874 -0.4064)
			(stroke
				(width 0.1524)
				(type default)
			)
			(layer "F.SilkS")
		)
		(fp_line
			(start 0.7874 -0.4064)
			(end 0.7874 0.4064)
			(stroke
				(width 0.1524)
				(type default)
			)
			(layer "F.SilkS")
		)
		(fp_line
			(start 0.7874 0.4064)
			(end -0.7874 0.4064)
			(stroke
				(width 0.1524)
				(type default)
			)
			(layer "F.SilkS")
		)
		(fp_line
			(start -0.67945 -0.305054)
			(end -0.12065 -0.305054)
			(stroke
				(width 0.1)
				(type default)
			)
			(layer "F.Fab")
		)
		(fp_line
			(start -0.67945 0.3048)
			(end -0.67945 -0.305054)
			(stroke
				(width 0.1)
				(type default)
			)
			(layer "F.Fab")
		)
		(fp_line
			(start -0.12065 -0.305054)
			(end -0.12065 -0.2794)
			(stroke
				(width 0.1)
				(type default)
			)
			(layer "F.Fab")
		)
		(fp_line
			(start -0.12065 -0.2794)
			(end 0.12065 -0.2794)
			(stroke
				(width 0.1)
				(type default)
			)
			(layer "F.Fab")
		)
		(fp_line
			(start -0.12065 0.2794)
			(end -0.12065 0.3048)
			(stroke
				(width 0.1)
				(type default)
			)
			(layer "F.Fab")
		)
		(fp_line
			(start -0.12065 0.3048)
			(end -0.67945 0.3048)
			(stroke
				(width 0.1)
				(type default)
			)
			(layer "F.Fab")
		)
		(fp_line
			(start 0.120396 0.2794)
			(end -0.12065 0.2794)
			(stroke
				(width 0.1)
				(type default)
			)
			(layer "F.Fab")
		)
		(fp_line
			(start 0.120396 0.3048)
			(end 0.120396 0.2794)
			(stroke
				(width 0.1)
				(type default)
			)
			(layer "F.Fab")
		)
		(fp_line
			(start 0.12065 -0.3048)
			(end 0.67945 -0.3048)
			(stroke
				(width 0.1)
				(type default)
			)
			(layer "F.Fab")
		)
		(fp_line
			(start 0.12065 -0.2794)
			(end 0.12065 -0.3048)
			(stroke
				(width 0.1)
				(type default)
			)
			(layer "F.Fab")
		)
		(fp_line
			(start 0.67945 -0.3048)
			(end 0.67945 0.3048)
			(stroke
				(width 0.1)
				(type default)
			)
			(layer "F.Fab")
		)
		(fp_line
			(start 0.67945 0.3048)
			(end 0.120396 0.3048)
			(stroke
				(width 0.1)
				(type default)
			)
			(layer "F.Fab")
		)
		(pad "1" smd circle
			(at -0.40005 0)
			(size 0 0)
			(layers "F.Cu" "F.Mask" "F.Paste")
			(net "P3V3_AUX")
		)
		(pad "2" smd circle
			(at 0.40005 0)
			(size 0 0)
			(layers "F.Cu" "F.Mask" "F.Paste")
			(net "SSD_0_7_ADC_ALERT_N")
		)
	)
	(footprint ""
		(layer "F.Cu")
		(at 32.411416 -296.445432 -90)
		(property "Reference" "R4558"
			(at 0 0 270)
			(layer "F.SilkS")
			(hide yes)
			(effects
				(font
					(size 1.27 1.27)
				)
			)
		)
		(property "Value" ""
			(at 0 0 270)
			(layer "F.Fab")
			(effects
				(font
					(size 1.27 1.27)
				)
			)
		)
		(duplicate_pad_numbers_are_jumpers no)
		(fp_line
			(start -0.7874 0.4064)
			(end -0.7874 -0.4064)
			(stroke
				(width 0.1524)
				(type default)
			)
			(layer "F.SilkS")
		)
		(fp_line
			(start 0.7874 0.4064)
			(end -0.7874 0.4064)
			(stroke
				(width 0.1524)
				(type default)
			)
			(layer "F.SilkS")
		)
		(fp_line
			(start -0.7874 -0.4064)
			(end 0.7874 -0.4064)
			(stroke
				(width 0.1524)
				(type default)
			)
			(layer "F.SilkS")
		)
		(fp_line
			(start 0.7874 -0.4064)
			(end 0.7874 0.4064)
			(stroke
				(width 0.1524)
				(type default)
			)
			(layer "F.SilkS")
		)
		(fp_line
			(start -0.67945 0.3048)
			(end -0.67945 -0.305054)
			(stroke
				(width 0.1)
				(type default)
			)
			(layer "F.Fab")
		)
		(fp_line
			(start -0.12065 0.3048)
			(end -0.67945 0.3048)
			(stroke
				(width 0.1)
				(type default)
			)
			(layer "F.Fab")
		)
		(fp_line
			(start 0.120396 0.3048)
			(end 0.120396 0.2794)
			(stroke
				(width 0.1)
				(type default)
			)
			(layer "F.Fab")
		)
		(fp_line
			(start 0.67945 0.3048)
			(end 0.120396 0.3048)
			(stroke
				(width 0.1)
				(type default)
			)
			(layer "F.Fab")
		)
		(fp_line
			(start -0.12065 0.2794)
			(end -0.12065 0.3048)
			(stroke
				(width 0.1)
				(type default)
			)
			(layer "F.Fab")
		)
		(fp_line
			(start 0.120396 0.2794)
			(end -0.12065 0.2794)
			(stroke
				(width 0.1)
				(type default)
			)
			(layer "F.Fab")
		)
		(fp_line
			(start -0.12065 -0.2794)
			(end 0.12065 -0.2794)
			(stroke
				(width 0.1)
				(type default)
			)
			(layer "F.Fab")
		)
		(fp_line
			(start 0.12065 -0.2794)
			(end 0.12065 -0.3048)
			(stroke
				(width 0.1)
				(type default)
			)
			(layer "F.Fab")
		)
		(fp_line
			(start 0.12065 -0.3048)
			(end 0.67945 -0.3048)
			(stroke
				(width 0.1)
				(type default)
			)
			(layer "F.Fab")
		)
		(fp_line
			(start 0.67945 -0.3048)
			(end 0.67945 0.3048)
			(stroke
				(width 0.1)
				(type default)
			)
			(layer "F.Fab")
		)
		(fp_line
			(start -0.67945 -0.305054)
			(end -0.12065 -0.305054)
			(stroke
				(width 0.1)
				(type default)
			)
			(layer "F.Fab")
		)
		(fp_line
			(start -0.12065 -0.305054)
			(end -0.12065 -0.2794)
			(stroke
				(width 0.1)
				(type default)
			)
			(layer "F.Fab")
		)
		(pad "1" smd circle
			(at -0.40005 0 270)
			(size 0 0)
			(layers "F.Cu" "F.Mask" "F.Paste")
			(net "PCEPLL0_VDDA18_PEX0")
		)
		(pad "2" smd circle
			(at 0.40005 0 270)
			(size 0 0)
			(layers "F.Cu" "F.Mask" "F.Paste")
			(net "PCEPLL0_VDDA18_PEX0_R")
		)
	)
	(footprint ""
		(layer "F.Cu")
		(at 38.608 -163.061396 180)
		(property "Reference" "R4"
			(at 0 0 180)
			(layer "F.SilkS")
			(hide yes)
			(effects
				(font
					(size 1.27 1.27)
				)
			)
		)
		(property "Value" ""
			(at 0 0 180)
			(layer "F.Fab")
			(effects
				(font
					(size 1.27 1.27)
				)
			)
		)
		(duplicate_pad_numbers_are_jumpers no)
		(fp_line
			(start 0.7874 0.4064)
			(end -0.7874 0.4064)
			(stroke
				(width 0.1524)
				(type default)
			)
			(layer "F.SilkS")
		)
		(fp_line
			(start 0.7874 -0.4064)
			(end 0.7874 0.4064)
			(stroke
				(width 0.1524)
				(type default)
			)
			(layer "F.SilkS")
		)
		(fp_line
			(start -0.7874 0.4064)
			(end -0.7874 -0.4064)
			(stroke
				(width 0.1524)
				(type default)
			)
			(layer "F.SilkS")
		)
		(fp_line
			(start -0.7874 -0.4064)
			(end 0.7874 -0.4064)
			(stroke
				(width 0.1524)
				(type default)
			)
			(layer "F.SilkS")
		)
		(fp_line
			(start 0.67945 0.3048)
			(end 0.120396 0.3048)
			(stroke
				(width 0.1)
				(type default)
			)
			(layer "F.Fab")
		)
		(fp_line
			(start 0.67945 -0.3048)
			(end 0.67945 0.3048)
			(stroke
				(width 0.1)
				(type default)
			)
			(layer "F.Fab")
		)
		(fp_line
			(start 0.12065 -0.2794)
			(end 0.12065 -0.3048)
			(stroke
				(width 0.1)
				(type default)
			)
			(layer "F.Fab")
		)
		(fp_line
			(start 0.12065 -0.3048)
			(end 0.67945 -0.3048)
			(stroke
				(width 0.1)
				(type default)
			)
			(layer "F.Fab")
		)
		(fp_line
			(start 0.120396 0.3048)
			(end 0.120396 0.2794)
			(stroke
				(width 0.1)
				(type default)
			)
			(layer "F.Fab")
		)
		(fp_line
			(start 0.120396 0.2794)
			(end -0.12065 0.2794)
			(stroke
				(width 0.1)
				(type default)
			)
			(layer "F.Fab")
		)
		(fp_line
			(start -0.12065 0.3048)
			(end -0.67945 0.3048)
			(stroke
				(width 0.1)
				(type default)
			)
			(layer "F.Fab")
		)
		(fp_line
			(start -0.12065 0.2794)
			(end -0.12065 0.3048)
			(stroke
				(width 0.1)
				(type default)
			)
			(layer "F.Fab")
		)
		(fp_line
			(start -0.12065 -0.2794)
			(end 0.12065 -0.2794)
			(stroke
				(width 0.1)
				(type default)
			)
			(layer "F.Fab")
		)
		(fp_line
			(start -0.12065 -0.305054)
			(end -0.12065 -0.2794)
			(stroke
				(width 0.1)
				(type default)
			)
			(layer "F.Fab")
		)
		(fp_line
			(start -0.67945 0.3048)
			(end -0.67945 -0.305054)
			(stroke
				(width 0.1)
				(type default)
			)
			(layer "F.Fab")
		)
		(fp_line
			(start -0.67945 -0.305054)
			(end -0.12065 -0.305054)
			(stroke
				(width 0.1)
				(type default)
			)
			(layer "F.Fab")
		)
		(pad "1" smd circle
			(at -0.40005 0 180)
			(size 0 0)
			(layers "F.Cu" "F.Mask" "F.Paste")
			(net "PWRGD_NIC0_PWR_GOOD")
		)
		(pad "2" smd circle
			(at 0.40005 0 180)
			(size 0 0)
			(layers "F.Cu" "F.Mask" "F.Paste")
			(net "PWRGD_NIC0_PWR_GOOD_R")
		)
	)
	(footprint ""
		(layer "F.Cu")
		(at 92.352622 -311.197244 135)
		(property "Reference" "R1246"
			(at 0 0 135)
			(layer "F.SilkS")
			(hide yes)
			(effects
				(font
					(size 1.27 1.27)
				)
			)
		)
		(property "Value" ""
			(at 0 0 135)
			(layer "F.Fab")
			(effects
				(font
					(size 1.27 1.27)
				)
			)
		)
		(duplicate_pad_numbers_are_jumpers no)
		(fp_line
			(start 0.787389 -0.406267)
			(end 0.787389 0.406267)
			(stroke
				(width 0.1524)
				(type default)
			)
			(layer "F.SilkS")
		)
		(fp_line
			(start 0.787389 0.406267)
			(end -0.787389 0.406267)
			(stroke
				(width 0.1524)
				(type default)
			)
			(layer "F.SilkS")
		)
		(fp_line
			(start -0.787389 -0.406267)
			(end 0.787389 -0.406267)
			(stroke
				(width 0.1524)
				(type default)
			)
			(layer "F.SilkS")
		)
		(fp_line
			(start -0.787389 0.406267)
			(end -0.787389 -0.406267)
			(stroke
				(width 0.1524)
				(type default)
			)
			(layer "F.SilkS")
		)
		(fp_line
			(start 0.679446 -0.30479)
			(end 0.679446 0.30479)
			(stroke
				(width 0.1)
				(type default)
			)
			(layer "F.Fab")
		)
		(fp_line
			(start 0.120515 -0.30479)
			(end 0.679446 -0.30479)
			(stroke
				(width 0.1)
				(type default)
			)
			(layer "F.Fab")
		)
		(fp_line
			(start 0.120695 -0.279466)
			(end 0.120515 -0.30479)
			(stroke
				(width 0.1)
				(type default)
			)
			(layer "F.Fab")
		)
		(fp_line
			(start 0.679446 0.30479)
			(end 0.120515 0.30479)
			(stroke
				(width 0.1)
				(type default)
			)
			(layer "F.Fab")
		)
		(fp_line
			(start -0.120695 -0.304969)
			(end -0.120695 -0.279466)
			(stroke
				(width 0.1)
				(type default)
			)
			(layer "F.Fab")
		)
		(fp_line
			(start -0.120695 -0.279466)
			(end 0.120695 -0.279466)
			(stroke
				(width 0.1)
				(type default)
			)
			(layer "F.Fab")
		)
		(fp_line
			(start 0.120335 0.279466)
			(end -0.120695 0.279466)
			(stroke
				(width 0.1)
				(type default)
			)
			(layer "F.Fab")
		)
		(fp_line
			(start 0.120515 0.30479)
			(end 0.120335 0.279466)
			(stroke
				(width 0.1)
				(type default)
			)
			(layer "F.Fab")
		)
		(fp_line
			(start -0.679446 -0.305149)
			(end -0.120695 -0.304969)
			(stroke
				(width 0.1)
				(type default)
			)
			(layer "F.Fab")
		)
		(fp_line
			(start -0.120695 0.279466)
			(end -0.120515 0.30479)
			(stroke
				(width 0.1)
				(type default)
			)
			(layer "F.Fab")
		)
		(fp_line
			(start -0.120515 0.30479)
			(end -0.679446 0.30479)
			(stroke
				(width 0.1)
				(type default)
			)
			(layer "F.Fab")
		)
		(fp_line
			(start -0.679446 0.30479)
			(end -0.679446 -0.305149)
			(stroke
				(width 0.1)
				(type default)
			)
			(layer "F.Fab")
		)
		(pad "1" smd circle
			(at -0.40005 0 135)
			(size 0 0)
			(layers "F.Cu" "F.Mask" "F.Paste")
			(net "GND")
		)
		(pad "2" smd circle
			(at 0.40005 0 135)
			(size 0 0)
			(layers "F.Cu" "F.Mask" "F.Paste")
			(net "PEX0_SPARE5")
		)
	)
	(footprint ""
		(layer "F.Cu")
		(at 338.074 -149.987 180)
		(property "Reference" "R4844"
			(at 0 0 180)
			(layer "F.SilkS")
			(hide yes)
			(effects
				(font
					(size 1.27 1.27)
				)
			)
		)
		(property "Value" ""
			(at 0 0 180)
			(layer "F.Fab")
			(effects
				(font
					(size 1.27 1.27)
				)
			)
		)
		(duplicate_pad_numbers_are_jumpers no)
		(fp_line
			(start 0.7874 0.4064)
			(end -0.7874 0.4064)
			(stroke
				(width 0.1524)
				(type default)
			)
			(layer "F.SilkS")
		)
		(fp_line
			(start 0.7874 -0.4064)
			(end 0.7874 0.4064)
			(stroke
				(width 0.1524)
				(type default)
			)
			(layer "F.SilkS")
		)
		(fp_line
			(start -0.7874 0.4064)
			(end -0.7874 -0.4064)
			(stroke
				(width 0.1524)
				(type default)
			)
			(layer "F.SilkS")
		)
		(fp_line
			(start -0.7874 -0.4064)
			(end 0.7874 -0.4064)
			(stroke
				(width 0.1524)
				(type default)
			)
			(layer "F.SilkS")
		)
		(fp_line
			(start 0.67945 0.3048)
			(end 0.120396 0.3048)
			(stroke
				(width 0.1)
				(type default)
			)
			(layer "F.Fab")
		)
		(fp_line
			(start 0.67945 -0.3048)
			(end 0.67945 0.3048)
			(stroke
				(width 0.1)
				(type default)
			)
			(layer "F.Fab")
		)
		(fp_line
			(start 0.12065 -0.2794)
			(end 0.12065 -0.3048)
			(stroke
				(width 0.1)
				(type default)
			)
			(layer "F.Fab")
		)
		(fp_line
			(start 0.12065 -0.3048)
			(end 0.67945 -0.3048)
			(stroke
				(width 0.1)
				(type default)
			)
			(layer "F.Fab")
		)
		(fp_line
			(start 0.120396 0.3048)
			(end 0.120396 0.2794)
			(stroke
				(width 0.1)
				(type default)
			)
			(layer "F.Fab")
		)
		(fp_line
			(start 0.120396 0.2794)
			(end -0.12065 0.2794)
			(stroke
				(width 0.1)
				(type default)
			)
			(layer "F.Fab")
		)
		(fp_line
			(start -0.12065 0.3048)
			(end -0.67945 0.3048)
			(stroke
				(width 0.1)
				(type default)
			)
			(layer "F.Fab")
		)
		(fp_line
			(start -0.12065 0.2794)
			(end -0.12065 0.3048)
			(stroke
				(width 0.1)
				(type default)
			)
			(layer "F.Fab")
		)
		(fp_line
			(start -0.12065 -0.2794)
			(end 0.12065 -0.2794)
			(stroke
				(width 0.1)
				(type default)
			)
			(layer "F.Fab")
		)
		(fp_line
			(start -0.12065 -0.305054)
			(end -0.12065 -0.2794)
			(stroke
				(width 0.1)
				(type default)
			)
			(layer "F.Fab")
		)
		(fp_line
			(start -0.67945 0.3048)
			(end -0.67945 -0.305054)
			(stroke
				(width 0.1)
				(type default)
			)
			(layer "F.Fab")
		)
		(fp_line
			(start -0.67945 -0.305054)
			(end -0.12065 -0.305054)
			(stroke
				(width 0.1)
				(type default)
			)
			(layer "F.Fab")
		)
		(pad "1" smd circle
			(at -0.40005 0 180)
			(size 0 0)
			(layers "F.Cu" "F.Mask" "F.Paste")
			(net "GND")
		)
		(pad "2" smd circle
			(at 0.40005 0 180)
			(size 0 0)
			(layers "F.Cu" "F.Mask" "F.Paste")
			(net "PCA9555_1_PEX3_A1")
		)
	)
	(footprint ""
		(layer "F.Cu")
		(at 115.727226 -318.51473 90)
		(property "Reference" "R6459"
			(at 0 0 90)
			(layer "F.SilkS")
			(hide yes)
			(effects
				(font
					(size 1.27 1.27)
				)
			)
		)
		(property "Value" ""
			(at 0 0 90)
			(layer "F.Fab")
			(effects
				(font
					(size 1.27 1.27)
				)
			)
		)
		(duplicate_pad_numbers_are_jumpers no)
		(fp_line
			(start 0.7874 -0.4064)
			(end 0.7874 0.4064)
			(stroke
				(width 0.1524)
				(type default)
			)
			(layer "F.SilkS")
		)
		(fp_line
			(start -0.7874 -0.4064)
			(end 0.7874 -0.4064)
			(stroke
				(width 0.1524)
				(type default)
			)
			(layer "F.SilkS")
		)
		(fp_line
			(start 0.7874 0.4064)
			(end -0.7874 0.4064)
			(stroke
				(width 0.1524)
				(type default)
			)
			(layer "F.SilkS")
		)
		(fp_line
			(start -0.7874 0.4064)
			(end -0.7874 -0.4064)
			(stroke
				(width 0.1524)
				(type default)
			)
			(layer "F.SilkS")
		)
		(fp_line
			(start -0.12065 -0.305054)
			(end -0.12065 -0.2794)
			(stroke
				(width 0.1)
				(type default)
			)
			(layer "F.Fab")
		)
		(fp_line
			(start -0.67945 -0.305054)
			(end -0.12065 -0.305054)
			(stroke
				(width 0.1)
				(type default)
			)
			(layer "F.Fab")
		)
		(fp_line
			(start 0.67945 -0.3048)
			(end 0.67945 0.3048)
			(stroke
				(width 0.1)
				(type default)
			)
			(layer "F.Fab")
		)
		(fp_line
			(start 0.12065 -0.3048)
			(end 0.67945 -0.3048)
			(stroke
				(width 0.1)
				(type default)
			)
			(layer "F.Fab")
		)
		(fp_line
			(start 0.12065 -0.2794)
			(end 0.12065 -0.3048)
			(stroke
				(width 0.1)
				(type default)
			)
			(layer "F.Fab")
		)
		(fp_line
			(start -0.12065 -0.2794)
			(end 0.12065 -0.2794)
			(stroke
				(width 0.1)
				(type default)
			)
			(layer "F.Fab")
		)
		(fp_line
			(start 0.120396 0.2794)
			(end -0.12065 0.2794)
			(stroke
				(width 0.1)
				(type default)
			)
			(layer "F.Fab")
		)
		(fp_line
			(start -0.12065 0.2794)
			(end -0.12065 0.3048)
			(stroke
				(width 0.1)
				(type default)
			)
			(layer "F.Fab")
		)
		(fp_line
			(start 0.67945 0.3048)
			(end 0.120396 0.3048)
			(stroke
				(width 0.1)
				(type default)
			)
			(layer "F.Fab")
		)
		(fp_line
			(start 0.120396 0.3048)
			(end 0.120396 0.2794)
			(stroke
				(width 0.1)
				(type default)
			)
			(layer "F.Fab")
		)
		(fp_line
			(start -0.12065 0.3048)
			(end -0.67945 0.3048)
			(stroke
				(width 0.1)
				(type default)
			)
			(layer "F.Fab")
		)
		(fp_line
			(start -0.67945 0.3048)
			(end -0.67945 -0.305054)
			(stroke
				(width 0.1)
				(type default)
			)
			(layer "F.Fab")
		)
		(pad "1" smd circle
			(at -0.40005 0 90)
			(size 0 0)
			(layers "F.Cu" "F.Mask" "F.Paste")
			(net "P0V8_SERDES_VDDA_PEX0")
		)
		(pad "2" smd circle
			(at 0.40005 0 90)
			(size 0 0)
			(layers "F.Cu" "F.Mask" "F.Paste")
			(net "P0V8_SERDES_VDDA_PEX0_C10")
		)
	)
	(footprint ""
		(layer "F.Cu")
		(at 380.711456 -296.445432 -90)
		(property "Reference" "R4588"
			(at 0 0 270)
			(layer "F.SilkS")
			(hide yes)
			(effects
				(font
					(size 1.27 1.27)
				)
			)
		)
		(property "Value" ""
			(at 0 0 270)
			(layer "F.Fab")
			(effects
				(font
					(size 1.27 1.27)
				)
			)
		)
		(duplicate_pad_numbers_are_jumpers no)
		(fp_line
			(start -0.7874 0.4064)
			(end -0.7874 -0.4064)
			(stroke
				(width 0.1524)
				(type default)
			)
			(layer "F.SilkS")
		)
		(fp_line
			(start 0.7874 0.4064)
			(end -0.7874 0.4064)
			(stroke
				(width 0.1524)
				(type default)
			)
			(layer "F.SilkS")
		)
		(fp_line
			(start -0.7874 -0.4064)
			(end 0.7874 -0.4064)
			(stroke
				(width 0.1524)
				(type default)
			)
			(layer "F.SilkS")
		)
		(fp_line
			(start 0.7874 -0.4064)
			(end 0.7874 0.4064)
			(stroke
				(width 0.1524)
				(type default)
			)
			(layer "F.SilkS")
		)
		(fp_line
			(start -0.67945 0.3048)
			(end -0.67945 -0.305054)
			(stroke
				(width 0.1)
				(type default)
			)
			(layer "F.Fab")
		)
		(fp_line
			(start -0.12065 0.3048)
			(end -0.67945 0.3048)
			(stroke
				(width 0.1)
				(type default)
			)
			(layer "F.Fab")
		)
		(fp_line
			(start 0.120396 0.3048)
			(end 0.120396 0.2794)
			(stroke
				(width 0.1)
				(type default)
			)
			(layer "F.Fab")
		)
		(fp_line
			(start 0.67945 0.3048)
			(end 0.120396 0.3048)
			(stroke
				(width 0.1)
				(type default)
			)
			(layer "F.Fab")
		)
		(fp_line
			(start -0.12065 0.2794)
			(end -0.12065 0.3048)
			(stroke
				(width 0.1)
				(type default)
			)
			(layer "F.Fab")
		)
		(fp_line
			(start 0.120396 0.2794)
			(end -0.12065 0.2794)
			(stroke
				(width 0.1)
				(type default)
			)
			(layer "F.Fab")
		)
		(fp_line
			(start -0.12065 -0.2794)
			(end 0.12065 -0.2794)
			(stroke
				(width 0.1)
				(type default)
			)
			(layer "F.Fab")
		)
		(fp_line
			(start 0.12065 -0.2794)
			(end 0.12065 -0.3048)
			(stroke
				(width 0.1)
				(type default)
			)
			(layer "F.Fab")
		)
		(fp_line
			(start 0.12065 -0.3048)
			(end 0.67945 -0.3048)
			(stroke
				(width 0.1)
				(type default)
			)
			(layer "F.Fab")
		)
		(fp_line
			(start 0.67945 -0.3048)
			(end 0.67945 0.3048)
			(stroke
				(width 0.1)
				(type default)
			)
			(layer "F.Fab")
		)
		(fp_line
			(start -0.67945 -0.305054)
			(end -0.12065 -0.305054)
			(stroke
				(width 0.1)
				(type default)
			)
			(layer "F.Fab")
		)
		(fp_line
			(start -0.12065 -0.305054)
			(end -0.12065 -0.2794)
			(stroke
				(width 0.1)
				(type default)
			)
			(layer "F.Fab")
		)
		(pad "1" smd circle
			(at -0.40005 0 270)
			(size 0 0)
			(layers "F.Cu" "F.Mask" "F.Paste")
			(net "PCEPLL0_VDDA18_PEX3")
		)
		(pad "2" smd circle
			(at 0.40005 0 270)
			(size 0 0)
			(layers "F.Cu" "F.Mask" "F.Paste")
			(net "PCEPLL0_VDDA18_PEX3_R")
		)
	)
	(footprint ""
		(layer "F.Cu")
		(at 76.477114 -49.856644)
		(property "Reference" "R5894"
			(at 0 0 0)
			(layer "F.SilkS")
			(hide yes)
			(effects
				(font
					(size 1.27 1.27)
				)
			)
		)
		(property "Value" ""
			(at 0 0 0)
			(layer "F.Fab")
			(effects
				(font
					(size 1.27 1.27)
				)
			)
		)
		(duplicate_pad_numbers_are_jumpers no)
		(fp_line
			(start -0.7874 -0.4064)
			(end 0.7874 -0.4064)
			(stroke
				(width 0.1524)
				(type default)
			)
			(layer "F.SilkS")
		)
		(fp_line
			(start -0.7874 0.4064)
			(end -0.7874 -0.4064)
			(stroke
				(width 0.1524)
				(type default)
			)
			(layer "F.SilkS")
		)
		(fp_line
			(start 0.7874 -0.4064)
			(end 0.7874 0.4064)
			(stroke
				(width 0.1524)
				(type default)
			)
			(layer "F.SilkS")
		)
		(fp_line
			(start 0.7874 0.4064)
			(end -0.7874 0.4064)
			(stroke
				(width 0.1524)
				(type default)
			)
			(layer "F.SilkS")
		)
		(fp_line
			(start -0.67945 -0.305054)
			(end -0.12065 -0.305054)
			(stroke
				(width 0.1)
				(type default)
			)
			(layer "F.Fab")
		)
		(fp_line
			(start -0.67945 0.3048)
			(end -0.67945 -0.305054)
			(stroke
				(width 0.1)
				(type default)
			)
			(layer "F.Fab")
		)
		(fp_line
			(start -0.12065 -0.305054)
			(end -0.12065 -0.2794)
			(stroke
				(width 0.1)
				(type default)
			)
			(layer "F.Fab")
		)
		(fp_line
			(start -0.12065 -0.2794)
			(end 0.12065 -0.2794)
			(stroke
				(width 0.1)
				(type default)
			)
			(layer "F.Fab")
		)
		(fp_line
			(start -0.12065 0.2794)
			(end -0.12065 0.3048)
			(stroke
				(width 0.1)
				(type default)
			)
			(layer "F.Fab")
		)
		(fp_line
			(start -0.12065 0.3048)
			(end -0.67945 0.3048)
			(stroke
				(width 0.1)
				(type default)
			)
			(layer "F.Fab")
		)
		(fp_line
			(start 0.120396 0.2794)
			(end -0.12065 0.2794)
			(stroke
				(width 0.1)
				(type default)
			)
			(layer "F.Fab")
		)
		(fp_line
			(start 0.120396 0.3048)
			(end 0.120396 0.2794)
			(stroke
				(width 0.1)
				(type default)
			)
			(layer "F.Fab")
		)
		(fp_line
			(start 0.12065 -0.3048)
			(end 0.67945 -0.3048)
			(stroke
				(width 0.1)
				(type default)
			)
			(layer "F.Fab")
		)
		(fp_line
			(start 0.12065 -0.2794)
			(end 0.12065 -0.3048)
			(stroke
				(width 0.1)
				(type default)
			)
			(layer "F.Fab")
		)
		(fp_line
			(start 0.67945 -0.3048)
			(end 0.67945 0.3048)
			(stroke
				(width 0.1)
				(type default)
			)
			(layer "F.Fab")
		)
		(fp_line
			(start 0.67945 0.3048)
			(end 0.120396 0.3048)
			(stroke
				(width 0.1)
				(type default)
			)
			(layer "F.Fab")
		)
		(pad "1" smd circle
			(at -0.40005 0)
			(size 0 0)
			(layers "F.Cu" "F.Mask" "F.Paste")
			(net "SSD2_ADC_A0")
		)
		(pad "2" smd circle
			(at 0.40005 0)
			(size 0 0)
			(layers "F.Cu" "F.Mask" "F.Paste")
			(net "SMB_SSD2_ADC_SDA")
		)
	)
	(footprint ""
		(layer "F.Cu")
		(at 37.1856 -115.2652 90)
		(property "Reference" "R44"
			(at 0 0 90)
			(layer "F.SilkS")
			(hide yes)
			(effects
				(font
					(size 1.27 1.27)
				)
			)
		)
		(property "Value" ""
			(at 0 0 90)
			(layer "F.Fab")
			(effects
				(font
					(size 1.27 1.27)
				)
			)
		)
		(duplicate_pad_numbers_are_jumpers no)
		(fp_line
			(start 0.7874 -0.4064)
			(end 0.7874 0.4064)
			(stroke
				(width 0.1524)
				(type default)
			)
			(layer "F.SilkS")
		)
		(fp_line
			(start -0.7874 -0.4064)
			(end 0.7874 -0.4064)
			(stroke
				(width 0.1524)
				(type default)
			)
			(layer "F.SilkS")
		)
		(fp_line
			(start 0.7874 0.4064)
			(end -0.7874 0.4064)
			(stroke
				(width 0.1524)
				(type default)
			)
			(layer "F.SilkS")
		)
		(fp_line
			(start -0.7874 0.4064)
			(end -0.7874 -0.4064)
			(stroke
				(width 0.1524)
				(type default)
			)
			(layer "F.SilkS")
		)
		(fp_line
			(start -0.12065 -0.305054)
			(end -0.12065 -0.2794)
			(stroke
				(width 0.1)
				(type default)
			)
			(layer "F.Fab")
		)
		(fp_line
			(start -0.67945 -0.305054)
			(end -0.12065 -0.305054)
			(stroke
				(width 0.1)
				(type default)
			)
			(layer "F.Fab")
		)
		(fp_line
			(start 0.67945 -0.3048)
			(end 0.67945 0.3048)
			(stroke
				(width 0.1)
				(type default)
			)
			(layer "F.Fab")
		)
		(fp_line
			(start 0.12065 -0.3048)
			(end 0.67945 -0.3048)
			(stroke
				(width 0.1)
				(type default)
			)
			(layer "F.Fab")
		)
		(fp_line
			(start 0.12065 -0.2794)
			(end 0.12065 -0.3048)
			(stroke
				(width 0.1)
				(type default)
			)
			(layer "F.Fab")
		)
		(fp_line
			(start -0.12065 -0.2794)
			(end 0.12065 -0.2794)
			(stroke
				(width 0.1)
				(type default)
			)
			(layer "F.Fab")
		)
		(fp_line
			(start 0.120396 0.2794)
			(end -0.12065 0.2794)
			(stroke
				(width 0.1)
				(type default)
			)
			(layer "F.Fab")
		)
		(fp_line
			(start -0.12065 0.2794)
			(end -0.12065 0.3048)
			(stroke
				(width 0.1)
				(type default)
			)
			(layer "F.Fab")
		)
		(fp_line
			(start 0.67945 0.3048)
			(end 0.120396 0.3048)
			(stroke
				(width 0.1)
				(type default)
			)
			(layer "F.Fab")
		)
		(fp_line
			(start 0.120396 0.3048)
			(end 0.120396 0.2794)
			(stroke
				(width 0.1)
				(type default)
			)
			(layer "F.Fab")
		)
		(fp_line
			(start -0.12065 0.3048)
			(end -0.67945 0.3048)
			(stroke
				(width 0.1)
				(type default)
			)
			(layer "F.Fab")
		)
		(fp_line
			(start -0.67945 0.3048)
			(end -0.67945 -0.305054)
			(stroke
				(width 0.1)
				(type default)
			)
			(layer "F.Fab")
		)
		(pad "1" smd circle
			(at -0.40005 0 90)
			(size 0 0)
			(layers "F.Cu" "F.Mask" "F.Paste")
			(net "P3V3_AUX")
		)
		(pad "2" smd circle
			(at 0.40005 0 90)
			(size 0 0)
			(layers "F.Cu" "F.Mask" "F.Paste")
			(net "HP_NIC0_EN")
		)
	)
	(footprint ""
		(layer "F.Cu")
		(at 63.002668 -388.33679 -90)
		(property "Reference" "C4048"
			(at 0 0 270)
			(layer "F.SilkS")
			(hide yes)
			(effects
				(font
					(size 1.27 1.27)
				)
			)
		)
		(property "Value" ""
			(at 0 0 270)
			(layer "F.Fab")
			(effects
				(font
					(size 1.27 1.27)
				)
			)
		)
		(duplicate_pad_numbers_are_jumpers no)
		(fp_line
			(start -0.7874 0.4064)
			(end -0.7874 -0.4064)
			(stroke
				(width 0.1524)
				(type default)
			)
			(layer "F.SilkS")
		)
		(fp_line
			(start 0.7874 0.4064)
			(end -0.7874 0.4064)
			(stroke
				(width 0.1524)
				(type default)
			)
			(layer "F.SilkS")
		)
		(fp_line
			(start -0.7874 -0.4064)
			(end 0.7874 -0.4064)
			(stroke
				(width 0.1524)
				(type default)
			)
			(layer "F.SilkS")
		)
		(fp_line
			(start 0.7874 -0.4064)
			(end 0.7874 0.4064)
			(stroke
				(width 0.1524)
				(type default)
			)
			(layer "F.SilkS")
		)
		(fp_line
			(start -0.67945 0.3048)
			(end -0.67945 -0.305054)
			(stroke
				(width 0.1)
				(type default)
			)
			(layer "F.Fab")
		)
		(fp_line
			(start -0.12065 0.3048)
			(end -0.67945 0.3048)
			(stroke
				(width 0.1)
				(type default)
			)
			(layer "F.Fab")
		)
		(fp_line
			(start 0.120396 0.3048)
			(end 0.120396 0.2794)
			(stroke
				(width 0.1)
				(type default)
			)
			(layer "F.Fab")
		)
		(fp_line
			(start 0.67945 0.3048)
			(end 0.120396 0.3048)
			(stroke
				(width 0.1)
				(type default)
			)
			(layer "F.Fab")
		)
		(fp_line
			(start -0.12065 0.2794)
			(end -0.12065 0.3048)
			(stroke
				(width 0.1)
				(type default)
			)
			(layer "F.Fab")
		)
		(fp_line
			(start 0.120396 0.2794)
			(end -0.12065 0.2794)
			(stroke
				(width 0.1)
				(type default)
			)
			(layer "F.Fab")
		)
		(fp_line
			(start -0.12065 -0.2794)
			(end 0.12065 -0.2794)
			(stroke
				(width 0.1)
				(type default)
			)
			(layer "F.Fab")
		)
		(fp_line
			(start 0.12065 -0.2794)
			(end 0.12065 -0.3048)
			(stroke
				(width 0.1)
				(type default)
			)
			(layer "F.Fab")
		)
		(fp_line
			(start 0.12065 -0.3048)
			(end 0.67945 -0.3048)
			(stroke
				(width 0.1)
				(type default)
			)
			(layer "F.Fab")
		)
		(fp_line
			(start 0.67945 -0.3048)
			(end 0.67945 0.3048)
			(stroke
				(width 0.1)
				(type default)
			)
			(layer "F.Fab")
		)
		(fp_line
			(start -0.67945 -0.305054)
			(end -0.12065 -0.305054)
			(stroke
				(width 0.1)
				(type default)
			)
			(layer "F.Fab")
		)
		(fp_line
			(start -0.12065 -0.305054)
			(end -0.12065 -0.2794)
			(stroke
				(width 0.1)
				(type default)
			)
			(layer "F.Fab")
		)
		(pad "1" smd circle
			(at -0.40005 0 270)
			(size 0 0)
			(layers "F.Cu" "F.Mask" "F.Paste")
			(net "GND")
		)
		(pad "2" smd circle
			(at 0.40005 0 270)
			(size 0 0)
			(layers "F.Cu" "F.Mask" "F.Paste")
			(net "GPU_PEX_STRAP1")
		)
	)
	(footprint ""
		(layer "F.Cu")
		(at 333.540608 -236.871256 -90)
		(property "Reference" "R1789"
			(at 0 0 270)
			(layer "F.SilkS")
			(hide yes)
			(effects
				(font
					(size 1.27 1.27)
				)
			)
		)
		(property "Value" ""
			(at 0 0 270)
			(layer "F.Fab")
			(effects
				(font
					(size 1.27 1.27)
				)
			)
		)
		(duplicate_pad_numbers_are_jumpers no)
		(fp_line
			(start -0.7874 0.4064)
			(end -0.7874 -0.4064)
			(stroke
				(width 0.1524)
				(type default)
			)
			(layer "F.SilkS")
		)
		(fp_line
			(start 0.7874 0.4064)
			(end -0.7874 0.4064)
			(stroke
				(width 0.1524)
				(type default)
			)
			(layer "F.SilkS")
		)
		(fp_line
			(start -0.7874 -0.4064)
			(end 0.7874 -0.4064)
			(stroke
				(width 0.1524)
				(type default)
			)
			(layer "F.SilkS")
		)
		(fp_line
			(start 0.7874 -0.4064)
			(end 0.7874 0.4064)
			(stroke
				(width 0.1524)
				(type default)
			)
			(layer "F.SilkS")
		)
		(fp_line
			(start -0.67945 0.3048)
			(end -0.67945 -0.305054)
			(stroke
				(width 0.1)
				(type default)
			)
			(layer "F.Fab")
		)
		(fp_line
			(start -0.12065 0.3048)
			(end -0.67945 0.3048)
			(stroke
				(width 0.1)
				(type default)
			)
			(layer "F.Fab")
		)
		(fp_line
			(start 0.120396 0.3048)
			(end 0.120396 0.2794)
			(stroke
				(width 0.1)
				(type default)
			)
			(layer "F.Fab")
		)
		(fp_line
			(start 0.67945 0.3048)
			(end 0.120396 0.3048)
			(stroke
				(width 0.1)
				(type default)
			)
			(layer "F.Fab")
		)
		(fp_line
			(start -0.12065 0.2794)
			(end -0.12065 0.3048)
			(stroke
				(width 0.1)
				(type default)
			)
			(layer "F.Fab")
		)
		(fp_line
			(start 0.120396 0.2794)
			(end -0.12065 0.2794)
			(stroke
				(width 0.1)
				(type default)
			)
			(layer "F.Fab")
		)
		(fp_line
			(start -0.12065 -0.2794)
			(end 0.12065 -0.2794)
			(stroke
				(width 0.1)
				(type default)
			)
			(layer "F.Fab")
		)
		(fp_line
			(start 0.12065 -0.2794)
			(end 0.12065 -0.3048)
			(stroke
				(width 0.1)
				(type default)
			)
			(layer "F.Fab")
		)
		(fp_line
			(start 0.12065 -0.3048)
			(end 0.67945 -0.3048)
			(stroke
				(width 0.1)
				(type default)
			)
			(layer "F.Fab")
		)
		(fp_line
			(start 0.67945 -0.3048)
			(end 0.67945 0.3048)
			(stroke
				(width 0.1)
				(type default)
			)
			(layer "F.Fab")
		)
		(fp_line
			(start -0.67945 -0.305054)
			(end -0.12065 -0.305054)
			(stroke
				(width 0.1)
				(type default)
			)
			(layer "F.Fab")
		)
		(fp_line
			(start -0.12065 -0.305054)
			(end -0.12065 -0.2794)
			(stroke
				(width 0.1)
				(type default)
			)
			(layer "F.Fab")
		)
		(pad "1" smd circle
			(at -0.40005 0 270)
			(size 0 0)
			(layers "F.Cu" "F.Mask" "F.Paste")
			(net "RST_MB_PERST_1_ISO_N")
		)
		(pad "2" smd circle
			(at 0.40005 0 270)
			(size 0 0)
			(layers "F.Cu" "F.Mask" "F.Paste")
			(net "RST_MB_PERST_1_ISO_R_N")
		)
	)
	(footprint ""
		(layer "F.Cu")
		(at 420.972996 -22.867366 90)
		(property "Reference" "C3970"
			(at 0 0 90)
			(layer "F.SilkS")
			(hide yes)
			(effects
				(font
					(size 1.27 1.27)
				)
			)
		)
		(property "Value" ""
			(at 0 0 90)
			(layer "F.Fab")
			(effects
				(font
					(size 1.27 1.27)
				)
			)
		)
		(duplicate_pad_numbers_are_jumpers no)
		(fp_line
			(start 0.7874 -0.4064)
			(end 0.7874 0.4064)
			(stroke
				(width 0.1524)
				(type default)
			)
			(layer "F.SilkS")
		)
		(fp_line
			(start -0.7874 -0.4064)
			(end 0.7874 -0.4064)
			(stroke
				(width 0.1524)
				(type default)
			)
			(layer "F.SilkS")
		)
		(fp_line
			(start 0.7874 0.4064)
			(end -0.7874 0.4064)
			(stroke
				(width 0.1524)
				(type default)
			)
			(layer "F.SilkS")
		)
		(fp_line
			(start -0.7874 0.4064)
			(end -0.7874 -0.4064)
			(stroke
				(width 0.1524)
				(type default)
			)
			(layer "F.SilkS")
		)
		(fp_line
			(start -0.12065 -0.305054)
			(end -0.12065 -0.2794)
			(stroke
				(width 0.1)
				(type default)
			)
			(layer "F.Fab")
		)
		(fp_line
			(start -0.67945 -0.305054)
			(end -0.12065 -0.305054)
			(stroke
				(width 0.1)
				(type default)
			)
			(layer "F.Fab")
		)
		(fp_line
			(start 0.67945 -0.3048)
			(end 0.67945 0.3048)
			(stroke
				(width 0.1)
				(type default)
			)
			(layer "F.Fab")
		)
		(fp_line
			(start 0.12065 -0.3048)
			(end 0.67945 -0.3048)
			(stroke
				(width 0.1)
				(type default)
			)
			(layer "F.Fab")
		)
		(fp_line
			(start 0.12065 -0.2794)
			(end 0.12065 -0.3048)
			(stroke
				(width 0.1)
				(type default)
			)
			(layer "F.Fab")
		)
		(fp_line
			(start -0.12065 -0.2794)
			(end 0.12065 -0.2794)
			(stroke
				(width 0.1)
				(type default)
			)
			(layer "F.Fab")
		)
		(fp_line
			(start 0.120396 0.2794)
			(end -0.12065 0.2794)
			(stroke
				(width 0.1)
				(type default)
			)
			(layer "F.Fab")
		)
		(fp_line
			(start -0.12065 0.2794)
			(end -0.12065 0.3048)
			(stroke
				(width 0.1)
				(type default)
			)
			(layer "F.Fab")
		)
		(fp_line
			(start 0.67945 0.3048)
			(end 0.120396 0.3048)
			(stroke
				(width 0.1)
				(type default)
			)
			(layer "F.Fab")
		)
		(fp_line
			(start 0.120396 0.3048)
			(end 0.120396 0.2794)
			(stroke
				(width 0.1)
				(type default)
			)
			(layer "F.Fab")
		)
		(fp_line
			(start -0.12065 0.3048)
			(end -0.67945 0.3048)
			(stroke
				(width 0.1)
				(type default)
			)
			(layer "F.Fab")
		)
		(fp_line
			(start -0.67945 0.3048)
			(end -0.67945 -0.305054)
			(stroke
				(width 0.1)
				(type default)
			)
			(layer "F.Fab")
		)
		(pad "1" smd circle
			(at -0.40005 0 90)
			(size 0 0)
			(layers "F.Cu" "F.Mask" "F.Paste")
			(net "P12V_SSD14")
		)
		(pad "2" smd circle
			(at 0.40005 0 90)
			(size 0 0)
			(layers "F.Cu" "F.Mask" "F.Paste")
			(net "GND")
		)
	)
	(footprint ""
		(layer "F.Cu")
		(at 253.147322 -19.33956)
		(property "Reference" "C3930"
			(at 0 0 0)
			(layer "F.SilkS")
			(hide yes)
			(effects
				(font
					(size 1.27 1.27)
				)
			)
		)
		(property "Value" ""
			(at 0 0 0)
			(layer "F.Fab")
			(effects
				(font
					(size 1.27 1.27)
				)
			)
		)
		(duplicate_pad_numbers_are_jumpers no)
		(fp_line
			(start -0.7874 -0.4064)
			(end 0.7874 -0.4064)
			(stroke
				(width 0.1524)
				(type default)
			)
			(layer "F.SilkS")
		)
		(fp_line
			(start -0.7874 0.4064)
			(end -0.7874 -0.4064)
			(stroke
				(width 0.1524)
				(type default)
			)
			(layer "F.SilkS")
		)
		(fp_line
			(start 0.7874 -0.4064)
			(end 0.7874 0.4064)
			(stroke
				(width 0.1524)
				(type default)
			)
			(layer "F.SilkS")
		)
		(fp_line
			(start 0.7874 0.4064)
			(end -0.7874 0.4064)
			(stroke
				(width 0.1524)
				(type default)
			)
			(layer "F.SilkS")
		)
		(fp_line
			(start -0.67945 -0.305054)
			(end -0.12065 -0.305054)
			(stroke
				(width 0.1)
				(type default)
			)
			(layer "F.Fab")
		)
		(fp_line
			(start -0.67945 0.3048)
			(end -0.67945 -0.305054)
			(stroke
				(width 0.1)
				(type default)
			)
			(layer "F.Fab")
		)
		(fp_line
			(start -0.12065 -0.305054)
			(end -0.12065 -0.2794)
			(stroke
				(width 0.1)
				(type default)
			)
			(layer "F.Fab")
		)
		(fp_line
			(start -0.12065 -0.2794)
			(end 0.12065 -0.2794)
			(stroke
				(width 0.1)
				(type default)
			)
			(layer "F.Fab")
		)
		(fp_line
			(start -0.12065 0.2794)
			(end -0.12065 0.3048)
			(stroke
				(width 0.1)
				(type default)
			)
			(layer "F.Fab")
		)
		(fp_line
			(start -0.12065 0.3048)
			(end -0.67945 0.3048)
			(stroke
				(width 0.1)
				(type default)
			)
			(layer "F.Fab")
		)
		(fp_line
			(start 0.120396 0.2794)
			(end -0.12065 0.2794)
			(stroke
				(width 0.1)
				(type default)
			)
			(layer "F.Fab")
		)
		(fp_line
			(start 0.120396 0.3048)
			(end 0.120396 0.2794)
			(stroke
				(width 0.1)
				(type default)
			)
			(layer "F.Fab")
		)
		(fp_line
			(start 0.12065 -0.3048)
			(end 0.67945 -0.3048)
			(stroke
				(width 0.1)
				(type default)
			)
			(layer "F.Fab")
		)
		(fp_line
			(start 0.12065 -0.2794)
			(end 0.12065 -0.3048)
			(stroke
				(width 0.1)
				(type default)
			)
			(layer "F.Fab")
		)
		(fp_line
			(start 0.67945 -0.3048)
			(end 0.67945 0.3048)
			(stroke
				(width 0.1)
				(type default)
			)
			(layer "F.Fab")
		)
		(fp_line
			(start 0.67945 0.3048)
			(end 0.120396 0.3048)
			(stroke
				(width 0.1)
				(type default)
			)
			(layer "F.Fab")
		)
		(pad "1" smd circle
			(at -0.40005 0)
			(size 0 0)
			(layers "F.Cu" "F.Mask" "F.Paste")
			(net "P12V_SSD8")
		)
		(pad "2" smd circle
			(at 0.40005 0)
			(size 0 0)
			(layers "F.Cu" "F.Mask" "F.Paste")
			(net "GND")
		)
	)
	(footprint ""
		(layer "F.Cu")
		(at 198.567294 -366.63503)
		(property "Reference" "PR1"
			(at 0 0 0)
			(layer "F.SilkS")
			(hide yes)
			(effects
				(font
					(size 1.27 1.27)
				)
			)
		)
		(property "Value" ""
			(at 0 0 0)
			(layer "F.Fab")
			(effects
				(font
					(size 1.27 1.27)
				)
			)
		)
		(duplicate_pad_numbers_are_jumpers no)
		(fp_line
			(start -0.7874 -0.4064)
			(end 0.7874 -0.4064)
			(stroke
				(width 0.1524)
				(type default)
			)
			(layer "F.SilkS")
		)
		(fp_line
			(start -0.7874 0.4064)
			(end -0.7874 -0.4064)
			(stroke
				(width 0.1524)
				(type default)
			)
			(layer "F.SilkS")
		)
		(fp_line
			(start 0.7874 -0.4064)
			(end 0.7874 0.4064)
			(stroke
				(width 0.1524)
				(type default)
			)
			(layer "F.SilkS")
		)
		(fp_line
			(start 0.7874 0.4064)
			(end -0.7874 0.4064)
			(stroke
				(width 0.1524)
				(type default)
			)
			(layer "F.SilkS")
		)
		(fp_line
			(start -0.67945 -0.305054)
			(end -0.12065 -0.305054)
			(stroke
				(width 0.1)
				(type default)
			)
			(layer "F.Fab")
		)
		(fp_line
			(start -0.67945 0.3048)
			(end -0.67945 -0.305054)
			(stroke
				(width 0.1)
				(type default)
			)
			(layer "F.Fab")
		)
		(fp_line
			(start -0.12065 -0.305054)
			(end -0.12065 -0.2794)
			(stroke
				(width 0.1)
				(type default)
			)
			(layer "F.Fab")
		)
		(fp_line
			(start -0.12065 -0.2794)
			(end 0.12065 -0.2794)
			(stroke
				(width 0.1)
				(type default)
			)
			(layer "F.Fab")
		)
		(fp_line
			(start -0.12065 0.2794)
			(end -0.12065 0.3048)
			(stroke
				(width 0.1)
				(type default)
			)
			(layer "F.Fab")
		)
		(fp_line
			(start -0.12065 0.3048)
			(end -0.67945 0.3048)
			(stroke
				(width 0.1)
				(type default)
			)
			(layer "F.Fab")
		)
		(fp_line
			(start 0.120396 0.2794)
			(end -0.12065 0.2794)
			(stroke
				(width 0.1)
				(type default)
			)
			(layer "F.Fab")
		)
		(fp_line
			(start 0.120396 0.3048)
			(end 0.120396 0.2794)
			(stroke
				(width 0.1)
				(type default)
			)
			(layer "F.Fab")
		)
		(fp_line
			(start 0.12065 -0.3048)
			(end 0.67945 -0.3048)
			(stroke
				(width 0.1)
				(type default)
			)
			(layer "F.Fab")
		)
		(fp_line
			(start 0.12065 -0.2794)
			(end 0.12065 -0.3048)
			(stroke
				(width 0.1)
				(type default)
			)
			(layer "F.Fab")
		)
		(fp_line
			(start 0.67945 -0.3048)
			(end 0.67945 0.3048)
			(stroke
				(width 0.1)
				(type default)
			)
			(layer "F.Fab")
		)
		(fp_line
			(start 0.67945 0.3048)
			(end 0.120396 0.3048)
			(stroke
				(width 0.1)
				(type default)
			)
			(layer "F.Fab")
		)
		(pad "1" smd circle
			(at -0.40005 0)
			(size 0 0)
			(layers "F.Cu" "F.Mask" "F.Paste")
			(net "GND")
		)
		(pad "2" smd circle
			(at 0.40005 0)
			(size 0 0)
			(layers "F.Cu" "F.Mask" "F.Paste")
			(net "AGND_HSC")
		)
	)
	(footprint ""
		(layer "F.Cu")
		(at 98.657156 -102.088442)
		(property "Reference" "PC320"
			(at 0 0 0)
			(layer "F.SilkS")
			(hide yes)
			(effects
				(font
					(size 1.27 1.27)
				)
			)
		)
		(property "Value" ""
			(at 0 0 0)
			(layer "F.Fab")
			(effects
				(font
					(size 1.27 1.27)
				)
			)
		)
		(duplicate_pad_numbers_are_jumpers no)
		(fp_line
			(start -0.7874 -0.4064)
			(end 0.7874 -0.4064)
			(stroke
				(width 0.1524)
				(type default)
			)
			(layer "F.SilkS")
		)
		(fp_line
			(start -0.7874 0.4064)
			(end -0.7874 -0.4064)
			(stroke
				(width 0.1524)
				(type default)
			)
			(layer "F.SilkS")
		)
		(fp_line
			(start 0.7874 -0.4064)
			(end 0.7874 0.4064)
			(stroke
				(width 0.1524)
				(type default)
			)
			(layer "F.SilkS")
		)
		(fp_line
			(start 0.7874 0.4064)
			(end -0.7874 0.4064)
			(stroke
				(width 0.1524)
				(type default)
			)
			(layer "F.SilkS")
		)
		(fp_line
			(start -0.67945 -0.305054)
			(end -0.12065 -0.305054)
			(stroke
				(width 0.1)
				(type default)
			)
			(layer "F.Fab")
		)
		(fp_line
			(start -0.67945 0.3048)
			(end -0.67945 -0.305054)
			(stroke
				(width 0.1)
				(type default)
			)
			(layer "F.Fab")
		)
		(fp_line
			(start -0.12065 -0.305054)
			(end -0.12065 -0.2794)
			(stroke
				(width 0.1)
				(type default)
			)
			(layer "F.Fab")
		)
		(fp_line
			(start -0.12065 -0.2794)
			(end 0.12065 -0.2794)
			(stroke
				(width 0.1)
				(type default)
			)
			(layer "F.Fab")
		)
		(fp_line
			(start -0.12065 0.2794)
			(end -0.12065 0.3048)
			(stroke
				(width 0.1)
				(type default)
			)
			(layer "F.Fab")
		)
		(fp_line
			(start -0.12065 0.3048)
			(end -0.67945 0.3048)
			(stroke
				(width 0.1)
				(type default)
			)
			(layer "F.Fab")
		)
		(fp_line
			(start 0.120396 0.2794)
			(end -0.12065 0.2794)
			(stroke
				(width 0.1)
				(type default)
			)
			(layer "F.Fab")
		)
		(fp_line
			(start 0.120396 0.3048)
			(end 0.120396 0.2794)
			(stroke
				(width 0.1)
				(type default)
			)
			(layer "F.Fab")
		)
		(fp_line
			(start 0.12065 -0.3048)
			(end 0.67945 -0.3048)
			(stroke
				(width 0.1)
				(type default)
			)
			(layer "F.Fab")
		)
		(fp_line
			(start 0.12065 -0.2794)
			(end 0.12065 -0.3048)
			(stroke
				(width 0.1)
				(type default)
			)
			(layer "F.Fab")
		)
		(fp_line
			(start 0.67945 -0.3048)
			(end 0.67945 0.3048)
			(stroke
				(width 0.1)
				(type default)
			)
			(layer "F.Fab")
		)
		(fp_line
			(start 0.67945 0.3048)
			(end 0.120396 0.3048)
			(stroke
				(width 0.1)
				(type default)
			)
			(layer "F.Fab")
		)
		(pad "1" smd circle
			(at -0.40005 0)
			(size 0 0)
			(layers "F.Cu" "F.Mask" "F.Paste")
			(net "P12V_NIC1_R")
		)
		(pad "2" smd circle
			(at 0.40005 0)
			(size 0 0)
			(layers "F.Cu" "F.Mask" "F.Paste")
			(net "GND")
		)
	)
	(footprint ""
		(layer "F.Cu")
		(at 408.510994 -61.386974)
		(property "Reference" "R4506"
			(at 0 0 0)
			(layer "F.SilkS")
			(hide yes)
			(effects
				(font
					(size 1.27 1.27)
				)
			)
		)
		(property "Value" ""
			(at 0 0 0)
			(layer "F.Fab")
			(effects
				(font
					(size 1.27 1.27)
				)
			)
		)
		(duplicate_pad_numbers_are_jumpers no)
		(fp_line
			(start -0.7874 -0.4064)
			(end 0.7874 -0.4064)
			(stroke
				(width 0.1524)
				(type default)
			)
			(layer "F.SilkS")
		)
		(fp_line
			(start -0.7874 0.4064)
			(end -0.7874 -0.4064)
			(stroke
				(width 0.1524)
				(type default)
			)
			(layer "F.SilkS")
		)
		(fp_line
			(start 0.7874 -0.4064)
			(end 0.7874 0.4064)
			(stroke
				(width 0.1524)
				(type default)
			)
			(layer "F.SilkS")
		)
		(fp_line
			(start 0.7874 0.4064)
			(end -0.7874 0.4064)
			(stroke
				(width 0.1524)
				(type default)
			)
			(layer "F.SilkS")
		)
		(fp_line
			(start -0.67945 -0.305054)
			(end -0.12065 -0.305054)
			(stroke
				(width 0.1)
				(type default)
			)
			(layer "F.Fab")
		)
		(fp_line
			(start -0.67945 0.3048)
			(end -0.67945 -0.305054)
			(stroke
				(width 0.1)
				(type default)
			)
			(layer "F.Fab")
		)
		(fp_line
			(start -0.12065 -0.305054)
			(end -0.12065 -0.2794)
			(stroke
				(width 0.1)
				(type default)
			)
			(layer "F.Fab")
		)
		(fp_line
			(start -0.12065 -0.2794)
			(end 0.12065 -0.2794)
			(stroke
				(width 0.1)
				(type default)
			)
			(layer "F.Fab")
		)
		(fp_line
			(start -0.12065 0.2794)
			(end -0.12065 0.3048)
			(stroke
				(width 0.1)
				(type default)
			)
			(layer "F.Fab")
		)
		(fp_line
			(start -0.12065 0.3048)
			(end -0.67945 0.3048)
			(stroke
				(width 0.1)
				(type default)
			)
			(layer "F.Fab")
		)
		(fp_line
			(start 0.120396 0.2794)
			(end -0.12065 0.2794)
			(stroke
				(width 0.1)
				(type default)
			)
			(layer "F.Fab")
		)
		(fp_line
			(start 0.120396 0.3048)
			(end 0.120396 0.2794)
			(stroke
				(width 0.1)
				(type default)
			)
			(layer "F.Fab")
		)
		(fp_line
			(start 0.12065 -0.3048)
			(end 0.67945 -0.3048)
			(stroke
				(width 0.1)
				(type default)
			)
			(layer "F.Fab")
		)
		(fp_line
			(start 0.12065 -0.2794)
			(end 0.12065 -0.3048)
			(stroke
				(width 0.1)
				(type default)
			)
			(layer "F.Fab")
		)
		(fp_line
			(start 0.67945 -0.3048)
			(end 0.67945 0.3048)
			(stroke
				(width 0.1)
				(type default)
			)
			(layer "F.Fab")
		)
		(fp_line
			(start 0.67945 0.3048)
			(end 0.120396 0.3048)
			(stroke
				(width 0.1)
				(type default)
			)
			(layer "F.Fab")
		)
		(pad "1" smd circle
			(at -0.40005 0)
			(size 0 0)
			(layers "F.Cu" "F.Mask" "F.Paste")
			(net "PWRGD_P3V3_SSD14")
		)
		(pad "2" smd circle
			(at 0.40005 0)
			(size 0 0)
			(layers "F.Cu" "F.Mask" "F.Paste")
			(net "PWRGD_P3V3_SSD14_R")
		)
	)
	(footprint ""
		(layer "F.Cu")
		(at 187.754768 -22.867366 90)
		(property "Reference" "C3920"
			(at 0 0 90)
			(layer "F.SilkS")
			(hide yes)
			(effects
				(font
					(size 1.27 1.27)
				)
			)
		)
		(property "Value" ""
			(at 0 0 90)
			(layer "F.Fab")
			(effects
				(font
					(size 1.27 1.27)
				)
			)
		)
		(duplicate_pad_numbers_are_jumpers no)
		(fp_line
			(start 0.7874 -0.4064)
			(end 0.7874 0.4064)
			(stroke
				(width 0.1524)
				(type default)
			)
			(layer "F.SilkS")
		)
		(fp_line
			(start -0.7874 -0.4064)
			(end 0.7874 -0.4064)
			(stroke
				(width 0.1524)
				(type default)
			)
			(layer "F.SilkS")
		)
		(fp_line
			(start 0.7874 0.4064)
			(end -0.7874 0.4064)
			(stroke
				(width 0.1524)
				(type default)
			)
			(layer "F.SilkS")
		)
		(fp_line
			(start -0.7874 0.4064)
			(end -0.7874 -0.4064)
			(stroke
				(width 0.1524)
				(type default)
			)
			(layer "F.SilkS")
		)
		(fp_line
			(start -0.12065 -0.305054)
			(end -0.12065 -0.2794)
			(stroke
				(width 0.1)
				(type default)
			)
			(layer "F.Fab")
		)
		(fp_line
			(start -0.67945 -0.305054)
			(end -0.12065 -0.305054)
			(stroke
				(width 0.1)
				(type default)
			)
			(layer "F.Fab")
		)
		(fp_line
			(start 0.67945 -0.3048)
			(end 0.67945 0.3048)
			(stroke
				(width 0.1)
				(type default)
			)
			(layer "F.Fab")
		)
		(fp_line
			(start 0.12065 -0.3048)
			(end 0.67945 -0.3048)
			(stroke
				(width 0.1)
				(type default)
			)
			(layer "F.Fab")
		)
		(fp_line
			(start 0.12065 -0.2794)
			(end 0.12065 -0.3048)
			(stroke
				(width 0.1)
				(type default)
			)
			(layer "F.Fab")
		)
		(fp_line
			(start -0.12065 -0.2794)
			(end 0.12065 -0.2794)
			(stroke
				(width 0.1)
				(type default)
			)
			(layer "F.Fab")
		)
		(fp_line
			(start 0.120396 0.2794)
			(end -0.12065 0.2794)
			(stroke
				(width 0.1)
				(type default)
			)
			(layer "F.Fab")
		)
		(fp_line
			(start -0.12065 0.2794)
			(end -0.12065 0.3048)
			(stroke
				(width 0.1)
				(type default)
			)
			(layer "F.Fab")
		)
		(fp_line
			(start 0.67945 0.3048)
			(end 0.120396 0.3048)
			(stroke
				(width 0.1)
				(type default)
			)
			(layer "F.Fab")
		)
		(fp_line
			(start 0.120396 0.3048)
			(end 0.120396 0.2794)
			(stroke
				(width 0.1)
				(type default)
			)
			(layer "F.Fab")
		)
		(fp_line
			(start -0.12065 0.3048)
			(end -0.67945 0.3048)
			(stroke
				(width 0.1)
				(type default)
			)
			(layer "F.Fab")
		)
		(fp_line
			(start -0.67945 0.3048)
			(end -0.67945 -0.305054)
			(stroke
				(width 0.1)
				(type default)
			)
			(layer "F.Fab")
		)
		(pad "1" smd circle
			(at -0.40005 0 90)
			(size 0 0)
			(layers "F.Cu" "F.Mask" "F.Paste")
			(net "P12V_SSD6")
		)
		(pad "2" smd circle
			(at 0.40005 0 90)
			(size 0 0)
			(layers "F.Cu" "F.Mask" "F.Paste")
			(net "GND")
		)
	)
	(footprint ""
		(layer "F.Cu")
		(at 445.9478 -236.4994)
		(property "Reference" "R6602"
			(at 0 0 0)
			(layer "F.SilkS")
			(hide yes)
			(effects
				(font
					(size 1.27 1.27)
				)
			)
		)
		(property "Value" ""
			(at 0 0 0)
			(layer "F.Fab")
			(effects
				(font
					(size 1.27 1.27)
				)
			)
		)
		(duplicate_pad_numbers_are_jumpers no)
		(fp_line
			(start -0.7874 -0.4064)
			(end 0.7874 -0.4064)
			(stroke
				(width 0.1524)
				(type default)
			)
			(layer "F.SilkS")
		)
		(fp_line
			(start -0.7874 0.4064)
			(end -0.7874 -0.4064)
			(stroke
				(width 0.1524)
				(type default)
			)
			(layer "F.SilkS")
		)
		(fp_line
			(start 0.7874 -0.4064)
			(end 0.7874 0.4064)
			(stroke
				(width 0.1524)
				(type default)
			)
			(layer "F.SilkS")
		)
		(fp_line
			(start 0.7874 0.4064)
			(end -0.7874 0.4064)
			(stroke
				(width 0.1524)
				(type default)
			)
			(layer "F.SilkS")
		)
		(fp_line
			(start -0.67945 -0.305054)
			(end -0.12065 -0.305054)
			(stroke
				(width 0.1)
				(type default)
			)
			(layer "F.Fab")
		)
		(fp_line
			(start -0.67945 0.3048)
			(end -0.67945 -0.305054)
			(stroke
				(width 0.1)
				(type default)
			)
			(layer "F.Fab")
		)
		(fp_line
			(start -0.12065 -0.305054)
			(end -0.12065 -0.2794)
			(stroke
				(width 0.1)
				(type default)
			)
			(layer "F.Fab")
		)
		(fp_line
			(start -0.12065 -0.2794)
			(end 0.12065 -0.2794)
			(stroke
				(width 0.1)
				(type default)
			)
			(layer "F.Fab")
		)
		(fp_line
			(start -0.12065 0.2794)
			(end -0.12065 0.3048)
			(stroke
				(width 0.1)
				(type default)
			)
			(layer "F.Fab")
		)
		(fp_line
			(start -0.12065 0.3048)
			(end -0.67945 0.3048)
			(stroke
				(width 0.1)
				(type default)
			)
			(layer "F.Fab")
		)
		(fp_line
			(start 0.120396 0.2794)
			(end -0.12065 0.2794)
			(stroke
				(width 0.1)
				(type default)
			)
			(layer "F.Fab")
		)
		(fp_line
			(start 0.120396 0.3048)
			(end 0.120396 0.2794)
			(stroke
				(width 0.1)
				(type default)
			)
			(layer "F.Fab")
		)
		(fp_line
			(start 0.12065 -0.3048)
			(end 0.67945 -0.3048)
			(stroke
				(width 0.1)
				(type default)
			)
			(layer "F.Fab")
		)
		(fp_line
			(start 0.12065 -0.2794)
			(end 0.12065 -0.3048)
			(stroke
				(width 0.1)
				(type default)
			)
			(layer "F.Fab")
		)
		(fp_line
			(start 0.67945 -0.3048)
			(end 0.67945 0.3048)
			(stroke
				(width 0.1)
				(type default)
			)
			(layer "F.Fab")
		)
		(fp_line
			(start 0.67945 0.3048)
			(end 0.120396 0.3048)
			(stroke
				(width 0.1)
				(type default)
			)
			(layer "F.Fab")
		)
		(pad "1" smd circle
			(at -0.40005 0)
			(size 0 0)
			(layers "F.Cu" "F.Mask" "F.Paste")
			(net "P3V3_AUX")
		)
		(pad "2" smd circle
			(at 0.40005 0)
			(size 0 0)
			(layers "F.Cu" "F.Mask" "F.Paste")
			(net "RST_CP2108_SDB_R_N")
		)
	)
	(footprint ""
		(layer "F.Cu")
		(at 325.287386 -96.811592 90)
		(property "Reference" "R743"
			(at 0 0 90)
			(layer "F.SilkS")
			(hide yes)
			(effects
				(font
					(size 1.27 1.27)
				)
			)
		)
		(property "Value" ""
			(at 0 0 90)
			(layer "F.Fab")
			(effects
				(font
					(size 1.27 1.27)
				)
			)
		)
		(duplicate_pad_numbers_are_jumpers no)
		(fp_line
			(start 0.7874 -0.4064)
			(end 0.7874 0.4064)
			(stroke
				(width 0.1524)
				(type default)
			)
			(layer "F.SilkS")
		)
		(fp_line
			(start -0.7874 -0.4064)
			(end 0.7874 -0.4064)
			(stroke
				(width 0.1524)
				(type default)
			)
			(layer "F.SilkS")
		)
		(fp_line
			(start 0.7874 0.4064)
			(end -0.7874 0.4064)
			(stroke
				(width 0.1524)
				(type default)
			)
			(layer "F.SilkS")
		)
		(fp_line
			(start -0.7874 0.4064)
			(end -0.7874 -0.4064)
			(stroke
				(width 0.1524)
				(type default)
			)
			(layer "F.SilkS")
		)
		(fp_line
			(start -0.12065 -0.305054)
			(end -0.12065 -0.2794)
			(stroke
				(width 0.1)
				(type default)
			)
			(layer "F.Fab")
		)
		(fp_line
			(start -0.67945 -0.305054)
			(end -0.12065 -0.305054)
			(stroke
				(width 0.1)
				(type default)
			)
			(layer "F.Fab")
		)
		(fp_line
			(start 0.67945 -0.3048)
			(end 0.67945 0.3048)
			(stroke
				(width 0.1)
				(type default)
			)
			(layer "F.Fab")
		)
		(fp_line
			(start 0.12065 -0.3048)
			(end 0.67945 -0.3048)
			(stroke
				(width 0.1)
				(type default)
			)
			(layer "F.Fab")
		)
		(fp_line
			(start 0.12065 -0.2794)
			(end 0.12065 -0.3048)
			(stroke
				(width 0.1)
				(type default)
			)
			(layer "F.Fab")
		)
		(fp_line
			(start -0.12065 -0.2794)
			(end 0.12065 -0.2794)
			(stroke
				(width 0.1)
				(type default)
			)
			(layer "F.Fab")
		)
		(fp_line
			(start 0.120396 0.2794)
			(end -0.12065 0.2794)
			(stroke
				(width 0.1)
				(type default)
			)
			(layer "F.Fab")
		)
		(fp_line
			(start -0.12065 0.2794)
			(end -0.12065 0.3048)
			(stroke
				(width 0.1)
				(type default)
			)
			(layer "F.Fab")
		)
		(fp_line
			(start 0.67945 0.3048)
			(end 0.120396 0.3048)
			(stroke
				(width 0.1)
				(type default)
			)
			(layer "F.Fab")
		)
		(fp_line
			(start 0.120396 0.3048)
			(end 0.120396 0.2794)
			(stroke
				(width 0.1)
				(type default)
			)
			(layer "F.Fab")
		)
		(fp_line
			(start -0.12065 0.3048)
			(end -0.67945 0.3048)
			(stroke
				(width 0.1)
				(type default)
			)
			(layer "F.Fab")
		)
		(fp_line
			(start -0.67945 0.3048)
			(end -0.67945 -0.305054)
			(stroke
				(width 0.1)
				(type default)
			)
			(layer "F.Fab")
		)
		(pad "1" smd circle
			(at -0.40005 0 90)
			(size 0 0)
			(layers "F.Cu" "F.Mask" "F.Paste")
			(net "SMB_BIC_I2C6_MUX_NIC_ADC_R_SDA")
		)
		(pad "2" smd circle
			(at 0.40005 0 90)
			(size 0 0)
			(layers "F.Cu" "F.Mask" "F.Paste")
			(net "SMB_NIC5_ADC_SDA")
		)
	)
	(footprint ""
		(layer "F.Cu")
		(at 103.611426 -71.458074 -90)
		(property "Reference" "PD89"
			(at 4.300474 -2.663444 90)
			(unlocked yes)
			(layer "F.SilkS")
			(effects
				(font
					(size 0.7874 0.5842)
					(thickness 0.1524)
				)
				(justify left)
			)
		)
		(property "Value" ""
			(at 0 0 270)
			(layer "F.Fab")
			(effects
				(font
					(size 1.27 1.27)
				)
			)
		)
		(duplicate_pad_numbers_are_jumpers no)
		(fp_line
			(start -3.656584 1.970024)
			(end 4.240784 1.970024)
			(stroke
				(width 0.1524)
				(type default)
			)
			(layer "F.SilkS")
		)
		(fp_line
			(start 4.240784 1.970024)
			(end 4.240784 -1.970024)
			(stroke
				(width 0.1524)
				(type default)
			)
			(layer "F.SilkS")
		)
		(fp_line
			(start -3.656584 -1.970024)
			(end -3.656584 1.970024)
			(stroke
				(width 0.1524)
				(type default)
			)
			(layer "F.SilkS")
		)
		(fp_line
			(start 4.240784 -1.970024)
			(end -3.656584 -1.970024)
			(stroke
				(width 0.1524)
				(type default)
			)
			(layer "F.SilkS")
		)
		(fp_poly
			(pts
				(xy 3.580384 1.970024) (xy 3.580384 -1.970024) (xy 4.240784 -1.970024) (xy 4.240784 1.970024)
			)
			(stroke
				(width 0)
				(type default)
			)
			(fill yes)
			(layer "F.SilkS")
		)
		(fp_line
			(start -2.3749 1.970024)
			(end 2.3749 1.970024)
			(stroke
				(width 0.1)
				(type default)
			)
			(layer "F.Fab")
		)
		(fp_line
			(start 2.3749 1.970024)
			(end 2.3749 -1.970024)
			(stroke
				(width 0.1)
				(type default)
			)
			(layer "F.Fab")
		)
		(fp_line
			(start -2.3749 -1.970024)
			(end -2.3749 1.970024)
			(stroke
				(width 0.1)
				(type default)
			)
			(layer "F.Fab")
		)
		(fp_line
			(start 2.3749 -1.970024)
			(end -2.3749 -1.970024)
			(stroke
				(width 0.1)
				(type default)
			)
			(layer "F.Fab")
		)
		(fp_text user "+"
			(at -4.9784 -0.23495 270)
			(unlocked yes)
			(layer "F.Fab")
			(effects
				(font
					(size 1.905 1.4224)
					(thickness 0.1524)
				)
				(justify left)
			)
		)
		(fp_text user "-"
			(at 4.1656 -0.23495 270)
			(unlocked yes)
			(layer "F.Fab")
			(effects
				(font
					(size 1.905 1.4224)
					(thickness 0.1524)
				)
				(justify left)
			)
		)
		(pad "A" smd rect
			(at -2.450084 0 270)
			(size 2.159 2.2606)
			(layers "F.Cu" "F.Mask" "F.Paste")
			(net "GND")
		)
		(pad "C" smd rect
			(at 2.450084 0 270)
			(size 2.159 2.2606)
			(layers "F.Cu" "F.Mask" "F.Paste")
			(net "P12V_AUX")
		)
	)
	(footprint ""
		(layer "F.Cu")
		(at 194.343782 -42.84091)
		(property "Reference" "R571"
			(at 0 0 0)
			(layer "F.SilkS")
			(hide yes)
			(effects
				(font
					(size 1.27 1.27)
				)
			)
		)
		(property "Value" ""
			(at 0 0 0)
			(layer "F.Fab")
			(effects
				(font
					(size 1.27 1.27)
				)
			)
		)
		(duplicate_pad_numbers_are_jumpers no)
		(fp_line
			(start -0.7874 -0.4064)
			(end 0.7874 -0.4064)
			(stroke
				(width 0.1524)
				(type default)
			)
			(layer "F.SilkS")
		)
		(fp_line
			(start -0.7874 0.4064)
			(end -0.7874 -0.4064)
			(stroke
				(width 0.1524)
				(type default)
			)
			(layer "F.SilkS")
		)
		(fp_line
			(start 0.7874 -0.4064)
			(end 0.7874 0.4064)
			(stroke
				(width 0.1524)
				(type default)
			)
			(layer "F.SilkS")
		)
		(fp_line
			(start 0.7874 0.4064)
			(end -0.7874 0.4064)
			(stroke
				(width 0.1524)
				(type default)
			)
			(layer "F.SilkS")
		)
		(fp_line
			(start -0.67945 -0.305054)
			(end -0.12065 -0.305054)
			(stroke
				(width 0.1)
				(type default)
			)
			(layer "F.Fab")
		)
		(fp_line
			(start -0.67945 0.3048)
			(end -0.67945 -0.305054)
			(stroke
				(width 0.1)
				(type default)
			)
			(layer "F.Fab")
		)
		(fp_line
			(start -0.12065 -0.305054)
			(end -0.12065 -0.2794)
			(stroke
				(width 0.1)
				(type default)
			)
			(layer "F.Fab")
		)
		(fp_line
			(start -0.12065 -0.2794)
			(end 0.12065 -0.2794)
			(stroke
				(width 0.1)
				(type default)
			)
			(layer "F.Fab")
		)
		(fp_line
			(start -0.12065 0.2794)
			(end -0.12065 0.3048)
			(stroke
				(width 0.1)
				(type default)
			)
			(layer "F.Fab")
		)
		(fp_line
			(start -0.12065 0.3048)
			(end -0.67945 0.3048)
			(stroke
				(width 0.1)
				(type default)
			)
			(layer "F.Fab")
		)
		(fp_line
			(start 0.120396 0.2794)
			(end -0.12065 0.2794)
			(stroke
				(width 0.1)
				(type default)
			)
			(layer "F.Fab")
		)
		(fp_line
			(start 0.120396 0.3048)
			(end 0.120396 0.2794)
			(stroke
				(width 0.1)
				(type default)
			)
			(layer "F.Fab")
		)
		(fp_line
			(start 0.12065 -0.3048)
			(end 0.67945 -0.3048)
			(stroke
				(width 0.1)
				(type default)
			)
			(layer "F.Fab")
		)
		(fp_line
			(start 0.12065 -0.2794)
			(end 0.12065 -0.3048)
			(stroke
				(width 0.1)
				(type default)
			)
			(layer "F.Fab")
		)
		(fp_line
			(start 0.67945 -0.3048)
			(end 0.67945 0.3048)
			(stroke
				(width 0.1)
				(type default)
			)
			(layer "F.Fab")
		)
		(fp_line
			(start 0.67945 0.3048)
			(end 0.120396 0.3048)
			(stroke
				(width 0.1)
				(type default)
			)
			(layer "F.Fab")
		)
		(pad "1" smd circle
			(at -0.40005 0)
			(size 0 0)
			(layers "F.Cu" "F.Mask" "F.Paste")
			(net "SSD6_ADC_A1")
		)
		(pad "2" smd circle
			(at 0.40005 0)
			(size 0 0)
			(layers "F.Cu" "F.Mask" "F.Paste")
			(net "P3V3_AUX")
		)
	)
	(footprint ""
		(layer "F.Cu")
		(at 169.759884 -195.868798)
		(property "Reference" "R3289"
			(at 0 0 0)
			(layer "F.SilkS")
			(hide yes)
			(effects
				(font
					(size 1.27 1.27)
				)
			)
		)
		(property "Value" ""
			(at 0 0 0)
			(layer "F.Fab")
			(effects
				(font
					(size 1.27 1.27)
				)
			)
		)
		(duplicate_pad_numbers_are_jumpers no)
		(fp_line
			(start -0.7874 -0.4064)
			(end 0.7874 -0.4064)
			(stroke
				(width 0.1524)
				(type default)
			)
			(layer "F.SilkS")
		)
		(fp_line
			(start -0.7874 0.4064)
			(end -0.7874 -0.4064)
			(stroke
				(width 0.1524)
				(type default)
			)
			(layer "F.SilkS")
		)
		(fp_line
			(start 0.7874 -0.4064)
			(end 0.7874 0.4064)
			(stroke
				(width 0.1524)
				(type default)
			)
			(layer "F.SilkS")
		)
		(fp_line
			(start 0.7874 0.4064)
			(end -0.7874 0.4064)
			(stroke
				(width 0.1524)
				(type default)
			)
			(layer "F.SilkS")
		)
		(fp_line
			(start -0.67945 -0.305054)
			(end -0.12065 -0.305054)
			(stroke
				(width 0.1)
				(type default)
			)
			(layer "F.Fab")
		)
		(fp_line
			(start -0.67945 0.3048)
			(end -0.67945 -0.305054)
			(stroke
				(width 0.1)
				(type default)
			)
			(layer "F.Fab")
		)
		(fp_line
			(start -0.12065 -0.305054)
			(end -0.12065 -0.2794)
			(stroke
				(width 0.1)
				(type default)
			)
			(layer "F.Fab")
		)
		(fp_line
			(start -0.12065 -0.2794)
			(end 0.12065 -0.2794)
			(stroke
				(width 0.1)
				(type default)
			)
			(layer "F.Fab")
		)
		(fp_line
			(start -0.12065 0.2794)
			(end -0.12065 0.3048)
			(stroke
				(width 0.1)
				(type default)
			)
			(layer "F.Fab")
		)
		(fp_line
			(start -0.12065 0.3048)
			(end -0.67945 0.3048)
			(stroke
				(width 0.1)
				(type default)
			)
			(layer "F.Fab")
		)
		(fp_line
			(start 0.120396 0.2794)
			(end -0.12065 0.2794)
			(stroke
				(width 0.1)
				(type default)
			)
			(layer "F.Fab")
		)
		(fp_line
			(start 0.120396 0.3048)
			(end 0.120396 0.2794)
			(stroke
				(width 0.1)
				(type default)
			)
			(layer "F.Fab")
		)
		(fp_line
			(start 0.12065 -0.3048)
			(end 0.67945 -0.3048)
			(stroke
				(width 0.1)
				(type default)
			)
			(layer "F.Fab")
		)
		(fp_line
			(start 0.12065 -0.2794)
			(end 0.12065 -0.3048)
			(stroke
				(width 0.1)
				(type default)
			)
			(layer "F.Fab")
		)
		(fp_line
			(start 0.67945 -0.3048)
			(end 0.67945 0.3048)
			(stroke
				(width 0.1)
				(type default)
			)
			(layer "F.Fab")
		)
		(fp_line
			(start 0.67945 0.3048)
			(end 0.120396 0.3048)
			(stroke
				(width 0.1)
				(type default)
			)
			(layer "F.Fab")
		)
		(pad "1" smd circle
			(at -0.40005 0)
			(size 0 0)
			(layers "F.Cu" "F.Mask" "F.Paste")
			(net "SPI_BIC1_MOSI_LS01_R")
		)
		(pad "2" smd circle
			(at 0.40005 0)
			(size 0 0)
			(layers "F.Cu" "F.Mask" "F.Paste")
			(net "SPI_BIC1_MOSI_LS01")
		)
	)
	(footprint ""
		(layer "F.Cu")
		(at 136.587738 -25.342342 -90)
		(property "Reference" "R423"
			(at 0 0 270)
			(layer "F.SilkS")
			(hide yes)
			(effects
				(font
					(size 1.27 1.27)
				)
			)
		)
		(property "Value" ""
			(at 0 0 270)
			(layer "F.Fab")
			(effects
				(font
					(size 1.27 1.27)
				)
			)
		)
		(duplicate_pad_numbers_are_jumpers no)
		(fp_line
			(start -0.7874 0.4064)
			(end -0.7874 -0.4064)
			(stroke
				(width 0.1524)
				(type default)
			)
			(layer "F.SilkS")
		)
		(fp_line
			(start 0.7874 0.4064)
			(end -0.7874 0.4064)
			(stroke
				(width 0.1524)
				(type default)
			)
			(layer "F.SilkS")
		)
		(fp_line
			(start -0.7874 -0.4064)
			(end 0.7874 -0.4064)
			(stroke
				(width 0.1524)
				(type default)
			)
			(layer "F.SilkS")
		)
		(fp_line
			(start 0.7874 -0.4064)
			(end 0.7874 0.4064)
			(stroke
				(width 0.1524)
				(type default)
			)
			(layer "F.SilkS")
		)
		(fp_line
			(start -0.67945 0.3048)
			(end -0.67945 -0.305054)
			(stroke
				(width 0.1)
				(type default)
			)
			(layer "F.Fab")
		)
		(fp_line
			(start -0.12065 0.3048)
			(end -0.67945 0.3048)
			(stroke
				(width 0.1)
				(type default)
			)
			(layer "F.Fab")
		)
		(fp_line
			(start 0.120396 0.3048)
			(end 0.120396 0.2794)
			(stroke
				(width 0.1)
				(type default)
			)
			(layer "F.Fab")
		)
		(fp_line
			(start 0.67945 0.3048)
			(end 0.120396 0.3048)
			(stroke
				(width 0.1)
				(type default)
			)
			(layer "F.Fab")
		)
		(fp_line
			(start -0.12065 0.2794)
			(end -0.12065 0.3048)
			(stroke
				(width 0.1)
				(type default)
			)
			(layer "F.Fab")
		)
		(fp_line
			(start 0.120396 0.2794)
			(end -0.12065 0.2794)
			(stroke
				(width 0.1)
				(type default)
			)
			(layer "F.Fab")
		)
		(fp_line
			(start -0.12065 -0.2794)
			(end 0.12065 -0.2794)
			(stroke
				(width 0.1)
				(type default)
			)
			(layer "F.Fab")
		)
		(fp_line
			(start 0.12065 -0.2794)
			(end 0.12065 -0.3048)
			(stroke
				(width 0.1)
				(type default)
			)
			(layer "F.Fab")
		)
		(fp_line
			(start 0.12065 -0.3048)
			(end 0.67945 -0.3048)
			(stroke
				(width 0.1)
				(type default)
			)
			(layer "F.Fab")
		)
		(fp_line
			(start 0.67945 -0.3048)
			(end 0.67945 0.3048)
			(stroke
				(width 0.1)
				(type default)
			)
			(layer "F.Fab")
		)
		(fp_line
			(start -0.67945 -0.305054)
			(end -0.12065 -0.305054)
			(stroke
				(width 0.1)
				(type default)
			)
			(layer "F.Fab")
		)
		(fp_line
			(start -0.12065 -0.305054)
			(end -0.12065 -0.2794)
			(stroke
				(width 0.1)
				(type default)
			)
			(layer "F.Fab")
		)
		(pad "1" smd circle
			(at -0.40005 0 270)
			(size 0 0)
			(layers "F.Cu" "F.Mask" "F.Paste")
			(net "GND")
		)
		(pad "2" smd circle
			(at 0.40005 0 270)
			(size 0 0)
			(layers "F.Cu" "F.Mask" "F.Paste")
			(net "DUALPORT_N_SSD4")
		)
	)
	(footprint ""
		(layer "F.Cu")
		(at 365.506 -206.883 180)
		(property "Reference" "R4628"
			(at 0 0 180)
			(layer "F.SilkS")
			(hide yes)
			(effects
				(font
					(size 1.27 1.27)
				)
			)
		)
		(property "Value" ""
			(at 0 0 180)
			(layer "F.Fab")
			(effects
				(font
					(size 1.27 1.27)
				)
			)
		)
		(duplicate_pad_numbers_are_jumpers no)
		(fp_line
			(start 0.7874 0.4064)
			(end -0.7874 0.4064)
			(stroke
				(width 0.1524)
				(type default)
			)
			(layer "F.SilkS")
		)
		(fp_line
			(start 0.7874 -0.4064)
			(end 0.7874 0.4064)
			(stroke
				(width 0.1524)
				(type default)
			)
			(layer "F.SilkS")
		)
		(fp_line
			(start -0.7874 0.4064)
			(end -0.7874 -0.4064)
			(stroke
				(width 0.1524)
				(type default)
			)
			(layer "F.SilkS")
		)
		(fp_line
			(start -0.7874 -0.4064)
			(end 0.7874 -0.4064)
			(stroke
				(width 0.1524)
				(type default)
			)
			(layer "F.SilkS")
		)
		(fp_line
			(start 0.67945 0.3048)
			(end 0.120396 0.3048)
			(stroke
				(width 0.1)
				(type default)
			)
			(layer "F.Fab")
		)
		(fp_line
			(start 0.67945 -0.3048)
			(end 0.67945 0.3048)
			(stroke
				(width 0.1)
				(type default)
			)
			(layer "F.Fab")
		)
		(fp_line
			(start 0.12065 -0.2794)
			(end 0.12065 -0.3048)
			(stroke
				(width 0.1)
				(type default)
			)
			(layer "F.Fab")
		)
		(fp_line
			(start 0.12065 -0.3048)
			(end 0.67945 -0.3048)
			(stroke
				(width 0.1)
				(type default)
			)
			(layer "F.Fab")
		)
		(fp_line
			(start 0.120396 0.3048)
			(end 0.120396 0.2794)
			(stroke
				(width 0.1)
				(type default)
			)
			(layer "F.Fab")
		)
		(fp_line
			(start 0.120396 0.2794)
			(end -0.12065 0.2794)
			(stroke
				(width 0.1)
				(type default)
			)
			(layer "F.Fab")
		)
		(fp_line
			(start -0.12065 0.3048)
			(end -0.67945 0.3048)
			(stroke
				(width 0.1)
				(type default)
			)
			(layer "F.Fab")
		)
		(fp_line
			(start -0.12065 0.2794)
			(end -0.12065 0.3048)
			(stroke
				(width 0.1)
				(type default)
			)
			(layer "F.Fab")
		)
		(fp_line
			(start -0.12065 -0.2794)
			(end 0.12065 -0.2794)
			(stroke
				(width 0.1)
				(type default)
			)
			(layer "F.Fab")
		)
		(fp_line
			(start -0.12065 -0.305054)
			(end -0.12065 -0.2794)
			(stroke
				(width 0.1)
				(type default)
			)
			(layer "F.Fab")
		)
		(fp_line
			(start -0.67945 0.3048)
			(end -0.67945 -0.305054)
			(stroke
				(width 0.1)
				(type default)
			)
			(layer "F.Fab")
		)
		(fp_line
			(start -0.67945 -0.305054)
			(end -0.12065 -0.305054)
			(stroke
				(width 0.1)
				(type default)
			)
			(layer "F.Fab")
		)
		(pad "1" smd circle
			(at -0.40005 0 180)
			(size 0 0)
			(layers "F.Cu" "F.Mask" "F.Paste")
			(net "SSD1_PEX_PWR_EN")
		)
		(pad "2" smd circle
			(at 0.40005 0 180)
			(size 0 0)
			(layers "F.Cu" "F.Mask" "F.Paste")
			(net "SSD1_PEX_PWR_EN_R")
		)
	)
	(footprint ""
		(layer "F.Cu")
		(at 210.942936 -188.652404 90)
		(property "Reference" "R5417"
			(at 0 0 90)
			(layer "F.SilkS")
			(hide yes)
			(effects
				(font
					(size 1.27 1.27)
				)
			)
		)
		(property "Value" ""
			(at 0 0 90)
			(layer "F.Fab")
			(effects
				(font
					(size 1.27 1.27)
				)
			)
		)
		(duplicate_pad_numbers_are_jumpers no)
		(fp_line
			(start 0.7874 -0.4064)
			(end 0.7874 0.4064)
			(stroke
				(width 0.1524)
				(type default)
			)
			(layer "F.SilkS")
		)
		(fp_line
			(start -0.7874 -0.4064)
			(end 0.7874 -0.4064)
			(stroke
				(width 0.1524)
				(type default)
			)
			(layer "F.SilkS")
		)
		(fp_line
			(start 0.7874 0.4064)
			(end -0.7874 0.4064)
			(stroke
				(width 0.1524)
				(type default)
			)
			(layer "F.SilkS")
		)
		(fp_line
			(start -0.7874 0.4064)
			(end -0.7874 -0.4064)
			(stroke
				(width 0.1524)
				(type default)
			)
			(layer "F.SilkS")
		)
		(fp_line
			(start -0.12065 -0.305054)
			(end -0.12065 -0.2794)
			(stroke
				(width 0.1)
				(type default)
			)
			(layer "F.Fab")
		)
		(fp_line
			(start -0.67945 -0.305054)
			(end -0.12065 -0.305054)
			(stroke
				(width 0.1)
				(type default)
			)
			(layer "F.Fab")
		)
		(fp_line
			(start 0.67945 -0.3048)
			(end 0.67945 0.3048)
			(stroke
				(width 0.1)
				(type default)
			)
			(layer "F.Fab")
		)
		(fp_line
			(start 0.12065 -0.3048)
			(end 0.67945 -0.3048)
			(stroke
				(width 0.1)
				(type default)
			)
			(layer "F.Fab")
		)
		(fp_line
			(start 0.12065 -0.2794)
			(end 0.12065 -0.3048)
			(stroke
				(width 0.1)
				(type default)
			)
			(layer "F.Fab")
		)
		(fp_line
			(start -0.12065 -0.2794)
			(end 0.12065 -0.2794)
			(stroke
				(width 0.1)
				(type default)
			)
			(layer "F.Fab")
		)
		(fp_line
			(start 0.120396 0.2794)
			(end -0.12065 0.2794)
			(stroke
				(width 0.1)
				(type default)
			)
			(layer "F.Fab")
		)
		(fp_line
			(start -0.12065 0.2794)
			(end -0.12065 0.3048)
			(stroke
				(width 0.1)
				(type default)
			)
			(layer "F.Fab")
		)
		(fp_line
			(start 0.67945 0.3048)
			(end 0.120396 0.3048)
			(stroke
				(width 0.1)
				(type default)
			)
			(layer "F.Fab")
		)
		(fp_line
			(start 0.120396 0.3048)
			(end 0.120396 0.2794)
			(stroke
				(width 0.1)
				(type default)
			)
			(layer "F.Fab")
		)
		(fp_line
			(start -0.12065 0.3048)
			(end -0.67945 0.3048)
			(stroke
				(width 0.1)
				(type default)
			)
			(layer "F.Fab")
		)
		(fp_line
			(start -0.67945 0.3048)
			(end -0.67945 -0.305054)
			(stroke
				(width 0.1)
				(type default)
			)
			(layer "F.Fab")
		)
		(pad "1" smd circle
			(at -0.40005 0 90)
			(size 0 0)
			(layers "F.Cu" "F.Mask" "F.Paste")
			(net "BIC_SEL_FLASH_SW3_R")
		)
		(pad "2" smd circle
			(at 0.40005 0 90)
			(size 0 0)
			(layers "F.Cu" "F.Mask" "F.Paste")
			(net "GND")
		)
	)
	(footprint ""
		(layer "F.Cu")
		(at 166.293292 -172.004482 -90)
		(property "Reference" "U21"
			(at 1.519682 -2.414778 90)
			(unlocked yes)
			(layer "F.SilkS")
			(effects
				(font
					(size 0.7874 0.5842)
					(thickness 0.1524)
				)
				(justify left)
			)
		)
		(property "Value" ""
			(at 0 0 270)
			(layer "F.Fab")
			(effects
				(font
					(size 1.27 1.27)
				)
			)
		)
		(duplicate_pad_numbers_are_jumpers no)
		(fp_line
			(start -2.0574 1.651)
			(end -2.0574 -1.651)
			(stroke
				(width 0.1524)
				(type default)
			)
			(layer "F.SilkS")
		)
		(fp_line
			(start 2.0574 1.651)
			(end -2.0574 1.651)
			(stroke
				(width 0.1524)
				(type default)
			)
			(layer "F.SilkS")
		)
		(fp_line
			(start 0 -1.016)
			(end 0.381 -1.651)
			(stroke
				(width 0.1524)
				(type default)
			)
			(layer "F.SilkS")
		)
		(fp_line
			(start -2.0574 -1.651)
			(end -0.381 -1.651)
			(stroke
				(width 0.1524)
				(type default)
			)
			(layer "F.SilkS")
		)
		(fp_line
			(start -0.381 -1.651)
			(end 0 -1.016)
			(stroke
				(width 0.1524)
				(type default)
			)
			(layer "F.SilkS")
		)
		(fp_line
			(start 0.381 -1.651)
			(end 2.0574 -1.651)
			(stroke
				(width 0.1524)
				(type default)
			)
			(layer "F.SilkS")
		)
		(fp_line
			(start 2.0574 -1.651)
			(end 2.0574 1.651)
			(stroke
				(width 0.1524)
				(type default)
			)
			(layer "F.SilkS")
		)
		(fp_poly
			(pts
				(xy -2.71272 -0.719328) (xy -2.71272 -1.344168) (xy -2.159 -1.016)
			)
			(stroke
				(width 0)
				(type default)
			)
			(fill yes)
			(layer "F.SilkS")
		)
		(fp_line
			(start -0.899922 1.549908)
			(end -0.899922 1.199896)
			(stroke
				(width 0.1)
				(type default)
			)
			(layer "F.Fab")
		)
		(fp_line
			(start 0.899922 1.549908)
			(end -0.899922 1.549908)
			(stroke
				(width 0.1)
				(type default)
			)
			(layer "F.Fab")
		)
		(fp_line
			(start -1.599946 1.199896)
			(end -1.599946 -1.199896)
			(stroke
				(width 0.1)
				(type default)
			)
			(layer "F.Fab")
		)
		(fp_line
			(start -0.899922 1.199896)
			(end -1.599946 1.199896)
			(stroke
				(width 0.1)
				(type default)
			)
			(layer "F.Fab")
		)
		(fp_line
			(start 0.899922 1.199896)
			(end 0.899922 1.549908)
			(stroke
				(width 0.1)
				(type default)
			)
			(layer "F.Fab")
		)
		(fp_line
			(start 1.599946 1.199896)
			(end 0.899922 1.199896)
			(stroke
				(width 0.1)
				(type default)
			)
			(layer "F.Fab")
		)
		(fp_line
			(start -1.599946 -1.199896)
			(end -0.899922 -1.199896)
			(stroke
				(width 0.1)
				(type default)
			)
			(layer "F.Fab")
		)
		(fp_line
			(start -0.899922 -1.199896)
			(end -0.899922 -1.549908)
			(stroke
				(width 0.1)
				(type default)
			)
			(layer "F.Fab")
		)
		(fp_line
			(start 0.899922 -1.199896)
			(end 1.599946 -1.199896)
			(stroke
				(width 0.1)
				(type default)
			)
			(layer "F.Fab")
		)
		(fp_line
			(start 1.599946 -1.199896)
			(end 1.599946 1.199896)
			(stroke
				(width 0.1)
				(type default)
			)
			(layer "F.Fab")
		)
		(fp_line
			(start -0.899922 -1.549908)
			(end 0.899922 -1.549908)
			(stroke
				(width 0.1)
				(type default)
			)
			(layer "F.Fab")
		)
		(fp_line
			(start 0.899922 -1.549908)
			(end 0.899922 -1.199896)
			(stroke
				(width 0.1)
				(type default)
			)
			(layer "F.Fab")
		)
		(fp_poly
			(pts
				(xy -2.71272 -0.719328) (xy -2.71272 -1.344168) (xy -2.159 -1.016)
			)
			(stroke
				(width 0)
				(type default)
			)
			(fill yes)
			(layer "F.Fab")
		)
		(pad "1" smd rect
			(at -1.225042 -0.94996 180)
			(size 0.5588 1.3462)
			(layers "F.Cu" "F.Mask" "F.Paste")
			(net "HP_NIC2_PWRGD_R")
		)
		(pad "2" smd rect
			(at -1.225042 0 180)
			(size 0.5588 1.3462)
			(layers "F.Cu" "F.Mask" "F.Paste")
			(net "RST_NIC2_PERST_R_N")
		)
		(pad "3" smd rect
			(at -1.225042 0.94996 180)
			(size 0.5588 1.3462)
			(layers "F.Cu" "F.Mask" "F.Paste")
			(net "GND")
		)
		(pad "4" smd rect
			(at 1.225042 0.94996 180)
			(size 0.5588 1.3462)
			(layers "F.Cu" "F.Mask" "F.Paste")
			(net "RST_HP_NIC2_N")
		)
		(pad "5" smd rect
			(at 1.225042 -0.94996 180)
			(size 0.5588 1.3462)
			(layers "F.Cu" "F.Mask" "F.Paste")
			(net "P3V3_AUX")
		)
	)
	(footprint ""
		(layer "F.Cu")
		(at 5.589524 -63.56223)
		(property "Reference" "Q127"
			(at 0.009144 -1.86563 0)
			(unlocked yes)
			(layer "F.SilkS")
			(effects
				(font
					(size 0.7874 0.5842)
					(thickness 0.1524)
				)
			)
		)
		(property "Value" ""
			(at 0 0 0)
			(layer "F.Fab")
			(effects
				(font
					(size 1.27 1.27)
				)
			)
		)
		(duplicate_pad_numbers_are_jumpers no)
		(fp_line
			(start -1.376172 -1.199896)
			(end -0.508 -1.199896)
			(stroke
				(width 0.1524)
				(type default)
			)
			(layer "F.SilkS")
		)
		(fp_line
			(start -1.376172 1.199896)
			(end -1.376172 -1.199896)
			(stroke
				(width 0.1524)
				(type default)
			)
			(layer "F.SilkS")
		)
		(fp_line
			(start -0.508 -1.199896)
			(end 0 -0.762)
			(stroke
				(width 0.1524)
				(type default)
			)
			(layer "F.SilkS")
		)
		(fp_line
			(start 0 -0.762)
			(end 0.508 -1.199896)
			(stroke
				(width 0.1524)
				(type default)
			)
			(layer "F.SilkS")
		)
		(fp_line
			(start 0.508 -1.199896)
			(end 1.376172 -1.199896)
			(stroke
				(width 0.1524)
				(type default)
			)
			(layer "F.SilkS")
		)
		(fp_line
			(start 1.376172 -1.199896)
			(end 1.376172 1.199896)
			(stroke
				(width 0.1524)
				(type default)
			)
			(layer "F.SilkS")
		)
		(fp_line
			(start 1.376172 1.199896)
			(end -1.376172 1.199896)
			(stroke
				(width 0.1524)
				(type default)
			)
			(layer "F.SilkS")
		)
		(fp_poly
			(pts
				(xy -1.574546 -1.051814) (xy -1.843786 -1.860042) (xy -2.382774 -1.321308)
			)
			(stroke
				(width 0)
				(type default)
			)
			(fill yes)
			(layer "F.SilkS")
		)
		(fp_line
			(start -0.674878 -1.100074)
			(end 0.674878 -1.100074)
			(stroke
				(width 0.1)
				(type default)
			)
			(layer "F.Fab")
		)
		(fp_line
			(start -0.674878 1.100074)
			(end -0.674878 -1.100074)
			(stroke
				(width 0.1)
				(type default)
			)
			(layer "F.Fab")
		)
		(fp_line
			(start 0.674878 -1.100074)
			(end 0.674878 1.100074)
			(stroke
				(width 0.1)
				(type default)
			)
			(layer "F.Fab")
		)
		(fp_line
			(start 0.674878 1.100074)
			(end -0.674878 1.100074)
			(stroke
				(width 0.1)
				(type default)
			)
			(layer "F.Fab")
		)
		(fp_poly
			(pts
				(xy -1.4605 -0.7493) (xy -2.2225 -1.1303) (xy -2.2225 -0.3683)
			)
			(stroke
				(width 0)
				(type default)
			)
			(fill yes)
			(layer "F.Fab")
		)
		(pad "1" smd rect
			(at -0.899922 -0.750062 270)
			(size 0.6096 0.6096)
			(layers "F.Cu" "F.Mask" "F.Paste")
			(net "GND")
		)
		(pad "2" smd rect
			(at -0.899922 0 270)
			(size 0.4064 0.6096)
			(layers "F.Cu" "F.Mask" "F.Paste")
			(net "P12V_SSD0_PG_G1")
		)
		(pad "3" smd rect
			(at -0.899922 0.750062 270)
			(size 0.6096 0.6096)
			(layers "F.Cu" "F.Mask" "F.Paste")
			(net "PWRGD_P12V_SSD0_D")
		)
		(pad "4" smd rect
			(at 0.899922 0.750062 270)
			(size 0.6096 0.6096)
			(layers "F.Cu" "F.Mask" "F.Paste")
			(net "GND")
		)
		(pad "5" smd rect
			(at 0.899922 0 270)
			(size 0.4064 0.6096)
			(layers "F.Cu" "F.Mask" "F.Paste")
			(net "P12V_SSD0_PG_G2")
		)
		(pad "6" smd rect
			(at 0.899922 -0.750062 270)
			(size 0.6096 0.6096)
			(layers "F.Cu" "F.Mask" "F.Paste")
			(net "P12V_SSD0_PG_G2")
		)
	)
	(footprint ""
		(layer "F.Cu")
		(at 336.042 -153.67)
		(property "Reference" "R4794"
			(at 0 0 0)
			(layer "F.SilkS")
			(hide yes)
			(effects
				(font
					(size 1.27 1.27)
				)
			)
		)
		(property "Value" ""
			(at 0 0 0)
			(layer "F.Fab")
			(effects
				(font
					(size 1.27 1.27)
				)
			)
		)
		(duplicate_pad_numbers_are_jumpers no)
		(fp_line
			(start -0.7874 -0.4064)
			(end 0.7874 -0.4064)
			(stroke
				(width 0.1524)
				(type default)
			)
			(layer "F.SilkS")
		)
		(fp_line
			(start -0.7874 0.4064)
			(end -0.7874 -0.4064)
			(stroke
				(width 0.1524)
				(type default)
			)
			(layer "F.SilkS")
		)
		(fp_line
			(start 0.7874 -0.4064)
			(end 0.7874 0.4064)
			(stroke
				(width 0.1524)
				(type default)
			)
			(layer "F.SilkS")
		)
		(fp_line
			(start 0.7874 0.4064)
			(end -0.7874 0.4064)
			(stroke
				(width 0.1524)
				(type default)
			)
			(layer "F.SilkS")
		)
		(fp_line
			(start -0.67945 -0.305054)
			(end -0.12065 -0.305054)
			(stroke
				(width 0.1)
				(type default)
			)
			(layer "F.Fab")
		)
		(fp_line
			(start -0.67945 0.3048)
			(end -0.67945 -0.305054)
			(stroke
				(width 0.1)
				(type default)
			)
			(layer "F.Fab")
		)
		(fp_line
			(start -0.12065 -0.305054)
			(end -0.12065 -0.2794)
			(stroke
				(width 0.1)
				(type default)
			)
			(layer "F.Fab")
		)
		(fp_line
			(start -0.12065 -0.2794)
			(end 0.12065 -0.2794)
			(stroke
				(width 0.1)
				(type default)
			)
			(layer "F.Fab")
		)
		(fp_line
			(start -0.12065 0.2794)
			(end -0.12065 0.3048)
			(stroke
				(width 0.1)
				(type default)
			)
			(layer "F.Fab")
		)
		(fp_line
			(start -0.12065 0.3048)
			(end -0.67945 0.3048)
			(stroke
				(width 0.1)
				(type default)
			)
			(layer "F.Fab")
		)
		(fp_line
			(start 0.120396 0.2794)
			(end -0.12065 0.2794)
			(stroke
				(width 0.1)
				(type default)
			)
			(layer "F.Fab")
		)
		(fp_line
			(start 0.120396 0.3048)
			(end 0.120396 0.2794)
			(stroke
				(width 0.1)
				(type default)
			)
			(layer "F.Fab")
		)
		(fp_line
			(start 0.12065 -0.3048)
			(end 0.67945 -0.3048)
			(stroke
				(width 0.1)
				(type default)
			)
			(layer "F.Fab")
		)
		(fp_line
			(start 0.12065 -0.2794)
			(end 0.12065 -0.3048)
			(stroke
				(width 0.1)
				(type default)
			)
			(layer "F.Fab")
		)
		(fp_line
			(start 0.67945 -0.3048)
			(end 0.67945 0.3048)
			(stroke
				(width 0.1)
				(type default)
			)
			(layer "F.Fab")
		)
		(fp_line
			(start 0.67945 0.3048)
			(end 0.120396 0.3048)
			(stroke
				(width 0.1)
				(type default)
			)
			(layer "F.Fab")
		)
		(pad "1" smd circle
			(at -0.40005 0)
			(size 0 0)
			(layers "F.Cu" "F.Mask" "F.Paste")
			(net "P3V3_AUX")
		)
		(pad "2" smd circle
			(at 0.40005 0)
			(size 0 0)
			(layers "F.Cu" "F.Mask" "F.Paste")
			(net "RST_PEX_SSD13_PERST_R_N")
		)
	)
	(footprint ""
		(layer "F.Cu")
		(at 238.738664 -206.51216 -90)
		(property "Reference" "R4851"
			(at 0 0 270)
			(layer "F.SilkS")
			(hide yes)
			(effects
				(font
					(size 1.27 1.27)
				)
			)
		)
		(property "Value" ""
			(at 0 0 270)
			(layer "F.Fab")
			(effects
				(font
					(size 1.27 1.27)
				)
			)
		)
		(duplicate_pad_numbers_are_jumpers no)
		(fp_line
			(start -0.7874 0.4064)
			(end -0.7874 -0.4064)
			(stroke
				(width 0.1524)
				(type default)
			)
			(layer "F.SilkS")
		)
		(fp_line
			(start 0.7874 0.4064)
			(end -0.7874 0.4064)
			(stroke
				(width 0.1524)
				(type default)
			)
			(layer "F.SilkS")
		)
		(fp_line
			(start -0.7874 -0.4064)
			(end 0.7874 -0.4064)
			(stroke
				(width 0.1524)
				(type default)
			)
			(layer "F.SilkS")
		)
		(fp_line
			(start 0.7874 -0.4064)
			(end 0.7874 0.4064)
			(stroke
				(width 0.1524)
				(type default)
			)
			(layer "F.SilkS")
		)
		(fp_line
			(start -0.67945 0.3048)
			(end -0.67945 -0.305054)
			(stroke
				(width 0.1)
				(type default)
			)
			(layer "F.Fab")
		)
		(fp_line
			(start -0.12065 0.3048)
			(end -0.67945 0.3048)
			(stroke
				(width 0.1)
				(type default)
			)
			(layer "F.Fab")
		)
		(fp_line
			(start 0.120396 0.3048)
			(end 0.120396 0.2794)
			(stroke
				(width 0.1)
				(type default)
			)
			(layer "F.Fab")
		)
		(fp_line
			(start 0.67945 0.3048)
			(end 0.120396 0.3048)
			(stroke
				(width 0.1)
				(type default)
			)
			(layer "F.Fab")
		)
		(fp_line
			(start -0.12065 0.2794)
			(end -0.12065 0.3048)
			(stroke
				(width 0.1)
				(type default)
			)
			(layer "F.Fab")
		)
		(fp_line
			(start 0.120396 0.2794)
			(end -0.12065 0.2794)
			(stroke
				(width 0.1)
				(type default)
			)
			(layer "F.Fab")
		)
		(fp_line
			(start -0.12065 -0.2794)
			(end 0.12065 -0.2794)
			(stroke
				(width 0.1)
				(type default)
			)
			(layer "F.Fab")
		)
		(fp_line
			(start 0.12065 -0.2794)
			(end 0.12065 -0.3048)
			(stroke
				(width 0.1)
				(type default)
			)
			(layer "F.Fab")
		)
		(fp_line
			(start 0.12065 -0.3048)
			(end 0.67945 -0.3048)
			(stroke
				(width 0.1)
				(type default)
			)
			(layer "F.Fab")
		)
		(fp_line
			(start 0.67945 -0.3048)
			(end 0.67945 0.3048)
			(stroke
				(width 0.1)
				(type default)
			)
			(layer "F.Fab")
		)
		(fp_line
			(start -0.67945 -0.305054)
			(end -0.12065 -0.305054)
			(stroke
				(width 0.1)
				(type default)
			)
			(layer "F.Fab")
		)
		(fp_line
			(start -0.12065 -0.305054)
			(end -0.12065 -0.2794)
			(stroke
				(width 0.1)
				(type default)
			)
			(layer "F.Fab")
		)
		(pad "1" smd circle
			(at -0.40005 0 270)
			(size 0 0)
			(layers "F.Cu" "F.Mask" "F.Paste")
			(net "P12V_AUX_SCALED")
		)
		(pad "2" smd circle
			(at 0.40005 0 270)
			(size 0 0)
			(layers "F.Cu" "F.Mask" "F.Paste")
			(net "GND")
		)
	)
	(footprint ""
		(layer "F.Cu")
		(at 327.533 -216.281 180)
		(property "Reference" "R4156"
			(at 0 0 180)
			(layer "F.SilkS")
			(hide yes)
			(effects
				(font
					(size 1.27 1.27)
				)
			)
		)
		(property "Value" ""
			(at 0 0 180)
			(layer "F.Fab")
			(effects
				(font
					(size 1.27 1.27)
				)
			)
		)
		(duplicate_pad_numbers_are_jumpers no)
		(fp_line
			(start 0.7874 0.4064)
			(end -0.7874 0.4064)
			(stroke
				(width 0.1524)
				(type default)
			)
			(layer "F.SilkS")
		)
		(fp_line
			(start 0.7874 -0.4064)
			(end 0.7874 0.4064)
			(stroke
				(width 0.1524)
				(type default)
			)
			(layer "F.SilkS")
		)
		(fp_line
			(start -0.7874 0.4064)
			(end -0.7874 -0.4064)
			(stroke
				(width 0.1524)
				(type default)
			)
			(layer "F.SilkS")
		)
		(fp_line
			(start -0.7874 -0.4064)
			(end 0.7874 -0.4064)
			(stroke
				(width 0.1524)
				(type default)
			)
			(layer "F.SilkS")
		)
		(fp_line
			(start 0.67945 0.3048)
			(end 0.120396 0.3048)
			(stroke
				(width 0.1)
				(type default)
			)
			(layer "F.Fab")
		)
		(fp_line
			(start 0.67945 -0.3048)
			(end 0.67945 0.3048)
			(stroke
				(width 0.1)
				(type default)
			)
			(layer "F.Fab")
		)
		(fp_line
			(start 0.12065 -0.2794)
			(end 0.12065 -0.3048)
			(stroke
				(width 0.1)
				(type default)
			)
			(layer "F.Fab")
		)
		(fp_line
			(start 0.12065 -0.3048)
			(end 0.67945 -0.3048)
			(stroke
				(width 0.1)
				(type default)
			)
			(layer "F.Fab")
		)
		(fp_line
			(start 0.120396 0.3048)
			(end 0.120396 0.2794)
			(stroke
				(width 0.1)
				(type default)
			)
			(layer "F.Fab")
		)
		(fp_line
			(start 0.120396 0.2794)
			(end -0.12065 0.2794)
			(stroke
				(width 0.1)
				(type default)
			)
			(layer "F.Fab")
		)
		(fp_line
			(start -0.12065 0.3048)
			(end -0.67945 0.3048)
			(stroke
				(width 0.1)
				(type default)
			)
			(layer "F.Fab")
		)
		(fp_line
			(start -0.12065 0.2794)
			(end -0.12065 0.3048)
			(stroke
				(width 0.1)
				(type default)
			)
			(layer "F.Fab")
		)
		(fp_line
			(start -0.12065 -0.2794)
			(end 0.12065 -0.2794)
			(stroke
				(width 0.1)
				(type default)
			)
			(layer "F.Fab")
		)
		(fp_line
			(start -0.12065 -0.305054)
			(end -0.12065 -0.2794)
			(stroke
				(width 0.1)
				(type default)
			)
			(layer "F.Fab")
		)
		(fp_line
			(start -0.67945 0.3048)
			(end -0.67945 -0.305054)
			(stroke
				(width 0.1)
				(type default)
			)
			(layer "F.Fab")
		)
		(fp_line
			(start -0.67945 -0.305054)
			(end -0.12065 -0.305054)
			(stroke
				(width 0.1)
				(type default)
			)
			(layer "F.Fab")
		)
		(pad "1" smd circle
			(at -0.40005 0 180)
			(size 0 0)
			(layers "F.Cu" "F.Mask" "F.Paste")
			(net "PRSNT_SSD9_FPGA_N")
		)
		(pad "2" smd circle
			(at 0.40005 0 180)
			(size 0 0)
			(layers "F.Cu" "F.Mask" "F.Paste")
			(net "PRSNT_SSD9_FPGA_R_N")
		)
	)
	(footprint ""
		(layer "F.Cu")
		(at 122.29719 -110.722918 90)
		(property "Reference" "R5826"
			(at 0 0 90)
			(layer "F.SilkS")
			(hide yes)
			(effects
				(font
					(size 1.27 1.27)
				)
			)
		)
		(property "Value" ""
			(at 0 0 90)
			(layer "F.Fab")
			(effects
				(font
					(size 1.27 1.27)
				)
			)
		)
		(duplicate_pad_numbers_are_jumpers no)
		(fp_line
			(start 0.7874 -0.4064)
			(end 0.7874 0.4064)
			(stroke
				(width 0.1524)
				(type default)
			)
			(layer "F.SilkS")
		)
		(fp_line
			(start -0.7874 -0.4064)
			(end 0.7874 -0.4064)
			(stroke
				(width 0.1524)
				(type default)
			)
			(layer "F.SilkS")
		)
		(fp_line
			(start 0.7874 0.4064)
			(end -0.7874 0.4064)
			(stroke
				(width 0.1524)
				(type default)
			)
			(layer "F.SilkS")
		)
		(fp_line
			(start -0.7874 0.4064)
			(end -0.7874 -0.4064)
			(stroke
				(width 0.1524)
				(type default)
			)
			(layer "F.SilkS")
		)
		(fp_line
			(start -0.12065 -0.305054)
			(end -0.12065 -0.2794)
			(stroke
				(width 0.1)
				(type default)
			)
			(layer "F.Fab")
		)
		(fp_line
			(start -0.67945 -0.305054)
			(end -0.12065 -0.305054)
			(stroke
				(width 0.1)
				(type default)
			)
			(layer "F.Fab")
		)
		(fp_line
			(start 0.67945 -0.3048)
			(end 0.67945 0.3048)
			(stroke
				(width 0.1)
				(type default)
			)
			(layer "F.Fab")
		)
		(fp_line
			(start 0.12065 -0.3048)
			(end 0.67945 -0.3048)
			(stroke
				(width 0.1)
				(type default)
			)
			(layer "F.Fab")
		)
		(fp_line
			(start 0.12065 -0.2794)
			(end 0.12065 -0.3048)
			(stroke
				(width 0.1)
				(type default)
			)
			(layer "F.Fab")
		)
		(fp_line
			(start -0.12065 -0.2794)
			(end 0.12065 -0.2794)
			(stroke
				(width 0.1)
				(type default)
			)
			(layer "F.Fab")
		)
		(fp_line
			(start 0.120396 0.2794)
			(end -0.12065 0.2794)
			(stroke
				(width 0.1)
				(type default)
			)
			(layer "F.Fab")
		)
		(fp_line
			(start -0.12065 0.2794)
			(end -0.12065 0.3048)
			(stroke
				(width 0.1)
				(type default)
			)
			(layer "F.Fab")
		)
		(fp_line
			(start 0.67945 0.3048)
			(end 0.120396 0.3048)
			(stroke
				(width 0.1)
				(type default)
			)
			(layer "F.Fab")
		)
		(fp_line
			(start 0.120396 0.3048)
			(end 0.120396 0.2794)
			(stroke
				(width 0.1)
				(type default)
			)
			(layer "F.Fab")
		)
		(fp_line
			(start -0.12065 0.3048)
			(end -0.67945 0.3048)
			(stroke
				(width 0.1)
				(type default)
			)
			(layer "F.Fab")
		)
		(fp_line
			(start -0.67945 0.3048)
			(end -0.67945 -0.305054)
			(stroke
				(width 0.1)
				(type default)
			)
			(layer "F.Fab")
		)
		(pad "1" smd circle
			(at -0.40005 0 90)
			(size 0 0)
			(layers "F.Cu" "F.Mask" "F.Paste")
			(net "PWRGD_P3V3_D")
		)
		(pad "2" smd circle
			(at 0.40005 0 90)
			(size 0 0)
			(layers "F.Cu" "F.Mask" "F.Paste")
			(net "PWRGD_P3V3_R")
		)
	)
	(footprint ""
		(layer "F.Cu")
		(at 337.752944 -80.607662 90)
		(property "Reference" "R1173"
			(at 0 0 90)
			(layer "F.SilkS")
			(hide yes)
			(effects
				(font
					(size 1.27 1.27)
				)
			)
		)
		(property "Value" ""
			(at 0 0 90)
			(layer "F.Fab")
			(effects
				(font
					(size 1.27 1.27)
				)
			)
		)
		(duplicate_pad_numbers_are_jumpers no)
		(fp_line
			(start 0.7874 0.4064)
			(end -0.7874 0.4064)
			(stroke
				(width 0.1524)
				(type default)
			)
			(layer "F.SilkS")
		)
		(fp_line
			(start -0.12065 -0.305054)
			(end -0.12065 -0.2794)
			(stroke
				(width 0.1)
				(type default)
			)
			(layer "F.Fab")
		)
		(fp_line
			(start -0.67945 -0.305054)
			(end -0.12065 -0.305054)
			(stroke
				(width 0.1)
				(type default)
			)
			(layer "F.Fab")
		)
		(fp_line
			(start 0.67945 -0.3048)
			(end 0.67945 0.3048)
			(stroke
				(width 0.1)
				(type default)
			)
			(layer "F.Fab")
		)
		(fp_line
			(start 0.12065 -0.3048)
			(end 0.67945 -0.3048)
			(stroke
				(width 0.1)
				(type default)
			)
			(layer "F.Fab")
		)
		(fp_line
			(start 0.12065 -0.2794)
			(end 0.12065 -0.3048)
			(stroke
				(width 0.1)
				(type default)
			)
			(layer "F.Fab")
		)
		(fp_line
			(start -0.12065 -0.2794)
			(end 0.12065 -0.2794)
			(stroke
				(width 0.1)
				(type default)
			)
			(layer "F.Fab")
		)
		(fp_line
			(start 0.120396 0.2794)
			(end -0.12065 0.2794)
			(stroke
				(width 0.1)
				(type default)
			)
			(layer "F.Fab")
		)
		(fp_line
			(start -0.12065 0.2794)
			(end -0.12065 0.3048)
			(stroke
				(width 0.1)
				(type default)
			)
			(layer "F.Fab")
		)
		(fp_line
			(start 0.67945 0.3048)
			(end 0.120396 0.3048)
			(stroke
				(width 0.1)
				(type default)
			)
			(layer "F.Fab")
		)
		(fp_line
			(start 0.120396 0.3048)
			(end 0.120396 0.2794)
			(stroke
				(width 0.1)
				(type default)
			)
			(layer "F.Fab")
		)
		(fp_line
			(start -0.12065 0.3048)
			(end -0.67945 0.3048)
			(stroke
				(width 0.1)
				(type default)
			)
			(layer "F.Fab")
		)
		(fp_line
			(start -0.67945 0.3048)
			(end -0.67945 -0.305054)
			(stroke
				(width 0.1)
				(type default)
			)
			(layer "F.Fab")
		)
		(pad "1" smd circle
			(at -0.40005 0 90)
			(size 0 0)
			(layers "F.Cu" "F.Mask" "F.Paste")
			(net "CLK_100M_DB800ZL_SSD9_R_DN")
		)
		(pad "2" smd circle
			(at 0.40005 0 90)
			(size 0 0)
			(layers "F.Cu" "F.Mask" "F.Paste")
			(net "CLK_100M_DB800ZL_SSD9_DN")
		)
	)
	(footprint ""
		(layer "F.Cu")
		(at 17.337786 -268.134084)
		(property "Reference" "C4238"
			(at 0 0 0)
			(layer "F.SilkS")
			(hide yes)
			(effects
				(font
					(size 1.27 1.27)
				)
			)
		)
		(property "Value" ""
			(at 0 0 0)
			(layer "F.Fab")
			(effects
				(font
					(size 1.27 1.27)
				)
			)
		)
		(duplicate_pad_numbers_are_jumpers no)
		(fp_line
			(start -0.299974 -0.150114)
			(end 0.299974 -0.150114)
			(stroke
				(width 0.1)
				(type default)
			)
			(layer "F.Fab")
		)
		(fp_line
			(start -0.299974 0.150114)
			(end -0.299974 -0.150114)
			(stroke
				(width 0.1)
				(type default)
			)
			(layer "F.Fab")
		)
		(fp_line
			(start 0.299974 -0.150114)
			(end 0.299974 0.150114)
			(stroke
				(width 0.1)
				(type default)
			)
			(layer "F.Fab")
		)
		(fp_line
			(start 0.299974 0.150114)
			(end -0.299974 0.150114)
			(stroke
				(width 0.1)
				(type default)
			)
			(layer "F.Fab")
		)
		(pad "1" smd rect
			(at -0.2667 0)
			(size 0.3048 0.381)
			(layers "F.Cu" "F.Mask" "F.Paste")
			(net "P1V25_SERDES_VDDPLL_PEX0")
		)
		(pad "2" smd rect
			(at 0.2667 0)
			(size 0.3048 0.381)
			(layers "F.Cu" "F.Mask" "F.Paste")
			(net "GND")
		)
	)
	(footprint ""
		(layer "F.Cu")
		(at 100.868734 -237.306612 90)
		(property "Reference" "PC294"
			(at 0 0 90)
			(layer "F.SilkS")
			(hide yes)
			(effects
				(font
					(size 1.27 1.27)
				)
			)
		)
		(property "Value" ""
			(at 0 0 90)
			(layer "F.Fab")
			(effects
				(font
					(size 1.27 1.27)
				)
			)
		)
		(duplicate_pad_numbers_are_jumpers no)
		(fp_line
			(start 1.524 -0.762)
			(end 1.524 0.762)
			(stroke
				(width 0.1524)
				(type default)
			)
			(layer "F.SilkS")
		)
		(fp_line
			(start -1.524 -0.762)
			(end 1.524 -0.762)
			(stroke
				(width 0.1524)
				(type default)
			)
			(layer "F.SilkS")
		)
		(fp_line
			(start 1.524 0.762)
			(end -1.524 0.762)
			(stroke
				(width 0.1524)
				(type default)
			)
			(layer "F.SilkS")
		)
		(fp_line
			(start -1.524 0.762)
			(end -1.524 -0.762)
			(stroke
				(width 0.1524)
				(type default)
			)
			(layer "F.SilkS")
		)
		(fp_line
			(start 1.1049 -0.724916)
			(end -1.1049 -0.724916)
			(stroke
				(width 0.1)
				(type default)
			)
			(layer "F.Fab")
		)
		(fp_line
			(start -1.1049 -0.724916)
			(end -1.1049 0.724916)
			(stroke
				(width 0.1)
				(type default)
			)
			(layer "F.Fab")
		)
		(fp_line
			(start 1.1049 0.724916)
			(end 1.1049 -0.724916)
			(stroke
				(width 0.1)
				(type default)
			)
			(layer "F.Fab")
		)
		(fp_line
			(start -1.1049 0.724916)
			(end 1.1049 0.724916)
			(stroke
				(width 0.1)
				(type default)
			)
			(layer "F.Fab")
		)
		(pad "1" smd rect
			(at -0.889 0 270)
			(size 1.016 1.27)
			(layers "F.Cu" "F.Mask" "F.Paste")
			(net "P1V8_PEX_R")
		)
		(pad "2" smd rect
			(at 0.889 0 270)
			(size 1.016 1.27)
			(layers "F.Cu" "F.Mask" "F.Paste")
			(net "GND")
		)
	)
	(footprint ""
		(layer "F.Cu")
		(at 115.356386 -87.384382 180)
		(property "Reference" "R1147"
			(at 0 0 180)
			(layer "F.SilkS")
			(hide yes)
			(effects
				(font
					(size 1.27 1.27)
				)
			)
		)
		(property "Value" ""
			(at 0 0 180)
			(layer "F.Fab")
			(effects
				(font
					(size 1.27 1.27)
				)
			)
		)
		(duplicate_pad_numbers_are_jumpers no)
		(fp_line
			(start 0.7874 0.4064)
			(end -0.7874 0.4064)
			(stroke
				(width 0.1524)
				(type default)
			)
			(layer "F.SilkS")
		)
		(fp_line
			(start 0.67945 0.3048)
			(end 0.120396 0.3048)
			(stroke
				(width 0.1)
				(type default)
			)
			(layer "F.Fab")
		)
		(fp_line
			(start 0.67945 -0.3048)
			(end 0.67945 0.3048)
			(stroke
				(width 0.1)
				(type default)
			)
			(layer "F.Fab")
		)
		(fp_line
			(start 0.12065 -0.2794)
			(end 0.12065 -0.3048)
			(stroke
				(width 0.1)
				(type default)
			)
			(layer "F.Fab")
		)
		(fp_line
			(start 0.12065 -0.3048)
			(end 0.67945 -0.3048)
			(stroke
				(width 0.1)
				(type default)
			)
			(layer "F.Fab")
		)
		(fp_line
			(start 0.120396 0.3048)
			(end 0.120396 0.2794)
			(stroke
				(width 0.1)
				(type default)
			)
			(layer "F.Fab")
		)
		(fp_line
			(start 0.120396 0.2794)
			(end -0.12065 0.2794)
			(stroke
				(width 0.1)
				(type default)
			)
			(layer "F.Fab")
		)
		(fp_line
			(start -0.12065 0.3048)
			(end -0.67945 0.3048)
			(stroke
				(width 0.1)
				(type default)
			)
			(layer "F.Fab")
		)
		(fp_line
			(start -0.12065 0.2794)
			(end -0.12065 0.3048)
			(stroke
				(width 0.1)
				(type default)
			)
			(layer "F.Fab")
		)
		(fp_line
			(start -0.12065 -0.2794)
			(end 0.12065 -0.2794)
			(stroke
				(width 0.1)
				(type default)
			)
			(layer "F.Fab")
		)
		(fp_line
			(start -0.12065 -0.305054)
			(end -0.12065 -0.2794)
			(stroke
				(width 0.1)
				(type default)
			)
			(layer "F.Fab")
		)
		(fp_line
			(start -0.67945 0.3048)
			(end -0.67945 -0.305054)
			(stroke
				(width 0.1)
				(type default)
			)
			(layer "F.Fab")
		)
		(fp_line
			(start -0.67945 -0.305054)
			(end -0.12065 -0.305054)
			(stroke
				(width 0.1)
				(type default)
			)
			(layer "F.Fab")
		)
		(pad "1" smd circle
			(at -0.40005 0 180)
			(size 0 0)
			(layers "F.Cu" "F.Mask" "F.Paste")
			(net "CLK_100M_DB800ZL_SSD5_R_DN")
		)
		(pad "2" smd circle
			(at 0.40005 0 180)
			(size 0 0)
			(layers "F.Cu" "F.Mask" "F.Paste")
			(net "CLK_100M_DB800ZL_SSD5_DN")
		)
	)
	(footprint ""
		(layer "F.Cu")
		(at 219.202 -199.644 180)
		(property "Reference" "C2627"
			(at 0 0 180)
			(layer "F.SilkS")
			(hide yes)
			(effects
				(font
					(size 1.27 1.27)
				)
			)
		)
		(property "Value" ""
			(at 0 0 180)
			(layer "F.Fab")
			(effects
				(font
					(size 1.27 1.27)
				)
			)
		)
		(duplicate_pad_numbers_are_jumpers no)
		(fp_line
			(start 0.7874 0.4064)
			(end -0.7874 0.4064)
			(stroke
				(width 0.1524)
				(type default)
			)
			(layer "F.SilkS")
		)
		(fp_line
			(start 0.7874 -0.4064)
			(end 0.7874 0.4064)
			(stroke
				(width 0.1524)
				(type default)
			)
			(layer "F.SilkS")
		)
		(fp_line
			(start -0.7874 0.4064)
			(end -0.7874 -0.4064)
			(stroke
				(width 0.1524)
				(type default)
			)
			(layer "F.SilkS")
		)
		(fp_line
			(start -0.7874 -0.4064)
			(end 0.7874 -0.4064)
			(stroke
				(width 0.1524)
				(type default)
			)
			(layer "F.SilkS")
		)
		(fp_line
			(start 0.67945 0.3048)
			(end 0.120396 0.3048)
			(stroke
				(width 0.1)
				(type default)
			)
			(layer "F.Fab")
		)
		(fp_line
			(start 0.67945 -0.3048)
			(end 0.67945 0.3048)
			(stroke
				(width 0.1)
				(type default)
			)
			(layer "F.Fab")
		)
		(fp_line
			(start 0.12065 -0.2794)
			(end 0.12065 -0.3048)
			(stroke
				(width 0.1)
				(type default)
			)
			(layer "F.Fab")
		)
		(fp_line
			(start 0.12065 -0.3048)
			(end 0.67945 -0.3048)
			(stroke
				(width 0.1)
				(type default)
			)
			(layer "F.Fab")
		)
		(fp_line
			(start 0.120396 0.3048)
			(end 0.120396 0.2794)
			(stroke
				(width 0.1)
				(type default)
			)
			(layer "F.Fab")
		)
		(fp_line
			(start 0.120396 0.2794)
			(end -0.12065 0.2794)
			(stroke
				(width 0.1)
				(type default)
			)
			(layer "F.Fab")
		)
		(fp_line
			(start -0.12065 0.3048)
			(end -0.67945 0.3048)
			(stroke
				(width 0.1)
				(type default)
			)
			(layer "F.Fab")
		)
		(fp_line
			(start -0.12065 0.2794)
			(end -0.12065 0.3048)
			(stroke
				(width 0.1)
				(type default)
			)
			(layer "F.Fab")
		)
		(fp_line
			(start -0.12065 -0.2794)
			(end 0.12065 -0.2794)
			(stroke
				(width 0.1)
				(type default)
			)
			(layer "F.Fab")
		)
		(fp_line
			(start -0.12065 -0.305054)
			(end -0.12065 -0.2794)
			(stroke
				(width 0.1)
				(type default)
			)
			(layer "F.Fab")
		)
		(fp_line
			(start -0.67945 0.3048)
			(end -0.67945 -0.305054)
			(stroke
				(width 0.1)
				(type default)
			)
			(layer "F.Fab")
		)
		(fp_line
			(start -0.67945 -0.305054)
			(end -0.12065 -0.305054)
			(stroke
				(width 0.1)
				(type default)
			)
			(layer "F.Fab")
		)
		(pad "1" smd circle
			(at -0.40005 0 180)
			(size 0 0)
			(layers "F.Cu" "F.Mask" "F.Paste")
			(net "GND")
		)
		(pad "2" smd circle
			(at 0.40005 0 180)
			(size 0 0)
			(layers "F.Cu" "F.Mask" "F.Paste")
			(net "P3V3_NIC6")
		)
	)
	(footprint ""
		(layer "F.Cu")
		(at 359.148126 -183.107076 180)
		(property "Reference" "R4680"
			(at 0 0 180)
			(layer "F.SilkS")
			(hide yes)
			(effects
				(font
					(size 1.27 1.27)
				)
			)
		)
		(property "Value" ""
			(at 0 0 180)
			(layer "F.Fab")
			(effects
				(font
					(size 1.27 1.27)
				)
			)
		)
		(duplicate_pad_numbers_are_jumpers no)
		(fp_line
			(start 0.7874 0.4064)
			(end -0.7874 0.4064)
			(stroke
				(width 0.1524)
				(type default)
			)
			(layer "F.SilkS")
		)
		(fp_line
			(start 0.7874 -0.4064)
			(end 0.7874 0.4064)
			(stroke
				(width 0.1524)
				(type default)
			)
			(layer "F.SilkS")
		)
		(fp_line
			(start -0.7874 0.4064)
			(end -0.7874 -0.4064)
			(stroke
				(width 0.1524)
				(type default)
			)
			(layer "F.SilkS")
		)
		(fp_line
			(start -0.7874 -0.4064)
			(end 0.7874 -0.4064)
			(stroke
				(width 0.1524)
				(type default)
			)
			(layer "F.SilkS")
		)
		(fp_line
			(start 0.67945 0.3048)
			(end 0.120396 0.3048)
			(stroke
				(width 0.1)
				(type default)
			)
			(layer "F.Fab")
		)
		(fp_line
			(start 0.67945 -0.3048)
			(end 0.67945 0.3048)
			(stroke
				(width 0.1)
				(type default)
			)
			(layer "F.Fab")
		)
		(fp_line
			(start 0.12065 -0.2794)
			(end 0.12065 -0.3048)
			(stroke
				(width 0.1)
				(type default)
			)
			(layer "F.Fab")
		)
		(fp_line
			(start 0.12065 -0.3048)
			(end 0.67945 -0.3048)
			(stroke
				(width 0.1)
				(type default)
			)
			(layer "F.Fab")
		)
		(fp_line
			(start 0.120396 0.3048)
			(end 0.120396 0.2794)
			(stroke
				(width 0.1)
				(type default)
			)
			(layer "F.Fab")
		)
		(fp_line
			(start 0.120396 0.2794)
			(end -0.12065 0.2794)
			(stroke
				(width 0.1)
				(type default)
			)
			(layer "F.Fab")
		)
		(fp_line
			(start -0.12065 0.3048)
			(end -0.67945 0.3048)
			(stroke
				(width 0.1)
				(type default)
			)
			(layer "F.Fab")
		)
		(fp_line
			(start -0.12065 0.2794)
			(end -0.12065 0.3048)
			(stroke
				(width 0.1)
				(type default)
			)
			(layer "F.Fab")
		)
		(fp_line
			(start -0.12065 -0.2794)
			(end 0.12065 -0.2794)
			(stroke
				(width 0.1)
				(type default)
			)
			(layer "F.Fab")
		)
		(fp_line
			(start -0.12065 -0.305054)
			(end -0.12065 -0.2794)
			(stroke
				(width 0.1)
				(type default)
			)
			(layer "F.Fab")
		)
		(fp_line
			(start -0.67945 0.3048)
			(end -0.67945 -0.305054)
			(stroke
				(width 0.1)
				(type default)
			)
			(layer "F.Fab")
		)
		(fp_line
			(start -0.67945 -0.305054)
			(end -0.12065 -0.305054)
			(stroke
				(width 0.1)
				(type default)
			)
			(layer "F.Fab")
		)
		(pad "1" smd circle
			(at -0.40005 0 180)
			(size 0 0)
			(layers "F.Cu" "F.Mask" "F.Paste")
			(net "PEX1_PCA9555_INT_R_N")
		)
		(pad "2" smd circle
			(at 0.40005 0 180)
			(size 0 0)
			(layers "F.Cu" "F.Mask" "F.Paste")
			(net "PEX1_PCA9555_INT_N")
		)
	)
	(footprint ""
		(layer "F.Cu")
		(at 219.202 -202.184)
		(property "Reference" "R1516"
			(at 0 0 0)
			(layer "F.SilkS")
			(hide yes)
			(effects
				(font
					(size 1.27 1.27)
				)
			)
		)
		(property "Value" ""
			(at 0 0 0)
			(layer "F.Fab")
			(effects
				(font
					(size 1.27 1.27)
				)
			)
		)
		(duplicate_pad_numbers_are_jumpers no)
		(fp_line
			(start -0.7874 -0.4064)
			(end 0.7874 -0.4064)
			(stroke
				(width 0.1524)
				(type default)
			)
			(layer "F.SilkS")
		)
		(fp_line
			(start -0.7874 0.4064)
			(end -0.7874 -0.4064)
			(stroke
				(width 0.1524)
				(type default)
			)
			(layer "F.SilkS")
		)
		(fp_line
			(start 0.7874 -0.4064)
			(end 0.7874 0.4064)
			(stroke
				(width 0.1524)
				(type default)
			)
			(layer "F.SilkS")
		)
		(fp_line
			(start 0.7874 0.4064)
			(end -0.7874 0.4064)
			(stroke
				(width 0.1524)
				(type default)
			)
			(layer "F.SilkS")
		)
		(fp_line
			(start -0.67945 -0.305054)
			(end -0.12065 -0.305054)
			(stroke
				(width 0.1)
				(type default)
			)
			(layer "F.Fab")
		)
		(fp_line
			(start -0.67945 0.3048)
			(end -0.67945 -0.305054)
			(stroke
				(width 0.1)
				(type default)
			)
			(layer "F.Fab")
		)
		(fp_line
			(start -0.12065 -0.305054)
			(end -0.12065 -0.2794)
			(stroke
				(width 0.1)
				(type default)
			)
			(layer "F.Fab")
		)
		(fp_line
			(start -0.12065 -0.2794)
			(end 0.12065 -0.2794)
			(stroke
				(width 0.1)
				(type default)
			)
			(layer "F.Fab")
		)
		(fp_line
			(start -0.12065 0.2794)
			(end -0.12065 0.3048)
			(stroke
				(width 0.1)
				(type default)
			)
			(layer "F.Fab")
		)
		(fp_line
			(start -0.12065 0.3048)
			(end -0.67945 0.3048)
			(stroke
				(width 0.1)
				(type default)
			)
			(layer "F.Fab")
		)
		(fp_line
			(start 0.120396 0.2794)
			(end -0.12065 0.2794)
			(stroke
				(width 0.1)
				(type default)
			)
			(layer "F.Fab")
		)
		(fp_line
			(start 0.120396 0.3048)
			(end 0.120396 0.2794)
			(stroke
				(width 0.1)
				(type default)
			)
			(layer "F.Fab")
		)
		(fp_line
			(start 0.12065 -0.3048)
			(end 0.67945 -0.3048)
			(stroke
				(width 0.1)
				(type default)
			)
			(layer "F.Fab")
		)
		(fp_line
			(start 0.12065 -0.2794)
			(end 0.12065 -0.3048)
			(stroke
				(width 0.1)
				(type default)
			)
			(layer "F.Fab")
		)
		(fp_line
			(start 0.67945 -0.3048)
			(end 0.67945 0.3048)
			(stroke
				(width 0.1)
				(type default)
			)
			(layer "F.Fab")
		)
		(fp_line
			(start 0.67945 0.3048)
			(end 0.120396 0.3048)
			(stroke
				(width 0.1)
				(type default)
			)
			(layer "F.Fab")
		)
		(pad "1" smd circle
			(at -0.40005 0)
			(size 0 0)
			(layers "F.Cu" "F.Mask" "F.Paste")
			(net "SMB_NIC5_LS_R_SCL")
		)
		(pad "2" smd circle
			(at 0.40005 0)
			(size 0 0)
			(layers "F.Cu" "F.Mask" "F.Paste")
			(net "P3V3_NIC5")
		)
	)
	(footprint ""
		(layer "F.Cu")
		(at 248.126504 -121.408952 180)
		(property "Reference" "PC449"
			(at 0 0 180)
			(layer "F.SilkS")
			(hide yes)
			(effects
				(font
					(size 1.27 1.27)
				)
			)
		)
		(property "Value" ""
			(at 0 0 180)
			(layer "F.Fab")
			(effects
				(font
					(size 1.27 1.27)
				)
			)
		)
		(duplicate_pad_numbers_are_jumpers no)
		(fp_line
			(start 1.524 0.762)
			(end -1.524 0.762)
			(stroke
				(width 0.1524)
				(type default)
			)
			(layer "F.SilkS")
		)
		(fp_line
			(start 1.524 -0.762)
			(end 1.524 0.762)
			(stroke
				(width 0.1524)
				(type default)
			)
			(layer "F.SilkS")
		)
		(fp_line
			(start -1.524 0.762)
			(end -1.524 -0.762)
			(stroke
				(width 0.1524)
				(type default)
			)
			(layer "F.SilkS")
		)
		(fp_line
			(start -1.524 -0.762)
			(end 1.524 -0.762)
			(stroke
				(width 0.1524)
				(type default)
			)
			(layer "F.SilkS")
		)
		(fp_line
			(start 1.1049 0.724916)
			(end 1.1049 -0.724916)
			(stroke
				(width 0.1)
				(type default)
			)
			(layer "F.Fab")
		)
		(fp_line
			(start 1.1049 -0.724916)
			(end -1.1049 -0.724916)
			(stroke
				(width 0.1)
				(type default)
			)
			(layer "F.Fab")
		)
		(fp_line
			(start -1.1049 0.724916)
			(end 1.1049 0.724916)
			(stroke
				(width 0.1)
				(type default)
			)
			(layer "F.Fab")
		)
		(fp_line
			(start -1.1049 -0.724916)
			(end -1.1049 0.724916)
			(stroke
				(width 0.1)
				(type default)
			)
			(layer "F.Fab")
		)
		(pad "1" smd rect
			(at -0.889 0)
			(size 1.016 1.27)
			(layers "F.Cu" "F.Mask" "F.Paste")
			(net "GND")
		)
		(pad "2" smd rect
			(at 0.889 0)
			(size 1.016 1.27)
			(layers "F.Cu" "F.Mask" "F.Paste")
			(net "P3V3_AUX")
		)
	)
	(footprint ""
		(layer "F.Cu")
		(at 11.956796 -394.137134 -90)
		(property "Reference" "R6743"
			(at 0 0 270)
			(layer "F.SilkS")
			(hide yes)
			(effects
				(font
					(size 1.27 1.27)
				)
			)
		)
		(property "Value" ""
			(at 0 0 270)
			(layer "F.Fab")
			(effects
				(font
					(size 1.27 1.27)
				)
			)
		)
		(duplicate_pad_numbers_are_jumpers no)
		(fp_line
			(start -0.7874 0.4064)
			(end -0.7874 -0.4064)
			(stroke
				(width 0.1524)
				(type default)
			)
			(layer "F.SilkS")
		)
		(fp_line
			(start 0.7874 0.4064)
			(end -0.7874 0.4064)
			(stroke
				(width 0.1524)
				(type default)
			)
			(layer "F.SilkS")
		)
		(fp_line
			(start -0.7874 -0.4064)
			(end 0.7874 -0.4064)
			(stroke
				(width 0.1524)
				(type default)
			)
			(layer "F.SilkS")
		)
		(fp_line
			(start 0.7874 -0.4064)
			(end 0.7874 0.4064)
			(stroke
				(width 0.1524)
				(type default)
			)
			(layer "F.SilkS")
		)
		(fp_line
			(start -0.67945 0.3048)
			(end -0.67945 -0.305054)
			(stroke
				(width 0.1)
				(type default)
			)
			(layer "F.Fab")
		)
		(fp_line
			(start -0.12065 0.3048)
			(end -0.67945 0.3048)
			(stroke
				(width 0.1)
				(type default)
			)
			(layer "F.Fab")
		)
		(fp_line
			(start 0.120396 0.3048)
			(end 0.120396 0.2794)
			(stroke
				(width 0.1)
				(type default)
			)
			(layer "F.Fab")
		)
		(fp_line
			(start 0.67945 0.3048)
			(end 0.120396 0.3048)
			(stroke
				(width 0.1)
				(type default)
			)
			(layer "F.Fab")
		)
		(fp_line
			(start -0.12065 0.2794)
			(end -0.12065 0.3048)
			(stroke
				(width 0.1)
				(type default)
			)
			(layer "F.Fab")
		)
		(fp_line
			(start 0.120396 0.2794)
			(end -0.12065 0.2794)
			(stroke
				(width 0.1)
				(type default)
			)
			(layer "F.Fab")
		)
		(fp_line
			(start -0.12065 -0.2794)
			(end 0.12065 -0.2794)
			(stroke
				(width 0.1)
				(type default)
			)
			(layer "F.Fab")
		)
		(fp_line
			(start 0.12065 -0.2794)
			(end 0.12065 -0.3048)
			(stroke
				(width 0.1)
				(type default)
			)
			(layer "F.Fab")
		)
		(fp_line
			(start 0.12065 -0.3048)
			(end 0.67945 -0.3048)
			(stroke
				(width 0.1)
				(type default)
			)
			(layer "F.Fab")
		)
		(fp_line
			(start 0.67945 -0.3048)
			(end 0.67945 0.3048)
			(stroke
				(width 0.1)
				(type default)
			)
			(layer "F.Fab")
		)
		(fp_line
			(start -0.67945 -0.305054)
			(end -0.12065 -0.305054)
			(stroke
				(width 0.1)
				(type default)
			)
			(layer "F.Fab")
		)
		(fp_line
			(start -0.12065 -0.305054)
			(end -0.12065 -0.2794)
			(stroke
				(width 0.1)
				(type default)
			)
			(layer "F.Fab")
		)
		(pad "1" smd circle
			(at -0.40005 0 270)
			(size 0 0)
			(layers "F.Cu" "F.Mask" "F.Paste")
			(net "P3V3_USB_8042")
		)
		(pad "2" smd circle
			(at 0.40005 0 270)
			(size 0 0)
			(layers "F.Cu" "F.Mask" "F.Paste")
			(net "BIC_USB_8042_HUB_OVCUR4")
		)
	)
	(footprint ""
		(layer "F.Cu")
		(at 163.41979 -127.700024)
		(property "Reference" "J22"
			(at -5.48132 34.685224 90)
			(unlocked yes)
			(layer "F.SilkS")
			(effects
				(font
					(size 0.7874 0.5842)
					(thickness 0.1524)
				)
				(justify left)
			)
		)
		(property "Value" ""
			(at 0 0 0)
			(layer "F.Fab")
			(effects
				(font
					(size 1.27 1.27)
				)
			)
		)
		(duplicate_pad_numbers_are_jumpers no)
		(fp_line
			(start -4.507484 34.720022)
			(end -0.5588 34.720022)
			(stroke
				(width 0.1524)
				(type default)
			)
			(layer "F.SilkS")
		)
		(fp_line
			(start -0.57658 -34.720022)
			(end -4.507484 -34.720022)
			(stroke
				(width 0.1524)
				(type default)
			)
			(layer "F.SilkS")
		)
		(fp_line
			(start 2.6035 34.720022)
			(end 4.507484 34.720022)
			(stroke
				(width 0.1524)
				(type default)
			)
			(layer "F.SilkS")
		)
		(fp_line
			(start 4.507484 -34.720022)
			(end 2.6162 -34.720022)
			(stroke
				(width 0.1524)
				(type default)
			)
			(layer "F.SilkS")
		)
		(fp_line
			(start 4.507484 -21.5265)
			(end 4.507484 -34.720022)
			(stroke
				(width 0.1524)
				(type default)
			)
			(layer "F.SilkS")
		)
		(fp_poly
			(pts
				(xy 5.735574 -17.957038) (xy 5.735574 -18.973038) (xy 4.719574 -18.465038)
			)
			(stroke
				(width 0)
				(type default)
			)
			(fill yes)
			(layer "F.SilkS")
		)
		(fp_line
			(start -4.507484 -34.720022)
			(end -4.507484 34.720022)
			(stroke
				(width 0.1)
				(type default)
			)
			(layer "F.Fab")
		)
		(fp_line
			(start -4.507484 34.720022)
			(end 4.507484 34.720022)
			(stroke
				(width 0.1)
				(type default)
			)
			(layer "F.Fab")
		)
		(fp_line
			(start 4.507484 -34.720022)
			(end -4.507484 -34.720022)
			(stroke
				(width 0.1)
				(type default)
			)
			(layer "F.Fab")
		)
		(fp_line
			(start 4.507484 34.720022)
			(end 4.507484 -34.720022)
			(stroke
				(width 0.1)
				(type default)
			)
			(layer "F.Fab")
		)
		(fp_poly
			(pts
				(xy 5.735574 -17.957038) (xy 5.735574 -18.973038) (xy 4.719574 -18.465038)
			)
			(stroke
				(width 0)
				(type default)
			)
			(fill yes)
			(layer "F.Fab")
		)
		(pad "" np_thru_hole circle
			(at -0.727456 -32.485076)
			(size 1.1176 1.1176)
			(drill 1.1176)
			(layers "*.Cu" "*.Mask")
			(clearance 0.381)
			(thermal_gap 0.381)
		)
		(pad "" np_thru_hole circle
			(at 1.022604 32.485076)
			(size 1.1176 1.1176)
			(drill 1.1176)
			(layers "*.Cu" "*.Mask")
			(clearance 0.381)
			(thermal_gap 0.381)
		)
		(pad "A1" smd rect
			(at 3.322574 -18.465038 270)
			(size 0.3556 1.2192)
			(layers "F.Cu" "F.Mask" "F.Paste")
			(net "GND")
		)
		(pad "A2" smd rect
			(at 3.322574 -17.86509 270)
			(size 0.3556 1.2192)
			(layers "F.Cu" "F.Mask" "F.Paste")
			(net "GND")
		)
		(pad "A3" smd rect
			(at 3.322574 -17.264888 270)
			(size 0.3556 1.2192)
			(layers "F.Cu" "F.Mask" "F.Paste")
			(net "GND")
		)
		(pad "A4" smd rect
			(at 3.322574 -16.66494 270)
			(size 0.3556 1.2192)
			(layers "F.Cu" "F.Mask" "F.Paste")
			(net "GND")
		)
		(pad "A5" smd rect
			(at 3.322574 -16.064992 270)
			(size 0.3556 1.2192)
			(layers "F.Cu" "F.Mask" "F.Paste")
			(net "GND")
		)
		(pad "A6" smd rect
			(at 3.322574 -15.465044 270)
			(size 0.3556 1.2192)
			(layers "F.Cu" "F.Mask" "F.Paste")
			(net "GND")
		)
		(pad "A7" smd rect
			(at 3.322574 -14.865096 270)
			(size 0.3556 1.2192)
			(layers "F.Cu" "F.Mask" "F.Paste")
			(net "SMB_NIC2_R_SCL")
		)
		(pad "A8" smd rect
			(at 3.322574 -14.264894 270)
			(size 0.3556 1.2192)
			(layers "F.Cu" "F.Mask" "F.Paste")
			(net "SMB_NIC2_R_SDA")
		)
		(pad "A9" smd rect
			(at 3.322574 -13.664946 270)
			(size 0.3556 1.2192)
			(layers "F.Cu" "F.Mask" "F.Paste")
			(net "RST_SMB_NIC2_MUX_ISO_R_N")
		)
		(pad "A10" smd rect
			(at 3.322574 -13.064998 270)
			(size 0.3556 1.2192)
			(layers "F.Cu" "F.Mask" "F.Paste")
			(net "GND")
		)
		(pad "A11" smd rect
			(at 3.322574 -12.46505 270)
			(size 0.3556 1.2192)
			(layers "F.Cu" "F.Mask" "F.Paste")
			(net "RST_NIC2_PERST1_R_N")
		)
		(pad "A12" smd rect
			(at 3.322574 -11.865102 270)
			(size 0.3556 1.2192)
			(layers "F.Cu" "F.Mask" "F.Paste")
			(net "PRSNTB2_NIC2_N")
		)
		(pad "A13" smd rect
			(at 3.322574 -11.2649 270)
			(size 0.3556 1.2192)
			(layers "F.Cu" "F.Mask" "F.Paste")
			(net "GND")
		)
		(pad "A14" smd rect
			(at 3.322574 -10.664952 270)
			(size 0.3556 1.2192)
			(layers "F.Cu" "F.Mask" "F.Paste")
			(net "Net_2601")
		)
		(pad "A15" smd rect
			(at 3.322574 -10.065004 270)
			(size 0.3556 1.2192)
			(layers "F.Cu" "F.Mask" "F.Paste")
			(net "Net_2604")
		)
		(pad "A16" smd rect
			(at 3.322574 -9.465056 270)
			(size 0.3556 1.2192)
			(layers "F.Cu" "F.Mask" "F.Paste")
			(net "GND")
		)
		(pad "A17" smd rect
			(at 3.322574 -8.865108 270)
			(size 0.3556 1.2192)
			(layers "F.Cu" "F.Mask" "F.Paste")
			(net "P5E_PEX1_STN1_RX_DN<31>")
		)
		(pad "A18" smd rect
			(at 3.322574 -8.264906 270)
			(size 0.3556 1.2192)
			(layers "F.Cu" "F.Mask" "F.Paste")
			(net "P5E_PEX1_STN1_RX_DP<31>")
		)
		(pad "A19" smd rect
			(at 3.322574 -7.664958 270)
			(size 0.3556 1.2192)
			(layers "F.Cu" "F.Mask" "F.Paste")
			(net "GND")
		)
		(pad "A20" smd rect
			(at 3.322574 -7.06501 270)
			(size 0.3556 1.2192)
			(layers "F.Cu" "F.Mask" "F.Paste")
			(net "P5E_PEX1_STN1_RX_DN<30>")
		)
		(pad "A21" smd rect
			(at 3.322574 -6.465062 270)
			(size 0.3556 1.2192)
			(layers "F.Cu" "F.Mask" "F.Paste")
			(net "P5E_PEX1_STN1_RX_DP<30>")
		)
		(pad "A22" smd rect
			(at 3.322574 -5.865114 270)
			(size 0.3556 1.2192)
			(layers "F.Cu" "F.Mask" "F.Paste")
			(net "GND")
		)
		(pad "A23" smd rect
			(at 3.322574 -5.264912 270)
			(size 0.3556 1.2192)
			(layers "F.Cu" "F.Mask" "F.Paste")
			(net "P5E_PEX1_STN1_RX_DN<29>")
		)
		(pad "A24" smd rect
			(at 3.322574 -4.664964 270)
			(size 0.3556 1.2192)
			(layers "F.Cu" "F.Mask" "F.Paste")
			(net "P5E_PEX1_STN1_RX_DP<29>")
		)
		(pad "A25" smd rect
			(at 3.322574 -4.065016 270)
			(size 0.3556 1.2192)
			(layers "F.Cu" "F.Mask" "F.Paste")
			(net "GND")
		)
		(pad "A26" smd rect
			(at 3.322574 -3.465068 270)
			(size 0.3556 1.2192)
			(layers "F.Cu" "F.Mask" "F.Paste")
			(net "P5E_PEX1_STN1_RX_DN<28>")
		)
		(pad "A27" smd rect
			(at 3.322574 -2.86512 270)
			(size 0.3556 1.2192)
			(layers "F.Cu" "F.Mask" "F.Paste")
			(net "P5E_PEX1_STN1_RX_DP<28>")
		)
		(pad "A28" smd rect
			(at 3.322574 -2.264918 270)
			(size 0.3556 1.2192)
			(layers "F.Cu" "F.Mask" "F.Paste")
			(net "GND")
		)
		(pad "A29" smd rect
			(at 3.322574 1.74498 270)
			(size 0.3556 1.2192)
			(layers "F.Cu" "F.Mask" "F.Paste")
			(net "GND")
		)
		(pad "A30" smd rect
			(at 3.322574 2.344928 270)
			(size 0.3556 1.2192)
			(layers "F.Cu" "F.Mask" "F.Paste")
			(net "P5E_PEX1_STN1_RX_DN<27>")
		)
		(pad "A31" smd rect
			(at 3.322574 2.944876 270)
			(size 0.3556 1.2192)
			(layers "F.Cu" "F.Mask" "F.Paste")
			(net "P5E_PEX1_STN1_RX_DP<27>")
		)
		(pad "A32" smd rect
			(at 3.322574 3.545078 270)
			(size 0.3556 1.2192)
			(layers "F.Cu" "F.Mask" "F.Paste")
			(net "GND")
		)
		(pad "A33" smd rect
			(at 3.322574 4.145026 270)
			(size 0.3556 1.2192)
			(layers "F.Cu" "F.Mask" "F.Paste")
			(net "P5E_PEX1_STN1_RX_DN<26>")
		)
		(pad "A34" smd rect
			(at 3.322574 4.744974 270)
			(size 0.3556 1.2192)
			(layers "F.Cu" "F.Mask" "F.Paste")
			(net "P5E_PEX1_STN1_RX_DP<26>")
		)
		(pad "A35" smd rect
			(at 3.322574 5.344922 270)
			(size 0.3556 1.2192)
			(layers "F.Cu" "F.Mask" "F.Paste")
			(net "GND")
		)
		(pad "A36" smd rect
			(at 3.322574 5.945124 270)
			(size 0.3556 1.2192)
			(layers "F.Cu" "F.Mask" "F.Paste")
			(net "P5E_PEX1_STN1_RX_DN<25>")
		)
		(pad "A37" smd rect
			(at 3.322574 6.545072 270)
			(size 0.3556 1.2192)
			(layers "F.Cu" "F.Mask" "F.Paste")
			(net "P5E_PEX1_STN1_RX_DP<25>")
		)
		(pad "A38" smd rect
			(at 3.322574 7.14502 270)
			(size 0.3556 1.2192)
			(layers "F.Cu" "F.Mask" "F.Paste")
			(net "GND")
		)
		(pad "A39" smd rect
			(at 3.322574 7.744968 270)
			(size 0.3556 1.2192)
			(layers "F.Cu" "F.Mask" "F.Paste")
			(net "P5E_PEX1_STN1_RX_DN<24>")
		)
		(pad "A40" smd rect
			(at 3.322574 8.344916 270)
			(size 0.3556 1.2192)
			(layers "F.Cu" "F.Mask" "F.Paste")
			(net "P5E_PEX1_STN1_RX_DP<24>")
		)
		(pad "A41" smd rect
			(at 3.322574 8.945118 270)
			(size 0.3556 1.2192)
			(layers "F.Cu" "F.Mask" "F.Paste")
			(net "GND")
		)
		(pad "A42" smd rect
			(at 3.322574 9.545066 270)
			(size 0.3556 1.2192)
			(layers "F.Cu" "F.Mask" "F.Paste")
			(net "PRSNTB1_NIC2_N")
		)
		(pad "A43" smd rect
			(at 3.322574 14.454886 270)
			(size 0.3556 1.2192)
			(layers "F.Cu" "F.Mask" "F.Paste")
			(net "GND")
		)
		(pad "A44" smd rect
			(at 3.322574 15.055088 270)
			(size 0.3556 1.2192)
			(layers "F.Cu" "F.Mask" "F.Paste")
			(net "P5E_PEX1_STN1_RX_DN<23>")
		)
		(pad "A45" smd rect
			(at 3.322574 15.655036 270)
			(size 0.3556 1.2192)
			(layers "F.Cu" "F.Mask" "F.Paste")
			(net "P5E_PEX1_STN1_RX_DP<23>")
		)
		(pad "A46" smd rect
			(at 3.322574 16.254984 270)
			(size 0.3556 1.2192)
			(layers "F.Cu" "F.Mask" "F.Paste")
			(net "GND")
		)
		(pad "A47" smd rect
			(at 3.322574 16.854932 270)
			(size 0.3556 1.2192)
			(layers "F.Cu" "F.Mask" "F.Paste")
			(net "P5E_PEX1_STN1_RX_DN<22>")
		)
		(pad "A48" smd rect
			(at 3.322574 17.45488 270)
			(size 0.3556 1.2192)
			(layers "F.Cu" "F.Mask" "F.Paste")
			(net "P5E_PEX1_STN1_RX_DP<22>")
		)
		(pad "A49" smd rect
			(at 3.322574 18.055082 270)
			(size 0.3556 1.2192)
			(layers "F.Cu" "F.Mask" "F.Paste")
			(net "GND")
		)
		(pad "A50" smd rect
			(at 3.322574 18.65503 270)
			(size 0.3556 1.2192)
			(layers "F.Cu" "F.Mask" "F.Paste")
			(net "P5E_PEX1_STN1_RX_DN<21>")
		)
		(pad "A51" smd rect
			(at 3.322574 19.254978 270)
			(size 0.3556 1.2192)
			(layers "F.Cu" "F.Mask" "F.Paste")
			(net "P5E_PEX1_STN1_RX_DP<21>")
		)
		(pad "A52" smd rect
			(at 3.322574 19.854926 270)
			(size 0.3556 1.2192)
			(layers "F.Cu" "F.Mask" "F.Paste")
			(net "GND")
		)
		(pad "A53" smd rect
			(at 3.322574 20.455128 270)
			(size 0.3556 1.2192)
			(layers "F.Cu" "F.Mask" "F.Paste")
			(net "P5E_PEX1_STN1_RX_DN<20>")
		)
		(pad "A54" smd rect
			(at 3.322574 21.055076 270)
			(size 0.3556 1.2192)
			(layers "F.Cu" "F.Mask" "F.Paste")
			(net "P5E_PEX1_STN1_RX_DP<20>")
		)
		(pad "A55" smd rect
			(at 3.322574 21.655024 270)
			(size 0.3556 1.2192)
			(layers "F.Cu" "F.Mask" "F.Paste")
			(net "GND")
		)
		(pad "A56" smd rect
			(at 3.322574 22.254972 270)
			(size 0.3556 1.2192)
			(layers "F.Cu" "F.Mask" "F.Paste")
			(net "P5E_PEX1_STN1_RX_DN<19>")
		)
		(pad "A57" smd rect
			(at 3.322574 22.85492 270)
			(size 0.3556 1.2192)
			(layers "F.Cu" "F.Mask" "F.Paste")
			(net "P5E_PEX1_STN1_RX_DP<19>")
		)
		(pad "A58" smd rect
			(at 3.322574 23.455122 270)
			(size 0.3556 1.2192)
			(layers "F.Cu" "F.Mask" "F.Paste")
			(net "GND")
		)
		(pad "A59" smd rect
			(at 3.322574 24.05507 270)
			(size 0.3556 1.2192)
			(layers "F.Cu" "F.Mask" "F.Paste")
			(net "P5E_PEX1_STN1_RX_DN<18>")
		)
		(pad "A60" smd rect
			(at 3.322574 24.655018 270)
			(size 0.3556 1.2192)
			(layers "F.Cu" "F.Mask" "F.Paste")
			(net "P5E_PEX1_STN1_RX_DP<18>")
		)
		(pad "A61" smd rect
			(at 3.322574 25.254966 270)
			(size 0.3556 1.2192)
			(layers "F.Cu" "F.Mask" "F.Paste")
			(net "GND")
		)
		(pad "A62" smd rect
			(at 3.322574 25.854914 270)
			(size 0.3556 1.2192)
			(layers "F.Cu" "F.Mask" "F.Paste")
			(net "P5E_PEX1_STN1_RX_DN<17>")
		)
		(pad "A63" smd rect
			(at 3.322574 26.455116 270)
			(size 0.3556 1.2192)
			(layers "F.Cu" "F.Mask" "F.Paste")
			(net "P5E_PEX1_STN1_RX_DP<17>")
		)
		(pad "A64" smd rect
			(at 3.322574 27.055064 270)
			(size 0.3556 1.2192)
			(layers "F.Cu" "F.Mask" "F.Paste")
			(net "GND")
		)
		(pad "A65" smd rect
			(at 3.322574 27.655012 270)
			(size 0.3556 1.2192)
			(layers "F.Cu" "F.Mask" "F.Paste")
			(net "P5E_PEX1_STN1_RX_DN<16>")
		)
		(pad "A66" smd rect
			(at 3.322574 28.25496 270)
			(size 0.3556 1.2192)
			(layers "F.Cu" "F.Mask" "F.Paste")
			(net "P5E_PEX1_STN1_RX_DP<16>")
		)
		(pad "A67" smd rect
			(at 3.322574 28.854908 270)
			(size 0.3556 1.2192)
			(layers "F.Cu" "F.Mask" "F.Paste")
			(net "GND")
		)
		(pad "A68" smd rect
			(at 3.322574 29.45511 270)
			(size 0.3556 1.2192)
			(layers "F.Cu" "F.Mask" "F.Paste")
			(net "Net_2609")
		)
		(pad "A69" smd rect
			(at 3.322574 30.055058 270)
			(size 0.3556 1.2192)
			(layers "F.Cu" "F.Mask" "F.Paste")
			(net "Net_2610")
		)
		(pad "A70" smd rect
			(at 3.322574 30.655006 270)
			(size 0.3556 1.2192)
			(layers "F.Cu" "F.Mask" "F.Paste")
			(net "NIC2_PWRBRK_R_N")
		)
		(pad "B1" smd rect
			(at -1.27762 -18.465038 270)
			(size 0.3556 1.2192)
			(layers "F.Cu" "F.Mask" "F.Paste")
			(net "P12V_NIC2")
		)
		(pad "B2" smd rect
			(at -1.27762 -17.86509 270)
			(size 0.3556 1.2192)
			(layers "F.Cu" "F.Mask" "F.Paste")
			(net "P12V_NIC2")
		)
		(pad "B3" smd rect
			(at -1.27762 -17.264888 270)
			(size 0.3556 1.2192)
			(layers "F.Cu" "F.Mask" "F.Paste")
			(net "P12V_NIC2")
		)
		(pad "B4" smd rect
			(at -1.27762 -16.66494 270)
			(size 0.3556 1.2192)
			(layers "F.Cu" "F.Mask" "F.Paste")
			(net "P12V_NIC2")
		)
		(pad "B5" smd rect
			(at -1.27762 -16.064992 270)
			(size 0.3556 1.2192)
			(layers "F.Cu" "F.Mask" "F.Paste")
			(net "P12V_NIC2")
		)
		(pad "B6" smd rect
			(at -1.27762 -15.465044 270)
			(size 0.3556 1.2192)
			(layers "F.Cu" "F.Mask" "F.Paste")
			(net "P12V_NIC2")
		)
		(pad "B7" smd rect
			(at -1.27762 -14.865096 270)
			(size 0.3556 1.2192)
			(layers "F.Cu" "F.Mask" "F.Paste")
			(net "NIC2_BIF0_N")
		)
		(pad "B8" smd rect
			(at -1.27762 -14.264894 270)
			(size 0.3556 1.2192)
			(layers "F.Cu" "F.Mask" "F.Paste")
			(net "NIC2_BIF1_N")
		)
		(pad "B9" smd rect
			(at -1.27762 -13.664946 270)
			(size 0.3556 1.2192)
			(layers "F.Cu" "F.Mask" "F.Paste")
			(net "NIC2_BIF2_N")
		)
		(pad "B10" smd rect
			(at -1.27762 -13.064998 270)
			(size 0.3556 1.2192)
			(layers "F.Cu" "F.Mask" "F.Paste")
			(net "RST_NIC2_PERST0_R_N")
		)
		(pad "B11" smd rect
			(at -1.27762 -12.46505 270)
			(size 0.3556 1.2192)
			(layers "F.Cu" "F.Mask" "F.Paste")
			(net "P3V3_NIC2")
		)
		(pad "B12" smd rect
			(at -1.27762 -11.865102 270)
			(size 0.3556 1.2192)
			(layers "F.Cu" "F.Mask" "F.Paste")
			(net "NIC2_AUX_PWR_EN_R")
		)
		(pad "B13" smd rect
			(at -1.27762 -11.2649 270)
			(size 0.3556 1.2192)
			(layers "F.Cu" "F.Mask" "F.Paste")
			(net "GND")
		)
		(pad "B14" smd rect
			(at -1.27762 -10.664952 270)
			(size 0.3556 1.2192)
			(layers "F.Cu" "F.Mask" "F.Paste")
			(net "CLK_100M_DB2000QL_NIC2_R_DN")
		)
		(pad "B15" smd rect
			(at -1.27762 -10.065004 270)
			(size 0.3556 1.2192)
			(layers "F.Cu" "F.Mask" "F.Paste")
			(net "CLK_100M_DB2000QL_NIC2_R_DP")
		)
		(pad "B16" smd rect
			(at -1.27762 -9.465056 270)
			(size 0.3556 1.2192)
			(layers "F.Cu" "F.Mask" "F.Paste")
			(net "GND")
		)
		(pad "B17" smd rect
			(at -1.27762 -8.865108 270)
			(size 0.3556 1.2192)
			(layers "F.Cu" "F.Mask" "F.Paste")
			(net "P5E_PEX1_STN1_TX_C_DP<31>")
		)
		(pad "B18" smd rect
			(at -1.27762 -8.264906 270)
			(size 0.3556 1.2192)
			(layers "F.Cu" "F.Mask" "F.Paste")
			(net "P5E_PEX1_STN1_TX_C_DN<31>")
		)
		(pad "B19" smd rect
			(at -1.27762 -7.664958 270)
			(size 0.3556 1.2192)
			(layers "F.Cu" "F.Mask" "F.Paste")
			(net "GND")
		)
		(pad "B20" smd rect
			(at -1.27762 -7.06501 270)
			(size 0.3556 1.2192)
			(layers "F.Cu" "F.Mask" "F.Paste")
			(net "P5E_PEX1_STN1_TX_C_DN<30>")
		)
		(pad "B21" smd rect
			(at -1.27762 -6.465062 270)
			(size 0.3556 1.2192)
			(layers "F.Cu" "F.Mask" "F.Paste")
			(net "P5E_PEX1_STN1_TX_C_DP<30>")
		)
		(pad "B22" smd rect
			(at -1.27762 -5.865114 270)
			(size 0.3556 1.2192)
			(layers "F.Cu" "F.Mask" "F.Paste")
			(net "GND")
		)
		(pad "B23" smd rect
			(at -1.27762 -5.264912 270)
			(size 0.3556 1.2192)
			(layers "F.Cu" "F.Mask" "F.Paste")
			(net "P5E_PEX1_STN1_TX_C_DP<29>")
		)
		(pad "B24" smd rect
			(at -1.27762 -4.664964 270)
			(size 0.3556 1.2192)
			(layers "F.Cu" "F.Mask" "F.Paste")
			(net "P5E_PEX1_STN1_TX_C_DN<29>")
		)
		(pad "B25" smd rect
			(at -1.27762 -4.065016 270)
			(size 0.3556 1.2192)
			(layers "F.Cu" "F.Mask" "F.Paste")
			(net "GND")
		)
		(pad "B26" smd rect
			(at -1.27762 -3.465068 270)
			(size 0.3556 1.2192)
			(layers "F.Cu" "F.Mask" "F.Paste")
			(net "P5E_PEX1_STN1_TX_C_DN<28>")
		)
		(pad "B27" smd rect
			(at -1.27762 -2.86512 270)
			(size 0.3556 1.2192)
			(layers "F.Cu" "F.Mask" "F.Paste")
			(net "P5E_PEX1_STN1_TX_C_DP<28>")
		)
		(pad "B28" smd rect
			(at -1.27762 -2.264918 270)
			(size 0.3556 1.2192)
			(layers "F.Cu" "F.Mask" "F.Paste")
			(net "GND")
		)
		(pad "B29" smd rect
			(at -1.27762 1.74498 270)
			(size 0.3556 1.2192)
			(layers "F.Cu" "F.Mask" "F.Paste")
			(net "GND")
		)
		(pad "B30" smd rect
			(at -1.27762 2.344928 270)
			(size 0.3556 1.2192)
			(layers "F.Cu" "F.Mask" "F.Paste")
			(net "P5E_PEX1_STN1_TX_C_DP<27>")
		)
		(pad "B31" smd rect
			(at -1.27762 2.944876 270)
			(size 0.3556 1.2192)
			(layers "F.Cu" "F.Mask" "F.Paste")
			(net "P5E_PEX1_STN1_TX_C_DN<27>")
		)
		(pad "B32" smd rect
			(at -1.27762 3.545078 270)
			(size 0.3556 1.2192)
			(layers "F.Cu" "F.Mask" "F.Paste")
			(net "GND")
		)
		(pad "B33" smd rect
			(at -1.27762 4.145026 270)
			(size 0.3556 1.2192)
			(layers "F.Cu" "F.Mask" "F.Paste")
			(net "P5E_PEX1_STN1_TX_C_DN<26>")
		)
		(pad "B34" smd rect
			(at -1.27762 4.744974 270)
			(size 0.3556 1.2192)
			(layers "F.Cu" "F.Mask" "F.Paste")
			(net "P5E_PEX1_STN1_TX_C_DP<26>")
		)
		(pad "B35" smd rect
			(at -1.27762 5.344922 270)
			(size 0.3556 1.2192)
			(layers "F.Cu" "F.Mask" "F.Paste")
			(net "GND")
		)
		(pad "B36" smd rect
			(at -1.27762 5.945124 270)
			(size 0.3556 1.2192)
			(layers "F.Cu" "F.Mask" "F.Paste")
			(net "P5E_PEX1_STN1_TX_C_DP<25>")
		)
		(pad "B37" smd rect
			(at -1.27762 6.545072 270)
			(size 0.3556 1.2192)
			(layers "F.Cu" "F.Mask" "F.Paste")
			(net "P5E_PEX1_STN1_TX_C_DN<25>")
		)
		(pad "B38" smd rect
			(at -1.27762 7.14502 270)
			(size 0.3556 1.2192)
			(layers "F.Cu" "F.Mask" "F.Paste")
			(net "GND")
		)
		(pad "B39" smd rect
			(at -1.27762 7.744968 270)
			(size 0.3556 1.2192)
			(layers "F.Cu" "F.Mask" "F.Paste")
			(net "P5E_PEX1_STN1_TX_C_DN<24>")
		)
		(pad "B40" smd rect
			(at -1.27762 8.344916 270)
			(size 0.3556 1.2192)
			(layers "F.Cu" "F.Mask" "F.Paste")
			(net "P5E_PEX1_STN1_TX_C_DP<24>")
		)
		(pad "B41" smd rect
			(at -1.27762 8.945118 270)
			(size 0.3556 1.2192)
			(layers "F.Cu" "F.Mask" "F.Paste")
			(net "GND")
		)
		(pad "B42" smd rect
			(at -1.27762 9.545066 270)
			(size 0.3556 1.2192)
			(layers "F.Cu" "F.Mask" "F.Paste")
			(net "PRSNTB0_NIC2_N")
		)
		(pad "B43" smd rect
			(at -1.27762 14.454886 270)
			(size 0.3556 1.2192)
			(layers "F.Cu" "F.Mask" "F.Paste")
			(net "GND")
		)
		(pad "B44" smd rect
			(at -1.27762 15.055088 270)
			(size 0.3556 1.2192)
			(layers "F.Cu" "F.Mask" "F.Paste")
			(net "P5E_PEX1_STN1_TX_C_DP<23>")
		)
		(pad "B45" smd rect
			(at -1.27762 15.655036 270)
			(size 0.3556 1.2192)
			(layers "F.Cu" "F.Mask" "F.Paste")
			(net "P5E_PEX1_STN1_TX_C_DN<23>")
		)
		(pad "B46" smd rect
			(at -1.27762 16.254984 270)
			(size 0.3556 1.2192)
			(layers "F.Cu" "F.Mask" "F.Paste")
			(net "GND")
		)
		(pad "B47" smd rect
			(at -1.27762 16.854932 270)
			(size 0.3556 1.2192)
			(layers "F.Cu" "F.Mask" "F.Paste")
			(net "P5E_PEX1_STN1_TX_C_DN<22>")
		)
		(pad "B48" smd rect
			(at -1.27762 17.45488 270)
			(size 0.3556 1.2192)
			(layers "F.Cu" "F.Mask" "F.Paste")
			(net "P5E_PEX1_STN1_TX_C_DP<22>")
		)
		(pad "B49" smd rect
			(at -1.27762 18.055082 270)
			(size 0.3556 1.2192)
			(layers "F.Cu" "F.Mask" "F.Paste")
			(net "GND")
		)
		(pad "B50" smd rect
			(at -1.27762 18.65503 270)
			(size 0.3556 1.2192)
			(layers "F.Cu" "F.Mask" "F.Paste")
			(net "P5E_PEX1_STN1_TX_C_DP<21>")
		)
		(pad "B51" smd rect
			(at -1.27762 19.254978 270)
			(size 0.3556 1.2192)
			(layers "F.Cu" "F.Mask" "F.Paste")
			(net "P5E_PEX1_STN1_TX_C_DN<21>")
		)
		(pad "B52" smd rect
			(at -1.27762 19.854926 270)
			(size 0.3556 1.2192)
			(layers "F.Cu" "F.Mask" "F.Paste")
			(net "GND")
		)
		(pad "B53" smd rect
			(at -1.27762 20.455128 270)
			(size 0.3556 1.2192)
			(layers "F.Cu" "F.Mask" "F.Paste")
			(net "P5E_PEX1_STN1_TX_C_DN<20>")
		)
		(pad "B54" smd rect
			(at -1.27762 21.055076 270)
			(size 0.3556 1.2192)
			(layers "F.Cu" "F.Mask" "F.Paste")
			(net "P5E_PEX1_STN1_TX_C_DP<20>")
		)
		(pad "B55" smd rect
			(at -1.27762 21.655024 270)
			(size 0.3556 1.2192)
			(layers "F.Cu" "F.Mask" "F.Paste")
			(net "GND")
		)
		(pad "B56" smd rect
			(at -1.27762 22.254972 270)
			(size 0.3556 1.2192)
			(layers "F.Cu" "F.Mask" "F.Paste")
			(net "P5E_PEX1_STN1_TX_C_DP<19>")
		)
		(pad "B57" smd rect
			(at -1.27762 22.85492 270)
			(size 0.3556 1.2192)
			(layers "F.Cu" "F.Mask" "F.Paste")
			(net "P5E_PEX1_STN1_TX_C_DN<19>")
		)
		(pad "B58" smd rect
			(at -1.27762 23.455122 270)
			(size 0.3556 1.2192)
			(layers "F.Cu" "F.Mask" "F.Paste")
			(net "GND")
		)
		(pad "B59" smd rect
			(at -1.27762 24.05507 270)
			(size 0.3556 1.2192)
			(layers "F.Cu" "F.Mask" "F.Paste")
			(net "P5E_PEX1_STN1_TX_C_DN<18>")
		)
		(pad "B60" smd rect
			(at -1.27762 24.655018 270)
			(size 0.3556 1.2192)
			(layers "F.Cu" "F.Mask" "F.Paste")
			(net "P5E_PEX1_STN1_TX_C_DP<18>")
		)
		(pad "B61" smd rect
			(at -1.27762 25.254966 270)
			(size 0.3556 1.2192)
			(layers "F.Cu" "F.Mask" "F.Paste")
			(net "GND")
		)
		(pad "B62" smd rect
			(at -1.27762 25.854914 270)
			(size 0.3556 1.2192)
			(layers "F.Cu" "F.Mask" "F.Paste")
			(net "P5E_PEX1_STN1_TX_C_DP<17>")
		)
		(pad "B63" smd rect
			(at -1.27762 26.455116 270)
			(size 0.3556 1.2192)
			(layers "F.Cu" "F.Mask" "F.Paste")
			(net "P5E_PEX1_STN1_TX_C_DN<17>")
		)
		(pad "B64" smd rect
			(at -1.27762 27.055064 270)
			(size 0.3556 1.2192)
			(layers "F.Cu" "F.Mask" "F.Paste")
			(net "GND")
		)
		(pad "B65" smd rect
			(at -1.27762 27.655012 270)
			(size 0.3556 1.2192)
			(layers "F.Cu" "F.Mask" "F.Paste")
			(net "P5E_PEX1_STN1_TX_C_DN<16>")
		)
		(pad "B66" smd rect
			(at -1.27762 28.25496 270)
			(size 0.3556 1.2192)
			(layers "F.Cu" "F.Mask" "F.Paste")
			(net "P5E_PEX1_STN1_TX_C_DP<16>")
		)
		(pad "B67" smd rect
			(at -1.27762 28.854908 270)
			(size 0.3556 1.2192)
			(layers "F.Cu" "F.Mask" "F.Paste")
			(net "GND")
		)
		(pad "B68" smd rect
			(at -1.27762 29.45511 270)
			(size 0.3556 1.2192)
			(layers "F.Cu" "F.Mask" "F.Paste")
			(net "Net_2607")
		)
		(pad "B69" smd rect
			(at -1.27762 30.055058 270)
			(size 0.3556 1.2192)
			(layers "F.Cu" "F.Mask" "F.Paste")
			(net "Net_2608")
		)
		(pad "B70" smd rect
			(at -1.27762 30.655006 270)
			(size 0.3556 1.2192)
			(layers "F.Cu" "F.Mask" "F.Paste")
			(net "PRSNTB3_NIC2_N")
		)
		(pad "G1" thru_hole oval
			(at 1.022604 -34.034984 270)
			(size 1.6256 3.4798)
			(drill oval 1.1176 2.4638)
			(layers "*.Cu" "*.Mask")
			(remove_unused_layers no)
			(net "GND")
			(clearance 0.127)
			(thermal_gap 0.127)
		)
		(pad "G2" thru_hole oval
			(at 1.022604 -20.625054 270)
			(size 1.6256 3.4798)
			(drill oval 1.1176 2.4638)
			(layers "*.Cu" "*.Mask")
			(remove_unused_layers no)
			(net "GND")
			(clearance 0.127)
			(thermal_gap 0.127)
		)
		(pad "G3" thru_hole oval
			(at 1.022604 -0.255016 270)
			(size 1.6256 3.4798)
			(drill oval 1.1176 2.4638)
			(layers "*.Cu" "*.Mask")
			(remove_unused_layers no)
			(net "GND")
			(clearance 0.127)
			(thermal_gap 0.127)
		)
		(pad "G4" thru_hole oval
			(at 1.022604 12.005056 270)
			(size 1.6256 3.4798)
			(drill oval 1.1176 2.4638)
			(layers "*.Cu" "*.Mask")
			(remove_unused_layers no)
			(net "GND")
			(clearance 0.127)
			(thermal_gap 0.127)
		)
		(pad "G5" thru_hole oval
			(at 1.022604 34.034984 270)
			(size 1.5748 3.4798)
			(drill oval 1.1176 2.4638)
			(layers "*.Cu" "*.Mask")
			(remove_unused_layers no)
			(net "GND")
			(clearance 0.1524)
			(thermal_gap 0.1524)
		)
		(pad "G6" thru_hole circle
			(at -3.16738 -20.625054)
			(size 1.6256 1.6256)
			(drill 1.1176)
			(layers "*.Cu" "*.Mask")
			(remove_unused_layers no)
			(net "GND")
			(clearance 0)
		)
		(pad "G7" thru_hole circle
			(at -3.16738 12.005056)
			(size 1.6256 1.6256)
			(drill 1.1176)
			(layers "*.Cu" "*.Mask")
			(remove_unused_layers no)
			(net "GND")
			(clearance 0)
		)
		(pad "G8" thru_hole circle
			(at 4.20243 -20.625054)
			(size 1.6256 1.6256)
			(drill 1.1176)
			(layers "*.Cu" "*.Mask")
			(remove_unused_layers no)
			(net "GND")
			(clearance 0)
		)
		(pad "G9" thru_hole circle
			(at 4.20243 12.005056)
			(size 1.6256 1.6256)
			(drill 1.1176)
			(layers "*.Cu" "*.Mask")
			(remove_unused_layers no)
			(net "GND")
			(clearance 0)
		)
		(pad "OA1" smd rect
			(at 3.322574 -30.660086 270)
			(size 0.3556 1.2192)
			(layers "F.Cu" "F.Mask" "F.Paste")
			(net "RST_NIC2_PERST2_R_N")
		)
		(pad "OA2" smd rect
			(at 3.322574 -30.059884 270)
			(size 0.3556 1.2192)
			(layers "F.Cu" "F.Mask" "F.Paste")
			(net "RST_NIC2_PERST3_R_N")
		)
		(pad "OA3" smd rect
			(at 3.322574 -29.459936 270)
			(size 0.3556 1.2192)
			(layers "F.Cu" "F.Mask" "F.Paste")
			(net "Net_2611")
		)
		(pad "OA4" smd rect
			(at 3.322574 -28.859988 270)
			(size 0.3556 1.2192)
			(layers "F.Cu" "F.Mask" "F.Paste")
			(net "NIC2_RBT_ARB_IN")
		)
		(pad "OA5" smd rect
			(at 3.322574 -28.26004 270)
			(size 0.3556 1.2192)
			(layers "F.Cu" "F.Mask" "F.Paste")
			(net "NIC2_RBT_ARB_OUT")
		)
		(pad "OA6" smd rect
			(at 3.322574 -27.660092 270)
			(size 0.3556 1.2192)
			(layers "F.Cu" "F.Mask" "F.Paste")
			(net "NIC2_SLOT_ID1")
		)
		(pad "OA7" smd rect
			(at 3.322574 -27.05989 270)
			(size 0.3556 1.2192)
			(layers "F.Cu" "F.Mask" "F.Paste")
			(net "NCSI_NIC2_TX_EN")
		)
		(pad "OA8" smd rect
			(at 3.322574 -26.459942 270)
			(size 0.3556 1.2192)
			(layers "F.Cu" "F.Mask" "F.Paste")
			(net "NCSI_NIC2_TXD1")
		)
		(pad "OA9" smd rect
			(at 3.322574 -25.859994 270)
			(size 0.3556 1.2192)
			(layers "F.Cu" "F.Mask" "F.Paste")
			(net "NCSI_NIC2_TXD0")
		)
		(pad "OA10" smd rect
			(at 3.322574 -25.260046 270)
			(size 0.3556 1.2192)
			(layers "F.Cu" "F.Mask" "F.Paste")
			(net "GND")
		)
		(pad "OA11" smd rect
			(at 3.322574 -24.660098 270)
			(size 0.3556 1.2192)
			(layers "F.Cu" "F.Mask" "F.Paste")
			(net "Net_2603")
		)
		(pad "OA12" smd rect
			(at 3.322574 -24.059896 270)
			(size 0.3556 1.2192)
			(layers "F.Cu" "F.Mask" "F.Paste")
			(net "Net_2606")
		)
		(pad "OA13" smd rect
			(at 3.322574 -23.459948 270)
			(size 0.3556 1.2192)
			(layers "F.Cu" "F.Mask" "F.Paste")
			(net "GND")
		)
		(pad "OA14" smd rect
			(at 3.322574 -22.86 270)
			(size 0.3556 1.2192)
			(layers "F.Cu" "F.Mask" "F.Paste")
			(net "CLK_50M_NIC2_RBT_REF")
		)
		(pad "OB1" smd rect
			(at -1.27762 -30.660086 270)
			(size 0.3556 1.2192)
			(layers "F.Cu" "F.Mask" "F.Paste")
			(net "PWRGD_NIC2_PWR_GOOD")
		)
		(pad "OB2" smd rect
			(at -1.27762 -30.059884 270)
			(size 0.3556 1.2192)
			(layers "F.Cu" "F.Mask" "F.Paste")
			(net "NIC2_MAIN_PWR_EN_R")
		)
		(pad "OB3" smd rect
			(at -1.27762 -29.459936 270)
			(size 0.3556 1.2192)
			(layers "F.Cu" "F.Mask" "F.Paste")
			(net "NIC2_LD_N")
		)
		(pad "OB4" smd rect
			(at -1.27762 -28.859988 270)
			(size 0.3556 1.2192)
			(layers "F.Cu" "F.Mask" "F.Paste")
			(net "NIC2_DATA_IN")
		)
		(pad "OB5" smd rect
			(at -1.27762 -28.26004 270)
			(size 0.3556 1.2192)
			(layers "F.Cu" "F.Mask" "F.Paste")
			(net "NIC2_DATA_OUT")
		)
		(pad "OB6" smd rect
			(at -1.27762 -27.660092 270)
			(size 0.3556 1.2192)
			(layers "F.Cu" "F.Mask" "F.Paste")
			(net "NIC2_CLK")
		)
		(pad "OB7" smd rect
			(at -1.27762 -27.05989 270)
			(size 0.3556 1.2192)
			(layers "F.Cu" "F.Mask" "F.Paste")
			(net "NIC2_SLOT_ID0")
		)
		(pad "OB8" smd rect
			(at -1.27762 -26.459942 270)
			(size 0.3556 1.2192)
			(layers "F.Cu" "F.Mask" "F.Paste")
			(net "NCSI_NIC2_RXD1")
		)
		(pad "OB9" smd rect
			(at -1.27762 -25.859994 270)
			(size 0.3556 1.2192)
			(layers "F.Cu" "F.Mask" "F.Paste")
			(net "NCSI_NIC2_RXD0")
		)
		(pad "OB10" smd rect
			(at -1.27762 -25.260046 270)
			(size 0.3556 1.2192)
			(layers "F.Cu" "F.Mask" "F.Paste")
			(net "GND")
		)
		(pad "OB11" smd rect
			(at -1.27762 -24.660098 270)
			(size 0.3556 1.2192)
			(layers "F.Cu" "F.Mask" "F.Paste")
			(net "Net_2602")
		)
		(pad "OB12" smd rect
			(at -1.27762 -24.059896 270)
			(size 0.3556 1.2192)
			(layers "F.Cu" "F.Mask" "F.Paste")
			(net "Net_2605")
		)
		(pad "OB13" smd rect
			(at -1.27762 -23.459948 270)
			(size 0.3556 1.2192)
			(layers "F.Cu" "F.Mask" "F.Paste")
			(net "GND")
		)
		(pad "OB14" smd rect
			(at -1.27762 -22.86 270)
			(size 0.3556 1.2192)
			(layers "F.Cu" "F.Mask" "F.Paste")
			(net "NCSI_NIC2_CRS_DV")
		)
		(zone
			(layers "F.Cu" "B.Cu" "In1.Cu" "In2.Cu" "In3.Cu" "In4.Cu" "In5.Cu" "In6.Cu"
				"In7.Cu" "In8.Cu" "In9.Cu" "In10.Cu" "In11.Cu" "In12.Cu" "In13.Cu" "In14.Cu"
				"In15.Cu" "In16.Cu"
			)
			(hatch none 0.5)
			(connect_pads
				(clearance 0)
			)
			(min_thickness 0.25)
			(keepout
				(tracks not_allowed)
				(vias allowed)
				(pads allowed)
				(copperpour not_allowed)
				(footprints allowed)
			)
			(placement
				(enabled no)
				(sheetname "")
			)
			(fill
				(thermal_gap 0.5)
				(thermal_bridge_width 0.5)
				(island_removal_mode 0)
			)
			(polygon
				(pts
					(arc
						(start 163.759134 -160.1851)
						(mid 161.625534 -160.1851)
						(end 163.759134 -160.1851)
					)
				)
			)
		)
		(zone
			(layers "F.Cu" "B.Cu" "In1.Cu" "In2.Cu" "In3.Cu" "In4.Cu" "In5.Cu" "In6.Cu"
				"In7.Cu" "In8.Cu" "In9.Cu" "In10.Cu" "In11.Cu" "In12.Cu" "In13.Cu" "In14.Cu"
				"In15.Cu" "In16.Cu"
			)
			(hatch none 0.5)
			(connect_pads
				(clearance 0)
			)
			(min_thickness 0.25)
			(keepout
				(tracks not_allowed)
				(vias allowed)
				(pads allowed)
				(copperpour not_allowed)
				(footprints allowed)
			)
			(placement
				(enabled no)
				(sheetname "")
			)
			(fill
				(thermal_gap 0.5)
				(thermal_bridge_width 0.5)
				(island_removal_mode 0)
			)
			(polygon
				(pts
					(arc
						(start 165.509194 -95.214948)
						(mid 163.375594 -95.214948)
						(end 165.509194 -95.214948)
					)
				)
			)
		)
	)
	(footprint ""
		(layer "F.Cu")
		(at 224.022158 -85.684868 180)
		(property "Reference" "R4260"
			(at 0 0 180)
			(layer "F.SilkS")
			(hide yes)
			(effects
				(font
					(size 1.27 1.27)
				)
			)
		)
		(property "Value" ""
			(at 0 0 180)
			(layer "F.Fab")
			(effects
				(font
					(size 1.27 1.27)
				)
			)
		)
		(duplicate_pad_numbers_are_jumpers no)
		(fp_line
			(start 0.7874 0.4064)
			(end -0.7874 0.4064)
			(stroke
				(width 0.1524)
				(type default)
			)
			(layer "F.SilkS")
		)
		(fp_line
			(start 0.7874 -0.4064)
			(end 0.7874 0.4064)
			(stroke
				(width 0.1524)
				(type default)
			)
			(layer "F.SilkS")
		)
		(fp_line
			(start -0.7874 0.4064)
			(end -0.7874 -0.4064)
			(stroke
				(width 0.1524)
				(type default)
			)
			(layer "F.SilkS")
		)
		(fp_line
			(start -0.7874 -0.4064)
			(end 0.7874 -0.4064)
			(stroke
				(width 0.1524)
				(type default)
			)
			(layer "F.SilkS")
		)
		(fp_line
			(start 0.67945 0.3048)
			(end 0.120396 0.3048)
			(stroke
				(width 0.1)
				(type default)
			)
			(layer "F.Fab")
		)
		(fp_line
			(start 0.67945 -0.3048)
			(end 0.67945 0.3048)
			(stroke
				(width 0.1)
				(type default)
			)
			(layer "F.Fab")
		)
		(fp_line
			(start 0.12065 -0.2794)
			(end 0.12065 -0.3048)
			(stroke
				(width 0.1)
				(type default)
			)
			(layer "F.Fab")
		)
		(fp_line
			(start 0.12065 -0.3048)
			(end 0.67945 -0.3048)
			(stroke
				(width 0.1)
				(type default)
			)
			(layer "F.Fab")
		)
		(fp_line
			(start 0.120396 0.3048)
			(end 0.120396 0.2794)
			(stroke
				(width 0.1)
				(type default)
			)
			(layer "F.Fab")
		)
		(fp_line
			(start 0.120396 0.2794)
			(end -0.12065 0.2794)
			(stroke
				(width 0.1)
				(type default)
			)
			(layer "F.Fab")
		)
		(fp_line
			(start -0.12065 0.3048)
			(end -0.67945 0.3048)
			(stroke
				(width 0.1)
				(type default)
			)
			(layer "F.Fab")
		)
		(fp_line
			(start -0.12065 0.2794)
			(end -0.12065 0.3048)
			(stroke
				(width 0.1)
				(type default)
			)
			(layer "F.Fab")
		)
		(fp_line
			(start -0.12065 -0.2794)
			(end 0.12065 -0.2794)
			(stroke
				(width 0.1)
				(type default)
			)
			(layer "F.Fab")
		)
		(fp_line
			(start -0.12065 -0.305054)
			(end -0.12065 -0.2794)
			(stroke
				(width 0.1)
				(type default)
			)
			(layer "F.Fab")
		)
		(fp_line
			(start -0.67945 0.3048)
			(end -0.67945 -0.305054)
			(stroke
				(width 0.1)
				(type default)
			)
			(layer "F.Fab")
		)
		(fp_line
			(start -0.67945 -0.305054)
			(end -0.12065 -0.305054)
			(stroke
				(width 0.1)
				(type default)
			)
			(layer "F.Fab")
		)
		(pad "1" smd circle
			(at -0.40005 0 180)
			(size 0 0)
			(layers "F.Cu" "F.Mask" "F.Paste")
			(net "P3V3_AUX")
		)
		(pad "2" smd circle
			(at 0.40005 0 180)
			(size 0 0)
			(layers "F.Cu" "F.Mask" "F.Paste")
			(net "SSD_LED_IOEXP_A0")
		)
	)
	(footprint ""
		(layer "F.Cu")
		(at 84.709 -27.04973 180)
		(property "Reference" "C2766"
			(at 0 0 180)
			(layer "F.SilkS")
			(hide yes)
			(effects
				(font
					(size 1.27 1.27)
				)
			)
		)
		(property "Value" ""
			(at 0 0 180)
			(layer "F.Fab")
			(effects
				(font
					(size 1.27 1.27)
				)
			)
		)
		(duplicate_pad_numbers_are_jumpers no)
		(fp_line
			(start 0.7874 0.4064)
			(end -0.7874 0.4064)
			(stroke
				(width 0.1524)
				(type default)
			)
			(layer "F.SilkS")
		)
		(fp_line
			(start 0.7874 -0.4064)
			(end 0.7874 0.4064)
			(stroke
				(width 0.1524)
				(type default)
			)
			(layer "F.SilkS")
		)
		(fp_line
			(start -0.7874 0.4064)
			(end -0.7874 -0.4064)
			(stroke
				(width 0.1524)
				(type default)
			)
			(layer "F.SilkS")
		)
		(fp_line
			(start -0.7874 -0.4064)
			(end 0.7874 -0.4064)
			(stroke
				(width 0.1524)
				(type default)
			)
			(layer "F.SilkS")
		)
		(fp_line
			(start 0.67945 0.3048)
			(end 0.120396 0.3048)
			(stroke
				(width 0.1)
				(type default)
			)
			(layer "F.Fab")
		)
		(fp_line
			(start 0.67945 -0.3048)
			(end 0.67945 0.3048)
			(stroke
				(width 0.1)
				(type default)
			)
			(layer "F.Fab")
		)
		(fp_line
			(start 0.12065 -0.2794)
			(end 0.12065 -0.3048)
			(stroke
				(width 0.1)
				(type default)
			)
			(layer "F.Fab")
		)
		(fp_line
			(start 0.12065 -0.3048)
			(end 0.67945 -0.3048)
			(stroke
				(width 0.1)
				(type default)
			)
			(layer "F.Fab")
		)
		(fp_line
			(start 0.120396 0.3048)
			(end 0.120396 0.2794)
			(stroke
				(width 0.1)
				(type default)
			)
			(layer "F.Fab")
		)
		(fp_line
			(start 0.120396 0.2794)
			(end -0.12065 0.2794)
			(stroke
				(width 0.1)
				(type default)
			)
			(layer "F.Fab")
		)
		(fp_line
			(start -0.12065 0.3048)
			(end -0.67945 0.3048)
			(stroke
				(width 0.1)
				(type default)
			)
			(layer "F.Fab")
		)
		(fp_line
			(start -0.12065 0.2794)
			(end -0.12065 0.3048)
			(stroke
				(width 0.1)
				(type default)
			)
			(layer "F.Fab")
		)
		(fp_line
			(start -0.12065 -0.2794)
			(end 0.12065 -0.2794)
			(stroke
				(width 0.1)
				(type default)
			)
			(layer "F.Fab")
		)
		(fp_line
			(start -0.12065 -0.305054)
			(end -0.12065 -0.2794)
			(stroke
				(width 0.1)
				(type default)
			)
			(layer "F.Fab")
		)
		(fp_line
			(start -0.67945 0.3048)
			(end -0.67945 -0.305054)
			(stroke
				(width 0.1)
				(type default)
			)
			(layer "F.Fab")
		)
		(fp_line
			(start -0.67945 -0.305054)
			(end -0.12065 -0.305054)
			(stroke
				(width 0.1)
				(type default)
			)
			(layer "F.Fab")
		)
		(pad "1" smd circle
			(at -0.40005 0 180)
			(size 0 0)
			(layers "F.Cu" "F.Mask" "F.Paste")
			(net "PRSNT_SSD3_R_N")
		)
		(pad "2" smd circle
			(at 0.40005 0 180)
			(size 0 0)
			(layers "F.Cu" "F.Mask" "F.Paste")
			(net "GND")
		)
	)
	(footprint ""
		(layer "F.Cu")
		(at 265.487658 -291.619432)
		(property "Reference" "C3390"
			(at 0 0 0)
			(layer "F.SilkS")
			(hide yes)
			(effects
				(font
					(size 1.27 1.27)
				)
			)
		)
		(property "Value" ""
			(at 0 0 0)
			(layer "F.Fab")
			(effects
				(font
					(size 1.27 1.27)
				)
			)
		)
		(duplicate_pad_numbers_are_jumpers no)
		(fp_line
			(start -1.2954 -0.5842)
			(end 1.2954 -0.5842)
			(stroke
				(width 0.1524)
				(type default)
			)
			(layer "F.SilkS")
		)
		(fp_line
			(start -1.2954 0.5842)
			(end -1.2954 -0.5842)
			(stroke
				(width 0.1524)
				(type default)
			)
			(layer "F.SilkS")
		)
		(fp_line
			(start 1.2954 -0.5842)
			(end 1.2954 0.5842)
			(stroke
				(width 0.1524)
				(type default)
			)
			(layer "F.SilkS")
		)
		(fp_line
			(start 1.2954 0.5842)
			(end -1.2954 0.5842)
			(stroke
				(width 0.1524)
				(type default)
			)
			(layer "F.SilkS")
		)
		(fp_line
			(start -1.1938 -0.4064)
			(end -0.8636 -0.4064)
			(stroke
				(width 0.1)
				(type default)
			)
			(layer "F.Fab")
		)
		(fp_line
			(start -1.1938 0.4064)
			(end -1.1938 -0.4064)
			(stroke
				(width 0.1)
				(type default)
			)
			(layer "F.Fab")
		)
		(fp_line
			(start -0.8636 -0.4572)
			(end 0.8636 -0.4572)
			(stroke
				(width 0.1)
				(type default)
			)
			(layer "F.Fab")
		)
		(fp_line
			(start -0.8636 -0.4064)
			(end -0.8636 -0.4572)
			(stroke
				(width 0.1)
				(type default)
			)
			(layer "F.Fab")
		)
		(fp_line
			(start -0.8636 0.4064)
			(end -1.1938 0.4064)
			(stroke
				(width 0.1)
				(type default)
			)
			(layer "F.Fab")
		)
		(fp_line
			(start -0.8636 0.4572)
			(end -0.8636 0.4064)
			(stroke
				(width 0.1)
				(type default)
			)
			(layer "F.Fab")
		)
		(fp_line
			(start 0.8636 -0.4572)
			(end 0.8636 -0.4064)
			(stroke
				(width 0.1)
				(type default)
			)
			(layer "F.Fab")
		)
		(fp_line
			(start 0.8636 -0.4064)
			(end 1.1938 -0.4064)
			(stroke
				(width 0.1)
				(type default)
			)
			(layer "F.Fab")
		)
		(fp_line
			(start 0.8636 0.4064)
			(end 0.8636 0.4572)
			(stroke
				(width 0.1)
				(type default)
			)
			(layer "F.Fab")
		)
		(fp_line
			(start 0.8636 0.4572)
			(end -0.8636 0.4572)
			(stroke
				(width 0.1)
				(type default)
			)
			(layer "F.Fab")
		)
		(fp_line
			(start 1.1938 -0.4064)
			(end 1.1938 0.4064)
			(stroke
				(width 0.1)
				(type default)
			)
			(layer "F.Fab")
		)
		(fp_line
			(start 1.1938 0.4064)
			(end 0.8636 0.4064)
			(stroke
				(width 0.1)
				(type default)
			)
			(layer "F.Fab")
		)
		(pad "1" smd rect
			(at -0.7366 0 270)
			(size 0.7112 0.8128)
			(layers "F.Cu" "F.Mask" "F.Paste")
			(net "PCEPLL4_VDDA18_PEX2")
		)
		(pad "2" smd rect
			(at 0.7366 0 270)
			(size 0.7112 0.8128)
			(layers "F.Cu" "F.Mask" "F.Paste")
			(net "GND")
		)
	)
	(footprint ""
		(layer "F.Cu")
		(at 442.02604 -125.530864)
		(property "Reference" "PC473"
			(at 0 0 0)
			(layer "F.SilkS")
			(hide yes)
			(effects
				(font
					(size 1.27 1.27)
				)
			)
		)
		(property "Value" ""
			(at 0 0 0)
			(layer "F.Fab")
			(effects
				(font
					(size 1.27 1.27)
				)
			)
		)
		(duplicate_pad_numbers_are_jumpers no)
		(fp_line
			(start -1.524 -0.762)
			(end 1.524 -0.762)
			(stroke
				(width 0.1524)
				(type default)
			)
			(layer "F.SilkS")
		)
		(fp_line
			(start -1.524 0.762)
			(end -1.524 -0.762)
			(stroke
				(width 0.1524)
				(type default)
			)
			(layer "F.SilkS")
		)
		(fp_line
			(start 1.524 -0.762)
			(end 1.524 0.762)
			(stroke
				(width 0.1524)
				(type default)
			)
			(layer "F.SilkS")
		)
		(fp_line
			(start 1.524 0.762)
			(end -1.524 0.762)
			(stroke
				(width 0.1524)
				(type default)
			)
			(layer "F.SilkS")
		)
		(fp_line
			(start -1.1049 -0.724916)
			(end -1.1049 0.724916)
			(stroke
				(width 0.1)
				(type default)
			)
			(layer "F.Fab")
		)
		(fp_line
			(start -1.1049 0.724916)
			(end 1.1049 0.724916)
			(stroke
				(width 0.1)
				(type default)
			)
			(layer "F.Fab")
		)
		(fp_line
			(start 1.1049 -0.724916)
			(end -1.1049 -0.724916)
			(stroke
				(width 0.1)
				(type default)
			)
			(layer "F.Fab")
		)
		(fp_line
			(start 1.1049 0.724916)
			(end 1.1049 -0.724916)
			(stroke
				(width 0.1)
				(type default)
			)
			(layer "F.Fab")
		)
		(pad "1" smd rect
			(at -0.889 0 180)
			(size 1.016 1.27)
			(layers "F.Cu" "F.Mask" "F.Paste")
			(net "GND")
		)
		(pad "2" smd rect
			(at 0.889 0 180)
			(size 1.016 1.27)
			(layers "F.Cu" "F.Mask" "F.Paste")
			(net "P3V3_AUX")
		)
	)
	(footprint ""
		(layer "F.Cu")
		(at 325.099934 -289.230816 -90)
		(property "Reference" "R3978"
			(at 0 0 270)
			(layer "F.SilkS")
			(hide yes)
			(effects
				(font
					(size 1.27 1.27)
				)
			)
		)
		(property "Value" ""
			(at 0 0 270)
			(layer "F.Fab")
			(effects
				(font
					(size 1.27 1.27)
				)
			)
		)
		(duplicate_pad_numbers_are_jumpers no)
		(fp_line
			(start -0.7874 0.4064)
			(end -0.7874 -0.4064)
			(stroke
				(width 0.1524)
				(type default)
			)
			(layer "F.SilkS")
		)
		(fp_line
			(start 0.7874 0.4064)
			(end -0.7874 0.4064)
			(stroke
				(width 0.1524)
				(type default)
			)
			(layer "F.SilkS")
		)
		(fp_line
			(start -0.7874 -0.4064)
			(end 0.7874 -0.4064)
			(stroke
				(width 0.1524)
				(type default)
			)
			(layer "F.SilkS")
		)
		(fp_line
			(start 0.7874 -0.4064)
			(end 0.7874 0.4064)
			(stroke
				(width 0.1524)
				(type default)
			)
			(layer "F.SilkS")
		)
		(fp_line
			(start -0.67945 0.3048)
			(end -0.67945 -0.305054)
			(stroke
				(width 0.1)
				(type default)
			)
			(layer "F.Fab")
		)
		(fp_line
			(start -0.12065 0.3048)
			(end -0.67945 0.3048)
			(stroke
				(width 0.1)
				(type default)
			)
			(layer "F.Fab")
		)
		(fp_line
			(start 0.120396 0.3048)
			(end 0.120396 0.2794)
			(stroke
				(width 0.1)
				(type default)
			)
			(layer "F.Fab")
		)
		(fp_line
			(start 0.67945 0.3048)
			(end 0.120396 0.3048)
			(stroke
				(width 0.1)
				(type default)
			)
			(layer "F.Fab")
		)
		(fp_line
			(start -0.12065 0.2794)
			(end -0.12065 0.3048)
			(stroke
				(width 0.1)
				(type default)
			)
			(layer "F.Fab")
		)
		(fp_line
			(start 0.120396 0.2794)
			(end -0.12065 0.2794)
			(stroke
				(width 0.1)
				(type default)
			)
			(layer "F.Fab")
		)
		(fp_line
			(start -0.12065 -0.2794)
			(end 0.12065 -0.2794)
			(stroke
				(width 0.1)
				(type default)
			)
			(layer "F.Fab")
		)
		(fp_line
			(start 0.12065 -0.2794)
			(end 0.12065 -0.3048)
			(stroke
				(width 0.1)
				(type default)
			)
			(layer "F.Fab")
		)
		(fp_line
			(start 0.12065 -0.3048)
			(end 0.67945 -0.3048)
			(stroke
				(width 0.1)
				(type default)
			)
			(layer "F.Fab")
		)
		(fp_line
			(start 0.67945 -0.3048)
			(end 0.67945 0.3048)
			(stroke
				(width 0.1)
				(type default)
			)
			(layer "F.Fab")
		)
		(fp_line
			(start -0.67945 -0.305054)
			(end -0.12065 -0.305054)
			(stroke
				(width 0.1)
				(type default)
			)
			(layer "F.Fab")
		)
		(fp_line
			(start -0.12065 -0.305054)
			(end -0.12065 -0.2794)
			(stroke
				(width 0.1)
				(type default)
			)
			(layer "F.Fab")
		)
		(pad "1" smd circle
			(at -0.40005 0 270)
			(size 0 0)
			(layers "F.Cu" "F.Mask" "F.Paste")
			(net "SMB_PEX2_HOST_LS_SCL")
		)
		(pad "2" smd circle
			(at 0.40005 0 270)
			(size 0 0)
			(layers "F.Cu" "F.Mask" "F.Paste")
			(net "P3V3_AUX")
		)
	)
	(footprint ""
		(layer "F.Cu")
		(at 198.76135 -144.396714 180)
		(property "Reference" "C225"
			(at 0 0 180)
			(layer "F.SilkS")
			(hide yes)
			(effects
				(font
					(size 1.27 1.27)
				)
			)
		)
		(property "Value" ""
			(at 0 0 180)
			(layer "F.Fab")
			(effects
				(font
					(size 1.27 1.27)
				)
			)
		)
		(duplicate_pad_numbers_are_jumpers no)
		(fp_line
			(start 0.299974 0.150114)
			(end -0.299974 0.150114)
			(stroke
				(width 0.1)
				(type default)
			)
			(layer "F.Fab")
		)
		(fp_line
			(start 0.299974 -0.150114)
			(end 0.299974 0.150114)
			(stroke
				(width 0.1)
				(type default)
			)
			(layer "F.Fab")
		)
		(fp_line
			(start -0.299974 0.150114)
			(end -0.299974 -0.150114)
			(stroke
				(width 0.1)
				(type default)
			)
			(layer "F.Fab")
		)
		(fp_line
			(start -0.299974 -0.150114)
			(end 0.299974 -0.150114)
			(stroke
				(width 0.1)
				(type default)
			)
			(layer "F.Fab")
		)
		(pad "1" smd rect
			(at -0.2667 0 180)
			(size 0.3048 0.381)
			(layers "F.Cu" "F.Mask" "F.Paste")
			(net "P5E_PEX1_STN0_TX_DN<9>")
		)
		(pad "2" smd rect
			(at 0.2667 0 180)
			(size 0.3048 0.381)
			(layers "F.Cu" "F.Mask" "F.Paste")
			(net "P5E_PEX1_STN0_TX_C_DN<9>")
		)
	)
	(footprint ""
		(layer "F.Cu")
		(at 302.922432 -44.341542 90)
		(property "Reference" "R624"
			(at 0 0 90)
			(layer "F.SilkS")
			(hide yes)
			(effects
				(font
					(size 1.27 1.27)
				)
			)
		)
		(property "Value" ""
			(at 0 0 90)
			(layer "F.Fab")
			(effects
				(font
					(size 1.27 1.27)
				)
			)
		)
		(duplicate_pad_numbers_are_jumpers no)
		(fp_line
			(start 0.7874 -0.4064)
			(end 0.7874 0.4064)
			(stroke
				(width 0.1524)
				(type default)
			)
			(layer "F.SilkS")
		)
		(fp_line
			(start -0.7874 -0.4064)
			(end 0.7874 -0.4064)
			(stroke
				(width 0.1524)
				(type default)
			)
			(layer "F.SilkS")
		)
		(fp_line
			(start 0.7874 0.4064)
			(end -0.7874 0.4064)
			(stroke
				(width 0.1524)
				(type default)
			)
			(layer "F.SilkS")
		)
		(fp_line
			(start -0.7874 0.4064)
			(end -0.7874 -0.4064)
			(stroke
				(width 0.1524)
				(type default)
			)
			(layer "F.SilkS")
		)
		(fp_line
			(start -0.12065 -0.305054)
			(end -0.12065 -0.2794)
			(stroke
				(width 0.1)
				(type default)
			)
			(layer "F.Fab")
		)
		(fp_line
			(start -0.67945 -0.305054)
			(end -0.12065 -0.305054)
			(stroke
				(width 0.1)
				(type default)
			)
			(layer "F.Fab")
		)
		(fp_line
			(start 0.67945 -0.3048)
			(end 0.67945 0.3048)
			(stroke
				(width 0.1)
				(type default)
			)
			(layer "F.Fab")
		)
		(fp_line
			(start 0.12065 -0.3048)
			(end 0.67945 -0.3048)
			(stroke
				(width 0.1)
				(type default)
			)
			(layer "F.Fab")
		)
		(fp_line
			(start 0.12065 -0.2794)
			(end 0.12065 -0.3048)
			(stroke
				(width 0.1)
				(type default)
			)
			(layer "F.Fab")
		)
		(fp_line
			(start -0.12065 -0.2794)
			(end 0.12065 -0.2794)
			(stroke
				(width 0.1)
				(type default)
			)
			(layer "F.Fab")
		)
		(fp_line
			(start 0.120396 0.2794)
			(end -0.12065 0.2794)
			(stroke
				(width 0.1)
				(type default)
			)
			(layer "F.Fab")
		)
		(fp_line
			(start -0.12065 0.2794)
			(end -0.12065 0.3048)
			(stroke
				(width 0.1)
				(type default)
			)
			(layer "F.Fab")
		)
		(fp_line
			(start 0.67945 0.3048)
			(end 0.120396 0.3048)
			(stroke
				(width 0.1)
				(type default)
			)
			(layer "F.Fab")
		)
		(fp_line
			(start 0.120396 0.3048)
			(end 0.120396 0.2794)
			(stroke
				(width 0.1)
				(type default)
			)
			(layer "F.Fab")
		)
		(fp_line
			(start -0.12065 0.3048)
			(end -0.67945 0.3048)
			(stroke
				(width 0.1)
				(type default)
			)
			(layer "F.Fab")
		)
		(fp_line
			(start -0.67945 0.3048)
			(end -0.67945 -0.305054)
			(stroke
				(width 0.1)
				(type default)
			)
			(layer "F.Fab")
		)
		(pad "1" smd circle
			(at -0.40005 0 90)
			(size 0 0)
			(layers "F.Cu" "F.Mask" "F.Paste")
			(net "P12V_SSD10")
		)
		(pad "2" smd circle
			(at 0.40005 0 90)
			(size 0 0)
			(layers "F.Cu" "F.Mask" "F.Paste")
			(net "P12V_SSD10_VIN_N")
		)
	)
	(footprint ""
		(layer "F.Cu")
		(at 214.908892 -104.962198 90)
		(property "Reference" "R722"
			(at 0 0 90)
			(layer "F.SilkS")
			(hide yes)
			(effects
				(font
					(size 1.27 1.27)
				)
			)
		)
		(property "Value" ""
			(at 0 0 90)
			(layer "F.Fab")
			(effects
				(font
					(size 1.27 1.27)
				)
			)
		)
		(duplicate_pad_numbers_are_jumpers no)
		(fp_line
			(start 0.7874 -0.4064)
			(end 0.7874 0.4064)
			(stroke
				(width 0.1524)
				(type default)
			)
			(layer "F.SilkS")
		)
		(fp_line
			(start -0.7874 -0.4064)
			(end 0.7874 -0.4064)
			(stroke
				(width 0.1524)
				(type default)
			)
			(layer "F.SilkS")
		)
		(fp_line
			(start 0.7874 0.4064)
			(end -0.7874 0.4064)
			(stroke
				(width 0.1524)
				(type default)
			)
			(layer "F.SilkS")
		)
		(fp_line
			(start -0.7874 0.4064)
			(end -0.7874 -0.4064)
			(stroke
				(width 0.1524)
				(type default)
			)
			(layer "F.SilkS")
		)
		(fp_line
			(start -0.12065 -0.305054)
			(end -0.12065 -0.2794)
			(stroke
				(width 0.1)
				(type default)
			)
			(layer "F.Fab")
		)
		(fp_line
			(start -0.67945 -0.305054)
			(end -0.12065 -0.305054)
			(stroke
				(width 0.1)
				(type default)
			)
			(layer "F.Fab")
		)
		(fp_line
			(start 0.67945 -0.3048)
			(end 0.67945 0.3048)
			(stroke
				(width 0.1)
				(type default)
			)
			(layer "F.Fab")
		)
		(fp_line
			(start 0.12065 -0.3048)
			(end 0.67945 -0.3048)
			(stroke
				(width 0.1)
				(type default)
			)
			(layer "F.Fab")
		)
		(fp_line
			(start 0.12065 -0.2794)
			(end 0.12065 -0.3048)
			(stroke
				(width 0.1)
				(type default)
			)
			(layer "F.Fab")
		)
		(fp_line
			(start -0.12065 -0.2794)
			(end 0.12065 -0.2794)
			(stroke
				(width 0.1)
				(type default)
			)
			(layer "F.Fab")
		)
		(fp_line
			(start 0.120396 0.2794)
			(end -0.12065 0.2794)
			(stroke
				(width 0.1)
				(type default)
			)
			(layer "F.Fab")
		)
		(fp_line
			(start -0.12065 0.2794)
			(end -0.12065 0.3048)
			(stroke
				(width 0.1)
				(type default)
			)
			(layer "F.Fab")
		)
		(fp_line
			(start 0.67945 0.3048)
			(end 0.120396 0.3048)
			(stroke
				(width 0.1)
				(type default)
			)
			(layer "F.Fab")
		)
		(fp_line
			(start 0.120396 0.3048)
			(end 0.120396 0.2794)
			(stroke
				(width 0.1)
				(type default)
			)
			(layer "F.Fab")
		)
		(fp_line
			(start -0.12065 0.3048)
			(end -0.67945 0.3048)
			(stroke
				(width 0.1)
				(type default)
			)
			(layer "F.Fab")
		)
		(fp_line
			(start -0.67945 0.3048)
			(end -0.67945 -0.305054)
			(stroke
				(width 0.1)
				(type default)
			)
			(layer "F.Fab")
		)
		(pad "1" smd circle
			(at -0.40005 0 90)
			(size 0 0)
			(layers "F.Cu" "F.Mask" "F.Paste")
			(net "P12V_NIC3_R")
		)
		(pad "2" smd circle
			(at 0.40005 0 90)
			(size 0 0)
			(layers "F.Cu" "F.Mask" "F.Paste")
			(net "P12V_NIC3_VIN_P")
		)
	)
	(footprint ""
		(layer "F.Cu")
		(at 94.494096 -117.426486)
		(property "Reference" "PC666"
			(at 0 0 0)
			(layer "F.SilkS")
			(hide yes)
			(effects
				(font
					(size 1.27 1.27)
				)
			)
		)
		(property "Value" ""
			(at 0 0 0)
			(layer "F.Fab")
			(effects
				(font
					(size 1.27 1.27)
				)
			)
		)
		(duplicate_pad_numbers_are_jumpers no)
		(fp_line
			(start -0.7874 -0.4064)
			(end 0.7874 -0.4064)
			(stroke
				(width 0.1524)
				(type default)
			)
			(layer "F.SilkS")
		)
		(fp_line
			(start -0.7874 0.4064)
			(end -0.7874 -0.4064)
			(stroke
				(width 0.1524)
				(type default)
			)
			(layer "F.SilkS")
		)
		(fp_line
			(start 0.7874 -0.4064)
			(end 0.7874 0.4064)
			(stroke
				(width 0.1524)
				(type default)
			)
			(layer "F.SilkS")
		)
		(fp_line
			(start 0.7874 0.4064)
			(end -0.7874 0.4064)
			(stroke
				(width 0.1524)
				(type default)
			)
			(layer "F.SilkS")
		)
		(fp_line
			(start -0.67945 -0.305054)
			(end -0.12065 -0.305054)
			(stroke
				(width 0.1)
				(type default)
			)
			(layer "F.Fab")
		)
		(fp_line
			(start -0.67945 0.3048)
			(end -0.67945 -0.305054)
			(stroke
				(width 0.1)
				(type default)
			)
			(layer "F.Fab")
		)
		(fp_line
			(start -0.12065 -0.305054)
			(end -0.12065 -0.2794)
			(stroke
				(width 0.1)
				(type default)
			)
			(layer "F.Fab")
		)
		(fp_line
			(start -0.12065 -0.2794)
			(end 0.12065 -0.2794)
			(stroke
				(width 0.1)
				(type default)
			)
			(layer "F.Fab")
		)
		(fp_line
			(start -0.12065 0.2794)
			(end -0.12065 0.3048)
			(stroke
				(width 0.1)
				(type default)
			)
			(layer "F.Fab")
		)
		(fp_line
			(start -0.12065 0.3048)
			(end -0.67945 0.3048)
			(stroke
				(width 0.1)
				(type default)
			)
			(layer "F.Fab")
		)
		(fp_line
			(start 0.120396 0.2794)
			(end -0.12065 0.2794)
			(stroke
				(width 0.1)
				(type default)
			)
			(layer "F.Fab")
		)
		(fp_line
			(start 0.120396 0.3048)
			(end 0.120396 0.2794)
			(stroke
				(width 0.1)
				(type default)
			)
			(layer "F.Fab")
		)
		(fp_line
			(start 0.12065 -0.3048)
			(end 0.67945 -0.3048)
			(stroke
				(width 0.1)
				(type default)
			)
			(layer "F.Fab")
		)
		(fp_line
			(start 0.12065 -0.2794)
			(end 0.12065 -0.3048)
			(stroke
				(width 0.1)
				(type default)
			)
			(layer "F.Fab")
		)
		(fp_line
			(start 0.67945 -0.3048)
			(end 0.67945 0.3048)
			(stroke
				(width 0.1)
				(type default)
			)
			(layer "F.Fab")
		)
		(fp_line
			(start 0.67945 0.3048)
			(end 0.120396 0.3048)
			(stroke
				(width 0.1)
				(type default)
			)
			(layer "F.Fab")
		)
		(pad "1" smd circle
			(at -0.40005 0)
			(size 0 0)
			(layers "F.Cu" "F.Mask" "F.Paste")
			(net "P3V3_NIC1_CO_MODE")
		)
		(pad "2" smd circle
			(at 0.40005 0)
			(size 0 0)
			(layers "F.Cu" "F.Mask" "F.Paste")
			(net "GND")
		)
	)
	(footprint ""
		(layer "F.Cu")
		(at 324.249542 -304.036476 90)
		(property "Reference" "R1389"
			(at 0 0 90)
			(layer "F.SilkS")
			(hide yes)
			(effects
				(font
					(size 1.27 1.27)
				)
			)
		)
		(property "Value" ""
			(at 0 0 90)
			(layer "F.Fab")
			(effects
				(font
					(size 1.27 1.27)
				)
			)
		)
		(duplicate_pad_numbers_are_jumpers no)
		(fp_line
			(start 0.7874 -0.4064)
			(end 0.7874 0.4064)
			(stroke
				(width 0.1524)
				(type default)
			)
			(layer "F.SilkS")
		)
		(fp_line
			(start -0.7874 -0.4064)
			(end 0.7874 -0.4064)
			(stroke
				(width 0.1524)
				(type default)
			)
			(layer "F.SilkS")
		)
		(fp_line
			(start 0.7874 0.4064)
			(end -0.7874 0.4064)
			(stroke
				(width 0.1524)
				(type default)
			)
			(layer "F.SilkS")
		)
		(fp_line
			(start -0.7874 0.4064)
			(end -0.7874 -0.4064)
			(stroke
				(width 0.1524)
				(type default)
			)
			(layer "F.SilkS")
		)
		(fp_line
			(start -0.12065 -0.305054)
			(end -0.12065 -0.2794)
			(stroke
				(width 0.1)
				(type default)
			)
			(layer "F.Fab")
		)
		(fp_line
			(start -0.67945 -0.305054)
			(end -0.12065 -0.305054)
			(stroke
				(width 0.1)
				(type default)
			)
			(layer "F.Fab")
		)
		(fp_line
			(start 0.67945 -0.3048)
			(end 0.67945 0.3048)
			(stroke
				(width 0.1)
				(type default)
			)
			(layer "F.Fab")
		)
		(fp_line
			(start 0.12065 -0.3048)
			(end 0.67945 -0.3048)
			(stroke
				(width 0.1)
				(type default)
			)
			(layer "F.Fab")
		)
		(fp_line
			(start 0.12065 -0.2794)
			(end 0.12065 -0.3048)
			(stroke
				(width 0.1)
				(type default)
			)
			(layer "F.Fab")
		)
		(fp_line
			(start -0.12065 -0.2794)
			(end 0.12065 -0.2794)
			(stroke
				(width 0.1)
				(type default)
			)
			(layer "F.Fab")
		)
		(fp_line
			(start 0.120396 0.2794)
			(end -0.12065 0.2794)
			(stroke
				(width 0.1)
				(type default)
			)
			(layer "F.Fab")
		)
		(fp_line
			(start -0.12065 0.2794)
			(end -0.12065 0.3048)
			(stroke
				(width 0.1)
				(type default)
			)
			(layer "F.Fab")
		)
		(fp_line
			(start 0.67945 0.3048)
			(end 0.120396 0.3048)
			(stroke
				(width 0.1)
				(type default)
			)
			(layer "F.Fab")
		)
		(fp_line
			(start 0.120396 0.3048)
			(end 0.120396 0.2794)
			(stroke
				(width 0.1)
				(type default)
			)
			(layer "F.Fab")
		)
		(fp_line
			(start -0.12065 0.3048)
			(end -0.67945 0.3048)
			(stroke
				(width 0.1)
				(type default)
			)
			(layer "F.Fab")
		)
		(fp_line
			(start -0.67945 0.3048)
			(end -0.67945 -0.305054)
			(stroke
				(width 0.1)
				(type default)
			)
			(layer "F.Fab")
		)
		(pad "1" smd circle
			(at -0.40005 0 90)
			(size 0 0)
			(layers "F.Cu" "F.Mask" "F.Paste")
			(net "GND")
		)
		(pad "2" smd circle
			(at 0.40005 0 90)
			(size 0 0)
			(layers "F.Cu" "F.Mask" "F.Paste")
			(net "PEX2_SPARE6")
		)
	)
	(footprint ""
		(layer "F.Cu")
		(at 278.131778 -410.014928 -90)
		(property "Reference" "U308"
			(at -0.56134 -2.822956 90)
			(unlocked yes)
			(layer "F.SilkS")
			(effects
				(font
					(size 0.7874 0.5842)
					(thickness 0.1524)
				)
			)
		)
		(property "Value" ""
			(at 0 0 270)
			(layer "F.Fab")
			(effects
				(font
					(size 1.27 1.27)
				)
			)
		)
		(duplicate_pad_numbers_are_jumpers no)
		(fp_line
			(start -1.0414 1.575054)
			(end -1.0414 -1.575054)
			(stroke
				(width 0.1524)
				(type default)
			)
			(layer "F.SilkS")
		)
		(fp_line
			(start 1.0414 1.575054)
			(end -1.0414 1.575054)
			(stroke
				(width 0.1524)
				(type default)
			)
			(layer "F.SilkS")
		)
		(fp_line
			(start 0 -1.272032)
			(end -0.254 -1.575054)
			(stroke
				(width 0.1524)
				(type default)
			)
			(layer "F.SilkS")
		)
		(fp_line
			(start -1.0414 -1.575054)
			(end -0.254 -1.575054)
			(stroke
				(width 0.1524)
				(type default)
			)
			(layer "F.SilkS")
		)
		(fp_line
			(start 0.2286 -1.575054)
			(end 0 -1.272032)
			(stroke
				(width 0.1524)
				(type default)
			)
			(layer "F.SilkS")
		)
		(fp_line
			(start 0.254 -1.575054)
			(end 1.0414 -1.575054)
			(stroke
				(width 0.1524)
				(type default)
			)
			(layer "F.SilkS")
		)
		(fp_line
			(start 1.0414 -1.575054)
			(end 1.0414 1.575054)
			(stroke
				(width 0.1524)
				(type default)
			)
			(layer "F.SilkS")
		)
		(fp_poly
			(pts
				(xy -2.710688 -0.975106) (xy -3.726688 -1.483106) (xy -3.726688 -0.467106)
			)
			(stroke
				(width 0)
				(type default)
			)
			(fill yes)
			(layer "F.SilkS")
		)
		(fp_line
			(start -1.4478 1.5748)
			(end -1.4478 1.2192)
			(stroke
				(width 0.1)
				(type default)
			)
			(layer "F.Fab")
		)
		(fp_line
			(start 1.4478 1.5748)
			(end -1.4478 1.5748)
			(stroke
				(width 0.1)
				(type default)
			)
			(layer "F.Fab")
		)
		(fp_line
			(start -2.5654 1.2192)
			(end -2.5654 -1.2192)
			(stroke
				(width 0.1)
				(type default)
			)
			(layer "F.Fab")
		)
		(fp_line
			(start -1.4478 1.2192)
			(end -2.5654 1.2192)
			(stroke
				(width 0.1)
				(type default)
			)
			(layer "F.Fab")
		)
		(fp_line
			(start 1.4478 1.2192)
			(end 1.4478 1.5748)
			(stroke
				(width 0.1)
				(type default)
			)
			(layer "F.Fab")
		)
		(fp_line
			(start 2.5654 1.2192)
			(end 1.4478 1.2192)
			(stroke
				(width 0.1)
				(type default)
			)
			(layer "F.Fab")
		)
		(fp_line
			(start -2.5654 -1.2192)
			(end -1.4478 -1.2192)
			(stroke
				(width 0.1)
				(type default)
			)
			(layer "F.Fab")
		)
		(fp_line
			(start -1.4478 -1.2192)
			(end -1.4478 -1.5748)
			(stroke
				(width 0.1)
				(type default)
			)
			(layer "F.Fab")
		)
		(fp_line
			(start 1.4478 -1.2192)
			(end 2.5654 -1.2192)
			(stroke
				(width 0.1)
				(type default)
			)
			(layer "F.Fab")
		)
		(fp_line
			(start 2.5654 -1.2192)
			(end 2.5654 1.2192)
			(stroke
				(width 0.1)
				(type default)
			)
			(layer "F.Fab")
		)
		(fp_line
			(start -1.4478 -1.5748)
			(end 1.4478 -1.5748)
			(stroke
				(width 0.1)
				(type default)
			)
			(layer "F.Fab")
		)
		(fp_line
			(start 1.4478 -1.5748)
			(end 1.4478 -1.2192)
			(stroke
				(width 0.1)
				(type default)
			)
			(layer "F.Fab")
		)
		(fp_poly
			(pts
				(xy -2.710688 -0.975106) (xy -3.726688 -1.483106) (xy -3.726688 -0.467106)
			)
			(stroke
				(width 0)
				(type default)
			)
			(fill yes)
			(layer "F.Fab")
		)
		(pad "1" smd rect
			(at -1.849882 -0.975106 180)
			(size 0.3556 1.3208)
			(layers "F.Cu" "F.Mask" "F.Paste")
			(net "MB_BIC_R_MON")
		)
		(pad "2" smd rect
			(at -1.849882 -0.32512 180)
			(size 0.3556 1.3208)
			(layers "F.Cu" "F.Mask" "F.Paste")
			(net "MB_BIC_READY_BUF_N")
		)
		(pad "3" smd rect
			(at -1.849882 0.32512 180)
			(size 0.3556 1.3208)
			(layers "F.Cu" "F.Mask" "F.Paste")
			(net "RST_MB_BMC_R_N")
		)
		(pad "4" smd rect
			(at -1.849882 0.975106 180)
			(size 0.3556 1.3208)
			(layers "F.Cu" "F.Mask" "F.Paste")
			(net "GND")
		)
		(pad "5" smd rect
			(at 1.849882 0.975106 180)
			(size 0.3556 1.3208)
			(layers "F.Cu" "F.Mask" "F.Paste")
			(net "RST_MB_BMC_BUF_N")
		)
		(pad "6" smd rect
			(at 1.849882 0.32512 180)
			(size 0.3556 1.3208)
			(layers "F.Cu" "F.Mask" "F.Paste")
			(net "BIC_SYS_READY_R1_N")
		)
		(pad "7" smd rect
			(at 1.849882 -0.32512 180)
			(size 0.3556 1.3208)
			(layers "F.Cu" "F.Mask" "F.Paste")
			(net "MB_BIC_MON_BUF")
		)
		(pad "8" smd rect
			(at 1.849882 -0.975106 180)
			(size 0.3556 1.3208)
			(layers "F.Cu" "F.Mask" "F.Paste")
			(net "P3V3_AUX")
		)
	)
	(footprint ""
		(layer "F.Cu")
		(at 239.812322 -60.163964 180)
		(property "Reference" "R5998"
			(at 0 0 180)
			(layer "F.SilkS")
			(hide yes)
			(effects
				(font
					(size 1.27 1.27)
				)
			)
		)
		(property "Value" ""
			(at 0 0 180)
			(layer "F.Fab")
			(effects
				(font
					(size 1.27 1.27)
				)
			)
		)
		(duplicate_pad_numbers_are_jumpers no)
		(fp_line
			(start 0.7874 0.4064)
			(end -0.7874 0.4064)
			(stroke
				(width 0.1524)
				(type default)
			)
			(layer "F.SilkS")
		)
		(fp_line
			(start 0.7874 -0.4064)
			(end 0.7874 0.4064)
			(stroke
				(width 0.1524)
				(type default)
			)
			(layer "F.SilkS")
		)
		(fp_line
			(start -0.7874 0.4064)
			(end -0.7874 -0.4064)
			(stroke
				(width 0.1524)
				(type default)
			)
			(layer "F.SilkS")
		)
		(fp_line
			(start -0.7874 -0.4064)
			(end 0.7874 -0.4064)
			(stroke
				(width 0.1524)
				(type default)
			)
			(layer "F.SilkS")
		)
		(fp_line
			(start 0.67945 0.3048)
			(end 0.120396 0.3048)
			(stroke
				(width 0.1)
				(type default)
			)
			(layer "F.Fab")
		)
		(fp_line
			(start 0.67945 -0.3048)
			(end 0.67945 0.3048)
			(stroke
				(width 0.1)
				(type default)
			)
			(layer "F.Fab")
		)
		(fp_line
			(start 0.12065 -0.2794)
			(end 0.12065 -0.3048)
			(stroke
				(width 0.1)
				(type default)
			)
			(layer "F.Fab")
		)
		(fp_line
			(start 0.12065 -0.3048)
			(end 0.67945 -0.3048)
			(stroke
				(width 0.1)
				(type default)
			)
			(layer "F.Fab")
		)
		(fp_line
			(start 0.120396 0.3048)
			(end 0.120396 0.2794)
			(stroke
				(width 0.1)
				(type default)
			)
			(layer "F.Fab")
		)
		(fp_line
			(start 0.120396 0.2794)
			(end -0.12065 0.2794)
			(stroke
				(width 0.1)
				(type default)
			)
			(layer "F.Fab")
		)
		(fp_line
			(start -0.12065 0.3048)
			(end -0.67945 0.3048)
			(stroke
				(width 0.1)
				(type default)
			)
			(layer "F.Fab")
		)
		(fp_line
			(start -0.12065 0.2794)
			(end -0.12065 0.3048)
			(stroke
				(width 0.1)
				(type default)
			)
			(layer "F.Fab")
		)
		(fp_line
			(start -0.12065 -0.2794)
			(end 0.12065 -0.2794)
			(stroke
				(width 0.1)
				(type default)
			)
			(layer "F.Fab")
		)
		(fp_line
			(start -0.12065 -0.305054)
			(end -0.12065 -0.2794)
			(stroke
				(width 0.1)
				(type default)
			)
			(layer "F.Fab")
		)
		(fp_line
			(start -0.67945 0.3048)
			(end -0.67945 -0.305054)
			(stroke
				(width 0.1)
				(type default)
			)
			(layer "F.Fab")
		)
		(fp_line
			(start -0.67945 -0.305054)
			(end -0.12065 -0.305054)
			(stroke
				(width 0.1)
				(type default)
			)
			(layer "F.Fab")
		)
		(pad "1" smd circle
			(at -0.40005 0 180)
			(size 0 0)
			(layers "F.Cu" "F.Mask" "F.Paste")
			(net "P12V_SSD8_R")
		)
		(pad "2" smd circle
			(at 0.40005 0 180)
			(size 0 0)
			(layers "F.Cu" "F.Mask" "F.Paste")
			(net "P12V_SSD8_PG_G1")
		)
	)
	(footprint ""
		(layer "F.Cu")
		(at 256.02946 -195.573396 -90)
		(property "Reference" "R4300"
			(at 0 0 270)
			(layer "F.SilkS")
			(hide yes)
			(effects
				(font
					(size 1.27 1.27)
				)
			)
		)
		(property "Value" ""
			(at 0 0 270)
			(layer "F.Fab")
			(effects
				(font
					(size 1.27 1.27)
				)
			)
		)
		(duplicate_pad_numbers_are_jumpers no)
		(fp_line
			(start -0.7874 0.4064)
			(end -0.7874 -0.4064)
			(stroke
				(width 0.1524)
				(type default)
			)
			(layer "F.SilkS")
		)
		(fp_line
			(start 0.7874 0.4064)
			(end -0.7874 0.4064)
			(stroke
				(width 0.1524)
				(type default)
			)
			(layer "F.SilkS")
		)
		(fp_line
			(start -0.7874 -0.4064)
			(end 0.7874 -0.4064)
			(stroke
				(width 0.1524)
				(type default)
			)
			(layer "F.SilkS")
		)
		(fp_line
			(start 0.7874 -0.4064)
			(end 0.7874 0.4064)
			(stroke
				(width 0.1524)
				(type default)
			)
			(layer "F.SilkS")
		)
		(fp_line
			(start -0.67945 0.3048)
			(end -0.67945 -0.305054)
			(stroke
				(width 0.1)
				(type default)
			)
			(layer "F.Fab")
		)
		(fp_line
			(start -0.12065 0.3048)
			(end -0.67945 0.3048)
			(stroke
				(width 0.1)
				(type default)
			)
			(layer "F.Fab")
		)
		(fp_line
			(start 0.120396 0.3048)
			(end 0.120396 0.2794)
			(stroke
				(width 0.1)
				(type default)
			)
			(layer "F.Fab")
		)
		(fp_line
			(start 0.67945 0.3048)
			(end 0.120396 0.3048)
			(stroke
				(width 0.1)
				(type default)
			)
			(layer "F.Fab")
		)
		(fp_line
			(start -0.12065 0.2794)
			(end -0.12065 0.3048)
			(stroke
				(width 0.1)
				(type default)
			)
			(layer "F.Fab")
		)
		(fp_line
			(start 0.120396 0.2794)
			(end -0.12065 0.2794)
			(stroke
				(width 0.1)
				(type default)
			)
			(layer "F.Fab")
		)
		(fp_line
			(start -0.12065 -0.2794)
			(end 0.12065 -0.2794)
			(stroke
				(width 0.1)
				(type default)
			)
			(layer "F.Fab")
		)
		(fp_line
			(start 0.12065 -0.2794)
			(end 0.12065 -0.3048)
			(stroke
				(width 0.1)
				(type default)
			)
			(layer "F.Fab")
		)
		(fp_line
			(start 0.12065 -0.3048)
			(end 0.67945 -0.3048)
			(stroke
				(width 0.1)
				(type default)
			)
			(layer "F.Fab")
		)
		(fp_line
			(start 0.67945 -0.3048)
			(end 0.67945 0.3048)
			(stroke
				(width 0.1)
				(type default)
			)
			(layer "F.Fab")
		)
		(fp_line
			(start -0.67945 -0.305054)
			(end -0.12065 -0.305054)
			(stroke
				(width 0.1)
				(type default)
			)
			(layer "F.Fab")
		)
		(fp_line
			(start -0.12065 -0.305054)
			(end -0.12065 -0.2794)
			(stroke
				(width 0.1)
				(type default)
			)
			(layer "F.Fab")
		)
		(pad "1" smd circle
			(at -0.40005 0 270)
			(size 0 0)
			(layers "F.Cu" "F.Mask" "F.Paste")
			(net "JTAG_PLD_TMS")
		)
		(pad "2" smd circle
			(at 0.40005 0 270)
			(size 0 0)
			(layers "F.Cu" "F.Mask" "F.Paste")
			(net "JTAG_FPGA_TMS")
		)
	)
	(footprint ""
		(layer "F.Cu")
		(at 336.042 -177.927)
		(property "Reference" "R4725"
			(at 0 0 0)
			(layer "F.SilkS")
			(hide yes)
			(effects
				(font
					(size 1.27 1.27)
				)
			)
		)
		(property "Value" ""
			(at 0 0 0)
			(layer "F.Fab")
			(effects
				(font
					(size 1.27 1.27)
				)
			)
		)
		(duplicate_pad_numbers_are_jumpers no)
		(fp_line
			(start -0.7874 -0.4064)
			(end 0.7874 -0.4064)
			(stroke
				(width 0.1524)
				(type default)
			)
			(layer "F.SilkS")
		)
		(fp_line
			(start -0.7874 0.4064)
			(end -0.7874 -0.4064)
			(stroke
				(width 0.1524)
				(type default)
			)
			(layer "F.SilkS")
		)
		(fp_line
			(start 0.7874 -0.4064)
			(end 0.7874 0.4064)
			(stroke
				(width 0.1524)
				(type default)
			)
			(layer "F.SilkS")
		)
		(fp_line
			(start 0.7874 0.4064)
			(end -0.7874 0.4064)
			(stroke
				(width 0.1524)
				(type default)
			)
			(layer "F.SilkS")
		)
		(fp_line
			(start -0.67945 -0.305054)
			(end -0.12065 -0.305054)
			(stroke
				(width 0.1)
				(type default)
			)
			(layer "F.Fab")
		)
		(fp_line
			(start -0.67945 0.3048)
			(end -0.67945 -0.305054)
			(stroke
				(width 0.1)
				(type default)
			)
			(layer "F.Fab")
		)
		(fp_line
			(start -0.12065 -0.305054)
			(end -0.12065 -0.2794)
			(stroke
				(width 0.1)
				(type default)
			)
			(layer "F.Fab")
		)
		(fp_line
			(start -0.12065 -0.2794)
			(end 0.12065 -0.2794)
			(stroke
				(width 0.1)
				(type default)
			)
			(layer "F.Fab")
		)
		(fp_line
			(start -0.12065 0.2794)
			(end -0.12065 0.3048)
			(stroke
				(width 0.1)
				(type default)
			)
			(layer "F.Fab")
		)
		(fp_line
			(start -0.12065 0.3048)
			(end -0.67945 0.3048)
			(stroke
				(width 0.1)
				(type default)
			)
			(layer "F.Fab")
		)
		(fp_line
			(start 0.120396 0.2794)
			(end -0.12065 0.2794)
			(stroke
				(width 0.1)
				(type default)
			)
			(layer "F.Fab")
		)
		(fp_line
			(start 0.120396 0.3048)
			(end 0.120396 0.2794)
			(stroke
				(width 0.1)
				(type default)
			)
			(layer "F.Fab")
		)
		(fp_line
			(start 0.12065 -0.3048)
			(end 0.67945 -0.3048)
			(stroke
				(width 0.1)
				(type default)
			)
			(layer "F.Fab")
		)
		(fp_line
			(start 0.12065 -0.2794)
			(end 0.12065 -0.3048)
			(stroke
				(width 0.1)
				(type default)
			)
			(layer "F.Fab")
		)
		(fp_line
			(start 0.67945 -0.3048)
			(end 0.67945 0.3048)
			(stroke
				(width 0.1)
				(type default)
			)
			(layer "F.Fab")
		)
		(fp_line
			(start 0.67945 0.3048)
			(end 0.120396 0.3048)
			(stroke
				(width 0.1)
				(type default)
			)
			(layer "F.Fab")
		)
		(pad "1" smd circle
			(at -0.40005 0)
			(size 0 0)
			(layers "F.Cu" "F.Mask" "F.Paste")
			(net "P3V3_AUX")
		)
		(pad "2" smd circle
			(at 0.40005 0)
			(size 0 0)
			(layers "F.Cu" "F.Mask" "F.Paste")
			(net "SSD9_PEX_PWR_EN_R")
		)
	)
	(footprint ""
		(layer "F.Cu")
		(at 108.689902 -279.486868 -90)
		(property "Reference" "PC73"
			(at 0 0 270)
			(layer "F.SilkS")
			(hide yes)
			(effects
				(font
					(size 1.27 1.27)
				)
			)
		)
		(property "Value" ""
			(at 0 0 270)
			(layer "F.Fab")
			(effects
				(font
					(size 1.27 1.27)
				)
			)
		)
		(duplicate_pad_numbers_are_jumpers no)
		(fp_line
			(start -0.7874 0.4064)
			(end -0.7874 -0.4064)
			(stroke
				(width 0.1524)
				(type default)
			)
			(layer "F.SilkS")
		)
		(fp_line
			(start 0.7874 0.4064)
			(end -0.7874 0.4064)
			(stroke
				(width 0.1524)
				(type default)
			)
			(layer "F.SilkS")
		)
		(fp_line
			(start -0.7874 -0.4064)
			(end 0.7874 -0.4064)
			(stroke
				(width 0.1524)
				(type default)
			)
			(layer "F.SilkS")
		)
		(fp_line
			(start 0.7874 -0.4064)
			(end 0.7874 0.4064)
			(stroke
				(width 0.1524)
				(type default)
			)
			(layer "F.SilkS")
		)
		(fp_line
			(start -0.67945 0.3048)
			(end -0.67945 -0.305054)
			(stroke
				(width 0.1)
				(type default)
			)
			(layer "F.Fab")
		)
		(fp_line
			(start -0.12065 0.3048)
			(end -0.67945 0.3048)
			(stroke
				(width 0.1)
				(type default)
			)
			(layer "F.Fab")
		)
		(fp_line
			(start 0.120396 0.3048)
			(end 0.120396 0.2794)
			(stroke
				(width 0.1)
				(type default)
			)
			(layer "F.Fab")
		)
		(fp_line
			(start 0.67945 0.3048)
			(end 0.120396 0.3048)
			(stroke
				(width 0.1)
				(type default)
			)
			(layer "F.Fab")
		)
		(fp_line
			(start -0.12065 0.2794)
			(end -0.12065 0.3048)
			(stroke
				(width 0.1)
				(type default)
			)
			(layer "F.Fab")
		)
		(fp_line
			(start 0.120396 0.2794)
			(end -0.12065 0.2794)
			(stroke
				(width 0.1)
				(type default)
			)
			(layer "F.Fab")
		)
		(fp_line
			(start -0.12065 -0.2794)
			(end 0.12065 -0.2794)
			(stroke
				(width 0.1)
				(type default)
			)
			(layer "F.Fab")
		)
		(fp_line
			(start 0.12065 -0.2794)
			(end 0.12065 -0.3048)
			(stroke
				(width 0.1)
				(type default)
			)
			(layer "F.Fab")
		)
		(fp_line
			(start 0.12065 -0.3048)
			(end 0.67945 -0.3048)
			(stroke
				(width 0.1)
				(type default)
			)
			(layer "F.Fab")
		)
		(fp_line
			(start 0.67945 -0.3048)
			(end 0.67945 0.3048)
			(stroke
				(width 0.1)
				(type default)
			)
			(layer "F.Fab")
		)
		(fp_line
			(start -0.67945 -0.305054)
			(end -0.12065 -0.305054)
			(stroke
				(width 0.1)
				(type default)
			)
			(layer "F.Fab")
		)
		(fp_line
			(start -0.12065 -0.305054)
			(end -0.12065 -0.2794)
			(stroke
				(width 0.1)
				(type default)
			)
			(layer "F.Fab")
		)
		(pad "1" smd circle
			(at -0.40005 0 270)
			(size 0 0)
			(layers "F.Cu" "F.Mask" "F.Paste")
			(net "P0V8_PEX0_VREF")
		)
		(pad "2" smd circle
			(at 0.40005 0 270)
			(size 0 0)
			(layers "F.Cu" "F.Mask" "F.Paste")
			(net "GND")
		)
	)
	(footprint ""
		(layer "F.Cu")
		(at 270.616426 -200.80859)
		(property "Reference" "ME7"
			(at 0.1016 -12.690348 0)
			(unlocked yes)
			(layer "F.SilkS")
			(effects
				(font
					(size 0.7874 0.5842)
					(thickness 0.1524)
				)
				(justify left)
			)
		)
		(property "Value" ""
			(at 0 0 0)
			(layer "F.Fab")
			(effects
				(font
					(size 1.27 1.27)
				)
			)
		)
		(duplicate_pad_numbers_are_jumpers no)
		(fp_line
			(start 0 -11.999976)
			(end 0 -10.475976)
			(stroke
				(width 0.1524)
				(type default)
			)
			(layer "F.SilkS")
		)
		(fp_line
			(start 0 -1.524)
			(end 0 0)
			(stroke
				(width 0.1524)
				(type default)
			)
			(layer "F.SilkS")
		)
		(fp_line
			(start 0 0)
			(end 1.524 0)
			(stroke
				(width 0.1524)
				(type default)
			)
			(layer "F.SilkS")
		)
		(fp_line
			(start 1.524 -11.999976)
			(end 0 -11.999976)
			(stroke
				(width 0.1524)
				(type default)
			)
			(layer "F.SilkS")
		)
		(fp_line
			(start 15.475966 0)
			(end 16.999966 0)
			(stroke
				(width 0.1524)
				(type default)
			)
			(layer "F.SilkS")
		)
		(fp_line
			(start 16.999966 -11.999976)
			(end 15.475966 -11.999976)
			(stroke
				(width 0.1524)
				(type default)
			)
			(layer "F.SilkS")
		)
		(fp_line
			(start 16.999966 -10.475976)
			(end 16.999966 -11.999976)
			(stroke
				(width 0.1524)
				(type default)
			)
			(layer "F.SilkS")
		)
		(fp_line
			(start 16.999966 0)
			(end 16.999966 -1.524)
			(stroke
				(width 0.1524)
				(type default)
			)
			(layer "F.SilkS")
		)
		(fp_text user "MAC"
			(at 0.3302 -10.50925 0)
			(unlocked yes)
			(layer "F.SilkS")
			(effects
				(font
					(size 1.905 1.4224)
					(thickness 0.1524)
				)
				(justify left)
			)
		)
	)
	(footprint ""
		(layer "F.Cu")
		(at 340.561422 -194.48145 180)
		(property "Reference" "R4240"
			(at 0 0 180)
			(layer "F.SilkS")
			(hide yes)
			(effects
				(font
					(size 1.27 1.27)
				)
			)
		)
		(property "Value" ""
			(at 0 0 180)
			(layer "F.Fab")
			(effects
				(font
					(size 1.27 1.27)
				)
			)
		)
		(duplicate_pad_numbers_are_jumpers no)
		(fp_line
			(start 0.7874 0.4064)
			(end -0.7874 0.4064)
			(stroke
				(width 0.1524)
				(type default)
			)
			(layer "F.SilkS")
		)
		(fp_line
			(start 0.7874 -0.4064)
			(end 0.7874 0.4064)
			(stroke
				(width 0.1524)
				(type default)
			)
			(layer "F.SilkS")
		)
		(fp_line
			(start -0.7874 0.4064)
			(end -0.7874 -0.4064)
			(stroke
				(width 0.1524)
				(type default)
			)
			(layer "F.SilkS")
		)
		(fp_line
			(start -0.7874 -0.4064)
			(end 0.7874 -0.4064)
			(stroke
				(width 0.1524)
				(type default)
			)
			(layer "F.SilkS")
		)
		(fp_line
			(start 0.67945 0.3048)
			(end 0.120396 0.3048)
			(stroke
				(width 0.1)
				(type default)
			)
			(layer "F.Fab")
		)
		(fp_line
			(start 0.67945 -0.3048)
			(end 0.67945 0.3048)
			(stroke
				(width 0.1)
				(type default)
			)
			(layer "F.Fab")
		)
		(fp_line
			(start 0.12065 -0.2794)
			(end 0.12065 -0.3048)
			(stroke
				(width 0.1)
				(type default)
			)
			(layer "F.Fab")
		)
		(fp_line
			(start 0.12065 -0.3048)
			(end 0.67945 -0.3048)
			(stroke
				(width 0.1)
				(type default)
			)
			(layer "F.Fab")
		)
		(fp_line
			(start 0.120396 0.3048)
			(end 0.120396 0.2794)
			(stroke
				(width 0.1)
				(type default)
			)
			(layer "F.Fab")
		)
		(fp_line
			(start 0.120396 0.2794)
			(end -0.12065 0.2794)
			(stroke
				(width 0.1)
				(type default)
			)
			(layer "F.Fab")
		)
		(fp_line
			(start -0.12065 0.3048)
			(end -0.67945 0.3048)
			(stroke
				(width 0.1)
				(type default)
			)
			(layer "F.Fab")
		)
		(fp_line
			(start -0.12065 0.2794)
			(end -0.12065 0.3048)
			(stroke
				(width 0.1)
				(type default)
			)
			(layer "F.Fab")
		)
		(fp_line
			(start -0.12065 -0.2794)
			(end 0.12065 -0.2794)
			(stroke
				(width 0.1)
				(type default)
			)
			(layer "F.Fab")
		)
		(fp_line
			(start -0.12065 -0.305054)
			(end -0.12065 -0.2794)
			(stroke
				(width 0.1)
				(type default)
			)
			(layer "F.Fab")
		)
		(fp_line
			(start -0.67945 0.3048)
			(end -0.67945 -0.305054)
			(stroke
				(width 0.1)
				(type default)
			)
			(layer "F.Fab")
		)
		(fp_line
			(start -0.67945 -0.305054)
			(end -0.12065 -0.305054)
			(stroke
				(width 0.1)
				(type default)
			)
			(layer "F.Fab")
		)
		(pad "1" smd circle
			(at -0.40005 0 180)
			(size 0 0)
			(layers "F.Cu" "F.Mask" "F.Paste")
			(net "P3V3_AUX")
		)
		(pad "2" smd circle
			(at 0.40005 0 180)
			(size 0 0)
			(layers "F.Cu" "F.Mask" "F.Paste")
			(net "FM_SOL_UART_CH_SEL")
		)
	)
	(footprint ""
		(layer "F.Cu")
		(at 431.694082 -29.507688 -90)
		(property "Reference" "PC976"
			(at 0 0 270)
			(layer "F.SilkS")
			(hide yes)
			(effects
				(font
					(size 1.27 1.27)
				)
			)
		)
		(property "Value" ""
			(at 0 0 270)
			(layer "F.Fab")
			(effects
				(font
					(size 1.27 1.27)
				)
			)
		)
		(duplicate_pad_numbers_are_jumpers no)
		(fp_line
			(start -1.524 0.762)
			(end -1.524 -0.762)
			(stroke
				(width 0.1524)
				(type default)
			)
			(layer "F.SilkS")
		)
		(fp_line
			(start 1.524 0.762)
			(end -1.524 0.762)
			(stroke
				(width 0.1524)
				(type default)
			)
			(layer "F.SilkS")
		)
		(fp_line
			(start -1.524 -0.762)
			(end 1.524 -0.762)
			(stroke
				(width 0.1524)
				(type default)
			)
			(layer "F.SilkS")
		)
		(fp_line
			(start 1.524 -0.762)
			(end 1.524 0.762)
			(stroke
				(width 0.1524)
				(type default)
			)
			(layer "F.SilkS")
		)
		(fp_line
			(start -1.1049 0.724916)
			(end 1.1049 0.724916)
			(stroke
				(width 0.1)
				(type default)
			)
			(layer "F.Fab")
		)
		(fp_line
			(start 1.1049 0.724916)
			(end 1.1049 -0.724916)
			(stroke
				(width 0.1)
				(type default)
			)
			(layer "F.Fab")
		)
		(fp_line
			(start -1.1049 -0.724916)
			(end -1.1049 0.724916)
			(stroke
				(width 0.1)
				(type default)
			)
			(layer "F.Fab")
		)
		(fp_line
			(start 1.1049 -0.724916)
			(end -1.1049 -0.724916)
			(stroke
				(width 0.1)
				(type default)
			)
			(layer "F.Fab")
		)
		(pad "1" smd rect
			(at -0.889 0 90)
			(size 1.016 1.27)
			(layers "F.Cu" "F.Mask" "F.Paste")
			(net "P3V3_SSD15")
		)
		(pad "2" smd rect
			(at 0.889 0 90)
			(size 1.016 1.27)
			(layers "F.Cu" "F.Mask" "F.Paste")
			(net "GND")
		)
	)
	(footprint ""
		(layer "F.Cu")
		(at 234.855512 -234.728004 -90)
		(property "Reference" "R6190"
			(at 0 0 270)
			(layer "F.SilkS")
			(hide yes)
			(effects
				(font
					(size 1.27 1.27)
				)
			)
		)
		(property "Value" ""
			(at 0 0 270)
			(layer "F.Fab")
			(effects
				(font
					(size 1.27 1.27)
				)
			)
		)
		(duplicate_pad_numbers_are_jumpers no)
		(fp_line
			(start -0.7874 0.4064)
			(end -0.7874 -0.4064)
			(stroke
				(width 0.1524)
				(type default)
			)
			(layer "F.SilkS")
		)
		(fp_line
			(start 0.7874 0.4064)
			(end -0.7874 0.4064)
			(stroke
				(width 0.1524)
				(type default)
			)
			(layer "F.SilkS")
		)
		(fp_line
			(start -0.7874 -0.4064)
			(end 0.7874 -0.4064)
			(stroke
				(width 0.1524)
				(type default)
			)
			(layer "F.SilkS")
		)
		(fp_line
			(start 0.7874 -0.4064)
			(end 0.7874 0.4064)
			(stroke
				(width 0.1524)
				(type default)
			)
			(layer "F.SilkS")
		)
		(fp_line
			(start -0.67945 0.3048)
			(end -0.67945 -0.305054)
			(stroke
				(width 0.1)
				(type default)
			)
			(layer "F.Fab")
		)
		(fp_line
			(start -0.12065 0.3048)
			(end -0.67945 0.3048)
			(stroke
				(width 0.1)
				(type default)
			)
			(layer "F.Fab")
		)
		(fp_line
			(start 0.120396 0.3048)
			(end 0.120396 0.2794)
			(stroke
				(width 0.1)
				(type default)
			)
			(layer "F.Fab")
		)
		(fp_line
			(start 0.67945 0.3048)
			(end 0.120396 0.3048)
			(stroke
				(width 0.1)
				(type default)
			)
			(layer "F.Fab")
		)
		(fp_line
			(start -0.12065 0.2794)
			(end -0.12065 0.3048)
			(stroke
				(width 0.1)
				(type default)
			)
			(layer "F.Fab")
		)
		(fp_line
			(start 0.120396 0.2794)
			(end -0.12065 0.2794)
			(stroke
				(width 0.1)
				(type default)
			)
			(layer "F.Fab")
		)
		(fp_line
			(start -0.12065 -0.2794)
			(end 0.12065 -0.2794)
			(stroke
				(width 0.1)
				(type default)
			)
			(layer "F.Fab")
		)
		(fp_line
			(start 0.12065 -0.2794)
			(end 0.12065 -0.3048)
			(stroke
				(width 0.1)
				(type default)
			)
			(layer "F.Fab")
		)
		(fp_line
			(start 0.12065 -0.3048)
			(end 0.67945 -0.3048)
			(stroke
				(width 0.1)
				(type default)
			)
			(layer "F.Fab")
		)
		(fp_line
			(start 0.67945 -0.3048)
			(end 0.67945 0.3048)
			(stroke
				(width 0.1)
				(type default)
			)
			(layer "F.Fab")
		)
		(fp_line
			(start -0.67945 -0.305054)
			(end -0.12065 -0.305054)
			(stroke
				(width 0.1)
				(type default)
			)
			(layer "F.Fab")
		)
		(fp_line
			(start -0.12065 -0.305054)
			(end -0.12065 -0.2794)
			(stroke
				(width 0.1)
				(type default)
			)
			(layer "F.Fab")
		)
		(pad "1" smd circle
			(at -0.40005 0 270)
			(size 0 0)
			(layers "F.Cu" "F.Mask" "F.Paste")
			(net "GND")
		)
		(pad "2" smd circle
			(at 0.40005 0 270)
			(size 0 0)
			(layers "F.Cu" "F.Mask" "F.Paste")
			(net "SSD8_PWRDIS_BIC_R")
		)
	)
	(footprint ""
		(layer "F.Cu")
		(at 112.973866 -161.405824 90)
		(property "Reference" "PR63"
			(at 0 0 90)
			(layer "F.SilkS")
			(hide yes)
			(effects
				(font
					(size 1.27 1.27)
				)
			)
		)
		(property "Value" ""
			(at 0 0 90)
			(layer "F.Fab")
			(effects
				(font
					(size 1.27 1.27)
				)
			)
		)
		(duplicate_pad_numbers_are_jumpers no)
		(fp_line
			(start 0.7874 -0.4064)
			(end 0.7874 0.4064)
			(stroke
				(width 0.1524)
				(type default)
			)
			(layer "F.SilkS")
		)
		(fp_line
			(start -0.7874 -0.4064)
			(end 0.7874 -0.4064)
			(stroke
				(width 0.1524)
				(type default)
			)
			(layer "F.SilkS")
		)
		(fp_line
			(start 0.7874 0.4064)
			(end -0.7874 0.4064)
			(stroke
				(width 0.1524)
				(type default)
			)
			(layer "F.SilkS")
		)
		(fp_line
			(start -0.7874 0.4064)
			(end -0.7874 -0.4064)
			(stroke
				(width 0.1524)
				(type default)
			)
			(layer "F.SilkS")
		)
		(fp_line
			(start -0.12065 -0.305054)
			(end -0.12065 -0.2794)
			(stroke
				(width 0.1)
				(type default)
			)
			(layer "F.Fab")
		)
		(fp_line
			(start -0.67945 -0.305054)
			(end -0.12065 -0.305054)
			(stroke
				(width 0.1)
				(type default)
			)
			(layer "F.Fab")
		)
		(fp_line
			(start 0.67945 -0.3048)
			(end 0.67945 0.3048)
			(stroke
				(width 0.1)
				(type default)
			)
			(layer "F.Fab")
		)
		(fp_line
			(start 0.12065 -0.3048)
			(end 0.67945 -0.3048)
			(stroke
				(width 0.1)
				(type default)
			)
			(layer "F.Fab")
		)
		(fp_line
			(start 0.12065 -0.2794)
			(end 0.12065 -0.3048)
			(stroke
				(width 0.1)
				(type default)
			)
			(layer "F.Fab")
		)
		(fp_line
			(start -0.12065 -0.2794)
			(end 0.12065 -0.2794)
			(stroke
				(width 0.1)
				(type default)
			)
			(layer "F.Fab")
		)
		(fp_line
			(start 0.120396 0.2794)
			(end -0.12065 0.2794)
			(stroke
				(width 0.1)
				(type default)
			)
			(layer "F.Fab")
		)
		(fp_line
			(start -0.12065 0.2794)
			(end -0.12065 0.3048)
			(stroke
				(width 0.1)
				(type default)
			)
			(layer "F.Fab")
		)
		(fp_line
			(start 0.67945 0.3048)
			(end 0.120396 0.3048)
			(stroke
				(width 0.1)
				(type default)
			)
			(layer "F.Fab")
		)
		(fp_line
			(start 0.120396 0.3048)
			(end 0.120396 0.2794)
			(stroke
				(width 0.1)
				(type default)
			)
			(layer "F.Fab")
		)
		(fp_line
			(start -0.12065 0.3048)
			(end -0.67945 0.3048)
			(stroke
				(width 0.1)
				(type default)
			)
			(layer "F.Fab")
		)
		(fp_line
			(start -0.67945 0.3048)
			(end -0.67945 -0.305054)
			(stroke
				(width 0.1)
				(type default)
			)
			(layer "F.Fab")
		)
		(pad "1" smd circle
			(at -0.40005 0 90)
			(size 0 0)
			(layers "F.Cu" "F.Mask" "F.Paste")
			(net "GND")
		)
		(pad "2" smd circle
			(at 0.40005 0 90)
			(size 0 0)
			(layers "F.Cu" "F.Mask" "F.Paste")
			(net "P3V3_AUX_FB")
		)
	)
	(footprint ""
		(layer "F.Cu")
		(at 177.705512 -343.952322 90)
		(property "Reference" "C2526"
			(at 0 0 90)
			(layer "F.SilkS")
			(hide yes)
			(effects
				(font
					(size 1.27 1.27)
				)
			)
		)
		(property "Value" ""
			(at 0 0 90)
			(layer "F.Fab")
			(effects
				(font
					(size 1.27 1.27)
				)
			)
		)
		(duplicate_pad_numbers_are_jumpers no)
		(fp_line
			(start 0.299974 -0.150114)
			(end 0.299974 0.150114)
			(stroke
				(width 0.1)
				(type default)
			)
			(layer "F.Fab")
		)
		(fp_line
			(start -0.299974 -0.150114)
			(end 0.299974 -0.150114)
			(stroke
				(width 0.1)
				(type default)
			)
			(layer "F.Fab")
		)
		(fp_line
			(start 0.299974 0.150114)
			(end -0.299974 0.150114)
			(stroke
				(width 0.1)
				(type default)
			)
			(layer "F.Fab")
		)
		(fp_line
			(start -0.299974 0.150114)
			(end -0.299974 -0.150114)
			(stroke
				(width 0.1)
				(type default)
			)
			(layer "F.Fab")
		)
		(pad "1" smd rect
			(at -0.2667 0 90)
			(size 0.3048 0.381)
			(layers "F.Cu" "F.Mask" "F.Paste")
			(net "P5E_PEX1_STN4_TX_DP<72>")
		)
		(pad "2" smd rect
			(at 0.2667 0 90)
			(size 0.3048 0.381)
			(layers "F.Cu" "F.Mask" "F.Paste")
			(net "P5E_PEX1_STN4_TX_C_DP<72>")
		)
	)
	(footprint ""
		(layer "F.Cu")
		(at 61.82995 -171.661328 180)
		(property "Reference" "C859"
			(at 0 0 180)
			(layer "F.SilkS")
			(hide yes)
			(effects
				(font
					(size 1.27 1.27)
				)
			)
		)
		(property "Value" ""
			(at 0 0 180)
			(layer "F.Fab")
			(effects
				(font
					(size 1.27 1.27)
				)
			)
		)
		(duplicate_pad_numbers_are_jumpers no)
		(fp_line
			(start 0.7874 0.4064)
			(end -0.7874 0.4064)
			(stroke
				(width 0.1524)
				(type default)
			)
			(layer "F.SilkS")
		)
		(fp_line
			(start 0.7874 -0.4064)
			(end 0.7874 0.4064)
			(stroke
				(width 0.1524)
				(type default)
			)
			(layer "F.SilkS")
		)
		(fp_line
			(start -0.7874 0.4064)
			(end -0.7874 -0.4064)
			(stroke
				(width 0.1524)
				(type default)
			)
			(layer "F.SilkS")
		)
		(fp_line
			(start -0.7874 -0.4064)
			(end 0.7874 -0.4064)
			(stroke
				(width 0.1524)
				(type default)
			)
			(layer "F.SilkS")
		)
		(fp_line
			(start 0.67945 0.3048)
			(end 0.120396 0.3048)
			(stroke
				(width 0.1)
				(type default)
			)
			(layer "F.Fab")
		)
		(fp_line
			(start 0.67945 -0.3048)
			(end 0.67945 0.3048)
			(stroke
				(width 0.1)
				(type default)
			)
			(layer "F.Fab")
		)
		(fp_line
			(start 0.12065 -0.2794)
			(end 0.12065 -0.3048)
			(stroke
				(width 0.1)
				(type default)
			)
			(layer "F.Fab")
		)
		(fp_line
			(start 0.12065 -0.3048)
			(end 0.67945 -0.3048)
			(stroke
				(width 0.1)
				(type default)
			)
			(layer "F.Fab")
		)
		(fp_line
			(start 0.120396 0.3048)
			(end 0.120396 0.2794)
			(stroke
				(width 0.1)
				(type default)
			)
			(layer "F.Fab")
		)
		(fp_line
			(start 0.120396 0.2794)
			(end -0.12065 0.2794)
			(stroke
				(width 0.1)
				(type default)
			)
			(layer "F.Fab")
		)
		(fp_line
			(start -0.12065 0.3048)
			(end -0.67945 0.3048)
			(stroke
				(width 0.1)
				(type default)
			)
			(layer "F.Fab")
		)
		(fp_line
			(start -0.12065 0.2794)
			(end -0.12065 0.3048)
			(stroke
				(width 0.1)
				(type default)
			)
			(layer "F.Fab")
		)
		(fp_line
			(start -0.12065 -0.2794)
			(end 0.12065 -0.2794)
			(stroke
				(width 0.1)
				(type default)
			)
			(layer "F.Fab")
		)
		(fp_line
			(start -0.12065 -0.305054)
			(end -0.12065 -0.2794)
			(stroke
				(width 0.1)
				(type default)
			)
			(layer "F.Fab")
		)
		(fp_line
			(start -0.67945 0.3048)
			(end -0.67945 -0.305054)
			(stroke
				(width 0.1)
				(type default)
			)
			(layer "F.Fab")
		)
		(fp_line
			(start -0.67945 -0.305054)
			(end -0.12065 -0.305054)
			(stroke
				(width 0.1)
				(type default)
			)
			(layer "F.Fab")
		)
		(pad "1" smd circle
			(at -0.40005 0 180)
			(size 0 0)
			(layers "F.Cu" "F.Mask" "F.Paste")
			(net "P3V3_NIC0")
		)
		(pad "2" smd circle
			(at 0.40005 0 180)
			(size 0 0)
			(layers "F.Cu" "F.Mask" "F.Paste")
			(net "GND")
		)
	)
	(footprint ""
		(layer "F.Cu")
		(at 311.514744 -81.36001 -90)
		(property "Reference" "R306"
			(at 0 0 270)
			(layer "F.SilkS")
			(hide yes)
			(effects
				(font
					(size 1.27 1.27)
				)
			)
		)
		(property "Value" ""
			(at 0 0 270)
			(layer "F.Fab")
			(effects
				(font
					(size 1.27 1.27)
				)
			)
		)
		(duplicate_pad_numbers_are_jumpers no)
		(fp_line
			(start -0.7874 0.4064)
			(end -0.7874 -0.4064)
			(stroke
				(width 0.1524)
				(type default)
			)
			(layer "F.SilkS")
		)
		(fp_line
			(start 0.7874 0.4064)
			(end -0.7874 0.4064)
			(stroke
				(width 0.1524)
				(type default)
			)
			(layer "F.SilkS")
		)
		(fp_line
			(start -0.7874 -0.4064)
			(end 0.7874 -0.4064)
			(stroke
				(width 0.1524)
				(type default)
			)
			(layer "F.SilkS")
		)
		(fp_line
			(start 0.7874 -0.4064)
			(end 0.7874 0.4064)
			(stroke
				(width 0.1524)
				(type default)
			)
			(layer "F.SilkS")
		)
		(fp_line
			(start -0.67945 0.3048)
			(end -0.67945 -0.305054)
			(stroke
				(width 0.1)
				(type default)
			)
			(layer "F.Fab")
		)
		(fp_line
			(start -0.12065 0.3048)
			(end -0.67945 0.3048)
			(stroke
				(width 0.1)
				(type default)
			)
			(layer "F.Fab")
		)
		(fp_line
			(start 0.120396 0.3048)
			(end 0.120396 0.2794)
			(stroke
				(width 0.1)
				(type default)
			)
			(layer "F.Fab")
		)
		(fp_line
			(start 0.67945 0.3048)
			(end 0.120396 0.3048)
			(stroke
				(width 0.1)
				(type default)
			)
			(layer "F.Fab")
		)
		(fp_line
			(start -0.12065 0.2794)
			(end -0.12065 0.3048)
			(stroke
				(width 0.1)
				(type default)
			)
			(layer "F.Fab")
		)
		(fp_line
			(start 0.120396 0.2794)
			(end -0.12065 0.2794)
			(stroke
				(width 0.1)
				(type default)
			)
			(layer "F.Fab")
		)
		(fp_line
			(start -0.12065 -0.2794)
			(end 0.12065 -0.2794)
			(stroke
				(width 0.1)
				(type default)
			)
			(layer "F.Fab")
		)
		(fp_line
			(start 0.12065 -0.2794)
			(end 0.12065 -0.3048)
			(stroke
				(width 0.1)
				(type default)
			)
			(layer "F.Fab")
		)
		(fp_line
			(start 0.12065 -0.3048)
			(end 0.67945 -0.3048)
			(stroke
				(width 0.1)
				(type default)
			)
			(layer "F.Fab")
		)
		(fp_line
			(start 0.67945 -0.3048)
			(end 0.67945 0.3048)
			(stroke
				(width 0.1)
				(type default)
			)
			(layer "F.Fab")
		)
		(fp_line
			(start -0.67945 -0.305054)
			(end -0.12065 -0.305054)
			(stroke
				(width 0.1)
				(type default)
			)
			(layer "F.Fab")
		)
		(fp_line
			(start -0.12065 -0.305054)
			(end -0.12065 -0.2794)
			(stroke
				(width 0.1)
				(type default)
			)
			(layer "F.Fab")
		)
		(pad "1" smd circle
			(at -0.40005 0 270)
			(size 0 0)
			(layers "F.Cu" "F.Mask" "F.Paste")
			(net "HP_NIC5_PWRGD_R")
		)
		(pad "2" smd circle
			(at 0.40005 0 270)
			(size 0 0)
			(layers "F.Cu" "F.Mask" "F.Paste")
			(net "HP_NIC5_PWRGD")
		)
	)
	(footprint ""
		(layer "F.Cu")
		(at 330.27239 -8.177022 90)
		(property "Reference" "C2734"
			(at 0 0 90)
			(layer "F.SilkS")
			(hide yes)
			(effects
				(font
					(size 1.27 1.27)
				)
			)
		)
		(property "Value" ""
			(at 0 0 90)
			(layer "F.Fab")
			(effects
				(font
					(size 1.27 1.27)
				)
			)
		)
		(duplicate_pad_numbers_are_jumpers no)
		(fp_line
			(start 0.7874 -0.4064)
			(end 0.7874 0.4064)
			(stroke
				(width 0.1524)
				(type default)
			)
			(layer "F.SilkS")
		)
		(fp_line
			(start -0.7874 -0.4064)
			(end 0.7874 -0.4064)
			(stroke
				(width 0.1524)
				(type default)
			)
			(layer "F.SilkS")
		)
		(fp_line
			(start 0.7874 0.4064)
			(end -0.7874 0.4064)
			(stroke
				(width 0.1524)
				(type default)
			)
			(layer "F.SilkS")
		)
		(fp_line
			(start -0.7874 0.4064)
			(end -0.7874 -0.4064)
			(stroke
				(width 0.1524)
				(type default)
			)
			(layer "F.SilkS")
		)
		(fp_line
			(start -0.12065 -0.305054)
			(end -0.12065 -0.2794)
			(stroke
				(width 0.1)
				(type default)
			)
			(layer "F.Fab")
		)
		(fp_line
			(start -0.67945 -0.305054)
			(end -0.12065 -0.305054)
			(stroke
				(width 0.1)
				(type default)
			)
			(layer "F.Fab")
		)
		(fp_line
			(start 0.67945 -0.3048)
			(end 0.67945 0.3048)
			(stroke
				(width 0.1)
				(type default)
			)
			(layer "F.Fab")
		)
		(fp_line
			(start 0.12065 -0.3048)
			(end 0.67945 -0.3048)
			(stroke
				(width 0.1)
				(type default)
			)
			(layer "F.Fab")
		)
		(fp_line
			(start 0.12065 -0.2794)
			(end 0.12065 -0.3048)
			(stroke
				(width 0.1)
				(type default)
			)
			(layer "F.Fab")
		)
		(fp_line
			(start -0.12065 -0.2794)
			(end 0.12065 -0.2794)
			(stroke
				(width 0.1)
				(type default)
			)
			(layer "F.Fab")
		)
		(fp_line
			(start 0.120396 0.2794)
			(end -0.12065 0.2794)
			(stroke
				(width 0.1)
				(type default)
			)
			(layer "F.Fab")
		)
		(fp_line
			(start -0.12065 0.2794)
			(end -0.12065 0.3048)
			(stroke
				(width 0.1)
				(type default)
			)
			(layer "F.Fab")
		)
		(fp_line
			(start 0.67945 0.3048)
			(end 0.120396 0.3048)
			(stroke
				(width 0.1)
				(type default)
			)
			(layer "F.Fab")
		)
		(fp_line
			(start 0.120396 0.3048)
			(end 0.120396 0.2794)
			(stroke
				(width 0.1)
				(type default)
			)
			(layer "F.Fab")
		)
		(fp_line
			(start -0.12065 0.3048)
			(end -0.67945 0.3048)
			(stroke
				(width 0.1)
				(type default)
			)
			(layer "F.Fab")
		)
		(fp_line
			(start -0.67945 0.3048)
			(end -0.67945 -0.305054)
			(stroke
				(width 0.1)
				(type default)
			)
			(layer "F.Fab")
		)
		(pad "1" smd circle
			(at -0.40005 0 90)
			(size 0 0)
			(layers "F.Cu" "F.Mask" "F.Paste")
			(net "GND")
		)
		(pad "2" smd circle
			(at 0.40005 0 90)
			(size 0 0)
			(layers "F.Cu" "F.Mask" "F.Paste")
			(net "P3V3_SSD11")
		)
	)
	(footprint ""
		(layer "F.Cu")
		(at 136.534652 -33.631886 180)
		(property "Reference" "C277"
			(at 0 0 180)
			(layer "F.SilkS")
			(hide yes)
			(effects
				(font
					(size 1.27 1.27)
				)
			)
		)
		(property "Value" ""
			(at 0 0 180)
			(layer "F.Fab")
			(effects
				(font
					(size 1.27 1.27)
				)
			)
		)
		(duplicate_pad_numbers_are_jumpers no)
		(fp_line
			(start 0.299974 0.150114)
			(end -0.299974 0.150114)
			(stroke
				(width 0.1)
				(type default)
			)
			(layer "F.Fab")
		)
		(fp_line
			(start 0.299974 -0.150114)
			(end 0.299974 0.150114)
			(stroke
				(width 0.1)
				(type default)
			)
			(layer "F.Fab")
		)
		(fp_line
			(start -0.299974 0.150114)
			(end -0.299974 -0.150114)
			(stroke
				(width 0.1)
				(type default)
			)
			(layer "F.Fab")
		)
		(fp_line
			(start -0.299974 -0.150114)
			(end 0.299974 -0.150114)
			(stroke
				(width 0.1)
				(type default)
			)
			(layer "F.Fab")
		)
		(pad "1" smd rect
			(at -0.2667 0 180)
			(size 0.3048 0.381)
			(layers "F.Cu" "F.Mask" "F.Paste")
			(net "P5E_PEX1_STN2_TX_DN<47>")
		)
		(pad "2" smd rect
			(at 0.2667 0 180)
			(size 0.3048 0.381)
			(layers "F.Cu" "F.Mask" "F.Paste")
			(net "P5E_PEX1_STN2_TX_C_DN<47>")
		)
	)
	(footprint ""
		(layer "F.Cu")
		(at 427.923452 -356.244906 90)
		(property "Reference" "C807"
			(at 0 0 90)
			(layer "F.SilkS")
			(hide yes)
			(effects
				(font
					(size 1.27 1.27)
				)
			)
		)
		(property "Value" ""
			(at 0 0 90)
			(layer "F.Fab")
			(effects
				(font
					(size 1.27 1.27)
				)
			)
		)
		(duplicate_pad_numbers_are_jumpers no)
		(fp_line
			(start 0.299974 -0.150114)
			(end 0.299974 0.150114)
			(stroke
				(width 0.1)
				(type default)
			)
			(layer "F.Fab")
		)
		(fp_line
			(start -0.299974 -0.150114)
			(end 0.299974 -0.150114)
			(stroke
				(width 0.1)
				(type default)
			)
			(layer "F.Fab")
		)
		(fp_line
			(start 0.299974 0.150114)
			(end -0.299974 0.150114)
			(stroke
				(width 0.1)
				(type default)
			)
			(layer "F.Fab")
		)
		(fp_line
			(start -0.299974 0.150114)
			(end -0.299974 -0.150114)
			(stroke
				(width 0.1)
				(type default)
			)
			(layer "F.Fab")
		)
		(pad "1" smd rect
			(at -0.2667 0 90)
			(size 0.3048 0.381)
			(layers "F.Cu" "F.Mask" "F.Paste")
			(net "P5E_PEX3_STN7_TX_DN<121>")
		)
		(pad "2" smd rect
			(at 0.2667 0 90)
			(size 0.3048 0.381)
			(layers "F.Cu" "F.Mask" "F.Paste")
			(net "P5E_PEX3_STN7_TX_C_DN<121>")
		)
	)
	(footprint ""
		(layer "F.Cu")
		(at 231.844596 -273.471386)
		(property "Reference" "R780"
			(at 0 0 0)
			(layer "F.SilkS")
			(hide yes)
			(effects
				(font
					(size 1.27 1.27)
				)
			)
		)
		(property "Value" ""
			(at 0 0 0)
			(layer "F.Fab")
			(effects
				(font
					(size 1.27 1.27)
				)
			)
		)
		(duplicate_pad_numbers_are_jumpers no)
		(fp_line
			(start -0.7874 -0.4064)
			(end 0.7874 -0.4064)
			(stroke
				(width 0.1524)
				(type default)
			)
			(layer "F.SilkS")
		)
		(fp_line
			(start -0.7874 0.4064)
			(end -0.7874 -0.4064)
			(stroke
				(width 0.1524)
				(type default)
			)
			(layer "F.SilkS")
		)
		(fp_line
			(start 0.7874 -0.4064)
			(end 0.7874 0.4064)
			(stroke
				(width 0.1524)
				(type default)
			)
			(layer "F.SilkS")
		)
		(fp_line
			(start 0.7874 0.4064)
			(end -0.7874 0.4064)
			(stroke
				(width 0.1524)
				(type default)
			)
			(layer "F.SilkS")
		)
		(fp_line
			(start -0.67945 -0.305054)
			(end -0.12065 -0.305054)
			(stroke
				(width 0.1)
				(type default)
			)
			(layer "F.Fab")
		)
		(fp_line
			(start -0.67945 0.3048)
			(end -0.67945 -0.305054)
			(stroke
				(width 0.1)
				(type default)
			)
			(layer "F.Fab")
		)
		(fp_line
			(start -0.12065 -0.305054)
			(end -0.12065 -0.2794)
			(stroke
				(width 0.1)
				(type default)
			)
			(layer "F.Fab")
		)
		(fp_line
			(start -0.12065 -0.2794)
			(end 0.12065 -0.2794)
			(stroke
				(width 0.1)
				(type default)
			)
			(layer "F.Fab")
		)
		(fp_line
			(start -0.12065 0.2794)
			(end -0.12065 0.3048)
			(stroke
				(width 0.1)
				(type default)
			)
			(layer "F.Fab")
		)
		(fp_line
			(start -0.12065 0.3048)
			(end -0.67945 0.3048)
			(stroke
				(width 0.1)
				(type default)
			)
			(layer "F.Fab")
		)
		(fp_line
			(start 0.120396 0.2794)
			(end -0.12065 0.2794)
			(stroke
				(width 0.1)
				(type default)
			)
			(layer "F.Fab")
		)
		(fp_line
			(start 0.120396 0.3048)
			(end 0.120396 0.2794)
			(stroke
				(width 0.1)
				(type default)
			)
			(layer "F.Fab")
		)
		(fp_line
			(start 0.12065 -0.3048)
			(end 0.67945 -0.3048)
			(stroke
				(width 0.1)
				(type default)
			)
			(layer "F.Fab")
		)
		(fp_line
			(start 0.12065 -0.2794)
			(end 0.12065 -0.3048)
			(stroke
				(width 0.1)
				(type default)
			)
			(layer "F.Fab")
		)
		(fp_line
			(start 0.67945 -0.3048)
			(end 0.67945 0.3048)
			(stroke
				(width 0.1)
				(type default)
			)
			(layer "F.Fab")
		)
		(fp_line
			(start 0.67945 0.3048)
			(end 0.120396 0.3048)
			(stroke
				(width 0.1)
				(type default)
			)
			(layer "F.Fab")
		)
		(pad "1" smd circle
			(at -0.40005 0)
			(size 0 0)
			(layers "F.Cu" "F.Mask" "F.Paste")
			(net "PEX1_P1V25_ADC_A1")
		)
		(pad "2" smd circle
			(at 0.40005 0)
			(size 0 0)
			(layers "F.Cu" "F.Mask" "F.Paste")
			(net "P3V3_AUX")
		)
	)
	(footprint ""
		(layer "F.Cu")
		(at 221.251272 -149.054312 180)
		(property "Reference" "R4192"
			(at 0 0 180)
			(layer "F.SilkS")
			(hide yes)
			(effects
				(font
					(size 1.27 1.27)
				)
			)
		)
		(property "Value" ""
			(at 0 0 180)
			(layer "F.Fab")
			(effects
				(font
					(size 1.27 1.27)
				)
			)
		)
		(duplicate_pad_numbers_are_jumpers no)
		(fp_line
			(start 0.7874 0.4064)
			(end -0.7874 0.4064)
			(stroke
				(width 0.1524)
				(type default)
			)
			(layer "F.SilkS")
		)
		(fp_line
			(start 0.7874 -0.4064)
			(end 0.7874 0.4064)
			(stroke
				(width 0.1524)
				(type default)
			)
			(layer "F.SilkS")
		)
		(fp_line
			(start -0.7874 0.4064)
			(end -0.7874 -0.4064)
			(stroke
				(width 0.1524)
				(type default)
			)
			(layer "F.SilkS")
		)
		(fp_line
			(start -0.7874 -0.4064)
			(end 0.7874 -0.4064)
			(stroke
				(width 0.1524)
				(type default)
			)
			(layer "F.SilkS")
		)
		(fp_line
			(start 0.67945 0.3048)
			(end 0.120396 0.3048)
			(stroke
				(width 0.1)
				(type default)
			)
			(layer "F.Fab")
		)
		(fp_line
			(start 0.67945 -0.3048)
			(end 0.67945 0.3048)
			(stroke
				(width 0.1)
				(type default)
			)
			(layer "F.Fab")
		)
		(fp_line
			(start 0.12065 -0.2794)
			(end 0.12065 -0.3048)
			(stroke
				(width 0.1)
				(type default)
			)
			(layer "F.Fab")
		)
		(fp_line
			(start 0.12065 -0.3048)
			(end 0.67945 -0.3048)
			(stroke
				(width 0.1)
				(type default)
			)
			(layer "F.Fab")
		)
		(fp_line
			(start 0.120396 0.3048)
			(end 0.120396 0.2794)
			(stroke
				(width 0.1)
				(type default)
			)
			(layer "F.Fab")
		)
		(fp_line
			(start 0.120396 0.2794)
			(end -0.12065 0.2794)
			(stroke
				(width 0.1)
				(type default)
			)
			(layer "F.Fab")
		)
		(fp_line
			(start -0.12065 0.3048)
			(end -0.67945 0.3048)
			(stroke
				(width 0.1)
				(type default)
			)
			(layer "F.Fab")
		)
		(fp_line
			(start -0.12065 0.2794)
			(end -0.12065 0.3048)
			(stroke
				(width 0.1)
				(type default)
			)
			(layer "F.Fab")
		)
		(fp_line
			(start -0.12065 -0.2794)
			(end 0.12065 -0.2794)
			(stroke
				(width 0.1)
				(type default)
			)
			(layer "F.Fab")
		)
		(fp_line
			(start -0.12065 -0.305054)
			(end -0.12065 -0.2794)
			(stroke
				(width 0.1)
				(type default)
			)
			(layer "F.Fab")
		)
		(fp_line
			(start -0.67945 0.3048)
			(end -0.67945 -0.305054)
			(stroke
				(width 0.1)
				(type default)
			)
			(layer "F.Fab")
		)
		(fp_line
			(start -0.67945 -0.305054)
			(end -0.12065 -0.305054)
			(stroke
				(width 0.1)
				(type default)
			)
			(layer "F.Fab")
		)
		(pad "1" smd circle
			(at -0.40005 0 180)
			(size 0 0)
			(layers "F.Cu" "F.Mask" "F.Paste")
			(net "FM_CK440_PEX_MXCK_25M_100M")
		)
		(pad "2" smd circle
			(at 0.40005 0 180)
			(size 0 0)
			(layers "F.Cu" "F.Mask" "F.Paste")
			(net "P3V3")
		)
	)
	(footprint ""
		(layer "F.Cu")
		(at 194.343782 -48.93691 180)
		(property "Reference" "R578"
			(at 0 0 180)
			(layer "F.SilkS")
			(hide yes)
			(effects
				(font
					(size 1.27 1.27)
				)
			)
		)
		(property "Value" ""
			(at 0 0 180)
			(layer "F.Fab")
			(effects
				(font
					(size 1.27 1.27)
				)
			)
		)
		(duplicate_pad_numbers_are_jumpers no)
		(fp_line
			(start 0.7874 0.4064)
			(end -0.7874 0.4064)
			(stroke
				(width 0.1524)
				(type default)
			)
			(layer "F.SilkS")
		)
		(fp_line
			(start 0.7874 -0.4064)
			(end 0.7874 0.4064)
			(stroke
				(width 0.1524)
				(type default)
			)
			(layer "F.SilkS")
		)
		(fp_line
			(start -0.7874 0.4064)
			(end -0.7874 -0.4064)
			(stroke
				(width 0.1524)
				(type default)
			)
			(layer "F.SilkS")
		)
		(fp_line
			(start -0.7874 -0.4064)
			(end 0.7874 -0.4064)
			(stroke
				(width 0.1524)
				(type default)
			)
			(layer "F.SilkS")
		)
		(fp_line
			(start 0.67945 0.3048)
			(end 0.120396 0.3048)
			(stroke
				(width 0.1)
				(type default)
			)
			(layer "F.Fab")
		)
		(fp_line
			(start 0.67945 -0.3048)
			(end 0.67945 0.3048)
			(stroke
				(width 0.1)
				(type default)
			)
			(layer "F.Fab")
		)
		(fp_line
			(start 0.12065 -0.2794)
			(end 0.12065 -0.3048)
			(stroke
				(width 0.1)
				(type default)
			)
			(layer "F.Fab")
		)
		(fp_line
			(start 0.12065 -0.3048)
			(end 0.67945 -0.3048)
			(stroke
				(width 0.1)
				(type default)
			)
			(layer "F.Fab")
		)
		(fp_line
			(start 0.120396 0.3048)
			(end 0.120396 0.2794)
			(stroke
				(width 0.1)
				(type default)
			)
			(layer "F.Fab")
		)
		(fp_line
			(start 0.120396 0.2794)
			(end -0.12065 0.2794)
			(stroke
				(width 0.1)
				(type default)
			)
			(layer "F.Fab")
		)
		(fp_line
			(start -0.12065 0.3048)
			(end -0.67945 0.3048)
			(stroke
				(width 0.1)
				(type default)
			)
			(layer "F.Fab")
		)
		(fp_line
			(start -0.12065 0.2794)
			(end -0.12065 0.3048)
			(stroke
				(width 0.1)
				(type default)
			)
			(layer "F.Fab")
		)
		(fp_line
			(start -0.12065 -0.2794)
			(end 0.12065 -0.2794)
			(stroke
				(width 0.1)
				(type default)
			)
			(layer "F.Fab")
		)
		(fp_line
			(start -0.12065 -0.305054)
			(end -0.12065 -0.2794)
			(stroke
				(width 0.1)
				(type default)
			)
			(layer "F.Fab")
		)
		(fp_line
			(start -0.67945 0.3048)
			(end -0.67945 -0.305054)
			(stroke
				(width 0.1)
				(type default)
			)
			(layer "F.Fab")
		)
		(fp_line
			(start -0.67945 -0.305054)
			(end -0.12065 -0.305054)
			(stroke
				(width 0.1)
				(type default)
			)
			(layer "F.Fab")
		)
		(pad "1" smd circle
			(at -0.40005 0 180)
			(size 0 0)
			(layers "F.Cu" "F.Mask" "F.Paste")
			(net "SMB_BIC_I2C6_MUX_SSD_0_7_ADC_R_SDA")
		)
		(pad "2" smd circle
			(at 0.40005 0 180)
			(size 0 0)
			(layers "F.Cu" "F.Mask" "F.Paste")
			(net "SMB_SSD6_ADC_SDA")
		)
	)
	(footprint ""
		(layer "F.Cu")
		(at 82.661506 -131.686808 180)
		(property "Reference" "C22"
			(at 0 0 180)
			(layer "F.SilkS")
			(hide yes)
			(effects
				(font
					(size 1.27 1.27)
				)
			)
		)
		(property "Value" ""
			(at 0 0 180)
			(layer "F.Fab")
			(effects
				(font
					(size 1.27 1.27)
				)
			)
		)
		(duplicate_pad_numbers_are_jumpers no)
		(fp_line
			(start 0.299974 0.150114)
			(end -0.299974 0.150114)
			(stroke
				(width 0.1)
				(type default)
			)
			(layer "F.Fab")
		)
		(fp_line
			(start 0.299974 -0.150114)
			(end 0.299974 0.150114)
			(stroke
				(width 0.1)
				(type default)
			)
			(layer "F.Fab")
		)
		(fp_line
			(start -0.299974 0.150114)
			(end -0.299974 -0.150114)
			(stroke
				(width 0.1)
				(type default)
			)
			(layer "F.Fab")
		)
		(fp_line
			(start -0.299974 -0.150114)
			(end 0.299974 -0.150114)
			(stroke
				(width 0.1)
				(type default)
			)
			(layer "F.Fab")
		)
		(pad "1" smd rect
			(at -0.2667 0 180)
			(size 0.3048 0.381)
			(layers "F.Cu" "F.Mask" "F.Paste")
			(net "P5E_PEX0_STN0_TX_DN<5>")
		)
		(pad "2" smd rect
			(at 0.2667 0 180)
			(size 0.3048 0.381)
			(layers "F.Cu" "F.Mask" "F.Paste")
			(net "P5E_PEX0_STN0_TX_C_DN<5>")
		)
	)
	(footprint ""
		(layer "F.Cu")
		(at 27.910028 -412.090108)
		(property "Reference" "J3"
			(at 26.184352 2.518918 90)
			(unlocked yes)
			(layer "F.SilkS")
			(effects
				(font
					(size 2.032 1.524)
					(thickness 0.1524)
				)
				(justify left)
			)
		)
		(property "Value" ""
			(at 0 0 0)
			(layer "F.Fab")
			(effects
				(font
					(size 1.27 1.27)
				)
			)
		)
		(duplicate_pad_numbers_are_jumpers no)
		(fp_line
			(start -4.249928 -16.999966)
			(end 24.45004 -16.999966)
			(stroke
				(width 0.1524)
				(type default)
			)
			(layer "F.SilkS")
		)
		(fp_line
			(start -4.249928 50.099976)
			(end -4.249928 -16.999966)
			(stroke
				(width 0.1524)
				(type default)
			)
			(layer "F.SilkS")
		)
		(fp_line
			(start -1.249934 -13.999972)
			(end -1.249934 47.099982)
			(stroke
				(width 0.1524)
				(type default)
			)
			(layer "F.SilkS")
		)
		(fp_line
			(start -1.249934 -6.500114)
			(end 21.450046 -6.500114)
			(stroke
				(width 0.1524)
				(type default)
			)
			(layer "F.SilkS")
		)
		(fp_line
			(start -1.249934 47.099982)
			(end 21.450046 47.099982)
			(stroke
				(width 0.1524)
				(type default)
			)
			(layer "F.SilkS")
		)
		(fp_line
			(start 21.450046 -13.999972)
			(end -1.249934 -13.999972)
			(stroke
				(width 0.1524)
				(type default)
			)
			(layer "F.SilkS")
		)
		(fp_line
			(start 21.450046 47.099982)
			(end 21.450046 -13.999972)
			(stroke
				(width 0.1524)
				(type default)
			)
			(layer "F.SilkS")
		)
		(fp_line
			(start 24.45004 -16.999966)
			(end 24.45004 50.099976)
			(stroke
				(width 0.1524)
				(type default)
			)
			(layer "F.SilkS")
		)
		(fp_line
			(start 24.45004 50.099976)
			(end -4.249928 50.099976)
			(stroke
				(width 0.1524)
				(type default)
			)
			(layer "F.SilkS")
		)
		(fp_poly
			(pts
				(xy -2.413 -0.508) (xy -2.413 0.508) (xy -1.397 0)
			)
			(stroke
				(width 0)
				(type default)
			)
			(fill yes)
			(layer "F.SilkS")
		)
		(fp_line
			(start -4.249928 -16.999966)
			(end 24.45004 -16.999966)
			(stroke
				(width 0.1524)
				(type default)
			)
			(layer "B.SilkS")
		)
		(fp_line
			(start -4.249928 50.099976)
			(end -4.249928 -16.999966)
			(stroke
				(width 0.1524)
				(type default)
			)
			(layer "B.SilkS")
		)
		(fp_line
			(start 13.209016 50.099976)
			(end -4.249928 50.099976)
			(stroke
				(width 0.1524)
				(type default)
			)
			(layer "B.SilkS")
		)
		(fp_line
			(start 18.697956 50.099976)
			(end 15.99819 50.099976)
			(stroke
				(width 0.1524)
				(type default)
			)
			(layer "B.SilkS")
		)
		(fp_line
			(start 24.45004 -16.999966)
			(end 24.45004 18.71472)
			(stroke
				(width 0.1524)
				(type default)
			)
			(layer "B.SilkS")
		)
		(fp_line
			(start 24.45004 20.052792)
			(end 24.45004 50.099976)
			(stroke
				(width 0.1524)
				(type default)
			)
			(layer "B.SilkS")
		)
		(fp_line
			(start 24.45004 50.099976)
			(end 19.989038 50.099976)
			(stroke
				(width 0.1524)
				(type default)
			)
			(layer "B.SilkS")
		)
		(fp_line
			(start -4.249928 -16.999966)
			(end 24.45004 -16.999966)
			(stroke
				(width 0.1)
				(type default)
			)
			(layer "B.Fab")
		)
		(fp_line
			(start -4.249928 50.099976)
			(end -4.249928 -16.999966)
			(stroke
				(width 0.1)
				(type default)
			)
			(layer "B.Fab")
		)
		(fp_line
			(start 24.45004 -16.999966)
			(end 24.45004 50.099976)
			(stroke
				(width 0.1)
				(type default)
			)
			(layer "B.Fab")
		)
		(fp_line
			(start 24.45004 50.099976)
			(end -4.249928 50.099976)
			(stroke
				(width 0.1)
				(type default)
			)
			(layer "B.Fab")
		)
		(fp_line
			(start -1.249934 -13.999972)
			(end -1.249934 47.099982)
			(stroke
				(width 0.1)
				(type default)
			)
			(layer "F.Fab")
		)
		(fp_line
			(start -1.249934 47.099982)
			(end 21.450046 47.099982)
			(stroke
				(width 0.1)
				(type default)
			)
			(layer "F.Fab")
		)
		(fp_line
			(start 21.450046 -13.999972)
			(end -1.249934 -13.999972)
			(stroke
				(width 0.1)
				(type default)
			)
			(layer "F.Fab")
		)
		(fp_line
			(start 21.450046 47.099982)
			(end 21.450046 -13.999972)
			(stroke
				(width 0.1)
				(type default)
			)
			(layer "F.Fab")
		)
		(fp_poly
			(pts
				(xy -2.413 -0.508) (xy -2.413 0.508) (xy -1.397 0)
			)
			(stroke
				(width 0)
				(type default)
			)
			(fill yes)
			(layer "F.Fab")
		)
		(fp_text user "PRESS-FIT"
			(at 23.213314 43.650154 90)
			(unlocked yes)
			(layer "F.SilkS")
			(effects
				(font
					(size 1.905 1.4224)
					(thickness 0.1524)
				)
				(justify left)
			)
		)
		(fp_text user "PRESS-FIT"
			(at -5.674868 27.35961 90)
			(unlocked yes)
			(layer "B.SilkS")
			(effects
				(font
					(size 1.905 1.4224)
					(thickness 0.1524)
				)
				(justify left mirror)
			)
		)
		(fp_text user "PRESS-FIT"
			(at 18.326862 48.74895 0)
			(unlocked yes)
			(layer "B.Fab")
			(effects
				(font
					(size 1.905 1.4224)
					(thickness 0.1524)
				)
				(justify left mirror)
			)
		)
		(fp_text user "PRESS-FIT"
			(at 1.5875 48.73625 0)
			(unlocked yes)
			(layer "F.Fab")
			(effects
				(font
					(size 1.905 1.4224)
					(thickness 0.1524)
				)
				(justify left)
			)
		)
		(pad "A1" thru_hole rect
			(at 0 0 180)
			(size 0.71628 0.71628)
			(drill 0.30988)
			(layers "*.Cu" "*.Mask")
			(remove_unused_layers no)
			(net "RST_GPU_PERST_2_BUF_R_N")
			(clearance 0.0508)
			(thermal_gap 0.0508)
			(padstack
				(mode front_inner_back)
				(layer "Inner"
					(shape circle)
					(size 0.71628 0.71628)
					(clearance 0.0508)
				)
				(layer "B.Cu"
					(shape rect)
					(size 0.71628 0.71628)
					(clearance 0.0508)
				)
			)
		)
		(pad "A2" thru_hole circle
			(at 2.199894 0.199898 180)
			(size 0.906272 0.906272)
			(drill 0.499872)
			(layers "*.Cu" "*.Mask")
			(remove_unused_layers no)
			(net "GND")
			(clearance 0.0508)
			(thermal_gap 0.0508)
		)
		(pad "A3" thru_hole circle
			(at 4.400042 0 180)
			(size 0.71628 0.71628)
			(drill 0.30988)
			(layers "*.Cu" "*.Mask")
			(remove_unused_layers no)
			(net "GPU_HGX_DETECT_N")
			(clearance 0.0508)
			(thermal_gap 0.0508)
		)
		(pad "A4" thru_hole circle
			(at 6.599936 0.199898 180)
			(size 0.906272 0.906272)
			(drill 0.499872)
			(layers "*.Cu" "*.Mask")
			(remove_unused_layers no)
			(net "GND")
			(clearance 0.0508)
			(thermal_gap 0.0508)
		)
		(pad "A5" thru_hole circle
			(at 8.800084 0 180)
			(size 0.71628 0.71628)
			(drill 0.30988)
			(layers "*.Cu" "*.Mask")
			(remove_unused_layers no)
			(net "RST_GPU_PERST_1_BUF_R_N")
			(clearance 0.0508)
			(thermal_gap 0.0508)
		)
		(pad "A6" thru_hole circle
			(at 10.999978 0.199898 180)
			(size 0.906272 0.906272)
			(drill 0.499872)
			(layers "*.Cu" "*.Mask")
			(remove_unused_layers no)
			(net "GND")
			(clearance 0.0508)
			(thermal_gap 0.0508)
		)
		(pad "A7" thru_hole circle
			(at 13.199872 0 180)
			(size 0.71628 0.71628)
			(drill 0.30988)
			(layers "*.Cu" "*.Mask")
			(remove_unused_layers no)
			(net "PRSNT_GPU_N")
			(clearance 0.0508)
			(thermal_gap 0.0508)
		)
		(pad "A8" thru_hole circle
			(at 15.40002 0.199898 180)
			(size 0.906272 0.906272)
			(drill 0.499872)
			(layers "*.Cu" "*.Mask")
			(remove_unused_layers no)
			(net "GND")
			(clearance 0.0508)
			(thermal_gap 0.0508)
		)
		(pad "A9" thru_hole circle
			(at 17.599914 0 180)
			(size 0.71628 0.71628)
			(drill 0.30988)
			(layers "*.Cu" "*.Mask")
			(remove_unused_layers no)
			(net "RST_GPU_FPGA_PEX_RST_R_N")
			(clearance 0.0508)
			(thermal_gap 0.0508)
		)
		(pad "A10" thru_hole circle
			(at 19.800062 0.199898 180)
			(size 0.906272 0.906272)
			(drill 0.499872)
			(layers "*.Cu" "*.Mask")
			(remove_unused_layers no)
			(net "GND")
			(clearance 0.0508)
			(thermal_gap 0.0508)
		)
		(pad "B1" thru_hole circle
			(at 0 1.299972 180)
			(size 0.906272 0.906272)
			(drill 0.499872)
			(layers "*.Cu" "*.Mask")
			(remove_unused_layers no)
			(net "GND")
			(clearance 0.0508)
			(thermal_gap 0.0508)
		)
		(pad "B3" thru_hole circle
			(at 4.400042 1.299972 180)
			(size 0.906272 0.906272)
			(drill 0.499872)
			(layers "*.Cu" "*.Mask")
			(remove_unused_layers no)
			(net "GND")
			(clearance 0.0508)
			(thermal_gap 0.0508)
		)
		(pad "B5" thru_hole circle
			(at 8.800084 1.299972 180)
			(size 0.906272 0.906272)
			(drill 0.499872)
			(layers "*.Cu" "*.Mask")
			(remove_unused_layers no)
			(net "GND")
			(clearance 0.0508)
			(thermal_gap 0.0508)
		)
		(pad "B7" thru_hole circle
			(at 13.199872 1.299972 180)
			(size 0.906272 0.906272)
			(drill 0.499872)
			(layers "*.Cu" "*.Mask")
			(remove_unused_layers no)
			(net "GND")
			(clearance 0.0508)
			(thermal_gap 0.0508)
		)
		(pad "B9" thru_hole circle
			(at 17.599914 1.299972 180)
			(size 0.906272 0.906272)
			(drill 0.499872)
			(layers "*.Cu" "*.Mask")
			(remove_unused_layers no)
			(net "GND")
			(clearance 0.0508)
			(thermal_gap 0.0508)
		)
		(pad "C9" thru_hole circle
			(at 17.599914 2.599944 180)
			(size 0.71628 0.71628)
			(drill 0.30988)
			(layers "*.Cu" "*.Mask")
			(remove_unused_layers no)
			(net "GPU_THERM_OVERT_N")
			(clearance 0.0508)
			(thermal_gap 0.0508)
		)
		(pad "D2" thru_hole circle
			(at 2.199894 4.100068 180)
			(size 0.906272 0.906272)
			(drill 0.499872)
			(layers "*.Cu" "*.Mask")
			(remove_unused_layers no)
			(net "GND")
			(clearance 0.0508)
			(thermal_gap 0.0508)
		)
		(pad "D4" thru_hole circle
			(at 6.599936 4.100068 180)
			(size 0.906272 0.906272)
			(drill 0.499872)
			(layers "*.Cu" "*.Mask")
			(remove_unused_layers no)
			(net "GND")
			(clearance 0.0508)
			(thermal_gap 0.0508)
		)
		(pad "D6" thru_hole circle
			(at 10.999978 4.100068 180)
			(size 0.906272 0.906272)
			(drill 0.499872)
			(layers "*.Cu" "*.Mask")
			(remove_unused_layers no)
			(net "GND")
			(clearance 0.0508)
			(thermal_gap 0.0508)
		)
		(pad "D8" thru_hole circle
			(at 15.40002 4.100068 180)
			(size 0.906272 0.906272)
			(drill 0.499872)
			(layers "*.Cu" "*.Mask")
			(remove_unused_layers no)
			(net "GND")
			(clearance 0.0508)
			(thermal_gap 0.0508)
		)
		(pad "D9" thru_hole circle
			(at 17.599914 3.899916 180)
			(size 0.71628 0.71628)
			(drill 0.30988)
			(layers "*.Cu" "*.Mask")
			(remove_unused_layers no)
			(net "GPU_PEX_STRAP0_R")
			(clearance 0.0508)
			(thermal_gap 0.0508)
		)
		(pad "D10" thru_hole circle
			(at 19.800062 4.100068 180)
			(size 0.906272 0.906272)
			(drill 0.499872)
			(layers "*.Cu" "*.Mask")
			(remove_unused_layers no)
			(net "GND")
			(clearance 0.0508)
			(thermal_gap 0.0508)
		)
		(pad "E1" thru_hole circle
			(at 0 5.199888 180)
			(size 0.906272 0.906272)
			(drill 0.499872)
			(layers "*.Cu" "*.Mask")
			(remove_unused_layers no)
			(net "GND")
			(clearance 0.0508)
			(thermal_gap 0.0508)
		)
		(pad "E3" thru_hole circle
			(at 4.400042 5.199888 180)
			(size 0.906272 0.906272)
			(drill 0.499872)
			(layers "*.Cu" "*.Mask")
			(remove_unused_layers no)
			(net "GND")
			(clearance 0.0508)
			(thermal_gap 0.0508)
		)
		(pad "E5" thru_hole circle
			(at 8.800084 5.199888 180)
			(size 0.906272 0.906272)
			(drill 0.499872)
			(layers "*.Cu" "*.Mask")
			(remove_unused_layers no)
			(net "GND")
			(clearance 0.0508)
			(thermal_gap 0.0508)
		)
		(pad "E7" thru_hole circle
			(at 13.199872 5.199888 180)
			(size 0.906272 0.906272)
			(drill 0.499872)
			(layers "*.Cu" "*.Mask")
			(remove_unused_layers no)
			(net "GND")
			(clearance 0.0508)
			(thermal_gap 0.0508)
		)
		(pad "E9" thru_hole circle
			(at 17.599914 5.199888 180)
			(size 0.906272 0.906272)
			(drill 0.499872)
			(layers "*.Cu" "*.Mask")
			(remove_unused_layers no)
			(net "GND")
			(clearance 0.0508)
			(thermal_gap 0.0508)
		)
		(pad "F9" thru_hole circle
			(at 17.599914 6.500114 180)
			(size 0.71628 0.71628)
			(drill 0.30988)
			(layers "*.Cu" "*.Mask")
			(remove_unused_layers no)
			(net "GPU_PWR_BRAKE_R_N")
			(clearance 0.0508)
			(thermal_gap 0.0508)
		)
		(pad "G2" thru_hole circle
			(at 2.199894 7.999984 180)
			(size 0.906272 0.906272)
			(drill 0.499872)
			(layers "*.Cu" "*.Mask")
			(remove_unused_layers no)
			(net "GND")
			(clearance 0.0508)
			(thermal_gap 0.0508)
		)
		(pad "G4" thru_hole circle
			(at 6.599936 7.999984 180)
			(size 0.906272 0.906272)
			(drill 0.499872)
			(layers "*.Cu" "*.Mask")
			(remove_unused_layers no)
			(net "GND")
			(clearance 0.0508)
			(thermal_gap 0.0508)
		)
		(pad "G6" thru_hole circle
			(at 10.999978 7.999984 180)
			(size 0.906272 0.906272)
			(drill 0.499872)
			(layers "*.Cu" "*.Mask")
			(remove_unused_layers no)
			(net "GND")
			(clearance 0.0508)
			(thermal_gap 0.0508)
		)
		(pad "G8" thru_hole circle
			(at 15.40002 7.999984 180)
			(size 0.906272 0.906272)
			(drill 0.499872)
			(layers "*.Cu" "*.Mask")
			(remove_unused_layers no)
			(net "GND")
			(clearance 0.0508)
			(thermal_gap 0.0508)
		)
		(pad "G9" thru_hole circle
			(at 17.599914 7.800086 180)
			(size 0.71628 0.71628)
			(drill 0.30988)
			(layers "*.Cu" "*.Mask")
			(remove_unused_layers no)
			(net "GPU_BASE_ID0_R")
			(clearance 0.0508)
			(thermal_gap 0.0508)
		)
		(pad "G10" thru_hole circle
			(at 19.800062 7.999984 180)
			(size 0.906272 0.906272)
			(drill 0.499872)
			(layers "*.Cu" "*.Mask")
			(remove_unused_layers no)
			(net "GND")
			(clearance 0.0508)
			(thermal_gap 0.0508)
		)
		(pad "H1" thru_hole circle
			(at 0 9.100058 180)
			(size 0.906272 0.906272)
			(drill 0.499872)
			(layers "*.Cu" "*.Mask")
			(remove_unused_layers no)
			(net "GND")
			(clearance 0.0508)
			(thermal_gap 0.0508)
		)
		(pad "H3" thru_hole circle
			(at 4.400042 9.100058 180)
			(size 0.906272 0.906272)
			(drill 0.499872)
			(layers "*.Cu" "*.Mask")
			(remove_unused_layers no)
			(net "GND")
			(clearance 0.0508)
			(thermal_gap 0.0508)
		)
		(pad "H5" thru_hole circle
			(at 8.800084 9.100058 180)
			(size 0.906272 0.906272)
			(drill 0.499872)
			(layers "*.Cu" "*.Mask")
			(remove_unused_layers no)
			(net "GND")
			(clearance 0.0508)
			(thermal_gap 0.0508)
		)
		(pad "H7" thru_hole circle
			(at 13.199872 9.100058 180)
			(size 0.906272 0.906272)
			(drill 0.499872)
			(layers "*.Cu" "*.Mask")
			(remove_unused_layers no)
			(net "GND")
			(clearance 0.0508)
			(thermal_gap 0.0508)
		)
		(pad "H9" thru_hole circle
			(at 17.599914 9.100058 180)
			(size 0.906272 0.906272)
			(drill 0.499872)
			(layers "*.Cu" "*.Mask")
			(remove_unused_layers no)
			(net "GND")
			(clearance 0.0508)
			(thermal_gap 0.0508)
		)
		(pad "H10" thru_hole circle
			(at 19.800062 9.299956 180)
			(size 0.71628 0.71628)
			(drill 0.30988)
			(layers "*.Cu" "*.Mask")
			(remove_unused_layers no)
			(net "GPU_BASE_FPGA_READY")
			(clearance 0.0508)
			(thermal_gap 0.0508)
		)
		(pad "I9" thru_hole circle
			(at 17.599914 10.40003 180)
			(size 0.71628 0.71628)
			(drill 0.30988)
			(layers "*.Cu" "*.Mask")
			(remove_unused_layers no)
			(net "CLK_100M_DB2000QL_GPU_REF2_R_DN")
			(clearance 0.0508)
			(thermal_gap 0.0508)
		)
		(pad "I10" thru_hole circle
			(at 19.800062 10.599928 180)
			(size 0.71628 0.71628)
			(drill 0.30988)
			(layers "*.Cu" "*.Mask")
			(remove_unused_layers no)
			(net "GPU_PEX_STRAP1_R")
			(clearance 0.0508)
			(thermal_gap 0.0508)
		)
		(pad "J2" thru_hole circle
			(at 2.199894 11.8999 180)
			(size 0.906272 0.906272)
			(drill 0.499872)
			(layers "*.Cu" "*.Mask")
			(remove_unused_layers no)
			(net "GND")
			(clearance 0.0508)
			(thermal_gap 0.0508)
		)
		(pad "J4" thru_hole circle
			(at 6.599936 11.8999 180)
			(size 0.906272 0.906272)
			(drill 0.499872)
			(layers "*.Cu" "*.Mask")
			(remove_unused_layers no)
			(net "GND")
			(clearance 0.0508)
			(thermal_gap 0.0508)
		)
		(pad "J6" thru_hole circle
			(at 10.999978 11.8999 180)
			(size 0.906272 0.906272)
			(drill 0.499872)
			(layers "*.Cu" "*.Mask")
			(remove_unused_layers no)
			(net "GND")
			(clearance 0.0508)
			(thermal_gap 0.0508)
		)
		(pad "J8" thru_hole circle
			(at 15.40002 11.8999 180)
			(size 0.906272 0.906272)
			(drill 0.499872)
			(layers "*.Cu" "*.Mask")
			(remove_unused_layers no)
			(net "GND")
			(clearance 0.0508)
			(thermal_gap 0.0508)
		)
		(pad "J9" thru_hole circle
			(at 17.599914 11.700002 180)
			(size 0.71628 0.71628)
			(drill 0.30988)
			(layers "*.Cu" "*.Mask")
			(remove_unused_layers no)
			(net "CLK_100M_DB2000QL_GPU_REF2_R_DP")
			(clearance 0.0508)
			(thermal_gap 0.0508)
		)
		(pad "J10" thru_hole circle
			(at 19.800062 11.8999 180)
			(size 0.906272 0.906272)
			(drill 0.499872)
			(layers "*.Cu" "*.Mask")
			(remove_unused_layers no)
			(net "GND")
			(clearance 0.0508)
			(thermal_gap 0.0508)
		)
		(pad "K1" thru_hole circle
			(at 0 12.999974 180)
			(size 0.906272 0.906272)
			(drill 0.499872)
			(layers "*.Cu" "*.Mask")
			(remove_unused_layers no)
			(net "GND")
			(clearance 0.0508)
			(thermal_gap 0.0508)
		)
		(pad "K3" thru_hole circle
			(at 4.400042 12.999974 180)
			(size 0.906272 0.906272)
			(drill 0.499872)
			(layers "*.Cu" "*.Mask")
			(remove_unused_layers no)
			(net "GND")
			(clearance 0.0508)
			(thermal_gap 0.0508)
		)
		(pad "K5" thru_hole circle
			(at 8.800084 12.999974 180)
			(size 0.906272 0.906272)
			(drill 0.499872)
			(layers "*.Cu" "*.Mask")
			(remove_unused_layers no)
			(net "GND")
			(clearance 0.0508)
			(thermal_gap 0.0508)
		)
		(pad "K7" thru_hole circle
			(at 13.199872 12.999974 180)
			(size 0.906272 0.906272)
			(drill 0.499872)
			(layers "*.Cu" "*.Mask")
			(remove_unused_layers no)
			(net "GND")
			(clearance 0.0508)
			(thermal_gap 0.0508)
		)
		(pad "K9" thru_hole circle
			(at 17.599914 12.999974 180)
			(size 0.906272 0.906272)
			(drill 0.499872)
			(layers "*.Cu" "*.Mask")
			(remove_unused_layers no)
			(net "GND")
			(clearance 0.0508)
			(thermal_gap 0.0508)
		)
		(pad "K10" thru_hole circle
			(at 19.800062 13.199872 180)
			(size 0.71628 0.71628)
			(drill 0.30988)
			(layers "*.Cu" "*.Mask")
			(remove_unused_layers no)
			(net "CLK_100M_GPU_FPGA_REF_DN")
			(clearance 0.0508)
			(thermal_gap 0.0508)
		)
		(pad "L9" thru_hole circle
			(at 17.599914 14.299946 180)
			(size 0.71628 0.71628)
			(drill 0.30988)
			(layers "*.Cu" "*.Mask")
			(remove_unused_layers no)
			(net "USB2_GPU_HMC_DN")
			(clearance 0.0508)
			(thermal_gap 0.0508)
		)
		(pad "L10" thru_hole circle
			(at 19.800062 14.500098 180)
			(size 0.71628 0.71628)
			(drill 0.30988)
			(layers "*.Cu" "*.Mask")
			(remove_unused_layers no)
			(net "CLK_100M_GPU_FPGA_REF_DP")
			(clearance 0.0508)
			(thermal_gap 0.0508)
		)
		(pad "M1_2" thru_hole circle
			(at 2.199894 15.80007 180)
			(size 0.906272 0.906272)
			(drill 0.499872)
			(layers "*.Cu" "*.Mask")
			(remove_unused_layers no)
			(net "GND")
			(clearance 0.0508)
			(thermal_gap 0.0508)
		)
		(pad "M1_4" thru_hole circle
			(at 6.599936 15.80007 180)
			(size 0.906272 0.906272)
			(drill 0.499872)
			(layers "*.Cu" "*.Mask")
			(remove_unused_layers no)
			(net "GND")
			(clearance 0.0508)
			(thermal_gap 0.0508)
		)
		(pad "M1_6" thru_hole circle
			(at 10.999978 15.80007 180)
			(size 0.906272 0.906272)
			(drill 0.499872)
			(layers "*.Cu" "*.Mask")
			(remove_unused_layers no)
			(net "GND")
			(clearance 0.0508)
			(thermal_gap 0.0508)
		)
		(pad "M1_8" thru_hole circle
			(at 15.40002 15.80007 180)
			(size 0.906272 0.906272)
			(drill 0.499872)
			(layers "*.Cu" "*.Mask")
			(remove_unused_layers no)
			(net "GND")
			(clearance 0.0508)
			(thermal_gap 0.0508)
		)
		(pad "M1_10" thru_hole circle
			(at 19.800062 15.80007 180)
			(size 0.906272 0.906272)
			(drill 0.499872)
			(layers "*.Cu" "*.Mask")
			(remove_unused_layers no)
			(net "GND")
			(clearance 0.0508)
			(thermal_gap 0.0508)
		)
		(pad "M2_2" thru_hole circle
			(at 2.199894 26.2001 180)
			(size 0.906272 0.906272)
			(drill 0.499872)
			(layers "*.Cu" "*.Mask")
			(remove_unused_layers no)
			(net "GND")
			(clearance 0.0508)
			(thermal_gap 0.0508)
		)
		(pad "M2_4" thru_hole circle
			(at 6.599936 26.2001 180)
			(size 0.906272 0.906272)
			(drill 0.499872)
			(layers "*.Cu" "*.Mask")
			(remove_unused_layers no)
			(net "GND")
			(clearance 0.0508)
			(thermal_gap 0.0508)
		)
		(pad "M2_6" thru_hole circle
			(at 10.999978 26.2001 180)
			(size 0.906272 0.906272)
			(drill 0.499872)
			(layers "*.Cu" "*.Mask")
			(remove_unused_layers no)
			(net "GND")
			(clearance 0.0508)
			(thermal_gap 0.0508)
		)
		(pad "M2_8" thru_hole circle
			(at 15.40002 26.2001 180)
			(size 0.906272 0.906272)
			(drill 0.499872)
			(layers "*.Cu" "*.Mask")
			(remove_unused_layers no)
			(net "GND")
			(clearance 0.0508)
			(thermal_gap 0.0508)
		)
		(pad "M2_10" thru_hole circle
			(at 19.800062 26.2001 180)
			(size 0.906272 0.906272)
			(drill 0.499872)
			(layers "*.Cu" "*.Mask")
			(remove_unused_layers no)
			(net "GND")
			(clearance 0.0508)
			(thermal_gap 0.0508)
		)
		(pad "M9" thru_hole circle
			(at 17.599914 15.599918 180)
			(size 0.71628 0.71628)
			(drill 0.30988)
			(layers "*.Cu" "*.Mask")
			(remove_unused_layers no)
			(net "USB2_GPU_HMC_DP")
			(clearance 0.0508)
			(thermal_gap 0.0508)
		)
		(pad "N1_1" thru_hole circle
			(at 0 16.89989 180)
			(size 0.906272 0.906272)
			(drill 0.499872)
			(layers "*.Cu" "*.Mask")
			(remove_unused_layers no)
			(net "GND")
			(clearance 0.0508)
			(thermal_gap 0.0508)
		)
		(pad "N1_3" thru_hole circle
			(at 4.400042 16.89989 180)
			(size 0.906272 0.906272)
			(drill 0.499872)
			(layers "*.Cu" "*.Mask")
			(remove_unused_layers no)
			(net "GND")
			(clearance 0.0508)
			(thermal_gap 0.0508)
		)
		(pad "N1_5" thru_hole circle
			(at 8.800084 16.89989 180)
			(size 0.906272 0.906272)
			(drill 0.499872)
			(layers "*.Cu" "*.Mask")
			(remove_unused_layers no)
			(net "GND")
			(clearance 0.0508)
			(thermal_gap 0.0508)
		)
		(pad "N1_7" thru_hole circle
			(at 13.199872 16.89989 180)
			(size 0.906272 0.906272)
			(drill 0.499872)
			(layers "*.Cu" "*.Mask")
			(remove_unused_layers no)
			(net "GND")
			(clearance 0.0508)
			(thermal_gap 0.0508)
		)
		(pad "N1_9" thru_hole circle
			(at 17.599914 16.89989 180)
			(size 0.906272 0.906272)
			(drill 0.499872)
			(layers "*.Cu" "*.Mask")
			(remove_unused_layers no)
			(net "GND")
			(clearance 0.0508)
			(thermal_gap 0.0508)
		)
		(pad "N2_1" thru_hole circle
			(at 0 27.29992 180)
			(size 0.906272 0.906272)
			(drill 0.499872)
			(layers "*.Cu" "*.Mask")
			(remove_unused_layers no)
			(net "GND")
			(clearance 0.0508)
			(thermal_gap 0.0508)
		)
		(pad "N2_3" thru_hole circle
			(at 4.400042 27.29992 180)
			(size 0.906272 0.906272)
			(drill 0.499872)
			(layers "*.Cu" "*.Mask")
			(remove_unused_layers no)
			(net "GND")
			(clearance 0.0508)
			(thermal_gap 0.0508)
		)
		(pad "N2_5" thru_hole circle
			(at 8.800084 27.29992 180)
			(size 0.906272 0.906272)
			(drill 0.499872)
			(layers "*.Cu" "*.Mask")
			(remove_unused_layers no)
			(net "GND")
			(clearance 0.0508)
			(thermal_gap 0.0508)
		)
		(pad "N2_7" thru_hole circle
			(at 13.199872 27.29992 180)
			(size 0.906272 0.906272)
			(drill 0.499872)
			(layers "*.Cu" "*.Mask")
			(remove_unused_layers no)
			(net "GND")
			(clearance 0.0508)
			(thermal_gap 0.0508)
		)
		(pad "N2_9" thru_hole circle
			(at 17.599914 27.29992 180)
			(size 0.906272 0.906272)
			(drill 0.499872)
			(layers "*.Cu" "*.Mask")
			(remove_unused_layers no)
			(net "GND")
			(clearance 0.0508)
			(thermal_gap 0.0508)
		)
		(pad "N10" thru_hole circle
			(at 19.800062 27.500072 180)
			(size 0.71628 0.71628)
			(drill 0.30988)
			(layers "*.Cu" "*.Mask")
			(remove_unused_layers no)
			(net "CLK_100M_DB2000QL_GPU_REF1_R_DN")
			(clearance 0.0508)
			(thermal_gap 0.0508)
		)
		(pad "O9" thru_hole circle
			(at 17.599914 28.599892 180)
			(size 0.71628 0.71628)
			(drill 0.30988)
			(layers "*.Cu" "*.Mask")
			(remove_unused_layers no)
			(net "CLK_100M_DB2000QL_GPU_REF0_R_DN")
			(clearance 0.0508)
			(thermal_gap 0.0508)
		)
		(pad "O10" thru_hole circle
			(at 19.800062 28.800044 180)
			(size 0.71628 0.71628)
			(drill 0.30988)
			(layers "*.Cu" "*.Mask")
			(remove_unused_layers no)
			(net "CLK_100M_DB2000QL_GPU_REF1_R_DP")
			(clearance 0.0508)
			(thermal_gap 0.0508)
		)
		(pad "P2" thru_hole circle
			(at 2.199894 30.100016 180)
			(size 0.906272 0.906272)
			(drill 0.499872)
			(layers "*.Cu" "*.Mask")
			(remove_unused_layers no)
			(net "GND")
			(clearance 0.0508)
			(thermal_gap 0.0508)
		)
		(pad "P4" thru_hole circle
			(at 6.599936 30.100016 180)
			(size 0.906272 0.906272)
			(drill 0.499872)
			(layers "*.Cu" "*.Mask")
			(remove_unused_layers no)
			(net "GND")
			(clearance 0.0508)
			(thermal_gap 0.0508)
		)
		(pad "P6" thru_hole circle
			(at 10.999978 30.100016 180)
			(size 0.906272 0.906272)
			(drill 0.499872)
			(layers "*.Cu" "*.Mask")
			(remove_unused_layers no)
			(net "GND")
			(clearance 0.0508)
			(thermal_gap 0.0508)
		)
		(pad "P8" thru_hole circle
			(at 15.40002 30.100016 180)
			(size 0.906272 0.906272)
			(drill 0.499872)
			(layers "*.Cu" "*.Mask")
			(remove_unused_layers no)
			(net "GND")
			(clearance 0.0508)
			(thermal_gap 0.0508)
		)
		(pad "P9" thru_hole circle
			(at 17.599914 29.900118 180)
			(size 0.71628 0.71628)
			(drill 0.30988)
			(layers "*.Cu" "*.Mask")
			(remove_unused_layers no)
			(net "CLK_100M_DB2000QL_GPU_REF0_R_DP")
			(clearance 0.0508)
			(thermal_gap 0.0508)
		)
		(pad "P10" thru_hole circle
			(at 19.800062 30.100016 180)
			(size 0.906272 0.906272)
			(drill 0.499872)
			(layers "*.Cu" "*.Mask")
			(remove_unused_layers no)
			(net "GND")
			(clearance 0.0508)
			(thermal_gap 0.0508)
		)
		(pad "Q1" thru_hole circle
			(at 0 31.20009 180)
			(size 0.906272 0.906272)
			(drill 0.499872)
			(layers "*.Cu" "*.Mask")
			(remove_unused_layers no)
			(net "GND")
			(clearance 0.0508)
			(thermal_gap 0.0508)
		)
		(pad "Q3" thru_hole circle
			(at 4.400042 31.20009 180)
			(size 0.906272 0.906272)
			(drill 0.499872)
			(layers "*.Cu" "*.Mask")
			(remove_unused_layers no)
			(net "GND")
			(clearance 0.0508)
			(thermal_gap 0.0508)
		)
		(pad "Q5" thru_hole circle
			(at 8.800084 31.20009 180)
			(size 0.906272 0.906272)
			(drill 0.499872)
			(layers "*.Cu" "*.Mask")
			(remove_unused_layers no)
			(net "GND")
			(clearance 0.0508)
			(thermal_gap 0.0508)
		)
		(pad "Q7" thru_hole circle
			(at 13.199872 31.20009 180)
			(size 0.906272 0.906272)
			(drill 0.499872)
			(layers "*.Cu" "*.Mask")
			(remove_unused_layers no)
			(net "GND")
			(clearance 0.0508)
			(thermal_gap 0.0508)
		)
		(pad "Q9" thru_hole circle
			(at 17.599914 31.20009 180)
			(size 0.906272 0.906272)
			(drill 0.499872)
			(layers "*.Cu" "*.Mask")
			(remove_unused_layers no)
			(net "GND")
			(clearance 0.0508)
			(thermal_gap 0.0508)
		)
		(pad "Q10" thru_hole circle
			(at 19.800062 31.399988 180)
			(size 0.71628 0.71628)
			(drill 0.30988)
			(layers "*.Cu" "*.Mask")
			(remove_unused_layers no)
			(net "SMB_GPU_1_R_SCL")
			(clearance 0.0508)
			(thermal_gap 0.0508)
		)
		(pad "R9" thru_hole circle
			(at 17.599914 32.500062 180)
			(size 0.71628 0.71628)
			(drill 0.30988)
			(layers "*.Cu" "*.Mask")
			(remove_unused_layers no)
			(net "SMB_GPU_2_R_SCL")
			(clearance 0.0508)
			(thermal_gap 0.0508)
		)
		(pad "R10" thru_hole circle
			(at 19.800062 32.69996 180)
			(size 0.71628 0.71628)
			(drill 0.30988)
			(layers "*.Cu" "*.Mask")
			(remove_unused_layers no)
			(net "SMB_GPU_1_R_SDA")
			(clearance 0.0508)
			(thermal_gap 0.0508)
		)
		(pad "S2" thru_hole circle
			(at 2.199894 33.999932 180)
			(size 0.906272 0.906272)
			(drill 0.499872)
			(layers "*.Cu" "*.Mask")
			(remove_unused_layers no)
			(net "GND")
			(clearance 0.0508)
			(thermal_gap 0.0508)
		)
		(pad "S4" thru_hole circle
			(at 6.599936 33.999932 180)
			(size 0.906272 0.906272)
			(drill 0.499872)
			(layers "*.Cu" "*.Mask")
			(remove_unused_layers no)
			(net "GND")
			(clearance 0.0508)
			(thermal_gap 0.0508)
		)
		(pad "S6" thru_hole circle
			(at 10.999978 33.999932 180)
			(size 0.906272 0.906272)
			(drill 0.499872)
			(layers "*.Cu" "*.Mask")
			(remove_unused_layers no)
			(net "GND")
			(clearance 0.0508)
			(thermal_gap 0.0508)
		)
		(pad "S8" thru_hole circle
			(at 15.40002 33.999932 180)
			(size 0.906272 0.906272)
			(drill 0.499872)
			(layers "*.Cu" "*.Mask")
			(remove_unused_layers no)
			(net "GND")
			(clearance 0.0508)
			(thermal_gap 0.0508)
		)
		(pad "S9" thru_hole circle
			(at 17.599914 33.800034 180)
			(size 0.71628 0.71628)
			(drill 0.30988)
			(layers "*.Cu" "*.Mask")
			(remove_unused_layers no)
			(net "SMB_GPU_2_R_SDA")
			(clearance 0.0508)
			(thermal_gap 0.0508)
		)
		(pad "S10" thru_hole circle
			(at 19.800062 33.999932 180)
			(size 0.906272 0.906272)
			(drill 0.499872)
			(layers "*.Cu" "*.Mask")
			(remove_unused_layers no)
			(net "GND")
			(clearance 0.0508)
			(thermal_gap 0.0508)
		)
		(pad "T1" thru_hole circle
			(at 0 35.100006 180)
			(size 0.906272 0.906272)
			(drill 0.499872)
			(layers "*.Cu" "*.Mask")
			(remove_unused_layers no)
			(net "GND")
			(clearance 0.0508)
			(thermal_gap 0.0508)
		)
		(pad "T3" thru_hole circle
			(at 4.400042 35.100006 180)
			(size 0.906272 0.906272)
			(drill 0.499872)
			(layers "*.Cu" "*.Mask")
			(remove_unused_layers no)
			(net "GND")
			(clearance 0.0508)
			(thermal_gap 0.0508)
		)
		(pad "T5" thru_hole circle
			(at 8.800084 35.100006 180)
			(size 0.906272 0.906272)
			(drill 0.499872)
			(layers "*.Cu" "*.Mask")
			(remove_unused_layers no)
			(net "GND")
			(clearance 0.0508)
			(thermal_gap 0.0508)
		)
		(pad "T7" thru_hole circle
			(at 13.199872 35.100006 180)
			(size 0.906272 0.906272)
			(drill 0.499872)
			(layers "*.Cu" "*.Mask")
			(remove_unused_layers no)
			(net "GND")
			(clearance 0.0508)
			(thermal_gap 0.0508)
		)
		(pad "T9" thru_hole circle
			(at 17.599914 35.100006 180)
			(size 0.906272 0.906272)
			(drill 0.499872)
			(layers "*.Cu" "*.Mask")
			(remove_unused_layers no)
			(net "GND")
			(clearance 0.0508)
			(thermal_gap 0.0508)
		)
		(pad "V2" thru_hole circle
			(at 2.199894 37.900102 180)
			(size 0.906272 0.906272)
			(drill 0.499872)
			(layers "*.Cu" "*.Mask")
			(remove_unused_layers no)
			(net "GND")
			(clearance 0.0508)
			(thermal_gap 0.0508)
		)
		(pad "V4" thru_hole circle
			(at 6.599936 37.900102 180)
			(size 0.906272 0.906272)
			(drill 0.499872)
			(layers "*.Cu" "*.Mask")
			(remove_unused_layers no)
			(net "GND")
			(clearance 0.0508)
			(thermal_gap 0.0508)
		)
		(pad "V6" thru_hole circle
			(at 10.999978 37.900102 180)
			(size 0.906272 0.906272)
			(drill 0.499872)
			(layers "*.Cu" "*.Mask")
			(remove_unused_layers no)
			(net "GND")
			(clearance 0.0508)
			(thermal_gap 0.0508)
		)
		(pad "V8" thru_hole circle
			(at 15.40002 37.900102 180)
			(size 0.906272 0.906272)
			(drill 0.499872)
			(layers "*.Cu" "*.Mask")
			(remove_unused_layers no)
			(net "GND")
			(clearance 0.0508)
			(thermal_gap 0.0508)
		)
		(pad "V10" thru_hole circle
			(at 19.800062 37.900102 180)
			(size 0.906272 0.906272)
			(drill 0.499872)
			(layers "*.Cu" "*.Mask")
			(remove_unused_layers no)
			(net "GND")
			(clearance 0.0508)
			(thermal_gap 0.0508)
		)
		(pad "W1" thru_hole circle
			(at 0 38.999922 180)
			(size 0.906272 0.906272)
			(drill 0.499872)
			(layers "*.Cu" "*.Mask")
			(remove_unused_layers no)
			(net "GND")
			(clearance 0.0508)
			(thermal_gap 0.0508)
		)
		(pad "W3" thru_hole circle
			(at 4.400042 38.999922 180)
			(size 0.906272 0.906272)
			(drill 0.499872)
			(layers "*.Cu" "*.Mask")
			(remove_unused_layers no)
			(net "GND")
			(clearance 0.0508)
			(thermal_gap 0.0508)
		)
		(pad "W5" thru_hole circle
			(at 8.800084 38.999922 180)
			(size 0.906272 0.906272)
			(drill 0.499872)
			(layers "*.Cu" "*.Mask")
			(remove_unused_layers no)
			(net "GND")
			(clearance 0.0508)
			(thermal_gap 0.0508)
		)
		(pad "W7" thru_hole circle
			(at 13.199872 38.999922 180)
			(size 0.906272 0.906272)
			(drill 0.499872)
			(layers "*.Cu" "*.Mask")
			(remove_unused_layers no)
			(net "GND")
			(clearance 0.0508)
			(thermal_gap 0.0508)
		)
		(pad "W9" thru_hole circle
			(at 17.599914 38.999922 180)
			(size 0.906272 0.906272)
			(drill 0.499872)
			(layers "*.Cu" "*.Mask")
			(remove_unused_layers no)
			(net "GND")
			(clearance 0.0508)
			(thermal_gap 0.0508)
		)
		(pad "Y2" thru_hole circle
			(at 2.199894 41.800018 180)
			(size 0.906272 0.906272)
			(drill 0.499872)
			(layers "*.Cu" "*.Mask")
			(remove_unused_layers no)
			(net "GND")
			(clearance 0.0508)
			(thermal_gap 0.0508)
		)
		(pad "Y4" thru_hole circle
			(at 6.599936 41.800018 180)
			(size 0.906272 0.906272)
			(drill 0.499872)
			(layers "*.Cu" "*.Mask")
			(remove_unused_layers no)
			(net "GND")
			(clearance 0.0508)
			(thermal_gap 0.0508)
		)
		(pad "Y6" thru_hole circle
			(at 10.999978 41.800018 180)
			(size 0.906272 0.906272)
			(drill 0.499872)
			(layers "*.Cu" "*.Mask")
			(remove_unused_layers no)
			(net "GND")
			(clearance 0.0508)
			(thermal_gap 0.0508)
		)
		(pad "Y8" thru_hole circle
			(at 15.40002 41.800018 180)
			(size 0.906272 0.906272)
			(drill 0.499872)
			(layers "*.Cu" "*.Mask")
			(remove_unused_layers no)
			(net "GND")
			(clearance 0.0508)
			(thermal_gap 0.0508)
		)
		(pad "Y10" thru_hole circle
			(at 19.800062 41.800018 180)
			(size 0.906272 0.906272)
			(drill 0.499872)
			(layers "*.Cu" "*.Mask")
			(remove_unused_layers no)
			(net "GND")
			(clearance 0.0508)
			(thermal_gap 0.0508)
		)
		(pad "Z1" thru_hole circle
			(at 0 42.900092 180)
			(size 0.906272 0.906272)
			(drill 0.499872)
			(layers "*.Cu" "*.Mask")
			(remove_unused_layers no)
			(net "GND")
			(clearance 0.0508)
			(thermal_gap 0.0508)
		)
		(pad "Z2" thru_hole circle
			(at 2.199894 43.09999 180)
			(size 0.71628 0.71628)
			(drill 0.30988)
			(layers "*.Cu" "*.Mask")
			(remove_unused_layers no)
			(net "PRSNT_GPU_D_N")
			(clearance 0.0508)
			(thermal_gap 0.0508)
		)
		(pad "Z3" thru_hole circle
			(at 4.400042 42.900092 180)
			(size 0.906272 0.906272)
			(drill 0.499872)
			(layers "*.Cu" "*.Mask")
			(remove_unused_layers no)
			(net "GND")
			(clearance 0.0508)
			(thermal_gap 0.0508)
		)
		(pad "Z4" thru_hole circle
			(at 6.599936 43.09999 180)
			(size 0.71628 0.71628)
			(drill 0.30988)
			(layers "*.Cu" "*.Mask")
			(remove_unused_layers no)
			(net "GPU_BASE_PWR_EN_R")
			(clearance 0.0508)
			(thermal_gap 0.0508)
		)
		(pad "Z5" thru_hole circle
			(at 8.800084 42.900092 180)
			(size 0.906272 0.906272)
			(drill 0.499872)
			(layers "*.Cu" "*.Mask")
			(remove_unused_layers no)
			(net "GND")
			(clearance 0.0508)
			(thermal_gap 0.0508)
		)
		(pad "Z6" thru_hole circle
			(at 10.999978 43.09999 180)
			(size 0.71628 0.71628)
			(drill 0.30988)
			(layers "*.Cu" "*.Mask")
			(remove_unused_layers no)
			(net "GPU_BASE_PWR_GD")
			(clearance 0.0508)
			(thermal_gap 0.0508)
		)
		(pad "Z7" thru_hole circle
			(at 13.199872 42.900092 180)
			(size 0.906272 0.906272)
			(drill 0.499872)
			(layers "*.Cu" "*.Mask")
			(remove_unused_layers no)
			(net "GND")
			(clearance 0.0508)
			(thermal_gap 0.0508)
		)
		(pad "Z8" thru_hole circle
			(at 15.40002 43.09999 180)
			(size 0.71628 0.71628)
			(drill 0.30988)
			(layers "*.Cu" "*.Mask")
			(remove_unused_layers no)
			(net "GPU_BASE_ID1_R")
			(clearance 0.0508)
			(thermal_gap 0.0508)
		)
		(pad "Z9" thru_hole circle
			(at 17.599914 42.900092 180)
			(size 0.906272 0.906272)
			(drill 0.499872)
			(layers "*.Cu" "*.Mask")
			(remove_unused_layers no)
			(net "GND")
			(clearance 0.0508)
			(thermal_gap 0.0508)
		)
		(pad "Z10" thru_hole circle
			(at 19.800062 43.09999 180)
			(size 0.71628 0.71628)
			(drill 0.30988)
			(layers "*.Cu" "*.Mask")
			(remove_unused_layers no)
			(net "RST_GPU_PERST_0_BUF_R_N")
			(clearance 0.0508)
			(thermal_gap 0.0508)
		)
		(zone
			(layer "B.Cu")
			(hatch none 0.5)
			(connect_pads
				(clearance 0)
			)
			(min_thickness 0.25)
			(keepout
				(tracks allowed)
				(vias not_allowed)
				(pads allowed)
				(copperpour not_allowed)
				(footprints allowed)
			)
			(placement
				(enabled no)
				(sheetname "")
			)
			(fill
				(thermal_gap 0.5)
				(thermal_bridge_width 0.5)
				(island_removal_mode 0)
			)
			(polygon
				(pts
					(xy 27.392884 -394.665708) (xy 48.220884 -394.665708) (xy 48.220884 -412.50743) (xy 27.392884 -412.50743)
				)
			)
		)
		(zone
			(layer "B.Cu")
			(hatch none 0.5)
			(connect_pads
				(clearance 0)
			)
			(min_thickness 0.25)
			(keepout
				(tracks allowed)
				(vias not_allowed)
				(pads allowed)
				(copperpour not_allowed)
				(footprints allowed)
			)
			(placement
				(enabled no)
				(sheetname "")
			)
			(fill
				(thermal_gap 0.5)
				(thermal_bridge_width 0.5)
				(island_removal_mode 0)
			)
			(polygon
				(pts
					(xy 27.392884 -368.572796) (xy 48.220884 -368.572796) (xy 48.220884 -386.414518) (xy 27.392884 -386.414518)
				)
			)
		)
	)
	(footprint ""
		(layer "F.Cu")
		(at 191.0461 -414.587436 -90)
		(property "Reference" "C4478"
			(at 0 0 270)
			(layer "F.SilkS")
			(hide yes)
			(effects
				(font
					(size 1.27 1.27)
				)
			)
		)
		(property "Value" ""
			(at 0 0 270)
			(layer "F.Fab")
			(effects
				(font
					(size 1.27 1.27)
				)
			)
		)
		(duplicate_pad_numbers_are_jumpers no)
		(fp_line
			(start -0.7874 0.4064)
			(end -0.7874 -0.4064)
			(stroke
				(width 0.1524)
				(type default)
			)
			(layer "F.SilkS")
		)
		(fp_line
			(start 0.7874 0.4064)
			(end -0.7874 0.4064)
			(stroke
				(width 0.1524)
				(type default)
			)
			(layer "F.SilkS")
		)
		(fp_line
			(start -0.7874 -0.4064)
			(end 0.7874 -0.4064)
			(stroke
				(width 0.1524)
				(type default)
			)
			(layer "F.SilkS")
		)
		(fp_line
			(start 0.7874 -0.4064)
			(end 0.7874 0.4064)
			(stroke
				(width 0.1524)
				(type default)
			)
			(layer "F.SilkS")
		)
		(fp_line
			(start -0.67945 0.3048)
			(end -0.67945 -0.305054)
			(stroke
				(width 0.1)
				(type default)
			)
			(layer "F.Fab")
		)
		(fp_line
			(start -0.12065 0.3048)
			(end -0.67945 0.3048)
			(stroke
				(width 0.1)
				(type default)
			)
			(layer "F.Fab")
		)
		(fp_line
			(start 0.120396 0.3048)
			(end 0.120396 0.2794)
			(stroke
				(width 0.1)
				(type default)
			)
			(layer "F.Fab")
		)
		(fp_line
			(start 0.67945 0.3048)
			(end 0.120396 0.3048)
			(stroke
				(width 0.1)
				(type default)
			)
			(layer "F.Fab")
		)
		(fp_line
			(start -0.12065 0.2794)
			(end -0.12065 0.3048)
			(stroke
				(width 0.1)
				(type default)
			)
			(layer "F.Fab")
		)
		(fp_line
			(start 0.120396 0.2794)
			(end -0.12065 0.2794)
			(stroke
				(width 0.1)
				(type default)
			)
			(layer "F.Fab")
		)
		(fp_line
			(start -0.12065 -0.2794)
			(end 0.12065 -0.2794)
			(stroke
				(width 0.1)
				(type default)
			)
			(layer "F.Fab")
		)
		(fp_line
			(start 0.12065 -0.2794)
			(end 0.12065 -0.3048)
			(stroke
				(width 0.1)
				(type default)
			)
			(layer "F.Fab")
		)
		(fp_line
			(start 0.12065 -0.3048)
			(end 0.67945 -0.3048)
			(stroke
				(width 0.1)
				(type default)
			)
			(layer "F.Fab")
		)
		(fp_line
			(start 0.67945 -0.3048)
			(end 0.67945 0.3048)
			(stroke
				(width 0.1)
				(type default)
			)
			(layer "F.Fab")
		)
		(fp_line
			(start -0.67945 -0.305054)
			(end -0.12065 -0.305054)
			(stroke
				(width 0.1)
				(type default)
			)
			(layer "F.Fab")
		)
		(fp_line
			(start -0.12065 -0.305054)
			(end -0.12065 -0.2794)
			(stroke
				(width 0.1)
				(type default)
			)
			(layer "F.Fab")
		)
		(pad "1" smd circle
			(at -0.40005 0 270)
			(size 0 0)
			(layers "F.Cu" "F.Mask" "F.Paste")
			(net "P12V_AUX_FP_TRIGGER")
		)
		(pad "2" smd circle
			(at 0.40005 0 270)
			(size 0 0)
			(layers "F.Cu" "F.Mask" "F.Paste")
			(net "GND")
		)
	)
	(footprint ""
		(layer "F.Cu")
		(at 249.020838 -119.140986 90)
		(property "Reference" "PC900"
			(at 0 0 90)
			(layer "F.SilkS")
			(hide yes)
			(effects
				(font
					(size 1.27 1.27)
				)
			)
		)
		(property "Value" ""
			(at 0 0 90)
			(layer "F.Fab")
			(effects
				(font
					(size 1.27 1.27)
				)
			)
		)
		(duplicate_pad_numbers_are_jumpers no)
		(fp_line
			(start 0.7874 -0.4064)
			(end 0.7874 0.4064)
			(stroke
				(width 0.1524)
				(type default)
			)
			(layer "F.SilkS")
		)
		(fp_line
			(start -0.7874 -0.4064)
			(end 0.7874 -0.4064)
			(stroke
				(width 0.1524)
				(type default)
			)
			(layer "F.SilkS")
		)
		(fp_line
			(start 0.7874 0.4064)
			(end -0.7874 0.4064)
			(stroke
				(width 0.1524)
				(type default)
			)
			(layer "F.SilkS")
		)
		(fp_line
			(start -0.7874 0.4064)
			(end -0.7874 -0.4064)
			(stroke
				(width 0.1524)
				(type default)
			)
			(layer "F.SilkS")
		)
		(fp_line
			(start -0.12065 -0.305054)
			(end -0.12065 -0.2794)
			(stroke
				(width 0.1)
				(type default)
			)
			(layer "F.Fab")
		)
		(fp_line
			(start -0.67945 -0.305054)
			(end -0.12065 -0.305054)
			(stroke
				(width 0.1)
				(type default)
			)
			(layer "F.Fab")
		)
		(fp_line
			(start 0.67945 -0.3048)
			(end 0.67945 0.3048)
			(stroke
				(width 0.1)
				(type default)
			)
			(layer "F.Fab")
		)
		(fp_line
			(start 0.12065 -0.3048)
			(end 0.67945 -0.3048)
			(stroke
				(width 0.1)
				(type default)
			)
			(layer "F.Fab")
		)
		(fp_line
			(start 0.12065 -0.2794)
			(end 0.12065 -0.3048)
			(stroke
				(width 0.1)
				(type default)
			)
			(layer "F.Fab")
		)
		(fp_line
			(start -0.12065 -0.2794)
			(end 0.12065 -0.2794)
			(stroke
				(width 0.1)
				(type default)
			)
			(layer "F.Fab")
		)
		(fp_line
			(start 0.120396 0.2794)
			(end -0.12065 0.2794)
			(stroke
				(width 0.1)
				(type default)
			)
			(layer "F.Fab")
		)
		(fp_line
			(start -0.12065 0.2794)
			(end -0.12065 0.3048)
			(stroke
				(width 0.1)
				(type default)
			)
			(layer "F.Fab")
		)
		(fp_line
			(start 0.67945 0.3048)
			(end 0.120396 0.3048)
			(stroke
				(width 0.1)
				(type default)
			)
			(layer "F.Fab")
		)
		(fp_line
			(start 0.120396 0.3048)
			(end 0.120396 0.2794)
			(stroke
				(width 0.1)
				(type default)
			)
			(layer "F.Fab")
		)
		(fp_line
			(start -0.12065 0.3048)
			(end -0.67945 0.3048)
			(stroke
				(width 0.1)
				(type default)
			)
			(layer "F.Fab")
		)
		(fp_line
			(start -0.67945 0.3048)
			(end -0.67945 -0.305054)
			(stroke
				(width 0.1)
				(type default)
			)
			(layer "F.Fab")
		)
		(pad "1" smd circle
			(at -0.40005 0 90)
			(size 0 0)
			(layers "F.Cu" "F.Mask" "F.Paste")
			(net "P3V3_NIC4_CO_GATE")
		)
		(pad "2" smd circle
			(at 0.40005 0 90)
			(size 0 0)
			(layers "F.Cu" "F.Mask" "F.Paste")
			(net "GND")
		)
	)
	(footprint ""
		(layer "F.Cu")
		(at 332.045564 -343.952322 90)
		(property "Reference" "C568"
			(at 0 0 90)
			(layer "F.SilkS")
			(hide yes)
			(effects
				(font
					(size 1.27 1.27)
				)
			)
		)
		(property "Value" ""
			(at 0 0 90)
			(layer "F.Fab")
			(effects
				(font
					(size 1.27 1.27)
				)
			)
		)
		(duplicate_pad_numbers_are_jumpers no)
		(fp_line
			(start 0.299974 -0.150114)
			(end 0.299974 0.150114)
			(stroke
				(width 0.1)
				(type default)
			)
			(layer "F.Fab")
		)
		(fp_line
			(start -0.299974 -0.150114)
			(end 0.299974 -0.150114)
			(stroke
				(width 0.1)
				(type default)
			)
			(layer "F.Fab")
		)
		(fp_line
			(start 0.299974 0.150114)
			(end -0.299974 0.150114)
			(stroke
				(width 0.1)
				(type default)
			)
			(layer "F.Fab")
		)
		(fp_line
			(start -0.299974 0.150114)
			(end -0.299974 -0.150114)
			(stroke
				(width 0.1)
				(type default)
			)
			(layer "F.Fab")
		)
		(pad "1" smd rect
			(at -0.2667 0 90)
			(size 0.3048 0.381)
			(layers "F.Cu" "F.Mask" "F.Paste")
			(net "P5E_PEX2_STN6_TX_DN<103>")
		)
		(pad "2" smd rect
			(at 0.2667 0 90)
			(size 0.3048 0.381)
			(layers "F.Cu" "F.Mask" "F.Paste")
			(net "P5E_PEX2_STN6_TX_C_DN<103>")
		)
	)
	(footprint ""
		(layer "F.Cu")
		(at 358.971088 -272.15846 -90)
		(property "Reference" "PL14"
			(at 1.491996 -3.25882 90)
			(unlocked yes)
			(layer "F.SilkS")
			(effects
				(font
					(size 0.7874 0.5842)
					(thickness 0.1524)
				)
				(justify left)
			)
		)
		(property "Value" ""
			(at 0 0 270)
			(layer "F.Fab")
			(effects
				(font
					(size 1.27 1.27)
				)
			)
		)
		(duplicate_pad_numbers_are_jumpers no)
		(fp_line
			(start -2.249932 2.249932)
			(end -2.249932 1.3843)
			(stroke
				(width 0.1524)
				(type default)
			)
			(layer "F.SilkS")
		)
		(fp_line
			(start 2.249932 2.249932)
			(end -2.249932 2.249932)
			(stroke
				(width 0.1524)
				(type default)
			)
			(layer "F.SilkS")
		)
		(fp_line
			(start 2.249932 1.3843)
			(end 2.249932 2.249932)
			(stroke
				(width 0.1524)
				(type default)
			)
			(layer "F.SilkS")
		)
		(fp_line
			(start -2.249932 -1.3843)
			(end -2.249932 -2.249932)
			(stroke
				(width 0.1524)
				(type default)
			)
			(layer "F.SilkS")
		)
		(fp_line
			(start -2.249932 -2.249932)
			(end 2.249932 -2.249932)
			(stroke
				(width 0.1524)
				(type default)
			)
			(layer "F.SilkS")
		)
		(fp_line
			(start 2.249932 -2.249932)
			(end 2.249932 -1.3843)
			(stroke
				(width 0.1524)
				(type default)
			)
			(layer "F.SilkS")
		)
		(fp_line
			(start -2.249932 2.249932)
			(end -2.249932 -2.249932)
			(stroke
				(width 0.1)
				(type default)
			)
			(layer "F.Fab")
		)
		(fp_line
			(start 2.249932 2.249932)
			(end -2.249932 2.249932)
			(stroke
				(width 0.1)
				(type default)
			)
			(layer "F.Fab")
		)
		(fp_line
			(start -2.249932 -2.249932)
			(end 2.249932 -2.249932)
			(stroke
				(width 0.1)
				(type default)
			)
			(layer "F.Fab")
		)
		(fp_line
			(start 2.249932 -2.249932)
			(end 2.249932 2.249932)
			(stroke
				(width 0.1)
				(type default)
			)
			(layer "F.Fab")
		)
		(pad "1" smd rect
			(at -1.82499 0 270)
			(size 1.0668 2.5146)
			(layers "F.Cu" "F.Mask" "F.Paste")
			(net "SW_P12V_P0V8_PEX3_FLT")
		)
		(pad "2" smd rect
			(at 1.82499 0 270)
			(size 1.0668 2.5146)
			(layers "F.Cu" "F.Mask" "F.Paste")
			(net "P12V_AUX")
		)
	)
	(footprint ""
		(layer "F.Cu")
		(at 368.539776 -152.71115 90)
		(property "Reference" "R749"
			(at 0 0 90)
			(layer "F.SilkS")
			(hide yes)
			(effects
				(font
					(size 1.27 1.27)
				)
			)
		)
		(property "Value" ""
			(at 0 0 90)
			(layer "F.Fab")
			(effects
				(font
					(size 1.27 1.27)
				)
			)
		)
		(duplicate_pad_numbers_are_jumpers no)
		(fp_line
			(start 0.7874 -0.4064)
			(end 0.7874 0.4064)
			(stroke
				(width 0.1524)
				(type default)
			)
			(layer "F.SilkS")
		)
		(fp_line
			(start -0.7874 -0.4064)
			(end 0.7874 -0.4064)
			(stroke
				(width 0.1524)
				(type default)
			)
			(layer "F.SilkS")
		)
		(fp_line
			(start 0.7874 0.4064)
			(end -0.7874 0.4064)
			(stroke
				(width 0.1524)
				(type default)
			)
			(layer "F.SilkS")
		)
		(fp_line
			(start -0.7874 0.4064)
			(end -0.7874 -0.4064)
			(stroke
				(width 0.1524)
				(type default)
			)
			(layer "F.SilkS")
		)
		(fp_line
			(start -0.12065 -0.305054)
			(end -0.12065 -0.2794)
			(stroke
				(width 0.1)
				(type default)
			)
			(layer "F.Fab")
		)
		(fp_line
			(start -0.67945 -0.305054)
			(end -0.12065 -0.305054)
			(stroke
				(width 0.1)
				(type default)
			)
			(layer "F.Fab")
		)
		(fp_line
			(start 0.67945 -0.3048)
			(end 0.67945 0.3048)
			(stroke
				(width 0.1)
				(type default)
			)
			(layer "F.Fab")
		)
		(fp_line
			(start 0.12065 -0.3048)
			(end 0.67945 -0.3048)
			(stroke
				(width 0.1)
				(type default)
			)
			(layer "F.Fab")
		)
		(fp_line
			(start 0.12065 -0.2794)
			(end 0.12065 -0.3048)
			(stroke
				(width 0.1)
				(type default)
			)
			(layer "F.Fab")
		)
		(fp_line
			(start -0.12065 -0.2794)
			(end 0.12065 -0.2794)
			(stroke
				(width 0.1)
				(type default)
			)
			(layer "F.Fab")
		)
		(fp_line
			(start 0.120396 0.2794)
			(end -0.12065 0.2794)
			(stroke
				(width 0.1)
				(type default)
			)
			(layer "F.Fab")
		)
		(fp_line
			(start -0.12065 0.2794)
			(end -0.12065 0.3048)
			(stroke
				(width 0.1)
				(type default)
			)
			(layer "F.Fab")
		)
		(fp_line
			(start 0.67945 0.3048)
			(end 0.120396 0.3048)
			(stroke
				(width 0.1)
				(type default)
			)
			(layer "F.Fab")
		)
		(fp_line
			(start 0.120396 0.3048)
			(end 0.120396 0.2794)
			(stroke
				(width 0.1)
				(type default)
			)
			(layer "F.Fab")
		)
		(fp_line
			(start -0.12065 0.3048)
			(end -0.67945 0.3048)
			(stroke
				(width 0.1)
				(type default)
			)
			(layer "F.Fab")
		)
		(fp_line
			(start -0.67945 0.3048)
			(end -0.67945 -0.305054)
			(stroke
				(width 0.1)
				(type default)
			)
			(layer "F.Fab")
		)
		(pad "1" smd circle
			(at -0.40005 0 90)
			(size 0 0)
			(layers "F.Cu" "F.Mask" "F.Paste")
			(net "NIC6_ADC_A0")
		)
		(pad "2" smd circle
			(at 0.40005 0 90)
			(size 0 0)
			(layers "F.Cu" "F.Mask" "F.Paste")
			(net "P3V3_AUX")
		)
	)
	(footprint ""
		(layer "F.Cu")
		(at 450.682106 -366.29594 -90)
		(property "Reference" "R6693"
			(at 0 0 270)
			(layer "F.SilkS")
			(hide yes)
			(effects
				(font
					(size 1.27 1.27)
				)
			)
		)
		(property "Value" ""
			(at 0 0 270)
			(layer "F.Fab")
			(effects
				(font
					(size 1.27 1.27)
				)
			)
		)
		(duplicate_pad_numbers_are_jumpers no)
		(fp_line
			(start -0.7874 0.4064)
			(end -0.7874 -0.4064)
			(stroke
				(width 0.1524)
				(type default)
			)
			(layer "F.SilkS")
		)
		(fp_line
			(start 0.7874 0.4064)
			(end -0.7874 0.4064)
			(stroke
				(width 0.1524)
				(type default)
			)
			(layer "F.SilkS")
		)
		(fp_line
			(start -0.7874 -0.4064)
			(end 0.7874 -0.4064)
			(stroke
				(width 0.1524)
				(type default)
			)
			(layer "F.SilkS")
		)
		(fp_line
			(start 0.7874 -0.4064)
			(end 0.7874 0.4064)
			(stroke
				(width 0.1524)
				(type default)
			)
			(layer "F.SilkS")
		)
		(fp_line
			(start -0.67945 0.3048)
			(end -0.67945 -0.305054)
			(stroke
				(width 0.1)
				(type default)
			)
			(layer "F.Fab")
		)
		(fp_line
			(start -0.12065 0.3048)
			(end -0.67945 0.3048)
			(stroke
				(width 0.1)
				(type default)
			)
			(layer "F.Fab")
		)
		(fp_line
			(start 0.120396 0.3048)
			(end 0.120396 0.2794)
			(stroke
				(width 0.1)
				(type default)
			)
			(layer "F.Fab")
		)
		(fp_line
			(start 0.67945 0.3048)
			(end 0.120396 0.3048)
			(stroke
				(width 0.1)
				(type default)
			)
			(layer "F.Fab")
		)
		(fp_line
			(start -0.12065 0.2794)
			(end -0.12065 0.3048)
			(stroke
				(width 0.1)
				(type default)
			)
			(layer "F.Fab")
		)
		(fp_line
			(start 0.120396 0.2794)
			(end -0.12065 0.2794)
			(stroke
				(width 0.1)
				(type default)
			)
			(layer "F.Fab")
		)
		(fp_line
			(start -0.12065 -0.2794)
			(end 0.12065 -0.2794)
			(stroke
				(width 0.1)
				(type default)
			)
			(layer "F.Fab")
		)
		(fp_line
			(start 0.12065 -0.2794)
			(end 0.12065 -0.3048)
			(stroke
				(width 0.1)
				(type default)
			)
			(layer "F.Fab")
		)
		(fp_line
			(start 0.12065 -0.3048)
			(end 0.67945 -0.3048)
			(stroke
				(width 0.1)
				(type default)
			)
			(layer "F.Fab")
		)
		(fp_line
			(start 0.67945 -0.3048)
			(end 0.67945 0.3048)
			(stroke
				(width 0.1)
				(type default)
			)
			(layer "F.Fab")
		)
		(fp_line
			(start -0.67945 -0.305054)
			(end -0.12065 -0.305054)
			(stroke
				(width 0.1)
				(type default)
			)
			(layer "F.Fab")
		)
		(fp_line
			(start -0.12065 -0.305054)
			(end -0.12065 -0.2794)
			(stroke
				(width 0.1)
				(type default)
			)
			(layer "F.Fab")
		)
		(pad "1" smd circle
			(at -0.40005 0 270)
			(size 0 0)
			(layers "F.Cu" "F.Mask" "F.Paste")
			(net "GPU_3V3IO_RSVD4")
		)
		(pad "2" smd circle
			(at 0.40005 0 270)
			(size 0 0)
			(layers "F.Cu" "F.Mask" "F.Paste")
			(net "GND")
		)
	)
	(footprint ""
		(layer "F.Cu")
		(at 340.561422 -193.46545 180)
		(property "Reference" "R4248"
			(at 0 0 180)
			(layer "F.SilkS")
			(hide yes)
			(effects
				(font
					(size 1.27 1.27)
				)
			)
		)
		(property "Value" ""
			(at 0 0 180)
			(layer "F.Fab")
			(effects
				(font
					(size 1.27 1.27)
				)
			)
		)
		(duplicate_pad_numbers_are_jumpers no)
		(fp_line
			(start 0.7874 0.4064)
			(end -0.7874 0.4064)
			(stroke
				(width 0.1524)
				(type default)
			)
			(layer "F.SilkS")
		)
		(fp_line
			(start 0.7874 -0.4064)
			(end 0.7874 0.4064)
			(stroke
				(width 0.1524)
				(type default)
			)
			(layer "F.SilkS")
		)
		(fp_line
			(start -0.7874 0.4064)
			(end -0.7874 -0.4064)
			(stroke
				(width 0.1524)
				(type default)
			)
			(layer "F.SilkS")
		)
		(fp_line
			(start -0.7874 -0.4064)
			(end 0.7874 -0.4064)
			(stroke
				(width 0.1524)
				(type default)
			)
			(layer "F.SilkS")
		)
		(fp_line
			(start 0.67945 0.3048)
			(end 0.120396 0.3048)
			(stroke
				(width 0.1)
				(type default)
			)
			(layer "F.Fab")
		)
		(fp_line
			(start 0.67945 -0.3048)
			(end 0.67945 0.3048)
			(stroke
				(width 0.1)
				(type default)
			)
			(layer "F.Fab")
		)
		(fp_line
			(start 0.12065 -0.2794)
			(end 0.12065 -0.3048)
			(stroke
				(width 0.1)
				(type default)
			)
			(layer "F.Fab")
		)
		(fp_line
			(start 0.12065 -0.3048)
			(end 0.67945 -0.3048)
			(stroke
				(width 0.1)
				(type default)
			)
			(layer "F.Fab")
		)
		(fp_line
			(start 0.120396 0.3048)
			(end 0.120396 0.2794)
			(stroke
				(width 0.1)
				(type default)
			)
			(layer "F.Fab")
		)
		(fp_line
			(start 0.120396 0.2794)
			(end -0.12065 0.2794)
			(stroke
				(width 0.1)
				(type default)
			)
			(layer "F.Fab")
		)
		(fp_line
			(start -0.12065 0.3048)
			(end -0.67945 0.3048)
			(stroke
				(width 0.1)
				(type default)
			)
			(layer "F.Fab")
		)
		(fp_line
			(start -0.12065 0.2794)
			(end -0.12065 0.3048)
			(stroke
				(width 0.1)
				(type default)
			)
			(layer "F.Fab")
		)
		(fp_line
			(start -0.12065 -0.2794)
			(end 0.12065 -0.2794)
			(stroke
				(width 0.1)
				(type default)
			)
			(layer "F.Fab")
		)
		(fp_line
			(start -0.12065 -0.305054)
			(end -0.12065 -0.2794)
			(stroke
				(width 0.1)
				(type default)
			)
			(layer "F.Fab")
		)
		(fp_line
			(start -0.67945 0.3048)
			(end -0.67945 -0.305054)
			(stroke
				(width 0.1)
				(type default)
			)
			(layer "F.Fab")
		)
		(fp_line
			(start -0.67945 -0.305054)
			(end -0.12065 -0.305054)
			(stroke
				(width 0.1)
				(type default)
			)
			(layer "F.Fab")
		)
		(pad "1" smd circle
			(at -0.40005 0 180)
			(size 0 0)
			(layers "F.Cu" "F.Mask" "F.Paste")
			(net "P3V3_AUX")
		)
		(pad "2" smd circle
			(at 0.40005 0 180)
			(size 0 0)
			(layers "F.Cu" "F.Mask" "F.Paste")
			(net "FM_SLPS3_N")
		)
	)
	(footprint ""
		(layer "F.Cu")
		(at 121.13514 -96.034606)
		(property "Reference" "R1552"
			(at 0 0 0)
			(layer "F.SilkS")
			(hide yes)
			(effects
				(font
					(size 1.27 1.27)
				)
			)
		)
		(property "Value" ""
			(at 0 0 0)
			(layer "F.Fab")
			(effects
				(font
					(size 1.27 1.27)
				)
			)
		)
		(duplicate_pad_numbers_are_jumpers no)
		(fp_line
			(start -0.7874 -0.4064)
			(end 0.7874 -0.4064)
			(stroke
				(width 0.1524)
				(type default)
			)
			(layer "F.SilkS")
		)
		(fp_line
			(start -0.7874 0.4064)
			(end -0.7874 -0.4064)
			(stroke
				(width 0.1524)
				(type default)
			)
			(layer "F.SilkS")
		)
		(fp_line
			(start 0.7874 -0.4064)
			(end 0.7874 0.4064)
			(stroke
				(width 0.1524)
				(type default)
			)
			(layer "F.SilkS")
		)
		(fp_line
			(start 0.7874 0.4064)
			(end -0.7874 0.4064)
			(stroke
				(width 0.1524)
				(type default)
			)
			(layer "F.SilkS")
		)
		(fp_line
			(start -0.67945 -0.305054)
			(end -0.12065 -0.305054)
			(stroke
				(width 0.1)
				(type default)
			)
			(layer "F.Fab")
		)
		(fp_line
			(start -0.67945 0.3048)
			(end -0.67945 -0.305054)
			(stroke
				(width 0.1)
				(type default)
			)
			(layer "F.Fab")
		)
		(fp_line
			(start -0.12065 -0.305054)
			(end -0.12065 -0.2794)
			(stroke
				(width 0.1)
				(type default)
			)
			(layer "F.Fab")
		)
		(fp_line
			(start -0.12065 -0.2794)
			(end 0.12065 -0.2794)
			(stroke
				(width 0.1)
				(type default)
			)
			(layer "F.Fab")
		)
		(fp_line
			(start -0.12065 0.2794)
			(end -0.12065 0.3048)
			(stroke
				(width 0.1)
				(type default)
			)
			(layer "F.Fab")
		)
		(fp_line
			(start -0.12065 0.3048)
			(end -0.67945 0.3048)
			(stroke
				(width 0.1)
				(type default)
			)
			(layer "F.Fab")
		)
		(fp_line
			(start 0.120396 0.2794)
			(end -0.12065 0.2794)
			(stroke
				(width 0.1)
				(type default)
			)
			(layer "F.Fab")
		)
		(fp_line
			(start 0.120396 0.3048)
			(end 0.120396 0.2794)
			(stroke
				(width 0.1)
				(type default)
			)
			(layer "F.Fab")
		)
		(fp_line
			(start 0.12065 -0.3048)
			(end 0.67945 -0.3048)
			(stroke
				(width 0.1)
				(type default)
			)
			(layer "F.Fab")
		)
		(fp_line
			(start 0.12065 -0.2794)
			(end 0.12065 -0.3048)
			(stroke
				(width 0.1)
				(type default)
			)
			(layer "F.Fab")
		)
		(fp_line
			(start 0.67945 -0.3048)
			(end 0.67945 0.3048)
			(stroke
				(width 0.1)
				(type default)
			)
			(layer "F.Fab")
		)
		(fp_line
			(start 0.67945 0.3048)
			(end 0.120396 0.3048)
			(stroke
				(width 0.1)
				(type default)
			)
			(layer "F.Fab")
		)
		(pad "1" smd circle
			(at -0.40005 0)
			(size 0 0)
			(layers "F.Cu" "F.Mask" "F.Paste")
			(net "P3V3_AUX")
		)
		(pad "2" smd circle
			(at 0.40005 0)
			(size 0 0)
			(layers "F.Cu" "F.Mask" "F.Paste")
			(net "SMB_BIC_I2C9_MUX0_SSD0_R_SCL")
		)
	)
	(footprint ""
		(layer "F.Cu")
		(at 154.666442 -250.070874 -90)
		(property "Reference" "R1268"
			(at 0 0 270)
			(layer "F.SilkS")
			(hide yes)
			(effects
				(font
					(size 1.27 1.27)
				)
			)
		)
		(property "Value" ""
			(at 0 0 270)
			(layer "F.Fab")
			(effects
				(font
					(size 1.27 1.27)
				)
			)
		)
		(duplicate_pad_numbers_are_jumpers no)
		(fp_line
			(start -0.7874 0.4064)
			(end -0.7874 -0.4064)
			(stroke
				(width 0.1524)
				(type default)
			)
			(layer "F.SilkS")
		)
		(fp_line
			(start 0.7874 0.4064)
			(end -0.7874 0.4064)
			(stroke
				(width 0.1524)
				(type default)
			)
			(layer "F.SilkS")
		)
		(fp_line
			(start -0.7874 -0.4064)
			(end 0.7874 -0.4064)
			(stroke
				(width 0.1524)
				(type default)
			)
			(layer "F.SilkS")
		)
		(fp_line
			(start 0.7874 -0.4064)
			(end 0.7874 0.4064)
			(stroke
				(width 0.1524)
				(type default)
			)
			(layer "F.SilkS")
		)
		(fp_line
			(start -0.67945 0.3048)
			(end -0.67945 -0.305054)
			(stroke
				(width 0.1)
				(type default)
			)
			(layer "F.Fab")
		)
		(fp_line
			(start -0.12065 0.3048)
			(end -0.67945 0.3048)
			(stroke
				(width 0.1)
				(type default)
			)
			(layer "F.Fab")
		)
		(fp_line
			(start 0.120396 0.3048)
			(end 0.120396 0.2794)
			(stroke
				(width 0.1)
				(type default)
			)
			(layer "F.Fab")
		)
		(fp_line
			(start 0.67945 0.3048)
			(end 0.120396 0.3048)
			(stroke
				(width 0.1)
				(type default)
			)
			(layer "F.Fab")
		)
		(fp_line
			(start -0.12065 0.2794)
			(end -0.12065 0.3048)
			(stroke
				(width 0.1)
				(type default)
			)
			(layer "F.Fab")
		)
		(fp_line
			(start 0.120396 0.2794)
			(end -0.12065 0.2794)
			(stroke
				(width 0.1)
				(type default)
			)
			(layer "F.Fab")
		)
		(fp_line
			(start -0.12065 -0.2794)
			(end 0.12065 -0.2794)
			(stroke
				(width 0.1)
				(type default)
			)
			(layer "F.Fab")
		)
		(fp_line
			(start 0.12065 -0.2794)
			(end 0.12065 -0.3048)
			(stroke
				(width 0.1)
				(type default)
			)
			(layer "F.Fab")
		)
		(fp_line
			(start 0.12065 -0.3048)
			(end 0.67945 -0.3048)
			(stroke
				(width 0.1)
				(type default)
			)
			(layer "F.Fab")
		)
		(fp_line
			(start 0.67945 -0.3048)
			(end 0.67945 0.3048)
			(stroke
				(width 0.1)
				(type default)
			)
			(layer "F.Fab")
		)
		(fp_line
			(start -0.67945 -0.305054)
			(end -0.12065 -0.305054)
			(stroke
				(width 0.1)
				(type default)
			)
			(layer "F.Fab")
		)
		(fp_line
			(start -0.12065 -0.305054)
			(end -0.12065 -0.2794)
			(stroke
				(width 0.1)
				(type default)
			)
			(layer "F.Fab")
		)
		(pad "1" smd circle
			(at -0.40005 0 270)
			(size 0 0)
			(layers "F.Cu" "F.Mask" "F.Paste")
			(net "PEX1_DBG_MODE4")
		)
		(pad "2" smd circle
			(at 0.40005 0 270)
			(size 0 0)
			(layers "F.Cu" "F.Mask" "F.Paste")
			(net "P1V8_PEX")
		)
	)
	(footprint ""
		(layer "F.Cu")
		(at 409.49499 -59.577986 90)
		(property "Reference" "PC579"
			(at 0 0 90)
			(layer "F.SilkS")
			(hide yes)
			(effects
				(font
					(size 1.27 1.27)
				)
			)
		)
		(property "Value" ""
			(at 0 0 90)
			(layer "F.Fab")
			(effects
				(font
					(size 1.27 1.27)
				)
			)
		)
		(duplicate_pad_numbers_are_jumpers no)
		(fp_line
			(start 0.7874 -0.4064)
			(end 0.7874 0.4064)
			(stroke
				(width 0.1524)
				(type default)
			)
			(layer "F.SilkS")
		)
		(fp_line
			(start -0.7874 -0.4064)
			(end 0.7874 -0.4064)
			(stroke
				(width 0.1524)
				(type default)
			)
			(layer "F.SilkS")
		)
		(fp_line
			(start 0.7874 0.4064)
			(end -0.7874 0.4064)
			(stroke
				(width 0.1524)
				(type default)
			)
			(layer "F.SilkS")
		)
		(fp_line
			(start -0.7874 0.4064)
			(end -0.7874 -0.4064)
			(stroke
				(width 0.1524)
				(type default)
			)
			(layer "F.SilkS")
		)
		(fp_line
			(start -0.12065 -0.305054)
			(end -0.12065 -0.2794)
			(stroke
				(width 0.1)
				(type default)
			)
			(layer "F.Fab")
		)
		(fp_line
			(start -0.67945 -0.305054)
			(end -0.12065 -0.305054)
			(stroke
				(width 0.1)
				(type default)
			)
			(layer "F.Fab")
		)
		(fp_line
			(start 0.67945 -0.3048)
			(end 0.67945 0.3048)
			(stroke
				(width 0.1)
				(type default)
			)
			(layer "F.Fab")
		)
		(fp_line
			(start 0.12065 -0.3048)
			(end 0.67945 -0.3048)
			(stroke
				(width 0.1)
				(type default)
			)
			(layer "F.Fab")
		)
		(fp_line
			(start 0.12065 -0.2794)
			(end 0.12065 -0.3048)
			(stroke
				(width 0.1)
				(type default)
			)
			(layer "F.Fab")
		)
		(fp_line
			(start -0.12065 -0.2794)
			(end 0.12065 -0.2794)
			(stroke
				(width 0.1)
				(type default)
			)
			(layer "F.Fab")
		)
		(fp_line
			(start 0.120396 0.2794)
			(end -0.12065 0.2794)
			(stroke
				(width 0.1)
				(type default)
			)
			(layer "F.Fab")
		)
		(fp_line
			(start -0.12065 0.2794)
			(end -0.12065 0.3048)
			(stroke
				(width 0.1)
				(type default)
			)
			(layer "F.Fab")
		)
		(fp_line
			(start 0.67945 0.3048)
			(end 0.120396 0.3048)
			(stroke
				(width 0.1)
				(type default)
			)
			(layer "F.Fab")
		)
		(fp_line
			(start 0.120396 0.3048)
			(end 0.120396 0.2794)
			(stroke
				(width 0.1)
				(type default)
			)
			(layer "F.Fab")
		)
		(fp_line
			(start -0.12065 0.3048)
			(end -0.67945 0.3048)
			(stroke
				(width 0.1)
				(type default)
			)
			(layer "F.Fab")
		)
		(fp_line
			(start -0.67945 0.3048)
			(end -0.67945 -0.305054)
			(stroke
				(width 0.1)
				(type default)
			)
			(layer "F.Fab")
		)
		(pad "1" smd circle
			(at -0.40005 0 90)
			(size 0 0)
			(layers "F.Cu" "F.Mask" "F.Paste")
			(net "P3V3_SSD14_SS")
		)
		(pad "2" smd circle
			(at 0.40005 0 90)
			(size 0 0)
			(layers "F.Cu" "F.Mask" "F.Paste")
			(net "GND")
		)
	)
	(footprint ""
		(layer "F.Cu")
		(at 431.946812 -356.244906 90)
		(property "Reference" "C2462"
			(at 0 0 90)
			(layer "F.SilkS")
			(hide yes)
			(effects
				(font
					(size 1.27 1.27)
				)
			)
		)
		(property "Value" ""
			(at 0 0 90)
			(layer "F.Fab")
			(effects
				(font
					(size 1.27 1.27)
				)
			)
		)
		(duplicate_pad_numbers_are_jumpers no)
		(fp_line
			(start 0.299974 -0.150114)
			(end 0.299974 0.150114)
			(stroke
				(width 0.1)
				(type default)
			)
			(layer "F.Fab")
		)
		(fp_line
			(start -0.299974 -0.150114)
			(end 0.299974 -0.150114)
			(stroke
				(width 0.1)
				(type default)
			)
			(layer "F.Fab")
		)
		(fp_line
			(start 0.299974 0.150114)
			(end -0.299974 0.150114)
			(stroke
				(width 0.1)
				(type default)
			)
			(layer "F.Fab")
		)
		(fp_line
			(start -0.299974 0.150114)
			(end -0.299974 -0.150114)
			(stroke
				(width 0.1)
				(type default)
			)
			(layer "F.Fab")
		)
		(pad "1" smd rect
			(at -0.2667 0 90)
			(size 0.3048 0.381)
			(layers "F.Cu" "F.Mask" "F.Paste")
			(net "P5E_PEX3_STN4_TX_DN<68>")
		)
		(pad "2" smd rect
			(at 0.2667 0 90)
			(size 0.3048 0.381)
			(layers "F.Cu" "F.Mask" "F.Paste")
			(net "P5E_PEX3_STN4_TX_C_DN<68>")
		)
	)
	(footprint ""
		(layer "F.Cu")
		(at 143.30045 -256.478786)
		(property "Reference" "C3240"
			(at 0 0 0)
			(layer "F.SilkS")
			(hide yes)
			(effects
				(font
					(size 1.27 1.27)
				)
			)
		)
		(property "Value" ""
			(at 0 0 0)
			(layer "F.Fab")
			(effects
				(font
					(size 1.27 1.27)
				)
			)
		)
		(duplicate_pad_numbers_are_jumpers no)
		(fp_line
			(start -0.299974 -0.150114)
			(end 0.299974 -0.150114)
			(stroke
				(width 0.1)
				(type default)
			)
			(layer "F.Fab")
		)
		(fp_line
			(start -0.299974 0.150114)
			(end -0.299974 -0.150114)
			(stroke
				(width 0.1)
				(type default)
			)
			(layer "F.Fab")
		)
		(fp_line
			(start 0.299974 -0.150114)
			(end 0.299974 0.150114)
			(stroke
				(width 0.1)
				(type default)
			)
			(layer "F.Fab")
		)
		(fp_line
			(start 0.299974 0.150114)
			(end -0.299974 0.150114)
			(stroke
				(width 0.1)
				(type default)
			)
			(layer "F.Fab")
		)
		(pad "1" smd rect
			(at -0.2667 0)
			(size 0.3048 0.381)
			(layers "F.Cu" "F.Mask" "F.Paste")
			(net "P1V8_PLL0_PEX1")
		)
		(pad "2" smd rect
			(at 0.2667 0)
			(size 0.3048 0.381)
			(layers "F.Cu" "F.Mask" "F.Paste")
			(net "GND")
		)
	)
	(footprint ""
		(layer "F.Cu")
		(at 436.95239 -116.416836 180)
		(property "Reference" "PC912"
			(at 0 0 180)
			(layer "F.SilkS")
			(hide yes)
			(effects
				(font
					(size 1.27 1.27)
				)
			)
		)
		(property "Value" ""
			(at 0 0 180)
			(layer "F.Fab")
			(effects
				(font
					(size 1.27 1.27)
				)
			)
		)
		(duplicate_pad_numbers_are_jumpers no)
		(fp_line
			(start 0.7874 0.4064)
			(end -0.7874 0.4064)
			(stroke
				(width 0.1524)
				(type default)
			)
			(layer "F.SilkS")
		)
		(fp_line
			(start 0.7874 -0.4064)
			(end 0.7874 0.4064)
			(stroke
				(width 0.1524)
				(type default)
			)
			(layer "F.SilkS")
		)
		(fp_line
			(start -0.7874 0.4064)
			(end -0.7874 -0.4064)
			(stroke
				(width 0.1524)
				(type default)
			)
			(layer "F.SilkS")
		)
		(fp_line
			(start -0.7874 -0.4064)
			(end 0.7874 -0.4064)
			(stroke
				(width 0.1524)
				(type default)
			)
			(layer "F.SilkS")
		)
		(fp_line
			(start 0.67945 0.3048)
			(end 0.120396 0.3048)
			(stroke
				(width 0.1)
				(type default)
			)
			(layer "F.Fab")
		)
		(fp_line
			(start 0.67945 -0.3048)
			(end 0.67945 0.3048)
			(stroke
				(width 0.1)
				(type default)
			)
			(layer "F.Fab")
		)
		(fp_line
			(start 0.12065 -0.2794)
			(end 0.12065 -0.3048)
			(stroke
				(width 0.1)
				(type default)
			)
			(layer "F.Fab")
		)
		(fp_line
			(start 0.12065 -0.3048)
			(end 0.67945 -0.3048)
			(stroke
				(width 0.1)
				(type default)
			)
			(layer "F.Fab")
		)
		(fp_line
			(start 0.120396 0.3048)
			(end 0.120396 0.2794)
			(stroke
				(width 0.1)
				(type default)
			)
			(layer "F.Fab")
		)
		(fp_line
			(start 0.120396 0.2794)
			(end -0.12065 0.2794)
			(stroke
				(width 0.1)
				(type default)
			)
			(layer "F.Fab")
		)
		(fp_line
			(start -0.12065 0.3048)
			(end -0.67945 0.3048)
			(stroke
				(width 0.1)
				(type default)
			)
			(layer "F.Fab")
		)
		(fp_line
			(start -0.12065 0.2794)
			(end -0.12065 0.3048)
			(stroke
				(width 0.1)
				(type default)
			)
			(layer "F.Fab")
		)
		(fp_line
			(start -0.12065 -0.2794)
			(end 0.12065 -0.2794)
			(stroke
				(width 0.1)
				(type default)
			)
			(layer "F.Fab")
		)
		(fp_line
			(start -0.12065 -0.305054)
			(end -0.12065 -0.2794)
			(stroke
				(width 0.1)
				(type default)
			)
			(layer "F.Fab")
		)
		(fp_line
			(start -0.67945 0.3048)
			(end -0.67945 -0.305054)
			(stroke
				(width 0.1)
				(type default)
			)
			(layer "F.Fab")
		)
		(fp_line
			(start -0.67945 -0.305054)
			(end -0.12065 -0.305054)
			(stroke
				(width 0.1)
				(type default)
			)
			(layer "F.Fab")
		)
		(pad "1" smd circle
			(at -0.40005 0 180)
			(size 0 0)
			(layers "F.Cu" "F.Mask" "F.Paste")
			(net "P3V3_NIC7_CO_GATE")
		)
		(pad "2" smd circle
			(at 0.40005 0 180)
			(size 0 0)
			(layers "F.Cu" "F.Mask" "F.Paste")
			(net "GND")
		)
	)
	(footprint ""
		(layer "F.Cu")
		(at 364.552992 -159.173418 90)
		(property "Reference" "PC798"
			(at 0 0 90)
			(layer "F.SilkS")
			(hide yes)
			(effects
				(font
					(size 1.27 1.27)
				)
			)
		)
		(property "Value" ""
			(at 0 0 90)
			(layer "F.Fab")
			(effects
				(font
					(size 1.27 1.27)
				)
			)
		)
		(duplicate_pad_numbers_are_jumpers no)
		(fp_line
			(start 0.7874 -0.4064)
			(end 0.7874 0.4064)
			(stroke
				(width 0.1524)
				(type default)
			)
			(layer "F.SilkS")
		)
		(fp_line
			(start -0.7874 -0.4064)
			(end 0.7874 -0.4064)
			(stroke
				(width 0.1524)
				(type default)
			)
			(layer "F.SilkS")
		)
		(fp_line
			(start 0.7874 0.4064)
			(end -0.7874 0.4064)
			(stroke
				(width 0.1524)
				(type default)
			)
			(layer "F.SilkS")
		)
		(fp_line
			(start -0.7874 0.4064)
			(end -0.7874 -0.4064)
			(stroke
				(width 0.1524)
				(type default)
			)
			(layer "F.SilkS")
		)
		(fp_line
			(start -0.12065 -0.305054)
			(end -0.12065 -0.2794)
			(stroke
				(width 0.1)
				(type default)
			)
			(layer "F.Fab")
		)
		(fp_line
			(start -0.67945 -0.305054)
			(end -0.12065 -0.305054)
			(stroke
				(width 0.1)
				(type default)
			)
			(layer "F.Fab")
		)
		(fp_line
			(start 0.67945 -0.3048)
			(end 0.67945 0.3048)
			(stroke
				(width 0.1)
				(type default)
			)
			(layer "F.Fab")
		)
		(fp_line
			(start 0.12065 -0.3048)
			(end 0.67945 -0.3048)
			(stroke
				(width 0.1)
				(type default)
			)
			(layer "F.Fab")
		)
		(fp_line
			(start 0.12065 -0.2794)
			(end 0.12065 -0.3048)
			(stroke
				(width 0.1)
				(type default)
			)
			(layer "F.Fab")
		)
		(fp_line
			(start -0.12065 -0.2794)
			(end 0.12065 -0.2794)
			(stroke
				(width 0.1)
				(type default)
			)
			(layer "F.Fab")
		)
		(fp_line
			(start 0.120396 0.2794)
			(end -0.12065 0.2794)
			(stroke
				(width 0.1)
				(type default)
			)
			(layer "F.Fab")
		)
		(fp_line
			(start -0.12065 0.2794)
			(end -0.12065 0.3048)
			(stroke
				(width 0.1)
				(type default)
			)
			(layer "F.Fab")
		)
		(fp_line
			(start 0.67945 0.3048)
			(end 0.120396 0.3048)
			(stroke
				(width 0.1)
				(type default)
			)
			(layer "F.Fab")
		)
		(fp_line
			(start 0.120396 0.3048)
			(end 0.120396 0.2794)
			(stroke
				(width 0.1)
				(type default)
			)
			(layer "F.Fab")
		)
		(fp_line
			(start -0.12065 0.3048)
			(end -0.67945 0.3048)
			(stroke
				(width 0.1)
				(type default)
			)
			(layer "F.Fab")
		)
		(fp_line
			(start -0.67945 0.3048)
			(end -0.67945 -0.305054)
			(stroke
				(width 0.1)
				(type default)
			)
			(layer "F.Fab")
		)
		(pad "1" smd circle
			(at -0.40005 0 90)
			(size 0 0)
			(layers "F.Cu" "F.Mask" "F.Paste")
			(net "P12V_AUX")
		)
		(pad "2" smd circle
			(at 0.40005 0 90)
			(size 0 0)
			(layers "F.Cu" "F.Mask" "F.Paste")
			(net "GND")
		)
	)
	(footprint ""
		(layer "F.Cu")
		(at 286.385 -84.836 180)
		(property "Reference" "R490"
			(at 0 0 180)
			(layer "F.SilkS")
			(hide yes)
			(effects
				(font
					(size 1.27 1.27)
				)
			)
		)
		(property "Value" ""
			(at 0 0 180)
			(layer "F.Fab")
			(effects
				(font
					(size 1.27 1.27)
				)
			)
		)
		(duplicate_pad_numbers_are_jumpers no)
		(fp_line
			(start 0.7874 0.4064)
			(end -0.7874 0.4064)
			(stroke
				(width 0.1524)
				(type default)
			)
			(layer "F.SilkS")
		)
		(fp_line
			(start 0.7874 -0.4064)
			(end 0.7874 0.4064)
			(stroke
				(width 0.1524)
				(type default)
			)
			(layer "F.SilkS")
		)
		(fp_line
			(start -0.7874 0.4064)
			(end -0.7874 -0.4064)
			(stroke
				(width 0.1524)
				(type default)
			)
			(layer "F.SilkS")
		)
		(fp_line
			(start -0.7874 -0.4064)
			(end 0.7874 -0.4064)
			(stroke
				(width 0.1524)
				(type default)
			)
			(layer "F.SilkS")
		)
		(fp_line
			(start 0.67945 0.3048)
			(end 0.120396 0.3048)
			(stroke
				(width 0.1)
				(type default)
			)
			(layer "F.Fab")
		)
		(fp_line
			(start 0.67945 -0.3048)
			(end 0.67945 0.3048)
			(stroke
				(width 0.1)
				(type default)
			)
			(layer "F.Fab")
		)
		(fp_line
			(start 0.12065 -0.2794)
			(end 0.12065 -0.3048)
			(stroke
				(width 0.1)
				(type default)
			)
			(layer "F.Fab")
		)
		(fp_line
			(start 0.12065 -0.3048)
			(end 0.67945 -0.3048)
			(stroke
				(width 0.1)
				(type default)
			)
			(layer "F.Fab")
		)
		(fp_line
			(start 0.120396 0.3048)
			(end 0.120396 0.2794)
			(stroke
				(width 0.1)
				(type default)
			)
			(layer "F.Fab")
		)
		(fp_line
			(start 0.120396 0.2794)
			(end -0.12065 0.2794)
			(stroke
				(width 0.1)
				(type default)
			)
			(layer "F.Fab")
		)
		(fp_line
			(start -0.12065 0.3048)
			(end -0.67945 0.3048)
			(stroke
				(width 0.1)
				(type default)
			)
			(layer "F.Fab")
		)
		(fp_line
			(start -0.12065 0.2794)
			(end -0.12065 0.3048)
			(stroke
				(width 0.1)
				(type default)
			)
			(layer "F.Fab")
		)
		(fp_line
			(start -0.12065 -0.2794)
			(end 0.12065 -0.2794)
			(stroke
				(width 0.1)
				(type default)
			)
			(layer "F.Fab")
		)
		(fp_line
			(start -0.12065 -0.305054)
			(end -0.12065 -0.2794)
			(stroke
				(width 0.1)
				(type default)
			)
			(layer "F.Fab")
		)
		(fp_line
			(start -0.67945 0.3048)
			(end -0.67945 -0.305054)
			(stroke
				(width 0.1)
				(type default)
			)
			(layer "F.Fab")
		)
		(fp_line
			(start -0.67945 -0.305054)
			(end -0.12065 -0.305054)
			(stroke
				(width 0.1)
				(type default)
			)
			(layer "F.Fab")
		)
		(pad "1" smd circle
			(at -0.40005 0 180)
			(size 0 0)
			(layers "F.Cu" "F.Mask" "F.Paste")
			(net "BB_FRU_A1")
		)
		(pad "2" smd circle
			(at 0.40005 0 180)
			(size 0 0)
			(layers "F.Cu" "F.Mask" "F.Paste")
			(net "GND")
		)
	)
	(footprint ""
		(layer "F.Cu")
		(at 348.742 -205.232 90)
		(property "Reference" "R4152"
			(at 0 0 90)
			(layer "F.SilkS")
			(hide yes)
			(effects
				(font
					(size 1.27 1.27)
				)
			)
		)
		(property "Value" ""
			(at 0 0 90)
			(layer "F.Fab")
			(effects
				(font
					(size 1.27 1.27)
				)
			)
		)
		(duplicate_pad_numbers_are_jumpers no)
		(fp_line
			(start 0.7874 -0.4064)
			(end 0.7874 0.4064)
			(stroke
				(width 0.1524)
				(type default)
			)
			(layer "F.SilkS")
		)
		(fp_line
			(start -0.7874 -0.4064)
			(end 0.7874 -0.4064)
			(stroke
				(width 0.1524)
				(type default)
			)
			(layer "F.SilkS")
		)
		(fp_line
			(start 0.7874 0.4064)
			(end -0.7874 0.4064)
			(stroke
				(width 0.1524)
				(type default)
			)
			(layer "F.SilkS")
		)
		(fp_line
			(start -0.7874 0.4064)
			(end -0.7874 -0.4064)
			(stroke
				(width 0.1524)
				(type default)
			)
			(layer "F.SilkS")
		)
		(fp_line
			(start -0.12065 -0.305054)
			(end -0.12065 -0.2794)
			(stroke
				(width 0.1)
				(type default)
			)
			(layer "F.Fab")
		)
		(fp_line
			(start -0.67945 -0.305054)
			(end -0.12065 -0.305054)
			(stroke
				(width 0.1)
				(type default)
			)
			(layer "F.Fab")
		)
		(fp_line
			(start 0.67945 -0.3048)
			(end 0.67945 0.3048)
			(stroke
				(width 0.1)
				(type default)
			)
			(layer "F.Fab")
		)
		(fp_line
			(start 0.12065 -0.3048)
			(end 0.67945 -0.3048)
			(stroke
				(width 0.1)
				(type default)
			)
			(layer "F.Fab")
		)
		(fp_line
			(start 0.12065 -0.2794)
			(end 0.12065 -0.3048)
			(stroke
				(width 0.1)
				(type default)
			)
			(layer "F.Fab")
		)
		(fp_line
			(start -0.12065 -0.2794)
			(end 0.12065 -0.2794)
			(stroke
				(width 0.1)
				(type default)
			)
			(layer "F.Fab")
		)
		(fp_line
			(start 0.120396 0.2794)
			(end -0.12065 0.2794)
			(stroke
				(width 0.1)
				(type default)
			)
			(layer "F.Fab")
		)
		(fp_line
			(start -0.12065 0.2794)
			(end -0.12065 0.3048)
			(stroke
				(width 0.1)
				(type default)
			)
			(layer "F.Fab")
		)
		(fp_line
			(start 0.67945 0.3048)
			(end 0.120396 0.3048)
			(stroke
				(width 0.1)
				(type default)
			)
			(layer "F.Fab")
		)
		(fp_line
			(start 0.120396 0.3048)
			(end 0.120396 0.2794)
			(stroke
				(width 0.1)
				(type default)
			)
			(layer "F.Fab")
		)
		(fp_line
			(start -0.12065 0.3048)
			(end -0.67945 0.3048)
			(stroke
				(width 0.1)
				(type default)
			)
			(layer "F.Fab")
		)
		(fp_line
			(start -0.67945 0.3048)
			(end -0.67945 -0.305054)
			(stroke
				(width 0.1)
				(type default)
			)
			(layer "F.Fab")
		)
		(pad "1" smd circle
			(at -0.40005 0 90)
			(size 0 0)
			(layers "F.Cu" "F.Mask" "F.Paste")
			(net "PRSNT_SSD5_FPGA_R_N")
		)
		(pad "2" smd circle
			(at 0.40005 0 90)
			(size 0 0)
			(layers "F.Cu" "F.Mask" "F.Paste")
			(net "PRSNT_SSD5_FPGA_N")
		)
	)
	(footprint ""
		(layer "F.Cu")
		(at 225.775774 -280.10104 180)
		(property "Reference" "C826"
			(at 0 0 180)
			(layer "F.SilkS")
			(hide yes)
			(effects
				(font
					(size 1.27 1.27)
				)
			)
		)
		(property "Value" ""
			(at 0 0 180)
			(layer "F.Fab")
			(effects
				(font
					(size 1.27 1.27)
				)
			)
		)
		(duplicate_pad_numbers_are_jumpers no)
		(fp_line
			(start 0.7874 0.4064)
			(end -0.7874 0.4064)
			(stroke
				(width 0.1524)
				(type default)
			)
			(layer "F.SilkS")
		)
		(fp_line
			(start 0.7874 -0.4064)
			(end 0.7874 0.4064)
			(stroke
				(width 0.1524)
				(type default)
			)
			(layer "F.SilkS")
		)
		(fp_line
			(start -0.7874 0.4064)
			(end -0.7874 -0.4064)
			(stroke
				(width 0.1524)
				(type default)
			)
			(layer "F.SilkS")
		)
		(fp_line
			(start -0.7874 -0.4064)
			(end 0.7874 -0.4064)
			(stroke
				(width 0.1524)
				(type default)
			)
			(layer "F.SilkS")
		)
		(fp_line
			(start 0.67945 0.3048)
			(end 0.120396 0.3048)
			(stroke
				(width 0.1)
				(type default)
			)
			(layer "F.Fab")
		)
		(fp_line
			(start 0.67945 -0.3048)
			(end 0.67945 0.3048)
			(stroke
				(width 0.1)
				(type default)
			)
			(layer "F.Fab")
		)
		(fp_line
			(start 0.12065 -0.2794)
			(end 0.12065 -0.3048)
			(stroke
				(width 0.1)
				(type default)
			)
			(layer "F.Fab")
		)
		(fp_line
			(start 0.12065 -0.3048)
			(end 0.67945 -0.3048)
			(stroke
				(width 0.1)
				(type default)
			)
			(layer "F.Fab")
		)
		(fp_line
			(start 0.120396 0.3048)
			(end 0.120396 0.2794)
			(stroke
				(width 0.1)
				(type default)
			)
			(layer "F.Fab")
		)
		(fp_line
			(start 0.120396 0.2794)
			(end -0.12065 0.2794)
			(stroke
				(width 0.1)
				(type default)
			)
			(layer "F.Fab")
		)
		(fp_line
			(start -0.12065 0.3048)
			(end -0.67945 0.3048)
			(stroke
				(width 0.1)
				(type default)
			)
			(layer "F.Fab")
		)
		(fp_line
			(start -0.12065 0.2794)
			(end -0.12065 0.3048)
			(stroke
				(width 0.1)
				(type default)
			)
			(layer "F.Fab")
		)
		(fp_line
			(start -0.12065 -0.2794)
			(end 0.12065 -0.2794)
			(stroke
				(width 0.1)
				(type default)
			)
			(layer "F.Fab")
		)
		(fp_line
			(start -0.12065 -0.305054)
			(end -0.12065 -0.2794)
			(stroke
				(width 0.1)
				(type default)
			)
			(layer "F.Fab")
		)
		(fp_line
			(start -0.67945 0.3048)
			(end -0.67945 -0.305054)
			(stroke
				(width 0.1)
				(type default)
			)
			(layer "F.Fab")
		)
		(fp_line
			(start -0.67945 -0.305054)
			(end -0.12065 -0.305054)
			(stroke
				(width 0.1)
				(type default)
			)
			(layer "F.Fab")
		)
		(pad "1" smd circle
			(at -0.40005 0 180)
			(size 0 0)
			(layers "F.Cu" "F.Mask" "F.Paste")
			(net "P3V3_AUX")
		)
		(pad "2" smd circle
			(at 0.40005 0 180)
			(size 0 0)
			(layers "F.Cu" "F.Mask" "F.Paste")
			(net "GND")
		)
	)
	(footprint ""
		(layer "F.Cu")
		(at 261.07517 -64.102234 180)
		(property "Reference" "PR7080"
			(at 0 0 180)
			(layer "F.SilkS")
			(hide yes)
			(effects
				(font
					(size 1.27 1.27)
				)
			)
		)
		(property "Value" ""
			(at 0 0 180)
			(layer "F.Fab")
			(effects
				(font
					(size 1.27 1.27)
				)
			)
		)
		(duplicate_pad_numbers_are_jumpers no)
		(fp_line
			(start 0.7874 0.4064)
			(end -0.7874 0.4064)
			(stroke
				(width 0.1524)
				(type default)
			)
			(layer "F.SilkS")
		)
		(fp_line
			(start 0.7874 -0.4064)
			(end 0.7874 0.4064)
			(stroke
				(width 0.1524)
				(type default)
			)
			(layer "F.SilkS")
		)
		(fp_line
			(start -0.7874 0.4064)
			(end -0.7874 -0.4064)
			(stroke
				(width 0.1524)
				(type default)
			)
			(layer "F.SilkS")
		)
		(fp_line
			(start -0.7874 -0.4064)
			(end 0.7874 -0.4064)
			(stroke
				(width 0.1524)
				(type default)
			)
			(layer "F.SilkS")
		)
		(fp_line
			(start 0.67945 0.3048)
			(end 0.120396 0.3048)
			(stroke
				(width 0.1)
				(type default)
			)
			(layer "F.Fab")
		)
		(fp_line
			(start 0.67945 -0.3048)
			(end 0.67945 0.3048)
			(stroke
				(width 0.1)
				(type default)
			)
			(layer "F.Fab")
		)
		(fp_line
			(start 0.12065 -0.2794)
			(end 0.12065 -0.3048)
			(stroke
				(width 0.1)
				(type default)
			)
			(layer "F.Fab")
		)
		(fp_line
			(start 0.12065 -0.3048)
			(end 0.67945 -0.3048)
			(stroke
				(width 0.1)
				(type default)
			)
			(layer "F.Fab")
		)
		(fp_line
			(start 0.120396 0.3048)
			(end 0.120396 0.2794)
			(stroke
				(width 0.1)
				(type default)
			)
			(layer "F.Fab")
		)
		(fp_line
			(start 0.120396 0.2794)
			(end -0.12065 0.2794)
			(stroke
				(width 0.1)
				(type default)
			)
			(layer "F.Fab")
		)
		(fp_line
			(start -0.12065 0.3048)
			(end -0.67945 0.3048)
			(stroke
				(width 0.1)
				(type default)
			)
			(layer "F.Fab")
		)
		(fp_line
			(start -0.12065 0.2794)
			(end -0.12065 0.3048)
			(stroke
				(width 0.1)
				(type default)
			)
			(layer "F.Fab")
		)
		(fp_line
			(start -0.12065 -0.2794)
			(end 0.12065 -0.2794)
			(stroke
				(width 0.1)
				(type default)
			)
			(layer "F.Fab")
		)
		(fp_line
			(start -0.12065 -0.305054)
			(end -0.12065 -0.2794)
			(stroke
				(width 0.1)
				(type default)
			)
			(layer "F.Fab")
		)
		(fp_line
			(start -0.67945 0.3048)
			(end -0.67945 -0.305054)
			(stroke
				(width 0.1)
				(type default)
			)
			(layer "F.Fab")
		)
		(fp_line
			(start -0.67945 -0.305054)
			(end -0.12065 -0.305054)
			(stroke
				(width 0.1)
				(type default)
			)
			(layer "F.Fab")
		)
		(pad "1" smd circle
			(at -0.40005 0 180)
			(size 0 0)
			(layers "F.Cu" "F.Mask" "F.Paste")
			(net "P12V_SSD9_PG_G1")
		)
		(pad "2" smd circle
			(at 0.40005 0 180)
			(size 0 0)
			(layers "F.Cu" "F.Mask" "F.Paste")
			(net "GND")
		)
	)
	(footprint ""
		(layer "F.Cu")
		(at 336.509868 -280.44902 -90)
		(property "Reference" "PC146"
			(at 0 0 270)
			(layer "F.SilkS")
			(hide yes)
			(effects
				(font
					(size 1.27 1.27)
				)
			)
		)
		(property "Value" ""
			(at 0 0 270)
			(layer "F.Fab")
			(effects
				(font
					(size 1.27 1.27)
				)
			)
		)
		(duplicate_pad_numbers_are_jumpers no)
		(fp_line
			(start -0.7874 0.4064)
			(end -0.7874 -0.4064)
			(stroke
				(width 0.1524)
				(type default)
			)
			(layer "F.SilkS")
		)
		(fp_line
			(start 0.7874 0.4064)
			(end -0.7874 0.4064)
			(stroke
				(width 0.1524)
				(type default)
			)
			(layer "F.SilkS")
		)
		(fp_line
			(start -0.7874 -0.4064)
			(end 0.7874 -0.4064)
			(stroke
				(width 0.1524)
				(type default)
			)
			(layer "F.SilkS")
		)
		(fp_line
			(start 0.7874 -0.4064)
			(end 0.7874 0.4064)
			(stroke
				(width 0.1524)
				(type default)
			)
			(layer "F.SilkS")
		)
		(fp_line
			(start -0.67945 0.3048)
			(end -0.67945 -0.305054)
			(stroke
				(width 0.1)
				(type default)
			)
			(layer "F.Fab")
		)
		(fp_line
			(start -0.12065 0.3048)
			(end -0.67945 0.3048)
			(stroke
				(width 0.1)
				(type default)
			)
			(layer "F.Fab")
		)
		(fp_line
			(start 0.120396 0.3048)
			(end 0.120396 0.2794)
			(stroke
				(width 0.1)
				(type default)
			)
			(layer "F.Fab")
		)
		(fp_line
			(start 0.67945 0.3048)
			(end 0.120396 0.3048)
			(stroke
				(width 0.1)
				(type default)
			)
			(layer "F.Fab")
		)
		(fp_line
			(start -0.12065 0.2794)
			(end -0.12065 0.3048)
			(stroke
				(width 0.1)
				(type default)
			)
			(layer "F.Fab")
		)
		(fp_line
			(start 0.120396 0.2794)
			(end -0.12065 0.2794)
			(stroke
				(width 0.1)
				(type default)
			)
			(layer "F.Fab")
		)
		(fp_line
			(start -0.12065 -0.2794)
			(end 0.12065 -0.2794)
			(stroke
				(width 0.1)
				(type default)
			)
			(layer "F.Fab")
		)
		(fp_line
			(start 0.12065 -0.2794)
			(end 0.12065 -0.3048)
			(stroke
				(width 0.1)
				(type default)
			)
			(layer "F.Fab")
		)
		(fp_line
			(start 0.12065 -0.3048)
			(end 0.67945 -0.3048)
			(stroke
				(width 0.1)
				(type default)
			)
			(layer "F.Fab")
		)
		(fp_line
			(start 0.67945 -0.3048)
			(end 0.67945 0.3048)
			(stroke
				(width 0.1)
				(type default)
			)
			(layer "F.Fab")
		)
		(fp_line
			(start -0.67945 -0.305054)
			(end -0.12065 -0.305054)
			(stroke
				(width 0.1)
				(type default)
			)
			(layer "F.Fab")
		)
		(fp_line
			(start -0.12065 -0.305054)
			(end -0.12065 -0.2794)
			(stroke
				(width 0.1)
				(type default)
			)
			(layer "F.Fab")
		)
		(pad "1" smd circle
			(at -0.40005 0 270)
			(size 0 0)
			(layers "F.Cu" "F.Mask" "F.Paste")
			(net "SW_P0V8_PEX2_PHASE1")
		)
		(pad "2" smd circle
			(at 0.40005 0 270)
			(size 0 0)
			(layers "F.Cu" "F.Mask" "F.Paste")
			(net "SW_P0V8_PEX2_BOOT1_R")
		)
	)
	(footprint ""
		(layer "F.Cu")
		(at 375.686828 -307.803296 -135)
		(property "Reference" "R1398"
			(at 0 0 225)
			(layer "F.SilkS")
			(hide yes)
			(effects
				(font
					(size 1.27 1.27)
				)
			)
		)
		(property "Value" ""
			(at 0 0 225)
			(layer "F.Fab")
			(effects
				(font
					(size 1.27 1.27)
				)
			)
		)
		(duplicate_pad_numbers_are_jumpers no)
		(fp_line
			(start 0.787389 0.406267)
			(end -0.787389 0.406267)
			(stroke
				(width 0.1524)
				(type default)
			)
			(layer "F.SilkS")
		)
		(fp_line
			(start 0.787389 -0.406267)
			(end 0.787389 0.406267)
			(stroke
				(width 0.1524)
				(type default)
			)
			(layer "F.SilkS")
		)
		(fp_line
			(start -0.787389 0.406267)
			(end -0.787389 -0.406267)
			(stroke
				(width 0.1524)
				(type default)
			)
			(layer "F.SilkS")
		)
		(fp_line
			(start -0.787389 -0.406267)
			(end 0.787389 -0.406267)
			(stroke
				(width 0.1524)
				(type default)
			)
			(layer "F.SilkS")
		)
		(fp_line
			(start 0.679446 0.30479)
			(end 0.120515 0.30479)
			(stroke
				(width 0.1)
				(type default)
			)
			(layer "F.Fab")
		)
		(fp_line
			(start 0.120515 0.30479)
			(end 0.120335 0.279466)
			(stroke
				(width 0.1)
				(type default)
			)
			(layer "F.Fab")
		)
		(fp_line
			(start 0.120335 0.279466)
			(end -0.120695 0.279466)
			(stroke
				(width 0.1)
				(type default)
			)
			(layer "F.Fab")
		)
		(fp_line
			(start 0.679446 -0.30479)
			(end 0.679446 0.30479)
			(stroke
				(width 0.1)
				(type default)
			)
			(layer "F.Fab")
		)
		(fp_line
			(start -0.120515 0.30479)
			(end -0.679446 0.30479)
			(stroke
				(width 0.1)
				(type default)
			)
			(layer "F.Fab")
		)
		(fp_line
			(start -0.120695 0.279466)
			(end -0.120515 0.30479)
			(stroke
				(width 0.1)
				(type default)
			)
			(layer "F.Fab")
		)
		(fp_line
			(start 0.120695 -0.279466)
			(end 0.120515 -0.30479)
			(stroke
				(width 0.1)
				(type default)
			)
			(layer "F.Fab")
		)
		(fp_line
			(start 0.120515 -0.30479)
			(end 0.679446 -0.30479)
			(stroke
				(width 0.1)
				(type default)
			)
			(layer "F.Fab")
		)
		(fp_line
			(start -0.679446 0.30479)
			(end -0.679446 -0.305149)
			(stroke
				(width 0.1)
				(type default)
			)
			(layer "F.Fab")
		)
		(fp_line
			(start -0.120695 -0.279466)
			(end 0.120695 -0.279466)
			(stroke
				(width 0.1)
				(type default)
			)
			(layer "F.Fab")
		)
		(fp_line
			(start -0.120695 -0.304969)
			(end -0.120695 -0.279466)
			(stroke
				(width 0.1)
				(type default)
			)
			(layer "F.Fab")
		)
		(fp_line
			(start -0.679446 -0.305149)
			(end -0.120695 -0.304969)
			(stroke
				(width 0.1)
				(type default)
			)
			(layer "F.Fab")
		)
		(pad "1" smd circle
			(at -0.40005 0 225)
			(size 0 0)
			(layers "F.Cu" "F.Mask" "F.Paste")
			(net "PEX3_DBG_SEL0")
		)
		(pad "2" smd circle
			(at 0.40005 0 225)
			(size 0 0)
			(layers "F.Cu" "F.Mask" "F.Paste")
			(net "P1V8_PEX")
		)
	)
	(footprint ""
		(layer "F.Cu")
		(at 51.61153 -71.458074 -90)
		(property "Reference" "PD88"
			(at 4.198874 -2.79654 90)
			(unlocked yes)
			(layer "F.SilkS")
			(effects
				(font
					(size 0.7874 0.5842)
					(thickness 0.1524)
				)
				(justify left)
			)
		)
		(property "Value" ""
			(at 0 0 270)
			(layer "F.Fab")
			(effects
				(font
					(size 1.27 1.27)
				)
			)
		)
		(duplicate_pad_numbers_are_jumpers no)
		(fp_line
			(start -3.656584 1.970024)
			(end 4.240784 1.970024)
			(stroke
				(width 0.1524)
				(type default)
			)
			(layer "F.SilkS")
		)
		(fp_line
			(start 4.240784 1.970024)
			(end 4.240784 -1.970024)
			(stroke
				(width 0.1524)
				(type default)
			)
			(layer "F.SilkS")
		)
		(fp_line
			(start -3.656584 -1.970024)
			(end -3.656584 1.970024)
			(stroke
				(width 0.1524)
				(type default)
			)
			(layer "F.SilkS")
		)
		(fp_line
			(start 4.240784 -1.970024)
			(end -3.656584 -1.970024)
			(stroke
				(width 0.1524)
				(type default)
			)
			(layer "F.SilkS")
		)
		(fp_poly
			(pts
				(xy 3.580384 1.970024) (xy 3.580384 -1.970024) (xy 4.240784 -1.970024) (xy 4.240784 1.970024)
			)
			(stroke
				(width 0)
				(type default)
			)
			(fill yes)
			(layer "F.SilkS")
		)
		(fp_line
			(start -2.3749 1.970024)
			(end 2.3749 1.970024)
			(stroke
				(width 0.1)
				(type default)
			)
			(layer "F.Fab")
		)
		(fp_line
			(start 2.3749 1.970024)
			(end 2.3749 -1.970024)
			(stroke
				(width 0.1)
				(type default)
			)
			(layer "F.Fab")
		)
		(fp_line
			(start -2.3749 -1.970024)
			(end -2.3749 1.970024)
			(stroke
				(width 0.1)
				(type default)
			)
			(layer "F.Fab")
		)
		(fp_line
			(start 2.3749 -1.970024)
			(end -2.3749 -1.970024)
			(stroke
				(width 0.1)
				(type default)
			)
			(layer "F.Fab")
		)
		(fp_text user "+"
			(at -4.9784 -0.23495 270)
			(unlocked yes)
			(layer "F.Fab")
			(effects
				(font
					(size 1.905 1.4224)
					(thickness 0.1524)
				)
				(justify left)
			)
		)
		(fp_text user "-"
			(at 4.1656 -0.23495 270)
			(unlocked yes)
			(layer "F.Fab")
			(effects
				(font
					(size 1.905 1.4224)
					(thickness 0.1524)
				)
				(justify left)
			)
		)
		(pad "A" smd rect
			(at -2.450084 0 270)
			(size 2.159 2.2606)
			(layers "F.Cu" "F.Mask" "F.Paste")
			(net "GND")
		)
		(pad "C" smd rect
			(at 2.450084 0 270)
			(size 2.159 2.2606)
			(layers "F.Cu" "F.Mask" "F.Paste")
			(net "P12V_AUX")
		)
	)
	(footprint ""
		(layer "F.Cu")
		(at 411.97784 -115.283742 180)
		(property "Reference" "R394"
			(at 0 0 180)
			(layer "F.SilkS")
			(hide yes)
			(effects
				(font
					(size 1.27 1.27)
				)
			)
		)
		(property "Value" ""
			(at 0 0 180)
			(layer "F.Fab")
			(effects
				(font
					(size 1.27 1.27)
				)
			)
		)
		(duplicate_pad_numbers_are_jumpers no)
		(fp_line
			(start 0.7874 0.4064)
			(end -0.7874 0.4064)
			(stroke
				(width 0.1524)
				(type default)
			)
			(layer "F.SilkS")
		)
		(fp_line
			(start 0.7874 -0.4064)
			(end 0.7874 0.4064)
			(stroke
				(width 0.1524)
				(type default)
			)
			(layer "F.SilkS")
		)
		(fp_line
			(start -0.7874 0.4064)
			(end -0.7874 -0.4064)
			(stroke
				(width 0.1524)
				(type default)
			)
			(layer "F.SilkS")
		)
		(fp_line
			(start -0.7874 -0.4064)
			(end 0.7874 -0.4064)
			(stroke
				(width 0.1524)
				(type default)
			)
			(layer "F.SilkS")
		)
		(fp_line
			(start 0.67945 0.3048)
			(end 0.120396 0.3048)
			(stroke
				(width 0.1)
				(type default)
			)
			(layer "F.Fab")
		)
		(fp_line
			(start 0.67945 -0.3048)
			(end 0.67945 0.3048)
			(stroke
				(width 0.1)
				(type default)
			)
			(layer "F.Fab")
		)
		(fp_line
			(start 0.12065 -0.2794)
			(end 0.12065 -0.3048)
			(stroke
				(width 0.1)
				(type default)
			)
			(layer "F.Fab")
		)
		(fp_line
			(start 0.12065 -0.3048)
			(end 0.67945 -0.3048)
			(stroke
				(width 0.1)
				(type default)
			)
			(layer "F.Fab")
		)
		(fp_line
			(start 0.120396 0.3048)
			(end 0.120396 0.2794)
			(stroke
				(width 0.1)
				(type default)
			)
			(layer "F.Fab")
		)
		(fp_line
			(start 0.120396 0.2794)
			(end -0.12065 0.2794)
			(stroke
				(width 0.1)
				(type default)
			)
			(layer "F.Fab")
		)
		(fp_line
			(start -0.12065 0.3048)
			(end -0.67945 0.3048)
			(stroke
				(width 0.1)
				(type default)
			)
			(layer "F.Fab")
		)
		(fp_line
			(start -0.12065 0.2794)
			(end -0.12065 0.3048)
			(stroke
				(width 0.1)
				(type default)
			)
			(layer "F.Fab")
		)
		(fp_line
			(start -0.12065 -0.2794)
			(end 0.12065 -0.2794)
			(stroke
				(width 0.1)
				(type default)
			)
			(layer "F.Fab")
		)
		(fp_line
			(start -0.12065 -0.305054)
			(end -0.12065 -0.2794)
			(stroke
				(width 0.1)
				(type default)
			)
			(layer "F.Fab")
		)
		(fp_line
			(start -0.67945 0.3048)
			(end -0.67945 -0.305054)
			(stroke
				(width 0.1)
				(type default)
			)
			(layer "F.Fab")
		)
		(fp_line
			(start -0.67945 -0.305054)
			(end -0.12065 -0.305054)
			(stroke
				(width 0.1)
				(type default)
			)
			(layer "F.Fab")
		)
		(pad "1" smd circle
			(at -0.40005 0 180)
			(size 0 0)
			(layers "F.Cu" "F.Mask" "F.Paste")
			(net "RST_SMB_NIC7_MUX_ISO_R_N")
		)
		(pad "2" smd circle
			(at 0.40005 0 180)
			(size 0 0)
			(layers "F.Cu" "F.Mask" "F.Paste")
			(net "RST_SMB_NIC7_MUX_ISO_N")
		)
	)
	(footprint ""
		(layer "F.Cu")
		(at 8.362696 -169.492676 180)
		(property "Reference" "PC20"
			(at 0 0 180)
			(layer "F.SilkS")
			(hide yes)
			(effects
				(font
					(size 1.27 1.27)
				)
			)
		)
		(property "Value" ""
			(at 0 0 180)
			(layer "F.Fab")
			(effects
				(font
					(size 1.27 1.27)
				)
			)
		)
		(duplicate_pad_numbers_are_jumpers no)
		(fp_line
			(start 1.524 0.762)
			(end -1.524 0.762)
			(stroke
				(width 0.1524)
				(type default)
			)
			(layer "F.SilkS")
		)
		(fp_line
			(start 1.524 -0.762)
			(end 1.524 0.762)
			(stroke
				(width 0.1524)
				(type default)
			)
			(layer "F.SilkS")
		)
		(fp_line
			(start -1.524 0.762)
			(end -1.524 -0.762)
			(stroke
				(width 0.1524)
				(type default)
			)
			(layer "F.SilkS")
		)
		(fp_line
			(start -1.524 -0.762)
			(end 1.524 -0.762)
			(stroke
				(width 0.1524)
				(type default)
			)
			(layer "F.SilkS")
		)
		(fp_line
			(start 1.1049 0.724916)
			(end 1.1049 -0.724916)
			(stroke
				(width 0.1)
				(type default)
			)
			(layer "F.Fab")
		)
		(fp_line
			(start 1.1049 -0.724916)
			(end -1.1049 -0.724916)
			(stroke
				(width 0.1)
				(type default)
			)
			(layer "F.Fab")
		)
		(fp_line
			(start -1.1049 0.724916)
			(end 1.1049 0.724916)
			(stroke
				(width 0.1)
				(type default)
			)
			(layer "F.Fab")
		)
		(fp_line
			(start -1.1049 -0.724916)
			(end -1.1049 0.724916)
			(stroke
				(width 0.1)
				(type default)
			)
			(layer "F.Fab")
		)
		(pad "1" smd rect
			(at -0.889 0)
			(size 1.016 1.27)
			(layers "F.Cu" "F.Mask" "F.Paste")
			(net "P5V_AUX")
		)
		(pad "2" smd rect
			(at 0.889 0)
			(size 1.016 1.27)
			(layers "F.Cu" "F.Mask" "F.Paste")
			(net "GND")
		)
	)
	(footprint ""
		(layer "F.Cu")
		(at 80.657446 -107.552998 -90)
		(property "Reference" "C860"
			(at 0 0 270)
			(layer "F.SilkS")
			(hide yes)
			(effects
				(font
					(size 1.27 1.27)
				)
			)
		)
		(property "Value" ""
			(at 0 0 270)
			(layer "F.Fab")
			(effects
				(font
					(size 1.27 1.27)
				)
			)
		)
		(duplicate_pad_numbers_are_jumpers no)
		(fp_line
			(start -1.524 0.762)
			(end -1.524 -0.762)
			(stroke
				(width 0.1524)
				(type default)
			)
			(layer "F.SilkS")
		)
		(fp_line
			(start 1.524 0.762)
			(end -1.524 0.762)
			(stroke
				(width 0.1524)
				(type default)
			)
			(layer "F.SilkS")
		)
		(fp_line
			(start -1.524 -0.762)
			(end 1.524 -0.762)
			(stroke
				(width 0.1524)
				(type default)
			)
			(layer "F.SilkS")
		)
		(fp_line
			(start 1.524 -0.762)
			(end 1.524 0.762)
			(stroke
				(width 0.1524)
				(type default)
			)
			(layer "F.SilkS")
		)
		(fp_line
			(start -1.1049 0.724916)
			(end 1.1049 0.724916)
			(stroke
				(width 0.1)
				(type default)
			)
			(layer "F.Fab")
		)
		(fp_line
			(start 1.1049 0.724916)
			(end 1.1049 -0.724916)
			(stroke
				(width 0.1)
				(type default)
			)
			(layer "F.Fab")
		)
		(fp_line
			(start -1.1049 -0.724916)
			(end -1.1049 0.724916)
			(stroke
				(width 0.1)
				(type default)
			)
			(layer "F.Fab")
		)
		(fp_line
			(start 1.1049 -0.724916)
			(end -1.1049 -0.724916)
			(stroke
				(width 0.1)
				(type default)
			)
			(layer "F.Fab")
		)
		(pad "1" smd rect
			(at -0.889 0 90)
			(size 1.016 1.27)
			(layers "F.Cu" "F.Mask" "F.Paste")
			(net "P12V_NIC1")
		)
		(pad "2" smd rect
			(at 0.889 0 90)
			(size 1.016 1.27)
			(layers "F.Cu" "F.Mask" "F.Paste")
			(net "GND")
		)
	)
	(footprint ""
		(layer "F.Cu")
		(at 99.149916 -289.820096)
		(property "Reference" "H136"
			(at -2.35966 5.20065 0)
			(unlocked yes)
			(layer "F.SilkS")
			(effects
				(font
					(size 0.7874 0.5842)
					(thickness 0.1524)
				)
				(justify left)
			)
		)
		(property "Value" ""
			(at 0 0 0)
			(layer "F.Fab")
			(effects
				(font
					(size 1.27 1.27)
				)
			)
		)
		(duplicate_pad_numbers_are_jumpers no)
		(pad "1" thru_hole circle
			(at 0 0)
			(size 6.5024 6.5024)
			(drill 3.2004)
			(layers "*.Cu" "*.Mask")
			(remove_unused_layers no)
			(net "GND")
			(clearance -1.397)
		)
	)
	(footprint ""
		(layer "F.Cu")
		(at 374.543828 -48.93691 180)
		(property "Reference" "R644"
			(at 0 0 180)
			(layer "F.SilkS")
			(hide yes)
			(effects
				(font
					(size 1.27 1.27)
				)
			)
		)
		(property "Value" ""
			(at 0 0 180)
			(layer "F.Fab")
			(effects
				(font
					(size 1.27 1.27)
				)
			)
		)
		(duplicate_pad_numbers_are_jumpers no)
		(fp_line
			(start 0.7874 0.4064)
			(end -0.7874 0.4064)
			(stroke
				(width 0.1524)
				(type default)
			)
			(layer "F.SilkS")
		)
		(fp_line
			(start 0.7874 -0.4064)
			(end 0.7874 0.4064)
			(stroke
				(width 0.1524)
				(type default)
			)
			(layer "F.SilkS")
		)
		(fp_line
			(start -0.7874 0.4064)
			(end -0.7874 -0.4064)
			(stroke
				(width 0.1524)
				(type default)
			)
			(layer "F.SilkS")
		)
		(fp_line
			(start -0.7874 -0.4064)
			(end 0.7874 -0.4064)
			(stroke
				(width 0.1524)
				(type default)
			)
			(layer "F.SilkS")
		)
		(fp_line
			(start 0.67945 0.3048)
			(end 0.120396 0.3048)
			(stroke
				(width 0.1)
				(type default)
			)
			(layer "F.Fab")
		)
		(fp_line
			(start 0.67945 -0.3048)
			(end 0.67945 0.3048)
			(stroke
				(width 0.1)
				(type default)
			)
			(layer "F.Fab")
		)
		(fp_line
			(start 0.12065 -0.2794)
			(end 0.12065 -0.3048)
			(stroke
				(width 0.1)
				(type default)
			)
			(layer "F.Fab")
		)
		(fp_line
			(start 0.12065 -0.3048)
			(end 0.67945 -0.3048)
			(stroke
				(width 0.1)
				(type default)
			)
			(layer "F.Fab")
		)
		(fp_line
			(start 0.120396 0.3048)
			(end 0.120396 0.2794)
			(stroke
				(width 0.1)
				(type default)
			)
			(layer "F.Fab")
		)
		(fp_line
			(start 0.120396 0.2794)
			(end -0.12065 0.2794)
			(stroke
				(width 0.1)
				(type default)
			)
			(layer "F.Fab")
		)
		(fp_line
			(start -0.12065 0.3048)
			(end -0.67945 0.3048)
			(stroke
				(width 0.1)
				(type default)
			)
			(layer "F.Fab")
		)
		(fp_line
			(start -0.12065 0.2794)
			(end -0.12065 0.3048)
			(stroke
				(width 0.1)
				(type default)
			)
			(layer "F.Fab")
		)
		(fp_line
			(start -0.12065 -0.2794)
			(end 0.12065 -0.2794)
			(stroke
				(width 0.1)
				(type default)
			)
			(layer "F.Fab")
		)
		(fp_line
			(start -0.12065 -0.305054)
			(end -0.12065 -0.2794)
			(stroke
				(width 0.1)
				(type default)
			)
			(layer "F.Fab")
		)
		(fp_line
			(start -0.67945 0.3048)
			(end -0.67945 -0.305054)
			(stroke
				(width 0.1)
				(type default)
			)
			(layer "F.Fab")
		)
		(fp_line
			(start -0.67945 -0.305054)
			(end -0.12065 -0.305054)
			(stroke
				(width 0.1)
				(type default)
			)
			(layer "F.Fab")
		)
		(pad "1" smd circle
			(at -0.40005 0 180)
			(size 0 0)
			(layers "F.Cu" "F.Mask" "F.Paste")
			(net "SMB_BIC_I2C6_MUX_SSD_8_15_ADC_R_SDA")
		)
		(pad "2" smd circle
			(at 0.40005 0 180)
			(size 0 0)
			(layers "F.Cu" "F.Mask" "F.Paste")
			(net "SMB_SSD12_ADC_SDA")
		)
	)
	(footprint ""
		(layer "F.Cu")
		(at 451.298056 -266.996672 180)
		(property "Reference" "R6140"
			(at 0 0 180)
			(layer "F.SilkS")
			(hide yes)
			(effects
				(font
					(size 1.27 1.27)
				)
			)
		)
		(property "Value" ""
			(at 0 0 180)
			(layer "F.Fab")
			(effects
				(font
					(size 1.27 1.27)
				)
			)
		)
		(duplicate_pad_numbers_are_jumpers no)
		(fp_line
			(start 2.576322 1.1303)
			(end -2.576322 1.1303)
			(stroke
				(width 0.1524)
				(type default)
			)
			(layer "F.SilkS")
		)
		(fp_line
			(start 2.576322 -1.1303)
			(end 2.576322 1.1303)
			(stroke
				(width 0.1524)
				(type default)
			)
			(layer "F.SilkS")
		)
		(fp_line
			(start -2.576322 1.1303)
			(end -2.576322 -1.1303)
			(stroke
				(width 0.1524)
				(type default)
			)
			(layer "F.SilkS")
		)
		(fp_line
			(start -2.576322 -1.1303)
			(end 2.576322 -1.1303)
			(stroke
				(width 0.1524)
				(type default)
			)
			(layer "F.SilkS")
		)
		(fp_line
			(start 1.649984 0.899922)
			(end 1.649984 -0.899922)
			(stroke
				(width 0.1)
				(type default)
			)
			(layer "F.Fab")
		)
		(fp_line
			(start 1.649984 -0.899922)
			(end -1.649984 -0.899922)
			(stroke
				(width 0.1)
				(type default)
			)
			(layer "F.Fab")
		)
		(fp_line
			(start -1.649984 0.899922)
			(end 1.649984 0.899922)
			(stroke
				(width 0.1)
				(type default)
			)
			(layer "F.Fab")
		)
		(fp_line
			(start -1.649984 -0.899922)
			(end -1.649984 0.899922)
			(stroke
				(width 0.1)
				(type default)
			)
			(layer "F.Fab")
		)
		(pad "1A" smd rect
			(at -1.700022 0 180)
			(size 1.4986 2.0066)
			(layers "F.Cu" "F.Mask" "F.Paste")
			(net "P1V25_PEX3")
		)
		(pad "1B" smd rect
			(at -1.077722 0 180)
			(size 0.254 0.508)
			(layers "F.Cu" "F.Mask" "F.Paste")
			(net "P1V25_PEX3")
		)
		(pad "2A" smd rect
			(at 1.700022 0 180)
			(size 1.4986 2.0066)
			(layers "F.Cu" "F.Mask" "F.Paste")
			(net "P1V25_SERDES_VDDPLL_PEX3")
		)
		(pad "2B" smd rect
			(at 1.077722 0 180)
			(size 0.254 0.508)
			(layers "F.Cu" "F.Mask" "F.Paste")
			(net "P1V25_SERDES_VDDPLL_PEX3")
		)
	)
	(footprint ""
		(layer "F.Cu")
		(at 80.019398 -143.504666 180)
		(property "Reference" "C15"
			(at 0 0 180)
			(layer "F.SilkS")
			(hide yes)
			(effects
				(font
					(size 1.27 1.27)
				)
			)
		)
		(property "Value" ""
			(at 0 0 180)
			(layer "F.Fab")
			(effects
				(font
					(size 1.27 1.27)
				)
			)
		)
		(duplicate_pad_numbers_are_jumpers no)
		(fp_line
			(start 0.299974 0.150114)
			(end -0.299974 0.150114)
			(stroke
				(width 0.1)
				(type default)
			)
			(layer "F.Fab")
		)
		(fp_line
			(start 0.299974 -0.150114)
			(end 0.299974 0.150114)
			(stroke
				(width 0.1)
				(type default)
			)
			(layer "F.Fab")
		)
		(fp_line
			(start -0.299974 0.150114)
			(end -0.299974 -0.150114)
			(stroke
				(width 0.1)
				(type default)
			)
			(layer "F.Fab")
		)
		(fp_line
			(start -0.299974 -0.150114)
			(end 0.299974 -0.150114)
			(stroke
				(width 0.1)
				(type default)
			)
			(layer "F.Fab")
		)
		(pad "1" smd rect
			(at -0.2667 0 180)
			(size 0.3048 0.381)
			(layers "F.Cu" "F.Mask" "F.Paste")
			(net "P5E_PEX0_STN0_TX_DP<8>")
		)
		(pad "2" smd rect
			(at 0.2667 0 180)
			(size 0.3048 0.381)
			(layers "F.Cu" "F.Mask" "F.Paste")
			(net "P5E_PEX0_STN0_TX_C_DP<8>")
		)
	)
	(footprint ""
		(layer "F.Cu")
		(at 207.915002 -188.595508)
		(property "Reference" "R4232"
			(at 0 0 0)
			(layer "F.SilkS")
			(hide yes)
			(effects
				(font
					(size 1.27 1.27)
				)
			)
		)
		(property "Value" ""
			(at 0 0 0)
			(layer "F.Fab")
			(effects
				(font
					(size 1.27 1.27)
				)
			)
		)
		(duplicate_pad_numbers_are_jumpers no)
		(fp_line
			(start -0.7874 -0.4064)
			(end 0.7874 -0.4064)
			(stroke
				(width 0.1524)
				(type default)
			)
			(layer "F.SilkS")
		)
		(fp_line
			(start -0.7874 0.4064)
			(end -0.7874 -0.4064)
			(stroke
				(width 0.1524)
				(type default)
			)
			(layer "F.SilkS")
		)
		(fp_line
			(start 0.7874 -0.4064)
			(end 0.7874 0.4064)
			(stroke
				(width 0.1524)
				(type default)
			)
			(layer "F.SilkS")
		)
		(fp_line
			(start 0.7874 0.4064)
			(end -0.7874 0.4064)
			(stroke
				(width 0.1524)
				(type default)
			)
			(layer "F.SilkS")
		)
		(fp_line
			(start -0.67945 -0.305054)
			(end -0.12065 -0.305054)
			(stroke
				(width 0.1)
				(type default)
			)
			(layer "F.Fab")
		)
		(fp_line
			(start -0.67945 0.3048)
			(end -0.67945 -0.305054)
			(stroke
				(width 0.1)
				(type default)
			)
			(layer "F.Fab")
		)
		(fp_line
			(start -0.12065 -0.305054)
			(end -0.12065 -0.2794)
			(stroke
				(width 0.1)
				(type default)
			)
			(layer "F.Fab")
		)
		(fp_line
			(start -0.12065 -0.2794)
			(end 0.12065 -0.2794)
			(stroke
				(width 0.1)
				(type default)
			)
			(layer "F.Fab")
		)
		(fp_line
			(start -0.12065 0.2794)
			(end -0.12065 0.3048)
			(stroke
				(width 0.1)
				(type default)
			)
			(layer "F.Fab")
		)
		(fp_line
			(start -0.12065 0.3048)
			(end -0.67945 0.3048)
			(stroke
				(width 0.1)
				(type default)
			)
			(layer "F.Fab")
		)
		(fp_line
			(start 0.120396 0.2794)
			(end -0.12065 0.2794)
			(stroke
				(width 0.1)
				(type default)
			)
			(layer "F.Fab")
		)
		(fp_line
			(start 0.120396 0.3048)
			(end 0.120396 0.2794)
			(stroke
				(width 0.1)
				(type default)
			)
			(layer "F.Fab")
		)
		(fp_line
			(start 0.12065 -0.3048)
			(end 0.67945 -0.3048)
			(stroke
				(width 0.1)
				(type default)
			)
			(layer "F.Fab")
		)
		(fp_line
			(start 0.12065 -0.2794)
			(end 0.12065 -0.3048)
			(stroke
				(width 0.1)
				(type default)
			)
			(layer "F.Fab")
		)
		(fp_line
			(start 0.67945 -0.3048)
			(end 0.67945 0.3048)
			(stroke
				(width 0.1)
				(type default)
			)
			(layer "F.Fab")
		)
		(fp_line
			(start 0.67945 0.3048)
			(end 0.120396 0.3048)
			(stroke
				(width 0.1)
				(type default)
			)
			(layer "F.Fab")
		)
		(pad "1" smd circle
			(at -0.40005 0)
			(size 0 0)
			(layers "F.Cu" "F.Mask" "F.Paste")
			(net "SMB_FIO_R1_SCL")
		)
		(pad "2" smd circle
			(at 0.40005 0)
			(size 0 0)
			(layers "F.Cu" "F.Mask" "F.Paste")
			(net "SMB_IO_DEBUG_CARD_R_SCL")
		)
	)
	(footprint ""
		(layer "F.Cu")
		(at 194.948048 -367.843308 -90)
		(property "Reference" "R6251"
			(at 0 0 270)
			(layer "F.SilkS")
			(hide yes)
			(effects
				(font
					(size 1.27 1.27)
				)
			)
		)
		(property "Value" ""
			(at 0 0 270)
			(layer "F.Fab")
			(effects
				(font
					(size 1.27 1.27)
				)
			)
		)
		(duplicate_pad_numbers_are_jumpers no)
		(fp_line
			(start -0.7874 0.4064)
			(end -0.7874 -0.4064)
			(stroke
				(width 0.1524)
				(type default)
			)
			(layer "F.SilkS")
		)
		(fp_line
			(start 0.7874 0.4064)
			(end -0.7874 0.4064)
			(stroke
				(width 0.1524)
				(type default)
			)
			(layer "F.SilkS")
		)
		(fp_line
			(start -0.7874 -0.4064)
			(end 0.7874 -0.4064)
			(stroke
				(width 0.1524)
				(type default)
			)
			(layer "F.SilkS")
		)
		(fp_line
			(start 0.7874 -0.4064)
			(end 0.7874 0.4064)
			(stroke
				(width 0.1524)
				(type default)
			)
			(layer "F.SilkS")
		)
		(fp_line
			(start -0.67945 0.3048)
			(end -0.67945 -0.305054)
			(stroke
				(width 0.1)
				(type default)
			)
			(layer "F.Fab")
		)
		(fp_line
			(start -0.12065 0.3048)
			(end -0.67945 0.3048)
			(stroke
				(width 0.1)
				(type default)
			)
			(layer "F.Fab")
		)
		(fp_line
			(start 0.120396 0.3048)
			(end 0.120396 0.2794)
			(stroke
				(width 0.1)
				(type default)
			)
			(layer "F.Fab")
		)
		(fp_line
			(start 0.67945 0.3048)
			(end 0.120396 0.3048)
			(stroke
				(width 0.1)
				(type default)
			)
			(layer "F.Fab")
		)
		(fp_line
			(start -0.12065 0.2794)
			(end -0.12065 0.3048)
			(stroke
				(width 0.1)
				(type default)
			)
			(layer "F.Fab")
		)
		(fp_line
			(start 0.120396 0.2794)
			(end -0.12065 0.2794)
			(stroke
				(width 0.1)
				(type default)
			)
			(layer "F.Fab")
		)
		(fp_line
			(start -0.12065 -0.2794)
			(end 0.12065 -0.2794)
			(stroke
				(width 0.1)
				(type default)
			)
			(layer "F.Fab")
		)
		(fp_line
			(start 0.12065 -0.2794)
			(end 0.12065 -0.3048)
			(stroke
				(width 0.1)
				(type default)
			)
			(layer "F.Fab")
		)
		(fp_line
			(start 0.12065 -0.3048)
			(end 0.67945 -0.3048)
			(stroke
				(width 0.1)
				(type default)
			)
			(layer "F.Fab")
		)
		(fp_line
			(start 0.67945 -0.3048)
			(end 0.67945 0.3048)
			(stroke
				(width 0.1)
				(type default)
			)
			(layer "F.Fab")
		)
		(fp_line
			(start -0.67945 -0.305054)
			(end -0.12065 -0.305054)
			(stroke
				(width 0.1)
				(type default)
			)
			(layer "F.Fab")
		)
		(fp_line
			(start -0.12065 -0.305054)
			(end -0.12065 -0.2794)
			(stroke
				(width 0.1)
				(type default)
			)
			(layer "F.Fab")
		)
		(pad "1" smd circle
			(at -0.40005 0 270)
			(size 0 0)
			(layers "F.Cu" "F.Mask" "F.Paste")
			(net "FM_HSC_PWROK")
		)
		(pad "2" smd circle
			(at 0.40005 0 270)
			(size 0 0)
			(layers "F.Cu" "F.Mask" "F.Paste")
			(net "PWRGD_P12V_AUX_R")
		)
	)
	(footprint ""
		(layer "F.Cu")
		(at 5.617718 -264.586466 180)
		(property "Reference" "L82"
			(at 0 0 180)
			(layer "F.SilkS")
			(hide yes)
			(effects
				(font
					(size 1.27 1.27)
				)
			)
		)
		(property "Value" ""
			(at 0 0 180)
			(layer "F.Fab")
			(effects
				(font
					(size 1.27 1.27)
				)
			)
		)
		(duplicate_pad_numbers_are_jumpers no)
		(fp_line
			(start 2.248154 4.9911)
			(end 2.248154 1.73482)
			(stroke
				(width 0.1524)
				(type default)
			)
			(layer "F.SilkS")
		)
		(fp_line
			(start 2.248154 -1.592072)
			(end 2.248154 -4.9911)
			(stroke
				(width 0.1524)
				(type default)
			)
			(layer "F.SilkS")
		)
		(fp_line
			(start 2.248154 -4.9911)
			(end -2.248154 -4.9911)
			(stroke
				(width 0.1524)
				(type default)
			)
			(layer "F.SilkS")
		)
		(fp_line
			(start -2.248154 4.9911)
			(end 2.248154 4.9911)
			(stroke
				(width 0.1524)
				(type default)
			)
			(layer "F.SilkS")
		)
		(fp_line
			(start -2.248154 1.646936)
			(end -2.248154 4.9911)
			(stroke
				(width 0.1524)
				(type default)
			)
			(layer "F.SilkS")
		)
		(fp_line
			(start -2.248154 -4.9911)
			(end -2.248154 -1.690878)
			(stroke
				(width 0.1524)
				(type default)
			)
			(layer "F.SilkS")
		)
		(fp_line
			(start 1.700022 0.899922)
			(end 1.700022 -0.899922)
			(stroke
				(width 0.1)
				(type default)
			)
			(layer "F.Fab")
		)
		(fp_line
			(start 1.700022 -0.899922)
			(end -1.700022 -0.899922)
			(stroke
				(width 0.1)
				(type default)
			)
			(layer "F.Fab")
		)
		(fp_line
			(start -1.700022 0.899922)
			(end 1.700022 0.899922)
			(stroke
				(width 0.1)
				(type default)
			)
			(layer "F.Fab")
		)
		(fp_line
			(start -1.700022 -0.899922)
			(end -1.700022 0.899922)
			(stroke
				(width 0.1)
				(type default)
			)
			(layer "F.Fab")
		)
		(pad "1" smd rect
			(at -1.575054 0 180)
			(size 1.1684 9.8044)
			(layers "F.Cu" "F.Mask" "F.Paste")
			(net "P1V25_PEX0")
		)
		(pad "2" smd rect
			(at 1.575054 0 180)
			(size 1.1684 9.8044)
			(layers "F.Cu" "F.Mask" "F.Paste")
			(net "P1V25_SERDES_VDDPLL_PEX0")
		)
	)
	(footprint ""
		(layer "F.Cu")
		(at 475.10827 -524.295624 180)
		(property "Reference" "SCREW_SSD4_2"
			(at -5.207 -1.402334 0)
			(unlocked yes)
			(layer "B.SilkS")
			(effects
				(font
					(size 0.7874 0.5842)
					(thickness 0.1524)
				)
				(justify mirror)
			)
		)
		(property "Value" ""
			(at 0 0 180)
			(layer "F.Fab")
			(effects
				(font
					(size 1.27 1.27)
				)
			)
		)
		(duplicate_pad_numbers_are_jumpers no)
		(pad "1" thru_hole circle
			(at 0 0 180)
			(size 0.4572 0.4572)
			(drill 0.2032)
			(layers "*.Cu" "*.Mask")
			(remove_unused_layers no)
			(net "Net_9135")
			(clearance 0.127)
			(thermal_gap 0.127)
			(padstack
				(mode front_inner_back)
				(layer "Inner"
					(shape circle)
					(size 0.4572 0.4572)
					(clearance 0.127)
				)
				(layer "B.Cu"
					(shape circle)
					(size 0.508 0.508)
					(clearance 0.1016)
				)
			)
		)
	)
	(footprint ""
		(layer "F.Cu")
		(at 10.11047 -121.661428 180)
		(property "Reference" "C2877"
			(at 0 0 180)
			(layer "F.SilkS")
			(hide yes)
			(effects
				(font
					(size 1.27 1.27)
				)
			)
		)
		(property "Value" ""
			(at 0 0 180)
			(layer "F.Fab")
			(effects
				(font
					(size 1.27 1.27)
				)
			)
		)
		(duplicate_pad_numbers_are_jumpers no)
		(fp_line
			(start 0.7874 0.4064)
			(end -0.7874 0.4064)
			(stroke
				(width 0.1524)
				(type default)
			)
			(layer "F.SilkS")
		)
		(fp_line
			(start 0.7874 -0.4064)
			(end 0.7874 0.4064)
			(stroke
				(width 0.1524)
				(type default)
			)
			(layer "F.SilkS")
		)
		(fp_line
			(start -0.7874 0.4064)
			(end -0.7874 -0.4064)
			(stroke
				(width 0.1524)
				(type default)
			)
			(layer "F.SilkS")
		)
		(fp_line
			(start -0.7874 -0.4064)
			(end 0.7874 -0.4064)
			(stroke
				(width 0.1524)
				(type default)
			)
			(layer "F.SilkS")
		)
		(fp_line
			(start 0.67945 0.3048)
			(end 0.120396 0.3048)
			(stroke
				(width 0.1)
				(type default)
			)
			(layer "F.Fab")
		)
		(fp_line
			(start 0.67945 -0.3048)
			(end 0.67945 0.3048)
			(stroke
				(width 0.1)
				(type default)
			)
			(layer "F.Fab")
		)
		(fp_line
			(start 0.12065 -0.2794)
			(end 0.12065 -0.3048)
			(stroke
				(width 0.1)
				(type default)
			)
			(layer "F.Fab")
		)
		(fp_line
			(start 0.12065 -0.3048)
			(end 0.67945 -0.3048)
			(stroke
				(width 0.1)
				(type default)
			)
			(layer "F.Fab")
		)
		(fp_line
			(start 0.120396 0.3048)
			(end 0.120396 0.2794)
			(stroke
				(width 0.1)
				(type default)
			)
			(layer "F.Fab")
		)
		(fp_line
			(start 0.120396 0.2794)
			(end -0.12065 0.2794)
			(stroke
				(width 0.1)
				(type default)
			)
			(layer "F.Fab")
		)
		(fp_line
			(start -0.12065 0.3048)
			(end -0.67945 0.3048)
			(stroke
				(width 0.1)
				(type default)
			)
			(layer "F.Fab")
		)
		(fp_line
			(start -0.12065 0.2794)
			(end -0.12065 0.3048)
			(stroke
				(width 0.1)
				(type default)
			)
			(layer "F.Fab")
		)
		(fp_line
			(start -0.12065 -0.2794)
			(end 0.12065 -0.2794)
			(stroke
				(width 0.1)
				(type default)
			)
			(layer "F.Fab")
		)
		(fp_line
			(start -0.12065 -0.305054)
			(end -0.12065 -0.2794)
			(stroke
				(width 0.1)
				(type default)
			)
			(layer "F.Fab")
		)
		(fp_line
			(start -0.67945 0.3048)
			(end -0.67945 -0.305054)
			(stroke
				(width 0.1)
				(type default)
			)
			(layer "F.Fab")
		)
		(fp_line
			(start -0.67945 -0.305054)
			(end -0.12065 -0.305054)
			(stroke
				(width 0.1)
				(type default)
			)
			(layer "F.Fab")
		)
		(pad "1" smd circle
			(at -0.40005 0 180)
			(size 0 0)
			(layers "F.Cu" "F.Mask" "F.Paste")
			(net "HP_NIC0_EN")
		)
		(pad "2" smd circle
			(at 0.40005 0 180)
			(size 0 0)
			(layers "F.Cu" "F.Mask" "F.Paste")
			(net "GND")
		)
	)
	(footprint ""
		(layer "F.Cu")
		(at 152.738328 -111.895382)
		(property "Reference" "C260"
			(at 0 0 0)
			(layer "F.SilkS")
			(hide yes)
			(effects
				(font
					(size 1.27 1.27)
				)
			)
		)
		(property "Value" ""
			(at 0 0 0)
			(layer "F.Fab")
			(effects
				(font
					(size 1.27 1.27)
				)
			)
		)
		(duplicate_pad_numbers_are_jumpers no)
		(fp_line
			(start -0.299974 -0.150114)
			(end 0.299974 -0.150114)
			(stroke
				(width 0.1)
				(type default)
			)
			(layer "F.Fab")
		)
		(fp_line
			(start -0.299974 0.150114)
			(end -0.299974 -0.150114)
			(stroke
				(width 0.1)
				(type default)
			)
			(layer "F.Fab")
		)
		(fp_line
			(start 0.299974 -0.150114)
			(end 0.299974 0.150114)
			(stroke
				(width 0.1)
				(type default)
			)
			(layer "F.Fab")
		)
		(fp_line
			(start 0.299974 0.150114)
			(end -0.299974 0.150114)
			(stroke
				(width 0.1)
				(type default)
			)
			(layer "F.Fab")
		)
		(pad "1" smd rect
			(at -0.2667 0)
			(size 0.3048 0.381)
			(layers "F.Cu" "F.Mask" "F.Paste")
			(net "P5E_PEX1_STN1_TX_DN<23>")
		)
		(pad "2" smd rect
			(at 0.2667 0)
			(size 0.3048 0.381)
			(layers "F.Cu" "F.Mask" "F.Paste")
			(net "P5E_PEX1_STN1_TX_C_DN<23>")
		)
	)
	(footprint ""
		(layer "F.Cu")
		(at 71.7042 -235.690156 90)
		(property "Reference" "R6639"
			(at 0 0 90)
			(layer "F.SilkS")
			(hide yes)
			(effects
				(font
					(size 1.27 1.27)
				)
			)
		)
		(property "Value" ""
			(at 0 0 90)
			(layer "F.Fab")
			(effects
				(font
					(size 1.27 1.27)
				)
			)
		)
		(duplicate_pad_numbers_are_jumpers no)
		(fp_line
			(start 0.7874 -0.4064)
			(end 0.7874 0.4064)
			(stroke
				(width 0.1524)
				(type default)
			)
			(layer "F.SilkS")
		)
		(fp_line
			(start -0.7874 -0.4064)
			(end 0.7874 -0.4064)
			(stroke
				(width 0.1524)
				(type default)
			)
			(layer "F.SilkS")
		)
		(fp_line
			(start 0.7874 0.4064)
			(end -0.7874 0.4064)
			(stroke
				(width 0.1524)
				(type default)
			)
			(layer "F.SilkS")
		)
		(fp_line
			(start -0.7874 0.4064)
			(end -0.7874 -0.4064)
			(stroke
				(width 0.1524)
				(type default)
			)
			(layer "F.SilkS")
		)
		(fp_line
			(start -0.12065 -0.305054)
			(end -0.12065 -0.2794)
			(stroke
				(width 0.1)
				(type default)
			)
			(layer "F.Fab")
		)
		(fp_line
			(start -0.67945 -0.305054)
			(end -0.12065 -0.305054)
			(stroke
				(width 0.1)
				(type default)
			)
			(layer "F.Fab")
		)
		(fp_line
			(start 0.67945 -0.3048)
			(end 0.67945 0.3048)
			(stroke
				(width 0.1)
				(type default)
			)
			(layer "F.Fab")
		)
		(fp_line
			(start 0.12065 -0.3048)
			(end 0.67945 -0.3048)
			(stroke
				(width 0.1)
				(type default)
			)
			(layer "F.Fab")
		)
		(fp_line
			(start 0.12065 -0.2794)
			(end 0.12065 -0.3048)
			(stroke
				(width 0.1)
				(type default)
			)
			(layer "F.Fab")
		)
		(fp_line
			(start -0.12065 -0.2794)
			(end 0.12065 -0.2794)
			(stroke
				(width 0.1)
				(type default)
			)
			(layer "F.Fab")
		)
		(fp_line
			(start 0.120396 0.2794)
			(end -0.12065 0.2794)
			(stroke
				(width 0.1)
				(type default)
			)
			(layer "F.Fab")
		)
		(fp_line
			(start -0.12065 0.2794)
			(end -0.12065 0.3048)
			(stroke
				(width 0.1)
				(type default)
			)
			(layer "F.Fab")
		)
		(fp_line
			(start 0.67945 0.3048)
			(end 0.120396 0.3048)
			(stroke
				(width 0.1)
				(type default)
			)
			(layer "F.Fab")
		)
		(fp_line
			(start 0.120396 0.3048)
			(end 0.120396 0.2794)
			(stroke
				(width 0.1)
				(type default)
			)
			(layer "F.Fab")
		)
		(fp_line
			(start -0.12065 0.3048)
			(end -0.67945 0.3048)
			(stroke
				(width 0.1)
				(type default)
			)
			(layer "F.Fab")
		)
		(fp_line
			(start -0.67945 0.3048)
			(end -0.67945 -0.305054)
			(stroke
				(width 0.1)
				(type default)
			)
			(layer "F.Fab")
		)
		(pad "1" smd circle
			(at -0.40005 0 90)
			(size 0 0)
			(layers "F.Cu" "F.Mask" "F.Paste")
			(net "UART_PEX0_CLI_R_RX")
		)
		(pad "2" smd circle
			(at 0.40005 0 90)
			(size 0 0)
			(layers "F.Cu" "F.Mask" "F.Paste")
			(net "UART_PEX0_CLI_R1_RX")
		)
	)
	(footprint ""
		(layer "F.Cu")
		(at 260.249162 -293.796212 -90)
		(property "Reference" "C3386"
			(at 0 0 270)
			(layer "F.SilkS")
			(hide yes)
			(effects
				(font
					(size 1.27 1.27)
				)
			)
		)
		(property "Value" ""
			(at 0 0 270)
			(layer "F.Fab")
			(effects
				(font
					(size 1.27 1.27)
				)
			)
		)
		(duplicate_pad_numbers_are_jumpers no)
		(fp_line
			(start -0.299974 0.150114)
			(end -0.299974 -0.150114)
			(stroke
				(width 0.1)
				(type default)
			)
			(layer "F.Fab")
		)
		(fp_line
			(start 0.299974 0.150114)
			(end -0.299974 0.150114)
			(stroke
				(width 0.1)
				(type default)
			)
			(layer "F.Fab")
		)
		(fp_line
			(start -0.299974 -0.150114)
			(end 0.299974 -0.150114)
			(stroke
				(width 0.1)
				(type default)
			)
			(layer "F.Fab")
		)
		(fp_line
			(start 0.299974 -0.150114)
			(end 0.299974 0.150114)
			(stroke
				(width 0.1)
				(type default)
			)
			(layer "F.Fab")
		)
		(pad "1" smd rect
			(at -0.2667 0 270)
			(size 0.3048 0.381)
			(layers "F.Cu" "F.Mask" "F.Paste")
			(net "P1V8_PLL0_PEX2")
		)
		(pad "2" smd rect
			(at 0.2667 0 270)
			(size 0.3048 0.381)
			(layers "F.Cu" "F.Mask" "F.Paste")
			(net "GND")
		)
	)
	(footprint ""
		(layer "F.Cu")
		(at 200.011538 -405.901144 -90)
		(property "Reference" "R6253"
			(at 0 0 270)
			(layer "F.SilkS")
			(hide yes)
			(effects
				(font
					(size 1.27 1.27)
				)
			)
		)
		(property "Value" ""
			(at 0 0 270)
			(layer "F.Fab")
			(effects
				(font
					(size 1.27 1.27)
				)
			)
		)
		(duplicate_pad_numbers_are_jumpers no)
		(fp_line
			(start -0.7874 0.4064)
			(end -0.7874 -0.4064)
			(stroke
				(width 0.1524)
				(type default)
			)
			(layer "F.SilkS")
		)
		(fp_line
			(start 0.7874 0.4064)
			(end -0.7874 0.4064)
			(stroke
				(width 0.1524)
				(type default)
			)
			(layer "F.SilkS")
		)
		(fp_line
			(start -0.7874 -0.4064)
			(end 0.7874 -0.4064)
			(stroke
				(width 0.1524)
				(type default)
			)
			(layer "F.SilkS")
		)
		(fp_line
			(start 0.7874 -0.4064)
			(end 0.7874 0.4064)
			(stroke
				(width 0.1524)
				(type default)
			)
			(layer "F.SilkS")
		)
		(fp_line
			(start -0.67945 0.3048)
			(end -0.67945 -0.305054)
			(stroke
				(width 0.1)
				(type default)
			)
			(layer "F.Fab")
		)
		(fp_line
			(start -0.12065 0.3048)
			(end -0.67945 0.3048)
			(stroke
				(width 0.1)
				(type default)
			)
			(layer "F.Fab")
		)
		(fp_line
			(start 0.120396 0.3048)
			(end 0.120396 0.2794)
			(stroke
				(width 0.1)
				(type default)
			)
			(layer "F.Fab")
		)
		(fp_line
			(start 0.67945 0.3048)
			(end 0.120396 0.3048)
			(stroke
				(width 0.1)
				(type default)
			)
			(layer "F.Fab")
		)
		(fp_line
			(start -0.12065 0.2794)
			(end -0.12065 0.3048)
			(stroke
				(width 0.1)
				(type default)
			)
			(layer "F.Fab")
		)
		(fp_line
			(start 0.120396 0.2794)
			(end -0.12065 0.2794)
			(stroke
				(width 0.1)
				(type default)
			)
			(layer "F.Fab")
		)
		(fp_line
			(start -0.12065 -0.2794)
			(end 0.12065 -0.2794)
			(stroke
				(width 0.1)
				(type default)
			)
			(layer "F.Fab")
		)
		(fp_line
			(start 0.12065 -0.2794)
			(end 0.12065 -0.3048)
			(stroke
				(width 0.1)
				(type default)
			)
			(layer "F.Fab")
		)
		(fp_line
			(start 0.12065 -0.3048)
			(end 0.67945 -0.3048)
			(stroke
				(width 0.1)
				(type default)
			)
			(layer "F.Fab")
		)
		(fp_line
			(start 0.67945 -0.3048)
			(end 0.67945 0.3048)
			(stroke
				(width 0.1)
				(type default)
			)
			(layer "F.Fab")
		)
		(fp_line
			(start -0.67945 -0.305054)
			(end -0.12065 -0.305054)
			(stroke
				(width 0.1)
				(type default)
			)
			(layer "F.Fab")
		)
		(fp_line
			(start -0.12065 -0.305054)
			(end -0.12065 -0.2794)
			(stroke
				(width 0.1)
				(type default)
			)
			(layer "F.Fab")
		)
		(pad "1" smd circle
			(at -0.40005 0 270)
			(size 0 0)
			(layers "F.Cu" "F.Mask" "F.Paste")
			(net "MB_HSC_EN")
		)
		(pad "2" smd circle
			(at 0.40005 0 270)
			(size 0 0)
			(layers "F.Cu" "F.Mask" "F.Paste")
			(net "GND")
		)
	)
	(footprint ""
		(layer "F.Cu")
		(at 98.434398 -33.631886 180)
		(property "Reference" "C90"
			(at 0 0 180)
			(layer "F.SilkS")
			(hide yes)
			(effects
				(font
					(size 1.27 1.27)
				)
			)
		)
		(property "Value" ""
			(at 0 0 180)
			(layer "F.Fab")
			(effects
				(font
					(size 1.27 1.27)
				)
			)
		)
		(duplicate_pad_numbers_are_jumpers no)
		(fp_line
			(start 0.299974 0.150114)
			(end -0.299974 0.150114)
			(stroke
				(width 0.1)
				(type default)
			)
			(layer "F.Fab")
		)
		(fp_line
			(start 0.299974 -0.150114)
			(end 0.299974 0.150114)
			(stroke
				(width 0.1)
				(type default)
			)
			(layer "F.Fab")
		)
		(fp_line
			(start -0.299974 0.150114)
			(end -0.299974 -0.150114)
			(stroke
				(width 0.1)
				(type default)
			)
			(layer "F.Fab")
		)
		(fp_line
			(start -0.299974 -0.150114)
			(end 0.299974 -0.150114)
			(stroke
				(width 0.1)
				(type default)
			)
			(layer "F.Fab")
		)
		(pad "1" smd rect
			(at -0.2667 0 180)
			(size 0.3048 0.381)
			(layers "F.Cu" "F.Mask" "F.Paste")
			(net "P5E_PEX0_STN2_TX_DN<35>")
		)
		(pad "2" smd rect
			(at 0.2667 0 180)
			(size 0.3048 0.381)
			(layers "F.Cu" "F.Mask" "F.Paste")
			(net "P5E_PEX0_STN2_TX_C_DN<35>")
		)
	)
	(footprint ""
		(layer "F.Cu")
		(at 37.004752 -142.88897 180)
		(property "Reference" "R29"
			(at 0 0 180)
			(layer "F.SilkS")
			(hide yes)
			(effects
				(font
					(size 1.27 1.27)
				)
			)
		)
		(property "Value" ""
			(at 0 0 180)
			(layer "F.Fab")
			(effects
				(font
					(size 1.27 1.27)
				)
			)
		)
		(duplicate_pad_numbers_are_jumpers no)
		(fp_line
			(start 0.7874 0.4064)
			(end -0.7874 0.4064)
			(stroke
				(width 0.1524)
				(type default)
			)
			(layer "F.SilkS")
		)
		(fp_line
			(start 0.7874 -0.4064)
			(end 0.7874 0.4064)
			(stroke
				(width 0.1524)
				(type default)
			)
			(layer "F.SilkS")
		)
		(fp_line
			(start -0.7874 0.4064)
			(end -0.7874 -0.4064)
			(stroke
				(width 0.1524)
				(type default)
			)
			(layer "F.SilkS")
		)
		(fp_line
			(start -0.7874 -0.4064)
			(end 0.7874 -0.4064)
			(stroke
				(width 0.1524)
				(type default)
			)
			(layer "F.SilkS")
		)
		(fp_line
			(start 0.67945 0.3048)
			(end 0.120396 0.3048)
			(stroke
				(width 0.1)
				(type default)
			)
			(layer "F.Fab")
		)
		(fp_line
			(start 0.67945 -0.3048)
			(end 0.67945 0.3048)
			(stroke
				(width 0.1)
				(type default)
			)
			(layer "F.Fab")
		)
		(fp_line
			(start 0.12065 -0.2794)
			(end 0.12065 -0.3048)
			(stroke
				(width 0.1)
				(type default)
			)
			(layer "F.Fab")
		)
		(fp_line
			(start 0.12065 -0.3048)
			(end 0.67945 -0.3048)
			(stroke
				(width 0.1)
				(type default)
			)
			(layer "F.Fab")
		)
		(fp_line
			(start 0.120396 0.3048)
			(end 0.120396 0.2794)
			(stroke
				(width 0.1)
				(type default)
			)
			(layer "F.Fab")
		)
		(fp_line
			(start 0.120396 0.2794)
			(end -0.12065 0.2794)
			(stroke
				(width 0.1)
				(type default)
			)
			(layer "F.Fab")
		)
		(fp_line
			(start -0.12065 0.3048)
			(end -0.67945 0.3048)
			(stroke
				(width 0.1)
				(type default)
			)
			(layer "F.Fab")
		)
		(fp_line
			(start -0.12065 0.2794)
			(end -0.12065 0.3048)
			(stroke
				(width 0.1)
				(type default)
			)
			(layer "F.Fab")
		)
		(fp_line
			(start -0.12065 -0.2794)
			(end 0.12065 -0.2794)
			(stroke
				(width 0.1)
				(type default)
			)
			(layer "F.Fab")
		)
		(fp_line
			(start -0.12065 -0.305054)
			(end -0.12065 -0.2794)
			(stroke
				(width 0.1)
				(type default)
			)
			(layer "F.Fab")
		)
		(fp_line
			(start -0.67945 0.3048)
			(end -0.67945 -0.305054)
			(stroke
				(width 0.1)
				(type default)
			)
			(layer "F.Fab")
		)
		(fp_line
			(start -0.67945 -0.305054)
			(end -0.12065 -0.305054)
			(stroke
				(width 0.1)
				(type default)
			)
			(layer "F.Fab")
		)
		(pad "1" smd circle
			(at -0.40005 0 180)
			(size 0 0)
			(layers "F.Cu" "F.Mask" "F.Paste")
			(net "NIC0_BIF0_N")
		)
		(pad "2" smd circle
			(at 0.40005 0 180)
			(size 0 0)
			(layers "F.Cu" "F.Mask" "F.Paste")
			(net "P3V3_AUX")
		)
	)
	(footprint ""
		(layer "F.Cu")
		(at 223.844612 -254.18542 -90)
		(property "Reference" "C4285"
			(at 0 0 270)
			(layer "F.SilkS")
			(hide yes)
			(effects
				(font
					(size 1.27 1.27)
				)
			)
		)
		(property "Value" ""
			(at 0 0 270)
			(layer "F.Fab")
			(effects
				(font
					(size 1.27 1.27)
				)
			)
		)
		(duplicate_pad_numbers_are_jumpers no)
		(fp_line
			(start -1.2954 0.5842)
			(end -1.2954 -0.5842)
			(stroke
				(width 0.1524)
				(type default)
			)
			(layer "F.SilkS")
		)
		(fp_line
			(start 1.2954 0.5842)
			(end -1.2954 0.5842)
			(stroke
				(width 0.1524)
				(type default)
			)
			(layer "F.SilkS")
		)
		(fp_line
			(start -1.2954 -0.5842)
			(end 1.2954 -0.5842)
			(stroke
				(width 0.1524)
				(type default)
			)
			(layer "F.SilkS")
		)
		(fp_line
			(start 1.2954 -0.5842)
			(end 1.2954 0.5842)
			(stroke
				(width 0.1524)
				(type default)
			)
			(layer "F.SilkS")
		)
		(fp_line
			(start -0.8636 0.4572)
			(end -0.8636 0.4064)
			(stroke
				(width 0.1)
				(type default)
			)
			(layer "F.Fab")
		)
		(fp_line
			(start 0.8636 0.4572)
			(end -0.8636 0.4572)
			(stroke
				(width 0.1)
				(type default)
			)
			(layer "F.Fab")
		)
		(fp_line
			(start -1.1938 0.4064)
			(end -1.1938 -0.4064)
			(stroke
				(width 0.1)
				(type default)
			)
			(layer "F.Fab")
		)
		(fp_line
			(start -0.8636 0.4064)
			(end -1.1938 0.4064)
			(stroke
				(width 0.1)
				(type default)
			)
			(layer "F.Fab")
		)
		(fp_line
			(start 0.8636 0.4064)
			(end 0.8636 0.4572)
			(stroke
				(width 0.1)
				(type default)
			)
			(layer "F.Fab")
		)
		(fp_line
			(start 1.1938 0.4064)
			(end 0.8636 0.4064)
			(stroke
				(width 0.1)
				(type default)
			)
			(layer "F.Fab")
		)
		(fp_line
			(start -1.1938 -0.4064)
			(end -0.8636 -0.4064)
			(stroke
				(width 0.1)
				(type default)
			)
			(layer "F.Fab")
		)
		(fp_line
			(start -0.8636 -0.4064)
			(end -0.8636 -0.4572)
			(stroke
				(width 0.1)
				(type default)
			)
			(layer "F.Fab")
		)
		(fp_line
			(start 0.8636 -0.4064)
			(end 1.1938 -0.4064)
			(stroke
				(width 0.1)
				(type default)
			)
			(layer "F.Fab")
		)
		(fp_line
			(start 1.1938 -0.4064)
			(end 1.1938 0.4064)
			(stroke
				(width 0.1)
				(type default)
			)
			(layer "F.Fab")
		)
		(fp_line
			(start -0.8636 -0.4572)
			(end 0.8636 -0.4572)
			(stroke
				(width 0.1)
				(type default)
			)
			(layer "F.Fab")
		)
		(fp_line
			(start 0.8636 -0.4572)
			(end 0.8636 -0.4064)
			(stroke
				(width 0.1)
				(type default)
			)
			(layer "F.Fab")
		)
		(pad "1" smd rect
			(at -0.7366 0 180)
			(size 0.7112 0.8128)
			(layers "F.Cu" "F.Mask" "F.Paste")
			(net "P1V25_SERDES_VDDPLL_PEX1_C3")
		)
		(pad "2" smd rect
			(at 0.7366 0 180)
			(size 0.7112 0.8128)
			(layers "F.Cu" "F.Mask" "F.Paste")
			(net "GND")
		)
	)
	(footprint ""
		(layer "F.Cu")
		(at 269.750286 -250.070874 -90)
		(property "Reference" "R1346"
			(at 0 0 270)
			(layer "F.SilkS")
			(hide yes)
			(effects
				(font
					(size 1.27 1.27)
				)
			)
		)
		(property "Value" ""
			(at 0 0 270)
			(layer "F.Fab")
			(effects
				(font
					(size 1.27 1.27)
				)
			)
		)
		(duplicate_pad_numbers_are_jumpers no)
		(fp_line
			(start -0.7874 0.4064)
			(end -0.7874 -0.4064)
			(stroke
				(width 0.1524)
				(type default)
			)
			(layer "F.SilkS")
		)
		(fp_line
			(start 0.7874 0.4064)
			(end -0.7874 0.4064)
			(stroke
				(width 0.1524)
				(type default)
			)
			(layer "F.SilkS")
		)
		(fp_line
			(start -0.7874 -0.4064)
			(end 0.7874 -0.4064)
			(stroke
				(width 0.1524)
				(type default)
			)
			(layer "F.SilkS")
		)
		(fp_line
			(start 0.7874 -0.4064)
			(end 0.7874 0.4064)
			(stroke
				(width 0.1524)
				(type default)
			)
			(layer "F.SilkS")
		)
		(fp_line
			(start -0.67945 0.3048)
			(end -0.67945 -0.305054)
			(stroke
				(width 0.1)
				(type default)
			)
			(layer "F.Fab")
		)
		(fp_line
			(start -0.12065 0.3048)
			(end -0.67945 0.3048)
			(stroke
				(width 0.1)
				(type default)
			)
			(layer "F.Fab")
		)
		(fp_line
			(start 0.120396 0.3048)
			(end 0.120396 0.2794)
			(stroke
				(width 0.1)
				(type default)
			)
			(layer "F.Fab")
		)
		(fp_line
			(start 0.67945 0.3048)
			(end 0.120396 0.3048)
			(stroke
				(width 0.1)
				(type default)
			)
			(layer "F.Fab")
		)
		(fp_line
			(start -0.12065 0.2794)
			(end -0.12065 0.3048)
			(stroke
				(width 0.1)
				(type default)
			)
			(layer "F.Fab")
		)
		(fp_line
			(start 0.120396 0.2794)
			(end -0.12065 0.2794)
			(stroke
				(width 0.1)
				(type default)
			)
			(layer "F.Fab")
		)
		(fp_line
			(start -0.12065 -0.2794)
			(end 0.12065 -0.2794)
			(stroke
				(width 0.1)
				(type default)
			)
			(layer "F.Fab")
		)
		(fp_line
			(start 0.12065 -0.2794)
			(end 0.12065 -0.3048)
			(stroke
				(width 0.1)
				(type default)
			)
			(layer "F.Fab")
		)
		(fp_line
			(start 0.12065 -0.3048)
			(end 0.67945 -0.3048)
			(stroke
				(width 0.1)
				(type default)
			)
			(layer "F.Fab")
		)
		(fp_line
			(start 0.67945 -0.3048)
			(end 0.67945 0.3048)
			(stroke
				(width 0.1)
				(type default)
			)
			(layer "F.Fab")
		)
		(fp_line
			(start -0.67945 -0.305054)
			(end -0.12065 -0.305054)
			(stroke
				(width 0.1)
				(type default)
			)
			(layer "F.Fab")
		)
		(fp_line
			(start -0.12065 -0.305054)
			(end -0.12065 -0.2794)
			(stroke
				(width 0.1)
				(type default)
			)
			(layer "F.Fab")
		)
		(pad "1" smd circle
			(at -0.40005 0 270)
			(size 0 0)
			(layers "F.Cu" "F.Mask" "F.Paste")
			(net "PEX2_MODE_SEL10")
		)
		(pad "2" smd circle
			(at 0.40005 0 270)
			(size 0 0)
			(layers "F.Cu" "F.Mask" "F.Paste")
			(net "P1V8_PEX")
		)
	)
	(footprint ""
		(layer "F.Cu")
		(at 319.206626 -294.77335 90)
		(property "Reference" "U427"
			(at -1.0922 -2.174748 90)
			(unlocked yes)
			(layer "F.SilkS")
			(effects
				(font
					(size 0.7874 0.5842)
					(thickness 0.1524)
				)
				(justify left)
			)
		)
		(property "Value" ""
			(at 0 0 90)
			(layer "F.Fab")
			(effects
				(font
					(size 1.27 1.27)
				)
			)
		)
		(duplicate_pad_numbers_are_jumpers no)
		(fp_line
			(start 1.0414 -1.575054)
			(end 1.0414 1.575054)
			(stroke
				(width 0.1524)
				(type default)
			)
			(layer "F.SilkS")
		)
		(fp_line
			(start 0.254 -1.575054)
			(end 1.0414 -1.575054)
			(stroke
				(width 0.1524)
				(type default)
			)
			(layer "F.SilkS")
		)
		(fp_line
			(start 0.2286 -1.575054)
			(end 0 -1.272032)
			(stroke
				(width 0.1524)
				(type default)
			)
			(layer "F.SilkS")
		)
		(fp_line
			(start -1.0414 -1.575054)
			(end -0.254 -1.575054)
			(stroke
				(width 0.1524)
				(type default)
			)
			(layer "F.SilkS")
		)
		(fp_line
			(start 0 -1.272032)
			(end -0.254 -1.575054)
			(stroke
				(width 0.1524)
				(type default)
			)
			(layer "F.SilkS")
		)
		(fp_line
			(start 1.0414 1.575054)
			(end -1.0414 1.575054)
			(stroke
				(width 0.1524)
				(type default)
			)
			(layer "F.SilkS")
		)
		(fp_line
			(start -1.0414 1.575054)
			(end -1.0414 -1.575054)
			(stroke
				(width 0.1524)
				(type default)
			)
			(layer "F.SilkS")
		)
		(fp_poly
			(pts
				(xy -2.710688 -0.975106) (xy -3.726688 -1.483106) (xy -3.726688 -0.467106)
			)
			(stroke
				(width 0)
				(type default)
			)
			(fill yes)
			(layer "F.SilkS")
		)
		(fp_line
			(start 1.4478 -1.5748)
			(end 1.4478 -1.2192)
			(stroke
				(width 0.1)
				(type default)
			)
			(layer "F.Fab")
		)
		(fp_line
			(start -1.4478 -1.5748)
			(end 1.4478 -1.5748)
			(stroke
				(width 0.1)
				(type default)
			)
			(layer "F.Fab")
		)
		(fp_line
			(start 2.5654 -1.2192)
			(end 2.5654 1.2192)
			(stroke
				(width 0.1)
				(type default)
			)
			(layer "F.Fab")
		)
		(fp_line
			(start 1.4478 -1.2192)
			(end 2.5654 -1.2192)
			(stroke
				(width 0.1)
				(type default)
			)
			(layer "F.Fab")
		)
		(fp_line
			(start -1.4478 -1.2192)
			(end -1.4478 -1.5748)
			(stroke
				(width 0.1)
				(type default)
			)
			(layer "F.Fab")
		)
		(fp_line
			(start -2.5654 -1.2192)
			(end -1.4478 -1.2192)
			(stroke
				(width 0.1)
				(type default)
			)
			(layer "F.Fab")
		)
		(fp_line
			(start 2.5654 1.2192)
			(end 1.4478 1.2192)
			(stroke
				(width 0.1)
				(type default)
			)
			(layer "F.Fab")
		)
		(fp_line
			(start 1.4478 1.2192)
			(end 1.4478 1.5748)
			(stroke
				(width 0.1)
				(type default)
			)
			(layer "F.Fab")
		)
		(fp_line
			(start -1.4478 1.2192)
			(end -2.5654 1.2192)
			(stroke
				(width 0.1)
				(type default)
			)
			(layer "F.Fab")
		)
		(fp_line
			(start -2.5654 1.2192)
			(end -2.5654 -1.2192)
			(stroke
				(width 0.1)
				(type default)
			)
			(layer "F.Fab")
		)
		(fp_line
			(start 1.4478 1.5748)
			(end -1.4478 1.5748)
			(stroke
				(width 0.1)
				(type default)
			)
			(layer "F.Fab")
		)
		(fp_line
			(start -1.4478 1.5748)
			(end -1.4478 1.2192)
			(stroke
				(width 0.1)
				(type default)
			)
			(layer "F.Fab")
		)
		(fp_poly
			(pts
				(xy -2.710688 -0.975106) (xy -3.726688 -1.483106) (xy -3.726688 -0.467106)
			)
			(stroke
				(width 0)
				(type default)
			)
			(fill yes)
			(layer "F.Fab")
		)
		(pad "1" smd rect
			(at -1.849882 -0.975106)
			(size 0.3556 1.3208)
			(layers "F.Cu" "F.Mask" "F.Paste")
			(net "RST_PEX2_PERST_R_N")
		)
		(pad "2" smd rect
			(at -1.849882 -0.32512)
			(size 0.3556 1.3208)
			(layers "F.Cu" "F.Mask" "F.Paste")
			(net "RST_PEX2_S0_PERST_N")
		)
		(pad "3" smd rect
			(at -1.849882 0.32512)
			(size 0.3556 1.3208)
			(layers "F.Cu" "F.Mask" "F.Paste")
			(net "RST_PEX2_PERST_R_N")
		)
		(pad "4" smd rect
			(at -1.849882 0.975106)
			(size 0.3556 1.3208)
			(layers "F.Cu" "F.Mask" "F.Paste")
			(net "GND")
		)
		(pad "5" smd rect
			(at 1.849882 0.975106)
			(size 0.3556 1.3208)
			(layers "F.Cu" "F.Mask" "F.Paste")
			(net "RST_PEX2_S1_PERST_N")
		)
		(pad "6" smd rect
			(at 1.849882 0.32512)
			(size 0.3556 1.3208)
			(layers "F.Cu" "F.Mask" "F.Paste")
			(net "RST_PEX2_PERST_R_N")
		)
		(pad "7" smd rect
			(at 1.849882 -0.32512)
			(size 0.3556 1.3208)
			(layers "F.Cu" "F.Mask" "F.Paste")
			(net "RST_PEX2_S3_PERST_N")
		)
		(pad "8" smd rect
			(at 1.849882 -0.975106)
			(size 0.3556 1.3208)
			(layers "F.Cu" "F.Mask" "F.Paste")
			(net "P1V8_PEX")
		)
	)
	(footprint ""
		(layer "F.Cu")
		(at 136.250172 -276.010116)
		(property "Reference" "H135"
			(at -0.550672 -4.599432 0)
			(unlocked yes)
			(layer "F.SilkS")
			(effects
				(font
					(size 0.7874 0.5842)
					(thickness 0.1524)
				)
				(justify left)
			)
		)
		(property "Value" ""
			(at 0 0 0)
			(layer "F.Fab")
			(effects
				(font
					(size 1.27 1.27)
				)
			)
		)
		(duplicate_pad_numbers_are_jumpers no)
		(pad "1" thru_hole circle
			(at 0 0)
			(size 6.5024 6.5024)
			(drill 3.2004)
			(layers "*.Cu" "*.Mask")
			(remove_unused_layers no)
			(net "GND")
			(clearance -1.397)
		)
	)
	(footprint ""
		(layer "F.Cu")
		(at 222.492316 -257.975862 -90)
		(property "Reference" "R6492"
			(at 0 0 270)
			(layer "F.SilkS")
			(hide yes)
			(effects
				(font
					(size 1.27 1.27)
				)
			)
		)
		(property "Value" ""
			(at 0 0 270)
			(layer "F.Fab")
			(effects
				(font
					(size 1.27 1.27)
				)
			)
		)
		(duplicate_pad_numbers_are_jumpers no)
		(fp_line
			(start -0.7874 0.4064)
			(end -0.7874 -0.4064)
			(stroke
				(width 0.1524)
				(type default)
			)
			(layer "F.SilkS")
		)
		(fp_line
			(start 0.7874 0.4064)
			(end -0.7874 0.4064)
			(stroke
				(width 0.1524)
				(type default)
			)
			(layer "F.SilkS")
		)
		(fp_line
			(start -0.7874 -0.4064)
			(end 0.7874 -0.4064)
			(stroke
				(width 0.1524)
				(type default)
			)
			(layer "F.SilkS")
		)
		(fp_line
			(start 0.7874 -0.4064)
			(end 0.7874 0.4064)
			(stroke
				(width 0.1524)
				(type default)
			)
			(layer "F.SilkS")
		)
		(fp_line
			(start -0.67945 0.3048)
			(end -0.67945 -0.305054)
			(stroke
				(width 0.1)
				(type default)
			)
			(layer "F.Fab")
		)
		(fp_line
			(start -0.12065 0.3048)
			(end -0.67945 0.3048)
			(stroke
				(width 0.1)
				(type default)
			)
			(layer "F.Fab")
		)
		(fp_line
			(start 0.120396 0.3048)
			(end 0.120396 0.2794)
			(stroke
				(width 0.1)
				(type default)
			)
			(layer "F.Fab")
		)
		(fp_line
			(start 0.67945 0.3048)
			(end 0.120396 0.3048)
			(stroke
				(width 0.1)
				(type default)
			)
			(layer "F.Fab")
		)
		(fp_line
			(start -0.12065 0.2794)
			(end -0.12065 0.3048)
			(stroke
				(width 0.1)
				(type default)
			)
			(layer "F.Fab")
		)
		(fp_line
			(start 0.120396 0.2794)
			(end -0.12065 0.2794)
			(stroke
				(width 0.1)
				(type default)
			)
			(layer "F.Fab")
		)
		(fp_line
			(start -0.12065 -0.2794)
			(end 0.12065 -0.2794)
			(stroke
				(width 0.1)
				(type default)
			)
			(layer "F.Fab")
		)
		(fp_line
			(start 0.12065 -0.2794)
			(end 0.12065 -0.3048)
			(stroke
				(width 0.1)
				(type default)
			)
			(layer "F.Fab")
		)
		(fp_line
			(start 0.12065 -0.3048)
			(end 0.67945 -0.3048)
			(stroke
				(width 0.1)
				(type default)
			)
			(layer "F.Fab")
		)
		(fp_line
			(start 0.67945 -0.3048)
			(end 0.67945 0.3048)
			(stroke
				(width 0.1)
				(type default)
			)
			(layer "F.Fab")
		)
		(fp_line
			(start -0.67945 -0.305054)
			(end -0.12065 -0.305054)
			(stroke
				(width 0.1)
				(type default)
			)
			(layer "F.Fab")
		)
		(fp_line
			(start -0.12065 -0.305054)
			(end -0.12065 -0.2794)
			(stroke
				(width 0.1)
				(type default)
			)
			(layer "F.Fab")
		)
		(pad "1" smd circle
			(at -0.40005 0 270)
			(size 0 0)
			(layers "F.Cu" "F.Mask" "F.Paste")
			(net "P1V25_SERDES_VDDPLL_PEX1")
		)
		(pad "2" smd circle
			(at 0.40005 0 270)
			(size 0 0)
			(layers "F.Cu" "F.Mask" "F.Paste")
			(net "P1V25_SERDES_VDDPLL_PEX1_C1")
		)
	)
	(footprint ""
		(layer "F.Cu")
		(at 445.9478 -237.5154 180)
		(property "Reference" "R6601"
			(at 0 0 180)
			(layer "F.SilkS")
			(hide yes)
			(effects
				(font
					(size 1.27 1.27)
				)
			)
		)
		(property "Value" ""
			(at 0 0 180)
			(layer "F.Fab")
			(effects
				(font
					(size 1.27 1.27)
				)
			)
		)
		(duplicate_pad_numbers_are_jumpers no)
		(fp_line
			(start 0.7874 0.4064)
			(end -0.7874 0.4064)
			(stroke
				(width 0.1524)
				(type default)
			)
			(layer "F.SilkS")
		)
		(fp_line
			(start 0.7874 -0.4064)
			(end 0.7874 0.4064)
			(stroke
				(width 0.1524)
				(type default)
			)
			(layer "F.SilkS")
		)
		(fp_line
			(start -0.7874 0.4064)
			(end -0.7874 -0.4064)
			(stroke
				(width 0.1524)
				(type default)
			)
			(layer "F.SilkS")
		)
		(fp_line
			(start -0.7874 -0.4064)
			(end 0.7874 -0.4064)
			(stroke
				(width 0.1524)
				(type default)
			)
			(layer "F.SilkS")
		)
		(fp_line
			(start 0.67945 0.3048)
			(end 0.120396 0.3048)
			(stroke
				(width 0.1)
				(type default)
			)
			(layer "F.Fab")
		)
		(fp_line
			(start 0.67945 -0.3048)
			(end 0.67945 0.3048)
			(stroke
				(width 0.1)
				(type default)
			)
			(layer "F.Fab")
		)
		(fp_line
			(start 0.12065 -0.2794)
			(end 0.12065 -0.3048)
			(stroke
				(width 0.1)
				(type default)
			)
			(layer "F.Fab")
		)
		(fp_line
			(start 0.12065 -0.3048)
			(end 0.67945 -0.3048)
			(stroke
				(width 0.1)
				(type default)
			)
			(layer "F.Fab")
		)
		(fp_line
			(start 0.120396 0.3048)
			(end 0.120396 0.2794)
			(stroke
				(width 0.1)
				(type default)
			)
			(layer "F.Fab")
		)
		(fp_line
			(start 0.120396 0.2794)
			(end -0.12065 0.2794)
			(stroke
				(width 0.1)
				(type default)
			)
			(layer "F.Fab")
		)
		(fp_line
			(start -0.12065 0.3048)
			(end -0.67945 0.3048)
			(stroke
				(width 0.1)
				(type default)
			)
			(layer "F.Fab")
		)
		(fp_line
			(start -0.12065 0.2794)
			(end -0.12065 0.3048)
			(stroke
				(width 0.1)
				(type default)
			)
			(layer "F.Fab")
		)
		(fp_line
			(start -0.12065 -0.2794)
			(end 0.12065 -0.2794)
			(stroke
				(width 0.1)
				(type default)
			)
			(layer "F.Fab")
		)
		(fp_line
			(start -0.12065 -0.305054)
			(end -0.12065 -0.2794)
			(stroke
				(width 0.1)
				(type default)
			)
			(layer "F.Fab")
		)
		(fp_line
			(start -0.67945 0.3048)
			(end -0.67945 -0.305054)
			(stroke
				(width 0.1)
				(type default)
			)
			(layer "F.Fab")
		)
		(fp_line
			(start -0.67945 -0.305054)
			(end -0.12065 -0.305054)
			(stroke
				(width 0.1)
				(type default)
			)
			(layer "F.Fab")
		)
		(pad "1" smd circle
			(at -0.40005 0 180)
			(size 0 0)
			(layers "F.Cu" "F.Mask" "F.Paste")
			(net "RST_CP2108_SDB_R_N")
		)
		(pad "2" smd circle
			(at 0.40005 0 180)
			(size 0 0)
			(layers "F.Cu" "F.Mask" "F.Paste")
			(net "RST_FT4232_R_N")
		)
	)
	(footprint ""
		(layer "F.Cu")
		(at 73.782682 -343.952322 90)
		(property "Reference" "C139"
			(at 0 0 90)
			(layer "F.SilkS")
			(hide yes)
			(effects
				(font
					(size 1.27 1.27)
				)
			)
		)
		(property "Value" ""
			(at 0 0 90)
			(layer "F.Fab")
			(effects
				(font
					(size 1.27 1.27)
				)
			)
		)
		(duplicate_pad_numbers_are_jumpers no)
		(fp_line
			(start 0.299974 -0.150114)
			(end 0.299974 0.150114)
			(stroke
				(width 0.1)
				(type default)
			)
			(layer "F.Fab")
		)
		(fp_line
			(start -0.299974 -0.150114)
			(end 0.299974 -0.150114)
			(stroke
				(width 0.1)
				(type default)
			)
			(layer "F.Fab")
		)
		(fp_line
			(start 0.299974 0.150114)
			(end -0.299974 0.150114)
			(stroke
				(width 0.1)
				(type default)
			)
			(layer "F.Fab")
		)
		(fp_line
			(start -0.299974 0.150114)
			(end -0.299974 -0.150114)
			(stroke
				(width 0.1)
				(type default)
			)
			(layer "F.Fab")
		)
		(pad "1" smd rect
			(at -0.2667 0 90)
			(size 0.3048 0.381)
			(layers "F.Cu" "F.Mask" "F.Paste")
			(net "P5E_PEX0_STN6_TX_DP<106>")
		)
		(pad "2" smd rect
			(at 0.2667 0 90)
			(size 0.3048 0.381)
			(layers "F.Cu" "F.Mask" "F.Paste")
			(net "P5E_PEX0_STN6_TX_C_DP<106>")
		)
	)
	(footprint ""
		(layer "F.Cu")
		(at 368.746532 -58.323734)
		(property "Reference" "PC413"
			(at 0 0 0)
			(layer "F.SilkS")
			(hide yes)
			(effects
				(font
					(size 1.27 1.27)
				)
			)
		)
		(property "Value" ""
			(at 0 0 0)
			(layer "F.Fab")
			(effects
				(font
					(size 1.27 1.27)
				)
			)
		)
		(duplicate_pad_numbers_are_jumpers no)
		(fp_line
			(start -1.524 -0.762)
			(end 1.524 -0.762)
			(stroke
				(width 0.1524)
				(type default)
			)
			(layer "F.SilkS")
		)
		(fp_line
			(start -1.524 0.762)
			(end -1.524 -0.762)
			(stroke
				(width 0.1524)
				(type default)
			)
			(layer "F.SilkS")
		)
		(fp_line
			(start 1.524 -0.762)
			(end 1.524 0.762)
			(stroke
				(width 0.1524)
				(type default)
			)
			(layer "F.SilkS")
		)
		(fp_line
			(start 1.524 0.762)
			(end -1.524 0.762)
			(stroke
				(width 0.1524)
				(type default)
			)
			(layer "F.SilkS")
		)
		(fp_line
			(start -1.1049 -0.724916)
			(end -1.1049 0.724916)
			(stroke
				(width 0.1)
				(type default)
			)
			(layer "F.Fab")
		)
		(fp_line
			(start -1.1049 0.724916)
			(end 1.1049 0.724916)
			(stroke
				(width 0.1)
				(type default)
			)
			(layer "F.Fab")
		)
		(fp_line
			(start 1.1049 -0.724916)
			(end -1.1049 -0.724916)
			(stroke
				(width 0.1)
				(type default)
			)
			(layer "F.Fab")
		)
		(fp_line
			(start 1.1049 0.724916)
			(end 1.1049 -0.724916)
			(stroke
				(width 0.1)
				(type default)
			)
			(layer "F.Fab")
		)
		(pad "1" smd rect
			(at -0.889 0 180)
			(size 1.016 1.27)
			(layers "F.Cu" "F.Mask" "F.Paste")
			(net "GND")
		)
		(pad "2" smd rect
			(at 0.889 0 180)
			(size 1.016 1.27)
			(layers "F.Cu" "F.Mask" "F.Paste")
			(net "P12V_AUX")
		)
	)
	(footprint ""
		(layer "F.Cu")
		(at 206.73949 -293.47287 -90)
		(property "Reference" "U314"
			(at 0.946404 -4.968748 90)
			(unlocked yes)
			(layer "F.SilkS")
			(effects
				(font
					(size 0.7874 0.5842)
					(thickness 0.1524)
				)
				(justify left)
			)
		)
		(property "Value" ""
			(at 0 0 270)
			(layer "F.Fab")
			(effects
				(font
					(size 1.27 1.27)
				)
			)
		)
		(duplicate_pad_numbers_are_jumpers no)
		(fp_line
			(start -1.463548 1.549908)
			(end -1.463548 -1.549908)
			(stroke
				(width 0.1524)
				(type default)
			)
			(layer "F.SilkS")
		)
		(fp_line
			(start 1.463548 1.549908)
			(end -1.463548 1.549908)
			(stroke
				(width 0.1524)
				(type default)
			)
			(layer "F.SilkS")
		)
		(fp_line
			(start 0 -0.762)
			(end 0.762 -1.549908)
			(stroke
				(width 0.1524)
				(type default)
			)
			(layer "F.SilkS")
		)
		(fp_line
			(start -1.463548 -1.549908)
			(end -0.787908 -1.549908)
			(stroke
				(width 0.1524)
				(type default)
			)
			(layer "F.SilkS")
		)
		(fp_line
			(start -0.787908 -1.549908)
			(end 0 -0.762)
			(stroke
				(width 0.1524)
				(type default)
			)
			(layer "F.SilkS")
		)
		(fp_line
			(start 0.762 -1.549908)
			(end 1.463548 -1.549908)
			(stroke
				(width 0.1524)
				(type default)
			)
			(layer "F.SilkS")
		)
		(fp_line
			(start 1.463548 -1.549908)
			(end 1.463548 1.549908)
			(stroke
				(width 0.1524)
				(type default)
			)
			(layer "F.SilkS")
		)
		(fp_poly
			(pts
				(xy -3.4798 -1.359916) (xy -2.86004 -1.050036) (xy -3.4798 -0.740156)
			)
			(stroke
				(width 0)
				(type default)
			)
			(fill yes)
			(layer "F.SilkS")
		)
		(fp_line
			(start -1.549908 1.549908)
			(end -1.549908 -1.549908)
			(stroke
				(width 0.1)
				(type default)
			)
			(layer "F.Fab")
		)
		(fp_line
			(start 1.549908 1.549908)
			(end -1.549908 1.549908)
			(stroke
				(width 0.1)
				(type default)
			)
			(layer "F.Fab")
		)
		(fp_line
			(start -1.549908 -1.549908)
			(end 1.549908 -1.549908)
			(stroke
				(width 0.1)
				(type default)
			)
			(layer "F.Fab")
		)
		(fp_line
			(start 1.549908 -1.549908)
			(end 1.549908 1.549908)
			(stroke
				(width 0.1)
				(type default)
			)
			(layer "F.Fab")
		)
		(fp_poly
			(pts
				(xy -3.4798 -1.359916) (xy -2.86004 -1.050036) (xy -3.4798 -0.740156)
			)
			(stroke
				(width 0)
				(type default)
			)
			(fill yes)
			(layer "F.Fab")
		)
		(pad "1" smd rect
			(at -2.175002 -1.050036)
			(size 0.6096 1.1684)
			(layers "F.Cu" "F.Mask" "F.Paste")
			(net "P1V8_PEX")
		)
		(pad "2" smd rect
			(at -2.175002 -0.32512)
			(size 0.4318 1.1684)
			(layers "F.Cu" "F.Mask" "F.Paste")
			(net "I2C_PEX1_HOST_R_SCL")
		)
		(pad "3" smd rect
			(at -2.175002 0.32512)
			(size 0.4318 1.1684)
			(layers "F.Cu" "F.Mask" "F.Paste")
			(net "I2C_PEX1_HOST_R_SDA")
		)
		(pad "4" smd rect
			(at -2.175002 1.050036)
			(size 0.6096 1.1684)
			(layers "F.Cu" "F.Mask" "F.Paste")
			(net "GND")
		)
		(pad "5" smd rect
			(at 2.175002 1.050036)
			(size 0.6096 1.1684)
			(layers "F.Cu" "F.Mask" "F.Paste")
			(net "PWRGD_P1V8_PEX1_R")
		)
		(pad "6" smd rect
			(at 2.175002 0.32512)
			(size 0.4318 1.1684)
			(layers "F.Cu" "F.Mask" "F.Paste")
			(net "SMB_PEX1_HOST_LS_SDA")
		)
		(pad "7" smd rect
			(at 2.175002 -0.32512)
			(size 0.4318 1.1684)
			(layers "F.Cu" "F.Mask" "F.Paste")
			(net "SMB_PEX1_HOST_LS_SCL")
		)
		(pad "8" smd rect
			(at 2.175002 -1.050036)
			(size 0.6096 1.1684)
			(layers "F.Cu" "F.Mask" "F.Paste")
			(net "P3V3_AUX")
		)
	)
	(footprint ""
		(layer "F.Cu")
		(at 396.94866 -343.952322 90)
		(property "Reference" "C739"
			(at 0 0 90)
			(layer "F.SilkS")
			(hide yes)
			(effects
				(font
					(size 1.27 1.27)
				)
			)
		)
		(property "Value" ""
			(at 0 0 90)
			(layer "F.Fab")
			(effects
				(font
					(size 1.27 1.27)
				)
			)
		)
		(duplicate_pad_numbers_are_jumpers no)
		(fp_line
			(start 0.299974 -0.150114)
			(end 0.299974 0.150114)
			(stroke
				(width 0.1)
				(type default)
			)
			(layer "F.Fab")
		)
		(fp_line
			(start -0.299974 -0.150114)
			(end 0.299974 -0.150114)
			(stroke
				(width 0.1)
				(type default)
			)
			(layer "F.Fab")
		)
		(fp_line
			(start 0.299974 0.150114)
			(end -0.299974 0.150114)
			(stroke
				(width 0.1)
				(type default)
			)
			(layer "F.Fab")
		)
		(fp_line
			(start -0.299974 0.150114)
			(end -0.299974 -0.150114)
			(stroke
				(width 0.1)
				(type default)
			)
			(layer "F.Fab")
		)
		(pad "1" smd rect
			(at -0.2667 0 90)
			(size 0.3048 0.381)
			(layers "F.Cu" "F.Mask" "F.Paste")
			(net "P5E_PEX3_STN5_TX_DN<91>")
		)
		(pad "2" smd rect
			(at 0.2667 0 90)
			(size 0.3048 0.381)
			(layers "F.Cu" "F.Mask" "F.Paste")
			(net "P5E_PEX3_STN5_TX_C_DN<91>")
		)
	)
	(footprint ""
		(layer "F.Cu")
		(at 115.48364 -279.486868 -90)
		(property "Reference" "PR106"
			(at 0 0 270)
			(layer "F.SilkS")
			(hide yes)
			(effects
				(font
					(size 1.27 1.27)
				)
			)
		)
		(property "Value" ""
			(at 0 0 270)
			(layer "F.Fab")
			(effects
				(font
					(size 1.27 1.27)
				)
			)
		)
		(duplicate_pad_numbers_are_jumpers no)
		(fp_line
			(start -0.7874 0.4064)
			(end -0.7874 -0.4064)
			(stroke
				(width 0.1524)
				(type default)
			)
			(layer "F.SilkS")
		)
		(fp_line
			(start 0.7874 0.4064)
			(end -0.7874 0.4064)
			(stroke
				(width 0.1524)
				(type default)
			)
			(layer "F.SilkS")
		)
		(fp_line
			(start -0.7874 -0.4064)
			(end 0.7874 -0.4064)
			(stroke
				(width 0.1524)
				(type default)
			)
			(layer "F.SilkS")
		)
		(fp_line
			(start 0.7874 -0.4064)
			(end 0.7874 0.4064)
			(stroke
				(width 0.1524)
				(type default)
			)
			(layer "F.SilkS")
		)
		(fp_line
			(start -0.67945 0.3048)
			(end -0.67945 -0.305054)
			(stroke
				(width 0.1)
				(type default)
			)
			(layer "F.Fab")
		)
		(fp_line
			(start -0.12065 0.3048)
			(end -0.67945 0.3048)
			(stroke
				(width 0.1)
				(type default)
			)
			(layer "F.Fab")
		)
		(fp_line
			(start 0.120396 0.3048)
			(end 0.120396 0.2794)
			(stroke
				(width 0.1)
				(type default)
			)
			(layer "F.Fab")
		)
		(fp_line
			(start 0.67945 0.3048)
			(end 0.120396 0.3048)
			(stroke
				(width 0.1)
				(type default)
			)
			(layer "F.Fab")
		)
		(fp_line
			(start -0.12065 0.2794)
			(end -0.12065 0.3048)
			(stroke
				(width 0.1)
				(type default)
			)
			(layer "F.Fab")
		)
		(fp_line
			(start 0.120396 0.2794)
			(end -0.12065 0.2794)
			(stroke
				(width 0.1)
				(type default)
			)
			(layer "F.Fab")
		)
		(fp_line
			(start -0.12065 -0.2794)
			(end 0.12065 -0.2794)
			(stroke
				(width 0.1)
				(type default)
			)
			(layer "F.Fab")
		)
		(fp_line
			(start 0.12065 -0.2794)
			(end 0.12065 -0.3048)
			(stroke
				(width 0.1)
				(type default)
			)
			(layer "F.Fab")
		)
		(fp_line
			(start 0.12065 -0.3048)
			(end 0.67945 -0.3048)
			(stroke
				(width 0.1)
				(type default)
			)
			(layer "F.Fab")
		)
		(fp_line
			(start 0.67945 -0.3048)
			(end 0.67945 0.3048)
			(stroke
				(width 0.1)
				(type default)
			)
			(layer "F.Fab")
		)
		(fp_line
			(start -0.67945 -0.305054)
			(end -0.12065 -0.305054)
			(stroke
				(width 0.1)
				(type default)
			)
			(layer "F.Fab")
		)
		(fp_line
			(start -0.12065 -0.305054)
			(end -0.12065 -0.2794)
			(stroke
				(width 0.1)
				(type default)
			)
			(layer "F.Fab")
		)
		(pad "1" smd circle
			(at -0.40005 0 270)
			(size 0 0)
			(layers "F.Cu" "F.Mask" "F.Paste")
			(net "P0V8_PEX0_LSET2")
		)
		(pad "2" smd circle
			(at 0.40005 0 270)
			(size 0 0)
			(layers "F.Cu" "F.Mask" "F.Paste")
			(net "GND")
		)
	)
	(footprint ""
		(layer "F.Cu")
		(at 266.320524 -26.666444 -90)
		(property "Reference" "R4071"
			(at 0 0 270)
			(layer "F.SilkS")
			(hide yes)
			(effects
				(font
					(size 1.27 1.27)
				)
			)
		)
		(property "Value" ""
			(at 0 0 270)
			(layer "F.Fab")
			(effects
				(font
					(size 1.27 1.27)
				)
			)
		)
		(duplicate_pad_numbers_are_jumpers no)
		(fp_line
			(start -0.7874 0.4064)
			(end -0.7874 -0.4064)
			(stroke
				(width 0.1524)
				(type default)
			)
			(layer "F.SilkS")
		)
		(fp_line
			(start 0.7874 0.4064)
			(end -0.7874 0.4064)
			(stroke
				(width 0.1524)
				(type default)
			)
			(layer "F.SilkS")
		)
		(fp_line
			(start -0.7874 -0.4064)
			(end 0.7874 -0.4064)
			(stroke
				(width 0.1524)
				(type default)
			)
			(layer "F.SilkS")
		)
		(fp_line
			(start 0.7874 -0.4064)
			(end 0.7874 0.4064)
			(stroke
				(width 0.1524)
				(type default)
			)
			(layer "F.SilkS")
		)
		(fp_line
			(start -0.67945 0.3048)
			(end -0.67945 -0.305054)
			(stroke
				(width 0.1)
				(type default)
			)
			(layer "F.Fab")
		)
		(fp_line
			(start -0.12065 0.3048)
			(end -0.67945 0.3048)
			(stroke
				(width 0.1)
				(type default)
			)
			(layer "F.Fab")
		)
		(fp_line
			(start 0.120396 0.3048)
			(end 0.120396 0.2794)
			(stroke
				(width 0.1)
				(type default)
			)
			(layer "F.Fab")
		)
		(fp_line
			(start 0.67945 0.3048)
			(end 0.120396 0.3048)
			(stroke
				(width 0.1)
				(type default)
			)
			(layer "F.Fab")
		)
		(fp_line
			(start -0.12065 0.2794)
			(end -0.12065 0.3048)
			(stroke
				(width 0.1)
				(type default)
			)
			(layer "F.Fab")
		)
		(fp_line
			(start 0.120396 0.2794)
			(end -0.12065 0.2794)
			(stroke
				(width 0.1)
				(type default)
			)
			(layer "F.Fab")
		)
		(fp_line
			(start -0.12065 -0.2794)
			(end 0.12065 -0.2794)
			(stroke
				(width 0.1)
				(type default)
			)
			(layer "F.Fab")
		)
		(fp_line
			(start 0.12065 -0.2794)
			(end 0.12065 -0.3048)
			(stroke
				(width 0.1)
				(type default)
			)
			(layer "F.Fab")
		)
		(fp_line
			(start 0.12065 -0.3048)
			(end 0.67945 -0.3048)
			(stroke
				(width 0.1)
				(type default)
			)
			(layer "F.Fab")
		)
		(fp_line
			(start 0.67945 -0.3048)
			(end 0.67945 0.3048)
			(stroke
				(width 0.1)
				(type default)
			)
			(layer "F.Fab")
		)
		(fp_line
			(start -0.67945 -0.305054)
			(end -0.12065 -0.305054)
			(stroke
				(width 0.1)
				(type default)
			)
			(layer "F.Fab")
		)
		(fp_line
			(start -0.12065 -0.305054)
			(end -0.12065 -0.2794)
			(stroke
				(width 0.1)
				(type default)
			)
			(layer "F.Fab")
		)
		(pad "1" smd circle
			(at -0.40005 0 270)
			(size 0 0)
			(layers "F.Cu" "F.Mask" "F.Paste")
			(net "PRSNT_SSD9_R_N")
		)
		(pad "2" smd circle
			(at 0.40005 0 270)
			(size 0 0)
			(layers "F.Cu" "F.Mask" "F.Paste")
			(net "PRSNT_SSD9_N")
		)
	)
	(footprint ""
		(layer "F.Cu")
		(at 459.574646 -306.510436 -90)
		(property "Reference" "PC281"
			(at 0 0 270)
			(layer "F.SilkS")
			(hide yes)
			(effects
				(font
					(size 1.27 1.27)
				)
			)
		)
		(property "Value" ""
			(at 0 0 270)
			(layer "F.Fab")
			(effects
				(font
					(size 1.27 1.27)
				)
			)
		)
		(duplicate_pad_numbers_are_jumpers no)
		(fp_line
			(start -0.7874 0.4064)
			(end -0.7874 -0.4064)
			(stroke
				(width 0.1524)
				(type default)
			)
			(layer "F.SilkS")
		)
		(fp_line
			(start 0.7874 0.4064)
			(end -0.7874 0.4064)
			(stroke
				(width 0.1524)
				(type default)
			)
			(layer "F.SilkS")
		)
		(fp_line
			(start -0.7874 -0.4064)
			(end 0.7874 -0.4064)
			(stroke
				(width 0.1524)
				(type default)
			)
			(layer "F.SilkS")
		)
		(fp_line
			(start 0.7874 -0.4064)
			(end 0.7874 0.4064)
			(stroke
				(width 0.1524)
				(type default)
			)
			(layer "F.SilkS")
		)
		(fp_line
			(start -0.67945 0.3048)
			(end -0.67945 -0.305054)
			(stroke
				(width 0.1)
				(type default)
			)
			(layer "F.Fab")
		)
		(fp_line
			(start -0.12065 0.3048)
			(end -0.67945 0.3048)
			(stroke
				(width 0.1)
				(type default)
			)
			(layer "F.Fab")
		)
		(fp_line
			(start 0.120396 0.3048)
			(end 0.120396 0.2794)
			(stroke
				(width 0.1)
				(type default)
			)
			(layer "F.Fab")
		)
		(fp_line
			(start 0.67945 0.3048)
			(end 0.120396 0.3048)
			(stroke
				(width 0.1)
				(type default)
			)
			(layer "F.Fab")
		)
		(fp_line
			(start -0.12065 0.2794)
			(end -0.12065 0.3048)
			(stroke
				(width 0.1)
				(type default)
			)
			(layer "F.Fab")
		)
		(fp_line
			(start 0.120396 0.2794)
			(end -0.12065 0.2794)
			(stroke
				(width 0.1)
				(type default)
			)
			(layer "F.Fab")
		)
		(fp_line
			(start -0.12065 -0.2794)
			(end 0.12065 -0.2794)
			(stroke
				(width 0.1)
				(type default)
			)
			(layer "F.Fab")
		)
		(fp_line
			(start 0.12065 -0.2794)
			(end 0.12065 -0.3048)
			(stroke
				(width 0.1)
				(type default)
			)
			(layer "F.Fab")
		)
		(fp_line
			(start 0.12065 -0.3048)
			(end 0.67945 -0.3048)
			(stroke
				(width 0.1)
				(type default)
			)
			(layer "F.Fab")
		)
		(fp_line
			(start 0.67945 -0.3048)
			(end 0.67945 0.3048)
			(stroke
				(width 0.1)
				(type default)
			)
			(layer "F.Fab")
		)
		(fp_line
			(start -0.67945 -0.305054)
			(end -0.12065 -0.305054)
			(stroke
				(width 0.1)
				(type default)
			)
			(layer "F.Fab")
		)
		(fp_line
			(start -0.12065 -0.305054)
			(end -0.12065 -0.2794)
			(stroke
				(width 0.1)
				(type default)
			)
			(layer "F.Fab")
		)
		(pad "1" smd circle
			(at -0.40005 0 270)
			(size 0 0)
			(layers "F.Cu" "F.Mask" "F.Paste")
			(net "P1V25_PEX3_REF")
		)
		(pad "2" smd circle
			(at 0.40005 0 270)
			(size 0 0)
			(layers "F.Cu" "F.Mask" "F.Paste")
			(net "GND")
		)
	)
	(footprint ""
		(layer "F.Cu")
		(at 251.996194 -47.20082 90)
		(property "Reference" "C322"
			(at 0 0 90)
			(layer "F.SilkS")
			(hide yes)
			(effects
				(font
					(size 1.27 1.27)
				)
			)
		)
		(property "Value" ""
			(at 0 0 90)
			(layer "F.Fab")
			(effects
				(font
					(size 1.27 1.27)
				)
			)
		)
		(duplicate_pad_numbers_are_jumpers no)
		(fp_line
			(start 0.7874 -0.4064)
			(end 0.7874 0.4064)
			(stroke
				(width 0.1524)
				(type default)
			)
			(layer "F.SilkS")
		)
		(fp_line
			(start -0.7874 -0.4064)
			(end 0.7874 -0.4064)
			(stroke
				(width 0.1524)
				(type default)
			)
			(layer "F.SilkS")
		)
		(fp_line
			(start 0.7874 0.4064)
			(end -0.7874 0.4064)
			(stroke
				(width 0.1524)
				(type default)
			)
			(layer "F.SilkS")
		)
		(fp_line
			(start -0.7874 0.4064)
			(end -0.7874 -0.4064)
			(stroke
				(width 0.1524)
				(type default)
			)
			(layer "F.SilkS")
		)
		(fp_line
			(start -0.12065 -0.305054)
			(end -0.12065 -0.2794)
			(stroke
				(width 0.1)
				(type default)
			)
			(layer "F.Fab")
		)
		(fp_line
			(start -0.67945 -0.305054)
			(end -0.12065 -0.305054)
			(stroke
				(width 0.1)
				(type default)
			)
			(layer "F.Fab")
		)
		(fp_line
			(start 0.67945 -0.3048)
			(end 0.67945 0.3048)
			(stroke
				(width 0.1)
				(type default)
			)
			(layer "F.Fab")
		)
		(fp_line
			(start 0.12065 -0.3048)
			(end 0.67945 -0.3048)
			(stroke
				(width 0.1)
				(type default)
			)
			(layer "F.Fab")
		)
		(fp_line
			(start 0.12065 -0.2794)
			(end 0.12065 -0.3048)
			(stroke
				(width 0.1)
				(type default)
			)
			(layer "F.Fab")
		)
		(fp_line
			(start -0.12065 -0.2794)
			(end 0.12065 -0.2794)
			(stroke
				(width 0.1)
				(type default)
			)
			(layer "F.Fab")
		)
		(fp_line
			(start 0.120396 0.2794)
			(end -0.12065 0.2794)
			(stroke
				(width 0.1)
				(type default)
			)
			(layer "F.Fab")
		)
		(fp_line
			(start -0.12065 0.2794)
			(end -0.12065 0.3048)
			(stroke
				(width 0.1)
				(type default)
			)
			(layer "F.Fab")
		)
		(fp_line
			(start 0.67945 0.3048)
			(end 0.120396 0.3048)
			(stroke
				(width 0.1)
				(type default)
			)
			(layer "F.Fab")
		)
		(fp_line
			(start 0.120396 0.3048)
			(end 0.120396 0.2794)
			(stroke
				(width 0.1)
				(type default)
			)
			(layer "F.Fab")
		)
		(fp_line
			(start -0.12065 0.3048)
			(end -0.67945 0.3048)
			(stroke
				(width 0.1)
				(type default)
			)
			(layer "F.Fab")
		)
		(fp_line
			(start -0.67945 0.3048)
			(end -0.67945 -0.305054)
			(stroke
				(width 0.1)
				(type default)
			)
			(layer "F.Fab")
		)
		(pad "1" smd circle
			(at -0.40005 0 90)
			(size 0 0)
			(layers "F.Cu" "F.Mask" "F.Paste")
			(net "P12V_SSD8_R")
		)
		(pad "2" smd circle
			(at 0.40005 0 90)
			(size 0 0)
			(layers "F.Cu" "F.Mask" "F.Paste")
			(net "GND")
		)
	)
	(footprint ""
		(layer "F.Cu")
		(at 206.623158 -79.595472)
		(property "Reference" "R4307"
			(at 0 0 0)
			(layer "F.SilkS")
			(hide yes)
			(effects
				(font
					(size 1.27 1.27)
				)
			)
		)
		(property "Value" ""
			(at 0 0 0)
			(layer "F.Fab")
			(effects
				(font
					(size 1.27 1.27)
				)
			)
		)
		(duplicate_pad_numbers_are_jumpers no)
		(fp_line
			(start -0.7874 -0.4064)
			(end 0.7874 -0.4064)
			(stroke
				(width 0.1524)
				(type default)
			)
			(layer "F.SilkS")
		)
		(fp_line
			(start -0.7874 0.4064)
			(end -0.7874 -0.4064)
			(stroke
				(width 0.1524)
				(type default)
			)
			(layer "F.SilkS")
		)
		(fp_line
			(start 0.7874 -0.4064)
			(end 0.7874 0.4064)
			(stroke
				(width 0.1524)
				(type default)
			)
			(layer "F.SilkS")
		)
		(fp_line
			(start 0.7874 0.4064)
			(end -0.7874 0.4064)
			(stroke
				(width 0.1524)
				(type default)
			)
			(layer "F.SilkS")
		)
		(fp_line
			(start -0.67945 -0.305054)
			(end -0.12065 -0.305054)
			(stroke
				(width 0.1)
				(type default)
			)
			(layer "F.Fab")
		)
		(fp_line
			(start -0.67945 0.3048)
			(end -0.67945 -0.305054)
			(stroke
				(width 0.1)
				(type default)
			)
			(layer "F.Fab")
		)
		(fp_line
			(start -0.12065 -0.305054)
			(end -0.12065 -0.2794)
			(stroke
				(width 0.1)
				(type default)
			)
			(layer "F.Fab")
		)
		(fp_line
			(start -0.12065 -0.2794)
			(end 0.12065 -0.2794)
			(stroke
				(width 0.1)
				(type default)
			)
			(layer "F.Fab")
		)
		(fp_line
			(start -0.12065 0.2794)
			(end -0.12065 0.3048)
			(stroke
				(width 0.1)
				(type default)
			)
			(layer "F.Fab")
		)
		(fp_line
			(start -0.12065 0.3048)
			(end -0.67945 0.3048)
			(stroke
				(width 0.1)
				(type default)
			)
			(layer "F.Fab")
		)
		(fp_line
			(start 0.120396 0.2794)
			(end -0.12065 0.2794)
			(stroke
				(width 0.1)
				(type default)
			)
			(layer "F.Fab")
		)
		(fp_line
			(start 0.120396 0.3048)
			(end 0.120396 0.2794)
			(stroke
				(width 0.1)
				(type default)
			)
			(layer "F.Fab")
		)
		(fp_line
			(start 0.12065 -0.3048)
			(end 0.67945 -0.3048)
			(stroke
				(width 0.1)
				(type default)
			)
			(layer "F.Fab")
		)
		(fp_line
			(start 0.12065 -0.2794)
			(end 0.12065 -0.3048)
			(stroke
				(width 0.1)
				(type default)
			)
			(layer "F.Fab")
		)
		(fp_line
			(start 0.67945 -0.3048)
			(end 0.67945 0.3048)
			(stroke
				(width 0.1)
				(type default)
			)
			(layer "F.Fab")
		)
		(fp_line
			(start 0.67945 0.3048)
			(end 0.120396 0.3048)
			(stroke
				(width 0.1)
				(type default)
			)
			(layer "F.Fab")
		)
		(pad "1" smd circle
			(at -0.40005 0)
			(size 0 0)
			(layers "F.Cu" "F.Mask" "F.Paste")
			(net "SSD5_LED_R")
		)
		(pad "2" smd circle
			(at 0.40005 0)
			(size 0 0)
			(layers "F.Cu" "F.Mask" "F.Paste")
			(net "SSD5_LED")
		)
	)
	(footprint ""
		(layer "F.Cu")
		(at 495.253772 -522.248892 90)
		(property "Reference" "VR_HS0"
			(at -0.3937 -0.588518 90)
			(unlocked yes)
			(layer "F.SilkS")
			(effects
				(font
					(size 0.254 0.127)
					(thickness 0.000001)
				)
				(justify left)
			)
		)
		(property "Value" ""
			(at 0 0 90)
			(layer "F.Fab")
			(effects
				(font
					(size 1.27 1.27)
				)
			)
		)
		(duplicate_pad_numbers_are_jumpers no)
		(pad "1" smd circle
			(at 0 0 90)
			(size 0.762 0.762)
			(layers "F.Cu" "F.Mask" "F.Paste")
			(net "Net_9198")
		)
	)
	(footprint ""
		(layer "F.Cu")
		(at 142.926308 -356.244906 90)
		(property "Reference" "C2243"
			(at 0 0 90)
			(layer "F.SilkS")
			(hide yes)
			(effects
				(font
					(size 1.27 1.27)
				)
			)
		)
		(property "Value" ""
			(at 0 0 90)
			(layer "F.Fab")
			(effects
				(font
					(size 1.27 1.27)
				)
			)
		)
		(duplicate_pad_numbers_are_jumpers no)
		(fp_line
			(start 0.299974 -0.150114)
			(end 0.299974 0.150114)
			(stroke
				(width 0.1)
				(type default)
			)
			(layer "F.Fab")
		)
		(fp_line
			(start -0.299974 -0.150114)
			(end 0.299974 -0.150114)
			(stroke
				(width 0.1)
				(type default)
			)
			(layer "F.Fab")
		)
		(fp_line
			(start 0.299974 0.150114)
			(end -0.299974 0.150114)
			(stroke
				(width 0.1)
				(type default)
			)
			(layer "F.Fab")
		)
		(fp_line
			(start -0.299974 0.150114)
			(end -0.299974 -0.150114)
			(stroke
				(width 0.1)
				(type default)
			)
			(layer "F.Fab")
		)
		(pad "1" smd rect
			(at -0.2667 0 90)
			(size 0.3048 0.381)
			(layers "F.Cu" "F.Mask" "F.Paste")
			(net "P5E_PEX1_STN5_TX_DP<95>")
		)
		(pad "2" smd rect
			(at 0.2667 0 90)
			(size 0.3048 0.381)
			(layers "F.Cu" "F.Mask" "F.Paste")
			(net "P5E_PEX1_STN5_TX_C_DP<95>")
		)
	)
	(footprint ""
		(layer "F.Cu")
		(at 231.807512 -234.728004 -90)
		(property "Reference" "R6193"
			(at 0 0 270)
			(layer "F.SilkS")
			(hide yes)
			(effects
				(font
					(size 1.27 1.27)
				)
			)
		)
		(property "Value" ""
			(at 0 0 270)
			(layer "F.Fab")
			(effects
				(font
					(size 1.27 1.27)
				)
			)
		)
		(duplicate_pad_numbers_are_jumpers no)
		(fp_line
			(start -0.7874 0.4064)
			(end -0.7874 -0.4064)
			(stroke
				(width 0.1524)
				(type default)
			)
			(layer "F.SilkS")
		)
		(fp_line
			(start 0.7874 0.4064)
			(end -0.7874 0.4064)
			(stroke
				(width 0.1524)
				(type default)
			)
			(layer "F.SilkS")
		)
		(fp_line
			(start -0.7874 -0.4064)
			(end 0.7874 -0.4064)
			(stroke
				(width 0.1524)
				(type default)
			)
			(layer "F.SilkS")
		)
		(fp_line
			(start 0.7874 -0.4064)
			(end 0.7874 0.4064)
			(stroke
				(width 0.1524)
				(type default)
			)
			(layer "F.SilkS")
		)
		(fp_line
			(start -0.67945 0.3048)
			(end -0.67945 -0.305054)
			(stroke
				(width 0.1)
				(type default)
			)
			(layer "F.Fab")
		)
		(fp_line
			(start -0.12065 0.3048)
			(end -0.67945 0.3048)
			(stroke
				(width 0.1)
				(type default)
			)
			(layer "F.Fab")
		)
		(fp_line
			(start 0.120396 0.3048)
			(end 0.120396 0.2794)
			(stroke
				(width 0.1)
				(type default)
			)
			(layer "F.Fab")
		)
		(fp_line
			(start 0.67945 0.3048)
			(end 0.120396 0.3048)
			(stroke
				(width 0.1)
				(type default)
			)
			(layer "F.Fab")
		)
		(fp_line
			(start -0.12065 0.2794)
			(end -0.12065 0.3048)
			(stroke
				(width 0.1)
				(type default)
			)
			(layer "F.Fab")
		)
		(fp_line
			(start 0.120396 0.2794)
			(end -0.12065 0.2794)
			(stroke
				(width 0.1)
				(type default)
			)
			(layer "F.Fab")
		)
		(fp_line
			(start -0.12065 -0.2794)
			(end 0.12065 -0.2794)
			(stroke
				(width 0.1)
				(type default)
			)
			(layer "F.Fab")
		)
		(fp_line
			(start 0.12065 -0.2794)
			(end 0.12065 -0.3048)
			(stroke
				(width 0.1)
				(type default)
			)
			(layer "F.Fab")
		)
		(fp_line
			(start 0.12065 -0.3048)
			(end 0.67945 -0.3048)
			(stroke
				(width 0.1)
				(type default)
			)
			(layer "F.Fab")
		)
		(fp_line
			(start 0.67945 -0.3048)
			(end 0.67945 0.3048)
			(stroke
				(width 0.1)
				(type default)
			)
			(layer "F.Fab")
		)
		(fp_line
			(start -0.67945 -0.305054)
			(end -0.12065 -0.305054)
			(stroke
				(width 0.1)
				(type default)
			)
			(layer "F.Fab")
		)
		(fp_line
			(start -0.12065 -0.305054)
			(end -0.12065 -0.2794)
			(stroke
				(width 0.1)
				(type default)
			)
			(layer "F.Fab")
		)
		(pad "1" smd circle
			(at -0.40005 0 270)
			(size 0 0)
			(layers "F.Cu" "F.Mask" "F.Paste")
			(net "GND")
		)
		(pad "2" smd circle
			(at 0.40005 0 270)
			(size 0 0)
			(layers "F.Cu" "F.Mask" "F.Paste")
			(net "SSD11_PWRDIS_BIC_R")
		)
	)
	(footprint ""
		(layer "F.Cu")
		(at 320.852292 -116.416836 180)
		(property "Reference" "PC902"
			(at 0 0 180)
			(layer "F.SilkS")
			(hide yes)
			(effects
				(font
					(size 1.27 1.27)
				)
			)
		)
		(property "Value" ""
			(at 0 0 180)
			(layer "F.Fab")
			(effects
				(font
					(size 1.27 1.27)
				)
			)
		)
		(duplicate_pad_numbers_are_jumpers no)
		(fp_line
			(start 0.7874 0.4064)
			(end -0.7874 0.4064)
			(stroke
				(width 0.1524)
				(type default)
			)
			(layer "F.SilkS")
		)
		(fp_line
			(start 0.7874 -0.4064)
			(end 0.7874 0.4064)
			(stroke
				(width 0.1524)
				(type default)
			)
			(layer "F.SilkS")
		)
		(fp_line
			(start -0.7874 0.4064)
			(end -0.7874 -0.4064)
			(stroke
				(width 0.1524)
				(type default)
			)
			(layer "F.SilkS")
		)
		(fp_line
			(start -0.7874 -0.4064)
			(end 0.7874 -0.4064)
			(stroke
				(width 0.1524)
				(type default)
			)
			(layer "F.SilkS")
		)
		(fp_line
			(start 0.67945 0.3048)
			(end 0.120396 0.3048)
			(stroke
				(width 0.1)
				(type default)
			)
			(layer "F.Fab")
		)
		(fp_line
			(start 0.67945 -0.3048)
			(end 0.67945 0.3048)
			(stroke
				(width 0.1)
				(type default)
			)
			(layer "F.Fab")
		)
		(fp_line
			(start 0.12065 -0.2794)
			(end 0.12065 -0.3048)
			(stroke
				(width 0.1)
				(type default)
			)
			(layer "F.Fab")
		)
		(fp_line
			(start 0.12065 -0.3048)
			(end 0.67945 -0.3048)
			(stroke
				(width 0.1)
				(type default)
			)
			(layer "F.Fab")
		)
		(fp_line
			(start 0.120396 0.3048)
			(end 0.120396 0.2794)
			(stroke
				(width 0.1)
				(type default)
			)
			(layer "F.Fab")
		)
		(fp_line
			(start 0.120396 0.2794)
			(end -0.12065 0.2794)
			(stroke
				(width 0.1)
				(type default)
			)
			(layer "F.Fab")
		)
		(fp_line
			(start -0.12065 0.3048)
			(end -0.67945 0.3048)
			(stroke
				(width 0.1)
				(type default)
			)
			(layer "F.Fab")
		)
		(fp_line
			(start -0.12065 0.2794)
			(end -0.12065 0.3048)
			(stroke
				(width 0.1)
				(type default)
			)
			(layer "F.Fab")
		)
		(fp_line
			(start -0.12065 -0.2794)
			(end 0.12065 -0.2794)
			(stroke
				(width 0.1)
				(type default)
			)
			(layer "F.Fab")
		)
		(fp_line
			(start -0.12065 -0.305054)
			(end -0.12065 -0.2794)
			(stroke
				(width 0.1)
				(type default)
			)
			(layer "F.Fab")
		)
		(fp_line
			(start -0.67945 0.3048)
			(end -0.67945 -0.305054)
			(stroke
				(width 0.1)
				(type default)
			)
			(layer "F.Fab")
		)
		(fp_line
			(start -0.67945 -0.305054)
			(end -0.12065 -0.305054)
			(stroke
				(width 0.1)
				(type default)
			)
			(layer "F.Fab")
		)
		(pad "1" smd circle
			(at -0.40005 0 180)
			(size 0 0)
			(layers "F.Cu" "F.Mask" "F.Paste")
			(net "P3V3_NIC5_CO_GATE")
		)
		(pad "2" smd circle
			(at 0.40005 0 180)
			(size 0 0)
			(layers "F.Cu" "F.Mask" "F.Paste")
			(net "GND")
		)
	)
	(footprint ""
		(layer "F.Cu")
		(at 257.165094 -346.337382 180)
		(property "Reference" "R6651"
			(at 0 0 180)
			(layer "F.SilkS")
			(hide yes)
			(effects
				(font
					(size 1.27 1.27)
				)
			)
		)
		(property "Value" ""
			(at 0 0 180)
			(layer "F.Fab")
			(effects
				(font
					(size 1.27 1.27)
				)
			)
		)
		(duplicate_pad_numbers_are_jumpers no)
		(fp_line
			(start 0.7874 0.4064)
			(end -0.7874 0.4064)
			(stroke
				(width 0.1524)
				(type default)
			)
			(layer "F.SilkS")
		)
		(fp_line
			(start 0.7874 -0.4064)
			(end 0.7874 0.4064)
			(stroke
				(width 0.1524)
				(type default)
			)
			(layer "F.SilkS")
		)
		(fp_line
			(start -0.7874 0.4064)
			(end -0.7874 -0.4064)
			(stroke
				(width 0.1524)
				(type default)
			)
			(layer "F.SilkS")
		)
		(fp_line
			(start -0.7874 -0.4064)
			(end 0.7874 -0.4064)
			(stroke
				(width 0.1524)
				(type default)
			)
			(layer "F.SilkS")
		)
		(fp_line
			(start 0.67945 0.3048)
			(end 0.120396 0.3048)
			(stroke
				(width 0.1)
				(type default)
			)
			(layer "F.Fab")
		)
		(fp_line
			(start 0.67945 -0.3048)
			(end 0.67945 0.3048)
			(stroke
				(width 0.1)
				(type default)
			)
			(layer "F.Fab")
		)
		(fp_line
			(start 0.12065 -0.2794)
			(end 0.12065 -0.3048)
			(stroke
				(width 0.1)
				(type default)
			)
			(layer "F.Fab")
		)
		(fp_line
			(start 0.12065 -0.3048)
			(end 0.67945 -0.3048)
			(stroke
				(width 0.1)
				(type default)
			)
			(layer "F.Fab")
		)
		(fp_line
			(start 0.120396 0.3048)
			(end 0.120396 0.2794)
			(stroke
				(width 0.1)
				(type default)
			)
			(layer "F.Fab")
		)
		(fp_line
			(start 0.120396 0.2794)
			(end -0.12065 0.2794)
			(stroke
				(width 0.1)
				(type default)
			)
			(layer "F.Fab")
		)
		(fp_line
			(start -0.12065 0.3048)
			(end -0.67945 0.3048)
			(stroke
				(width 0.1)
				(type default)
			)
			(layer "F.Fab")
		)
		(fp_line
			(start -0.12065 0.2794)
			(end -0.12065 0.3048)
			(stroke
				(width 0.1)
				(type default)
			)
			(layer "F.Fab")
		)
		(fp_line
			(start -0.12065 -0.2794)
			(end 0.12065 -0.2794)
			(stroke
				(width 0.1)
				(type default)
			)
			(layer "F.Fab")
		)
		(fp_line
			(start -0.12065 -0.305054)
			(end -0.12065 -0.2794)
			(stroke
				(width 0.1)
				(type default)
			)
			(layer "F.Fab")
		)
		(fp_line
			(start -0.67945 0.3048)
			(end -0.67945 -0.305054)
			(stroke
				(width 0.1)
				(type default)
			)
			(layer "F.Fab")
		)
		(fp_line
			(start -0.67945 -0.305054)
			(end -0.12065 -0.305054)
			(stroke
				(width 0.1)
				(type default)
			)
			(layer "F.Fab")
		)
		(pad "1" smd circle
			(at -0.40005 0 180)
			(size 0 0)
			(layers "F.Cu" "F.Mask" "F.Paste")
			(net "A_HSC_HIGH")
		)
		(pad "2" smd circle
			(at 0.40005 0 180)
			(size 0 0)
			(layers "F.Cu" "F.Mask" "F.Paste")
			(net "GND")
		)
	)
	(footprint ""
		(layer "F.Cu")
		(at 125.419612 -162.003994 90)
		(property "Reference" "PR6901"
			(at 0 0 90)
			(layer "F.SilkS")
			(hide yes)
			(effects
				(font
					(size 1.27 1.27)
				)
			)
		)
		(property "Value" ""
			(at 0 0 90)
			(layer "F.Fab")
			(effects
				(font
					(size 1.27 1.27)
				)
			)
		)
		(duplicate_pad_numbers_are_jumpers no)
		(fp_line
			(start 0.7874 -0.4064)
			(end 0.7874 0.4064)
			(stroke
				(width 0.1524)
				(type default)
			)
			(layer "F.SilkS")
		)
		(fp_line
			(start -0.7874 -0.4064)
			(end 0.7874 -0.4064)
			(stroke
				(width 0.1524)
				(type default)
			)
			(layer "F.SilkS")
		)
		(fp_line
			(start 0.7874 0.4064)
			(end -0.7874 0.4064)
			(stroke
				(width 0.1524)
				(type default)
			)
			(layer "F.SilkS")
		)
		(fp_line
			(start -0.7874 0.4064)
			(end -0.7874 -0.4064)
			(stroke
				(width 0.1524)
				(type default)
			)
			(layer "F.SilkS")
		)
		(fp_line
			(start -0.12065 -0.305054)
			(end -0.12065 -0.2794)
			(stroke
				(width 0.1)
				(type default)
			)
			(layer "F.Fab")
		)
		(fp_line
			(start -0.67945 -0.305054)
			(end -0.12065 -0.305054)
			(stroke
				(width 0.1)
				(type default)
			)
			(layer "F.Fab")
		)
		(fp_line
			(start 0.67945 -0.3048)
			(end 0.67945 0.3048)
			(stroke
				(width 0.1)
				(type default)
			)
			(layer "F.Fab")
		)
		(fp_line
			(start 0.12065 -0.3048)
			(end 0.67945 -0.3048)
			(stroke
				(width 0.1)
				(type default)
			)
			(layer "F.Fab")
		)
		(fp_line
			(start 0.12065 -0.2794)
			(end 0.12065 -0.3048)
			(stroke
				(width 0.1)
				(type default)
			)
			(layer "F.Fab")
		)
		(fp_line
			(start -0.12065 -0.2794)
			(end 0.12065 -0.2794)
			(stroke
				(width 0.1)
				(type default)
			)
			(layer "F.Fab")
		)
		(fp_line
			(start 0.120396 0.2794)
			(end -0.12065 0.2794)
			(stroke
				(width 0.1)
				(type default)
			)
			(layer "F.Fab")
		)
		(fp_line
			(start -0.12065 0.2794)
			(end -0.12065 0.3048)
			(stroke
				(width 0.1)
				(type default)
			)
			(layer "F.Fab")
		)
		(fp_line
			(start 0.67945 0.3048)
			(end 0.120396 0.3048)
			(stroke
				(width 0.1)
				(type default)
			)
			(layer "F.Fab")
		)
		(fp_line
			(start 0.120396 0.3048)
			(end 0.120396 0.2794)
			(stroke
				(width 0.1)
				(type default)
			)
			(layer "F.Fab")
		)
		(fp_line
			(start -0.12065 0.3048)
			(end -0.67945 0.3048)
			(stroke
				(width 0.1)
				(type default)
			)
			(layer "F.Fab")
		)
		(fp_line
			(start -0.67945 0.3048)
			(end -0.67945 -0.305054)
			(stroke
				(width 0.1)
				(type default)
			)
			(layer "F.Fab")
		)
		(pad "1" smd circle
			(at -0.40005 0 90)
			(size 0 0)
			(layers "F.Cu" "F.Mask" "F.Paste")
			(net "P12V_NIC2_CO_IMON_VR")
		)
		(pad "2" smd circle
			(at 0.40005 0 90)
			(size 0 0)
			(layers "F.Cu" "F.Mask" "F.Paste")
			(net "GND")
		)
	)
	(footprint ""
		(layer "F.Cu")
		(at 290.318952 -59.574684 90)
		(property "Reference" "PC565"
			(at 0 0 90)
			(layer "F.SilkS")
			(hide yes)
			(effects
				(font
					(size 1.27 1.27)
				)
			)
		)
		(property "Value" ""
			(at 0 0 90)
			(layer "F.Fab")
			(effects
				(font
					(size 1.27 1.27)
				)
			)
		)
		(duplicate_pad_numbers_are_jumpers no)
		(fp_line
			(start 0.7874 -0.4064)
			(end 0.7874 0.4064)
			(stroke
				(width 0.1524)
				(type default)
			)
			(layer "F.SilkS")
		)
		(fp_line
			(start -0.7874 -0.4064)
			(end 0.7874 -0.4064)
			(stroke
				(width 0.1524)
				(type default)
			)
			(layer "F.SilkS")
		)
		(fp_line
			(start 0.7874 0.4064)
			(end -0.7874 0.4064)
			(stroke
				(width 0.1524)
				(type default)
			)
			(layer "F.SilkS")
		)
		(fp_line
			(start -0.7874 0.4064)
			(end -0.7874 -0.4064)
			(stroke
				(width 0.1524)
				(type default)
			)
			(layer "F.SilkS")
		)
		(fp_line
			(start -0.12065 -0.305054)
			(end -0.12065 -0.2794)
			(stroke
				(width 0.1)
				(type default)
			)
			(layer "F.Fab")
		)
		(fp_line
			(start -0.67945 -0.305054)
			(end -0.12065 -0.305054)
			(stroke
				(width 0.1)
				(type default)
			)
			(layer "F.Fab")
		)
		(fp_line
			(start 0.67945 -0.3048)
			(end 0.67945 0.3048)
			(stroke
				(width 0.1)
				(type default)
			)
			(layer "F.Fab")
		)
		(fp_line
			(start 0.12065 -0.3048)
			(end 0.67945 -0.3048)
			(stroke
				(width 0.1)
				(type default)
			)
			(layer "F.Fab")
		)
		(fp_line
			(start 0.12065 -0.2794)
			(end 0.12065 -0.3048)
			(stroke
				(width 0.1)
				(type default)
			)
			(layer "F.Fab")
		)
		(fp_line
			(start -0.12065 -0.2794)
			(end 0.12065 -0.2794)
			(stroke
				(width 0.1)
				(type default)
			)
			(layer "F.Fab")
		)
		(fp_line
			(start 0.120396 0.2794)
			(end -0.12065 0.2794)
			(stroke
				(width 0.1)
				(type default)
			)
			(layer "F.Fab")
		)
		(fp_line
			(start -0.12065 0.2794)
			(end -0.12065 0.3048)
			(stroke
				(width 0.1)
				(type default)
			)
			(layer "F.Fab")
		)
		(fp_line
			(start 0.67945 0.3048)
			(end 0.120396 0.3048)
			(stroke
				(width 0.1)
				(type default)
			)
			(layer "F.Fab")
		)
		(fp_line
			(start 0.120396 0.3048)
			(end 0.120396 0.2794)
			(stroke
				(width 0.1)
				(type default)
			)
			(layer "F.Fab")
		)
		(fp_line
			(start -0.12065 0.3048)
			(end -0.67945 0.3048)
			(stroke
				(width 0.1)
				(type default)
			)
			(layer "F.Fab")
		)
		(fp_line
			(start -0.67945 0.3048)
			(end -0.67945 -0.305054)
			(stroke
				(width 0.1)
				(type default)
			)
			(layer "F.Fab")
		)
		(pad "1" smd circle
			(at -0.40005 0 90)
			(size 0 0)
			(layers "F.Cu" "F.Mask" "F.Paste")
			(net "P5V_AUX")
		)
		(pad "2" smd circle
			(at 0.40005 0 90)
			(size 0 0)
			(layers "F.Cu" "F.Mask" "F.Paste")
			(net "GND")
		)
	)
	(footprint ""
		(layer "F.Cu")
		(at 327.279 -230.886 90)
		(property "Reference" "U336"
			(at -1.6256 2.21107 90)
			(unlocked yes)
			(layer "F.SilkS")
			(effects
				(font
					(size 0.7874 0.5842)
					(thickness 0.1524)
				)
				(justify left)
			)
		)
		(property "Value" ""
			(at 0 0 90)
			(layer "F.Fab")
			(effects
				(font
					(size 1.27 1.27)
				)
			)
		)
		(duplicate_pad_numbers_are_jumpers no)
		(fp_line
			(start 1.684274 -1.074928)
			(end 1.684274 1.074928)
			(stroke
				(width 0.1524)
				(type default)
			)
			(layer "F.SilkS")
		)
		(fp_line
			(start 0.381 -1.074928)
			(end 1.684274 -1.074928)
			(stroke
				(width 0.1524)
				(type default)
			)
			(layer "F.SilkS")
		)
		(fp_line
			(start -0.381 -1.074928)
			(end 0 -0.625094)
			(stroke
				(width 0.1524)
				(type default)
			)
			(layer "F.SilkS")
		)
		(fp_line
			(start -1.684274 -1.074928)
			(end -0.381 -1.074928)
			(stroke
				(width 0.1524)
				(type default)
			)
			(layer "F.SilkS")
		)
		(fp_line
			(start 0 -0.625094)
			(end 0.381 -1.074928)
			(stroke
				(width 0.1524)
				(type default)
			)
			(layer "F.SilkS")
		)
		(fp_line
			(start 1.684274 1.074928)
			(end -1.684274 1.074928)
			(stroke
				(width 0.1524)
				(type default)
			)
			(layer "F.SilkS")
		)
		(fp_line
			(start -1.684274 1.074928)
			(end -1.684274 -1.074928)
			(stroke
				(width 0.1524)
				(type default)
			)
			(layer "F.SilkS")
		)
		(fp_poly
			(pts
				(xy -2.01803 -1.725422) (xy -2.377186 -1.366012) (xy -1.65862 -1.006856)
			)
			(stroke
				(width 0)
				(type default)
			)
			(fill yes)
			(layer "F.SilkS")
		)
		(fp_line
			(start 0.700024 -1.074928)
			(end -0.700024 -1.074928)
			(stroke
				(width 0.1)
				(type default)
			)
			(layer "F.Fab")
		)
		(fp_line
			(start -0.700024 -1.074928)
			(end -0.700024 1.074928)
			(stroke
				(width 0.1)
				(type default)
			)
			(layer "F.Fab")
		)
		(fp_line
			(start 0.700024 1.074928)
			(end 0.700024 -1.074928)
			(stroke
				(width 0.1)
				(type default)
			)
			(layer "F.Fab")
		)
		(fp_line
			(start -0.700024 1.074928)
			(end 0.700024 1.074928)
			(stroke
				(width 0.1)
				(type default)
			)
			(layer "F.Fab")
		)
		(fp_poly
			(pts
				(xy -2.637282 -0.903986) (xy -2.637282 -0.395986) (xy -1.875282 -0.649986)
			)
			(stroke
				(width 0)
				(type default)
			)
			(fill yes)
			(layer "F.Fab")
		)
		(pad "1" smd rect
			(at -1.100074 -0.649986)
			(size 0.4064 0.9144)
			(layers "F.Cu" "F.Mask" "F.Paste")
			(net "Net_8993")
		)
		(pad "2" smd rect
			(at -1.100074 0)
			(size 0.4064 0.9144)
			(layers "F.Cu" "F.Mask" "F.Paste")
			(net "RST_PEX_SYS_R_N")
		)
		(pad "3" smd rect
			(at -1.100074 0.649986)
			(size 0.4064 0.9144)
			(layers "F.Cu" "F.Mask" "F.Paste")
			(net "GND")
		)
		(pad "4" smd rect
			(at 1.100074 0.649986)
			(size 0.4064 0.9144)
			(layers "F.Cu" "F.Mask" "F.Paste")
			(net "RST_PEX_SYS_BUF_N")
		)
		(pad "5" smd rect
			(at 1.100074 -0.649986)
			(size 0.4064 0.9144)
			(layers "F.Cu" "F.Mask" "F.Paste")
			(net "P3V3_AUX")
		)
	)
	(footprint ""
		(layer "F.Cu")
		(at 217.235786 -212.206586)
		(property "Reference" "R5718"
			(at 0 0 0)
			(layer "F.SilkS")
			(hide yes)
			(effects
				(font
					(size 1.27 1.27)
				)
			)
		)
		(property "Value" ""
			(at 0 0 0)
			(layer "F.Fab")
			(effects
				(font
					(size 1.27 1.27)
				)
			)
		)
		(duplicate_pad_numbers_are_jumpers no)
		(fp_line
			(start -0.7874 -0.4064)
			(end 0.7874 -0.4064)
			(stroke
				(width 0.1524)
				(type default)
			)
			(layer "F.SilkS")
		)
		(fp_line
			(start -0.7874 0.4064)
			(end -0.7874 -0.4064)
			(stroke
				(width 0.1524)
				(type default)
			)
			(layer "F.SilkS")
		)
		(fp_line
			(start 0.7874 -0.4064)
			(end 0.7874 0.4064)
			(stroke
				(width 0.1524)
				(type default)
			)
			(layer "F.SilkS")
		)
		(fp_line
			(start 0.7874 0.4064)
			(end -0.7874 0.4064)
			(stroke
				(width 0.1524)
				(type default)
			)
			(layer "F.SilkS")
		)
		(fp_line
			(start -0.67945 -0.305054)
			(end -0.12065 -0.305054)
			(stroke
				(width 0.1)
				(type default)
			)
			(layer "F.Fab")
		)
		(fp_line
			(start -0.67945 0.3048)
			(end -0.67945 -0.305054)
			(stroke
				(width 0.1)
				(type default)
			)
			(layer "F.Fab")
		)
		(fp_line
			(start -0.12065 -0.305054)
			(end -0.12065 -0.2794)
			(stroke
				(width 0.1)
				(type default)
			)
			(layer "F.Fab")
		)
		(fp_line
			(start -0.12065 -0.2794)
			(end 0.12065 -0.2794)
			(stroke
				(width 0.1)
				(type default)
			)
			(layer "F.Fab")
		)
		(fp_line
			(start -0.12065 0.2794)
			(end -0.12065 0.3048)
			(stroke
				(width 0.1)
				(type default)
			)
			(layer "F.Fab")
		)
		(fp_line
			(start -0.12065 0.3048)
			(end -0.67945 0.3048)
			(stroke
				(width 0.1)
				(type default)
			)
			(layer "F.Fab")
		)
		(fp_line
			(start 0.120396 0.2794)
			(end -0.12065 0.2794)
			(stroke
				(width 0.1)
				(type default)
			)
			(layer "F.Fab")
		)
		(fp_line
			(start 0.120396 0.3048)
			(end 0.120396 0.2794)
			(stroke
				(width 0.1)
				(type default)
			)
			(layer "F.Fab")
		)
		(fp_line
			(start 0.12065 -0.3048)
			(end 0.67945 -0.3048)
			(stroke
				(width 0.1)
				(type default)
			)
			(layer "F.Fab")
		)
		(fp_line
			(start 0.12065 -0.2794)
			(end 0.12065 -0.3048)
			(stroke
				(width 0.1)
				(type default)
			)
			(layer "F.Fab")
		)
		(fp_line
			(start 0.67945 -0.3048)
			(end 0.67945 0.3048)
			(stroke
				(width 0.1)
				(type default)
			)
			(layer "F.Fab")
		)
		(fp_line
			(start 0.67945 0.3048)
			(end 0.120396 0.3048)
			(stroke
				(width 0.1)
				(type default)
			)
			(layer "F.Fab")
		)
		(pad "1" smd circle
			(at -0.40005 0)
			(size 0 0)
			(layers "F.Cu" "F.Mask" "F.Paste")
			(net "RST_BIC_I2C9_SSD_MUX0_R_N")
		)
		(pad "2" smd circle
			(at 0.40005 0)
			(size 0 0)
			(layers "F.Cu" "F.Mask" "F.Paste")
			(net "RST_BIC_I2C9_SSD_MUX0_N")
		)
	)
	(footprint ""
		(layer "F.Cu")
		(at 284.443678 -44.87291)
		(property "Reference" "R606"
			(at 0 0 0)
			(layer "F.SilkS")
			(hide yes)
			(effects
				(font
					(size 1.27 1.27)
				)
			)
		)
		(property "Value" ""
			(at 0 0 0)
			(layer "F.Fab")
			(effects
				(font
					(size 1.27 1.27)
				)
			)
		)
		(duplicate_pad_numbers_are_jumpers no)
		(fp_line
			(start -0.7874 -0.4064)
			(end 0.7874 -0.4064)
			(stroke
				(width 0.1524)
				(type default)
			)
			(layer "F.SilkS")
		)
		(fp_line
			(start -0.7874 0.4064)
			(end -0.7874 -0.4064)
			(stroke
				(width 0.1524)
				(type default)
			)
			(layer "F.SilkS")
		)
		(fp_line
			(start 0.7874 -0.4064)
			(end 0.7874 0.4064)
			(stroke
				(width 0.1524)
				(type default)
			)
			(layer "F.SilkS")
		)
		(fp_line
			(start 0.7874 0.4064)
			(end -0.7874 0.4064)
			(stroke
				(width 0.1524)
				(type default)
			)
			(layer "F.SilkS")
		)
		(fp_line
			(start -0.67945 -0.305054)
			(end -0.12065 -0.305054)
			(stroke
				(width 0.1)
				(type default)
			)
			(layer "F.Fab")
		)
		(fp_line
			(start -0.67945 0.3048)
			(end -0.67945 -0.305054)
			(stroke
				(width 0.1)
				(type default)
			)
			(layer "F.Fab")
		)
		(fp_line
			(start -0.12065 -0.305054)
			(end -0.12065 -0.2794)
			(stroke
				(width 0.1)
				(type default)
			)
			(layer "F.Fab")
		)
		(fp_line
			(start -0.12065 -0.2794)
			(end 0.12065 -0.2794)
			(stroke
				(width 0.1)
				(type default)
			)
			(layer "F.Fab")
		)
		(fp_line
			(start -0.12065 0.2794)
			(end -0.12065 0.3048)
			(stroke
				(width 0.1)
				(type default)
			)
			(layer "F.Fab")
		)
		(fp_line
			(start -0.12065 0.3048)
			(end -0.67945 0.3048)
			(stroke
				(width 0.1)
				(type default)
			)
			(layer "F.Fab")
		)
		(fp_line
			(start 0.120396 0.2794)
			(end -0.12065 0.2794)
			(stroke
				(width 0.1)
				(type default)
			)
			(layer "F.Fab")
		)
		(fp_line
			(start 0.120396 0.3048)
			(end 0.120396 0.2794)
			(stroke
				(width 0.1)
				(type default)
			)
			(layer "F.Fab")
		)
		(fp_line
			(start 0.12065 -0.3048)
			(end 0.67945 -0.3048)
			(stroke
				(width 0.1)
				(type default)
			)
			(layer "F.Fab")
		)
		(fp_line
			(start 0.12065 -0.2794)
			(end 0.12065 -0.3048)
			(stroke
				(width 0.1)
				(type default)
			)
			(layer "F.Fab")
		)
		(fp_line
			(start 0.67945 -0.3048)
			(end 0.67945 0.3048)
			(stroke
				(width 0.1)
				(type default)
			)
			(layer "F.Fab")
		)
		(fp_line
			(start 0.67945 0.3048)
			(end 0.120396 0.3048)
			(stroke
				(width 0.1)
				(type default)
			)
			(layer "F.Fab")
		)
		(pad "1" smd circle
			(at -0.40005 0)
			(size 0 0)
			(layers "F.Cu" "F.Mask" "F.Paste")
			(net "SSD9_ADC_A0")
		)
		(pad "2" smd circle
			(at 0.40005 0)
			(size 0 0)
			(layers "F.Cu" "F.Mask" "F.Paste")
			(net "P3V3_AUX")
		)
	)
	(footprint ""
		(layer "F.Cu")
		(at 19.526758 -55.418228 90)
		(property "Reference" "PC356"
			(at 0 0 90)
			(layer "F.SilkS")
			(hide yes)
			(effects
				(font
					(size 1.27 1.27)
				)
			)
		)
		(property "Value" ""
			(at 0 0 90)
			(layer "F.Fab")
			(effects
				(font
					(size 1.27 1.27)
				)
			)
		)
		(duplicate_pad_numbers_are_jumpers no)
		(fp_line
			(start 0.7874 -0.4064)
			(end 0.7874 0.4064)
			(stroke
				(width 0.1524)
				(type default)
			)
			(layer "F.SilkS")
		)
		(fp_line
			(start -0.7874 -0.4064)
			(end 0.7874 -0.4064)
			(stroke
				(width 0.1524)
				(type default)
			)
			(layer "F.SilkS")
		)
		(fp_line
			(start 0.7874 0.4064)
			(end -0.7874 0.4064)
			(stroke
				(width 0.1524)
				(type default)
			)
			(layer "F.SilkS")
		)
		(fp_line
			(start -0.7874 0.4064)
			(end -0.7874 -0.4064)
			(stroke
				(width 0.1524)
				(type default)
			)
			(layer "F.SilkS")
		)
		(fp_line
			(start -0.12065 -0.305054)
			(end -0.12065 -0.2794)
			(stroke
				(width 0.1)
				(type default)
			)
			(layer "F.Fab")
		)
		(fp_line
			(start -0.67945 -0.305054)
			(end -0.12065 -0.305054)
			(stroke
				(width 0.1)
				(type default)
			)
			(layer "F.Fab")
		)
		(fp_line
			(start 0.67945 -0.3048)
			(end 0.67945 0.3048)
			(stroke
				(width 0.1)
				(type default)
			)
			(layer "F.Fab")
		)
		(fp_line
			(start 0.12065 -0.3048)
			(end 0.67945 -0.3048)
			(stroke
				(width 0.1)
				(type default)
			)
			(layer "F.Fab")
		)
		(fp_line
			(start 0.12065 -0.2794)
			(end 0.12065 -0.3048)
			(stroke
				(width 0.1)
				(type default)
			)
			(layer "F.Fab")
		)
		(fp_line
			(start -0.12065 -0.2794)
			(end 0.12065 -0.2794)
			(stroke
				(width 0.1)
				(type default)
			)
			(layer "F.Fab")
		)
		(fp_line
			(start 0.120396 0.2794)
			(end -0.12065 0.2794)
			(stroke
				(width 0.1)
				(type default)
			)
			(layer "F.Fab")
		)
		(fp_line
			(start -0.12065 0.2794)
			(end -0.12065 0.3048)
			(stroke
				(width 0.1)
				(type default)
			)
			(layer "F.Fab")
		)
		(fp_line
			(start 0.67945 0.3048)
			(end 0.120396 0.3048)
			(stroke
				(width 0.1)
				(type default)
			)
			(layer "F.Fab")
		)
		(fp_line
			(start 0.120396 0.3048)
			(end 0.120396 0.2794)
			(stroke
				(width 0.1)
				(type default)
			)
			(layer "F.Fab")
		)
		(fp_line
			(start -0.12065 0.3048)
			(end -0.67945 0.3048)
			(stroke
				(width 0.1)
				(type default)
			)
			(layer "F.Fab")
		)
		(fp_line
			(start -0.67945 0.3048)
			(end -0.67945 -0.305054)
			(stroke
				(width 0.1)
				(type default)
			)
			(layer "F.Fab")
		)
		(pad "1" smd circle
			(at -0.40005 0 90)
			(size 0 0)
			(layers "F.Cu" "F.Mask" "F.Paste")
			(net "P12V_SSD0_R")
		)
		(pad "2" smd circle
			(at 0.40005 0 90)
			(size 0 0)
			(layers "F.Cu" "F.Mask" "F.Paste")
			(net "GND")
		)
	)
	(footprint ""
		(layer "F.Cu")
		(at 430.961546 -120.476772 180)
		(property "Reference" "C663"
			(at 0 0 180)
			(layer "F.SilkS")
			(hide yes)
			(effects
				(font
					(size 1.27 1.27)
				)
			)
		)
		(property "Value" ""
			(at 0 0 180)
			(layer "F.Fab")
			(effects
				(font
					(size 1.27 1.27)
				)
			)
		)
		(duplicate_pad_numbers_are_jumpers no)
		(fp_line
			(start 0.299974 0.150114)
			(end -0.299974 0.150114)
			(stroke
				(width 0.1)
				(type default)
			)
			(layer "F.Fab")
		)
		(fp_line
			(start 0.299974 -0.150114)
			(end 0.299974 0.150114)
			(stroke
				(width 0.1)
				(type default)
			)
			(layer "F.Fab")
		)
		(fp_line
			(start -0.299974 0.150114)
			(end -0.299974 -0.150114)
			(stroke
				(width 0.1)
				(type default)
			)
			(layer "F.Fab")
		)
		(fp_line
			(start -0.299974 -0.150114)
			(end 0.299974 -0.150114)
			(stroke
				(width 0.1)
				(type default)
			)
			(layer "F.Fab")
		)
		(pad "1" smd rect
			(at -0.2667 0 180)
			(size 0.3048 0.381)
			(layers "F.Cu" "F.Mask" "F.Paste")
			(net "P5E_PEX3_STN0_TX_DN<1>")
		)
		(pad "2" smd rect
			(at 0.2667 0 180)
			(size 0.3048 0.381)
			(layers "F.Cu" "F.Mask" "F.Paste")
			(net "P5E_PEX3_STN0_TX_C_DN<1>")
		)
	)
	(footprint ""
		(layer "F.Cu")
		(at 263.335008 -369.930426 90)
		(property "Reference" "PQ6605"
			(at -8.22325 -1.874774 0)
			(unlocked yes)
			(layer "F.SilkS")
			(effects
				(font
					(size 0.7874 0.5842)
					(thickness 0.1524)
				)
				(justify left)
			)
		)
		(property "Value" ""
			(at 0 0 90)
			(layer "F.Fab")
			(effects
				(font
					(size 1.27 1.27)
				)
			)
		)
		(duplicate_pad_numbers_are_jumpers no)
		(fp_line
			(start 2.350008 -2.649982)
			(end 2.350008 -2.4892)
			(stroke
				(width 0.1524)
				(type default)
			)
			(layer "F.SilkS")
		)
		(fp_line
			(start -2.350008 -2.649982)
			(end 2.350008 -2.649982)
			(stroke
				(width 0.1524)
				(type default)
			)
			(layer "F.SilkS")
		)
		(fp_line
			(start -2.350008 -2.4384)
			(end -2.350008 -2.649982)
			(stroke
				(width 0.1524)
				(type default)
			)
			(layer "F.SilkS")
		)
		(fp_line
			(start 2.350008 2.4892)
			(end 2.350008 2.649982)
			(stroke
				(width 0.1524)
				(type default)
			)
			(layer "F.SilkS")
		)
		(fp_line
			(start 2.350008 2.649982)
			(end -2.350008 2.649982)
			(stroke
				(width 0.1524)
				(type default)
			)
			(layer "F.SilkS")
		)
		(fp_line
			(start -2.350008 2.649982)
			(end -2.350008 2.413)
			(stroke
				(width 0.1524)
				(type default)
			)
			(layer "F.SilkS")
		)
		(fp_poly
			(pts
				(xy -3.717544 -1.905) (xy -4.758944 -2.3241) (xy -4.758944 -1.524)
			)
			(stroke
				(width 0)
				(type default)
			)
			(fill yes)
			(layer "F.SilkS")
		)
		(fp_line
			(start 2.350008 -2.649982)
			(end 2.350008 2.649982)
			(stroke
				(width 0.1)
				(type default)
			)
			(layer "F.Fab")
		)
		(fp_line
			(start -2.350008 -2.649982)
			(end 2.350008 -2.649982)
			(stroke
				(width 0.1)
				(type default)
			)
			(layer "F.Fab")
		)
		(fp_line
			(start 2.350008 2.649982)
			(end -2.350008 2.649982)
			(stroke
				(width 0.1)
				(type default)
			)
			(layer "F.Fab")
		)
		(fp_line
			(start -2.350008 2.649982)
			(end -2.350008 -2.649982)
			(stroke
				(width 0.1)
				(type default)
			)
			(layer "F.Fab")
		)
		(fp_poly
			(pts
				(xy -3.717544 -1.905) (xy -4.758944 -2.3241) (xy -4.758944 -1.524)
			)
			(stroke
				(width 0)
				(type default)
			)
			(fill yes)
			(layer "F.Fab")
		)
		(pad "1" smd rect
			(at -2.999994 -1.905)
			(size 0.7112 1.1684)
			(layers "F.Cu" "F.Mask" "F.Paste")
			(net "P12V_AUX")
		)
		(pad "2" smd rect
			(at -2.999994 -0.635)
			(size 0.7112 1.1684)
			(layers "F.Cu" "F.Mask" "F.Paste")
			(net "P12V_AUX")
		)
		(pad "3" smd rect
			(at -2.999994 0.635)
			(size 0.7112 1.1684)
			(layers "F.Cu" "F.Mask" "F.Paste")
			(net "P12V_AUX")
		)
		(pad "4" smd rect
			(at -2.999994 1.905)
			(size 0.7112 1.1684)
			(layers "F.Cu" "F.Mask" "F.Paste")
			(net "HS_GATE2_R_4")
		)
		(pad "5" smd circle
			(at 0.925068 0)
			(size 0 0)
			(layers "F.Cu" "F.Mask" "F.Paste")
			(net "P12V_STBY_R2")
		)
		(zone
			(layer "F.Cu")
			(hatch none 0.5)
			(connect_pads
				(clearance 0)
			)
			(min_thickness 0.25)
			(keepout
				(tracks not_allowed)
				(vias allowed)
				(pads allowed)
				(copperpour not_allowed)
				(footprints allowed)
			)
			(placement
				(enabled no)
				(sheetname "")
			)
			(fill
				(thermal_gap 0.5)
				(thermal_bridge_width 0.5)
				(island_removal_mode 0)
			)
			(polygon
				(pts
					(xy 261.176008 -368.482626) (xy 265.494008 -368.482626) (xy 265.976608 -368.482626) (xy 265.976608 -367.580926)
					(xy 260.693408 -367.580926) (xy 260.693408 -368.482626)
				)
			)
		)
	)
	(footprint ""
		(layer "F.Cu")
		(at 104.517698 -380.923546 -90)
		(property "Reference" "R5449"
			(at 0 0 270)
			(layer "F.SilkS")
			(hide yes)
			(effects
				(font
					(size 1.27 1.27)
				)
			)
		)
		(property "Value" ""
			(at 0 0 270)
			(layer "F.Fab")
			(effects
				(font
					(size 1.27 1.27)
				)
			)
		)
		(duplicate_pad_numbers_are_jumpers no)
		(fp_line
			(start 0.7874 0.4064)
			(end -0.7874 0.4064)
			(stroke
				(width 0.1524)
				(type default)
			)
			(layer "F.SilkS")
		)
		(fp_line
			(start -0.7874 -0.4064)
			(end 0.047244 -0.4064)
			(stroke
				(width 0.1524)
				(type default)
			)
			(layer "F.SilkS")
		)
		(fp_line
			(start 0.7874 -0.4064)
			(end 0.7874 0.4064)
			(stroke
				(width 0.1524)
				(type default)
			)
			(layer "F.SilkS")
		)
		(fp_line
			(start -0.67945 0.3048)
			(end -0.67945 -0.305054)
			(stroke
				(width 0.1)
				(type default)
			)
			(layer "F.Fab")
		)
		(fp_line
			(start -0.12065 0.3048)
			(end -0.67945 0.3048)
			(stroke
				(width 0.1)
				(type default)
			)
			(layer "F.Fab")
		)
		(fp_line
			(start 0.120396 0.3048)
			(end 0.120396 0.2794)
			(stroke
				(width 0.1)
				(type default)
			)
			(layer "F.Fab")
		)
		(fp_line
			(start 0.67945 0.3048)
			(end 0.120396 0.3048)
			(stroke
				(width 0.1)
				(type default)
			)
			(layer "F.Fab")
		)
		(fp_line
			(start -0.12065 0.2794)
			(end -0.12065 0.3048)
			(stroke
				(width 0.1)
				(type default)
			)
			(layer "F.Fab")
		)
		(fp_line
			(start 0.120396 0.2794)
			(end -0.12065 0.2794)
			(stroke
				(width 0.1)
				(type default)
			)
			(layer "F.Fab")
		)
		(fp_line
			(start -0.12065 -0.2794)
			(end 0.12065 -0.2794)
			(stroke
				(width 0.1)
				(type default)
			)
			(layer "F.Fab")
		)
		(fp_line
			(start 0.12065 -0.2794)
			(end 0.12065 -0.3048)
			(stroke
				(width 0.1)
				(type default)
			)
			(layer "F.Fab")
		)
		(fp_line
			(start 0.12065 -0.3048)
			(end 0.67945 -0.3048)
			(stroke
				(width 0.1)
				(type default)
			)
			(layer "F.Fab")
		)
		(fp_line
			(start 0.67945 -0.3048)
			(end 0.67945 0.3048)
			(stroke
				(width 0.1)
				(type default)
			)
			(layer "F.Fab")
		)
		(fp_line
			(start -0.67945 -0.305054)
			(end -0.12065 -0.305054)
			(stroke
				(width 0.1)
				(type default)
			)
			(layer "F.Fab")
		)
		(fp_line
			(start -0.12065 -0.305054)
			(end -0.12065 -0.2794)
			(stroke
				(width 0.1)
				(type default)
			)
			(layer "F.Fab")
		)
		(pad "1" smd rect
			(at -0.40005 0 90)
			(size 0.4572 0.508)
			(layers "F.Cu" "F.Mask" "F.Paste")
			(net "USB2_BIC_R_DN")
		)
		(pad "2" smd rect
			(at 0.40005 0 90)
			(size 0.4572 0.508)
			(layers "F.Cu" "F.Mask" "F.Paste")
			(net "USB2_BIC_DN")
		)
	)
	(footprint ""
		(layer "F.Cu")
		(at 344.67038 -280.44902 -90)
		(property "Reference" "PC162"
			(at 0 0 270)
			(layer "F.SilkS")
			(hide yes)
			(effects
				(font
					(size 1.27 1.27)
				)
			)
		)
		(property "Value" ""
			(at 0 0 270)
			(layer "F.Fab")
			(effects
				(font
					(size 1.27 1.27)
				)
			)
		)
		(duplicate_pad_numbers_are_jumpers no)
		(fp_line
			(start -0.7874 0.4064)
			(end -0.7874 -0.4064)
			(stroke
				(width 0.1524)
				(type default)
			)
			(layer "F.SilkS")
		)
		(fp_line
			(start 0.7874 0.4064)
			(end -0.7874 0.4064)
			(stroke
				(width 0.1524)
				(type default)
			)
			(layer "F.SilkS")
		)
		(fp_line
			(start -0.7874 -0.4064)
			(end 0.7874 -0.4064)
			(stroke
				(width 0.1524)
				(type default)
			)
			(layer "F.SilkS")
		)
		(fp_line
			(start 0.7874 -0.4064)
			(end 0.7874 0.4064)
			(stroke
				(width 0.1524)
				(type default)
			)
			(layer "F.SilkS")
		)
		(fp_line
			(start -0.67945 0.3048)
			(end -0.67945 -0.305054)
			(stroke
				(width 0.1)
				(type default)
			)
			(layer "F.Fab")
		)
		(fp_line
			(start -0.12065 0.3048)
			(end -0.67945 0.3048)
			(stroke
				(width 0.1)
				(type default)
			)
			(layer "F.Fab")
		)
		(fp_line
			(start 0.120396 0.3048)
			(end 0.120396 0.2794)
			(stroke
				(width 0.1)
				(type default)
			)
			(layer "F.Fab")
		)
		(fp_line
			(start 0.67945 0.3048)
			(end 0.120396 0.3048)
			(stroke
				(width 0.1)
				(type default)
			)
			(layer "F.Fab")
		)
		(fp_line
			(start -0.12065 0.2794)
			(end -0.12065 0.3048)
			(stroke
				(width 0.1)
				(type default)
			)
			(layer "F.Fab")
		)
		(fp_line
			(start 0.120396 0.2794)
			(end -0.12065 0.2794)
			(stroke
				(width 0.1)
				(type default)
			)
			(layer "F.Fab")
		)
		(fp_line
			(start -0.12065 -0.2794)
			(end 0.12065 -0.2794)
			(stroke
				(width 0.1)
				(type default)
			)
			(layer "F.Fab")
		)
		(fp_line
			(start 0.12065 -0.2794)
			(end 0.12065 -0.3048)
			(stroke
				(width 0.1)
				(type default)
			)
			(layer "F.Fab")
		)
		(fp_line
			(start 0.12065 -0.3048)
			(end 0.67945 -0.3048)
			(stroke
				(width 0.1)
				(type default)
			)
			(layer "F.Fab")
		)
		(fp_line
			(start 0.67945 -0.3048)
			(end 0.67945 0.3048)
			(stroke
				(width 0.1)
				(type default)
			)
			(layer "F.Fab")
		)
		(fp_line
			(start -0.67945 -0.305054)
			(end -0.12065 -0.305054)
			(stroke
				(width 0.1)
				(type default)
			)
			(layer "F.Fab")
		)
		(fp_line
			(start -0.12065 -0.305054)
			(end -0.12065 -0.2794)
			(stroke
				(width 0.1)
				(type default)
			)
			(layer "F.Fab")
		)
		(pad "1" smd circle
			(at -0.40005 0 270)
			(size 0 0)
			(layers "F.Cu" "F.Mask" "F.Paste")
			(net "SW_P0V8_PEX2_PHASE2")
		)
		(pad "2" smd circle
			(at 0.40005 0 270)
			(size 0 0)
			(layers "F.Cu" "F.Mask" "F.Paste")
			(net "SW_P0V8_PEX2_BOOT2_R")
		)
	)
	(footprint ""
		(layer "F.Cu")
		(at 336.80908 -109.432598 -90)
		(property "Reference" "PC807"
			(at 0 0 270)
			(layer "F.SilkS")
			(hide yes)
			(effects
				(font
					(size 1.27 1.27)
				)
			)
		)
		(property "Value" ""
			(at 0 0 270)
			(layer "F.Fab")
			(effects
				(font
					(size 1.27 1.27)
				)
			)
		)
		(duplicate_pad_numbers_are_jumpers no)
		(fp_line
			(start -0.7874 0.4064)
			(end -0.7874 -0.4064)
			(stroke
				(width 0.1524)
				(type default)
			)
			(layer "F.SilkS")
		)
		(fp_line
			(start 0.7874 0.4064)
			(end -0.7874 0.4064)
			(stroke
				(width 0.1524)
				(type default)
			)
			(layer "F.SilkS")
		)
		(fp_line
			(start -0.7874 -0.4064)
			(end 0.7874 -0.4064)
			(stroke
				(width 0.1524)
				(type default)
			)
			(layer "F.SilkS")
		)
		(fp_line
			(start 0.7874 -0.4064)
			(end 0.7874 0.4064)
			(stroke
				(width 0.1524)
				(type default)
			)
			(layer "F.SilkS")
		)
		(fp_line
			(start -0.67945 0.3048)
			(end -0.67945 -0.305054)
			(stroke
				(width 0.1)
				(type default)
			)
			(layer "F.Fab")
		)
		(fp_line
			(start -0.12065 0.3048)
			(end -0.67945 0.3048)
			(stroke
				(width 0.1)
				(type default)
			)
			(layer "F.Fab")
		)
		(fp_line
			(start 0.120396 0.3048)
			(end 0.120396 0.2794)
			(stroke
				(width 0.1)
				(type default)
			)
			(layer "F.Fab")
		)
		(fp_line
			(start 0.67945 0.3048)
			(end 0.120396 0.3048)
			(stroke
				(width 0.1)
				(type default)
			)
			(layer "F.Fab")
		)
		(fp_line
			(start -0.12065 0.2794)
			(end -0.12065 0.3048)
			(stroke
				(width 0.1)
				(type default)
			)
			(layer "F.Fab")
		)
		(fp_line
			(start 0.120396 0.2794)
			(end -0.12065 0.2794)
			(stroke
				(width 0.1)
				(type default)
			)
			(layer "F.Fab")
		)
		(fp_line
			(start -0.12065 -0.2794)
			(end 0.12065 -0.2794)
			(stroke
				(width 0.1)
				(type default)
			)
			(layer "F.Fab")
		)
		(fp_line
			(start 0.12065 -0.2794)
			(end 0.12065 -0.3048)
			(stroke
				(width 0.1)
				(type default)
			)
			(layer "F.Fab")
		)
		(fp_line
			(start 0.12065 -0.3048)
			(end 0.67945 -0.3048)
			(stroke
				(width 0.1)
				(type default)
			)
			(layer "F.Fab")
		)
		(fp_line
			(start 0.67945 -0.3048)
			(end 0.67945 0.3048)
			(stroke
				(width 0.1)
				(type default)
			)
			(layer "F.Fab")
		)
		(fp_line
			(start -0.67945 -0.305054)
			(end -0.12065 -0.305054)
			(stroke
				(width 0.1)
				(type default)
			)
			(layer "F.Fab")
		)
		(fp_line
			(start -0.12065 -0.305054)
			(end -0.12065 -0.2794)
			(stroke
				(width 0.1)
				(type default)
			)
			(layer "F.Fab")
		)
		(pad "1" smd circle
			(at -0.40005 0 270)
			(size 0 0)
			(layers "F.Cu" "F.Mask" "F.Paste")
			(net "P12V_NIC5_R")
		)
		(pad "2" smd circle
			(at 0.40005 0 270)
			(size 0 0)
			(layers "F.Cu" "F.Mask" "F.Paste")
			(net "GND")
		)
	)
	(footprint ""
		(layer "F.Cu")
		(at 358.369362 -118.343426 90)
		(property "Reference" "R6046"
			(at 0 0 90)
			(layer "F.SilkS")
			(hide yes)
			(effects
				(font
					(size 1.27 1.27)
				)
			)
		)
		(property "Value" ""
			(at 0 0 90)
			(layer "F.Fab")
			(effects
				(font
					(size 1.27 1.27)
				)
			)
		)
		(duplicate_pad_numbers_are_jumpers no)
		(fp_line
			(start 0.7874 -0.4064)
			(end 0.7874 0.4064)
			(stroke
				(width 0.1524)
				(type default)
			)
			(layer "F.SilkS")
		)
		(fp_line
			(start -0.7874 -0.4064)
			(end 0.7874 -0.4064)
			(stroke
				(width 0.1524)
				(type default)
			)
			(layer "F.SilkS")
		)
		(fp_line
			(start 0.7874 0.4064)
			(end -0.7874 0.4064)
			(stroke
				(width 0.1524)
				(type default)
			)
			(layer "F.SilkS")
		)
		(fp_line
			(start -0.7874 0.4064)
			(end -0.7874 -0.4064)
			(stroke
				(width 0.1524)
				(type default)
			)
			(layer "F.SilkS")
		)
		(fp_line
			(start -0.12065 -0.305054)
			(end -0.12065 -0.2794)
			(stroke
				(width 0.1)
				(type default)
			)
			(layer "F.Fab")
		)
		(fp_line
			(start -0.67945 -0.305054)
			(end -0.12065 -0.305054)
			(stroke
				(width 0.1)
				(type default)
			)
			(layer "F.Fab")
		)
		(fp_line
			(start 0.67945 -0.3048)
			(end 0.67945 0.3048)
			(stroke
				(width 0.1)
				(type default)
			)
			(layer "F.Fab")
		)
		(fp_line
			(start 0.12065 -0.3048)
			(end 0.67945 -0.3048)
			(stroke
				(width 0.1)
				(type default)
			)
			(layer "F.Fab")
		)
		(fp_line
			(start 0.12065 -0.2794)
			(end 0.12065 -0.3048)
			(stroke
				(width 0.1)
				(type default)
			)
			(layer "F.Fab")
		)
		(fp_line
			(start -0.12065 -0.2794)
			(end 0.12065 -0.2794)
			(stroke
				(width 0.1)
				(type default)
			)
			(layer "F.Fab")
		)
		(fp_line
			(start 0.120396 0.2794)
			(end -0.12065 0.2794)
			(stroke
				(width 0.1)
				(type default)
			)
			(layer "F.Fab")
		)
		(fp_line
			(start -0.12065 0.2794)
			(end -0.12065 0.3048)
			(stroke
				(width 0.1)
				(type default)
			)
			(layer "F.Fab")
		)
		(fp_line
			(start 0.67945 0.3048)
			(end 0.120396 0.3048)
			(stroke
				(width 0.1)
				(type default)
			)
			(layer "F.Fab")
		)
		(fp_line
			(start 0.120396 0.3048)
			(end 0.120396 0.2794)
			(stroke
				(width 0.1)
				(type default)
			)
			(layer "F.Fab")
		)
		(fp_line
			(start -0.12065 0.3048)
			(end -0.67945 0.3048)
			(stroke
				(width 0.1)
				(type default)
			)
			(layer "F.Fab")
		)
		(fp_line
			(start -0.67945 0.3048)
			(end -0.67945 -0.305054)
			(stroke
				(width 0.1)
				(type default)
			)
			(layer "F.Fab")
		)
		(pad "1" smd circle
			(at -0.40005 0 90)
			(size 0 0)
			(layers "F.Cu" "F.Mask" "F.Paste")
			(net "PWRGD_P3V3_NIC6_D")
		)
		(pad "2" smd circle
			(at 0.40005 0 90)
			(size 0 0)
			(layers "F.Cu" "F.Mask" "F.Paste")
			(net "PWRGD_P3V3_NIC6_R")
		)
	)
	(footprint ""
		(layer "F.Cu")
		(at 110.038896 -393.740132)
		(property "Reference" "C3635"
			(at 0 0 0)
			(layer "F.SilkS")
			(hide yes)
			(effects
				(font
					(size 1.27 1.27)
				)
			)
		)
		(property "Value" ""
			(at 0 0 0)
			(layer "F.Fab")
			(effects
				(font
					(size 1.27 1.27)
				)
			)
		)
		(duplicate_pad_numbers_are_jumpers no)
		(fp_line
			(start -0.7874 -0.4064)
			(end 0.7874 -0.4064)
			(stroke
				(width 0.1524)
				(type default)
			)
			(layer "F.SilkS")
		)
		(fp_line
			(start -0.7874 0.4064)
			(end -0.7874 -0.4064)
			(stroke
				(width 0.1524)
				(type default)
			)
			(layer "F.SilkS")
		)
		(fp_line
			(start 0.7874 -0.4064)
			(end 0.7874 0.4064)
			(stroke
				(width 0.1524)
				(type default)
			)
			(layer "F.SilkS")
		)
		(fp_line
			(start 0.7874 0.4064)
			(end -0.7874 0.4064)
			(stroke
				(width 0.1524)
				(type default)
			)
			(layer "F.SilkS")
		)
		(fp_line
			(start -0.67945 -0.305054)
			(end -0.12065 -0.305054)
			(stroke
				(width 0.1)
				(type default)
			)
			(layer "F.Fab")
		)
		(fp_line
			(start -0.67945 0.3048)
			(end -0.67945 -0.305054)
			(stroke
				(width 0.1)
				(type default)
			)
			(layer "F.Fab")
		)
		(fp_line
			(start -0.12065 -0.305054)
			(end -0.12065 -0.2794)
			(stroke
				(width 0.1)
				(type default)
			)
			(layer "F.Fab")
		)
		(fp_line
			(start -0.12065 -0.2794)
			(end 0.12065 -0.2794)
			(stroke
				(width 0.1)
				(type default)
			)
			(layer "F.Fab")
		)
		(fp_line
			(start -0.12065 0.2794)
			(end -0.12065 0.3048)
			(stroke
				(width 0.1)
				(type default)
			)
			(layer "F.Fab")
		)
		(fp_line
			(start -0.12065 0.3048)
			(end -0.67945 0.3048)
			(stroke
				(width 0.1)
				(type default)
			)
			(layer "F.Fab")
		)
		(fp_line
			(start 0.120396 0.2794)
			(end -0.12065 0.2794)
			(stroke
				(width 0.1)
				(type default)
			)
			(layer "F.Fab")
		)
		(fp_line
			(start 0.120396 0.3048)
			(end 0.120396 0.2794)
			(stroke
				(width 0.1)
				(type default)
			)
			(layer "F.Fab")
		)
		(fp_line
			(start 0.12065 -0.3048)
			(end 0.67945 -0.3048)
			(stroke
				(width 0.1)
				(type default)
			)
			(layer "F.Fab")
		)
		(fp_line
			(start 0.12065 -0.2794)
			(end 0.12065 -0.3048)
			(stroke
				(width 0.1)
				(type default)
			)
			(layer "F.Fab")
		)
		(fp_line
			(start 0.67945 -0.3048)
			(end 0.67945 0.3048)
			(stroke
				(width 0.1)
				(type default)
			)
			(layer "F.Fab")
		)
		(fp_line
			(start 0.67945 0.3048)
			(end 0.120396 0.3048)
			(stroke
				(width 0.1)
				(type default)
			)
			(layer "F.Fab")
		)
		(pad "1" smd circle
			(at -0.40005 0)
			(size 0 0)
			(layers "F.Cu" "F.Mask" "F.Paste")
			(net "BIC_USB_HUB_XIN")
		)
		(pad "2" smd circle
			(at 0.40005 0)
			(size 0 0)
			(layers "F.Cu" "F.Mask" "F.Paste")
			(net "GND")
		)
	)
	(footprint ""
		(layer "F.Cu")
		(at 368.450114 -276.010116)
		(property "Reference" "H139"
			(at -0.739394 -4.636516 0)
			(unlocked yes)
			(layer "F.SilkS")
			(effects
				(font
					(size 0.7874 0.5842)
					(thickness 0.1524)
				)
				(justify left)
			)
		)
		(property "Value" ""
			(at 0 0 0)
			(layer "F.Fab")
			(effects
				(font
					(size 1.27 1.27)
				)
			)
		)
		(duplicate_pad_numbers_are_jumpers no)
		(pad "1" thru_hole circle
			(at 0 0)
			(size 6.5024 6.5024)
			(drill 3.2004)
			(layers "*.Cu" "*.Mask")
			(remove_unused_layers no)
			(net "GND")
			(clearance -1.397)
		)
	)
	(footprint ""
		(layer "F.Cu")
		(at 190.141352 -343.952322 90)
		(property "Reference" "C2538"
			(at 0 0 90)
			(layer "F.SilkS")
			(hide yes)
			(effects
				(font
					(size 1.27 1.27)
				)
			)
		)
		(property "Value" ""
			(at 0 0 90)
			(layer "F.Fab")
			(effects
				(font
					(size 1.27 1.27)
				)
			)
		)
		(duplicate_pad_numbers_are_jumpers no)
		(fp_line
			(start 0.299974 -0.150114)
			(end 0.299974 0.150114)
			(stroke
				(width 0.1)
				(type default)
			)
			(layer "F.Fab")
		)
		(fp_line
			(start -0.299974 -0.150114)
			(end 0.299974 -0.150114)
			(stroke
				(width 0.1)
				(type default)
			)
			(layer "F.Fab")
		)
		(fp_line
			(start 0.299974 0.150114)
			(end -0.299974 0.150114)
			(stroke
				(width 0.1)
				(type default)
			)
			(layer "F.Fab")
		)
		(fp_line
			(start -0.299974 0.150114)
			(end -0.299974 -0.150114)
			(stroke
				(width 0.1)
				(type default)
			)
			(layer "F.Fab")
		)
		(pad "1" smd rect
			(at -0.2667 0 90)
			(size 0.3048 0.381)
			(layers "F.Cu" "F.Mask" "F.Paste")
			(net "P5E_PEX1_STN4_TX_DP<66>")
		)
		(pad "2" smd rect
			(at 0.2667 0 90)
			(size 0.3048 0.381)
			(layers "F.Cu" "F.Mask" "F.Paste")
			(net "P5E_PEX1_STN4_TX_C_DP<66>")
		)
	)
	(footprint ""
		(layer "F.Cu")
		(at 240.54816 -55.81142 -90)
		(property "Reference" "R894"
			(at 0 0 270)
			(layer "F.SilkS")
			(hide yes)
			(effects
				(font
					(size 1.27 1.27)
				)
			)
		)
		(property "Value" ""
			(at 0 0 270)
			(layer "F.Fab")
			(effects
				(font
					(size 1.27 1.27)
				)
			)
		)
		(duplicate_pad_numbers_are_jumpers no)
		(fp_line
			(start -0.7874 0.4064)
			(end -0.7874 -0.4064)
			(stroke
				(width 0.1524)
				(type default)
			)
			(layer "F.SilkS")
		)
		(fp_line
			(start 0.7874 0.4064)
			(end -0.7874 0.4064)
			(stroke
				(width 0.1524)
				(type default)
			)
			(layer "F.SilkS")
		)
		(fp_line
			(start -0.7874 -0.4064)
			(end 0.7874 -0.4064)
			(stroke
				(width 0.1524)
				(type default)
			)
			(layer "F.SilkS")
		)
		(fp_line
			(start 0.7874 -0.4064)
			(end 0.7874 0.4064)
			(stroke
				(width 0.1524)
				(type default)
			)
			(layer "F.SilkS")
		)
		(fp_line
			(start -0.67945 0.3048)
			(end -0.67945 -0.305054)
			(stroke
				(width 0.1)
				(type default)
			)
			(layer "F.Fab")
		)
		(fp_line
			(start -0.12065 0.3048)
			(end -0.67945 0.3048)
			(stroke
				(width 0.1)
				(type default)
			)
			(layer "F.Fab")
		)
		(fp_line
			(start 0.120396 0.3048)
			(end 0.120396 0.2794)
			(stroke
				(width 0.1)
				(type default)
			)
			(layer "F.Fab")
		)
		(fp_line
			(start 0.67945 0.3048)
			(end 0.120396 0.3048)
			(stroke
				(width 0.1)
				(type default)
			)
			(layer "F.Fab")
		)
		(fp_line
			(start -0.12065 0.2794)
			(end -0.12065 0.3048)
			(stroke
				(width 0.1)
				(type default)
			)
			(layer "F.Fab")
		)
		(fp_line
			(start 0.120396 0.2794)
			(end -0.12065 0.2794)
			(stroke
				(width 0.1)
				(type default)
			)
			(layer "F.Fab")
		)
		(fp_line
			(start -0.12065 -0.2794)
			(end 0.12065 -0.2794)
			(stroke
				(width 0.1)
				(type default)
			)
			(layer "F.Fab")
		)
		(fp_line
			(start 0.12065 -0.2794)
			(end 0.12065 -0.3048)
			(stroke
				(width 0.1)
				(type default)
			)
			(layer "F.Fab")
		)
		(fp_line
			(start 0.12065 -0.3048)
			(end 0.67945 -0.3048)
			(stroke
				(width 0.1)
				(type default)
			)
			(layer "F.Fab")
		)
		(fp_line
			(start 0.67945 -0.3048)
			(end 0.67945 0.3048)
			(stroke
				(width 0.1)
				(type default)
			)
			(layer "F.Fab")
		)
		(fp_line
			(start -0.67945 -0.305054)
			(end -0.12065 -0.305054)
			(stroke
				(width 0.1)
				(type default)
			)
			(layer "F.Fab")
		)
		(fp_line
			(start -0.12065 -0.305054)
			(end -0.12065 -0.2794)
			(stroke
				(width 0.1)
				(type default)
			)
			(layer "F.Fab")
		)
		(pad "1" smd circle
			(at -0.40005 0 270)
			(size 0 0)
			(layers "F.Cu" "F.Mask" "F.Paste")
			(net "P3V3_SSD8")
		)
		(pad "2" smd circle
			(at 0.40005 0 270)
			(size 0 0)
			(layers "F.Cu" "F.Mask" "F.Paste")
			(net "PWRGD_P3V3_SSD8")
		)
	)
	(footprint ""
		(layer "F.Cu")
		(at 98.975672 -119.477028 180)
		(property "Reference" "R880"
			(at 0 0 180)
			(layer "F.SilkS")
			(hide yes)
			(effects
				(font
					(size 1.27 1.27)
				)
			)
		)
		(property "Value" ""
			(at 0 0 180)
			(layer "F.Fab")
			(effects
				(font
					(size 1.27 1.27)
				)
			)
		)
		(duplicate_pad_numbers_are_jumpers no)
		(fp_line
			(start 0.7874 0.4064)
			(end -0.7874 0.4064)
			(stroke
				(width 0.1524)
				(type default)
			)
			(layer "F.SilkS")
		)
		(fp_line
			(start 0.7874 -0.4064)
			(end 0.7874 0.4064)
			(stroke
				(width 0.1524)
				(type default)
			)
			(layer "F.SilkS")
		)
		(fp_line
			(start -0.7874 0.4064)
			(end -0.7874 -0.4064)
			(stroke
				(width 0.1524)
				(type default)
			)
			(layer "F.SilkS")
		)
		(fp_line
			(start -0.7874 -0.4064)
			(end 0.7874 -0.4064)
			(stroke
				(width 0.1524)
				(type default)
			)
			(layer "F.SilkS")
		)
		(fp_line
			(start 0.67945 0.3048)
			(end 0.120396 0.3048)
			(stroke
				(width 0.1)
				(type default)
			)
			(layer "F.Fab")
		)
		(fp_line
			(start 0.67945 -0.3048)
			(end 0.67945 0.3048)
			(stroke
				(width 0.1)
				(type default)
			)
			(layer "F.Fab")
		)
		(fp_line
			(start 0.12065 -0.2794)
			(end 0.12065 -0.3048)
			(stroke
				(width 0.1)
				(type default)
			)
			(layer "F.Fab")
		)
		(fp_line
			(start 0.12065 -0.3048)
			(end 0.67945 -0.3048)
			(stroke
				(width 0.1)
				(type default)
			)
			(layer "F.Fab")
		)
		(fp_line
			(start 0.120396 0.3048)
			(end 0.120396 0.2794)
			(stroke
				(width 0.1)
				(type default)
			)
			(layer "F.Fab")
		)
		(fp_line
			(start 0.120396 0.2794)
			(end -0.12065 0.2794)
			(stroke
				(width 0.1)
				(type default)
			)
			(layer "F.Fab")
		)
		(fp_line
			(start -0.12065 0.3048)
			(end -0.67945 0.3048)
			(stroke
				(width 0.1)
				(type default)
			)
			(layer "F.Fab")
		)
		(fp_line
			(start -0.12065 0.2794)
			(end -0.12065 0.3048)
			(stroke
				(width 0.1)
				(type default)
			)
			(layer "F.Fab")
		)
		(fp_line
			(start -0.12065 -0.2794)
			(end 0.12065 -0.2794)
			(stroke
				(width 0.1)
				(type default)
			)
			(layer "F.Fab")
		)
		(fp_line
			(start -0.12065 -0.305054)
			(end -0.12065 -0.2794)
			(stroke
				(width 0.1)
				(type default)
			)
			(layer "F.Fab")
		)
		(fp_line
			(start -0.67945 0.3048)
			(end -0.67945 -0.305054)
			(stroke
				(width 0.1)
				(type default)
			)
			(layer "F.Fab")
		)
		(fp_line
			(start -0.67945 -0.305054)
			(end -0.12065 -0.305054)
			(stroke
				(width 0.1)
				(type default)
			)
			(layer "F.Fab")
		)
		(pad "1" smd circle
			(at -0.40005 0 180)
			(size 0 0)
			(layers "F.Cu" "F.Mask" "F.Paste")
			(net "P3V3_NIC1")
		)
		(pad "2" smd circle
			(at 0.40005 0 180)
			(size 0 0)
			(layers "F.Cu" "F.Mask" "F.Paste")
			(net "PWRGD_P3V3_NIC1")
		)
	)
	(footprint ""
		(layer "F.Cu")
		(at 335.534 -205.232 -90)
		(property "Reference" "R4121"
			(at 0 0 270)
			(layer "F.SilkS")
			(hide yes)
			(effects
				(font
					(size 1.27 1.27)
				)
			)
		)
		(property "Value" ""
			(at 0 0 270)
			(layer "F.Fab")
			(effects
				(font
					(size 1.27 1.27)
				)
			)
		)
		(duplicate_pad_numbers_are_jumpers no)
		(fp_line
			(start -0.7874 0.4064)
			(end -0.7874 -0.4064)
			(stroke
				(width 0.1524)
				(type default)
			)
			(layer "F.SilkS")
		)
		(fp_line
			(start 0.7874 0.4064)
			(end -0.7874 0.4064)
			(stroke
				(width 0.1524)
				(type default)
			)
			(layer "F.SilkS")
		)
		(fp_line
			(start -0.7874 -0.4064)
			(end 0.7874 -0.4064)
			(stroke
				(width 0.1524)
				(type default)
			)
			(layer "F.SilkS")
		)
		(fp_line
			(start 0.7874 -0.4064)
			(end 0.7874 0.4064)
			(stroke
				(width 0.1524)
				(type default)
			)
			(layer "F.SilkS")
		)
		(fp_line
			(start -0.67945 0.3048)
			(end -0.67945 -0.305054)
			(stroke
				(width 0.1)
				(type default)
			)
			(layer "F.Fab")
		)
		(fp_line
			(start -0.12065 0.3048)
			(end -0.67945 0.3048)
			(stroke
				(width 0.1)
				(type default)
			)
			(layer "F.Fab")
		)
		(fp_line
			(start 0.120396 0.3048)
			(end 0.120396 0.2794)
			(stroke
				(width 0.1)
				(type default)
			)
			(layer "F.Fab")
		)
		(fp_line
			(start 0.67945 0.3048)
			(end 0.120396 0.3048)
			(stroke
				(width 0.1)
				(type default)
			)
			(layer "F.Fab")
		)
		(fp_line
			(start -0.12065 0.2794)
			(end -0.12065 0.3048)
			(stroke
				(width 0.1)
				(type default)
			)
			(layer "F.Fab")
		)
		(fp_line
			(start 0.120396 0.2794)
			(end -0.12065 0.2794)
			(stroke
				(width 0.1)
				(type default)
			)
			(layer "F.Fab")
		)
		(fp_line
			(start -0.12065 -0.2794)
			(end 0.12065 -0.2794)
			(stroke
				(width 0.1)
				(type default)
			)
			(layer "F.Fab")
		)
		(fp_line
			(start 0.12065 -0.2794)
			(end 0.12065 -0.3048)
			(stroke
				(width 0.1)
				(type default)
			)
			(layer "F.Fab")
		)
		(fp_line
			(start 0.12065 -0.3048)
			(end 0.67945 -0.3048)
			(stroke
				(width 0.1)
				(type default)
			)
			(layer "F.Fab")
		)
		(fp_line
			(start 0.67945 -0.3048)
			(end 0.67945 0.3048)
			(stroke
				(width 0.1)
				(type default)
			)
			(layer "F.Fab")
		)
		(fp_line
			(start -0.67945 -0.305054)
			(end -0.12065 -0.305054)
			(stroke
				(width 0.1)
				(type default)
			)
			(layer "F.Fab")
		)
		(fp_line
			(start -0.12065 -0.305054)
			(end -0.12065 -0.2794)
			(stroke
				(width 0.1)
				(type default)
			)
			(layer "F.Fab")
		)
		(pad "1" smd circle
			(at -0.40005 0 270)
			(size 0 0)
			(layers "F.Cu" "F.Mask" "F.Paste")
			(net "RST_SSD9_PERST_N")
		)
		(pad "2" smd circle
			(at 0.40005 0 270)
			(size 0 0)
			(layers "F.Cu" "F.Mask" "F.Paste")
			(net "RST_SSD9_PERST_R_N")
		)
	)
	(footprint ""
		(layer "F.Cu")
		(at 361.89031 -253.178564 180)
		(property "Reference" "R834"
			(at 0 0 180)
			(layer "F.SilkS")
			(hide yes)
			(effects
				(font
					(size 1.27 1.27)
				)
			)
		)
		(property "Value" ""
			(at 0 0 180)
			(layer "F.Fab")
			(effects
				(font
					(size 1.27 1.27)
				)
			)
		)
		(duplicate_pad_numbers_are_jumpers no)
		(fp_line
			(start 0.7874 0.4064)
			(end -0.7874 0.4064)
			(stroke
				(width 0.1524)
				(type default)
			)
			(layer "F.SilkS")
		)
		(fp_line
			(start 0.7874 -0.4064)
			(end 0.7874 0.4064)
			(stroke
				(width 0.1524)
				(type default)
			)
			(layer "F.SilkS")
		)
		(fp_line
			(start -0.7874 0.4064)
			(end -0.7874 -0.4064)
			(stroke
				(width 0.1524)
				(type default)
			)
			(layer "F.SilkS")
		)
		(fp_line
			(start -0.7874 -0.4064)
			(end 0.7874 -0.4064)
			(stroke
				(width 0.1524)
				(type default)
			)
			(layer "F.SilkS")
		)
		(fp_line
			(start 0.67945 0.3048)
			(end 0.120396 0.3048)
			(stroke
				(width 0.1)
				(type default)
			)
			(layer "F.Fab")
		)
		(fp_line
			(start 0.67945 -0.3048)
			(end 0.67945 0.3048)
			(stroke
				(width 0.1)
				(type default)
			)
			(layer "F.Fab")
		)
		(fp_line
			(start 0.12065 -0.2794)
			(end 0.12065 -0.3048)
			(stroke
				(width 0.1)
				(type default)
			)
			(layer "F.Fab")
		)
		(fp_line
			(start 0.12065 -0.3048)
			(end 0.67945 -0.3048)
			(stroke
				(width 0.1)
				(type default)
			)
			(layer "F.Fab")
		)
		(fp_line
			(start 0.120396 0.3048)
			(end 0.120396 0.2794)
			(stroke
				(width 0.1)
				(type default)
			)
			(layer "F.Fab")
		)
		(fp_line
			(start 0.120396 0.2794)
			(end -0.12065 0.2794)
			(stroke
				(width 0.1)
				(type default)
			)
			(layer "F.Fab")
		)
		(fp_line
			(start -0.12065 0.3048)
			(end -0.67945 0.3048)
			(stroke
				(width 0.1)
				(type default)
			)
			(layer "F.Fab")
		)
		(fp_line
			(start -0.12065 0.2794)
			(end -0.12065 0.3048)
			(stroke
				(width 0.1)
				(type default)
			)
			(layer "F.Fab")
		)
		(fp_line
			(start -0.12065 -0.2794)
			(end 0.12065 -0.2794)
			(stroke
				(width 0.1)
				(type default)
			)
			(layer "F.Fab")
		)
		(fp_line
			(start -0.12065 -0.305054)
			(end -0.12065 -0.2794)
			(stroke
				(width 0.1)
				(type default)
			)
			(layer "F.Fab")
		)
		(fp_line
			(start -0.67945 0.3048)
			(end -0.67945 -0.305054)
			(stroke
				(width 0.1)
				(type default)
			)
			(layer "F.Fab")
		)
		(fp_line
			(start -0.67945 -0.305054)
			(end -0.12065 -0.305054)
			(stroke
				(width 0.1)
				(type default)
			)
			(layer "F.Fab")
		)
		(pad "1" smd circle
			(at -0.40005 0 180)
			(size 0 0)
			(layers "F.Cu" "F.Mask" "F.Paste")
			(net "PWRGD_P0V8_PEX2_R")
		)
		(pad "2" smd circle
			(at 0.40005 0 180)
			(size 0 0)
			(layers "F.Cu" "F.Mask" "F.Paste")
			(net "P0V8_PEX2_AVRRDY")
		)
	)
	(footprint ""
		(layer "F.Cu")
		(at 423.95648 -20.467574 180)
		(property "Reference" "R1731"
			(at 0 0 180)
			(layer "F.SilkS")
			(hide yes)
			(effects
				(font
					(size 1.27 1.27)
				)
			)
		)
		(property "Value" ""
			(at 0 0 180)
			(layer "F.Fab")
			(effects
				(font
					(size 1.27 1.27)
				)
			)
		)
		(duplicate_pad_numbers_are_jumpers no)
		(fp_line
			(start 0.7874 0.4064)
			(end -0.7874 0.4064)
			(stroke
				(width 0.1524)
				(type default)
			)
			(layer "F.SilkS")
		)
		(fp_line
			(start 0.7874 -0.4064)
			(end 0.7874 0.4064)
			(stroke
				(width 0.1524)
				(type default)
			)
			(layer "F.SilkS")
		)
		(fp_line
			(start -0.7874 0.4064)
			(end -0.7874 -0.4064)
			(stroke
				(width 0.1524)
				(type default)
			)
			(layer "F.SilkS")
		)
		(fp_line
			(start -0.7874 -0.4064)
			(end 0.7874 -0.4064)
			(stroke
				(width 0.1524)
				(type default)
			)
			(layer "F.SilkS")
		)
		(fp_line
			(start 0.67945 0.3048)
			(end 0.120396 0.3048)
			(stroke
				(width 0.1)
				(type default)
			)
			(layer "F.Fab")
		)
		(fp_line
			(start 0.67945 -0.3048)
			(end 0.67945 0.3048)
			(stroke
				(width 0.1)
				(type default)
			)
			(layer "F.Fab")
		)
		(fp_line
			(start 0.12065 -0.2794)
			(end 0.12065 -0.3048)
			(stroke
				(width 0.1)
				(type default)
			)
			(layer "F.Fab")
		)
		(fp_line
			(start 0.12065 -0.3048)
			(end 0.67945 -0.3048)
			(stroke
				(width 0.1)
				(type default)
			)
			(layer "F.Fab")
		)
		(fp_line
			(start 0.120396 0.3048)
			(end 0.120396 0.2794)
			(stroke
				(width 0.1)
				(type default)
			)
			(layer "F.Fab")
		)
		(fp_line
			(start 0.120396 0.2794)
			(end -0.12065 0.2794)
			(stroke
				(width 0.1)
				(type default)
			)
			(layer "F.Fab")
		)
		(fp_line
			(start -0.12065 0.3048)
			(end -0.67945 0.3048)
			(stroke
				(width 0.1)
				(type default)
			)
			(layer "F.Fab")
		)
		(fp_line
			(start -0.12065 0.2794)
			(end -0.12065 0.3048)
			(stroke
				(width 0.1)
				(type default)
			)
			(layer "F.Fab")
		)
		(fp_line
			(start -0.12065 -0.2794)
			(end 0.12065 -0.2794)
			(stroke
				(width 0.1)
				(type default)
			)
			(layer "F.Fab")
		)
		(fp_line
			(start -0.12065 -0.305054)
			(end -0.12065 -0.2794)
			(stroke
				(width 0.1)
				(type default)
			)
			(layer "F.Fab")
		)
		(fp_line
			(start -0.67945 0.3048)
			(end -0.67945 -0.305054)
			(stroke
				(width 0.1)
				(type default)
			)
			(layer "F.Fab")
		)
		(fp_line
			(start -0.67945 -0.305054)
			(end -0.12065 -0.305054)
			(stroke
				(width 0.1)
				(type default)
			)
			(layer "F.Fab")
		)
		(pad "1" smd circle
			(at -0.40005 0 180)
			(size 0 0)
			(layers "F.Cu" "F.Mask" "F.Paste")
			(net "P3V3_SSD14")
		)
		(pad "2" smd circle
			(at 0.40005 0 180)
			(size 0 0)
			(layers "F.Cu" "F.Mask" "F.Paste")
			(net "SMB_ISO_SSD14_SDA")
		)
	)
	(footprint ""
		(layer "F.Cu")
		(at 385.304792 -141.87297 180)
		(property "Reference" "R337"
			(at 0 0 180)
			(layer "F.SilkS")
			(hide yes)
			(effects
				(font
					(size 1.27 1.27)
				)
			)
		)
		(property "Value" ""
			(at 0 0 180)
			(layer "F.Fab")
			(effects
				(font
					(size 1.27 1.27)
				)
			)
		)
		(duplicate_pad_numbers_are_jumpers no)
		(fp_line
			(start 0.7874 0.4064)
			(end -0.7874 0.4064)
			(stroke
				(width 0.1524)
				(type default)
			)
			(layer "F.SilkS")
		)
		(fp_line
			(start 0.7874 -0.4064)
			(end 0.7874 0.4064)
			(stroke
				(width 0.1524)
				(type default)
			)
			(layer "F.SilkS")
		)
		(fp_line
			(start -0.7874 0.4064)
			(end -0.7874 -0.4064)
			(stroke
				(width 0.1524)
				(type default)
			)
			(layer "F.SilkS")
		)
		(fp_line
			(start -0.7874 -0.4064)
			(end 0.7874 -0.4064)
			(stroke
				(width 0.1524)
				(type default)
			)
			(layer "F.SilkS")
		)
		(fp_line
			(start 0.67945 0.3048)
			(end 0.120396 0.3048)
			(stroke
				(width 0.1)
				(type default)
			)
			(layer "F.Fab")
		)
		(fp_line
			(start 0.67945 -0.3048)
			(end 0.67945 0.3048)
			(stroke
				(width 0.1)
				(type default)
			)
			(layer "F.Fab")
		)
		(fp_line
			(start 0.12065 -0.2794)
			(end 0.12065 -0.3048)
			(stroke
				(width 0.1)
				(type default)
			)
			(layer "F.Fab")
		)
		(fp_line
			(start 0.12065 -0.3048)
			(end 0.67945 -0.3048)
			(stroke
				(width 0.1)
				(type default)
			)
			(layer "F.Fab")
		)
		(fp_line
			(start 0.120396 0.3048)
			(end 0.120396 0.2794)
			(stroke
				(width 0.1)
				(type default)
			)
			(layer "F.Fab")
		)
		(fp_line
			(start 0.120396 0.2794)
			(end -0.12065 0.2794)
			(stroke
				(width 0.1)
				(type default)
			)
			(layer "F.Fab")
		)
		(fp_line
			(start -0.12065 0.3048)
			(end -0.67945 0.3048)
			(stroke
				(width 0.1)
				(type default)
			)
			(layer "F.Fab")
		)
		(fp_line
			(start -0.12065 0.2794)
			(end -0.12065 0.3048)
			(stroke
				(width 0.1)
				(type default)
			)
			(layer "F.Fab")
		)
		(fp_line
			(start -0.12065 -0.2794)
			(end 0.12065 -0.2794)
			(stroke
				(width 0.1)
				(type default)
			)
			(layer "F.Fab")
		)
		(fp_line
			(start -0.12065 -0.305054)
			(end -0.12065 -0.2794)
			(stroke
				(width 0.1)
				(type default)
			)
			(layer "F.Fab")
		)
		(fp_line
			(start -0.67945 0.3048)
			(end -0.67945 -0.305054)
			(stroke
				(width 0.1)
				(type default)
			)
			(layer "F.Fab")
		)
		(fp_line
			(start -0.67945 -0.305054)
			(end -0.12065 -0.305054)
			(stroke
				(width 0.1)
				(type default)
			)
			(layer "F.Fab")
		)
		(pad "1" smd circle
			(at -0.40005 0 180)
			(size 0 0)
			(layers "F.Cu" "F.Mask" "F.Paste")
			(net "NIC6_BIF1_N")
		)
		(pad "2" smd circle
			(at 0.40005 0 180)
			(size 0 0)
			(layers "F.Cu" "F.Mask" "F.Paste")
			(net "P3V3_AUX")
		)
	)
	(footprint ""
		(layer "F.Cu")
		(at 381.254 -208.534)
		(property "Reference" "R4602"
			(at 0 0 0)
			(layer "F.SilkS")
			(hide yes)
			(effects
				(font
					(size 1.27 1.27)
				)
			)
		)
		(property "Value" ""
			(at 0 0 0)
			(layer "F.Fab")
			(effects
				(font
					(size 1.27 1.27)
				)
			)
		)
		(duplicate_pad_numbers_are_jumpers no)
		(fp_line
			(start -0.7874 -0.4064)
			(end 0.7874 -0.4064)
			(stroke
				(width 0.1524)
				(type default)
			)
			(layer "F.SilkS")
		)
		(fp_line
			(start -0.7874 0.4064)
			(end -0.7874 -0.4064)
			(stroke
				(width 0.1524)
				(type default)
			)
			(layer "F.SilkS")
		)
		(fp_line
			(start 0.7874 -0.4064)
			(end 0.7874 0.4064)
			(stroke
				(width 0.1524)
				(type default)
			)
			(layer "F.SilkS")
		)
		(fp_line
			(start 0.7874 0.4064)
			(end -0.7874 0.4064)
			(stroke
				(width 0.1524)
				(type default)
			)
			(layer "F.SilkS")
		)
		(fp_line
			(start -0.67945 -0.305054)
			(end -0.12065 -0.305054)
			(stroke
				(width 0.1)
				(type default)
			)
			(layer "F.Fab")
		)
		(fp_line
			(start -0.67945 0.3048)
			(end -0.67945 -0.305054)
			(stroke
				(width 0.1)
				(type default)
			)
			(layer "F.Fab")
		)
		(fp_line
			(start -0.12065 -0.305054)
			(end -0.12065 -0.2794)
			(stroke
				(width 0.1)
				(type default)
			)
			(layer "F.Fab")
		)
		(fp_line
			(start -0.12065 -0.2794)
			(end 0.12065 -0.2794)
			(stroke
				(width 0.1)
				(type default)
			)
			(layer "F.Fab")
		)
		(fp_line
			(start -0.12065 0.2794)
			(end -0.12065 0.3048)
			(stroke
				(width 0.1)
				(type default)
			)
			(layer "F.Fab")
		)
		(fp_line
			(start -0.12065 0.3048)
			(end -0.67945 0.3048)
			(stroke
				(width 0.1)
				(type default)
			)
			(layer "F.Fab")
		)
		(fp_line
			(start 0.120396 0.2794)
			(end -0.12065 0.2794)
			(stroke
				(width 0.1)
				(type default)
			)
			(layer "F.Fab")
		)
		(fp_line
			(start 0.120396 0.3048)
			(end 0.120396 0.2794)
			(stroke
				(width 0.1)
				(type default)
			)
			(layer "F.Fab")
		)
		(fp_line
			(start 0.12065 -0.3048)
			(end 0.67945 -0.3048)
			(stroke
				(width 0.1)
				(type default)
			)
			(layer "F.Fab")
		)
		(fp_line
			(start 0.12065 -0.2794)
			(end 0.12065 -0.3048)
			(stroke
				(width 0.1)
				(type default)
			)
			(layer "F.Fab")
		)
		(fp_line
			(start 0.67945 -0.3048)
			(end 0.67945 0.3048)
			(stroke
				(width 0.1)
				(type default)
			)
			(layer "F.Fab")
		)
		(fp_line
			(start 0.67945 0.3048)
			(end 0.120396 0.3048)
			(stroke
				(width 0.1)
				(type default)
			)
			(layer "F.Fab")
		)
		(pad "1" smd circle
			(at -0.40005 0)
			(size 0 0)
			(layers "F.Cu" "F.Mask" "F.Paste")
			(net "P3V3_AUX")
		)
		(pad "2" smd circle
			(at 0.40005 0)
			(size 0 0)
			(layers "F.Cu" "F.Mask" "F.Paste")
			(net "NIC0_PEX_PWR_EN_R")
		)
	)
	(footprint ""
		(layer "F.Cu")
		(at 142.368016 -54.067456)
		(property "Reference" "PR210"
			(at 0 0 0)
			(layer "F.SilkS")
			(hide yes)
			(effects
				(font
					(size 1.27 1.27)
				)
			)
		)
		(property "Value" ""
			(at 0 0 0)
			(layer "F.Fab")
			(effects
				(font
					(size 1.27 1.27)
				)
			)
		)
		(duplicate_pad_numbers_are_jumpers no)
		(fp_line
			(start -0.7874 -0.4064)
			(end 0.7874 -0.4064)
			(stroke
				(width 0.1524)
				(type default)
			)
			(layer "F.SilkS")
		)
		(fp_line
			(start -0.7874 0.4064)
			(end -0.7874 -0.4064)
			(stroke
				(width 0.1524)
				(type default)
			)
			(layer "F.SilkS")
		)
		(fp_line
			(start 0.7874 -0.4064)
			(end 0.7874 0.4064)
			(stroke
				(width 0.1524)
				(type default)
			)
			(layer "F.SilkS")
		)
		(fp_line
			(start 0.7874 0.4064)
			(end -0.7874 0.4064)
			(stroke
				(width 0.1524)
				(type default)
			)
			(layer "F.SilkS")
		)
		(fp_line
			(start -0.67945 -0.305054)
			(end -0.12065 -0.305054)
			(stroke
				(width 0.1)
				(type default)
			)
			(layer "F.Fab")
		)
		(fp_line
			(start -0.67945 0.3048)
			(end -0.67945 -0.305054)
			(stroke
				(width 0.1)
				(type default)
			)
			(layer "F.Fab")
		)
		(fp_line
			(start -0.12065 -0.305054)
			(end -0.12065 -0.2794)
			(stroke
				(width 0.1)
				(type default)
			)
			(layer "F.Fab")
		)
		(fp_line
			(start -0.12065 -0.2794)
			(end 0.12065 -0.2794)
			(stroke
				(width 0.1)
				(type default)
			)
			(layer "F.Fab")
		)
		(fp_line
			(start -0.12065 0.2794)
			(end -0.12065 0.3048)
			(stroke
				(width 0.1)
				(type default)
			)
			(layer "F.Fab")
		)
		(fp_line
			(start -0.12065 0.3048)
			(end -0.67945 0.3048)
			(stroke
				(width 0.1)
				(type default)
			)
			(layer "F.Fab")
		)
		(fp_line
			(start 0.120396 0.2794)
			(end -0.12065 0.2794)
			(stroke
				(width 0.1)
				(type default)
			)
			(layer "F.Fab")
		)
		(fp_line
			(start 0.120396 0.3048)
			(end 0.120396 0.2794)
			(stroke
				(width 0.1)
				(type default)
			)
			(layer "F.Fab")
		)
		(fp_line
			(start 0.12065 -0.3048)
			(end 0.67945 -0.3048)
			(stroke
				(width 0.1)
				(type default)
			)
			(layer "F.Fab")
		)
		(fp_line
			(start 0.12065 -0.2794)
			(end 0.12065 -0.3048)
			(stroke
				(width 0.1)
				(type default)
			)
			(layer "F.Fab")
		)
		(fp_line
			(start 0.67945 -0.3048)
			(end 0.67945 0.3048)
			(stroke
				(width 0.1)
				(type default)
			)
			(layer "F.Fab")
		)
		(fp_line
			(start 0.67945 0.3048)
			(end 0.120396 0.3048)
			(stroke
				(width 0.1)
				(type default)
			)
			(layer "F.Fab")
		)
		(pad "1" smd circle
			(at -0.40005 0)
			(size 0 0)
			(layers "F.Cu" "F.Mask" "F.Paste")
			(net "P12V_SSD4_OCP")
		)
		(pad "2" smd circle
			(at 0.40005 0)
			(size 0 0)
			(layers "F.Cu" "F.Mask" "F.Paste")
			(net "GND")
		)
	)
	(footprint ""
		(layer "F.Cu")
		(at 387.132068 -147.969224 90)
		(property "Reference" "C935"
			(at 0 0 90)
			(layer "F.SilkS")
			(hide yes)
			(effects
				(font
					(size 1.27 1.27)
				)
			)
		)
		(property "Value" ""
			(at 0 0 90)
			(layer "F.Fab")
			(effects
				(font
					(size 1.27 1.27)
				)
			)
		)
		(duplicate_pad_numbers_are_jumpers no)
		(fp_line
			(start 1.524 -0.762)
			(end 1.524 0.762)
			(stroke
				(width 0.1524)
				(type default)
			)
			(layer "F.SilkS")
		)
		(fp_line
			(start -1.524 -0.762)
			(end 1.524 -0.762)
			(stroke
				(width 0.1524)
				(type default)
			)
			(layer "F.SilkS")
		)
		(fp_line
			(start 1.524 0.762)
			(end -1.524 0.762)
			(stroke
				(width 0.1524)
				(type default)
			)
			(layer "F.SilkS")
		)
		(fp_line
			(start -1.524 0.762)
			(end -1.524 -0.762)
			(stroke
				(width 0.1524)
				(type default)
			)
			(layer "F.SilkS")
		)
		(fp_line
			(start 1.1049 -0.724916)
			(end -1.1049 -0.724916)
			(stroke
				(width 0.1)
				(type default)
			)
			(layer "F.Fab")
		)
		(fp_line
			(start -1.1049 -0.724916)
			(end -1.1049 0.724916)
			(stroke
				(width 0.1)
				(type default)
			)
			(layer "F.Fab")
		)
		(fp_line
			(start 1.1049 0.724916)
			(end 1.1049 -0.724916)
			(stroke
				(width 0.1)
				(type default)
			)
			(layer "F.Fab")
		)
		(fp_line
			(start -1.1049 0.724916)
			(end 1.1049 0.724916)
			(stroke
				(width 0.1)
				(type default)
			)
			(layer "F.Fab")
		)
		(pad "1" smd rect
			(at -0.889 0 270)
			(size 1.016 1.27)
			(layers "F.Cu" "F.Mask" "F.Paste")
			(net "P12V_NIC6")
		)
		(pad "2" smd rect
			(at 0.889 0 270)
			(size 1.016 1.27)
			(layers "F.Cu" "F.Mask" "F.Paste")
			(net "GND")
		)
	)
	(footprint ""
		(layer "F.Cu")
		(at 337.566 -205.232 -90)
		(property "Reference" "R4123"
			(at 0 0 270)
			(layer "F.SilkS")
			(hide yes)
			(effects
				(font
					(size 1.27 1.27)
				)
			)
		)
		(property "Value" ""
			(at 0 0 270)
			(layer "F.Fab")
			(effects
				(font
					(size 1.27 1.27)
				)
			)
		)
		(duplicate_pad_numbers_are_jumpers no)
		(fp_line
			(start -0.7874 0.4064)
			(end -0.7874 -0.4064)
			(stroke
				(width 0.1524)
				(type default)
			)
			(layer "F.SilkS")
		)
		(fp_line
			(start 0.7874 0.4064)
			(end -0.7874 0.4064)
			(stroke
				(width 0.1524)
				(type default)
			)
			(layer "F.SilkS")
		)
		(fp_line
			(start -0.7874 -0.4064)
			(end 0.7874 -0.4064)
			(stroke
				(width 0.1524)
				(type default)
			)
			(layer "F.SilkS")
		)
		(fp_line
			(start 0.7874 -0.4064)
			(end 0.7874 0.4064)
			(stroke
				(width 0.1524)
				(type default)
			)
			(layer "F.SilkS")
		)
		(fp_line
			(start -0.67945 0.3048)
			(end -0.67945 -0.305054)
			(stroke
				(width 0.1)
				(type default)
			)
			(layer "F.Fab")
		)
		(fp_line
			(start -0.12065 0.3048)
			(end -0.67945 0.3048)
			(stroke
				(width 0.1)
				(type default)
			)
			(layer "F.Fab")
		)
		(fp_line
			(start 0.120396 0.3048)
			(end 0.120396 0.2794)
			(stroke
				(width 0.1)
				(type default)
			)
			(layer "F.Fab")
		)
		(fp_line
			(start 0.67945 0.3048)
			(end 0.120396 0.3048)
			(stroke
				(width 0.1)
				(type default)
			)
			(layer "F.Fab")
		)
		(fp_line
			(start -0.12065 0.2794)
			(end -0.12065 0.3048)
			(stroke
				(width 0.1)
				(type default)
			)
			(layer "F.Fab")
		)
		(fp_line
			(start 0.120396 0.2794)
			(end -0.12065 0.2794)
			(stroke
				(width 0.1)
				(type default)
			)
			(layer "F.Fab")
		)
		(fp_line
			(start -0.12065 -0.2794)
			(end 0.12065 -0.2794)
			(stroke
				(width 0.1)
				(type default)
			)
			(layer "F.Fab")
		)
		(fp_line
			(start 0.12065 -0.2794)
			(end 0.12065 -0.3048)
			(stroke
				(width 0.1)
				(type default)
			)
			(layer "F.Fab")
		)
		(fp_line
			(start 0.12065 -0.3048)
			(end 0.67945 -0.3048)
			(stroke
				(width 0.1)
				(type default)
			)
			(layer "F.Fab")
		)
		(fp_line
			(start 0.67945 -0.3048)
			(end 0.67945 0.3048)
			(stroke
				(width 0.1)
				(type default)
			)
			(layer "F.Fab")
		)
		(fp_line
			(start -0.67945 -0.305054)
			(end -0.12065 -0.305054)
			(stroke
				(width 0.1)
				(type default)
			)
			(layer "F.Fab")
		)
		(fp_line
			(start -0.12065 -0.305054)
			(end -0.12065 -0.2794)
			(stroke
				(width 0.1)
				(type default)
			)
			(layer "F.Fab")
		)
		(pad "1" smd circle
			(at -0.40005 0 270)
			(size 0 0)
			(layers "F.Cu" "F.Mask" "F.Paste")
			(net "SSD10_PWR_EN")
		)
		(pad "2" smd circle
			(at 0.40005 0 270)
			(size 0 0)
			(layers "F.Cu" "F.Mask" "F.Paste")
			(net "SSD10_PWR_EN_R")
		)
	)
	(footprint ""
		(layer "F.Cu")
		(at 189.047374 -19.33956)
		(property "Reference" "C3916"
			(at 0 0 0)
			(layer "F.SilkS")
			(hide yes)
			(effects
				(font
					(size 1.27 1.27)
				)
			)
		)
		(property "Value" ""
			(at 0 0 0)
			(layer "F.Fab")
			(effects
				(font
					(size 1.27 1.27)
				)
			)
		)
		(duplicate_pad_numbers_are_jumpers no)
		(fp_line
			(start -0.7874 -0.4064)
			(end 0.7874 -0.4064)
			(stroke
				(width 0.1524)
				(type default)
			)
			(layer "F.SilkS")
		)
		(fp_line
			(start -0.7874 0.4064)
			(end -0.7874 -0.4064)
			(stroke
				(width 0.1524)
				(type default)
			)
			(layer "F.SilkS")
		)
		(fp_line
			(start 0.7874 -0.4064)
			(end 0.7874 0.4064)
			(stroke
				(width 0.1524)
				(type default)
			)
			(layer "F.SilkS")
		)
		(fp_line
			(start 0.7874 0.4064)
			(end -0.7874 0.4064)
			(stroke
				(width 0.1524)
				(type default)
			)
			(layer "F.SilkS")
		)
		(fp_line
			(start -0.67945 -0.305054)
			(end -0.12065 -0.305054)
			(stroke
				(width 0.1)
				(type default)
			)
			(layer "F.Fab")
		)
		(fp_line
			(start -0.67945 0.3048)
			(end -0.67945 -0.305054)
			(stroke
				(width 0.1)
				(type default)
			)
			(layer "F.Fab")
		)
		(fp_line
			(start -0.12065 -0.305054)
			(end -0.12065 -0.2794)
			(stroke
				(width 0.1)
				(type default)
			)
			(layer "F.Fab")
		)
		(fp_line
			(start -0.12065 -0.2794)
			(end 0.12065 -0.2794)
			(stroke
				(width 0.1)
				(type default)
			)
			(layer "F.Fab")
		)
		(fp_line
			(start -0.12065 0.2794)
			(end -0.12065 0.3048)
			(stroke
				(width 0.1)
				(type default)
			)
			(layer "F.Fab")
		)
		(fp_line
			(start -0.12065 0.3048)
			(end -0.67945 0.3048)
			(stroke
				(width 0.1)
				(type default)
			)
			(layer "F.Fab")
		)
		(fp_line
			(start 0.120396 0.2794)
			(end -0.12065 0.2794)
			(stroke
				(width 0.1)
				(type default)
			)
			(layer "F.Fab")
		)
		(fp_line
			(start 0.120396 0.3048)
			(end 0.120396 0.2794)
			(stroke
				(width 0.1)
				(type default)
			)
			(layer "F.Fab")
		)
		(fp_line
			(start 0.12065 -0.3048)
			(end 0.67945 -0.3048)
			(stroke
				(width 0.1)
				(type default)
			)
			(layer "F.Fab")
		)
		(fp_line
			(start 0.12065 -0.2794)
			(end 0.12065 -0.3048)
			(stroke
				(width 0.1)
				(type default)
			)
			(layer "F.Fab")
		)
		(fp_line
			(start 0.67945 -0.3048)
			(end 0.67945 0.3048)
			(stroke
				(width 0.1)
				(type default)
			)
			(layer "F.Fab")
		)
		(fp_line
			(start 0.67945 0.3048)
			(end 0.120396 0.3048)
			(stroke
				(width 0.1)
				(type default)
			)
			(layer "F.Fab")
		)
		(pad "1" smd circle
			(at -0.40005 0)
			(size 0 0)
			(layers "F.Cu" "F.Mask" "F.Paste")
			(net "P12V_SSD6")
		)
		(pad "2" smd circle
			(at 0.40005 0)
			(size 0 0)
			(layers "F.Cu" "F.Mask" "F.Paste")
			(net "GND")
		)
	)
	(footprint ""
		(layer "F.Cu")
		(at 355.081586 -262.04672 180)
		(property "Reference" "PC129"
			(at 0 0 180)
			(layer "F.SilkS")
			(hide yes)
			(effects
				(font
					(size 1.27 1.27)
				)
			)
		)
		(property "Value" ""
			(at 0 0 180)
			(layer "F.Fab")
			(effects
				(font
					(size 1.27 1.27)
				)
			)
		)
		(duplicate_pad_numbers_are_jumpers no)
		(fp_line
			(start 0.7874 0.4064)
			(end -0.7874 0.4064)
			(stroke
				(width 0.1524)
				(type default)
			)
			(layer "F.SilkS")
		)
		(fp_line
			(start 0.7874 -0.4064)
			(end 0.7874 0.4064)
			(stroke
				(width 0.1524)
				(type default)
			)
			(layer "F.SilkS")
		)
		(fp_line
			(start -0.7874 0.4064)
			(end -0.7874 -0.4064)
			(stroke
				(width 0.1524)
				(type default)
			)
			(layer "F.SilkS")
		)
		(fp_line
			(start -0.7874 -0.4064)
			(end 0.7874 -0.4064)
			(stroke
				(width 0.1524)
				(type default)
			)
			(layer "F.SilkS")
		)
		(fp_line
			(start 0.67945 0.3048)
			(end 0.120396 0.3048)
			(stroke
				(width 0.1)
				(type default)
			)
			(layer "F.Fab")
		)
		(fp_line
			(start 0.67945 -0.3048)
			(end 0.67945 0.3048)
			(stroke
				(width 0.1)
				(type default)
			)
			(layer "F.Fab")
		)
		(fp_line
			(start 0.12065 -0.2794)
			(end 0.12065 -0.3048)
			(stroke
				(width 0.1)
				(type default)
			)
			(layer "F.Fab")
		)
		(fp_line
			(start 0.12065 -0.3048)
			(end 0.67945 -0.3048)
			(stroke
				(width 0.1)
				(type default)
			)
			(layer "F.Fab")
		)
		(fp_line
			(start 0.120396 0.3048)
			(end 0.120396 0.2794)
			(stroke
				(width 0.1)
				(type default)
			)
			(layer "F.Fab")
		)
		(fp_line
			(start 0.120396 0.2794)
			(end -0.12065 0.2794)
			(stroke
				(width 0.1)
				(type default)
			)
			(layer "F.Fab")
		)
		(fp_line
			(start -0.12065 0.3048)
			(end -0.67945 0.3048)
			(stroke
				(width 0.1)
				(type default)
			)
			(layer "F.Fab")
		)
		(fp_line
			(start -0.12065 0.2794)
			(end -0.12065 0.3048)
			(stroke
				(width 0.1)
				(type default)
			)
			(layer "F.Fab")
		)
		(fp_line
			(start -0.12065 -0.2794)
			(end 0.12065 -0.2794)
			(stroke
				(width 0.1)
				(type default)
			)
			(layer "F.Fab")
		)
		(fp_line
			(start -0.12065 -0.305054)
			(end -0.12065 -0.2794)
			(stroke
				(width 0.1)
				(type default)
			)
			(layer "F.Fab")
		)
		(fp_line
			(start -0.67945 0.3048)
			(end -0.67945 -0.305054)
			(stroke
				(width 0.1)
				(type default)
			)
			(layer "F.Fab")
		)
		(fp_line
			(start -0.67945 -0.305054)
			(end -0.12065 -0.305054)
			(stroke
				(width 0.1)
				(type default)
			)
			(layer "F.Fab")
		)
		(pad "1" smd circle
			(at -0.40005 0 180)
			(size 0 0)
			(layers "F.Cu" "F.Mask" "F.Paste")
			(net "P0V8_PEX2_VSEN2")
		)
		(pad "2" smd circle
			(at 0.40005 0 180)
			(size 0 0)
			(layers "F.Cu" "F.Mask" "F.Paste")
			(net "SH_P0V8_PEX2_RGND2")
		)
	)
	(footprint ""
		(layer "F.Cu")
		(at 106.385106 -380.098808 90)
		(property "Reference" "R6731"
			(at 0 0 90)
			(layer "F.SilkS")
			(hide yes)
			(effects
				(font
					(size 1.27 1.27)
				)
			)
		)
		(property "Value" ""
			(at 0 0 90)
			(layer "F.Fab")
			(effects
				(font
					(size 1.27 1.27)
				)
			)
		)
		(duplicate_pad_numbers_are_jumpers no)
		(fp_line
			(start 0.7874 -0.4064)
			(end 0.7874 0.4064)
			(stroke
				(width 0.1524)
				(type default)
			)
			(layer "F.SilkS")
		)
		(fp_line
			(start -0.7874 -0.4064)
			(end 0.03429 -0.4064)
			(stroke
				(width 0.1524)
				(type default)
			)
			(layer "F.SilkS")
		)
		(fp_line
			(start 0.7874 0.4064)
			(end -0.7874 0.4064)
			(stroke
				(width 0.1524)
				(type default)
			)
			(layer "F.SilkS")
		)
		(fp_line
			(start -0.12065 -0.305054)
			(end -0.12065 -0.2794)
			(stroke
				(width 0.1)
				(type default)
			)
			(layer "F.Fab")
		)
		(fp_line
			(start -0.67945 -0.305054)
			(end -0.12065 -0.305054)
			(stroke
				(width 0.1)
				(type default)
			)
			(layer "F.Fab")
		)
		(fp_line
			(start 0.67945 -0.3048)
			(end 0.67945 0.3048)
			(stroke
				(width 0.1)
				(type default)
			)
			(layer "F.Fab")
		)
		(fp_line
			(start 0.12065 -0.3048)
			(end 0.67945 -0.3048)
			(stroke
				(width 0.1)
				(type default)
			)
			(layer "F.Fab")
		)
		(fp_line
			(start 0.12065 -0.2794)
			(end 0.12065 -0.3048)
			(stroke
				(width 0.1)
				(type default)
			)
			(layer "F.Fab")
		)
		(fp_line
			(start -0.12065 -0.2794)
			(end 0.12065 -0.2794)
			(stroke
				(width 0.1)
				(type default)
			)
			(layer "F.Fab")
		)
		(fp_line
			(start 0.120396 0.2794)
			(end -0.12065 0.2794)
			(stroke
				(width 0.1)
				(type default)
			)
			(layer "F.Fab")
		)
		(fp_line
			(start -0.12065 0.2794)
			(end -0.12065 0.3048)
			(stroke
				(width 0.1)
				(type default)
			)
			(layer "F.Fab")
		)
		(fp_line
			(start 0.67945 0.3048)
			(end 0.120396 0.3048)
			(stroke
				(width 0.1)
				(type default)
			)
			(layer "F.Fab")
		)
		(fp_line
			(start 0.120396 0.3048)
			(end 0.120396 0.2794)
			(stroke
				(width 0.1)
				(type default)
			)
			(layer "F.Fab")
		)
		(fp_line
			(start -0.12065 0.3048)
			(end -0.67945 0.3048)
			(stroke
				(width 0.1)
				(type default)
			)
			(layer "F.Fab")
		)
		(fp_line
			(start -0.67945 0.3048)
			(end -0.67945 -0.305054)
			(stroke
				(width 0.1)
				(type default)
			)
			(layer "F.Fab")
		)
		(pad "1" smd rect
			(at -0.40005 0 270)
			(size 0.4572 0.508)
			(layers "F.Cu" "F.Mask" "F.Paste")
			(net "USB2_BIC_USB8042_DP")
		)
		(pad "2" smd rect
			(at 0.40005 0 270)
			(size 0.4572 0.508)
			(layers "F.Cu" "F.Mask" "F.Paste")
			(net "USB2_BIC_DP")
		)
	)
	(footprint ""
		(layer "F.Cu")
		(at 221.251272 -143.942562)
		(property "Reference" "R4206"
			(at 0 0 0)
			(layer "F.SilkS")
			(hide yes)
			(effects
				(font
					(size 1.27 1.27)
				)
			)
		)
		(property "Value" ""
			(at 0 0 0)
			(layer "F.Fab")
			(effects
				(font
					(size 1.27 1.27)
				)
			)
		)
		(duplicate_pad_numbers_are_jumpers no)
		(fp_line
			(start -0.7874 -0.4064)
			(end 0.7874 -0.4064)
			(stroke
				(width 0.1524)
				(type default)
			)
			(layer "F.SilkS")
		)
		(fp_line
			(start -0.7874 0.4064)
			(end -0.7874 -0.4064)
			(stroke
				(width 0.1524)
				(type default)
			)
			(layer "F.SilkS")
		)
		(fp_line
			(start 0.7874 -0.4064)
			(end 0.7874 0.4064)
			(stroke
				(width 0.1524)
				(type default)
			)
			(layer "F.SilkS")
		)
		(fp_line
			(start 0.7874 0.4064)
			(end -0.7874 0.4064)
			(stroke
				(width 0.1524)
				(type default)
			)
			(layer "F.SilkS")
		)
		(fp_line
			(start -0.67945 -0.305054)
			(end -0.12065 -0.305054)
			(stroke
				(width 0.1)
				(type default)
			)
			(layer "F.Fab")
		)
		(fp_line
			(start -0.67945 0.3048)
			(end -0.67945 -0.305054)
			(stroke
				(width 0.1)
				(type default)
			)
			(layer "F.Fab")
		)
		(fp_line
			(start -0.12065 -0.305054)
			(end -0.12065 -0.2794)
			(stroke
				(width 0.1)
				(type default)
			)
			(layer "F.Fab")
		)
		(fp_line
			(start -0.12065 -0.2794)
			(end 0.12065 -0.2794)
			(stroke
				(width 0.1)
				(type default)
			)
			(layer "F.Fab")
		)
		(fp_line
			(start -0.12065 0.2794)
			(end -0.12065 0.3048)
			(stroke
				(width 0.1)
				(type default)
			)
			(layer "F.Fab")
		)
		(fp_line
			(start -0.12065 0.3048)
			(end -0.67945 0.3048)
			(stroke
				(width 0.1)
				(type default)
			)
			(layer "F.Fab")
		)
		(fp_line
			(start 0.120396 0.2794)
			(end -0.12065 0.2794)
			(stroke
				(width 0.1)
				(type default)
			)
			(layer "F.Fab")
		)
		(fp_line
			(start 0.120396 0.3048)
			(end 0.120396 0.2794)
			(stroke
				(width 0.1)
				(type default)
			)
			(layer "F.Fab")
		)
		(fp_line
			(start 0.12065 -0.3048)
			(end 0.67945 -0.3048)
			(stroke
				(width 0.1)
				(type default)
			)
			(layer "F.Fab")
		)
		(fp_line
			(start 0.12065 -0.2794)
			(end 0.12065 -0.3048)
			(stroke
				(width 0.1)
				(type default)
			)
			(layer "F.Fab")
		)
		(fp_line
			(start 0.67945 -0.3048)
			(end 0.67945 0.3048)
			(stroke
				(width 0.1)
				(type default)
			)
			(layer "F.Fab")
		)
		(fp_line
			(start 0.67945 0.3048)
			(end 0.120396 0.3048)
			(stroke
				(width 0.1)
				(type default)
			)
			(layer "F.Fab")
		)
		(pad "1" smd circle
			(at -0.40005 0)
			(size 0 0)
			(layers "F.Cu" "F.Mask" "F.Paste")
			(net "GND")
		)
		(pad "2" smd circle
			(at 0.40005 0)
			(size 0 0)
			(layers "F.Cu" "F.Mask" "F.Paste")
			(net "PD_CK440_PEX_SBI_CLK")
		)
	)
	(footprint ""
		(layer "F.Cu")
		(at 357.965756 -232.457244)
		(property "Reference" "R4297"
			(at 0 0 0)
			(layer "F.SilkS")
			(hide yes)
			(effects
				(font
					(size 1.27 1.27)
				)
			)
		)
		(property "Value" ""
			(at 0 0 0)
			(layer "F.Fab")
			(effects
				(font
					(size 1.27 1.27)
				)
			)
		)
		(duplicate_pad_numbers_are_jumpers no)
		(fp_line
			(start -0.7874 -0.4064)
			(end 0.7874 -0.4064)
			(stroke
				(width 0.1524)
				(type default)
			)
			(layer "F.SilkS")
		)
		(fp_line
			(start -0.7874 0.4064)
			(end -0.7874 -0.4064)
			(stroke
				(width 0.1524)
				(type default)
			)
			(layer "F.SilkS")
		)
		(fp_line
			(start 0.7874 -0.4064)
			(end 0.7874 0.4064)
			(stroke
				(width 0.1524)
				(type default)
			)
			(layer "F.SilkS")
		)
		(fp_line
			(start 0.7874 0.4064)
			(end -0.7874 0.4064)
			(stroke
				(width 0.1524)
				(type default)
			)
			(layer "F.SilkS")
		)
		(fp_line
			(start -0.67945 -0.305054)
			(end -0.12065 -0.305054)
			(stroke
				(width 0.1)
				(type default)
			)
			(layer "F.Fab")
		)
		(fp_line
			(start -0.67945 0.3048)
			(end -0.67945 -0.305054)
			(stroke
				(width 0.1)
				(type default)
			)
			(layer "F.Fab")
		)
		(fp_line
			(start -0.12065 -0.305054)
			(end -0.12065 -0.2794)
			(stroke
				(width 0.1)
				(type default)
			)
			(layer "F.Fab")
		)
		(fp_line
			(start -0.12065 -0.2794)
			(end 0.12065 -0.2794)
			(stroke
				(width 0.1)
				(type default)
			)
			(layer "F.Fab")
		)
		(fp_line
			(start -0.12065 0.2794)
			(end -0.12065 0.3048)
			(stroke
				(width 0.1)
				(type default)
			)
			(layer "F.Fab")
		)
		(fp_line
			(start -0.12065 0.3048)
			(end -0.67945 0.3048)
			(stroke
				(width 0.1)
				(type default)
			)
			(layer "F.Fab")
		)
		(fp_line
			(start 0.120396 0.2794)
			(end -0.12065 0.2794)
			(stroke
				(width 0.1)
				(type default)
			)
			(layer "F.Fab")
		)
		(fp_line
			(start 0.120396 0.3048)
			(end 0.120396 0.2794)
			(stroke
				(width 0.1)
				(type default)
			)
			(layer "F.Fab")
		)
		(fp_line
			(start 0.12065 -0.3048)
			(end 0.67945 -0.3048)
			(stroke
				(width 0.1)
				(type default)
			)
			(layer "F.Fab")
		)
		(fp_line
			(start 0.12065 -0.2794)
			(end 0.12065 -0.3048)
			(stroke
				(width 0.1)
				(type default)
			)
			(layer "F.Fab")
		)
		(fp_line
			(start 0.67945 -0.3048)
			(end 0.67945 0.3048)
			(stroke
				(width 0.1)
				(type default)
			)
			(layer "F.Fab")
		)
		(fp_line
			(start 0.67945 0.3048)
			(end 0.120396 0.3048)
			(stroke
				(width 0.1)
				(type default)
			)
			(layer "F.Fab")
		)
		(pad "1" smd circle
			(at -0.40005 0)
			(size 0 0)
			(layers "F.Cu" "F.Mask" "F.Paste")
			(net "FPGA_JTAGENB")
		)
		(pad "2" smd circle
			(at 0.40005 0)
			(size 0 0)
			(layers "F.Cu" "F.Mask" "F.Paste")
			(net "GND")
		)
	)
	(footprint ""
		(layer "F.Cu")
		(at 372.901718 -240.6904 180)
		(property "Reference" "R6403"
			(at 0 0 180)
			(layer "F.SilkS")
			(hide yes)
			(effects
				(font
					(size 1.27 1.27)
				)
			)
		)
		(property "Value" ""
			(at 0 0 180)
			(layer "F.Fab")
			(effects
				(font
					(size 1.27 1.27)
				)
			)
		)
		(duplicate_pad_numbers_are_jumpers no)
		(fp_line
			(start 0.7874 0.4064)
			(end -0.7874 0.4064)
			(stroke
				(width 0.1524)
				(type default)
			)
			(layer "F.SilkS")
		)
		(fp_line
			(start 0.7874 -0.4064)
			(end 0.7874 0.4064)
			(stroke
				(width 0.1524)
				(type default)
			)
			(layer "F.SilkS")
		)
		(fp_line
			(start -0.7874 0.4064)
			(end -0.7874 -0.4064)
			(stroke
				(width 0.1524)
				(type default)
			)
			(layer "F.SilkS")
		)
		(fp_line
			(start -0.7874 -0.4064)
			(end 0.7874 -0.4064)
			(stroke
				(width 0.1524)
				(type default)
			)
			(layer "F.SilkS")
		)
		(fp_line
			(start 0.67945 0.3048)
			(end 0.120396 0.3048)
			(stroke
				(width 0.1)
				(type default)
			)
			(layer "F.Fab")
		)
		(fp_line
			(start 0.67945 -0.3048)
			(end 0.67945 0.3048)
			(stroke
				(width 0.1)
				(type default)
			)
			(layer "F.Fab")
		)
		(fp_line
			(start 0.12065 -0.2794)
			(end 0.12065 -0.3048)
			(stroke
				(width 0.1)
				(type default)
			)
			(layer "F.Fab")
		)
		(fp_line
			(start 0.12065 -0.3048)
			(end 0.67945 -0.3048)
			(stroke
				(width 0.1)
				(type default)
			)
			(layer "F.Fab")
		)
		(fp_line
			(start 0.120396 0.3048)
			(end 0.120396 0.2794)
			(stroke
				(width 0.1)
				(type default)
			)
			(layer "F.Fab")
		)
		(fp_line
			(start 0.120396 0.2794)
			(end -0.12065 0.2794)
			(stroke
				(width 0.1)
				(type default)
			)
			(layer "F.Fab")
		)
		(fp_line
			(start -0.12065 0.3048)
			(end -0.67945 0.3048)
			(stroke
				(width 0.1)
				(type default)
			)
			(layer "F.Fab")
		)
		(fp_line
			(start -0.12065 0.2794)
			(end -0.12065 0.3048)
			(stroke
				(width 0.1)
				(type default)
			)
			(layer "F.Fab")
		)
		(fp_line
			(start -0.12065 -0.2794)
			(end 0.12065 -0.2794)
			(stroke
				(width 0.1)
				(type default)
			)
			(layer "F.Fab")
		)
		(fp_line
			(start -0.12065 -0.305054)
			(end -0.12065 -0.2794)
			(stroke
				(width 0.1)
				(type default)
			)
			(layer "F.Fab")
		)
		(fp_line
			(start -0.67945 0.3048)
			(end -0.67945 -0.305054)
			(stroke
				(width 0.1)
				(type default)
			)
			(layer "F.Fab")
		)
		(fp_line
			(start -0.67945 -0.305054)
			(end -0.12065 -0.305054)
			(stroke
				(width 0.1)
				(type default)
			)
			(layer "F.Fab")
		)
		(pad "1" smd circle
			(at -0.40005 0 180)
			(size 0 0)
			(layers "F.Cu" "F.Mask" "F.Paste")
			(net "GND")
		)
		(pad "2" smd circle
			(at 0.40005 0 180)
			(size 0 0)
			(layers "F.Cu" "F.Mask" "F.Paste")
			(net "PWRGD_P12V_AUX_BUF")
		)
	)
	(footprint ""
		(layer "F.Cu")
		(at 410.12999 -171.661328 180)
		(property "Reference" "C943"
			(at 0 0 180)
			(layer "F.SilkS")
			(hide yes)
			(effects
				(font
					(size 1.27 1.27)
				)
			)
		)
		(property "Value" ""
			(at 0 0 180)
			(layer "F.Fab")
			(effects
				(font
					(size 1.27 1.27)
				)
			)
		)
		(duplicate_pad_numbers_are_jumpers no)
		(fp_line
			(start 0.7874 0.4064)
			(end -0.7874 0.4064)
			(stroke
				(width 0.1524)
				(type default)
			)
			(layer "F.SilkS")
		)
		(fp_line
			(start 0.7874 -0.4064)
			(end 0.7874 0.4064)
			(stroke
				(width 0.1524)
				(type default)
			)
			(layer "F.SilkS")
		)
		(fp_line
			(start -0.7874 0.4064)
			(end -0.7874 -0.4064)
			(stroke
				(width 0.1524)
				(type default)
			)
			(layer "F.SilkS")
		)
		(fp_line
			(start -0.7874 -0.4064)
			(end 0.7874 -0.4064)
			(stroke
				(width 0.1524)
				(type default)
			)
			(layer "F.SilkS")
		)
		(fp_line
			(start 0.67945 0.3048)
			(end 0.120396 0.3048)
			(stroke
				(width 0.1)
				(type default)
			)
			(layer "F.Fab")
		)
		(fp_line
			(start 0.67945 -0.3048)
			(end 0.67945 0.3048)
			(stroke
				(width 0.1)
				(type default)
			)
			(layer "F.Fab")
		)
		(fp_line
			(start 0.12065 -0.2794)
			(end 0.12065 -0.3048)
			(stroke
				(width 0.1)
				(type default)
			)
			(layer "F.Fab")
		)
		(fp_line
			(start 0.12065 -0.3048)
			(end 0.67945 -0.3048)
			(stroke
				(width 0.1)
				(type default)
			)
			(layer "F.Fab")
		)
		(fp_line
			(start 0.120396 0.3048)
			(end 0.120396 0.2794)
			(stroke
				(width 0.1)
				(type default)
			)
			(layer "F.Fab")
		)
		(fp_line
			(start 0.120396 0.2794)
			(end -0.12065 0.2794)
			(stroke
				(width 0.1)
				(type default)
			)
			(layer "F.Fab")
		)
		(fp_line
			(start -0.12065 0.3048)
			(end -0.67945 0.3048)
			(stroke
				(width 0.1)
				(type default)
			)
			(layer "F.Fab")
		)
		(fp_line
			(start -0.12065 0.2794)
			(end -0.12065 0.3048)
			(stroke
				(width 0.1)
				(type default)
			)
			(layer "F.Fab")
		)
		(fp_line
			(start -0.12065 -0.2794)
			(end 0.12065 -0.2794)
			(stroke
				(width 0.1)
				(type default)
			)
			(layer "F.Fab")
		)
		(fp_line
			(start -0.12065 -0.305054)
			(end -0.12065 -0.2794)
			(stroke
				(width 0.1)
				(type default)
			)
			(layer "F.Fab")
		)
		(fp_line
			(start -0.67945 0.3048)
			(end -0.67945 -0.305054)
			(stroke
				(width 0.1)
				(type default)
			)
			(layer "F.Fab")
		)
		(fp_line
			(start -0.67945 -0.305054)
			(end -0.12065 -0.305054)
			(stroke
				(width 0.1)
				(type default)
			)
			(layer "F.Fab")
		)
		(pad "1" smd circle
			(at -0.40005 0 180)
			(size 0 0)
			(layers "F.Cu" "F.Mask" "F.Paste")
			(net "P3V3_NIC6")
		)
		(pad "2" smd circle
			(at 0.40005 0 180)
			(size 0 0)
			(layers "F.Cu" "F.Mask" "F.Paste")
			(net "GND")
		)
	)
	(footprint ""
		(layer "F.Cu")
		(at 118.054628 -343.952322 90)
		(property "Reference" "C344"
			(at 0 0 90)
			(layer "F.SilkS")
			(hide yes)
			(effects
				(font
					(size 1.27 1.27)
				)
			)
		)
		(property "Value" ""
			(at 0 0 90)
			(layer "F.Fab")
			(effects
				(font
					(size 1.27 1.27)
				)
			)
		)
		(duplicate_pad_numbers_are_jumpers no)
		(fp_line
			(start 0.299974 -0.150114)
			(end 0.299974 0.150114)
			(stroke
				(width 0.1)
				(type default)
			)
			(layer "F.Fab")
		)
		(fp_line
			(start -0.299974 -0.150114)
			(end 0.299974 -0.150114)
			(stroke
				(width 0.1)
				(type default)
			)
			(layer "F.Fab")
		)
		(fp_line
			(start 0.299974 0.150114)
			(end -0.299974 0.150114)
			(stroke
				(width 0.1)
				(type default)
			)
			(layer "F.Fab")
		)
		(fp_line
			(start -0.299974 0.150114)
			(end -0.299974 -0.150114)
			(stroke
				(width 0.1)
				(type default)
			)
			(layer "F.Fab")
		)
		(pad "1" smd rect
			(at -0.2667 0 90)
			(size 0.3048 0.381)
			(layers "F.Cu" "F.Mask" "F.Paste")
			(net "P5E_PEX1_STN6_TX_DP<109>")
		)
		(pad "2" smd rect
			(at 0.2667 0 90)
			(size 0.3048 0.381)
			(layers "F.Cu" "F.Mask" "F.Paste")
			(net "P5E_PEX1_STN6_TX_C_DP<109>")
		)
	)
	(footprint ""
		(layer "F.Cu")
		(at 377.082558 -29.875734)
		(property "Reference" "PU132"
			(at -3.37058 -1.99644 90)
			(unlocked yes)
			(layer "F.SilkS")
			(effects
				(font
					(size 0.7874 0.5842)
					(thickness 0.1524)
				)
			)
		)
		(property "Value" ""
			(at 0 0 0)
			(layer "F.Fab")
			(effects
				(font
					(size 1.27 1.27)
				)
			)
		)
		(duplicate_pad_numbers_are_jumpers no)
		(fp_line
			(start -1.239774 -1.495298)
			(end 1.239774 -1.495298)
			(stroke
				(width 0.1524)
				(type default)
			)
			(layer "F.SilkS")
		)
		(fp_line
			(start -1.239774 1.495298)
			(end -1.239774 -1.495298)
			(stroke
				(width 0.1524)
				(type default)
			)
			(layer "F.SilkS")
		)
		(fp_line
			(start 1.239774 -1.495298)
			(end 1.239774 1.495298)
			(stroke
				(width 0.1524)
				(type default)
			)
			(layer "F.SilkS")
		)
		(fp_line
			(start 1.239774 1.495298)
			(end -1.239774 1.495298)
			(stroke
				(width 0.1524)
				(type default)
			)
			(layer "F.SilkS")
		)
		(fp_poly
			(pts
				(xy -2.03962 -1.238504) (xy -2.757932 -0.520192) (xy -1.68021 -0.161036)
			)
			(stroke
				(width 0)
				(type default)
			)
			(fill yes)
			(layer "F.SilkS")
		)
		(fp_line
			(start -0.8001 -1.050036)
			(end 0.8001 -1.050036)
			(stroke
				(width 0.1)
				(type default)
			)
			(layer "F.Fab")
		)
		(fp_line
			(start -0.8001 1.050036)
			(end -0.8001 -1.050036)
			(stroke
				(width 0.1)
				(type default)
			)
			(layer "F.Fab")
		)
		(fp_line
			(start 0.8001 -1.050036)
			(end 0.8001 1.050036)
			(stroke
				(width 0.1)
				(type default)
			)
			(layer "F.Fab")
		)
		(fp_line
			(start 0.8001 1.050036)
			(end -0.8001 1.050036)
			(stroke
				(width 0.1)
				(type default)
			)
			(layer "F.Fab")
		)
		(fp_poly
			(pts
				(xy -2.458974 -0.508) (xy -2.458974 0.508) (xy -1.442974 0)
			)
			(stroke
				(width 0)
				(type default)
			)
			(fill yes)
			(layer "F.Fab")
		)
		(pad "1_2" smd circle
			(at -0.374904 0 90)
			(size 0 0)
			(layers "F.Cu" "F.Mask" "F.Paste")
			(net "P3V3_AUX")
		)
		(pad "3" smd rect
			(at -0.499872 0.999998)
			(size 0.254 0.7112)
			(layers "F.Cu" "F.Mask" "F.Paste")
			(net "GND")
		)
		(pad "4" smd rect
			(at 0 0.999998)
			(size 0.254 0.7112)
			(layers "F.Cu" "F.Mask" "F.Paste")
			(net "P3V3_SSD13_CO_ILIMIT")
		)
		(pad "5" smd rect
			(at 0.499872 0.999998)
			(size 0.254 0.7112)
			(layers "F.Cu" "F.Mask" "F.Paste")
			(net "P3V3_SSD13_CO_MODE")
		)
		(pad "6_7" smd circle
			(at 0.374904 0 270)
			(size 0 0)
			(layers "F.Cu" "F.Mask" "F.Paste")
			(net "P3V3_SSD13")
		)
		(pad "8" smd rect
			(at 0.499872 -0.999998)
			(size 0.254 0.7112)
			(layers "F.Cu" "F.Mask" "F.Paste")
			(net "P3V3_SSD13_CO_GATE")
		)
		(pad "9" smd rect
			(at 0 -0.999998)
			(size 0.254 0.7112)
			(layers "F.Cu" "F.Mask" "F.Paste")
			(net "P3V3_SSD13_CO_EN")
		)
		(pad "10" smd rect
			(at -0.499872 -0.999998)
			(size 0.254 0.7112)
			(layers "F.Cu" "F.Mask" "F.Paste")
			(net "P3V3_SSD13_CO_DV_DT")
		)
	)
	(footprint ""
		(layer "F.Cu")
		(at 438.152032 -289.230816 90)
		(property "Reference" "R4002"
			(at 0 0 90)
			(layer "F.SilkS")
			(hide yes)
			(effects
				(font
					(size 1.27 1.27)
				)
			)
		)
		(property "Value" ""
			(at 0 0 90)
			(layer "F.Fab")
			(effects
				(font
					(size 1.27 1.27)
				)
			)
		)
		(duplicate_pad_numbers_are_jumpers no)
		(fp_line
			(start 0.7874 -0.4064)
			(end 0.7874 0.4064)
			(stroke
				(width 0.1524)
				(type default)
			)
			(layer "F.SilkS")
		)
		(fp_line
			(start -0.7874 -0.4064)
			(end 0.7874 -0.4064)
			(stroke
				(width 0.1524)
				(type default)
			)
			(layer "F.SilkS")
		)
		(fp_line
			(start 0.7874 0.4064)
			(end -0.7874 0.4064)
			(stroke
				(width 0.1524)
				(type default)
			)
			(layer "F.SilkS")
		)
		(fp_line
			(start -0.7874 0.4064)
			(end -0.7874 -0.4064)
			(stroke
				(width 0.1524)
				(type default)
			)
			(layer "F.SilkS")
		)
		(fp_line
			(start -0.12065 -0.305054)
			(end -0.12065 -0.2794)
			(stroke
				(width 0.1)
				(type default)
			)
			(layer "F.Fab")
		)
		(fp_line
			(start -0.67945 -0.305054)
			(end -0.12065 -0.305054)
			(stroke
				(width 0.1)
				(type default)
			)
			(layer "F.Fab")
		)
		(fp_line
			(start 0.67945 -0.3048)
			(end 0.67945 0.3048)
			(stroke
				(width 0.1)
				(type default)
			)
			(layer "F.Fab")
		)
		(fp_line
			(start 0.12065 -0.3048)
			(end 0.67945 -0.3048)
			(stroke
				(width 0.1)
				(type default)
			)
			(layer "F.Fab")
		)
		(fp_line
			(start 0.12065 -0.2794)
			(end 0.12065 -0.3048)
			(stroke
				(width 0.1)
				(type default)
			)
			(layer "F.Fab")
		)
		(fp_line
			(start -0.12065 -0.2794)
			(end 0.12065 -0.2794)
			(stroke
				(width 0.1)
				(type default)
			)
			(layer "F.Fab")
		)
		(fp_line
			(start 0.120396 0.2794)
			(end -0.12065 0.2794)
			(stroke
				(width 0.1)
				(type default)
			)
			(layer "F.Fab")
		)
		(fp_line
			(start -0.12065 0.2794)
			(end -0.12065 0.3048)
			(stroke
				(width 0.1)
				(type default)
			)
			(layer "F.Fab")
		)
		(fp_line
			(start 0.67945 0.3048)
			(end 0.120396 0.3048)
			(stroke
				(width 0.1)
				(type default)
			)
			(layer "F.Fab")
		)
		(fp_line
			(start 0.120396 0.3048)
			(end 0.120396 0.2794)
			(stroke
				(width 0.1)
				(type default)
			)
			(layer "F.Fab")
		)
		(fp_line
			(start -0.12065 0.3048)
			(end -0.67945 0.3048)
			(stroke
				(width 0.1)
				(type default)
			)
			(layer "F.Fab")
		)
		(fp_line
			(start -0.67945 0.3048)
			(end -0.67945 -0.305054)
			(stroke
				(width 0.1)
				(type default)
			)
			(layer "F.Fab")
		)
		(pad "1" smd circle
			(at -0.40005 0 90)
			(size 0 0)
			(layers "F.Cu" "F.Mask" "F.Paste")
			(net "SMB_PEX3_PCA9555_SDA")
		)
		(pad "2" smd circle
			(at 0.40005 0 90)
			(size 0 0)
			(layers "F.Cu" "F.Mask" "F.Paste")
			(net "SMB_PEX3_HOST_LS_SDA")
		)
	)
	(footprint ""
		(layer "F.Cu")
		(at 63.6778 -115.283742 180)
		(property "Reference" "R88"
			(at 0 0 180)
			(layer "F.SilkS")
			(hide yes)
			(effects
				(font
					(size 1.27 1.27)
				)
			)
		)
		(property "Value" ""
			(at 0 0 180)
			(layer "F.Fab")
			(effects
				(font
					(size 1.27 1.27)
				)
			)
		)
		(duplicate_pad_numbers_are_jumpers no)
		(fp_line
			(start 0.7874 0.4064)
			(end -0.7874 0.4064)
			(stroke
				(width 0.1524)
				(type default)
			)
			(layer "F.SilkS")
		)
		(fp_line
			(start 0.7874 -0.4064)
			(end 0.7874 0.4064)
			(stroke
				(width 0.1524)
				(type default)
			)
			(layer "F.SilkS")
		)
		(fp_line
			(start -0.7874 0.4064)
			(end -0.7874 -0.4064)
			(stroke
				(width 0.1524)
				(type default)
			)
			(layer "F.SilkS")
		)
		(fp_line
			(start -0.7874 -0.4064)
			(end 0.7874 -0.4064)
			(stroke
				(width 0.1524)
				(type default)
			)
			(layer "F.SilkS")
		)
		(fp_line
			(start 0.67945 0.3048)
			(end 0.120396 0.3048)
			(stroke
				(width 0.1)
				(type default)
			)
			(layer "F.Fab")
		)
		(fp_line
			(start 0.67945 -0.3048)
			(end 0.67945 0.3048)
			(stroke
				(width 0.1)
				(type default)
			)
			(layer "F.Fab")
		)
		(fp_line
			(start 0.12065 -0.2794)
			(end 0.12065 -0.3048)
			(stroke
				(width 0.1)
				(type default)
			)
			(layer "F.Fab")
		)
		(fp_line
			(start 0.12065 -0.3048)
			(end 0.67945 -0.3048)
			(stroke
				(width 0.1)
				(type default)
			)
			(layer "F.Fab")
		)
		(fp_line
			(start 0.120396 0.3048)
			(end 0.120396 0.2794)
			(stroke
				(width 0.1)
				(type default)
			)
			(layer "F.Fab")
		)
		(fp_line
			(start 0.120396 0.2794)
			(end -0.12065 0.2794)
			(stroke
				(width 0.1)
				(type default)
			)
			(layer "F.Fab")
		)
		(fp_line
			(start -0.12065 0.3048)
			(end -0.67945 0.3048)
			(stroke
				(width 0.1)
				(type default)
			)
			(layer "F.Fab")
		)
		(fp_line
			(start -0.12065 0.2794)
			(end -0.12065 0.3048)
			(stroke
				(width 0.1)
				(type default)
			)
			(layer "F.Fab")
		)
		(fp_line
			(start -0.12065 -0.2794)
			(end 0.12065 -0.2794)
			(stroke
				(width 0.1)
				(type default)
			)
			(layer "F.Fab")
		)
		(fp_line
			(start -0.12065 -0.305054)
			(end -0.12065 -0.2794)
			(stroke
				(width 0.1)
				(type default)
			)
			(layer "F.Fab")
		)
		(fp_line
			(start -0.67945 0.3048)
			(end -0.67945 -0.305054)
			(stroke
				(width 0.1)
				(type default)
			)
			(layer "F.Fab")
		)
		(fp_line
			(start -0.67945 -0.305054)
			(end -0.12065 -0.305054)
			(stroke
				(width 0.1)
				(type default)
			)
			(layer "F.Fab")
		)
		(pad "1" smd circle
			(at -0.40005 0 180)
			(size 0 0)
			(layers "F.Cu" "F.Mask" "F.Paste")
			(net "RST_SMB_NIC1_MUX_ISO_R_N")
		)
		(pad "2" smd circle
			(at 0.40005 0 180)
			(size 0 0)
			(layers "F.Cu" "F.Mask" "F.Paste")
			(net "RST_SMB_NIC1_MUX_ISO_N")
		)
	)
	(footprint ""
		(layer "F.Cu")
		(at 410.932122 -169.040302 -90)
		(property "Reference" "U42"
			(at 0.333502 2.295652 90)
			(unlocked yes)
			(layer "F.SilkS")
			(effects
				(font
					(size 0.7874 0.5842)
					(thickness 0.1524)
				)
			)
		)
		(property "Value" ""
			(at 0 0 270)
			(layer "F.Fab")
			(effects
				(font
					(size 1.27 1.27)
				)
			)
		)
		(duplicate_pad_numbers_are_jumpers no)
		(fp_line
			(start -1.905 1.651)
			(end -1.905 -1.651)
			(stroke
				(width 0.1524)
				(type default)
			)
			(layer "F.SilkS")
		)
		(fp_line
			(start 1.905 1.651)
			(end -1.905 1.651)
			(stroke
				(width 0.1524)
				(type default)
			)
			(layer "F.SilkS")
		)
		(fp_line
			(start -1.905 -1.651)
			(end 1.905 -1.651)
			(stroke
				(width 0.1524)
				(type default)
			)
			(layer "F.SilkS")
		)
		(fp_line
			(start 1.905 -1.651)
			(end 1.905 1.651)
			(stroke
				(width 0.1524)
				(type default)
			)
			(layer "F.SilkS")
		)
		(fp_line
			(start -0.649986 1.524)
			(end -0.649986 1.169924)
			(stroke
				(width 0.1)
				(type default)
			)
			(layer "F.Fab")
		)
		(fp_line
			(start 0.6985 1.524)
			(end -0.649986 1.524)
			(stroke
				(width 0.1)
				(type default)
			)
			(layer "F.Fab")
		)
		(fp_line
			(start -1.249934 1.169924)
			(end -1.249934 0.729996)
			(stroke
				(width 0.1)
				(type default)
			)
			(layer "F.Fab")
		)
		(fp_line
			(start -0.649986 1.169924)
			(end -1.249934 1.169924)
			(stroke
				(width 0.1)
				(type default)
			)
			(layer "F.Fab")
		)
		(fp_line
			(start -1.249934 0.729996)
			(end -0.6985 0.729996)
			(stroke
				(width 0.1)
				(type default)
			)
			(layer "F.Fab")
		)
		(fp_line
			(start -0.6985 0.729996)
			(end -0.6985 -0.729996)
			(stroke
				(width 0.1)
				(type default)
			)
			(layer "F.Fab")
		)
		(fp_line
			(start 0.6985 0.219964)
			(end 0.6985 1.524)
			(stroke
				(width 0.1)
				(type default)
			)
			(layer "F.Fab")
		)
		(fp_line
			(start 1.249934 0.219964)
			(end 0.6985 0.219964)
			(stroke
				(width 0.1)
				(type default)
			)
			(layer "F.Fab")
		)
		(fp_line
			(start 0.6985 -0.219964)
			(end 1.249934 -0.219964)
			(stroke
				(width 0.1)
				(type default)
			)
			(layer "F.Fab")
		)
		(fp_line
			(start 1.249934 -0.219964)
			(end 1.249934 0.219964)
			(stroke
				(width 0.1)
				(type default)
			)
			(layer "F.Fab")
		)
		(fp_line
			(start -1.249934 -0.729996)
			(end -1.249934 -1.169924)
			(stroke
				(width 0.1)
				(type default)
			)
			(layer "F.Fab")
		)
		(fp_line
			(start -0.6985 -0.729996)
			(end -1.249934 -0.729996)
			(stroke
				(width 0.1)
				(type default)
			)
			(layer "F.Fab")
		)
		(fp_line
			(start -1.249934 -1.169924)
			(end -0.649986 -1.169924)
			(stroke
				(width 0.1)
				(type default)
			)
			(layer "F.Fab")
		)
		(fp_line
			(start -0.649986 -1.169924)
			(end -0.649986 -1.524)
			(stroke
				(width 0.1)
				(type default)
			)
			(layer "F.Fab")
		)
		(fp_line
			(start -0.649986 -1.524)
			(end 0.6985 -1.524)
			(stroke
				(width 0.1)
				(type default)
			)
			(layer "F.Fab")
		)
		(fp_line
			(start 0.6985 -1.524)
			(end 0.6985 -0.219964)
			(stroke
				(width 0.1)
				(type default)
			)
			(layer "F.Fab")
		)
		(pad "1" smd rect
			(at -1.1176 -1.016 180)
			(size 1.016 1.27)
			(layers "F.Cu" "F.Mask" "F.Paste")
			(net "HP_NIC6_PWRGD")
		)
		(pad "2" smd rect
			(at -1.1176 1.016 180)
			(size 1.016 1.27)
			(layers "F.Cu" "F.Mask" "F.Paste")
			(net "P3V3_NIC6")
		)
		(pad "3" smd rect
			(at 1.1176 0 180)
			(size 1.016 1.27)
			(layers "F.Cu" "F.Mask" "F.Paste")
			(net "GND")
		)
	)
	(footprint ""
		(layer "F.Cu")
		(at 144.975326 -63.086234)
		(property "Reference" "R5979"
			(at 0 0 0)
			(layer "F.SilkS")
			(hide yes)
			(effects
				(font
					(size 1.27 1.27)
				)
			)
		)
		(property "Value" ""
			(at 0 0 0)
			(layer "F.Fab")
			(effects
				(font
					(size 1.27 1.27)
				)
			)
		)
		(duplicate_pad_numbers_are_jumpers no)
		(fp_line
			(start -0.7874 -0.4064)
			(end 0.7874 -0.4064)
			(stroke
				(width 0.1524)
				(type default)
			)
			(layer "F.SilkS")
		)
		(fp_line
			(start -0.7874 0.4064)
			(end -0.7874 -0.4064)
			(stroke
				(width 0.1524)
				(type default)
			)
			(layer "F.SilkS")
		)
		(fp_line
			(start 0.7874 -0.4064)
			(end 0.7874 0.4064)
			(stroke
				(width 0.1524)
				(type default)
			)
			(layer "F.SilkS")
		)
		(fp_line
			(start 0.7874 0.4064)
			(end -0.7874 0.4064)
			(stroke
				(width 0.1524)
				(type default)
			)
			(layer "F.SilkS")
		)
		(fp_line
			(start -0.67945 -0.305054)
			(end -0.12065 -0.305054)
			(stroke
				(width 0.1)
				(type default)
			)
			(layer "F.Fab")
		)
		(fp_line
			(start -0.67945 0.3048)
			(end -0.67945 -0.305054)
			(stroke
				(width 0.1)
				(type default)
			)
			(layer "F.Fab")
		)
		(fp_line
			(start -0.12065 -0.305054)
			(end -0.12065 -0.2794)
			(stroke
				(width 0.1)
				(type default)
			)
			(layer "F.Fab")
		)
		(fp_line
			(start -0.12065 -0.2794)
			(end 0.12065 -0.2794)
			(stroke
				(width 0.1)
				(type default)
			)
			(layer "F.Fab")
		)
		(fp_line
			(start -0.12065 0.2794)
			(end -0.12065 0.3048)
			(stroke
				(width 0.1)
				(type default)
			)
			(layer "F.Fab")
		)
		(fp_line
			(start -0.12065 0.3048)
			(end -0.67945 0.3048)
			(stroke
				(width 0.1)
				(type default)
			)
			(layer "F.Fab")
		)
		(fp_line
			(start 0.120396 0.2794)
			(end -0.12065 0.2794)
			(stroke
				(width 0.1)
				(type default)
			)
			(layer "F.Fab")
		)
		(fp_line
			(start 0.120396 0.3048)
			(end 0.120396 0.2794)
			(stroke
				(width 0.1)
				(type default)
			)
			(layer "F.Fab")
		)
		(fp_line
			(start 0.12065 -0.3048)
			(end 0.67945 -0.3048)
			(stroke
				(width 0.1)
				(type default)
			)
			(layer "F.Fab")
		)
		(fp_line
			(start 0.12065 -0.2794)
			(end 0.12065 -0.3048)
			(stroke
				(width 0.1)
				(type default)
			)
			(layer "F.Fab")
		)
		(fp_line
			(start 0.67945 -0.3048)
			(end 0.67945 0.3048)
			(stroke
				(width 0.1)
				(type default)
			)
			(layer "F.Fab")
		)
		(fp_line
			(start 0.67945 0.3048)
			(end 0.120396 0.3048)
			(stroke
				(width 0.1)
				(type default)
			)
			(layer "F.Fab")
		)
		(pad "1" smd circle
			(at -0.40005 0)
			(size 0 0)
			(layers "F.Cu" "F.Mask" "F.Paste")
			(net "P12V_SSD5_R")
		)
		(pad "2" smd circle
			(at 0.40005 0)
			(size 0 0)
			(layers "F.Cu" "F.Mask" "F.Paste")
			(net "P12V_SSD5_PG_G1")
		)
	)
	(footprint ""
		(layer "F.Cu")
		(at 143.486886 -307.803296 -135)
		(property "Reference" "R1262"
			(at 0 0 225)
			(layer "F.SilkS")
			(hide yes)
			(effects
				(font
					(size 1.27 1.27)
				)
			)
		)
		(property "Value" ""
			(at 0 0 225)
			(layer "F.Fab")
			(effects
				(font
					(size 1.27 1.27)
				)
			)
		)
		(duplicate_pad_numbers_are_jumpers no)
		(fp_line
			(start 0.787389 0.406267)
			(end -0.787389 0.406267)
			(stroke
				(width 0.1524)
				(type default)
			)
			(layer "F.SilkS")
		)
		(fp_line
			(start 0.787389 -0.406267)
			(end 0.787389 0.406267)
			(stroke
				(width 0.1524)
				(type default)
			)
			(layer "F.SilkS")
		)
		(fp_line
			(start -0.787389 0.406267)
			(end -0.787389 -0.406267)
			(stroke
				(width 0.1524)
				(type default)
			)
			(layer "F.SilkS")
		)
		(fp_line
			(start -0.787389 -0.406267)
			(end 0.787389 -0.406267)
			(stroke
				(width 0.1524)
				(type default)
			)
			(layer "F.SilkS")
		)
		(fp_line
			(start 0.679446 0.30479)
			(end 0.120515 0.30479)
			(stroke
				(width 0.1)
				(type default)
			)
			(layer "F.Fab")
		)
		(fp_line
			(start 0.120515 0.30479)
			(end 0.120335 0.279466)
			(stroke
				(width 0.1)
				(type default)
			)
			(layer "F.Fab")
		)
		(fp_line
			(start 0.120335 0.279466)
			(end -0.120695 0.279466)
			(stroke
				(width 0.1)
				(type default)
			)
			(layer "F.Fab")
		)
		(fp_line
			(start 0.679446 -0.30479)
			(end 0.679446 0.30479)
			(stroke
				(width 0.1)
				(type default)
			)
			(layer "F.Fab")
		)
		(fp_line
			(start -0.120515 0.30479)
			(end -0.679446 0.30479)
			(stroke
				(width 0.1)
				(type default)
			)
			(layer "F.Fab")
		)
		(fp_line
			(start -0.120695 0.279466)
			(end -0.120515 0.30479)
			(stroke
				(width 0.1)
				(type default)
			)
			(layer "F.Fab")
		)
		(fp_line
			(start 0.120695 -0.279466)
			(end 0.120515 -0.30479)
			(stroke
				(width 0.1)
				(type default)
			)
			(layer "F.Fab")
		)
		(fp_line
			(start 0.120515 -0.30479)
			(end 0.679446 -0.30479)
			(stroke
				(width 0.1)
				(type default)
			)
			(layer "F.Fab")
		)
		(fp_line
			(start -0.679446 0.30479)
			(end -0.679446 -0.305149)
			(stroke
				(width 0.1)
				(type default)
			)
			(layer "F.Fab")
		)
		(fp_line
			(start -0.120695 -0.279466)
			(end 0.120695 -0.279466)
			(stroke
				(width 0.1)
				(type default)
			)
			(layer "F.Fab")
		)
		(fp_line
			(start -0.120695 -0.304969)
			(end -0.120695 -0.279466)
			(stroke
				(width 0.1)
				(type default)
			)
			(layer "F.Fab")
		)
		(fp_line
			(start -0.679446 -0.305149)
			(end -0.120695 -0.304969)
			(stroke
				(width 0.1)
				(type default)
			)
			(layer "F.Fab")
		)
		(pad "1" smd circle
			(at -0.40005 0 225)
			(size 0 0)
			(layers "F.Cu" "F.Mask" "F.Paste")
			(net "PEX1_DBG_SEL0")
		)
		(pad "2" smd circle
			(at 0.40005 0 225)
			(size 0 0)
			(layers "F.Cu" "F.Mask" "F.Paste")
			(net "P1V8_PEX")
		)
	)
	(footprint ""
		(layer "F.Cu")
		(at 53.126132 -39.73576 -90)
		(property "Reference" "R5545"
			(at 0 0 270)
			(layer "F.SilkS")
			(hide yes)
			(effects
				(font
					(size 1.27 1.27)
				)
			)
		)
		(property "Value" ""
			(at 0 0 270)
			(layer "F.Fab")
			(effects
				(font
					(size 1.27 1.27)
				)
			)
		)
		(duplicate_pad_numbers_are_jumpers no)
		(fp_line
			(start -0.7874 0.4064)
			(end -0.7874 -0.4064)
			(stroke
				(width 0.1524)
				(type default)
			)
			(layer "F.SilkS")
		)
		(fp_line
			(start 0.7874 0.4064)
			(end -0.7874 0.4064)
			(stroke
				(width 0.1524)
				(type default)
			)
			(layer "F.SilkS")
		)
		(fp_line
			(start -0.7874 -0.4064)
			(end 0.7874 -0.4064)
			(stroke
				(width 0.1524)
				(type default)
			)
			(layer "F.SilkS")
		)
		(fp_line
			(start 0.7874 -0.4064)
			(end 0.7874 0.4064)
			(stroke
				(width 0.1524)
				(type default)
			)
			(layer "F.SilkS")
		)
		(fp_line
			(start -0.67945 0.3048)
			(end -0.67945 -0.305054)
			(stroke
				(width 0.1)
				(type default)
			)
			(layer "F.Fab")
		)
		(fp_line
			(start -0.12065 0.3048)
			(end -0.67945 0.3048)
			(stroke
				(width 0.1)
				(type default)
			)
			(layer "F.Fab")
		)
		(fp_line
			(start 0.120396 0.3048)
			(end 0.120396 0.2794)
			(stroke
				(width 0.1)
				(type default)
			)
			(layer "F.Fab")
		)
		(fp_line
			(start 0.67945 0.3048)
			(end 0.120396 0.3048)
			(stroke
				(width 0.1)
				(type default)
			)
			(layer "F.Fab")
		)
		(fp_line
			(start -0.12065 0.2794)
			(end -0.12065 0.3048)
			(stroke
				(width 0.1)
				(type default)
			)
			(layer "F.Fab")
		)
		(fp_line
			(start 0.120396 0.2794)
			(end -0.12065 0.2794)
			(stroke
				(width 0.1)
				(type default)
			)
			(layer "F.Fab")
		)
		(fp_line
			(start -0.12065 -0.2794)
			(end 0.12065 -0.2794)
			(stroke
				(width 0.1)
				(type default)
			)
			(layer "F.Fab")
		)
		(fp_line
			(start 0.12065 -0.2794)
			(end 0.12065 -0.3048)
			(stroke
				(width 0.1)
				(type default)
			)
			(layer "F.Fab")
		)
		(fp_line
			(start 0.12065 -0.3048)
			(end 0.67945 -0.3048)
			(stroke
				(width 0.1)
				(type default)
			)
			(layer "F.Fab")
		)
		(fp_line
			(start 0.67945 -0.3048)
			(end 0.67945 0.3048)
			(stroke
				(width 0.1)
				(type default)
			)
			(layer "F.Fab")
		)
		(fp_line
			(start -0.67945 -0.305054)
			(end -0.12065 -0.305054)
			(stroke
				(width 0.1)
				(type default)
			)
			(layer "F.Fab")
		)
		(fp_line
			(start -0.12065 -0.305054)
			(end -0.12065 -0.2794)
			(stroke
				(width 0.1)
				(type default)
			)
			(layer "F.Fab")
		)
		(pad "1" smd circle
			(at -0.40005 0 270)
			(size 0 0)
			(layers "F.Cu" "F.Mask" "F.Paste")
			(net "P3V3_AUX")
		)
		(pad "2" smd circle
			(at 0.40005 0 270)
			(size 0 0)
			(layers "F.Cu" "F.Mask" "F.Paste")
			(net "SSD2_AUX_P3V3_EN")
		)
	)
	(footprint ""
		(layer "F.Cu")
		(at 419.510972 -350.098614 90)
		(property "Reference" "C817"
			(at 0 0 90)
			(layer "F.SilkS")
			(hide yes)
			(effects
				(font
					(size 1.27 1.27)
				)
			)
		)
		(property "Value" ""
			(at 0 0 90)
			(layer "F.Fab")
			(effects
				(font
					(size 1.27 1.27)
				)
			)
		)
		(duplicate_pad_numbers_are_jumpers no)
		(fp_line
			(start 0.299974 -0.150114)
			(end 0.299974 0.150114)
			(stroke
				(width 0.1)
				(type default)
			)
			(layer "F.Fab")
		)
		(fp_line
			(start -0.299974 -0.150114)
			(end 0.299974 -0.150114)
			(stroke
				(width 0.1)
				(type default)
			)
			(layer "F.Fab")
		)
		(fp_line
			(start 0.299974 0.150114)
			(end -0.299974 0.150114)
			(stroke
				(width 0.1)
				(type default)
			)
			(layer "F.Fab")
		)
		(fp_line
			(start -0.299974 0.150114)
			(end -0.299974 -0.150114)
			(stroke
				(width 0.1)
				(type default)
			)
			(layer "F.Fab")
		)
		(pad "1" smd rect
			(at -0.2667 0 90)
			(size 0.3048 0.381)
			(layers "F.Cu" "F.Mask" "F.Paste")
			(net "P5E_PEX3_STN7_TX_DN<116>")
		)
		(pad "2" smd rect
			(at 0.2667 0 90)
			(size 0.3048 0.381)
			(layers "F.Cu" "F.Mask" "F.Paste")
			(net "P5E_PEX3_STN7_TX_C_DN<116>")
		)
	)
	(footprint ""
		(layer "F.Cu")
		(at 310.443626 -46.90491)
		(property "Reference" "R618"
			(at 0 0 0)
			(layer "F.SilkS")
			(hide yes)
			(effects
				(font
					(size 1.27 1.27)
				)
			)
		)
		(property "Value" ""
			(at 0 0 0)
			(layer "F.Fab")
			(effects
				(font
					(size 1.27 1.27)
				)
			)
		)
		(duplicate_pad_numbers_are_jumpers no)
		(fp_line
			(start -0.7874 -0.4064)
			(end 0.7874 -0.4064)
			(stroke
				(width 0.1524)
				(type default)
			)
			(layer "F.SilkS")
		)
		(fp_line
			(start -0.7874 0.4064)
			(end -0.7874 -0.4064)
			(stroke
				(width 0.1524)
				(type default)
			)
			(layer "F.SilkS")
		)
		(fp_line
			(start 0.7874 -0.4064)
			(end 0.7874 0.4064)
			(stroke
				(width 0.1524)
				(type default)
			)
			(layer "F.SilkS")
		)
		(fp_line
			(start 0.7874 0.4064)
			(end -0.7874 0.4064)
			(stroke
				(width 0.1524)
				(type default)
			)
			(layer "F.SilkS")
		)
		(fp_line
			(start -0.67945 -0.305054)
			(end -0.12065 -0.305054)
			(stroke
				(width 0.1)
				(type default)
			)
			(layer "F.Fab")
		)
		(fp_line
			(start -0.67945 0.3048)
			(end -0.67945 -0.305054)
			(stroke
				(width 0.1)
				(type default)
			)
			(layer "F.Fab")
		)
		(fp_line
			(start -0.12065 -0.305054)
			(end -0.12065 -0.2794)
			(stroke
				(width 0.1)
				(type default)
			)
			(layer "F.Fab")
		)
		(fp_line
			(start -0.12065 -0.2794)
			(end 0.12065 -0.2794)
			(stroke
				(width 0.1)
				(type default)
			)
			(layer "F.Fab")
		)
		(fp_line
			(start -0.12065 0.2794)
			(end -0.12065 0.3048)
			(stroke
				(width 0.1)
				(type default)
			)
			(layer "F.Fab")
		)
		(fp_line
			(start -0.12065 0.3048)
			(end -0.67945 0.3048)
			(stroke
				(width 0.1)
				(type default)
			)
			(layer "F.Fab")
		)
		(fp_line
			(start 0.120396 0.2794)
			(end -0.12065 0.2794)
			(stroke
				(width 0.1)
				(type default)
			)
			(layer "F.Fab")
		)
		(fp_line
			(start 0.120396 0.3048)
			(end 0.120396 0.2794)
			(stroke
				(width 0.1)
				(type default)
			)
			(layer "F.Fab")
		)
		(fp_line
			(start 0.12065 -0.3048)
			(end 0.67945 -0.3048)
			(stroke
				(width 0.1)
				(type default)
			)
			(layer "F.Fab")
		)
		(fp_line
			(start 0.12065 -0.2794)
			(end 0.12065 -0.3048)
			(stroke
				(width 0.1)
				(type default)
			)
			(layer "F.Fab")
		)
		(fp_line
			(start 0.67945 -0.3048)
			(end 0.67945 0.3048)
			(stroke
				(width 0.1)
				(type default)
			)
			(layer "F.Fab")
		)
		(fp_line
			(start 0.67945 0.3048)
			(end 0.120396 0.3048)
			(stroke
				(width 0.1)
				(type default)
			)
			(layer "F.Fab")
		)
		(pad "1" smd circle
			(at -0.40005 0)
			(size 0 0)
			(layers "F.Cu" "F.Mask" "F.Paste")
			(net "SSD10_ADC_ALERT_N")
		)
		(pad "2" smd circle
			(at 0.40005 0)
			(size 0 0)
			(layers "F.Cu" "F.Mask" "F.Paste")
			(net "SSD_8_15_ADC_ALERT_N")
		)
	)
	(footprint ""
		(layer "F.Cu")
		(at 196.119242 -119.584724 180)
		(property "Reference" "C242"
			(at 0 0 180)
			(layer "F.SilkS")
			(hide yes)
			(effects
				(font
					(size 1.27 1.27)
				)
			)
		)
		(property "Value" ""
			(at 0 0 180)
			(layer "F.Fab")
			(effects
				(font
					(size 1.27 1.27)
				)
			)
		)
		(duplicate_pad_numbers_are_jumpers no)
		(fp_line
			(start 0.299974 0.150114)
			(end -0.299974 0.150114)
			(stroke
				(width 0.1)
				(type default)
			)
			(layer "F.Fab")
		)
		(fp_line
			(start 0.299974 -0.150114)
			(end 0.299974 0.150114)
			(stroke
				(width 0.1)
				(type default)
			)
			(layer "F.Fab")
		)
		(fp_line
			(start -0.299974 0.150114)
			(end -0.299974 -0.150114)
			(stroke
				(width 0.1)
				(type default)
			)
			(layer "F.Fab")
		)
		(fp_line
			(start -0.299974 -0.150114)
			(end 0.299974 -0.150114)
			(stroke
				(width 0.1)
				(type default)
			)
			(layer "F.Fab")
		)
		(pad "1" smd rect
			(at -0.2667 0 180)
			(size 0.3048 0.381)
			(layers "F.Cu" "F.Mask" "F.Paste")
			(net "P5E_PEX1_STN0_TX_DP<0>")
		)
		(pad "2" smd rect
			(at 0.2667 0 180)
			(size 0.3048 0.381)
			(layers "F.Cu" "F.Mask" "F.Paste")
			(net "P5E_PEX1_STN0_TX_C_DP<0>")
		)
	)
	(footprint ""
		(layer "F.Cu")
		(at 135.882888 -225.49993 180)
		(property "Reference" "JPEX1"
			(at -8.892286 -8.467852 0)
			(unlocked yes)
			(layer "F.SilkS")
			(effects
				(font
					(size 0.7874 0.5842)
					(thickness 0.1524)
				)
				(justify left)
			)
		)
		(property "Value" ""
			(at 0 0 180)
			(layer "F.Fab")
			(effects
				(font
					(size 1.27 1.27)
				)
			)
		)
		(duplicate_pad_numbers_are_jumpers no)
		(fp_line
			(start 12.46505 7.649972)
			(end -12.46505 7.649972)
			(stroke
				(width 0.1524)
				(type default)
			)
			(layer "F.SilkS")
		)
		(fp_line
			(start 12.46505 -7.649972)
			(end 12.46505 7.649972)
			(stroke
				(width 0.1524)
				(type default)
			)
			(layer "F.SilkS")
		)
		(fp_line
			(start 6.945122 7.649972)
			(end -6.945122 7.649972)
			(stroke
				(width 0.1524)
				(type default)
			)
			(layer "F.SilkS")
		)
		(fp_line
			(start 6.945122 -7.649972)
			(end 6.945122 7.649972)
			(stroke
				(width 0.1524)
				(type default)
			)
			(layer "F.SilkS")
		)
		(fp_line
			(start 6.945122 -7.649972)
			(end 0 -7.649972)
			(stroke
				(width 0.1524)
				(type default)
			)
			(layer "F.SilkS")
		)
		(fp_line
			(start 0 -7.649972)
			(end 12.46505 -7.649972)
			(stroke
				(width 0.1524)
				(type default)
			)
			(layer "F.SilkS")
		)
		(fp_line
			(start -6.945122 -7.649972)
			(end 0 -7.649972)
			(stroke
				(width 0.1524)
				(type default)
			)
			(layer "F.SilkS")
		)
		(fp_line
			(start -6.945122 -7.649972)
			(end -6.945122 7.649972)
			(stroke
				(width 0.1524)
				(type default)
			)
			(layer "F.SilkS")
		)
		(fp_line
			(start -12.46505 7.649972)
			(end -12.46505 -7.649972)
			(stroke
				(width 0.1524)
				(type default)
			)
			(layer "F.SilkS")
		)
		(fp_line
			(start -12.46505 -7.649972)
			(end 0 -7.649972)
			(stroke
				(width 0.1524)
				(type default)
			)
			(layer "F.SilkS")
		)
		(fp_poly
			(pts
				(xy -7.112 -4.445) (xy -8.128 -4.953) (xy -8.128 -3.937)
			)
			(stroke
				(width 0)
				(type default)
			)
			(fill yes)
			(layer "F.SilkS")
		)
		(fp_line
			(start 6.945122 7.649972)
			(end -6.945122 7.649972)
			(stroke
				(width 0.1)
				(type default)
			)
			(layer "F.Fab")
		)
		(fp_line
			(start 6.945122 -7.649972)
			(end 6.945122 7.649972)
			(stroke
				(width 0.1)
				(type default)
			)
			(layer "F.Fab")
		)
		(fp_line
			(start -6.945122 7.649972)
			(end -6.945122 -7.649972)
			(stroke
				(width 0.1)
				(type default)
			)
			(layer "F.Fab")
		)
		(fp_line
			(start -6.945122 -7.649972)
			(end 6.945122 -7.649972)
			(stroke
				(width 0.1)
				(type default)
			)
			(layer "F.Fab")
		)
		(fp_poly
			(pts
				(xy -7.112 -4.445) (xy -8.128 -4.953) (xy -8.128 -3.937)
			)
			(stroke
				(width 0)
				(type default)
			)
			(fill yes)
			(layer "F.Fab")
		)
		(fp_text user "9"
			(at 7.51713 4.1656 90)
			(unlocked yes)
			(layer "F.SilkS")
			(effects
				(font
					(size 0.7874 0.5842)
					(thickness 0.1524)
				)
				(justify left)
			)
		)
		(fp_text user "16"
			(at 7.49173 -5.2324 90)
			(unlocked yes)
			(layer "F.SilkS")
			(effects
				(font
					(size 0.7874 0.5842)
					(thickness 0.1524)
				)
				(justify left)
			)
		)
		(fp_text user "8"
			(at -7.77367 4.2164 90)
			(unlocked yes)
			(layer "F.SilkS")
			(effects
				(font
					(size 0.7874 0.5842)
					(thickness 0.1524)
				)
				(justify left)
			)
		)
		(fp_text user "9"
			(at 7.51713 4.1656 90)
			(unlocked yes)
			(layer "F.Fab")
			(effects
				(font
					(size 0.7874 0.5842)
					(thickness 0.1524)
				)
				(justify left)
			)
		)
		(fp_text user "16"
			(at 7.49173 -5.2324 90)
			(unlocked yes)
			(layer "F.Fab")
			(effects
				(font
					(size 0.7874 0.5842)
					(thickness 0.1524)
				)
				(justify left)
			)
		)
		(fp_text user "8"
			(at -7.77367 4.2164 90)
			(unlocked yes)
			(layer "F.Fab")
			(effects
				(font
					(size 0.7874 0.5842)
					(thickness 0.1524)
				)
				(justify left)
			)
		)
		(pad "1" smd rect
			(at -4.800092 -4.445 90)
			(size 0.508 1.524)
			(layers "F.Cu" "F.Mask" "F.Paste")
			(net "SPI_PEX1_SDIO3_R1")
		)
		(pad "2" smd rect
			(at -4.800092 -3.175 90)
			(size 0.508 1.524)
			(layers "F.Cu" "F.Mask" "F.Paste")
			(net "P1V8_PEX")
		)
		(pad "3" smd rect
			(at -4.800092 -1.905 90)
			(size 0.508 1.524)
			(layers "F.Cu" "F.Mask" "F.Paste")
			(net "SPI_PEX1_RST_R_N")
		)
		(pad "4" smd rect
			(at -4.800092 -0.635 90)
			(size 0.508 1.524)
			(layers "F.Cu" "F.Mask" "F.Paste")
			(net "Net_2691")
		)
		(pad "5" smd rect
			(at -4.800092 0.635 90)
			(size 0.508 1.524)
			(layers "F.Cu" "F.Mask" "F.Paste")
			(net "Net_2690")
		)
		(pad "6" smd rect
			(at -4.800092 1.905 90)
			(size 0.508 1.524)
			(layers "F.Cu" "F.Mask" "F.Paste")
			(net "Net_2689")
		)
		(pad "7" smd rect
			(at -4.800092 3.175 90)
			(size 0.508 1.524)
			(layers "F.Cu" "F.Mask" "F.Paste")
			(net "SPI_PEX1_CS_MUX_R_N")
		)
		(pad "8" smd rect
			(at -4.800092 4.445 90)
			(size 0.508 1.524)
			(layers "F.Cu" "F.Mask" "F.Paste")
			(net "SPI_PEX1_SDIO1_MUX_R")
		)
		(pad "9" smd rect
			(at 4.800092 4.445 90)
			(size 0.508 1.524)
			(layers "F.Cu" "F.Mask" "F.Paste")
			(net "SPI_PEX1_SDIO2_R1")
		)
		(pad "10" smd rect
			(at 4.800092 3.175 90)
			(size 0.508 1.524)
			(layers "F.Cu" "F.Mask" "F.Paste")
			(net "GND")
		)
		(pad "11" smd rect
			(at 4.800092 1.905 90)
			(size 0.508 1.524)
			(layers "F.Cu" "F.Mask" "F.Paste")
			(net "Net_2692")
		)
		(pad "12" smd rect
			(at 4.800092 0.635 90)
			(size 0.508 1.524)
			(layers "F.Cu" "F.Mask" "F.Paste")
			(net "Net_2693")
		)
		(pad "13" smd rect
			(at 4.800092 -0.635 90)
			(size 0.508 1.524)
			(layers "F.Cu" "F.Mask" "F.Paste")
			(net "Net_2694")
		)
		(pad "14" smd rect
			(at 4.800092 -1.905 90)
			(size 0.508 1.524)
			(layers "F.Cu" "F.Mask" "F.Paste")
			(net "Net_2695")
		)
		(pad "15" smd rect
			(at 4.800092 -3.175 90)
			(size 0.508 1.524)
			(layers "F.Cu" "F.Mask" "F.Paste")
			(net "SPI_PEX1_SDIO0_MUX_R")
		)
		(pad "16" smd rect
			(at 4.800092 -4.445 90)
			(size 0.508 1.524)
			(layers "F.Cu" "F.Mask" "F.Paste")
			(net "SPI_PEX1_CLK_MUX_R")
		)
	)
	(footprint ""
		(layer "F.Cu")
		(at 384.938524 -134.008876)
		(property "Reference" "C668"
			(at 0 0 0)
			(layer "F.SilkS")
			(hide yes)
			(effects
				(font
					(size 1.27 1.27)
				)
			)
		)
		(property "Value" ""
			(at 0 0 0)
			(layer "F.Fab")
			(effects
				(font
					(size 1.27 1.27)
				)
			)
		)
		(duplicate_pad_numbers_are_jumpers no)
		(fp_line
			(start -0.299974 -0.150114)
			(end 0.299974 -0.150114)
			(stroke
				(width 0.1)
				(type default)
			)
			(layer "F.Fab")
		)
		(fp_line
			(start -0.299974 0.150114)
			(end -0.299974 -0.150114)
			(stroke
				(width 0.1)
				(type default)
			)
			(layer "F.Fab")
		)
		(fp_line
			(start 0.299974 -0.150114)
			(end 0.299974 0.150114)
			(stroke
				(width 0.1)
				(type default)
			)
			(layer "F.Fab")
		)
		(fp_line
			(start 0.299974 0.150114)
			(end -0.299974 0.150114)
			(stroke
				(width 0.1)
				(type default)
			)
			(layer "F.Fab")
		)
		(pad "1" smd rect
			(at -0.2667 0)
			(size 0.3048 0.381)
			(layers "F.Cu" "F.Mask" "F.Paste")
			(net "P5E_PEX3_STN1_TX_DP<30>")
		)
		(pad "2" smd rect
			(at 0.2667 0)
			(size 0.3048 0.381)
			(layers "F.Cu" "F.Mask" "F.Paste")
			(net "P5E_PEX3_STN1_TX_C_DP<30>")
		)
	)
	(footprint ""
		(layer "F.Cu")
		(at 183.923432 -350.098614 90)
		(property "Reference" "C380"
			(at 0 0 90)
			(layer "F.SilkS")
			(hide yes)
			(effects
				(font
					(size 1.27 1.27)
				)
			)
		)
		(property "Value" ""
			(at 0 0 90)
			(layer "F.Fab")
			(effects
				(font
					(size 1.27 1.27)
				)
			)
		)
		(duplicate_pad_numbers_are_jumpers no)
		(fp_line
			(start 0.299974 -0.150114)
			(end 0.299974 0.150114)
			(stroke
				(width 0.1)
				(type default)
			)
			(layer "F.Fab")
		)
		(fp_line
			(start -0.299974 -0.150114)
			(end 0.299974 -0.150114)
			(stroke
				(width 0.1)
				(type default)
			)
			(layer "F.Fab")
		)
		(fp_line
			(start 0.299974 0.150114)
			(end -0.299974 0.150114)
			(stroke
				(width 0.1)
				(type default)
			)
			(layer "F.Fab")
		)
		(fp_line
			(start -0.299974 0.150114)
			(end -0.299974 -0.150114)
			(stroke
				(width 0.1)
				(type default)
			)
			(layer "F.Fab")
		)
		(pad "1" smd rect
			(at -0.2667 0 90)
			(size 0.3048 0.381)
			(layers "F.Cu" "F.Mask" "F.Paste")
			(net "P5E_PEX1_STN7_TX_DP<123>")
		)
		(pad "2" smd rect
			(at 0.2667 0 90)
			(size 0.3048 0.381)
			(layers "F.Cu" "F.Mask" "F.Paste")
			(net "P5E_PEX1_STN7_TX_C_DP<123>")
		)
	)
	(footprint ""
		(layer "F.Cu")
		(at 352.920554 -81.501234)
		(property "Reference" "R1629"
			(at 0 0 0)
			(layer "F.SilkS")
			(hide yes)
			(effects
				(font
					(size 1.27 1.27)
				)
			)
		)
		(property "Value" ""
			(at 0 0 0)
			(layer "F.Fab")
			(effects
				(font
					(size 1.27 1.27)
				)
			)
		)
		(duplicate_pad_numbers_are_jumpers no)
		(fp_line
			(start -0.7874 -0.4064)
			(end 0.7874 -0.4064)
			(stroke
				(width 0.1524)
				(type default)
			)
			(layer "F.SilkS")
		)
		(fp_line
			(start -0.7874 0.4064)
			(end -0.7874 -0.4064)
			(stroke
				(width 0.1524)
				(type default)
			)
			(layer "F.SilkS")
		)
		(fp_line
			(start 0.7874 -0.4064)
			(end 0.7874 0.4064)
			(stroke
				(width 0.1524)
				(type default)
			)
			(layer "F.SilkS")
		)
		(fp_line
			(start 0.7874 0.4064)
			(end -0.7874 0.4064)
			(stroke
				(width 0.1524)
				(type default)
			)
			(layer "F.SilkS")
		)
		(fp_line
			(start -0.67945 -0.305054)
			(end -0.12065 -0.305054)
			(stroke
				(width 0.1)
				(type default)
			)
			(layer "F.Fab")
		)
		(fp_line
			(start -0.67945 0.3048)
			(end -0.67945 -0.305054)
			(stroke
				(width 0.1)
				(type default)
			)
			(layer "F.Fab")
		)
		(fp_line
			(start -0.12065 -0.305054)
			(end -0.12065 -0.2794)
			(stroke
				(width 0.1)
				(type default)
			)
			(layer "F.Fab")
		)
		(fp_line
			(start -0.12065 -0.2794)
			(end 0.12065 -0.2794)
			(stroke
				(width 0.1)
				(type default)
			)
			(layer "F.Fab")
		)
		(fp_line
			(start -0.12065 0.2794)
			(end -0.12065 0.3048)
			(stroke
				(width 0.1)
				(type default)
			)
			(layer "F.Fab")
		)
		(fp_line
			(start -0.12065 0.3048)
			(end -0.67945 0.3048)
			(stroke
				(width 0.1)
				(type default)
			)
			(layer "F.Fab")
		)
		(fp_line
			(start 0.120396 0.2794)
			(end -0.12065 0.2794)
			(stroke
				(width 0.1)
				(type default)
			)
			(layer "F.Fab")
		)
		(fp_line
			(start 0.120396 0.3048)
			(end 0.120396 0.2794)
			(stroke
				(width 0.1)
				(type default)
			)
			(layer "F.Fab")
		)
		(fp_line
			(start 0.12065 -0.3048)
			(end 0.67945 -0.3048)
			(stroke
				(width 0.1)
				(type default)
			)
			(layer "F.Fab")
		)
		(fp_line
			(start 0.12065 -0.2794)
			(end 0.12065 -0.3048)
			(stroke
				(width 0.1)
				(type default)
			)
			(layer "F.Fab")
		)
		(fp_line
			(start 0.67945 -0.3048)
			(end 0.67945 0.3048)
			(stroke
				(width 0.1)
				(type default)
			)
			(layer "F.Fab")
		)
		(fp_line
			(start 0.67945 0.3048)
			(end 0.120396 0.3048)
			(stroke
				(width 0.1)
				(type default)
			)
			(layer "F.Fab")
		)
		(pad "1" smd circle
			(at -0.40005 0)
			(size 0 0)
			(layers "F.Cu" "F.Mask" "F.Paste")
			(net "SMB_BIC_I2C9_MUX1_SSD11_R_SCL")
		)
		(pad "2" smd circle
			(at 0.40005 0)
			(size 0 0)
			(layers "F.Cu" "F.Mask" "F.Paste")
			(net "SMB_BIC_I2C9_MUX1_SSD11_SCL")
		)
	)
	(footprint ""
		(layer "F.Cu")
		(at 184.088024 -45.704252 90)
		(property "Reference" "R573"
			(at 0 0 90)
			(layer "F.SilkS")
			(hide yes)
			(effects
				(font
					(size 1.27 1.27)
				)
			)
		)
		(property "Value" ""
			(at 0 0 90)
			(layer "F.Fab")
			(effects
				(font
					(size 1.27 1.27)
				)
			)
		)
		(duplicate_pad_numbers_are_jumpers no)
		(fp_line
			(start 3.937508 -1.8796)
			(end -3.937508 -1.8796)
			(stroke
				(width 0.1524)
				(type default)
			)
			(layer "F.SilkS")
		)
		(fp_line
			(start -3.937508 -1.8796)
			(end -3.937508 1.8796)
			(stroke
				(width 0.1524)
				(type default)
			)
			(layer "F.SilkS")
		)
		(fp_line
			(start 3.937508 1.8796)
			(end 3.937508 -1.8796)
			(stroke
				(width 0.1524)
				(type default)
			)
			(layer "F.SilkS")
		)
		(fp_line
			(start -3.937508 1.8796)
			(end 3.937508 1.8796)
			(stroke
				(width 0.1524)
				(type default)
			)
			(layer "F.SilkS")
		)
		(fp_line
			(start 3.275076 -1.674876)
			(end -3.275076 -1.674876)
			(stroke
				(width 0.1)
				(type default)
			)
			(layer "F.Fab")
		)
		(fp_line
			(start -3.275076 -1.674876)
			(end -3.275076 1.674876)
			(stroke
				(width 0.1)
				(type default)
			)
			(layer "F.Fab")
		)
		(fp_line
			(start 3.275076 1.674876)
			(end 3.275076 -1.674876)
			(stroke
				(width 0.1)
				(type default)
			)
			(layer "F.Fab")
		)
		(fp_line
			(start -3.275076 1.674876)
			(end 3.275076 1.674876)
			(stroke
				(width 0.1)
				(type default)
			)
			(layer "F.Fab")
		)
		(pad "1" smd rect
			(at -2.350008 0 90)
			(size 2.921 3.5052)
			(layers "F.Cu" "F.Mask" "F.Paste")
			(net "P12V_SSD6")
		)
		(pad "2" smd rect
			(at 2.350008 0 90)
			(size 2.921 3.5052)
			(layers "F.Cu" "F.Mask" "F.Paste")
			(net "P12V_SSD6_R")
		)
	)
	(footprint ""
		(layer "F.Cu")
		(at 338.074 -153.67 180)
		(property "Reference" "R4818"
			(at 0 0 180)
			(layer "F.SilkS")
			(hide yes)
			(effects
				(font
					(size 1.27 1.27)
				)
			)
		)
		(property "Value" ""
			(at 0 0 180)
			(layer "F.Fab")
			(effects
				(font
					(size 1.27 1.27)
				)
			)
		)
		(duplicate_pad_numbers_are_jumpers no)
		(fp_line
			(start 0.7874 0.4064)
			(end -0.7874 0.4064)
			(stroke
				(width 0.1524)
				(type default)
			)
			(layer "F.SilkS")
		)
		(fp_line
			(start 0.7874 -0.4064)
			(end 0.7874 0.4064)
			(stroke
				(width 0.1524)
				(type default)
			)
			(layer "F.SilkS")
		)
		(fp_line
			(start -0.7874 0.4064)
			(end -0.7874 -0.4064)
			(stroke
				(width 0.1524)
				(type default)
			)
			(layer "F.SilkS")
		)
		(fp_line
			(start -0.7874 -0.4064)
			(end 0.7874 -0.4064)
			(stroke
				(width 0.1524)
				(type default)
			)
			(layer "F.SilkS")
		)
		(fp_line
			(start 0.67945 0.3048)
			(end 0.120396 0.3048)
			(stroke
				(width 0.1)
				(type default)
			)
			(layer "F.Fab")
		)
		(fp_line
			(start 0.67945 -0.3048)
			(end 0.67945 0.3048)
			(stroke
				(width 0.1)
				(type default)
			)
			(layer "F.Fab")
		)
		(fp_line
			(start 0.12065 -0.2794)
			(end 0.12065 -0.3048)
			(stroke
				(width 0.1)
				(type default)
			)
			(layer "F.Fab")
		)
		(fp_line
			(start 0.12065 -0.3048)
			(end 0.67945 -0.3048)
			(stroke
				(width 0.1)
				(type default)
			)
			(layer "F.Fab")
		)
		(fp_line
			(start 0.120396 0.3048)
			(end 0.120396 0.2794)
			(stroke
				(width 0.1)
				(type default)
			)
			(layer "F.Fab")
		)
		(fp_line
			(start 0.120396 0.2794)
			(end -0.12065 0.2794)
			(stroke
				(width 0.1)
				(type default)
			)
			(layer "F.Fab")
		)
		(fp_line
			(start -0.12065 0.3048)
			(end -0.67945 0.3048)
			(stroke
				(width 0.1)
				(type default)
			)
			(layer "F.Fab")
		)
		(fp_line
			(start -0.12065 0.2794)
			(end -0.12065 0.3048)
			(stroke
				(width 0.1)
				(type default)
			)
			(layer "F.Fab")
		)
		(fp_line
			(start -0.12065 -0.2794)
			(end 0.12065 -0.2794)
			(stroke
				(width 0.1)
				(type default)
			)
			(layer "F.Fab")
		)
		(fp_line
			(start -0.12065 -0.305054)
			(end -0.12065 -0.2794)
			(stroke
				(width 0.1)
				(type default)
			)
			(layer "F.Fab")
		)
		(fp_line
			(start -0.67945 0.3048)
			(end -0.67945 -0.305054)
			(stroke
				(width 0.1)
				(type default)
			)
			(layer "F.Fab")
		)
		(fp_line
			(start -0.67945 -0.305054)
			(end -0.12065 -0.305054)
			(stroke
				(width 0.1)
				(type default)
			)
			(layer "F.Fab")
		)
		(pad "1" smd circle
			(at -0.40005 0 180)
			(size 0 0)
			(layers "F.Cu" "F.Mask" "F.Paste")
			(net "RST_PEX_SSD13_PERST_N")
		)
		(pad "2" smd circle
			(at 0.40005 0 180)
			(size 0 0)
			(layers "F.Cu" "F.Mask" "F.Paste")
			(net "RST_PEX_SSD13_PERST_R_N")
		)
	)
	(footprint ""
		(layer "F.Cu")
		(at 255.935226 -239.095788 -90)
		(property "Reference" "C4425"
			(at 0 0 270)
			(layer "F.SilkS")
			(hide yes)
			(effects
				(font
					(size 1.27 1.27)
				)
			)
		)
		(property "Value" ""
			(at 0 0 270)
			(layer "F.Fab")
			(effects
				(font
					(size 1.27 1.27)
				)
			)
		)
		(duplicate_pad_numbers_are_jumpers no)
		(fp_line
			(start -1.524 0.762)
			(end -1.524 -0.762)
			(stroke
				(width 0.1524)
				(type default)
			)
			(layer "F.SilkS")
		)
		(fp_line
			(start 1.524 0.762)
			(end -1.524 0.762)
			(stroke
				(width 0.1524)
				(type default)
			)
			(layer "F.SilkS")
		)
		(fp_line
			(start -1.524 -0.762)
			(end 1.524 -0.762)
			(stroke
				(width 0.1524)
				(type default)
			)
			(layer "F.SilkS")
		)
		(fp_line
			(start 1.524 -0.762)
			(end 1.524 0.762)
			(stroke
				(width 0.1524)
				(type default)
			)
			(layer "F.SilkS")
		)
		(fp_line
			(start -1.1049 0.724916)
			(end 1.1049 0.724916)
			(stroke
				(width 0.1)
				(type default)
			)
			(layer "F.Fab")
		)
		(fp_line
			(start 1.1049 0.724916)
			(end 1.1049 -0.724916)
			(stroke
				(width 0.1)
				(type default)
			)
			(layer "F.Fab")
		)
		(fp_line
			(start -1.1049 -0.724916)
			(end -1.1049 0.724916)
			(stroke
				(width 0.1)
				(type default)
			)
			(layer "F.Fab")
		)
		(fp_line
			(start 1.1049 -0.724916)
			(end -1.1049 -0.724916)
			(stroke
				(width 0.1)
				(type default)
			)
			(layer "F.Fab")
		)
		(pad "1" smd rect
			(at -0.889 0 90)
			(size 1.016 1.27)
			(layers "F.Cu" "F.Mask" "F.Paste")
			(net "P3V3_AUX")
		)
		(pad "2" smd rect
			(at 0.889 0 90)
			(size 1.016 1.27)
			(layers "F.Cu" "F.Mask" "F.Paste")
			(net "GND")
		)
	)
	(footprint ""
		(layer "F.Cu")
		(at 178.908456 -158.080202 90)
		(property "Reference" "R2473"
			(at 0 0 90)
			(layer "F.SilkS")
			(hide yes)
			(effects
				(font
					(size 1.27 1.27)
				)
			)
		)
		(property "Value" ""
			(at 0 0 90)
			(layer "F.Fab")
			(effects
				(font
					(size 1.27 1.27)
				)
			)
		)
		(duplicate_pad_numbers_are_jumpers no)
		(fp_line
			(start 0.7874 -0.4064)
			(end 0.7874 0.4064)
			(stroke
				(width 0.1524)
				(type default)
			)
			(layer "F.SilkS")
		)
		(fp_line
			(start -0.7874 -0.4064)
			(end 0.7874 -0.4064)
			(stroke
				(width 0.1524)
				(type default)
			)
			(layer "F.SilkS")
		)
		(fp_line
			(start 0.7874 0.4064)
			(end -0.7874 0.4064)
			(stroke
				(width 0.1524)
				(type default)
			)
			(layer "F.SilkS")
		)
		(fp_line
			(start -0.7874 0.4064)
			(end -0.7874 -0.4064)
			(stroke
				(width 0.1524)
				(type default)
			)
			(layer "F.SilkS")
		)
		(fp_line
			(start -0.12065 -0.305054)
			(end -0.12065 -0.2794)
			(stroke
				(width 0.1)
				(type default)
			)
			(layer "F.Fab")
		)
		(fp_line
			(start -0.67945 -0.305054)
			(end -0.12065 -0.305054)
			(stroke
				(width 0.1)
				(type default)
			)
			(layer "F.Fab")
		)
		(fp_line
			(start 0.67945 -0.3048)
			(end 0.67945 0.3048)
			(stroke
				(width 0.1)
				(type default)
			)
			(layer "F.Fab")
		)
		(fp_line
			(start 0.12065 -0.3048)
			(end 0.67945 -0.3048)
			(stroke
				(width 0.1)
				(type default)
			)
			(layer "F.Fab")
		)
		(fp_line
			(start 0.12065 -0.2794)
			(end 0.12065 -0.3048)
			(stroke
				(width 0.1)
				(type default)
			)
			(layer "F.Fab")
		)
		(fp_line
			(start -0.12065 -0.2794)
			(end 0.12065 -0.2794)
			(stroke
				(width 0.1)
				(type default)
			)
			(layer "F.Fab")
		)
		(fp_line
			(start 0.120396 0.2794)
			(end -0.12065 0.2794)
			(stroke
				(width 0.1)
				(type default)
			)
			(layer "F.Fab")
		)
		(fp_line
			(start -0.12065 0.2794)
			(end -0.12065 0.3048)
			(stroke
				(width 0.1)
				(type default)
			)
			(layer "F.Fab")
		)
		(fp_line
			(start 0.67945 0.3048)
			(end 0.120396 0.3048)
			(stroke
				(width 0.1)
				(type default)
			)
			(layer "F.Fab")
		)
		(fp_line
			(start 0.120396 0.3048)
			(end 0.120396 0.2794)
			(stroke
				(width 0.1)
				(type default)
			)
			(layer "F.Fab")
		)
		(fp_line
			(start -0.12065 0.3048)
			(end -0.67945 0.3048)
			(stroke
				(width 0.1)
				(type default)
			)
			(layer "F.Fab")
		)
		(fp_line
			(start -0.67945 0.3048)
			(end -0.67945 -0.305054)
			(stroke
				(width 0.1)
				(type default)
			)
			(layer "F.Fab")
		)
		(pad "1" smd circle
			(at -0.40005 0 90)
			(size 0 0)
			(layers "F.Cu" "F.Mask" "F.Paste")
			(net "P3V3_NIC3")
		)
		(pad "2" smd circle
			(at 0.40005 0 90)
			(size 0 0)
			(layers "F.Cu" "F.Mask" "F.Paste")
			(net "NIC3_PWRBRK_N")
		)
	)
	(footprint ""
		(layer "F.Cu")
		(at 254.062992 -259.819394 -90)
		(property "Reference" "R1391"
			(at 0 0 270)
			(layer "F.SilkS")
			(hide yes)
			(effects
				(font
					(size 1.27 1.27)
				)
			)
		)
		(property "Value" ""
			(at 0 0 270)
			(layer "F.Fab")
			(effects
				(font
					(size 1.27 1.27)
				)
			)
		)
		(duplicate_pad_numbers_are_jumpers no)
		(fp_line
			(start -0.7874 0.4064)
			(end -0.7874 -0.4064)
			(stroke
				(width 0.1524)
				(type default)
			)
			(layer "F.SilkS")
		)
		(fp_line
			(start 0.7874 0.4064)
			(end -0.7874 0.4064)
			(stroke
				(width 0.1524)
				(type default)
			)
			(layer "F.SilkS")
		)
		(fp_line
			(start -0.7874 -0.4064)
			(end 0.7874 -0.4064)
			(stroke
				(width 0.1524)
				(type default)
			)
			(layer "F.SilkS")
		)
		(fp_line
			(start 0.7874 -0.4064)
			(end 0.7874 0.4064)
			(stroke
				(width 0.1524)
				(type default)
			)
			(layer "F.SilkS")
		)
		(fp_line
			(start -0.67945 0.3048)
			(end -0.67945 -0.305054)
			(stroke
				(width 0.1)
				(type default)
			)
			(layer "F.Fab")
		)
		(fp_line
			(start -0.12065 0.3048)
			(end -0.67945 0.3048)
			(stroke
				(width 0.1)
				(type default)
			)
			(layer "F.Fab")
		)
		(fp_line
			(start 0.120396 0.3048)
			(end 0.120396 0.2794)
			(stroke
				(width 0.1)
				(type default)
			)
			(layer "F.Fab")
		)
		(fp_line
			(start 0.67945 0.3048)
			(end 0.120396 0.3048)
			(stroke
				(width 0.1)
				(type default)
			)
			(layer "F.Fab")
		)
		(fp_line
			(start -0.12065 0.2794)
			(end -0.12065 0.3048)
			(stroke
				(width 0.1)
				(type default)
			)
			(layer "F.Fab")
		)
		(fp_line
			(start 0.120396 0.2794)
			(end -0.12065 0.2794)
			(stroke
				(width 0.1)
				(type default)
			)
			(layer "F.Fab")
		)
		(fp_line
			(start -0.12065 -0.2794)
			(end 0.12065 -0.2794)
			(stroke
				(width 0.1)
				(type default)
			)
			(layer "F.Fab")
		)
		(fp_line
			(start 0.12065 -0.2794)
			(end 0.12065 -0.3048)
			(stroke
				(width 0.1)
				(type default)
			)
			(layer "F.Fab")
		)
		(fp_line
			(start 0.12065 -0.3048)
			(end 0.67945 -0.3048)
			(stroke
				(width 0.1)
				(type default)
			)
			(layer "F.Fab")
		)
		(fp_line
			(start 0.67945 -0.3048)
			(end 0.67945 0.3048)
			(stroke
				(width 0.1)
				(type default)
			)
			(layer "F.Fab")
		)
		(fp_line
			(start -0.67945 -0.305054)
			(end -0.12065 -0.305054)
			(stroke
				(width 0.1)
				(type default)
			)
			(layer "F.Fab")
		)
		(fp_line
			(start -0.12065 -0.305054)
			(end -0.12065 -0.2794)
			(stroke
				(width 0.1)
				(type default)
			)
			(layer "F.Fab")
		)
		(pad "1" smd circle
			(at -0.40005 0 270)
			(size 0 0)
			(layers "F.Cu" "F.Mask" "F.Paste")
			(net "PEX2_SYS_ERR_N")
		)
		(pad "2" smd circle
			(at 0.40005 0 270)
			(size 0 0)
			(layers "F.Cu" "F.Mask" "F.Paste")
			(net "PEX2_SYS_ERR_R_N")
		)
	)
	(footprint ""
		(layer "F.Cu")
		(at 269.204694 -142.88897 180)
		(property "Reference" "R233"
			(at 0 0 180)
			(layer "F.SilkS")
			(hide yes)
			(effects
				(font
					(size 1.27 1.27)
				)
			)
		)
		(property "Value" ""
			(at 0 0 180)
			(layer "F.Fab")
			(effects
				(font
					(size 1.27 1.27)
				)
			)
		)
		(duplicate_pad_numbers_are_jumpers no)
		(fp_line
			(start 0.7874 0.4064)
			(end -0.7874 0.4064)
			(stroke
				(width 0.1524)
				(type default)
			)
			(layer "F.SilkS")
		)
		(fp_line
			(start 0.7874 -0.4064)
			(end 0.7874 0.4064)
			(stroke
				(width 0.1524)
				(type default)
			)
			(layer "F.SilkS")
		)
		(fp_line
			(start -0.7874 0.4064)
			(end -0.7874 -0.4064)
			(stroke
				(width 0.1524)
				(type default)
			)
			(layer "F.SilkS")
		)
		(fp_line
			(start -0.7874 -0.4064)
			(end 0.7874 -0.4064)
			(stroke
				(width 0.1524)
				(type default)
			)
			(layer "F.SilkS")
		)
		(fp_line
			(start 0.67945 0.3048)
			(end 0.120396 0.3048)
			(stroke
				(width 0.1)
				(type default)
			)
			(layer "F.Fab")
		)
		(fp_line
			(start 0.67945 -0.3048)
			(end 0.67945 0.3048)
			(stroke
				(width 0.1)
				(type default)
			)
			(layer "F.Fab")
		)
		(fp_line
			(start 0.12065 -0.2794)
			(end 0.12065 -0.3048)
			(stroke
				(width 0.1)
				(type default)
			)
			(layer "F.Fab")
		)
		(fp_line
			(start 0.12065 -0.3048)
			(end 0.67945 -0.3048)
			(stroke
				(width 0.1)
				(type default)
			)
			(layer "F.Fab")
		)
		(fp_line
			(start 0.120396 0.3048)
			(end 0.120396 0.2794)
			(stroke
				(width 0.1)
				(type default)
			)
			(layer "F.Fab")
		)
		(fp_line
			(start 0.120396 0.2794)
			(end -0.12065 0.2794)
			(stroke
				(width 0.1)
				(type default)
			)
			(layer "F.Fab")
		)
		(fp_line
			(start -0.12065 0.3048)
			(end -0.67945 0.3048)
			(stroke
				(width 0.1)
				(type default)
			)
			(layer "F.Fab")
		)
		(fp_line
			(start -0.12065 0.2794)
			(end -0.12065 0.3048)
			(stroke
				(width 0.1)
				(type default)
			)
			(layer "F.Fab")
		)
		(fp_line
			(start -0.12065 -0.2794)
			(end 0.12065 -0.2794)
			(stroke
				(width 0.1)
				(type default)
			)
			(layer "F.Fab")
		)
		(fp_line
			(start -0.12065 -0.305054)
			(end -0.12065 -0.2794)
			(stroke
				(width 0.1)
				(type default)
			)
			(layer "F.Fab")
		)
		(fp_line
			(start -0.67945 0.3048)
			(end -0.67945 -0.305054)
			(stroke
				(width 0.1)
				(type default)
			)
			(layer "F.Fab")
		)
		(fp_line
			(start -0.67945 -0.305054)
			(end -0.12065 -0.305054)
			(stroke
				(width 0.1)
				(type default)
			)
			(layer "F.Fab")
		)
		(pad "1" smd circle
			(at -0.40005 0 180)
			(size 0 0)
			(layers "F.Cu" "F.Mask" "F.Paste")
			(net "NIC4_BIF0_N")
		)
		(pad "2" smd circle
			(at 0.40005 0 180)
			(size 0 0)
			(layers "F.Cu" "F.Mask" "F.Paste")
			(net "P3V3_AUX")
		)
	)
	(footprint ""
		(layer "F.Cu")
		(at 246.153686 -115.147852 -90)
		(property "Reference" "PC899"
			(at 0 0 270)
			(layer "F.SilkS")
			(hide yes)
			(effects
				(font
					(size 1.27 1.27)
				)
			)
		)
		(property "Value" ""
			(at 0 0 270)
			(layer "F.Fab")
			(effects
				(font
					(size 1.27 1.27)
				)
			)
		)
		(duplicate_pad_numbers_are_jumpers no)
		(fp_line
			(start -0.7874 0.4064)
			(end -0.7874 -0.4064)
			(stroke
				(width 0.1524)
				(type default)
			)
			(layer "F.SilkS")
		)
		(fp_line
			(start 0.7874 0.4064)
			(end -0.7874 0.4064)
			(stroke
				(width 0.1524)
				(type default)
			)
			(layer "F.SilkS")
		)
		(fp_line
			(start -0.7874 -0.4064)
			(end 0.7874 -0.4064)
			(stroke
				(width 0.1524)
				(type default)
			)
			(layer "F.SilkS")
		)
		(fp_line
			(start 0.7874 -0.4064)
			(end 0.7874 0.4064)
			(stroke
				(width 0.1524)
				(type default)
			)
			(layer "F.SilkS")
		)
		(fp_line
			(start -0.67945 0.3048)
			(end -0.67945 -0.305054)
			(stroke
				(width 0.1)
				(type default)
			)
			(layer "F.Fab")
		)
		(fp_line
			(start -0.12065 0.3048)
			(end -0.67945 0.3048)
			(stroke
				(width 0.1)
				(type default)
			)
			(layer "F.Fab")
		)
		(fp_line
			(start 0.120396 0.3048)
			(end 0.120396 0.2794)
			(stroke
				(width 0.1)
				(type default)
			)
			(layer "F.Fab")
		)
		(fp_line
			(start 0.67945 0.3048)
			(end 0.120396 0.3048)
			(stroke
				(width 0.1)
				(type default)
			)
			(layer "F.Fab")
		)
		(fp_line
			(start -0.12065 0.2794)
			(end -0.12065 0.3048)
			(stroke
				(width 0.1)
				(type default)
			)
			(layer "F.Fab")
		)
		(fp_line
			(start 0.120396 0.2794)
			(end -0.12065 0.2794)
			(stroke
				(width 0.1)
				(type default)
			)
			(layer "F.Fab")
		)
		(fp_line
			(start -0.12065 -0.2794)
			(end 0.12065 -0.2794)
			(stroke
				(width 0.1)
				(type default)
			)
			(layer "F.Fab")
		)
		(fp_line
			(start 0.12065 -0.2794)
			(end 0.12065 -0.3048)
			(stroke
				(width 0.1)
				(type default)
			)
			(layer "F.Fab")
		)
		(fp_line
			(start 0.12065 -0.3048)
			(end 0.67945 -0.3048)
			(stroke
				(width 0.1)
				(type default)
			)
			(layer "F.Fab")
		)
		(fp_line
			(start 0.67945 -0.3048)
			(end 0.67945 0.3048)
			(stroke
				(width 0.1)
				(type default)
			)
			(layer "F.Fab")
		)
		(fp_line
			(start -0.67945 -0.305054)
			(end -0.12065 -0.305054)
			(stroke
				(width 0.1)
				(type default)
			)
			(layer "F.Fab")
		)
		(fp_line
			(start -0.12065 -0.305054)
			(end -0.12065 -0.2794)
			(stroke
				(width 0.1)
				(type default)
			)
			(layer "F.Fab")
		)
		(pad "1" smd circle
			(at -0.40005 0 270)
			(size 0 0)
			(layers "F.Cu" "F.Mask" "F.Paste")
			(net "P3V3_AUX")
		)
		(pad "2" smd circle
			(at 0.40005 0 270)
			(size 0 0)
			(layers "F.Cu" "F.Mask" "F.Paste")
			(net "GND")
		)
	)
	(footprint ""
		(layer "F.Cu")
		(at 94.103444 -96.811592 90)
		(property "Reference" "R698"
			(at 0 0 90)
			(layer "F.SilkS")
			(hide yes)
			(effects
				(font
					(size 1.27 1.27)
				)
			)
		)
		(property "Value" ""
			(at 0 0 90)
			(layer "F.Fab")
			(effects
				(font
					(size 1.27 1.27)
				)
			)
		)
		(duplicate_pad_numbers_are_jumpers no)
		(fp_line
			(start 0.7874 -0.4064)
			(end 0.7874 0.4064)
			(stroke
				(width 0.1524)
				(type default)
			)
			(layer "F.SilkS")
		)
		(fp_line
			(start -0.7874 -0.4064)
			(end 0.7874 -0.4064)
			(stroke
				(width 0.1524)
				(type default)
			)
			(layer "F.SilkS")
		)
		(fp_line
			(start 0.7874 0.4064)
			(end -0.7874 0.4064)
			(stroke
				(width 0.1524)
				(type default)
			)
			(layer "F.SilkS")
		)
		(fp_line
			(start -0.7874 0.4064)
			(end -0.7874 -0.4064)
			(stroke
				(width 0.1524)
				(type default)
			)
			(layer "F.SilkS")
		)
		(fp_line
			(start -0.12065 -0.305054)
			(end -0.12065 -0.2794)
			(stroke
				(width 0.1)
				(type default)
			)
			(layer "F.Fab")
		)
		(fp_line
			(start -0.67945 -0.305054)
			(end -0.12065 -0.305054)
			(stroke
				(width 0.1)
				(type default)
			)
			(layer "F.Fab")
		)
		(fp_line
			(start 0.67945 -0.3048)
			(end 0.67945 0.3048)
			(stroke
				(width 0.1)
				(type default)
			)
			(layer "F.Fab")
		)
		(fp_line
			(start 0.12065 -0.3048)
			(end 0.67945 -0.3048)
			(stroke
				(width 0.1)
				(type default)
			)
			(layer "F.Fab")
		)
		(fp_line
			(start 0.12065 -0.2794)
			(end 0.12065 -0.3048)
			(stroke
				(width 0.1)
				(type default)
			)
			(layer "F.Fab")
		)
		(fp_line
			(start -0.12065 -0.2794)
			(end 0.12065 -0.2794)
			(stroke
				(width 0.1)
				(type default)
			)
			(layer "F.Fab")
		)
		(fp_line
			(start 0.120396 0.2794)
			(end -0.12065 0.2794)
			(stroke
				(width 0.1)
				(type default)
			)
			(layer "F.Fab")
		)
		(fp_line
			(start -0.12065 0.2794)
			(end -0.12065 0.3048)
			(stroke
				(width 0.1)
				(type default)
			)
			(layer "F.Fab")
		)
		(fp_line
			(start 0.67945 0.3048)
			(end 0.120396 0.3048)
			(stroke
				(width 0.1)
				(type default)
			)
			(layer "F.Fab")
		)
		(fp_line
			(start 0.120396 0.3048)
			(end 0.120396 0.2794)
			(stroke
				(width 0.1)
				(type default)
			)
			(layer "F.Fab")
		)
		(fp_line
			(start -0.12065 0.3048)
			(end -0.67945 0.3048)
			(stroke
				(width 0.1)
				(type default)
			)
			(layer "F.Fab")
		)
		(fp_line
			(start -0.67945 0.3048)
			(end -0.67945 -0.305054)
			(stroke
				(width 0.1)
				(type default)
			)
			(layer "F.Fab")
		)
		(pad "1" smd circle
			(at -0.40005 0 90)
			(size 0 0)
			(layers "F.Cu" "F.Mask" "F.Paste")
			(net "SMB_BIC_I2C6_MUX_NIC_ADC_R_SCL")
		)
		(pad "2" smd circle
			(at 0.40005 0 90)
			(size 0 0)
			(layers "F.Cu" "F.Mask" "F.Paste")
			(net "SMB_NIC1_ADC_SCL")
		)
	)
	(footprint ""
		(layer "F.Cu")
		(at 72.255126 -35.876738)
		(property "Reference" "R5881"
			(at 0 0 0)
			(layer "F.SilkS")
			(hide yes)
			(effects
				(font
					(size 1.27 1.27)
				)
			)
		)
		(property "Value" ""
			(at 0 0 0)
			(layer "F.Fab")
			(effects
				(font
					(size 1.27 1.27)
				)
			)
		)
		(duplicate_pad_numbers_are_jumpers no)
		(fp_line
			(start -0.7874 -0.4064)
			(end 0.7874 -0.4064)
			(stroke
				(width 0.1524)
				(type default)
			)
			(layer "F.SilkS")
		)
		(fp_line
			(start -0.7874 0.4064)
			(end -0.7874 -0.4064)
			(stroke
				(width 0.1524)
				(type default)
			)
			(layer "F.SilkS")
		)
		(fp_line
			(start 0.7874 -0.4064)
			(end 0.7874 0.4064)
			(stroke
				(width 0.1524)
				(type default)
			)
			(layer "F.SilkS")
		)
		(fp_line
			(start 0.7874 0.4064)
			(end -0.7874 0.4064)
			(stroke
				(width 0.1524)
				(type default)
			)
			(layer "F.SilkS")
		)
		(fp_line
			(start -0.67945 -0.305054)
			(end -0.12065 -0.305054)
			(stroke
				(width 0.1)
				(type default)
			)
			(layer "F.Fab")
		)
		(fp_line
			(start -0.67945 0.3048)
			(end -0.67945 -0.305054)
			(stroke
				(width 0.1)
				(type default)
			)
			(layer "F.Fab")
		)
		(fp_line
			(start -0.12065 -0.305054)
			(end -0.12065 -0.2794)
			(stroke
				(width 0.1)
				(type default)
			)
			(layer "F.Fab")
		)
		(fp_line
			(start -0.12065 -0.2794)
			(end 0.12065 -0.2794)
			(stroke
				(width 0.1)
				(type default)
			)
			(layer "F.Fab")
		)
		(fp_line
			(start -0.12065 0.2794)
			(end -0.12065 0.3048)
			(stroke
				(width 0.1)
				(type default)
			)
			(layer "F.Fab")
		)
		(fp_line
			(start -0.12065 0.3048)
			(end -0.67945 0.3048)
			(stroke
				(width 0.1)
				(type default)
			)
			(layer "F.Fab")
		)
		(fp_line
			(start 0.120396 0.2794)
			(end -0.12065 0.2794)
			(stroke
				(width 0.1)
				(type default)
			)
			(layer "F.Fab")
		)
		(fp_line
			(start 0.120396 0.3048)
			(end 0.120396 0.2794)
			(stroke
				(width 0.1)
				(type default)
			)
			(layer "F.Fab")
		)
		(fp_line
			(start 0.12065 -0.3048)
			(end 0.67945 -0.3048)
			(stroke
				(width 0.1)
				(type default)
			)
			(layer "F.Fab")
		)
		(fp_line
			(start 0.12065 -0.2794)
			(end 0.12065 -0.3048)
			(stroke
				(width 0.1)
				(type default)
			)
			(layer "F.Fab")
		)
		(fp_line
			(start 0.67945 -0.3048)
			(end 0.67945 0.3048)
			(stroke
				(width 0.1)
				(type default)
			)
			(layer "F.Fab")
		)
		(fp_line
			(start 0.67945 0.3048)
			(end 0.120396 0.3048)
			(stroke
				(width 0.1)
				(type default)
			)
			(layer "F.Fab")
		)
		(pad "1" smd circle
			(at -0.40005 0)
			(size 0 0)
			(layers "F.Cu" "F.Mask" "F.Paste")
			(net "P3V3_AUX")
		)
		(pad "2" smd circle
			(at 0.40005 0)
			(size 0 0)
			(layers "F.Cu" "F.Mask" "F.Paste")
			(net "PWRGD_P3V3_SSD3_D")
		)
	)
	(footprint ""
		(layer "F.Cu")
		(at 199.966834 -52.543456 180)
		(property "Reference" "PC536"
			(at 0 0 180)
			(layer "F.SilkS")
			(hide yes)
			(effects
				(font
					(size 1.27 1.27)
				)
			)
		)
		(property "Value" ""
			(at 0 0 180)
			(layer "F.Fab")
			(effects
				(font
					(size 1.27 1.27)
				)
			)
		)
		(duplicate_pad_numbers_are_jumpers no)
		(fp_line
			(start 0.7874 0.4064)
			(end -0.7874 0.4064)
			(stroke
				(width 0.1524)
				(type default)
			)
			(layer "F.SilkS")
		)
		(fp_line
			(start 0.7874 -0.4064)
			(end 0.7874 0.4064)
			(stroke
				(width 0.1524)
				(type default)
			)
			(layer "F.SilkS")
		)
		(fp_line
			(start -0.7874 0.4064)
			(end -0.7874 -0.4064)
			(stroke
				(width 0.1524)
				(type default)
			)
			(layer "F.SilkS")
		)
		(fp_line
			(start -0.7874 -0.4064)
			(end 0.7874 -0.4064)
			(stroke
				(width 0.1524)
				(type default)
			)
			(layer "F.SilkS")
		)
		(fp_line
			(start 0.67945 0.3048)
			(end 0.120396 0.3048)
			(stroke
				(width 0.1)
				(type default)
			)
			(layer "F.Fab")
		)
		(fp_line
			(start 0.67945 -0.3048)
			(end 0.67945 0.3048)
			(stroke
				(width 0.1)
				(type default)
			)
			(layer "F.Fab")
		)
		(fp_line
			(start 0.12065 -0.2794)
			(end 0.12065 -0.3048)
			(stroke
				(width 0.1)
				(type default)
			)
			(layer "F.Fab")
		)
		(fp_line
			(start 0.12065 -0.3048)
			(end 0.67945 -0.3048)
			(stroke
				(width 0.1)
				(type default)
			)
			(layer "F.Fab")
		)
		(fp_line
			(start 0.120396 0.3048)
			(end 0.120396 0.2794)
			(stroke
				(width 0.1)
				(type default)
			)
			(layer "F.Fab")
		)
		(fp_line
			(start 0.120396 0.2794)
			(end -0.12065 0.2794)
			(stroke
				(width 0.1)
				(type default)
			)
			(layer "F.Fab")
		)
		(fp_line
			(start -0.12065 0.3048)
			(end -0.67945 0.3048)
			(stroke
				(width 0.1)
				(type default)
			)
			(layer "F.Fab")
		)
		(fp_line
			(start -0.12065 0.2794)
			(end -0.12065 0.3048)
			(stroke
				(width 0.1)
				(type default)
			)
			(layer "F.Fab")
		)
		(fp_line
			(start -0.12065 -0.2794)
			(end 0.12065 -0.2794)
			(stroke
				(width 0.1)
				(type default)
			)
			(layer "F.Fab")
		)
		(fp_line
			(start -0.12065 -0.305054)
			(end -0.12065 -0.2794)
			(stroke
				(width 0.1)
				(type default)
			)
			(layer "F.Fab")
		)
		(fp_line
			(start -0.67945 0.3048)
			(end -0.67945 -0.305054)
			(stroke
				(width 0.1)
				(type default)
			)
			(layer "F.Fab")
		)
		(fp_line
			(start -0.67945 -0.305054)
			(end -0.12065 -0.305054)
			(stroke
				(width 0.1)
				(type default)
			)
			(layer "F.Fab")
		)
		(pad "1" smd circle
			(at -0.40005 0 180)
			(size 0 0)
			(layers "F.Cu" "F.Mask" "F.Paste")
			(net "P3V3_SSD7")
		)
		(pad "2" smd circle
			(at 0.40005 0 180)
			(size 0 0)
			(layers "F.Cu" "F.Mask" "F.Paste")
			(net "GND")
		)
	)
	(footprint ""
		(layer "F.Cu")
		(at 190.747142 -54.3941)
		(property "Reference" "PU35"
			(at -1.633982 2.792222 0)
			(unlocked yes)
			(layer "F.SilkS")
			(effects
				(font
					(size 0.7874 0.5842)
					(thickness 0.1524)
				)
				(justify left)
			)
		)
		(property "Value" ""
			(at 0 0 0)
			(layer "F.Fab")
			(effects
				(font
					(size 1.27 1.27)
				)
			)
		)
		(duplicate_pad_numbers_are_jumpers no)
		(fp_line
			(start -1.943608 -1.549908)
			(end 1.943608 -1.549908)
			(stroke
				(width 0.1524)
				(type default)
			)
			(layer "F.SilkS")
		)
		(fp_line
			(start -1.943608 1.549908)
			(end -1.943608 -1.549908)
			(stroke
				(width 0.1524)
				(type default)
			)
			(layer "F.SilkS")
		)
		(fp_line
			(start 1.943608 -1.549908)
			(end 1.943608 1.549908)
			(stroke
				(width 0.1524)
				(type default)
			)
			(layer "F.SilkS")
		)
		(fp_line
			(start 1.943608 1.549908)
			(end -1.943608 1.549908)
			(stroke
				(width 0.1524)
				(type default)
			)
			(layer "F.SilkS")
		)
		(fp_poly
			(pts
				(xy -2.019808 -1.549908) (xy -1.257808 -1.549908) (xy -1.257808 -1.880108) (xy -2.019808 -1.880108)
			)
			(stroke
				(width 0)
				(type default)
			)
			(fill yes)
			(layer "F.SilkS")
		)
		(fp_line
			(start -1.549908 -1.549908)
			(end 1.549908 -1.549908)
			(stroke
				(width 0.1)
				(type default)
			)
			(layer "F.Fab")
		)
		(fp_line
			(start -1.549908 1.549908)
			(end -1.549908 -1.549908)
			(stroke
				(width 0.1)
				(type default)
			)
			(layer "F.Fab")
		)
		(fp_line
			(start 1.549908 -1.549908)
			(end 1.549908 1.549908)
			(stroke
				(width 0.1)
				(type default)
			)
			(layer "F.Fab")
		)
		(fp_line
			(start 1.549908 1.549908)
			(end -1.549908 1.549908)
			(stroke
				(width 0.1)
				(type default)
			)
			(layer "F.Fab")
		)
		(fp_poly
			(pts
				(xy -2.019808 -1.549908) (xy -1.257808 -1.549908) (xy -1.257808 -1.880108) (xy -2.019808 -1.880108)
			)
			(stroke
				(width 0)
				(type default)
			)
			(fill yes)
			(layer "F.Fab")
		)
		(pad "1" smd rect
			(at -1.500124 -1.249934 270)
			(size 0.2794 0.6096)
			(layers "F.Cu" "F.Mask" "F.Paste")
			(net "P12V_SSD6_R")
		)
		(pad "2" smd rect
			(at -1.500124 -0.750062 270)
			(size 0.2794 0.6096)
			(layers "F.Cu" "F.Mask" "F.Paste")
			(net "P12V_SSD6_R")
		)
		(pad "3" smd rect
			(at -1.500124 -0.249936 270)
			(size 0.2794 0.6096)
			(layers "F.Cu" "F.Mask" "F.Paste")
			(net "P12V_SSD6_R")
		)
		(pad "4" smd rect
			(at -1.500124 0.249936 270)
			(size 0.2794 0.6096)
			(layers "F.Cu" "F.Mask" "F.Paste")
			(net "P12V_SSD6_R")
		)
		(pad "5" smd rect
			(at -1.500124 0.750062 270)
			(size 0.2794 0.6096)
			(layers "F.Cu" "F.Mask" "F.Paste")
			(net "P12V_SSD6_R")
		)
		(pad "6" smd rect
			(at -1.500124 1.249934 270)
			(size 0.2794 0.6096)
			(layers "F.Cu" "F.Mask" "F.Paste")
			(net "GND")
		)
		(pad "7" smd rect
			(at 1.500124 1.249934 270)
			(size 0.2794 0.6096)
			(layers "F.Cu" "F.Mask" "F.Paste")
			(net "P12V_SSD6_SS")
		)
		(pad "8" smd rect
			(at 1.500124 0.750062 270)
			(size 0.2794 0.6096)
			(layers "F.Cu" "F.Mask" "F.Paste")
			(net "PWRGD_P12V_SSD6")
		)
		(pad "9" smd rect
			(at 1.500124 0.249936 270)
			(size 0.2794 0.6096)
			(layers "F.Cu" "F.Mask" "F.Paste")
			(net "P12V_SSD6_OCP")
		)
		(pad "10" smd rect
			(at 1.500124 -0.249936 270)
			(size 0.2794 0.6096)
			(layers "F.Cu" "F.Mask" "F.Paste")
			(net "P5V_AUX")
		)
		(pad "11" smd rect
			(at 1.500124 -0.750062 270)
			(size 0.2794 0.6096)
			(layers "F.Cu" "F.Mask" "F.Paste")
			(net "SSD6_PWR_EN_R")
		)
		(pad "12" smd rect
			(at 1.500124 -1.249934 270)
			(size 0.2794 0.6096)
			(layers "F.Cu" "F.Mask" "F.Paste")
			(net "P12V_AUX")
		)
		(pad "13" smd rect
			(at 0 0)
			(size 1.9812 2.7178)
			(layers "F.Cu" "F.Mask" "F.Paste")
			(net "P12V_AUX")
		)
		(zone
			(layer "F.Cu")
			(hatch none 0.5)
			(connect_pads
				(clearance 0)
			)
			(min_thickness 0.25)
			(keepout
				(tracks not_allowed)
				(vias allowed)
				(pads allowed)
				(copperpour not_allowed)
				(footprints allowed)
			)
			(placement
				(enabled no)
				(sheetname "")
			)
			(fill
				(thermal_gap 0.5)
				(thermal_bridge_width 0.5)
				(island_removal_mode 0)
			)
			(polygon
				(pts
					(xy 191.890142 -55.9435) (xy 191.890142 -55.8165) (xy 191.890142 -52.8447) (xy 191.890142 -52.844192)
					(xy 189.604142 -52.844192) (xy 189.604142 -52.8447) (xy 189.604142 -52.9717) (xy 189.604142 -54.3941)
					(xy 189.705742 -54.3941) (xy 189.705742 -52.9717) (xy 191.788542 -52.9717) (xy 191.788542 -55.8165)
					(xy 189.705742 -55.8165) (xy 189.705742 -54.4195) (xy 189.604142 -54.4195) (xy 189.604142 -55.8165)
					(xy 189.604142 -55.9435) (xy 189.604142 -55.944008) (xy 191.890142 -55.944008)
				)
			)
		)
	)
	(footprint ""
		(layer "F.Cu")
		(at 223.50476 -317.573914 180)
		(property "Reference" "PC1008"
			(at 0 0 180)
			(layer "F.SilkS")
			(hide yes)
			(effects
				(font
					(size 1.27 1.27)
				)
			)
		)
		(property "Value" ""
			(at 0 0 180)
			(layer "F.Fab")
			(effects
				(font
					(size 1.27 1.27)
				)
			)
		)
		(duplicate_pad_numbers_are_jumpers no)
		(fp_line
			(start 1.524 0.762)
			(end -1.524 0.762)
			(stroke
				(width 0.1524)
				(type default)
			)
			(layer "F.SilkS")
		)
		(fp_line
			(start 1.524 -0.762)
			(end 1.524 0.762)
			(stroke
				(width 0.1524)
				(type default)
			)
			(layer "F.SilkS")
		)
		(fp_line
			(start -1.524 0.762)
			(end -1.524 -0.762)
			(stroke
				(width 0.1524)
				(type default)
			)
			(layer "F.SilkS")
		)
		(fp_line
			(start -1.524 -0.762)
			(end 1.524 -0.762)
			(stroke
				(width 0.1524)
				(type default)
			)
			(layer "F.SilkS")
		)
		(fp_line
			(start 1.1049 0.724916)
			(end 1.1049 -0.724916)
			(stroke
				(width 0.1)
				(type default)
			)
			(layer "F.Fab")
		)
		(fp_line
			(start 1.1049 -0.724916)
			(end -1.1049 -0.724916)
			(stroke
				(width 0.1)
				(type default)
			)
			(layer "F.Fab")
		)
		(fp_line
			(start -1.1049 0.724916)
			(end 1.1049 0.724916)
			(stroke
				(width 0.1)
				(type default)
			)
			(layer "F.Fab")
		)
		(fp_line
			(start -1.1049 -0.724916)
			(end -1.1049 0.724916)
			(stroke
				(width 0.1)
				(type default)
			)
			(layer "F.Fab")
		)
		(pad "1" smd rect
			(at -0.889 0)
			(size 1.016 1.27)
			(layers "F.Cu" "F.Mask" "F.Paste")
			(net "SW_P12V_P1V25_PEX1_FLT")
		)
		(pad "2" smd rect
			(at 0.889 0)
			(size 1.016 1.27)
			(layers "F.Cu" "F.Mask" "F.Paste")
			(net "GND")
		)
	)
	(footprint ""
		(layer "F.Cu")
		(at 268.53515 -82.002122 180)
		(property "Reference" "R1073"
			(at 0 0 180)
			(layer "F.SilkS")
			(hide yes)
			(effects
				(font
					(size 1.27 1.27)
				)
			)
		)
		(property "Value" ""
			(at 0 0 180)
			(layer "F.Fab")
			(effects
				(font
					(size 1.27 1.27)
				)
			)
		)
		(duplicate_pad_numbers_are_jumpers no)
		(fp_line
			(start 0.7874 0.4064)
			(end -0.7874 0.4064)
			(stroke
				(width 0.1524)
				(type default)
			)
			(layer "F.SilkS")
		)
		(fp_line
			(start 0.67945 0.3048)
			(end 0.120396 0.3048)
			(stroke
				(width 0.1)
				(type default)
			)
			(layer "F.Fab")
		)
		(fp_line
			(start 0.67945 -0.3048)
			(end 0.67945 0.3048)
			(stroke
				(width 0.1)
				(type default)
			)
			(layer "F.Fab")
		)
		(fp_line
			(start 0.12065 -0.2794)
			(end 0.12065 -0.3048)
			(stroke
				(width 0.1)
				(type default)
			)
			(layer "F.Fab")
		)
		(fp_line
			(start 0.12065 -0.3048)
			(end 0.67945 -0.3048)
			(stroke
				(width 0.1)
				(type default)
			)
			(layer "F.Fab")
		)
		(fp_line
			(start 0.120396 0.3048)
			(end 0.120396 0.2794)
			(stroke
				(width 0.1)
				(type default)
			)
			(layer "F.Fab")
		)
		(fp_line
			(start 0.120396 0.2794)
			(end -0.12065 0.2794)
			(stroke
				(width 0.1)
				(type default)
			)
			(layer "F.Fab")
		)
		(fp_line
			(start -0.12065 0.3048)
			(end -0.67945 0.3048)
			(stroke
				(width 0.1)
				(type default)
			)
			(layer "F.Fab")
		)
		(fp_line
			(start -0.12065 0.2794)
			(end -0.12065 0.3048)
			(stroke
				(width 0.1)
				(type default)
			)
			(layer "F.Fab")
		)
		(fp_line
			(start -0.12065 -0.2794)
			(end 0.12065 -0.2794)
			(stroke
				(width 0.1)
				(type default)
			)
			(layer "F.Fab")
		)
		(fp_line
			(start -0.12065 -0.305054)
			(end -0.12065 -0.2794)
			(stroke
				(width 0.1)
				(type default)
			)
			(layer "F.Fab")
		)
		(fp_line
			(start -0.67945 0.3048)
			(end -0.67945 -0.305054)
			(stroke
				(width 0.1)
				(type default)
			)
			(layer "F.Fab")
		)
		(fp_line
			(start -0.67945 -0.305054)
			(end -0.12065 -0.305054)
			(stroke
				(width 0.1)
				(type default)
			)
			(layer "F.Fab")
		)
		(pad "1" smd circle
			(at -0.40005 0 180)
			(size 0 0)
			(layers "F.Cu" "F.Mask" "F.Paste")
			(net "CLK_100M_CK440Q_1_DB800ZL_R_DP")
		)
		(pad "2" smd circle
			(at 0.40005 0 180)
			(size 0 0)
			(layers "F.Cu" "F.Mask" "F.Paste")
			(net "CLK_100M_CK440Q_1_DB800ZL_DP")
		)
	)
	(footprint ""
		(layer "F.Cu")
		(at 312.823606 -87.349076 -90)
		(property "Reference" "R301"
			(at 0 0 270)
			(layer "F.SilkS")
			(hide yes)
			(effects
				(font
					(size 1.27 1.27)
				)
			)
		)
		(property "Value" ""
			(at 0 0 270)
			(layer "F.Fab")
			(effects
				(font
					(size 1.27 1.27)
				)
			)
		)
		(duplicate_pad_numbers_are_jumpers no)
		(fp_line
			(start -0.7874 0.4064)
			(end -0.7874 -0.4064)
			(stroke
				(width 0.1524)
				(type default)
			)
			(layer "F.SilkS")
		)
		(fp_line
			(start 0.7874 0.4064)
			(end -0.7874 0.4064)
			(stroke
				(width 0.1524)
				(type default)
			)
			(layer "F.SilkS")
		)
		(fp_line
			(start -0.7874 -0.4064)
			(end 0.7874 -0.4064)
			(stroke
				(width 0.1524)
				(type default)
			)
			(layer "F.SilkS")
		)
		(fp_line
			(start 0.7874 -0.4064)
			(end 0.7874 0.4064)
			(stroke
				(width 0.1524)
				(type default)
			)
			(layer "F.SilkS")
		)
		(fp_line
			(start -0.67945 0.3048)
			(end -0.67945 -0.305054)
			(stroke
				(width 0.1)
				(type default)
			)
			(layer "F.Fab")
		)
		(fp_line
			(start -0.12065 0.3048)
			(end -0.67945 0.3048)
			(stroke
				(width 0.1)
				(type default)
			)
			(layer "F.Fab")
		)
		(fp_line
			(start 0.120396 0.3048)
			(end 0.120396 0.2794)
			(stroke
				(width 0.1)
				(type default)
			)
			(layer "F.Fab")
		)
		(fp_line
			(start 0.67945 0.3048)
			(end 0.120396 0.3048)
			(stroke
				(width 0.1)
				(type default)
			)
			(layer "F.Fab")
		)
		(fp_line
			(start -0.12065 0.2794)
			(end -0.12065 0.3048)
			(stroke
				(width 0.1)
				(type default)
			)
			(layer "F.Fab")
		)
		(fp_line
			(start 0.120396 0.2794)
			(end -0.12065 0.2794)
			(stroke
				(width 0.1)
				(type default)
			)
			(layer "F.Fab")
		)
		(fp_line
			(start -0.12065 -0.2794)
			(end 0.12065 -0.2794)
			(stroke
				(width 0.1)
				(type default)
			)
			(layer "F.Fab")
		)
		(fp_line
			(start 0.12065 -0.2794)
			(end 0.12065 -0.3048)
			(stroke
				(width 0.1)
				(type default)
			)
			(layer "F.Fab")
		)
		(fp_line
			(start 0.12065 -0.3048)
			(end 0.67945 -0.3048)
			(stroke
				(width 0.1)
				(type default)
			)
			(layer "F.Fab")
		)
		(fp_line
			(start 0.67945 -0.3048)
			(end 0.67945 0.3048)
			(stroke
				(width 0.1)
				(type default)
			)
			(layer "F.Fab")
		)
		(fp_line
			(start -0.67945 -0.305054)
			(end -0.12065 -0.305054)
			(stroke
				(width 0.1)
				(type default)
			)
			(layer "F.Fab")
		)
		(fp_line
			(start -0.12065 -0.305054)
			(end -0.12065 -0.2794)
			(stroke
				(width 0.1)
				(type default)
			)
			(layer "F.Fab")
		)
		(pad "1" smd circle
			(at -0.40005 0 270)
			(size 0 0)
			(layers "F.Cu" "F.Mask" "F.Paste")
			(net "RST_NIC5_PERST1_R_N")
		)
		(pad "2" smd circle
			(at 0.40005 0 270)
			(size 0 0)
			(layers "F.Cu" "F.Mask" "F.Paste")
			(net "RST_HP_NIC5_BUF_N")
		)
	)
	(footprint ""
		(layer "F.Cu")
		(at 258.44373 -46.90491)
		(property "Reference" "R596"
			(at 0 0 0)
			(layer "F.SilkS")
			(hide yes)
			(effects
				(font
					(size 1.27 1.27)
				)
			)
		)
		(property "Value" ""
			(at 0 0 0)
			(layer "F.Fab")
			(effects
				(font
					(size 1.27 1.27)
				)
			)
		)
		(duplicate_pad_numbers_are_jumpers no)
		(fp_line
			(start -0.7874 -0.4064)
			(end 0.7874 -0.4064)
			(stroke
				(width 0.1524)
				(type default)
			)
			(layer "F.SilkS")
		)
		(fp_line
			(start -0.7874 0.4064)
			(end -0.7874 -0.4064)
			(stroke
				(width 0.1524)
				(type default)
			)
			(layer "F.SilkS")
		)
		(fp_line
			(start 0.7874 -0.4064)
			(end 0.7874 0.4064)
			(stroke
				(width 0.1524)
				(type default)
			)
			(layer "F.SilkS")
		)
		(fp_line
			(start 0.7874 0.4064)
			(end -0.7874 0.4064)
			(stroke
				(width 0.1524)
				(type default)
			)
			(layer "F.SilkS")
		)
		(fp_line
			(start -0.67945 -0.305054)
			(end -0.12065 -0.305054)
			(stroke
				(width 0.1)
				(type default)
			)
			(layer "F.Fab")
		)
		(fp_line
			(start -0.67945 0.3048)
			(end -0.67945 -0.305054)
			(stroke
				(width 0.1)
				(type default)
			)
			(layer "F.Fab")
		)
		(fp_line
			(start -0.12065 -0.305054)
			(end -0.12065 -0.2794)
			(stroke
				(width 0.1)
				(type default)
			)
			(layer "F.Fab")
		)
		(fp_line
			(start -0.12065 -0.2794)
			(end 0.12065 -0.2794)
			(stroke
				(width 0.1)
				(type default)
			)
			(layer "F.Fab")
		)
		(fp_line
			(start -0.12065 0.2794)
			(end -0.12065 0.3048)
			(stroke
				(width 0.1)
				(type default)
			)
			(layer "F.Fab")
		)
		(fp_line
			(start -0.12065 0.3048)
			(end -0.67945 0.3048)
			(stroke
				(width 0.1)
				(type default)
			)
			(layer "F.Fab")
		)
		(fp_line
			(start 0.120396 0.2794)
			(end -0.12065 0.2794)
			(stroke
				(width 0.1)
				(type default)
			)
			(layer "F.Fab")
		)
		(fp_line
			(start 0.120396 0.3048)
			(end 0.120396 0.2794)
			(stroke
				(width 0.1)
				(type default)
			)
			(layer "F.Fab")
		)
		(fp_line
			(start 0.12065 -0.3048)
			(end 0.67945 -0.3048)
			(stroke
				(width 0.1)
				(type default)
			)
			(layer "F.Fab")
		)
		(fp_line
			(start 0.12065 -0.2794)
			(end 0.12065 -0.3048)
			(stroke
				(width 0.1)
				(type default)
			)
			(layer "F.Fab")
		)
		(fp_line
			(start 0.67945 -0.3048)
			(end 0.67945 0.3048)
			(stroke
				(width 0.1)
				(type default)
			)
			(layer "F.Fab")
		)
		(fp_line
			(start 0.67945 0.3048)
			(end 0.120396 0.3048)
			(stroke
				(width 0.1)
				(type default)
			)
			(layer "F.Fab")
		)
		(pad "1" smd circle
			(at -0.40005 0)
			(size 0 0)
			(layers "F.Cu" "F.Mask" "F.Paste")
			(net "SSD8_ADC_ALERT_N")
		)
		(pad "2" smd circle
			(at 0.40005 0)
			(size 0 0)
			(layers "F.Cu" "F.Mask" "F.Paste")
			(net "SSD_8_15_ADC_ALERT_N")
		)
	)
	(footprint ""
		(layer "F.Cu")
		(at 218.080844 -96.139 -90)
		(property "Reference" "R715"
			(at 0 0 270)
			(layer "F.SilkS")
			(hide yes)
			(effects
				(font
					(size 1.27 1.27)
				)
			)
		)
		(property "Value" ""
			(at 0 0 270)
			(layer "F.Fab")
			(effects
				(font
					(size 1.27 1.27)
				)
			)
		)
		(duplicate_pad_numbers_are_jumpers no)
		(fp_line
			(start -0.7874 0.4064)
			(end -0.7874 -0.4064)
			(stroke
				(width 0.1524)
				(type default)
			)
			(layer "F.SilkS")
		)
		(fp_line
			(start 0.7874 0.4064)
			(end -0.7874 0.4064)
			(stroke
				(width 0.1524)
				(type default)
			)
			(layer "F.SilkS")
		)
		(fp_line
			(start -0.7874 -0.4064)
			(end 0.7874 -0.4064)
			(stroke
				(width 0.1524)
				(type default)
			)
			(layer "F.SilkS")
		)
		(fp_line
			(start 0.7874 -0.4064)
			(end 0.7874 0.4064)
			(stroke
				(width 0.1524)
				(type default)
			)
			(layer "F.SilkS")
		)
		(fp_line
			(start -0.67945 0.3048)
			(end -0.67945 -0.305054)
			(stroke
				(width 0.1)
				(type default)
			)
			(layer "F.Fab")
		)
		(fp_line
			(start -0.12065 0.3048)
			(end -0.67945 0.3048)
			(stroke
				(width 0.1)
				(type default)
			)
			(layer "F.Fab")
		)
		(fp_line
			(start 0.120396 0.3048)
			(end 0.120396 0.2794)
			(stroke
				(width 0.1)
				(type default)
			)
			(layer "F.Fab")
		)
		(fp_line
			(start 0.67945 0.3048)
			(end 0.120396 0.3048)
			(stroke
				(width 0.1)
				(type default)
			)
			(layer "F.Fab")
		)
		(fp_line
			(start -0.12065 0.2794)
			(end -0.12065 0.3048)
			(stroke
				(width 0.1)
				(type default)
			)
			(layer "F.Fab")
		)
		(fp_line
			(start 0.120396 0.2794)
			(end -0.12065 0.2794)
			(stroke
				(width 0.1)
				(type default)
			)
			(layer "F.Fab")
		)
		(fp_line
			(start -0.12065 -0.2794)
			(end 0.12065 -0.2794)
			(stroke
				(width 0.1)
				(type default)
			)
			(layer "F.Fab")
		)
		(fp_line
			(start 0.12065 -0.2794)
			(end 0.12065 -0.3048)
			(stroke
				(width 0.1)
				(type default)
			)
			(layer "F.Fab")
		)
		(fp_line
			(start 0.12065 -0.3048)
			(end 0.67945 -0.3048)
			(stroke
				(width 0.1)
				(type default)
			)
			(layer "F.Fab")
		)
		(fp_line
			(start 0.67945 -0.3048)
			(end 0.67945 0.3048)
			(stroke
				(width 0.1)
				(type default)
			)
			(layer "F.Fab")
		)
		(fp_line
			(start -0.67945 -0.305054)
			(end -0.12065 -0.305054)
			(stroke
				(width 0.1)
				(type default)
			)
			(layer "F.Fab")
		)
		(fp_line
			(start -0.12065 -0.305054)
			(end -0.12065 -0.2794)
			(stroke
				(width 0.1)
				(type default)
			)
			(layer "F.Fab")
		)
		(pad "1" smd circle
			(at -0.40005 0 270)
			(size 0 0)
			(layers "F.Cu" "F.Mask" "F.Paste")
			(net "NIC3_ADC_A0")
		)
		(pad "2" smd circle
			(at 0.40005 0 270)
			(size 0 0)
			(layers "F.Cu" "F.Mask" "F.Paste")
			(net "P3V3_AUX")
		)
	)
	(footprint ""
		(layer "F.Cu")
		(at 129.690114 -261.814564 180)
		(property "Reference" "R830"
			(at 0 0 180)
			(layer "F.SilkS")
			(hide yes)
			(effects
				(font
					(size 1.27 1.27)
				)
			)
		)
		(property "Value" ""
			(at 0 0 180)
			(layer "F.Fab")
			(effects
				(font
					(size 1.27 1.27)
				)
			)
		)
		(duplicate_pad_numbers_are_jumpers no)
		(fp_line
			(start 0.7874 0.4064)
			(end -0.7874 0.4064)
			(stroke
				(width 0.1524)
				(type default)
			)
			(layer "F.SilkS")
		)
		(fp_line
			(start 0.7874 -0.4064)
			(end 0.7874 0.4064)
			(stroke
				(width 0.1524)
				(type default)
			)
			(layer "F.SilkS")
		)
		(fp_line
			(start -0.7874 0.4064)
			(end -0.7874 -0.4064)
			(stroke
				(width 0.1524)
				(type default)
			)
			(layer "F.SilkS")
		)
		(fp_line
			(start -0.7874 -0.4064)
			(end 0.7874 -0.4064)
			(stroke
				(width 0.1524)
				(type default)
			)
			(layer "F.SilkS")
		)
		(fp_line
			(start 0.67945 0.3048)
			(end 0.120396 0.3048)
			(stroke
				(width 0.1)
				(type default)
			)
			(layer "F.Fab")
		)
		(fp_line
			(start 0.67945 -0.3048)
			(end 0.67945 0.3048)
			(stroke
				(width 0.1)
				(type default)
			)
			(layer "F.Fab")
		)
		(fp_line
			(start 0.12065 -0.2794)
			(end 0.12065 -0.3048)
			(stroke
				(width 0.1)
				(type default)
			)
			(layer "F.Fab")
		)
		(fp_line
			(start 0.12065 -0.3048)
			(end 0.67945 -0.3048)
			(stroke
				(width 0.1)
				(type default)
			)
			(layer "F.Fab")
		)
		(fp_line
			(start 0.120396 0.3048)
			(end 0.120396 0.2794)
			(stroke
				(width 0.1)
				(type default)
			)
			(layer "F.Fab")
		)
		(fp_line
			(start 0.120396 0.2794)
			(end -0.12065 0.2794)
			(stroke
				(width 0.1)
				(type default)
			)
			(layer "F.Fab")
		)
		(fp_line
			(start -0.12065 0.3048)
			(end -0.67945 0.3048)
			(stroke
				(width 0.1)
				(type default)
			)
			(layer "F.Fab")
		)
		(fp_line
			(start -0.12065 0.2794)
			(end -0.12065 0.3048)
			(stroke
				(width 0.1)
				(type default)
			)
			(layer "F.Fab")
		)
		(fp_line
			(start -0.12065 -0.2794)
			(end 0.12065 -0.2794)
			(stroke
				(width 0.1)
				(type default)
			)
			(layer "F.Fab")
		)
		(fp_line
			(start -0.12065 -0.305054)
			(end -0.12065 -0.2794)
			(stroke
				(width 0.1)
				(type default)
			)
			(layer "F.Fab")
		)
		(fp_line
			(start -0.67945 0.3048)
			(end -0.67945 -0.305054)
			(stroke
				(width 0.1)
				(type default)
			)
			(layer "F.Fab")
		)
		(fp_line
			(start -0.67945 -0.305054)
			(end -0.12065 -0.305054)
			(stroke
				(width 0.1)
				(type default)
			)
			(layer "F.Fab")
		)
		(pad "1" smd circle
			(at -0.40005 0 180)
			(size 0 0)
			(layers "F.Cu" "F.Mask" "F.Paste")
			(net "PWR_EN_PEX_R")
		)
		(pad "2" smd circle
			(at 0.40005 0 180)
			(size 0 0)
			(layers "F.Cu" "F.Mask" "F.Paste")
			(net "FM_P0V8_PEX1_EN_R")
		)
	)
	(footprint ""
		(layer "F.Cu")
		(at 394.734542 -34.546286 180)
		(property "Reference" "C706"
			(at 0 0 180)
			(layer "F.SilkS")
			(hide yes)
			(effects
				(font
					(size 1.27 1.27)
				)
			)
		)
		(property "Value" ""
			(at 0 0 180)
			(layer "F.Fab")
			(effects
				(font
					(size 1.27 1.27)
				)
			)
		)
		(duplicate_pad_numbers_are_jumpers no)
		(fp_line
			(start 0.299974 0.150114)
			(end -0.299974 0.150114)
			(stroke
				(width 0.1)
				(type default)
			)
			(layer "F.Fab")
		)
		(fp_line
			(start 0.299974 -0.150114)
			(end 0.299974 0.150114)
			(stroke
				(width 0.1)
				(type default)
			)
			(layer "F.Fab")
		)
		(fp_line
			(start -0.299974 0.150114)
			(end -0.299974 -0.150114)
			(stroke
				(width 0.1)
				(type default)
			)
			(layer "F.Fab")
		)
		(fp_line
			(start -0.299974 -0.150114)
			(end 0.299974 -0.150114)
			(stroke
				(width 0.1)
				(type default)
			)
			(layer "F.Fab")
		)
		(pad "1" smd rect
			(at -0.2667 0 180)
			(size 0.3048 0.381)
			(layers "F.Cu" "F.Mask" "F.Paste")
			(net "P5E_PEX3_STN2_TX_DP<43>")
		)
		(pad "2" smd rect
			(at 0.2667 0 180)
			(size 0.3048 0.381)
			(layers "F.Cu" "F.Mask" "F.Paste")
			(net "P5E_PEX3_STN2_TX_C_DP<43>")
		)
	)
	(footprint ""
		(layer "F.Cu")
		(at 121.96699 -52.543456 180)
		(property "Reference" "PC502"
			(at 0 0 180)
			(layer "F.SilkS")
			(hide yes)
			(effects
				(font
					(size 1.27 1.27)
				)
			)
		)
		(property "Value" ""
			(at 0 0 180)
			(layer "F.Fab")
			(effects
				(font
					(size 1.27 1.27)
				)
			)
		)
		(duplicate_pad_numbers_are_jumpers no)
		(fp_line
			(start 0.7874 0.4064)
			(end -0.7874 0.4064)
			(stroke
				(width 0.1524)
				(type default)
			)
			(layer "F.SilkS")
		)
		(fp_line
			(start 0.7874 -0.4064)
			(end 0.7874 0.4064)
			(stroke
				(width 0.1524)
				(type default)
			)
			(layer "F.SilkS")
		)
		(fp_line
			(start -0.7874 0.4064)
			(end -0.7874 -0.4064)
			(stroke
				(width 0.1524)
				(type default)
			)
			(layer "F.SilkS")
		)
		(fp_line
			(start -0.7874 -0.4064)
			(end 0.7874 -0.4064)
			(stroke
				(width 0.1524)
				(type default)
			)
			(layer "F.SilkS")
		)
		(fp_line
			(start 0.67945 0.3048)
			(end 0.120396 0.3048)
			(stroke
				(width 0.1)
				(type default)
			)
			(layer "F.Fab")
		)
		(fp_line
			(start 0.67945 -0.3048)
			(end 0.67945 0.3048)
			(stroke
				(width 0.1)
				(type default)
			)
			(layer "F.Fab")
		)
		(fp_line
			(start 0.12065 -0.2794)
			(end 0.12065 -0.3048)
			(stroke
				(width 0.1)
				(type default)
			)
			(layer "F.Fab")
		)
		(fp_line
			(start 0.12065 -0.3048)
			(end 0.67945 -0.3048)
			(stroke
				(width 0.1)
				(type default)
			)
			(layer "F.Fab")
		)
		(fp_line
			(start 0.120396 0.3048)
			(end 0.120396 0.2794)
			(stroke
				(width 0.1)
				(type default)
			)
			(layer "F.Fab")
		)
		(fp_line
			(start 0.120396 0.2794)
			(end -0.12065 0.2794)
			(stroke
				(width 0.1)
				(type default)
			)
			(layer "F.Fab")
		)
		(fp_line
			(start -0.12065 0.3048)
			(end -0.67945 0.3048)
			(stroke
				(width 0.1)
				(type default)
			)
			(layer "F.Fab")
		)
		(fp_line
			(start -0.12065 0.2794)
			(end -0.12065 0.3048)
			(stroke
				(width 0.1)
				(type default)
			)
			(layer "F.Fab")
		)
		(fp_line
			(start -0.12065 -0.2794)
			(end 0.12065 -0.2794)
			(stroke
				(width 0.1)
				(type default)
			)
			(layer "F.Fab")
		)
		(fp_line
			(start -0.12065 -0.305054)
			(end -0.12065 -0.2794)
			(stroke
				(width 0.1)
				(type default)
			)
			(layer "F.Fab")
		)
		(fp_line
			(start -0.67945 0.3048)
			(end -0.67945 -0.305054)
			(stroke
				(width 0.1)
				(type default)
			)
			(layer "F.Fab")
		)
		(fp_line
			(start -0.67945 -0.305054)
			(end -0.12065 -0.305054)
			(stroke
				(width 0.1)
				(type default)
			)
			(layer "F.Fab")
		)
		(pad "1" smd circle
			(at -0.40005 0 180)
			(size 0 0)
			(layers "F.Cu" "F.Mask" "F.Paste")
			(net "P3V3_SSD4")
		)
		(pad "2" smd circle
			(at 0.40005 0 180)
			(size 0 0)
			(layers "F.Cu" "F.Mask" "F.Paste")
			(net "GND")
		)
	)
	(footprint ""
		(layer "F.Cu")
		(at 10.693146 -151.737822 180)
		(property "Reference" "PR6861"
			(at 0 0 180)
			(layer "F.SilkS")
			(hide yes)
			(effects
				(font
					(size 1.27 1.27)
				)
			)
		)
		(property "Value" ""
			(at 0 0 180)
			(layer "F.Fab")
			(effects
				(font
					(size 1.27 1.27)
				)
			)
		)
		(duplicate_pad_numbers_are_jumpers no)
		(fp_line
			(start 0.7874 0.4064)
			(end -0.7874 0.4064)
			(stroke
				(width 0.1524)
				(type default)
			)
			(layer "F.SilkS")
		)
		(fp_line
			(start 0.7874 -0.4064)
			(end 0.7874 0.4064)
			(stroke
				(width 0.1524)
				(type default)
			)
			(layer "F.SilkS")
		)
		(fp_line
			(start -0.7874 0.4064)
			(end -0.7874 -0.4064)
			(stroke
				(width 0.1524)
				(type default)
			)
			(layer "F.SilkS")
		)
		(fp_line
			(start -0.7874 -0.4064)
			(end 0.7874 -0.4064)
			(stroke
				(width 0.1524)
				(type default)
			)
			(layer "F.SilkS")
		)
		(fp_line
			(start 0.67945 0.3048)
			(end 0.120396 0.3048)
			(stroke
				(width 0.1)
				(type default)
			)
			(layer "F.Fab")
		)
		(fp_line
			(start 0.67945 -0.3048)
			(end 0.67945 0.3048)
			(stroke
				(width 0.1)
				(type default)
			)
			(layer "F.Fab")
		)
		(fp_line
			(start 0.12065 -0.2794)
			(end 0.12065 -0.3048)
			(stroke
				(width 0.1)
				(type default)
			)
			(layer "F.Fab")
		)
		(fp_line
			(start 0.12065 -0.3048)
			(end 0.67945 -0.3048)
			(stroke
				(width 0.1)
				(type default)
			)
			(layer "F.Fab")
		)
		(fp_line
			(start 0.120396 0.3048)
			(end 0.120396 0.2794)
			(stroke
				(width 0.1)
				(type default)
			)
			(layer "F.Fab")
		)
		(fp_line
			(start 0.120396 0.2794)
			(end -0.12065 0.2794)
			(stroke
				(width 0.1)
				(type default)
			)
			(layer "F.Fab")
		)
		(fp_line
			(start -0.12065 0.3048)
			(end -0.67945 0.3048)
			(stroke
				(width 0.1)
				(type default)
			)
			(layer "F.Fab")
		)
		(fp_line
			(start -0.12065 0.2794)
			(end -0.12065 0.3048)
			(stroke
				(width 0.1)
				(type default)
			)
			(layer "F.Fab")
		)
		(fp_line
			(start -0.12065 -0.2794)
			(end 0.12065 -0.2794)
			(stroke
				(width 0.1)
				(type default)
			)
			(layer "F.Fab")
		)
		(fp_line
			(start -0.12065 -0.305054)
			(end -0.12065 -0.2794)
			(stroke
				(width 0.1)
				(type default)
			)
			(layer "F.Fab")
		)
		(fp_line
			(start -0.67945 0.3048)
			(end -0.67945 -0.305054)
			(stroke
				(width 0.1)
				(type default)
			)
			(layer "F.Fab")
		)
		(fp_line
			(start -0.67945 -0.305054)
			(end -0.12065 -0.305054)
			(stroke
				(width 0.1)
				(type default)
			)
			(layer "F.Fab")
		)
		(pad "1" smd circle
			(at -0.40005 0 180)
			(size 0 0)
			(layers "F.Cu" "F.Mask" "F.Paste")
			(net "P12V_NIC0_R")
		)
		(pad "2" smd circle
			(at 0.40005 0 180)
			(size 0 0)
			(layers "F.Cu" "F.Mask" "F.Paste")
			(net "P12V_NIC0_CO_AVIN_PD")
		)
	)
	(footprint ""
		(layer "F.Cu")
		(at 196.639434 -159.235648 180)
		(property "Reference" "R195"
			(at 0 0 180)
			(layer "F.SilkS")
			(hide yes)
			(effects
				(font
					(size 1.27 1.27)
				)
			)
		)
		(property "Value" ""
			(at 0 0 180)
			(layer "F.Fab")
			(effects
				(font
					(size 1.27 1.27)
				)
			)
		)
		(duplicate_pad_numbers_are_jumpers no)
		(fp_line
			(start 0.7874 0.4064)
			(end -0.7874 0.4064)
			(stroke
				(width 0.1524)
				(type default)
			)
			(layer "F.SilkS")
		)
		(fp_line
			(start 0.7874 -0.4064)
			(end 0.7874 0.4064)
			(stroke
				(width 0.1524)
				(type default)
			)
			(layer "F.SilkS")
		)
		(fp_line
			(start -0.7874 0.4064)
			(end -0.7874 -0.4064)
			(stroke
				(width 0.1524)
				(type default)
			)
			(layer "F.SilkS")
		)
		(fp_line
			(start -0.7874 -0.4064)
			(end 0.7874 -0.4064)
			(stroke
				(width 0.1524)
				(type default)
			)
			(layer "F.SilkS")
		)
		(fp_line
			(start 0.67945 0.3048)
			(end 0.120396 0.3048)
			(stroke
				(width 0.1)
				(type default)
			)
			(layer "F.Fab")
		)
		(fp_line
			(start 0.67945 -0.3048)
			(end 0.67945 0.3048)
			(stroke
				(width 0.1)
				(type default)
			)
			(layer "F.Fab")
		)
		(fp_line
			(start 0.12065 -0.2794)
			(end 0.12065 -0.3048)
			(stroke
				(width 0.1)
				(type default)
			)
			(layer "F.Fab")
		)
		(fp_line
			(start 0.12065 -0.3048)
			(end 0.67945 -0.3048)
			(stroke
				(width 0.1)
				(type default)
			)
			(layer "F.Fab")
		)
		(fp_line
			(start 0.120396 0.3048)
			(end 0.120396 0.2794)
			(stroke
				(width 0.1)
				(type default)
			)
			(layer "F.Fab")
		)
		(fp_line
			(start 0.120396 0.2794)
			(end -0.12065 0.2794)
			(stroke
				(width 0.1)
				(type default)
			)
			(layer "F.Fab")
		)
		(fp_line
			(start -0.12065 0.3048)
			(end -0.67945 0.3048)
			(stroke
				(width 0.1)
				(type default)
			)
			(layer "F.Fab")
		)
		(fp_line
			(start -0.12065 0.2794)
			(end -0.12065 0.3048)
			(stroke
				(width 0.1)
				(type default)
			)
			(layer "F.Fab")
		)
		(fp_line
			(start -0.12065 -0.2794)
			(end 0.12065 -0.2794)
			(stroke
				(width 0.1)
				(type default)
			)
			(layer "F.Fab")
		)
		(fp_line
			(start -0.12065 -0.305054)
			(end -0.12065 -0.2794)
			(stroke
				(width 0.1)
				(type default)
			)
			(layer "F.Fab")
		)
		(fp_line
			(start -0.67945 0.3048)
			(end -0.67945 -0.305054)
			(stroke
				(width 0.1)
				(type default)
			)
			(layer "F.Fab")
		)
		(fp_line
			(start -0.67945 -0.305054)
			(end -0.12065 -0.305054)
			(stroke
				(width 0.1)
				(type default)
			)
			(layer "F.Fab")
		)
		(pad "1" smd circle
			(at -0.40005 0 180)
			(size 0 0)
			(layers "F.Cu" "F.Mask" "F.Paste")
			(net "PRSNT_NIC3_N")
		)
		(pad "2" smd circle
			(at 0.40005 0 180)
			(size 0 0)
			(layers "F.Cu" "F.Mask" "F.Paste")
			(net "PRSNTB3_NIC3_N")
		)
	)
	(footprint ""
		(layer "F.Cu")
		(at 277.44674 -38.49116 180)
		(property "Reference" "R6100"
			(at 0 0 180)
			(layer "F.SilkS")
			(hide yes)
			(effects
				(font
					(size 1.27 1.27)
				)
			)
		)
		(property "Value" ""
			(at 0 0 180)
			(layer "F.Fab")
			(effects
				(font
					(size 1.27 1.27)
				)
			)
		)
		(duplicate_pad_numbers_are_jumpers no)
		(fp_line
			(start 0.7874 0.4064)
			(end -0.7874 0.4064)
			(stroke
				(width 0.1524)
				(type default)
			)
			(layer "F.SilkS")
		)
		(fp_line
			(start 0.7874 -0.4064)
			(end 0.7874 0.4064)
			(stroke
				(width 0.1524)
				(type default)
			)
			(layer "F.SilkS")
		)
		(fp_line
			(start -0.7874 0.4064)
			(end -0.7874 -0.4064)
			(stroke
				(width 0.1524)
				(type default)
			)
			(layer "F.SilkS")
		)
		(fp_line
			(start -0.7874 -0.4064)
			(end 0.7874 -0.4064)
			(stroke
				(width 0.1524)
				(type default)
			)
			(layer "F.SilkS")
		)
		(fp_line
			(start 0.67945 0.3048)
			(end 0.120396 0.3048)
			(stroke
				(width 0.1)
				(type default)
			)
			(layer "F.Fab")
		)
		(fp_line
			(start 0.67945 -0.3048)
			(end 0.67945 0.3048)
			(stroke
				(width 0.1)
				(type default)
			)
			(layer "F.Fab")
		)
		(fp_line
			(start 0.12065 -0.2794)
			(end 0.12065 -0.3048)
			(stroke
				(width 0.1)
				(type default)
			)
			(layer "F.Fab")
		)
		(fp_line
			(start 0.12065 -0.3048)
			(end 0.67945 -0.3048)
			(stroke
				(width 0.1)
				(type default)
			)
			(layer "F.Fab")
		)
		(fp_line
			(start 0.120396 0.3048)
			(end 0.120396 0.2794)
			(stroke
				(width 0.1)
				(type default)
			)
			(layer "F.Fab")
		)
		(fp_line
			(start 0.120396 0.2794)
			(end -0.12065 0.2794)
			(stroke
				(width 0.1)
				(type default)
			)
			(layer "F.Fab")
		)
		(fp_line
			(start -0.12065 0.3048)
			(end -0.67945 0.3048)
			(stroke
				(width 0.1)
				(type default)
			)
			(layer "F.Fab")
		)
		(fp_line
			(start -0.12065 0.2794)
			(end -0.12065 0.3048)
			(stroke
				(width 0.1)
				(type default)
			)
			(layer "F.Fab")
		)
		(fp_line
			(start -0.12065 -0.2794)
			(end 0.12065 -0.2794)
			(stroke
				(width 0.1)
				(type default)
			)
			(layer "F.Fab")
		)
		(fp_line
			(start -0.12065 -0.305054)
			(end -0.12065 -0.2794)
			(stroke
				(width 0.1)
				(type default)
			)
			(layer "F.Fab")
		)
		(fp_line
			(start -0.67945 0.3048)
			(end -0.67945 -0.305054)
			(stroke
				(width 0.1)
				(type default)
			)
			(layer "F.Fab")
		)
		(fp_line
			(start -0.67945 -0.305054)
			(end -0.12065 -0.305054)
			(stroke
				(width 0.1)
				(type default)
			)
			(layer "F.Fab")
		)
		(pad "1" smd circle
			(at -0.40005 0 180)
			(size 0 0)
			(layers "F.Cu" "F.Mask" "F.Paste")
			(net "P3V3_SSD10_PG_G1")
		)
		(pad "2" smd circle
			(at 0.40005 0 180)
			(size 0 0)
			(layers "F.Cu" "F.Mask" "F.Paste")
			(net "GND")
		)
	)
	(footprint ""
		(layer "F.Cu")
		(at 221.251272 -142.926562)
		(property "Reference" "R4210"
			(at 0 0 0)
			(layer "F.SilkS")
			(hide yes)
			(effects
				(font
					(size 1.27 1.27)
				)
			)
		)
		(property "Value" ""
			(at 0 0 0)
			(layer "F.Fab")
			(effects
				(font
					(size 1.27 1.27)
				)
			)
		)
		(duplicate_pad_numbers_are_jumpers no)
		(fp_line
			(start -0.7874 -0.4064)
			(end 0.7874 -0.4064)
			(stroke
				(width 0.1524)
				(type default)
			)
			(layer "F.SilkS")
		)
		(fp_line
			(start -0.7874 0.4064)
			(end -0.7874 -0.4064)
			(stroke
				(width 0.1524)
				(type default)
			)
			(layer "F.SilkS")
		)
		(fp_line
			(start 0.7874 -0.4064)
			(end 0.7874 0.4064)
			(stroke
				(width 0.1524)
				(type default)
			)
			(layer "F.SilkS")
		)
		(fp_line
			(start 0.7874 0.4064)
			(end -0.7874 0.4064)
			(stroke
				(width 0.1524)
				(type default)
			)
			(layer "F.SilkS")
		)
		(fp_line
			(start -0.67945 -0.305054)
			(end -0.12065 -0.305054)
			(stroke
				(width 0.1)
				(type default)
			)
			(layer "F.Fab")
		)
		(fp_line
			(start -0.67945 0.3048)
			(end -0.67945 -0.305054)
			(stroke
				(width 0.1)
				(type default)
			)
			(layer "F.Fab")
		)
		(fp_line
			(start -0.12065 -0.305054)
			(end -0.12065 -0.2794)
			(stroke
				(width 0.1)
				(type default)
			)
			(layer "F.Fab")
		)
		(fp_line
			(start -0.12065 -0.2794)
			(end 0.12065 -0.2794)
			(stroke
				(width 0.1)
				(type default)
			)
			(layer "F.Fab")
		)
		(fp_line
			(start -0.12065 0.2794)
			(end -0.12065 0.3048)
			(stroke
				(width 0.1)
				(type default)
			)
			(layer "F.Fab")
		)
		(fp_line
			(start -0.12065 0.3048)
			(end -0.67945 0.3048)
			(stroke
				(width 0.1)
				(type default)
			)
			(layer "F.Fab")
		)
		(fp_line
			(start 0.120396 0.2794)
			(end -0.12065 0.2794)
			(stroke
				(width 0.1)
				(type default)
			)
			(layer "F.Fab")
		)
		(fp_line
			(start 0.120396 0.3048)
			(end 0.120396 0.2794)
			(stroke
				(width 0.1)
				(type default)
			)
			(layer "F.Fab")
		)
		(fp_line
			(start 0.12065 -0.3048)
			(end 0.67945 -0.3048)
			(stroke
				(width 0.1)
				(type default)
			)
			(layer "F.Fab")
		)
		(fp_line
			(start 0.12065 -0.2794)
			(end 0.12065 -0.3048)
			(stroke
				(width 0.1)
				(type default)
			)
			(layer "F.Fab")
		)
		(fp_line
			(start 0.67945 -0.3048)
			(end 0.67945 0.3048)
			(stroke
				(width 0.1)
				(type default)
			)
			(layer "F.Fab")
		)
		(fp_line
			(start 0.67945 0.3048)
			(end 0.120396 0.3048)
			(stroke
				(width 0.1)
				(type default)
			)
			(layer "F.Fab")
		)
		(pad "1" smd circle
			(at -0.40005 0)
			(size 0 0)
			(layers "F.Cu" "F.Mask" "F.Paste")
			(net "GND")
		)
		(pad "2" smd circle
			(at 0.40005 0)
			(size 0 0)
			(layers "F.Cu" "F.Mask" "F.Paste")
			(net "FM_CK440_PEX_DEV_25M_EN")
		)
	)
	(footprint ""
		(layer "F.Cu")
		(at 150.394162 -241.610134 90)
		(property "Reference" "R6574"
			(at 0 0 90)
			(layer "F.SilkS")
			(hide yes)
			(effects
				(font
					(size 1.27 1.27)
				)
			)
		)
		(property "Value" ""
			(at 0 0 90)
			(layer "F.Fab")
			(effects
				(font
					(size 1.27 1.27)
				)
			)
		)
		(duplicate_pad_numbers_are_jumpers no)
		(fp_line
			(start 0.7874 -0.4064)
			(end 0.7874 0.4064)
			(stroke
				(width 0.1524)
				(type default)
			)
			(layer "F.SilkS")
		)
		(fp_line
			(start -0.7874 -0.4064)
			(end 0.7874 -0.4064)
			(stroke
				(width 0.1524)
				(type default)
			)
			(layer "F.SilkS")
		)
		(fp_line
			(start 0.7874 0.4064)
			(end -0.7874 0.4064)
			(stroke
				(width 0.1524)
				(type default)
			)
			(layer "F.SilkS")
		)
		(fp_line
			(start -0.7874 0.4064)
			(end -0.7874 -0.4064)
			(stroke
				(width 0.1524)
				(type default)
			)
			(layer "F.SilkS")
		)
		(fp_line
			(start -0.12065 -0.305054)
			(end -0.12065 -0.2794)
			(stroke
				(width 0.1)
				(type default)
			)
			(layer "F.Fab")
		)
		(fp_line
			(start -0.67945 -0.305054)
			(end -0.12065 -0.305054)
			(stroke
				(width 0.1)
				(type default)
			)
			(layer "F.Fab")
		)
		(fp_line
			(start 0.67945 -0.3048)
			(end 0.67945 0.3048)
			(stroke
				(width 0.1)
				(type default)
			)
			(layer "F.Fab")
		)
		(fp_line
			(start 0.12065 -0.3048)
			(end 0.67945 -0.3048)
			(stroke
				(width 0.1)
				(type default)
			)
			(layer "F.Fab")
		)
		(fp_line
			(start 0.12065 -0.2794)
			(end 0.12065 -0.3048)
			(stroke
				(width 0.1)
				(type default)
			)
			(layer "F.Fab")
		)
		(fp_line
			(start -0.12065 -0.2794)
			(end 0.12065 -0.2794)
			(stroke
				(width 0.1)
				(type default)
			)
			(layer "F.Fab")
		)
		(fp_line
			(start 0.120396 0.2794)
			(end -0.12065 0.2794)
			(stroke
				(width 0.1)
				(type default)
			)
			(layer "F.Fab")
		)
		(fp_line
			(start -0.12065 0.2794)
			(end -0.12065 0.3048)
			(stroke
				(width 0.1)
				(type default)
			)
			(layer "F.Fab")
		)
		(fp_line
			(start 0.67945 0.3048)
			(end 0.120396 0.3048)
			(stroke
				(width 0.1)
				(type default)
			)
			(layer "F.Fab")
		)
		(fp_line
			(start 0.120396 0.3048)
			(end 0.120396 0.2794)
			(stroke
				(width 0.1)
				(type default)
			)
			(layer "F.Fab")
		)
		(fp_line
			(start -0.12065 0.3048)
			(end -0.67945 0.3048)
			(stroke
				(width 0.1)
				(type default)
			)
			(layer "F.Fab")
		)
		(fp_line
			(start -0.67945 0.3048)
			(end -0.67945 -0.305054)
			(stroke
				(width 0.1)
				(type default)
			)
			(layer "F.Fab")
		)
		(pad "1" smd circle
			(at -0.40005 0 90)
			(size 0 0)
			(layers "F.Cu" "F.Mask" "F.Paste")
			(net "P1V8_PLL_PEX1_ADJ")
		)
		(pad "2" smd circle
			(at 0.40005 0 90)
			(size 0 0)
			(layers "F.Cu" "F.Mask" "F.Paste")
			(net "GND")
		)
	)
	(footprint ""
		(layer "F.Cu")
		(at 83.109562 -343.952322 90)
		(property "Reference" "C107"
			(at 0 0 90)
			(layer "F.SilkS")
			(hide yes)
			(effects
				(font
					(size 1.27 1.27)
				)
			)
		)
		(property "Value" ""
			(at 0 0 90)
			(layer "F.Fab")
			(effects
				(font
					(size 1.27 1.27)
				)
			)
		)
		(duplicate_pad_numbers_are_jumpers no)
		(fp_line
			(start 0.299974 -0.150114)
			(end 0.299974 0.150114)
			(stroke
				(width 0.1)
				(type default)
			)
			(layer "F.Fab")
		)
		(fp_line
			(start -0.299974 -0.150114)
			(end 0.299974 -0.150114)
			(stroke
				(width 0.1)
				(type default)
			)
			(layer "F.Fab")
		)
		(fp_line
			(start 0.299974 0.150114)
			(end -0.299974 0.150114)
			(stroke
				(width 0.1)
				(type default)
			)
			(layer "F.Fab")
		)
		(fp_line
			(start -0.299974 0.150114)
			(end -0.299974 -0.150114)
			(stroke
				(width 0.1)
				(type default)
			)
			(layer "F.Fab")
		)
		(pad "1" smd rect
			(at -0.2667 0 90)
			(size 0.3048 0.381)
			(layers "F.Cu" "F.Mask" "F.Paste")
			(net "P5E_PEX0_STN5_TX_DP<90>")
		)
		(pad "2" smd rect
			(at 0.2667 0 90)
			(size 0.3048 0.381)
			(layers "F.Cu" "F.Mask" "F.Paste")
			(net "P5E_PEX0_STN5_TX_C_DP<90>")
		)
	)
	(footprint ""
		(layer "F.Cu")
		(at 161.626804 -55.418228 90)
		(property "Reference" "PC370"
			(at 0 0 90)
			(layer "F.SilkS")
			(hide yes)
			(effects
				(font
					(size 1.27 1.27)
				)
			)
		)
		(property "Value" ""
			(at 0 0 90)
			(layer "F.Fab")
			(effects
				(font
					(size 1.27 1.27)
				)
			)
		)
		(duplicate_pad_numbers_are_jumpers no)
		(fp_line
			(start 0.7874 -0.4064)
			(end 0.7874 0.4064)
			(stroke
				(width 0.1524)
				(type default)
			)
			(layer "F.SilkS")
		)
		(fp_line
			(start -0.7874 -0.4064)
			(end 0.7874 -0.4064)
			(stroke
				(width 0.1524)
				(type default)
			)
			(layer "F.SilkS")
		)
		(fp_line
			(start 0.7874 0.4064)
			(end -0.7874 0.4064)
			(stroke
				(width 0.1524)
				(type default)
			)
			(layer "F.SilkS")
		)
		(fp_line
			(start -0.7874 0.4064)
			(end -0.7874 -0.4064)
			(stroke
				(width 0.1524)
				(type default)
			)
			(layer "F.SilkS")
		)
		(fp_line
			(start -0.12065 -0.305054)
			(end -0.12065 -0.2794)
			(stroke
				(width 0.1)
				(type default)
			)
			(layer "F.Fab")
		)
		(fp_line
			(start -0.67945 -0.305054)
			(end -0.12065 -0.305054)
			(stroke
				(width 0.1)
				(type default)
			)
			(layer "F.Fab")
		)
		(fp_line
			(start 0.67945 -0.3048)
			(end 0.67945 0.3048)
			(stroke
				(width 0.1)
				(type default)
			)
			(layer "F.Fab")
		)
		(fp_line
			(start 0.12065 -0.3048)
			(end 0.67945 -0.3048)
			(stroke
				(width 0.1)
				(type default)
			)
			(layer "F.Fab")
		)
		(fp_line
			(start 0.12065 -0.2794)
			(end 0.12065 -0.3048)
			(stroke
				(width 0.1)
				(type default)
			)
			(layer "F.Fab")
		)
		(fp_line
			(start -0.12065 -0.2794)
			(end 0.12065 -0.2794)
			(stroke
				(width 0.1)
				(type default)
			)
			(layer "F.Fab")
		)
		(fp_line
			(start 0.120396 0.2794)
			(end -0.12065 0.2794)
			(stroke
				(width 0.1)
				(type default)
			)
			(layer "F.Fab")
		)
		(fp_line
			(start -0.12065 0.2794)
			(end -0.12065 0.3048)
			(stroke
				(width 0.1)
				(type default)
			)
			(layer "F.Fab")
		)
		(fp_line
			(start 0.67945 0.3048)
			(end 0.120396 0.3048)
			(stroke
				(width 0.1)
				(type default)
			)
			(layer "F.Fab")
		)
		(fp_line
			(start 0.120396 0.3048)
			(end 0.120396 0.2794)
			(stroke
				(width 0.1)
				(type default)
			)
			(layer "F.Fab")
		)
		(fp_line
			(start -0.12065 0.3048)
			(end -0.67945 0.3048)
			(stroke
				(width 0.1)
				(type default)
			)
			(layer "F.Fab")
		)
		(fp_line
			(start -0.67945 0.3048)
			(end -0.67945 -0.305054)
			(stroke
				(width 0.1)
				(type default)
			)
			(layer "F.Fab")
		)
		(pad "1" smd circle
			(at -0.40005 0 90)
			(size 0 0)
			(layers "F.Cu" "F.Mask" "F.Paste")
			(net "P12V_SSD5_R")
		)
		(pad "2" smd circle
			(at 0.40005 0 90)
			(size 0 0)
			(layers "F.Cu" "F.Mask" "F.Paste")
			(net "GND")
		)
	)
	(footprint ""
		(layer "F.Cu")
		(at 253.587504 -201.87793 90)
		(property "Reference" "U294"
			(at -1.692656 3.454146 90)
			(unlocked yes)
			(layer "F.SilkS")
			(effects
				(font
					(size 0.7874 0.5842)
					(thickness 0.1524)
				)
				(justify left)
			)
		)
		(property "Value" ""
			(at 0 0 90)
			(layer "F.Fab")
			(effects
				(font
					(size 1.27 1.27)
				)
			)
		)
		(duplicate_pad_numbers_are_jumpers no)
		(fp_line
			(start 2.0066 -2.5527)
			(end 2.0066 2.5527)
			(stroke
				(width 0.1524)
				(type default)
			)
			(layer "F.SilkS")
		)
		(fp_line
			(start 0.5715 -2.5527)
			(end 2.0066 -2.5527)
			(stroke
				(width 0.1524)
				(type default)
			)
			(layer "F.SilkS")
		)
		(fp_line
			(start -0.5715 -2.5527)
			(end 0 -1.9812)
			(stroke
				(width 0.1524)
				(type default)
			)
			(layer "F.SilkS")
		)
		(fp_line
			(start -2.0066 -2.5527)
			(end -0.5715 -2.5527)
			(stroke
				(width 0.1524)
				(type default)
			)
			(layer "F.SilkS")
		)
		(fp_line
			(start 0 -1.9812)
			(end 0.5715 -2.5527)
			(stroke
				(width 0.1524)
				(type default)
			)
			(layer "F.SilkS")
		)
		(fp_line
			(start 2.0066 2.5527)
			(end -2.0066 2.5527)
			(stroke
				(width 0.1524)
				(type default)
			)
			(layer "F.SilkS")
		)
		(fp_line
			(start -2.0066 2.5527)
			(end -2.0066 -2.5527)
			(stroke
				(width 0.1524)
				(type default)
			)
			(layer "F.SilkS")
		)
		(fp_poly
			(pts
				(xy -4.90982 -1.712214) (xy -4.90982 -2.337054) (xy -4.3561 -2.008886)
			)
			(stroke
				(width 0)
				(type default)
			)
			(fill yes)
			(layer "F.SilkS")
		)
		(fp_line
			(start 2.249932 -2.549906)
			(end 2.249932 2.549906)
			(stroke
				(width 0.1)
				(type default)
			)
			(layer "F.Fab")
		)
		(fp_line
			(start -2.249932 -2.549906)
			(end 2.249932 -2.549906)
			(stroke
				(width 0.1)
				(type default)
			)
			(layer "F.Fab")
		)
		(fp_line
			(start 2.249932 2.549906)
			(end -2.249932 2.549906)
			(stroke
				(width 0.1)
				(type default)
			)
			(layer "F.Fab")
		)
		(fp_line
			(start -2.249932 2.549906)
			(end -2.249932 -2.549906)
			(stroke
				(width 0.1)
				(type default)
			)
			(layer "F.Fab")
		)
		(fp_poly
			(pts
				(xy -4.36372 -1.608328) (xy -4.36372 -2.233168) (xy -3.81 -1.905)
			)
			(stroke
				(width 0)
				(type default)
			)
			(fill yes)
			(layer "F.Fab")
		)
		(pad "1" smd rect
			(at -2.921 -1.949958)
			(size 0.3556 1.4986)
			(layers "F.Cu" "F.Mask" "F.Paste")
			(net "JTAG_BIC_EN_R")
		)
		(pad "2" smd rect
			(at -2.921 -1.299972)
			(size 0.3556 1.4986)
			(layers "F.Cu" "F.Mask" "F.Paste")
			(net "JTAG_BIC_TCK_R1")
		)
		(pad "3" smd rect
			(at -2.921 -0.649986)
			(size 0.3556 1.4986)
			(layers "F.Cu" "F.Mask" "F.Paste")
			(net "JTAG_PLD_TCK")
		)
		(pad "4" smd rect
			(at -2.921 0)
			(size 0.3556 1.4986)
			(layers "F.Cu" "F.Mask" "F.Paste")
			(net "JTAG_BIC_EN_R")
		)
		(pad "5" smd rect
			(at -2.921 0.649986)
			(size 0.3556 1.4986)
			(layers "F.Cu" "F.Mask" "F.Paste")
			(net "JTAG_BIC_TMS_R1")
		)
		(pad "6" smd rect
			(at -2.921 1.299972)
			(size 0.3556 1.4986)
			(layers "F.Cu" "F.Mask" "F.Paste")
			(net "JTAG_PLD_TMS")
		)
		(pad "7" smd rect
			(at -2.921 1.949958)
			(size 0.3556 1.4986)
			(layers "F.Cu" "F.Mask" "F.Paste")
			(net "GND")
		)
		(pad "8" smd rect
			(at 2.921 1.949958)
			(size 0.3556 1.4986)
			(layers "F.Cu" "F.Mask" "F.Paste")
			(net "JTAG_PLD_TDI")
		)
		(pad "9" smd rect
			(at 2.921 1.299972)
			(size 0.3556 1.4986)
			(layers "F.Cu" "F.Mask" "F.Paste")
			(net "JTAG_BIC_TDI_R1")
		)
		(pad "10" smd rect
			(at 2.921 0.649986)
			(size 0.3556 1.4986)
			(layers "F.Cu" "F.Mask" "F.Paste")
			(net "JTAG_BIC_EN_R")
		)
		(pad "11" smd rect
			(at 2.921 0)
			(size 0.3556 1.4986)
			(layers "F.Cu" "F.Mask" "F.Paste")
			(net "JTAG_PLD_TDO")
		)
		(pad "12" smd rect
			(at 2.921 -0.649986)
			(size 0.3556 1.4986)
			(layers "F.Cu" "F.Mask" "F.Paste")
			(net "JTAG_BIC_TDO")
		)
		(pad "13" smd rect
			(at 2.921 -1.299972)
			(size 0.3556 1.4986)
			(layers "F.Cu" "F.Mask" "F.Paste")
			(net "JTAG_BIC_EN_R")
		)
		(pad "14" smd rect
			(at 2.921 -1.949958)
			(size 0.3556 1.4986)
			(layers "F.Cu" "F.Mask" "F.Paste")
			(net "P3V3_AUX")
		)
	)
	(footprint ""
		(layer "F.Cu")
		(at 305.147218 -19.33956)
		(property "Reference" "C3944"
			(at 0 0 0)
			(layer "F.SilkS")
			(hide yes)
			(effects
				(font
					(size 1.27 1.27)
				)
			)
		)
		(property "Value" ""
			(at 0 0 0)
			(layer "F.Fab")
			(effects
				(font
					(size 1.27 1.27)
				)
			)
		)
		(duplicate_pad_numbers_are_jumpers no)
		(fp_line
			(start -0.7874 -0.4064)
			(end 0.7874 -0.4064)
			(stroke
				(width 0.1524)
				(type default)
			)
			(layer "F.SilkS")
		)
		(fp_line
			(start -0.7874 0.4064)
			(end -0.7874 -0.4064)
			(stroke
				(width 0.1524)
				(type default)
			)
			(layer "F.SilkS")
		)
		(fp_line
			(start 0.7874 -0.4064)
			(end 0.7874 0.4064)
			(stroke
				(width 0.1524)
				(type default)
			)
			(layer "F.SilkS")
		)
		(fp_line
			(start 0.7874 0.4064)
			(end -0.7874 0.4064)
			(stroke
				(width 0.1524)
				(type default)
			)
			(layer "F.SilkS")
		)
		(fp_line
			(start -0.67945 -0.305054)
			(end -0.12065 -0.305054)
			(stroke
				(width 0.1)
				(type default)
			)
			(layer "F.Fab")
		)
		(fp_line
			(start -0.67945 0.3048)
			(end -0.67945 -0.305054)
			(stroke
				(width 0.1)
				(type default)
			)
			(layer "F.Fab")
		)
		(fp_line
			(start -0.12065 -0.305054)
			(end -0.12065 -0.2794)
			(stroke
				(width 0.1)
				(type default)
			)
			(layer "F.Fab")
		)
		(fp_line
			(start -0.12065 -0.2794)
			(end 0.12065 -0.2794)
			(stroke
				(width 0.1)
				(type default)
			)
			(layer "F.Fab")
		)
		(fp_line
			(start -0.12065 0.2794)
			(end -0.12065 0.3048)
			(stroke
				(width 0.1)
				(type default)
			)
			(layer "F.Fab")
		)
		(fp_line
			(start -0.12065 0.3048)
			(end -0.67945 0.3048)
			(stroke
				(width 0.1)
				(type default)
			)
			(layer "F.Fab")
		)
		(fp_line
			(start 0.120396 0.2794)
			(end -0.12065 0.2794)
			(stroke
				(width 0.1)
				(type default)
			)
			(layer "F.Fab")
		)
		(fp_line
			(start 0.120396 0.3048)
			(end 0.120396 0.2794)
			(stroke
				(width 0.1)
				(type default)
			)
			(layer "F.Fab")
		)
		(fp_line
			(start 0.12065 -0.3048)
			(end 0.67945 -0.3048)
			(stroke
				(width 0.1)
				(type default)
			)
			(layer "F.Fab")
		)
		(fp_line
			(start 0.12065 -0.2794)
			(end 0.12065 -0.3048)
			(stroke
				(width 0.1)
				(type default)
			)
			(layer "F.Fab")
		)
		(fp_line
			(start 0.67945 -0.3048)
			(end 0.67945 0.3048)
			(stroke
				(width 0.1)
				(type default)
			)
			(layer "F.Fab")
		)
		(fp_line
			(start 0.67945 0.3048)
			(end 0.120396 0.3048)
			(stroke
				(width 0.1)
				(type default)
			)
			(layer "F.Fab")
		)
		(pad "1" smd circle
			(at -0.40005 0)
			(size 0 0)
			(layers "F.Cu" "F.Mask" "F.Paste")
			(net "P12V_SSD10")
		)
		(pad "2" smd circle
			(at 0.40005 0)
			(size 0 0)
			(layers "F.Cu" "F.Mask" "F.Paste")
			(net "GND")
		)
	)
	(footprint ""
		(layer "F.Cu")
		(at 376.754898 -22.961346 90)
		(property "Reference" "R1715"
			(at 0 0 90)
			(layer "F.SilkS")
			(hide yes)
			(effects
				(font
					(size 1.27 1.27)
				)
			)
		)
		(property "Value" ""
			(at 0 0 90)
			(layer "F.Fab")
			(effects
				(font
					(size 1.27 1.27)
				)
			)
		)
		(duplicate_pad_numbers_are_jumpers no)
		(fp_line
			(start 0.7874 -0.4064)
			(end 0.7874 0.4064)
			(stroke
				(width 0.1524)
				(type default)
			)
			(layer "F.SilkS")
		)
		(fp_line
			(start -0.7874 -0.4064)
			(end 0.7874 -0.4064)
			(stroke
				(width 0.1524)
				(type default)
			)
			(layer "F.SilkS")
		)
		(fp_line
			(start 0.7874 0.4064)
			(end -0.7874 0.4064)
			(stroke
				(width 0.1524)
				(type default)
			)
			(layer "F.SilkS")
		)
		(fp_line
			(start -0.7874 0.4064)
			(end -0.7874 -0.4064)
			(stroke
				(width 0.1524)
				(type default)
			)
			(layer "F.SilkS")
		)
		(fp_line
			(start -0.12065 -0.305054)
			(end -0.12065 -0.2794)
			(stroke
				(width 0.1)
				(type default)
			)
			(layer "F.Fab")
		)
		(fp_line
			(start -0.67945 -0.305054)
			(end -0.12065 -0.305054)
			(stroke
				(width 0.1)
				(type default)
			)
			(layer "F.Fab")
		)
		(fp_line
			(start 0.67945 -0.3048)
			(end 0.67945 0.3048)
			(stroke
				(width 0.1)
				(type default)
			)
			(layer "F.Fab")
		)
		(fp_line
			(start 0.12065 -0.3048)
			(end 0.67945 -0.3048)
			(stroke
				(width 0.1)
				(type default)
			)
			(layer "F.Fab")
		)
		(fp_line
			(start 0.12065 -0.2794)
			(end 0.12065 -0.3048)
			(stroke
				(width 0.1)
				(type default)
			)
			(layer "F.Fab")
		)
		(fp_line
			(start -0.12065 -0.2794)
			(end 0.12065 -0.2794)
			(stroke
				(width 0.1)
				(type default)
			)
			(layer "F.Fab")
		)
		(fp_line
			(start 0.120396 0.2794)
			(end -0.12065 0.2794)
			(stroke
				(width 0.1)
				(type default)
			)
			(layer "F.Fab")
		)
		(fp_line
			(start -0.12065 0.2794)
			(end -0.12065 0.3048)
			(stroke
				(width 0.1)
				(type default)
			)
			(layer "F.Fab")
		)
		(fp_line
			(start 0.67945 0.3048)
			(end 0.120396 0.3048)
			(stroke
				(width 0.1)
				(type default)
			)
			(layer "F.Fab")
		)
		(fp_line
			(start 0.120396 0.3048)
			(end 0.120396 0.2794)
			(stroke
				(width 0.1)
				(type default)
			)
			(layer "F.Fab")
		)
		(fp_line
			(start -0.12065 0.3048)
			(end -0.67945 0.3048)
			(stroke
				(width 0.1)
				(type default)
			)
			(layer "F.Fab")
		)
		(fp_line
			(start -0.67945 0.3048)
			(end -0.67945 -0.305054)
			(stroke
				(width 0.1)
				(type default)
			)
			(layer "F.Fab")
		)
		(pad "1" smd circle
			(at -0.40005 0 90)
			(size 0 0)
			(layers "F.Cu" "F.Mask" "F.Paste")
			(net "SMB_SSD12_ISO_EN")
		)
		(pad "2" smd circle
			(at 0.40005 0 90)
			(size 0 0)
			(layers "F.Cu" "F.Mask" "F.Paste")
			(net "P3V3_AUX")
		)
	)
	(footprint ""
		(layer "F.Cu")
		(at 376.34926 -296.996612 -90)
		(property "Reference" "C3538"
			(at 0 0 270)
			(layer "F.SilkS")
			(hide yes)
			(effects
				(font
					(size 1.27 1.27)
				)
			)
		)
		(property "Value" ""
			(at 0 0 270)
			(layer "F.Fab")
			(effects
				(font
					(size 1.27 1.27)
				)
			)
		)
		(duplicate_pad_numbers_are_jumpers no)
		(fp_line
			(start -0.299974 0.150114)
			(end -0.299974 -0.150114)
			(stroke
				(width 0.1)
				(type default)
			)
			(layer "F.Fab")
		)
		(fp_line
			(start 0.299974 0.150114)
			(end -0.299974 0.150114)
			(stroke
				(width 0.1)
				(type default)
			)
			(layer "F.Fab")
		)
		(fp_line
			(start -0.299974 -0.150114)
			(end 0.299974 -0.150114)
			(stroke
				(width 0.1)
				(type default)
			)
			(layer "F.Fab")
		)
		(fp_line
			(start 0.299974 -0.150114)
			(end 0.299974 0.150114)
			(stroke
				(width 0.1)
				(type default)
			)
			(layer "F.Fab")
		)
		(pad "1" smd rect
			(at -0.2667 0 270)
			(size 0.3048 0.381)
			(layers "F.Cu" "F.Mask" "F.Paste")
			(net "P1V8_PLL0_PEX3")
		)
		(pad "2" smd rect
			(at 0.2667 0 270)
			(size 0.3048 0.381)
			(layers "F.Cu" "F.Mask" "F.Paste")
			(net "GND")
		)
	)
	(footprint ""
		(layer "F.Cu")
		(at 101.930454 -120.79224)
		(property "Reference" "R5863"
			(at 0 0 0)
			(layer "F.SilkS")
			(hide yes)
			(effects
				(font
					(size 1.27 1.27)
				)
			)
		)
		(property "Value" ""
			(at 0 0 0)
			(layer "F.Fab")
			(effects
				(font
					(size 1.27 1.27)
				)
			)
		)
		(duplicate_pad_numbers_are_jumpers no)
		(fp_line
			(start -0.7874 -0.4064)
			(end 0.7874 -0.4064)
			(stroke
				(width 0.1524)
				(type default)
			)
			(layer "F.SilkS")
		)
		(fp_line
			(start -0.7874 0.4064)
			(end -0.7874 -0.4064)
			(stroke
				(width 0.1524)
				(type default)
			)
			(layer "F.SilkS")
		)
		(fp_line
			(start 0.7874 -0.4064)
			(end 0.7874 0.4064)
			(stroke
				(width 0.1524)
				(type default)
			)
			(layer "F.SilkS")
		)
		(fp_line
			(start 0.7874 0.4064)
			(end -0.7874 0.4064)
			(stroke
				(width 0.1524)
				(type default)
			)
			(layer "F.SilkS")
		)
		(fp_line
			(start -0.67945 -0.305054)
			(end -0.12065 -0.305054)
			(stroke
				(width 0.1)
				(type default)
			)
			(layer "F.Fab")
		)
		(fp_line
			(start -0.67945 0.3048)
			(end -0.67945 -0.305054)
			(stroke
				(width 0.1)
				(type default)
			)
			(layer "F.Fab")
		)
		(fp_line
			(start -0.12065 -0.305054)
			(end -0.12065 -0.2794)
			(stroke
				(width 0.1)
				(type default)
			)
			(layer "F.Fab")
		)
		(fp_line
			(start -0.12065 -0.2794)
			(end 0.12065 -0.2794)
			(stroke
				(width 0.1)
				(type default)
			)
			(layer "F.Fab")
		)
		(fp_line
			(start -0.12065 0.2794)
			(end -0.12065 0.3048)
			(stroke
				(width 0.1)
				(type default)
			)
			(layer "F.Fab")
		)
		(fp_line
			(start -0.12065 0.3048)
			(end -0.67945 0.3048)
			(stroke
				(width 0.1)
				(type default)
			)
			(layer "F.Fab")
		)
		(fp_line
			(start 0.120396 0.2794)
			(end -0.12065 0.2794)
			(stroke
				(width 0.1)
				(type default)
			)
			(layer "F.Fab")
		)
		(fp_line
			(start 0.120396 0.3048)
			(end 0.120396 0.2794)
			(stroke
				(width 0.1)
				(type default)
			)
			(layer "F.Fab")
		)
		(fp_line
			(start 0.12065 -0.3048)
			(end 0.67945 -0.3048)
			(stroke
				(width 0.1)
				(type default)
			)
			(layer "F.Fab")
		)
		(fp_line
			(start 0.12065 -0.2794)
			(end 0.12065 -0.3048)
			(stroke
				(width 0.1)
				(type default)
			)
			(layer "F.Fab")
		)
		(fp_line
			(start 0.67945 -0.3048)
			(end 0.67945 0.3048)
			(stroke
				(width 0.1)
				(type default)
			)
			(layer "F.Fab")
		)
		(fp_line
			(start 0.67945 0.3048)
			(end 0.120396 0.3048)
			(stroke
				(width 0.1)
				(type default)
			)
			(layer "F.Fab")
		)
		(pad "1" smd circle
			(at -0.40005 0)
			(size 0 0)
			(layers "F.Cu" "F.Mask" "F.Paste")
			(net "P3V3_NIC1")
		)
		(pad "2" smd circle
			(at 0.40005 0)
			(size 0 0)
			(layers "F.Cu" "F.Mask" "F.Paste")
			(net "P3V3_NIC1_PG_G1")
		)
	)
	(footprint ""
		(layer "F.Cu")
		(at 136.534652 -30.03169 180)
		(property "Reference" "C281"
			(at 0 0 180)
			(layer "F.SilkS")
			(hide yes)
			(effects
				(font
					(size 1.27 1.27)
				)
			)
		)
		(property "Value" ""
			(at 0 0 180)
			(layer "F.Fab")
			(effects
				(font
					(size 1.27 1.27)
				)
			)
		)
		(duplicate_pad_numbers_are_jumpers no)
		(fp_line
			(start 0.299974 0.150114)
			(end -0.299974 0.150114)
			(stroke
				(width 0.1)
				(type default)
			)
			(layer "F.Fab")
		)
		(fp_line
			(start 0.299974 -0.150114)
			(end 0.299974 0.150114)
			(stroke
				(width 0.1)
				(type default)
			)
			(layer "F.Fab")
		)
		(fp_line
			(start -0.299974 0.150114)
			(end -0.299974 -0.150114)
			(stroke
				(width 0.1)
				(type default)
			)
			(layer "F.Fab")
		)
		(fp_line
			(start -0.299974 -0.150114)
			(end 0.299974 -0.150114)
			(stroke
				(width 0.1)
				(type default)
			)
			(layer "F.Fab")
		)
		(pad "1" smd rect
			(at -0.2667 0 180)
			(size 0.3048 0.381)
			(layers "F.Cu" "F.Mask" "F.Paste")
			(net "P5E_PEX1_STN2_TX_DN<45>")
		)
		(pad "2" smd rect
			(at 0.2667 0 180)
			(size 0.3048 0.381)
			(layers "F.Cu" "F.Mask" "F.Paste")
			(net "P5E_PEX1_STN2_TX_C_DN<45>")
		)
	)
	(footprint ""
		(layer "F.Cu")
		(at 437.323484 -96.811592 -90)
		(property "Reference" "R760"
			(at 0 0 270)
			(layer "F.SilkS")
			(hide yes)
			(effects
				(font
					(size 1.27 1.27)
				)
			)
		)
		(property "Value" ""
			(at 0 0 270)
			(layer "F.Fab")
			(effects
				(font
					(size 1.27 1.27)
				)
			)
		)
		(duplicate_pad_numbers_are_jumpers no)
		(fp_line
			(start -0.7874 0.4064)
			(end -0.7874 -0.4064)
			(stroke
				(width 0.1524)
				(type default)
			)
			(layer "F.SilkS")
		)
		(fp_line
			(start 0.7874 0.4064)
			(end -0.7874 0.4064)
			(stroke
				(width 0.1524)
				(type default)
			)
			(layer "F.SilkS")
		)
		(fp_line
			(start -0.7874 -0.4064)
			(end 0.7874 -0.4064)
			(stroke
				(width 0.1524)
				(type default)
			)
			(layer "F.SilkS")
		)
		(fp_line
			(start 0.7874 -0.4064)
			(end 0.7874 0.4064)
			(stroke
				(width 0.1524)
				(type default)
			)
			(layer "F.SilkS")
		)
		(fp_line
			(start -0.67945 0.3048)
			(end -0.67945 -0.305054)
			(stroke
				(width 0.1)
				(type default)
			)
			(layer "F.Fab")
		)
		(fp_line
			(start -0.12065 0.3048)
			(end -0.67945 0.3048)
			(stroke
				(width 0.1)
				(type default)
			)
			(layer "F.Fab")
		)
		(fp_line
			(start 0.120396 0.3048)
			(end 0.120396 0.2794)
			(stroke
				(width 0.1)
				(type default)
			)
			(layer "F.Fab")
		)
		(fp_line
			(start 0.67945 0.3048)
			(end 0.120396 0.3048)
			(stroke
				(width 0.1)
				(type default)
			)
			(layer "F.Fab")
		)
		(fp_line
			(start -0.12065 0.2794)
			(end -0.12065 0.3048)
			(stroke
				(width 0.1)
				(type default)
			)
			(layer "F.Fab")
		)
		(fp_line
			(start 0.120396 0.2794)
			(end -0.12065 0.2794)
			(stroke
				(width 0.1)
				(type default)
			)
			(layer "F.Fab")
		)
		(fp_line
			(start -0.12065 -0.2794)
			(end 0.12065 -0.2794)
			(stroke
				(width 0.1)
				(type default)
			)
			(layer "F.Fab")
		)
		(fp_line
			(start 0.12065 -0.2794)
			(end 0.12065 -0.3048)
			(stroke
				(width 0.1)
				(type default)
			)
			(layer "F.Fab")
		)
		(fp_line
			(start 0.12065 -0.3048)
			(end 0.67945 -0.3048)
			(stroke
				(width 0.1)
				(type default)
			)
			(layer "F.Fab")
		)
		(fp_line
			(start 0.67945 -0.3048)
			(end 0.67945 0.3048)
			(stroke
				(width 0.1)
				(type default)
			)
			(layer "F.Fab")
		)
		(fp_line
			(start -0.67945 -0.305054)
			(end -0.12065 -0.305054)
			(stroke
				(width 0.1)
				(type default)
			)
			(layer "F.Fab")
		)
		(fp_line
			(start -0.12065 -0.305054)
			(end -0.12065 -0.2794)
			(stroke
				(width 0.1)
				(type default)
			)
			(layer "F.Fab")
		)
		(pad "1" smd circle
			(at -0.40005 0 270)
			(size 0 0)
			(layers "F.Cu" "F.Mask" "F.Paste")
			(net "NIC7_ADC_A0")
		)
		(pad "2" smd circle
			(at 0.40005 0 270)
			(size 0 0)
			(layers "F.Cu" "F.Mask" "F.Paste")
			(net "P3V3_AUX")
		)
	)
	(footprint ""
		(layer "F.Cu")
		(at 33.77184 -24.807418)
		(property "Reference" "R413"
			(at 0 0 0)
			(layer "F.SilkS")
			(hide yes)
			(effects
				(font
					(size 1.27 1.27)
				)
			)
		)
		(property "Value" ""
			(at 0 0 0)
			(layer "F.Fab")
			(effects
				(font
					(size 1.27 1.27)
				)
			)
		)
		(duplicate_pad_numbers_are_jumpers no)
		(fp_line
			(start -0.7874 -0.4064)
			(end 0.7874 -0.4064)
			(stroke
				(width 0.1524)
				(type default)
			)
			(layer "F.SilkS")
		)
		(fp_line
			(start -0.7874 0.4064)
			(end -0.7874 -0.4064)
			(stroke
				(width 0.1524)
				(type default)
			)
			(layer "F.SilkS")
		)
		(fp_line
			(start 0.7874 -0.4064)
			(end 0.7874 0.4064)
			(stroke
				(width 0.1524)
				(type default)
			)
			(layer "F.SilkS")
		)
		(fp_line
			(start 0.7874 0.4064)
			(end -0.7874 0.4064)
			(stroke
				(width 0.1524)
				(type default)
			)
			(layer "F.SilkS")
		)
		(fp_line
			(start -0.67945 -0.305054)
			(end -0.12065 -0.305054)
			(stroke
				(width 0.1)
				(type default)
			)
			(layer "F.Fab")
		)
		(fp_line
			(start -0.67945 0.3048)
			(end -0.67945 -0.305054)
			(stroke
				(width 0.1)
				(type default)
			)
			(layer "F.Fab")
		)
		(fp_line
			(start -0.12065 -0.305054)
			(end -0.12065 -0.2794)
			(stroke
				(width 0.1)
				(type default)
			)
			(layer "F.Fab")
		)
		(fp_line
			(start -0.12065 -0.2794)
			(end 0.12065 -0.2794)
			(stroke
				(width 0.1)
				(type default)
			)
			(layer "F.Fab")
		)
		(fp_line
			(start -0.12065 0.2794)
			(end -0.12065 0.3048)
			(stroke
				(width 0.1)
				(type default)
			)
			(layer "F.Fab")
		)
		(fp_line
			(start -0.12065 0.3048)
			(end -0.67945 0.3048)
			(stroke
				(width 0.1)
				(type default)
			)
			(layer "F.Fab")
		)
		(fp_line
			(start 0.120396 0.2794)
			(end -0.12065 0.2794)
			(stroke
				(width 0.1)
				(type default)
			)
			(layer "F.Fab")
		)
		(fp_line
			(start 0.120396 0.3048)
			(end 0.120396 0.2794)
			(stroke
				(width 0.1)
				(type default)
			)
			(layer "F.Fab")
		)
		(fp_line
			(start 0.12065 -0.3048)
			(end 0.67945 -0.3048)
			(stroke
				(width 0.1)
				(type default)
			)
			(layer "F.Fab")
		)
		(fp_line
			(start 0.12065 -0.2794)
			(end 0.12065 -0.3048)
			(stroke
				(width 0.1)
				(type default)
			)
			(layer "F.Fab")
		)
		(fp_line
			(start 0.67945 -0.3048)
			(end 0.67945 0.3048)
			(stroke
				(width 0.1)
				(type default)
			)
			(layer "F.Fab")
		)
		(fp_line
			(start 0.67945 0.3048)
			(end 0.120396 0.3048)
			(stroke
				(width 0.1)
				(type default)
			)
			(layer "F.Fab")
		)
		(pad "1" smd circle
			(at -0.40005 0)
			(size 0 0)
			(layers "F.Cu" "F.Mask" "F.Paste")
			(net "P3V3_SSD1")
		)
		(pad "2" smd circle
			(at 0.40005 0)
			(size 0 0)
			(layers "F.Cu" "F.Mask" "F.Paste")
			(net "PU_CLKREQ1")
		)
	)
	(footprint ""
		(layer "F.Cu")
		(at 239.813338 -135.058404 180)
		(property "Reference" "C2854"
			(at 0 0 180)
			(layer "F.SilkS")
			(hide yes)
			(effects
				(font
					(size 1.27 1.27)
				)
			)
		)
		(property "Value" ""
			(at 0 0 180)
			(layer "F.Fab")
			(effects
				(font
					(size 1.27 1.27)
				)
			)
		)
		(duplicate_pad_numbers_are_jumpers no)
		(fp_line
			(start 0.7874 0.4064)
			(end -0.7874 0.4064)
			(stroke
				(width 0.1524)
				(type default)
			)
			(layer "F.SilkS")
		)
		(fp_line
			(start 0.7874 -0.4064)
			(end 0.7874 0.4064)
			(stroke
				(width 0.1524)
				(type default)
			)
			(layer "F.SilkS")
		)
		(fp_line
			(start -0.7874 0.4064)
			(end -0.7874 -0.4064)
			(stroke
				(width 0.1524)
				(type default)
			)
			(layer "F.SilkS")
		)
		(fp_line
			(start -0.7874 -0.4064)
			(end 0.7874 -0.4064)
			(stroke
				(width 0.1524)
				(type default)
			)
			(layer "F.SilkS")
		)
		(fp_line
			(start 0.67945 0.3048)
			(end 0.120396 0.3048)
			(stroke
				(width 0.1)
				(type default)
			)
			(layer "F.Fab")
		)
		(fp_line
			(start 0.67945 -0.3048)
			(end 0.67945 0.3048)
			(stroke
				(width 0.1)
				(type default)
			)
			(layer "F.Fab")
		)
		(fp_line
			(start 0.12065 -0.2794)
			(end 0.12065 -0.3048)
			(stroke
				(width 0.1)
				(type default)
			)
			(layer "F.Fab")
		)
		(fp_line
			(start 0.12065 -0.3048)
			(end 0.67945 -0.3048)
			(stroke
				(width 0.1)
				(type default)
			)
			(layer "F.Fab")
		)
		(fp_line
			(start 0.120396 0.3048)
			(end 0.120396 0.2794)
			(stroke
				(width 0.1)
				(type default)
			)
			(layer "F.Fab")
		)
		(fp_line
			(start 0.120396 0.2794)
			(end -0.12065 0.2794)
			(stroke
				(width 0.1)
				(type default)
			)
			(layer "F.Fab")
		)
		(fp_line
			(start -0.12065 0.3048)
			(end -0.67945 0.3048)
			(stroke
				(width 0.1)
				(type default)
			)
			(layer "F.Fab")
		)
		(fp_line
			(start -0.12065 0.2794)
			(end -0.12065 0.3048)
			(stroke
				(width 0.1)
				(type default)
			)
			(layer "F.Fab")
		)
		(fp_line
			(start -0.12065 -0.2794)
			(end 0.12065 -0.2794)
			(stroke
				(width 0.1)
				(type default)
			)
			(layer "F.Fab")
		)
		(fp_line
			(start -0.12065 -0.305054)
			(end -0.12065 -0.2794)
			(stroke
				(width 0.1)
				(type default)
			)
			(layer "F.Fab")
		)
		(fp_line
			(start -0.67945 0.3048)
			(end -0.67945 -0.305054)
			(stroke
				(width 0.1)
				(type default)
			)
			(layer "F.Fab")
		)
		(fp_line
			(start -0.67945 -0.305054)
			(end -0.12065 -0.305054)
			(stroke
				(width 0.1)
				(type default)
			)
			(layer "F.Fab")
		)
		(pad "1" smd circle
			(at -0.40005 0 180)
			(size 0 0)
			(layers "F.Cu" "F.Mask" "F.Paste")
			(net "P12V_NIC4_EN_R")
		)
		(pad "2" smd circle
			(at 0.40005 0 180)
			(size 0 0)
			(layers "F.Cu" "F.Mask" "F.Paste")
			(net "GND")
		)
	)
	(footprint ""
		(layer "F.Cu")
		(at 363.459776 -152.71115 -90)
		(property "Reference" "R753"
			(at 0 0 270)
			(layer "F.SilkS")
			(hide yes)
			(effects
				(font
					(size 1.27 1.27)
				)
			)
		)
		(property "Value" ""
			(at 0 0 270)
			(layer "F.Fab")
			(effects
				(font
					(size 1.27 1.27)
				)
			)
		)
		(duplicate_pad_numbers_are_jumpers no)
		(fp_line
			(start -0.7874 0.4064)
			(end -0.7874 -0.4064)
			(stroke
				(width 0.1524)
				(type default)
			)
			(layer "F.SilkS")
		)
		(fp_line
			(start 0.7874 0.4064)
			(end -0.7874 0.4064)
			(stroke
				(width 0.1524)
				(type default)
			)
			(layer "F.SilkS")
		)
		(fp_line
			(start -0.7874 -0.4064)
			(end 0.7874 -0.4064)
			(stroke
				(width 0.1524)
				(type default)
			)
			(layer "F.SilkS")
		)
		(fp_line
			(start 0.7874 -0.4064)
			(end 0.7874 0.4064)
			(stroke
				(width 0.1524)
				(type default)
			)
			(layer "F.SilkS")
		)
		(fp_line
			(start -0.67945 0.3048)
			(end -0.67945 -0.305054)
			(stroke
				(width 0.1)
				(type default)
			)
			(layer "F.Fab")
		)
		(fp_line
			(start -0.12065 0.3048)
			(end -0.67945 0.3048)
			(stroke
				(width 0.1)
				(type default)
			)
			(layer "F.Fab")
		)
		(fp_line
			(start 0.120396 0.3048)
			(end 0.120396 0.2794)
			(stroke
				(width 0.1)
				(type default)
			)
			(layer "F.Fab")
		)
		(fp_line
			(start 0.67945 0.3048)
			(end 0.120396 0.3048)
			(stroke
				(width 0.1)
				(type default)
			)
			(layer "F.Fab")
		)
		(fp_line
			(start -0.12065 0.2794)
			(end -0.12065 0.3048)
			(stroke
				(width 0.1)
				(type default)
			)
			(layer "F.Fab")
		)
		(fp_line
			(start 0.120396 0.2794)
			(end -0.12065 0.2794)
			(stroke
				(width 0.1)
				(type default)
			)
			(layer "F.Fab")
		)
		(fp_line
			(start -0.12065 -0.2794)
			(end 0.12065 -0.2794)
			(stroke
				(width 0.1)
				(type default)
			)
			(layer "F.Fab")
		)
		(fp_line
			(start 0.12065 -0.2794)
			(end 0.12065 -0.3048)
			(stroke
				(width 0.1)
				(type default)
			)
			(layer "F.Fab")
		)
		(fp_line
			(start 0.12065 -0.3048)
			(end 0.67945 -0.3048)
			(stroke
				(width 0.1)
				(type default)
			)
			(layer "F.Fab")
		)
		(fp_line
			(start 0.67945 -0.3048)
			(end 0.67945 0.3048)
			(stroke
				(width 0.1)
				(type default)
			)
			(layer "F.Fab")
		)
		(fp_line
			(start -0.67945 -0.305054)
			(end -0.12065 -0.305054)
			(stroke
				(width 0.1)
				(type default)
			)
			(layer "F.Fab")
		)
		(fp_line
			(start -0.12065 -0.305054)
			(end -0.12065 -0.2794)
			(stroke
				(width 0.1)
				(type default)
			)
			(layer "F.Fab")
		)
		(pad "1" smd circle
			(at -0.40005 0 270)
			(size 0 0)
			(layers "F.Cu" "F.Mask" "F.Paste")
			(net "SMB_BIC_I2C6_MUX_NIC_ADC_R_SCL")
		)
		(pad "2" smd circle
			(at 0.40005 0 270)
			(size 0 0)
			(layers "F.Cu" "F.Mask" "F.Paste")
			(net "SMB_NIC6_ADC_SCL")
		)
	)
	(footprint ""
		(layer "F.Cu")
		(at 27.200352 -256.478786)
		(property "Reference" "C3066"
			(at 0 0 0)
			(layer "F.SilkS")
			(hide yes)
			(effects
				(font
					(size 1.27 1.27)
				)
			)
		)
		(property "Value" ""
			(at 0 0 0)
			(layer "F.Fab")
			(effects
				(font
					(size 1.27 1.27)
				)
			)
		)
		(duplicate_pad_numbers_are_jumpers no)
		(fp_line
			(start -0.299974 -0.150114)
			(end 0.299974 -0.150114)
			(stroke
				(width 0.1)
				(type default)
			)
			(layer "F.Fab")
		)
		(fp_line
			(start -0.299974 0.150114)
			(end -0.299974 -0.150114)
			(stroke
				(width 0.1)
				(type default)
			)
			(layer "F.Fab")
		)
		(fp_line
			(start 0.299974 -0.150114)
			(end 0.299974 0.150114)
			(stroke
				(width 0.1)
				(type default)
			)
			(layer "F.Fab")
		)
		(fp_line
			(start 0.299974 0.150114)
			(end -0.299974 0.150114)
			(stroke
				(width 0.1)
				(type default)
			)
			(layer "F.Fab")
		)
		(pad "1" smd rect
			(at -0.2667 0)
			(size 0.3048 0.381)
			(layers "F.Cu" "F.Mask" "F.Paste")
			(net "P1V8_PLL0_PEX0")
		)
		(pad "2" smd rect
			(at 0.2667 0)
			(size 0.3048 0.381)
			(layers "F.Cu" "F.Mask" "F.Paste")
			(net "GND")
		)
	)
	(footprint ""
		(layer "F.Cu")
		(at 105.361486 -243.976906 -90)
		(property "Reference" "R815"
			(at 0 0 270)
			(layer "F.SilkS")
			(hide yes)
			(effects
				(font
					(size 1.27 1.27)
				)
			)
		)
		(property "Value" ""
			(at 0 0 270)
			(layer "F.Fab")
			(effects
				(font
					(size 1.27 1.27)
				)
			)
		)
		(duplicate_pad_numbers_are_jumpers no)
		(fp_line
			(start -3.937508 1.8796)
			(end 3.937508 1.8796)
			(stroke
				(width 0.1524)
				(type default)
			)
			(layer "F.SilkS")
		)
		(fp_line
			(start 3.937508 1.8796)
			(end 3.937508 -1.8796)
			(stroke
				(width 0.1524)
				(type default)
			)
			(layer "F.SilkS")
		)
		(fp_line
			(start -3.937508 -1.8796)
			(end -3.937508 1.8796)
			(stroke
				(width 0.1524)
				(type default)
			)
			(layer "F.SilkS")
		)
		(fp_line
			(start 3.937508 -1.8796)
			(end -3.937508 -1.8796)
			(stroke
				(width 0.1524)
				(type default)
			)
			(layer "F.SilkS")
		)
		(fp_line
			(start -3.275076 1.674876)
			(end 3.275076 1.674876)
			(stroke
				(width 0.1)
				(type default)
			)
			(layer "F.Fab")
		)
		(fp_line
			(start 3.275076 1.674876)
			(end 3.275076 -1.674876)
			(stroke
				(width 0.1)
				(type default)
			)
			(layer "F.Fab")
		)
		(fp_line
			(start -3.275076 -1.674876)
			(end -3.275076 1.674876)
			(stroke
				(width 0.1)
				(type default)
			)
			(layer "F.Fab")
		)
		(fp_line
			(start 3.275076 -1.674876)
			(end -3.275076 -1.674876)
			(stroke
				(width 0.1)
				(type default)
			)
			(layer "F.Fab")
		)
		(pad "1" smd rect
			(at -2.350008 0 270)
			(size 2.921 3.5052)
			(layers "F.Cu" "F.Mask" "F.Paste")
			(net "P1V8_PEX")
		)
		(pad "2" smd rect
			(at 2.350008 0 270)
			(size 2.921 3.5052)
			(layers "F.Cu" "F.Mask" "F.Paste")
			(net "P1V8_PEX_R")
		)
	)
	(footprint ""
		(layer "F.Cu")
		(at 102.521512 -88.884506)
		(property "Reference" "R1128"
			(at 0 0 0)
			(layer "F.SilkS")
			(hide yes)
			(effects
				(font
					(size 1.27 1.27)
				)
			)
		)
		(property "Value" ""
			(at 0 0 0)
			(layer "F.Fab")
			(effects
				(font
					(size 1.27 1.27)
				)
			)
		)
		(duplicate_pad_numbers_are_jumpers no)
		(fp_line
			(start -1.2954 -0.5842)
			(end 1.2954 -0.5842)
			(stroke
				(width 0.1524)
				(type default)
			)
			(layer "F.SilkS")
		)
		(fp_line
			(start -1.2954 0.5842)
			(end -1.2954 -0.5842)
			(stroke
				(width 0.1524)
				(type default)
			)
			(layer "F.SilkS")
		)
		(fp_line
			(start 1.2954 -0.5842)
			(end 1.2954 0.5842)
			(stroke
				(width 0.1524)
				(type default)
			)
			(layer "F.SilkS")
		)
		(fp_line
			(start 1.2954 0.5842)
			(end -1.2954 0.5842)
			(stroke
				(width 0.1524)
				(type default)
			)
			(layer "F.SilkS")
		)
		(fp_line
			(start -1.1938 -0.406654)
			(end -0.8636 -0.406654)
			(stroke
				(width 0.1)
				(type default)
			)
			(layer "F.Fab")
		)
		(fp_line
			(start -1.1938 0.4064)
			(end -1.1938 -0.406654)
			(stroke
				(width 0.1)
				(type default)
			)
			(layer "F.Fab")
		)
		(fp_line
			(start -0.8636 -0.4572)
			(end 0.8636 -0.4572)
			(stroke
				(width 0.1)
				(type default)
			)
			(layer "F.Fab")
		)
		(fp_line
			(start -0.8636 -0.406654)
			(end -0.8636 -0.4572)
			(stroke
				(width 0.1)
				(type default)
			)
			(layer "F.Fab")
		)
		(fp_line
			(start -0.8636 0.4064)
			(end -1.1938 0.4064)
			(stroke
				(width 0.1)
				(type default)
			)
			(layer "F.Fab")
		)
		(fp_line
			(start -0.8636 0.4318)
			(end -0.8636 0.4064)
			(stroke
				(width 0.1)
				(type default)
			)
			(layer "F.Fab")
		)
		(fp_line
			(start -0.8636 0.4572)
			(end -0.8636 0.4318)
			(stroke
				(width 0.1)
				(type default)
			)
			(layer "F.Fab")
		)
		(fp_line
			(start 0.8636 -0.4572)
			(end 0.8636 -0.406654)
			(stroke
				(width 0.1)
				(type default)
			)
			(layer "F.Fab")
		)
		(fp_line
			(start 0.8636 -0.406654)
			(end 1.1938 -0.406654)
			(stroke
				(width 0.1)
				(type default)
			)
			(layer "F.Fab")
		)
		(fp_line
			(start 0.8636 0.4064)
			(end 0.8636 0.4572)
			(stroke
				(width 0.1)
				(type default)
			)
			(layer "F.Fab")
		)
		(fp_line
			(start 0.8636 0.4572)
			(end -0.8636 0.4572)
			(stroke
				(width 0.1)
				(type default)
			)
			(layer "F.Fab")
		)
		(fp_line
			(start 1.1938 -0.406654)
			(end 1.1938 0.4064)
			(stroke
				(width 0.1)
				(type default)
			)
			(layer "F.Fab")
		)
		(fp_line
			(start 1.1938 0.4064)
			(end 0.8636 0.4064)
			(stroke
				(width 0.1)
				(type default)
			)
			(layer "F.Fab")
		)
		(pad "1" smd rect
			(at -0.7366 0 270)
			(size 0.7112 0.8128)
			(layers "F.Cu" "F.Mask" "F.Paste")
			(net "P3V3_VDD_9ZXL0851_0_7")
		)
		(pad "2" smd rect
			(at 0.7366 0 270)
			(size 0.7112 0.8128)
			(layers "F.Cu" "F.Mask" "F.Paste")
			(net "P3V3_VDDAR_9ZXL0851_0_7")
		)
	)
	(footprint ""
		(layer "F.Cu")
		(at 83.034124 -6.046724)
		(property "Reference" "R5812"
			(at 0 0 0)
			(layer "F.SilkS")
			(hide yes)
			(effects
				(font
					(size 1.27 1.27)
				)
			)
		)
		(property "Value" ""
			(at 0 0 0)
			(layer "F.Fab")
			(effects
				(font
					(size 1.27 1.27)
				)
			)
		)
		(duplicate_pad_numbers_are_jumpers no)
		(fp_line
			(start -0.7874 -0.4064)
			(end 0.7874 -0.4064)
			(stroke
				(width 0.1524)
				(type default)
			)
			(layer "F.SilkS")
		)
		(fp_line
			(start -0.7874 0.4064)
			(end -0.7874 -0.4064)
			(stroke
				(width 0.1524)
				(type default)
			)
			(layer "F.SilkS")
		)
		(fp_line
			(start 0.7874 -0.4064)
			(end 0.7874 0.4064)
			(stroke
				(width 0.1524)
				(type default)
			)
			(layer "F.SilkS")
		)
		(fp_line
			(start 0.7874 0.4064)
			(end -0.7874 0.4064)
			(stroke
				(width 0.1524)
				(type default)
			)
			(layer "F.SilkS")
		)
		(fp_line
			(start -0.67945 -0.305054)
			(end -0.12065 -0.305054)
			(stroke
				(width 0.1)
				(type default)
			)
			(layer "F.Fab")
		)
		(fp_line
			(start -0.67945 0.3048)
			(end -0.67945 -0.305054)
			(stroke
				(width 0.1)
				(type default)
			)
			(layer "F.Fab")
		)
		(fp_line
			(start -0.12065 -0.305054)
			(end -0.12065 -0.2794)
			(stroke
				(width 0.1)
				(type default)
			)
			(layer "F.Fab")
		)
		(fp_line
			(start -0.12065 -0.2794)
			(end 0.12065 -0.2794)
			(stroke
				(width 0.1)
				(type default)
			)
			(layer "F.Fab")
		)
		(fp_line
			(start -0.12065 0.2794)
			(end -0.12065 0.3048)
			(stroke
				(width 0.1)
				(type default)
			)
			(layer "F.Fab")
		)
		(fp_line
			(start -0.12065 0.3048)
			(end -0.67945 0.3048)
			(stroke
				(width 0.1)
				(type default)
			)
			(layer "F.Fab")
		)
		(fp_line
			(start 0.120396 0.2794)
			(end -0.12065 0.2794)
			(stroke
				(width 0.1)
				(type default)
			)
			(layer "F.Fab")
		)
		(fp_line
			(start 0.120396 0.3048)
			(end 0.120396 0.2794)
			(stroke
				(width 0.1)
				(type default)
			)
			(layer "F.Fab")
		)
		(fp_line
			(start 0.12065 -0.3048)
			(end 0.67945 -0.3048)
			(stroke
				(width 0.1)
				(type default)
			)
			(layer "F.Fab")
		)
		(fp_line
			(start 0.12065 -0.2794)
			(end 0.12065 -0.3048)
			(stroke
				(width 0.1)
				(type default)
			)
			(layer "F.Fab")
		)
		(fp_line
			(start 0.67945 -0.3048)
			(end 0.67945 0.3048)
			(stroke
				(width 0.1)
				(type default)
			)
			(layer "F.Fab")
		)
		(fp_line
			(start 0.67945 0.3048)
			(end 0.120396 0.3048)
			(stroke
				(width 0.1)
				(type default)
			)
			(layer "F.Fab")
		)
		(pad "1" smd circle
			(at -0.40005 0)
			(size 0 0)
			(layers "F.Cu" "F.Mask" "F.Paste")
			(net "LM75_2_A1")
		)
		(pad "2" smd circle
			(at 0.40005 0)
			(size 0 0)
			(layers "F.Cu" "F.Mask" "F.Paste")
			(net "GND")
		)
	)
	(footprint ""
		(layer "F.Cu")
		(at 346.71 -205.232 90)
		(property "Reference" "R4148"
			(at 0 0 90)
			(layer "F.SilkS")
			(hide yes)
			(effects
				(font
					(size 1.27 1.27)
				)
			)
		)
		(property "Value" ""
			(at 0 0 90)
			(layer "F.Fab")
			(effects
				(font
					(size 1.27 1.27)
				)
			)
		)
		(duplicate_pad_numbers_are_jumpers no)
		(fp_line
			(start 0.7874 -0.4064)
			(end 0.7874 0.4064)
			(stroke
				(width 0.1524)
				(type default)
			)
			(layer "F.SilkS")
		)
		(fp_line
			(start -0.7874 -0.4064)
			(end 0.7874 -0.4064)
			(stroke
				(width 0.1524)
				(type default)
			)
			(layer "F.SilkS")
		)
		(fp_line
			(start 0.7874 0.4064)
			(end -0.7874 0.4064)
			(stroke
				(width 0.1524)
				(type default)
			)
			(layer "F.SilkS")
		)
		(fp_line
			(start -0.7874 0.4064)
			(end -0.7874 -0.4064)
			(stroke
				(width 0.1524)
				(type default)
			)
			(layer "F.SilkS")
		)
		(fp_line
			(start -0.12065 -0.305054)
			(end -0.12065 -0.2794)
			(stroke
				(width 0.1)
				(type default)
			)
			(layer "F.Fab")
		)
		(fp_line
			(start -0.67945 -0.305054)
			(end -0.12065 -0.305054)
			(stroke
				(width 0.1)
				(type default)
			)
			(layer "F.Fab")
		)
		(fp_line
			(start 0.67945 -0.3048)
			(end 0.67945 0.3048)
			(stroke
				(width 0.1)
				(type default)
			)
			(layer "F.Fab")
		)
		(fp_line
			(start 0.12065 -0.3048)
			(end 0.67945 -0.3048)
			(stroke
				(width 0.1)
				(type default)
			)
			(layer "F.Fab")
		)
		(fp_line
			(start 0.12065 -0.2794)
			(end 0.12065 -0.3048)
			(stroke
				(width 0.1)
				(type default)
			)
			(layer "F.Fab")
		)
		(fp_line
			(start -0.12065 -0.2794)
			(end 0.12065 -0.2794)
			(stroke
				(width 0.1)
				(type default)
			)
			(layer "F.Fab")
		)
		(fp_line
			(start 0.120396 0.2794)
			(end -0.12065 0.2794)
			(stroke
				(width 0.1)
				(type default)
			)
			(layer "F.Fab")
		)
		(fp_line
			(start -0.12065 0.2794)
			(end -0.12065 0.3048)
			(stroke
				(width 0.1)
				(type default)
			)
			(layer "F.Fab")
		)
		(fp_line
			(start 0.67945 0.3048)
			(end 0.120396 0.3048)
			(stroke
				(width 0.1)
				(type default)
			)
			(layer "F.Fab")
		)
		(fp_line
			(start 0.120396 0.3048)
			(end 0.120396 0.2794)
			(stroke
				(width 0.1)
				(type default)
			)
			(layer "F.Fab")
		)
		(fp_line
			(start -0.12065 0.3048)
			(end -0.67945 0.3048)
			(stroke
				(width 0.1)
				(type default)
			)
			(layer "F.Fab")
		)
		(fp_line
			(start -0.67945 0.3048)
			(end -0.67945 -0.305054)
			(stroke
				(width 0.1)
				(type default)
			)
			(layer "F.Fab")
		)
		(pad "1" smd circle
			(at -0.40005 0 90)
			(size 0 0)
			(layers "F.Cu" "F.Mask" "F.Paste")
			(net "PRSNT_SSD1_FPGA_R_N")
		)
		(pad "2" smd circle
			(at 0.40005 0 90)
			(size 0 0)
			(layers "F.Cu" "F.Mask" "F.Paste")
			(net "PRSNT_SSD1_FPGA_N")
		)
	)
	(footprint ""
		(layer "F.Cu")
		(at 211.610448 -210.366102 90)
		(property "Reference" "R5532"
			(at 0 0 90)
			(layer "F.SilkS")
			(hide yes)
			(effects
				(font
					(size 1.27 1.27)
				)
			)
		)
		(property "Value" ""
			(at 0 0 90)
			(layer "F.Fab")
			(effects
				(font
					(size 1.27 1.27)
				)
			)
		)
		(duplicate_pad_numbers_are_jumpers no)
		(fp_line
			(start 0.7874 -0.4064)
			(end 0.7874 0.4064)
			(stroke
				(width 0.1524)
				(type default)
			)
			(layer "F.SilkS")
		)
		(fp_line
			(start -0.7874 -0.4064)
			(end 0.7874 -0.4064)
			(stroke
				(width 0.1524)
				(type default)
			)
			(layer "F.SilkS")
		)
		(fp_line
			(start 0.7874 0.4064)
			(end -0.7874 0.4064)
			(stroke
				(width 0.1524)
				(type default)
			)
			(layer "F.SilkS")
		)
		(fp_line
			(start -0.7874 0.4064)
			(end -0.7874 -0.4064)
			(stroke
				(width 0.1524)
				(type default)
			)
			(layer "F.SilkS")
		)
		(fp_line
			(start -0.12065 -0.305054)
			(end -0.12065 -0.2794)
			(stroke
				(width 0.1)
				(type default)
			)
			(layer "F.Fab")
		)
		(fp_line
			(start -0.67945 -0.305054)
			(end -0.12065 -0.305054)
			(stroke
				(width 0.1)
				(type default)
			)
			(layer "F.Fab")
		)
		(fp_line
			(start 0.67945 -0.3048)
			(end 0.67945 0.3048)
			(stroke
				(width 0.1)
				(type default)
			)
			(layer "F.Fab")
		)
		(fp_line
			(start 0.12065 -0.3048)
			(end 0.67945 -0.3048)
			(stroke
				(width 0.1)
				(type default)
			)
			(layer "F.Fab")
		)
		(fp_line
			(start 0.12065 -0.2794)
			(end 0.12065 -0.3048)
			(stroke
				(width 0.1)
				(type default)
			)
			(layer "F.Fab")
		)
		(fp_line
			(start -0.12065 -0.2794)
			(end 0.12065 -0.2794)
			(stroke
				(width 0.1)
				(type default)
			)
			(layer "F.Fab")
		)
		(fp_line
			(start 0.120396 0.2794)
			(end -0.12065 0.2794)
			(stroke
				(width 0.1)
				(type default)
			)
			(layer "F.Fab")
		)
		(fp_line
			(start -0.12065 0.2794)
			(end -0.12065 0.3048)
			(stroke
				(width 0.1)
				(type default)
			)
			(layer "F.Fab")
		)
		(fp_line
			(start 0.67945 0.3048)
			(end 0.120396 0.3048)
			(stroke
				(width 0.1)
				(type default)
			)
			(layer "F.Fab")
		)
		(fp_line
			(start 0.120396 0.3048)
			(end 0.120396 0.2794)
			(stroke
				(width 0.1)
				(type default)
			)
			(layer "F.Fab")
		)
		(fp_line
			(start -0.12065 0.3048)
			(end -0.67945 0.3048)
			(stroke
				(width 0.1)
				(type default)
			)
			(layer "F.Fab")
		)
		(fp_line
			(start -0.67945 0.3048)
			(end -0.67945 -0.305054)
			(stroke
				(width 0.1)
				(type default)
			)
			(layer "F.Fab")
		)
		(pad "1" smd circle
			(at -0.40005 0 90)
			(size 0 0)
			(layers "F.Cu" "F.Mask" "F.Paste")
			(net "P3V3_AUX")
		)
		(pad "2" smd circle
			(at 0.40005 0 90)
			(size 0 0)
			(layers "F.Cu" "F.Mask" "F.Paste")
			(net "UART_BIC_DEBUG_TX")
		)
	)
	(footprint ""
		(layer "F.Cu")
		(at 183.847994 -188.101224 -90)
		(property "Reference" "C2093"
			(at 0 0 270)
			(layer "F.SilkS")
			(hide yes)
			(effects
				(font
					(size 1.27 1.27)
				)
			)
		)
		(property "Value" ""
			(at 0 0 270)
			(layer "F.Fab")
			(effects
				(font
					(size 1.27 1.27)
				)
			)
		)
		(duplicate_pad_numbers_are_jumpers no)
		(fp_line
			(start -0.7874 0.4064)
			(end -0.7874 -0.4064)
			(stroke
				(width 0.1524)
				(type default)
			)
			(layer "F.SilkS")
		)
		(fp_line
			(start 0.7874 0.4064)
			(end -0.7874 0.4064)
			(stroke
				(width 0.1524)
				(type default)
			)
			(layer "F.SilkS")
		)
		(fp_line
			(start -0.7874 -0.4064)
			(end 0.7874 -0.4064)
			(stroke
				(width 0.1524)
				(type default)
			)
			(layer "F.SilkS")
		)
		(fp_line
			(start 0.7874 -0.4064)
			(end 0.7874 0.4064)
			(stroke
				(width 0.1524)
				(type default)
			)
			(layer "F.SilkS")
		)
		(fp_line
			(start -0.67945 0.3048)
			(end -0.67945 -0.305054)
			(stroke
				(width 0.1)
				(type default)
			)
			(layer "F.Fab")
		)
		(fp_line
			(start -0.12065 0.3048)
			(end -0.67945 0.3048)
			(stroke
				(width 0.1)
				(type default)
			)
			(layer "F.Fab")
		)
		(fp_line
			(start 0.120396 0.3048)
			(end 0.120396 0.2794)
			(stroke
				(width 0.1)
				(type default)
			)
			(layer "F.Fab")
		)
		(fp_line
			(start 0.67945 0.3048)
			(end 0.120396 0.3048)
			(stroke
				(width 0.1)
				(type default)
			)
			(layer "F.Fab")
		)
		(fp_line
			(start -0.12065 0.2794)
			(end -0.12065 0.3048)
			(stroke
				(width 0.1)
				(type default)
			)
			(layer "F.Fab")
		)
		(fp_line
			(start 0.120396 0.2794)
			(end -0.12065 0.2794)
			(stroke
				(width 0.1)
				(type default)
			)
			(layer "F.Fab")
		)
		(fp_line
			(start -0.12065 -0.2794)
			(end 0.12065 -0.2794)
			(stroke
				(width 0.1)
				(type default)
			)
			(layer "F.Fab")
		)
		(fp_line
			(start 0.12065 -0.2794)
			(end 0.12065 -0.3048)
			(stroke
				(width 0.1)
				(type default)
			)
			(layer "F.Fab")
		)
		(fp_line
			(start 0.12065 -0.3048)
			(end 0.67945 -0.3048)
			(stroke
				(width 0.1)
				(type default)
			)
			(layer "F.Fab")
		)
		(fp_line
			(start 0.67945 -0.3048)
			(end 0.67945 0.3048)
			(stroke
				(width 0.1)
				(type default)
			)
			(layer "F.Fab")
		)
		(fp_line
			(start -0.67945 -0.305054)
			(end -0.12065 -0.305054)
			(stroke
				(width 0.1)
				(type default)
			)
			(layer "F.Fab")
		)
		(fp_line
			(start -0.12065 -0.305054)
			(end -0.12065 -0.2794)
			(stroke
				(width 0.1)
				(type default)
			)
			(layer "F.Fab")
		)
		(pad "1" smd circle
			(at -0.40005 0 270)
			(size 0 0)
			(layers "F.Cu" "F.Mask" "F.Paste")
			(net "GND")
		)
		(pad "2" smd circle
			(at 0.40005 0 270)
			(size 0 0)
			(layers "F.Cu" "F.Mask" "F.Paste")
			(net "P3V3_AUX")
		)
	)
	(footprint ""
		(layer "F.Cu")
		(at 378.18822 -260.84911 -90)
		(property "Reference" "C3555"
			(at 0 0 270)
			(layer "F.SilkS")
			(hide yes)
			(effects
				(font
					(size 1.27 1.27)
				)
			)
		)
		(property "Value" ""
			(at 0 0 270)
			(layer "F.Fab")
			(effects
				(font
					(size 1.27 1.27)
				)
			)
		)
		(duplicate_pad_numbers_are_jumpers no)
		(fp_line
			(start -1.2954 0.5842)
			(end -1.2954 -0.5842)
			(stroke
				(width 0.1524)
				(type default)
			)
			(layer "F.SilkS")
		)
		(fp_line
			(start 1.2954 0.5842)
			(end -1.2954 0.5842)
			(stroke
				(width 0.1524)
				(type default)
			)
			(layer "F.SilkS")
		)
		(fp_line
			(start -1.2954 -0.5842)
			(end 1.2954 -0.5842)
			(stroke
				(width 0.1524)
				(type default)
			)
			(layer "F.SilkS")
		)
		(fp_line
			(start 1.2954 -0.5842)
			(end 1.2954 0.5842)
			(stroke
				(width 0.1524)
				(type default)
			)
			(layer "F.SilkS")
		)
		(fp_line
			(start -0.8636 0.4572)
			(end -0.8636 0.4064)
			(stroke
				(width 0.1)
				(type default)
			)
			(layer "F.Fab")
		)
		(fp_line
			(start 0.8636 0.4572)
			(end -0.8636 0.4572)
			(stroke
				(width 0.1)
				(type default)
			)
			(layer "F.Fab")
		)
		(fp_line
			(start -1.1938 0.4064)
			(end -1.1938 -0.4064)
			(stroke
				(width 0.1)
				(type default)
			)
			(layer "F.Fab")
		)
		(fp_line
			(start -0.8636 0.4064)
			(end -1.1938 0.4064)
			(stroke
				(width 0.1)
				(type default)
			)
			(layer "F.Fab")
		)
		(fp_line
			(start 0.8636 0.4064)
			(end 0.8636 0.4572)
			(stroke
				(width 0.1)
				(type default)
			)
			(layer "F.Fab")
		)
		(fp_line
			(start 1.1938 0.4064)
			(end 0.8636 0.4064)
			(stroke
				(width 0.1)
				(type default)
			)
			(layer "F.Fab")
		)
		(fp_line
			(start -1.1938 -0.4064)
			(end -0.8636 -0.4064)
			(stroke
				(width 0.1)
				(type default)
			)
			(layer "F.Fab")
		)
		(fp_line
			(start -0.8636 -0.4064)
			(end -0.8636 -0.4572)
			(stroke
				(width 0.1)
				(type default)
			)
			(layer "F.Fab")
		)
		(fp_line
			(start 0.8636 -0.4064)
			(end 1.1938 -0.4064)
			(stroke
				(width 0.1)
				(type default)
			)
			(layer "F.Fab")
		)
		(fp_line
			(start 1.1938 -0.4064)
			(end 1.1938 0.4064)
			(stroke
				(width 0.1)
				(type default)
			)
			(layer "F.Fab")
		)
		(fp_line
			(start -0.8636 -0.4572)
			(end 0.8636 -0.4572)
			(stroke
				(width 0.1)
				(type default)
			)
			(layer "F.Fab")
		)
		(fp_line
			(start 0.8636 -0.4572)
			(end 0.8636 -0.4064)
			(stroke
				(width 0.1)
				(type default)
			)
			(layer "F.Fab")
		)
		(pad "1" smd rect
			(at -0.7366 0 180)
			(size 0.7112 0.8128)
			(layers "F.Cu" "F.Mask" "F.Paste")
			(net "P1V8_PLL0_PEX3")
		)
		(pad "2" smd rect
			(at 0.7366 0 180)
			(size 0.7112 0.8128)
			(layers "F.Cu" "F.Mask" "F.Paste")
			(net "GND")
		)
	)
	(footprint ""
		(layer "F.Cu")
		(at 270.799814 -154.327352 180)
		(property "Reference" "R230"
			(at 0 0 180)
			(layer "F.SilkS")
			(hide yes)
			(effects
				(font
					(size 1.27 1.27)
				)
			)
		)
		(property "Value" ""
			(at 0 0 180)
			(layer "F.Fab")
			(effects
				(font
					(size 1.27 1.27)
				)
			)
		)
		(duplicate_pad_numbers_are_jumpers no)
		(fp_line
			(start 0.7874 0.4064)
			(end -0.7874 0.4064)
			(stroke
				(width 0.1524)
				(type default)
			)
			(layer "F.SilkS")
		)
		(fp_line
			(start 0.7874 -0.4064)
			(end 0.7874 0.4064)
			(stroke
				(width 0.1524)
				(type default)
			)
			(layer "F.SilkS")
		)
		(fp_line
			(start -0.7874 0.4064)
			(end -0.7874 -0.4064)
			(stroke
				(width 0.1524)
				(type default)
			)
			(layer "F.SilkS")
		)
		(fp_line
			(start -0.7874 -0.4064)
			(end 0.7874 -0.4064)
			(stroke
				(width 0.1524)
				(type default)
			)
			(layer "F.SilkS")
		)
		(fp_line
			(start 0.67945 0.3048)
			(end 0.120396 0.3048)
			(stroke
				(width 0.1)
				(type default)
			)
			(layer "F.Fab")
		)
		(fp_line
			(start 0.67945 -0.3048)
			(end 0.67945 0.3048)
			(stroke
				(width 0.1)
				(type default)
			)
			(layer "F.Fab")
		)
		(fp_line
			(start 0.12065 -0.2794)
			(end 0.12065 -0.3048)
			(stroke
				(width 0.1)
				(type default)
			)
			(layer "F.Fab")
		)
		(fp_line
			(start 0.12065 -0.3048)
			(end 0.67945 -0.3048)
			(stroke
				(width 0.1)
				(type default)
			)
			(layer "F.Fab")
		)
		(fp_line
			(start 0.120396 0.3048)
			(end 0.120396 0.2794)
			(stroke
				(width 0.1)
				(type default)
			)
			(layer "F.Fab")
		)
		(fp_line
			(start 0.120396 0.2794)
			(end -0.12065 0.2794)
			(stroke
				(width 0.1)
				(type default)
			)
			(layer "F.Fab")
		)
		(fp_line
			(start -0.12065 0.3048)
			(end -0.67945 0.3048)
			(stroke
				(width 0.1)
				(type default)
			)
			(layer "F.Fab")
		)
		(fp_line
			(start -0.12065 0.2794)
			(end -0.12065 0.3048)
			(stroke
				(width 0.1)
				(type default)
			)
			(layer "F.Fab")
		)
		(fp_line
			(start -0.12065 -0.2794)
			(end 0.12065 -0.2794)
			(stroke
				(width 0.1)
				(type default)
			)
			(layer "F.Fab")
		)
		(fp_line
			(start -0.12065 -0.305054)
			(end -0.12065 -0.2794)
			(stroke
				(width 0.1)
				(type default)
			)
			(layer "F.Fab")
		)
		(fp_line
			(start -0.67945 0.3048)
			(end -0.67945 -0.305054)
			(stroke
				(width 0.1)
				(type default)
			)
			(layer "F.Fab")
		)
		(fp_line
			(start -0.67945 -0.305054)
			(end -0.12065 -0.305054)
			(stroke
				(width 0.1)
				(type default)
			)
			(layer "F.Fab")
		)
		(pad "1" smd circle
			(at -0.40005 0 180)
			(size 0 0)
			(layers "F.Cu" "F.Mask" "F.Paste")
			(net "NIC4_SLOT_ID0")
		)
		(pad "2" smd circle
			(at 0.40005 0 180)
			(size 0 0)
			(layers "F.Cu" "F.Mask" "F.Paste")
			(net "GND")
		)
	)
	(footprint ""
		(layer "F.Cu")
		(at 359.016808 -162.003994 90)
		(property "Reference" "PC831"
			(at 0 0 90)
			(layer "F.SilkS")
			(hide yes)
			(effects
				(font
					(size 1.27 1.27)
				)
			)
		)
		(property "Value" ""
			(at 0 0 90)
			(layer "F.Fab")
			(effects
				(font
					(size 1.27 1.27)
				)
			)
		)
		(duplicate_pad_numbers_are_jumpers no)
		(fp_line
			(start 0.7874 -0.4064)
			(end 0.7874 0.4064)
			(stroke
				(width 0.1524)
				(type default)
			)
			(layer "F.SilkS")
		)
		(fp_line
			(start -0.7874 -0.4064)
			(end 0.7874 -0.4064)
			(stroke
				(width 0.1524)
				(type default)
			)
			(layer "F.SilkS")
		)
		(fp_line
			(start 0.7874 0.4064)
			(end -0.7874 0.4064)
			(stroke
				(width 0.1524)
				(type default)
			)
			(layer "F.SilkS")
		)
		(fp_line
			(start -0.7874 0.4064)
			(end -0.7874 -0.4064)
			(stroke
				(width 0.1524)
				(type default)
			)
			(layer "F.SilkS")
		)
		(fp_line
			(start -0.12065 -0.305054)
			(end -0.12065 -0.2794)
			(stroke
				(width 0.1)
				(type default)
			)
			(layer "F.Fab")
		)
		(fp_line
			(start -0.67945 -0.305054)
			(end -0.12065 -0.305054)
			(stroke
				(width 0.1)
				(type default)
			)
			(layer "F.Fab")
		)
		(fp_line
			(start 0.67945 -0.3048)
			(end 0.67945 0.3048)
			(stroke
				(width 0.1)
				(type default)
			)
			(layer "F.Fab")
		)
		(fp_line
			(start 0.12065 -0.3048)
			(end 0.67945 -0.3048)
			(stroke
				(width 0.1)
				(type default)
			)
			(layer "F.Fab")
		)
		(fp_line
			(start 0.12065 -0.2794)
			(end 0.12065 -0.3048)
			(stroke
				(width 0.1)
				(type default)
			)
			(layer "F.Fab")
		)
		(fp_line
			(start -0.12065 -0.2794)
			(end 0.12065 -0.2794)
			(stroke
				(width 0.1)
				(type default)
			)
			(layer "F.Fab")
		)
		(fp_line
			(start 0.120396 0.2794)
			(end -0.12065 0.2794)
			(stroke
				(width 0.1)
				(type default)
			)
			(layer "F.Fab")
		)
		(fp_line
			(start -0.12065 0.2794)
			(end -0.12065 0.3048)
			(stroke
				(width 0.1)
				(type default)
			)
			(layer "F.Fab")
		)
		(fp_line
			(start 0.67945 0.3048)
			(end 0.120396 0.3048)
			(stroke
				(width 0.1)
				(type default)
			)
			(layer "F.Fab")
		)
		(fp_line
			(start 0.120396 0.3048)
			(end 0.120396 0.2794)
			(stroke
				(width 0.1)
				(type default)
			)
			(layer "F.Fab")
		)
		(fp_line
			(start -0.12065 0.3048)
			(end -0.67945 0.3048)
			(stroke
				(width 0.1)
				(type default)
			)
			(layer "F.Fab")
		)
		(fp_line
			(start -0.67945 0.3048)
			(end -0.67945 -0.305054)
			(stroke
				(width 0.1)
				(type default)
			)
			(layer "F.Fab")
		)
		(pad "1" smd circle
			(at -0.40005 0 90)
			(size 0 0)
			(layers "F.Cu" "F.Mask" "F.Paste")
			(net "P12V_NIC6_CO_SS")
		)
		(pad "2" smd circle
			(at 0.40005 0 90)
			(size 0 0)
			(layers "F.Cu" "F.Mask" "F.Paste")
			(net "GND")
		)
	)
	(footprint ""
		(layer "F.Cu")
		(at 411.97784 -113.251742)
		(property "Reference" "R392"
			(at 0 0 0)
			(layer "F.SilkS")
			(hide yes)
			(effects
				(font
					(size 1.27 1.27)
				)
			)
		)
		(property "Value" ""
			(at 0 0 0)
			(layer "F.Fab")
			(effects
				(font
					(size 1.27 1.27)
				)
			)
		)
		(duplicate_pad_numbers_are_jumpers no)
		(fp_line
			(start -0.7874 -0.4064)
			(end 0.7874 -0.4064)
			(stroke
				(width 0.1524)
				(type default)
			)
			(layer "F.SilkS")
		)
		(fp_line
			(start -0.7874 0.4064)
			(end -0.7874 -0.4064)
			(stroke
				(width 0.1524)
				(type default)
			)
			(layer "F.SilkS")
		)
		(fp_line
			(start 0.7874 -0.4064)
			(end 0.7874 0.4064)
			(stroke
				(width 0.1524)
				(type default)
			)
			(layer "F.SilkS")
		)
		(fp_line
			(start 0.7874 0.4064)
			(end -0.7874 0.4064)
			(stroke
				(width 0.1524)
				(type default)
			)
			(layer "F.SilkS")
		)
		(fp_line
			(start -0.67945 -0.305054)
			(end -0.12065 -0.305054)
			(stroke
				(width 0.1)
				(type default)
			)
			(layer "F.Fab")
		)
		(fp_line
			(start -0.67945 0.3048)
			(end -0.67945 -0.305054)
			(stroke
				(width 0.1)
				(type default)
			)
			(layer "F.Fab")
		)
		(fp_line
			(start -0.12065 -0.305054)
			(end -0.12065 -0.2794)
			(stroke
				(width 0.1)
				(type default)
			)
			(layer "F.Fab")
		)
		(fp_line
			(start -0.12065 -0.2794)
			(end 0.12065 -0.2794)
			(stroke
				(width 0.1)
				(type default)
			)
			(layer "F.Fab")
		)
		(fp_line
			(start -0.12065 0.2794)
			(end -0.12065 0.3048)
			(stroke
				(width 0.1)
				(type default)
			)
			(layer "F.Fab")
		)
		(fp_line
			(start -0.12065 0.3048)
			(end -0.67945 0.3048)
			(stroke
				(width 0.1)
				(type default)
			)
			(layer "F.Fab")
		)
		(fp_line
			(start 0.120396 0.2794)
			(end -0.12065 0.2794)
			(stroke
				(width 0.1)
				(type default)
			)
			(layer "F.Fab")
		)
		(fp_line
			(start 0.120396 0.3048)
			(end 0.120396 0.2794)
			(stroke
				(width 0.1)
				(type default)
			)
			(layer "F.Fab")
		)
		(fp_line
			(start 0.12065 -0.3048)
			(end 0.67945 -0.3048)
			(stroke
				(width 0.1)
				(type default)
			)
			(layer "F.Fab")
		)
		(fp_line
			(start 0.12065 -0.2794)
			(end 0.12065 -0.3048)
			(stroke
				(width 0.1)
				(type default)
			)
			(layer "F.Fab")
		)
		(fp_line
			(start 0.67945 -0.3048)
			(end 0.67945 0.3048)
			(stroke
				(width 0.1)
				(type default)
			)
			(layer "F.Fab")
		)
		(fp_line
			(start 0.67945 0.3048)
			(end 0.120396 0.3048)
			(stroke
				(width 0.1)
				(type default)
			)
			(layer "F.Fab")
		)
		(pad "1" smd circle
			(at -0.40005 0)
			(size 0 0)
			(layers "F.Cu" "F.Mask" "F.Paste")
			(net "RST_SMB_NIC7_MUX_ISO_N")
		)
		(pad "2" smd circle
			(at 0.40005 0)
			(size 0 0)
			(layers "F.Cu" "F.Mask" "F.Paste")
			(net "P3V3_NIC7")
		)
	)
	(footprint ""
		(layer "F.Cu")
		(at 366.968786 -149.313392 -90)
		(property "Reference" "U85"
			(at -0.089408 -2.500884 90)
			(unlocked yes)
			(layer "F.SilkS")
			(effects
				(font
					(size 0.7874 0.5842)
					(thickness 0.1524)
				)
			)
		)
		(property "Value" ""
			(at 0 0 270)
			(layer "F.Fab")
			(effects
				(font
					(size 1.27 1.27)
				)
			)
		)
		(duplicate_pad_numbers_are_jumpers no)
		(fp_line
			(start -1.500124 1.500124)
			(end -1.500124 1.004062)
			(stroke
				(width 0.1524)
				(type default)
			)
			(layer "F.SilkS")
		)
		(fp_line
			(start -1.004062 1.500124)
			(end -1.500124 1.500124)
			(stroke
				(width 0.1524)
				(type default)
			)
			(layer "F.SilkS")
		)
		(fp_line
			(start 1.500124 1.500124)
			(end 1.004062 1.500124)
			(stroke
				(width 0.1524)
				(type default)
			)
			(layer "F.SilkS")
		)
		(fp_line
			(start 1.500124 1.004062)
			(end 1.500124 1.500124)
			(stroke
				(width 0.1524)
				(type default)
			)
			(layer "F.SilkS")
		)
		(fp_line
			(start -1.500124 -1.004062)
			(end -1.500124 -1.500124)
			(stroke
				(width 0.1524)
				(type default)
			)
			(layer "F.SilkS")
		)
		(fp_line
			(start -1.500124 -1.500124)
			(end -1.004062 -1.500124)
			(stroke
				(width 0.1524)
				(type default)
			)
			(layer "F.SilkS")
		)
		(fp_line
			(start 1.004062 -1.500124)
			(end 1.500124 -1.500124)
			(stroke
				(width 0.1524)
				(type default)
			)
			(layer "F.SilkS")
		)
		(fp_line
			(start 1.500124 -1.500124)
			(end 1.500124 -1.004062)
			(stroke
				(width 0.1524)
				(type default)
			)
			(layer "F.SilkS")
		)
		(fp_poly
			(pts
				(xy -1.93421 -2.102612) (xy -2.652522 -1.3843) (xy -1.575054 -1.025144)
			)
			(stroke
				(width 0)
				(type default)
			)
			(fill yes)
			(layer "F.SilkS")
		)
		(fp_line
			(start -1.500124 1.500124)
			(end -1.500124 -1.500124)
			(stroke
				(width 0.1)
				(type default)
			)
			(layer "F.Fab")
		)
		(fp_line
			(start 1.500124 1.500124)
			(end -1.500124 1.500124)
			(stroke
				(width 0.1)
				(type default)
			)
			(layer "F.Fab")
		)
		(fp_line
			(start -1.500124 -1.500124)
			(end 1.500124 -1.500124)
			(stroke
				(width 0.1)
				(type default)
			)
			(layer "F.Fab")
		)
		(fp_line
			(start 1.500124 -1.500124)
			(end 1.500124 1.500124)
			(stroke
				(width 0.1)
				(type default)
			)
			(layer "F.Fab")
		)
		(fp_poly
			(pts
				(xy -2.847848 -1.258062) (xy -2.847848 -0.242062) (xy -1.831848 -0.750062)
			)
			(stroke
				(width 0)
				(type default)
			)
			(fill yes)
			(layer "F.Fab")
		)
		(pad "1" smd rect
			(at -1.400048 -0.750062 180)
			(size 0.2286 0.6096)
			(layers "F.Cu" "F.Mask" "F.Paste")
			(net "NIC6_ADC_A1")
		)
		(pad "2" smd rect
			(at -1.400048 -0.249936 180)
			(size 0.2286 0.6096)
			(layers "F.Cu" "F.Mask" "F.Paste")
			(net "NIC6_ADC_A0")
		)
		(pad "3" smd rect
			(at -1.400048 0.249936 180)
			(size 0.2286 0.6096)
			(layers "F.Cu" "F.Mask" "F.Paste")
			(net "NIC6_ADC_ALERT_N")
		)
		(pad "4" smd rect
			(at -1.400048 0.750062 180)
			(size 0.2286 0.6096)
			(layers "F.Cu" "F.Mask" "F.Paste")
			(net "SMB_NIC6_ADC_SDA")
		)
		(pad "5" smd rect
			(at -0.750062 1.400048 270)
			(size 0.2286 0.6096)
			(layers "F.Cu" "F.Mask" "F.Paste")
			(net "SMB_NIC6_ADC_SCL")
		)
		(pad "6" smd rect
			(at -0.249936 1.400048 270)
			(size 0.2286 0.6096)
			(layers "F.Cu" "F.Mask" "F.Paste")
			(net "Net_8630")
		)
		(pad "7" smd rect
			(at 0.249936 1.400048 270)
			(size 0.2286 0.6096)
			(layers "F.Cu" "F.Mask" "F.Paste")
			(net "Net_8629")
		)
		(pad "8" smd rect
			(at 0.750062 1.400048 270)
			(size 0.2286 0.6096)
			(layers "F.Cu" "F.Mask" "F.Paste")
			(net "Net_8628")
		)
		(pad "9" smd rect
			(at 1.400048 0.750062 180)
			(size 0.2286 0.6096)
			(layers "F.Cu" "F.Mask" "F.Paste")
			(net "P3V3_AUX")
		)
		(pad "10" smd rect
			(at 1.400048 0.249936 180)
			(size 0.2286 0.6096)
			(layers "F.Cu" "F.Mask" "F.Paste")
			(net "GND")
		)
		(pad "11" smd rect
			(at 1.400048 -0.249936 180)
			(size 0.2286 0.6096)
			(layers "F.Cu" "F.Mask" "F.Paste")
			(net "P12V_NIC6_R")
		)
		(pad "12" smd rect
			(at 1.400048 -0.750062 180)
			(size 0.2286 0.6096)
			(layers "F.Cu" "F.Mask" "F.Paste")
			(net "P12V_NIC6_VIN_N")
		)
		(pad "13" smd rect
			(at 0.750062 -1.400048 270)
			(size 0.2286 0.6096)
			(layers "F.Cu" "F.Mask" "F.Paste")
			(net "P12V_NIC6_VIN_P")
		)
		(pad "14" smd rect
			(at 0.249936 -1.400048 270)
			(size 0.2286 0.6096)
			(layers "F.Cu" "F.Mask" "F.Paste")
			(net "Net_8627")
		)
		(pad "15" smd rect
			(at -0.249936 -1.400048 270)
			(size 0.2286 0.6096)
			(layers "F.Cu" "F.Mask" "F.Paste")
			(net "Net_8626")
		)
		(pad "16" smd rect
			(at -0.750062 -1.400048 270)
			(size 0.2286 0.6096)
			(layers "F.Cu" "F.Mask" "F.Paste")
			(net "Net_8625")
		)
		(pad "TH" smd rect
			(at 0 0 270)
			(size 1.7018 1.7018)
			(layers "F.Cu" "F.Mask" "F.Paste")
			(net "GND")
		)
		(zone
			(layer "F.Cu")
			(hatch none 0.5)
			(connect_pads
				(clearance 0)
			)
			(min_thickness 0.25)
			(keepout
				(tracks not_allowed)
				(vias allowed)
				(pads allowed)
				(copperpour not_allowed)
				(footprints allowed)
			)
			(placement
				(enabled no)
				(sheetname "")
			)
			(fill
				(thermal_gap 0.5)
				(thermal_bridge_width 0.5)
				(island_removal_mode 0)
			)
			(polygon
				(pts
					(xy 366.994186 -150.35784) (xy 368.013234 -150.35784) (xy 368.013234 -148.268944) (xy 365.924338 -148.268944)
					(xy 365.924338 -150.35784) (xy 366.968786 -150.35784) (xy 366.968786 -150.215092) (xy 366.067086 -150.215092)
					(xy 366.067086 -148.411692) (xy 367.870486 -148.411692) (xy 367.870486 -150.215092) (xy 366.994186 -150.215092)
				)
			)
		)
	)
	(footprint ""
		(layer "F.Cu")
		(at 237.047786 -40.037258 90)
		(property "Reference" "U371"
			(at 0.247142 2.373884 90)
			(unlocked yes)
			(layer "F.SilkS")
			(effects
				(font
					(size 0.7874 0.5842)
					(thickness 0.1524)
				)
			)
		)
		(property "Value" ""
			(at 0 0 90)
			(layer "F.Fab")
			(effects
				(font
					(size 1.27 1.27)
				)
			)
		)
		(duplicate_pad_numbers_are_jumpers no)
		(fp_line
			(start -1.949958 -1.610106)
			(end 1.949958 -1.610106)
			(stroke
				(width 0.1524)
				(type default)
			)
			(layer "F.SilkS")
		)
		(fp_line
			(start 1.949958 -1.560068)
			(end 1.949958 1.610106)
			(stroke
				(width 0.1524)
				(type default)
			)
			(layer "F.SilkS")
		)
		(fp_line
			(start 1.949958 1.610106)
			(end -1.949958 1.610106)
			(stroke
				(width 0.1524)
				(type default)
			)
			(layer "F.SilkS")
		)
		(fp_line
			(start -1.949958 1.610106)
			(end -1.949958 -1.610106)
			(stroke
				(width 0.1524)
				(type default)
			)
			(layer "F.SilkS")
		)
		(fp_line
			(start 0.750062 -1.560068)
			(end 0.750062 1.560068)
			(stroke
				(width 0.1)
				(type default)
			)
			(layer "F.Fab")
		)
		(fp_line
			(start -0.750062 -1.560068)
			(end 0.750062 -1.560068)
			(stroke
				(width 0.1)
				(type default)
			)
			(layer "F.Fab")
		)
		(fp_line
			(start 0.750062 1.560068)
			(end -0.750062 1.560068)
			(stroke
				(width 0.1)
				(type default)
			)
			(layer "F.Fab")
		)
		(fp_line
			(start -0.750062 1.560068)
			(end -0.750062 -1.560068)
			(stroke
				(width 0.1)
				(type default)
			)
			(layer "F.Fab")
		)
		(pad "D" smd rect
			(at 1.100074 0)
			(size 1.016 1.4224)
			(layers "F.Cu" "F.Mask" "F.Paste")
			(net "SSD8_AUX_P3V3_EN")
		)
		(pad "G" smd rect
			(at -1.100074 -0.94996)
			(size 1.016 1.4224)
			(layers "F.Cu" "F.Mask" "F.Paste")
			(net "PRSNT_SSD8_R1_N")
		)
		(pad "S" smd rect
			(at -1.100074 0.94996)
			(size 1.016 1.4224)
			(layers "F.Cu" "F.Mask" "F.Paste")
			(net "GND")
		)
	)
	(footprint ""
		(layer "F.Cu")
		(at 76.891642 -350.098614 90)
		(property "Reference" "C143"
			(at 0 0 90)
			(layer "F.SilkS")
			(hide yes)
			(effects
				(font
					(size 1.27 1.27)
				)
			)
		)
		(property "Value" ""
			(at 0 0 90)
			(layer "F.Fab")
			(effects
				(font
					(size 1.27 1.27)
				)
			)
		)
		(duplicate_pad_numbers_are_jumpers no)
		(fp_line
			(start 0.299974 -0.150114)
			(end 0.299974 0.150114)
			(stroke
				(width 0.1)
				(type default)
			)
			(layer "F.Fab")
		)
		(fp_line
			(start -0.299974 -0.150114)
			(end 0.299974 -0.150114)
			(stroke
				(width 0.1)
				(type default)
			)
			(layer "F.Fab")
		)
		(fp_line
			(start 0.299974 0.150114)
			(end -0.299974 0.150114)
			(stroke
				(width 0.1)
				(type default)
			)
			(layer "F.Fab")
		)
		(fp_line
			(start -0.299974 0.150114)
			(end -0.299974 -0.150114)
			(stroke
				(width 0.1)
				(type default)
			)
			(layer "F.Fab")
		)
		(pad "1" smd rect
			(at -0.2667 0 90)
			(size 0.3048 0.381)
			(layers "F.Cu" "F.Mask" "F.Paste")
			(net "P5E_PEX0_STN6_TX_DP<104>")
		)
		(pad "2" smd rect
			(at 0.2667 0 90)
			(size 0.3048 0.381)
			(layers "F.Cu" "F.Mask" "F.Paste")
			(net "P5E_PEX0_STN6_TX_C_DP<104>")
		)
	)
	(footprint ""
		(layer "F.Cu")
		(at 386.899912 -152.295352 180)
		(property "Reference" "R323"
			(at 0 0 180)
			(layer "F.SilkS")
			(hide yes)
			(effects
				(font
					(size 1.27 1.27)
				)
			)
		)
		(property "Value" ""
			(at 0 0 180)
			(layer "F.Fab")
			(effects
				(font
					(size 1.27 1.27)
				)
			)
		)
		(duplicate_pad_numbers_are_jumpers no)
		(fp_line
			(start 0.7874 0.4064)
			(end -0.7874 0.4064)
			(stroke
				(width 0.1524)
				(type default)
			)
			(layer "F.SilkS")
		)
		(fp_line
			(start 0.7874 -0.4064)
			(end 0.7874 0.4064)
			(stroke
				(width 0.1524)
				(type default)
			)
			(layer "F.SilkS")
		)
		(fp_line
			(start -0.7874 0.4064)
			(end -0.7874 -0.4064)
			(stroke
				(width 0.1524)
				(type default)
			)
			(layer "F.SilkS")
		)
		(fp_line
			(start -0.7874 -0.4064)
			(end 0.7874 -0.4064)
			(stroke
				(width 0.1524)
				(type default)
			)
			(layer "F.SilkS")
		)
		(fp_line
			(start 0.67945 0.3048)
			(end 0.120396 0.3048)
			(stroke
				(width 0.1)
				(type default)
			)
			(layer "F.Fab")
		)
		(fp_line
			(start 0.67945 -0.3048)
			(end 0.67945 0.3048)
			(stroke
				(width 0.1)
				(type default)
			)
			(layer "F.Fab")
		)
		(fp_line
			(start 0.12065 -0.2794)
			(end 0.12065 -0.3048)
			(stroke
				(width 0.1)
				(type default)
			)
			(layer "F.Fab")
		)
		(fp_line
			(start 0.12065 -0.3048)
			(end 0.67945 -0.3048)
			(stroke
				(width 0.1)
				(type default)
			)
			(layer "F.Fab")
		)
		(fp_line
			(start 0.120396 0.3048)
			(end 0.120396 0.2794)
			(stroke
				(width 0.1)
				(type default)
			)
			(layer "F.Fab")
		)
		(fp_line
			(start 0.120396 0.2794)
			(end -0.12065 0.2794)
			(stroke
				(width 0.1)
				(type default)
			)
			(layer "F.Fab")
		)
		(fp_line
			(start -0.12065 0.3048)
			(end -0.67945 0.3048)
			(stroke
				(width 0.1)
				(type default)
			)
			(layer "F.Fab")
		)
		(fp_line
			(start -0.12065 0.2794)
			(end -0.12065 0.3048)
			(stroke
				(width 0.1)
				(type default)
			)
			(layer "F.Fab")
		)
		(fp_line
			(start -0.12065 -0.2794)
			(end 0.12065 -0.2794)
			(stroke
				(width 0.1)
				(type default)
			)
			(layer "F.Fab")
		)
		(fp_line
			(start -0.12065 -0.305054)
			(end -0.12065 -0.2794)
			(stroke
				(width 0.1)
				(type default)
			)
			(layer "F.Fab")
		)
		(fp_line
			(start -0.67945 0.3048)
			(end -0.67945 -0.305054)
			(stroke
				(width 0.1)
				(type default)
			)
			(layer "F.Fab")
		)
		(fp_line
			(start -0.67945 -0.305054)
			(end -0.12065 -0.305054)
			(stroke
				(width 0.1)
				(type default)
			)
			(layer "F.Fab")
		)
		(pad "1" smd circle
			(at -0.40005 0 180)
			(size 0 0)
			(layers "F.Cu" "F.Mask" "F.Paste")
			(net "NCSI_NIC6_RXD1")
		)
		(pad "2" smd circle
			(at 0.40005 0 180)
			(size 0 0)
			(layers "F.Cu" "F.Mask" "F.Paste")
			(net "GND")
		)
	)
	(footprint ""
		(layer "F.Cu")
		(at 138.985244 -90.099642 180)
		(property "Reference" "R1564"
			(at 0 0 180)
			(layer "F.SilkS")
			(hide yes)
			(effects
				(font
					(size 1.27 1.27)
				)
			)
		)
		(property "Value" ""
			(at 0 0 180)
			(layer "F.Fab")
			(effects
				(font
					(size 1.27 1.27)
				)
			)
		)
		(duplicate_pad_numbers_are_jumpers no)
		(fp_line
			(start 0.7874 0.4064)
			(end -0.7874 0.4064)
			(stroke
				(width 0.1524)
				(type default)
			)
			(layer "F.SilkS")
		)
		(fp_line
			(start 0.7874 -0.4064)
			(end 0.7874 0.4064)
			(stroke
				(width 0.1524)
				(type default)
			)
			(layer "F.SilkS")
		)
		(fp_line
			(start -0.7874 0.4064)
			(end -0.7874 -0.4064)
			(stroke
				(width 0.1524)
				(type default)
			)
			(layer "F.SilkS")
		)
		(fp_line
			(start -0.7874 -0.4064)
			(end 0.7874 -0.4064)
			(stroke
				(width 0.1524)
				(type default)
			)
			(layer "F.SilkS")
		)
		(fp_line
			(start 0.67945 0.3048)
			(end 0.120396 0.3048)
			(stroke
				(width 0.1)
				(type default)
			)
			(layer "F.Fab")
		)
		(fp_line
			(start 0.67945 -0.3048)
			(end 0.67945 0.3048)
			(stroke
				(width 0.1)
				(type default)
			)
			(layer "F.Fab")
		)
		(fp_line
			(start 0.12065 -0.2794)
			(end 0.12065 -0.3048)
			(stroke
				(width 0.1)
				(type default)
			)
			(layer "F.Fab")
		)
		(fp_line
			(start 0.12065 -0.3048)
			(end 0.67945 -0.3048)
			(stroke
				(width 0.1)
				(type default)
			)
			(layer "F.Fab")
		)
		(fp_line
			(start 0.120396 0.3048)
			(end 0.120396 0.2794)
			(stroke
				(width 0.1)
				(type default)
			)
			(layer "F.Fab")
		)
		(fp_line
			(start 0.120396 0.2794)
			(end -0.12065 0.2794)
			(stroke
				(width 0.1)
				(type default)
			)
			(layer "F.Fab")
		)
		(fp_line
			(start -0.12065 0.3048)
			(end -0.67945 0.3048)
			(stroke
				(width 0.1)
				(type default)
			)
			(layer "F.Fab")
		)
		(fp_line
			(start -0.12065 0.2794)
			(end -0.12065 0.3048)
			(stroke
				(width 0.1)
				(type default)
			)
			(layer "F.Fab")
		)
		(fp_line
			(start -0.12065 -0.2794)
			(end 0.12065 -0.2794)
			(stroke
				(width 0.1)
				(type default)
			)
			(layer "F.Fab")
		)
		(fp_line
			(start -0.12065 -0.305054)
			(end -0.12065 -0.2794)
			(stroke
				(width 0.1)
				(type default)
			)
			(layer "F.Fab")
		)
		(fp_line
			(start -0.67945 0.3048)
			(end -0.67945 -0.305054)
			(stroke
				(width 0.1)
				(type default)
			)
			(layer "F.Fab")
		)
		(fp_line
			(start -0.67945 -0.305054)
			(end -0.12065 -0.305054)
			(stroke
				(width 0.1)
				(type default)
			)
			(layer "F.Fab")
		)
		(pad "1" smd circle
			(at -0.40005 0 180)
			(size 0 0)
			(layers "F.Cu" "F.Mask" "F.Paste")
			(net "P3V3_AUX")
		)
		(pad "2" smd circle
			(at 0.40005 0 180)
			(size 0 0)
			(layers "F.Cu" "F.Mask" "F.Paste")
			(net "SMB_BIC_I2C9_MUX0_SSD5_R_SDA")
		)
	)
	(footprint ""
		(layer "F.Cu")
		(at 211.55152 -220.691456 -90)
		(property "Reference" "R2739"
			(at 0 0 270)
			(layer "F.SilkS")
			(hide yes)
			(effects
				(font
					(size 1.27 1.27)
				)
			)
		)
		(property "Value" ""
			(at 0 0 270)
			(layer "F.Fab")
			(effects
				(font
					(size 1.27 1.27)
				)
			)
		)
		(duplicate_pad_numbers_are_jumpers no)
		(fp_line
			(start -0.7874 0.4064)
			(end -0.7874 -0.4064)
			(stroke
				(width 0.1524)
				(type default)
			)
			(layer "F.SilkS")
		)
		(fp_line
			(start 0.7874 0.4064)
			(end -0.7874 0.4064)
			(stroke
				(width 0.1524)
				(type default)
			)
			(layer "F.SilkS")
		)
		(fp_line
			(start -0.7874 -0.4064)
			(end 0.7874 -0.4064)
			(stroke
				(width 0.1524)
				(type default)
			)
			(layer "F.SilkS")
		)
		(fp_line
			(start 0.7874 -0.4064)
			(end 0.7874 0.4064)
			(stroke
				(width 0.1524)
				(type default)
			)
			(layer "F.SilkS")
		)
		(fp_line
			(start -0.67945 0.3048)
			(end -0.67945 -0.305054)
			(stroke
				(width 0.1)
				(type default)
			)
			(layer "F.Fab")
		)
		(fp_line
			(start -0.12065 0.3048)
			(end -0.67945 0.3048)
			(stroke
				(width 0.1)
				(type default)
			)
			(layer "F.Fab")
		)
		(fp_line
			(start 0.120396 0.3048)
			(end 0.120396 0.2794)
			(stroke
				(width 0.1)
				(type default)
			)
			(layer "F.Fab")
		)
		(fp_line
			(start 0.67945 0.3048)
			(end 0.120396 0.3048)
			(stroke
				(width 0.1)
				(type default)
			)
			(layer "F.Fab")
		)
		(fp_line
			(start -0.12065 0.2794)
			(end -0.12065 0.3048)
			(stroke
				(width 0.1)
				(type default)
			)
			(layer "F.Fab")
		)
		(fp_line
			(start 0.120396 0.2794)
			(end -0.12065 0.2794)
			(stroke
				(width 0.1)
				(type default)
			)
			(layer "F.Fab")
		)
		(fp_line
			(start -0.12065 -0.2794)
			(end 0.12065 -0.2794)
			(stroke
				(width 0.1)
				(type default)
			)
			(layer "F.Fab")
		)
		(fp_line
			(start 0.12065 -0.2794)
			(end 0.12065 -0.3048)
			(stroke
				(width 0.1)
				(type default)
			)
			(layer "F.Fab")
		)
		(fp_line
			(start 0.12065 -0.3048)
			(end 0.67945 -0.3048)
			(stroke
				(width 0.1)
				(type default)
			)
			(layer "F.Fab")
		)
		(fp_line
			(start 0.67945 -0.3048)
			(end 0.67945 0.3048)
			(stroke
				(width 0.1)
				(type default)
			)
			(layer "F.Fab")
		)
		(fp_line
			(start -0.67945 -0.305054)
			(end -0.12065 -0.305054)
			(stroke
				(width 0.1)
				(type default)
			)
			(layer "F.Fab")
		)
		(fp_line
			(start -0.12065 -0.305054)
			(end -0.12065 -0.2794)
			(stroke
				(width 0.1)
				(type default)
			)
			(layer "F.Fab")
		)
		(pad "1" smd circle
			(at -0.40005 0 270)
			(size 0 0)
			(layers "F.Cu" "F.Mask" "F.Paste")
			(net "UART_MB_BIC_R_TX")
		)
		(pad "2" smd circle
			(at 0.40005 0 270)
			(size 0 0)
			(layers "F.Cu" "F.Mask" "F.Paste")
			(net "UART_MB_BIC_TX")
		)
	)
	(footprint ""
		(layer "F.Cu")
		(at 58.177176 -374.528588 180)
		(property "Reference" "C4009"
			(at 0 0 180)
			(layer "F.SilkS")
			(hide yes)
			(effects
				(font
					(size 1.27 1.27)
				)
			)
		)
		(property "Value" ""
			(at 0 0 180)
			(layer "F.Fab")
			(effects
				(font
					(size 1.27 1.27)
				)
			)
		)
		(duplicate_pad_numbers_are_jumpers no)
		(fp_line
			(start 0.7874 0.4064)
			(end -0.7874 0.4064)
			(stroke
				(width 0.1524)
				(type default)
			)
			(layer "F.SilkS")
		)
		(fp_line
			(start 0.7874 -0.4064)
			(end 0.7874 0.4064)
			(stroke
				(width 0.1524)
				(type default)
			)
			(layer "F.SilkS")
		)
		(fp_line
			(start -0.7874 0.4064)
			(end -0.7874 -0.4064)
			(stroke
				(width 0.1524)
				(type default)
			)
			(layer "F.SilkS")
		)
		(fp_line
			(start -0.7874 -0.4064)
			(end 0.7874 -0.4064)
			(stroke
				(width 0.1524)
				(type default)
			)
			(layer "F.SilkS")
		)
		(fp_line
			(start 0.67945 0.3048)
			(end 0.120396 0.3048)
			(stroke
				(width 0.1)
				(type default)
			)
			(layer "F.Fab")
		)
		(fp_line
			(start 0.67945 -0.3048)
			(end 0.67945 0.3048)
			(stroke
				(width 0.1)
				(type default)
			)
			(layer "F.Fab")
		)
		(fp_line
			(start 0.12065 -0.2794)
			(end 0.12065 -0.3048)
			(stroke
				(width 0.1)
				(type default)
			)
			(layer "F.Fab")
		)
		(fp_line
			(start 0.12065 -0.3048)
			(end 0.67945 -0.3048)
			(stroke
				(width 0.1)
				(type default)
			)
			(layer "F.Fab")
		)
		(fp_line
			(start 0.120396 0.3048)
			(end 0.120396 0.2794)
			(stroke
				(width 0.1)
				(type default)
			)
			(layer "F.Fab")
		)
		(fp_line
			(start 0.120396 0.2794)
			(end -0.12065 0.2794)
			(stroke
				(width 0.1)
				(type default)
			)
			(layer "F.Fab")
		)
		(fp_line
			(start -0.12065 0.3048)
			(end -0.67945 0.3048)
			(stroke
				(width 0.1)
				(type default)
			)
			(layer "F.Fab")
		)
		(fp_line
			(start -0.12065 0.2794)
			(end -0.12065 0.3048)
			(stroke
				(width 0.1)
				(type default)
			)
			(layer "F.Fab")
		)
		(fp_line
			(start -0.12065 -0.2794)
			(end 0.12065 -0.2794)
			(stroke
				(width 0.1)
				(type default)
			)
			(layer "F.Fab")
		)
		(fp_line
			(start -0.12065 -0.305054)
			(end -0.12065 -0.2794)
			(stroke
				(width 0.1)
				(type default)
			)
			(layer "F.Fab")
		)
		(fp_line
			(start -0.67945 0.3048)
			(end -0.67945 -0.305054)
			(stroke
				(width 0.1)
				(type default)
			)
			(layer "F.Fab")
		)
		(fp_line
			(start -0.67945 -0.305054)
			(end -0.12065 -0.305054)
			(stroke
				(width 0.1)
				(type default)
			)
			(layer "F.Fab")
		)
		(pad "1" smd circle
			(at -0.40005 0 180)
			(size 0 0)
			(layers "F.Cu" "F.Mask" "F.Paste")
			(net "GND")
		)
		(pad "2" smd circle
			(at 0.40005 0 180)
			(size 0 0)
			(layers "F.Cu" "F.Mask" "F.Paste")
			(net "PRSNT_GPU_D_N")
		)
	)
	(footprint ""
		(layer "F.Cu")
		(at 155.380436 -121.005346)
		(property "Reference" "C256"
			(at 0 0 0)
			(layer "F.SilkS")
			(hide yes)
			(effects
				(font
					(size 1.27 1.27)
				)
			)
		)
		(property "Value" ""
			(at 0 0 0)
			(layer "F.Fab")
			(effects
				(font
					(size 1.27 1.27)
				)
			)
		)
		(duplicate_pad_numbers_are_jumpers no)
		(fp_line
			(start -0.299974 -0.150114)
			(end 0.299974 -0.150114)
			(stroke
				(width 0.1)
				(type default)
			)
			(layer "F.Fab")
		)
		(fp_line
			(start -0.299974 0.150114)
			(end -0.299974 -0.150114)
			(stroke
				(width 0.1)
				(type default)
			)
			(layer "F.Fab")
		)
		(fp_line
			(start 0.299974 -0.150114)
			(end 0.299974 0.150114)
			(stroke
				(width 0.1)
				(type default)
			)
			(layer "F.Fab")
		)
		(fp_line
			(start 0.299974 0.150114)
			(end -0.299974 0.150114)
			(stroke
				(width 0.1)
				(type default)
			)
			(layer "F.Fab")
		)
		(pad "1" smd rect
			(at -0.2667 0)
			(size 0.3048 0.381)
			(layers "F.Cu" "F.Mask" "F.Paste")
			(net "P5E_PEX1_STN1_TX_DN<25>")
		)
		(pad "2" smd rect
			(at 0.2667 0)
			(size 0.3048 0.381)
			(layers "F.Cu" "F.Mask" "F.Paste")
			(net "P5E_PEX1_STN1_TX_C_DN<25>")
		)
	)
	(footprint ""
		(layer "F.Cu")
		(at 232.092754 -254.43942 -90)
		(property "Reference" "C4339"
			(at 0 0 270)
			(layer "F.SilkS")
			(hide yes)
			(effects
				(font
					(size 1.27 1.27)
				)
			)
		)
		(property "Value" ""
			(at 0 0 270)
			(layer "F.Fab")
			(effects
				(font
					(size 1.27 1.27)
				)
			)
		)
		(duplicate_pad_numbers_are_jumpers no)
		(fp_line
			(start -1.2954 0.5842)
			(end -1.2954 -0.5842)
			(stroke
				(width 0.1524)
				(type default)
			)
			(layer "F.SilkS")
		)
		(fp_line
			(start 1.2954 0.5842)
			(end -1.2954 0.5842)
			(stroke
				(width 0.1524)
				(type default)
			)
			(layer "F.SilkS")
		)
		(fp_line
			(start -1.2954 -0.5842)
			(end 1.2954 -0.5842)
			(stroke
				(width 0.1524)
				(type default)
			)
			(layer "F.SilkS")
		)
		(fp_line
			(start 1.2954 -0.5842)
			(end 1.2954 0.5842)
			(stroke
				(width 0.1524)
				(type default)
			)
			(layer "F.SilkS")
		)
		(fp_line
			(start -0.8636 0.4572)
			(end -0.8636 0.4064)
			(stroke
				(width 0.1)
				(type default)
			)
			(layer "F.Fab")
		)
		(fp_line
			(start 0.8636 0.4572)
			(end -0.8636 0.4572)
			(stroke
				(width 0.1)
				(type default)
			)
			(layer "F.Fab")
		)
		(fp_line
			(start -1.1938 0.4064)
			(end -1.1938 -0.4064)
			(stroke
				(width 0.1)
				(type default)
			)
			(layer "F.Fab")
		)
		(fp_line
			(start -0.8636 0.4064)
			(end -1.1938 0.4064)
			(stroke
				(width 0.1)
				(type default)
			)
			(layer "F.Fab")
		)
		(fp_line
			(start 0.8636 0.4064)
			(end 0.8636 0.4572)
			(stroke
				(width 0.1)
				(type default)
			)
			(layer "F.Fab")
		)
		(fp_line
			(start 1.1938 0.4064)
			(end 0.8636 0.4064)
			(stroke
				(width 0.1)
				(type default)
			)
			(layer "F.Fab")
		)
		(fp_line
			(start -1.1938 -0.4064)
			(end -0.8636 -0.4064)
			(stroke
				(width 0.1)
				(type default)
			)
			(layer "F.Fab")
		)
		(fp_line
			(start -0.8636 -0.4064)
			(end -0.8636 -0.4572)
			(stroke
				(width 0.1)
				(type default)
			)
			(layer "F.Fab")
		)
		(fp_line
			(start 0.8636 -0.4064)
			(end 1.1938 -0.4064)
			(stroke
				(width 0.1)
				(type default)
			)
			(layer "F.Fab")
		)
		(fp_line
			(start 1.1938 -0.4064)
			(end 1.1938 0.4064)
			(stroke
				(width 0.1)
				(type default)
			)
			(layer "F.Fab")
		)
		(fp_line
			(start -0.8636 -0.4572)
			(end 0.8636 -0.4572)
			(stroke
				(width 0.1)
				(type default)
			)
			(layer "F.Fab")
		)
		(fp_line
			(start 0.8636 -0.4572)
			(end 0.8636 -0.4064)
			(stroke
				(width 0.1)
				(type default)
			)
			(layer "F.Fab")
		)
		(pad "1" smd rect
			(at -0.7366 0 180)
			(size 0.7112 0.8128)
			(layers "F.Cu" "F.Mask" "F.Paste")
			(net "P1V25_SERDES_VDDPLL_PEX2_C1")
		)
		(pad "2" smd rect
			(at 0.7366 0 180)
			(size 0.7112 0.8128)
			(layers "F.Cu" "F.Mask" "F.Paste")
			(net "GND")
		)
	)
	(footprint ""
		(layer "F.Cu")
		(at 136.445244 -91.242642 180)
		(property "Reference" "R1582"
			(at 0 0 180)
			(layer "F.SilkS")
			(hide yes)
			(effects
				(font
					(size 1.27 1.27)
				)
			)
		)
		(property "Value" ""
			(at 0 0 180)
			(layer "F.Fab")
			(effects
				(font
					(size 1.27 1.27)
				)
			)
		)
		(duplicate_pad_numbers_are_jumpers no)
		(fp_line
			(start 0.7874 0.4064)
			(end -0.7874 0.4064)
			(stroke
				(width 0.1524)
				(type default)
			)
			(layer "F.SilkS")
		)
		(fp_line
			(start 0.7874 -0.4064)
			(end 0.7874 0.4064)
			(stroke
				(width 0.1524)
				(type default)
			)
			(layer "F.SilkS")
		)
		(fp_line
			(start -0.7874 0.4064)
			(end -0.7874 -0.4064)
			(stroke
				(width 0.1524)
				(type default)
			)
			(layer "F.SilkS")
		)
		(fp_line
			(start -0.7874 -0.4064)
			(end 0.7874 -0.4064)
			(stroke
				(width 0.1524)
				(type default)
			)
			(layer "F.SilkS")
		)
		(fp_line
			(start 0.67945 0.3048)
			(end 0.120396 0.3048)
			(stroke
				(width 0.1)
				(type default)
			)
			(layer "F.Fab")
		)
		(fp_line
			(start 0.67945 -0.3048)
			(end 0.67945 0.3048)
			(stroke
				(width 0.1)
				(type default)
			)
			(layer "F.Fab")
		)
		(fp_line
			(start 0.12065 -0.2794)
			(end 0.12065 -0.3048)
			(stroke
				(width 0.1)
				(type default)
			)
			(layer "F.Fab")
		)
		(fp_line
			(start 0.12065 -0.3048)
			(end 0.67945 -0.3048)
			(stroke
				(width 0.1)
				(type default)
			)
			(layer "F.Fab")
		)
		(fp_line
			(start 0.120396 0.3048)
			(end 0.120396 0.2794)
			(stroke
				(width 0.1)
				(type default)
			)
			(layer "F.Fab")
		)
		(fp_line
			(start 0.120396 0.2794)
			(end -0.12065 0.2794)
			(stroke
				(width 0.1)
				(type default)
			)
			(layer "F.Fab")
		)
		(fp_line
			(start -0.12065 0.3048)
			(end -0.67945 0.3048)
			(stroke
				(width 0.1)
				(type default)
			)
			(layer "F.Fab")
		)
		(fp_line
			(start -0.12065 0.2794)
			(end -0.12065 0.3048)
			(stroke
				(width 0.1)
				(type default)
			)
			(layer "F.Fab")
		)
		(fp_line
			(start -0.12065 -0.2794)
			(end 0.12065 -0.2794)
			(stroke
				(width 0.1)
				(type default)
			)
			(layer "F.Fab")
		)
		(fp_line
			(start -0.12065 -0.305054)
			(end -0.12065 -0.2794)
			(stroke
				(width 0.1)
				(type default)
			)
			(layer "F.Fab")
		)
		(fp_line
			(start -0.67945 0.3048)
			(end -0.67945 -0.305054)
			(stroke
				(width 0.1)
				(type default)
			)
			(layer "F.Fab")
		)
		(fp_line
			(start -0.67945 -0.305054)
			(end -0.12065 -0.305054)
			(stroke
				(width 0.1)
				(type default)
			)
			(layer "F.Fab")
		)
		(pad "1" smd circle
			(at -0.40005 0 180)
			(size 0 0)
			(layers "F.Cu" "F.Mask" "F.Paste")
			(net "SMB_BIC_I2C9_MUX0_SSD5_R_SCL")
		)
		(pad "2" smd circle
			(at 0.40005 0 180)
			(size 0 0)
			(layers "F.Cu" "F.Mask" "F.Paste")
			(net "SMB_BIC_I2C9_MUX0_SSD5_SCL")
		)
	)
	(footprint ""
		(layer "F.Cu")
		(at 220.125036 -14.735302 180)
		(property "Reference" "C2726"
			(at 0 0 180)
			(layer "F.SilkS")
			(hide yes)
			(effects
				(font
					(size 1.27 1.27)
				)
			)
		)
		(property "Value" ""
			(at 0 0 180)
			(layer "F.Fab")
			(effects
				(font
					(size 1.27 1.27)
				)
			)
		)
		(duplicate_pad_numbers_are_jumpers no)
		(fp_line
			(start 0.7874 0.4064)
			(end -0.7874 0.4064)
			(stroke
				(width 0.1524)
				(type default)
			)
			(layer "F.SilkS")
		)
		(fp_line
			(start 0.7874 -0.4064)
			(end 0.7874 0.4064)
			(stroke
				(width 0.1524)
				(type default)
			)
			(layer "F.SilkS")
		)
		(fp_line
			(start -0.7874 0.4064)
			(end -0.7874 -0.4064)
			(stroke
				(width 0.1524)
				(type default)
			)
			(layer "F.SilkS")
		)
		(fp_line
			(start -0.7874 -0.4064)
			(end 0.7874 -0.4064)
			(stroke
				(width 0.1524)
				(type default)
			)
			(layer "F.SilkS")
		)
		(fp_line
			(start 0.67945 0.3048)
			(end 0.120396 0.3048)
			(stroke
				(width 0.1)
				(type default)
			)
			(layer "F.Fab")
		)
		(fp_line
			(start 0.67945 -0.3048)
			(end 0.67945 0.3048)
			(stroke
				(width 0.1)
				(type default)
			)
			(layer "F.Fab")
		)
		(fp_line
			(start 0.12065 -0.2794)
			(end 0.12065 -0.3048)
			(stroke
				(width 0.1)
				(type default)
			)
			(layer "F.Fab")
		)
		(fp_line
			(start 0.12065 -0.3048)
			(end 0.67945 -0.3048)
			(stroke
				(width 0.1)
				(type default)
			)
			(layer "F.Fab")
		)
		(fp_line
			(start 0.120396 0.3048)
			(end 0.120396 0.2794)
			(stroke
				(width 0.1)
				(type default)
			)
			(layer "F.Fab")
		)
		(fp_line
			(start 0.120396 0.2794)
			(end -0.12065 0.2794)
			(stroke
				(width 0.1)
				(type default)
			)
			(layer "F.Fab")
		)
		(fp_line
			(start -0.12065 0.3048)
			(end -0.67945 0.3048)
			(stroke
				(width 0.1)
				(type default)
			)
			(layer "F.Fab")
		)
		(fp_line
			(start -0.12065 0.2794)
			(end -0.12065 0.3048)
			(stroke
				(width 0.1)
				(type default)
			)
			(layer "F.Fab")
		)
		(fp_line
			(start -0.12065 -0.2794)
			(end 0.12065 -0.2794)
			(stroke
				(width 0.1)
				(type default)
			)
			(layer "F.Fab")
		)
		(fp_line
			(start -0.12065 -0.305054)
			(end -0.12065 -0.2794)
			(stroke
				(width 0.1)
				(type default)
			)
			(layer "F.Fab")
		)
		(fp_line
			(start -0.67945 0.3048)
			(end -0.67945 -0.305054)
			(stroke
				(width 0.1)
				(type default)
			)
			(layer "F.Fab")
		)
		(fp_line
			(start -0.67945 -0.305054)
			(end -0.12065 -0.305054)
			(stroke
				(width 0.1)
				(type default)
			)
			(layer "F.Fab")
		)
		(pad "1" smd circle
			(at -0.40005 0 180)
			(size 0 0)
			(layers "F.Cu" "F.Mask" "F.Paste")
			(net "GND")
		)
		(pad "2" smd circle
			(at 0.40005 0 180)
			(size 0 0)
			(layers "F.Cu" "F.Mask" "F.Paste")
			(net "P3V3_SSD7")
		)
	)
	(footprint ""
		(layer "F.Cu")
		(at 58.686192 -386.734812)
		(property "Reference" "R1830"
			(at 0 0 0)
			(layer "F.SilkS")
			(hide yes)
			(effects
				(font
					(size 1.27 1.27)
				)
			)
		)
		(property "Value" ""
			(at 0 0 0)
			(layer "F.Fab")
			(effects
				(font
					(size 1.27 1.27)
				)
			)
		)
		(duplicate_pad_numbers_are_jumpers no)
		(fp_line
			(start -0.7874 -0.4064)
			(end 0.7874 -0.4064)
			(stroke
				(width 0.1524)
				(type default)
			)
			(layer "F.SilkS")
		)
		(fp_line
			(start -0.7874 0.4064)
			(end -0.7874 -0.4064)
			(stroke
				(width 0.1524)
				(type default)
			)
			(layer "F.SilkS")
		)
		(fp_line
			(start 0.7874 -0.4064)
			(end 0.7874 0.4064)
			(stroke
				(width 0.1524)
				(type default)
			)
			(layer "F.SilkS")
		)
		(fp_line
			(start 0.7874 0.4064)
			(end -0.7874 0.4064)
			(stroke
				(width 0.1524)
				(type default)
			)
			(layer "F.SilkS")
		)
		(fp_line
			(start -0.67945 -0.305054)
			(end -0.12065 -0.305054)
			(stroke
				(width 0.1)
				(type default)
			)
			(layer "F.Fab")
		)
		(fp_line
			(start -0.67945 0.3048)
			(end -0.67945 -0.305054)
			(stroke
				(width 0.1)
				(type default)
			)
			(layer "F.Fab")
		)
		(fp_line
			(start -0.12065 -0.305054)
			(end -0.12065 -0.2794)
			(stroke
				(width 0.1)
				(type default)
			)
			(layer "F.Fab")
		)
		(fp_line
			(start -0.12065 -0.2794)
			(end 0.12065 -0.2794)
			(stroke
				(width 0.1)
				(type default)
			)
			(layer "F.Fab")
		)
		(fp_line
			(start -0.12065 0.2794)
			(end -0.12065 0.3048)
			(stroke
				(width 0.1)
				(type default)
			)
			(layer "F.Fab")
		)
		(fp_line
			(start -0.12065 0.3048)
			(end -0.67945 0.3048)
			(stroke
				(width 0.1)
				(type default)
			)
			(layer "F.Fab")
		)
		(fp_line
			(start 0.120396 0.2794)
			(end -0.12065 0.2794)
			(stroke
				(width 0.1)
				(type default)
			)
			(layer "F.Fab")
		)
		(fp_line
			(start 0.120396 0.3048)
			(end 0.120396 0.2794)
			(stroke
				(width 0.1)
				(type default)
			)
			(layer "F.Fab")
		)
		(fp_line
			(start 0.12065 -0.3048)
			(end 0.67945 -0.3048)
			(stroke
				(width 0.1)
				(type default)
			)
			(layer "F.Fab")
		)
		(fp_line
			(start 0.12065 -0.2794)
			(end 0.12065 -0.3048)
			(stroke
				(width 0.1)
				(type default)
			)
			(layer "F.Fab")
		)
		(fp_line
			(start 0.67945 -0.3048)
			(end 0.67945 0.3048)
			(stroke
				(width 0.1)
				(type default)
			)
			(layer "F.Fab")
		)
		(fp_line
			(start 0.67945 0.3048)
			(end 0.120396 0.3048)
			(stroke
				(width 0.1)
				(type default)
			)
			(layer "F.Fab")
		)
		(pad "1" smd circle
			(at -0.40005 0)
			(size 0 0)
			(layers "F.Cu" "F.Mask" "F.Paste")
			(net "GPU_BASE_ID0_R")
		)
		(pad "2" smd circle
			(at 0.40005 0)
			(size 0 0)
			(layers "F.Cu" "F.Mask" "F.Paste")
			(net "GPU_BASE_ID0")
		)
	)
	(footprint ""
		(layer "F.Cu")
		(at 359.156 -173.99)
		(property "Reference" "R4664"
			(at 0 0 0)
			(layer "F.SilkS")
			(hide yes)
			(effects
				(font
					(size 1.27 1.27)
				)
			)
		)
		(property "Value" ""
			(at 0 0 0)
			(layer "F.Fab")
			(effects
				(font
					(size 1.27 1.27)
				)
			)
		)
		(duplicate_pad_numbers_are_jumpers no)
		(fp_line
			(start -0.7874 -0.4064)
			(end 0.7874 -0.4064)
			(stroke
				(width 0.1524)
				(type default)
			)
			(layer "F.SilkS")
		)
		(fp_line
			(start -0.7874 0.4064)
			(end -0.7874 -0.4064)
			(stroke
				(width 0.1524)
				(type default)
			)
			(layer "F.SilkS")
		)
		(fp_line
			(start 0.7874 -0.4064)
			(end 0.7874 0.4064)
			(stroke
				(width 0.1524)
				(type default)
			)
			(layer "F.SilkS")
		)
		(fp_line
			(start 0.7874 0.4064)
			(end -0.7874 0.4064)
			(stroke
				(width 0.1524)
				(type default)
			)
			(layer "F.SilkS")
		)
		(fp_line
			(start -0.67945 -0.305054)
			(end -0.12065 -0.305054)
			(stroke
				(width 0.1)
				(type default)
			)
			(layer "F.Fab")
		)
		(fp_line
			(start -0.67945 0.3048)
			(end -0.67945 -0.305054)
			(stroke
				(width 0.1)
				(type default)
			)
			(layer "F.Fab")
		)
		(fp_line
			(start -0.12065 -0.305054)
			(end -0.12065 -0.2794)
			(stroke
				(width 0.1)
				(type default)
			)
			(layer "F.Fab")
		)
		(fp_line
			(start -0.12065 -0.2794)
			(end 0.12065 -0.2794)
			(stroke
				(width 0.1)
				(type default)
			)
			(layer "F.Fab")
		)
		(fp_line
			(start -0.12065 0.2794)
			(end -0.12065 0.3048)
			(stroke
				(width 0.1)
				(type default)
			)
			(layer "F.Fab")
		)
		(fp_line
			(start -0.12065 0.3048)
			(end -0.67945 0.3048)
			(stroke
				(width 0.1)
				(type default)
			)
			(layer "F.Fab")
		)
		(fp_line
			(start 0.120396 0.2794)
			(end -0.12065 0.2794)
			(stroke
				(width 0.1)
				(type default)
			)
			(layer "F.Fab")
		)
		(fp_line
			(start 0.120396 0.3048)
			(end 0.120396 0.2794)
			(stroke
				(width 0.1)
				(type default)
			)
			(layer "F.Fab")
		)
		(fp_line
			(start 0.12065 -0.3048)
			(end 0.67945 -0.3048)
			(stroke
				(width 0.1)
				(type default)
			)
			(layer "F.Fab")
		)
		(fp_line
			(start 0.12065 -0.2794)
			(end 0.12065 -0.3048)
			(stroke
				(width 0.1)
				(type default)
			)
			(layer "F.Fab")
		)
		(fp_line
			(start 0.67945 -0.3048)
			(end 0.67945 0.3048)
			(stroke
				(width 0.1)
				(type default)
			)
			(layer "F.Fab")
		)
		(fp_line
			(start 0.67945 0.3048)
			(end 0.120396 0.3048)
			(stroke
				(width 0.1)
				(type default)
			)
			(layer "F.Fab")
		)
		(pad "1" smd circle
			(at -0.40005 0)
			(size 0 0)
			(layers "F.Cu" "F.Mask" "F.Paste")
			(net "P3V3_AUX")
		)
		(pad "2" smd circle
			(at 0.40005 0)
			(size 0 0)
			(layers "F.Cu" "F.Mask" "F.Paste")
			(net "SSD7_PEX_PWR_EN_R")
		)
	)
	(footprint ""
		(layer "F.Cu")
		(at 279.730454 -66.32194 -90)
		(property "Reference" "PC867"
			(at 0 0 270)
			(layer "F.SilkS")
			(hide yes)
			(effects
				(font
					(size 1.27 1.27)
				)
			)
		)
		(property "Value" ""
			(at 0 0 270)
			(layer "F.Fab")
			(effects
				(font
					(size 1.27 1.27)
				)
			)
		)
		(duplicate_pad_numbers_are_jumpers no)
		(fp_line
			(start -0.7874 0.4064)
			(end -0.7874 -0.4064)
			(stroke
				(width 0.1524)
				(type default)
			)
			(layer "F.SilkS")
		)
		(fp_line
			(start 0.7874 0.4064)
			(end -0.7874 0.4064)
			(stroke
				(width 0.1524)
				(type default)
			)
			(layer "F.SilkS")
		)
		(fp_line
			(start -0.7874 -0.4064)
			(end 0.7874 -0.4064)
			(stroke
				(width 0.1524)
				(type default)
			)
			(layer "F.SilkS")
		)
		(fp_line
			(start 0.7874 -0.4064)
			(end 0.7874 0.4064)
			(stroke
				(width 0.1524)
				(type default)
			)
			(layer "F.SilkS")
		)
		(fp_line
			(start -0.67945 0.3048)
			(end -0.67945 -0.305054)
			(stroke
				(width 0.1)
				(type default)
			)
			(layer "F.Fab")
		)
		(fp_line
			(start -0.12065 0.3048)
			(end -0.67945 0.3048)
			(stroke
				(width 0.1)
				(type default)
			)
			(layer "F.Fab")
		)
		(fp_line
			(start 0.120396 0.3048)
			(end 0.120396 0.2794)
			(stroke
				(width 0.1)
				(type default)
			)
			(layer "F.Fab")
		)
		(fp_line
			(start 0.67945 0.3048)
			(end 0.120396 0.3048)
			(stroke
				(width 0.1)
				(type default)
			)
			(layer "F.Fab")
		)
		(fp_line
			(start -0.12065 0.2794)
			(end -0.12065 0.3048)
			(stroke
				(width 0.1)
				(type default)
			)
			(layer "F.Fab")
		)
		(fp_line
			(start 0.120396 0.2794)
			(end -0.12065 0.2794)
			(stroke
				(width 0.1)
				(type default)
			)
			(layer "F.Fab")
		)
		(fp_line
			(start -0.12065 -0.2794)
			(end 0.12065 -0.2794)
			(stroke
				(width 0.1)
				(type default)
			)
			(layer "F.Fab")
		)
		(fp_line
			(start 0.12065 -0.2794)
			(end 0.12065 -0.3048)
			(stroke
				(width 0.1)
				(type default)
			)
			(layer "F.Fab")
		)
		(fp_line
			(start 0.12065 -0.3048)
			(end 0.67945 -0.3048)
			(stroke
				(width 0.1)
				(type default)
			)
			(layer "F.Fab")
		)
		(fp_line
			(start 0.67945 -0.3048)
			(end 0.67945 0.3048)
			(stroke
				(width 0.1)
				(type default)
			)
			(layer "F.Fab")
		)
		(fp_line
			(start -0.67945 -0.305054)
			(end -0.12065 -0.305054)
			(stroke
				(width 0.1)
				(type default)
			)
			(layer "F.Fab")
		)
		(fp_line
			(start -0.12065 -0.305054)
			(end -0.12065 -0.2794)
			(stroke
				(width 0.1)
				(type default)
			)
			(layer "F.Fab")
		)
		(pad "1" smd circle
			(at -0.40005 0 270)
			(size 0 0)
			(layers "F.Cu" "F.Mask" "F.Paste")
			(net "P12V_SSD9_CO_DV_DT")
		)
		(pad "2" smd circle
			(at 0.40005 0 270)
			(size 0 0)
			(layers "F.Cu" "F.Mask" "F.Paste")
			(net "GND")
		)
	)
	(footprint ""
		(layer "F.Cu")
		(at 112.85728 -313.620404)
		(property "Reference" "L49"
			(at 3.58267 1.35636 90)
			(unlocked yes)
			(layer "F.SilkS")
			(effects
				(font
					(size 0.7874 0.5842)
					(thickness 0.1524)
				)
				(justify left)
			)
		)
		(property "Value" ""
			(at 0 0 0)
			(layer "F.Fab")
			(effects
				(font
					(size 1.27 1.27)
				)
			)
		)
		(duplicate_pad_numbers_are_jumpers no)
		(fp_line
			(start -2.248154 -4.9911)
			(end -2.248154 -1.54559)
			(stroke
				(width 0.1524)
				(type default)
			)
			(layer "F.SilkS")
		)
		(fp_line
			(start -2.248154 1.572768)
			(end -2.248154 4.9911)
			(stroke
				(width 0.1524)
				(type default)
			)
			(layer "F.SilkS")
		)
		(fp_line
			(start -2.248154 4.9911)
			(end 2.248154 4.9911)
			(stroke
				(width 0.1524)
				(type default)
			)
			(layer "F.SilkS")
		)
		(fp_line
			(start 2.248154 -4.9911)
			(end -2.248154 -4.9911)
			(stroke
				(width 0.1524)
				(type default)
			)
			(layer "F.SilkS")
		)
		(fp_line
			(start 2.248154 -1.501648)
			(end 2.248154 -4.9911)
			(stroke
				(width 0.1524)
				(type default)
			)
			(layer "F.SilkS")
		)
		(fp_line
			(start 2.248154 4.9911)
			(end 2.248154 1.605788)
			(stroke
				(width 0.1524)
				(type default)
			)
			(layer "F.SilkS")
		)
		(fp_line
			(start -1.700022 -0.899922)
			(end -1.700022 0.899922)
			(stroke
				(width 0.1)
				(type default)
			)
			(layer "F.Fab")
		)
		(fp_line
			(start -1.700022 0.899922)
			(end 1.700022 0.899922)
			(stroke
				(width 0.1)
				(type default)
			)
			(layer "F.Fab")
		)
		(fp_line
			(start 1.700022 -0.899922)
			(end -1.700022 -0.899922)
			(stroke
				(width 0.1)
				(type default)
			)
			(layer "F.Fab")
		)
		(fp_line
			(start 1.700022 0.899922)
			(end 1.700022 -0.899922)
			(stroke
				(width 0.1)
				(type default)
			)
			(layer "F.Fab")
		)
		(pad "1" smd rect
			(at -1.575054 0)
			(size 1.1684 9.8044)
			(layers "F.Cu" "F.Mask" "F.Paste")
			(net "P0V8_PEX0")
		)
		(pad "2" smd rect
			(at 1.575054 0)
			(size 1.1684 9.8044)
			(layers "F.Cu" "F.Mask" "F.Paste")
			(net "P0V8_SERDES_VDDA_PEX0")
		)
	)
	(footprint ""
		(layer "F.Cu")
		(at 135.96239 -184.656984 -90)
		(property "Reference" "R1110"
			(at 0 0 270)
			(layer "F.SilkS")
			(hide yes)
			(effects
				(font
					(size 1.27 1.27)
				)
			)
		)
		(property "Value" ""
			(at 0 0 270)
			(layer "F.Fab")
			(effects
				(font
					(size 1.27 1.27)
				)
			)
		)
		(duplicate_pad_numbers_are_jumpers no)
		(fp_line
			(start 0.7874 0.4064)
			(end -0.7874 0.4064)
			(stroke
				(width 0.1524)
				(type default)
			)
			(layer "F.SilkS")
		)
		(fp_line
			(start -0.67945 0.3048)
			(end -0.67945 -0.305054)
			(stroke
				(width 0.1)
				(type default)
			)
			(layer "F.Fab")
		)
		(fp_line
			(start -0.12065 0.3048)
			(end -0.67945 0.3048)
			(stroke
				(width 0.1)
				(type default)
			)
			(layer "F.Fab")
		)
		(fp_line
			(start 0.120396 0.3048)
			(end 0.120396 0.2794)
			(stroke
				(width 0.1)
				(type default)
			)
			(layer "F.Fab")
		)
		(fp_line
			(start 0.67945 0.3048)
			(end 0.120396 0.3048)
			(stroke
				(width 0.1)
				(type default)
			)
			(layer "F.Fab")
		)
		(fp_line
			(start -0.12065 0.2794)
			(end -0.12065 0.3048)
			(stroke
				(width 0.1)
				(type default)
			)
			(layer "F.Fab")
		)
		(fp_line
			(start 0.120396 0.2794)
			(end -0.12065 0.2794)
			(stroke
				(width 0.1)
				(type default)
			)
			(layer "F.Fab")
		)
		(fp_line
			(start -0.12065 -0.2794)
			(end 0.12065 -0.2794)
			(stroke
				(width 0.1)
				(type default)
			)
			(layer "F.Fab")
		)
		(fp_line
			(start 0.12065 -0.2794)
			(end 0.12065 -0.3048)
			(stroke
				(width 0.1)
				(type default)
			)
			(layer "F.Fab")
		)
		(fp_line
			(start 0.12065 -0.3048)
			(end 0.67945 -0.3048)
			(stroke
				(width 0.1)
				(type default)
			)
			(layer "F.Fab")
		)
		(fp_line
			(start 0.67945 -0.3048)
			(end 0.67945 0.3048)
			(stroke
				(width 0.1)
				(type default)
			)
			(layer "F.Fab")
		)
		(fp_line
			(start -0.67945 -0.305054)
			(end -0.12065 -0.305054)
			(stroke
				(width 0.1)
				(type default)
			)
			(layer "F.Fab")
		)
		(fp_line
			(start -0.12065 -0.305054)
			(end -0.12065 -0.2794)
			(stroke
				(width 0.1)
				(type default)
			)
			(layer "F.Fab")
		)
		(pad "1" smd circle
			(at -0.40005 0 270)
			(size 0 0)
			(layers "F.Cu" "F.Mask" "F.Paste")
			(net "CLK_100M_DB2000QL_NIC7_R_DN")
		)
		(pad "2" smd circle
			(at 0.40005 0 270)
			(size 0 0)
			(layers "F.Cu" "F.Mask" "F.Paste")
			(net "CLK_100M_DB2000QL_NIC7_DN")
		)
	)
	(footprint ""
		(layer "F.Cu")
		(at 110.152942 -116.230654 90)
		(property "Reference" "PR6873"
			(at 0 0 90)
			(layer "F.SilkS")
			(hide yes)
			(effects
				(font
					(size 1.27 1.27)
				)
			)
		)
		(property "Value" ""
			(at 0 0 90)
			(layer "F.Fab")
			(effects
				(font
					(size 1.27 1.27)
				)
			)
		)
		(duplicate_pad_numbers_are_jumpers no)
		(fp_line
			(start 0.7874 -0.4064)
			(end 0.7874 0.4064)
			(stroke
				(width 0.1524)
				(type default)
			)
			(layer "F.SilkS")
		)
		(fp_line
			(start -0.7874 -0.4064)
			(end 0.7874 -0.4064)
			(stroke
				(width 0.1524)
				(type default)
			)
			(layer "F.SilkS")
		)
		(fp_line
			(start 0.7874 0.4064)
			(end -0.7874 0.4064)
			(stroke
				(width 0.1524)
				(type default)
			)
			(layer "F.SilkS")
		)
		(fp_line
			(start -0.7874 0.4064)
			(end -0.7874 -0.4064)
			(stroke
				(width 0.1524)
				(type default)
			)
			(layer "F.SilkS")
		)
		(fp_line
			(start -0.12065 -0.305054)
			(end -0.12065 -0.2794)
			(stroke
				(width 0.1)
				(type default)
			)
			(layer "F.Fab")
		)
		(fp_line
			(start -0.67945 -0.305054)
			(end -0.12065 -0.305054)
			(stroke
				(width 0.1)
				(type default)
			)
			(layer "F.Fab")
		)
		(fp_line
			(start 0.67945 -0.3048)
			(end 0.67945 0.3048)
			(stroke
				(width 0.1)
				(type default)
			)
			(layer "F.Fab")
		)
		(fp_line
			(start 0.12065 -0.3048)
			(end 0.67945 -0.3048)
			(stroke
				(width 0.1)
				(type default)
			)
			(layer "F.Fab")
		)
		(fp_line
			(start 0.12065 -0.2794)
			(end 0.12065 -0.3048)
			(stroke
				(width 0.1)
				(type default)
			)
			(layer "F.Fab")
		)
		(fp_line
			(start -0.12065 -0.2794)
			(end 0.12065 -0.2794)
			(stroke
				(width 0.1)
				(type default)
			)
			(layer "F.Fab")
		)
		(fp_line
			(start 0.120396 0.2794)
			(end -0.12065 0.2794)
			(stroke
				(width 0.1)
				(type default)
			)
			(layer "F.Fab")
		)
		(fp_line
			(start -0.12065 0.2794)
			(end -0.12065 0.3048)
			(stroke
				(width 0.1)
				(type default)
			)
			(layer "F.Fab")
		)
		(fp_line
			(start 0.67945 0.3048)
			(end 0.120396 0.3048)
			(stroke
				(width 0.1)
				(type default)
			)
			(layer "F.Fab")
		)
		(fp_line
			(start 0.120396 0.3048)
			(end 0.120396 0.2794)
			(stroke
				(width 0.1)
				(type default)
			)
			(layer "F.Fab")
		)
		(fp_line
			(start -0.12065 0.3048)
			(end -0.67945 0.3048)
			(stroke
				(width 0.1)
				(type default)
			)
			(layer "F.Fab")
		)
		(fp_line
			(start -0.67945 0.3048)
			(end -0.67945 -0.305054)
			(stroke
				(width 0.1)
				(type default)
			)
			(layer "F.Fab")
		)
		(pad "1" smd circle
			(at -0.40005 0 90)
			(size 0 0)
			(layers "F.Cu" "F.Mask" "F.Paste")
			(net "P12V_NIC1_CO_FLTB")
		)
		(pad "2" smd circle
			(at 0.40005 0 90)
			(size 0 0)
			(layers "F.Cu" "F.Mask" "F.Paste")
			(net "P3V3_AUX")
		)
	)
	(footprint ""
		(layer "F.Cu")
		(at 355.854 -167.64 180)
		(property "Reference" "R4735"
			(at 0 0 180)
			(layer "F.SilkS")
			(hide yes)
			(effects
				(font
					(size 1.27 1.27)
				)
			)
		)
		(property "Value" ""
			(at 0 0 180)
			(layer "F.Fab")
			(effects
				(font
					(size 1.27 1.27)
				)
			)
		)
		(duplicate_pad_numbers_are_jumpers no)
		(fp_line
			(start 0.7874 0.4064)
			(end -0.7874 0.4064)
			(stroke
				(width 0.1524)
				(type default)
			)
			(layer "F.SilkS")
		)
		(fp_line
			(start 0.7874 -0.4064)
			(end 0.7874 0.4064)
			(stroke
				(width 0.1524)
				(type default)
			)
			(layer "F.SilkS")
		)
		(fp_line
			(start -0.7874 0.4064)
			(end -0.7874 -0.4064)
			(stroke
				(width 0.1524)
				(type default)
			)
			(layer "F.SilkS")
		)
		(fp_line
			(start -0.7874 -0.4064)
			(end 0.7874 -0.4064)
			(stroke
				(width 0.1524)
				(type default)
			)
			(layer "F.SilkS")
		)
		(fp_line
			(start 0.67945 0.3048)
			(end 0.120396 0.3048)
			(stroke
				(width 0.1)
				(type default)
			)
			(layer "F.Fab")
		)
		(fp_line
			(start 0.67945 -0.3048)
			(end 0.67945 0.3048)
			(stroke
				(width 0.1)
				(type default)
			)
			(layer "F.Fab")
		)
		(fp_line
			(start 0.12065 -0.2794)
			(end 0.12065 -0.3048)
			(stroke
				(width 0.1)
				(type default)
			)
			(layer "F.Fab")
		)
		(fp_line
			(start 0.12065 -0.3048)
			(end 0.67945 -0.3048)
			(stroke
				(width 0.1)
				(type default)
			)
			(layer "F.Fab")
		)
		(fp_line
			(start 0.120396 0.3048)
			(end 0.120396 0.2794)
			(stroke
				(width 0.1)
				(type default)
			)
			(layer "F.Fab")
		)
		(fp_line
			(start 0.120396 0.2794)
			(end -0.12065 0.2794)
			(stroke
				(width 0.1)
				(type default)
			)
			(layer "F.Fab")
		)
		(fp_line
			(start -0.12065 0.3048)
			(end -0.67945 0.3048)
			(stroke
				(width 0.1)
				(type default)
			)
			(layer "F.Fab")
		)
		(fp_line
			(start -0.12065 0.2794)
			(end -0.12065 0.3048)
			(stroke
				(width 0.1)
				(type default)
			)
			(layer "F.Fab")
		)
		(fp_line
			(start -0.12065 -0.2794)
			(end 0.12065 -0.2794)
			(stroke
				(width 0.1)
				(type default)
			)
			(layer "F.Fab")
		)
		(fp_line
			(start -0.12065 -0.305054)
			(end -0.12065 -0.2794)
			(stroke
				(width 0.1)
				(type default)
			)
			(layer "F.Fab")
		)
		(fp_line
			(start -0.67945 0.3048)
			(end -0.67945 -0.305054)
			(stroke
				(width 0.1)
				(type default)
			)
			(layer "F.Fab")
		)
		(fp_line
			(start -0.67945 -0.305054)
			(end -0.12065 -0.305054)
			(stroke
				(width 0.1)
				(type default)
			)
			(layer "F.Fab")
		)
		(pad "1" smd circle
			(at -0.40005 0 180)
			(size 0 0)
			(layers "F.Cu" "F.Mask" "F.Paste")
			(net "P3V3_AUX")
		)
		(pad "2" smd circle
			(at 0.40005 0 180)
			(size 0 0)
			(layers "F.Cu" "F.Mask" "F.Paste")
			(net "RST_PEX_NIC5_PERST_R_N")
		)
	)
	(footprint ""
		(layer "F.Cu")
		(at 34.179002 -59.577986 -90)
		(property "Reference" "R888"
			(at 0 0 270)
			(layer "F.SilkS")
			(hide yes)
			(effects
				(font
					(size 1.27 1.27)
				)
			)
		)
		(property "Value" ""
			(at 0 0 270)
			(layer "F.Fab")
			(effects
				(font
					(size 1.27 1.27)
				)
			)
		)
		(duplicate_pad_numbers_are_jumpers no)
		(fp_line
			(start -0.7874 0.4064)
			(end -0.7874 -0.4064)
			(stroke
				(width 0.1524)
				(type default)
			)
			(layer "F.SilkS")
		)
		(fp_line
			(start 0.7874 0.4064)
			(end -0.7874 0.4064)
			(stroke
				(width 0.1524)
				(type default)
			)
			(layer "F.SilkS")
		)
		(fp_line
			(start -0.7874 -0.4064)
			(end 0.7874 -0.4064)
			(stroke
				(width 0.1524)
				(type default)
			)
			(layer "F.SilkS")
		)
		(fp_line
			(start 0.7874 -0.4064)
			(end 0.7874 0.4064)
			(stroke
				(width 0.1524)
				(type default)
			)
			(layer "F.SilkS")
		)
		(fp_line
			(start -0.67945 0.3048)
			(end -0.67945 -0.305054)
			(stroke
				(width 0.1)
				(type default)
			)
			(layer "F.Fab")
		)
		(fp_line
			(start -0.12065 0.3048)
			(end -0.67945 0.3048)
			(stroke
				(width 0.1)
				(type default)
			)
			(layer "F.Fab")
		)
		(fp_line
			(start 0.120396 0.3048)
			(end 0.120396 0.2794)
			(stroke
				(width 0.1)
				(type default)
			)
			(layer "F.Fab")
		)
		(fp_line
			(start 0.67945 0.3048)
			(end 0.120396 0.3048)
			(stroke
				(width 0.1)
				(type default)
			)
			(layer "F.Fab")
		)
		(fp_line
			(start -0.12065 0.2794)
			(end -0.12065 0.3048)
			(stroke
				(width 0.1)
				(type default)
			)
			(layer "F.Fab")
		)
		(fp_line
			(start 0.120396 0.2794)
			(end -0.12065 0.2794)
			(stroke
				(width 0.1)
				(type default)
			)
			(layer "F.Fab")
		)
		(fp_line
			(start -0.12065 -0.2794)
			(end 0.12065 -0.2794)
			(stroke
				(width 0.1)
				(type default)
			)
			(layer "F.Fab")
		)
		(fp_line
			(start 0.12065 -0.2794)
			(end 0.12065 -0.3048)
			(stroke
				(width 0.1)
				(type default)
			)
			(layer "F.Fab")
		)
		(fp_line
			(start 0.12065 -0.3048)
			(end 0.67945 -0.3048)
			(stroke
				(width 0.1)
				(type default)
			)
			(layer "F.Fab")
		)
		(fp_line
			(start 0.67945 -0.3048)
			(end 0.67945 0.3048)
			(stroke
				(width 0.1)
				(type default)
			)
			(layer "F.Fab")
		)
		(fp_line
			(start -0.67945 -0.305054)
			(end -0.12065 -0.305054)
			(stroke
				(width 0.1)
				(type default)
			)
			(layer "F.Fab")
		)
		(fp_line
			(start -0.12065 -0.305054)
			(end -0.12065 -0.2794)
			(stroke
				(width 0.1)
				(type default)
			)
			(layer "F.Fab")
		)
		(pad "1" smd circle
			(at -0.40005 0 270)
			(size 0 0)
			(layers "F.Cu" "F.Mask" "F.Paste")
			(net "P3V3_SSD1")
		)
		(pad "2" smd circle
			(at 0.40005 0 270)
			(size 0 0)
			(layers "F.Cu" "F.Mask" "F.Paste")
			(net "PWRGD_P3V3_SSD1")
		)
	)
	(footprint ""
		(layer "F.Cu")
		(at 131.404868 -356.244906 90)
		(property "Reference" "C2256"
			(at 0 0 90)
			(layer "F.SilkS")
			(hide yes)
			(effects
				(font
					(size 1.27 1.27)
				)
			)
		)
		(property "Value" ""
			(at 0 0 90)
			(layer "F.Fab")
			(effects
				(font
					(size 1.27 1.27)
				)
			)
		)
		(duplicate_pad_numbers_are_jumpers no)
		(fp_line
			(start 0.299974 -0.150114)
			(end 0.299974 0.150114)
			(stroke
				(width 0.1)
				(type default)
			)
			(layer "F.Fab")
		)
		(fp_line
			(start -0.299974 -0.150114)
			(end 0.299974 -0.150114)
			(stroke
				(width 0.1)
				(type default)
			)
			(layer "F.Fab")
		)
		(fp_line
			(start 0.299974 0.150114)
			(end -0.299974 0.150114)
			(stroke
				(width 0.1)
				(type default)
			)
			(layer "F.Fab")
		)
		(fp_line
			(start -0.299974 0.150114)
			(end -0.299974 -0.150114)
			(stroke
				(width 0.1)
				(type default)
			)
			(layer "F.Fab")
		)
		(pad "1" smd rect
			(at -0.2667 0 90)
			(size 0.3048 0.381)
			(layers "F.Cu" "F.Mask" "F.Paste")
			(net "P5E_PEX1_STN5_TX_DN<89>")
		)
		(pad "2" smd rect
			(at 0.2667 0 90)
			(size 0.3048 0.381)
			(layers "F.Cu" "F.Mask" "F.Paste")
			(net "P5E_PEX1_STN5_TX_C_DN<89>")
		)
	)
	(footprint ""
		(layer "F.Cu")
		(at 137.7696 -214.963756 90)
		(property "Reference" "R6643"
			(at 0 0 90)
			(layer "F.SilkS")
			(hide yes)
			(effects
				(font
					(size 1.27 1.27)
				)
			)
		)
		(property "Value" ""
			(at 0 0 90)
			(layer "F.Fab")
			(effects
				(font
					(size 1.27 1.27)
				)
			)
		)
		(duplicate_pad_numbers_are_jumpers no)
		(fp_line
			(start 0.7874 -0.4064)
			(end 0.7874 0.4064)
			(stroke
				(width 0.1524)
				(type default)
			)
			(layer "F.SilkS")
		)
		(fp_line
			(start -0.7874 -0.4064)
			(end 0.7874 -0.4064)
			(stroke
				(width 0.1524)
				(type default)
			)
			(layer "F.SilkS")
		)
		(fp_line
			(start 0.7874 0.4064)
			(end -0.7874 0.4064)
			(stroke
				(width 0.1524)
				(type default)
			)
			(layer "F.SilkS")
		)
		(fp_line
			(start -0.7874 0.4064)
			(end -0.7874 -0.4064)
			(stroke
				(width 0.1524)
				(type default)
			)
			(layer "F.SilkS")
		)
		(fp_line
			(start -0.12065 -0.305054)
			(end -0.12065 -0.2794)
			(stroke
				(width 0.1)
				(type default)
			)
			(layer "F.Fab")
		)
		(fp_line
			(start -0.67945 -0.305054)
			(end -0.12065 -0.305054)
			(stroke
				(width 0.1)
				(type default)
			)
			(layer "F.Fab")
		)
		(fp_line
			(start 0.67945 -0.3048)
			(end 0.67945 0.3048)
			(stroke
				(width 0.1)
				(type default)
			)
			(layer "F.Fab")
		)
		(fp_line
			(start 0.12065 -0.3048)
			(end 0.67945 -0.3048)
			(stroke
				(width 0.1)
				(type default)
			)
			(layer "F.Fab")
		)
		(fp_line
			(start 0.12065 -0.2794)
			(end 0.12065 -0.3048)
			(stroke
				(width 0.1)
				(type default)
			)
			(layer "F.Fab")
		)
		(fp_line
			(start -0.12065 -0.2794)
			(end 0.12065 -0.2794)
			(stroke
				(width 0.1)
				(type default)
			)
			(layer "F.Fab")
		)
		(fp_line
			(start 0.120396 0.2794)
			(end -0.12065 0.2794)
			(stroke
				(width 0.1)
				(type default)
			)
			(layer "F.Fab")
		)
		(fp_line
			(start -0.12065 0.2794)
			(end -0.12065 0.3048)
			(stroke
				(width 0.1)
				(type default)
			)
			(layer "F.Fab")
		)
		(fp_line
			(start 0.67945 0.3048)
			(end 0.120396 0.3048)
			(stroke
				(width 0.1)
				(type default)
			)
			(layer "F.Fab")
		)
		(fp_line
			(start 0.120396 0.3048)
			(end 0.120396 0.2794)
			(stroke
				(width 0.1)
				(type default)
			)
			(layer "F.Fab")
		)
		(fp_line
			(start -0.12065 0.3048)
			(end -0.67945 0.3048)
			(stroke
				(width 0.1)
				(type default)
			)
			(layer "F.Fab")
		)
		(fp_line
			(start -0.67945 0.3048)
			(end -0.67945 -0.305054)
			(stroke
				(width 0.1)
				(type default)
			)
			(layer "F.Fab")
		)
		(pad "1" smd circle
			(at -0.40005 0 90)
			(size 0 0)
			(layers "F.Cu" "F.Mask" "F.Paste")
			(net "UART_PEX2_CLI_RX")
		)
		(pad "2" smd circle
			(at 0.40005 0 90)
			(size 0 0)
			(layers "F.Cu" "F.Mask" "F.Paste")
			(net "UART_PEX2_CLI_R_RX")
		)
	)
	(footprint ""
		(layer "F.Cu")
		(at 312.21934 -149.79015 180)
		(property "Reference" "C430"
			(at 0 0 180)
			(layer "F.SilkS")
			(hide yes)
			(effects
				(font
					(size 1.27 1.27)
				)
			)
		)
		(property "Value" ""
			(at 0 0 180)
			(layer "F.Fab")
			(effects
				(font
					(size 1.27 1.27)
				)
			)
		)
		(duplicate_pad_numbers_are_jumpers no)
		(fp_line
			(start 0.299974 0.150114)
			(end -0.299974 0.150114)
			(stroke
				(width 0.1)
				(type default)
			)
			(layer "F.Fab")
		)
		(fp_line
			(start 0.299974 -0.150114)
			(end 0.299974 0.150114)
			(stroke
				(width 0.1)
				(type default)
			)
			(layer "F.Fab")
		)
		(fp_line
			(start -0.299974 0.150114)
			(end -0.299974 -0.150114)
			(stroke
				(width 0.1)
				(type default)
			)
			(layer "F.Fab")
		)
		(fp_line
			(start -0.299974 -0.150114)
			(end 0.299974 -0.150114)
			(stroke
				(width 0.1)
				(type default)
			)
			(layer "F.Fab")
		)
		(pad "1" smd rect
			(at -0.2667 0 180)
			(size 0.3048 0.381)
			(layers "F.Cu" "F.Mask" "F.Paste")
			(net "P5E_PEX2_STN0_TX_DP<12>")
		)
		(pad "2" smd rect
			(at 0.2667 0 180)
			(size 0.3048 0.381)
			(layers "F.Cu" "F.Mask" "F.Paste")
			(net "P5E_PEX2_STN0_TX_C_DP<12>")
		)
	)
	(footprint ""
		(layer "F.Cu")
		(at 129.534666 -133.088126 180)
		(property "Reference" "PC329"
			(at 0 0 180)
			(layer "F.SilkS")
			(hide yes)
			(effects
				(font
					(size 1.27 1.27)
				)
			)
		)
		(property "Value" ""
			(at 0 0 180)
			(layer "F.Fab")
			(effects
				(font
					(size 1.27 1.27)
				)
			)
		)
		(duplicate_pad_numbers_are_jumpers no)
		(fp_line
			(start 1.524 0.762)
			(end -1.524 0.762)
			(stroke
				(width 0.1524)
				(type default)
			)
			(layer "F.SilkS")
		)
		(fp_line
			(start 1.524 -0.762)
			(end 1.524 0.762)
			(stroke
				(width 0.1524)
				(type default)
			)
			(layer "F.SilkS")
		)
		(fp_line
			(start -1.524 0.762)
			(end -1.524 -0.762)
			(stroke
				(width 0.1524)
				(type default)
			)
			(layer "F.SilkS")
		)
		(fp_line
			(start -1.524 -0.762)
			(end 1.524 -0.762)
			(stroke
				(width 0.1524)
				(type default)
			)
			(layer "F.SilkS")
		)
		(fp_line
			(start 1.1049 0.724916)
			(end 1.1049 -0.724916)
			(stroke
				(width 0.1)
				(type default)
			)
			(layer "F.Fab")
		)
		(fp_line
			(start 1.1049 -0.724916)
			(end -1.1049 -0.724916)
			(stroke
				(width 0.1)
				(type default)
			)
			(layer "F.Fab")
		)
		(fp_line
			(start -1.1049 0.724916)
			(end 1.1049 0.724916)
			(stroke
				(width 0.1)
				(type default)
			)
			(layer "F.Fab")
		)
		(fp_line
			(start -1.1049 -0.724916)
			(end -1.1049 0.724916)
			(stroke
				(width 0.1)
				(type default)
			)
			(layer "F.Fab")
		)
		(pad "1" smd rect
			(at -0.889 0)
			(size 1.016 1.27)
			(layers "F.Cu" "F.Mask" "F.Paste")
			(net "GND")
		)
		(pad "2" smd rect
			(at 0.889 0)
			(size 1.016 1.27)
			(layers "F.Cu" "F.Mask" "F.Paste")
			(net "P12V_AUX")
		)
	)
	(footprint ""
		(layer "F.Cu")
		(at 44.178728 -343.952322 90)
		(property "Reference" "C2174"
			(at 0 0 90)
			(layer "F.SilkS")
			(hide yes)
			(effects
				(font
					(size 1.27 1.27)
				)
			)
		)
		(property "Value" ""
			(at 0 0 90)
			(layer "F.Fab")
			(effects
				(font
					(size 1.27 1.27)
				)
			)
		)
		(duplicate_pad_numbers_are_jumpers no)
		(fp_line
			(start 0.299974 -0.150114)
			(end 0.299974 0.150114)
			(stroke
				(width 0.1)
				(type default)
			)
			(layer "F.Fab")
		)
		(fp_line
			(start -0.299974 -0.150114)
			(end 0.299974 -0.150114)
			(stroke
				(width 0.1)
				(type default)
			)
			(layer "F.Fab")
		)
		(fp_line
			(start 0.299974 0.150114)
			(end -0.299974 0.150114)
			(stroke
				(width 0.1)
				(type default)
			)
			(layer "F.Fab")
		)
		(fp_line
			(start -0.299974 0.150114)
			(end -0.299974 -0.150114)
			(stroke
				(width 0.1)
				(type default)
			)
			(layer "F.Fab")
		)
		(pad "1" smd rect
			(at -0.2667 0 90)
			(size 0.3048 0.381)
			(layers "F.Cu" "F.Mask" "F.Paste")
			(net "P5E_PEX0_STN4_TX_DP<68>")
		)
		(pad "2" smd rect
			(at 0.2667 0 90)
			(size 0.3048 0.381)
			(layers "F.Cu" "F.Mask" "F.Paste")
			(net "P5E_PEX0_STN4_TX_C_DP<68>")
		)
	)
	(footprint ""
		(layer "F.Cu")
		(at 196.882512 -29.875734)
		(property "Reference" "PU126"
			(at -3.162046 -2.160524 90)
			(unlocked yes)
			(layer "F.SilkS")
			(effects
				(font
					(size 0.7874 0.5842)
					(thickness 0.1524)
				)
			)
		)
		(property "Value" ""
			(at 0 0 0)
			(layer "F.Fab")
			(effects
				(font
					(size 1.27 1.27)
				)
			)
		)
		(duplicate_pad_numbers_are_jumpers no)
		(fp_line
			(start -1.239774 -1.495298)
			(end 1.239774 -1.495298)
			(stroke
				(width 0.1524)
				(type default)
			)
			(layer "F.SilkS")
		)
		(fp_line
			(start -1.239774 1.495298)
			(end -1.239774 -1.495298)
			(stroke
				(width 0.1524)
				(type default)
			)
			(layer "F.SilkS")
		)
		(fp_line
			(start 1.239774 -1.495298)
			(end 1.239774 1.495298)
			(stroke
				(width 0.1524)
				(type default)
			)
			(layer "F.SilkS")
		)
		(fp_line
			(start 1.239774 1.495298)
			(end -1.239774 1.495298)
			(stroke
				(width 0.1524)
				(type default)
			)
			(layer "F.SilkS")
		)
		(fp_poly
			(pts
				(xy -2.797556 -1.220724) (xy -2.797556 -0.204724) (xy -1.781556 -0.712724)
			)
			(stroke
				(width 0)
				(type default)
			)
			(fill yes)
			(layer "F.SilkS")
		)
		(fp_line
			(start -0.8001 -1.050036)
			(end 0.8001 -1.050036)
			(stroke
				(width 0.1)
				(type default)
			)
			(layer "F.Fab")
		)
		(fp_line
			(start -0.8001 1.050036)
			(end -0.8001 -1.050036)
			(stroke
				(width 0.1)
				(type default)
			)
			(layer "F.Fab")
		)
		(fp_line
			(start 0.8001 -1.050036)
			(end 0.8001 1.050036)
			(stroke
				(width 0.1)
				(type default)
			)
			(layer "F.Fab")
		)
		(fp_line
			(start 0.8001 1.050036)
			(end -0.8001 1.050036)
			(stroke
				(width 0.1)
				(type default)
			)
			(layer "F.Fab")
		)
		(fp_poly
			(pts
				(xy -2.458974 -0.508) (xy -2.458974 0.508) (xy -1.442974 0)
			)
			(stroke
				(width 0)
				(type default)
			)
			(fill yes)
			(layer "F.Fab")
		)
		(pad "1_2" smd circle
			(at -0.374904 0 90)
			(size 0 0)
			(layers "F.Cu" "F.Mask" "F.Paste")
			(net "P3V3_AUX")
		)
		(pad "3" smd rect
			(at -0.499872 0.999998)
			(size 0.254 0.7112)
			(layers "F.Cu" "F.Mask" "F.Paste")
			(net "GND")
		)
		(pad "4" smd rect
			(at 0 0.999998)
			(size 0.254 0.7112)
			(layers "F.Cu" "F.Mask" "F.Paste")
			(net "P3V3_SSD7_CO_ILIMIT")
		)
		(pad "5" smd rect
			(at 0.499872 0.999998)
			(size 0.254 0.7112)
			(layers "F.Cu" "F.Mask" "F.Paste")
			(net "P3V3_SSD7_CO_MODE")
		)
		(pad "6_7" smd circle
			(at 0.374904 0 270)
			(size 0 0)
			(layers "F.Cu" "F.Mask" "F.Paste")
			(net "P3V3_SSD7")
		)
		(pad "8" smd rect
			(at 0.499872 -0.999998)
			(size 0.254 0.7112)
			(layers "F.Cu" "F.Mask" "F.Paste")
			(net "P3V3_SSD7_CO_GATE")
		)
		(pad "9" smd rect
			(at 0 -0.999998)
			(size 0.254 0.7112)
			(layers "F.Cu" "F.Mask" "F.Paste")
			(net "P3V3_SSD7_CO_EN")
		)
		(pad "10" smd rect
			(at -0.499872 -0.999998)
			(size 0.254 0.7112)
			(layers "F.Cu" "F.Mask" "F.Paste")
			(net "P3V3_SSD7_CO_DV_DT")
		)
	)
	(footprint ""
		(layer "F.Cu")
		(at 16.231362 -392.321034 180)
		(property "Reference" "R6756"
			(at 0 0 180)
			(layer "F.SilkS")
			(hide yes)
			(effects
				(font
					(size 1.27 1.27)
				)
			)
		)
		(property "Value" ""
			(at 0 0 180)
			(layer "F.Fab")
			(effects
				(font
					(size 1.27 1.27)
				)
			)
		)
		(duplicate_pad_numbers_are_jumpers no)
		(fp_line
			(start 0.7874 0.4064)
			(end -0.7874 0.4064)
			(stroke
				(width 0.1524)
				(type default)
			)
			(layer "F.SilkS")
		)
		(fp_line
			(start 0.7874 -0.4064)
			(end 0.7874 0.4064)
			(stroke
				(width 0.1524)
				(type default)
			)
			(layer "F.SilkS")
		)
		(fp_line
			(start -0.7874 0.4064)
			(end -0.7874 -0.4064)
			(stroke
				(width 0.1524)
				(type default)
			)
			(layer "F.SilkS")
		)
		(fp_line
			(start -0.7874 -0.4064)
			(end 0.7874 -0.4064)
			(stroke
				(width 0.1524)
				(type default)
			)
			(layer "F.SilkS")
		)
		(fp_line
			(start 0.67945 0.3048)
			(end 0.120396 0.3048)
			(stroke
				(width 0.1)
				(type default)
			)
			(layer "F.Fab")
		)
		(fp_line
			(start 0.67945 -0.3048)
			(end 0.67945 0.3048)
			(stroke
				(width 0.1)
				(type default)
			)
			(layer "F.Fab")
		)
		(fp_line
			(start 0.12065 -0.2794)
			(end 0.12065 -0.3048)
			(stroke
				(width 0.1)
				(type default)
			)
			(layer "F.Fab")
		)
		(fp_line
			(start 0.12065 -0.3048)
			(end 0.67945 -0.3048)
			(stroke
				(width 0.1)
				(type default)
			)
			(layer "F.Fab")
		)
		(fp_line
			(start 0.120396 0.3048)
			(end 0.120396 0.2794)
			(stroke
				(width 0.1)
				(type default)
			)
			(layer "F.Fab")
		)
		(fp_line
			(start 0.120396 0.2794)
			(end -0.12065 0.2794)
			(stroke
				(width 0.1)
				(type default)
			)
			(layer "F.Fab")
		)
		(fp_line
			(start -0.12065 0.3048)
			(end -0.67945 0.3048)
			(stroke
				(width 0.1)
				(type default)
			)
			(layer "F.Fab")
		)
		(fp_line
			(start -0.12065 0.2794)
			(end -0.12065 0.3048)
			(stroke
				(width 0.1)
				(type default)
			)
			(layer "F.Fab")
		)
		(fp_line
			(start -0.12065 -0.2794)
			(end 0.12065 -0.2794)
			(stroke
				(width 0.1)
				(type default)
			)
			(layer "F.Fab")
		)
		(fp_line
			(start -0.12065 -0.305054)
			(end -0.12065 -0.2794)
			(stroke
				(width 0.1)
				(type default)
			)
			(layer "F.Fab")
		)
		(fp_line
			(start -0.67945 0.3048)
			(end -0.67945 -0.305054)
			(stroke
				(width 0.1)
				(type default)
			)
			(layer "F.Fab")
		)
		(fp_line
			(start -0.67945 -0.305054)
			(end -0.12065 -0.305054)
			(stroke
				(width 0.1)
				(type default)
			)
			(layer "F.Fab")
		)
		(pad "1" smd circle
			(at -0.40005 0 180)
			(size 0 0)
			(layers "F.Cu" "F.Mask" "F.Paste")
			(net "P3V3_USB_8042")
		)
		(pad "2" smd circle
			(at 0.40005 0 180)
			(size 0 0)
			(layers "F.Cu" "F.Mask" "F.Paste")
			(net "BIC_USB_8042_HUB_PWRCTL3")
		)
	)
	(footprint ""
		(layer "F.Cu")
		(at 429.082454 -29.875734)
		(property "Reference" "PU134"
			(at -2.954528 -2.694178 90)
			(unlocked yes)
			(layer "F.SilkS")
			(effects
				(font
					(size 0.7874 0.5842)
					(thickness 0.1524)
				)
			)
		)
		(property "Value" ""
			(at 0 0 0)
			(layer "F.Fab")
			(effects
				(font
					(size 1.27 1.27)
				)
			)
		)
		(duplicate_pad_numbers_are_jumpers no)
		(fp_line
			(start -1.239774 -1.495298)
			(end 1.239774 -1.495298)
			(stroke
				(width 0.1524)
				(type default)
			)
			(layer "F.SilkS")
		)
		(fp_line
			(start -1.239774 1.495298)
			(end -1.239774 -1.495298)
			(stroke
				(width 0.1524)
				(type default)
			)
			(layer "F.SilkS")
		)
		(fp_line
			(start 1.239774 -1.495298)
			(end 1.239774 1.495298)
			(stroke
				(width 0.1524)
				(type default)
			)
			(layer "F.SilkS")
		)
		(fp_line
			(start 1.239774 1.495298)
			(end -1.239774 1.495298)
			(stroke
				(width 0.1524)
				(type default)
			)
			(layer "F.SilkS")
		)
		(fp_poly
			(pts
				(xy -2.07137 -1.295146) (xy -2.789682 -0.576834) (xy -1.712214 -0.217424)
			)
			(stroke
				(width 0)
				(type default)
			)
			(fill yes)
			(layer "F.SilkS")
		)
		(fp_line
			(start -0.8001 -1.050036)
			(end 0.8001 -1.050036)
			(stroke
				(width 0.1)
				(type default)
			)
			(layer "F.Fab")
		)
		(fp_line
			(start -0.8001 1.050036)
			(end -0.8001 -1.050036)
			(stroke
				(width 0.1)
				(type default)
			)
			(layer "F.Fab")
		)
		(fp_line
			(start 0.8001 -1.050036)
			(end 0.8001 1.050036)
			(stroke
				(width 0.1)
				(type default)
			)
			(layer "F.Fab")
		)
		(fp_line
			(start 0.8001 1.050036)
			(end -0.8001 1.050036)
			(stroke
				(width 0.1)
				(type default)
			)
			(layer "F.Fab")
		)
		(fp_poly
			(pts
				(xy -2.458974 -0.508) (xy -2.458974 0.508) (xy -1.442974 0)
			)
			(stroke
				(width 0)
				(type default)
			)
			(fill yes)
			(layer "F.Fab")
		)
		(pad "1_2" smd circle
			(at -0.374904 0 90)
			(size 0 0)
			(layers "F.Cu" "F.Mask" "F.Paste")
			(net "P3V3_AUX")
		)
		(pad "3" smd rect
			(at -0.499872 0.999998)
			(size 0.254 0.7112)
			(layers "F.Cu" "F.Mask" "F.Paste")
			(net "GND")
		)
		(pad "4" smd rect
			(at 0 0.999998)
			(size 0.254 0.7112)
			(layers "F.Cu" "F.Mask" "F.Paste")
			(net "P3V3_SSD15_CO_ILIMIT")
		)
		(pad "5" smd rect
			(at 0.499872 0.999998)
			(size 0.254 0.7112)
			(layers "F.Cu" "F.Mask" "F.Paste")
			(net "P3V3_SSD15_CO_MODE")
		)
		(pad "6_7" smd circle
			(at 0.374904 0 270)
			(size 0 0)
			(layers "F.Cu" "F.Mask" "F.Paste")
			(net "P3V3_SSD15")
		)
		(pad "8" smd rect
			(at 0.499872 -0.999998)
			(size 0.254 0.7112)
			(layers "F.Cu" "F.Mask" "F.Paste")
			(net "P3V3_SSD15_CO_GATE")
		)
		(pad "9" smd rect
			(at 0 -0.999998)
			(size 0.254 0.7112)
			(layers "F.Cu" "F.Mask" "F.Paste")
			(net "P3V3_SSD15_CO_EN")
		)
		(pad "10" smd rect
			(at -0.499872 -0.999998)
			(size 0.254 0.7112)
			(layers "F.Cu" "F.Mask" "F.Paste")
			(net "P3V3_SSD15_CO_DV_DT")
		)
	)
	(footprint ""
		(layer "F.Cu")
		(at 374.910604 -18.61439 90)
		(property "Reference" "U138"
			(at -1.39319 2.280666 90)
			(unlocked yes)
			(layer "F.SilkS")
			(effects
				(font
					(size 0.7874 0.5842)
					(thickness 0.1524)
				)
				(justify left)
			)
		)
		(property "Value" ""
			(at 0 0 90)
			(layer "F.Fab")
			(effects
				(font
					(size 1.27 1.27)
				)
			)
		)
		(duplicate_pad_numbers_are_jumpers no)
		(fp_line
			(start 1.463548 -1.549908)
			(end 1.463548 1.549908)
			(stroke
				(width 0.1524)
				(type default)
			)
			(layer "F.SilkS")
		)
		(fp_line
			(start 0.762 -1.549908)
			(end 1.463548 -1.549908)
			(stroke
				(width 0.1524)
				(type default)
			)
			(layer "F.SilkS")
		)
		(fp_line
			(start -0.787908 -1.549908)
			(end 0 -0.762)
			(stroke
				(width 0.1524)
				(type default)
			)
			(layer "F.SilkS")
		)
		(fp_line
			(start -1.463548 -1.549908)
			(end -0.787908 -1.549908)
			(stroke
				(width 0.1524)
				(type default)
			)
			(layer "F.SilkS")
		)
		(fp_line
			(start 0 -0.762)
			(end 0.762 -1.549908)
			(stroke
				(width 0.1524)
				(type default)
			)
			(layer "F.SilkS")
		)
		(fp_line
			(start 1.463548 1.549908)
			(end -1.463548 1.549908)
			(stroke
				(width 0.1524)
				(type default)
			)
			(layer "F.SilkS")
		)
		(fp_line
			(start -1.463548 1.549908)
			(end -1.463548 -1.549908)
			(stroke
				(width 0.1524)
				(type default)
			)
			(layer "F.SilkS")
		)
		(fp_poly
			(pts
				(xy -3.4798 -1.359916) (xy -2.86004 -1.050036) (xy -3.4798 -0.740156)
			)
			(stroke
				(width 0)
				(type default)
			)
			(fill yes)
			(layer "F.SilkS")
		)
		(fp_line
			(start 1.549908 -1.549908)
			(end 1.549908 1.549908)
			(stroke
				(width 0.1)
				(type default)
			)
			(layer "F.Fab")
		)
		(fp_line
			(start -1.549908 -1.549908)
			(end 1.549908 -1.549908)
			(stroke
				(width 0.1)
				(type default)
			)
			(layer "F.Fab")
		)
		(fp_line
			(start 1.549908 1.549908)
			(end -1.549908 1.549908)
			(stroke
				(width 0.1)
				(type default)
			)
			(layer "F.Fab")
		)
		(fp_line
			(start -1.549908 1.549908)
			(end -1.549908 -1.549908)
			(stroke
				(width 0.1)
				(type default)
			)
			(layer "F.Fab")
		)
		(fp_poly
			(pts
				(xy -3.4798 -1.359916) (xy -2.86004 -1.050036) (xy -3.4798 -0.740156)
			)
			(stroke
				(width 0)
				(type default)
			)
			(fill yes)
			(layer "F.Fab")
		)
		(pad "1" smd rect
			(at -2.175002 -1.050036 180)
			(size 0.6096 1.1684)
			(layers "F.Cu" "F.Mask" "F.Paste")
			(net "P3V3_SSD12")
		)
		(pad "2" smd rect
			(at -2.175002 -0.32512 180)
			(size 0.4318 1.1684)
			(layers "F.Cu" "F.Mask" "F.Paste")
			(net "SMB_ISO_SSD12_SCL")
		)
		(pad "3" smd rect
			(at -2.175002 0.32512 180)
			(size 0.4318 1.1684)
			(layers "F.Cu" "F.Mask" "F.Paste")
			(net "SMB_ISO_SSD12_SDA")
		)
		(pad "4" smd rect
			(at -2.175002 1.050036 180)
			(size 0.6096 1.1684)
			(layers "F.Cu" "F.Mask" "F.Paste")
			(net "GND")
		)
		(pad "5" smd rect
			(at 2.175002 1.050036 180)
			(size 0.6096 1.1684)
			(layers "F.Cu" "F.Mask" "F.Paste")
			(net "SMB_SSD12_ISO_EN")
		)
		(pad "6" smd rect
			(at 2.175002 0.32512 180)
			(size 0.4318 1.1684)
			(layers "F.Cu" "F.Mask" "F.Paste")
			(net "SMB_BIC_I2C9_MUX1_SSD12_R_SDA")
		)
		(pad "7" smd rect
			(at 2.175002 -0.32512 180)
			(size 0.4318 1.1684)
			(layers "F.Cu" "F.Mask" "F.Paste")
			(net "SMB_BIC_I2C9_MUX1_SSD12_R_SCL")
		)
		(pad "8" smd rect
			(at 2.175002 -1.050036 180)
			(size 0.6096 1.1684)
			(layers "F.Cu" "F.Mask" "F.Paste")
			(net "P3V3_AUX")
		)
	)
	(footprint ""
		(layer "F.Cu")
		(at 145.239486 -390.398254 -90)
		(property "Reference" "R1846"
			(at 0 0 270)
			(layer "F.SilkS")
			(hide yes)
			(effects
				(font
					(size 1.27 1.27)
				)
			)
		)
		(property "Value" ""
			(at 0 0 270)
			(layer "F.Fab")
			(effects
				(font
					(size 1.27 1.27)
				)
			)
		)
		(duplicate_pad_numbers_are_jumpers no)
		(fp_line
			(start -0.7874 0.4064)
			(end -0.7874 -0.4064)
			(stroke
				(width 0.1524)
				(type default)
			)
			(layer "F.SilkS")
		)
		(fp_line
			(start 0.7874 0.4064)
			(end -0.7874 0.4064)
			(stroke
				(width 0.1524)
				(type default)
			)
			(layer "F.SilkS")
		)
		(fp_line
			(start -0.7874 -0.4064)
			(end 0.7874 -0.4064)
			(stroke
				(width 0.1524)
				(type default)
			)
			(layer "F.SilkS")
		)
		(fp_line
			(start 0.7874 -0.4064)
			(end 0.7874 0.4064)
			(stroke
				(width 0.1524)
				(type default)
			)
			(layer "F.SilkS")
		)
		(fp_line
			(start -0.67945 0.3048)
			(end -0.67945 -0.305054)
			(stroke
				(width 0.1)
				(type default)
			)
			(layer "F.Fab")
		)
		(fp_line
			(start -0.12065 0.3048)
			(end -0.67945 0.3048)
			(stroke
				(width 0.1)
				(type default)
			)
			(layer "F.Fab")
		)
		(fp_line
			(start 0.120396 0.3048)
			(end 0.120396 0.2794)
			(stroke
				(width 0.1)
				(type default)
			)
			(layer "F.Fab")
		)
		(fp_line
			(start 0.67945 0.3048)
			(end 0.120396 0.3048)
			(stroke
				(width 0.1)
				(type default)
			)
			(layer "F.Fab")
		)
		(fp_line
			(start -0.12065 0.2794)
			(end -0.12065 0.3048)
			(stroke
				(width 0.1)
				(type default)
			)
			(layer "F.Fab")
		)
		(fp_line
			(start 0.120396 0.2794)
			(end -0.12065 0.2794)
			(stroke
				(width 0.1)
				(type default)
			)
			(layer "F.Fab")
		)
		(fp_line
			(start -0.12065 -0.2794)
			(end 0.12065 -0.2794)
			(stroke
				(width 0.1)
				(type default)
			)
			(layer "F.Fab")
		)
		(fp_line
			(start 0.12065 -0.2794)
			(end 0.12065 -0.3048)
			(stroke
				(width 0.1)
				(type default)
			)
			(layer "F.Fab")
		)
		(fp_line
			(start 0.12065 -0.3048)
			(end 0.67945 -0.3048)
			(stroke
				(width 0.1)
				(type default)
			)
			(layer "F.Fab")
		)
		(fp_line
			(start 0.67945 -0.3048)
			(end 0.67945 0.3048)
			(stroke
				(width 0.1)
				(type default)
			)
			(layer "F.Fab")
		)
		(fp_line
			(start -0.67945 -0.305054)
			(end -0.12065 -0.305054)
			(stroke
				(width 0.1)
				(type default)
			)
			(layer "F.Fab")
		)
		(fp_line
			(start -0.12065 -0.305054)
			(end -0.12065 -0.2794)
			(stroke
				(width 0.1)
				(type default)
			)
			(layer "F.Fab")
		)
		(pad "1" smd circle
			(at -0.40005 0 270)
			(size 0 0)
			(layers "F.Cu" "F.Mask" "F.Paste")
			(net "SMB_GPU1_ALERT_R_N")
		)
		(pad "2" smd circle
			(at 0.40005 0 270)
			(size 0 0)
			(layers "F.Cu" "F.Mask" "F.Paste")
			(net "SMB_GPU1_ALERT_N")
		)
	)
	(footprint ""
		(layer "F.Cu")
		(at 327.471278 -121.291858)
		(property "Reference" "PU49"
			(at -1.010412 2.700528 0)
			(unlocked yes)
			(layer "F.SilkS")
			(effects
				(font
					(size 0.7874 0.5842)
					(thickness 0.1524)
				)
				(justify left)
			)
		)
		(property "Value" ""
			(at 0 0 0)
			(layer "F.Fab")
			(effects
				(font
					(size 1.27 1.27)
				)
			)
		)
		(duplicate_pad_numbers_are_jumpers no)
		(fp_line
			(start -1.943608 -1.549908)
			(end 1.943608 -1.549908)
			(stroke
				(width 0.1524)
				(type default)
			)
			(layer "F.SilkS")
		)
		(fp_line
			(start -1.943608 1.549908)
			(end -1.943608 -1.549908)
			(stroke
				(width 0.1524)
				(type default)
			)
			(layer "F.SilkS")
		)
		(fp_line
			(start 1.943608 -1.549908)
			(end 1.943608 1.549908)
			(stroke
				(width 0.1524)
				(type default)
			)
			(layer "F.SilkS")
		)
		(fp_line
			(start 1.943608 1.549908)
			(end -1.943608 1.549908)
			(stroke
				(width 0.1524)
				(type default)
			)
			(layer "F.SilkS")
		)
		(fp_poly
			(pts
				(xy -2.019808 -1.549908) (xy -1.257808 -1.549908) (xy -1.257808 -1.880108) (xy -2.019808 -1.880108)
			)
			(stroke
				(width 0)
				(type default)
			)
			(fill yes)
			(layer "F.SilkS")
		)
		(fp_line
			(start -1.549908 -1.549908)
			(end 1.549908 -1.549908)
			(stroke
				(width 0.1)
				(type default)
			)
			(layer "F.Fab")
		)
		(fp_line
			(start -1.549908 1.549908)
			(end -1.549908 -1.549908)
			(stroke
				(width 0.1)
				(type default)
			)
			(layer "F.Fab")
		)
		(fp_line
			(start 1.549908 -1.549908)
			(end 1.549908 1.549908)
			(stroke
				(width 0.1)
				(type default)
			)
			(layer "F.Fab")
		)
		(fp_line
			(start 1.549908 1.549908)
			(end -1.549908 1.549908)
			(stroke
				(width 0.1)
				(type default)
			)
			(layer "F.Fab")
		)
		(fp_poly
			(pts
				(xy -2.019808 -1.549908) (xy -1.257808 -1.549908) (xy -1.257808 -1.880108) (xy -2.019808 -1.880108)
			)
			(stroke
				(width 0)
				(type default)
			)
			(fill yes)
			(layer "F.Fab")
		)
		(pad "1" smd rect
			(at -1.500124 -1.249934 270)
			(size 0.2794 0.6096)
			(layers "F.Cu" "F.Mask" "F.Paste")
			(net "P3V3_NIC5")
		)
		(pad "2" smd rect
			(at -1.500124 -0.750062 270)
			(size 0.2794 0.6096)
			(layers "F.Cu" "F.Mask" "F.Paste")
			(net "P3V3_NIC5")
		)
		(pad "3" smd rect
			(at -1.500124 -0.249936 270)
			(size 0.2794 0.6096)
			(layers "F.Cu" "F.Mask" "F.Paste")
			(net "P3V3_NIC5")
		)
		(pad "4" smd rect
			(at -1.500124 0.249936 270)
			(size 0.2794 0.6096)
			(layers "F.Cu" "F.Mask" "F.Paste")
			(net "P3V3_NIC5")
		)
		(pad "5" smd rect
			(at -1.500124 0.750062 270)
			(size 0.2794 0.6096)
			(layers "F.Cu" "F.Mask" "F.Paste")
			(net "P3V3_NIC5")
		)
		(pad "6" smd rect
			(at -1.500124 1.249934 270)
			(size 0.2794 0.6096)
			(layers "F.Cu" "F.Mask" "F.Paste")
			(net "GND")
		)
		(pad "7" smd rect
			(at 1.500124 1.249934 270)
			(size 0.2794 0.6096)
			(layers "F.Cu" "F.Mask" "F.Paste")
			(net "P3V3_NIC5_SS")
		)
		(pad "8" smd rect
			(at 1.500124 0.750062 270)
			(size 0.2794 0.6096)
			(layers "F.Cu" "F.Mask" "F.Paste")
			(net "PWRGD_P3V3_NIC5")
		)
		(pad "9" smd rect
			(at 1.500124 0.249936 270)
			(size 0.2794 0.6096)
			(layers "F.Cu" "F.Mask" "F.Paste")
			(net "P3V3_NIC5_OCP")
		)
		(pad "10" smd rect
			(at 1.500124 -0.249936 270)
			(size 0.2794 0.6096)
			(layers "F.Cu" "F.Mask" "F.Paste")
			(net "P5V_AUX")
		)
		(pad "11" smd rect
			(at 1.500124 -0.750062 270)
			(size 0.2794 0.6096)
			(layers "F.Cu" "F.Mask" "F.Paste")
			(net "HP_NIC5_EN")
		)
		(pad "12" smd rect
			(at 1.500124 -1.249934 270)
			(size 0.2794 0.6096)
			(layers "F.Cu" "F.Mask" "F.Paste")
			(net "P3V3_AUX")
		)
		(pad "13" smd rect
			(at 0 0)
			(size 1.9812 2.7178)
			(layers "F.Cu" "F.Mask" "F.Paste")
			(net "P3V3_AUX")
		)
		(zone
			(layer "F.Cu")
			(hatch none 0.5)
			(connect_pads
				(clearance 0)
			)
			(min_thickness 0.25)
			(keepout
				(tracks not_allowed)
				(vias allowed)
				(pads allowed)
				(copperpour not_allowed)
				(footprints allowed)
			)
			(placement
				(enabled no)
				(sheetname "")
			)
			(fill
				(thermal_gap 0.5)
				(thermal_bridge_width 0.5)
				(island_removal_mode 0)
			)
			(polygon
				(pts
					(xy 328.614278 -122.841258) (xy 328.614278 -122.714258) (xy 328.614278 -119.742458) (xy 328.614278 -119.74195)
					(xy 326.328278 -119.74195) (xy 326.328278 -119.742458) (xy 326.328278 -119.869458) (xy 326.328278 -121.291858)
					(xy 326.429878 -121.291858) (xy 326.429878 -119.869458) (xy 328.512678 -119.869458) (xy 328.512678 -122.714258)
					(xy 326.429878 -122.714258) (xy 326.429878 -121.317258) (xy 326.328278 -121.317258) (xy 326.328278 -122.714258)
					(xy 326.328278 -122.841258) (xy 326.328278 -122.841766) (xy 328.614278 -122.841766)
				)
			)
		)
	)
	(footprint ""
		(layer "F.Cu")
		(at 128.295908 -343.952322 90)
		(property "Reference" "C371"
			(at 0 0 90)
			(layer "F.SilkS")
			(hide yes)
			(effects
				(font
					(size 1.27 1.27)
				)
			)
		)
		(property "Value" ""
			(at 0 0 90)
			(layer "F.Fab")
			(effects
				(font
					(size 1.27 1.27)
				)
			)
		)
		(duplicate_pad_numbers_are_jumpers no)
		(fp_line
			(start 0.299974 -0.150114)
			(end 0.299974 0.150114)
			(stroke
				(width 0.1)
				(type default)
			)
			(layer "F.Fab")
		)
		(fp_line
			(start -0.299974 -0.150114)
			(end 0.299974 -0.150114)
			(stroke
				(width 0.1)
				(type default)
			)
			(layer "F.Fab")
		)
		(fp_line
			(start 0.299974 0.150114)
			(end -0.299974 0.150114)
			(stroke
				(width 0.1)
				(type default)
			)
			(layer "F.Fab")
		)
		(fp_line
			(start -0.299974 0.150114)
			(end -0.299974 -0.150114)
			(stroke
				(width 0.1)
				(type default)
			)
			(layer "F.Fab")
		)
		(pad "1" smd rect
			(at -0.2667 0 90)
			(size 0.3048 0.381)
			(layers "F.Cu" "F.Mask" "F.Paste")
			(net "P5E_PEX1_STN6_TX_DN<96>")
		)
		(pad "2" smd rect
			(at 0.2667 0 90)
			(size 0.3048 0.381)
			(layers "F.Cu" "F.Mask" "F.Paste")
			(net "P5E_PEX1_STN6_TX_C_DN<96>")
		)
	)
	(footprint ""
		(layer "F.Cu")
		(at 207.98409 -289.230816 90)
		(property "Reference" "R3937"
			(at 0 0 90)
			(layer "F.SilkS")
			(hide yes)
			(effects
				(font
					(size 1.27 1.27)
				)
			)
		)
		(property "Value" ""
			(at 0 0 90)
			(layer "F.Fab")
			(effects
				(font
					(size 1.27 1.27)
				)
			)
		)
		(duplicate_pad_numbers_are_jumpers no)
		(fp_line
			(start 0.7874 -0.4064)
			(end 0.7874 0.4064)
			(stroke
				(width 0.1524)
				(type default)
			)
			(layer "F.SilkS")
		)
		(fp_line
			(start -0.7874 -0.4064)
			(end 0.7874 -0.4064)
			(stroke
				(width 0.1524)
				(type default)
			)
			(layer "F.SilkS")
		)
		(fp_line
			(start 0.7874 0.4064)
			(end -0.7874 0.4064)
			(stroke
				(width 0.1524)
				(type default)
			)
			(layer "F.SilkS")
		)
		(fp_line
			(start -0.7874 0.4064)
			(end -0.7874 -0.4064)
			(stroke
				(width 0.1524)
				(type default)
			)
			(layer "F.SilkS")
		)
		(fp_line
			(start -0.12065 -0.305054)
			(end -0.12065 -0.2794)
			(stroke
				(width 0.1)
				(type default)
			)
			(layer "F.Fab")
		)
		(fp_line
			(start -0.67945 -0.305054)
			(end -0.12065 -0.305054)
			(stroke
				(width 0.1)
				(type default)
			)
			(layer "F.Fab")
		)
		(fp_line
			(start 0.67945 -0.3048)
			(end 0.67945 0.3048)
			(stroke
				(width 0.1)
				(type default)
			)
			(layer "F.Fab")
		)
		(fp_line
			(start 0.12065 -0.3048)
			(end 0.67945 -0.3048)
			(stroke
				(width 0.1)
				(type default)
			)
			(layer "F.Fab")
		)
		(fp_line
			(start 0.12065 -0.2794)
			(end 0.12065 -0.3048)
			(stroke
				(width 0.1)
				(type default)
			)
			(layer "F.Fab")
		)
		(fp_line
			(start -0.12065 -0.2794)
			(end 0.12065 -0.2794)
			(stroke
				(width 0.1)
				(type default)
			)
			(layer "F.Fab")
		)
		(fp_line
			(start 0.120396 0.2794)
			(end -0.12065 0.2794)
			(stroke
				(width 0.1)
				(type default)
			)
			(layer "F.Fab")
		)
		(fp_line
			(start -0.12065 0.2794)
			(end -0.12065 0.3048)
			(stroke
				(width 0.1)
				(type default)
			)
			(layer "F.Fab")
		)
		(fp_line
			(start 0.67945 0.3048)
			(end 0.120396 0.3048)
			(stroke
				(width 0.1)
				(type default)
			)
			(layer "F.Fab")
		)
		(fp_line
			(start 0.120396 0.3048)
			(end 0.120396 0.2794)
			(stroke
				(width 0.1)
				(type default)
			)
			(layer "F.Fab")
		)
		(fp_line
			(start -0.12065 0.3048)
			(end -0.67945 0.3048)
			(stroke
				(width 0.1)
				(type default)
			)
			(layer "F.Fab")
		)
		(fp_line
			(start -0.67945 0.3048)
			(end -0.67945 -0.305054)
			(stroke
				(width 0.1)
				(type default)
			)
			(layer "F.Fab")
		)
		(pad "1" smd circle
			(at -0.40005 0 90)
			(size 0 0)
			(layers "F.Cu" "F.Mask" "F.Paste")
			(net "SMB_PEX1_PCA9555_SCL")
		)
		(pad "2" smd circle
			(at 0.40005 0 90)
			(size 0 0)
			(layers "F.Cu" "F.Mask" "F.Paste")
			(net "SMB_PEX1_HOST_LS_SCL")
		)
	)
	(footprint ""
		(layer "F.Cu")
		(at 366.092486 -29.139642 180)
		(property "Reference" "C704"
			(at 0 0 180)
			(layer "F.SilkS")
			(hide yes)
			(effects
				(font
					(size 1.27 1.27)
				)
			)
		)
		(property "Value" ""
			(at 0 0 180)
			(layer "F.Fab")
			(effects
				(font
					(size 1.27 1.27)
				)
			)
		)
		(duplicate_pad_numbers_are_jumpers no)
		(fp_line
			(start 0.299974 0.150114)
			(end -0.299974 0.150114)
			(stroke
				(width 0.1)
				(type default)
			)
			(layer "F.Fab")
		)
		(fp_line
			(start 0.299974 -0.150114)
			(end 0.299974 0.150114)
			(stroke
				(width 0.1)
				(type default)
			)
			(layer "F.Fab")
		)
		(fp_line
			(start -0.299974 0.150114)
			(end -0.299974 -0.150114)
			(stroke
				(width 0.1)
				(type default)
			)
			(layer "F.Fab")
		)
		(fp_line
			(start -0.299974 -0.150114)
			(end 0.299974 -0.150114)
			(stroke
				(width 0.1)
				(type default)
			)
			(layer "F.Fab")
		)
		(pad "1" smd rect
			(at -0.2667 0 180)
			(size 0.3048 0.381)
			(layers "F.Cu" "F.Mask" "F.Paste")
			(net "P5E_PEX3_STN2_TX_DP<44>")
		)
		(pad "2" smd rect
			(at 0.2667 0 180)
			(size 0.3048 0.381)
			(layers "F.Cu" "F.Mask" "F.Paste")
			(net "P5E_PEX3_STN2_TX_C_DP<44>")
		)
	)
	(footprint ""
		(layer "F.Cu")
		(at 465.041488 -529.209762 180)
		(property "Reference" "J33_OTH"
			(at -3.2385 -1.402334 0)
			(unlocked yes)
			(layer "B.SilkS")
			(effects
				(font
					(size 0.7874 0.5842)
					(thickness 0.1524)
				)
				(justify mirror)
			)
		)
		(property "Value" ""
			(at 0 0 180)
			(layer "F.Fab")
			(effects
				(font
					(size 1.27 1.27)
				)
			)
		)
		(duplicate_pad_numbers_are_jumpers no)
		(pad "1" thru_hole circle
			(at 0 0 180)
			(size 0.4572 0.4572)
			(drill 0.2032)
			(layers "*.Cu" "*.Mask")
			(remove_unused_layers no)
			(net "Net_9103")
			(clearance 0.127)
			(thermal_gap 0.127)
			(padstack
				(mode front_inner_back)
				(layer "Inner"
					(shape circle)
					(size 0.4572 0.4572)
					(clearance 0.127)
				)
				(layer "B.Cu"
					(shape circle)
					(size 0.508 0.508)
					(clearance 0.1016)
				)
			)
		)
	)
	(footprint ""
		(layer "F.Cu")
		(at 237.332012 -257.975862 -90)
		(property "Reference" "R6531"
			(at 0 0 270)
			(layer "F.SilkS")
			(hide yes)
			(effects
				(font
					(size 1.27 1.27)
				)
			)
		)
		(property "Value" ""
			(at 0 0 270)
			(layer "F.Fab")
			(effects
				(font
					(size 1.27 1.27)
				)
			)
		)
		(duplicate_pad_numbers_are_jumpers no)
		(fp_line
			(start -0.7874 0.4064)
			(end -0.7874 -0.4064)
			(stroke
				(width 0.1524)
				(type default)
			)
			(layer "F.SilkS")
		)
		(fp_line
			(start 0.7874 0.4064)
			(end -0.7874 0.4064)
			(stroke
				(width 0.1524)
				(type default)
			)
			(layer "F.SilkS")
		)
		(fp_line
			(start -0.7874 -0.4064)
			(end 0.7874 -0.4064)
			(stroke
				(width 0.1524)
				(type default)
			)
			(layer "F.SilkS")
		)
		(fp_line
			(start 0.7874 -0.4064)
			(end 0.7874 0.4064)
			(stroke
				(width 0.1524)
				(type default)
			)
			(layer "F.SilkS")
		)
		(fp_line
			(start -0.67945 0.3048)
			(end -0.67945 -0.305054)
			(stroke
				(width 0.1)
				(type default)
			)
			(layer "F.Fab")
		)
		(fp_line
			(start -0.12065 0.3048)
			(end -0.67945 0.3048)
			(stroke
				(width 0.1)
				(type default)
			)
			(layer "F.Fab")
		)
		(fp_line
			(start 0.120396 0.3048)
			(end 0.120396 0.2794)
			(stroke
				(width 0.1)
				(type default)
			)
			(layer "F.Fab")
		)
		(fp_line
			(start 0.67945 0.3048)
			(end 0.120396 0.3048)
			(stroke
				(width 0.1)
				(type default)
			)
			(layer "F.Fab")
		)
		(fp_line
			(start -0.12065 0.2794)
			(end -0.12065 0.3048)
			(stroke
				(width 0.1)
				(type default)
			)
			(layer "F.Fab")
		)
		(fp_line
			(start 0.120396 0.2794)
			(end -0.12065 0.2794)
			(stroke
				(width 0.1)
				(type default)
			)
			(layer "F.Fab")
		)
		(fp_line
			(start -0.12065 -0.2794)
			(end 0.12065 -0.2794)
			(stroke
				(width 0.1)
				(type default)
			)
			(layer "F.Fab")
		)
		(fp_line
			(start 0.12065 -0.2794)
			(end 0.12065 -0.3048)
			(stroke
				(width 0.1)
				(type default)
			)
			(layer "F.Fab")
		)
		(fp_line
			(start 0.12065 -0.3048)
			(end 0.67945 -0.3048)
			(stroke
				(width 0.1)
				(type default)
			)
			(layer "F.Fab")
		)
		(fp_line
			(start 0.67945 -0.3048)
			(end 0.67945 0.3048)
			(stroke
				(width 0.1)
				(type default)
			)
			(layer "F.Fab")
		)
		(fp_line
			(start -0.67945 -0.305054)
			(end -0.12065 -0.305054)
			(stroke
				(width 0.1)
				(type default)
			)
			(layer "F.Fab")
		)
		(fp_line
			(start -0.12065 -0.305054)
			(end -0.12065 -0.2794)
			(stroke
				(width 0.1)
				(type default)
			)
			(layer "F.Fab")
		)
		(pad "1" smd circle
			(at -0.40005 0 270)
			(size 0 0)
			(layers "F.Cu" "F.Mask" "F.Paste")
			(net "P1V25_SERDES_VDDPLL_PEX2")
		)
		(pad "2" smd circle
			(at 0.40005 0 270)
			(size 0 0)
			(layers "F.Cu" "F.Mask" "F.Paste")
			(net "P1V25_SERDES_VDDPLL_PEX2_C8")
		)
	)
	(footprint ""
		(layer "F.Cu")
		(at 147.394168 -34.248852)
		(property "Reference" "R5664"
			(at 0 0 0)
			(layer "F.SilkS")
			(hide yes)
			(effects
				(font
					(size 1.27 1.27)
				)
			)
		)
		(property "Value" ""
			(at 0 0 0)
			(layer "F.Fab")
			(effects
				(font
					(size 1.27 1.27)
				)
			)
		)
		(duplicate_pad_numbers_are_jumpers no)
		(fp_line
			(start -0.7874 -0.4064)
			(end 0.7874 -0.4064)
			(stroke
				(width 0.1524)
				(type default)
			)
			(layer "F.SilkS")
		)
		(fp_line
			(start -0.7874 0.4064)
			(end -0.7874 -0.4064)
			(stroke
				(width 0.1524)
				(type default)
			)
			(layer "F.SilkS")
		)
		(fp_line
			(start 0.7874 -0.4064)
			(end 0.7874 0.4064)
			(stroke
				(width 0.1524)
				(type default)
			)
			(layer "F.SilkS")
		)
		(fp_line
			(start 0.7874 0.4064)
			(end -0.7874 0.4064)
			(stroke
				(width 0.1524)
				(type default)
			)
			(layer "F.SilkS")
		)
		(fp_line
			(start -0.67945 -0.305054)
			(end -0.12065 -0.305054)
			(stroke
				(width 0.1)
				(type default)
			)
			(layer "F.Fab")
		)
		(fp_line
			(start -0.67945 0.3048)
			(end -0.67945 -0.305054)
			(stroke
				(width 0.1)
				(type default)
			)
			(layer "F.Fab")
		)
		(fp_line
			(start -0.12065 -0.305054)
			(end -0.12065 -0.2794)
			(stroke
				(width 0.1)
				(type default)
			)
			(layer "F.Fab")
		)
		(fp_line
			(start -0.12065 -0.2794)
			(end 0.12065 -0.2794)
			(stroke
				(width 0.1)
				(type default)
			)
			(layer "F.Fab")
		)
		(fp_line
			(start -0.12065 0.2794)
			(end -0.12065 0.3048)
			(stroke
				(width 0.1)
				(type default)
			)
			(layer "F.Fab")
		)
		(fp_line
			(start -0.12065 0.3048)
			(end -0.67945 0.3048)
			(stroke
				(width 0.1)
				(type default)
			)
			(layer "F.Fab")
		)
		(fp_line
			(start 0.120396 0.2794)
			(end -0.12065 0.2794)
			(stroke
				(width 0.1)
				(type default)
			)
			(layer "F.Fab")
		)
		(fp_line
			(start 0.120396 0.3048)
			(end 0.120396 0.2794)
			(stroke
				(width 0.1)
				(type default)
			)
			(layer "F.Fab")
		)
		(fp_line
			(start 0.12065 -0.3048)
			(end 0.67945 -0.3048)
			(stroke
				(width 0.1)
				(type default)
			)
			(layer "F.Fab")
		)
		(fp_line
			(start 0.12065 -0.2794)
			(end 0.12065 -0.3048)
			(stroke
				(width 0.1)
				(type default)
			)
			(layer "F.Fab")
		)
		(fp_line
			(start 0.67945 -0.3048)
			(end 0.67945 0.3048)
			(stroke
				(width 0.1)
				(type default)
			)
			(layer "F.Fab")
		)
		(fp_line
			(start 0.67945 0.3048)
			(end 0.120396 0.3048)
			(stroke
				(width 0.1)
				(type default)
			)
			(layer "F.Fab")
		)
		(pad "1" smd circle
			(at -0.40005 0)
			(size 0 0)
			(layers "F.Cu" "F.Mask" "F.Paste")
			(net "RST_SMB_SSD5_ISO_N")
		)
		(pad "2" smd circle
			(at 0.40005 0)
			(size 0 0)
			(layers "F.Cu" "F.Mask" "F.Paste")
			(net "P3V3_SSD5")
		)
	)
	(footprint ""
		(layer "F.Cu")
		(at 13.439394 -308.282086)
		(property "Reference" "R842"
			(at 0 0 0)
			(layer "F.SilkS")
			(hide yes)
			(effects
				(font
					(size 1.27 1.27)
				)
			)
		)
		(property "Value" ""
			(at 0 0 0)
			(layer "F.Fab")
			(effects
				(font
					(size 1.27 1.27)
				)
			)
		)
		(duplicate_pad_numbers_are_jumpers no)
		(fp_line
			(start -0.7874 -0.4064)
			(end 0.7874 -0.4064)
			(stroke
				(width 0.1524)
				(type default)
			)
			(layer "F.SilkS")
		)
		(fp_line
			(start -0.7874 0.4064)
			(end -0.7874 -0.4064)
			(stroke
				(width 0.1524)
				(type default)
			)
			(layer "F.SilkS")
		)
		(fp_line
			(start 0.7874 -0.4064)
			(end 0.7874 0.4064)
			(stroke
				(width 0.1524)
				(type default)
			)
			(layer "F.SilkS")
		)
		(fp_line
			(start 0.7874 0.4064)
			(end -0.7874 0.4064)
			(stroke
				(width 0.1524)
				(type default)
			)
			(layer "F.SilkS")
		)
		(fp_line
			(start -0.67945 -0.305054)
			(end -0.12065 -0.305054)
			(stroke
				(width 0.1)
				(type default)
			)
			(layer "F.Fab")
		)
		(fp_line
			(start -0.67945 0.3048)
			(end -0.67945 -0.305054)
			(stroke
				(width 0.1)
				(type default)
			)
			(layer "F.Fab")
		)
		(fp_line
			(start -0.12065 -0.305054)
			(end -0.12065 -0.2794)
			(stroke
				(width 0.1)
				(type default)
			)
			(layer "F.Fab")
		)
		(fp_line
			(start -0.12065 -0.2794)
			(end 0.12065 -0.2794)
			(stroke
				(width 0.1)
				(type default)
			)
			(layer "F.Fab")
		)
		(fp_line
			(start -0.12065 0.2794)
			(end -0.12065 0.3048)
			(stroke
				(width 0.1)
				(type default)
			)
			(layer "F.Fab")
		)
		(fp_line
			(start -0.12065 0.3048)
			(end -0.67945 0.3048)
			(stroke
				(width 0.1)
				(type default)
			)
			(layer "F.Fab")
		)
		(fp_line
			(start 0.120396 0.2794)
			(end -0.12065 0.2794)
			(stroke
				(width 0.1)
				(type default)
			)
			(layer "F.Fab")
		)
		(fp_line
			(start 0.120396 0.3048)
			(end 0.120396 0.2794)
			(stroke
				(width 0.1)
				(type default)
			)
			(layer "F.Fab")
		)
		(fp_line
			(start 0.12065 -0.3048)
			(end 0.67945 -0.3048)
			(stroke
				(width 0.1)
				(type default)
			)
			(layer "F.Fab")
		)
		(fp_line
			(start 0.12065 -0.2794)
			(end 0.12065 -0.3048)
			(stroke
				(width 0.1)
				(type default)
			)
			(layer "F.Fab")
		)
		(fp_line
			(start 0.67945 -0.3048)
			(end 0.67945 0.3048)
			(stroke
				(width 0.1)
				(type default)
			)
			(layer "F.Fab")
		)
		(fp_line
			(start 0.67945 0.3048)
			(end 0.120396 0.3048)
			(stroke
				(width 0.1)
				(type default)
			)
			(layer "F.Fab")
		)
		(pad "1" smd circle
			(at -0.40005 0)
			(size 0 0)
			(layers "F.Cu" "F.Mask" "F.Paste")
			(net "P1V25_PEX0_EN")
		)
		(pad "2" smd circle
			(at 0.40005 0)
			(size 0 0)
			(layers "F.Cu" "F.Mask" "F.Paste")
			(net "PWR_EN_PEX_R")
		)
	)
	(footprint ""
		(layer "F.Cu")
		(at 387.26491 -26.785062 180)
		(property "Reference" "J43"
			(at 4.476496 -11.077956 90)
			(unlocked yes)
			(layer "F.SilkS")
			(effects
				(font
					(size 0.7874 0.5842)
					(thickness 0.1524)
				)
			)
		)
		(property "Value" ""
			(at 0 0 180)
			(layer "F.Fab")
			(effects
				(font
					(size 1.27 1.27)
				)
			)
		)
		(duplicate_pad_numbers_are_jumpers no)
		(fp_line
			(start 3.150108 12.115038)
			(end 1.529334 12.115038)
			(stroke
				(width 0.1524)
				(type default)
			)
			(layer "F.SilkS")
		)
		(fp_line
			(start 3.074924 12.014962)
			(end 1.632204 12.014962)
			(stroke
				(width 0.1524)
				(type default)
			)
			(layer "F.SilkS")
		)
		(fp_line
			(start 1.632204 -12.014962)
			(end 3.074924 -12.014962)
			(stroke
				(width 0.1524)
				(type default)
			)
			(layer "F.SilkS")
		)
		(fp_line
			(start 1.529334 -12.115038)
			(end 3.150108 -12.115038)
			(stroke
				(width 0.1524)
				(type default)
			)
			(layer "F.SilkS")
		)
		(fp_line
			(start -1.529334 12.115038)
			(end -3.150108 12.115038)
			(stroke
				(width 0.1524)
				(type default)
			)
			(layer "F.SilkS")
		)
		(fp_line
			(start -1.632204 12.014962)
			(end -3.074924 12.014962)
			(stroke
				(width 0.1524)
				(type default)
			)
			(layer "F.SilkS")
		)
		(fp_line
			(start -3.074924 -12.014962)
			(end -1.632204 -12.014962)
			(stroke
				(width 0.1524)
				(type default)
			)
			(layer "F.SilkS")
		)
		(fp_line
			(start -3.150108 -12.115038)
			(end -1.529334 -12.115038)
			(stroke
				(width 0.1524)
				(type default)
			)
			(layer "F.SilkS")
		)
		(fp_poly
			(pts
				(xy 3.27279 -8.645398) (xy 3.695192 -9.913112) (xy 4.54025 -9.068054)
			)
			(stroke
				(width 0)
				(type default)
			)
			(fill yes)
			(layer "F.SilkS")
		)
		(fp_line
			(start 3.074924 12.014962)
			(end -3.074924 12.014962)
			(stroke
				(width 0.1)
				(type default)
			)
			(layer "F.Fab")
		)
		(fp_line
			(start 3.074924 -12.014962)
			(end 3.074924 12.014962)
			(stroke
				(width 0.1)
				(type default)
			)
			(layer "F.Fab")
		)
		(fp_line
			(start -3.074924 12.014962)
			(end -3.074924 -12.014962)
			(stroke
				(width 0.1)
				(type default)
			)
			(layer "F.Fab")
		)
		(fp_line
			(start -3.074924 -12.014962)
			(end 3.074924 -12.014962)
			(stroke
				(width 0.1)
				(type default)
			)
			(layer "F.Fab")
		)
		(fp_poly
			(pts
				(xy 3.348736 -7.994904) (xy 4.543806 -8.592566) (xy 4.543806 -7.397496)
			)
			(stroke
				(width 0)
				(type default)
			)
			(fill yes)
			(layer "F.Fab")
		)
		(pad "" np_thru_hole circle
			(at -1.75006 -9.815068 90)
			(size 1.1176 1.1176)
			(drill 1.1176)
			(layers "*.Cu" "*.Mask")
			(clearance 0.381)
			(thermal_gap 0.381)
		)
		(pad "" np_thru_hole circle
			(at 0 9.815068 90)
			(size 1.1176 1.1176)
			(drill 1.1176)
			(layers "*.Cu" "*.Mask")
			(clearance 0.381)
			(thermal_gap 0.381)
		)
		(pad "A1" smd rect
			(at 2.29997 -7.994904 90)
			(size 0.381 1.27)
			(layers "F.Cu" "F.Mask" "F.Paste")
			(net "GND")
		)
		(pad "A2" smd rect
			(at 2.29997 -7.394956 90)
			(size 0.381 1.27)
			(layers "F.Cu" "F.Mask" "F.Paste")
			(net "GND")
		)
		(pad "A3" smd rect
			(at 2.29997 -6.795008 90)
			(size 0.381 1.27)
			(layers "F.Cu" "F.Mask" "F.Paste")
			(net "GND")
		)
		(pad "A4" smd rect
			(at 2.29997 -6.19506 90)
			(size 0.381 1.27)
			(layers "F.Cu" "F.Mask" "F.Paste")
			(net "GND")
		)
		(pad "A5" smd rect
			(at 2.29997 -5.595112 90)
			(size 0.381 1.27)
			(layers "F.Cu" "F.Mask" "F.Paste")
			(net "GND")
		)
		(pad "A6" smd rect
			(at 2.29997 -4.99491 90)
			(size 0.381 1.27)
			(layers "F.Cu" "F.Mask" "F.Paste")
			(net "GND")
		)
		(pad "A7" smd rect
			(at 2.29997 -4.394962 90)
			(size 0.381 1.27)
			(layers "F.Cu" "F.Mask" "F.Paste")
			(net "SMB_ISO_SSD13_R_SCL")
		)
		(pad "A8" smd rect
			(at 2.29997 -3.795014 90)
			(size 0.381 1.27)
			(layers "F.Cu" "F.Mask" "F.Paste")
			(net "SMB_ISO_SSD13_R_SDA")
		)
		(pad "A9" smd rect
			(at 2.29997 -3.195066 90)
			(size 0.381 1.27)
			(layers "F.Cu" "F.Mask" "F.Paste")
			(net "RST_SMB_SSD13_ISO_R_N")
		)
		(pad "A10" smd rect
			(at 2.29997 -2.595118 90)
			(size 0.381 1.27)
			(layers "F.Cu" "F.Mask" "F.Paste")
			(net "SSD13_LED_ISO_R_N")
		)
		(pad "A11" smd rect
			(at 2.29997 -1.994916 90)
			(size 0.381 1.27)
			(layers "F.Cu" "F.Mask" "F.Paste")
			(net "PU_CLKREQ13")
		)
		(pad "A12" smd rect
			(at 2.29997 -1.394968 90)
			(size 0.381 1.27)
			(layers "F.Cu" "F.Mask" "F.Paste")
			(net "PRSNT_SSD13_N")
		)
		(pad "A13" smd rect
			(at 2.29997 -0.79502 90)
			(size 0.381 1.27)
			(layers "F.Cu" "F.Mask" "F.Paste")
			(net "GND")
		)
		(pad "A14" smd rect
			(at 2.29997 -0.195072 90)
			(size 0.381 1.27)
			(layers "F.Cu" "F.Mask" "F.Paste")
			(net "Net_8471")
		)
		(pad "A15" smd rect
			(at 2.29997 0.404876 90)
			(size 0.381 1.27)
			(layers "F.Cu" "F.Mask" "F.Paste")
			(net "Net_8470")
		)
		(pad "A16" smd rect
			(at 2.29997 1.005078 90)
			(size 0.381 1.27)
			(layers "F.Cu" "F.Mask" "F.Paste")
			(net "GND")
		)
		(pad "A17" smd rect
			(at 2.29997 1.605026 90)
			(size 0.381 1.27)
			(layers "F.Cu" "F.Mask" "F.Paste")
			(net "P5E_PEX3_STN2_RX_DN<40>")
		)
		(pad "A18" smd rect
			(at 2.29997 2.204974 90)
			(size 0.381 1.27)
			(layers "F.Cu" "F.Mask" "F.Paste")
			(net "P5E_PEX3_STN2_RX_DP<40>")
		)
		(pad "A19" smd rect
			(at 2.29997 2.804922 90)
			(size 0.381 1.27)
			(layers "F.Cu" "F.Mask" "F.Paste")
			(net "GND")
		)
		(pad "A20" smd rect
			(at 2.29997 3.405124 90)
			(size 0.381 1.27)
			(layers "F.Cu" "F.Mask" "F.Paste")
			(net "P5E_PEX3_STN2_RX_DN<41>")
		)
		(pad "A21" smd rect
			(at 2.29997 4.005072 90)
			(size 0.381 1.27)
			(layers "F.Cu" "F.Mask" "F.Paste")
			(net "P5E_PEX3_STN2_RX_DP<41>")
		)
		(pad "A22" smd rect
			(at 2.29997 4.60502 90)
			(size 0.381 1.27)
			(layers "F.Cu" "F.Mask" "F.Paste")
			(net "GND")
		)
		(pad "A23" smd rect
			(at 2.29997 5.204968 90)
			(size 0.381 1.27)
			(layers "F.Cu" "F.Mask" "F.Paste")
			(net "P5E_PEX3_STN2_RX_DN<42>")
		)
		(pad "A24" smd rect
			(at 2.29997 5.804916 90)
			(size 0.381 1.27)
			(layers "F.Cu" "F.Mask" "F.Paste")
			(net "P5E_PEX3_STN2_RX_DP<42>")
		)
		(pad "A25" smd rect
			(at 2.29997 6.405118 90)
			(size 0.381 1.27)
			(layers "F.Cu" "F.Mask" "F.Paste")
			(net "GND")
		)
		(pad "A26" smd rect
			(at 2.29997 7.005066 90)
			(size 0.381 1.27)
			(layers "F.Cu" "F.Mask" "F.Paste")
			(net "P5E_PEX3_STN2_RX_DN<43>")
		)
		(pad "A27" smd rect
			(at 2.29997 7.605014 90)
			(size 0.381 1.27)
			(layers "F.Cu" "F.Mask" "F.Paste")
			(net "P5E_PEX3_STN2_RX_DP<43>")
		)
		(pad "A28" smd rect
			(at 2.29997 8.204962 90)
			(size 0.381 1.27)
			(layers "F.Cu" "F.Mask" "F.Paste")
			(net "GND")
		)
		(pad "B1" smd rect
			(at -2.29997 -7.994904 90)
			(size 0.381 1.27)
			(layers "F.Cu" "F.Mask" "F.Paste")
			(net "P12V_SSD13")
		)
		(pad "B2" smd rect
			(at -2.29997 -7.394956 90)
			(size 0.381 1.27)
			(layers "F.Cu" "F.Mask" "F.Paste")
			(net "P12V_SSD13")
		)
		(pad "B3" smd rect
			(at -2.29997 -6.795008 90)
			(size 0.381 1.27)
			(layers "F.Cu" "F.Mask" "F.Paste")
			(net "P12V_SSD13")
		)
		(pad "B4" smd rect
			(at -2.29997 -6.19506 90)
			(size 0.381 1.27)
			(layers "F.Cu" "F.Mask" "F.Paste")
			(net "P12V_SSD13")
		)
		(pad "B5" smd rect
			(at -2.29997 -5.595112 90)
			(size 0.381 1.27)
			(layers "F.Cu" "F.Mask" "F.Paste")
			(net "P12V_SSD13")
		)
		(pad "B6" smd rect
			(at -2.29997 -4.99491 90)
			(size 0.381 1.27)
			(layers "F.Cu" "F.Mask" "F.Paste")
			(net "P12V_SSD13")
		)
		(pad "B7" smd rect
			(at -2.29997 -4.394962 90)
			(size 0.381 1.27)
			(layers "F.Cu" "F.Mask" "F.Paste")
			(net "Net_8472")
		)
		(pad "B8" smd rect
			(at -2.29997 -3.795014 90)
			(size 0.381 1.27)
			(layers "F.Cu" "F.Mask" "F.Paste")
			(net "Net_8469")
		)
		(pad "B9" smd rect
			(at -2.29997 -3.195066 90)
			(size 0.381 1.27)
			(layers "F.Cu" "F.Mask" "F.Paste")
			(net "DUALPORT_N_SSD13")
		)
		(pad "B10" smd rect
			(at -2.29997 -2.595118 90)
			(size 0.381 1.27)
			(layers "F.Cu" "F.Mask" "F.Paste")
			(net "RST_SSD13_PERST_R_N")
		)
		(pad "B11" smd rect
			(at -2.29997 -1.994916 90)
			(size 0.381 1.27)
			(layers "F.Cu" "F.Mask" "F.Paste")
			(net "P3V3_SSD13")
		)
		(pad "B12" smd rect
			(at -2.29997 -1.394968 90)
			(size 0.381 1.27)
			(layers "F.Cu" "F.Mask" "F.Paste")
			(net "SSD13_PWRDIS_R")
		)
		(pad "B13" smd rect
			(at -2.29997 -0.79502 90)
			(size 0.381 1.27)
			(layers "F.Cu" "F.Mask" "F.Paste")
			(net "GND")
		)
		(pad "B14" smd rect
			(at -2.29997 -0.195072 90)
			(size 0.381 1.27)
			(layers "F.Cu" "F.Mask" "F.Paste")
			(net "CLK_100M_DB800ZL_SSD13_R_DN")
		)
		(pad "B15" smd rect
			(at -2.29997 0.404876 90)
			(size 0.381 1.27)
			(layers "F.Cu" "F.Mask" "F.Paste")
			(net "CLK_100M_DB800ZL_SSD13_R_DP")
		)
		(pad "B16" smd rect
			(at -2.29997 1.005078 90)
			(size 0.381 1.27)
			(layers "F.Cu" "F.Mask" "F.Paste")
			(net "GND")
		)
		(pad "B17" smd rect
			(at -2.29997 1.605026 90)
			(size 0.381 1.27)
			(layers "F.Cu" "F.Mask" "F.Paste")
			(net "P5E_PEX3_STN2_TX_C_DN<40>")
		)
		(pad "B18" smd rect
			(at -2.29997 2.204974 90)
			(size 0.381 1.27)
			(layers "F.Cu" "F.Mask" "F.Paste")
			(net "P5E_PEX3_STN2_TX_C_DP<40>")
		)
		(pad "B19" smd rect
			(at -2.29997 2.804922 90)
			(size 0.381 1.27)
			(layers "F.Cu" "F.Mask" "F.Paste")
			(net "GND")
		)
		(pad "B20" smd rect
			(at -2.29997 3.405124 90)
			(size 0.381 1.27)
			(layers "F.Cu" "F.Mask" "F.Paste")
			(net "P5E_PEX3_STN2_TX_C_DN<41>")
		)
		(pad "B21" smd rect
			(at -2.29997 4.005072 90)
			(size 0.381 1.27)
			(layers "F.Cu" "F.Mask" "F.Paste")
			(net "P5E_PEX3_STN2_TX_C_DP<41>")
		)
		(pad "B22" smd rect
			(at -2.29997 4.60502 90)
			(size 0.381 1.27)
			(layers "F.Cu" "F.Mask" "F.Paste")
			(net "GND")
		)
		(pad "B23" smd rect
			(at -2.29997 5.204968 90)
			(size 0.381 1.27)
			(layers "F.Cu" "F.Mask" "F.Paste")
			(net "P5E_PEX3_STN2_TX_C_DN<42>")
		)
		(pad "B24" smd rect
			(at -2.29997 5.804916 90)
			(size 0.381 1.27)
			(layers "F.Cu" "F.Mask" "F.Paste")
			(net "P5E_PEX3_STN2_TX_C_DP<42>")
		)
		(pad "B25" smd rect
			(at -2.29997 6.405118 90)
			(size 0.381 1.27)
			(layers "F.Cu" "F.Mask" "F.Paste")
			(net "GND")
		)
		(pad "B26" smd rect
			(at -2.29997 7.005066 90)
			(size 0.381 1.27)
			(layers "F.Cu" "F.Mask" "F.Paste")
			(net "P5E_PEX3_STN2_TX_C_DN<43>")
		)
		(pad "B27" smd rect
			(at -2.29997 7.605014 90)
			(size 0.381 1.27)
			(layers "F.Cu" "F.Mask" "F.Paste")
			(net "P5E_PEX3_STN2_TX_C_DP<43>")
		)
		(pad "B28" smd rect
			(at -2.29997 8.204962 90)
			(size 0.381 1.27)
			(layers "F.Cu" "F.Mask" "F.Paste")
			(net "GND")
		)
		(pad "G1" thru_hole oval
			(at 0 -11.364976 90)
			(size 1.6256 3.4798)
			(drill oval 1.1176 2.4638)
			(layers "*.Cu" "*.Mask")
			(remove_unused_layers no)
			(net "GND")
			(clearance 0.127)
			(thermal_gap 0.127)
		)
		(pad "G2" thru_hole oval
			(at 0 11.364976 90)
			(size 1.6256 3.4798)
			(drill oval 1.1176 2.4638)
			(layers "*.Cu" "*.Mask")
			(remove_unused_layers no)
			(net "GND")
			(clearance 0.127)
			(thermal_gap 0.127)
		)
		(zone
			(layer "F.Cu")
			(hatch none 0.5)
			(connect_pads
				(clearance 0)
			)
			(min_thickness 0.25)
			(keepout
				(tracks not_allowed)
				(vias allowed)
				(pads allowed)
				(copperpour not_allowed)
				(footprints allowed)
			)
			(placement
				(enabled no)
				(sheetname "")
			)
			(fill
				(thermal_gap 0.5)
				(thermal_bridge_width 0.5)
				(island_removal_mode 0)
			)
			(polygon
				(pts
					(xy 388.644892 -38.850062) (xy 385.894834 -38.850062) (xy 385.894834 -35.900106) (xy 388.644892 -35.900106)
				)
			)
		)
		(zone
			(layer "F.Cu")
			(hatch none 0.5)
			(connect_pads
				(clearance 0)
			)
			(min_thickness 0.25)
			(keepout
				(tracks not_allowed)
				(vias allowed)
				(pads allowed)
				(copperpour not_allowed)
				(footprints allowed)
			)
			(placement
				(enabled no)
				(sheetname "")
			)
			(fill
				(thermal_gap 0.5)
				(thermal_bridge_width 0.5)
				(island_removal_mode 0)
			)
			(polygon
				(pts
					(xy 389.714994 -17.670018) (xy 385.884928 -17.670018) (xy 385.884928 -14.720062) (xy 389.714994 -14.720062)
				)
			)
		)
		(zone
			(layers "F.Cu" "B.Cu" "In1.Cu" "In2.Cu" "In3.Cu" "In4.Cu" "In5.Cu" "In6.Cu"
				"In7.Cu" "In8.Cu" "In9.Cu" "In10.Cu" "In11.Cu" "In12.Cu" "In13.Cu" "In14.Cu"
				"In15.Cu" "In16.Cu"
			)
			(hatch none 0.5)
			(connect_pads
				(clearance 0)
			)
			(min_thickness 0.25)
			(keepout
				(tracks not_allowed)
				(vias allowed)
				(pads allowed)
				(copperpour not_allowed)
				(footprints allowed)
			)
			(placement
				(enabled no)
				(sheetname "")
			)
			(fill
				(thermal_gap 0.5)
				(thermal_bridge_width 0.5)
				(island_removal_mode 0)
			)
			(polygon
				(pts
					(arc
						(start 388.23011 -36.60013)
						(mid 386.29971 -36.60013)
						(end 388.23011 -36.60013)
					)
				)
			)
		)
		(zone
			(layers "F.Cu" "B.Cu" "In1.Cu" "In2.Cu" "In3.Cu" "In4.Cu" "In5.Cu" "In6.Cu"
				"In7.Cu" "In8.Cu" "In9.Cu" "In10.Cu" "In11.Cu" "In12.Cu" "In13.Cu" "In14.Cu"
				"In15.Cu" "In16.Cu"
			)
			(hatch none 0.5)
			(connect_pads
				(clearance 0)
			)
			(min_thickness 0.25)
			(keepout
				(tracks not_allowed)
				(vias allowed)
				(pads allowed)
				(copperpour not_allowed)
				(footprints allowed)
			)
			(placement
				(enabled no)
				(sheetname "")
			)
			(fill
				(thermal_gap 0.5)
				(thermal_bridge_width 0.5)
				(island_removal_mode 0)
			)
			(polygon
				(pts
					(arc
						(start 389.98017 -16.969994)
						(mid 388.04977 -16.969994)
						(end 389.98017 -16.969994)
					)
				)
			)
		)
	)
	(footprint ""
		(layer "F.Cu")
		(at 368.038634 -44.341542 90)
		(property "Reference" "C335"
			(at 0 0 90)
			(layer "F.SilkS")
			(hide yes)
			(effects
				(font
					(size 1.27 1.27)
				)
			)
		)
		(property "Value" ""
			(at 0 0 90)
			(layer "F.Fab")
			(effects
				(font
					(size 1.27 1.27)
				)
			)
		)
		(duplicate_pad_numbers_are_jumpers no)
		(fp_line
			(start 0.7874 -0.4064)
			(end 0.7874 0.4064)
			(stroke
				(width 0.1524)
				(type default)
			)
			(layer "F.SilkS")
		)
		(fp_line
			(start -0.7874 -0.4064)
			(end 0.7874 -0.4064)
			(stroke
				(width 0.1524)
				(type default)
			)
			(layer "F.SilkS")
		)
		(fp_line
			(start 0.7874 0.4064)
			(end -0.7874 0.4064)
			(stroke
				(width 0.1524)
				(type default)
			)
			(layer "F.SilkS")
		)
		(fp_line
			(start -0.7874 0.4064)
			(end -0.7874 -0.4064)
			(stroke
				(width 0.1524)
				(type default)
			)
			(layer "F.SilkS")
		)
		(fp_line
			(start -0.12065 -0.305054)
			(end -0.12065 -0.2794)
			(stroke
				(width 0.1)
				(type default)
			)
			(layer "F.Fab")
		)
		(fp_line
			(start -0.67945 -0.305054)
			(end -0.12065 -0.305054)
			(stroke
				(width 0.1)
				(type default)
			)
			(layer "F.Fab")
		)
		(fp_line
			(start 0.67945 -0.3048)
			(end 0.67945 0.3048)
			(stroke
				(width 0.1)
				(type default)
			)
			(layer "F.Fab")
		)
		(fp_line
			(start 0.12065 -0.3048)
			(end 0.67945 -0.3048)
			(stroke
				(width 0.1)
				(type default)
			)
			(layer "F.Fab")
		)
		(fp_line
			(start 0.12065 -0.2794)
			(end 0.12065 -0.3048)
			(stroke
				(width 0.1)
				(type default)
			)
			(layer "F.Fab")
		)
		(fp_line
			(start -0.12065 -0.2794)
			(end 0.12065 -0.2794)
			(stroke
				(width 0.1)
				(type default)
			)
			(layer "F.Fab")
		)
		(fp_line
			(start 0.120396 0.2794)
			(end -0.12065 0.2794)
			(stroke
				(width 0.1)
				(type default)
			)
			(layer "F.Fab")
		)
		(fp_line
			(start -0.12065 0.2794)
			(end -0.12065 0.3048)
			(stroke
				(width 0.1)
				(type default)
			)
			(layer "F.Fab")
		)
		(fp_line
			(start 0.67945 0.3048)
			(end 0.120396 0.3048)
			(stroke
				(width 0.1)
				(type default)
			)
			(layer "F.Fab")
		)
		(fp_line
			(start 0.120396 0.3048)
			(end 0.120396 0.2794)
			(stroke
				(width 0.1)
				(type default)
			)
			(layer "F.Fab")
		)
		(fp_line
			(start -0.12065 0.3048)
			(end -0.67945 0.3048)
			(stroke
				(width 0.1)
				(type default)
			)
			(layer "F.Fab")
		)
		(fp_line
			(start -0.67945 0.3048)
			(end -0.67945 -0.305054)
			(stroke
				(width 0.1)
				(type default)
			)
			(layer "F.Fab")
		)
		(pad "1" smd circle
			(at -0.40005 0 90)
			(size 0 0)
			(layers "F.Cu" "F.Mask" "F.Paste")
			(net "P12V_SSD12_VIN_P")
		)
		(pad "2" smd circle
			(at 0.40005 0 90)
			(size 0 0)
			(layers "F.Cu" "F.Mask" "F.Paste")
			(net "P12V_SSD12_VIN_N")
		)
	)
	(footprint ""
		(layer "F.Cu")
		(at 274.089622 -356.244906 90)
		(property "Reference" "C2347"
			(at 0 0 90)
			(layer "F.SilkS")
			(hide yes)
			(effects
				(font
					(size 1.27 1.27)
				)
			)
		)
		(property "Value" ""
			(at 0 0 90)
			(layer "F.Fab")
			(effects
				(font
					(size 1.27 1.27)
				)
			)
		)
		(duplicate_pad_numbers_are_jumpers no)
		(fp_line
			(start 0.299974 -0.150114)
			(end 0.299974 0.150114)
			(stroke
				(width 0.1)
				(type default)
			)
			(layer "F.Fab")
		)
		(fp_line
			(start -0.299974 -0.150114)
			(end 0.299974 -0.150114)
			(stroke
				(width 0.1)
				(type default)
			)
			(layer "F.Fab")
		)
		(fp_line
			(start 0.299974 0.150114)
			(end -0.299974 0.150114)
			(stroke
				(width 0.1)
				(type default)
			)
			(layer "F.Fab")
		)
		(fp_line
			(start -0.299974 0.150114)
			(end -0.299974 -0.150114)
			(stroke
				(width 0.1)
				(type default)
			)
			(layer "F.Fab")
		)
		(pad "1" smd rect
			(at -0.2667 0 90)
			(size 0.3048 0.381)
			(layers "F.Cu" "F.Mask" "F.Paste")
			(net "P5E_PEX2_STN4_TX_DP<76>")
		)
		(pad "2" smd rect
			(at 0.2667 0 90)
			(size 0.3048 0.381)
			(layers "F.Cu" "F.Mask" "F.Paste")
			(net "P5E_PEX2_STN4_TX_C_DP<76>")
		)
	)
	(footprint ""
		(layer "F.Cu")
		(at 492.65967 -522.577822 90)
		(property "Reference" "VR_HS1"
			(at -0.3937 -0.588518 90)
			(unlocked yes)
			(layer "F.SilkS")
			(effects
				(font
					(size 0.254 0.127)
					(thickness 0.000001)
				)
				(justify left)
			)
		)
		(property "Value" ""
			(at 0 0 90)
			(layer "F.Fab")
			(effects
				(font
					(size 1.27 1.27)
				)
			)
		)
		(duplicate_pad_numbers_are_jumpers no)
		(pad "1" smd circle
			(at 0 0 90)
			(size 0.762 0.762)
			(layers "F.Cu" "F.Mask" "F.Paste")
			(net "Net_9197")
		)
	)
	(footprint ""
		(layer "F.Cu")
		(at 224.851976 -371.058186)
		(property "Reference" "PC11"
			(at 0 0 0)
			(layer "F.SilkS")
			(hide yes)
			(effects
				(font
					(size 1.27 1.27)
				)
			)
		)
		(property "Value" ""
			(at 0 0 0)
			(layer "F.Fab")
			(effects
				(font
					(size 1.27 1.27)
				)
			)
		)
		(duplicate_pad_numbers_are_jumpers no)
		(fp_line
			(start -0.7874 0.4064)
			(end -0.7874 -0.4064)
			(stroke
				(width 0.1524)
				(type default)
			)
			(layer "F.SilkS")
		)
		(fp_line
			(start 0.7874 -0.4064)
			(end 0.7874 0.4064)
			(stroke
				(width 0.1524)
				(type default)
			)
			(layer "F.SilkS")
		)
		(fp_line
			(start 0.7874 0.4064)
			(end -0.7874 0.4064)
			(stroke
				(width 0.1524)
				(type default)
			)
			(layer "F.SilkS")
		)
		(fp_line
			(start -0.67945 -0.305054)
			(end -0.12065 -0.305054)
			(stroke
				(width 0.1)
				(type default)
			)
			(layer "F.Fab")
		)
		(fp_line
			(start -0.67945 0.3048)
			(end -0.67945 -0.305054)
			(stroke
				(width 0.1)
				(type default)
			)
			(layer "F.Fab")
		)
		(fp_line
			(start -0.12065 -0.305054)
			(end -0.12065 -0.2794)
			(stroke
				(width 0.1)
				(type default)
			)
			(layer "F.Fab")
		)
		(fp_line
			(start -0.12065 -0.2794)
			(end 0.12065 -0.2794)
			(stroke
				(width 0.1)
				(type default)
			)
			(layer "F.Fab")
		)
		(fp_line
			(start -0.12065 0.2794)
			(end -0.12065 0.3048)
			(stroke
				(width 0.1)
				(type default)
			)
			(layer "F.Fab")
		)
		(fp_line
			(start -0.12065 0.3048)
			(end -0.67945 0.3048)
			(stroke
				(width 0.1)
				(type default)
			)
			(layer "F.Fab")
		)
		(fp_line
			(start 0.120396 0.2794)
			(end -0.12065 0.2794)
			(stroke
				(width 0.1)
				(type default)
			)
			(layer "F.Fab")
		)
		(fp_line
			(start 0.120396 0.3048)
			(end 0.120396 0.2794)
			(stroke
				(width 0.1)
				(type default)
			)
			(layer "F.Fab")
		)
		(fp_line
			(start 0.12065 -0.3048)
			(end 0.67945 -0.3048)
			(stroke
				(width 0.1)
				(type default)
			)
			(layer "F.Fab")
		)
		(fp_line
			(start 0.12065 -0.2794)
			(end 0.12065 -0.3048)
			(stroke
				(width 0.1)
				(type default)
			)
			(layer "F.Fab")
		)
		(fp_line
			(start 0.67945 -0.3048)
			(end 0.67945 0.3048)
			(stroke
				(width 0.1)
				(type default)
			)
			(layer "F.Fab")
		)
		(fp_line
			(start 0.67945 0.3048)
			(end 0.120396 0.3048)
			(stroke
				(width 0.1)
				(type default)
			)
			(layer "F.Fab")
		)
		(pad "1" smd circle
			(at -0.40005 0)
			(size 0 0)
			(layers "F.Cu" "F.Mask" "F.Paste")
			(net "HSC_ON")
		)
		(pad "2" smd circle
			(at 0.40005 0)
			(size 0 0)
			(layers "F.Cu" "F.Mask" "F.Paste")
			(net "AGND_HSC")
		)
	)
	(footprint ""
		(layer "F.Cu")
		(at 476.232728 -553.86859 90)
		(property "Reference" "HS_BP2"
			(at -0.5842 -1.31953 90)
			(unlocked yes)
			(layer "B.SilkS")
			(effects
				(font
					(size 0.7874 0.5842)
					(thickness 0.1524)
				)
				(justify left mirror)
			)
		)
		(property "Value" ""
			(at 0 0 90)
			(layer "F.Fab")
			(effects
				(font
					(size 1.27 1.27)
				)
			)
		)
		(duplicate_pad_numbers_are_jumpers no)
		(pad "1" thru_hole circle
			(at 0 0 90)
			(size 0.4572 0.4572)
			(drill 0.2032)
			(layers "*.Cu" "*.Mask")
			(remove_unused_layers no)
			(net "Net_9200")
			(clearance 0.127)
			(thermal_gap 0.127)
			(padstack
				(mode front_inner_back)
				(layer "Inner"
					(shape circle)
					(size 0.4572 0.4572)
					(clearance 0.127)
				)
				(layer "B.Cu"
					(shape circle)
					(size 0.508 0.508)
					(clearance 0.1016)
				)
			)
		)
	)
	(footprint ""
		(layer "F.Cu")
		(at 364.475776 -152.71115 -90)
		(property "Reference" "R754"
			(at 0 0 270)
			(layer "F.SilkS")
			(hide yes)
			(effects
				(font
					(size 1.27 1.27)
				)
			)
		)
		(property "Value" ""
			(at 0 0 270)
			(layer "F.Fab")
			(effects
				(font
					(size 1.27 1.27)
				)
			)
		)
		(duplicate_pad_numbers_are_jumpers no)
		(fp_line
			(start -0.7874 0.4064)
			(end -0.7874 -0.4064)
			(stroke
				(width 0.1524)
				(type default)
			)
			(layer "F.SilkS")
		)
		(fp_line
			(start 0.7874 0.4064)
			(end -0.7874 0.4064)
			(stroke
				(width 0.1524)
				(type default)
			)
			(layer "F.SilkS")
		)
		(fp_line
			(start -0.7874 -0.4064)
			(end 0.7874 -0.4064)
			(stroke
				(width 0.1524)
				(type default)
			)
			(layer "F.SilkS")
		)
		(fp_line
			(start 0.7874 -0.4064)
			(end 0.7874 0.4064)
			(stroke
				(width 0.1524)
				(type default)
			)
			(layer "F.SilkS")
		)
		(fp_line
			(start -0.67945 0.3048)
			(end -0.67945 -0.305054)
			(stroke
				(width 0.1)
				(type default)
			)
			(layer "F.Fab")
		)
		(fp_line
			(start -0.12065 0.3048)
			(end -0.67945 0.3048)
			(stroke
				(width 0.1)
				(type default)
			)
			(layer "F.Fab")
		)
		(fp_line
			(start 0.120396 0.3048)
			(end 0.120396 0.2794)
			(stroke
				(width 0.1)
				(type default)
			)
			(layer "F.Fab")
		)
		(fp_line
			(start 0.67945 0.3048)
			(end 0.120396 0.3048)
			(stroke
				(width 0.1)
				(type default)
			)
			(layer "F.Fab")
		)
		(fp_line
			(start -0.12065 0.2794)
			(end -0.12065 0.3048)
			(stroke
				(width 0.1)
				(type default)
			)
			(layer "F.Fab")
		)
		(fp_line
			(start 0.120396 0.2794)
			(end -0.12065 0.2794)
			(stroke
				(width 0.1)
				(type default)
			)
			(layer "F.Fab")
		)
		(fp_line
			(start -0.12065 -0.2794)
			(end 0.12065 -0.2794)
			(stroke
				(width 0.1)
				(type default)
			)
			(layer "F.Fab")
		)
		(fp_line
			(start 0.12065 -0.2794)
			(end 0.12065 -0.3048)
			(stroke
				(width 0.1)
				(type default)
			)
			(layer "F.Fab")
		)
		(fp_line
			(start 0.12065 -0.3048)
			(end 0.67945 -0.3048)
			(stroke
				(width 0.1)
				(type default)
			)
			(layer "F.Fab")
		)
		(fp_line
			(start 0.67945 -0.3048)
			(end 0.67945 0.3048)
			(stroke
				(width 0.1)
				(type default)
			)
			(layer "F.Fab")
		)
		(fp_line
			(start -0.67945 -0.305054)
			(end -0.12065 -0.305054)
			(stroke
				(width 0.1)
				(type default)
			)
			(layer "F.Fab")
		)
		(fp_line
			(start -0.12065 -0.305054)
			(end -0.12065 -0.2794)
			(stroke
				(width 0.1)
				(type default)
			)
			(layer "F.Fab")
		)
		(pad "1" smd circle
			(at -0.40005 0 270)
			(size 0 0)
			(layers "F.Cu" "F.Mask" "F.Paste")
			(net "SMB_BIC_I2C6_MUX_NIC_ADC_R_SDA")
		)
		(pad "2" smd circle
			(at 0.40005 0 270)
			(size 0 0)
			(layers "F.Cu" "F.Mask" "F.Paste")
			(net "SMB_NIC6_ADC_SDA")
		)
	)
	(footprint ""
		(layer "F.Cu")
		(at 338.074 -142.875 180)
		(property "Reference" "R4836"
			(at 0 0 180)
			(layer "F.SilkS")
			(hide yes)
			(effects
				(font
					(size 1.27 1.27)
				)
			)
		)
		(property "Value" ""
			(at 0 0 180)
			(layer "F.Fab")
			(effects
				(font
					(size 1.27 1.27)
				)
			)
		)
		(duplicate_pad_numbers_are_jumpers no)
		(fp_line
			(start 0.7874 0.4064)
			(end -0.7874 0.4064)
			(stroke
				(width 0.1524)
				(type default)
			)
			(layer "F.SilkS")
		)
		(fp_line
			(start 0.7874 -0.4064)
			(end 0.7874 0.4064)
			(stroke
				(width 0.1524)
				(type default)
			)
			(layer "F.SilkS")
		)
		(fp_line
			(start -0.7874 0.4064)
			(end -0.7874 -0.4064)
			(stroke
				(width 0.1524)
				(type default)
			)
			(layer "F.SilkS")
		)
		(fp_line
			(start -0.7874 -0.4064)
			(end 0.7874 -0.4064)
			(stroke
				(width 0.1524)
				(type default)
			)
			(layer "F.SilkS")
		)
		(fp_line
			(start 0.67945 0.3048)
			(end 0.120396 0.3048)
			(stroke
				(width 0.1)
				(type default)
			)
			(layer "F.Fab")
		)
		(fp_line
			(start 0.67945 -0.3048)
			(end 0.67945 0.3048)
			(stroke
				(width 0.1)
				(type default)
			)
			(layer "F.Fab")
		)
		(fp_line
			(start 0.12065 -0.2794)
			(end 0.12065 -0.3048)
			(stroke
				(width 0.1)
				(type default)
			)
			(layer "F.Fab")
		)
		(fp_line
			(start 0.12065 -0.3048)
			(end 0.67945 -0.3048)
			(stroke
				(width 0.1)
				(type default)
			)
			(layer "F.Fab")
		)
		(fp_line
			(start 0.120396 0.3048)
			(end 0.120396 0.2794)
			(stroke
				(width 0.1)
				(type default)
			)
			(layer "F.Fab")
		)
		(fp_line
			(start 0.120396 0.2794)
			(end -0.12065 0.2794)
			(stroke
				(width 0.1)
				(type default)
			)
			(layer "F.Fab")
		)
		(fp_line
			(start -0.12065 0.3048)
			(end -0.67945 0.3048)
			(stroke
				(width 0.1)
				(type default)
			)
			(layer "F.Fab")
		)
		(fp_line
			(start -0.12065 0.2794)
			(end -0.12065 0.3048)
			(stroke
				(width 0.1)
				(type default)
			)
			(layer "F.Fab")
		)
		(fp_line
			(start -0.12065 -0.2794)
			(end 0.12065 -0.2794)
			(stroke
				(width 0.1)
				(type default)
			)
			(layer "F.Fab")
		)
		(fp_line
			(start -0.12065 -0.305054)
			(end -0.12065 -0.2794)
			(stroke
				(width 0.1)
				(type default)
			)
			(layer "F.Fab")
		)
		(fp_line
			(start -0.67945 0.3048)
			(end -0.67945 -0.305054)
			(stroke
				(width 0.1)
				(type default)
			)
			(layer "F.Fab")
		)
		(fp_line
			(start -0.67945 -0.305054)
			(end -0.12065 -0.305054)
			(stroke
				(width 0.1)
				(type default)
			)
			(layer "F.Fab")
		)
		(pad "1" smd circle
			(at -0.40005 0 180)
			(size 0 0)
			(layers "F.Cu" "F.Mask" "F.Paste")
			(net "SSD15_PEX_PWR_EN")
		)
		(pad "2" smd circle
			(at 0.40005 0 180)
			(size 0 0)
			(layers "F.Cu" "F.Mask" "F.Paste")
			(net "SSD15_PEX_PWR_EN_R")
		)
	)
	(footprint ""
		(layer "F.Cu")
		(at 204.591158 -79.595472)
		(property "Reference" "R4335"
			(at 0 0 0)
			(layer "F.SilkS")
			(hide yes)
			(effects
				(font
					(size 1.27 1.27)
				)
			)
		)
		(property "Value" ""
			(at 0 0 0)
			(layer "F.Fab")
			(effects
				(font
					(size 1.27 1.27)
				)
			)
		)
		(duplicate_pad_numbers_are_jumpers no)
		(fp_line
			(start -0.7874 -0.4064)
			(end 0.7874 -0.4064)
			(stroke
				(width 0.1524)
				(type default)
			)
			(layer "F.SilkS")
		)
		(fp_line
			(start -0.7874 0.4064)
			(end -0.7874 -0.4064)
			(stroke
				(width 0.1524)
				(type default)
			)
			(layer "F.SilkS")
		)
		(fp_line
			(start 0.7874 -0.4064)
			(end 0.7874 0.4064)
			(stroke
				(width 0.1524)
				(type default)
			)
			(layer "F.SilkS")
		)
		(fp_line
			(start 0.7874 0.4064)
			(end -0.7874 0.4064)
			(stroke
				(width 0.1524)
				(type default)
			)
			(layer "F.SilkS")
		)
		(fp_line
			(start -0.67945 -0.305054)
			(end -0.12065 -0.305054)
			(stroke
				(width 0.1)
				(type default)
			)
			(layer "F.Fab")
		)
		(fp_line
			(start -0.67945 0.3048)
			(end -0.67945 -0.305054)
			(stroke
				(width 0.1)
				(type default)
			)
			(layer "F.Fab")
		)
		(fp_line
			(start -0.12065 -0.305054)
			(end -0.12065 -0.2794)
			(stroke
				(width 0.1)
				(type default)
			)
			(layer "F.Fab")
		)
		(fp_line
			(start -0.12065 -0.2794)
			(end 0.12065 -0.2794)
			(stroke
				(width 0.1)
				(type default)
			)
			(layer "F.Fab")
		)
		(fp_line
			(start -0.12065 0.2794)
			(end -0.12065 0.3048)
			(stroke
				(width 0.1)
				(type default)
			)
			(layer "F.Fab")
		)
		(fp_line
			(start -0.12065 0.3048)
			(end -0.67945 0.3048)
			(stroke
				(width 0.1)
				(type default)
			)
			(layer "F.Fab")
		)
		(fp_line
			(start 0.120396 0.2794)
			(end -0.12065 0.2794)
			(stroke
				(width 0.1)
				(type default)
			)
			(layer "F.Fab")
		)
		(fp_line
			(start 0.120396 0.3048)
			(end 0.120396 0.2794)
			(stroke
				(width 0.1)
				(type default)
			)
			(layer "F.Fab")
		)
		(fp_line
			(start 0.12065 -0.3048)
			(end 0.67945 -0.3048)
			(stroke
				(width 0.1)
				(type default)
			)
			(layer "F.Fab")
		)
		(fp_line
			(start 0.12065 -0.2794)
			(end 0.12065 -0.3048)
			(stroke
				(width 0.1)
				(type default)
			)
			(layer "F.Fab")
		)
		(fp_line
			(start 0.67945 -0.3048)
			(end 0.67945 0.3048)
			(stroke
				(width 0.1)
				(type default)
			)
			(layer "F.Fab")
		)
		(fp_line
			(start 0.67945 0.3048)
			(end 0.120396 0.3048)
			(stroke
				(width 0.1)
				(type default)
			)
			(layer "F.Fab")
		)
		(pad "1" smd circle
			(at -0.40005 0)
			(size 0 0)
			(layers "F.Cu" "F.Mask" "F.Paste")
			(net "P3V3_AUX")
		)
		(pad "2" smd circle
			(at 0.40005 0)
			(size 0 0)
			(layers "F.Cu" "F.Mask" "F.Paste")
			(net "SSD5_LED_R")
		)
	)
	(footprint ""
		(layer "F.Cu")
		(at 8.110474 -68.732146 180)
		(property "Reference" "R5872"
			(at 0 0 180)
			(layer "F.SilkS")
			(hide yes)
			(effects
				(font
					(size 1.27 1.27)
				)
			)
		)
		(property "Value" ""
			(at 0 0 180)
			(layer "F.Fab")
			(effects
				(font
					(size 1.27 1.27)
				)
			)
		)
		(duplicate_pad_numbers_are_jumpers no)
		(fp_line
			(start 0.7874 0.4064)
			(end -0.7874 0.4064)
			(stroke
				(width 0.1524)
				(type default)
			)
			(layer "F.SilkS")
		)
		(fp_line
			(start 0.7874 -0.4064)
			(end 0.7874 0.4064)
			(stroke
				(width 0.1524)
				(type default)
			)
			(layer "F.SilkS")
		)
		(fp_line
			(start -0.7874 0.4064)
			(end -0.7874 -0.4064)
			(stroke
				(width 0.1524)
				(type default)
			)
			(layer "F.SilkS")
		)
		(fp_line
			(start -0.7874 -0.4064)
			(end 0.7874 -0.4064)
			(stroke
				(width 0.1524)
				(type default)
			)
			(layer "F.SilkS")
		)
		(fp_line
			(start 0.67945 0.3048)
			(end 0.120396 0.3048)
			(stroke
				(width 0.1)
				(type default)
			)
			(layer "F.Fab")
		)
		(fp_line
			(start 0.67945 -0.3048)
			(end 0.67945 0.3048)
			(stroke
				(width 0.1)
				(type default)
			)
			(layer "F.Fab")
		)
		(fp_line
			(start 0.12065 -0.2794)
			(end 0.12065 -0.3048)
			(stroke
				(width 0.1)
				(type default)
			)
			(layer "F.Fab")
		)
		(fp_line
			(start 0.12065 -0.3048)
			(end 0.67945 -0.3048)
			(stroke
				(width 0.1)
				(type default)
			)
			(layer "F.Fab")
		)
		(fp_line
			(start 0.120396 0.3048)
			(end 0.120396 0.2794)
			(stroke
				(width 0.1)
				(type default)
			)
			(layer "F.Fab")
		)
		(fp_line
			(start 0.120396 0.2794)
			(end -0.12065 0.2794)
			(stroke
				(width 0.1)
				(type default)
			)
			(layer "F.Fab")
		)
		(fp_line
			(start -0.12065 0.3048)
			(end -0.67945 0.3048)
			(stroke
				(width 0.1)
				(type default)
			)
			(layer "F.Fab")
		)
		(fp_line
			(start -0.12065 0.2794)
			(end -0.12065 0.3048)
			(stroke
				(width 0.1)
				(type default)
			)
			(layer "F.Fab")
		)
		(fp_line
			(start -0.12065 -0.2794)
			(end 0.12065 -0.2794)
			(stroke
				(width 0.1)
				(type default)
			)
			(layer "F.Fab")
		)
		(fp_line
			(start -0.12065 -0.305054)
			(end -0.12065 -0.2794)
			(stroke
				(width 0.1)
				(type default)
			)
			(layer "F.Fab")
		)
		(fp_line
			(start -0.67945 0.3048)
			(end -0.67945 -0.305054)
			(stroke
				(width 0.1)
				(type default)
			)
			(layer "F.Fab")
		)
		(fp_line
			(start -0.67945 -0.305054)
			(end -0.12065 -0.305054)
			(stroke
				(width 0.1)
				(type default)
			)
			(layer "F.Fab")
		)
		(pad "1" smd circle
			(at -0.40005 0 180)
			(size 0 0)
			(layers "F.Cu" "F.Mask" "F.Paste")
			(net "P5V_AUX")
		)
		(pad "2" smd circle
			(at 0.40005 0 180)
			(size 0 0)
			(layers "F.Cu" "F.Mask" "F.Paste")
			(net "P3V3_SSD0_PG_G2")
		)
	)
	(footprint ""
		(layer "F.Cu")
		(at 121.13514 -98.320606)
		(property "Reference" "R1558"
			(at 0 0 0)
			(layer "F.SilkS")
			(hide yes)
			(effects
				(font
					(size 1.27 1.27)
				)
			)
		)
		(property "Value" ""
			(at 0 0 0)
			(layer "F.Fab")
			(effects
				(font
					(size 1.27 1.27)
				)
			)
		)
		(duplicate_pad_numbers_are_jumpers no)
		(fp_line
			(start -0.7874 -0.4064)
			(end 0.7874 -0.4064)
			(stroke
				(width 0.1524)
				(type default)
			)
			(layer "F.SilkS")
		)
		(fp_line
			(start -0.7874 0.4064)
			(end -0.7874 -0.4064)
			(stroke
				(width 0.1524)
				(type default)
			)
			(layer "F.SilkS")
		)
		(fp_line
			(start 0.7874 -0.4064)
			(end 0.7874 0.4064)
			(stroke
				(width 0.1524)
				(type default)
			)
			(layer "F.SilkS")
		)
		(fp_line
			(start 0.7874 0.4064)
			(end -0.7874 0.4064)
			(stroke
				(width 0.1524)
				(type default)
			)
			(layer "F.SilkS")
		)
		(fp_line
			(start -0.67945 -0.305054)
			(end -0.12065 -0.305054)
			(stroke
				(width 0.1)
				(type default)
			)
			(layer "F.Fab")
		)
		(fp_line
			(start -0.67945 0.3048)
			(end -0.67945 -0.305054)
			(stroke
				(width 0.1)
				(type default)
			)
			(layer "F.Fab")
		)
		(fp_line
			(start -0.12065 -0.305054)
			(end -0.12065 -0.2794)
			(stroke
				(width 0.1)
				(type default)
			)
			(layer "F.Fab")
		)
		(fp_line
			(start -0.12065 -0.2794)
			(end 0.12065 -0.2794)
			(stroke
				(width 0.1)
				(type default)
			)
			(layer "F.Fab")
		)
		(fp_line
			(start -0.12065 0.2794)
			(end -0.12065 0.3048)
			(stroke
				(width 0.1)
				(type default)
			)
			(layer "F.Fab")
		)
		(fp_line
			(start -0.12065 0.3048)
			(end -0.67945 0.3048)
			(stroke
				(width 0.1)
				(type default)
			)
			(layer "F.Fab")
		)
		(fp_line
			(start 0.120396 0.2794)
			(end -0.12065 0.2794)
			(stroke
				(width 0.1)
				(type default)
			)
			(layer "F.Fab")
		)
		(fp_line
			(start 0.120396 0.3048)
			(end 0.120396 0.2794)
			(stroke
				(width 0.1)
				(type default)
			)
			(layer "F.Fab")
		)
		(fp_line
			(start 0.12065 -0.3048)
			(end 0.67945 -0.3048)
			(stroke
				(width 0.1)
				(type default)
			)
			(layer "F.Fab")
		)
		(fp_line
			(start 0.12065 -0.2794)
			(end 0.12065 -0.3048)
			(stroke
				(width 0.1)
				(type default)
			)
			(layer "F.Fab")
		)
		(fp_line
			(start 0.67945 -0.3048)
			(end 0.67945 0.3048)
			(stroke
				(width 0.1)
				(type default)
			)
			(layer "F.Fab")
		)
		(fp_line
			(start 0.67945 0.3048)
			(end 0.120396 0.3048)
			(stroke
				(width 0.1)
				(type default)
			)
			(layer "F.Fab")
		)
		(pad "1" smd circle
			(at -0.40005 0)
			(size 0 0)
			(layers "F.Cu" "F.Mask" "F.Paste")
			(net "P3V3_AUX")
		)
		(pad "2" smd circle
			(at 0.40005 0)
			(size 0 0)
			(layers "F.Cu" "F.Mask" "F.Paste")
			(net "BIC_I2C9_SSD_MUX0_A1")
		)
	)
	(footprint ""
		(layer "F.Cu")
		(at 27.390344 -252.356874 -90)
		(property "Reference" "R1196"
			(at 0 0 270)
			(layer "F.SilkS")
			(hide yes)
			(effects
				(font
					(size 1.27 1.27)
				)
			)
		)
		(property "Value" ""
			(at 0 0 270)
			(layer "F.Fab")
			(effects
				(font
					(size 1.27 1.27)
				)
			)
		)
		(duplicate_pad_numbers_are_jumpers no)
		(fp_line
			(start -0.7874 0.4064)
			(end -0.7874 -0.4064)
			(stroke
				(width 0.1524)
				(type default)
			)
			(layer "F.SilkS")
		)
		(fp_line
			(start 0.7874 0.4064)
			(end -0.7874 0.4064)
			(stroke
				(width 0.1524)
				(type default)
			)
			(layer "F.SilkS")
		)
		(fp_line
			(start -0.7874 -0.4064)
			(end 0.7874 -0.4064)
			(stroke
				(width 0.1524)
				(type default)
			)
			(layer "F.SilkS")
		)
		(fp_line
			(start 0.7874 -0.4064)
			(end 0.7874 0.4064)
			(stroke
				(width 0.1524)
				(type default)
			)
			(layer "F.SilkS")
		)
		(fp_line
			(start -0.67945 0.3048)
			(end -0.67945 -0.305054)
			(stroke
				(width 0.1)
				(type default)
			)
			(layer "F.Fab")
		)
		(fp_line
			(start -0.12065 0.3048)
			(end -0.67945 0.3048)
			(stroke
				(width 0.1)
				(type default)
			)
			(layer "F.Fab")
		)
		(fp_line
			(start 0.120396 0.3048)
			(end 0.120396 0.2794)
			(stroke
				(width 0.1)
				(type default)
			)
			(layer "F.Fab")
		)
		(fp_line
			(start 0.67945 0.3048)
			(end 0.120396 0.3048)
			(stroke
				(width 0.1)
				(type default)
			)
			(layer "F.Fab")
		)
		(fp_line
			(start -0.12065 0.2794)
			(end -0.12065 0.3048)
			(stroke
				(width 0.1)
				(type default)
			)
			(layer "F.Fab")
		)
		(fp_line
			(start 0.120396 0.2794)
			(end -0.12065 0.2794)
			(stroke
				(width 0.1)
				(type default)
			)
			(layer "F.Fab")
		)
		(fp_line
			(start -0.12065 -0.2794)
			(end 0.12065 -0.2794)
			(stroke
				(width 0.1)
				(type default)
			)
			(layer "F.Fab")
		)
		(fp_line
			(start 0.12065 -0.2794)
			(end 0.12065 -0.3048)
			(stroke
				(width 0.1)
				(type default)
			)
			(layer "F.Fab")
		)
		(fp_line
			(start 0.12065 -0.3048)
			(end 0.67945 -0.3048)
			(stroke
				(width 0.1)
				(type default)
			)
			(layer "F.Fab")
		)
		(fp_line
			(start 0.67945 -0.3048)
			(end 0.67945 0.3048)
			(stroke
				(width 0.1)
				(type default)
			)
			(layer "F.Fab")
		)
		(fp_line
			(start -0.67945 -0.305054)
			(end -0.12065 -0.305054)
			(stroke
				(width 0.1)
				(type default)
			)
			(layer "F.Fab")
		)
		(fp_line
			(start -0.12065 -0.305054)
			(end -0.12065 -0.2794)
			(stroke
				(width 0.1)
				(type default)
			)
			(layer "F.Fab")
		)
		(pad "1" smd circle
			(at -0.40005 0 270)
			(size 0 0)
			(layers "F.Cu" "F.Mask" "F.Paste")
			(net "GND")
		)
		(pad "2" smd circle
			(at 0.40005 0 270)
			(size 0 0)
			(layers "F.Cu" "F.Mask" "F.Paste")
			(net "PEX0_MODE_SEL5")
		)
	)
	(footprint ""
		(layer "F.Cu")
		(at 4.647692 -24.934164 -90)
		(property "Reference" "R1633"
			(at 0 0 270)
			(layer "F.SilkS")
			(hide yes)
			(effects
				(font
					(size 1.27 1.27)
				)
			)
		)
		(property "Value" ""
			(at 0 0 270)
			(layer "F.Fab")
			(effects
				(font
					(size 1.27 1.27)
				)
			)
		)
		(duplicate_pad_numbers_are_jumpers no)
		(fp_line
			(start -0.7874 0.4064)
			(end -0.7874 -0.4064)
			(stroke
				(width 0.1524)
				(type default)
			)
			(layer "F.SilkS")
		)
		(fp_line
			(start 0.7874 0.4064)
			(end -0.7874 0.4064)
			(stroke
				(width 0.1524)
				(type default)
			)
			(layer "F.SilkS")
		)
		(fp_line
			(start -0.7874 -0.4064)
			(end 0.7874 -0.4064)
			(stroke
				(width 0.1524)
				(type default)
			)
			(layer "F.SilkS")
		)
		(fp_line
			(start 0.7874 -0.4064)
			(end 0.7874 0.4064)
			(stroke
				(width 0.1524)
				(type default)
			)
			(layer "F.SilkS")
		)
		(fp_line
			(start -0.67945 0.3048)
			(end -0.67945 -0.305054)
			(stroke
				(width 0.1)
				(type default)
			)
			(layer "F.Fab")
		)
		(fp_line
			(start -0.12065 0.3048)
			(end -0.67945 0.3048)
			(stroke
				(width 0.1)
				(type default)
			)
			(layer "F.Fab")
		)
		(fp_line
			(start 0.120396 0.3048)
			(end 0.120396 0.2794)
			(stroke
				(width 0.1)
				(type default)
			)
			(layer "F.Fab")
		)
		(fp_line
			(start 0.67945 0.3048)
			(end 0.120396 0.3048)
			(stroke
				(width 0.1)
				(type default)
			)
			(layer "F.Fab")
		)
		(fp_line
			(start -0.12065 0.2794)
			(end -0.12065 0.3048)
			(stroke
				(width 0.1)
				(type default)
			)
			(layer "F.Fab")
		)
		(fp_line
			(start 0.120396 0.2794)
			(end -0.12065 0.2794)
			(stroke
				(width 0.1)
				(type default)
			)
			(layer "F.Fab")
		)
		(fp_line
			(start -0.12065 -0.2794)
			(end 0.12065 -0.2794)
			(stroke
				(width 0.1)
				(type default)
			)
			(layer "F.Fab")
		)
		(fp_line
			(start 0.12065 -0.2794)
			(end 0.12065 -0.3048)
			(stroke
				(width 0.1)
				(type default)
			)
			(layer "F.Fab")
		)
		(fp_line
			(start 0.12065 -0.3048)
			(end 0.67945 -0.3048)
			(stroke
				(width 0.1)
				(type default)
			)
			(layer "F.Fab")
		)
		(fp_line
			(start 0.67945 -0.3048)
			(end 0.67945 0.3048)
			(stroke
				(width 0.1)
				(type default)
			)
			(layer "F.Fab")
		)
		(fp_line
			(start -0.67945 -0.305054)
			(end -0.12065 -0.305054)
			(stroke
				(width 0.1)
				(type default)
			)
			(layer "F.Fab")
		)
		(fp_line
			(start -0.12065 -0.305054)
			(end -0.12065 -0.2794)
			(stroke
				(width 0.1)
				(type default)
			)
			(layer "F.Fab")
		)
		(pad "1" smd circle
			(at -0.40005 0 270)
			(size 0 0)
			(layers "F.Cu" "F.Mask" "F.Paste")
			(net "P3V3_SSD0")
		)
		(pad "2" smd circle
			(at 0.40005 0 270)
			(size 0 0)
			(layers "F.Cu" "F.Mask" "F.Paste")
			(net "SMB_ISO_SSD0_SDA")
		)
	)
	(footprint ""
		(layer "F.Cu")
		(at 155.380436 -102.888796)
		(property "Reference" "C270"
			(at 0 0 0)
			(layer "F.SilkS")
			(hide yes)
			(effects
				(font
					(size 1.27 1.27)
				)
			)
		)
		(property "Value" ""
			(at 0 0 0)
			(layer "F.Fab")
			(effects
				(font
					(size 1.27 1.27)
				)
			)
		)
		(duplicate_pad_numbers_are_jumpers no)
		(fp_line
			(start -0.299974 -0.150114)
			(end 0.299974 -0.150114)
			(stroke
				(width 0.1)
				(type default)
			)
			(layer "F.Fab")
		)
		(fp_line
			(start -0.299974 0.150114)
			(end -0.299974 -0.150114)
			(stroke
				(width 0.1)
				(type default)
			)
			(layer "F.Fab")
		)
		(fp_line
			(start 0.299974 -0.150114)
			(end 0.299974 0.150114)
			(stroke
				(width 0.1)
				(type default)
			)
			(layer "F.Fab")
		)
		(fp_line
			(start 0.299974 0.150114)
			(end -0.299974 0.150114)
			(stroke
				(width 0.1)
				(type default)
			)
			(layer "F.Fab")
		)
		(pad "1" smd rect
			(at -0.2667 0)
			(size 0.3048 0.381)
			(layers "F.Cu" "F.Mask" "F.Paste")
			(net "P5E_PEX1_STN1_TX_DP<18>")
		)
		(pad "2" smd rect
			(at 0.2667 0)
			(size 0.3048 0.381)
			(layers "F.Cu" "F.Mask" "F.Paste")
			(net "P5E_PEX1_STN1_TX_C_DP<18>")
		)
	)
	(footprint ""
		(layer "F.Cu")
		(at 44.619926 -15.649956 180)
		(property "Reference" "H100"
			(at -0.987298 2.69621 0)
			(unlocked yes)
			(layer "B.SilkS")
			(effects
				(font
					(size 0.7874 0.5842)
					(thickness 0.1524)
				)
				(justify left mirror)
			)
		)
		(property "Value" ""
			(at 0 0 180)
			(layer "F.Fab")
			(effects
				(font
					(size 1.27 1.27)
				)
			)
		)
		(duplicate_pad_numbers_are_jumpers no)
		(pad "1" thru_hole rect
			(at 0 0 180)
			(size 4.2164 5.0038)
			(drill 2.0066
				(offset 0.099822 0)
			)
			(layers "*.Cu" "*.Mask")
			(remove_unused_layers no)
			(net "Net_8563")
			(clearance -0.8509)
			(padstack
				(mode front_inner_back)
				(layer "Inner"
					(shape circle)
					(size 4.0132 4.0132)
					(clearance -0.7493)
				)
				(layer "B.Cu"
					(shape circle)
					(size 4.0132 4.0132)
					(clearance -0.7493)
				)
			)
		)
	)
	(footprint ""
		(layer "F.Cu")
		(at 15.926562 -121.408952 180)
		(property "Reference" "PC451"
			(at 0 0 180)
			(layer "F.SilkS")
			(hide yes)
			(effects
				(font
					(size 1.27 1.27)
				)
			)
		)
		(property "Value" ""
			(at 0 0 180)
			(layer "F.Fab")
			(effects
				(font
					(size 1.27 1.27)
				)
			)
		)
		(duplicate_pad_numbers_are_jumpers no)
		(fp_line
			(start 1.524 0.762)
			(end -1.524 0.762)
			(stroke
				(width 0.1524)
				(type default)
			)
			(layer "F.SilkS")
		)
		(fp_line
			(start 1.524 -0.762)
			(end 1.524 0.762)
			(stroke
				(width 0.1524)
				(type default)
			)
			(layer "F.SilkS")
		)
		(fp_line
			(start -1.524 0.762)
			(end -1.524 -0.762)
			(stroke
				(width 0.1524)
				(type default)
			)
			(layer "F.SilkS")
		)
		(fp_line
			(start -1.524 -0.762)
			(end 1.524 -0.762)
			(stroke
				(width 0.1524)
				(type default)
			)
			(layer "F.SilkS")
		)
		(fp_line
			(start 1.1049 0.724916)
			(end 1.1049 -0.724916)
			(stroke
				(width 0.1)
				(type default)
			)
			(layer "F.Fab")
		)
		(fp_line
			(start 1.1049 -0.724916)
			(end -1.1049 -0.724916)
			(stroke
				(width 0.1)
				(type default)
			)
			(layer "F.Fab")
		)
		(fp_line
			(start -1.1049 0.724916)
			(end 1.1049 0.724916)
			(stroke
				(width 0.1)
				(type default)
			)
			(layer "F.Fab")
		)
		(fp_line
			(start -1.1049 -0.724916)
			(end -1.1049 0.724916)
			(stroke
				(width 0.1)
				(type default)
			)
			(layer "F.Fab")
		)
		(pad "1" smd rect
			(at -0.889 0)
			(size 1.016 1.27)
			(layers "F.Cu" "F.Mask" "F.Paste")
			(net "GND")
		)
		(pad "2" smd rect
			(at 0.889 0)
			(size 1.016 1.27)
			(layers "F.Cu" "F.Mask" "F.Paste")
			(net "P3V3_AUX")
		)
	)
	(footprint ""
		(layer "F.Cu")
		(at 228.22789 -35.876738)
		(property "Reference" "R6082"
			(at 0 0 0)
			(layer "F.SilkS")
			(hide yes)
			(effects
				(font
					(size 1.27 1.27)
				)
			)
		)
		(property "Value" ""
			(at 0 0 0)
			(layer "F.Fab")
			(effects
				(font
					(size 1.27 1.27)
				)
			)
		)
		(duplicate_pad_numbers_are_jumpers no)
		(fp_line
			(start -0.7874 -0.4064)
			(end 0.7874 -0.4064)
			(stroke
				(width 0.1524)
				(type default)
			)
			(layer "F.SilkS")
		)
		(fp_line
			(start -0.7874 0.4064)
			(end -0.7874 -0.4064)
			(stroke
				(width 0.1524)
				(type default)
			)
			(layer "F.SilkS")
		)
		(fp_line
			(start 0.7874 -0.4064)
			(end 0.7874 0.4064)
			(stroke
				(width 0.1524)
				(type default)
			)
			(layer "F.SilkS")
		)
		(fp_line
			(start 0.7874 0.4064)
			(end -0.7874 0.4064)
			(stroke
				(width 0.1524)
				(type default)
			)
			(layer "F.SilkS")
		)
		(fp_line
			(start -0.67945 -0.305054)
			(end -0.12065 -0.305054)
			(stroke
				(width 0.1)
				(type default)
			)
			(layer "F.Fab")
		)
		(fp_line
			(start -0.67945 0.3048)
			(end -0.67945 -0.305054)
			(stroke
				(width 0.1)
				(type default)
			)
			(layer "F.Fab")
		)
		(fp_line
			(start -0.12065 -0.305054)
			(end -0.12065 -0.2794)
			(stroke
				(width 0.1)
				(type default)
			)
			(layer "F.Fab")
		)
		(fp_line
			(start -0.12065 -0.2794)
			(end 0.12065 -0.2794)
			(stroke
				(width 0.1)
				(type default)
			)
			(layer "F.Fab")
		)
		(fp_line
			(start -0.12065 0.2794)
			(end -0.12065 0.3048)
			(stroke
				(width 0.1)
				(type default)
			)
			(layer "F.Fab")
		)
		(fp_line
			(start -0.12065 0.3048)
			(end -0.67945 0.3048)
			(stroke
				(width 0.1)
				(type default)
			)
			(layer "F.Fab")
		)
		(fp_line
			(start 0.120396 0.2794)
			(end -0.12065 0.2794)
			(stroke
				(width 0.1)
				(type default)
			)
			(layer "F.Fab")
		)
		(fp_line
			(start 0.120396 0.3048)
			(end 0.120396 0.2794)
			(stroke
				(width 0.1)
				(type default)
			)
			(layer "F.Fab")
		)
		(fp_line
			(start 0.12065 -0.3048)
			(end 0.67945 -0.3048)
			(stroke
				(width 0.1)
				(type default)
			)
			(layer "F.Fab")
		)
		(fp_line
			(start 0.12065 -0.2794)
			(end 0.12065 -0.3048)
			(stroke
				(width 0.1)
				(type default)
			)
			(layer "F.Fab")
		)
		(fp_line
			(start 0.67945 -0.3048)
			(end 0.67945 0.3048)
			(stroke
				(width 0.1)
				(type default)
			)
			(layer "F.Fab")
		)
		(fp_line
			(start 0.67945 0.3048)
			(end 0.120396 0.3048)
			(stroke
				(width 0.1)
				(type default)
			)
			(layer "F.Fab")
		)
		(pad "1" smd circle
			(at -0.40005 0)
			(size 0 0)
			(layers "F.Cu" "F.Mask" "F.Paste")
			(net "PWRGD_P3V3_SSD8_D")
		)
		(pad "2" smd circle
			(at 0.40005 0)
			(size 0 0)
			(layers "F.Cu" "F.Mask" "F.Paste")
			(net "PWRGD_P3V3_SSD8_R")
		)
	)
	(footprint ""
		(layer "F.Cu")
		(at 133.892544 -28.225242 180)
		(property "Reference" "C283"
			(at 0 0 180)
			(layer "F.SilkS")
			(hide yes)
			(effects
				(font
					(size 1.27 1.27)
				)
			)
		)
		(property "Value" ""
			(at 0 0 180)
			(layer "F.Fab")
			(effects
				(font
					(size 1.27 1.27)
				)
			)
		)
		(duplicate_pad_numbers_are_jumpers no)
		(fp_line
			(start 0.299974 0.150114)
			(end -0.299974 0.150114)
			(stroke
				(width 0.1)
				(type default)
			)
			(layer "F.Fab")
		)
		(fp_line
			(start 0.299974 -0.150114)
			(end 0.299974 0.150114)
			(stroke
				(width 0.1)
				(type default)
			)
			(layer "F.Fab")
		)
		(fp_line
			(start -0.299974 0.150114)
			(end -0.299974 -0.150114)
			(stroke
				(width 0.1)
				(type default)
			)
			(layer "F.Fab")
		)
		(fp_line
			(start -0.299974 -0.150114)
			(end 0.299974 -0.150114)
			(stroke
				(width 0.1)
				(type default)
			)
			(layer "F.Fab")
		)
		(pad "1" smd rect
			(at -0.2667 0 180)
			(size 0.3048 0.381)
			(layers "F.Cu" "F.Mask" "F.Paste")
			(net "P5E_PEX1_STN2_TX_DN<44>")
		)
		(pad "2" smd rect
			(at 0.2667 0 180)
			(size 0.3048 0.381)
			(layers "F.Cu" "F.Mask" "F.Paste")
			(net "P5E_PEX1_STN2_TX_C_DN<44>")
		)
	)
	(footprint ""
		(layer "F.Cu")
		(at 138.061192 -37.951156)
		(property "Reference" "Q221"
			(at -0.063246 -1.936242 0)
			(unlocked yes)
			(layer "F.SilkS")
			(effects
				(font
					(size 0.7874 0.5842)
					(thickness 0.1524)
				)
			)
		)
		(property "Value" ""
			(at 0 0 0)
			(layer "F.Fab")
			(effects
				(font
					(size 1.27 1.27)
				)
			)
		)
		(duplicate_pad_numbers_are_jumpers no)
		(fp_line
			(start -1.376172 -1.199896)
			(end -0.508 -1.199896)
			(stroke
				(width 0.1524)
				(type default)
			)
			(layer "F.SilkS")
		)
		(fp_line
			(start -1.376172 1.199896)
			(end -1.376172 -1.199896)
			(stroke
				(width 0.1524)
				(type default)
			)
			(layer "F.SilkS")
		)
		(fp_line
			(start -0.508 -1.199896)
			(end 0 -0.762)
			(stroke
				(width 0.1524)
				(type default)
			)
			(layer "F.SilkS")
		)
		(fp_line
			(start 0 -0.762)
			(end 0.508 -1.199896)
			(stroke
				(width 0.1524)
				(type default)
			)
			(layer "F.SilkS")
		)
		(fp_line
			(start 0.508 -1.199896)
			(end 1.376172 -1.199896)
			(stroke
				(width 0.1524)
				(type default)
			)
			(layer "F.SilkS")
		)
		(fp_line
			(start 1.376172 -1.199896)
			(end 1.376172 1.199896)
			(stroke
				(width 0.1524)
				(type default)
			)
			(layer "F.SilkS")
		)
		(fp_line
			(start 1.376172 1.199896)
			(end -1.376172 1.199896)
			(stroke
				(width 0.1524)
				(type default)
			)
			(layer "F.SilkS")
		)
		(fp_poly
			(pts
				(xy -1.474216 -0.832612) (xy -1.74371 -1.64084) (xy -2.282444 -1.101852)
			)
			(stroke
				(width 0)
				(type default)
			)
			(fill yes)
			(layer "F.SilkS")
		)
		(fp_line
			(start -0.674878 -1.100074)
			(end 0.674878 -1.100074)
			(stroke
				(width 0.1)
				(type default)
			)
			(layer "F.Fab")
		)
		(fp_line
			(start -0.674878 1.100074)
			(end -0.674878 -1.100074)
			(stroke
				(width 0.1)
				(type default)
			)
			(layer "F.Fab")
		)
		(fp_line
			(start 0.674878 -1.100074)
			(end 0.674878 1.100074)
			(stroke
				(width 0.1)
				(type default)
			)
			(layer "F.Fab")
		)
		(fp_line
			(start 0.674878 1.100074)
			(end -0.674878 1.100074)
			(stroke
				(width 0.1)
				(type default)
			)
			(layer "F.Fab")
		)
		(fp_poly
			(pts
				(xy -1.4605 -0.7493) (xy -2.2225 -1.1303) (xy -2.2225 -0.3683)
			)
			(stroke
				(width 0)
				(type default)
			)
			(fill yes)
			(layer "F.Fab")
		)
		(pad "1" smd rect
			(at -0.899922 -0.750062 270)
			(size 0.6096 0.6096)
			(layers "F.Cu" "F.Mask" "F.Paste")
			(net "GND")
		)
		(pad "2" smd rect
			(at -0.899922 0 270)
			(size 0.4064 0.6096)
			(layers "F.Cu" "F.Mask" "F.Paste")
			(net "P3V3_SSD5_PG_G1")
		)
		(pad "3" smd rect
			(at -0.899922 0.750062 270)
			(size 0.6096 0.6096)
			(layers "F.Cu" "F.Mask" "F.Paste")
			(net "PWRGD_P3V3_SSD5_D")
		)
		(pad "4" smd rect
			(at 0.899922 0.750062 270)
			(size 0.6096 0.6096)
			(layers "F.Cu" "F.Mask" "F.Paste")
			(net "GND")
		)
		(pad "5" smd rect
			(at 0.899922 0 270)
			(size 0.4064 0.6096)
			(layers "F.Cu" "F.Mask" "F.Paste")
			(net "P3V3_SSD5_PG_G2")
		)
		(pad "6" smd rect
			(at 0.899922 -0.750062 270)
			(size 0.6096 0.6096)
			(layers "F.Cu" "F.Mask" "F.Paste")
			(net "P3V3_SSD5_PG_G2")
		)
	)
	(footprint ""
		(layer "F.Cu")
		(at 461.734408 -265.876024)
		(property "Reference" "C4406"
			(at 0 0 0)
			(layer "F.SilkS")
			(hide yes)
			(effects
				(font
					(size 1.27 1.27)
				)
			)
		)
		(property "Value" ""
			(at 0 0 0)
			(layer "F.Fab")
			(effects
				(font
					(size 1.27 1.27)
				)
			)
		)
		(duplicate_pad_numbers_are_jumpers no)
		(fp_line
			(start -0.299974 -0.150114)
			(end 0.299974 -0.150114)
			(stroke
				(width 0.1)
				(type default)
			)
			(layer "F.Fab")
		)
		(fp_line
			(start -0.299974 0.150114)
			(end -0.299974 -0.150114)
			(stroke
				(width 0.1)
				(type default)
			)
			(layer "F.Fab")
		)
		(fp_line
			(start 0.299974 -0.150114)
			(end 0.299974 0.150114)
			(stroke
				(width 0.1)
				(type default)
			)
			(layer "F.Fab")
		)
		(fp_line
			(start 0.299974 0.150114)
			(end -0.299974 0.150114)
			(stroke
				(width 0.1)
				(type default)
			)
			(layer "F.Fab")
		)
		(pad "1" smd rect
			(at -0.2667 0)
			(size 0.3048 0.381)
			(layers "F.Cu" "F.Mask" "F.Paste")
			(net "P1V25_SERDES_VDDPLL_PEX3")
		)
		(pad "2" smd rect
			(at 0.2667 0)
			(size 0.3048 0.381)
			(layers "F.Cu" "F.Mask" "F.Paste")
			(net "GND")
		)
	)
	(footprint ""
		(layer "F.Cu")
		(at 148.417534 -113.558574 -90)
		(property "Reference" "C4000"
			(at 0 0 270)
			(layer "F.SilkS")
			(hide yes)
			(effects
				(font
					(size 1.27 1.27)
				)
			)
		)
		(property "Value" ""
			(at 0 0 270)
			(layer "F.Fab")
			(effects
				(font
					(size 1.27 1.27)
				)
			)
		)
		(duplicate_pad_numbers_are_jumpers no)
		(fp_line
			(start -0.7874 0.4064)
			(end -0.7874 -0.4064)
			(stroke
				(width 0.1524)
				(type default)
			)
			(layer "F.SilkS")
		)
		(fp_line
			(start 0.7874 0.4064)
			(end -0.7874 0.4064)
			(stroke
				(width 0.1524)
				(type default)
			)
			(layer "F.SilkS")
		)
		(fp_line
			(start -0.7874 -0.4064)
			(end 0.7874 -0.4064)
			(stroke
				(width 0.1524)
				(type default)
			)
			(layer "F.SilkS")
		)
		(fp_line
			(start 0.7874 -0.4064)
			(end 0.7874 0.4064)
			(stroke
				(width 0.1524)
				(type default)
			)
			(layer "F.SilkS")
		)
		(fp_line
			(start -0.67945 0.3048)
			(end -0.67945 -0.305054)
			(stroke
				(width 0.1)
				(type default)
			)
			(layer "F.Fab")
		)
		(fp_line
			(start -0.12065 0.3048)
			(end -0.67945 0.3048)
			(stroke
				(width 0.1)
				(type default)
			)
			(layer "F.Fab")
		)
		(fp_line
			(start 0.120396 0.3048)
			(end 0.120396 0.2794)
			(stroke
				(width 0.1)
				(type default)
			)
			(layer "F.Fab")
		)
		(fp_line
			(start 0.67945 0.3048)
			(end 0.120396 0.3048)
			(stroke
				(width 0.1)
				(type default)
			)
			(layer "F.Fab")
		)
		(fp_line
			(start -0.12065 0.2794)
			(end -0.12065 0.3048)
			(stroke
				(width 0.1)
				(type default)
			)
			(layer "F.Fab")
		)
		(fp_line
			(start 0.120396 0.2794)
			(end -0.12065 0.2794)
			(stroke
				(width 0.1)
				(type default)
			)
			(layer "F.Fab")
		)
		(fp_line
			(start -0.12065 -0.2794)
			(end 0.12065 -0.2794)
			(stroke
				(width 0.1)
				(type default)
			)
			(layer "F.Fab")
		)
		(fp_line
			(start 0.12065 -0.2794)
			(end 0.12065 -0.3048)
			(stroke
				(width 0.1)
				(type default)
			)
			(layer "F.Fab")
		)
		(fp_line
			(start 0.12065 -0.3048)
			(end 0.67945 -0.3048)
			(stroke
				(width 0.1)
				(type default)
			)
			(layer "F.Fab")
		)
		(fp_line
			(start 0.67945 -0.3048)
			(end 0.67945 0.3048)
			(stroke
				(width 0.1)
				(type default)
			)
			(layer "F.Fab")
		)
		(fp_line
			(start -0.67945 -0.305054)
			(end -0.12065 -0.305054)
			(stroke
				(width 0.1)
				(type default)
			)
			(layer "F.Fab")
		)
		(fp_line
			(start -0.12065 -0.305054)
			(end -0.12065 -0.2794)
			(stroke
				(width 0.1)
				(type default)
			)
			(layer "F.Fab")
		)
		(pad "1" smd circle
			(at -0.40005 0 270)
			(size 0 0)
			(layers "F.Cu" "F.Mask" "F.Paste")
			(net "PRSNT_NIC2_R_N")
		)
		(pad "2" smd circle
			(at 0.40005 0 270)
			(size 0 0)
			(layers "F.Cu" "F.Mask" "F.Paste")
			(net "GND")
		)
	)
	(footprint ""
		(layer "F.Cu")
		(at 188.534548 -30.94609 180)
		(property "Reference" "C296"
			(at 0 0 180)
			(layer "F.SilkS")
			(hide yes)
			(effects
				(font
					(size 1.27 1.27)
				)
			)
		)
		(property "Value" ""
			(at 0 0 180)
			(layer "F.Fab")
			(effects
				(font
					(size 1.27 1.27)
				)
			)
		)
		(duplicate_pad_numbers_are_jumpers no)
		(fp_line
			(start 0.299974 0.150114)
			(end -0.299974 0.150114)
			(stroke
				(width 0.1)
				(type default)
			)
			(layer "F.Fab")
		)
		(fp_line
			(start 0.299974 -0.150114)
			(end 0.299974 0.150114)
			(stroke
				(width 0.1)
				(type default)
			)
			(layer "F.Fab")
		)
		(fp_line
			(start -0.299974 0.150114)
			(end -0.299974 -0.150114)
			(stroke
				(width 0.1)
				(type default)
			)
			(layer "F.Fab")
		)
		(fp_line
			(start -0.299974 -0.150114)
			(end 0.299974 -0.150114)
			(stroke
				(width 0.1)
				(type default)
			)
			(layer "F.Fab")
		)
		(pad "1" smd rect
			(at -0.2667 0 180)
			(size 0.3048 0.381)
			(layers "F.Cu" "F.Mask" "F.Paste")
			(net "P5E_PEX1_STN2_TX_DP<37>")
		)
		(pad "2" smd rect
			(at 0.2667 0 180)
			(size 0.3048 0.381)
			(layers "F.Cu" "F.Mask" "F.Paste")
			(net "P5E_PEX1_STN2_TX_C_DP<37>")
		)
	)
	(footprint ""
		(layer "F.Cu")
		(at 400.543776 -44.87291)
		(property "Reference" "R650"
			(at 0 0 0)
			(layer "F.SilkS")
			(hide yes)
			(effects
				(font
					(size 1.27 1.27)
				)
			)
		)
		(property "Value" ""
			(at 0 0 0)
			(layer "F.Fab")
			(effects
				(font
					(size 1.27 1.27)
				)
			)
		)
		(duplicate_pad_numbers_are_jumpers no)
		(fp_line
			(start -0.7874 -0.4064)
			(end 0.7874 -0.4064)
			(stroke
				(width 0.1524)
				(type default)
			)
			(layer "F.SilkS")
		)
		(fp_line
			(start -0.7874 0.4064)
			(end -0.7874 -0.4064)
			(stroke
				(width 0.1524)
				(type default)
			)
			(layer "F.SilkS")
		)
		(fp_line
			(start 0.7874 -0.4064)
			(end 0.7874 0.4064)
			(stroke
				(width 0.1524)
				(type default)
			)
			(layer "F.SilkS")
		)
		(fp_line
			(start 0.7874 0.4064)
			(end -0.7874 0.4064)
			(stroke
				(width 0.1524)
				(type default)
			)
			(layer "F.SilkS")
		)
		(fp_line
			(start -0.67945 -0.305054)
			(end -0.12065 -0.305054)
			(stroke
				(width 0.1)
				(type default)
			)
			(layer "F.Fab")
		)
		(fp_line
			(start -0.67945 0.3048)
			(end -0.67945 -0.305054)
			(stroke
				(width 0.1)
				(type default)
			)
			(layer "F.Fab")
		)
		(fp_line
			(start -0.12065 -0.305054)
			(end -0.12065 -0.2794)
			(stroke
				(width 0.1)
				(type default)
			)
			(layer "F.Fab")
		)
		(fp_line
			(start -0.12065 -0.2794)
			(end 0.12065 -0.2794)
			(stroke
				(width 0.1)
				(type default)
			)
			(layer "F.Fab")
		)
		(fp_line
			(start -0.12065 0.2794)
			(end -0.12065 0.3048)
			(stroke
				(width 0.1)
				(type default)
			)
			(layer "F.Fab")
		)
		(fp_line
			(start -0.12065 0.3048)
			(end -0.67945 0.3048)
			(stroke
				(width 0.1)
				(type default)
			)
			(layer "F.Fab")
		)
		(fp_line
			(start 0.120396 0.2794)
			(end -0.12065 0.2794)
			(stroke
				(width 0.1)
				(type default)
			)
			(layer "F.Fab")
		)
		(fp_line
			(start 0.120396 0.3048)
			(end 0.120396 0.2794)
			(stroke
				(width 0.1)
				(type default)
			)
			(layer "F.Fab")
		)
		(fp_line
			(start 0.12065 -0.3048)
			(end 0.67945 -0.3048)
			(stroke
				(width 0.1)
				(type default)
			)
			(layer "F.Fab")
		)
		(fp_line
			(start 0.12065 -0.2794)
			(end 0.12065 -0.3048)
			(stroke
				(width 0.1)
				(type default)
			)
			(layer "F.Fab")
		)
		(fp_line
			(start 0.67945 -0.3048)
			(end 0.67945 0.3048)
			(stroke
				(width 0.1)
				(type default)
			)
			(layer "F.Fab")
		)
		(fp_line
			(start 0.67945 0.3048)
			(end 0.120396 0.3048)
			(stroke
				(width 0.1)
				(type default)
			)
			(layer "F.Fab")
		)
		(pad "1" smd circle
			(at -0.40005 0)
			(size 0 0)
			(layers "F.Cu" "F.Mask" "F.Paste")
			(net "SSD13_ADC_A0")
		)
		(pad "2" smd circle
			(at 0.40005 0)
			(size 0 0)
			(layers "F.Cu" "F.Mask" "F.Paste")
			(net "P3V3_AUX")
		)
	)
	(footprint ""
		(layer "F.Cu")
		(at 458.903324 -553.91304 180)
		(property "Reference" "SCREW_SSD14_2"
			(at -5.6007 -1.402334 0)
			(unlocked yes)
			(layer "B.SilkS")
			(effects
				(font
					(size 0.7874 0.5842)
					(thickness 0.1524)
				)
				(justify mirror)
			)
		)
		(property "Value" ""
			(at 0 0 180)
			(layer "F.Fab")
			(effects
				(font
					(size 1.27 1.27)
				)
			)
		)
		(duplicate_pad_numbers_are_jumpers no)
		(pad "1" thru_hole circle
			(at 0 0 180)
			(size 0.4572 0.4572)
			(drill 0.2032)
			(layers "*.Cu" "*.Mask")
			(remove_unused_layers no)
			(net "Net_9145")
			(clearance 0.127)
			(thermal_gap 0.127)
			(padstack
				(mode front_inner_back)
				(layer "Inner"
					(shape circle)
					(size 0.4572 0.4572)
					(clearance 0.127)
				)
				(layer "B.Cu"
					(shape circle)
					(size 0.508 0.508)
					(clearance 0.1016)
				)
			)
		)
	)
	(footprint ""
		(layer "F.Cu")
		(at 431.946812 -350.098614 90)
		(property "Reference" "C804"
			(at 0 0 90)
			(layer "F.SilkS")
			(hide yes)
			(effects
				(font
					(size 1.27 1.27)
				)
			)
		)
		(property "Value" ""
			(at 0 0 90)
			(layer "F.Fab")
			(effects
				(font
					(size 1.27 1.27)
				)
			)
		)
		(duplicate_pad_numbers_are_jumpers no)
		(fp_line
			(start 0.299974 -0.150114)
			(end 0.299974 0.150114)
			(stroke
				(width 0.1)
				(type default)
			)
			(layer "F.Fab")
		)
		(fp_line
			(start -0.299974 -0.150114)
			(end 0.299974 -0.150114)
			(stroke
				(width 0.1)
				(type default)
			)
			(layer "F.Fab")
		)
		(fp_line
			(start 0.299974 0.150114)
			(end -0.299974 0.150114)
			(stroke
				(width 0.1)
				(type default)
			)
			(layer "F.Fab")
		)
		(fp_line
			(start -0.299974 0.150114)
			(end -0.299974 -0.150114)
			(stroke
				(width 0.1)
				(type default)
			)
			(layer "F.Fab")
		)
		(pad "1" smd rect
			(at -0.2667 0 90)
			(size 0.3048 0.381)
			(layers "F.Cu" "F.Mask" "F.Paste")
			(net "P5E_PEX3_STN7_TX_DP<122>")
		)
		(pad "2" smd rect
			(at 0.2667 0 90)
			(size 0.3048 0.381)
			(layers "F.Cu" "F.Mask" "F.Paste")
			(net "P5E_PEX3_STN7_TX_C_DP<122>")
		)
	)
	(footprint ""
		(layer "F.Cu")
		(at 241.600736 -201.29627 180)
		(property "Reference" "R4859"
			(at 0 0 180)
			(layer "F.SilkS")
			(hide yes)
			(effects
				(font
					(size 1.27 1.27)
				)
			)
		)
		(property "Value" ""
			(at 0 0 180)
			(layer "F.Fab")
			(effects
				(font
					(size 1.27 1.27)
				)
			)
		)
		(duplicate_pad_numbers_are_jumpers no)
		(fp_line
			(start 0.7874 0.4064)
			(end -0.7874 0.4064)
			(stroke
				(width 0.1524)
				(type default)
			)
			(layer "F.SilkS")
		)
		(fp_line
			(start 0.7874 -0.4064)
			(end 0.7874 0.4064)
			(stroke
				(width 0.1524)
				(type default)
			)
			(layer "F.SilkS")
		)
		(fp_line
			(start -0.7874 0.4064)
			(end -0.7874 -0.4064)
			(stroke
				(width 0.1524)
				(type default)
			)
			(layer "F.SilkS")
		)
		(fp_line
			(start -0.7874 -0.4064)
			(end 0.7874 -0.4064)
			(stroke
				(width 0.1524)
				(type default)
			)
			(layer "F.SilkS")
		)
		(fp_line
			(start 0.67945 0.3048)
			(end 0.120396 0.3048)
			(stroke
				(width 0.1)
				(type default)
			)
			(layer "F.Fab")
		)
		(fp_line
			(start 0.67945 -0.3048)
			(end 0.67945 0.3048)
			(stroke
				(width 0.1)
				(type default)
			)
			(layer "F.Fab")
		)
		(fp_line
			(start 0.12065 -0.2794)
			(end 0.12065 -0.3048)
			(stroke
				(width 0.1)
				(type default)
			)
			(layer "F.Fab")
		)
		(fp_line
			(start 0.12065 -0.3048)
			(end 0.67945 -0.3048)
			(stroke
				(width 0.1)
				(type default)
			)
			(layer "F.Fab")
		)
		(fp_line
			(start 0.120396 0.3048)
			(end 0.120396 0.2794)
			(stroke
				(width 0.1)
				(type default)
			)
			(layer "F.Fab")
		)
		(fp_line
			(start 0.120396 0.2794)
			(end -0.12065 0.2794)
			(stroke
				(width 0.1)
				(type default)
			)
			(layer "F.Fab")
		)
		(fp_line
			(start -0.12065 0.3048)
			(end -0.67945 0.3048)
			(stroke
				(width 0.1)
				(type default)
			)
			(layer "F.Fab")
		)
		(fp_line
			(start -0.12065 0.2794)
			(end -0.12065 0.3048)
			(stroke
				(width 0.1)
				(type default)
			)
			(layer "F.Fab")
		)
		(fp_line
			(start -0.12065 -0.2794)
			(end 0.12065 -0.2794)
			(stroke
				(width 0.1)
				(type default)
			)
			(layer "F.Fab")
		)
		(fp_line
			(start -0.12065 -0.305054)
			(end -0.12065 -0.2794)
			(stroke
				(width 0.1)
				(type default)
			)
			(layer "F.Fab")
		)
		(fp_line
			(start -0.67945 0.3048)
			(end -0.67945 -0.305054)
			(stroke
				(width 0.1)
				(type default)
			)
			(layer "F.Fab")
		)
		(fp_line
			(start -0.67945 -0.305054)
			(end -0.12065 -0.305054)
			(stroke
				(width 0.1)
				(type default)
			)
			(layer "F.Fab")
		)
		(pad "1" smd circle
			(at -0.40005 0 180)
			(size 0 0)
			(layers "F.Cu" "F.Mask" "F.Paste")
			(net "P3V3_AUX")
		)
		(pad "2" smd circle
			(at 0.40005 0 180)
			(size 0 0)
			(layers "F.Cu" "F.Mask" "F.Paste")
			(net "PU_CLK_25M_BIC_EN")
		)
	)
	(footprint ""
		(layer "F.Cu")
		(at 287.056068 -32.848042 -90)
		(property "Reference" "R6090"
			(at 0 0 270)
			(layer "F.SilkS")
			(hide yes)
			(effects
				(font
					(size 1.27 1.27)
				)
			)
		)
		(property "Value" ""
			(at 0 0 270)
			(layer "F.Fab")
			(effects
				(font
					(size 1.27 1.27)
				)
			)
		)
		(duplicate_pad_numbers_are_jumpers no)
		(fp_line
			(start -0.7874 0.4064)
			(end -0.7874 -0.4064)
			(stroke
				(width 0.1524)
				(type default)
			)
			(layer "F.SilkS")
		)
		(fp_line
			(start 0.7874 0.4064)
			(end -0.7874 0.4064)
			(stroke
				(width 0.1524)
				(type default)
			)
			(layer "F.SilkS")
		)
		(fp_line
			(start -0.7874 -0.4064)
			(end 0.7874 -0.4064)
			(stroke
				(width 0.1524)
				(type default)
			)
			(layer "F.SilkS")
		)
		(fp_line
			(start 0.7874 -0.4064)
			(end 0.7874 0.4064)
			(stroke
				(width 0.1524)
				(type default)
			)
			(layer "F.SilkS")
		)
		(fp_line
			(start -0.67945 0.3048)
			(end -0.67945 -0.305054)
			(stroke
				(width 0.1)
				(type default)
			)
			(layer "F.Fab")
		)
		(fp_line
			(start -0.12065 0.3048)
			(end -0.67945 0.3048)
			(stroke
				(width 0.1)
				(type default)
			)
			(layer "F.Fab")
		)
		(fp_line
			(start 0.120396 0.3048)
			(end 0.120396 0.2794)
			(stroke
				(width 0.1)
				(type default)
			)
			(layer "F.Fab")
		)
		(fp_line
			(start 0.67945 0.3048)
			(end 0.120396 0.3048)
			(stroke
				(width 0.1)
				(type default)
			)
			(layer "F.Fab")
		)
		(fp_line
			(start -0.12065 0.2794)
			(end -0.12065 0.3048)
			(stroke
				(width 0.1)
				(type default)
			)
			(layer "F.Fab")
		)
		(fp_line
			(start 0.120396 0.2794)
			(end -0.12065 0.2794)
			(stroke
				(width 0.1)
				(type default)
			)
			(layer "F.Fab")
		)
		(fp_line
			(start -0.12065 -0.2794)
			(end 0.12065 -0.2794)
			(stroke
				(width 0.1)
				(type default)
			)
			(layer "F.Fab")
		)
		(fp_line
			(start 0.12065 -0.2794)
			(end 0.12065 -0.3048)
			(stroke
				(width 0.1)
				(type default)
			)
			(layer "F.Fab")
		)
		(fp_line
			(start 0.12065 -0.3048)
			(end 0.67945 -0.3048)
			(stroke
				(width 0.1)
				(type default)
			)
			(layer "F.Fab")
		)
		(fp_line
			(start 0.67945 -0.3048)
			(end 0.67945 0.3048)
			(stroke
				(width 0.1)
				(type default)
			)
			(layer "F.Fab")
		)
		(fp_line
			(start -0.67945 -0.305054)
			(end -0.12065 -0.305054)
			(stroke
				(width 0.1)
				(type default)
			)
			(layer "F.Fab")
		)
		(fp_line
			(start -0.12065 -0.305054)
			(end -0.12065 -0.2794)
			(stroke
				(width 0.1)
				(type default)
			)
			(layer "F.Fab")
		)
		(pad "1" smd circle
			(at -0.40005 0 270)
			(size 0 0)
			(layers "F.Cu" "F.Mask" "F.Paste")
			(net "SSD10_AUX_P3V3_EN_R")
		)
		(pad "2" smd circle
			(at 0.40005 0 270)
			(size 0 0)
			(layers "F.Cu" "F.Mask" "F.Paste")
			(net "P3V3_SSD10_CO_EN")
		)
	)
	(footprint ""
		(layer "F.Cu")
		(at 127.658114 -253.178564 180)
		(property "Reference" "PR7131"
			(at 0 0 180)
			(layer "F.SilkS")
			(hide yes)
			(effects
				(font
					(size 1.27 1.27)
				)
			)
		)
		(property "Value" ""
			(at 0 0 180)
			(layer "F.Fab")
			(effects
				(font
					(size 1.27 1.27)
				)
			)
		)
		(duplicate_pad_numbers_are_jumpers no)
		(fp_line
			(start 0.7874 0.4064)
			(end -0.7874 0.4064)
			(stroke
				(width 0.1524)
				(type default)
			)
			(layer "F.SilkS")
		)
		(fp_line
			(start 0.7874 -0.4064)
			(end 0.7874 0.4064)
			(stroke
				(width 0.1524)
				(type default)
			)
			(layer "F.SilkS")
		)
		(fp_line
			(start -0.7874 0.4064)
			(end -0.7874 -0.4064)
			(stroke
				(width 0.1524)
				(type default)
			)
			(layer "F.SilkS")
		)
		(fp_line
			(start -0.7874 -0.4064)
			(end 0.7874 -0.4064)
			(stroke
				(width 0.1524)
				(type default)
			)
			(layer "F.SilkS")
		)
		(fp_line
			(start 0.67945 0.3048)
			(end 0.120396 0.3048)
			(stroke
				(width 0.1)
				(type default)
			)
			(layer "F.Fab")
		)
		(fp_line
			(start 0.67945 -0.3048)
			(end 0.67945 0.3048)
			(stroke
				(width 0.1)
				(type default)
			)
			(layer "F.Fab")
		)
		(fp_line
			(start 0.12065 -0.2794)
			(end 0.12065 -0.3048)
			(stroke
				(width 0.1)
				(type default)
			)
			(layer "F.Fab")
		)
		(fp_line
			(start 0.12065 -0.3048)
			(end 0.67945 -0.3048)
			(stroke
				(width 0.1)
				(type default)
			)
			(layer "F.Fab")
		)
		(fp_line
			(start 0.120396 0.3048)
			(end 0.120396 0.2794)
			(stroke
				(width 0.1)
				(type default)
			)
			(layer "F.Fab")
		)
		(fp_line
			(start 0.120396 0.2794)
			(end -0.12065 0.2794)
			(stroke
				(width 0.1)
				(type default)
			)
			(layer "F.Fab")
		)
		(fp_line
			(start -0.12065 0.3048)
			(end -0.67945 0.3048)
			(stroke
				(width 0.1)
				(type default)
			)
			(layer "F.Fab")
		)
		(fp_line
			(start -0.12065 0.2794)
			(end -0.12065 0.3048)
			(stroke
				(width 0.1)
				(type default)
			)
			(layer "F.Fab")
		)
		(fp_line
			(start -0.12065 -0.2794)
			(end 0.12065 -0.2794)
			(stroke
				(width 0.1)
				(type default)
			)
			(layer "F.Fab")
		)
		(fp_line
			(start -0.12065 -0.305054)
			(end -0.12065 -0.2794)
			(stroke
				(width 0.1)
				(type default)
			)
			(layer "F.Fab")
		)
		(fp_line
			(start -0.67945 0.3048)
			(end -0.67945 -0.305054)
			(stroke
				(width 0.1)
				(type default)
			)
			(layer "F.Fab")
		)
		(fp_line
			(start -0.67945 -0.305054)
			(end -0.12065 -0.305054)
			(stroke
				(width 0.1)
				(type default)
			)
			(layer "F.Fab")
		)
		(pad "1" smd circle
			(at -0.40005 0 180)
			(size 0 0)
			(layers "F.Cu" "F.Mask" "F.Paste")
			(net "P3V3_AUX")
		)
		(pad "2" smd circle
			(at 0.40005 0 180)
			(size 0 0)
			(layers "F.Cu" "F.Mask" "F.Paste")
			(net "P0V8_PEX0_SMBALERT")
		)
	)
	(footprint ""
		(layer "F.Cu")
		(at 247.553988 -308.568852)
		(property "Reference" "PJ13"
			(at 0 0 0)
			(layer "F.SilkS")
			(hide yes)
			(effects
				(font
					(size 1.27 1.27)
				)
			)
		)
		(property "Value" ""
			(at 0 0 0)
			(layer "F.Fab")
			(effects
				(font
					(size 1.27 1.27)
				)
			)
		)
		(duplicate_pad_numbers_are_jumpers no)
		(pad "1" smd circle
			(at -0.40005 0 90)
			(size 0 0)
			(layers "F.Cu" "F.Mask" "F.Paste")
			(net "SH_P1V25_PEX2_FB_P")
		)
		(pad "2" smd rect
			(at 0.40005 0 180)
			(size 0.4572 0.508)
			(layers "F.Cu" "F.Mask" "F.Paste")
			(net "P1V25_PEX2")
		)
		(zone
			(layer "F.Cu")
			(hatch none 0.5)
			(connect_pads
				(clearance 0)
			)
			(min_thickness 0.25)
			(keepout
				(tracks allowed)
				(vias not_allowed)
				(pads allowed)
				(copperpour not_allowed)
				(footprints allowed)
			)
			(placement
				(enabled no)
				(sheetname "")
			)
			(fill
				(thermal_gap 0.5)
				(thermal_bridge_width 0.5)
				(island_removal_mode 0)
			)
			(polygon
				(pts
					(xy 246.868188 -308.264052) (xy 248.239788 -308.264052) (xy 248.239788 -308.873652) (xy 246.868188 -308.873652)
				)
			)
		)
	)
	(footprint ""
		(layer "F.Cu")
		(at 369.24742 -19.33956)
		(property "Reference" "C3958"
			(at 0 0 0)
			(layer "F.SilkS")
			(hide yes)
			(effects
				(font
					(size 1.27 1.27)
				)
			)
		)
		(property "Value" ""
			(at 0 0 0)
			(layer "F.Fab")
			(effects
				(font
					(size 1.27 1.27)
				)
			)
		)
		(duplicate_pad_numbers_are_jumpers no)
		(fp_line
			(start -0.7874 -0.4064)
			(end 0.7874 -0.4064)
			(stroke
				(width 0.1524)
				(type default)
			)
			(layer "F.SilkS")
		)
		(fp_line
			(start -0.7874 0.4064)
			(end -0.7874 -0.4064)
			(stroke
				(width 0.1524)
				(type default)
			)
			(layer "F.SilkS")
		)
		(fp_line
			(start 0.7874 -0.4064)
			(end 0.7874 0.4064)
			(stroke
				(width 0.1524)
				(type default)
			)
			(layer "F.SilkS")
		)
		(fp_line
			(start 0.7874 0.4064)
			(end -0.7874 0.4064)
			(stroke
				(width 0.1524)
				(type default)
			)
			(layer "F.SilkS")
		)
		(fp_line
			(start -0.67945 -0.305054)
			(end -0.12065 -0.305054)
			(stroke
				(width 0.1)
				(type default)
			)
			(layer "F.Fab")
		)
		(fp_line
			(start -0.67945 0.3048)
			(end -0.67945 -0.305054)
			(stroke
				(width 0.1)
				(type default)
			)
			(layer "F.Fab")
		)
		(fp_line
			(start -0.12065 -0.305054)
			(end -0.12065 -0.2794)
			(stroke
				(width 0.1)
				(type default)
			)
			(layer "F.Fab")
		)
		(fp_line
			(start -0.12065 -0.2794)
			(end 0.12065 -0.2794)
			(stroke
				(width 0.1)
				(type default)
			)
			(layer "F.Fab")
		)
		(fp_line
			(start -0.12065 0.2794)
			(end -0.12065 0.3048)
			(stroke
				(width 0.1)
				(type default)
			)
			(layer "F.Fab")
		)
		(fp_line
			(start -0.12065 0.3048)
			(end -0.67945 0.3048)
			(stroke
				(width 0.1)
				(type default)
			)
			(layer "F.Fab")
		)
		(fp_line
			(start 0.120396 0.2794)
			(end -0.12065 0.2794)
			(stroke
				(width 0.1)
				(type default)
			)
			(layer "F.Fab")
		)
		(fp_line
			(start 0.120396 0.3048)
			(end 0.120396 0.2794)
			(stroke
				(width 0.1)
				(type default)
			)
			(layer "F.Fab")
		)
		(fp_line
			(start 0.12065 -0.3048)
			(end 0.67945 -0.3048)
			(stroke
				(width 0.1)
				(type default)
			)
			(layer "F.Fab")
		)
		(fp_line
			(start 0.12065 -0.2794)
			(end 0.12065 -0.3048)
			(stroke
				(width 0.1)
				(type default)
			)
			(layer "F.Fab")
		)
		(fp_line
			(start 0.67945 -0.3048)
			(end 0.67945 0.3048)
			(stroke
				(width 0.1)
				(type default)
			)
			(layer "F.Fab")
		)
		(fp_line
			(start 0.67945 0.3048)
			(end 0.120396 0.3048)
			(stroke
				(width 0.1)
				(type default)
			)
			(layer "F.Fab")
		)
		(pad "1" smd circle
			(at -0.40005 0)
			(size 0 0)
			(layers "F.Cu" "F.Mask" "F.Paste")
			(net "P12V_SSD12")
		)
		(pad "2" smd circle
			(at 0.40005 0)
			(size 0 0)
			(layers "F.Cu" "F.Mask" "F.Paste")
			(net "GND")
		)
	)
	(footprint ""
		(layer "F.Cu")
		(at 300.059344 -86.132162)
		(property "Reference" "C198"
			(at 0 0 0)
			(layer "F.SilkS")
			(hide yes)
			(effects
				(font
					(size 1.27 1.27)
				)
			)
		)
		(property "Value" ""
			(at 0 0 0)
			(layer "F.Fab")
			(effects
				(font
					(size 1.27 1.27)
				)
			)
		)
		(duplicate_pad_numbers_are_jumpers no)
		(fp_line
			(start -0.7874 -0.4064)
			(end 0.7874 -0.4064)
			(stroke
				(width 0.1524)
				(type default)
			)
			(layer "F.SilkS")
		)
		(fp_line
			(start -0.7874 0.4064)
			(end -0.7874 -0.4064)
			(stroke
				(width 0.1524)
				(type default)
			)
			(layer "F.SilkS")
		)
		(fp_line
			(start 0.7874 -0.4064)
			(end 0.7874 0.4064)
			(stroke
				(width 0.1524)
				(type default)
			)
			(layer "F.SilkS")
		)
		(fp_line
			(start 0.7874 0.4064)
			(end -0.7874 0.4064)
			(stroke
				(width 0.1524)
				(type default)
			)
			(layer "F.SilkS")
		)
		(fp_line
			(start -0.67945 -0.305054)
			(end -0.12065 -0.305054)
			(stroke
				(width 0.1)
				(type default)
			)
			(layer "F.Fab")
		)
		(fp_line
			(start -0.67945 0.3048)
			(end -0.67945 -0.305054)
			(stroke
				(width 0.1)
				(type default)
			)
			(layer "F.Fab")
		)
		(fp_line
			(start -0.12065 -0.305054)
			(end -0.12065 -0.2794)
			(stroke
				(width 0.1)
				(type default)
			)
			(layer "F.Fab")
		)
		(fp_line
			(start -0.12065 -0.2794)
			(end 0.12065 -0.2794)
			(stroke
				(width 0.1)
				(type default)
			)
			(layer "F.Fab")
		)
		(fp_line
			(start -0.12065 0.2794)
			(end -0.12065 0.3048)
			(stroke
				(width 0.1)
				(type default)
			)
			(layer "F.Fab")
		)
		(fp_line
			(start -0.12065 0.3048)
			(end -0.67945 0.3048)
			(stroke
				(width 0.1)
				(type default)
			)
			(layer "F.Fab")
		)
		(fp_line
			(start 0.120396 0.2794)
			(end -0.12065 0.2794)
			(stroke
				(width 0.1)
				(type default)
			)
			(layer "F.Fab")
		)
		(fp_line
			(start 0.120396 0.3048)
			(end 0.120396 0.2794)
			(stroke
				(width 0.1)
				(type default)
			)
			(layer "F.Fab")
		)
		(fp_line
			(start 0.12065 -0.3048)
			(end 0.67945 -0.3048)
			(stroke
				(width 0.1)
				(type default)
			)
			(layer "F.Fab")
		)
		(fp_line
			(start 0.12065 -0.2794)
			(end 0.12065 -0.3048)
			(stroke
				(width 0.1)
				(type default)
			)
			(layer "F.Fab")
		)
		(fp_line
			(start 0.67945 -0.3048)
			(end 0.67945 0.3048)
			(stroke
				(width 0.1)
				(type default)
			)
			(layer "F.Fab")
		)
		(fp_line
			(start 0.67945 0.3048)
			(end 0.120396 0.3048)
			(stroke
				(width 0.1)
				(type default)
			)
			(layer "F.Fab")
		)
		(pad "1" smd circle
			(at -0.40005 0)
			(size 0 0)
			(layers "F.Cu" "F.Mask" "F.Paste")
			(net "P3V3_AUX")
		)
		(pad "2" smd circle
			(at 0.40005 0)
			(size 0 0)
			(layers "F.Cu" "F.Mask" "F.Paste")
			(net "GND")
		)
	)
	(footprint ""
		(layer "F.Cu")
		(at 145.734278 -387.660896)
		(property "Reference" "R6298"
			(at 0 0 0)
			(layer "F.SilkS")
			(hide yes)
			(effects
				(font
					(size 1.27 1.27)
				)
			)
		)
		(property "Value" ""
			(at 0 0 0)
			(layer "F.Fab")
			(effects
				(font
					(size 1.27 1.27)
				)
			)
		)
		(duplicate_pad_numbers_are_jumpers no)
		(fp_line
			(start -0.7874 -0.4064)
			(end 0.7874 -0.4064)
			(stroke
				(width 0.1524)
				(type default)
			)
			(layer "F.SilkS")
		)
		(fp_line
			(start -0.7874 0.4064)
			(end -0.7874 -0.4064)
			(stroke
				(width 0.1524)
				(type default)
			)
			(layer "F.SilkS")
		)
		(fp_line
			(start 0.7874 -0.4064)
			(end 0.7874 0.4064)
			(stroke
				(width 0.1524)
				(type default)
			)
			(layer "F.SilkS")
		)
		(fp_line
			(start 0.7874 0.4064)
			(end -0.7874 0.4064)
			(stroke
				(width 0.1524)
				(type default)
			)
			(layer "F.SilkS")
		)
		(fp_line
			(start -0.67945 -0.305054)
			(end -0.12065 -0.305054)
			(stroke
				(width 0.1)
				(type default)
			)
			(layer "F.Fab")
		)
		(fp_line
			(start -0.67945 0.3048)
			(end -0.67945 -0.305054)
			(stroke
				(width 0.1)
				(type default)
			)
			(layer "F.Fab")
		)
		(fp_line
			(start -0.12065 -0.305054)
			(end -0.12065 -0.2794)
			(stroke
				(width 0.1)
				(type default)
			)
			(layer "F.Fab")
		)
		(fp_line
			(start -0.12065 -0.2794)
			(end 0.12065 -0.2794)
			(stroke
				(width 0.1)
				(type default)
			)
			(layer "F.Fab")
		)
		(fp_line
			(start -0.12065 0.2794)
			(end -0.12065 0.3048)
			(stroke
				(width 0.1)
				(type default)
			)
			(layer "F.Fab")
		)
		(fp_line
			(start -0.12065 0.3048)
			(end -0.67945 0.3048)
			(stroke
				(width 0.1)
				(type default)
			)
			(layer "F.Fab")
		)
		(fp_line
			(start 0.120396 0.2794)
			(end -0.12065 0.2794)
			(stroke
				(width 0.1)
				(type default)
			)
			(layer "F.Fab")
		)
		(fp_line
			(start 0.120396 0.3048)
			(end 0.120396 0.2794)
			(stroke
				(width 0.1)
				(type default)
			)
			(layer "F.Fab")
		)
		(fp_line
			(start 0.12065 -0.3048)
			(end 0.67945 -0.3048)
			(stroke
				(width 0.1)
				(type default)
			)
			(layer "F.Fab")
		)
		(fp_line
			(start 0.12065 -0.2794)
			(end 0.12065 -0.3048)
			(stroke
				(width 0.1)
				(type default)
			)
			(layer "F.Fab")
		)
		(fp_line
			(start 0.67945 -0.3048)
			(end 0.67945 0.3048)
			(stroke
				(width 0.1)
				(type default)
			)
			(layer "F.Fab")
		)
		(fp_line
			(start 0.67945 0.3048)
			(end 0.120396 0.3048)
			(stroke
				(width 0.1)
				(type default)
			)
			(layer "F.Fab")
		)
		(pad "1" smd circle
			(at -0.40005 0)
			(size 0 0)
			(layers "F.Cu" "F.Mask" "F.Paste")
			(net "MB_BMC_MON")
		)
		(pad "2" smd circle
			(at 0.40005 0)
			(size 0 0)
			(layers "F.Cu" "F.Mask" "F.Paste")
			(net "GND")
		)
	)
	(footprint ""
		(layer "F.Cu")
		(at 6.521196 -378.533914 -90)
		(property "Reference" "R6737"
			(at 0 0 270)
			(layer "F.SilkS")
			(hide yes)
			(effects
				(font
					(size 1.27 1.27)
				)
			)
		)
		(property "Value" ""
			(at 0 0 270)
			(layer "F.Fab")
			(effects
				(font
					(size 1.27 1.27)
				)
			)
		)
		(duplicate_pad_numbers_are_jumpers no)
		(fp_line
			(start -0.7874 0.4064)
			(end -0.7874 -0.4064)
			(stroke
				(width 0.1524)
				(type default)
			)
			(layer "F.SilkS")
		)
		(fp_line
			(start 0.7874 0.4064)
			(end -0.7874 0.4064)
			(stroke
				(width 0.1524)
				(type default)
			)
			(layer "F.SilkS")
		)
		(fp_line
			(start -0.7874 -0.4064)
			(end 0.7874 -0.4064)
			(stroke
				(width 0.1524)
				(type default)
			)
			(layer "F.SilkS")
		)
		(fp_line
			(start 0.7874 -0.4064)
			(end 0.7874 0.4064)
			(stroke
				(width 0.1524)
				(type default)
			)
			(layer "F.SilkS")
		)
		(fp_line
			(start -0.67945 0.3048)
			(end -0.67945 -0.305054)
			(stroke
				(width 0.1)
				(type default)
			)
			(layer "F.Fab")
		)
		(fp_line
			(start -0.12065 0.3048)
			(end -0.67945 0.3048)
			(stroke
				(width 0.1)
				(type default)
			)
			(layer "F.Fab")
		)
		(fp_line
			(start 0.120396 0.3048)
			(end 0.120396 0.2794)
			(stroke
				(width 0.1)
				(type default)
			)
			(layer "F.Fab")
		)
		(fp_line
			(start 0.67945 0.3048)
			(end 0.120396 0.3048)
			(stroke
				(width 0.1)
				(type default)
			)
			(layer "F.Fab")
		)
		(fp_line
			(start -0.12065 0.2794)
			(end -0.12065 0.3048)
			(stroke
				(width 0.1)
				(type default)
			)
			(layer "F.Fab")
		)
		(fp_line
			(start 0.120396 0.2794)
			(end -0.12065 0.2794)
			(stroke
				(width 0.1)
				(type default)
			)
			(layer "F.Fab")
		)
		(fp_line
			(start -0.12065 -0.2794)
			(end 0.12065 -0.2794)
			(stroke
				(width 0.1)
				(type default)
			)
			(layer "F.Fab")
		)
		(fp_line
			(start 0.12065 -0.2794)
			(end 0.12065 -0.3048)
			(stroke
				(width 0.1)
				(type default)
			)
			(layer "F.Fab")
		)
		(fp_line
			(start 0.12065 -0.3048)
			(end 0.67945 -0.3048)
			(stroke
				(width 0.1)
				(type default)
			)
			(layer "F.Fab")
		)
		(fp_line
			(start 0.67945 -0.3048)
			(end 0.67945 0.3048)
			(stroke
				(width 0.1)
				(type default)
			)
			(layer "F.Fab")
		)
		(fp_line
			(start -0.67945 -0.305054)
			(end -0.12065 -0.305054)
			(stroke
				(width 0.1)
				(type default)
			)
			(layer "F.Fab")
		)
		(fp_line
			(start -0.12065 -0.305054)
			(end -0.12065 -0.2794)
			(stroke
				(width 0.1)
				(type default)
			)
			(layer "F.Fab")
		)
		(pad "1" smd circle
			(at -0.40005 0 270)
			(size 0 0)
			(layers "F.Cu" "F.Mask" "F.Paste")
			(net "BIC_USB_8042_HUB_R1")
		)
		(pad "2" smd circle
			(at 0.40005 0 270)
			(size 0 0)
			(layers "F.Cu" "F.Mask" "F.Paste")
			(net "GND")
		)
	)
	(footprint ""
		(layer "F.Cu")
		(at 452.909178 -109.432598 -90)
		(property "Reference" "PC827"
			(at 0 0 270)
			(layer "F.SilkS")
			(hide yes)
			(effects
				(font
					(size 1.27 1.27)
				)
			)
		)
		(property "Value" ""
			(at 0 0 270)
			(layer "F.Fab")
			(effects
				(font
					(size 1.27 1.27)
				)
			)
		)
		(duplicate_pad_numbers_are_jumpers no)
		(fp_line
			(start -0.7874 0.4064)
			(end -0.7874 -0.4064)
			(stroke
				(width 0.1524)
				(type default)
			)
			(layer "F.SilkS")
		)
		(fp_line
			(start 0.7874 0.4064)
			(end -0.7874 0.4064)
			(stroke
				(width 0.1524)
				(type default)
			)
			(layer "F.SilkS")
		)
		(fp_line
			(start -0.7874 -0.4064)
			(end 0.7874 -0.4064)
			(stroke
				(width 0.1524)
				(type default)
			)
			(layer "F.SilkS")
		)
		(fp_line
			(start 0.7874 -0.4064)
			(end 0.7874 0.4064)
			(stroke
				(width 0.1524)
				(type default)
			)
			(layer "F.SilkS")
		)
		(fp_line
			(start -0.67945 0.3048)
			(end -0.67945 -0.305054)
			(stroke
				(width 0.1)
				(type default)
			)
			(layer "F.Fab")
		)
		(fp_line
			(start -0.12065 0.3048)
			(end -0.67945 0.3048)
			(stroke
				(width 0.1)
				(type default)
			)
			(layer "F.Fab")
		)
		(fp_line
			(start 0.120396 0.3048)
			(end 0.120396 0.2794)
			(stroke
				(width 0.1)
				(type default)
			)
			(layer "F.Fab")
		)
		(fp_line
			(start 0.67945 0.3048)
			(end 0.120396 0.3048)
			(stroke
				(width 0.1)
				(type default)
			)
			(layer "F.Fab")
		)
		(fp_line
			(start -0.12065 0.2794)
			(end -0.12065 0.3048)
			(stroke
				(width 0.1)
				(type default)
			)
			(layer "F.Fab")
		)
		(fp_line
			(start 0.120396 0.2794)
			(end -0.12065 0.2794)
			(stroke
				(width 0.1)
				(type default)
			)
			(layer "F.Fab")
		)
		(fp_line
			(start -0.12065 -0.2794)
			(end 0.12065 -0.2794)
			(stroke
				(width 0.1)
				(type default)
			)
			(layer "F.Fab")
		)
		(fp_line
			(start 0.12065 -0.2794)
			(end 0.12065 -0.3048)
			(stroke
				(width 0.1)
				(type default)
			)
			(layer "F.Fab")
		)
		(fp_line
			(start 0.12065 -0.3048)
			(end 0.67945 -0.3048)
			(stroke
				(width 0.1)
				(type default)
			)
			(layer "F.Fab")
		)
		(fp_line
			(start 0.67945 -0.3048)
			(end 0.67945 0.3048)
			(stroke
				(width 0.1)
				(type default)
			)
			(layer "F.Fab")
		)
		(fp_line
			(start -0.67945 -0.305054)
			(end -0.12065 -0.305054)
			(stroke
				(width 0.1)
				(type default)
			)
			(layer "F.Fab")
		)
		(fp_line
			(start -0.12065 -0.305054)
			(end -0.12065 -0.2794)
			(stroke
				(width 0.1)
				(type default)
			)
			(layer "F.Fab")
		)
		(pad "1" smd circle
			(at -0.40005 0 270)
			(size 0 0)
			(layers "F.Cu" "F.Mask" "F.Paste")
			(net "P12V_NIC7_R")
		)
		(pad "2" smd circle
			(at 0.40005 0 270)
			(size 0 0)
			(layers "F.Cu" "F.Mask" "F.Paste")
			(net "GND")
		)
	)
	(footprint ""
		(layer "F.Cu")
		(at 260.12521 -338.426806 90)
		(property "Reference" "C4486"
			(at 0 0 90)
			(layer "F.SilkS")
			(hide yes)
			(effects
				(font
					(size 1.27 1.27)
				)
			)
		)
		(property "Value" ""
			(at 0 0 90)
			(layer "F.Fab")
			(effects
				(font
					(size 1.27 1.27)
				)
			)
		)
		(duplicate_pad_numbers_are_jumpers no)
		(fp_line
			(start 0.7874 -0.4064)
			(end 0.7874 0.4064)
			(stroke
				(width 0.1524)
				(type default)
			)
			(layer "F.SilkS")
		)
		(fp_line
			(start -0.7874 -0.4064)
			(end 0.7874 -0.4064)
			(stroke
				(width 0.1524)
				(type default)
			)
			(layer "F.SilkS")
		)
		(fp_line
			(start 0.7874 0.4064)
			(end -0.7874 0.4064)
			(stroke
				(width 0.1524)
				(type default)
			)
			(layer "F.SilkS")
		)
		(fp_line
			(start -0.7874 0.4064)
			(end -0.7874 -0.4064)
			(stroke
				(width 0.1524)
				(type default)
			)
			(layer "F.SilkS")
		)
		(fp_line
			(start -0.12065 -0.305054)
			(end -0.12065 -0.2794)
			(stroke
				(width 0.1)
				(type default)
			)
			(layer "F.Fab")
		)
		(fp_line
			(start -0.67945 -0.305054)
			(end -0.12065 -0.305054)
			(stroke
				(width 0.1)
				(type default)
			)
			(layer "F.Fab")
		)
		(fp_line
			(start 0.67945 -0.3048)
			(end 0.67945 0.3048)
			(stroke
				(width 0.1)
				(type default)
			)
			(layer "F.Fab")
		)
		(fp_line
			(start 0.12065 -0.3048)
			(end 0.67945 -0.3048)
			(stroke
				(width 0.1)
				(type default)
			)
			(layer "F.Fab")
		)
		(fp_line
			(start 0.12065 -0.2794)
			(end 0.12065 -0.3048)
			(stroke
				(width 0.1)
				(type default)
			)
			(layer "F.Fab")
		)
		(fp_line
			(start -0.12065 -0.2794)
			(end 0.12065 -0.2794)
			(stroke
				(width 0.1)
				(type default)
			)
			(layer "F.Fab")
		)
		(fp_line
			(start 0.120396 0.2794)
			(end -0.12065 0.2794)
			(stroke
				(width 0.1)
				(type default)
			)
			(layer "F.Fab")
		)
		(fp_line
			(start -0.12065 0.2794)
			(end -0.12065 0.3048)
			(stroke
				(width 0.1)
				(type default)
			)
			(layer "F.Fab")
		)
		(fp_line
			(start 0.67945 0.3048)
			(end 0.120396 0.3048)
			(stroke
				(width 0.1)
				(type default)
			)
			(layer "F.Fab")
		)
		(fp_line
			(start 0.120396 0.3048)
			(end 0.120396 0.2794)
			(stroke
				(width 0.1)
				(type default)
			)
			(layer "F.Fab")
		)
		(fp_line
			(start -0.12065 0.3048)
			(end -0.67945 0.3048)
			(stroke
				(width 0.1)
				(type default)
			)
			(layer "F.Fab")
		)
		(fp_line
			(start -0.67945 0.3048)
			(end -0.67945 -0.305054)
			(stroke
				(width 0.1)
				(type default)
			)
			(layer "F.Fab")
		)
		(pad "1" smd circle
			(at -0.40005 0 90)
			(size 0 0)
			(layers "F.Cu" "F.Mask" "F.Paste")
			(net "OC_P2V5_COMP")
		)
		(pad "2" smd circle
			(at 0.40005 0 90)
			(size 0 0)
			(layers "F.Cu" "F.Mask" "F.Paste")
			(net "GND")
		)
	)
	(footprint ""
		(layer "F.Cu")
		(at 219.014294 -178.09718)
		(property "Reference" "R5781"
			(at 0 0 0)
			(layer "F.SilkS")
			(hide yes)
			(effects
				(font
					(size 1.27 1.27)
				)
			)
		)
		(property "Value" ""
			(at 0 0 0)
			(layer "F.Fab")
			(effects
				(font
					(size 1.27 1.27)
				)
			)
		)
		(duplicate_pad_numbers_are_jumpers no)
		(fp_line
			(start -0.7874 -0.4064)
			(end 0.7874 -0.4064)
			(stroke
				(width 0.1524)
				(type default)
			)
			(layer "F.SilkS")
		)
		(fp_line
			(start -0.7874 0.4064)
			(end -0.7874 -0.4064)
			(stroke
				(width 0.1524)
				(type default)
			)
			(layer "F.SilkS")
		)
		(fp_line
			(start 0.7874 -0.4064)
			(end 0.7874 0.4064)
			(stroke
				(width 0.1524)
				(type default)
			)
			(layer "F.SilkS")
		)
		(fp_line
			(start 0.7874 0.4064)
			(end -0.7874 0.4064)
			(stroke
				(width 0.1524)
				(type default)
			)
			(layer "F.SilkS")
		)
		(fp_line
			(start -0.67945 -0.305054)
			(end -0.12065 -0.305054)
			(stroke
				(width 0.1)
				(type default)
			)
			(layer "F.Fab")
		)
		(fp_line
			(start -0.67945 0.3048)
			(end -0.67945 -0.305054)
			(stroke
				(width 0.1)
				(type default)
			)
			(layer "F.Fab")
		)
		(fp_line
			(start -0.12065 -0.305054)
			(end -0.12065 -0.2794)
			(stroke
				(width 0.1)
				(type default)
			)
			(layer "F.Fab")
		)
		(fp_line
			(start -0.12065 -0.2794)
			(end 0.12065 -0.2794)
			(stroke
				(width 0.1)
				(type default)
			)
			(layer "F.Fab")
		)
		(fp_line
			(start -0.12065 0.2794)
			(end -0.12065 0.3048)
			(stroke
				(width 0.1)
				(type default)
			)
			(layer "F.Fab")
		)
		(fp_line
			(start -0.12065 0.3048)
			(end -0.67945 0.3048)
			(stroke
				(width 0.1)
				(type default)
			)
			(layer "F.Fab")
		)
		(fp_line
			(start 0.120396 0.2794)
			(end -0.12065 0.2794)
			(stroke
				(width 0.1)
				(type default)
			)
			(layer "F.Fab")
		)
		(fp_line
			(start 0.120396 0.3048)
			(end 0.120396 0.2794)
			(stroke
				(width 0.1)
				(type default)
			)
			(layer "F.Fab")
		)
		(fp_line
			(start 0.12065 -0.3048)
			(end 0.67945 -0.3048)
			(stroke
				(width 0.1)
				(type default)
			)
			(layer "F.Fab")
		)
		(fp_line
			(start 0.12065 -0.2794)
			(end 0.12065 -0.3048)
			(stroke
				(width 0.1)
				(type default)
			)
			(layer "F.Fab")
		)
		(fp_line
			(start 0.67945 -0.3048)
			(end 0.67945 0.3048)
			(stroke
				(width 0.1)
				(type default)
			)
			(layer "F.Fab")
		)
		(fp_line
			(start 0.67945 0.3048)
			(end 0.120396 0.3048)
			(stroke
				(width 0.1)
				(type default)
			)
			(layer "F.Fab")
		)
		(pad "1" smd circle
			(at -0.40005 0)
			(size 0 0)
			(layers "F.Cu" "F.Mask" "F.Paste")
			(net "P3V3_AUX")
		)
		(pad "2" smd circle
			(at 0.40005 0)
			(size 0 0)
			(layers "F.Cu" "F.Mask" "F.Paste")
			(net "RST_FW_BIC_PLTRST")
		)
	)
	(footprint ""
		(layer "F.Cu")
		(at 262.281924 -289.790632 180)
		(property "Reference" "C3397"
			(at 0 0 180)
			(layer "F.SilkS")
			(hide yes)
			(effects
				(font
					(size 1.27 1.27)
				)
			)
		)
		(property "Value" ""
			(at 0 0 180)
			(layer "F.Fab")
			(effects
				(font
					(size 1.27 1.27)
				)
			)
		)
		(duplicate_pad_numbers_are_jumpers no)
		(fp_line
			(start 1.2954 0.5842)
			(end -1.2954 0.5842)
			(stroke
				(width 0.1524)
				(type default)
			)
			(layer "F.SilkS")
		)
		(fp_line
			(start 1.2954 -0.5842)
			(end 1.2954 0.5842)
			(stroke
				(width 0.1524)
				(type default)
			)
			(layer "F.SilkS")
		)
		(fp_line
			(start -1.2954 0.5842)
			(end -1.2954 -0.5842)
			(stroke
				(width 0.1524)
				(type default)
			)
			(layer "F.SilkS")
		)
		(fp_line
			(start -1.2954 -0.5842)
			(end 1.2954 -0.5842)
			(stroke
				(width 0.1524)
				(type default)
			)
			(layer "F.SilkS")
		)
		(fp_line
			(start 1.1938 0.4064)
			(end 0.8636 0.4064)
			(stroke
				(width 0.1)
				(type default)
			)
			(layer "F.Fab")
		)
		(fp_line
			(start 1.1938 -0.4064)
			(end 1.1938 0.4064)
			(stroke
				(width 0.1)
				(type default)
			)
			(layer "F.Fab")
		)
		(fp_line
			(start 0.8636 0.4572)
			(end -0.8636 0.4572)
			(stroke
				(width 0.1)
				(type default)
			)
			(layer "F.Fab")
		)
		(fp_line
			(start 0.8636 0.4064)
			(end 0.8636 0.4572)
			(stroke
				(width 0.1)
				(type default)
			)
			(layer "F.Fab")
		)
		(fp_line
			(start 0.8636 -0.4064)
			(end 1.1938 -0.4064)
			(stroke
				(width 0.1)
				(type default)
			)
			(layer "F.Fab")
		)
		(fp_line
			(start 0.8636 -0.4572)
			(end 0.8636 -0.4064)
			(stroke
				(width 0.1)
				(type default)
			)
			(layer "F.Fab")
		)
		(fp_line
			(start -0.8636 0.4572)
			(end -0.8636 0.4064)
			(stroke
				(width 0.1)
				(type default)
			)
			(layer "F.Fab")
		)
		(fp_line
			(start -0.8636 0.4064)
			(end -1.1938 0.4064)
			(stroke
				(width 0.1)
				(type default)
			)
			(layer "F.Fab")
		)
		(fp_line
			(start -0.8636 -0.4064)
			(end -0.8636 -0.4572)
			(stroke
				(width 0.1)
				(type default)
			)
			(layer "F.Fab")
		)
		(fp_line
			(start -0.8636 -0.4572)
			(end 0.8636 -0.4572)
			(stroke
				(width 0.1)
				(type default)
			)
			(layer "F.Fab")
		)
		(fp_line
			(start -1.1938 0.4064)
			(end -1.1938 -0.4064)
			(stroke
				(width 0.1)
				(type default)
			)
			(layer "F.Fab")
		)
		(fp_line
			(start -1.1938 -0.4064)
			(end -0.8636 -0.4064)
			(stroke
				(width 0.1)
				(type default)
			)
			(layer "F.Fab")
		)
		(pad "1" smd rect
			(at -0.7366 0 90)
			(size 0.7112 0.8128)
			(layers "F.Cu" "F.Mask" "F.Paste")
			(net "PCEPLL4_VDDA18_PEX2_R")
		)
		(pad "2" smd rect
			(at 0.7366 0 90)
			(size 0.7112 0.8128)
			(layers "F.Cu" "F.Mask" "F.Paste")
			(net "GND")
		)
	)
	(footprint ""
		(layer "F.Cu")
		(at 261.528306 -77.279754 -90)
		(property "Reference" "R1078"
			(at 0 0 270)
			(layer "F.SilkS")
			(hide yes)
			(effects
				(font
					(size 1.27 1.27)
				)
			)
		)
		(property "Value" ""
			(at 0 0 270)
			(layer "F.Fab")
			(effects
				(font
					(size 1.27 1.27)
				)
			)
		)
		(duplicate_pad_numbers_are_jumpers no)
		(fp_line
			(start -0.7874 0.4064)
			(end -0.7874 -0.4064)
			(stroke
				(width 0.1524)
				(type default)
			)
			(layer "F.SilkS")
		)
		(fp_line
			(start 0.7874 0.4064)
			(end -0.7874 0.4064)
			(stroke
				(width 0.1524)
				(type default)
			)
			(layer "F.SilkS")
		)
		(fp_line
			(start -0.7874 -0.4064)
			(end 0.7874 -0.4064)
			(stroke
				(width 0.1524)
				(type default)
			)
			(layer "F.SilkS")
		)
		(fp_line
			(start 0.7874 -0.4064)
			(end 0.7874 0.4064)
			(stroke
				(width 0.1524)
				(type default)
			)
			(layer "F.SilkS")
		)
		(fp_line
			(start -0.67945 0.3048)
			(end -0.67945 -0.305054)
			(stroke
				(width 0.1)
				(type default)
			)
			(layer "F.Fab")
		)
		(fp_line
			(start -0.12065 0.3048)
			(end -0.67945 0.3048)
			(stroke
				(width 0.1)
				(type default)
			)
			(layer "F.Fab")
		)
		(fp_line
			(start 0.120396 0.3048)
			(end 0.120396 0.2794)
			(stroke
				(width 0.1)
				(type default)
			)
			(layer "F.Fab")
		)
		(fp_line
			(start 0.67945 0.3048)
			(end 0.120396 0.3048)
			(stroke
				(width 0.1)
				(type default)
			)
			(layer "F.Fab")
		)
		(fp_line
			(start -0.12065 0.2794)
			(end -0.12065 0.3048)
			(stroke
				(width 0.1)
				(type default)
			)
			(layer "F.Fab")
		)
		(fp_line
			(start 0.120396 0.2794)
			(end -0.12065 0.2794)
			(stroke
				(width 0.1)
				(type default)
			)
			(layer "F.Fab")
		)
		(fp_line
			(start -0.12065 -0.2794)
			(end 0.12065 -0.2794)
			(stroke
				(width 0.1)
				(type default)
			)
			(layer "F.Fab")
		)
		(fp_line
			(start 0.12065 -0.2794)
			(end 0.12065 -0.3048)
			(stroke
				(width 0.1)
				(type default)
			)
			(layer "F.Fab")
		)
		(fp_line
			(start 0.12065 -0.3048)
			(end 0.67945 -0.3048)
			(stroke
				(width 0.1)
				(type default)
			)
			(layer "F.Fab")
		)
		(fp_line
			(start 0.67945 -0.3048)
			(end 0.67945 0.3048)
			(stroke
				(width 0.1)
				(type default)
			)
			(layer "F.Fab")
		)
		(fp_line
			(start -0.67945 -0.305054)
			(end -0.12065 -0.305054)
			(stroke
				(width 0.1)
				(type default)
			)
			(layer "F.Fab")
		)
		(fp_line
			(start -0.12065 -0.305054)
			(end -0.12065 -0.2794)
			(stroke
				(width 0.1)
				(type default)
			)
			(layer "F.Fab")
		)
		(pad "1" smd circle
			(at -0.40005 0 270)
			(size 0 0)
			(layers "F.Cu" "F.Mask" "F.Paste")
			(net "CLK_GEN_CK440_OE3_N")
		)
		(pad "2" smd circle
			(at 0.40005 0 270)
			(size 0 0)
			(layers "F.Cu" "F.Mask" "F.Paste")
			(net "P3V3")
		)
	)
	(footprint ""
		(layer "F.Cu")
		(at 331.07376 -103.668068)
		(property "Reference" "PC806"
			(at 0 0 0)
			(layer "F.SilkS")
			(hide yes)
			(effects
				(font
					(size 1.27 1.27)
				)
			)
		)
		(property "Value" ""
			(at 0 0 0)
			(layer "F.Fab")
			(effects
				(font
					(size 1.27 1.27)
				)
			)
		)
		(duplicate_pad_numbers_are_jumpers no)
		(fp_line
			(start -1.524 -0.762)
			(end 1.524 -0.762)
			(stroke
				(width 0.1524)
				(type default)
			)
			(layer "F.SilkS")
		)
		(fp_line
			(start -1.524 0.762)
			(end -1.524 -0.762)
			(stroke
				(width 0.1524)
				(type default)
			)
			(layer "F.SilkS")
		)
		(fp_line
			(start 1.524 -0.762)
			(end 1.524 0.762)
			(stroke
				(width 0.1524)
				(type default)
			)
			(layer "F.SilkS")
		)
		(fp_line
			(start 1.524 0.762)
			(end -1.524 0.762)
			(stroke
				(width 0.1524)
				(type default)
			)
			(layer "F.SilkS")
		)
		(fp_line
			(start -1.1049 -0.724916)
			(end -1.1049 0.724916)
			(stroke
				(width 0.1)
				(type default)
			)
			(layer "F.Fab")
		)
		(fp_line
			(start -1.1049 0.724916)
			(end 1.1049 0.724916)
			(stroke
				(width 0.1)
				(type default)
			)
			(layer "F.Fab")
		)
		(fp_line
			(start 1.1049 -0.724916)
			(end -1.1049 -0.724916)
			(stroke
				(width 0.1)
				(type default)
			)
			(layer "F.Fab")
		)
		(fp_line
			(start 1.1049 0.724916)
			(end 1.1049 -0.724916)
			(stroke
				(width 0.1)
				(type default)
			)
			(layer "F.Fab")
		)
		(pad "1" smd rect
			(at -0.889 0 180)
			(size 1.016 1.27)
			(layers "F.Cu" "F.Mask" "F.Paste")
			(net "P12V_NIC5_R")
		)
		(pad "2" smd rect
			(at 0.889 0 180)
			(size 1.016 1.27)
			(layers "F.Cu" "F.Mask" "F.Paste")
			(net "GND")
		)
	)
	(footprint ""
		(layer "F.Cu")
		(at 244.023642 -309.211218 90)
		(property "Reference" "PR178"
			(at 0 0 90)
			(layer "F.SilkS")
			(hide yes)
			(effects
				(font
					(size 1.27 1.27)
				)
			)
		)
		(property "Value" ""
			(at 0 0 90)
			(layer "F.Fab")
			(effects
				(font
					(size 1.27 1.27)
				)
			)
		)
		(duplicate_pad_numbers_are_jumpers no)
		(fp_line
			(start 0.7874 -0.4064)
			(end 0.7874 0.4064)
			(stroke
				(width 0.1524)
				(type default)
			)
			(layer "F.SilkS")
		)
		(fp_line
			(start -0.7874 -0.4064)
			(end 0.7874 -0.4064)
			(stroke
				(width 0.1524)
				(type default)
			)
			(layer "F.SilkS")
		)
		(fp_line
			(start 0.7874 0.4064)
			(end -0.7874 0.4064)
			(stroke
				(width 0.1524)
				(type default)
			)
			(layer "F.SilkS")
		)
		(fp_line
			(start -0.7874 0.4064)
			(end -0.7874 -0.4064)
			(stroke
				(width 0.1524)
				(type default)
			)
			(layer "F.SilkS")
		)
		(fp_line
			(start -0.12065 -0.305054)
			(end -0.12065 -0.2794)
			(stroke
				(width 0.1)
				(type default)
			)
			(layer "F.Fab")
		)
		(fp_line
			(start -0.67945 -0.305054)
			(end -0.12065 -0.305054)
			(stroke
				(width 0.1)
				(type default)
			)
			(layer "F.Fab")
		)
		(fp_line
			(start 0.67945 -0.3048)
			(end 0.67945 0.3048)
			(stroke
				(width 0.1)
				(type default)
			)
			(layer "F.Fab")
		)
		(fp_line
			(start 0.12065 -0.3048)
			(end 0.67945 -0.3048)
			(stroke
				(width 0.1)
				(type default)
			)
			(layer "F.Fab")
		)
		(fp_line
			(start 0.12065 -0.2794)
			(end 0.12065 -0.3048)
			(stroke
				(width 0.1)
				(type default)
			)
			(layer "F.Fab")
		)
		(fp_line
			(start -0.12065 -0.2794)
			(end 0.12065 -0.2794)
			(stroke
				(width 0.1)
				(type default)
			)
			(layer "F.Fab")
		)
		(fp_line
			(start 0.120396 0.2794)
			(end -0.12065 0.2794)
			(stroke
				(width 0.1)
				(type default)
			)
			(layer "F.Fab")
		)
		(fp_line
			(start -0.12065 0.2794)
			(end -0.12065 0.3048)
			(stroke
				(width 0.1)
				(type default)
			)
			(layer "F.Fab")
		)
		(fp_line
			(start 0.67945 0.3048)
			(end 0.120396 0.3048)
			(stroke
				(width 0.1)
				(type default)
			)
			(layer "F.Fab")
		)
		(fp_line
			(start 0.120396 0.3048)
			(end 0.120396 0.2794)
			(stroke
				(width 0.1)
				(type default)
			)
			(layer "F.Fab")
		)
		(fp_line
			(start -0.12065 0.3048)
			(end -0.67945 0.3048)
			(stroke
				(width 0.1)
				(type default)
			)
			(layer "F.Fab")
		)
		(fp_line
			(start -0.67945 0.3048)
			(end -0.67945 -0.305054)
			(stroke
				(width 0.1)
				(type default)
			)
			(layer "F.Fab")
		)
		(pad "1" smd circle
			(at -0.40005 0 90)
			(size 0 0)
			(layers "F.Cu" "F.Mask" "F.Paste")
			(net "SH_P1V25_PEX2_FB_N")
		)
		(pad "2" smd circle
			(at 0.40005 0 90)
			(size 0 0)
			(layers "F.Cu" "F.Mask" "F.Paste")
			(net "P1V25_PEX2_FB")
		)
	)
	(footprint ""
		(layer "F.Cu")
		(at 47.287688 -350.098614 90)
		(property "Reference" "C2178"
			(at 0 0 90)
			(layer "F.SilkS")
			(hide yes)
			(effects
				(font
					(size 1.27 1.27)
				)
			)
		)
		(property "Value" ""
			(at 0 0 90)
			(layer "F.Fab")
			(effects
				(font
					(size 1.27 1.27)
				)
			)
		)
		(duplicate_pad_numbers_are_jumpers no)
		(fp_line
			(start 0.299974 -0.150114)
			(end 0.299974 0.150114)
			(stroke
				(width 0.1)
				(type default)
			)
			(layer "F.Fab")
		)
		(fp_line
			(start -0.299974 -0.150114)
			(end 0.299974 -0.150114)
			(stroke
				(width 0.1)
				(type default)
			)
			(layer "F.Fab")
		)
		(fp_line
			(start 0.299974 0.150114)
			(end -0.299974 0.150114)
			(stroke
				(width 0.1)
				(type default)
			)
			(layer "F.Fab")
		)
		(fp_line
			(start -0.299974 0.150114)
			(end -0.299974 -0.150114)
			(stroke
				(width 0.1)
				(type default)
			)
			(layer "F.Fab")
		)
		(pad "1" smd rect
			(at -0.2667 0 90)
			(size 0.3048 0.381)
			(layers "F.Cu" "F.Mask" "F.Paste")
			(net "P5E_PEX0_STN4_TX_DP<66>")
		)
		(pad "2" smd rect
			(at 0.2667 0 90)
			(size 0.3048 0.381)
			(layers "F.Cu" "F.Mask" "F.Paste")
			(net "P5E_PEX0_STN4_TX_C_DP<66>")
		)
	)
	(footprint ""
		(layer "F.Cu")
		(at 172.626782 -53.697124 -90)
		(property "Reference" "PC522"
			(at 0 0 270)
			(layer "F.SilkS")
			(hide yes)
			(effects
				(font
					(size 1.27 1.27)
				)
			)
		)
		(property "Value" ""
			(at 0 0 270)
			(layer "F.Fab")
			(effects
				(font
					(size 1.27 1.27)
				)
			)
		)
		(duplicate_pad_numbers_are_jumpers no)
		(fp_line
			(start -0.7874 0.4064)
			(end -0.7874 -0.4064)
			(stroke
				(width 0.1524)
				(type default)
			)
			(layer "F.SilkS")
		)
		(fp_line
			(start 0.7874 0.4064)
			(end -0.7874 0.4064)
			(stroke
				(width 0.1524)
				(type default)
			)
			(layer "F.SilkS")
		)
		(fp_line
			(start -0.7874 -0.4064)
			(end 0.7874 -0.4064)
			(stroke
				(width 0.1524)
				(type default)
			)
			(layer "F.SilkS")
		)
		(fp_line
			(start 0.7874 -0.4064)
			(end 0.7874 0.4064)
			(stroke
				(width 0.1524)
				(type default)
			)
			(layer "F.SilkS")
		)
		(fp_line
			(start -0.67945 0.3048)
			(end -0.67945 -0.305054)
			(stroke
				(width 0.1)
				(type default)
			)
			(layer "F.Fab")
		)
		(fp_line
			(start -0.12065 0.3048)
			(end -0.67945 0.3048)
			(stroke
				(width 0.1)
				(type default)
			)
			(layer "F.Fab")
		)
		(fp_line
			(start 0.120396 0.3048)
			(end 0.120396 0.2794)
			(stroke
				(width 0.1)
				(type default)
			)
			(layer "F.Fab")
		)
		(fp_line
			(start 0.67945 0.3048)
			(end 0.120396 0.3048)
			(stroke
				(width 0.1)
				(type default)
			)
			(layer "F.Fab")
		)
		(fp_line
			(start -0.12065 0.2794)
			(end -0.12065 0.3048)
			(stroke
				(width 0.1)
				(type default)
			)
			(layer "F.Fab")
		)
		(fp_line
			(start 0.120396 0.2794)
			(end -0.12065 0.2794)
			(stroke
				(width 0.1)
				(type default)
			)
			(layer "F.Fab")
		)
		(fp_line
			(start -0.12065 -0.2794)
			(end 0.12065 -0.2794)
			(stroke
				(width 0.1)
				(type default)
			)
			(layer "F.Fab")
		)
		(fp_line
			(start 0.12065 -0.2794)
			(end 0.12065 -0.3048)
			(stroke
				(width 0.1)
				(type default)
			)
			(layer "F.Fab")
		)
		(fp_line
			(start 0.12065 -0.3048)
			(end 0.67945 -0.3048)
			(stroke
				(width 0.1)
				(type default)
			)
			(layer "F.Fab")
		)
		(fp_line
			(start 0.67945 -0.3048)
			(end 0.67945 0.3048)
			(stroke
				(width 0.1)
				(type default)
			)
			(layer "F.Fab")
		)
		(fp_line
			(start -0.67945 -0.305054)
			(end -0.12065 -0.305054)
			(stroke
				(width 0.1)
				(type default)
			)
			(layer "F.Fab")
		)
		(fp_line
			(start -0.12065 -0.305054)
			(end -0.12065 -0.2794)
			(stroke
				(width 0.1)
				(type default)
			)
			(layer "F.Fab")
		)
		(pad "1" smd circle
			(at -0.40005 0 270)
			(size 0 0)
			(layers "F.Cu" "F.Mask" "F.Paste")
			(net "P3V3_AUX")
		)
		(pad "2" smd circle
			(at 0.40005 0 270)
			(size 0 0)
			(layers "F.Cu" "F.Mask" "F.Paste")
			(net "GND")
		)
	)
	(footprint ""
		(layer "F.Cu")
		(at 245.931182 -125.144784 180)
		(property "Reference" "PU47"
			(at 2.516632 -2.944876 0)
			(unlocked yes)
			(layer "F.SilkS")
			(effects
				(font
					(size 0.7874 0.5842)
					(thickness 0.1524)
				)
				(justify left)
			)
		)
		(property "Value" ""
			(at 0 0 180)
			(layer "F.Fab")
			(effects
				(font
					(size 1.27 1.27)
				)
			)
		)
		(duplicate_pad_numbers_are_jumpers no)
		(fp_line
			(start 1.943608 1.549908)
			(end -1.943608 1.549908)
			(stroke
				(width 0.1524)
				(type default)
			)
			(layer "F.SilkS")
		)
		(fp_line
			(start 1.943608 -1.549908)
			(end 1.943608 1.549908)
			(stroke
				(width 0.1524)
				(type default)
			)
			(layer "F.SilkS")
		)
		(fp_line
			(start -1.943608 1.549908)
			(end -1.943608 -1.549908)
			(stroke
				(width 0.1524)
				(type default)
			)
			(layer "F.SilkS")
		)
		(fp_line
			(start -1.943608 -1.549908)
			(end 1.943608 -1.549908)
			(stroke
				(width 0.1524)
				(type default)
			)
			(layer "F.SilkS")
		)
		(fp_poly
			(pts
				(xy -2.019808 -1.549908) (xy -1.257808 -1.549908) (xy -1.257808 -1.880108) (xy -2.019808 -1.880108)
			)
			(stroke
				(width 0)
				(type default)
			)
			(fill yes)
			(layer "F.SilkS")
		)
		(fp_line
			(start 1.549908 1.549908)
			(end -1.549908 1.549908)
			(stroke
				(width 0.1)
				(type default)
			)
			(layer "F.Fab")
		)
		(fp_line
			(start 1.549908 -1.549908)
			(end 1.549908 1.549908)
			(stroke
				(width 0.1)
				(type default)
			)
			(layer "F.Fab")
		)
		(fp_line
			(start -1.549908 1.549908)
			(end -1.549908 -1.549908)
			(stroke
				(width 0.1)
				(type default)
			)
			(layer "F.Fab")
		)
		(fp_line
			(start -1.549908 -1.549908)
			(end 1.549908 -1.549908)
			(stroke
				(width 0.1)
				(type default)
			)
			(layer "F.Fab")
		)
		(fp_poly
			(pts
				(xy -2.019808 -1.549908) (xy -1.257808 -1.549908) (xy -1.257808 -1.880108) (xy -2.019808 -1.880108)
			)
			(stroke
				(width 0)
				(type default)
			)
			(fill yes)
			(layer "F.Fab")
		)
		(pad "1" smd rect
			(at -1.500124 -1.249934 90)
			(size 0.2794 0.6096)
			(layers "F.Cu" "F.Mask" "F.Paste")
			(net "P3V3_NIC4")
		)
		(pad "2" smd rect
			(at -1.500124 -0.750062 90)
			(size 0.2794 0.6096)
			(layers "F.Cu" "F.Mask" "F.Paste")
			(net "P3V3_NIC4")
		)
		(pad "3" smd rect
			(at -1.500124 -0.249936 90)
			(size 0.2794 0.6096)
			(layers "F.Cu" "F.Mask" "F.Paste")
			(net "P3V3_NIC4")
		)
		(pad "4" smd rect
			(at -1.500124 0.249936 90)
			(size 0.2794 0.6096)
			(layers "F.Cu" "F.Mask" "F.Paste")
			(net "P3V3_NIC4")
		)
		(pad "5" smd rect
			(at -1.500124 0.750062 90)
			(size 0.2794 0.6096)
			(layers "F.Cu" "F.Mask" "F.Paste")
			(net "P3V3_NIC4")
		)
		(pad "6" smd rect
			(at -1.500124 1.249934 90)
			(size 0.2794 0.6096)
			(layers "F.Cu" "F.Mask" "F.Paste")
			(net "GND")
		)
		(pad "7" smd rect
			(at 1.500124 1.249934 90)
			(size 0.2794 0.6096)
			(layers "F.Cu" "F.Mask" "F.Paste")
			(net "P3V3_NIC4_SS")
		)
		(pad "8" smd rect
			(at 1.500124 0.750062 90)
			(size 0.2794 0.6096)
			(layers "F.Cu" "F.Mask" "F.Paste")
			(net "PWRGD_P3V3_NIC4")
		)
		(pad "9" smd rect
			(at 1.500124 0.249936 90)
			(size 0.2794 0.6096)
			(layers "F.Cu" "F.Mask" "F.Paste")
			(net "P3V3_NIC4_OCP")
		)
		(pad "10" smd rect
			(at 1.500124 -0.249936 90)
			(size 0.2794 0.6096)
			(layers "F.Cu" "F.Mask" "F.Paste")
			(net "P5V_AUX")
		)
		(pad "11" smd rect
			(at 1.500124 -0.750062 90)
			(size 0.2794 0.6096)
			(layers "F.Cu" "F.Mask" "F.Paste")
			(net "HP_NIC4_EN")
		)
		(pad "12" smd rect
			(at 1.500124 -1.249934 90)
			(size 0.2794 0.6096)
			(layers "F.Cu" "F.Mask" "F.Paste")
			(net "P3V3_AUX")
		)
		(pad "13" smd rect
			(at 0 0 180)
			(size 1.9812 2.7178)
			(layers "F.Cu" "F.Mask" "F.Paste")
			(net "P3V3_AUX")
		)
		(zone
			(layer "F.Cu")
			(hatch none 0.5)
			(connect_pads
				(clearance 0)
			)
			(min_thickness 0.25)
			(keepout
				(tracks not_allowed)
				(vias allowed)
				(pads allowed)
				(copperpour not_allowed)
				(footprints allowed)
			)
			(placement
				(enabled no)
				(sheetname "")
			)
			(fill
				(thermal_gap 0.5)
				(thermal_bridge_width 0.5)
				(island_removal_mode 0)
			)
			(polygon
				(pts
					(xy 244.788182 -123.595384) (xy 244.788182 -123.722384) (xy 244.788182 -126.694184) (xy 244.788182 -126.694692)
					(xy 247.074182 -126.694692) (xy 247.074182 -126.694184) (xy 247.074182 -126.567184) (xy 247.074182 -125.144784)
					(xy 246.972582 -125.144784) (xy 246.972582 -126.567184) (xy 244.889782 -126.567184) (xy 244.889782 -123.722384)
					(xy 246.972582 -123.722384) (xy 246.972582 -125.119384) (xy 247.074182 -125.119384) (xy 247.074182 -123.722384)
					(xy 247.074182 -123.595384) (xy 247.074182 -123.594876) (xy 244.788182 -123.594876)
				)
			)
		)
	)
	(footprint ""
		(layer "F.Cu")
		(at 91.883992 -289.230816 90)
		(property "Reference" "R3891"
			(at 0 0 90)
			(layer "F.SilkS")
			(hide yes)
			(effects
				(font
					(size 1.27 1.27)
				)
			)
		)
		(property "Value" ""
			(at 0 0 90)
			(layer "F.Fab")
			(effects
				(font
					(size 1.27 1.27)
				)
			)
		)
		(duplicate_pad_numbers_are_jumpers no)
		(fp_line
			(start 0.7874 -0.4064)
			(end 0.7874 0.4064)
			(stroke
				(width 0.1524)
				(type default)
			)
			(layer "F.SilkS")
		)
		(fp_line
			(start -0.7874 -0.4064)
			(end 0.7874 -0.4064)
			(stroke
				(width 0.1524)
				(type default)
			)
			(layer "F.SilkS")
		)
		(fp_line
			(start 0.7874 0.4064)
			(end -0.7874 0.4064)
			(stroke
				(width 0.1524)
				(type default)
			)
			(layer "F.SilkS")
		)
		(fp_line
			(start -0.7874 0.4064)
			(end -0.7874 -0.4064)
			(stroke
				(width 0.1524)
				(type default)
			)
			(layer "F.SilkS")
		)
		(fp_line
			(start -0.12065 -0.305054)
			(end -0.12065 -0.2794)
			(stroke
				(width 0.1)
				(type default)
			)
			(layer "F.Fab")
		)
		(fp_line
			(start -0.67945 -0.305054)
			(end -0.12065 -0.305054)
			(stroke
				(width 0.1)
				(type default)
			)
			(layer "F.Fab")
		)
		(fp_line
			(start 0.67945 -0.3048)
			(end 0.67945 0.3048)
			(stroke
				(width 0.1)
				(type default)
			)
			(layer "F.Fab")
		)
		(fp_line
			(start 0.12065 -0.3048)
			(end 0.67945 -0.3048)
			(stroke
				(width 0.1)
				(type default)
			)
			(layer "F.Fab")
		)
		(fp_line
			(start 0.12065 -0.2794)
			(end 0.12065 -0.3048)
			(stroke
				(width 0.1)
				(type default)
			)
			(layer "F.Fab")
		)
		(fp_line
			(start -0.12065 -0.2794)
			(end 0.12065 -0.2794)
			(stroke
				(width 0.1)
				(type default)
			)
			(layer "F.Fab")
		)
		(fp_line
			(start 0.120396 0.2794)
			(end -0.12065 0.2794)
			(stroke
				(width 0.1)
				(type default)
			)
			(layer "F.Fab")
		)
		(fp_line
			(start -0.12065 0.2794)
			(end -0.12065 0.3048)
			(stroke
				(width 0.1)
				(type default)
			)
			(layer "F.Fab")
		)
		(fp_line
			(start 0.67945 0.3048)
			(end 0.120396 0.3048)
			(stroke
				(width 0.1)
				(type default)
			)
			(layer "F.Fab")
		)
		(fp_line
			(start 0.120396 0.3048)
			(end 0.120396 0.2794)
			(stroke
				(width 0.1)
				(type default)
			)
			(layer "F.Fab")
		)
		(fp_line
			(start -0.12065 0.3048)
			(end -0.67945 0.3048)
			(stroke
				(width 0.1)
				(type default)
			)
			(layer "F.Fab")
		)
		(fp_line
			(start -0.67945 0.3048)
			(end -0.67945 -0.305054)
			(stroke
				(width 0.1)
				(type default)
			)
			(layer "F.Fab")
		)
		(pad "1" smd circle
			(at -0.40005 0 90)
			(size 0 0)
			(layers "F.Cu" "F.Mask" "F.Paste")
			(net "SMB_PEX0_FPGA_SCL")
		)
		(pad "2" smd circle
			(at 0.40005 0 90)
			(size 0 0)
			(layers "F.Cu" "F.Mask" "F.Paste")
			(net "SMB_PEX0_HOST_LS_SCL")
		)
	)
	(footprint ""
		(layer "F.Cu")
		(at 72.672956 -22.867366 90)
		(property "Reference" "C3886"
			(at 0 0 90)
			(layer "F.SilkS")
			(hide yes)
			(effects
				(font
					(size 1.27 1.27)
				)
			)
		)
		(property "Value" ""
			(at 0 0 90)
			(layer "F.Fab")
			(effects
				(font
					(size 1.27 1.27)
				)
			)
		)
		(duplicate_pad_numbers_are_jumpers no)
		(fp_line
			(start 0.7874 -0.4064)
			(end 0.7874 0.4064)
			(stroke
				(width 0.1524)
				(type default)
			)
			(layer "F.SilkS")
		)
		(fp_line
			(start -0.7874 -0.4064)
			(end 0.7874 -0.4064)
			(stroke
				(width 0.1524)
				(type default)
			)
			(layer "F.SilkS")
		)
		(fp_line
			(start 0.7874 0.4064)
			(end -0.7874 0.4064)
			(stroke
				(width 0.1524)
				(type default)
			)
			(layer "F.SilkS")
		)
		(fp_line
			(start -0.7874 0.4064)
			(end -0.7874 -0.4064)
			(stroke
				(width 0.1524)
				(type default)
			)
			(layer "F.SilkS")
		)
		(fp_line
			(start -0.12065 -0.305054)
			(end -0.12065 -0.2794)
			(stroke
				(width 0.1)
				(type default)
			)
			(layer "F.Fab")
		)
		(fp_line
			(start -0.67945 -0.305054)
			(end -0.12065 -0.305054)
			(stroke
				(width 0.1)
				(type default)
			)
			(layer "F.Fab")
		)
		(fp_line
			(start 0.67945 -0.3048)
			(end 0.67945 0.3048)
			(stroke
				(width 0.1)
				(type default)
			)
			(layer "F.Fab")
		)
		(fp_line
			(start 0.12065 -0.3048)
			(end 0.67945 -0.3048)
			(stroke
				(width 0.1)
				(type default)
			)
			(layer "F.Fab")
		)
		(fp_line
			(start 0.12065 -0.2794)
			(end 0.12065 -0.3048)
			(stroke
				(width 0.1)
				(type default)
			)
			(layer "F.Fab")
		)
		(fp_line
			(start -0.12065 -0.2794)
			(end 0.12065 -0.2794)
			(stroke
				(width 0.1)
				(type default)
			)
			(layer "F.Fab")
		)
		(fp_line
			(start 0.120396 0.2794)
			(end -0.12065 0.2794)
			(stroke
				(width 0.1)
				(type default)
			)
			(layer "F.Fab")
		)
		(fp_line
			(start -0.12065 0.2794)
			(end -0.12065 0.3048)
			(stroke
				(width 0.1)
				(type default)
			)
			(layer "F.Fab")
		)
		(fp_line
			(start 0.67945 0.3048)
			(end 0.120396 0.3048)
			(stroke
				(width 0.1)
				(type default)
			)
			(layer "F.Fab")
		)
		(fp_line
			(start 0.120396 0.3048)
			(end 0.120396 0.2794)
			(stroke
				(width 0.1)
				(type default)
			)
			(layer "F.Fab")
		)
		(fp_line
			(start -0.12065 0.3048)
			(end -0.67945 0.3048)
			(stroke
				(width 0.1)
				(type default)
			)
			(layer "F.Fab")
		)
		(fp_line
			(start -0.67945 0.3048)
			(end -0.67945 -0.305054)
			(stroke
				(width 0.1)
				(type default)
			)
			(layer "F.Fab")
		)
		(pad "1" smd circle
			(at -0.40005 0 90)
			(size 0 0)
			(layers "F.Cu" "F.Mask" "F.Paste")
			(net "P12V_SSD2")
		)
		(pad "2" smd circle
			(at 0.40005 0 90)
			(size 0 0)
			(layers "F.Cu" "F.Mask" "F.Paste")
			(net "GND")
		)
	)
	(footprint ""
		(layer "F.Cu")
		(at 284.467046 -57.332626)
		(property "Reference" "R6832"
			(at 0 0 0)
			(layer "F.SilkS")
			(hide yes)
			(effects
				(font
					(size 1.27 1.27)
				)
			)
		)
		(property "Value" ""
			(at 0 0 0)
			(layer "F.Fab")
			(effects
				(font
					(size 1.27 1.27)
				)
			)
		)
		(duplicate_pad_numbers_are_jumpers no)
		(fp_line
			(start -0.7874 -0.4064)
			(end 0.7874 -0.4064)
			(stroke
				(width 0.1524)
				(type default)
			)
			(layer "F.SilkS")
		)
		(fp_line
			(start -0.7874 0.4064)
			(end -0.7874 -0.4064)
			(stroke
				(width 0.1524)
				(type default)
			)
			(layer "F.SilkS")
		)
		(fp_line
			(start 0.7874 -0.4064)
			(end 0.7874 0.4064)
			(stroke
				(width 0.1524)
				(type default)
			)
			(layer "F.SilkS")
		)
		(fp_line
			(start 0.7874 0.4064)
			(end -0.7874 0.4064)
			(stroke
				(width 0.1524)
				(type default)
			)
			(layer "F.SilkS")
		)
		(fp_line
			(start -0.67945 -0.305054)
			(end -0.12065 -0.305054)
			(stroke
				(width 0.1)
				(type default)
			)
			(layer "F.Fab")
		)
		(fp_line
			(start -0.67945 0.3048)
			(end -0.67945 -0.305054)
			(stroke
				(width 0.1)
				(type default)
			)
			(layer "F.Fab")
		)
		(fp_line
			(start -0.12065 -0.305054)
			(end -0.12065 -0.2794)
			(stroke
				(width 0.1)
				(type default)
			)
			(layer "F.Fab")
		)
		(fp_line
			(start -0.12065 -0.2794)
			(end 0.12065 -0.2794)
			(stroke
				(width 0.1)
				(type default)
			)
			(layer "F.Fab")
		)
		(fp_line
			(start -0.12065 0.2794)
			(end -0.12065 0.3048)
			(stroke
				(width 0.1)
				(type default)
			)
			(layer "F.Fab")
		)
		(fp_line
			(start -0.12065 0.3048)
			(end -0.67945 0.3048)
			(stroke
				(width 0.1)
				(type default)
			)
			(layer "F.Fab")
		)
		(fp_line
			(start 0.120396 0.2794)
			(end -0.12065 0.2794)
			(stroke
				(width 0.1)
				(type default)
			)
			(layer "F.Fab")
		)
		(fp_line
			(start 0.120396 0.3048)
			(end 0.120396 0.2794)
			(stroke
				(width 0.1)
				(type default)
			)
			(layer "F.Fab")
		)
		(fp_line
			(start 0.12065 -0.3048)
			(end 0.67945 -0.3048)
			(stroke
				(width 0.1)
				(type default)
			)
			(layer "F.Fab")
		)
		(fp_line
			(start 0.12065 -0.2794)
			(end 0.12065 -0.3048)
			(stroke
				(width 0.1)
				(type default)
			)
			(layer "F.Fab")
		)
		(fp_line
			(start 0.67945 -0.3048)
			(end 0.67945 0.3048)
			(stroke
				(width 0.1)
				(type default)
			)
			(layer "F.Fab")
		)
		(fp_line
			(start 0.67945 0.3048)
			(end 0.120396 0.3048)
			(stroke
				(width 0.1)
				(type default)
			)
			(layer "F.Fab")
		)
		(pad "1" smd circle
			(at -0.40005 0)
			(size 0 0)
			(layers "F.Cu" "F.Mask" "F.Paste")
			(net "SSD9_PWR_EN_R")
		)
		(pad "2" smd circle
			(at 0.40005 0)
			(size 0 0)
			(layers "F.Cu" "F.Mask" "F.Paste")
			(net "GND")
		)
	)
	(footprint ""
		(layer "F.Cu")
		(at 410.612082 -193.802508 -90)
		(property "Reference" "R6429"
			(at 0 0 270)
			(layer "F.SilkS")
			(hide yes)
			(effects
				(font
					(size 1.27 1.27)
				)
			)
		)
		(property "Value" ""
			(at 0 0 270)
			(layer "F.Fab")
			(effects
				(font
					(size 1.27 1.27)
				)
			)
		)
		(duplicate_pad_numbers_are_jumpers no)
		(fp_line
			(start -0.7874 0.4064)
			(end -0.7874 -0.4064)
			(stroke
				(width 0.1524)
				(type default)
			)
			(layer "F.SilkS")
		)
		(fp_line
			(start 0.7874 0.4064)
			(end -0.7874 0.4064)
			(stroke
				(width 0.1524)
				(type default)
			)
			(layer "F.SilkS")
		)
		(fp_line
			(start -0.7874 -0.4064)
			(end 0.7874 -0.4064)
			(stroke
				(width 0.1524)
				(type default)
			)
			(layer "F.SilkS")
		)
		(fp_line
			(start 0.7874 -0.4064)
			(end 0.7874 0.4064)
			(stroke
				(width 0.1524)
				(type default)
			)
			(layer "F.SilkS")
		)
		(fp_line
			(start -0.67945 0.3048)
			(end -0.67945 -0.305054)
			(stroke
				(width 0.1)
				(type default)
			)
			(layer "F.Fab")
		)
		(fp_line
			(start -0.12065 0.3048)
			(end -0.67945 0.3048)
			(stroke
				(width 0.1)
				(type default)
			)
			(layer "F.Fab")
		)
		(fp_line
			(start 0.120396 0.3048)
			(end 0.120396 0.2794)
			(stroke
				(width 0.1)
				(type default)
			)
			(layer "F.Fab")
		)
		(fp_line
			(start 0.67945 0.3048)
			(end 0.120396 0.3048)
			(stroke
				(width 0.1)
				(type default)
			)
			(layer "F.Fab")
		)
		(fp_line
			(start -0.12065 0.2794)
			(end -0.12065 0.3048)
			(stroke
				(width 0.1)
				(type default)
			)
			(layer "F.Fab")
		)
		(fp_line
			(start 0.120396 0.2794)
			(end -0.12065 0.2794)
			(stroke
				(width 0.1)
				(type default)
			)
			(layer "F.Fab")
		)
		(fp_line
			(start -0.12065 -0.2794)
			(end 0.12065 -0.2794)
			(stroke
				(width 0.1)
				(type default)
			)
			(layer "F.Fab")
		)
		(fp_line
			(start 0.12065 -0.2794)
			(end 0.12065 -0.3048)
			(stroke
				(width 0.1)
				(type default)
			)
			(layer "F.Fab")
		)
		(fp_line
			(start 0.12065 -0.3048)
			(end 0.67945 -0.3048)
			(stroke
				(width 0.1)
				(type default)
			)
			(layer "F.Fab")
		)
		(fp_line
			(start 0.67945 -0.3048)
			(end 0.67945 0.3048)
			(stroke
				(width 0.1)
				(type default)
			)
			(layer "F.Fab")
		)
		(fp_line
			(start -0.67945 -0.305054)
			(end -0.12065 -0.305054)
			(stroke
				(width 0.1)
				(type default)
			)
			(layer "F.Fab")
		)
		(fp_line
			(start -0.12065 -0.305054)
			(end -0.12065 -0.2794)
			(stroke
				(width 0.1)
				(type default)
			)
			(layer "F.Fab")
		)
		(pad "1" smd circle
			(at -0.40005 0 270)
			(size 0 0)
			(layers "F.Cu" "F.Mask" "F.Paste")
			(net "FPGA_PEX0_MODE_SEL1_ISO")
		)
		(pad "2" smd circle
			(at 0.40005 0 270)
			(size 0 0)
			(layers "F.Cu" "F.Mask" "F.Paste")
			(net "PEX0_MODE_SEL1")
		)
	)
	(footprint ""
		(layer "F.Cu")
		(at 249.733562 -212.638386 180)
		(property "Reference" "R4434"
			(at 0 0 180)
			(layer "F.SilkS")
			(hide yes)
			(effects
				(font
					(size 1.27 1.27)
				)
			)
		)
		(property "Value" ""
			(at 0 0 180)
			(layer "F.Fab")
			(effects
				(font
					(size 1.27 1.27)
				)
			)
		)
		(duplicate_pad_numbers_are_jumpers no)
		(fp_line
			(start 0.7874 0.4064)
			(end -0.7874 0.4064)
			(stroke
				(width 0.1524)
				(type default)
			)
			(layer "F.SilkS")
		)
		(fp_line
			(start 0.7874 -0.4064)
			(end 0.7874 0.4064)
			(stroke
				(width 0.1524)
				(type default)
			)
			(layer "F.SilkS")
		)
		(fp_line
			(start -0.7874 0.4064)
			(end -0.7874 -0.4064)
			(stroke
				(width 0.1524)
				(type default)
			)
			(layer "F.SilkS")
		)
		(fp_line
			(start -0.7874 -0.4064)
			(end 0.7874 -0.4064)
			(stroke
				(width 0.1524)
				(type default)
			)
			(layer "F.SilkS")
		)
		(fp_line
			(start 0.67945 0.3048)
			(end 0.120396 0.3048)
			(stroke
				(width 0.1)
				(type default)
			)
			(layer "F.Fab")
		)
		(fp_line
			(start 0.67945 -0.3048)
			(end 0.67945 0.3048)
			(stroke
				(width 0.1)
				(type default)
			)
			(layer "F.Fab")
		)
		(fp_line
			(start 0.12065 -0.2794)
			(end 0.12065 -0.3048)
			(stroke
				(width 0.1)
				(type default)
			)
			(layer "F.Fab")
		)
		(fp_line
			(start 0.12065 -0.3048)
			(end 0.67945 -0.3048)
			(stroke
				(width 0.1)
				(type default)
			)
			(layer "F.Fab")
		)
		(fp_line
			(start 0.120396 0.3048)
			(end 0.120396 0.2794)
			(stroke
				(width 0.1)
				(type default)
			)
			(layer "F.Fab")
		)
		(fp_line
			(start 0.120396 0.2794)
			(end -0.12065 0.2794)
			(stroke
				(width 0.1)
				(type default)
			)
			(layer "F.Fab")
		)
		(fp_line
			(start -0.12065 0.3048)
			(end -0.67945 0.3048)
			(stroke
				(width 0.1)
				(type default)
			)
			(layer "F.Fab")
		)
		(fp_line
			(start -0.12065 0.2794)
			(end -0.12065 0.3048)
			(stroke
				(width 0.1)
				(type default)
			)
			(layer "F.Fab")
		)
		(fp_line
			(start -0.12065 -0.2794)
			(end 0.12065 -0.2794)
			(stroke
				(width 0.1)
				(type default)
			)
			(layer "F.Fab")
		)
		(fp_line
			(start -0.12065 -0.305054)
			(end -0.12065 -0.2794)
			(stroke
				(width 0.1)
				(type default)
			)
			(layer "F.Fab")
		)
		(fp_line
			(start -0.67945 0.3048)
			(end -0.67945 -0.305054)
			(stroke
				(width 0.1)
				(type default)
			)
			(layer "F.Fab")
		)
		(fp_line
			(start -0.67945 -0.305054)
			(end -0.12065 -0.305054)
			(stroke
				(width 0.1)
				(type default)
			)
			(layer "F.Fab")
		)
		(pad "1" smd circle
			(at -0.40005 0 180)
			(size 0 0)
			(layers "F.Cu" "F.Mask" "F.Paste")
			(net "P1V2_AUX_ADJ")
		)
		(pad "2" smd circle
			(at 0.40005 0 180)
			(size 0 0)
			(layers "F.Cu" "F.Mask" "F.Paste")
			(net "GND")
		)
	)
	(footprint ""
		(layer "F.Cu")
		(at 213.896194 -47.20082 90)
		(property "Reference" "C319"
			(at 0 0 90)
			(layer "F.SilkS")
			(hide yes)
			(effects
				(font
					(size 1.27 1.27)
				)
			)
		)
		(property "Value" ""
			(at 0 0 90)
			(layer "F.Fab")
			(effects
				(font
					(size 1.27 1.27)
				)
			)
		)
		(duplicate_pad_numbers_are_jumpers no)
		(fp_line
			(start 0.7874 -0.4064)
			(end 0.7874 0.4064)
			(stroke
				(width 0.1524)
				(type default)
			)
			(layer "F.SilkS")
		)
		(fp_line
			(start -0.7874 -0.4064)
			(end 0.7874 -0.4064)
			(stroke
				(width 0.1524)
				(type default)
			)
			(layer "F.SilkS")
		)
		(fp_line
			(start 0.7874 0.4064)
			(end -0.7874 0.4064)
			(stroke
				(width 0.1524)
				(type default)
			)
			(layer "F.SilkS")
		)
		(fp_line
			(start -0.7874 0.4064)
			(end -0.7874 -0.4064)
			(stroke
				(width 0.1524)
				(type default)
			)
			(layer "F.SilkS")
		)
		(fp_line
			(start -0.12065 -0.305054)
			(end -0.12065 -0.2794)
			(stroke
				(width 0.1)
				(type default)
			)
			(layer "F.Fab")
		)
		(fp_line
			(start -0.67945 -0.305054)
			(end -0.12065 -0.305054)
			(stroke
				(width 0.1)
				(type default)
			)
			(layer "F.Fab")
		)
		(fp_line
			(start 0.67945 -0.3048)
			(end 0.67945 0.3048)
			(stroke
				(width 0.1)
				(type default)
			)
			(layer "F.Fab")
		)
		(fp_line
			(start 0.12065 -0.3048)
			(end 0.67945 -0.3048)
			(stroke
				(width 0.1)
				(type default)
			)
			(layer "F.Fab")
		)
		(fp_line
			(start 0.12065 -0.2794)
			(end 0.12065 -0.3048)
			(stroke
				(width 0.1)
				(type default)
			)
			(layer "F.Fab")
		)
		(fp_line
			(start -0.12065 -0.2794)
			(end 0.12065 -0.2794)
			(stroke
				(width 0.1)
				(type default)
			)
			(layer "F.Fab")
		)
		(fp_line
			(start 0.120396 0.2794)
			(end -0.12065 0.2794)
			(stroke
				(width 0.1)
				(type default)
			)
			(layer "F.Fab")
		)
		(fp_line
			(start -0.12065 0.2794)
			(end -0.12065 0.3048)
			(stroke
				(width 0.1)
				(type default)
			)
			(layer "F.Fab")
		)
		(fp_line
			(start 0.67945 0.3048)
			(end 0.120396 0.3048)
			(stroke
				(width 0.1)
				(type default)
			)
			(layer "F.Fab")
		)
		(fp_line
			(start 0.120396 0.3048)
			(end 0.120396 0.2794)
			(stroke
				(width 0.1)
				(type default)
			)
			(layer "F.Fab")
		)
		(fp_line
			(start -0.12065 0.3048)
			(end -0.67945 0.3048)
			(stroke
				(width 0.1)
				(type default)
			)
			(layer "F.Fab")
		)
		(fp_line
			(start -0.67945 0.3048)
			(end -0.67945 -0.305054)
			(stroke
				(width 0.1)
				(type default)
			)
			(layer "F.Fab")
		)
		(pad "1" smd circle
			(at -0.40005 0 90)
			(size 0 0)
			(layers "F.Cu" "F.Mask" "F.Paste")
			(net "P12V_SSD7_R")
		)
		(pad "2" smd circle
			(at 0.40005 0 90)
			(size 0 0)
			(layers "F.Cu" "F.Mask" "F.Paste")
			(net "GND")
		)
	)
	(footprint ""
		(layer "F.Cu")
		(at 168.343834 -49.95291 180)
		(property "Reference" "R566"
			(at 0 0 180)
			(layer "F.SilkS")
			(hide yes)
			(effects
				(font
					(size 1.27 1.27)
				)
			)
		)
		(property "Value" ""
			(at 0 0 180)
			(layer "F.Fab")
			(effects
				(font
					(size 1.27 1.27)
				)
			)
		)
		(duplicate_pad_numbers_are_jumpers no)
		(fp_line
			(start 0.7874 0.4064)
			(end -0.7874 0.4064)
			(stroke
				(width 0.1524)
				(type default)
			)
			(layer "F.SilkS")
		)
		(fp_line
			(start 0.7874 -0.4064)
			(end 0.7874 0.4064)
			(stroke
				(width 0.1524)
				(type default)
			)
			(layer "F.SilkS")
		)
		(fp_line
			(start -0.7874 0.4064)
			(end -0.7874 -0.4064)
			(stroke
				(width 0.1524)
				(type default)
			)
			(layer "F.SilkS")
		)
		(fp_line
			(start -0.7874 -0.4064)
			(end 0.7874 -0.4064)
			(stroke
				(width 0.1524)
				(type default)
			)
			(layer "F.SilkS")
		)
		(fp_line
			(start 0.67945 0.3048)
			(end 0.120396 0.3048)
			(stroke
				(width 0.1)
				(type default)
			)
			(layer "F.Fab")
		)
		(fp_line
			(start 0.67945 -0.3048)
			(end 0.67945 0.3048)
			(stroke
				(width 0.1)
				(type default)
			)
			(layer "F.Fab")
		)
		(fp_line
			(start 0.12065 -0.2794)
			(end 0.12065 -0.3048)
			(stroke
				(width 0.1)
				(type default)
			)
			(layer "F.Fab")
		)
		(fp_line
			(start 0.12065 -0.3048)
			(end 0.67945 -0.3048)
			(stroke
				(width 0.1)
				(type default)
			)
			(layer "F.Fab")
		)
		(fp_line
			(start 0.120396 0.3048)
			(end 0.120396 0.2794)
			(stroke
				(width 0.1)
				(type default)
			)
			(layer "F.Fab")
		)
		(fp_line
			(start 0.120396 0.2794)
			(end -0.12065 0.2794)
			(stroke
				(width 0.1)
				(type default)
			)
			(layer "F.Fab")
		)
		(fp_line
			(start -0.12065 0.3048)
			(end -0.67945 0.3048)
			(stroke
				(width 0.1)
				(type default)
			)
			(layer "F.Fab")
		)
		(fp_line
			(start -0.12065 0.2794)
			(end -0.12065 0.3048)
			(stroke
				(width 0.1)
				(type default)
			)
			(layer "F.Fab")
		)
		(fp_line
			(start -0.12065 -0.2794)
			(end 0.12065 -0.2794)
			(stroke
				(width 0.1)
				(type default)
			)
			(layer "F.Fab")
		)
		(fp_line
			(start -0.12065 -0.305054)
			(end -0.12065 -0.2794)
			(stroke
				(width 0.1)
				(type default)
			)
			(layer "F.Fab")
		)
		(fp_line
			(start -0.67945 0.3048)
			(end -0.67945 -0.305054)
			(stroke
				(width 0.1)
				(type default)
			)
			(layer "F.Fab")
		)
		(fp_line
			(start -0.67945 -0.305054)
			(end -0.12065 -0.305054)
			(stroke
				(width 0.1)
				(type default)
			)
			(layer "F.Fab")
		)
		(pad "1" smd circle
			(at -0.40005 0 180)
			(size 0 0)
			(layers "F.Cu" "F.Mask" "F.Paste")
			(net "SMB_BIC_I2C6_MUX_SSD_0_7_ADC_R_SCL")
		)
		(pad "2" smd circle
			(at 0.40005 0 180)
			(size 0 0)
			(layers "F.Cu" "F.Mask" "F.Paste")
			(net "SMB_SSD5_ADC_SCL")
		)
	)
	(footprint ""
		(layer "F.Cu")
		(at 231.460294 -180.28158)
		(property "Reference" "Q56"
			(at -3.977894 0.55245 0)
			(unlocked yes)
			(layer "F.SilkS")
			(effects
				(font
					(size 0.7874 0.5842)
					(thickness 0.1524)
				)
				(justify left)
			)
		)
		(property "Value" ""
			(at 0 0 0)
			(layer "F.Fab")
			(effects
				(font
					(size 1.27 1.27)
				)
			)
		)
		(duplicate_pad_numbers_are_jumpers no)
		(fp_line
			(start -1.584198 -1.53416)
			(end 1.584198 -1.53416)
			(stroke
				(width 0.1524)
				(type default)
			)
			(layer "F.SilkS")
		)
		(fp_line
			(start -1.584198 1.53416)
			(end -1.584198 -1.53416)
			(stroke
				(width 0.1524)
				(type default)
			)
			(layer "F.SilkS")
		)
		(fp_line
			(start 1.584198 -1.53416)
			(end 1.584198 1.53416)
			(stroke
				(width 0.1524)
				(type default)
			)
			(layer "F.SilkS")
		)
		(fp_line
			(start 1.584198 1.53416)
			(end -1.584198 1.53416)
			(stroke
				(width 0.1524)
				(type default)
			)
			(layer "F.SilkS")
		)
		(fp_line
			(start -0.700024 -1.500124)
			(end 0.700024 -1.500124)
			(stroke
				(width 0.1)
				(type default)
			)
			(layer "F.Fab")
		)
		(fp_line
			(start -0.700024 1.500124)
			(end -0.700024 -1.500124)
			(stroke
				(width 0.1)
				(type default)
			)
			(layer "F.Fab")
		)
		(fp_line
			(start 0.700024 -1.500124)
			(end 0.700024 1.500124)
			(stroke
				(width 0.1)
				(type default)
			)
			(layer "F.Fab")
		)
		(fp_line
			(start 0.700024 1.500124)
			(end -0.700024 1.500124)
			(stroke
				(width 0.1)
				(type default)
			)
			(layer "F.Fab")
		)
		(pad "B" smd rect
			(at -0.999998 -0.94996 90)
			(size 0.8128 0.9144)
			(layers "F.Cu" "F.Mask" "F.Paste")
			(net "RST_BJT_Q15_C")
		)
		(pad "C" smd rect
			(at 0.999998 0 90)
			(size 0.8128 0.9144)
			(layers "F.Cu" "F.Mask" "F.Paste")
			(net "RST_BIC_EXTRST_R_N")
		)
		(pad "E" smd rect
			(at -0.999998 0.94996 90)
			(size 0.8128 0.9144)
			(layers "F.Cu" "F.Mask" "F.Paste")
			(net "GND")
		)
	)
	(footprint ""
		(layer "F.Cu")
		(at 363.474 -215.011)
		(property "Reference" "R4610"
			(at 0 0 0)
			(layer "F.SilkS")
			(hide yes)
			(effects
				(font
					(size 1.27 1.27)
				)
			)
		)
		(property "Value" ""
			(at 0 0 0)
			(layer "F.Fab")
			(effects
				(font
					(size 1.27 1.27)
				)
			)
		)
		(duplicate_pad_numbers_are_jumpers no)
		(fp_line
			(start -0.7874 -0.4064)
			(end 0.7874 -0.4064)
			(stroke
				(width 0.1524)
				(type default)
			)
			(layer "F.SilkS")
		)
		(fp_line
			(start -0.7874 0.4064)
			(end -0.7874 -0.4064)
			(stroke
				(width 0.1524)
				(type default)
			)
			(layer "F.SilkS")
		)
		(fp_line
			(start 0.7874 -0.4064)
			(end 0.7874 0.4064)
			(stroke
				(width 0.1524)
				(type default)
			)
			(layer "F.SilkS")
		)
		(fp_line
			(start 0.7874 0.4064)
			(end -0.7874 0.4064)
			(stroke
				(width 0.1524)
				(type default)
			)
			(layer "F.SilkS")
		)
		(fp_line
			(start -0.67945 -0.305054)
			(end -0.12065 -0.305054)
			(stroke
				(width 0.1)
				(type default)
			)
			(layer "F.Fab")
		)
		(fp_line
			(start -0.67945 0.3048)
			(end -0.67945 -0.305054)
			(stroke
				(width 0.1)
				(type default)
			)
			(layer "F.Fab")
		)
		(fp_line
			(start -0.12065 -0.305054)
			(end -0.12065 -0.2794)
			(stroke
				(width 0.1)
				(type default)
			)
			(layer "F.Fab")
		)
		(fp_line
			(start -0.12065 -0.2794)
			(end 0.12065 -0.2794)
			(stroke
				(width 0.1)
				(type default)
			)
			(layer "F.Fab")
		)
		(fp_line
			(start -0.12065 0.2794)
			(end -0.12065 0.3048)
			(stroke
				(width 0.1)
				(type default)
			)
			(layer "F.Fab")
		)
		(fp_line
			(start -0.12065 0.3048)
			(end -0.67945 0.3048)
			(stroke
				(width 0.1)
				(type default)
			)
			(layer "F.Fab")
		)
		(fp_line
			(start 0.120396 0.2794)
			(end -0.12065 0.2794)
			(stroke
				(width 0.1)
				(type default)
			)
			(layer "F.Fab")
		)
		(fp_line
			(start 0.120396 0.3048)
			(end 0.120396 0.2794)
			(stroke
				(width 0.1)
				(type default)
			)
			(layer "F.Fab")
		)
		(fp_line
			(start 0.12065 -0.3048)
			(end 0.67945 -0.3048)
			(stroke
				(width 0.1)
				(type default)
			)
			(layer "F.Fab")
		)
		(fp_line
			(start 0.12065 -0.2794)
			(end 0.12065 -0.3048)
			(stroke
				(width 0.1)
				(type default)
			)
			(layer "F.Fab")
		)
		(fp_line
			(start 0.67945 -0.3048)
			(end 0.67945 0.3048)
			(stroke
				(width 0.1)
				(type default)
			)
			(layer "F.Fab")
		)
		(fp_line
			(start 0.67945 0.3048)
			(end 0.120396 0.3048)
			(stroke
				(width 0.1)
				(type default)
			)
			(layer "F.Fab")
		)
		(pad "1" smd circle
			(at -0.40005 0)
			(size 0 0)
			(layers "F.Cu" "F.Mask" "F.Paste")
			(net "PEX0_PCA9555_INT_N")
		)
		(pad "2" smd circle
			(at 0.40005 0)
			(size 0 0)
			(layers "F.Cu" "F.Mask" "F.Paste")
			(net "PEX0_PCA9555_0_INT_N")
		)
	)
	(footprint ""
		(layer "F.Cu")
		(at 428.424594 -84.476336 180)
		(property "Reference" "U46"
			(at -2.767076 -0.503936 90)
			(unlocked yes)
			(layer "F.SilkS")
			(effects
				(font
					(size 0.7874 0.5842)
					(thickness 0.1524)
				)
				(justify left)
			)
		)
		(property "Value" ""
			(at 0 0 180)
			(layer "F.Fab")
			(effects
				(font
					(size 1.27 1.27)
				)
			)
		)
		(duplicate_pad_numbers_are_jumpers no)
		(fp_line
			(start 2.0574 1.651)
			(end -2.0574 1.651)
			(stroke
				(width 0.1524)
				(type default)
			)
			(layer "F.SilkS")
		)
		(fp_line
			(start 2.0574 -1.651)
			(end 2.0574 1.651)
			(stroke
				(width 0.1524)
				(type default)
			)
			(layer "F.SilkS")
		)
		(fp_line
			(start 0.381 -1.651)
			(end 2.0574 -1.651)
			(stroke
				(width 0.1524)
				(type default)
			)
			(layer "F.SilkS")
		)
		(fp_line
			(start 0 -1.016)
			(end 0.381 -1.651)
			(stroke
				(width 0.1524)
				(type default)
			)
			(layer "F.SilkS")
		)
		(fp_line
			(start -0.381 -1.651)
			(end 0 -1.016)
			(stroke
				(width 0.1524)
				(type default)
			)
			(layer "F.SilkS")
		)
		(fp_line
			(start -2.0574 1.651)
			(end -2.0574 -1.651)
			(stroke
				(width 0.1524)
				(type default)
			)
			(layer "F.SilkS")
		)
		(fp_line
			(start -2.0574 -1.651)
			(end -0.381 -1.651)
			(stroke
				(width 0.1524)
				(type default)
			)
			(layer "F.SilkS")
		)
		(fp_poly
			(pts
				(xy -2.71272 -0.719328) (xy -2.71272 -1.344168) (xy -2.159 -1.016)
			)
			(stroke
				(width 0)
				(type default)
			)
			(fill yes)
			(layer "F.SilkS")
		)
		(fp_line
			(start 1.599946 1.199896)
			(end 0.899922 1.199896)
			(stroke
				(width 0.1)
				(type default)
			)
			(layer "F.Fab")
		)
		(fp_line
			(start 1.599946 -1.199896)
			(end 1.599946 1.199896)
			(stroke
				(width 0.1)
				(type default)
			)
			(layer "F.Fab")
		)
		(fp_line
			(start 0.899922 1.549908)
			(end -0.899922 1.549908)
			(stroke
				(width 0.1)
				(type default)
			)
			(layer "F.Fab")
		)
		(fp_line
			(start 0.899922 1.199896)
			(end 0.899922 1.549908)
			(stroke
				(width 0.1)
				(type default)
			)
			(layer "F.Fab")
		)
		(fp_line
			(start 0.899922 -1.199896)
			(end 1.599946 -1.199896)
			(stroke
				(width 0.1)
				(type default)
			)
			(layer "F.Fab")
		)
		(fp_line
			(start 0.899922 -1.549908)
			(end 0.899922 -1.199896)
			(stroke
				(width 0.1)
				(type default)
			)
			(layer "F.Fab")
		)
		(fp_line
			(start -0.899922 1.549908)
			(end -0.899922 1.199896)
			(stroke
				(width 0.1)
				(type default)
			)
			(layer "F.Fab")
		)
		(fp_line
			(start -0.899922 1.199896)
			(end -1.599946 1.199896)
			(stroke
				(width 0.1)
				(type default)
			)
			(layer "F.Fab")
		)
		(fp_line
			(start -0.899922 -1.199896)
			(end -0.899922 -1.549908)
			(stroke
				(width 0.1)
				(type default)
			)
			(layer "F.Fab")
		)
		(fp_line
			(start -0.899922 -1.549908)
			(end 0.899922 -1.549908)
			(stroke
				(width 0.1)
				(type default)
			)
			(layer "F.Fab")
		)
		(fp_line
			(start -1.599946 1.199896)
			(end -1.599946 -1.199896)
			(stroke
				(width 0.1)
				(type default)
			)
			(layer "F.Fab")
		)
		(fp_line
			(start -1.599946 -1.199896)
			(end -0.899922 -1.199896)
			(stroke
				(width 0.1)
				(type default)
			)
			(layer "F.Fab")
		)
		(fp_poly
			(pts
				(xy -2.71272 -0.719328) (xy -2.71272 -1.344168) (xy -2.159 -1.016)
			)
			(stroke
				(width 0)
				(type default)
			)
			(fill yes)
			(layer "F.Fab")
		)
		(pad "1" smd rect
			(at -1.225042 -0.94996 90)
			(size 0.5588 1.3462)
			(layers "F.Cu" "F.Mask" "F.Paste")
			(net "HP_NIC7_PWRGD_R")
		)
		(pad "2" smd rect
			(at -1.225042 0 90)
			(size 0.5588 1.3462)
			(layers "F.Cu" "F.Mask" "F.Paste")
			(net "RST_NIC7_PERST_R_N")
		)
		(pad "3" smd rect
			(at -1.225042 0.94996 90)
			(size 0.5588 1.3462)
			(layers "F.Cu" "F.Mask" "F.Paste")
			(net "GND")
		)
		(pad "4" smd rect
			(at 1.225042 0.94996 90)
			(size 0.5588 1.3462)
			(layers "F.Cu" "F.Mask" "F.Paste")
			(net "RST_HP_NIC7_N")
		)
		(pad "5" smd rect
			(at 1.225042 -0.94996 90)
			(size 0.5588 1.3462)
			(layers "F.Cu" "F.Mask" "F.Paste")
			(net "P3V3_AUX")
		)
	)
	(footprint ""
		(layer "F.Cu")
		(at 213.467442 -244.016276 -90)
		(property "Reference" "R6161"
			(at 0 0 270)
			(layer "F.SilkS")
			(hide yes)
			(effects
				(font
					(size 1.27 1.27)
				)
			)
		)
		(property "Value" ""
			(at 0 0 270)
			(layer "F.Fab")
			(effects
				(font
					(size 1.27 1.27)
				)
			)
		)
		(duplicate_pad_numbers_are_jumpers no)
		(fp_line
			(start -0.7874 0.4064)
			(end -0.7874 -0.4064)
			(stroke
				(width 0.1524)
				(type default)
			)
			(layer "F.SilkS")
		)
		(fp_line
			(start 0.7874 0.4064)
			(end -0.7874 0.4064)
			(stroke
				(width 0.1524)
				(type default)
			)
			(layer "F.SilkS")
		)
		(fp_line
			(start -0.7874 -0.4064)
			(end 0.7874 -0.4064)
			(stroke
				(width 0.1524)
				(type default)
			)
			(layer "F.SilkS")
		)
		(fp_line
			(start 0.7874 -0.4064)
			(end 0.7874 0.4064)
			(stroke
				(width 0.1524)
				(type default)
			)
			(layer "F.SilkS")
		)
		(fp_line
			(start -0.67945 0.3048)
			(end -0.67945 -0.305054)
			(stroke
				(width 0.1)
				(type default)
			)
			(layer "F.Fab")
		)
		(fp_line
			(start -0.12065 0.3048)
			(end -0.67945 0.3048)
			(stroke
				(width 0.1)
				(type default)
			)
			(layer "F.Fab")
		)
		(fp_line
			(start 0.120396 0.3048)
			(end 0.120396 0.2794)
			(stroke
				(width 0.1)
				(type default)
			)
			(layer "F.Fab")
		)
		(fp_line
			(start 0.67945 0.3048)
			(end 0.120396 0.3048)
			(stroke
				(width 0.1)
				(type default)
			)
			(layer "F.Fab")
		)
		(fp_line
			(start -0.12065 0.2794)
			(end -0.12065 0.3048)
			(stroke
				(width 0.1)
				(type default)
			)
			(layer "F.Fab")
		)
		(fp_line
			(start 0.120396 0.2794)
			(end -0.12065 0.2794)
			(stroke
				(width 0.1)
				(type default)
			)
			(layer "F.Fab")
		)
		(fp_line
			(start -0.12065 -0.2794)
			(end 0.12065 -0.2794)
			(stroke
				(width 0.1)
				(type default)
			)
			(layer "F.Fab")
		)
		(fp_line
			(start 0.12065 -0.2794)
			(end 0.12065 -0.3048)
			(stroke
				(width 0.1)
				(type default)
			)
			(layer "F.Fab")
		)
		(fp_line
			(start 0.12065 -0.3048)
			(end 0.67945 -0.3048)
			(stroke
				(width 0.1)
				(type default)
			)
			(layer "F.Fab")
		)
		(fp_line
			(start 0.67945 -0.3048)
			(end 0.67945 0.3048)
			(stroke
				(width 0.1)
				(type default)
			)
			(layer "F.Fab")
		)
		(fp_line
			(start -0.67945 -0.305054)
			(end -0.12065 -0.305054)
			(stroke
				(width 0.1)
				(type default)
			)
			(layer "F.Fab")
		)
		(fp_line
			(start -0.12065 -0.305054)
			(end -0.12065 -0.2794)
			(stroke
				(width 0.1)
				(type default)
			)
			(layer "F.Fab")
		)
		(pad "1" smd circle
			(at -0.40005 0 270)
			(size 0 0)
			(layers "F.Cu" "F.Mask" "F.Paste")
			(net "PWRGD_P1V8_PEX_R")
		)
		(pad "2" smd circle
			(at 0.40005 0 270)
			(size 0 0)
			(layers "F.Cu" "F.Mask" "F.Paste")
			(net "PWRGD_P1V8_PEX_R1")
		)
	)
	(footprint ""
		(layer "F.Cu")
		(at 219.202 -205.74)
		(property "Reference" "R1510"
			(at 0 0 0)
			(layer "F.SilkS")
			(hide yes)
			(effects
				(font
					(size 1.27 1.27)
				)
			)
		)
		(property "Value" ""
			(at 0 0 0)
			(layer "F.Fab")
			(effects
				(font
					(size 1.27 1.27)
				)
			)
		)
		(duplicate_pad_numbers_are_jumpers no)
		(fp_line
			(start -0.7874 -0.4064)
			(end 0.7874 -0.4064)
			(stroke
				(width 0.1524)
				(type default)
			)
			(layer "F.SilkS")
		)
		(fp_line
			(start -0.7874 0.4064)
			(end -0.7874 -0.4064)
			(stroke
				(width 0.1524)
				(type default)
			)
			(layer "F.SilkS")
		)
		(fp_line
			(start 0.7874 -0.4064)
			(end 0.7874 0.4064)
			(stroke
				(width 0.1524)
				(type default)
			)
			(layer "F.SilkS")
		)
		(fp_line
			(start 0.7874 0.4064)
			(end -0.7874 0.4064)
			(stroke
				(width 0.1524)
				(type default)
			)
			(layer "F.SilkS")
		)
		(fp_line
			(start -0.67945 -0.305054)
			(end -0.12065 -0.305054)
			(stroke
				(width 0.1)
				(type default)
			)
			(layer "F.Fab")
		)
		(fp_line
			(start -0.67945 0.3048)
			(end -0.67945 -0.305054)
			(stroke
				(width 0.1)
				(type default)
			)
			(layer "F.Fab")
		)
		(fp_line
			(start -0.12065 -0.305054)
			(end -0.12065 -0.2794)
			(stroke
				(width 0.1)
				(type default)
			)
			(layer "F.Fab")
		)
		(fp_line
			(start -0.12065 -0.2794)
			(end 0.12065 -0.2794)
			(stroke
				(width 0.1)
				(type default)
			)
			(layer "F.Fab")
		)
		(fp_line
			(start -0.12065 0.2794)
			(end -0.12065 0.3048)
			(stroke
				(width 0.1)
				(type default)
			)
			(layer "F.Fab")
		)
		(fp_line
			(start -0.12065 0.3048)
			(end -0.67945 0.3048)
			(stroke
				(width 0.1)
				(type default)
			)
			(layer "F.Fab")
		)
		(fp_line
			(start 0.120396 0.2794)
			(end -0.12065 0.2794)
			(stroke
				(width 0.1)
				(type default)
			)
			(layer "F.Fab")
		)
		(fp_line
			(start 0.120396 0.3048)
			(end 0.120396 0.2794)
			(stroke
				(width 0.1)
				(type default)
			)
			(layer "F.Fab")
		)
		(fp_line
			(start 0.12065 -0.3048)
			(end 0.67945 -0.3048)
			(stroke
				(width 0.1)
				(type default)
			)
			(layer "F.Fab")
		)
		(fp_line
			(start 0.12065 -0.2794)
			(end 0.12065 -0.3048)
			(stroke
				(width 0.1)
				(type default)
			)
			(layer "F.Fab")
		)
		(fp_line
			(start 0.67945 -0.3048)
			(end 0.67945 0.3048)
			(stroke
				(width 0.1)
				(type default)
			)
			(layer "F.Fab")
		)
		(fp_line
			(start 0.67945 0.3048)
			(end 0.120396 0.3048)
			(stroke
				(width 0.1)
				(type default)
			)
			(layer "F.Fab")
		)
		(pad "1" smd circle
			(at -0.40005 0)
			(size 0 0)
			(layers "F.Cu" "F.Mask" "F.Paste")
			(net "SMB_NIC4_LS_EN")
		)
		(pad "2" smd circle
			(at 0.40005 0)
			(size 0 0)
			(layers "F.Cu" "F.Mask" "F.Paste")
			(net "P3V3_NIC4")
		)
	)
	(footprint ""
		(layer "F.Cu")
		(at 312.477404 -343.952322 90)
		(property "Reference" "C551"
			(at 0 0 90)
			(layer "F.SilkS")
			(hide yes)
			(effects
				(font
					(size 1.27 1.27)
				)
			)
		)
		(property "Value" ""
			(at 0 0 90)
			(layer "F.Fab")
			(effects
				(font
					(size 1.27 1.27)
				)
			)
		)
		(duplicate_pad_numbers_are_jumpers no)
		(fp_line
			(start 0.299974 -0.150114)
			(end 0.299974 0.150114)
			(stroke
				(width 0.1)
				(type default)
			)
			(layer "F.Fab")
		)
		(fp_line
			(start -0.299974 -0.150114)
			(end 0.299974 -0.150114)
			(stroke
				(width 0.1)
				(type default)
			)
			(layer "F.Fab")
		)
		(fp_line
			(start 0.299974 0.150114)
			(end -0.299974 0.150114)
			(stroke
				(width 0.1)
				(type default)
			)
			(layer "F.Fab")
		)
		(fp_line
			(start -0.299974 0.150114)
			(end -0.299974 -0.150114)
			(stroke
				(width 0.1)
				(type default)
			)
			(layer "F.Fab")
		)
		(pad "1" smd rect
			(at -0.2667 0 90)
			(size 0.3048 0.381)
			(layers "F.Cu" "F.Mask" "F.Paste")
			(net "P5E_PEX2_STN6_TX_DP<111>")
		)
		(pad "2" smd rect
			(at 0.2667 0 90)
			(size 0.3048 0.381)
			(layers "F.Cu" "F.Mask" "F.Paste")
			(net "P5E_PEX2_STN6_TX_C_DP<111>")
		)
	)
	(footprint ""
		(layer "F.Cu")
		(at 242.310412 -121.661428 180)
		(property "Reference" "C2878"
			(at 0 0 180)
			(layer "F.SilkS")
			(hide yes)
			(effects
				(font
					(size 1.27 1.27)
				)
			)
		)
		(property "Value" ""
			(at 0 0 180)
			(layer "F.Fab")
			(effects
				(font
					(size 1.27 1.27)
				)
			)
		)
		(duplicate_pad_numbers_are_jumpers no)
		(fp_line
			(start 0.7874 0.4064)
			(end -0.7874 0.4064)
			(stroke
				(width 0.1524)
				(type default)
			)
			(layer "F.SilkS")
		)
		(fp_line
			(start 0.7874 -0.4064)
			(end 0.7874 0.4064)
			(stroke
				(width 0.1524)
				(type default)
			)
			(layer "F.SilkS")
		)
		(fp_line
			(start -0.7874 0.4064)
			(end -0.7874 -0.4064)
			(stroke
				(width 0.1524)
				(type default)
			)
			(layer "F.SilkS")
		)
		(fp_line
			(start -0.7874 -0.4064)
			(end 0.7874 -0.4064)
			(stroke
				(width 0.1524)
				(type default)
			)
			(layer "F.SilkS")
		)
		(fp_line
			(start 0.67945 0.3048)
			(end 0.120396 0.3048)
			(stroke
				(width 0.1)
				(type default)
			)
			(layer "F.Fab")
		)
		(fp_line
			(start 0.67945 -0.3048)
			(end 0.67945 0.3048)
			(stroke
				(width 0.1)
				(type default)
			)
			(layer "F.Fab")
		)
		(fp_line
			(start 0.12065 -0.2794)
			(end 0.12065 -0.3048)
			(stroke
				(width 0.1)
				(type default)
			)
			(layer "F.Fab")
		)
		(fp_line
			(start 0.12065 -0.3048)
			(end 0.67945 -0.3048)
			(stroke
				(width 0.1)
				(type default)
			)
			(layer "F.Fab")
		)
		(fp_line
			(start 0.120396 0.3048)
			(end 0.120396 0.2794)
			(stroke
				(width 0.1)
				(type default)
			)
			(layer "F.Fab")
		)
		(fp_line
			(start 0.120396 0.2794)
			(end -0.12065 0.2794)
			(stroke
				(width 0.1)
				(type default)
			)
			(layer "F.Fab")
		)
		(fp_line
			(start -0.12065 0.3048)
			(end -0.67945 0.3048)
			(stroke
				(width 0.1)
				(type default)
			)
			(layer "F.Fab")
		)
		(fp_line
			(start -0.12065 0.2794)
			(end -0.12065 0.3048)
			(stroke
				(width 0.1)
				(type default)
			)
			(layer "F.Fab")
		)
		(fp_line
			(start -0.12065 -0.2794)
			(end 0.12065 -0.2794)
			(stroke
				(width 0.1)
				(type default)
			)
			(layer "F.Fab")
		)
		(fp_line
			(start -0.12065 -0.305054)
			(end -0.12065 -0.2794)
			(stroke
				(width 0.1)
				(type default)
			)
			(layer "F.Fab")
		)
		(fp_line
			(start -0.67945 0.3048)
			(end -0.67945 -0.305054)
			(stroke
				(width 0.1)
				(type default)
			)
			(layer "F.Fab")
		)
		(fp_line
			(start -0.67945 -0.305054)
			(end -0.12065 -0.305054)
			(stroke
				(width 0.1)
				(type default)
			)
			(layer "F.Fab")
		)
		(pad "1" smd circle
			(at -0.40005 0 180)
			(size 0 0)
			(layers "F.Cu" "F.Mask" "F.Paste")
			(net "HP_NIC4_EN")
		)
		(pad "2" smd circle
			(at 0.40005 0 180)
			(size 0 0)
			(layers "F.Cu" "F.Mask" "F.Paste")
			(net "GND")
		)
	)
	(footprint ""
		(layer "F.Cu")
		(at 29.548328 -350.098614 90)
		(property "Reference" "C2161"
			(at 0 0 90)
			(layer "F.SilkS")
			(hide yes)
			(effects
				(font
					(size 1.27 1.27)
				)
			)
		)
		(property "Value" ""
			(at 0 0 90)
			(layer "F.Fab")
			(effects
				(font
					(size 1.27 1.27)
				)
			)
		)
		(duplicate_pad_numbers_are_jumpers no)
		(fp_line
			(start 0.299974 -0.150114)
			(end 0.299974 0.150114)
			(stroke
				(width 0.1)
				(type default)
			)
			(layer "F.Fab")
		)
		(fp_line
			(start -0.299974 -0.150114)
			(end 0.299974 -0.150114)
			(stroke
				(width 0.1)
				(type default)
			)
			(layer "F.Fab")
		)
		(fp_line
			(start 0.299974 0.150114)
			(end -0.299974 0.150114)
			(stroke
				(width 0.1)
				(type default)
			)
			(layer "F.Fab")
		)
		(fp_line
			(start -0.299974 0.150114)
			(end -0.299974 -0.150114)
			(stroke
				(width 0.1)
				(type default)
			)
			(layer "F.Fab")
		)
		(pad "1" smd rect
			(at -0.2667 0 90)
			(size 0.3048 0.381)
			(layers "F.Cu" "F.Mask" "F.Paste")
			(net "P5E_PEX0_STN4_TX_DN<75>")
		)
		(pad "2" smd rect
			(at 0.2667 0 90)
			(size 0.3048 0.381)
			(layers "F.Cu" "F.Mask" "F.Paste")
			(net "P5E_PEX0_STN4_TX_C_DN<75>")
		)
	)
	(footprint ""
		(layer "F.Cu")
		(at 270.982694 -141.87297)
		(property "Reference" "R236"
			(at 0 0 0)
			(layer "F.SilkS")
			(hide yes)
			(effects
				(font
					(size 1.27 1.27)
				)
			)
		)
		(property "Value" ""
			(at 0 0 0)
			(layer "F.Fab")
			(effects
				(font
					(size 1.27 1.27)
				)
			)
		)
		(duplicate_pad_numbers_are_jumpers no)
		(fp_line
			(start -0.7874 -0.4064)
			(end 0.7874 -0.4064)
			(stroke
				(width 0.1524)
				(type default)
			)
			(layer "F.SilkS")
		)
		(fp_line
			(start -0.7874 0.4064)
			(end -0.7874 -0.4064)
			(stroke
				(width 0.1524)
				(type default)
			)
			(layer "F.SilkS")
		)
		(fp_line
			(start 0.7874 -0.4064)
			(end 0.7874 0.4064)
			(stroke
				(width 0.1524)
				(type default)
			)
			(layer "F.SilkS")
		)
		(fp_line
			(start 0.7874 0.4064)
			(end -0.7874 0.4064)
			(stroke
				(width 0.1524)
				(type default)
			)
			(layer "F.SilkS")
		)
		(fp_line
			(start -0.67945 -0.305054)
			(end -0.12065 -0.305054)
			(stroke
				(width 0.1)
				(type default)
			)
			(layer "F.Fab")
		)
		(fp_line
			(start -0.67945 0.3048)
			(end -0.67945 -0.305054)
			(stroke
				(width 0.1)
				(type default)
			)
			(layer "F.Fab")
		)
		(fp_line
			(start -0.12065 -0.305054)
			(end -0.12065 -0.2794)
			(stroke
				(width 0.1)
				(type default)
			)
			(layer "F.Fab")
		)
		(fp_line
			(start -0.12065 -0.2794)
			(end 0.12065 -0.2794)
			(stroke
				(width 0.1)
				(type default)
			)
			(layer "F.Fab")
		)
		(fp_line
			(start -0.12065 0.2794)
			(end -0.12065 0.3048)
			(stroke
				(width 0.1)
				(type default)
			)
			(layer "F.Fab")
		)
		(fp_line
			(start -0.12065 0.3048)
			(end -0.67945 0.3048)
			(stroke
				(width 0.1)
				(type default)
			)
			(layer "F.Fab")
		)
		(fp_line
			(start 0.120396 0.2794)
			(end -0.12065 0.2794)
			(stroke
				(width 0.1)
				(type default)
			)
			(layer "F.Fab")
		)
		(fp_line
			(start 0.120396 0.3048)
			(end 0.120396 0.2794)
			(stroke
				(width 0.1)
				(type default)
			)
			(layer "F.Fab")
		)
		(fp_line
			(start 0.12065 -0.3048)
			(end 0.67945 -0.3048)
			(stroke
				(width 0.1)
				(type default)
			)
			(layer "F.Fab")
		)
		(fp_line
			(start 0.12065 -0.2794)
			(end 0.12065 -0.3048)
			(stroke
				(width 0.1)
				(type default)
			)
			(layer "F.Fab")
		)
		(fp_line
			(start 0.67945 -0.3048)
			(end 0.67945 0.3048)
			(stroke
				(width 0.1)
				(type default)
			)
			(layer "F.Fab")
		)
		(fp_line
			(start 0.67945 0.3048)
			(end 0.120396 0.3048)
			(stroke
				(width 0.1)
				(type default)
			)
			(layer "F.Fab")
		)
		(pad "1" smd circle
			(at -0.40005 0)
			(size 0 0)
			(layers "F.Cu" "F.Mask" "F.Paste")
			(net "NIC4_BIF1_N")
		)
		(pad "2" smd circle
			(at 0.40005 0)
			(size 0 0)
			(layers "F.Cu" "F.Mask" "F.Paste")
			(net "GND")
		)
	)
	(footprint ""
		(layer "F.Cu")
		(at 369.477036 -124.008134 90)
		(property "Reference" "PD57"
			(at -3.459734 2.278634 90)
			(unlocked yes)
			(layer "F.SilkS")
			(effects
				(font
					(size 0.7874 0.5842)
					(thickness 0.1524)
				)
				(justify left)
			)
		)
		(property "Value" ""
			(at 0 0 90)
			(layer "F.Fab")
			(effects
				(font
					(size 1.27 1.27)
				)
			)
		)
		(duplicate_pad_numbers_are_jumpers no)
		(fp_line
			(start 4.107942 -1.459992)
			(end 4.107942 1.459992)
			(stroke
				(width 0.1524)
				(type default)
			)
			(layer "F.SilkS")
		)
		(fp_line
			(start -3.400044 -1.459992)
			(end 4.107942 -1.459992)
			(stroke
				(width 0.1524)
				(type default)
			)
			(layer "F.SilkS")
		)
		(fp_line
			(start 4.107942 1.459992)
			(end -3.400044 1.459992)
			(stroke
				(width 0.1524)
				(type default)
			)
			(layer "F.SilkS")
		)
		(fp_line
			(start -3.400044 1.459992)
			(end -3.400044 -1.459992)
			(stroke
				(width 0.1524)
				(type default)
			)
			(layer "F.SilkS")
		)
		(fp_poly
			(pts
				(xy 4.107942 -1.459992) (xy 4.107942 1.459992) (xy 3.308096 1.459992) (xy 3.308096 -1.459992)
			)
			(stroke
				(width 0)
				(type default)
			)
			(fill yes)
			(layer "F.SilkS")
		)
		(fp_line
			(start 2.29997 -1.459992)
			(end 2.29997 1.459992)
			(stroke
				(width 0.1)
				(type default)
			)
			(layer "F.Fab")
		)
		(fp_line
			(start -2.29997 -1.459992)
			(end 2.29997 -1.459992)
			(stroke
				(width 0.1)
				(type default)
			)
			(layer "F.Fab")
		)
		(fp_line
			(start 2.29997 1.459992)
			(end -2.29997 1.459992)
			(stroke
				(width 0.1)
				(type default)
			)
			(layer "F.Fab")
		)
		(fp_line
			(start -2.29997 1.459992)
			(end -2.29997 -1.459992)
			(stroke
				(width 0.1)
				(type default)
			)
			(layer "F.Fab")
		)
		(fp_text user "+"
			(at -4.7752 -0.12065 90)
			(unlocked yes)
			(layer "F.SilkS")
			(effects
				(font
					(size 1.905 1.4224)
					(thickness 0.1524)
				)
				(justify left)
			)
		)
		(fp_text user "-"
			(at 5.4102 0.29845 270)
			(unlocked yes)
			(layer "F.SilkS")
			(effects
				(font
					(size 1.905 1.4224)
					(thickness 0.1524)
				)
				(justify left)
			)
		)
		(fp_text user "+"
			(at -4.7752 -0.12065 90)
			(unlocked yes)
			(layer "F.Fab")
			(effects
				(font
					(size 1.905 1.4224)
					(thickness 0.1524)
				)
				(justify left)
			)
		)
		(fp_text user "-"
			(at 5.4102 0.29845 270)
			(unlocked yes)
			(layer "F.Fab")
			(effects
				(font
					(size 1.905 1.4224)
					(thickness 0.1524)
				)
				(justify left)
			)
		)
		(pad "A" smd rect
			(at -1.999996 0 180)
			(size 1.7018 2.5146)
			(layers "F.Cu" "F.Mask" "F.Paste")
			(net "GND")
		)
		(pad "C" smd rect
			(at 1.999996 0 180)
			(size 1.7018 2.5146)
			(layers "F.Cu" "F.Mask" "F.Paste")
			(net "P3V3_NIC6")
		)
	)
	(footprint ""
		(layer "F.Cu")
		(at 34.120582 -26.666444 -90)
		(property "Reference" "R4052"
			(at 0 0 270)
			(layer "F.SilkS")
			(hide yes)
			(effects
				(font
					(size 1.27 1.27)
				)
			)
		)
		(property "Value" ""
			(at 0 0 270)
			(layer "F.Fab")
			(effects
				(font
					(size 1.27 1.27)
				)
			)
		)
		(duplicate_pad_numbers_are_jumpers no)
		(fp_line
			(start -0.7874 0.4064)
			(end -0.7874 -0.4064)
			(stroke
				(width 0.1524)
				(type default)
			)
			(layer "F.SilkS")
		)
		(fp_line
			(start 0.7874 0.4064)
			(end -0.7874 0.4064)
			(stroke
				(width 0.1524)
				(type default)
			)
			(layer "F.SilkS")
		)
		(fp_line
			(start -0.7874 -0.4064)
			(end 0.7874 -0.4064)
			(stroke
				(width 0.1524)
				(type default)
			)
			(layer "F.SilkS")
		)
		(fp_line
			(start 0.7874 -0.4064)
			(end 0.7874 0.4064)
			(stroke
				(width 0.1524)
				(type default)
			)
			(layer "F.SilkS")
		)
		(fp_line
			(start -0.67945 0.3048)
			(end -0.67945 -0.305054)
			(stroke
				(width 0.1)
				(type default)
			)
			(layer "F.Fab")
		)
		(fp_line
			(start -0.12065 0.3048)
			(end -0.67945 0.3048)
			(stroke
				(width 0.1)
				(type default)
			)
			(layer "F.Fab")
		)
		(fp_line
			(start 0.120396 0.3048)
			(end 0.120396 0.2794)
			(stroke
				(width 0.1)
				(type default)
			)
			(layer "F.Fab")
		)
		(fp_line
			(start 0.67945 0.3048)
			(end 0.120396 0.3048)
			(stroke
				(width 0.1)
				(type default)
			)
			(layer "F.Fab")
		)
		(fp_line
			(start -0.12065 0.2794)
			(end -0.12065 0.3048)
			(stroke
				(width 0.1)
				(type default)
			)
			(layer "F.Fab")
		)
		(fp_line
			(start 0.120396 0.2794)
			(end -0.12065 0.2794)
			(stroke
				(width 0.1)
				(type default)
			)
			(layer "F.Fab")
		)
		(fp_line
			(start -0.12065 -0.2794)
			(end 0.12065 -0.2794)
			(stroke
				(width 0.1)
				(type default)
			)
			(layer "F.Fab")
		)
		(fp_line
			(start 0.12065 -0.2794)
			(end 0.12065 -0.3048)
			(stroke
				(width 0.1)
				(type default)
			)
			(layer "F.Fab")
		)
		(fp_line
			(start 0.12065 -0.3048)
			(end 0.67945 -0.3048)
			(stroke
				(width 0.1)
				(type default)
			)
			(layer "F.Fab")
		)
		(fp_line
			(start 0.67945 -0.3048)
			(end 0.67945 0.3048)
			(stroke
				(width 0.1)
				(type default)
			)
			(layer "F.Fab")
		)
		(fp_line
			(start -0.67945 -0.305054)
			(end -0.12065 -0.305054)
			(stroke
				(width 0.1)
				(type default)
			)
			(layer "F.Fab")
		)
		(fp_line
			(start -0.12065 -0.305054)
			(end -0.12065 -0.2794)
			(stroke
				(width 0.1)
				(type default)
			)
			(layer "F.Fab")
		)
		(pad "1" smd circle
			(at -0.40005 0 270)
			(size 0 0)
			(layers "F.Cu" "F.Mask" "F.Paste")
			(net "PRSNT_SSD1_R_N")
		)
		(pad "2" smd circle
			(at 0.40005 0 270)
			(size 0 0)
			(layers "F.Cu" "F.Mask" "F.Paste")
			(net "PRSNT_SSD1_N")
		)
	)
	(footprint ""
		(layer "F.Cu")
		(at 140.892784 -257.148838 -90)
		(property "Reference" "R1327"
			(at 0 0 270)
			(layer "F.SilkS")
			(hide yes)
			(effects
				(font
					(size 1.27 1.27)
				)
			)
		)
		(property "Value" ""
			(at 0 0 270)
			(layer "F.Fab")
			(effects
				(font
					(size 1.27 1.27)
				)
			)
		)
		(duplicate_pad_numbers_are_jumpers no)
		(fp_line
			(start -0.7874 0.4064)
			(end -0.7874 -0.4064)
			(stroke
				(width 0.1524)
				(type default)
			)
			(layer "F.SilkS")
		)
		(fp_line
			(start 0.7874 0.4064)
			(end -0.7874 0.4064)
			(stroke
				(width 0.1524)
				(type default)
			)
			(layer "F.SilkS")
		)
		(fp_line
			(start -0.7874 -0.4064)
			(end 0.7874 -0.4064)
			(stroke
				(width 0.1524)
				(type default)
			)
			(layer "F.SilkS")
		)
		(fp_line
			(start 0.7874 -0.4064)
			(end 0.7874 0.4064)
			(stroke
				(width 0.1524)
				(type default)
			)
			(layer "F.SilkS")
		)
		(fp_line
			(start -0.67945 0.3048)
			(end -0.67945 -0.305054)
			(stroke
				(width 0.1)
				(type default)
			)
			(layer "F.Fab")
		)
		(fp_line
			(start -0.12065 0.3048)
			(end -0.67945 0.3048)
			(stroke
				(width 0.1)
				(type default)
			)
			(layer "F.Fab")
		)
		(fp_line
			(start 0.120396 0.3048)
			(end 0.120396 0.2794)
			(stroke
				(width 0.1)
				(type default)
			)
			(layer "F.Fab")
		)
		(fp_line
			(start 0.67945 0.3048)
			(end 0.120396 0.3048)
			(stroke
				(width 0.1)
				(type default)
			)
			(layer "F.Fab")
		)
		(fp_line
			(start -0.12065 0.2794)
			(end -0.12065 0.3048)
			(stroke
				(width 0.1)
				(type default)
			)
			(layer "F.Fab")
		)
		(fp_line
			(start 0.120396 0.2794)
			(end -0.12065 0.2794)
			(stroke
				(width 0.1)
				(type default)
			)
			(layer "F.Fab")
		)
		(fp_line
			(start -0.12065 -0.2794)
			(end 0.12065 -0.2794)
			(stroke
				(width 0.1)
				(type default)
			)
			(layer "F.Fab")
		)
		(fp_line
			(start 0.12065 -0.2794)
			(end 0.12065 -0.3048)
			(stroke
				(width 0.1)
				(type default)
			)
			(layer "F.Fab")
		)
		(fp_line
			(start 0.12065 -0.3048)
			(end 0.67945 -0.3048)
			(stroke
				(width 0.1)
				(type default)
			)
			(layer "F.Fab")
		)
		(fp_line
			(start 0.67945 -0.3048)
			(end 0.67945 0.3048)
			(stroke
				(width 0.1)
				(type default)
			)
			(layer "F.Fab")
		)
		(fp_line
			(start -0.67945 -0.305054)
			(end -0.12065 -0.305054)
			(stroke
				(width 0.1)
				(type default)
			)
			(layer "F.Fab")
		)
		(fp_line
			(start -0.12065 -0.305054)
			(end -0.12065 -0.2794)
			(stroke
				(width 0.1)
				(type default)
			)
			(layer "F.Fab")
		)
		(pad "1" smd circle
			(at -0.40005 0 270)
			(size 0 0)
			(layers "F.Cu" "F.Mask" "F.Paste")
			(net "P3V3_LED")
		)
		(pad "2" smd circle
			(at 0.40005 0 270)
			(size 0 0)
			(layers "F.Cu" "F.Mask" "F.Paste")
			(net "LED_PEX1_SYS_ERR_N")
		)
	)
	(footprint ""
		(layer "F.Cu")
		(at 175.0949 -101.782372 180)
		(property "Reference" "R174"
			(at 0 0 180)
			(layer "F.SilkS")
			(hide yes)
			(effects
				(font
					(size 1.27 1.27)
				)
			)
		)
		(property "Value" ""
			(at 0 0 180)
			(layer "F.Fab")
			(effects
				(font
					(size 1.27 1.27)
				)
			)
		)
		(duplicate_pad_numbers_are_jumpers no)
		(fp_line
			(start 0.7874 0.4064)
			(end -0.7874 0.4064)
			(stroke
				(width 0.1524)
				(type default)
			)
			(layer "F.SilkS")
		)
		(fp_line
			(start 0.7874 -0.4064)
			(end 0.7874 0.4064)
			(stroke
				(width 0.1524)
				(type default)
			)
			(layer "F.SilkS")
		)
		(fp_line
			(start -0.7874 0.4064)
			(end -0.7874 -0.4064)
			(stroke
				(width 0.1524)
				(type default)
			)
			(layer "F.SilkS")
		)
		(fp_line
			(start -0.7874 -0.4064)
			(end 0.7874 -0.4064)
			(stroke
				(width 0.1524)
				(type default)
			)
			(layer "F.SilkS")
		)
		(fp_line
			(start 0.67945 0.3048)
			(end 0.120396 0.3048)
			(stroke
				(width 0.1)
				(type default)
			)
			(layer "F.Fab")
		)
		(fp_line
			(start 0.67945 -0.3048)
			(end 0.67945 0.3048)
			(stroke
				(width 0.1)
				(type default)
			)
			(layer "F.Fab")
		)
		(fp_line
			(start 0.12065 -0.2794)
			(end 0.12065 -0.3048)
			(stroke
				(width 0.1)
				(type default)
			)
			(layer "F.Fab")
		)
		(fp_line
			(start 0.12065 -0.3048)
			(end 0.67945 -0.3048)
			(stroke
				(width 0.1)
				(type default)
			)
			(layer "F.Fab")
		)
		(fp_line
			(start 0.120396 0.3048)
			(end 0.120396 0.2794)
			(stroke
				(width 0.1)
				(type default)
			)
			(layer "F.Fab")
		)
		(fp_line
			(start 0.120396 0.2794)
			(end -0.12065 0.2794)
			(stroke
				(width 0.1)
				(type default)
			)
			(layer "F.Fab")
		)
		(fp_line
			(start -0.12065 0.3048)
			(end -0.67945 0.3048)
			(stroke
				(width 0.1)
				(type default)
			)
			(layer "F.Fab")
		)
		(fp_line
			(start -0.12065 0.2794)
			(end -0.12065 0.3048)
			(stroke
				(width 0.1)
				(type default)
			)
			(layer "F.Fab")
		)
		(fp_line
			(start -0.12065 -0.2794)
			(end 0.12065 -0.2794)
			(stroke
				(width 0.1)
				(type default)
			)
			(layer "F.Fab")
		)
		(fp_line
			(start -0.12065 -0.305054)
			(end -0.12065 -0.2794)
			(stroke
				(width 0.1)
				(type default)
			)
			(layer "F.Fab")
		)
		(fp_line
			(start -0.67945 0.3048)
			(end -0.67945 -0.305054)
			(stroke
				(width 0.1)
				(type default)
			)
			(layer "F.Fab")
		)
		(fp_line
			(start -0.67945 -0.305054)
			(end -0.12065 -0.305054)
			(stroke
				(width 0.1)
				(type default)
			)
			(layer "F.Fab")
		)
		(pad "1" smd circle
			(at -0.40005 0 180)
			(size 0 0)
			(layers "F.Cu" "F.Mask" "F.Paste")
			(net "NCSI_NIC3_TX_EN")
		)
		(pad "2" smd circle
			(at 0.40005 0 180)
			(size 0 0)
			(layers "F.Cu" "F.Mask" "F.Paste")
			(net "GND")
		)
	)
	(footprint ""
		(layer "F.Cu")
		(at 43.792394 -29.139642 180)
		(property "Reference" "C79"
			(at 0 0 180)
			(layer "F.SilkS")
			(hide yes)
			(effects
				(font
					(size 1.27 1.27)
				)
			)
		)
		(property "Value" ""
			(at 0 0 180)
			(layer "F.Fab")
			(effects
				(font
					(size 1.27 1.27)
				)
			)
		)
		(duplicate_pad_numbers_are_jumpers no)
		(fp_line
			(start 0.299974 0.150114)
			(end -0.299974 0.150114)
			(stroke
				(width 0.1)
				(type default)
			)
			(layer "F.Fab")
		)
		(fp_line
			(start 0.299974 -0.150114)
			(end 0.299974 0.150114)
			(stroke
				(width 0.1)
				(type default)
			)
			(layer "F.Fab")
		)
		(fp_line
			(start -0.299974 0.150114)
			(end -0.299974 -0.150114)
			(stroke
				(width 0.1)
				(type default)
			)
			(layer "F.Fab")
		)
		(fp_line
			(start -0.299974 -0.150114)
			(end 0.299974 -0.150114)
			(stroke
				(width 0.1)
				(type default)
			)
			(layer "F.Fab")
		)
		(pad "1" smd rect
			(at -0.2667 0 180)
			(size 0.3048 0.381)
			(layers "F.Cu" "F.Mask" "F.Paste")
			(net "P5E_PEX0_STN2_TX_DP<40>")
		)
		(pad "2" smd rect
			(at 0.2667 0 180)
			(size 0.3048 0.381)
			(layers "F.Cu" "F.Mask" "F.Paste")
			(net "P5E_PEX0_STN2_TX_C_DP<40>")
		)
	)
	(footprint ""
		(layer "F.Cu")
		(at 124.796296 -169.484802 -90)
		(property "Reference" "U438"
			(at -1.35001 1.893824 90)
			(unlocked yes)
			(layer "F.SilkS")
			(effects
				(font
					(size 0.7874 0.5842)
					(thickness 0.1524)
				)
			)
		)
		(property "Value" ""
			(at 0 0 270)
			(layer "F.Fab")
			(effects
				(font
					(size 1.27 1.27)
				)
			)
		)
		(duplicate_pad_numbers_are_jumpers no)
		(fp_line
			(start -1.7272 1.1176)
			(end -1.7272 -1.1176)
			(stroke
				(width 0.1524)
				(type default)
			)
			(layer "F.SilkS")
		)
		(fp_line
			(start 1.7272 1.1176)
			(end -1.7272 1.1176)
			(stroke
				(width 0.1524)
				(type default)
			)
			(layer "F.SilkS")
		)
		(fp_line
			(start 0 -0.7366)
			(end -0.254 -1.1176)
			(stroke
				(width 0.1524)
				(type default)
			)
			(layer "F.SilkS")
		)
		(fp_line
			(start -0.254 -1.1176)
			(end -1.7272 -1.1176)
			(stroke
				(width 0.1524)
				(type default)
			)
			(layer "F.SilkS")
		)
		(fp_line
			(start 0.254 -1.1176)
			(end 0 -0.7366)
			(stroke
				(width 0.1524)
				(type default)
			)
			(layer "F.SilkS")
		)
		(fp_line
			(start 1.7272 -1.1176)
			(end 1.7272 1.1176)
			(stroke
				(width 0.1524)
				(type default)
			)
			(layer "F.SilkS")
		)
		(fp_line
			(start 1.7272 -1.1176)
			(end 0.254 -1.1176)
			(stroke
				(width 0.1524)
				(type default)
			)
			(layer "F.SilkS")
		)
		(fp_poly
			(pts
				(xy -1.14173 -1.37922) (xy -1.52273 -2.14122) (xy -0.76073 -2.14122)
			)
			(stroke
				(width 0)
				(type default)
			)
			(fill yes)
			(layer "F.SilkS")
		)
		(fp_line
			(start -1.5748 1.1176)
			(end 1.5748 1.1176)
			(stroke
				(width 0.1)
				(type default)
			)
			(layer "F.Fab")
		)
		(fp_line
			(start 1.5748 1.1176)
			(end 1.5748 -1.1176)
			(stroke
				(width 0.1)
				(type default)
			)
			(layer "F.Fab")
		)
		(fp_line
			(start -1.5748 -1.1176)
			(end -1.5748 1.1176)
			(stroke
				(width 0.1)
				(type default)
			)
			(layer "F.Fab")
		)
		(fp_line
			(start 1.5748 -1.1176)
			(end -1.5748 -1.1176)
			(stroke
				(width 0.1)
				(type default)
			)
			(layer "F.Fab")
		)
		(fp_poly
			(pts
				(xy -1.9558 -0.649986) (xy -2.7178 -0.268986) (xy -2.7178 -1.030986)
			)
			(stroke
				(width 0)
				(type default)
			)
			(fill yes)
			(layer "F.Fab")
		)
		(pad "1" smd rect
			(at -0.999998 -0.649986 180)
			(size 0.3556 1.1176)
			(layers "F.Cu" "F.Mask" "F.Paste")
			(net "NIC0_CLK_EN_R_N")
		)
		(pad "2" smd rect
			(at -0.999998 0 180)
			(size 0.3556 1.1176)
			(layers "F.Cu" "F.Mask" "F.Paste")
			(net "GND")
		)
		(pad "3" smd rect
			(at -0.999998 0.649986 180)
			(size 0.3556 1.1176)
			(layers "F.Cu" "F.Mask" "F.Paste")
			(net "NIC1_CLK_EN_R_N")
		)
		(pad "4" smd rect
			(at 0.999998 0.649986 180)
			(size 0.3556 1.1176)
			(layers "F.Cu" "F.Mask" "F.Paste")
			(net "NIC1_CLK_EN_BUF_N")
		)
		(pad "5" smd rect
			(at 0.999998 0 180)
			(size 0.3556 1.1176)
			(layers "F.Cu" "F.Mask" "F.Paste")
			(net "P3V3_AUX")
		)
		(pad "6" smd rect
			(at 0.999998 -0.649986 180)
			(size 0.3556 1.1176)
			(layers "F.Cu" "F.Mask" "F.Paste")
			(net "NIC0_CLK_EN_BUF_N")
		)
	)
	(footprint ""
		(layer "F.Cu")
		(at 199.394064 -35.264852)
		(property "Reference" "R5676"
			(at 0 0 0)
			(layer "F.SilkS")
			(hide yes)
			(effects
				(font
					(size 1.27 1.27)
				)
			)
		)
		(property "Value" ""
			(at 0 0 0)
			(layer "F.Fab")
			(effects
				(font
					(size 1.27 1.27)
				)
			)
		)
		(duplicate_pad_numbers_are_jumpers no)
		(fp_line
			(start -0.7874 -0.4064)
			(end 0.7874 -0.4064)
			(stroke
				(width 0.1524)
				(type default)
			)
			(layer "F.SilkS")
		)
		(fp_line
			(start -0.7874 0.4064)
			(end -0.7874 -0.4064)
			(stroke
				(width 0.1524)
				(type default)
			)
			(layer "F.SilkS")
		)
		(fp_line
			(start 0.7874 -0.4064)
			(end 0.7874 0.4064)
			(stroke
				(width 0.1524)
				(type default)
			)
			(layer "F.SilkS")
		)
		(fp_line
			(start 0.7874 0.4064)
			(end -0.7874 0.4064)
			(stroke
				(width 0.1524)
				(type default)
			)
			(layer "F.SilkS")
		)
		(fp_line
			(start -0.67945 -0.305054)
			(end -0.12065 -0.305054)
			(stroke
				(width 0.1)
				(type default)
			)
			(layer "F.Fab")
		)
		(fp_line
			(start -0.67945 0.3048)
			(end -0.67945 -0.305054)
			(stroke
				(width 0.1)
				(type default)
			)
			(layer "F.Fab")
		)
		(fp_line
			(start -0.12065 -0.305054)
			(end -0.12065 -0.2794)
			(stroke
				(width 0.1)
				(type default)
			)
			(layer "F.Fab")
		)
		(fp_line
			(start -0.12065 -0.2794)
			(end 0.12065 -0.2794)
			(stroke
				(width 0.1)
				(type default)
			)
			(layer "F.Fab")
		)
		(fp_line
			(start -0.12065 0.2794)
			(end -0.12065 0.3048)
			(stroke
				(width 0.1)
				(type default)
			)
			(layer "F.Fab")
		)
		(fp_line
			(start -0.12065 0.3048)
			(end -0.67945 0.3048)
			(stroke
				(width 0.1)
				(type default)
			)
			(layer "F.Fab")
		)
		(fp_line
			(start 0.120396 0.2794)
			(end -0.12065 0.2794)
			(stroke
				(width 0.1)
				(type default)
			)
			(layer "F.Fab")
		)
		(fp_line
			(start 0.120396 0.3048)
			(end 0.120396 0.2794)
			(stroke
				(width 0.1)
				(type default)
			)
			(layer "F.Fab")
		)
		(fp_line
			(start 0.12065 -0.3048)
			(end 0.67945 -0.3048)
			(stroke
				(width 0.1)
				(type default)
			)
			(layer "F.Fab")
		)
		(fp_line
			(start 0.12065 -0.2794)
			(end 0.12065 -0.3048)
			(stroke
				(width 0.1)
				(type default)
			)
			(layer "F.Fab")
		)
		(fp_line
			(start 0.67945 -0.3048)
			(end 0.67945 0.3048)
			(stroke
				(width 0.1)
				(type default)
			)
			(layer "F.Fab")
		)
		(fp_line
			(start 0.67945 0.3048)
			(end 0.120396 0.3048)
			(stroke
				(width 0.1)
				(type default)
			)
			(layer "F.Fab")
		)
		(pad "1" smd circle
			(at -0.40005 0)
			(size 0 0)
			(layers "F.Cu" "F.Mask" "F.Paste")
			(net "RST_SMB_SSD7_ISO_N")
		)
		(pad "2" smd circle
			(at 0.40005 0)
			(size 0 0)
			(layers "F.Cu" "F.Mask" "F.Paste")
			(net "GND")
		)
	)
	(footprint ""
		(layer "F.Cu")
		(at 378.2949 -350.098614 90)
		(property "Reference" "C785"
			(at 0 0 90)
			(layer "F.SilkS")
			(hide yes)
			(effects
				(font
					(size 1.27 1.27)
				)
			)
		)
		(property "Value" ""
			(at 0 0 90)
			(layer "F.Fab")
			(effects
				(font
					(size 1.27 1.27)
				)
			)
		)
		(duplicate_pad_numbers_are_jumpers no)
		(fp_line
			(start 0.299974 -0.150114)
			(end 0.299974 0.150114)
			(stroke
				(width 0.1)
				(type default)
			)
			(layer "F.Fab")
		)
		(fp_line
			(start -0.299974 -0.150114)
			(end 0.299974 -0.150114)
			(stroke
				(width 0.1)
				(type default)
			)
			(layer "F.Fab")
		)
		(fp_line
			(start 0.299974 0.150114)
			(end -0.299974 0.150114)
			(stroke
				(width 0.1)
				(type default)
			)
			(layer "F.Fab")
		)
		(fp_line
			(start -0.299974 0.150114)
			(end -0.299974 -0.150114)
			(stroke
				(width 0.1)
				(type default)
			)
			(layer "F.Fab")
		)
		(pad "1" smd rect
			(at -0.2667 0 90)
			(size 0.3048 0.381)
			(layers "F.Cu" "F.Mask" "F.Paste")
			(net "P5E_PEX3_STN6_TX_DN<100>")
		)
		(pad "2" smd rect
			(at 0.2667 0 90)
			(size 0.3048 0.381)
			(layers "F.Cu" "F.Mask" "F.Paste")
			(net "P5E_PEX3_STN6_TX_C_DN<100>")
		)
	)
	(footprint ""
		(layer "F.Cu")
		(at 336.042 -147.955 180)
		(property "Reference" "R4802"
			(at 0 0 180)
			(layer "F.SilkS")
			(hide yes)
			(effects
				(font
					(size 1.27 1.27)
				)
			)
		)
		(property "Value" ""
			(at 0 0 180)
			(layer "F.Fab")
			(effects
				(font
					(size 1.27 1.27)
				)
			)
		)
		(duplicate_pad_numbers_are_jumpers no)
		(fp_line
			(start 0.7874 0.4064)
			(end -0.7874 0.4064)
			(stroke
				(width 0.1524)
				(type default)
			)
			(layer "F.SilkS")
		)
		(fp_line
			(start 0.7874 -0.4064)
			(end 0.7874 0.4064)
			(stroke
				(width 0.1524)
				(type default)
			)
			(layer "F.SilkS")
		)
		(fp_line
			(start -0.7874 0.4064)
			(end -0.7874 -0.4064)
			(stroke
				(width 0.1524)
				(type default)
			)
			(layer "F.SilkS")
		)
		(fp_line
			(start -0.7874 -0.4064)
			(end 0.7874 -0.4064)
			(stroke
				(width 0.1524)
				(type default)
			)
			(layer "F.SilkS")
		)
		(fp_line
			(start 0.67945 0.3048)
			(end 0.120396 0.3048)
			(stroke
				(width 0.1)
				(type default)
			)
			(layer "F.Fab")
		)
		(fp_line
			(start 0.67945 -0.3048)
			(end 0.67945 0.3048)
			(stroke
				(width 0.1)
				(type default)
			)
			(layer "F.Fab")
		)
		(fp_line
			(start 0.12065 -0.2794)
			(end 0.12065 -0.3048)
			(stroke
				(width 0.1)
				(type default)
			)
			(layer "F.Fab")
		)
		(fp_line
			(start 0.12065 -0.3048)
			(end 0.67945 -0.3048)
			(stroke
				(width 0.1)
				(type default)
			)
			(layer "F.Fab")
		)
		(fp_line
			(start 0.120396 0.3048)
			(end 0.120396 0.2794)
			(stroke
				(width 0.1)
				(type default)
			)
			(layer "F.Fab")
		)
		(fp_line
			(start 0.120396 0.2794)
			(end -0.12065 0.2794)
			(stroke
				(width 0.1)
				(type default)
			)
			(layer "F.Fab")
		)
		(fp_line
			(start -0.12065 0.3048)
			(end -0.67945 0.3048)
			(stroke
				(width 0.1)
				(type default)
			)
			(layer "F.Fab")
		)
		(fp_line
			(start -0.12065 0.2794)
			(end -0.12065 0.3048)
			(stroke
				(width 0.1)
				(type default)
			)
			(layer "F.Fab")
		)
		(fp_line
			(start -0.12065 -0.2794)
			(end 0.12065 -0.2794)
			(stroke
				(width 0.1)
				(type default)
			)
			(layer "F.Fab")
		)
		(fp_line
			(start -0.12065 -0.305054)
			(end -0.12065 -0.2794)
			(stroke
				(width 0.1)
				(type default)
			)
			(layer "F.Fab")
		)
		(fp_line
			(start -0.67945 0.3048)
			(end -0.67945 -0.305054)
			(stroke
				(width 0.1)
				(type default)
			)
			(layer "F.Fab")
		)
		(fp_line
			(start -0.67945 -0.305054)
			(end -0.12065 -0.305054)
			(stroke
				(width 0.1)
				(type default)
			)
			(layer "F.Fab")
		)
		(pad "1" smd circle
			(at -0.40005 0 180)
			(size 0 0)
			(layers "F.Cu" "F.Mask" "F.Paste")
			(net "SSD14_PEX_PWR_EN_R")
		)
		(pad "2" smd circle
			(at 0.40005 0 180)
			(size 0 0)
			(layers "F.Cu" "F.Mask" "F.Paste")
			(net "GND")
		)
	)
	(footprint ""
		(layer "F.Cu")
		(at 283.539184 -177.428398 -90)
		(property "Reference" "Q5"
			(at 0.745998 -1.856486 90)
			(unlocked yes)
			(layer "F.SilkS")
			(effects
				(font
					(size 0.7874 0.5842)
					(thickness 0.1524)
				)
				(justify left)
			)
		)
		(property "Value" ""
			(at 0 0 270)
			(layer "F.Fab")
			(effects
				(font
					(size 1.27 1.27)
				)
			)
		)
		(duplicate_pad_numbers_are_jumpers no)
		(fp_line
			(start -1.38176 1.100074)
			(end 1.38176 1.100074)
			(stroke
				(width 0.1524)
				(type default)
			)
			(layer "F.SilkS")
		)
		(fp_line
			(start 1.38176 1.100074)
			(end 1.38176 -1.100074)
			(stroke
				(width 0.1524)
				(type default)
			)
			(layer "F.SilkS")
		)
		(fp_line
			(start 0 -0.508)
			(end -0.592074 -1.100074)
			(stroke
				(width 0.1524)
				(type default)
			)
			(layer "F.SilkS")
		)
		(fp_line
			(start -1.38176 -1.100074)
			(end -1.38176 1.100074)
			(stroke
				(width 0.1524)
				(type default)
			)
			(layer "F.SilkS")
		)
		(fp_line
			(start -0.592074 -1.100074)
			(end -1.38176 -1.100074)
			(stroke
				(width 0.1524)
				(type default)
			)
			(layer "F.SilkS")
		)
		(fp_line
			(start 0.592074 -1.100074)
			(end 0 -0.508)
			(stroke
				(width 0.1524)
				(type default)
			)
			(layer "F.SilkS")
		)
		(fp_line
			(start 1.38176 -1.100074)
			(end 0.592074 -1.100074)
			(stroke
				(width 0.1524)
				(type default)
			)
			(layer "F.SilkS")
		)
		(fp_poly
			(pts
				(xy -1.705864 -1.452118) (xy -1.549908 -0.984758) (xy -2.017268 -1.140714)
			)
			(stroke
				(width 0)
				(type default)
			)
			(fill yes)
			(layer "F.SilkS")
		)
		(fp_line
			(start -0.674878 1.100074)
			(end 0.674878 1.100074)
			(stroke
				(width 0.1)
				(type default)
			)
			(layer "F.Fab")
		)
		(fp_line
			(start 0.674878 1.100074)
			(end 0.674878 -1.100074)
			(stroke
				(width 0.1)
				(type default)
			)
			(layer "F.Fab")
		)
		(fp_line
			(start -0.674878 -1.100074)
			(end -0.674878 1.100074)
			(stroke
				(width 0.1)
				(type default)
			)
			(layer "F.Fab")
		)
		(fp_line
			(start 0.674878 -1.100074)
			(end -0.674878 -1.100074)
			(stroke
				(width 0.1)
				(type default)
			)
			(layer "F.Fab")
		)
		(fp_poly
			(pts
				(xy -1.9431 -0.870204) (xy -1.50241 -0.649986) (xy -1.9431 -0.429768)
			)
			(stroke
				(width 0)
				(type default)
			)
			(fill yes)
			(layer "F.Fab")
		)
		(pad "1" smd rect
			(at -0.94996 -0.649986 180)
			(size 0.4318 0.6096)
			(layers "F.Cu" "F.Mask" "F.Paste")
			(net "GND")
		)
		(pad "2" smd rect
			(at -0.94996 0 180)
			(size 0.4318 0.6096)
			(layers "F.Cu" "F.Mask" "F.Paste")
			(net "HP_NIC4_HSC_PWRGD_N")
		)
		(pad "3" smd rect
			(at -0.94996 0.649986 180)
			(size 0.4318 0.6096)
			(layers "F.Cu" "F.Mask" "F.Paste")
			(net "HP_NIC4_HSC_PWRGD_N")
		)
		(pad "4" smd rect
			(at 0.94996 0.649986 180)
			(size 0.4318 0.6096)
			(layers "F.Cu" "F.Mask" "F.Paste")
			(net "GND")
		)
		(pad "5" smd rect
			(at 0.94996 0 180)
			(size 0.4318 0.6096)
			(layers "F.Cu" "F.Mask" "F.Paste")
			(net "PWRGD_P12V_NIC4_R")
		)
		(pad "6" smd rect
			(at 0.94996 -0.649986 180)
			(size 0.4318 0.6096)
			(layers "F.Cu" "F.Mask" "F.Paste")
			(net "HP_NIC4_PWRGD_R")
		)
	)
	(footprint ""
		(layer "F.Cu")
		(at 135.89635 -47.20082 90)
		(property "Reference" "C310"
			(at 0 0 90)
			(layer "F.SilkS")
			(hide yes)
			(effects
				(font
					(size 1.27 1.27)
				)
			)
		)
		(property "Value" ""
			(at 0 0 90)
			(layer "F.Fab")
			(effects
				(font
					(size 1.27 1.27)
				)
			)
		)
		(duplicate_pad_numbers_are_jumpers no)
		(fp_line
			(start 0.7874 -0.4064)
			(end 0.7874 0.4064)
			(stroke
				(width 0.1524)
				(type default)
			)
			(layer "F.SilkS")
		)
		(fp_line
			(start -0.7874 -0.4064)
			(end 0.7874 -0.4064)
			(stroke
				(width 0.1524)
				(type default)
			)
			(layer "F.SilkS")
		)
		(fp_line
			(start 0.7874 0.4064)
			(end -0.7874 0.4064)
			(stroke
				(width 0.1524)
				(type default)
			)
			(layer "F.SilkS")
		)
		(fp_line
			(start -0.7874 0.4064)
			(end -0.7874 -0.4064)
			(stroke
				(width 0.1524)
				(type default)
			)
			(layer "F.SilkS")
		)
		(fp_line
			(start -0.12065 -0.305054)
			(end -0.12065 -0.2794)
			(stroke
				(width 0.1)
				(type default)
			)
			(layer "F.Fab")
		)
		(fp_line
			(start -0.67945 -0.305054)
			(end -0.12065 -0.305054)
			(stroke
				(width 0.1)
				(type default)
			)
			(layer "F.Fab")
		)
		(fp_line
			(start 0.67945 -0.3048)
			(end 0.67945 0.3048)
			(stroke
				(width 0.1)
				(type default)
			)
			(layer "F.Fab")
		)
		(fp_line
			(start 0.12065 -0.3048)
			(end 0.67945 -0.3048)
			(stroke
				(width 0.1)
				(type default)
			)
			(layer "F.Fab")
		)
		(fp_line
			(start 0.12065 -0.2794)
			(end 0.12065 -0.3048)
			(stroke
				(width 0.1)
				(type default)
			)
			(layer "F.Fab")
		)
		(fp_line
			(start -0.12065 -0.2794)
			(end 0.12065 -0.2794)
			(stroke
				(width 0.1)
				(type default)
			)
			(layer "F.Fab")
		)
		(fp_line
			(start 0.120396 0.2794)
			(end -0.12065 0.2794)
			(stroke
				(width 0.1)
				(type default)
			)
			(layer "F.Fab")
		)
		(fp_line
			(start -0.12065 0.2794)
			(end -0.12065 0.3048)
			(stroke
				(width 0.1)
				(type default)
			)
			(layer "F.Fab")
		)
		(fp_line
			(start 0.67945 0.3048)
			(end 0.120396 0.3048)
			(stroke
				(width 0.1)
				(type default)
			)
			(layer "F.Fab")
		)
		(fp_line
			(start 0.120396 0.3048)
			(end 0.120396 0.2794)
			(stroke
				(width 0.1)
				(type default)
			)
			(layer "F.Fab")
		)
		(fp_line
			(start -0.12065 0.3048)
			(end -0.67945 0.3048)
			(stroke
				(width 0.1)
				(type default)
			)
			(layer "F.Fab")
		)
		(fp_line
			(start -0.67945 0.3048)
			(end -0.67945 -0.305054)
			(stroke
				(width 0.1)
				(type default)
			)
			(layer "F.Fab")
		)
		(pad "1" smd circle
			(at -0.40005 0 90)
			(size 0 0)
			(layers "F.Cu" "F.Mask" "F.Paste")
			(net "P12V_SSD4_R")
		)
		(pad "2" smd circle
			(at 0.40005 0 90)
			(size 0 0)
			(layers "F.Cu" "F.Mask" "F.Paste")
			(net "GND")
		)
	)
	(footprint ""
		(layer "F.Cu")
		(at 30.081982 -280.189432 180)
		(property "Reference" "C3073"
			(at 0 0 180)
			(layer "F.SilkS")
			(hide yes)
			(effects
				(font
					(size 1.27 1.27)
				)
			)
		)
		(property "Value" ""
			(at 0 0 180)
			(layer "F.Fab")
			(effects
				(font
					(size 1.27 1.27)
				)
			)
		)
		(duplicate_pad_numbers_are_jumpers no)
		(fp_line
			(start 1.2954 0.5842)
			(end -1.2954 0.5842)
			(stroke
				(width 0.1524)
				(type default)
			)
			(layer "F.SilkS")
		)
		(fp_line
			(start 1.2954 -0.5842)
			(end 1.2954 0.5842)
			(stroke
				(width 0.1524)
				(type default)
			)
			(layer "F.SilkS")
		)
		(fp_line
			(start -1.2954 0.5842)
			(end -1.2954 -0.5842)
			(stroke
				(width 0.1524)
				(type default)
			)
			(layer "F.SilkS")
		)
		(fp_line
			(start -1.2954 -0.5842)
			(end 1.2954 -0.5842)
			(stroke
				(width 0.1524)
				(type default)
			)
			(layer "F.SilkS")
		)
		(fp_line
			(start 1.1938 0.4064)
			(end 0.8636 0.4064)
			(stroke
				(width 0.1)
				(type default)
			)
			(layer "F.Fab")
		)
		(fp_line
			(start 1.1938 -0.4064)
			(end 1.1938 0.4064)
			(stroke
				(width 0.1)
				(type default)
			)
			(layer "F.Fab")
		)
		(fp_line
			(start 0.8636 0.4572)
			(end -0.8636 0.4572)
			(stroke
				(width 0.1)
				(type default)
			)
			(layer "F.Fab")
		)
		(fp_line
			(start 0.8636 0.4064)
			(end 0.8636 0.4572)
			(stroke
				(width 0.1)
				(type default)
			)
			(layer "F.Fab")
		)
		(fp_line
			(start 0.8636 -0.4064)
			(end 1.1938 -0.4064)
			(stroke
				(width 0.1)
				(type default)
			)
			(layer "F.Fab")
		)
		(fp_line
			(start 0.8636 -0.4572)
			(end 0.8636 -0.4064)
			(stroke
				(width 0.1)
				(type default)
			)
			(layer "F.Fab")
		)
		(fp_line
			(start -0.8636 0.4572)
			(end -0.8636 0.4064)
			(stroke
				(width 0.1)
				(type default)
			)
			(layer "F.Fab")
		)
		(fp_line
			(start -0.8636 0.4064)
			(end -1.1938 0.4064)
			(stroke
				(width 0.1)
				(type default)
			)
			(layer "F.Fab")
		)
		(fp_line
			(start -0.8636 -0.4064)
			(end -0.8636 -0.4572)
			(stroke
				(width 0.1)
				(type default)
			)
			(layer "F.Fab")
		)
		(fp_line
			(start -0.8636 -0.4572)
			(end 0.8636 -0.4572)
			(stroke
				(width 0.1)
				(type default)
			)
			(layer "F.Fab")
		)
		(fp_line
			(start -1.1938 0.4064)
			(end -1.1938 -0.4064)
			(stroke
				(width 0.1)
				(type default)
			)
			(layer "F.Fab")
		)
		(fp_line
			(start -1.1938 -0.4064)
			(end -0.8636 -0.4064)
			(stroke
				(width 0.1)
				(type default)
			)
			(layer "F.Fab")
		)
		(pad "1" smd rect
			(at -0.7366 0 90)
			(size 0.7112 0.8128)
			(layers "F.Cu" "F.Mask" "F.Paste")
			(net "SYSPLL_VDDA18_PEX0_R")
		)
		(pad "2" smd rect
			(at 0.7366 0 90)
			(size 0.7112 0.8128)
			(layers "F.Cu" "F.Mask" "F.Paste")
			(net "GND")
		)
	)
	(footprint ""
		(layer "F.Cu")
		(at 230.620062 -254.454914 -90)
		(property "Reference" "C4286"
			(at 0 0 270)
			(layer "F.SilkS")
			(hide yes)
			(effects
				(font
					(size 1.27 1.27)
				)
			)
		)
		(property "Value" ""
			(at 0 0 270)
			(layer "F.Fab")
			(effects
				(font
					(size 1.27 1.27)
				)
			)
		)
		(duplicate_pad_numbers_are_jumpers no)
		(fp_line
			(start -1.524 0.762)
			(end -1.524 -0.762)
			(stroke
				(width 0.1524)
				(type default)
			)
			(layer "F.SilkS")
		)
		(fp_line
			(start 1.524 0.762)
			(end -1.524 0.762)
			(stroke
				(width 0.1524)
				(type default)
			)
			(layer "F.SilkS")
		)
		(fp_line
			(start -1.524 -0.762)
			(end 1.524 -0.762)
			(stroke
				(width 0.1524)
				(type default)
			)
			(layer "F.SilkS")
		)
		(fp_line
			(start 1.524 -0.762)
			(end 1.524 0.762)
			(stroke
				(width 0.1524)
				(type default)
			)
			(layer "F.SilkS")
		)
		(fp_line
			(start -1.1049 0.724916)
			(end 1.1049 0.724916)
			(stroke
				(width 0.1)
				(type default)
			)
			(layer "F.Fab")
		)
		(fp_line
			(start 1.1049 0.724916)
			(end 1.1049 -0.724916)
			(stroke
				(width 0.1)
				(type default)
			)
			(layer "F.Fab")
		)
		(fp_line
			(start -1.1049 -0.724916)
			(end -1.1049 0.724916)
			(stroke
				(width 0.1)
				(type default)
			)
			(layer "F.Fab")
		)
		(fp_line
			(start 1.1049 -0.724916)
			(end -1.1049 -0.724916)
			(stroke
				(width 0.1)
				(type default)
			)
			(layer "F.Fab")
		)
		(pad "1" smd rect
			(at -0.889 0 90)
			(size 1.016 1.27)
			(layers "F.Cu" "F.Mask" "F.Paste")
			(net "P1V25_SERDES_VDDPLL_PEX1_C4")
		)
		(pad "2" smd rect
			(at 0.889 0 90)
			(size 1.016 1.27)
			(layers "F.Cu" "F.Mask" "F.Paste")
			(net "GND")
		)
		(zone
			(layer "F.Cu")
			(hatch none 0.5)
			(connect_pads
				(clearance 0)
			)
			(min_thickness 0.25)
			(keepout
				(tracks not_allowed)
				(vias allowed)
				(pads allowed)
				(copperpour not_allowed)
				(footprints allowed)
			)
			(placement
				(enabled no)
				(sheetname "")
			)
			(fill
				(thermal_gap 0.5)
				(thermal_bridge_width 0.5)
				(island_removal_mode 0)
			)
			(polygon
				(pts
					(xy 231.344978 -254.785114) (xy 229.895146 -254.785114) (xy 229.895146 -254.124714) (xy 231.344978 -254.124714)
				)
			)
		)
	)
	(footprint ""
		(layer "F.Cu")
		(at 407.009092 -27.04973 180)
		(property "Reference" "C2777"
			(at 0 0 180)
			(layer "F.SilkS")
			(hide yes)
			(effects
				(font
					(size 1.27 1.27)
				)
			)
		)
		(property "Value" ""
			(at 0 0 180)
			(layer "F.Fab")
			(effects
				(font
					(size 1.27 1.27)
				)
			)
		)
		(duplicate_pad_numbers_are_jumpers no)
		(fp_line
			(start 0.7874 0.4064)
			(end -0.7874 0.4064)
			(stroke
				(width 0.1524)
				(type default)
			)
			(layer "F.SilkS")
		)
		(fp_line
			(start 0.7874 -0.4064)
			(end 0.7874 0.4064)
			(stroke
				(width 0.1524)
				(type default)
			)
			(layer "F.SilkS")
		)
		(fp_line
			(start -0.7874 0.4064)
			(end -0.7874 -0.4064)
			(stroke
				(width 0.1524)
				(type default)
			)
			(layer "F.SilkS")
		)
		(fp_line
			(start -0.7874 -0.4064)
			(end 0.7874 -0.4064)
			(stroke
				(width 0.1524)
				(type default)
			)
			(layer "F.SilkS")
		)
		(fp_line
			(start 0.67945 0.3048)
			(end 0.120396 0.3048)
			(stroke
				(width 0.1)
				(type default)
			)
			(layer "F.Fab")
		)
		(fp_line
			(start 0.67945 -0.3048)
			(end 0.67945 0.3048)
			(stroke
				(width 0.1)
				(type default)
			)
			(layer "F.Fab")
		)
		(fp_line
			(start 0.12065 -0.2794)
			(end 0.12065 -0.3048)
			(stroke
				(width 0.1)
				(type default)
			)
			(layer "F.Fab")
		)
		(fp_line
			(start 0.12065 -0.3048)
			(end 0.67945 -0.3048)
			(stroke
				(width 0.1)
				(type default)
			)
			(layer "F.Fab")
		)
		(fp_line
			(start 0.120396 0.3048)
			(end 0.120396 0.2794)
			(stroke
				(width 0.1)
				(type default)
			)
			(layer "F.Fab")
		)
		(fp_line
			(start 0.120396 0.2794)
			(end -0.12065 0.2794)
			(stroke
				(width 0.1)
				(type default)
			)
			(layer "F.Fab")
		)
		(fp_line
			(start -0.12065 0.3048)
			(end -0.67945 0.3048)
			(stroke
				(width 0.1)
				(type default)
			)
			(layer "F.Fab")
		)
		(fp_line
			(start -0.12065 0.2794)
			(end -0.12065 0.3048)
			(stroke
				(width 0.1)
				(type default)
			)
			(layer "F.Fab")
		)
		(fp_line
			(start -0.12065 -0.2794)
			(end 0.12065 -0.2794)
			(stroke
				(width 0.1)
				(type default)
			)
			(layer "F.Fab")
		)
		(fp_line
			(start -0.12065 -0.305054)
			(end -0.12065 -0.2794)
			(stroke
				(width 0.1)
				(type default)
			)
			(layer "F.Fab")
		)
		(fp_line
			(start -0.67945 0.3048)
			(end -0.67945 -0.305054)
			(stroke
				(width 0.1)
				(type default)
			)
			(layer "F.Fab")
		)
		(fp_line
			(start -0.67945 -0.305054)
			(end -0.12065 -0.305054)
			(stroke
				(width 0.1)
				(type default)
			)
			(layer "F.Fab")
		)
		(pad "1" smd circle
			(at -0.40005 0 180)
			(size 0 0)
			(layers "F.Cu" "F.Mask" "F.Paste")
			(net "PRSNT_SSD14_R_N")
		)
		(pad "2" smd circle
			(at 0.40005 0 180)
			(size 0 0)
			(layers "F.Cu" "F.Mask" "F.Paste")
			(net "GND")
		)
	)
	(footprint ""
		(layer "F.Cu")
		(at 136.534652 -34.546286 180)
		(property "Reference" "C276"
			(at 0 0 180)
			(layer "F.SilkS")
			(hide yes)
			(effects
				(font
					(size 1.27 1.27)
				)
			)
		)
		(property "Value" ""
			(at 0 0 180)
			(layer "F.Fab")
			(effects
				(font
					(size 1.27 1.27)
				)
			)
		)
		(duplicate_pad_numbers_are_jumpers no)
		(fp_line
			(start 0.299974 0.150114)
			(end -0.299974 0.150114)
			(stroke
				(width 0.1)
				(type default)
			)
			(layer "F.Fab")
		)
		(fp_line
			(start 0.299974 -0.150114)
			(end 0.299974 0.150114)
			(stroke
				(width 0.1)
				(type default)
			)
			(layer "F.Fab")
		)
		(fp_line
			(start -0.299974 0.150114)
			(end -0.299974 -0.150114)
			(stroke
				(width 0.1)
				(type default)
			)
			(layer "F.Fab")
		)
		(fp_line
			(start -0.299974 -0.150114)
			(end 0.299974 -0.150114)
			(stroke
				(width 0.1)
				(type default)
			)
			(layer "F.Fab")
		)
		(pad "1" smd rect
			(at -0.2667 0 180)
			(size 0.3048 0.381)
			(layers "F.Cu" "F.Mask" "F.Paste")
			(net "P5E_PEX1_STN2_TX_DP<47>")
		)
		(pad "2" smd rect
			(at 0.2667 0 180)
			(size 0.3048 0.381)
			(layers "F.Cu" "F.Mask" "F.Paste")
			(net "P5E_PEX1_STN2_TX_C_DP<47>")
		)
	)
	(footprint ""
		(layer "F.Cu")
		(at 223.706944 -98.36912 -90)
		(property "Reference" "R4454"
			(at 0 0 270)
			(layer "F.SilkS")
			(hide yes)
			(effects
				(font
					(size 1.27 1.27)
				)
			)
		)
		(property "Value" ""
			(at 0 0 270)
			(layer "F.Fab")
			(effects
				(font
					(size 1.27 1.27)
				)
			)
		)
		(duplicate_pad_numbers_are_jumpers no)
		(fp_line
			(start -0.7874 0.4064)
			(end -0.7874 -0.4064)
			(stroke
				(width 0.1524)
				(type default)
			)
			(layer "F.SilkS")
		)
		(fp_line
			(start 0.7874 0.4064)
			(end -0.7874 0.4064)
			(stroke
				(width 0.1524)
				(type default)
			)
			(layer "F.SilkS")
		)
		(fp_line
			(start -0.7874 -0.4064)
			(end 0.7874 -0.4064)
			(stroke
				(width 0.1524)
				(type default)
			)
			(layer "F.SilkS")
		)
		(fp_line
			(start 0.7874 -0.4064)
			(end 0.7874 0.4064)
			(stroke
				(width 0.1524)
				(type default)
			)
			(layer "F.SilkS")
		)
		(fp_line
			(start -0.67945 0.3048)
			(end -0.67945 -0.305054)
			(stroke
				(width 0.1)
				(type default)
			)
			(layer "F.Fab")
		)
		(fp_line
			(start -0.12065 0.3048)
			(end -0.67945 0.3048)
			(stroke
				(width 0.1)
				(type default)
			)
			(layer "F.Fab")
		)
		(fp_line
			(start 0.120396 0.3048)
			(end 0.120396 0.2794)
			(stroke
				(width 0.1)
				(type default)
			)
			(layer "F.Fab")
		)
		(fp_line
			(start 0.67945 0.3048)
			(end 0.120396 0.3048)
			(stroke
				(width 0.1)
				(type default)
			)
			(layer "F.Fab")
		)
		(fp_line
			(start -0.12065 0.2794)
			(end -0.12065 0.3048)
			(stroke
				(width 0.1)
				(type default)
			)
			(layer "F.Fab")
		)
		(fp_line
			(start 0.120396 0.2794)
			(end -0.12065 0.2794)
			(stroke
				(width 0.1)
				(type default)
			)
			(layer "F.Fab")
		)
		(fp_line
			(start -0.12065 -0.2794)
			(end 0.12065 -0.2794)
			(stroke
				(width 0.1)
				(type default)
			)
			(layer "F.Fab")
		)
		(fp_line
			(start 0.12065 -0.2794)
			(end 0.12065 -0.3048)
			(stroke
				(width 0.1)
				(type default)
			)
			(layer "F.Fab")
		)
		(fp_line
			(start 0.12065 -0.3048)
			(end 0.67945 -0.3048)
			(stroke
				(width 0.1)
				(type default)
			)
			(layer "F.Fab")
		)
		(fp_line
			(start 0.67945 -0.3048)
			(end 0.67945 0.3048)
			(stroke
				(width 0.1)
				(type default)
			)
			(layer "F.Fab")
		)
		(fp_line
			(start -0.67945 -0.305054)
			(end -0.12065 -0.305054)
			(stroke
				(width 0.1)
				(type default)
			)
			(layer "F.Fab")
		)
		(fp_line
			(start -0.12065 -0.305054)
			(end -0.12065 -0.2794)
			(stroke
				(width 0.1)
				(type default)
			)
			(layer "F.Fab")
		)
		(pad "1" smd circle
			(at -0.40005 0 270)
			(size 0 0)
			(layers "F.Cu" "F.Mask" "F.Paste")
			(net "PWRGD_P12V_NIC3")
		)
		(pad "2" smd circle
			(at 0.40005 0 270)
			(size 0 0)
			(layers "F.Cu" "F.Mask" "F.Paste")
			(net "PWRGD_P12V_NIC3_R")
		)
	)
	(footprint ""
		(layer "F.Cu")
		(at 173.047406 -36.686998 90)
		(property "Reference" "C3665"
			(at 0 0 90)
			(layer "F.SilkS")
			(hide yes)
			(effects
				(font
					(size 1.27 1.27)
				)
			)
		)
		(property "Value" ""
			(at 0 0 90)
			(layer "F.Fab")
			(effects
				(font
					(size 1.27 1.27)
				)
			)
		)
		(duplicate_pad_numbers_are_jumpers no)
		(fp_line
			(start 0.7874 -0.4064)
			(end 0.7874 0.4064)
			(stroke
				(width 0.1524)
				(type default)
			)
			(layer "F.SilkS")
		)
		(fp_line
			(start -0.7874 -0.4064)
			(end 0.7874 -0.4064)
			(stroke
				(width 0.1524)
				(type default)
			)
			(layer "F.SilkS")
		)
		(fp_line
			(start 0.7874 0.4064)
			(end -0.7874 0.4064)
			(stroke
				(width 0.1524)
				(type default)
			)
			(layer "F.SilkS")
		)
		(fp_line
			(start -0.7874 0.4064)
			(end -0.7874 -0.4064)
			(stroke
				(width 0.1524)
				(type default)
			)
			(layer "F.SilkS")
		)
		(fp_line
			(start -0.12065 -0.305054)
			(end -0.12065 -0.2794)
			(stroke
				(width 0.1)
				(type default)
			)
			(layer "F.Fab")
		)
		(fp_line
			(start -0.67945 -0.305054)
			(end -0.12065 -0.305054)
			(stroke
				(width 0.1)
				(type default)
			)
			(layer "F.Fab")
		)
		(fp_line
			(start 0.67945 -0.3048)
			(end 0.67945 0.3048)
			(stroke
				(width 0.1)
				(type default)
			)
			(layer "F.Fab")
		)
		(fp_line
			(start 0.12065 -0.3048)
			(end 0.67945 -0.3048)
			(stroke
				(width 0.1)
				(type default)
			)
			(layer "F.Fab")
		)
		(fp_line
			(start 0.12065 -0.2794)
			(end 0.12065 -0.3048)
			(stroke
				(width 0.1)
				(type default)
			)
			(layer "F.Fab")
		)
		(fp_line
			(start -0.12065 -0.2794)
			(end 0.12065 -0.2794)
			(stroke
				(width 0.1)
				(type default)
			)
			(layer "F.Fab")
		)
		(fp_line
			(start 0.120396 0.2794)
			(end -0.12065 0.2794)
			(stroke
				(width 0.1)
				(type default)
			)
			(layer "F.Fab")
		)
		(fp_line
			(start -0.12065 0.2794)
			(end -0.12065 0.3048)
			(stroke
				(width 0.1)
				(type default)
			)
			(layer "F.Fab")
		)
		(fp_line
			(start 0.67945 0.3048)
			(end 0.120396 0.3048)
			(stroke
				(width 0.1)
				(type default)
			)
			(layer "F.Fab")
		)
		(fp_line
			(start 0.120396 0.3048)
			(end 0.120396 0.2794)
			(stroke
				(width 0.1)
				(type default)
			)
			(layer "F.Fab")
		)
		(fp_line
			(start -0.12065 0.3048)
			(end -0.67945 0.3048)
			(stroke
				(width 0.1)
				(type default)
			)
			(layer "F.Fab")
		)
		(fp_line
			(start -0.67945 0.3048)
			(end -0.67945 -0.305054)
			(stroke
				(width 0.1)
				(type default)
			)
			(layer "F.Fab")
		)
		(pad "1" smd circle
			(at -0.40005 0 90)
			(size 0 0)
			(layers "F.Cu" "F.Mask" "F.Paste")
			(net "P3V3_AUX")
		)
		(pad "2" smd circle
			(at 0.40005 0 90)
			(size 0 0)
			(layers "F.Cu" "F.Mask" "F.Paste")
			(net "GND")
		)
	)
	(footprint ""
		(layer "F.Cu")
		(at 367.558066 -72.766682 90)
		(property "Reference" "PC880"
			(at 0 0 90)
			(layer "F.SilkS")
			(hide yes)
			(effects
				(font
					(size 1.27 1.27)
				)
			)
		)
		(property "Value" ""
			(at 0 0 90)
			(layer "F.Fab")
			(effects
				(font
					(size 1.27 1.27)
				)
			)
		)
		(duplicate_pad_numbers_are_jumpers no)
		(fp_line
			(start 0.7874 -0.4064)
			(end 0.7874 0.4064)
			(stroke
				(width 0.1524)
				(type default)
			)
			(layer "F.SilkS")
		)
		(fp_line
			(start -0.7874 -0.4064)
			(end 0.7874 -0.4064)
			(stroke
				(width 0.1524)
				(type default)
			)
			(layer "F.SilkS")
		)
		(fp_line
			(start 0.7874 0.4064)
			(end -0.7874 0.4064)
			(stroke
				(width 0.1524)
				(type default)
			)
			(layer "F.SilkS")
		)
		(fp_line
			(start -0.7874 0.4064)
			(end -0.7874 -0.4064)
			(stroke
				(width 0.1524)
				(type default)
			)
			(layer "F.SilkS")
		)
		(fp_line
			(start -0.12065 -0.305054)
			(end -0.12065 -0.2794)
			(stroke
				(width 0.1)
				(type default)
			)
			(layer "F.Fab")
		)
		(fp_line
			(start -0.67945 -0.305054)
			(end -0.12065 -0.305054)
			(stroke
				(width 0.1)
				(type default)
			)
			(layer "F.Fab")
		)
		(fp_line
			(start 0.67945 -0.3048)
			(end 0.67945 0.3048)
			(stroke
				(width 0.1)
				(type default)
			)
			(layer "F.Fab")
		)
		(fp_line
			(start 0.12065 -0.3048)
			(end 0.67945 -0.3048)
			(stroke
				(width 0.1)
				(type default)
			)
			(layer "F.Fab")
		)
		(fp_line
			(start 0.12065 -0.2794)
			(end 0.12065 -0.3048)
			(stroke
				(width 0.1)
				(type default)
			)
			(layer "F.Fab")
		)
		(fp_line
			(start -0.12065 -0.2794)
			(end 0.12065 -0.2794)
			(stroke
				(width 0.1)
				(type default)
			)
			(layer "F.Fab")
		)
		(fp_line
			(start 0.120396 0.2794)
			(end -0.12065 0.2794)
			(stroke
				(width 0.1)
				(type default)
			)
			(layer "F.Fab")
		)
		(fp_line
			(start -0.12065 0.2794)
			(end -0.12065 0.3048)
			(stroke
				(width 0.1)
				(type default)
			)
			(layer "F.Fab")
		)
		(fp_line
			(start 0.67945 0.3048)
			(end 0.120396 0.3048)
			(stroke
				(width 0.1)
				(type default)
			)
			(layer "F.Fab")
		)
		(fp_line
			(start 0.120396 0.3048)
			(end 0.120396 0.2794)
			(stroke
				(width 0.1)
				(type default)
			)
			(layer "F.Fab")
		)
		(fp_line
			(start -0.12065 0.3048)
			(end -0.67945 0.3048)
			(stroke
				(width 0.1)
				(type default)
			)
			(layer "F.Fab")
		)
		(fp_line
			(start -0.67945 0.3048)
			(end -0.67945 -0.305054)
			(stroke
				(width 0.1)
				(type default)
			)
			(layer "F.Fab")
		)
		(pad "1" smd circle
			(at -0.40005 0 90)
			(size 0 0)
			(layers "F.Cu" "F.Mask" "F.Paste")
			(net "P12V_SSD12_CO_MODE")
		)
		(pad "2" smd circle
			(at 0.40005 0 90)
			(size 0 0)
			(layers "F.Cu" "F.Mask" "F.Paste")
			(net "GND")
		)
	)
	(footprint ""
		(layer "F.Cu")
		(at 159.72282 -22.867366 90)
		(property "Reference" "C3911"
			(at 0 0 90)
			(layer "F.SilkS")
			(hide yes)
			(effects
				(font
					(size 1.27 1.27)
				)
			)
		)
		(property "Value" ""
			(at 0 0 90)
			(layer "F.Fab")
			(effects
				(font
					(size 1.27 1.27)
				)
			)
		)
		(duplicate_pad_numbers_are_jumpers no)
		(fp_line
			(start 0.7874 -0.4064)
			(end 0.7874 0.4064)
			(stroke
				(width 0.1524)
				(type default)
			)
			(layer "F.SilkS")
		)
		(fp_line
			(start -0.7874 -0.4064)
			(end 0.7874 -0.4064)
			(stroke
				(width 0.1524)
				(type default)
			)
			(layer "F.SilkS")
		)
		(fp_line
			(start 0.7874 0.4064)
			(end -0.7874 0.4064)
			(stroke
				(width 0.1524)
				(type default)
			)
			(layer "F.SilkS")
		)
		(fp_line
			(start -0.7874 0.4064)
			(end -0.7874 -0.4064)
			(stroke
				(width 0.1524)
				(type default)
			)
			(layer "F.SilkS")
		)
		(fp_line
			(start -0.12065 -0.305054)
			(end -0.12065 -0.2794)
			(stroke
				(width 0.1)
				(type default)
			)
			(layer "F.Fab")
		)
		(fp_line
			(start -0.67945 -0.305054)
			(end -0.12065 -0.305054)
			(stroke
				(width 0.1)
				(type default)
			)
			(layer "F.Fab")
		)
		(fp_line
			(start 0.67945 -0.3048)
			(end 0.67945 0.3048)
			(stroke
				(width 0.1)
				(type default)
			)
			(layer "F.Fab")
		)
		(fp_line
			(start 0.12065 -0.3048)
			(end 0.67945 -0.3048)
			(stroke
				(width 0.1)
				(type default)
			)
			(layer "F.Fab")
		)
		(fp_line
			(start 0.12065 -0.2794)
			(end 0.12065 -0.3048)
			(stroke
				(width 0.1)
				(type default)
			)
			(layer "F.Fab")
		)
		(fp_line
			(start -0.12065 -0.2794)
			(end 0.12065 -0.2794)
			(stroke
				(width 0.1)
				(type default)
			)
			(layer "F.Fab")
		)
		(fp_line
			(start 0.120396 0.2794)
			(end -0.12065 0.2794)
			(stroke
				(width 0.1)
				(type default)
			)
			(layer "F.Fab")
		)
		(fp_line
			(start -0.12065 0.2794)
			(end -0.12065 0.3048)
			(stroke
				(width 0.1)
				(type default)
			)
			(layer "F.Fab")
		)
		(fp_line
			(start 0.67945 0.3048)
			(end 0.120396 0.3048)
			(stroke
				(width 0.1)
				(type default)
			)
			(layer "F.Fab")
		)
		(fp_line
			(start 0.120396 0.3048)
			(end 0.120396 0.2794)
			(stroke
				(width 0.1)
				(type default)
			)
			(layer "F.Fab")
		)
		(fp_line
			(start -0.12065 0.3048)
			(end -0.67945 0.3048)
			(stroke
				(width 0.1)
				(type default)
			)
			(layer "F.Fab")
		)
		(fp_line
			(start -0.67945 0.3048)
			(end -0.67945 -0.305054)
			(stroke
				(width 0.1)
				(type default)
			)
			(layer "F.Fab")
		)
		(pad "1" smd circle
			(at -0.40005 0 90)
			(size 0 0)
			(layers "F.Cu" "F.Mask" "F.Paste")
			(net "P12V_SSD5")
		)
		(pad "2" smd circle
			(at 0.40005 0 90)
			(size 0 0)
			(layers "F.Cu" "F.Mask" "F.Paste")
			(net "GND")
		)
	)
	(footprint ""
		(layer "F.Cu")
		(at 348.04731 -262.322564 -90)
		(property "Reference" "PJ8"
			(at 0 0 270)
			(layer "F.SilkS")
			(hide yes)
			(effects
				(font
					(size 1.27 1.27)
				)
			)
		)
		(property "Value" ""
			(at 0 0 270)
			(layer "F.Fab")
			(effects
				(font
					(size 1.27 1.27)
				)
			)
		)
		(duplicate_pad_numbers_are_jumpers no)
		(pad "1" smd circle
			(at -0.7493 0)
			(size 0 0)
			(layers "F.Cu" "F.Mask" "F.Paste")
			(net "SH_P0V8_PEX3_VSEN3_L")
		)
		(pad "2" smd rect
			(at 0.7493 0 180)
			(size 0.7112 0.8128)
			(layers "F.Cu" "F.Mask" "F.Paste")
			(net "SH_P0V8_PEX3_VSEN3_R")
		)
		(zone
			(layer "F.Cu")
			(hatch none 0.5)
			(connect_pads
				(clearance 0)
			)
			(min_thickness 0.25)
			(keepout
				(tracks allowed)
				(vias not_allowed)
				(pads allowed)
				(copperpour not_allowed)
				(footprints allowed)
			)
			(placement
				(enabled no)
				(sheetname "")
			)
			(fill
				(thermal_gap 0.5)
				(thermal_bridge_width 0.5)
				(island_removal_mode 0)
			)
			(polygon
				(pts
					(xy 347.636084 -261.116064) (xy 348.45371 -261.116064) (xy 348.45371 -263.503664) (xy 347.636084 -263.503664)
				)
			)
		)
	)
	(footprint ""
		(layer "F.Cu")
		(at 244.69471 -157.304994 -90)
		(property "Reference" "PU103"
			(at -3.170936 -0.87249 0)
			(unlocked yes)
			(layer "F.SilkS")
			(effects
				(font
					(size 0.7874 0.5842)
					(thickness 0.1524)
				)
				(justify left)
			)
		)
		(property "Value" ""
			(at 0 0 270)
			(layer "F.Fab")
			(effects
				(font
					(size 1.27 1.27)
				)
			)
		)
		(duplicate_pad_numbers_are_jumpers no)
		(fp_line
			(start -1.549908 2.549906)
			(end -0.753872 2.549906)
			(stroke
				(width 0.1524)
				(type default)
			)
			(layer "F.SilkS")
		)
		(fp_line
			(start -0.245872 2.549906)
			(end 0.245872 2.549906)
			(stroke
				(width 0.1524)
				(type default)
			)
			(layer "F.SilkS")
		)
		(fp_line
			(start 0.753872 2.549906)
			(end 1.549908 2.549906)
			(stroke
				(width 0.1524)
				(type default)
			)
			(layer "F.SilkS")
		)
		(fp_line
			(start 1.549908 2.549906)
			(end 1.549908 2.253996)
			(stroke
				(width 0.1524)
				(type default)
			)
			(layer "F.SilkS")
		)
		(fp_line
			(start -1.549908 2.253996)
			(end -1.549908 2.549906)
			(stroke
				(width 0.1524)
				(type default)
			)
			(layer "F.SilkS")
		)
		(fp_line
			(start 1.549908 -2.253996)
			(end 1.549908 -2.549906)
			(stroke
				(width 0.1524)
				(type default)
			)
			(layer "F.SilkS")
		)
		(fp_line
			(start -1.549908 -2.549906)
			(end -1.549908 -2.251964)
			(stroke
				(width 0.1524)
				(type default)
			)
			(layer "F.SilkS")
		)
		(fp_line
			(start -0.752094 -2.549906)
			(end -1.549908 -2.549906)
			(stroke
				(width 0.1524)
				(type default)
			)
			(layer "F.SilkS")
		)
		(fp_line
			(start 0.2413 -2.549906)
			(end -0.2413 -2.549906)
			(stroke
				(width 0.1524)
				(type default)
			)
			(layer "F.SilkS")
		)
		(fp_line
			(start 1.549908 -2.549906)
			(end 0.752094 -2.549906)
			(stroke
				(width 0.1524)
				(type default)
			)
			(layer "F.SilkS")
		)
		(fp_poly
			(pts
				(xy -1.724152 -2.437892) (xy -2.627376 -2.739136) (xy -2.025396 -3.341116)
			)
			(stroke
				(width 0)
				(type default)
			)
			(fill yes)
			(layer "F.SilkS")
		)
		(fp_line
			(start -1.549908 2.549906)
			(end 1.549908 2.549906)
			(stroke
				(width 0.1)
				(type default)
			)
			(layer "F.Fab")
		)
		(fp_line
			(start 1.549908 2.549906)
			(end 1.549908 -2.549906)
			(stroke
				(width 0.1)
				(type default)
			)
			(layer "F.Fab")
		)
		(fp_line
			(start -1.549908 -2.549906)
			(end -1.549908 2.549906)
			(stroke
				(width 0.1)
				(type default)
			)
			(layer "F.Fab")
		)
		(fp_line
			(start 1.549908 -2.549906)
			(end -1.549908 -2.549906)
			(stroke
				(width 0.1)
				(type default)
			)
			(layer "F.Fab")
		)
		(fp_poly
			(pts
				(xy -1.891538 -1.999996) (xy -2.7432 -1.574292) (xy -2.7432 -2.4257)
			)
			(stroke
				(width 0)
				(type default)
			)
			(fill yes)
			(layer "F.Fab")
		)
		(fp_text user "10"
			(at -1.4224 3.253232 270)
			(unlocked yes)
			(layer "F.SilkS")
			(effects
				(font
					(size 0.635 0.4064)
					(thickness 0.1524)
				)
			)
		)
		(fp_text user "11"
			(at 1.303528 2.912364 270)
			(unlocked yes)
			(layer "F.SilkS")
			(effects
				(font
					(size 0.635 0.4064)
					(thickness 0.1524)
				)
			)
		)
		(fp_text user "9"
			(at -2.338832 2.5908 180)
			(unlocked yes)
			(layer "F.SilkS")
			(effects
				(font
					(size 0.635 0.4064)
					(thickness 0.1524)
				)
			)
		)
		(fp_text user "12"
			(at 2.460244 1.136904 180)
			(unlocked yes)
			(layer "F.SilkS")
			(effects
				(font
					(size 0.635 0.4064)
					(thickness 0.1524)
				)
			)
		)
		(fp_text user "21_22"
			(at 0.429006 -3.467608 270)
			(unlocked yes)
			(layer "F.SilkS")
			(effects
				(font
					(size 0.635 0.4064)
					(thickness 0.1524)
				)
			)
		)
		(fp_text user "20"
			(at 2.31902 -3.75666 180)
			(unlocked yes)
			(layer "F.SilkS")
			(effects
				(font
					(size 0.635 0.4064)
					(thickness 0.1524)
				)
			)
		)
		(fp_text user "11"
			(at 1.1938 3.329432 270)
			(unlocked yes)
			(layer "F.Fab")
			(effects
				(font
					(size 0.635 0.4064)
					(thickness 0.1524)
				)
			)
		)
		(fp_text user "10"
			(at -1.4224 3.253232 270)
			(unlocked yes)
			(layer "F.Fab")
			(effects
				(font
					(size 0.635 0.4064)
					(thickness 0.1524)
				)
			)
		)
		(fp_text user "12"
			(at 2.207768 2.7178 180)
			(unlocked yes)
			(layer "F.Fab")
			(effects
				(font
					(size 0.635 0.4064)
					(thickness 0.1524)
				)
			)
		)
		(fp_text user "9"
			(at -2.338832 2.5908 180)
			(unlocked yes)
			(layer "F.Fab")
			(effects
				(font
					(size 0.635 0.4064)
					(thickness 0.1524)
				)
			)
		)
		(fp_text user "20"
			(at 2.055368 -2.7686 180)
			(unlocked yes)
			(layer "F.Fab")
			(effects
				(font
					(size 0.635 0.4064)
					(thickness 0.1524)
				)
			)
		)
		(fp_text user "21_22"
			(at -0.0762 -3.401568 270)
			(unlocked yes)
			(layer "F.Fab")
			(effects
				(font
					(size 0.635 0.4064)
					(thickness 0.1524)
				)
			)
		)
		(pad "1" smd circle
			(at -1.374902 -1.999996 180)
			(size 0 0)
			(layers "F.Cu" "F.Mask" "F.Paste")
			(net "P12V_NIC4_CO_EN")
		)
		(pad "2" smd rect
			(at -1.400048 -1.500124 180)
			(size 0.254 0.8128)
			(layers "F.Cu" "F.Mask" "F.Paste")
			(net "GND")
		)
		(pad "3" smd rect
			(at -1.400048 -0.999998 180)
			(size 0.254 0.8128)
			(layers "F.Cu" "F.Mask" "F.Paste")
			(net "GND")
		)
		(pad "4" smd rect
			(at -1.400048 -0.499872 180)
			(size 0.254 0.8128)
			(layers "F.Cu" "F.Mask" "F.Paste")
			(net "P12V_NIC4_CO_TIMER")
		)
		(pad "5" smd rect
			(at -1.400048 0 180)
			(size 0.254 0.8128)
			(layers "F.Cu" "F.Mask" "F.Paste")
			(net "P12V_NIC4_CO_ISET")
		)
		(pad "6" smd rect
			(at -1.400048 0.499872 180)
			(size 0.254 0.8128)
			(layers "F.Cu" "F.Mask" "F.Paste")
			(net "P12V_NIC4_CO_SS")
		)
		(pad "7" smd rect
			(at -1.400048 0.999998 180)
			(size 0.254 0.8128)
			(layers "F.Cu" "F.Mask" "F.Paste")
			(net "GND")
		)
		(pad "8" smd rect
			(at -1.400048 1.500124 180)
			(size 0.254 0.8128)
			(layers "F.Cu" "F.Mask" "F.Paste")
			(net "P12V_NIC4_CO_IMON_VR")
		)
		(pad "9" smd rect
			(at -1.400048 1.999996 180)
			(size 0.254 0.8128)
			(layers "F.Cu" "F.Mask" "F.Paste")
			(net "P12V_NIC4_CO_FLTB")
		)
		(pad "10" smd rect
			(at -0.499872 2.400046 270)
			(size 0.254 0.8128)
			(layers "F.Cu" "F.Mask" "F.Paste")
			(net "PWRGD_P12V_NIC4_CO")
		)
		(pad "11" smd rect
			(at 0.499872 2.400046 270)
			(size 0.254 0.8128)
			(layers "F.Cu" "F.Mask" "F.Paste")
			(net "P12V_NIC4_CO_OV_FB")
		)
		(pad "12" smd rect
			(at 1.400048 1.999996 180)
			(size 0.254 0.8128)
			(layers "F.Cu" "F.Mask" "F.Paste")
			(net "P12V_NIC4_CO_AVIN_PD")
		)
		(pad "13" smd rect
			(at 1.400048 1.500124 180)
			(size 0.254 0.8128)
			(layers "F.Cu" "F.Mask" "F.Paste")
			(net "P12V_NIC4_R")
		)
		(pad "14" smd rect
			(at 1.400048 0.999998 180)
			(size 0.254 0.8128)
			(layers "F.Cu" "F.Mask" "F.Paste")
			(net "P12V_NIC4_R")
		)
		(pad "15" smd rect
			(at 1.400048 0.499872 180)
			(size 0.254 0.8128)
			(layers "F.Cu" "F.Mask" "F.Paste")
			(net "P12V_NIC4_R")
		)
		(pad "16" smd rect
			(at 1.400048 0 180)
			(size 0.254 0.8128)
			(layers "F.Cu" "F.Mask" "F.Paste")
			(net "P12V_NIC4_R")
		)
		(pad "17" smd rect
			(at 1.400048 -0.499872 180)
			(size 0.254 0.8128)
			(layers "F.Cu" "F.Mask" "F.Paste")
			(net "P12V_NIC4_R")
		)
		(pad "18" smd rect
			(at 1.400048 -0.999998 180)
			(size 0.254 0.8128)
			(layers "F.Cu" "F.Mask" "F.Paste")
			(net "P12V_NIC4_R")
		)
		(pad "19" smd rect
			(at 1.400048 -1.500124 180)
			(size 0.254 0.8128)
			(layers "F.Cu" "F.Mask" "F.Paste")
			(net "P12V_NIC4_R")
		)
		(pad "20" smd rect
			(at 1.400048 -1.999996 180)
			(size 0.254 0.8128)
			(layers "F.Cu" "F.Mask" "F.Paste")
			(net "P12V_NIC4_R")
		)
		(pad "21_22" smd circle
			(at 0.499872 -2.337562 180)
			(size 0 0)
			(layers "F.Cu" "F.Mask" "F.Paste")
			(net "P12V_AUX")
		)
		(pad "23" smd rect
			(at 0 -1.100074 180)
			(size 0.254 1.27)
			(layers "F.Cu" "F.Mask" "F.Paste")
			(net "P12V_AUX")
		)
		(pad "24" smd rect
			(at 0 -0.199898 180)
			(size 0.254 1.27)
			(layers "F.Cu" "F.Mask" "F.Paste")
			(net "P12V_AUX")
		)
		(pad "25" smd rect
			(at 0 0.700024 180)
			(size 0.254 1.27)
			(layers "F.Cu" "F.Mask" "F.Paste")
			(net "P12V_AUX")
		)
		(pad "26" smd rect
			(at 0 1.599946 180)
			(size 0.254 1.27)
			(layers "F.Cu" "F.Mask" "F.Paste")
			(net "P12V_AUX")
		)
	)
	(footprint ""
		(layer "F.Cu")
		(at 295.77919 -195.362068 90)
		(property "Reference" "R3391"
			(at 0 0 90)
			(layer "F.SilkS")
			(hide yes)
			(effects
				(font
					(size 1.27 1.27)
				)
			)
		)
		(property "Value" ""
			(at 0 0 90)
			(layer "F.Fab")
			(effects
				(font
					(size 1.27 1.27)
				)
			)
		)
		(duplicate_pad_numbers_are_jumpers no)
		(fp_line
			(start 0.7874 -0.4064)
			(end 0.7874 0.4064)
			(stroke
				(width 0.1524)
				(type default)
			)
			(layer "F.SilkS")
		)
		(fp_line
			(start -0.7874 -0.4064)
			(end 0.7874 -0.4064)
			(stroke
				(width 0.1524)
				(type default)
			)
			(layer "F.SilkS")
		)
		(fp_line
			(start 0.7874 0.4064)
			(end -0.7874 0.4064)
			(stroke
				(width 0.1524)
				(type default)
			)
			(layer "F.SilkS")
		)
		(fp_line
			(start -0.7874 0.4064)
			(end -0.7874 -0.4064)
			(stroke
				(width 0.1524)
				(type default)
			)
			(layer "F.SilkS")
		)
		(fp_line
			(start -0.12065 -0.305054)
			(end -0.12065 -0.2794)
			(stroke
				(width 0.1)
				(type default)
			)
			(layer "F.Fab")
		)
		(fp_line
			(start -0.67945 -0.305054)
			(end -0.12065 -0.305054)
			(stroke
				(width 0.1)
				(type default)
			)
			(layer "F.Fab")
		)
		(fp_line
			(start 0.67945 -0.3048)
			(end 0.67945 0.3048)
			(stroke
				(width 0.1)
				(type default)
			)
			(layer "F.Fab")
		)
		(fp_line
			(start 0.12065 -0.3048)
			(end 0.67945 -0.3048)
			(stroke
				(width 0.1)
				(type default)
			)
			(layer "F.Fab")
		)
		(fp_line
			(start 0.12065 -0.2794)
			(end 0.12065 -0.3048)
			(stroke
				(width 0.1)
				(type default)
			)
			(layer "F.Fab")
		)
		(fp_line
			(start -0.12065 -0.2794)
			(end 0.12065 -0.2794)
			(stroke
				(width 0.1)
				(type default)
			)
			(layer "F.Fab")
		)
		(fp_line
			(start 0.120396 0.2794)
			(end -0.12065 0.2794)
			(stroke
				(width 0.1)
				(type default)
			)
			(layer "F.Fab")
		)
		(fp_line
			(start -0.12065 0.2794)
			(end -0.12065 0.3048)
			(stroke
				(width 0.1)
				(type default)
			)
			(layer "F.Fab")
		)
		(fp_line
			(start 0.67945 0.3048)
			(end 0.120396 0.3048)
			(stroke
				(width 0.1)
				(type default)
			)
			(layer "F.Fab")
		)
		(fp_line
			(start 0.120396 0.3048)
			(end 0.120396 0.2794)
			(stroke
				(width 0.1)
				(type default)
			)
			(layer "F.Fab")
		)
		(fp_line
			(start -0.12065 0.3048)
			(end -0.67945 0.3048)
			(stroke
				(width 0.1)
				(type default)
			)
			(layer "F.Fab")
		)
		(fp_line
			(start -0.67945 0.3048)
			(end -0.67945 -0.305054)
			(stroke
				(width 0.1)
				(type default)
			)
			(layer "F.Fab")
		)
		(pad "1" smd circle
			(at -0.40005 0 90)
			(size 0 0)
			(layers "F.Cu" "F.Mask" "F.Paste")
			(net "SPI_BIC1_CLK_R2")
		)
		(pad "2" smd circle
			(at 0.40005 0 90)
			(size 0 0)
			(layers "F.Cu" "F.Mask" "F.Paste")
			(net "SPI_BIC1_CLK_R4")
		)
	)
	(footprint ""
		(layer "F.Cu")
		(at 77.064362 -29.079952 180)
		(property "Reference" "R6200"
			(at 0 0 180)
			(layer "F.SilkS")
			(hide yes)
			(effects
				(font
					(size 1.27 1.27)
				)
			)
		)
		(property "Value" ""
			(at 0 0 180)
			(layer "F.Fab")
			(effects
				(font
					(size 1.27 1.27)
				)
			)
		)
		(duplicate_pad_numbers_are_jumpers no)
		(fp_line
			(start 0.7874 0.4064)
			(end -0.7874 0.4064)
			(stroke
				(width 0.1524)
				(type default)
			)
			(layer "F.SilkS")
		)
		(fp_line
			(start 0.7874 -0.4064)
			(end 0.7874 0.4064)
			(stroke
				(width 0.1524)
				(type default)
			)
			(layer "F.SilkS")
		)
		(fp_line
			(start -0.7874 0.4064)
			(end -0.7874 -0.4064)
			(stroke
				(width 0.1524)
				(type default)
			)
			(layer "F.SilkS")
		)
		(fp_line
			(start -0.7874 -0.4064)
			(end 0.7874 -0.4064)
			(stroke
				(width 0.1524)
				(type default)
			)
			(layer "F.SilkS")
		)
		(fp_line
			(start 0.67945 0.3048)
			(end 0.120396 0.3048)
			(stroke
				(width 0.1)
				(type default)
			)
			(layer "F.Fab")
		)
		(fp_line
			(start 0.67945 -0.3048)
			(end 0.67945 0.3048)
			(stroke
				(width 0.1)
				(type default)
			)
			(layer "F.Fab")
		)
		(fp_line
			(start 0.12065 -0.2794)
			(end 0.12065 -0.3048)
			(stroke
				(width 0.1)
				(type default)
			)
			(layer "F.Fab")
		)
		(fp_line
			(start 0.12065 -0.3048)
			(end 0.67945 -0.3048)
			(stroke
				(width 0.1)
				(type default)
			)
			(layer "F.Fab")
		)
		(fp_line
			(start 0.120396 0.3048)
			(end 0.120396 0.2794)
			(stroke
				(width 0.1)
				(type default)
			)
			(layer "F.Fab")
		)
		(fp_line
			(start 0.120396 0.2794)
			(end -0.12065 0.2794)
			(stroke
				(width 0.1)
				(type default)
			)
			(layer "F.Fab")
		)
		(fp_line
			(start -0.12065 0.3048)
			(end -0.67945 0.3048)
			(stroke
				(width 0.1)
				(type default)
			)
			(layer "F.Fab")
		)
		(fp_line
			(start -0.12065 0.2794)
			(end -0.12065 0.3048)
			(stroke
				(width 0.1)
				(type default)
			)
			(layer "F.Fab")
		)
		(fp_line
			(start -0.12065 -0.2794)
			(end 0.12065 -0.2794)
			(stroke
				(width 0.1)
				(type default)
			)
			(layer "F.Fab")
		)
		(fp_line
			(start -0.12065 -0.305054)
			(end -0.12065 -0.2794)
			(stroke
				(width 0.1)
				(type default)
			)
			(layer "F.Fab")
		)
		(fp_line
			(start -0.67945 0.3048)
			(end -0.67945 -0.305054)
			(stroke
				(width 0.1)
				(type default)
			)
			(layer "F.Fab")
		)
		(fp_line
			(start -0.67945 -0.305054)
			(end -0.12065 -0.305054)
			(stroke
				(width 0.1)
				(type default)
			)
			(layer "F.Fab")
		)
		(pad "1" smd circle
			(at -0.40005 0 180)
			(size 0 0)
			(layers "F.Cu" "F.Mask" "F.Paste")
			(net "GND")
		)
		(pad "2" smd circle
			(at 0.40005 0 180)
			(size 0 0)
			(layers "F.Cu" "F.Mask" "F.Paste")
			(net "SSD2_PWRDIS_R")
		)
	)
	(footprint ""
		(layer "F.Cu")
		(at 38.608 -158.3944 180)
		(property "Reference" "R11"
			(at 0 0 180)
			(layer "F.SilkS")
			(hide yes)
			(effects
				(font
					(size 1.27 1.27)
				)
			)
		)
		(property "Value" ""
			(at 0 0 180)
			(layer "F.Fab")
			(effects
				(font
					(size 1.27 1.27)
				)
			)
		)
		(duplicate_pad_numbers_are_jumpers no)
		(fp_line
			(start 0.7874 0.4064)
			(end -0.7874 0.4064)
			(stroke
				(width 0.1524)
				(type default)
			)
			(layer "F.SilkS")
		)
		(fp_line
			(start 0.7874 -0.4064)
			(end 0.7874 0.4064)
			(stroke
				(width 0.1524)
				(type default)
			)
			(layer "F.SilkS")
		)
		(fp_line
			(start -0.7874 0.4064)
			(end -0.7874 -0.4064)
			(stroke
				(width 0.1524)
				(type default)
			)
			(layer "F.SilkS")
		)
		(fp_line
			(start -0.7874 -0.4064)
			(end 0.7874 -0.4064)
			(stroke
				(width 0.1524)
				(type default)
			)
			(layer "F.SilkS")
		)
		(fp_line
			(start 0.67945 0.3048)
			(end 0.120396 0.3048)
			(stroke
				(width 0.1)
				(type default)
			)
			(layer "F.Fab")
		)
		(fp_line
			(start 0.67945 -0.3048)
			(end 0.67945 0.3048)
			(stroke
				(width 0.1)
				(type default)
			)
			(layer "F.Fab")
		)
		(fp_line
			(start 0.12065 -0.2794)
			(end 0.12065 -0.3048)
			(stroke
				(width 0.1)
				(type default)
			)
			(layer "F.Fab")
		)
		(fp_line
			(start 0.12065 -0.3048)
			(end 0.67945 -0.3048)
			(stroke
				(width 0.1)
				(type default)
			)
			(layer "F.Fab")
		)
		(fp_line
			(start 0.120396 0.3048)
			(end 0.120396 0.2794)
			(stroke
				(width 0.1)
				(type default)
			)
			(layer "F.Fab")
		)
		(fp_line
			(start 0.120396 0.2794)
			(end -0.12065 0.2794)
			(stroke
				(width 0.1)
				(type default)
			)
			(layer "F.Fab")
		)
		(fp_line
			(start -0.12065 0.3048)
			(end -0.67945 0.3048)
			(stroke
				(width 0.1)
				(type default)
			)
			(layer "F.Fab")
		)
		(fp_line
			(start -0.12065 0.2794)
			(end -0.12065 0.3048)
			(stroke
				(width 0.1)
				(type default)
			)
			(layer "F.Fab")
		)
		(fp_line
			(start -0.12065 -0.2794)
			(end 0.12065 -0.2794)
			(stroke
				(width 0.1)
				(type default)
			)
			(layer "F.Fab")
		)
		(fp_line
			(start -0.12065 -0.305054)
			(end -0.12065 -0.2794)
			(stroke
				(width 0.1)
				(type default)
			)
			(layer "F.Fab")
		)
		(fp_line
			(start -0.67945 0.3048)
			(end -0.67945 -0.305054)
			(stroke
				(width 0.1)
				(type default)
			)
			(layer "F.Fab")
		)
		(fp_line
			(start -0.67945 -0.305054)
			(end -0.12065 -0.305054)
			(stroke
				(width 0.1)
				(type default)
			)
			(layer "F.Fab")
		)
		(pad "1" smd circle
			(at -0.40005 0 180)
			(size 0 0)
			(layers "F.Cu" "F.Mask" "F.Paste")
			(net "NIC0_LD_N")
		)
		(pad "2" smd circle
			(at 0.40005 0 180)
			(size 0 0)
			(layers "F.Cu" "F.Mask" "F.Paste")
			(net "P3V3_NIC0")
		)
	)
	(footprint ""
		(layer "F.Cu")
		(at 426.543724 -45.88891)
		(property "Reference" "R664"
			(at 0 0 0)
			(layer "F.SilkS")
			(hide yes)
			(effects
				(font
					(size 1.27 1.27)
				)
			)
		)
		(property "Value" ""
			(at 0 0 0)
			(layer "F.Fab")
			(effects
				(font
					(size 1.27 1.27)
				)
			)
		)
		(duplicate_pad_numbers_are_jumpers no)
		(fp_line
			(start -0.7874 -0.4064)
			(end 0.7874 -0.4064)
			(stroke
				(width 0.1524)
				(type default)
			)
			(layer "F.SilkS")
		)
		(fp_line
			(start -0.7874 0.4064)
			(end -0.7874 -0.4064)
			(stroke
				(width 0.1524)
				(type default)
			)
			(layer "F.SilkS")
		)
		(fp_line
			(start 0.7874 -0.4064)
			(end 0.7874 0.4064)
			(stroke
				(width 0.1524)
				(type default)
			)
			(layer "F.SilkS")
		)
		(fp_line
			(start 0.7874 0.4064)
			(end -0.7874 0.4064)
			(stroke
				(width 0.1524)
				(type default)
			)
			(layer "F.SilkS")
		)
		(fp_line
			(start -0.67945 -0.305054)
			(end -0.12065 -0.305054)
			(stroke
				(width 0.1)
				(type default)
			)
			(layer "F.Fab")
		)
		(fp_line
			(start -0.67945 0.3048)
			(end -0.67945 -0.305054)
			(stroke
				(width 0.1)
				(type default)
			)
			(layer "F.Fab")
		)
		(fp_line
			(start -0.12065 -0.305054)
			(end -0.12065 -0.2794)
			(stroke
				(width 0.1)
				(type default)
			)
			(layer "F.Fab")
		)
		(fp_line
			(start -0.12065 -0.2794)
			(end 0.12065 -0.2794)
			(stroke
				(width 0.1)
				(type default)
			)
			(layer "F.Fab")
		)
		(fp_line
			(start -0.12065 0.2794)
			(end -0.12065 0.3048)
			(stroke
				(width 0.1)
				(type default)
			)
			(layer "F.Fab")
		)
		(fp_line
			(start -0.12065 0.3048)
			(end -0.67945 0.3048)
			(stroke
				(width 0.1)
				(type default)
			)
			(layer "F.Fab")
		)
		(fp_line
			(start 0.120396 0.2794)
			(end -0.12065 0.2794)
			(stroke
				(width 0.1)
				(type default)
			)
			(layer "F.Fab")
		)
		(fp_line
			(start 0.120396 0.3048)
			(end 0.120396 0.2794)
			(stroke
				(width 0.1)
				(type default)
			)
			(layer "F.Fab")
		)
		(fp_line
			(start 0.12065 -0.3048)
			(end 0.67945 -0.3048)
			(stroke
				(width 0.1)
				(type default)
			)
			(layer "F.Fab")
		)
		(fp_line
			(start 0.12065 -0.2794)
			(end 0.12065 -0.3048)
			(stroke
				(width 0.1)
				(type default)
			)
			(layer "F.Fab")
		)
		(fp_line
			(start 0.67945 -0.3048)
			(end 0.67945 0.3048)
			(stroke
				(width 0.1)
				(type default)
			)
			(layer "F.Fab")
		)
		(fp_line
			(start 0.67945 0.3048)
			(end 0.120396 0.3048)
			(stroke
				(width 0.1)
				(type default)
			)
			(layer "F.Fab")
		)
		(pad "1" smd circle
			(at -0.40005 0)
			(size 0 0)
			(layers "F.Cu" "F.Mask" "F.Paste")
			(net "SSD14_ADC_A0")
		)
		(pad "2" smd circle
			(at 0.40005 0)
			(size 0 0)
			(layers "F.Cu" "F.Mask" "F.Paste")
			(net "GND")
		)
	)
	(footprint ""
		(layer "F.Cu")
		(at 418.596572 -356.244906 90)
		(property "Reference" "C2449"
			(at 0 0 90)
			(layer "F.SilkS")
			(hide yes)
			(effects
				(font
					(size 1.27 1.27)
				)
			)
		)
		(property "Value" ""
			(at 0 0 90)
			(layer "F.Fab")
			(effects
				(font
					(size 1.27 1.27)
				)
			)
		)
		(duplicate_pad_numbers_are_jumpers no)
		(fp_line
			(start 0.299974 -0.150114)
			(end 0.299974 0.150114)
			(stroke
				(width 0.1)
				(type default)
			)
			(layer "F.Fab")
		)
		(fp_line
			(start -0.299974 -0.150114)
			(end 0.299974 -0.150114)
			(stroke
				(width 0.1)
				(type default)
			)
			(layer "F.Fab")
		)
		(fp_line
			(start 0.299974 0.150114)
			(end -0.299974 0.150114)
			(stroke
				(width 0.1)
				(type default)
			)
			(layer "F.Fab")
		)
		(fp_line
			(start -0.299974 0.150114)
			(end -0.299974 -0.150114)
			(stroke
				(width 0.1)
				(type default)
			)
			(layer "F.Fab")
		)
		(pad "1" smd rect
			(at -0.2667 0 90)
			(size 0.3048 0.381)
			(layers "F.Cu" "F.Mask" "F.Paste")
			(net "P5E_PEX3_STN4_TX_DP<74>")
		)
		(pad "2" smd rect
			(at 0.2667 0 90)
			(size 0.3048 0.381)
			(layers "F.Cu" "F.Mask" "F.Paste")
			(net "P5E_PEX3_STN4_TX_C_DP<74>")
		)
	)
	(footprint ""
		(layer "F.Cu")
		(at 312.21934 -130.794506 180)
		(property "Reference" "C445"
			(at 0 0 180)
			(layer "F.SilkS")
			(hide yes)
			(effects
				(font
					(size 1.27 1.27)
				)
			)
		)
		(property "Value" ""
			(at 0 0 180)
			(layer "F.Fab")
			(effects
				(font
					(size 1.27 1.27)
				)
			)
		)
		(duplicate_pad_numbers_are_jumpers no)
		(fp_line
			(start 0.299974 0.150114)
			(end -0.299974 0.150114)
			(stroke
				(width 0.1)
				(type default)
			)
			(layer "F.Fab")
		)
		(fp_line
			(start 0.299974 -0.150114)
			(end 0.299974 0.150114)
			(stroke
				(width 0.1)
				(type default)
			)
			(layer "F.Fab")
		)
		(fp_line
			(start -0.299974 0.150114)
			(end -0.299974 -0.150114)
			(stroke
				(width 0.1)
				(type default)
			)
			(layer "F.Fab")
		)
		(fp_line
			(start -0.299974 -0.150114)
			(end 0.299974 -0.150114)
			(stroke
				(width 0.1)
				(type default)
			)
			(layer "F.Fab")
		)
		(pad "1" smd rect
			(at -0.2667 0 180)
			(size 0.3048 0.381)
			(layers "F.Cu" "F.Mask" "F.Paste")
			(net "P5E_PEX2_STN0_TX_DP<4>")
		)
		(pad "2" smd rect
			(at 0.2667 0 180)
			(size 0.3048 0.381)
			(layers "F.Cu" "F.Mask" "F.Paste")
			(net "P5E_PEX2_STN0_TX_C_DP<4>")
		)
	)
	(footprint ""
		(layer "F.Cu")
		(at 457.935838 -314.547758)
		(property "Reference" "PC267"
			(at 0 0 0)
			(layer "F.SilkS")
			(hide yes)
			(effects
				(font
					(size 1.27 1.27)
				)
			)
		)
		(property "Value" ""
			(at 0 0 0)
			(layer "F.Fab")
			(effects
				(font
					(size 1.27 1.27)
				)
			)
		)
		(duplicate_pad_numbers_are_jumpers no)
		(fp_line
			(start -1.524 -0.762)
			(end 1.524 -0.762)
			(stroke
				(width 0.1524)
				(type default)
			)
			(layer "F.SilkS")
		)
		(fp_line
			(start -1.524 0.762)
			(end -1.524 -0.762)
			(stroke
				(width 0.1524)
				(type default)
			)
			(layer "F.SilkS")
		)
		(fp_line
			(start 1.524 -0.762)
			(end 1.524 0.762)
			(stroke
				(width 0.1524)
				(type default)
			)
			(layer "F.SilkS")
		)
		(fp_line
			(start 1.524 0.762)
			(end -1.524 0.762)
			(stroke
				(width 0.1524)
				(type default)
			)
			(layer "F.SilkS")
		)
		(fp_line
			(start -1.1049 -0.724916)
			(end -1.1049 0.724916)
			(stroke
				(width 0.1)
				(type default)
			)
			(layer "F.Fab")
		)
		(fp_line
			(start -1.1049 0.724916)
			(end 1.1049 0.724916)
			(stroke
				(width 0.1)
				(type default)
			)
			(layer "F.Fab")
		)
		(fp_line
			(start 1.1049 -0.724916)
			(end -1.1049 -0.724916)
			(stroke
				(width 0.1)
				(type default)
			)
			(layer "F.Fab")
		)
		(fp_line
			(start 1.1049 0.724916)
			(end 1.1049 -0.724916)
			(stroke
				(width 0.1)
				(type default)
			)
			(layer "F.Fab")
		)
		(pad "1" smd rect
			(at -0.889 0 180)
			(size 1.016 1.27)
			(layers "F.Cu" "F.Mask" "F.Paste")
			(net "SW_P12V_P1V25_PEX3_FLT")
		)
		(pad "2" smd rect
			(at 0.889 0 180)
			(size 1.016 1.27)
			(layers "F.Cu" "F.Mask" "F.Paste")
			(net "GND")
		)
	)
	(footprint ""
		(layer "F.Cu")
		(at 405.694134 -29.507688 -90)
		(property "Reference" "PC972"
			(at 0 0 270)
			(layer "F.SilkS")
			(hide yes)
			(effects
				(font
					(size 1.27 1.27)
				)
			)
		)
		(property "Value" ""
			(at 0 0 270)
			(layer "F.Fab")
			(effects
				(font
					(size 1.27 1.27)
				)
			)
		)
		(duplicate_pad_numbers_are_jumpers no)
		(fp_line
			(start -1.524 0.762)
			(end -1.524 -0.762)
			(stroke
				(width 0.1524)
				(type default)
			)
			(layer "F.SilkS")
		)
		(fp_line
			(start 1.524 0.762)
			(end -1.524 0.762)
			(stroke
				(width 0.1524)
				(type default)
			)
			(layer "F.SilkS")
		)
		(fp_line
			(start -1.524 -0.762)
			(end 1.524 -0.762)
			(stroke
				(width 0.1524)
				(type default)
			)
			(layer "F.SilkS")
		)
		(fp_line
			(start 1.524 -0.762)
			(end 1.524 0.762)
			(stroke
				(width 0.1524)
				(type default)
			)
			(layer "F.SilkS")
		)
		(fp_line
			(start -1.1049 0.724916)
			(end 1.1049 0.724916)
			(stroke
				(width 0.1)
				(type default)
			)
			(layer "F.Fab")
		)
		(fp_line
			(start 1.1049 0.724916)
			(end 1.1049 -0.724916)
			(stroke
				(width 0.1)
				(type default)
			)
			(layer "F.Fab")
		)
		(fp_line
			(start -1.1049 -0.724916)
			(end -1.1049 0.724916)
			(stroke
				(width 0.1)
				(type default)
			)
			(layer "F.Fab")
		)
		(fp_line
			(start 1.1049 -0.724916)
			(end -1.1049 -0.724916)
			(stroke
				(width 0.1)
				(type default)
			)
			(layer "F.Fab")
		)
		(pad "1" smd rect
			(at -0.889 0 90)
			(size 1.016 1.27)
			(layers "F.Cu" "F.Mask" "F.Paste")
			(net "P3V3_SSD14")
		)
		(pad "2" smd rect
			(at 0.889 0 90)
			(size 1.016 1.27)
			(layers "F.Cu" "F.Mask" "F.Paste")
			(net "GND")
		)
	)
	(footprint ""
		(layer "F.Cu")
		(at 258.44373 -48.93691 180)
		(property "Reference" "R5898"
			(at 0 0 180)
			(layer "F.SilkS")
			(hide yes)
			(effects
				(font
					(size 1.27 1.27)
				)
			)
		)
		(property "Value" ""
			(at 0 0 180)
			(layer "F.Fab")
			(effects
				(font
					(size 1.27 1.27)
				)
			)
		)
		(duplicate_pad_numbers_are_jumpers no)
		(fp_line
			(start 0.7874 0.4064)
			(end -0.7874 0.4064)
			(stroke
				(width 0.1524)
				(type default)
			)
			(layer "F.SilkS")
		)
		(fp_line
			(start 0.7874 -0.4064)
			(end 0.7874 0.4064)
			(stroke
				(width 0.1524)
				(type default)
			)
			(layer "F.SilkS")
		)
		(fp_line
			(start -0.7874 0.4064)
			(end -0.7874 -0.4064)
			(stroke
				(width 0.1524)
				(type default)
			)
			(layer "F.SilkS")
		)
		(fp_line
			(start -0.7874 -0.4064)
			(end 0.7874 -0.4064)
			(stroke
				(width 0.1524)
				(type default)
			)
			(layer "F.SilkS")
		)
		(fp_line
			(start 0.67945 0.3048)
			(end 0.120396 0.3048)
			(stroke
				(width 0.1)
				(type default)
			)
			(layer "F.Fab")
		)
		(fp_line
			(start 0.67945 -0.3048)
			(end 0.67945 0.3048)
			(stroke
				(width 0.1)
				(type default)
			)
			(layer "F.Fab")
		)
		(fp_line
			(start 0.12065 -0.2794)
			(end 0.12065 -0.3048)
			(stroke
				(width 0.1)
				(type default)
			)
			(layer "F.Fab")
		)
		(fp_line
			(start 0.12065 -0.3048)
			(end 0.67945 -0.3048)
			(stroke
				(width 0.1)
				(type default)
			)
			(layer "F.Fab")
		)
		(fp_line
			(start 0.120396 0.3048)
			(end 0.120396 0.2794)
			(stroke
				(width 0.1)
				(type default)
			)
			(layer "F.Fab")
		)
		(fp_line
			(start 0.120396 0.2794)
			(end -0.12065 0.2794)
			(stroke
				(width 0.1)
				(type default)
			)
			(layer "F.Fab")
		)
		(fp_line
			(start -0.12065 0.3048)
			(end -0.67945 0.3048)
			(stroke
				(width 0.1)
				(type default)
			)
			(layer "F.Fab")
		)
		(fp_line
			(start -0.12065 0.2794)
			(end -0.12065 0.3048)
			(stroke
				(width 0.1)
				(type default)
			)
			(layer "F.Fab")
		)
		(fp_line
			(start -0.12065 -0.2794)
			(end 0.12065 -0.2794)
			(stroke
				(width 0.1)
				(type default)
			)
			(layer "F.Fab")
		)
		(fp_line
			(start -0.12065 -0.305054)
			(end -0.12065 -0.2794)
			(stroke
				(width 0.1)
				(type default)
			)
			(layer "F.Fab")
		)
		(fp_line
			(start -0.67945 0.3048)
			(end -0.67945 -0.305054)
			(stroke
				(width 0.1)
				(type default)
			)
			(layer "F.Fab")
		)
		(fp_line
			(start -0.67945 -0.305054)
			(end -0.12065 -0.305054)
			(stroke
				(width 0.1)
				(type default)
			)
			(layer "F.Fab")
		)
		(pad "1" smd circle
			(at -0.40005 0 180)
			(size 0 0)
			(layers "F.Cu" "F.Mask" "F.Paste")
			(net "SSD8_ADC_A1")
		)
		(pad "2" smd circle
			(at 0.40005 0 180)
			(size 0 0)
			(layers "F.Cu" "F.Mask" "F.Paste")
			(net "SMB_SSD8_ADC_SDA")
		)
	)
	(footprint ""
		(layer "F.Cu")
		(at 13.0175 -313.890152)
		(property "Reference" "PC207"
			(at 0 0 0)
			(layer "F.SilkS")
			(hide yes)
			(effects
				(font
					(size 1.27 1.27)
				)
			)
		)
		(property "Value" ""
			(at 0 0 0)
			(layer "F.Fab")
			(effects
				(font
					(size 1.27 1.27)
				)
			)
		)
		(duplicate_pad_numbers_are_jumpers no)
		(fp_line
			(start -1.524 -0.762)
			(end 1.524 -0.762)
			(stroke
				(width 0.1524)
				(type default)
			)
			(layer "F.SilkS")
		)
		(fp_line
			(start -1.524 0.762)
			(end -1.524 -0.762)
			(stroke
				(width 0.1524)
				(type default)
			)
			(layer "F.SilkS")
		)
		(fp_line
			(start 1.524 -0.762)
			(end 1.524 0.762)
			(stroke
				(width 0.1524)
				(type default)
			)
			(layer "F.SilkS")
		)
		(fp_line
			(start 1.524 0.762)
			(end -1.524 0.762)
			(stroke
				(width 0.1524)
				(type default)
			)
			(layer "F.SilkS")
		)
		(fp_line
			(start -1.1049 -0.724916)
			(end -1.1049 0.724916)
			(stroke
				(width 0.1)
				(type default)
			)
			(layer "F.Fab")
		)
		(fp_line
			(start -1.1049 0.724916)
			(end 1.1049 0.724916)
			(stroke
				(width 0.1)
				(type default)
			)
			(layer "F.Fab")
		)
		(fp_line
			(start 1.1049 -0.724916)
			(end -1.1049 -0.724916)
			(stroke
				(width 0.1)
				(type default)
			)
			(layer "F.Fab")
		)
		(fp_line
			(start 1.1049 0.724916)
			(end 1.1049 -0.724916)
			(stroke
				(width 0.1)
				(type default)
			)
			(layer "F.Fab")
		)
		(pad "1" smd rect
			(at -0.889 0 180)
			(size 1.016 1.27)
			(layers "F.Cu" "F.Mask" "F.Paste")
			(net "SW_P12V_P1V25_PEX0_FLT")
		)
		(pad "2" smd rect
			(at 0.889 0 180)
			(size 1.016 1.27)
			(layers "F.Cu" "F.Mask" "F.Paste")
			(net "GND")
		)
	)
	(footprint ""
		(layer "F.Cu")
		(at 440.350148 -306.074572 90)
		(property "Reference" "R1445"
			(at 0 0 90)
			(layer "F.SilkS")
			(hide yes)
			(effects
				(font
					(size 1.27 1.27)
				)
			)
		)
		(property "Value" ""
			(at 0 0 90)
			(layer "F.Fab")
			(effects
				(font
					(size 1.27 1.27)
				)
			)
		)
		(duplicate_pad_numbers_are_jumpers no)
		(fp_line
			(start 0.7874 -0.4064)
			(end 0.7874 0.4064)
			(stroke
				(width 0.1524)
				(type default)
			)
			(layer "F.SilkS")
		)
		(fp_line
			(start -0.7874 -0.4064)
			(end 0.7874 -0.4064)
			(stroke
				(width 0.1524)
				(type default)
			)
			(layer "F.SilkS")
		)
		(fp_line
			(start 0.7874 0.4064)
			(end -0.7874 0.4064)
			(stroke
				(width 0.1524)
				(type default)
			)
			(layer "F.SilkS")
		)
		(fp_line
			(start -0.7874 0.4064)
			(end -0.7874 -0.4064)
			(stroke
				(width 0.1524)
				(type default)
			)
			(layer "F.SilkS")
		)
		(fp_line
			(start -0.12065 -0.305054)
			(end -0.12065 -0.2794)
			(stroke
				(width 0.1)
				(type default)
			)
			(layer "F.Fab")
		)
		(fp_line
			(start -0.67945 -0.305054)
			(end -0.12065 -0.305054)
			(stroke
				(width 0.1)
				(type default)
			)
			(layer "F.Fab")
		)
		(fp_line
			(start 0.67945 -0.3048)
			(end 0.67945 0.3048)
			(stroke
				(width 0.1)
				(type default)
			)
			(layer "F.Fab")
		)
		(fp_line
			(start 0.12065 -0.3048)
			(end 0.67945 -0.3048)
			(stroke
				(width 0.1)
				(type default)
			)
			(layer "F.Fab")
		)
		(fp_line
			(start 0.12065 -0.2794)
			(end 0.12065 -0.3048)
			(stroke
				(width 0.1)
				(type default)
			)
			(layer "F.Fab")
		)
		(fp_line
			(start -0.12065 -0.2794)
			(end 0.12065 -0.2794)
			(stroke
				(width 0.1)
				(type default)
			)
			(layer "F.Fab")
		)
		(fp_line
			(start 0.120396 0.2794)
			(end -0.12065 0.2794)
			(stroke
				(width 0.1)
				(type default)
			)
			(layer "F.Fab")
		)
		(fp_line
			(start -0.12065 0.2794)
			(end -0.12065 0.3048)
			(stroke
				(width 0.1)
				(type default)
			)
			(layer "F.Fab")
		)
		(fp_line
			(start 0.67945 0.3048)
			(end 0.120396 0.3048)
			(stroke
				(width 0.1)
				(type default)
			)
			(layer "F.Fab")
		)
		(fp_line
			(start 0.120396 0.3048)
			(end 0.120396 0.2794)
			(stroke
				(width 0.1)
				(type default)
			)
			(layer "F.Fab")
		)
		(fp_line
			(start -0.12065 0.3048)
			(end -0.67945 0.3048)
			(stroke
				(width 0.1)
				(type default)
			)
			(layer "F.Fab")
		)
		(fp_line
			(start -0.67945 0.3048)
			(end -0.67945 -0.305054)
			(stroke
				(width 0.1)
				(type default)
			)
			(layer "F.Fab")
		)
		(pad "1" smd circle
			(at -0.40005 0 90)
			(size 0 0)
			(layers "F.Cu" "F.Mask" "F.Paste")
			(net "PEX3_SPARE6")
		)
		(pad "2" smd circle
			(at 0.40005 0 90)
			(size 0 0)
			(layers "F.Cu" "F.Mask" "F.Paste")
			(net "P1V8_PEX")
		)
	)
	(footprint ""
		(layer "F.Cu")
		(at 165.76802 -19.453098)
		(property "Reference" "R1668"
			(at 0 0 0)
			(layer "F.SilkS")
			(hide yes)
			(effects
				(font
					(size 1.27 1.27)
				)
			)
		)
		(property "Value" ""
			(at 0 0 0)
			(layer "F.Fab")
			(effects
				(font
					(size 1.27 1.27)
				)
			)
		)
		(duplicate_pad_numbers_are_jumpers no)
		(fp_line
			(start -0.7874 -0.4064)
			(end 0.7874 -0.4064)
			(stroke
				(width 0.1524)
				(type default)
			)
			(layer "F.SilkS")
		)
		(fp_line
			(start -0.7874 0.4064)
			(end -0.7874 -0.4064)
			(stroke
				(width 0.1524)
				(type default)
			)
			(layer "F.SilkS")
		)
		(fp_line
			(start 0.7874 -0.4064)
			(end 0.7874 0.4064)
			(stroke
				(width 0.1524)
				(type default)
			)
			(layer "F.SilkS")
		)
		(fp_line
			(start 0.7874 0.4064)
			(end -0.7874 0.4064)
			(stroke
				(width 0.1524)
				(type default)
			)
			(layer "F.SilkS")
		)
		(fp_line
			(start -0.67945 -0.305054)
			(end -0.12065 -0.305054)
			(stroke
				(width 0.1)
				(type default)
			)
			(layer "F.Fab")
		)
		(fp_line
			(start -0.67945 0.3048)
			(end -0.67945 -0.305054)
			(stroke
				(width 0.1)
				(type default)
			)
			(layer "F.Fab")
		)
		(fp_line
			(start -0.12065 -0.305054)
			(end -0.12065 -0.2794)
			(stroke
				(width 0.1)
				(type default)
			)
			(layer "F.Fab")
		)
		(fp_line
			(start -0.12065 -0.2794)
			(end 0.12065 -0.2794)
			(stroke
				(width 0.1)
				(type default)
			)
			(layer "F.Fab")
		)
		(fp_line
			(start -0.12065 0.2794)
			(end -0.12065 0.3048)
			(stroke
				(width 0.1)
				(type default)
			)
			(layer "F.Fab")
		)
		(fp_line
			(start -0.12065 0.3048)
			(end -0.67945 0.3048)
			(stroke
				(width 0.1)
				(type default)
			)
			(layer "F.Fab")
		)
		(fp_line
			(start 0.120396 0.2794)
			(end -0.12065 0.2794)
			(stroke
				(width 0.1)
				(type default)
			)
			(layer "F.Fab")
		)
		(fp_line
			(start 0.120396 0.3048)
			(end 0.120396 0.2794)
			(stroke
				(width 0.1)
				(type default)
			)
			(layer "F.Fab")
		)
		(fp_line
			(start 0.12065 -0.3048)
			(end 0.67945 -0.3048)
			(stroke
				(width 0.1)
				(type default)
			)
			(layer "F.Fab")
		)
		(fp_line
			(start 0.12065 -0.2794)
			(end 0.12065 -0.3048)
			(stroke
				(width 0.1)
				(type default)
			)
			(layer "F.Fab")
		)
		(fp_line
			(start 0.67945 -0.3048)
			(end 0.67945 0.3048)
			(stroke
				(width 0.1)
				(type default)
			)
			(layer "F.Fab")
		)
		(fp_line
			(start 0.67945 0.3048)
			(end 0.120396 0.3048)
			(stroke
				(width 0.1)
				(type default)
			)
			(layer "F.Fab")
		)
		(pad "1" smd circle
			(at -0.40005 0)
			(size 0 0)
			(layers "F.Cu" "F.Mask" "F.Paste")
			(net "SMB_ISO_SSD5_R_SDA")
		)
		(pad "2" smd circle
			(at 0.40005 0)
			(size 0 0)
			(layers "F.Cu" "F.Mask" "F.Paste")
			(net "SMB_ISO_SSD5_SDA")
		)
	)
	(footprint ""
		(layer "F.Cu")
		(at 358.013 -213.36 180)
		(property "Reference" "R4094"
			(at 0 0 180)
			(layer "F.SilkS")
			(hide yes)
			(effects
				(font
					(size 1.27 1.27)
				)
			)
		)
		(property "Value" ""
			(at 0 0 180)
			(layer "F.Fab")
			(effects
				(font
					(size 1.27 1.27)
				)
			)
		)
		(duplicate_pad_numbers_are_jumpers no)
		(fp_line
			(start 0.7874 0.4064)
			(end -0.7874 0.4064)
			(stroke
				(width 0.1524)
				(type default)
			)
			(layer "F.SilkS")
		)
		(fp_line
			(start 0.7874 -0.4064)
			(end 0.7874 0.4064)
			(stroke
				(width 0.1524)
				(type default)
			)
			(layer "F.SilkS")
		)
		(fp_line
			(start -0.7874 0.4064)
			(end -0.7874 -0.4064)
			(stroke
				(width 0.1524)
				(type default)
			)
			(layer "F.SilkS")
		)
		(fp_line
			(start -0.7874 -0.4064)
			(end 0.7874 -0.4064)
			(stroke
				(width 0.1524)
				(type default)
			)
			(layer "F.SilkS")
		)
		(fp_line
			(start 0.67945 0.3048)
			(end 0.120396 0.3048)
			(stroke
				(width 0.1)
				(type default)
			)
			(layer "F.Fab")
		)
		(fp_line
			(start 0.67945 -0.3048)
			(end 0.67945 0.3048)
			(stroke
				(width 0.1)
				(type default)
			)
			(layer "F.Fab")
		)
		(fp_line
			(start 0.12065 -0.2794)
			(end 0.12065 -0.3048)
			(stroke
				(width 0.1)
				(type default)
			)
			(layer "F.Fab")
		)
		(fp_line
			(start 0.12065 -0.3048)
			(end 0.67945 -0.3048)
			(stroke
				(width 0.1)
				(type default)
			)
			(layer "F.Fab")
		)
		(fp_line
			(start 0.120396 0.3048)
			(end 0.120396 0.2794)
			(stroke
				(width 0.1)
				(type default)
			)
			(layer "F.Fab")
		)
		(fp_line
			(start 0.120396 0.2794)
			(end -0.12065 0.2794)
			(stroke
				(width 0.1)
				(type default)
			)
			(layer "F.Fab")
		)
		(fp_line
			(start -0.12065 0.3048)
			(end -0.67945 0.3048)
			(stroke
				(width 0.1)
				(type default)
			)
			(layer "F.Fab")
		)
		(fp_line
			(start -0.12065 0.2794)
			(end -0.12065 0.3048)
			(stroke
				(width 0.1)
				(type default)
			)
			(layer "F.Fab")
		)
		(fp_line
			(start -0.12065 -0.2794)
			(end 0.12065 -0.2794)
			(stroke
				(width 0.1)
				(type default)
			)
			(layer "F.Fab")
		)
		(fp_line
			(start -0.12065 -0.305054)
			(end -0.12065 -0.2794)
			(stroke
				(width 0.1)
				(type default)
			)
			(layer "F.Fab")
		)
		(fp_line
			(start -0.67945 0.3048)
			(end -0.67945 -0.305054)
			(stroke
				(width 0.1)
				(type default)
			)
			(layer "F.Fab")
		)
		(fp_line
			(start -0.67945 -0.305054)
			(end -0.12065 -0.305054)
			(stroke
				(width 0.1)
				(type default)
			)
			(layer "F.Fab")
		)
		(pad "1" smd circle
			(at -0.40005 0 180)
			(size 0 0)
			(layers "F.Cu" "F.Mask" "F.Paste")
			(net "PRSNT_NIC2_FPGA_R_N")
		)
		(pad "2" smd circle
			(at 0.40005 0 180)
			(size 0 0)
			(layers "F.Cu" "F.Mask" "F.Paste")
			(net "PRSNT_NIC2_FPGA_N")
		)
	)
	(footprint ""
		(layer "F.Cu")
		(at 30.081982 -299.391832 180)
		(property "Reference" "C3031"
			(at 0 0 180)
			(layer "F.SilkS")
			(hide yes)
			(effects
				(font
					(size 1.27 1.27)
				)
			)
		)
		(property "Value" ""
			(at 0 0 180)
			(layer "F.Fab")
			(effects
				(font
					(size 1.27 1.27)
				)
			)
		)
		(duplicate_pad_numbers_are_jumpers no)
		(fp_line
			(start 1.2954 0.5842)
			(end -1.2954 0.5842)
			(stroke
				(width 0.1524)
				(type default)
			)
			(layer "F.SilkS")
		)
		(fp_line
			(start 1.2954 -0.5842)
			(end 1.2954 0.5842)
			(stroke
				(width 0.1524)
				(type default)
			)
			(layer "F.SilkS")
		)
		(fp_line
			(start -1.2954 0.5842)
			(end -1.2954 -0.5842)
			(stroke
				(width 0.1524)
				(type default)
			)
			(layer "F.SilkS")
		)
		(fp_line
			(start -1.2954 -0.5842)
			(end 1.2954 -0.5842)
			(stroke
				(width 0.1524)
				(type default)
			)
			(layer "F.SilkS")
		)
		(fp_line
			(start 1.1938 0.4064)
			(end 0.8636 0.4064)
			(stroke
				(width 0.1)
				(type default)
			)
			(layer "F.Fab")
		)
		(fp_line
			(start 1.1938 -0.4064)
			(end 1.1938 0.4064)
			(stroke
				(width 0.1)
				(type default)
			)
			(layer "F.Fab")
		)
		(fp_line
			(start 0.8636 0.4572)
			(end -0.8636 0.4572)
			(stroke
				(width 0.1)
				(type default)
			)
			(layer "F.Fab")
		)
		(fp_line
			(start 0.8636 0.4064)
			(end 0.8636 0.4572)
			(stroke
				(width 0.1)
				(type default)
			)
			(layer "F.Fab")
		)
		(fp_line
			(start 0.8636 -0.4064)
			(end 1.1938 -0.4064)
			(stroke
				(width 0.1)
				(type default)
			)
			(layer "F.Fab")
		)
		(fp_line
			(start 0.8636 -0.4572)
			(end 0.8636 -0.4064)
			(stroke
				(width 0.1)
				(type default)
			)
			(layer "F.Fab")
		)
		(fp_line
			(start -0.8636 0.4572)
			(end -0.8636 0.4064)
			(stroke
				(width 0.1)
				(type default)
			)
			(layer "F.Fab")
		)
		(fp_line
			(start -0.8636 0.4064)
			(end -1.1938 0.4064)
			(stroke
				(width 0.1)
				(type default)
			)
			(layer "F.Fab")
		)
		(fp_line
			(start -0.8636 -0.4064)
			(end -0.8636 -0.4572)
			(stroke
				(width 0.1)
				(type default)
			)
			(layer "F.Fab")
		)
		(fp_line
			(start -0.8636 -0.4572)
			(end 0.8636 -0.4572)
			(stroke
				(width 0.1)
				(type default)
			)
			(layer "F.Fab")
		)
		(fp_line
			(start -1.1938 0.4064)
			(end -1.1938 -0.4064)
			(stroke
				(width 0.1)
				(type default)
			)
			(layer "F.Fab")
		)
		(fp_line
			(start -1.1938 -0.4064)
			(end -0.8636 -0.4064)
			(stroke
				(width 0.1)
				(type default)
			)
			(layer "F.Fab")
		)
		(pad "1" smd rect
			(at -0.7366 0 90)
			(size 0.7112 0.8128)
			(layers "F.Cu" "F.Mask" "F.Paste")
			(net "PCEPLL1_VDDA18_PEX0_R")
		)
		(pad "2" smd rect
			(at 0.7366 0 90)
			(size 0.7112 0.8128)
			(layers "F.Cu" "F.Mask" "F.Paste")
			(net "GND")
		)
	)
	(footprint ""
		(layer "F.Cu")
		(at 104.6734 -202.466956 90)
		(property "Reference" "R6632"
			(at 0 0 90)
			(layer "F.SilkS")
			(hide yes)
			(effects
				(font
					(size 1.27 1.27)
				)
			)
		)
		(property "Value" ""
			(at 0 0 90)
			(layer "F.Fab")
			(effects
				(font
					(size 1.27 1.27)
				)
			)
		)
		(duplicate_pad_numbers_are_jumpers no)
		(fp_line
			(start 0.7874 -0.4064)
			(end 0.7874 0.4064)
			(stroke
				(width 0.1524)
				(type default)
			)
			(layer "F.SilkS")
		)
		(fp_line
			(start -0.7874 -0.4064)
			(end 0.7874 -0.4064)
			(stroke
				(width 0.1524)
				(type default)
			)
			(layer "F.SilkS")
		)
		(fp_line
			(start 0.7874 0.4064)
			(end -0.7874 0.4064)
			(stroke
				(width 0.1524)
				(type default)
			)
			(layer "F.SilkS")
		)
		(fp_line
			(start -0.7874 0.4064)
			(end -0.7874 -0.4064)
			(stroke
				(width 0.1524)
				(type default)
			)
			(layer "F.SilkS")
		)
		(fp_line
			(start -0.12065 -0.305054)
			(end -0.12065 -0.2794)
			(stroke
				(width 0.1)
				(type default)
			)
			(layer "F.Fab")
		)
		(fp_line
			(start -0.67945 -0.305054)
			(end -0.12065 -0.305054)
			(stroke
				(width 0.1)
				(type default)
			)
			(layer "F.Fab")
		)
		(fp_line
			(start 0.67945 -0.3048)
			(end 0.67945 0.3048)
			(stroke
				(width 0.1)
				(type default)
			)
			(layer "F.Fab")
		)
		(fp_line
			(start 0.12065 -0.3048)
			(end 0.67945 -0.3048)
			(stroke
				(width 0.1)
				(type default)
			)
			(layer "F.Fab")
		)
		(fp_line
			(start 0.12065 -0.2794)
			(end 0.12065 -0.3048)
			(stroke
				(width 0.1)
				(type default)
			)
			(layer "F.Fab")
		)
		(fp_line
			(start -0.12065 -0.2794)
			(end 0.12065 -0.2794)
			(stroke
				(width 0.1)
				(type default)
			)
			(layer "F.Fab")
		)
		(fp_line
			(start 0.120396 0.2794)
			(end -0.12065 0.2794)
			(stroke
				(width 0.1)
				(type default)
			)
			(layer "F.Fab")
		)
		(fp_line
			(start -0.12065 0.2794)
			(end -0.12065 0.3048)
			(stroke
				(width 0.1)
				(type default)
			)
			(layer "F.Fab")
		)
		(fp_line
			(start 0.67945 0.3048)
			(end 0.120396 0.3048)
			(stroke
				(width 0.1)
				(type default)
			)
			(layer "F.Fab")
		)
		(fp_line
			(start 0.120396 0.3048)
			(end 0.120396 0.2794)
			(stroke
				(width 0.1)
				(type default)
			)
			(layer "F.Fab")
		)
		(fp_line
			(start -0.12065 0.3048)
			(end -0.67945 0.3048)
			(stroke
				(width 0.1)
				(type default)
			)
			(layer "F.Fab")
		)
		(fp_line
			(start -0.67945 0.3048)
			(end -0.67945 -0.305054)
			(stroke
				(width 0.1)
				(type default)
			)
			(layer "F.Fab")
		)
		(pad "1" smd circle
			(at -0.40005 0 90)
			(size 0 0)
			(layers "F.Cu" "F.Mask" "F.Paste")
			(net "UART_PEX0_CLI_CP2108_RX")
		)
		(pad "2" smd circle
			(at 0.40005 0 90)
			(size 0 0)
			(layers "F.Cu" "F.Mask" "F.Paste")
			(net "UART_PEX0_CLI_R_RX")
		)
	)
	(footprint ""
		(layer "F.Cu")
		(at 86.906608 -306.074572 90)
		(property "Reference" "R3894"
			(at 0 0 90)
			(layer "F.SilkS")
			(hide yes)
			(effects
				(font
					(size 1.27 1.27)
				)
			)
		)
		(property "Value" ""
			(at 0 0 90)
			(layer "F.Fab")
			(effects
				(font
					(size 1.27 1.27)
				)
			)
		)
		(duplicate_pad_numbers_are_jumpers no)
		(fp_line
			(start 0.7874 -0.4064)
			(end 0.7874 0.4064)
			(stroke
				(width 0.1524)
				(type default)
			)
			(layer "F.SilkS")
		)
		(fp_line
			(start -0.7874 -0.4064)
			(end 0.7874 -0.4064)
			(stroke
				(width 0.1524)
				(type default)
			)
			(layer "F.SilkS")
		)
		(fp_line
			(start 0.7874 0.4064)
			(end -0.7874 0.4064)
			(stroke
				(width 0.1524)
				(type default)
			)
			(layer "F.SilkS")
		)
		(fp_line
			(start -0.7874 0.4064)
			(end -0.7874 -0.4064)
			(stroke
				(width 0.1524)
				(type default)
			)
			(layer "F.SilkS")
		)
		(fp_line
			(start -0.12065 -0.305054)
			(end -0.12065 -0.2794)
			(stroke
				(width 0.1)
				(type default)
			)
			(layer "F.Fab")
		)
		(fp_line
			(start -0.67945 -0.305054)
			(end -0.12065 -0.305054)
			(stroke
				(width 0.1)
				(type default)
			)
			(layer "F.Fab")
		)
		(fp_line
			(start 0.67945 -0.3048)
			(end 0.67945 0.3048)
			(stroke
				(width 0.1)
				(type default)
			)
			(layer "F.Fab")
		)
		(fp_line
			(start 0.12065 -0.3048)
			(end 0.67945 -0.3048)
			(stroke
				(width 0.1)
				(type default)
			)
			(layer "F.Fab")
		)
		(fp_line
			(start 0.12065 -0.2794)
			(end 0.12065 -0.3048)
			(stroke
				(width 0.1)
				(type default)
			)
			(layer "F.Fab")
		)
		(fp_line
			(start -0.12065 -0.2794)
			(end 0.12065 -0.2794)
			(stroke
				(width 0.1)
				(type default)
			)
			(layer "F.Fab")
		)
		(fp_line
			(start 0.120396 0.2794)
			(end -0.12065 0.2794)
			(stroke
				(width 0.1)
				(type default)
			)
			(layer "F.Fab")
		)
		(fp_line
			(start -0.12065 0.2794)
			(end -0.12065 0.3048)
			(stroke
				(width 0.1)
				(type default)
			)
			(layer "F.Fab")
		)
		(fp_line
			(start 0.67945 0.3048)
			(end 0.120396 0.3048)
			(stroke
				(width 0.1)
				(type default)
			)
			(layer "F.Fab")
		)
		(fp_line
			(start 0.120396 0.3048)
			(end 0.120396 0.2794)
			(stroke
				(width 0.1)
				(type default)
			)
			(layer "F.Fab")
		)
		(fp_line
			(start -0.12065 0.3048)
			(end -0.67945 0.3048)
			(stroke
				(width 0.1)
				(type default)
			)
			(layer "F.Fab")
		)
		(fp_line
			(start -0.67945 0.3048)
			(end -0.67945 -0.305054)
			(stroke
				(width 0.1)
				(type default)
			)
			(layer "F.Fab")
		)
		(pad "1" smd circle
			(at -0.40005 0 90)
			(size 0 0)
			(layers "F.Cu" "F.Mask" "F.Paste")
			(net "SMB_PEX0_SLAVE_SCL")
		)
		(pad "2" smd circle
			(at 0.40005 0 90)
			(size 0 0)
			(layers "F.Cu" "F.Mask" "F.Paste")
			(net "SMB_PEX0_R_SCL")
		)
	)
	(footprint ""
		(layer "F.Cu")
		(at 278.112982 -350.098614 90)
		(property "Reference" "C2350"
			(at 0 0 90)
			(layer "F.SilkS")
			(hide yes)
			(effects
				(font
					(size 1.27 1.27)
				)
			)
		)
		(property "Value" ""
			(at 0 0 90)
			(layer "F.Fab")
			(effects
				(font
					(size 1.27 1.27)
				)
			)
		)
		(duplicate_pad_numbers_are_jumpers no)
		(fp_line
			(start 0.299974 -0.150114)
			(end 0.299974 0.150114)
			(stroke
				(width 0.1)
				(type default)
			)
			(layer "F.Fab")
		)
		(fp_line
			(start -0.299974 -0.150114)
			(end 0.299974 -0.150114)
			(stroke
				(width 0.1)
				(type default)
			)
			(layer "F.Fab")
		)
		(fp_line
			(start 0.299974 0.150114)
			(end -0.299974 0.150114)
			(stroke
				(width 0.1)
				(type default)
			)
			(layer "F.Fab")
		)
		(fp_line
			(start -0.299974 0.150114)
			(end -0.299974 -0.150114)
			(stroke
				(width 0.1)
				(type default)
			)
			(layer "F.Fab")
		)
		(pad "1" smd rect
			(at -0.2667 0 90)
			(size 0.3048 0.381)
			(layers "F.Cu" "F.Mask" "F.Paste")
			(net "P5E_PEX2_STN4_TX_DN<75>")
		)
		(pad "2" smd rect
			(at 0.2667 0 90)
			(size 0.3048 0.381)
			(layers "F.Cu" "F.Mask" "F.Paste")
			(net "P5E_PEX2_STN4_TX_C_DN<75>")
		)
	)
	(footprint ""
		(layer "F.Cu")
		(at 331.175614 -122.525028)
		(property "Reference" "PC468"
			(at 0 0 0)
			(layer "F.SilkS")
			(hide yes)
			(effects
				(font
					(size 1.27 1.27)
				)
			)
		)
		(property "Value" ""
			(at 0 0 0)
			(layer "F.Fab")
			(effects
				(font
					(size 1.27 1.27)
				)
			)
		)
		(duplicate_pad_numbers_are_jumpers no)
		(fp_line
			(start -0.7874 -0.4064)
			(end 0.7874 -0.4064)
			(stroke
				(width 0.1524)
				(type default)
			)
			(layer "F.SilkS")
		)
		(fp_line
			(start -0.7874 0.4064)
			(end -0.7874 -0.4064)
			(stroke
				(width 0.1524)
				(type default)
			)
			(layer "F.SilkS")
		)
		(fp_line
			(start 0.7874 -0.4064)
			(end 0.7874 0.4064)
			(stroke
				(width 0.1524)
				(type default)
			)
			(layer "F.SilkS")
		)
		(fp_line
			(start 0.7874 0.4064)
			(end -0.7874 0.4064)
			(stroke
				(width 0.1524)
				(type default)
			)
			(layer "F.SilkS")
		)
		(fp_line
			(start -0.67945 -0.305054)
			(end -0.12065 -0.305054)
			(stroke
				(width 0.1)
				(type default)
			)
			(layer "F.Fab")
		)
		(fp_line
			(start -0.67945 0.3048)
			(end -0.67945 -0.305054)
			(stroke
				(width 0.1)
				(type default)
			)
			(layer "F.Fab")
		)
		(fp_line
			(start -0.12065 -0.305054)
			(end -0.12065 -0.2794)
			(stroke
				(width 0.1)
				(type default)
			)
			(layer "F.Fab")
		)
		(fp_line
			(start -0.12065 -0.2794)
			(end 0.12065 -0.2794)
			(stroke
				(width 0.1)
				(type default)
			)
			(layer "F.Fab")
		)
		(fp_line
			(start -0.12065 0.2794)
			(end -0.12065 0.3048)
			(stroke
				(width 0.1)
				(type default)
			)
			(layer "F.Fab")
		)
		(fp_line
			(start -0.12065 0.3048)
			(end -0.67945 0.3048)
			(stroke
				(width 0.1)
				(type default)
			)
			(layer "F.Fab")
		)
		(fp_line
			(start 0.120396 0.2794)
			(end -0.12065 0.2794)
			(stroke
				(width 0.1)
				(type default)
			)
			(layer "F.Fab")
		)
		(fp_line
			(start 0.120396 0.3048)
			(end 0.120396 0.2794)
			(stroke
				(width 0.1)
				(type default)
			)
			(layer "F.Fab")
		)
		(fp_line
			(start 0.12065 -0.3048)
			(end 0.67945 -0.3048)
			(stroke
				(width 0.1)
				(type default)
			)
			(layer "F.Fab")
		)
		(fp_line
			(start 0.12065 -0.2794)
			(end 0.12065 -0.3048)
			(stroke
				(width 0.1)
				(type default)
			)
			(layer "F.Fab")
		)
		(fp_line
			(start 0.67945 -0.3048)
			(end 0.67945 0.3048)
			(stroke
				(width 0.1)
				(type default)
			)
			(layer "F.Fab")
		)
		(fp_line
			(start 0.67945 0.3048)
			(end 0.120396 0.3048)
			(stroke
				(width 0.1)
				(type default)
			)
			(layer "F.Fab")
		)
		(pad "1" smd circle
			(at -0.40005 0)
			(size 0 0)
			(layers "F.Cu" "F.Mask" "F.Paste")
			(net "P5V_AUX")
		)
		(pad "2" smd circle
			(at 0.40005 0)
			(size 0 0)
			(layers "F.Cu" "F.Mask" "F.Paste")
			(net "GND")
		)
	)
	(footprint ""
		(layer "F.Cu")
		(at 212.974936 -188.652404 90)
		(property "Reference" "R5303"
			(at 0 0 90)
			(layer "F.SilkS")
			(hide yes)
			(effects
				(font
					(size 1.27 1.27)
				)
			)
		)
		(property "Value" ""
			(at 0 0 90)
			(layer "F.Fab")
			(effects
				(font
					(size 1.27 1.27)
				)
			)
		)
		(duplicate_pad_numbers_are_jumpers no)
		(fp_line
			(start 0.7874 -0.4064)
			(end 0.7874 0.4064)
			(stroke
				(width 0.1524)
				(type default)
			)
			(layer "F.SilkS")
		)
		(fp_line
			(start -0.7874 -0.4064)
			(end 0.7874 -0.4064)
			(stroke
				(width 0.1524)
				(type default)
			)
			(layer "F.SilkS")
		)
		(fp_line
			(start 0.7874 0.4064)
			(end -0.7874 0.4064)
			(stroke
				(width 0.1524)
				(type default)
			)
			(layer "F.SilkS")
		)
		(fp_line
			(start -0.7874 0.4064)
			(end -0.7874 -0.4064)
			(stroke
				(width 0.1524)
				(type default)
			)
			(layer "F.SilkS")
		)
		(fp_line
			(start -0.12065 -0.305054)
			(end -0.12065 -0.2794)
			(stroke
				(width 0.1)
				(type default)
			)
			(layer "F.Fab")
		)
		(fp_line
			(start -0.67945 -0.305054)
			(end -0.12065 -0.305054)
			(stroke
				(width 0.1)
				(type default)
			)
			(layer "F.Fab")
		)
		(fp_line
			(start 0.67945 -0.3048)
			(end 0.67945 0.3048)
			(stroke
				(width 0.1)
				(type default)
			)
			(layer "F.Fab")
		)
		(fp_line
			(start 0.12065 -0.3048)
			(end 0.67945 -0.3048)
			(stroke
				(width 0.1)
				(type default)
			)
			(layer "F.Fab")
		)
		(fp_line
			(start 0.12065 -0.2794)
			(end 0.12065 -0.3048)
			(stroke
				(width 0.1)
				(type default)
			)
			(layer "F.Fab")
		)
		(fp_line
			(start -0.12065 -0.2794)
			(end 0.12065 -0.2794)
			(stroke
				(width 0.1)
				(type default)
			)
			(layer "F.Fab")
		)
		(fp_line
			(start 0.120396 0.2794)
			(end -0.12065 0.2794)
			(stroke
				(width 0.1)
				(type default)
			)
			(layer "F.Fab")
		)
		(fp_line
			(start -0.12065 0.2794)
			(end -0.12065 0.3048)
			(stroke
				(width 0.1)
				(type default)
			)
			(layer "F.Fab")
		)
		(fp_line
			(start 0.67945 0.3048)
			(end 0.120396 0.3048)
			(stroke
				(width 0.1)
				(type default)
			)
			(layer "F.Fab")
		)
		(fp_line
			(start 0.120396 0.3048)
			(end 0.120396 0.2794)
			(stroke
				(width 0.1)
				(type default)
			)
			(layer "F.Fab")
		)
		(fp_line
			(start -0.12065 0.3048)
			(end -0.67945 0.3048)
			(stroke
				(width 0.1)
				(type default)
			)
			(layer "F.Fab")
		)
		(fp_line
			(start -0.67945 0.3048)
			(end -0.67945 -0.305054)
			(stroke
				(width 0.1)
				(type default)
			)
			(layer "F.Fab")
		)
		(pad "1" smd circle
			(at -0.40005 0 90)
			(size 0 0)
			(layers "F.Cu" "F.Mask" "F.Paste")
			(net "BIC_SEL_FLASH_SW2_R")
		)
		(pad "2" smd circle
			(at 0.40005 0 90)
			(size 0 0)
			(layers "F.Cu" "F.Mask" "F.Paste")
			(net "P3V3_AUX")
		)
	)
	(footprint ""
		(layer "F.Cu")
		(at 128.387856 -170.599862 90)
		(property "Reference" "R1090"
			(at 0 0 90)
			(layer "F.SilkS")
			(hide yes)
			(effects
				(font
					(size 1.27 1.27)
				)
			)
		)
		(property "Value" ""
			(at 0 0 90)
			(layer "F.Fab")
			(effects
				(font
					(size 1.27 1.27)
				)
			)
		)
		(duplicate_pad_numbers_are_jumpers no)
		(fp_line
			(start -0.7874 -0.4064)
			(end 0.7874 -0.4064)
			(stroke
				(width 0.1524)
				(type default)
			)
			(layer "F.SilkS")
		)
		(fp_line
			(start -0.12065 -0.305054)
			(end -0.12065 -0.2794)
			(stroke
				(width 0.1)
				(type default)
			)
			(layer "F.Fab")
		)
		(fp_line
			(start -0.67945 -0.305054)
			(end -0.12065 -0.305054)
			(stroke
				(width 0.1)
				(type default)
			)
			(layer "F.Fab")
		)
		(fp_line
			(start 0.67945 -0.3048)
			(end 0.67945 0.3048)
			(stroke
				(width 0.1)
				(type default)
			)
			(layer "F.Fab")
		)
		(fp_line
			(start 0.12065 -0.3048)
			(end 0.67945 -0.3048)
			(stroke
				(width 0.1)
				(type default)
			)
			(layer "F.Fab")
		)
		(fp_line
			(start 0.12065 -0.2794)
			(end 0.12065 -0.3048)
			(stroke
				(width 0.1)
				(type default)
			)
			(layer "F.Fab")
		)
		(fp_line
			(start -0.12065 -0.2794)
			(end 0.12065 -0.2794)
			(stroke
				(width 0.1)
				(type default)
			)
			(layer "F.Fab")
		)
		(fp_line
			(start 0.120396 0.2794)
			(end -0.12065 0.2794)
			(stroke
				(width 0.1)
				(type default)
			)
			(layer "F.Fab")
		)
		(fp_line
			(start -0.12065 0.2794)
			(end -0.12065 0.3048)
			(stroke
				(width 0.1)
				(type default)
			)
			(layer "F.Fab")
		)
		(fp_line
			(start 0.67945 0.3048)
			(end 0.120396 0.3048)
			(stroke
				(width 0.1)
				(type default)
			)
			(layer "F.Fab")
		)
		(fp_line
			(start 0.120396 0.3048)
			(end 0.120396 0.2794)
			(stroke
				(width 0.1)
				(type default)
			)
			(layer "F.Fab")
		)
		(fp_line
			(start -0.12065 0.3048)
			(end -0.67945 0.3048)
			(stroke
				(width 0.1)
				(type default)
			)
			(layer "F.Fab")
		)
		(fp_line
			(start -0.67945 0.3048)
			(end -0.67945 -0.305054)
			(stroke
				(width 0.1)
				(type default)
			)
			(layer "F.Fab")
		)
		(pad "1" smd circle
			(at -0.40005 0 90)
			(size 0 0)
			(layers "F.Cu" "F.Mask" "F.Paste")
			(net "CLK_100M_DB2000QL_PEX2_S1_R_DP")
		)
		(pad "2" smd circle
			(at 0.40005 0 90)
			(size 0 0)
			(layers "F.Cu" "F.Mask" "F.Paste")
			(net "CLK_100M_DB2000QL_PEX2_S1_DP")
		)
	)
	(footprint ""
		(layer "F.Cu")
		(at 456.018138 -278.79929 90)
		(property "Reference" "C827"
			(at 0 0 90)
			(layer "F.SilkS")
			(hide yes)
			(effects
				(font
					(size 1.27 1.27)
				)
			)
		)
		(property "Value" ""
			(at 0 0 90)
			(layer "F.Fab")
			(effects
				(font
					(size 1.27 1.27)
				)
			)
		)
		(duplicate_pad_numbers_are_jumpers no)
		(fp_line
			(start 0.7874 -0.4064)
			(end 0.7874 0.4064)
			(stroke
				(width 0.1524)
				(type default)
			)
			(layer "F.SilkS")
		)
		(fp_line
			(start -0.7874 -0.4064)
			(end 0.7874 -0.4064)
			(stroke
				(width 0.1524)
				(type default)
			)
			(layer "F.SilkS")
		)
		(fp_line
			(start 0.7874 0.4064)
			(end -0.7874 0.4064)
			(stroke
				(width 0.1524)
				(type default)
			)
			(layer "F.SilkS")
		)
		(fp_line
			(start -0.7874 0.4064)
			(end -0.7874 -0.4064)
			(stroke
				(width 0.1524)
				(type default)
			)
			(layer "F.SilkS")
		)
		(fp_line
			(start -0.12065 -0.305054)
			(end -0.12065 -0.2794)
			(stroke
				(width 0.1)
				(type default)
			)
			(layer "F.Fab")
		)
		(fp_line
			(start -0.67945 -0.305054)
			(end -0.12065 -0.305054)
			(stroke
				(width 0.1)
				(type default)
			)
			(layer "F.Fab")
		)
		(fp_line
			(start 0.67945 -0.3048)
			(end 0.67945 0.3048)
			(stroke
				(width 0.1)
				(type default)
			)
			(layer "F.Fab")
		)
		(fp_line
			(start 0.12065 -0.3048)
			(end 0.67945 -0.3048)
			(stroke
				(width 0.1)
				(type default)
			)
			(layer "F.Fab")
		)
		(fp_line
			(start 0.12065 -0.2794)
			(end 0.12065 -0.3048)
			(stroke
				(width 0.1)
				(type default)
			)
			(layer "F.Fab")
		)
		(fp_line
			(start -0.12065 -0.2794)
			(end 0.12065 -0.2794)
			(stroke
				(width 0.1)
				(type default)
			)
			(layer "F.Fab")
		)
		(fp_line
			(start 0.120396 0.2794)
			(end -0.12065 0.2794)
			(stroke
				(width 0.1)
				(type default)
			)
			(layer "F.Fab")
		)
		(fp_line
			(start -0.12065 0.2794)
			(end -0.12065 0.3048)
			(stroke
				(width 0.1)
				(type default)
			)
			(layer "F.Fab")
		)
		(fp_line
			(start 0.67945 0.3048)
			(end 0.120396 0.3048)
			(stroke
				(width 0.1)
				(type default)
			)
			(layer "F.Fab")
		)
		(fp_line
			(start 0.120396 0.3048)
			(end 0.120396 0.2794)
			(stroke
				(width 0.1)
				(type default)
			)
			(layer "F.Fab")
		)
		(fp_line
			(start -0.12065 0.3048)
			(end -0.67945 0.3048)
			(stroke
				(width 0.1)
				(type default)
			)
			(layer "F.Fab")
		)
		(fp_line
			(start -0.67945 0.3048)
			(end -0.67945 -0.305054)
			(stroke
				(width 0.1)
				(type default)
			)
			(layer "F.Fab")
		)
		(pad "1" smd circle
			(at -0.40005 0 90)
			(size 0 0)
			(layers "F.Cu" "F.Mask" "F.Paste")
			(net "P1V25_PEX3_R")
		)
		(pad "2" smd circle
			(at 0.40005 0 90)
			(size 0 0)
			(layers "F.Cu" "F.Mask" "F.Paste")
			(net "GND")
		)
	)
	(footprint ""
		(layer "F.Cu")
		(at 260.249162 -280.994612 -90)
		(property "Reference" "C3400"
			(at 0 0 270)
			(layer "F.SilkS")
			(hide yes)
			(effects
				(font
					(size 1.27 1.27)
				)
			)
		)
		(property "Value" ""
			(at 0 0 270)
			(layer "F.Fab")
			(effects
				(font
					(size 1.27 1.27)
				)
			)
		)
		(duplicate_pad_numbers_are_jumpers no)
		(fp_line
			(start -0.299974 0.150114)
			(end -0.299974 -0.150114)
			(stroke
				(width 0.1)
				(type default)
			)
			(layer "F.Fab")
		)
		(fp_line
			(start 0.299974 0.150114)
			(end -0.299974 0.150114)
			(stroke
				(width 0.1)
				(type default)
			)
			(layer "F.Fab")
		)
		(fp_line
			(start -0.299974 -0.150114)
			(end 0.299974 -0.150114)
			(stroke
				(width 0.1)
				(type default)
			)
			(layer "F.Fab")
		)
		(fp_line
			(start 0.299974 -0.150114)
			(end 0.299974 0.150114)
			(stroke
				(width 0.1)
				(type default)
			)
			(layer "F.Fab")
		)
		(pad "1" smd rect
			(at -0.2667 0 270)
			(size 0.3048 0.381)
			(layers "F.Cu" "F.Mask" "F.Paste")
			(net "P1V8_PLL0_PEX2")
		)
		(pad "2" smd rect
			(at 0.2667 0 270)
			(size 0.3048 0.381)
			(layers "F.Cu" "F.Mask" "F.Paste")
			(net "GND")
		)
	)
	(footprint ""
		(layer "F.Cu")
		(at 326.694038 -116.410486)
		(property "Reference" "PR7101"
			(at 0 0 0)
			(layer "F.SilkS")
			(hide yes)
			(effects
				(font
					(size 1.27 1.27)
				)
			)
		)
		(property "Value" ""
			(at 0 0 0)
			(layer "F.Fab")
			(effects
				(font
					(size 1.27 1.27)
				)
			)
		)
		(duplicate_pad_numbers_are_jumpers no)
		(fp_line
			(start -0.7874 -0.4064)
			(end 0.7874 -0.4064)
			(stroke
				(width 0.1524)
				(type default)
			)
			(layer "F.SilkS")
		)
		(fp_line
			(start -0.7874 0.4064)
			(end -0.7874 -0.4064)
			(stroke
				(width 0.1524)
				(type default)
			)
			(layer "F.SilkS")
		)
		(fp_line
			(start 0.7874 -0.4064)
			(end 0.7874 0.4064)
			(stroke
				(width 0.1524)
				(type default)
			)
			(layer "F.SilkS")
		)
		(fp_line
			(start 0.7874 0.4064)
			(end -0.7874 0.4064)
			(stroke
				(width 0.1524)
				(type default)
			)
			(layer "F.SilkS")
		)
		(fp_line
			(start -0.67945 -0.305054)
			(end -0.12065 -0.305054)
			(stroke
				(width 0.1)
				(type default)
			)
			(layer "F.Fab")
		)
		(fp_line
			(start -0.67945 0.3048)
			(end -0.67945 -0.305054)
			(stroke
				(width 0.1)
				(type default)
			)
			(layer "F.Fab")
		)
		(fp_line
			(start -0.12065 -0.305054)
			(end -0.12065 -0.2794)
			(stroke
				(width 0.1)
				(type default)
			)
			(layer "F.Fab")
		)
		(fp_line
			(start -0.12065 -0.2794)
			(end 0.12065 -0.2794)
			(stroke
				(width 0.1)
				(type default)
			)
			(layer "F.Fab")
		)
		(fp_line
			(start -0.12065 0.2794)
			(end -0.12065 0.3048)
			(stroke
				(width 0.1)
				(type default)
			)
			(layer "F.Fab")
		)
		(fp_line
			(start -0.12065 0.3048)
			(end -0.67945 0.3048)
			(stroke
				(width 0.1)
				(type default)
			)
			(layer "F.Fab")
		)
		(fp_line
			(start 0.120396 0.2794)
			(end -0.12065 0.2794)
			(stroke
				(width 0.1)
				(type default)
			)
			(layer "F.Fab")
		)
		(fp_line
			(start 0.120396 0.3048)
			(end 0.120396 0.2794)
			(stroke
				(width 0.1)
				(type default)
			)
			(layer "F.Fab")
		)
		(fp_line
			(start 0.12065 -0.3048)
			(end 0.67945 -0.3048)
			(stroke
				(width 0.1)
				(type default)
			)
			(layer "F.Fab")
		)
		(fp_line
			(start 0.12065 -0.2794)
			(end 0.12065 -0.3048)
			(stroke
				(width 0.1)
				(type default)
			)
			(layer "F.Fab")
		)
		(fp_line
			(start 0.67945 -0.3048)
			(end 0.67945 0.3048)
			(stroke
				(width 0.1)
				(type default)
			)
			(layer "F.Fab")
		)
		(fp_line
			(start 0.67945 0.3048)
			(end 0.120396 0.3048)
			(stroke
				(width 0.1)
				(type default)
			)
			(layer "F.Fab")
		)
		(pad "1" smd circle
			(at -0.40005 0)
			(size 0 0)
			(layers "F.Cu" "F.Mask" "F.Paste")
			(net "P3V3_NIC5_CO_MODE")
		)
		(pad "2" smd circle
			(at 0.40005 0)
			(size 0 0)
			(layers "F.Cu" "F.Mask" "F.Paste")
			(net "GND")
		)
	)
	(footprint ""
		(layer "F.Cu")
		(at 259.53212 -32.848042 90)
		(property "Reference" "PC947"
			(at 0 0 90)
			(layer "F.SilkS")
			(hide yes)
			(effects
				(font
					(size 1.27 1.27)
				)
			)
		)
		(property "Value" ""
			(at 0 0 90)
			(layer "F.Fab")
			(effects
				(font
					(size 1.27 1.27)
				)
			)
		)
		(duplicate_pad_numbers_are_jumpers no)
		(fp_line
			(start 0.7874 -0.4064)
			(end 0.7874 0.4064)
			(stroke
				(width 0.1524)
				(type default)
			)
			(layer "F.SilkS")
		)
		(fp_line
			(start -0.7874 -0.4064)
			(end 0.7874 -0.4064)
			(stroke
				(width 0.1524)
				(type default)
			)
			(layer "F.SilkS")
		)
		(fp_line
			(start 0.7874 0.4064)
			(end -0.7874 0.4064)
			(stroke
				(width 0.1524)
				(type default)
			)
			(layer "F.SilkS")
		)
		(fp_line
			(start -0.7874 0.4064)
			(end -0.7874 -0.4064)
			(stroke
				(width 0.1524)
				(type default)
			)
			(layer "F.SilkS")
		)
		(fp_line
			(start -0.12065 -0.305054)
			(end -0.12065 -0.2794)
			(stroke
				(width 0.1)
				(type default)
			)
			(layer "F.Fab")
		)
		(fp_line
			(start -0.67945 -0.305054)
			(end -0.12065 -0.305054)
			(stroke
				(width 0.1)
				(type default)
			)
			(layer "F.Fab")
		)
		(fp_line
			(start 0.67945 -0.3048)
			(end 0.67945 0.3048)
			(stroke
				(width 0.1)
				(type default)
			)
			(layer "F.Fab")
		)
		(fp_line
			(start 0.12065 -0.3048)
			(end 0.67945 -0.3048)
			(stroke
				(width 0.1)
				(type default)
			)
			(layer "F.Fab")
		)
		(fp_line
			(start 0.12065 -0.2794)
			(end 0.12065 -0.3048)
			(stroke
				(width 0.1)
				(type default)
			)
			(layer "F.Fab")
		)
		(fp_line
			(start -0.12065 -0.2794)
			(end 0.12065 -0.2794)
			(stroke
				(width 0.1)
				(type default)
			)
			(layer "F.Fab")
		)
		(fp_line
			(start 0.120396 0.2794)
			(end -0.12065 0.2794)
			(stroke
				(width 0.1)
				(type default)
			)
			(layer "F.Fab")
		)
		(fp_line
			(start -0.12065 0.2794)
			(end -0.12065 0.3048)
			(stroke
				(width 0.1)
				(type default)
			)
			(layer "F.Fab")
		)
		(fp_line
			(start 0.67945 0.3048)
			(end 0.120396 0.3048)
			(stroke
				(width 0.1)
				(type default)
			)
			(layer "F.Fab")
		)
		(fp_line
			(start 0.120396 0.3048)
			(end 0.120396 0.2794)
			(stroke
				(width 0.1)
				(type default)
			)
			(layer "F.Fab")
		)
		(fp_line
			(start -0.12065 0.3048)
			(end -0.67945 0.3048)
			(stroke
				(width 0.1)
				(type default)
			)
			(layer "F.Fab")
		)
		(fp_line
			(start -0.67945 0.3048)
			(end -0.67945 -0.305054)
			(stroke
				(width 0.1)
				(type default)
			)
			(layer "F.Fab")
		)
		(pad "1" smd circle
			(at -0.40005 0 90)
			(size 0 0)
			(layers "F.Cu" "F.Mask" "F.Paste")
			(net "P3V3_SSD9_CO_DV_DT")
		)
		(pad "2" smd circle
			(at 0.40005 0 90)
			(size 0 0)
			(layers "F.Cu" "F.Mask" "F.Paste")
			(net "GND")
		)
	)
	(footprint ""
		(layer "F.Cu")
		(at 15.686786 -112.139476 -90)
		(property "Reference" "PR6915"
			(at 0 0 270)
			(layer "F.SilkS")
			(hide yes)
			(effects
				(font
					(size 1.27 1.27)
				)
			)
		)
		(property "Value" ""
			(at 0 0 270)
			(layer "F.Fab")
			(effects
				(font
					(size 1.27 1.27)
				)
			)
		)
		(duplicate_pad_numbers_are_jumpers no)
		(fp_line
			(start -0.7874 0.4064)
			(end -0.7874 -0.4064)
			(stroke
				(width 0.1524)
				(type default)
			)
			(layer "F.SilkS")
		)
		(fp_line
			(start 0.7874 0.4064)
			(end -0.7874 0.4064)
			(stroke
				(width 0.1524)
				(type default)
			)
			(layer "F.SilkS")
		)
		(fp_line
			(start -0.7874 -0.4064)
			(end 0.7874 -0.4064)
			(stroke
				(width 0.1524)
				(type default)
			)
			(layer "F.SilkS")
		)
		(fp_line
			(start 0.7874 -0.4064)
			(end 0.7874 0.4064)
			(stroke
				(width 0.1524)
				(type default)
			)
			(layer "F.SilkS")
		)
		(fp_line
			(start -0.67945 0.3048)
			(end -0.67945 -0.305054)
			(stroke
				(width 0.1)
				(type default)
			)
			(layer "F.Fab")
		)
		(fp_line
			(start -0.12065 0.3048)
			(end -0.67945 0.3048)
			(stroke
				(width 0.1)
				(type default)
			)
			(layer "F.Fab")
		)
		(fp_line
			(start 0.120396 0.3048)
			(end 0.120396 0.2794)
			(stroke
				(width 0.1)
				(type default)
			)
			(layer "F.Fab")
		)
		(fp_line
			(start 0.67945 0.3048)
			(end 0.120396 0.3048)
			(stroke
				(width 0.1)
				(type default)
			)
			(layer "F.Fab")
		)
		(fp_line
			(start -0.12065 0.2794)
			(end -0.12065 0.3048)
			(stroke
				(width 0.1)
				(type default)
			)
			(layer "F.Fab")
		)
		(fp_line
			(start 0.120396 0.2794)
			(end -0.12065 0.2794)
			(stroke
				(width 0.1)
				(type default)
			)
			(layer "F.Fab")
		)
		(fp_line
			(start -0.12065 -0.2794)
			(end 0.12065 -0.2794)
			(stroke
				(width 0.1)
				(type default)
			)
			(layer "F.Fab")
		)
		(fp_line
			(start 0.12065 -0.2794)
			(end 0.12065 -0.3048)
			(stroke
				(width 0.1)
				(type default)
			)
			(layer "F.Fab")
		)
		(fp_line
			(start 0.12065 -0.3048)
			(end 0.67945 -0.3048)
			(stroke
				(width 0.1)
				(type default)
			)
			(layer "F.Fab")
		)
		(fp_line
			(start 0.67945 -0.3048)
			(end 0.67945 0.3048)
			(stroke
				(width 0.1)
				(type default)
			)
			(layer "F.Fab")
		)
		(fp_line
			(start -0.67945 -0.305054)
			(end -0.12065 -0.305054)
			(stroke
				(width 0.1)
				(type default)
			)
			(layer "F.Fab")
		)
		(fp_line
			(start -0.12065 -0.305054)
			(end -0.12065 -0.2794)
			(stroke
				(width 0.1)
				(type default)
			)
			(layer "F.Fab")
		)
		(pad "1" smd circle
			(at -0.40005 0 270)
			(size 0 0)
			(layers "F.Cu" "F.Mask" "F.Paste")
			(net "P3V3_NIC0_CO_MODE")
		)
		(pad "2" smd circle
			(at 0.40005 0 270)
			(size 0 0)
			(layers "F.Cu" "F.Mask" "F.Paste")
			(net "GND")
		)
	)
	(footprint ""
		(layer "F.Cu")
		(at 111.668306 -230.949754 -90)
		(property "Reference" "PC1006"
			(at 0 0 270)
			(layer "F.SilkS")
			(hide yes)
			(effects
				(font
					(size 1.27 1.27)
				)
			)
		)
		(property "Value" ""
			(at 0 0 270)
			(layer "F.Fab")
			(effects
				(font
					(size 1.27 1.27)
				)
			)
		)
		(duplicate_pad_numbers_are_jumpers no)
		(fp_line
			(start -4.533392 2.249932)
			(end -4.533392 -2.249932)
			(stroke
				(width 0.1524)
				(type default)
			)
			(layer "F.SilkS")
		)
		(fp_line
			(start 4.533392 2.249932)
			(end -4.533392 2.249932)
			(stroke
				(width 0.1524)
				(type default)
			)
			(layer "F.SilkS")
		)
		(fp_line
			(start -4.533392 -2.249932)
			(end 4.533392 -2.249932)
			(stroke
				(width 0.1524)
				(type default)
			)
			(layer "F.SilkS")
		)
		(fp_line
			(start 4.533392 -2.249932)
			(end 4.533392 2.249932)
			(stroke
				(width 0.1524)
				(type default)
			)
			(layer "F.SilkS")
		)
		(fp_poly
			(pts
				(xy -4.533392 -2.326132) (xy -5.39242 -2.326132) (xy -5.39242 2.326132) (xy -4.533392 2.326132)
			)
			(stroke
				(width 0)
				(type default)
			)
			(fill yes)
			(layer "F.SilkS")
		)
		(fp_line
			(start -3.750056 2.249932)
			(end -3.750056 -2.249932)
			(stroke
				(width 0.1)
				(type default)
			)
			(layer "F.Fab")
		)
		(fp_line
			(start 3.750056 2.249932)
			(end -3.750056 2.249932)
			(stroke
				(width 0.1)
				(type default)
			)
			(layer "F.Fab")
		)
		(fp_line
			(start -3.750056 -2.249932)
			(end 3.750056 -2.249932)
			(stroke
				(width 0.1)
				(type default)
			)
			(layer "F.Fab")
		)
		(fp_line
			(start 3.750056 -2.249932)
			(end 3.750056 2.249932)
			(stroke
				(width 0.1)
				(type default)
			)
			(layer "F.Fab")
		)
		(fp_text user "+"
			(at -6.322314 0.786384 0)
			(unlocked yes)
			(layer "F.SilkS")
			(effects
				(font
					(size 1.905 1.4224)
					(thickness 0.1524)
				)
				(justify left)
			)
		)
		(fp_text user "-"
			(at 4.8514 -0.14605 270)
			(unlocked yes)
			(layer "F.SilkS")
			(effects
				(font
					(size 1.905 1.4224)
					(thickness 0.1524)
				)
				(justify left)
			)
		)
		(fp_text user "+"
			(at -6.322314 0.786384 0)
			(unlocked yes)
			(layer "F.Fab")
			(effects
				(font
					(size 1.905 1.4224)
					(thickness 0.1524)
				)
				(justify left)
			)
		)
		(fp_text user "-"
			(at 4.8514 -0.14605 270)
			(unlocked yes)
			(layer "F.Fab")
			(effects
				(font
					(size 1.905 1.4224)
					(thickness 0.1524)
				)
				(justify left)
			)
		)
		(pad "1" smd rect
			(at -3.199892 0 270)
			(size 2.413 2.8194)
			(layers "F.Cu" "F.Mask" "F.Paste")
			(net "P1V8_PEX_R")
		)
		(pad "2" smd rect
			(at 3.199892 0 270)
			(size 2.413 2.8194)
			(layers "F.Cu" "F.Mask" "F.Paste")
			(net "GND")
		)
	)
	(footprint ""
		(layer "F.Cu")
		(at 270.766286 -252.356874 -90)
		(property "Reference" "R1355"
			(at 0 0 270)
			(layer "F.SilkS")
			(hide yes)
			(effects
				(font
					(size 1.27 1.27)
				)
			)
		)
		(property "Value" ""
			(at 0 0 270)
			(layer "F.Fab")
			(effects
				(font
					(size 1.27 1.27)
				)
			)
		)
		(duplicate_pad_numbers_are_jumpers no)
		(fp_line
			(start -0.7874 0.4064)
			(end -0.7874 -0.4064)
			(stroke
				(width 0.1524)
				(type default)
			)
			(layer "F.SilkS")
		)
		(fp_line
			(start 0.7874 0.4064)
			(end -0.7874 0.4064)
			(stroke
				(width 0.1524)
				(type default)
			)
			(layer "F.SilkS")
		)
		(fp_line
			(start -0.7874 -0.4064)
			(end 0.7874 -0.4064)
			(stroke
				(width 0.1524)
				(type default)
			)
			(layer "F.SilkS")
		)
		(fp_line
			(start 0.7874 -0.4064)
			(end 0.7874 0.4064)
			(stroke
				(width 0.1524)
				(type default)
			)
			(layer "F.SilkS")
		)
		(fp_line
			(start -0.67945 0.3048)
			(end -0.67945 -0.305054)
			(stroke
				(width 0.1)
				(type default)
			)
			(layer "F.Fab")
		)
		(fp_line
			(start -0.12065 0.3048)
			(end -0.67945 0.3048)
			(stroke
				(width 0.1)
				(type default)
			)
			(layer "F.Fab")
		)
		(fp_line
			(start 0.120396 0.3048)
			(end 0.120396 0.2794)
			(stroke
				(width 0.1)
				(type default)
			)
			(layer "F.Fab")
		)
		(fp_line
			(start 0.67945 0.3048)
			(end 0.120396 0.3048)
			(stroke
				(width 0.1)
				(type default)
			)
			(layer "F.Fab")
		)
		(fp_line
			(start -0.12065 0.2794)
			(end -0.12065 0.3048)
			(stroke
				(width 0.1)
				(type default)
			)
			(layer "F.Fab")
		)
		(fp_line
			(start 0.120396 0.2794)
			(end -0.12065 0.2794)
			(stroke
				(width 0.1)
				(type default)
			)
			(layer "F.Fab")
		)
		(fp_line
			(start -0.12065 -0.2794)
			(end 0.12065 -0.2794)
			(stroke
				(width 0.1)
				(type default)
			)
			(layer "F.Fab")
		)
		(fp_line
			(start 0.12065 -0.2794)
			(end 0.12065 -0.3048)
			(stroke
				(width 0.1)
				(type default)
			)
			(layer "F.Fab")
		)
		(fp_line
			(start 0.12065 -0.3048)
			(end 0.67945 -0.3048)
			(stroke
				(width 0.1)
				(type default)
			)
			(layer "F.Fab")
		)
		(fp_line
			(start 0.67945 -0.3048)
			(end 0.67945 0.3048)
			(stroke
				(width 0.1)
				(type default)
			)
			(layer "F.Fab")
		)
		(fp_line
			(start -0.67945 -0.305054)
			(end -0.12065 -0.305054)
			(stroke
				(width 0.1)
				(type default)
			)
			(layer "F.Fab")
		)
		(fp_line
			(start -0.12065 -0.305054)
			(end -0.12065 -0.2794)
			(stroke
				(width 0.1)
				(type default)
			)
			(layer "F.Fab")
		)
		(pad "1" smd circle
			(at -0.40005 0 270)
			(size 0 0)
			(layers "F.Cu" "F.Mask" "F.Paste")
			(net "GND")
		)
		(pad "2" smd circle
			(at 0.40005 0 270)
			(size 0 0)
			(layers "F.Cu" "F.Mask" "F.Paste")
			(net "PEX2_DBG_MODE4")
		)
	)
	(footprint ""
		(layer "F.Cu")
		(at 428.957486 -112.504474 90)
		(property "Reference" "C950"
			(at 0 0 90)
			(layer "F.SilkS")
			(hide yes)
			(effects
				(font
					(size 1.27 1.27)
				)
			)
		)
		(property "Value" ""
			(at 0 0 90)
			(layer "F.Fab")
			(effects
				(font
					(size 1.27 1.27)
				)
			)
		)
		(duplicate_pad_numbers_are_jumpers no)
		(fp_line
			(start 1.524 -0.762)
			(end 1.524 0.762)
			(stroke
				(width 0.1524)
				(type default)
			)
			(layer "F.SilkS")
		)
		(fp_line
			(start -1.524 -0.762)
			(end 1.524 -0.762)
			(stroke
				(width 0.1524)
				(type default)
			)
			(layer "F.SilkS")
		)
		(fp_line
			(start 1.524 0.762)
			(end -1.524 0.762)
			(stroke
				(width 0.1524)
				(type default)
			)
			(layer "F.SilkS")
		)
		(fp_line
			(start -1.524 0.762)
			(end -1.524 -0.762)
			(stroke
				(width 0.1524)
				(type default)
			)
			(layer "F.SilkS")
		)
		(fp_line
			(start 1.1049 -0.724916)
			(end -1.1049 -0.724916)
			(stroke
				(width 0.1)
				(type default)
			)
			(layer "F.Fab")
		)
		(fp_line
			(start -1.1049 -0.724916)
			(end -1.1049 0.724916)
			(stroke
				(width 0.1)
				(type default)
			)
			(layer "F.Fab")
		)
		(fp_line
			(start 1.1049 0.724916)
			(end 1.1049 -0.724916)
			(stroke
				(width 0.1)
				(type default)
			)
			(layer "F.Fab")
		)
		(fp_line
			(start -1.1049 0.724916)
			(end 1.1049 0.724916)
			(stroke
				(width 0.1)
				(type default)
			)
			(layer "F.Fab")
		)
		(pad "1" smd rect
			(at -0.889 0 270)
			(size 1.016 1.27)
			(layers "F.Cu" "F.Mask" "F.Paste")
			(net "P12V_NIC7")
		)
		(pad "2" smd rect
			(at 0.889 0 270)
			(size 1.016 1.27)
			(layers "F.Cu" "F.Mask" "F.Paste")
			(net "GND")
		)
	)
	(footprint ""
		(layer "F.Cu")
		(at 213.630256 -233.830622 -90)
		(property "Reference" "R1549"
			(at 0 0 270)
			(layer "F.SilkS")
			(hide yes)
			(effects
				(font
					(size 1.27 1.27)
				)
			)
		)
		(property "Value" ""
			(at 0 0 270)
			(layer "F.Fab")
			(effects
				(font
					(size 1.27 1.27)
				)
			)
		)
		(duplicate_pad_numbers_are_jumpers no)
		(fp_line
			(start -0.7874 0.4064)
			(end -0.7874 -0.4064)
			(stroke
				(width 0.1524)
				(type default)
			)
			(layer "F.SilkS")
		)
		(fp_line
			(start 0.7874 0.4064)
			(end -0.7874 0.4064)
			(stroke
				(width 0.1524)
				(type default)
			)
			(layer "F.SilkS")
		)
		(fp_line
			(start -0.7874 -0.4064)
			(end 0.7874 -0.4064)
			(stroke
				(width 0.1524)
				(type default)
			)
			(layer "F.SilkS")
		)
		(fp_line
			(start 0.7874 -0.4064)
			(end 0.7874 0.4064)
			(stroke
				(width 0.1524)
				(type default)
			)
			(layer "F.SilkS")
		)
		(fp_line
			(start -0.67945 0.3048)
			(end -0.67945 -0.305054)
			(stroke
				(width 0.1)
				(type default)
			)
			(layer "F.Fab")
		)
		(fp_line
			(start -0.12065 0.3048)
			(end -0.67945 0.3048)
			(stroke
				(width 0.1)
				(type default)
			)
			(layer "F.Fab")
		)
		(fp_line
			(start 0.120396 0.3048)
			(end 0.120396 0.2794)
			(stroke
				(width 0.1)
				(type default)
			)
			(layer "F.Fab")
		)
		(fp_line
			(start 0.67945 0.3048)
			(end 0.120396 0.3048)
			(stroke
				(width 0.1)
				(type default)
			)
			(layer "F.Fab")
		)
		(fp_line
			(start -0.12065 0.2794)
			(end -0.12065 0.3048)
			(stroke
				(width 0.1)
				(type default)
			)
			(layer "F.Fab")
		)
		(fp_line
			(start 0.120396 0.2794)
			(end -0.12065 0.2794)
			(stroke
				(width 0.1)
				(type default)
			)
			(layer "F.Fab")
		)
		(fp_line
			(start -0.12065 -0.2794)
			(end 0.12065 -0.2794)
			(stroke
				(width 0.1)
				(type default)
			)
			(layer "F.Fab")
		)
		(fp_line
			(start 0.12065 -0.2794)
			(end 0.12065 -0.3048)
			(stroke
				(width 0.1)
				(type default)
			)
			(layer "F.Fab")
		)
		(fp_line
			(start 0.12065 -0.3048)
			(end 0.67945 -0.3048)
			(stroke
				(width 0.1)
				(type default)
			)
			(layer "F.Fab")
		)
		(fp_line
			(start 0.67945 -0.3048)
			(end 0.67945 0.3048)
			(stroke
				(width 0.1)
				(type default)
			)
			(layer "F.Fab")
		)
		(fp_line
			(start -0.67945 -0.305054)
			(end -0.12065 -0.305054)
			(stroke
				(width 0.1)
				(type default)
			)
			(layer "F.Fab")
		)
		(fp_line
			(start -0.12065 -0.305054)
			(end -0.12065 -0.2794)
			(stroke
				(width 0.1)
				(type default)
			)
			(layer "F.Fab")
		)
		(pad "1" smd circle
			(at -0.40005 0 270)
			(size 0 0)
			(layers "F.Cu" "F.Mask" "F.Paste")
			(net "SMB_PEX_LS_R_SCL")
		)
		(pad "2" smd circle
			(at 0.40005 0 270)
			(size 0 0)
			(layers "F.Cu" "F.Mask" "F.Paste")
			(net "SMB_PEX3_SCL")
		)
	)
	(footprint ""
		(layer "F.Cu")
		(at 175.415194 -20.72513)
		(property "Reference" "H119"
			(at 1.530604 -2.573528 0)
			(unlocked yes)
			(layer "B.SilkS")
			(effects
				(font
					(size 0.7874 0.5842)
					(thickness 0.1524)
				)
				(justify left mirror)
			)
		)
		(property "Value" ""
			(at 0 0 0)
			(layer "F.Fab")
			(effects
				(font
					(size 1.27 1.27)
				)
			)
		)
		(duplicate_pad_numbers_are_jumpers no)
		(pad "1" thru_hole rect
			(at 0 0)
			(size 4.2164 5.0038)
			(drill 2.0066
				(offset 0.099822 0)
			)
			(layers "*.Cu" "*.Mask")
			(remove_unused_layers no)
			(net "Net_8544")
			(clearance -0.8509)
			(padstack
				(mode front_inner_back)
				(layer "Inner"
					(shape circle)
					(size 4.0132 4.0132)
					(clearance -0.7493)
				)
				(layer "B.Cu"
					(shape circle)
					(size 4.0132 4.0132)
					(clearance -0.7493)
				)
			)
		)
	)
	(footprint ""
		(layer "F.Cu")
		(at 101.152198 -95.264224 90)
		(property "Reference" "R4448"
			(at 0 0 90)
			(layer "F.SilkS")
			(hide yes)
			(effects
				(font
					(size 1.27 1.27)
				)
			)
		)
		(property "Value" ""
			(at 0 0 90)
			(layer "F.Fab")
			(effects
				(font
					(size 1.27 1.27)
				)
			)
		)
		(duplicate_pad_numbers_are_jumpers no)
		(fp_line
			(start 0.7874 -0.4064)
			(end 0.7874 0.4064)
			(stroke
				(width 0.1524)
				(type default)
			)
			(layer "F.SilkS")
		)
		(fp_line
			(start -0.7874 -0.4064)
			(end 0.7874 -0.4064)
			(stroke
				(width 0.1524)
				(type default)
			)
			(layer "F.SilkS")
		)
		(fp_line
			(start 0.7874 0.4064)
			(end -0.7874 0.4064)
			(stroke
				(width 0.1524)
				(type default)
			)
			(layer "F.SilkS")
		)
		(fp_line
			(start -0.7874 0.4064)
			(end -0.7874 -0.4064)
			(stroke
				(width 0.1524)
				(type default)
			)
			(layer "F.SilkS")
		)
		(fp_line
			(start -0.12065 -0.305054)
			(end -0.12065 -0.2794)
			(stroke
				(width 0.1)
				(type default)
			)
			(layer "F.Fab")
		)
		(fp_line
			(start -0.67945 -0.305054)
			(end -0.12065 -0.305054)
			(stroke
				(width 0.1)
				(type default)
			)
			(layer "F.Fab")
		)
		(fp_line
			(start 0.67945 -0.3048)
			(end 0.67945 0.3048)
			(stroke
				(width 0.1)
				(type default)
			)
			(layer "F.Fab")
		)
		(fp_line
			(start 0.12065 -0.3048)
			(end 0.67945 -0.3048)
			(stroke
				(width 0.1)
				(type default)
			)
			(layer "F.Fab")
		)
		(fp_line
			(start 0.12065 -0.2794)
			(end 0.12065 -0.3048)
			(stroke
				(width 0.1)
				(type default)
			)
			(layer "F.Fab")
		)
		(fp_line
			(start -0.12065 -0.2794)
			(end 0.12065 -0.2794)
			(stroke
				(width 0.1)
				(type default)
			)
			(layer "F.Fab")
		)
		(fp_line
			(start 0.120396 0.2794)
			(end -0.12065 0.2794)
			(stroke
				(width 0.1)
				(type default)
			)
			(layer "F.Fab")
		)
		(fp_line
			(start -0.12065 0.2794)
			(end -0.12065 0.3048)
			(stroke
				(width 0.1)
				(type default)
			)
			(layer "F.Fab")
		)
		(fp_line
			(start 0.67945 0.3048)
			(end 0.120396 0.3048)
			(stroke
				(width 0.1)
				(type default)
			)
			(layer "F.Fab")
		)
		(fp_line
			(start 0.120396 0.3048)
			(end 0.120396 0.2794)
			(stroke
				(width 0.1)
				(type default)
			)
			(layer "F.Fab")
		)
		(fp_line
			(start -0.12065 0.3048)
			(end -0.67945 0.3048)
			(stroke
				(width 0.1)
				(type default)
			)
			(layer "F.Fab")
		)
		(fp_line
			(start -0.67945 0.3048)
			(end -0.67945 -0.305054)
			(stroke
				(width 0.1)
				(type default)
			)
			(layer "F.Fab")
		)
		(pad "1" smd circle
			(at -0.40005 0 90)
			(size 0 0)
			(layers "F.Cu" "F.Mask" "F.Paste")
			(net "HP_NIC1_EN")
		)
		(pad "2" smd circle
			(at 0.40005 0 90)
			(size 0 0)
			(layers "F.Cu" "F.Mask" "F.Paste")
			(net "P12V_NIC1_EN_R")
		)
	)
	(footprint ""
		(layer "F.Cu")
		(at 136.445244 -94.671642 180)
		(property "Reference" "R1588"
			(at 0 0 180)
			(layer "F.SilkS")
			(hide yes)
			(effects
				(font
					(size 1.27 1.27)
				)
			)
		)
		(property "Value" ""
			(at 0 0 180)
			(layer "F.Fab")
			(effects
				(font
					(size 1.27 1.27)
				)
			)
		)
		(duplicate_pad_numbers_are_jumpers no)
		(fp_line
			(start 0.7874 0.4064)
			(end -0.7874 0.4064)
			(stroke
				(width 0.1524)
				(type default)
			)
			(layer "F.SilkS")
		)
		(fp_line
			(start 0.7874 -0.4064)
			(end 0.7874 0.4064)
			(stroke
				(width 0.1524)
				(type default)
			)
			(layer "F.SilkS")
		)
		(fp_line
			(start -0.7874 0.4064)
			(end -0.7874 -0.4064)
			(stroke
				(width 0.1524)
				(type default)
			)
			(layer "F.SilkS")
		)
		(fp_line
			(start -0.7874 -0.4064)
			(end 0.7874 -0.4064)
			(stroke
				(width 0.1524)
				(type default)
			)
			(layer "F.SilkS")
		)
		(fp_line
			(start 0.67945 0.3048)
			(end 0.120396 0.3048)
			(stroke
				(width 0.1)
				(type default)
			)
			(layer "F.Fab")
		)
		(fp_line
			(start 0.67945 -0.3048)
			(end 0.67945 0.3048)
			(stroke
				(width 0.1)
				(type default)
			)
			(layer "F.Fab")
		)
		(fp_line
			(start 0.12065 -0.2794)
			(end 0.12065 -0.3048)
			(stroke
				(width 0.1)
				(type default)
			)
			(layer "F.Fab")
		)
		(fp_line
			(start 0.12065 -0.3048)
			(end 0.67945 -0.3048)
			(stroke
				(width 0.1)
				(type default)
			)
			(layer "F.Fab")
		)
		(fp_line
			(start 0.120396 0.3048)
			(end 0.120396 0.2794)
			(stroke
				(width 0.1)
				(type default)
			)
			(layer "F.Fab")
		)
		(fp_line
			(start 0.120396 0.2794)
			(end -0.12065 0.2794)
			(stroke
				(width 0.1)
				(type default)
			)
			(layer "F.Fab")
		)
		(fp_line
			(start -0.12065 0.3048)
			(end -0.67945 0.3048)
			(stroke
				(width 0.1)
				(type default)
			)
			(layer "F.Fab")
		)
		(fp_line
			(start -0.12065 0.2794)
			(end -0.12065 0.3048)
			(stroke
				(width 0.1)
				(type default)
			)
			(layer "F.Fab")
		)
		(fp_line
			(start -0.12065 -0.2794)
			(end 0.12065 -0.2794)
			(stroke
				(width 0.1)
				(type default)
			)
			(layer "F.Fab")
		)
		(fp_line
			(start -0.12065 -0.305054)
			(end -0.12065 -0.2794)
			(stroke
				(width 0.1)
				(type default)
			)
			(layer "F.Fab")
		)
		(fp_line
			(start -0.67945 0.3048)
			(end -0.67945 -0.305054)
			(stroke
				(width 0.1)
				(type default)
			)
			(layer "F.Fab")
		)
		(fp_line
			(start -0.67945 -0.305054)
			(end -0.12065 -0.305054)
			(stroke
				(width 0.1)
				(type default)
			)
			(layer "F.Fab")
		)
		(pad "1" smd circle
			(at -0.40005 0 180)
			(size 0 0)
			(layers "F.Cu" "F.Mask" "F.Paste")
			(net "SMB_BIC_I2C9_MUX0_SSD7_R_SDA")
		)
		(pad "2" smd circle
			(at 0.40005 0 180)
			(size 0 0)
			(layers "F.Cu" "F.Mask" "F.Paste")
			(net "SMB_BIC_I2C9_MUX0_SSD7_SDA")
		)
	)
	(footprint ""
		(layer "F.Cu")
		(at 36.638484 -134.923276)
		(property "Reference" "C36"
			(at 0 0 0)
			(layer "F.SilkS")
			(hide yes)
			(effects
				(font
					(size 1.27 1.27)
				)
			)
		)
		(property "Value" ""
			(at 0 0 0)
			(layer "F.Fab")
			(effects
				(font
					(size 1.27 1.27)
				)
			)
		)
		(duplicate_pad_numbers_are_jumpers no)
		(fp_line
			(start -0.299974 -0.150114)
			(end 0.299974 -0.150114)
			(stroke
				(width 0.1)
				(type default)
			)
			(layer "F.Fab")
		)
		(fp_line
			(start -0.299974 0.150114)
			(end -0.299974 -0.150114)
			(stroke
				(width 0.1)
				(type default)
			)
			(layer "F.Fab")
		)
		(fp_line
			(start 0.299974 -0.150114)
			(end 0.299974 0.150114)
			(stroke
				(width 0.1)
				(type default)
			)
			(layer "F.Fab")
		)
		(fp_line
			(start 0.299974 0.150114)
			(end -0.299974 0.150114)
			(stroke
				(width 0.1)
				(type default)
			)
			(layer "F.Fab")
		)
		(pad "1" smd rect
			(at -0.2667 0)
			(size 0.3048 0.381)
			(layers "F.Cu" "F.Mask" "F.Paste")
			(net "P5E_PEX0_STN1_TX_DN<30>")
		)
		(pad "2" smd rect
			(at 0.2667 0)
			(size 0.3048 0.381)
			(layers "F.Cu" "F.Mask" "F.Paste")
			(net "P5E_PEX0_STN1_TX_C_DN<30>")
		)
	)
	(footprint ""
		(layer "F.Cu")
		(at 336.443574 -49.95291 180)
		(property "Reference" "R632"
			(at 0 0 180)
			(layer "F.SilkS")
			(hide yes)
			(effects
				(font
					(size 1.27 1.27)
				)
			)
		)
		(property "Value" ""
			(at 0 0 180)
			(layer "F.Fab")
			(effects
				(font
					(size 1.27 1.27)
				)
			)
		)
		(duplicate_pad_numbers_are_jumpers no)
		(fp_line
			(start 0.7874 0.4064)
			(end -0.7874 0.4064)
			(stroke
				(width 0.1524)
				(type default)
			)
			(layer "F.SilkS")
		)
		(fp_line
			(start 0.7874 -0.4064)
			(end 0.7874 0.4064)
			(stroke
				(width 0.1524)
				(type default)
			)
			(layer "F.SilkS")
		)
		(fp_line
			(start -0.7874 0.4064)
			(end -0.7874 -0.4064)
			(stroke
				(width 0.1524)
				(type default)
			)
			(layer "F.SilkS")
		)
		(fp_line
			(start -0.7874 -0.4064)
			(end 0.7874 -0.4064)
			(stroke
				(width 0.1524)
				(type default)
			)
			(layer "F.SilkS")
		)
		(fp_line
			(start 0.67945 0.3048)
			(end 0.120396 0.3048)
			(stroke
				(width 0.1)
				(type default)
			)
			(layer "F.Fab")
		)
		(fp_line
			(start 0.67945 -0.3048)
			(end 0.67945 0.3048)
			(stroke
				(width 0.1)
				(type default)
			)
			(layer "F.Fab")
		)
		(fp_line
			(start 0.12065 -0.2794)
			(end 0.12065 -0.3048)
			(stroke
				(width 0.1)
				(type default)
			)
			(layer "F.Fab")
		)
		(fp_line
			(start 0.12065 -0.3048)
			(end 0.67945 -0.3048)
			(stroke
				(width 0.1)
				(type default)
			)
			(layer "F.Fab")
		)
		(fp_line
			(start 0.120396 0.3048)
			(end 0.120396 0.2794)
			(stroke
				(width 0.1)
				(type default)
			)
			(layer "F.Fab")
		)
		(fp_line
			(start 0.120396 0.2794)
			(end -0.12065 0.2794)
			(stroke
				(width 0.1)
				(type default)
			)
			(layer "F.Fab")
		)
		(fp_line
			(start -0.12065 0.3048)
			(end -0.67945 0.3048)
			(stroke
				(width 0.1)
				(type default)
			)
			(layer "F.Fab")
		)
		(fp_line
			(start -0.12065 0.2794)
			(end -0.12065 0.3048)
			(stroke
				(width 0.1)
				(type default)
			)
			(layer "F.Fab")
		)
		(fp_line
			(start -0.12065 -0.2794)
			(end 0.12065 -0.2794)
			(stroke
				(width 0.1)
				(type default)
			)
			(layer "F.Fab")
		)
		(fp_line
			(start -0.12065 -0.305054)
			(end -0.12065 -0.2794)
			(stroke
				(width 0.1)
				(type default)
			)
			(layer "F.Fab")
		)
		(fp_line
			(start -0.67945 0.3048)
			(end -0.67945 -0.305054)
			(stroke
				(width 0.1)
				(type default)
			)
			(layer "F.Fab")
		)
		(fp_line
			(start -0.67945 -0.305054)
			(end -0.12065 -0.305054)
			(stroke
				(width 0.1)
				(type default)
			)
			(layer "F.Fab")
		)
		(pad "1" smd circle
			(at -0.40005 0 180)
			(size 0 0)
			(layers "F.Cu" "F.Mask" "F.Paste")
			(net "SMB_BIC_I2C6_MUX_SSD_8_15_ADC_R_SCL")
		)
		(pad "2" smd circle
			(at 0.40005 0 180)
			(size 0 0)
			(layers "F.Cu" "F.Mask" "F.Paste")
			(net "SMB_SSD11_ADC_SCL")
		)
	)
	(footprint ""
		(layer "F.Cu")
		(at 179.625752 -165.670484 -90)
		(property "Reference" "R3307"
			(at 0 0 270)
			(layer "F.SilkS")
			(hide yes)
			(effects
				(font
					(size 1.27 1.27)
				)
			)
		)
		(property "Value" ""
			(at 0 0 270)
			(layer "F.Fab")
			(effects
				(font
					(size 1.27 1.27)
				)
			)
		)
		(duplicate_pad_numbers_are_jumpers no)
		(fp_line
			(start -0.7874 0.4064)
			(end -0.7874 -0.4064)
			(stroke
				(width 0.1524)
				(type default)
			)
			(layer "F.SilkS")
		)
		(fp_line
			(start 0.7874 0.4064)
			(end -0.7874 0.4064)
			(stroke
				(width 0.1524)
				(type default)
			)
			(layer "F.SilkS")
		)
		(fp_line
			(start -0.7874 -0.4064)
			(end 0.7874 -0.4064)
			(stroke
				(width 0.1524)
				(type default)
			)
			(layer "F.SilkS")
		)
		(fp_line
			(start 0.7874 -0.4064)
			(end 0.7874 0.4064)
			(stroke
				(width 0.1524)
				(type default)
			)
			(layer "F.SilkS")
		)
		(fp_line
			(start -0.67945 0.3048)
			(end -0.67945 -0.305054)
			(stroke
				(width 0.1)
				(type default)
			)
			(layer "F.Fab")
		)
		(fp_line
			(start -0.12065 0.3048)
			(end -0.67945 0.3048)
			(stroke
				(width 0.1)
				(type default)
			)
			(layer "F.Fab")
		)
		(fp_line
			(start 0.120396 0.3048)
			(end 0.120396 0.2794)
			(stroke
				(width 0.1)
				(type default)
			)
			(layer "F.Fab")
		)
		(fp_line
			(start 0.67945 0.3048)
			(end 0.120396 0.3048)
			(stroke
				(width 0.1)
				(type default)
			)
			(layer "F.Fab")
		)
		(fp_line
			(start -0.12065 0.2794)
			(end -0.12065 0.3048)
			(stroke
				(width 0.1)
				(type default)
			)
			(layer "F.Fab")
		)
		(fp_line
			(start 0.120396 0.2794)
			(end -0.12065 0.2794)
			(stroke
				(width 0.1)
				(type default)
			)
			(layer "F.Fab")
		)
		(fp_line
			(start -0.12065 -0.2794)
			(end 0.12065 -0.2794)
			(stroke
				(width 0.1)
				(type default)
			)
			(layer "F.Fab")
		)
		(fp_line
			(start 0.12065 -0.2794)
			(end 0.12065 -0.3048)
			(stroke
				(width 0.1)
				(type default)
			)
			(layer "F.Fab")
		)
		(fp_line
			(start 0.12065 -0.3048)
			(end 0.67945 -0.3048)
			(stroke
				(width 0.1)
				(type default)
			)
			(layer "F.Fab")
		)
		(fp_line
			(start 0.67945 -0.3048)
			(end 0.67945 0.3048)
			(stroke
				(width 0.1)
				(type default)
			)
			(layer "F.Fab")
		)
		(fp_line
			(start -0.67945 -0.305054)
			(end -0.12065 -0.305054)
			(stroke
				(width 0.1)
				(type default)
			)
			(layer "F.Fab")
		)
		(fp_line
			(start -0.12065 -0.305054)
			(end -0.12065 -0.2794)
			(stroke
				(width 0.1)
				(type default)
			)
			(layer "F.Fab")
		)
		(pad "1" smd circle
			(at -0.40005 0 270)
			(size 0 0)
			(layers "F.Cu" "F.Mask" "F.Paste")
			(net "FM_SYS_THROTTLE_R")
		)
		(pad "2" smd circle
			(at 0.40005 0 270)
			(size 0 0)
			(layers "F.Cu" "F.Mask" "F.Paste")
			(net "FM_SYS_THROTTLE_NIC3")
		)
	)
	(footprint ""
		(layer "F.Cu")
		(at 229.5398 -231.4194 -90)
		(property "Reference" "R4536"
			(at 0 0 270)
			(layer "F.SilkS")
			(hide yes)
			(effects
				(font
					(size 1.27 1.27)
				)
			)
		)
		(property "Value" ""
			(at 0 0 270)
			(layer "F.Fab")
			(effects
				(font
					(size 1.27 1.27)
				)
			)
		)
		(duplicate_pad_numbers_are_jumpers no)
		(fp_line
			(start -0.7874 0.4064)
			(end -0.7874 -0.4064)
			(stroke
				(width 0.1524)
				(type default)
			)
			(layer "F.SilkS")
		)
		(fp_line
			(start 0.7874 0.4064)
			(end -0.7874 0.4064)
			(stroke
				(width 0.1524)
				(type default)
			)
			(layer "F.SilkS")
		)
		(fp_line
			(start -0.7874 -0.4064)
			(end 0.7874 -0.4064)
			(stroke
				(width 0.1524)
				(type default)
			)
			(layer "F.SilkS")
		)
		(fp_line
			(start 0.7874 -0.4064)
			(end 0.7874 0.4064)
			(stroke
				(width 0.1524)
				(type default)
			)
			(layer "F.SilkS")
		)
		(fp_line
			(start -0.67945 0.3048)
			(end -0.67945 -0.305054)
			(stroke
				(width 0.1)
				(type default)
			)
			(layer "F.Fab")
		)
		(fp_line
			(start -0.12065 0.3048)
			(end -0.67945 0.3048)
			(stroke
				(width 0.1)
				(type default)
			)
			(layer "F.Fab")
		)
		(fp_line
			(start 0.120396 0.3048)
			(end 0.120396 0.2794)
			(stroke
				(width 0.1)
				(type default)
			)
			(layer "F.Fab")
		)
		(fp_line
			(start 0.67945 0.3048)
			(end 0.120396 0.3048)
			(stroke
				(width 0.1)
				(type default)
			)
			(layer "F.Fab")
		)
		(fp_line
			(start -0.12065 0.2794)
			(end -0.12065 0.3048)
			(stroke
				(width 0.1)
				(type default)
			)
			(layer "F.Fab")
		)
		(fp_line
			(start 0.120396 0.2794)
			(end -0.12065 0.2794)
			(stroke
				(width 0.1)
				(type default)
			)
			(layer "F.Fab")
		)
		(fp_line
			(start -0.12065 -0.2794)
			(end 0.12065 -0.2794)
			(stroke
				(width 0.1)
				(type default)
			)
			(layer "F.Fab")
		)
		(fp_line
			(start 0.12065 -0.2794)
			(end 0.12065 -0.3048)
			(stroke
				(width 0.1)
				(type default)
			)
			(layer "F.Fab")
		)
		(fp_line
			(start 0.12065 -0.3048)
			(end 0.67945 -0.3048)
			(stroke
				(width 0.1)
				(type default)
			)
			(layer "F.Fab")
		)
		(fp_line
			(start 0.67945 -0.3048)
			(end 0.67945 0.3048)
			(stroke
				(width 0.1)
				(type default)
			)
			(layer "F.Fab")
		)
		(fp_line
			(start -0.67945 -0.305054)
			(end -0.12065 -0.305054)
			(stroke
				(width 0.1)
				(type default)
			)
			(layer "F.Fab")
		)
		(fp_line
			(start -0.12065 -0.305054)
			(end -0.12065 -0.2794)
			(stroke
				(width 0.1)
				(type default)
			)
			(layer "F.Fab")
		)
		(pad "1" smd circle
			(at -0.40005 0 270)
			(size 0 0)
			(layers "F.Cu" "F.Mask" "F.Paste")
			(net "NIC0_MAIN_PWR_BIC_EN_R")
		)
		(pad "2" smd circle
			(at 0.40005 0 270)
			(size 0 0)
			(layers "F.Cu" "F.Mask" "F.Paste")
			(net "NIC0_MAIN_PWR_BIC_EN")
		)
	)
	(footprint ""
		(layer "F.Cu")
		(at 365.506 -213.995 180)
		(property "Reference" "R4636"
			(at 0 0 180)
			(layer "F.SilkS")
			(hide yes)
			(effects
				(font
					(size 1.27 1.27)
				)
			)
		)
		(property "Value" ""
			(at 0 0 180)
			(layer "F.Fab")
			(effects
				(font
					(size 1.27 1.27)
				)
			)
		)
		(duplicate_pad_numbers_are_jumpers no)
		(fp_line
			(start 0.7874 0.4064)
			(end -0.7874 0.4064)
			(stroke
				(width 0.1524)
				(type default)
			)
			(layer "F.SilkS")
		)
		(fp_line
			(start 0.7874 -0.4064)
			(end 0.7874 0.4064)
			(stroke
				(width 0.1524)
				(type default)
			)
			(layer "F.SilkS")
		)
		(fp_line
			(start -0.7874 0.4064)
			(end -0.7874 -0.4064)
			(stroke
				(width 0.1524)
				(type default)
			)
			(layer "F.SilkS")
		)
		(fp_line
			(start -0.7874 -0.4064)
			(end 0.7874 -0.4064)
			(stroke
				(width 0.1524)
				(type default)
			)
			(layer "F.SilkS")
		)
		(fp_line
			(start 0.67945 0.3048)
			(end 0.120396 0.3048)
			(stroke
				(width 0.1)
				(type default)
			)
			(layer "F.Fab")
		)
		(fp_line
			(start 0.67945 -0.3048)
			(end 0.67945 0.3048)
			(stroke
				(width 0.1)
				(type default)
			)
			(layer "F.Fab")
		)
		(fp_line
			(start 0.12065 -0.2794)
			(end 0.12065 -0.3048)
			(stroke
				(width 0.1)
				(type default)
			)
			(layer "F.Fab")
		)
		(fp_line
			(start 0.12065 -0.3048)
			(end 0.67945 -0.3048)
			(stroke
				(width 0.1)
				(type default)
			)
			(layer "F.Fab")
		)
		(fp_line
			(start 0.120396 0.3048)
			(end 0.120396 0.2794)
			(stroke
				(width 0.1)
				(type default)
			)
			(layer "F.Fab")
		)
		(fp_line
			(start 0.120396 0.2794)
			(end -0.12065 0.2794)
			(stroke
				(width 0.1)
				(type default)
			)
			(layer "F.Fab")
		)
		(fp_line
			(start -0.12065 0.3048)
			(end -0.67945 0.3048)
			(stroke
				(width 0.1)
				(type default)
			)
			(layer "F.Fab")
		)
		(fp_line
			(start -0.12065 0.2794)
			(end -0.12065 0.3048)
			(stroke
				(width 0.1)
				(type default)
			)
			(layer "F.Fab")
		)
		(fp_line
			(start -0.12065 -0.2794)
			(end 0.12065 -0.2794)
			(stroke
				(width 0.1)
				(type default)
			)
			(layer "F.Fab")
		)
		(fp_line
			(start -0.12065 -0.305054)
			(end -0.12065 -0.2794)
			(stroke
				(width 0.1)
				(type default)
			)
			(layer "F.Fab")
		)
		(fp_line
			(start -0.67945 0.3048)
			(end -0.67945 -0.305054)
			(stroke
				(width 0.1)
				(type default)
			)
			(layer "F.Fab")
		)
		(fp_line
			(start -0.67945 -0.305054)
			(end -0.12065 -0.305054)
			(stroke
				(width 0.1)
				(type default)
			)
			(layer "F.Fab")
		)
		(pad "1" smd circle
			(at -0.40005 0 180)
			(size 0 0)
			(layers "F.Cu" "F.Mask" "F.Paste")
			(net "GND")
		)
		(pad "2" smd circle
			(at 0.40005 0 180)
			(size 0 0)
			(layers "F.Cu" "F.Mask" "F.Paste")
			(net "PCA9555_0_PEX0_A1")
		)
	)
	(footprint ""
		(layer "F.Cu")
		(at 72.947276 -19.33956)
		(property "Reference" "C3887"
			(at 0 0 0)
			(layer "F.SilkS")
			(hide yes)
			(effects
				(font
					(size 1.27 1.27)
				)
			)
		)
		(property "Value" ""
			(at 0 0 0)
			(layer "F.Fab")
			(effects
				(font
					(size 1.27 1.27)
				)
			)
		)
		(duplicate_pad_numbers_are_jumpers no)
		(fp_line
			(start -0.7874 -0.4064)
			(end 0.7874 -0.4064)
			(stroke
				(width 0.1524)
				(type default)
			)
			(layer "F.SilkS")
		)
		(fp_line
			(start -0.7874 0.4064)
			(end -0.7874 -0.4064)
			(stroke
				(width 0.1524)
				(type default)
			)
			(layer "F.SilkS")
		)
		(fp_line
			(start 0.7874 -0.4064)
			(end 0.7874 0.4064)
			(stroke
				(width 0.1524)
				(type default)
			)
			(layer "F.SilkS")
		)
		(fp_line
			(start 0.7874 0.4064)
			(end -0.7874 0.4064)
			(stroke
				(width 0.1524)
				(type default)
			)
			(layer "F.SilkS")
		)
		(fp_line
			(start -0.67945 -0.305054)
			(end -0.12065 -0.305054)
			(stroke
				(width 0.1)
				(type default)
			)
			(layer "F.Fab")
		)
		(fp_line
			(start -0.67945 0.3048)
			(end -0.67945 -0.305054)
			(stroke
				(width 0.1)
				(type default)
			)
			(layer "F.Fab")
		)
		(fp_line
			(start -0.12065 -0.305054)
			(end -0.12065 -0.2794)
			(stroke
				(width 0.1)
				(type default)
			)
			(layer "F.Fab")
		)
		(fp_line
			(start -0.12065 -0.2794)
			(end 0.12065 -0.2794)
			(stroke
				(width 0.1)
				(type default)
			)
			(layer "F.Fab")
		)
		(fp_line
			(start -0.12065 0.2794)
			(end -0.12065 0.3048)
			(stroke
				(width 0.1)
				(type default)
			)
			(layer "F.Fab")
		)
		(fp_line
			(start -0.12065 0.3048)
			(end -0.67945 0.3048)
			(stroke
				(width 0.1)
				(type default)
			)
			(layer "F.Fab")
		)
		(fp_line
			(start 0.120396 0.2794)
			(end -0.12065 0.2794)
			(stroke
				(width 0.1)
				(type default)
			)
			(layer "F.Fab")
		)
		(fp_line
			(start 0.120396 0.3048)
			(end 0.120396 0.2794)
			(stroke
				(width 0.1)
				(type default)
			)
			(layer "F.Fab")
		)
		(fp_line
			(start 0.12065 -0.3048)
			(end 0.67945 -0.3048)
			(stroke
				(width 0.1)
				(type default)
			)
			(layer "F.Fab")
		)
		(fp_line
			(start 0.12065 -0.2794)
			(end 0.12065 -0.3048)
			(stroke
				(width 0.1)
				(type default)
			)
			(layer "F.Fab")
		)
		(fp_line
			(start 0.67945 -0.3048)
			(end 0.67945 0.3048)
			(stroke
				(width 0.1)
				(type default)
			)
			(layer "F.Fab")
		)
		(fp_line
			(start 0.67945 0.3048)
			(end 0.120396 0.3048)
			(stroke
				(width 0.1)
				(type default)
			)
			(layer "F.Fab")
		)
		(pad "1" smd circle
			(at -0.40005 0)
			(size 0 0)
			(layers "F.Cu" "F.Mask" "F.Paste")
			(net "P12V_SSD2")
		)
		(pad "2" smd circle
			(at 0.40005 0)
			(size 0 0)
			(layers "F.Cu" "F.Mask" "F.Paste")
			(net "GND")
		)
	)
	(footprint ""
		(layer "F.Cu")
		(at 316.701932 -141.150848 -90)
		(property "Reference" "U34"
			(at 2.671318 0.014732 0)
			(unlocked yes)
			(layer "F.SilkS")
			(effects
				(font
					(size 0.7874 0.5842)
					(thickness 0.1524)
				)
			)
		)
		(property "Value" ""
			(at 0 0 270)
			(layer "F.Fab")
			(effects
				(font
					(size 1.27 1.27)
				)
			)
		)
		(duplicate_pad_numbers_are_jumpers no)
		(fp_line
			(start -1.949958 1.610106)
			(end -1.949958 -1.610106)
			(stroke
				(width 0.1524)
				(type default)
			)
			(layer "F.SilkS")
		)
		(fp_line
			(start 1.949958 1.610106)
			(end -1.949958 1.610106)
			(stroke
				(width 0.1524)
				(type default)
			)
			(layer "F.SilkS")
		)
		(fp_line
			(start 1.949958 -1.560068)
			(end 1.949958 1.610106)
			(stroke
				(width 0.1524)
				(type default)
			)
			(layer "F.SilkS")
		)
		(fp_line
			(start -1.949958 -1.610106)
			(end 1.949958 -1.610106)
			(stroke
				(width 0.1524)
				(type default)
			)
			(layer "F.SilkS")
		)
		(fp_line
			(start -0.750062 1.560068)
			(end -0.750062 -1.560068)
			(stroke
				(width 0.1)
				(type default)
			)
			(layer "F.Fab")
		)
		(fp_line
			(start 0.750062 1.560068)
			(end -0.750062 1.560068)
			(stroke
				(width 0.1)
				(type default)
			)
			(layer "F.Fab")
		)
		(fp_line
			(start -0.750062 -1.560068)
			(end 0.750062 -1.560068)
			(stroke
				(width 0.1)
				(type default)
			)
			(layer "F.Fab")
		)
		(fp_line
			(start 0.750062 -1.560068)
			(end 0.750062 1.560068)
			(stroke
				(width 0.1)
				(type default)
			)
			(layer "F.Fab")
		)
		(pad "D" smd rect
			(at 1.100074 0 180)
			(size 1.016 1.4224)
			(layers "F.Cu" "F.Mask" "F.Paste")
			(net "HP_NIC5_EN")
		)
		(pad "G" smd rect
			(at -1.100074 -0.94996 180)
			(size 1.016 1.4224)
			(layers "F.Cu" "F.Mask" "F.Paste")
			(net "PRSNT_NIC5_R_N")
		)
		(pad "S" smd rect
			(at -1.100074 0.94996 180)
			(size 1.016 1.4224)
			(layers "F.Cu" "F.Mask" "F.Paste")
			(net "GND")
		)
	)
	(footprint ""
		(layer "F.Cu")
		(at 216.437718 -251.163836 -90)
		(property "Reference" "C4287"
			(at 0 0 270)
			(layer "F.SilkS")
			(hide yes)
			(effects
				(font
					(size 1.27 1.27)
				)
			)
		)
		(property "Value" ""
			(at 0 0 270)
			(layer "F.Fab")
			(effects
				(font
					(size 1.27 1.27)
				)
			)
		)
		(duplicate_pad_numbers_are_jumpers no)
		(fp_line
			(start -1.524 0.762)
			(end -1.524 -0.762)
			(stroke
				(width 0.1524)
				(type default)
			)
			(layer "F.SilkS")
		)
		(fp_line
			(start 1.524 0.762)
			(end -1.524 0.762)
			(stroke
				(width 0.1524)
				(type default)
			)
			(layer "F.SilkS")
		)
		(fp_line
			(start -1.524 -0.762)
			(end 1.524 -0.762)
			(stroke
				(width 0.1524)
				(type default)
			)
			(layer "F.SilkS")
		)
		(fp_line
			(start 1.524 -0.762)
			(end 1.524 0.762)
			(stroke
				(width 0.1524)
				(type default)
			)
			(layer "F.SilkS")
		)
		(fp_line
			(start -1.1049 0.724916)
			(end 1.1049 0.724916)
			(stroke
				(width 0.1)
				(type default)
			)
			(layer "F.Fab")
		)
		(fp_line
			(start 1.1049 0.724916)
			(end 1.1049 -0.724916)
			(stroke
				(width 0.1)
				(type default)
			)
			(layer "F.Fab")
		)
		(fp_line
			(start -1.1049 -0.724916)
			(end -1.1049 0.724916)
			(stroke
				(width 0.1)
				(type default)
			)
			(layer "F.Fab")
		)
		(fp_line
			(start 1.1049 -0.724916)
			(end -1.1049 -0.724916)
			(stroke
				(width 0.1)
				(type default)
			)
			(layer "F.Fab")
		)
		(pad "1" smd rect
			(at -0.889 0 90)
			(size 1.016 1.27)
			(layers "F.Cu" "F.Mask" "F.Paste")
			(net "P1V25_SERDES_VDDPLL_PEX1_C5")
		)
		(pad "2" smd rect
			(at 0.889 0 90)
			(size 1.016 1.27)
			(layers "F.Cu" "F.Mask" "F.Paste")
			(net "GND")
		)
		(zone
			(layer "F.Cu")
			(hatch none 0.5)
			(connect_pads
				(clearance 0)
			)
			(min_thickness 0.25)
			(keepout
				(tracks not_allowed)
				(vias allowed)
				(pads allowed)
				(copperpour not_allowed)
				(footprints allowed)
			)
			(placement
				(enabled no)
				(sheetname "")
			)
			(fill
				(thermal_gap 0.5)
				(thermal_bridge_width 0.5)
				(island_removal_mode 0)
			)
			(polygon
				(pts
					(xy 217.162634 -251.494036) (xy 215.712802 -251.494036) (xy 215.712802 -250.833636) (xy 217.162634 -250.833636)
				)
			)
		)
	)
	(footprint ""
		(layer "F.Cu")
		(at 345.76131 -260.671564)
		(property "Reference" "PR140"
			(at 0 0 0)
			(layer "F.SilkS")
			(hide yes)
			(effects
				(font
					(size 1.27 1.27)
				)
			)
		)
		(property "Value" ""
			(at 0 0 0)
			(layer "F.Fab")
			(effects
				(font
					(size 1.27 1.27)
				)
			)
		)
		(duplicate_pad_numbers_are_jumpers no)
		(fp_line
			(start -0.7874 -0.4064)
			(end 0.7874 -0.4064)
			(stroke
				(width 0.1524)
				(type default)
			)
			(layer "F.SilkS")
		)
		(fp_line
			(start -0.7874 0.4064)
			(end -0.7874 -0.4064)
			(stroke
				(width 0.1524)
				(type default)
			)
			(layer "F.SilkS")
		)
		(fp_line
			(start 0.7874 -0.4064)
			(end 0.7874 0.4064)
			(stroke
				(width 0.1524)
				(type default)
			)
			(layer "F.SilkS")
		)
		(fp_line
			(start 0.7874 0.4064)
			(end -0.7874 0.4064)
			(stroke
				(width 0.1524)
				(type default)
			)
			(layer "F.SilkS")
		)
		(fp_line
			(start -0.67945 -0.305054)
			(end -0.12065 -0.305054)
			(stroke
				(width 0.1)
				(type default)
			)
			(layer "F.Fab")
		)
		(fp_line
			(start -0.67945 0.3048)
			(end -0.67945 -0.305054)
			(stroke
				(width 0.1)
				(type default)
			)
			(layer "F.Fab")
		)
		(fp_line
			(start -0.12065 -0.305054)
			(end -0.12065 -0.2794)
			(stroke
				(width 0.1)
				(type default)
			)
			(layer "F.Fab")
		)
		(fp_line
			(start -0.12065 -0.2794)
			(end 0.12065 -0.2794)
			(stroke
				(width 0.1)
				(type default)
			)
			(layer "F.Fab")
		)
		(fp_line
			(start -0.12065 0.2794)
			(end -0.12065 0.3048)
			(stroke
				(width 0.1)
				(type default)
			)
			(layer "F.Fab")
		)
		(fp_line
			(start -0.12065 0.3048)
			(end -0.67945 0.3048)
			(stroke
				(width 0.1)
				(type default)
			)
			(layer "F.Fab")
		)
		(fp_line
			(start 0.120396 0.2794)
			(end -0.12065 0.2794)
			(stroke
				(width 0.1)
				(type default)
			)
			(layer "F.Fab")
		)
		(fp_line
			(start 0.120396 0.3048)
			(end 0.120396 0.2794)
			(stroke
				(width 0.1)
				(type default)
			)
			(layer "F.Fab")
		)
		(fp_line
			(start 0.12065 -0.3048)
			(end 0.67945 -0.3048)
			(stroke
				(width 0.1)
				(type default)
			)
			(layer "F.Fab")
		)
		(fp_line
			(start 0.12065 -0.2794)
			(end 0.12065 -0.3048)
			(stroke
				(width 0.1)
				(type default)
			)
			(layer "F.Fab")
		)
		(fp_line
			(start 0.67945 -0.3048)
			(end 0.67945 0.3048)
			(stroke
				(width 0.1)
				(type default)
			)
			(layer "F.Fab")
		)
		(fp_line
			(start 0.67945 0.3048)
			(end 0.120396 0.3048)
			(stroke
				(width 0.1)
				(type default)
			)
			(layer "F.Fab")
		)
		(pad "1" smd circle
			(at -0.40005 0)
			(size 0 0)
			(layers "F.Cu" "F.Mask" "F.Paste")
			(net "P0V8_PEX2_VREF")
		)
		(pad "2" smd circle
			(at 0.40005 0)
			(size 0 0)
			(layers "F.Cu" "F.Mask" "F.Paste")
			(net "P0V8_PEX2_ADDR")
		)
	)
	(footprint ""
		(layer "F.Cu")
		(at 363.590078 -407.599896)
		(property "Reference" "H59"
			(at -3.877818 -5.352542 0)
			(unlocked yes)
			(layer "F.SilkS")
			(effects
				(font
					(size 0.7874 0.5842)
					(thickness 0.1524)
				)
				(justify left)
			)
		)
		(property "Value" ""
			(at 0 0 0)
			(layer "F.Fab")
			(effects
				(font
					(size 1.27 1.27)
				)
			)
		)
		(duplicate_pad_numbers_are_jumpers no)
		(pad "1" thru_hole circle
			(at 0 0)
			(size 10.0076 10.0076)
			(drill 5.6134)
			(layers "*.Cu" "*.Mask")
			(remove_unused_layers no)
			(net "GND")
			(clearance -1.9431)
		)
	)
	(footprint ""
		(layer "F.Cu")
		(at 303.938432 -44.341542 90)
		(property "Reference" "C329"
			(at 0 0 90)
			(layer "F.SilkS")
			(hide yes)
			(effects
				(font
					(size 1.27 1.27)
				)
			)
		)
		(property "Value" ""
			(at 0 0 90)
			(layer "F.Fab")
			(effects
				(font
					(size 1.27 1.27)
				)
			)
		)
		(duplicate_pad_numbers_are_jumpers no)
		(fp_line
			(start 0.7874 -0.4064)
			(end 0.7874 0.4064)
			(stroke
				(width 0.1524)
				(type default)
			)
			(layer "F.SilkS")
		)
		(fp_line
			(start -0.7874 -0.4064)
			(end 0.7874 -0.4064)
			(stroke
				(width 0.1524)
				(type default)
			)
			(layer "F.SilkS")
		)
		(fp_line
			(start 0.7874 0.4064)
			(end -0.7874 0.4064)
			(stroke
				(width 0.1524)
				(type default)
			)
			(layer "F.SilkS")
		)
		(fp_line
			(start -0.7874 0.4064)
			(end -0.7874 -0.4064)
			(stroke
				(width 0.1524)
				(type default)
			)
			(layer "F.SilkS")
		)
		(fp_line
			(start -0.12065 -0.305054)
			(end -0.12065 -0.2794)
			(stroke
				(width 0.1)
				(type default)
			)
			(layer "F.Fab")
		)
		(fp_line
			(start -0.67945 -0.305054)
			(end -0.12065 -0.305054)
			(stroke
				(width 0.1)
				(type default)
			)
			(layer "F.Fab")
		)
		(fp_line
			(start 0.67945 -0.3048)
			(end 0.67945 0.3048)
			(stroke
				(width 0.1)
				(type default)
			)
			(layer "F.Fab")
		)
		(fp_line
			(start 0.12065 -0.3048)
			(end 0.67945 -0.3048)
			(stroke
				(width 0.1)
				(type default)
			)
			(layer "F.Fab")
		)
		(fp_line
			(start 0.12065 -0.2794)
			(end 0.12065 -0.3048)
			(stroke
				(width 0.1)
				(type default)
			)
			(layer "F.Fab")
		)
		(fp_line
			(start -0.12065 -0.2794)
			(end 0.12065 -0.2794)
			(stroke
				(width 0.1)
				(type default)
			)
			(layer "F.Fab")
		)
		(fp_line
			(start 0.120396 0.2794)
			(end -0.12065 0.2794)
			(stroke
				(width 0.1)
				(type default)
			)
			(layer "F.Fab")
		)
		(fp_line
			(start -0.12065 0.2794)
			(end -0.12065 0.3048)
			(stroke
				(width 0.1)
				(type default)
			)
			(layer "F.Fab")
		)
		(fp_line
			(start 0.67945 0.3048)
			(end 0.120396 0.3048)
			(stroke
				(width 0.1)
				(type default)
			)
			(layer "F.Fab")
		)
		(fp_line
			(start 0.120396 0.3048)
			(end 0.120396 0.2794)
			(stroke
				(width 0.1)
				(type default)
			)
			(layer "F.Fab")
		)
		(fp_line
			(start -0.12065 0.3048)
			(end -0.67945 0.3048)
			(stroke
				(width 0.1)
				(type default)
			)
			(layer "F.Fab")
		)
		(fp_line
			(start -0.67945 0.3048)
			(end -0.67945 -0.305054)
			(stroke
				(width 0.1)
				(type default)
			)
			(layer "F.Fab")
		)
		(pad "1" smd circle
			(at -0.40005 0 90)
			(size 0 0)
			(layers "F.Cu" "F.Mask" "F.Paste")
			(net "P12V_SSD10_VIN_P")
		)
		(pad "2" smd circle
			(at 0.40005 0 90)
			(size 0 0)
			(layers "F.Cu" "F.Mask" "F.Paste")
			(net "P12V_SSD10_VIN_N")
		)
	)
	(footprint ""
		(layer "F.Cu")
		(at 189.98565 -25.1587 -90)
		(property "Reference" "R5744"
			(at 0 0 270)
			(layer "F.SilkS")
			(hide yes)
			(effects
				(font
					(size 1.27 1.27)
				)
			)
		)
		(property "Value" ""
			(at 0 0 270)
			(layer "F.Fab")
			(effects
				(font
					(size 1.27 1.27)
				)
			)
		)
		(duplicate_pad_numbers_are_jumpers no)
		(fp_line
			(start -0.7874 0.4064)
			(end -0.7874 -0.4064)
			(stroke
				(width 0.1524)
				(type default)
			)
			(layer "F.SilkS")
		)
		(fp_line
			(start 0.7874 0.4064)
			(end -0.7874 0.4064)
			(stroke
				(width 0.1524)
				(type default)
			)
			(layer "F.SilkS")
		)
		(fp_line
			(start -0.7874 -0.4064)
			(end 0.7874 -0.4064)
			(stroke
				(width 0.1524)
				(type default)
			)
			(layer "F.SilkS")
		)
		(fp_line
			(start 0.7874 -0.4064)
			(end 0.7874 0.4064)
			(stroke
				(width 0.1524)
				(type default)
			)
			(layer "F.SilkS")
		)
		(fp_line
			(start -0.67945 0.3048)
			(end -0.67945 -0.305054)
			(stroke
				(width 0.1)
				(type default)
			)
			(layer "F.Fab")
		)
		(fp_line
			(start -0.12065 0.3048)
			(end -0.67945 0.3048)
			(stroke
				(width 0.1)
				(type default)
			)
			(layer "F.Fab")
		)
		(fp_line
			(start 0.120396 0.3048)
			(end 0.120396 0.2794)
			(stroke
				(width 0.1)
				(type default)
			)
			(layer "F.Fab")
		)
		(fp_line
			(start 0.67945 0.3048)
			(end 0.120396 0.3048)
			(stroke
				(width 0.1)
				(type default)
			)
			(layer "F.Fab")
		)
		(fp_line
			(start -0.12065 0.2794)
			(end -0.12065 0.3048)
			(stroke
				(width 0.1)
				(type default)
			)
			(layer "F.Fab")
		)
		(fp_line
			(start 0.120396 0.2794)
			(end -0.12065 0.2794)
			(stroke
				(width 0.1)
				(type default)
			)
			(layer "F.Fab")
		)
		(fp_line
			(start -0.12065 -0.2794)
			(end 0.12065 -0.2794)
			(stroke
				(width 0.1)
				(type default)
			)
			(layer "F.Fab")
		)
		(fp_line
			(start 0.12065 -0.2794)
			(end 0.12065 -0.3048)
			(stroke
				(width 0.1)
				(type default)
			)
			(layer "F.Fab")
		)
		(fp_line
			(start 0.12065 -0.3048)
			(end 0.67945 -0.3048)
			(stroke
				(width 0.1)
				(type default)
			)
			(layer "F.Fab")
		)
		(fp_line
			(start 0.67945 -0.3048)
			(end 0.67945 0.3048)
			(stroke
				(width 0.1)
				(type default)
			)
			(layer "F.Fab")
		)
		(fp_line
			(start -0.67945 -0.305054)
			(end -0.12065 -0.305054)
			(stroke
				(width 0.1)
				(type default)
			)
			(layer "F.Fab")
		)
		(fp_line
			(start -0.12065 -0.305054)
			(end -0.12065 -0.2794)
			(stroke
				(width 0.1)
				(type default)
			)
			(layer "F.Fab")
		)
		(pad "1" smd circle
			(at -0.40005 0 270)
			(size 0 0)
			(layers "F.Cu" "F.Mask" "F.Paste")
			(net "SSD6_LED_ISO_N")
		)
		(pad "2" smd circle
			(at 0.40005 0 270)
			(size 0 0)
			(layers "F.Cu" "F.Mask" "F.Paste")
			(net "SSD6_LED_ISO_R_N")
		)
	)
	(footprint ""
		(layer "F.Cu")
		(at 6.196584 -13.029184 180)
		(property "Reference" "C3877"
			(at 0 0 180)
			(layer "F.SilkS")
			(hide yes)
			(effects
				(font
					(size 1.27 1.27)
				)
			)
		)
		(property "Value" ""
			(at 0 0 180)
			(layer "F.Fab")
			(effects
				(font
					(size 1.27 1.27)
				)
			)
		)
		(duplicate_pad_numbers_are_jumpers no)
		(fp_line
			(start 0.7874 0.4064)
			(end -0.7874 0.4064)
			(stroke
				(width 0.1524)
				(type default)
			)
			(layer "F.SilkS")
		)
		(fp_line
			(start 0.7874 -0.4064)
			(end 0.7874 0.4064)
			(stroke
				(width 0.1524)
				(type default)
			)
			(layer "F.SilkS")
		)
		(fp_line
			(start -0.7874 0.4064)
			(end -0.7874 -0.4064)
			(stroke
				(width 0.1524)
				(type default)
			)
			(layer "F.SilkS")
		)
		(fp_line
			(start -0.7874 -0.4064)
			(end 0.7874 -0.4064)
			(stroke
				(width 0.1524)
				(type default)
			)
			(layer "F.SilkS")
		)
		(fp_line
			(start 0.67945 0.3048)
			(end 0.120396 0.3048)
			(stroke
				(width 0.1)
				(type default)
			)
			(layer "F.Fab")
		)
		(fp_line
			(start 0.67945 -0.3048)
			(end 0.67945 0.3048)
			(stroke
				(width 0.1)
				(type default)
			)
			(layer "F.Fab")
		)
		(fp_line
			(start 0.12065 -0.2794)
			(end 0.12065 -0.3048)
			(stroke
				(width 0.1)
				(type default)
			)
			(layer "F.Fab")
		)
		(fp_line
			(start 0.12065 -0.3048)
			(end 0.67945 -0.3048)
			(stroke
				(width 0.1)
				(type default)
			)
			(layer "F.Fab")
		)
		(fp_line
			(start 0.120396 0.3048)
			(end 0.120396 0.2794)
			(stroke
				(width 0.1)
				(type default)
			)
			(layer "F.Fab")
		)
		(fp_line
			(start 0.120396 0.2794)
			(end -0.12065 0.2794)
			(stroke
				(width 0.1)
				(type default)
			)
			(layer "F.Fab")
		)
		(fp_line
			(start -0.12065 0.3048)
			(end -0.67945 0.3048)
			(stroke
				(width 0.1)
				(type default)
			)
			(layer "F.Fab")
		)
		(fp_line
			(start -0.12065 0.2794)
			(end -0.12065 0.3048)
			(stroke
				(width 0.1)
				(type default)
			)
			(layer "F.Fab")
		)
		(fp_line
			(start -0.12065 -0.2794)
			(end 0.12065 -0.2794)
			(stroke
				(width 0.1)
				(type default)
			)
			(layer "F.Fab")
		)
		(fp_line
			(start -0.12065 -0.305054)
			(end -0.12065 -0.2794)
			(stroke
				(width 0.1)
				(type default)
			)
			(layer "F.Fab")
		)
		(fp_line
			(start -0.67945 0.3048)
			(end -0.67945 -0.305054)
			(stroke
				(width 0.1)
				(type default)
			)
			(layer "F.Fab")
		)
		(fp_line
			(start -0.67945 -0.305054)
			(end -0.12065 -0.305054)
			(stroke
				(width 0.1)
				(type default)
			)
			(layer "F.Fab")
		)
		(pad "1" smd circle
			(at -0.40005 0 180)
			(size 0 0)
			(layers "F.Cu" "F.Mask" "F.Paste")
			(net "P12V_SSD0")
		)
		(pad "2" smd circle
			(at 0.40005 0 180)
			(size 0 0)
			(layers "F.Cu" "F.Mask" "F.Paste")
			(net "GND")
		)
	)
	(footprint ""
		(layer "F.Cu")
		(at 159.051752 -356.244906 90)
		(property "Reference" "C402"
			(at 0 0 90)
			(layer "F.SilkS")
			(hide yes)
			(effects
				(font
					(size 1.27 1.27)
				)
			)
		)
		(property "Value" ""
			(at 0 0 90)
			(layer "F.Fab")
			(effects
				(font
					(size 1.27 1.27)
				)
			)
		)
		(duplicate_pad_numbers_are_jumpers no)
		(fp_line
			(start 0.299974 -0.150114)
			(end 0.299974 0.150114)
			(stroke
				(width 0.1)
				(type default)
			)
			(layer "F.Fab")
		)
		(fp_line
			(start -0.299974 -0.150114)
			(end 0.299974 -0.150114)
			(stroke
				(width 0.1)
				(type default)
			)
			(layer "F.Fab")
		)
		(fp_line
			(start 0.299974 0.150114)
			(end -0.299974 0.150114)
			(stroke
				(width 0.1)
				(type default)
			)
			(layer "F.Fab")
		)
		(fp_line
			(start -0.299974 0.150114)
			(end -0.299974 -0.150114)
			(stroke
				(width 0.1)
				(type default)
			)
			(layer "F.Fab")
		)
		(pad "1" smd rect
			(at -0.2667 0 90)
			(size 0.3048 0.381)
			(layers "F.Cu" "F.Mask" "F.Paste")
			(net "P5E_PEX1_STN7_TX_DP<112>")
		)
		(pad "2" smd rect
			(at 0.2667 0 90)
			(size 0.3048 0.381)
			(layers "F.Cu" "F.Mask" "F.Paste")
			(net "P5E_PEX1_STN7_TX_C_DP<112>")
		)
	)
	(footprint ""
		(layer "F.Cu")
		(at 186.719972 -15.649956 180)
		(property "Reference" "H101"
			(at -1.124966 2.488184 0)
			(unlocked yes)
			(layer "B.SilkS")
			(effects
				(font
					(size 0.7874 0.5842)
					(thickness 0.1524)
				)
				(justify left mirror)
			)
		)
		(property "Value" ""
			(at 0 0 180)
			(layer "F.Fab")
			(effects
				(font
					(size 1.27 1.27)
				)
			)
		)
		(duplicate_pad_numbers_are_jumpers no)
		(pad "1" thru_hole rect
			(at 0 0 180)
			(size 4.2164 5.0038)
			(drill 2.0066
				(offset 0.099822 0)
			)
			(layers "*.Cu" "*.Mask")
			(remove_unused_layers no)
			(net "Net_8562")
			(clearance -0.8509)
			(padstack
				(mode front_inner_back)
				(layer "Inner"
					(shape circle)
					(size 4.0132 4.0132)
					(clearance -0.7493)
				)
				(layer "B.Cu"
					(shape circle)
					(size 4.0132 4.0132)
					(clearance -0.7493)
				)
			)
		)
	)
	(footprint ""
		(layer "F.Cu")
		(at 162.275012 -48.753014 180)
		(property "Reference" "C309"
			(at 0 0 180)
			(layer "F.SilkS")
			(hide yes)
			(effects
				(font
					(size 1.27 1.27)
				)
			)
		)
		(property "Value" ""
			(at 0 0 180)
			(layer "F.Fab")
			(effects
				(font
					(size 1.27 1.27)
				)
			)
		)
		(duplicate_pad_numbers_are_jumpers no)
		(fp_line
			(start 0.7874 0.4064)
			(end -0.7874 0.4064)
			(stroke
				(width 0.1524)
				(type default)
			)
			(layer "F.SilkS")
		)
		(fp_line
			(start 0.7874 -0.4064)
			(end 0.7874 0.4064)
			(stroke
				(width 0.1524)
				(type default)
			)
			(layer "F.SilkS")
		)
		(fp_line
			(start -0.7874 0.4064)
			(end -0.7874 -0.4064)
			(stroke
				(width 0.1524)
				(type default)
			)
			(layer "F.SilkS")
		)
		(fp_line
			(start -0.7874 -0.4064)
			(end 0.7874 -0.4064)
			(stroke
				(width 0.1524)
				(type default)
			)
			(layer "F.SilkS")
		)
		(fp_line
			(start 0.67945 0.3048)
			(end 0.120396 0.3048)
			(stroke
				(width 0.1)
				(type default)
			)
			(layer "F.Fab")
		)
		(fp_line
			(start 0.67945 -0.3048)
			(end 0.67945 0.3048)
			(stroke
				(width 0.1)
				(type default)
			)
			(layer "F.Fab")
		)
		(fp_line
			(start 0.12065 -0.2794)
			(end 0.12065 -0.3048)
			(stroke
				(width 0.1)
				(type default)
			)
			(layer "F.Fab")
		)
		(fp_line
			(start 0.12065 -0.3048)
			(end 0.67945 -0.3048)
			(stroke
				(width 0.1)
				(type default)
			)
			(layer "F.Fab")
		)
		(fp_line
			(start 0.120396 0.3048)
			(end 0.120396 0.2794)
			(stroke
				(width 0.1)
				(type default)
			)
			(layer "F.Fab")
		)
		(fp_line
			(start 0.120396 0.2794)
			(end -0.12065 0.2794)
			(stroke
				(width 0.1)
				(type default)
			)
			(layer "F.Fab")
		)
		(fp_line
			(start -0.12065 0.3048)
			(end -0.67945 0.3048)
			(stroke
				(width 0.1)
				(type default)
			)
			(layer "F.Fab")
		)
		(fp_line
			(start -0.12065 0.2794)
			(end -0.12065 0.3048)
			(stroke
				(width 0.1)
				(type default)
			)
			(layer "F.Fab")
		)
		(fp_line
			(start -0.12065 -0.2794)
			(end 0.12065 -0.2794)
			(stroke
				(width 0.1)
				(type default)
			)
			(layer "F.Fab")
		)
		(fp_line
			(start -0.12065 -0.305054)
			(end -0.12065 -0.2794)
			(stroke
				(width 0.1)
				(type default)
			)
			(layer "F.Fab")
		)
		(fp_line
			(start -0.67945 0.3048)
			(end -0.67945 -0.305054)
			(stroke
				(width 0.1)
				(type default)
			)
			(layer "F.Fab")
		)
		(fp_line
			(start -0.67945 -0.305054)
			(end -0.12065 -0.305054)
			(stroke
				(width 0.1)
				(type default)
			)
			(layer "F.Fab")
		)
		(pad "1" smd circle
			(at -0.40005 0 180)
			(size 0 0)
			(layers "F.Cu" "F.Mask" "F.Paste")
			(net "P3V3_AUX")
		)
		(pad "2" smd circle
			(at 0.40005 0 180)
			(size 0 0)
			(layers "F.Cu" "F.Mask" "F.Paste")
			(net "GND")
		)
	)
	(footprint ""
		(layer "F.Cu")
		(at 239.813338 -138.360404 180)
		(property "Reference" "R4443"
			(at 0 0 180)
			(layer "F.SilkS")
			(hide yes)
			(effects
				(font
					(size 1.27 1.27)
				)
			)
		)
		(property "Value" ""
			(at 0 0 180)
			(layer "F.Fab")
			(effects
				(font
					(size 1.27 1.27)
				)
			)
		)
		(duplicate_pad_numbers_are_jumpers no)
		(fp_line
			(start 0.7874 0.4064)
			(end -0.7874 0.4064)
			(stroke
				(width 0.1524)
				(type default)
			)
			(layer "F.SilkS")
		)
		(fp_line
			(start 0.7874 -0.4064)
			(end 0.7874 0.4064)
			(stroke
				(width 0.1524)
				(type default)
			)
			(layer "F.SilkS")
		)
		(fp_line
			(start -0.7874 0.4064)
			(end -0.7874 -0.4064)
			(stroke
				(width 0.1524)
				(type default)
			)
			(layer "F.SilkS")
		)
		(fp_line
			(start -0.7874 -0.4064)
			(end 0.7874 -0.4064)
			(stroke
				(width 0.1524)
				(type default)
			)
			(layer "F.SilkS")
		)
		(fp_line
			(start 0.67945 0.3048)
			(end 0.120396 0.3048)
			(stroke
				(width 0.1)
				(type default)
			)
			(layer "F.Fab")
		)
		(fp_line
			(start 0.67945 -0.3048)
			(end 0.67945 0.3048)
			(stroke
				(width 0.1)
				(type default)
			)
			(layer "F.Fab")
		)
		(fp_line
			(start 0.12065 -0.2794)
			(end 0.12065 -0.3048)
			(stroke
				(width 0.1)
				(type default)
			)
			(layer "F.Fab")
		)
		(fp_line
			(start 0.12065 -0.3048)
			(end 0.67945 -0.3048)
			(stroke
				(width 0.1)
				(type default)
			)
			(layer "F.Fab")
		)
		(fp_line
			(start 0.120396 0.3048)
			(end 0.120396 0.2794)
			(stroke
				(width 0.1)
				(type default)
			)
			(layer "F.Fab")
		)
		(fp_line
			(start 0.120396 0.2794)
			(end -0.12065 0.2794)
			(stroke
				(width 0.1)
				(type default)
			)
			(layer "F.Fab")
		)
		(fp_line
			(start -0.12065 0.3048)
			(end -0.67945 0.3048)
			(stroke
				(width 0.1)
				(type default)
			)
			(layer "F.Fab")
		)
		(fp_line
			(start -0.12065 0.2794)
			(end -0.12065 0.3048)
			(stroke
				(width 0.1)
				(type default)
			)
			(layer "F.Fab")
		)
		(fp_line
			(start -0.12065 -0.2794)
			(end 0.12065 -0.2794)
			(stroke
				(width 0.1)
				(type default)
			)
			(layer "F.Fab")
		)
		(fp_line
			(start -0.12065 -0.305054)
			(end -0.12065 -0.2794)
			(stroke
				(width 0.1)
				(type default)
			)
			(layer "F.Fab")
		)
		(fp_line
			(start -0.67945 0.3048)
			(end -0.67945 -0.305054)
			(stroke
				(width 0.1)
				(type default)
			)
			(layer "F.Fab")
		)
		(fp_line
			(start -0.67945 -0.305054)
			(end -0.12065 -0.305054)
			(stroke
				(width 0.1)
				(type default)
			)
			(layer "F.Fab")
		)
		(pad "1" smd circle
			(at -0.40005 0 180)
			(size 0 0)
			(layers "F.Cu" "F.Mask" "F.Paste")
			(net "PWRGD_P12V_NIC4")
		)
		(pad "2" smd circle
			(at 0.40005 0 180)
			(size 0 0)
			(layers "F.Cu" "F.Mask" "F.Paste")
			(net "PWRGD_P12V_NIC4_R")
		)
	)
	(footprint ""
		(layer "F.Cu")
		(at 214.534496 -33.631886 180)
		(property "Reference" "C301"
			(at 0 0 180)
			(layer "F.SilkS")
			(hide yes)
			(effects
				(font
					(size 1.27 1.27)
				)
			)
		)
		(property "Value" ""
			(at 0 0 180)
			(layer "F.Fab")
			(effects
				(font
					(size 1.27 1.27)
				)
			)
		)
		(duplicate_pad_numbers_are_jumpers no)
		(fp_line
			(start 0.299974 0.150114)
			(end -0.299974 0.150114)
			(stroke
				(width 0.1)
				(type default)
			)
			(layer "F.Fab")
		)
		(fp_line
			(start 0.299974 -0.150114)
			(end 0.299974 0.150114)
			(stroke
				(width 0.1)
				(type default)
			)
			(layer "F.Fab")
		)
		(fp_line
			(start -0.299974 0.150114)
			(end -0.299974 -0.150114)
			(stroke
				(width 0.1)
				(type default)
			)
			(layer "F.Fab")
		)
		(fp_line
			(start -0.299974 -0.150114)
			(end 0.299974 -0.150114)
			(stroke
				(width 0.1)
				(type default)
			)
			(layer "F.Fab")
		)
		(pad "1" smd rect
			(at -0.2667 0 180)
			(size 0.3048 0.381)
			(layers "F.Cu" "F.Mask" "F.Paste")
			(net "P5E_PEX1_STN2_TX_DN<35>")
		)
		(pad "2" smd rect
			(at 0.2667 0 180)
			(size 0.3048 0.381)
			(layers "F.Cu" "F.Mask" "F.Paste")
			(net "P5E_PEX1_STN2_TX_C_DN<35>")
		)
	)
	(footprint ""
		(layer "F.Cu")
		(at 142.474442 -250.070874 -90)
		(property "Reference" "R1271"
			(at 0 0 270)
			(layer "F.SilkS")
			(hide yes)
			(effects
				(font
					(size 1.27 1.27)
				)
			)
		)
		(property "Value" ""
			(at 0 0 270)
			(layer "F.Fab")
			(effects
				(font
					(size 1.27 1.27)
				)
			)
		)
		(duplicate_pad_numbers_are_jumpers no)
		(fp_line
			(start -0.7874 0.4064)
			(end -0.7874 -0.4064)
			(stroke
				(width 0.1524)
				(type default)
			)
			(layer "F.SilkS")
		)
		(fp_line
			(start 0.7874 0.4064)
			(end -0.7874 0.4064)
			(stroke
				(width 0.1524)
				(type default)
			)
			(layer "F.SilkS")
		)
		(fp_line
			(start -0.7874 -0.4064)
			(end 0.7874 -0.4064)
			(stroke
				(width 0.1524)
				(type default)
			)
			(layer "F.SilkS")
		)
		(fp_line
			(start 0.7874 -0.4064)
			(end 0.7874 0.4064)
			(stroke
				(width 0.1524)
				(type default)
			)
			(layer "F.SilkS")
		)
		(fp_line
			(start -0.67945 0.3048)
			(end -0.67945 -0.305054)
			(stroke
				(width 0.1)
				(type default)
			)
			(layer "F.Fab")
		)
		(fp_line
			(start -0.12065 0.3048)
			(end -0.67945 0.3048)
			(stroke
				(width 0.1)
				(type default)
			)
			(layer "F.Fab")
		)
		(fp_line
			(start 0.120396 0.3048)
			(end 0.120396 0.2794)
			(stroke
				(width 0.1)
				(type default)
			)
			(layer "F.Fab")
		)
		(fp_line
			(start 0.67945 0.3048)
			(end 0.120396 0.3048)
			(stroke
				(width 0.1)
				(type default)
			)
			(layer "F.Fab")
		)
		(fp_line
			(start -0.12065 0.2794)
			(end -0.12065 0.3048)
			(stroke
				(width 0.1)
				(type default)
			)
			(layer "F.Fab")
		)
		(fp_line
			(start 0.120396 0.2794)
			(end -0.12065 0.2794)
			(stroke
				(width 0.1)
				(type default)
			)
			(layer "F.Fab")
		)
		(fp_line
			(start -0.12065 -0.2794)
			(end 0.12065 -0.2794)
			(stroke
				(width 0.1)
				(type default)
			)
			(layer "F.Fab")
		)
		(fp_line
			(start 0.12065 -0.2794)
			(end 0.12065 -0.3048)
			(stroke
				(width 0.1)
				(type default)
			)
			(layer "F.Fab")
		)
		(fp_line
			(start 0.12065 -0.3048)
			(end 0.67945 -0.3048)
			(stroke
				(width 0.1)
				(type default)
			)
			(layer "F.Fab")
		)
		(fp_line
			(start 0.67945 -0.3048)
			(end 0.67945 0.3048)
			(stroke
				(width 0.1)
				(type default)
			)
			(layer "F.Fab")
		)
		(fp_line
			(start -0.67945 -0.305054)
			(end -0.12065 -0.305054)
			(stroke
				(width 0.1)
				(type default)
			)
			(layer "F.Fab")
		)
		(fp_line
			(start -0.12065 -0.305054)
			(end -0.12065 -0.2794)
			(stroke
				(width 0.1)
				(type default)
			)
			(layer "F.Fab")
		)
		(pad "1" smd circle
			(at -0.40005 0 270)
			(size 0 0)
			(layers "F.Cu" "F.Mask" "F.Paste")
			(net "PEX1_MODE_SEL2")
		)
		(pad "2" smd circle
			(at 0.40005 0 270)
			(size 0 0)
			(layers "F.Cu" "F.Mask" "F.Paste")
			(net "P1V8_PEX")
		)
	)
	(footprint ""
		(layer "F.Cu")
		(at 292.743382 -356.244906 90)
		(property "Reference" "C2365"
			(at 0 0 90)
			(layer "F.SilkS")
			(hide yes)
			(effects
				(font
					(size 1.27 1.27)
				)
			)
		)
		(property "Value" ""
			(at 0 0 90)
			(layer "F.Fab")
			(effects
				(font
					(size 1.27 1.27)
				)
			)
		)
		(duplicate_pad_numbers_are_jumpers no)
		(fp_line
			(start 0.299974 -0.150114)
			(end 0.299974 0.150114)
			(stroke
				(width 0.1)
				(type default)
			)
			(layer "F.Fab")
		)
		(fp_line
			(start -0.299974 -0.150114)
			(end 0.299974 -0.150114)
			(stroke
				(width 0.1)
				(type default)
			)
			(layer "F.Fab")
		)
		(fp_line
			(start 0.299974 0.150114)
			(end -0.299974 0.150114)
			(stroke
				(width 0.1)
				(type default)
			)
			(layer "F.Fab")
		)
		(fp_line
			(start -0.299974 0.150114)
			(end -0.299974 -0.150114)
			(stroke
				(width 0.1)
				(type default)
			)
			(layer "F.Fab")
		)
		(pad "1" smd rect
			(at -0.2667 0 90)
			(size 0.3048 0.381)
			(layers "F.Cu" "F.Mask" "F.Paste")
			(net "P5E_PEX2_STN4_TX_DP<67>")
		)
		(pad "2" smd rect
			(at 0.2667 0 90)
			(size 0.3048 0.381)
			(layers "F.Cu" "F.Mask" "F.Paste")
			(net "P5E_PEX2_STN4_TX_C_DP<67>")
		)
	)
	(footprint ""
		(layer "F.Cu")
		(at 336.443574 -47.92091)
		(property "Reference" "R625"
			(at 0 0 0)
			(layer "F.SilkS")
			(hide yes)
			(effects
				(font
					(size 1.27 1.27)
				)
			)
		)
		(property "Value" ""
			(at 0 0 0)
			(layer "F.Fab")
			(effects
				(font
					(size 1.27 1.27)
				)
			)
		)
		(duplicate_pad_numbers_are_jumpers no)
		(fp_line
			(start -0.7874 -0.4064)
			(end 0.7874 -0.4064)
			(stroke
				(width 0.1524)
				(type default)
			)
			(layer "F.SilkS")
		)
		(fp_line
			(start -0.7874 0.4064)
			(end -0.7874 -0.4064)
			(stroke
				(width 0.1524)
				(type default)
			)
			(layer "F.SilkS")
		)
		(fp_line
			(start 0.7874 -0.4064)
			(end 0.7874 0.4064)
			(stroke
				(width 0.1524)
				(type default)
			)
			(layer "F.SilkS")
		)
		(fp_line
			(start 0.7874 0.4064)
			(end -0.7874 0.4064)
			(stroke
				(width 0.1524)
				(type default)
			)
			(layer "F.SilkS")
		)
		(fp_line
			(start -0.67945 -0.305054)
			(end -0.12065 -0.305054)
			(stroke
				(width 0.1)
				(type default)
			)
			(layer "F.Fab")
		)
		(fp_line
			(start -0.67945 0.3048)
			(end -0.67945 -0.305054)
			(stroke
				(width 0.1)
				(type default)
			)
			(layer "F.Fab")
		)
		(fp_line
			(start -0.12065 -0.305054)
			(end -0.12065 -0.2794)
			(stroke
				(width 0.1)
				(type default)
			)
			(layer "F.Fab")
		)
		(fp_line
			(start -0.12065 -0.2794)
			(end 0.12065 -0.2794)
			(stroke
				(width 0.1)
				(type default)
			)
			(layer "F.Fab")
		)
		(fp_line
			(start -0.12065 0.2794)
			(end -0.12065 0.3048)
			(stroke
				(width 0.1)
				(type default)
			)
			(layer "F.Fab")
		)
		(fp_line
			(start -0.12065 0.3048)
			(end -0.67945 0.3048)
			(stroke
				(width 0.1)
				(type default)
			)
			(layer "F.Fab")
		)
		(fp_line
			(start 0.120396 0.2794)
			(end -0.12065 0.2794)
			(stroke
				(width 0.1)
				(type default)
			)
			(layer "F.Fab")
		)
		(fp_line
			(start 0.120396 0.3048)
			(end 0.120396 0.2794)
			(stroke
				(width 0.1)
				(type default)
			)
			(layer "F.Fab")
		)
		(fp_line
			(start 0.12065 -0.3048)
			(end 0.67945 -0.3048)
			(stroke
				(width 0.1)
				(type default)
			)
			(layer "F.Fab")
		)
		(fp_line
			(start 0.12065 -0.2794)
			(end 0.12065 -0.3048)
			(stroke
				(width 0.1)
				(type default)
			)
			(layer "F.Fab")
		)
		(fp_line
			(start 0.67945 -0.3048)
			(end 0.67945 0.3048)
			(stroke
				(width 0.1)
				(type default)
			)
			(layer "F.Fab")
		)
		(fp_line
			(start 0.67945 0.3048)
			(end 0.120396 0.3048)
			(stroke
				(width 0.1)
				(type default)
			)
			(layer "F.Fab")
		)
		(pad "1" smd circle
			(at -0.40005 0)
			(size 0 0)
			(layers "F.Cu" "F.Mask" "F.Paste")
			(net "P3V3_AUX")
		)
		(pad "2" smd circle
			(at 0.40005 0)
			(size 0 0)
			(layers "F.Cu" "F.Mask" "F.Paste")
			(net "SSD_8_15_ADC_ALERT_N")
		)
	)
	(footprint ""
		(layer "F.Cu")
		(at 338.474304 -6.739636)
		(property "Reference" "R1712"
			(at 0 0 0)
			(layer "F.SilkS")
			(hide yes)
			(effects
				(font
					(size 1.27 1.27)
				)
			)
		)
		(property "Value" ""
			(at 0 0 0)
			(layer "F.Fab")
			(effects
				(font
					(size 1.27 1.27)
				)
			)
		)
		(duplicate_pad_numbers_are_jumpers no)
		(fp_line
			(start -0.7874 -0.4064)
			(end 0.7874 -0.4064)
			(stroke
				(width 0.1524)
				(type default)
			)
			(layer "F.SilkS")
		)
		(fp_line
			(start -0.7874 0.4064)
			(end -0.7874 -0.4064)
			(stroke
				(width 0.1524)
				(type default)
			)
			(layer "F.SilkS")
		)
		(fp_line
			(start 0.7874 -0.4064)
			(end 0.7874 0.4064)
			(stroke
				(width 0.1524)
				(type default)
			)
			(layer "F.SilkS")
		)
		(fp_line
			(start 0.7874 0.4064)
			(end -0.7874 0.4064)
			(stroke
				(width 0.1524)
				(type default)
			)
			(layer "F.SilkS")
		)
		(fp_line
			(start -0.67945 -0.305054)
			(end -0.12065 -0.305054)
			(stroke
				(width 0.1)
				(type default)
			)
			(layer "F.Fab")
		)
		(fp_line
			(start -0.67945 0.3048)
			(end -0.67945 -0.305054)
			(stroke
				(width 0.1)
				(type default)
			)
			(layer "F.Fab")
		)
		(fp_line
			(start -0.12065 -0.305054)
			(end -0.12065 -0.2794)
			(stroke
				(width 0.1)
				(type default)
			)
			(layer "F.Fab")
		)
		(fp_line
			(start -0.12065 -0.2794)
			(end 0.12065 -0.2794)
			(stroke
				(width 0.1)
				(type default)
			)
			(layer "F.Fab")
		)
		(fp_line
			(start -0.12065 0.2794)
			(end -0.12065 0.3048)
			(stroke
				(width 0.1)
				(type default)
			)
			(layer "F.Fab")
		)
		(fp_line
			(start -0.12065 0.3048)
			(end -0.67945 0.3048)
			(stroke
				(width 0.1)
				(type default)
			)
			(layer "F.Fab")
		)
		(fp_line
			(start 0.120396 0.2794)
			(end -0.12065 0.2794)
			(stroke
				(width 0.1)
				(type default)
			)
			(layer "F.Fab")
		)
		(fp_line
			(start 0.120396 0.3048)
			(end 0.120396 0.2794)
			(stroke
				(width 0.1)
				(type default)
			)
			(layer "F.Fab")
		)
		(fp_line
			(start 0.12065 -0.3048)
			(end 0.67945 -0.3048)
			(stroke
				(width 0.1)
				(type default)
			)
			(layer "F.Fab")
		)
		(fp_line
			(start 0.12065 -0.2794)
			(end 0.12065 -0.3048)
			(stroke
				(width 0.1)
				(type default)
			)
			(layer "F.Fab")
		)
		(fp_line
			(start 0.67945 -0.3048)
			(end 0.67945 0.3048)
			(stroke
				(width 0.1)
				(type default)
			)
			(layer "F.Fab")
		)
		(fp_line
			(start 0.67945 0.3048)
			(end 0.120396 0.3048)
			(stroke
				(width 0.1)
				(type default)
			)
			(layer "F.Fab")
		)
		(pad "1" smd circle
			(at -0.40005 0)
			(size 0 0)
			(layers "F.Cu" "F.Mask" "F.Paste")
			(net "SMB_BIC_I2C9_MUX1_SSD11_R_SDA")
		)
		(pad "2" smd circle
			(at 0.40005 0)
			(size 0 0)
			(layers "F.Cu" "F.Mask" "F.Paste")
			(net "SMB_ISO_SSD11_SDA")
		)
	)
	(footprint ""
		(layer "F.Cu")
		(at 378.18822 -257.64871 -90)
		(property "Reference" "C3559"
			(at 0 0 270)
			(layer "F.SilkS")
			(hide yes)
			(effects
				(font
					(size 1.27 1.27)
				)
			)
		)
		(property "Value" ""
			(at 0 0 270)
			(layer "F.Fab")
			(effects
				(font
					(size 1.27 1.27)
				)
			)
		)
		(duplicate_pad_numbers_are_jumpers no)
		(fp_line
			(start -1.2954 0.5842)
			(end -1.2954 -0.5842)
			(stroke
				(width 0.1524)
				(type default)
			)
			(layer "F.SilkS")
		)
		(fp_line
			(start 1.2954 0.5842)
			(end -1.2954 0.5842)
			(stroke
				(width 0.1524)
				(type default)
			)
			(layer "F.SilkS")
		)
		(fp_line
			(start -1.2954 -0.5842)
			(end 1.2954 -0.5842)
			(stroke
				(width 0.1524)
				(type default)
			)
			(layer "F.SilkS")
		)
		(fp_line
			(start 1.2954 -0.5842)
			(end 1.2954 0.5842)
			(stroke
				(width 0.1524)
				(type default)
			)
			(layer "F.SilkS")
		)
		(fp_line
			(start -0.8636 0.4572)
			(end -0.8636 0.4064)
			(stroke
				(width 0.1)
				(type default)
			)
			(layer "F.Fab")
		)
		(fp_line
			(start 0.8636 0.4572)
			(end -0.8636 0.4572)
			(stroke
				(width 0.1)
				(type default)
			)
			(layer "F.Fab")
		)
		(fp_line
			(start -1.1938 0.4064)
			(end -1.1938 -0.4064)
			(stroke
				(width 0.1)
				(type default)
			)
			(layer "F.Fab")
		)
		(fp_line
			(start -0.8636 0.4064)
			(end -1.1938 0.4064)
			(stroke
				(width 0.1)
				(type default)
			)
			(layer "F.Fab")
		)
		(fp_line
			(start 0.8636 0.4064)
			(end 0.8636 0.4572)
			(stroke
				(width 0.1)
				(type default)
			)
			(layer "F.Fab")
		)
		(fp_line
			(start 1.1938 0.4064)
			(end 0.8636 0.4064)
			(stroke
				(width 0.1)
				(type default)
			)
			(layer "F.Fab")
		)
		(fp_line
			(start -1.1938 -0.4064)
			(end -0.8636 -0.4064)
			(stroke
				(width 0.1)
				(type default)
			)
			(layer "F.Fab")
		)
		(fp_line
			(start -0.8636 -0.4064)
			(end -0.8636 -0.4572)
			(stroke
				(width 0.1)
				(type default)
			)
			(layer "F.Fab")
		)
		(fp_line
			(start 0.8636 -0.4064)
			(end 1.1938 -0.4064)
			(stroke
				(width 0.1)
				(type default)
			)
			(layer "F.Fab")
		)
		(fp_line
			(start 1.1938 -0.4064)
			(end 1.1938 0.4064)
			(stroke
				(width 0.1)
				(type default)
			)
			(layer "F.Fab")
		)
		(fp_line
			(start -0.8636 -0.4572)
			(end 0.8636 -0.4572)
			(stroke
				(width 0.1)
				(type default)
			)
			(layer "F.Fab")
		)
		(fp_line
			(start 0.8636 -0.4572)
			(end 0.8636 -0.4064)
			(stroke
				(width 0.1)
				(type default)
			)
			(layer "F.Fab")
		)
		(pad "1" smd rect
			(at -0.7366 0 180)
			(size 0.7112 0.8128)
			(layers "F.Cu" "F.Mask" "F.Paste")
			(net "P1V8_PLL0_PEX3")
		)
		(pad "2" smd rect
			(at 0.7366 0 180)
			(size 0.7112 0.8128)
			(layers "F.Cu" "F.Mask" "F.Paste")
			(net "GND")
		)
	)
	(footprint ""
		(layer "F.Cu")
		(at 430.450498 -80.581246 90)
		(property "Reference" "U47"
			(at -0.672846 2.366772 90)
			(unlocked yes)
			(layer "F.SilkS")
			(effects
				(font
					(size 0.7874 0.5842)
					(thickness 0.1524)
				)
			)
		)
		(property "Value" ""
			(at 0 0 90)
			(layer "F.Fab")
			(effects
				(font
					(size 1.27 1.27)
				)
			)
		)
		(duplicate_pad_numbers_are_jumpers no)
		(fp_line
			(start 1.905 -1.651)
			(end 1.905 1.651)
			(stroke
				(width 0.1524)
				(type default)
			)
			(layer "F.SilkS")
		)
		(fp_line
			(start -1.905 -1.651)
			(end 1.905 -1.651)
			(stroke
				(width 0.1524)
				(type default)
			)
			(layer "F.SilkS")
		)
		(fp_line
			(start 1.905 1.651)
			(end -1.905 1.651)
			(stroke
				(width 0.1524)
				(type default)
			)
			(layer "F.SilkS")
		)
		(fp_line
			(start -1.905 1.651)
			(end -1.905 -1.651)
			(stroke
				(width 0.1524)
				(type default)
			)
			(layer "F.SilkS")
		)
		(fp_line
			(start 0.6985 -1.524)
			(end 0.6985 -0.219964)
			(stroke
				(width 0.1)
				(type default)
			)
			(layer "F.Fab")
		)
		(fp_line
			(start -0.649986 -1.524)
			(end 0.6985 -1.524)
			(stroke
				(width 0.1)
				(type default)
			)
			(layer "F.Fab")
		)
		(fp_line
			(start -0.649986 -1.169924)
			(end -0.649986 -1.524)
			(stroke
				(width 0.1)
				(type default)
			)
			(layer "F.Fab")
		)
		(fp_line
			(start -1.249934 -1.169924)
			(end -0.649986 -1.169924)
			(stroke
				(width 0.1)
				(type default)
			)
			(layer "F.Fab")
		)
		(fp_line
			(start -0.6985 -0.729996)
			(end -1.249934 -0.729996)
			(stroke
				(width 0.1)
				(type default)
			)
			(layer "F.Fab")
		)
		(fp_line
			(start -1.249934 -0.729996)
			(end -1.249934 -1.169924)
			(stroke
				(width 0.1)
				(type default)
			)
			(layer "F.Fab")
		)
		(fp_line
			(start 1.249934 -0.219964)
			(end 1.249934 0.219964)
			(stroke
				(width 0.1)
				(type default)
			)
			(layer "F.Fab")
		)
		(fp_line
			(start 0.6985 -0.219964)
			(end 1.249934 -0.219964)
			(stroke
				(width 0.1)
				(type default)
			)
			(layer "F.Fab")
		)
		(fp_line
			(start 1.249934 0.219964)
			(end 0.6985 0.219964)
			(stroke
				(width 0.1)
				(type default)
			)
			(layer "F.Fab")
		)
		(fp_line
			(start 0.6985 0.219964)
			(end 0.6985 1.524)
			(stroke
				(width 0.1)
				(type default)
			)
			(layer "F.Fab")
		)
		(fp_line
			(start -0.6985 0.729996)
			(end -0.6985 -0.729996)
			(stroke
				(width 0.1)
				(type default)
			)
			(layer "F.Fab")
		)
		(fp_line
			(start -1.249934 0.729996)
			(end -0.6985 0.729996)
			(stroke
				(width 0.1)
				(type default)
			)
			(layer "F.Fab")
		)
		(fp_line
			(start -0.649986 1.169924)
			(end -1.249934 1.169924)
			(stroke
				(width 0.1)
				(type default)
			)
			(layer "F.Fab")
		)
		(fp_line
			(start -1.249934 1.169924)
			(end -1.249934 0.729996)
			(stroke
				(width 0.1)
				(type default)
			)
			(layer "F.Fab")
		)
		(fp_line
			(start 0.6985 1.524)
			(end -0.649986 1.524)
			(stroke
				(width 0.1)
				(type default)
			)
			(layer "F.Fab")
		)
		(fp_line
			(start -0.649986 1.524)
			(end -0.649986 1.169924)
			(stroke
				(width 0.1)
				(type default)
			)
			(layer "F.Fab")
		)
		(pad "1" smd rect
			(at -1.1176 -1.016)
			(size 1.016 1.27)
			(layers "F.Cu" "F.Mask" "F.Paste")
			(net "HP_NIC7_PWRGD")
		)
		(pad "2" smd rect
			(at -1.1176 1.016)
			(size 1.016 1.27)
			(layers "F.Cu" "F.Mask" "F.Paste")
			(net "P3V3_NIC7")
		)
		(pad "3" smd rect
			(at 1.1176 0)
			(size 1.016 1.27)
			(layers "F.Cu" "F.Mask" "F.Paste")
			(net "GND")
		)
	)
	(footprint ""
		(layer "F.Cu")
		(at 221.211902 -139.641834)
		(property "Reference" "R4219"
			(at 0 0 0)
			(layer "F.SilkS")
			(hide yes)
			(effects
				(font
					(size 1.27 1.27)
				)
			)
		)
		(property "Value" ""
			(at 0 0 0)
			(layer "F.Fab")
			(effects
				(font
					(size 1.27 1.27)
				)
			)
		)
		(duplicate_pad_numbers_are_jumpers no)
		(fp_line
			(start -0.7874 -0.4064)
			(end 0.7874 -0.4064)
			(stroke
				(width 0.1524)
				(type default)
			)
			(layer "F.SilkS")
		)
		(fp_line
			(start -0.7874 0.4064)
			(end -0.7874 -0.4064)
			(stroke
				(width 0.1524)
				(type default)
			)
			(layer "F.SilkS")
		)
		(fp_line
			(start 0.7874 -0.4064)
			(end 0.7874 0.4064)
			(stroke
				(width 0.1524)
				(type default)
			)
			(layer "F.SilkS")
		)
		(fp_line
			(start 0.7874 0.4064)
			(end -0.7874 0.4064)
			(stroke
				(width 0.1524)
				(type default)
			)
			(layer "F.SilkS")
		)
		(fp_line
			(start -0.67945 -0.305054)
			(end -0.12065 -0.305054)
			(stroke
				(width 0.1)
				(type default)
			)
			(layer "F.Fab")
		)
		(fp_line
			(start -0.67945 0.3048)
			(end -0.67945 -0.305054)
			(stroke
				(width 0.1)
				(type default)
			)
			(layer "F.Fab")
		)
		(fp_line
			(start -0.12065 -0.305054)
			(end -0.12065 -0.2794)
			(stroke
				(width 0.1)
				(type default)
			)
			(layer "F.Fab")
		)
		(fp_line
			(start -0.12065 -0.2794)
			(end 0.12065 -0.2794)
			(stroke
				(width 0.1)
				(type default)
			)
			(layer "F.Fab")
		)
		(fp_line
			(start -0.12065 0.2794)
			(end -0.12065 0.3048)
			(stroke
				(width 0.1)
				(type default)
			)
			(layer "F.Fab")
		)
		(fp_line
			(start -0.12065 0.3048)
			(end -0.67945 0.3048)
			(stroke
				(width 0.1)
				(type default)
			)
			(layer "F.Fab")
		)
		(fp_line
			(start 0.120396 0.2794)
			(end -0.12065 0.2794)
			(stroke
				(width 0.1)
				(type default)
			)
			(layer "F.Fab")
		)
		(fp_line
			(start 0.120396 0.3048)
			(end 0.120396 0.2794)
			(stroke
				(width 0.1)
				(type default)
			)
			(layer "F.Fab")
		)
		(fp_line
			(start 0.12065 -0.3048)
			(end 0.67945 -0.3048)
			(stroke
				(width 0.1)
				(type default)
			)
			(layer "F.Fab")
		)
		(fp_line
			(start 0.12065 -0.2794)
			(end 0.12065 -0.3048)
			(stroke
				(width 0.1)
				(type default)
			)
			(layer "F.Fab")
		)
		(fp_line
			(start 0.67945 -0.3048)
			(end 0.67945 0.3048)
			(stroke
				(width 0.1)
				(type default)
			)
			(layer "F.Fab")
		)
		(fp_line
			(start 0.67945 0.3048)
			(end 0.120396 0.3048)
			(stroke
				(width 0.1)
				(type default)
			)
			(layer "F.Fab")
		)
		(pad "1" smd circle
			(at -0.40005 0)
			(size 0 0)
			(layers "F.Cu" "F.Mask" "F.Paste")
			(net "P3V3")
		)
		(pad "2" smd circle
			(at 0.40005 0)
			(size 0 0)
			(layers "F.Cu" "F.Mask" "F.Paste")
			(net "PU_CK440_PEX_PFT_LOST_N")
		)
	)
	(footprint ""
		(layer "F.Cu")
		(at 58.0644 -139.6238)
		(property "Reference" "R37"
			(at 0 0 0)
			(layer "F.SilkS")
			(hide yes)
			(effects
				(font
					(size 1.27 1.27)
				)
			)
		)
		(property "Value" ""
			(at 0 0 0)
			(layer "F.Fab")
			(effects
				(font
					(size 1.27 1.27)
				)
			)
		)
		(duplicate_pad_numbers_are_jumpers no)
		(fp_line
			(start -0.7874 -0.4064)
			(end 0.7874 -0.4064)
			(stroke
				(width 0.1524)
				(type default)
			)
			(layer "F.SilkS")
		)
		(fp_line
			(start -0.7874 0.4064)
			(end -0.7874 -0.4064)
			(stroke
				(width 0.1524)
				(type default)
			)
			(layer "F.SilkS")
		)
		(fp_line
			(start 0.7874 -0.4064)
			(end 0.7874 0.4064)
			(stroke
				(width 0.1524)
				(type default)
			)
			(layer "F.SilkS")
		)
		(fp_line
			(start 0.7874 0.4064)
			(end -0.7874 0.4064)
			(stroke
				(width 0.1524)
				(type default)
			)
			(layer "F.SilkS")
		)
		(fp_line
			(start -0.67945 -0.305054)
			(end -0.12065 -0.305054)
			(stroke
				(width 0.1)
				(type default)
			)
			(layer "F.Fab")
		)
		(fp_line
			(start -0.67945 0.3048)
			(end -0.67945 -0.305054)
			(stroke
				(width 0.1)
				(type default)
			)
			(layer "F.Fab")
		)
		(fp_line
			(start -0.12065 -0.305054)
			(end -0.12065 -0.2794)
			(stroke
				(width 0.1)
				(type default)
			)
			(layer "F.Fab")
		)
		(fp_line
			(start -0.12065 -0.2794)
			(end 0.12065 -0.2794)
			(stroke
				(width 0.1)
				(type default)
			)
			(layer "F.Fab")
		)
		(fp_line
			(start -0.12065 0.2794)
			(end -0.12065 0.3048)
			(stroke
				(width 0.1)
				(type default)
			)
			(layer "F.Fab")
		)
		(fp_line
			(start -0.12065 0.3048)
			(end -0.67945 0.3048)
			(stroke
				(width 0.1)
				(type default)
			)
			(layer "F.Fab")
		)
		(fp_line
			(start 0.120396 0.2794)
			(end -0.12065 0.2794)
			(stroke
				(width 0.1)
				(type default)
			)
			(layer "F.Fab")
		)
		(fp_line
			(start 0.120396 0.3048)
			(end 0.120396 0.2794)
			(stroke
				(width 0.1)
				(type default)
			)
			(layer "F.Fab")
		)
		(fp_line
			(start 0.12065 -0.3048)
			(end 0.67945 -0.3048)
			(stroke
				(width 0.1)
				(type default)
			)
			(layer "F.Fab")
		)
		(fp_line
			(start 0.12065 -0.2794)
			(end 0.12065 -0.3048)
			(stroke
				(width 0.1)
				(type default)
			)
			(layer "F.Fab")
		)
		(fp_line
			(start 0.67945 -0.3048)
			(end 0.67945 0.3048)
			(stroke
				(width 0.1)
				(type default)
			)
			(layer "F.Fab")
		)
		(fp_line
			(start 0.67945 0.3048)
			(end 0.120396 0.3048)
			(stroke
				(width 0.1)
				(type default)
			)
			(layer "F.Fab")
		)
		(pad "1" smd circle
			(at -0.40005 0)
			(size 0 0)
			(layers "F.Cu" "F.Mask" "F.Paste")
			(net "RST_SMB_NIC0_MUX_ISO_R_N")
		)
		(pad "2" smd circle
			(at 0.40005 0)
			(size 0 0)
			(layers "F.Cu" "F.Mask" "F.Paste")
			(net "RST_SMB_NIC0_MUX_ISO_N")
		)
	)
	(footprint ""
		(layer "F.Cu")
		(at 270.960342 -96.1644)
		(property "Reference" "R246"
			(at 0 0 0)
			(layer "F.SilkS")
			(hide yes)
			(effects
				(font
					(size 1.27 1.27)
				)
			)
		)
		(property "Value" ""
			(at 0 0 0)
			(layer "F.Fab")
			(effects
				(font
					(size 1.27 1.27)
				)
			)
		)
		(duplicate_pad_numbers_are_jumpers no)
		(fp_line
			(start -0.7874 -0.4064)
			(end 0.7874 -0.4064)
			(stroke
				(width 0.1524)
				(type default)
			)
			(layer "F.SilkS")
		)
		(fp_line
			(start -0.7874 0.4064)
			(end -0.7874 -0.4064)
			(stroke
				(width 0.1524)
				(type default)
			)
			(layer "F.SilkS")
		)
		(fp_line
			(start 0.7874 -0.4064)
			(end 0.7874 0.4064)
			(stroke
				(width 0.1524)
				(type default)
			)
			(layer "F.SilkS")
		)
		(fp_line
			(start 0.7874 0.4064)
			(end -0.7874 0.4064)
			(stroke
				(width 0.1524)
				(type default)
			)
			(layer "F.SilkS")
		)
		(fp_line
			(start -0.67945 -0.305054)
			(end -0.12065 -0.305054)
			(stroke
				(width 0.1)
				(type default)
			)
			(layer "F.Fab")
		)
		(fp_line
			(start -0.67945 0.3048)
			(end -0.67945 -0.305054)
			(stroke
				(width 0.1)
				(type default)
			)
			(layer "F.Fab")
		)
		(fp_line
			(start -0.12065 -0.305054)
			(end -0.12065 -0.2794)
			(stroke
				(width 0.1)
				(type default)
			)
			(layer "F.Fab")
		)
		(fp_line
			(start -0.12065 -0.2794)
			(end 0.12065 -0.2794)
			(stroke
				(width 0.1)
				(type default)
			)
			(layer "F.Fab")
		)
		(fp_line
			(start -0.12065 0.2794)
			(end -0.12065 0.3048)
			(stroke
				(width 0.1)
				(type default)
			)
			(layer "F.Fab")
		)
		(fp_line
			(start -0.12065 0.3048)
			(end -0.67945 0.3048)
			(stroke
				(width 0.1)
				(type default)
			)
			(layer "F.Fab")
		)
		(fp_line
			(start 0.120396 0.2794)
			(end -0.12065 0.2794)
			(stroke
				(width 0.1)
				(type default)
			)
			(layer "F.Fab")
		)
		(fp_line
			(start 0.120396 0.3048)
			(end 0.120396 0.2794)
			(stroke
				(width 0.1)
				(type default)
			)
			(layer "F.Fab")
		)
		(fp_line
			(start 0.12065 -0.3048)
			(end 0.67945 -0.3048)
			(stroke
				(width 0.1)
				(type default)
			)
			(layer "F.Fab")
		)
		(fp_line
			(start 0.12065 -0.2794)
			(end 0.12065 -0.3048)
			(stroke
				(width 0.1)
				(type default)
			)
			(layer "F.Fab")
		)
		(fp_line
			(start 0.67945 -0.3048)
			(end 0.67945 0.3048)
			(stroke
				(width 0.1)
				(type default)
			)
			(layer "F.Fab")
		)
		(fp_line
			(start 0.67945 0.3048)
			(end 0.120396 0.3048)
			(stroke
				(width 0.1)
				(type default)
			)
			(layer "F.Fab")
		)
		(pad "1" smd circle
			(at -0.40005 0)
			(size 0 0)
			(layers "F.Cu" "F.Mask" "F.Paste")
			(net "PRSNT_NIC4_N")
		)
		(pad "2" smd circle
			(at 0.40005 0)
			(size 0 0)
			(layers "F.Cu" "F.Mask" "F.Paste")
			(net "PRSNTB3_NIC4_N")
		)
	)
	(footprint ""
		(layer "F.Cu")
		(at 384.938524 -105.609898)
		(property "Reference" "C691"
			(at 0 0 0)
			(layer "F.SilkS")
			(hide yes)
			(effects
				(font
					(size 1.27 1.27)
				)
			)
		)
		(property "Value" ""
			(at 0 0 0)
			(layer "F.Fab")
			(effects
				(font
					(size 1.27 1.27)
				)
			)
		)
		(duplicate_pad_numbers_are_jumpers no)
		(fp_line
			(start -0.299974 -0.150114)
			(end 0.299974 -0.150114)
			(stroke
				(width 0.1)
				(type default)
			)
			(layer "F.Fab")
		)
		(fp_line
			(start -0.299974 0.150114)
			(end -0.299974 -0.150114)
			(stroke
				(width 0.1)
				(type default)
			)
			(layer "F.Fab")
		)
		(fp_line
			(start 0.299974 -0.150114)
			(end 0.299974 0.150114)
			(stroke
				(width 0.1)
				(type default)
			)
			(layer "F.Fab")
		)
		(fp_line
			(start 0.299974 0.150114)
			(end -0.299974 0.150114)
			(stroke
				(width 0.1)
				(type default)
			)
			(layer "F.Fab")
		)
		(pad "1" smd rect
			(at -0.2667 0)
			(size 0.3048 0.381)
			(layers "F.Cu" "F.Mask" "F.Paste")
			(net "P5E_PEX3_STN1_TX_DP<19>")
		)
		(pad "2" smd rect
			(at 0.2667 0)
			(size 0.3048 0.381)
			(layers "F.Cu" "F.Mask" "F.Paste")
			(net "P5E_PEX3_STN1_TX_C_DP<19>")
		)
	)
	(footprint ""
		(layer "F.Cu")
		(at 394.959586 -61.612526)
		(property "Reference" "PD45"
			(at -3.7084 -2.733548 0)
			(unlocked yes)
			(layer "F.SilkS")
			(effects
				(font
					(size 0.7874 0.5842)
					(thickness 0.1524)
				)
				(justify left)
			)
		)
		(property "Value" ""
			(at 0 0 0)
			(layer "F.Fab")
			(effects
				(font
					(size 1.27 1.27)
				)
			)
		)
		(duplicate_pad_numbers_are_jumpers no)
		(fp_line
			(start -3.656584 -1.970024)
			(end -3.656584 1.970024)
			(stroke
				(width 0.1524)
				(type default)
			)
			(layer "F.SilkS")
		)
		(fp_line
			(start -3.656584 1.970024)
			(end 4.240784 1.970024)
			(stroke
				(width 0.1524)
				(type default)
			)
			(layer "F.SilkS")
		)
		(fp_line
			(start 4.240784 -1.970024)
			(end -3.656584 -1.970024)
			(stroke
				(width 0.1524)
				(type default)
			)
			(layer "F.SilkS")
		)
		(fp_line
			(start 4.240784 1.970024)
			(end 4.240784 -1.970024)
			(stroke
				(width 0.1524)
				(type default)
			)
			(layer "F.SilkS")
		)
		(fp_poly
			(pts
				(xy 3.580384 1.970024) (xy 3.580384 -1.970024) (xy 4.240784 -1.970024) (xy 4.240784 1.970024)
			)
			(stroke
				(width 0)
				(type default)
			)
			(fill yes)
			(layer "F.SilkS")
		)
		(fp_line
			(start -2.3749 -1.970024)
			(end -2.3749 1.970024)
			(stroke
				(width 0.1)
				(type default)
			)
			(layer "F.Fab")
		)
		(fp_line
			(start -2.3749 1.970024)
			(end 2.3749 1.970024)
			(stroke
				(width 0.1)
				(type default)
			)
			(layer "F.Fab")
		)
		(fp_line
			(start 2.3749 -1.970024)
			(end -2.3749 -1.970024)
			(stroke
				(width 0.1)
				(type default)
			)
			(layer "F.Fab")
		)
		(fp_line
			(start 2.3749 1.970024)
			(end 2.3749 -1.970024)
			(stroke
				(width 0.1)
				(type default)
			)
			(layer "F.Fab")
		)
		(fp_text user "+"
			(at -4.9784 -0.23495 0)
			(unlocked yes)
			(layer "F.Fab")
			(effects
				(font
					(size 1.905 1.4224)
					(thickness 0.1524)
				)
				(justify left)
			)
		)
		(fp_text user "-"
			(at 4.1656 -0.23495 0)
			(unlocked yes)
			(layer "F.Fab")
			(effects
				(font
					(size 1.905 1.4224)
					(thickness 0.1524)
				)
				(justify left)
			)
		)
		(pad "A" smd rect
			(at -2.450084 0)
			(size 2.159 2.2606)
			(layers "F.Cu" "F.Mask" "F.Paste")
			(net "GND")
		)
		(pad "C" smd rect
			(at 2.450084 0)
			(size 2.159 2.2606)
			(layers "F.Cu" "F.Mask" "F.Paste")
			(net "P12V_AUX")
		)
	)
	(footprint ""
		(layer "F.Cu")
		(at 142.343886 -42.84091)
		(property "Reference" "R549"
			(at 0 0 0)
			(layer "F.SilkS")
			(hide yes)
			(effects
				(font
					(size 1.27 1.27)
				)
			)
		)
		(property "Value" ""
			(at 0 0 0)
			(layer "F.Fab")
			(effects
				(font
					(size 1.27 1.27)
				)
			)
		)
		(duplicate_pad_numbers_are_jumpers no)
		(fp_line
			(start -0.7874 -0.4064)
			(end 0.7874 -0.4064)
			(stroke
				(width 0.1524)
				(type default)
			)
			(layer "F.SilkS")
		)
		(fp_line
			(start -0.7874 0.4064)
			(end -0.7874 -0.4064)
			(stroke
				(width 0.1524)
				(type default)
			)
			(layer "F.SilkS")
		)
		(fp_line
			(start 0.7874 -0.4064)
			(end 0.7874 0.4064)
			(stroke
				(width 0.1524)
				(type default)
			)
			(layer "F.SilkS")
		)
		(fp_line
			(start 0.7874 0.4064)
			(end -0.7874 0.4064)
			(stroke
				(width 0.1524)
				(type default)
			)
			(layer "F.SilkS")
		)
		(fp_line
			(start -0.67945 -0.305054)
			(end -0.12065 -0.305054)
			(stroke
				(width 0.1)
				(type default)
			)
			(layer "F.Fab")
		)
		(fp_line
			(start -0.67945 0.3048)
			(end -0.67945 -0.305054)
			(stroke
				(width 0.1)
				(type default)
			)
			(layer "F.Fab")
		)
		(fp_line
			(start -0.12065 -0.305054)
			(end -0.12065 -0.2794)
			(stroke
				(width 0.1)
				(type default)
			)
			(layer "F.Fab")
		)
		(fp_line
			(start -0.12065 -0.2794)
			(end 0.12065 -0.2794)
			(stroke
				(width 0.1)
				(type default)
			)
			(layer "F.Fab")
		)
		(fp_line
			(start -0.12065 0.2794)
			(end -0.12065 0.3048)
			(stroke
				(width 0.1)
				(type default)
			)
			(layer "F.Fab")
		)
		(fp_line
			(start -0.12065 0.3048)
			(end -0.67945 0.3048)
			(stroke
				(width 0.1)
				(type default)
			)
			(layer "F.Fab")
		)
		(fp_line
			(start 0.120396 0.2794)
			(end -0.12065 0.2794)
			(stroke
				(width 0.1)
				(type default)
			)
			(layer "F.Fab")
		)
		(fp_line
			(start 0.120396 0.3048)
			(end 0.120396 0.2794)
			(stroke
				(width 0.1)
				(type default)
			)
			(layer "F.Fab")
		)
		(fp_line
			(start 0.12065 -0.3048)
			(end 0.67945 -0.3048)
			(stroke
				(width 0.1)
				(type default)
			)
			(layer "F.Fab")
		)
		(fp_line
			(start 0.12065 -0.2794)
			(end 0.12065 -0.3048)
			(stroke
				(width 0.1)
				(type default)
			)
			(layer "F.Fab")
		)
		(fp_line
			(start 0.67945 -0.3048)
			(end 0.67945 0.3048)
			(stroke
				(width 0.1)
				(type default)
			)
			(layer "F.Fab")
		)
		(fp_line
			(start 0.67945 0.3048)
			(end 0.120396 0.3048)
			(stroke
				(width 0.1)
				(type default)
			)
			(layer "F.Fab")
		)
		(pad "1" smd circle
			(at -0.40005 0)
			(size 0 0)
			(layers "F.Cu" "F.Mask" "F.Paste")
			(net "SSD4_ADC_A1")
		)
		(pad "2" smd circle
			(at 0.40005 0)
			(size 0 0)
			(layers "F.Cu" "F.Mask" "F.Paste")
			(net "P3V3_AUX")
		)
	)
	(footprint ""
		(layer "F.Cu")
		(at 72.674988 -56.977534 180)
		(property "Reference" "PC376"
			(at 0 0 180)
			(layer "F.SilkS")
			(hide yes)
			(effects
				(font
					(size 1.27 1.27)
				)
			)
		)
		(property "Value" ""
			(at 0 0 180)
			(layer "F.Fab")
			(effects
				(font
					(size 1.27 1.27)
				)
			)
		)
		(duplicate_pad_numbers_are_jumpers no)
		(fp_line
			(start 0.7874 0.4064)
			(end -0.7874 0.4064)
			(stroke
				(width 0.1524)
				(type default)
			)
			(layer "F.SilkS")
		)
		(fp_line
			(start 0.7874 -0.4064)
			(end 0.7874 0.4064)
			(stroke
				(width 0.1524)
				(type default)
			)
			(layer "F.SilkS")
		)
		(fp_line
			(start -0.7874 0.4064)
			(end -0.7874 -0.4064)
			(stroke
				(width 0.1524)
				(type default)
			)
			(layer "F.SilkS")
		)
		(fp_line
			(start -0.7874 -0.4064)
			(end 0.7874 -0.4064)
			(stroke
				(width 0.1524)
				(type default)
			)
			(layer "F.SilkS")
		)
		(fp_line
			(start 0.67945 0.3048)
			(end 0.120396 0.3048)
			(stroke
				(width 0.1)
				(type default)
			)
			(layer "F.Fab")
		)
		(fp_line
			(start 0.67945 -0.3048)
			(end 0.67945 0.3048)
			(stroke
				(width 0.1)
				(type default)
			)
			(layer "F.Fab")
		)
		(fp_line
			(start 0.12065 -0.2794)
			(end 0.12065 -0.3048)
			(stroke
				(width 0.1)
				(type default)
			)
			(layer "F.Fab")
		)
		(fp_line
			(start 0.12065 -0.3048)
			(end 0.67945 -0.3048)
			(stroke
				(width 0.1)
				(type default)
			)
			(layer "F.Fab")
		)
		(fp_line
			(start 0.120396 0.3048)
			(end 0.120396 0.2794)
			(stroke
				(width 0.1)
				(type default)
			)
			(layer "F.Fab")
		)
		(fp_line
			(start 0.120396 0.2794)
			(end -0.12065 0.2794)
			(stroke
				(width 0.1)
				(type default)
			)
			(layer "F.Fab")
		)
		(fp_line
			(start -0.12065 0.3048)
			(end -0.67945 0.3048)
			(stroke
				(width 0.1)
				(type default)
			)
			(layer "F.Fab")
		)
		(fp_line
			(start -0.12065 0.2794)
			(end -0.12065 0.3048)
			(stroke
				(width 0.1)
				(type default)
			)
			(layer "F.Fab")
		)
		(fp_line
			(start -0.12065 -0.2794)
			(end 0.12065 -0.2794)
			(stroke
				(width 0.1)
				(type default)
			)
			(layer "F.Fab")
		)
		(fp_line
			(start -0.12065 -0.305054)
			(end -0.12065 -0.2794)
			(stroke
				(width 0.1)
				(type default)
			)
			(layer "F.Fab")
		)
		(fp_line
			(start -0.67945 0.3048)
			(end -0.67945 -0.305054)
			(stroke
				(width 0.1)
				(type default)
			)
			(layer "F.Fab")
		)
		(fp_line
			(start -0.67945 -0.305054)
			(end -0.12065 -0.305054)
			(stroke
				(width 0.1)
				(type default)
			)
			(layer "F.Fab")
		)
		(pad "1" smd circle
			(at -0.40005 0 180)
			(size 0 0)
			(layers "F.Cu" "F.Mask" "F.Paste")
			(net "P12V_AUX")
		)
		(pad "2" smd circle
			(at 0.40005 0 180)
			(size 0 0)
			(layers "F.Cu" "F.Mask" "F.Paste")
			(net "GND")
		)
	)
	(footprint ""
		(layer "F.Cu")
		(at 257.264408 -29.079952 180)
		(property "Reference" "R6206"
			(at 0 0 180)
			(layer "F.SilkS")
			(hide yes)
			(effects
				(font
					(size 1.27 1.27)
				)
			)
		)
		(property "Value" ""
			(at 0 0 180)
			(layer "F.Fab")
			(effects
				(font
					(size 1.27 1.27)
				)
			)
		)
		(duplicate_pad_numbers_are_jumpers no)
		(fp_line
			(start 0.7874 0.4064)
			(end -0.7874 0.4064)
			(stroke
				(width 0.1524)
				(type default)
			)
			(layer "F.SilkS")
		)
		(fp_line
			(start 0.7874 -0.4064)
			(end 0.7874 0.4064)
			(stroke
				(width 0.1524)
				(type default)
			)
			(layer "F.SilkS")
		)
		(fp_line
			(start -0.7874 0.4064)
			(end -0.7874 -0.4064)
			(stroke
				(width 0.1524)
				(type default)
			)
			(layer "F.SilkS")
		)
		(fp_line
			(start -0.7874 -0.4064)
			(end 0.7874 -0.4064)
			(stroke
				(width 0.1524)
				(type default)
			)
			(layer "F.SilkS")
		)
		(fp_line
			(start 0.67945 0.3048)
			(end 0.120396 0.3048)
			(stroke
				(width 0.1)
				(type default)
			)
			(layer "F.Fab")
		)
		(fp_line
			(start 0.67945 -0.3048)
			(end 0.67945 0.3048)
			(stroke
				(width 0.1)
				(type default)
			)
			(layer "F.Fab")
		)
		(fp_line
			(start 0.12065 -0.2794)
			(end 0.12065 -0.3048)
			(stroke
				(width 0.1)
				(type default)
			)
			(layer "F.Fab")
		)
		(fp_line
			(start 0.12065 -0.3048)
			(end 0.67945 -0.3048)
			(stroke
				(width 0.1)
				(type default)
			)
			(layer "F.Fab")
		)
		(fp_line
			(start 0.120396 0.3048)
			(end 0.120396 0.2794)
			(stroke
				(width 0.1)
				(type default)
			)
			(layer "F.Fab")
		)
		(fp_line
			(start 0.120396 0.2794)
			(end -0.12065 0.2794)
			(stroke
				(width 0.1)
				(type default)
			)
			(layer "F.Fab")
		)
		(fp_line
			(start -0.12065 0.3048)
			(end -0.67945 0.3048)
			(stroke
				(width 0.1)
				(type default)
			)
			(layer "F.Fab")
		)
		(fp_line
			(start -0.12065 0.2794)
			(end -0.12065 0.3048)
			(stroke
				(width 0.1)
				(type default)
			)
			(layer "F.Fab")
		)
		(fp_line
			(start -0.12065 -0.2794)
			(end 0.12065 -0.2794)
			(stroke
				(width 0.1)
				(type default)
			)
			(layer "F.Fab")
		)
		(fp_line
			(start -0.12065 -0.305054)
			(end -0.12065 -0.2794)
			(stroke
				(width 0.1)
				(type default)
			)
			(layer "F.Fab")
		)
		(fp_line
			(start -0.67945 0.3048)
			(end -0.67945 -0.305054)
			(stroke
				(width 0.1)
				(type default)
			)
			(layer "F.Fab")
		)
		(fp_line
			(start -0.67945 -0.305054)
			(end -0.12065 -0.305054)
			(stroke
				(width 0.1)
				(type default)
			)
			(layer "F.Fab")
		)
		(pad "1" smd circle
			(at -0.40005 0 180)
			(size 0 0)
			(layers "F.Cu" "F.Mask" "F.Paste")
			(net "GND")
		)
		(pad "2" smd circle
			(at 0.40005 0 180)
			(size 0 0)
			(layers "F.Cu" "F.Mask" "F.Paste")
			(net "SSD8_PWRDIS_R")
		)
	)
	(footprint ""
		(layer "F.Cu")
		(at 384.51282 -343.952322 90)
		(property "Reference" "C773"
			(at 0 0 90)
			(layer "F.SilkS")
			(hide yes)
			(effects
				(font
					(size 1.27 1.27)
				)
			)
		)
		(property "Value" ""
			(at 0 0 90)
			(layer "F.Fab")
			(effects
				(font
					(size 1.27 1.27)
				)
			)
		)
		(duplicate_pad_numbers_are_jumpers no)
		(fp_line
			(start 0.299974 -0.150114)
			(end 0.299974 0.150114)
			(stroke
				(width 0.1)
				(type default)
			)
			(layer "F.Fab")
		)
		(fp_line
			(start -0.299974 -0.150114)
			(end 0.299974 -0.150114)
			(stroke
				(width 0.1)
				(type default)
			)
			(layer "F.Fab")
		)
		(fp_line
			(start 0.299974 0.150114)
			(end -0.299974 0.150114)
			(stroke
				(width 0.1)
				(type default)
			)
			(layer "F.Fab")
		)
		(fp_line
			(start -0.299974 0.150114)
			(end -0.299974 -0.150114)
			(stroke
				(width 0.1)
				(type default)
			)
			(layer "F.Fab")
		)
		(pad "1" smd rect
			(at -0.2667 0 90)
			(size 0.3048 0.381)
			(layers "F.Cu" "F.Mask" "F.Paste")
			(net "P5E_PEX3_STN6_TX_DN<106>")
		)
		(pad "2" smd rect
			(at 0.2667 0 90)
			(size 0.3048 0.381)
			(layers "F.Cu" "F.Mask" "F.Paste")
			(net "P5E_PEX3_STN6_TX_C_DN<106>")
		)
	)
	(footprint ""
		(layer "F.Cu")
		(at 338.074 -159.766 180)
		(property "Reference" "R4812"
			(at 0 0 180)
			(layer "F.SilkS")
			(hide yes)
			(effects
				(font
					(size 1.27 1.27)
				)
			)
		)
		(property "Value" ""
			(at 0 0 180)
			(layer "F.Fab")
			(effects
				(font
					(size 1.27 1.27)
				)
			)
		)
		(duplicate_pad_numbers_are_jumpers no)
		(fp_line
			(start 0.7874 0.4064)
			(end -0.7874 0.4064)
			(stroke
				(width 0.1524)
				(type default)
			)
			(layer "F.SilkS")
		)
		(fp_line
			(start 0.7874 -0.4064)
			(end 0.7874 0.4064)
			(stroke
				(width 0.1524)
				(type default)
			)
			(layer "F.SilkS")
		)
		(fp_line
			(start -0.7874 0.4064)
			(end -0.7874 -0.4064)
			(stroke
				(width 0.1524)
				(type default)
			)
			(layer "F.SilkS")
		)
		(fp_line
			(start -0.7874 -0.4064)
			(end 0.7874 -0.4064)
			(stroke
				(width 0.1524)
				(type default)
			)
			(layer "F.SilkS")
		)
		(fp_line
			(start 0.67945 0.3048)
			(end 0.120396 0.3048)
			(stroke
				(width 0.1)
				(type default)
			)
			(layer "F.Fab")
		)
		(fp_line
			(start 0.67945 -0.3048)
			(end 0.67945 0.3048)
			(stroke
				(width 0.1)
				(type default)
			)
			(layer "F.Fab")
		)
		(fp_line
			(start 0.12065 -0.2794)
			(end 0.12065 -0.3048)
			(stroke
				(width 0.1)
				(type default)
			)
			(layer "F.Fab")
		)
		(fp_line
			(start 0.12065 -0.3048)
			(end 0.67945 -0.3048)
			(stroke
				(width 0.1)
				(type default)
			)
			(layer "F.Fab")
		)
		(fp_line
			(start 0.120396 0.3048)
			(end 0.120396 0.2794)
			(stroke
				(width 0.1)
				(type default)
			)
			(layer "F.Fab")
		)
		(fp_line
			(start 0.120396 0.2794)
			(end -0.12065 0.2794)
			(stroke
				(width 0.1)
				(type default)
			)
			(layer "F.Fab")
		)
		(fp_line
			(start -0.12065 0.3048)
			(end -0.67945 0.3048)
			(stroke
				(width 0.1)
				(type default)
			)
			(layer "F.Fab")
		)
		(fp_line
			(start -0.12065 0.2794)
			(end -0.12065 0.3048)
			(stroke
				(width 0.1)
				(type default)
			)
			(layer "F.Fab")
		)
		(fp_line
			(start -0.12065 -0.2794)
			(end 0.12065 -0.2794)
			(stroke
				(width 0.1)
				(type default)
			)
			(layer "F.Fab")
		)
		(fp_line
			(start -0.12065 -0.305054)
			(end -0.12065 -0.2794)
			(stroke
				(width 0.1)
				(type default)
			)
			(layer "F.Fab")
		)
		(fp_line
			(start -0.67945 0.3048)
			(end -0.67945 -0.305054)
			(stroke
				(width 0.1)
				(type default)
			)
			(layer "F.Fab")
		)
		(fp_line
			(start -0.67945 -0.305054)
			(end -0.12065 -0.305054)
			(stroke
				(width 0.1)
				(type default)
			)
			(layer "F.Fab")
		)
		(pad "1" smd circle
			(at -0.40005 0 180)
			(size 0 0)
			(layers "F.Cu" "F.Mask" "F.Paste")
			(net "PRSNT_SSD12_FPGA_PCA9555_N")
		)
		(pad "2" smd circle
			(at 0.40005 0 180)
			(size 0 0)
			(layers "F.Cu" "F.Mask" "F.Paste")
			(net "PRSNT_SSD12_FPGA_R_N")
		)
	)
	(footprint ""
		(layer "F.Cu")
		(at 240.300256 -224.319084)
		(property "Reference" "R4526"
			(at 0 0 0)
			(layer "F.SilkS")
			(hide yes)
			(effects
				(font
					(size 1.27 1.27)
				)
			)
		)
		(property "Value" ""
			(at 0 0 0)
			(layer "F.Fab")
			(effects
				(font
					(size 1.27 1.27)
				)
			)
		)
		(duplicate_pad_numbers_are_jumpers no)
		(fp_line
			(start -0.7874 -0.4064)
			(end 0.7874 -0.4064)
			(stroke
				(width 0.1524)
				(type default)
			)
			(layer "F.SilkS")
		)
		(fp_line
			(start -0.7874 0.4064)
			(end -0.7874 -0.4064)
			(stroke
				(width 0.1524)
				(type default)
			)
			(layer "F.SilkS")
		)
		(fp_line
			(start 0.7874 -0.4064)
			(end 0.7874 0.4064)
			(stroke
				(width 0.1524)
				(type default)
			)
			(layer "F.SilkS")
		)
		(fp_line
			(start 0.7874 0.4064)
			(end -0.7874 0.4064)
			(stroke
				(width 0.1524)
				(type default)
			)
			(layer "F.SilkS")
		)
		(fp_line
			(start -0.67945 -0.305054)
			(end -0.12065 -0.305054)
			(stroke
				(width 0.1)
				(type default)
			)
			(layer "F.Fab")
		)
		(fp_line
			(start -0.67945 0.3048)
			(end -0.67945 -0.305054)
			(stroke
				(width 0.1)
				(type default)
			)
			(layer "F.Fab")
		)
		(fp_line
			(start -0.12065 -0.305054)
			(end -0.12065 -0.2794)
			(stroke
				(width 0.1)
				(type default)
			)
			(layer "F.Fab")
		)
		(fp_line
			(start -0.12065 -0.2794)
			(end 0.12065 -0.2794)
			(stroke
				(width 0.1)
				(type default)
			)
			(layer "F.Fab")
		)
		(fp_line
			(start -0.12065 0.2794)
			(end -0.12065 0.3048)
			(stroke
				(width 0.1)
				(type default)
			)
			(layer "F.Fab")
		)
		(fp_line
			(start -0.12065 0.3048)
			(end -0.67945 0.3048)
			(stroke
				(width 0.1)
				(type default)
			)
			(layer "F.Fab")
		)
		(fp_line
			(start 0.120396 0.2794)
			(end -0.12065 0.2794)
			(stroke
				(width 0.1)
				(type default)
			)
			(layer "F.Fab")
		)
		(fp_line
			(start 0.120396 0.3048)
			(end 0.120396 0.2794)
			(stroke
				(width 0.1)
				(type default)
			)
			(layer "F.Fab")
		)
		(fp_line
			(start 0.12065 -0.3048)
			(end 0.67945 -0.3048)
			(stroke
				(width 0.1)
				(type default)
			)
			(layer "F.Fab")
		)
		(fp_line
			(start 0.12065 -0.2794)
			(end 0.12065 -0.3048)
			(stroke
				(width 0.1)
				(type default)
			)
			(layer "F.Fab")
		)
		(fp_line
			(start 0.67945 -0.3048)
			(end 0.67945 0.3048)
			(stroke
				(width 0.1)
				(type default)
			)
			(layer "F.Fab")
		)
		(fp_line
			(start 0.67945 0.3048)
			(end 0.120396 0.3048)
			(stroke
				(width 0.1)
				(type default)
			)
			(layer "F.Fab")
		)
		(pad "1" smd circle
			(at -0.40005 0)
			(size 0 0)
			(layers "F.Cu" "F.Mask" "F.Paste")
			(net "SSD12_PWRDIS_BIC")
		)
		(pad "2" smd circle
			(at 0.40005 0)
			(size 0 0)
			(layers "F.Cu" "F.Mask" "F.Paste")
			(net "SSD12_PWRDIS_BIC_R")
		)
	)
	(footprint ""
		(layer "F.Cu")
		(at 144.526762 -189.758066 180)
		(property "Reference" "C4449"
			(at 0 0 180)
			(layer "F.SilkS")
			(hide yes)
			(effects
				(font
					(size 1.27 1.27)
				)
			)
		)
		(property "Value" ""
			(at 0 0 180)
			(layer "F.Fab")
			(effects
				(font
					(size 1.27 1.27)
				)
			)
		)
		(duplicate_pad_numbers_are_jumpers no)
		(fp_line
			(start 0.7874 0.4064)
			(end -0.7874 0.4064)
			(stroke
				(width 0.1524)
				(type default)
			)
			(layer "F.SilkS")
		)
		(fp_line
			(start 0.7874 -0.4064)
			(end 0.7874 0.4064)
			(stroke
				(width 0.1524)
				(type default)
			)
			(layer "F.SilkS")
		)
		(fp_line
			(start -0.7874 0.4064)
			(end -0.7874 -0.4064)
			(stroke
				(width 0.1524)
				(type default)
			)
			(layer "F.SilkS")
		)
		(fp_line
			(start -0.7874 -0.4064)
			(end 0.7874 -0.4064)
			(stroke
				(width 0.1524)
				(type default)
			)
			(layer "F.SilkS")
		)
		(fp_line
			(start 0.67945 0.3048)
			(end 0.120396 0.3048)
			(stroke
				(width 0.1)
				(type default)
			)
			(layer "F.Fab")
		)
		(fp_line
			(start 0.67945 -0.3048)
			(end 0.67945 0.3048)
			(stroke
				(width 0.1)
				(type default)
			)
			(layer "F.Fab")
		)
		(fp_line
			(start 0.12065 -0.2794)
			(end 0.12065 -0.3048)
			(stroke
				(width 0.1)
				(type default)
			)
			(layer "F.Fab")
		)
		(fp_line
			(start 0.12065 -0.3048)
			(end 0.67945 -0.3048)
			(stroke
				(width 0.1)
				(type default)
			)
			(layer "F.Fab")
		)
		(fp_line
			(start 0.120396 0.3048)
			(end 0.120396 0.2794)
			(stroke
				(width 0.1)
				(type default)
			)
			(layer "F.Fab")
		)
		(fp_line
			(start 0.120396 0.2794)
			(end -0.12065 0.2794)
			(stroke
				(width 0.1)
				(type default)
			)
			(layer "F.Fab")
		)
		(fp_line
			(start -0.12065 0.3048)
			(end -0.67945 0.3048)
			(stroke
				(width 0.1)
				(type default)
			)
			(layer "F.Fab")
		)
		(fp_line
			(start -0.12065 0.2794)
			(end -0.12065 0.3048)
			(stroke
				(width 0.1)
				(type default)
			)
			(layer "F.Fab")
		)
		(fp_line
			(start -0.12065 -0.2794)
			(end 0.12065 -0.2794)
			(stroke
				(width 0.1)
				(type default)
			)
			(layer "F.Fab")
		)
		(fp_line
			(start -0.12065 -0.305054)
			(end -0.12065 -0.2794)
			(stroke
				(width 0.1)
				(type default)
			)
			(layer "F.Fab")
		)
		(fp_line
			(start -0.67945 0.3048)
			(end -0.67945 -0.305054)
			(stroke
				(width 0.1)
				(type default)
			)
			(layer "F.Fab")
		)
		(fp_line
			(start -0.67945 -0.305054)
			(end -0.12065 -0.305054)
			(stroke
				(width 0.1)
				(type default)
			)
			(layer "F.Fab")
		)
		(pad "1" smd circle
			(at -0.40005 0 180)
			(size 0 0)
			(layers "F.Cu" "F.Mask" "F.Paste")
			(net "GND")
		)
		(pad "2" smd circle
			(at 0.40005 0 180)
			(size 0 0)
			(layers "F.Cu" "F.Mask" "F.Paste")
			(net "P3V3_AUX")
		)
	)
	(footprint ""
		(layer "F.Cu")
		(at 215.81872 -175.415956 90)
		(property "Reference" "R5913"
			(at 0 0 90)
			(layer "F.SilkS")
			(hide yes)
			(effects
				(font
					(size 1.27 1.27)
				)
			)
		)
		(property "Value" ""
			(at 0 0 90)
			(layer "F.Fab")
			(effects
				(font
					(size 1.27 1.27)
				)
			)
		)
		(duplicate_pad_numbers_are_jumpers no)
		(fp_line
			(start 0.7874 -0.4064)
			(end 0.7874 0.4064)
			(stroke
				(width 0.1524)
				(type default)
			)
			(layer "F.SilkS")
		)
		(fp_line
			(start -0.7874 -0.4064)
			(end 0.7874 -0.4064)
			(stroke
				(width 0.1524)
				(type default)
			)
			(layer "F.SilkS")
		)
		(fp_line
			(start 0.7874 0.4064)
			(end -0.7874 0.4064)
			(stroke
				(width 0.1524)
				(type default)
			)
			(layer "F.SilkS")
		)
		(fp_line
			(start -0.7874 0.4064)
			(end -0.7874 -0.4064)
			(stroke
				(width 0.1524)
				(type default)
			)
			(layer "F.SilkS")
		)
		(fp_line
			(start -0.12065 -0.305054)
			(end -0.12065 -0.2794)
			(stroke
				(width 0.1)
				(type default)
			)
			(layer "F.Fab")
		)
		(fp_line
			(start -0.67945 -0.305054)
			(end -0.12065 -0.305054)
			(stroke
				(width 0.1)
				(type default)
			)
			(layer "F.Fab")
		)
		(fp_line
			(start 0.67945 -0.3048)
			(end 0.67945 0.3048)
			(stroke
				(width 0.1)
				(type default)
			)
			(layer "F.Fab")
		)
		(fp_line
			(start 0.12065 -0.3048)
			(end 0.67945 -0.3048)
			(stroke
				(width 0.1)
				(type default)
			)
			(layer "F.Fab")
		)
		(fp_line
			(start 0.12065 -0.2794)
			(end 0.12065 -0.3048)
			(stroke
				(width 0.1)
				(type default)
			)
			(layer "F.Fab")
		)
		(fp_line
			(start -0.12065 -0.2794)
			(end 0.12065 -0.2794)
			(stroke
				(width 0.1)
				(type default)
			)
			(layer "F.Fab")
		)
		(fp_line
			(start 0.120396 0.2794)
			(end -0.12065 0.2794)
			(stroke
				(width 0.1)
				(type default)
			)
			(layer "F.Fab")
		)
		(fp_line
			(start -0.12065 0.2794)
			(end -0.12065 0.3048)
			(stroke
				(width 0.1)
				(type default)
			)
			(layer "F.Fab")
		)
		(fp_line
			(start 0.67945 0.3048)
			(end 0.120396 0.3048)
			(stroke
				(width 0.1)
				(type default)
			)
			(layer "F.Fab")
		)
		(fp_line
			(start 0.120396 0.3048)
			(end 0.120396 0.2794)
			(stroke
				(width 0.1)
				(type default)
			)
			(layer "F.Fab")
		)
		(fp_line
			(start -0.12065 0.3048)
			(end -0.67945 0.3048)
			(stroke
				(width 0.1)
				(type default)
			)
			(layer "F.Fab")
		)
		(fp_line
			(start -0.67945 0.3048)
			(end -0.67945 -0.305054)
			(stroke
				(width 0.1)
				(type default)
			)
			(layer "F.Fab")
		)
		(pad "1" smd circle
			(at -0.40005 0 90)
			(size 0 0)
			(layers "F.Cu" "F.Mask" "F.Paste")
			(net "RST_BIC_SELF_HW_RST_R_N")
		)
		(pad "2" smd circle
			(at 0.40005 0 90)
			(size 0 0)
			(layers "F.Cu" "F.Mask" "F.Paste")
			(net "P3V3_AUX")
		)
	)
	(footprint ""
		(layer "F.Cu")
		(at 225.446844 -37.47516)
		(property "Reference" "R6086"
			(at 0 0 0)
			(layer "F.SilkS")
			(hide yes)
			(effects
				(font
					(size 1.27 1.27)
				)
			)
		)
		(property "Value" ""
			(at 0 0 0)
			(layer "F.Fab")
			(effects
				(font
					(size 1.27 1.27)
				)
			)
		)
		(duplicate_pad_numbers_are_jumpers no)
		(fp_line
			(start -0.7874 -0.4064)
			(end 0.7874 -0.4064)
			(stroke
				(width 0.1524)
				(type default)
			)
			(layer "F.SilkS")
		)
		(fp_line
			(start -0.7874 0.4064)
			(end -0.7874 -0.4064)
			(stroke
				(width 0.1524)
				(type default)
			)
			(layer "F.SilkS")
		)
		(fp_line
			(start 0.7874 -0.4064)
			(end 0.7874 0.4064)
			(stroke
				(width 0.1524)
				(type default)
			)
			(layer "F.SilkS")
		)
		(fp_line
			(start 0.7874 0.4064)
			(end -0.7874 0.4064)
			(stroke
				(width 0.1524)
				(type default)
			)
			(layer "F.SilkS")
		)
		(fp_line
			(start -0.67945 -0.305054)
			(end -0.12065 -0.305054)
			(stroke
				(width 0.1)
				(type default)
			)
			(layer "F.Fab")
		)
		(fp_line
			(start -0.67945 0.3048)
			(end -0.67945 -0.305054)
			(stroke
				(width 0.1)
				(type default)
			)
			(layer "F.Fab")
		)
		(fp_line
			(start -0.12065 -0.305054)
			(end -0.12065 -0.2794)
			(stroke
				(width 0.1)
				(type default)
			)
			(layer "F.Fab")
		)
		(fp_line
			(start -0.12065 -0.2794)
			(end 0.12065 -0.2794)
			(stroke
				(width 0.1)
				(type default)
			)
			(layer "F.Fab")
		)
		(fp_line
			(start -0.12065 0.2794)
			(end -0.12065 0.3048)
			(stroke
				(width 0.1)
				(type default)
			)
			(layer "F.Fab")
		)
		(fp_line
			(start -0.12065 0.3048)
			(end -0.67945 0.3048)
			(stroke
				(width 0.1)
				(type default)
			)
			(layer "F.Fab")
		)
		(fp_line
			(start 0.120396 0.2794)
			(end -0.12065 0.2794)
			(stroke
				(width 0.1)
				(type default)
			)
			(layer "F.Fab")
		)
		(fp_line
			(start 0.120396 0.3048)
			(end 0.120396 0.2794)
			(stroke
				(width 0.1)
				(type default)
			)
			(layer "F.Fab")
		)
		(fp_line
			(start 0.12065 -0.3048)
			(end 0.67945 -0.3048)
			(stroke
				(width 0.1)
				(type default)
			)
			(layer "F.Fab")
		)
		(fp_line
			(start 0.12065 -0.2794)
			(end 0.12065 -0.3048)
			(stroke
				(width 0.1)
				(type default)
			)
			(layer "F.Fab")
		)
		(fp_line
			(start 0.67945 -0.3048)
			(end 0.67945 0.3048)
			(stroke
				(width 0.1)
				(type default)
			)
			(layer "F.Fab")
		)
		(fp_line
			(start 0.67945 0.3048)
			(end 0.120396 0.3048)
			(stroke
				(width 0.1)
				(type default)
			)
			(layer "F.Fab")
		)
		(pad "1" smd circle
			(at -0.40005 0)
			(size 0 0)
			(layers "F.Cu" "F.Mask" "F.Paste")
			(net "P3V3_SSD8")
		)
		(pad "2" smd circle
			(at 0.40005 0)
			(size 0 0)
			(layers "F.Cu" "F.Mask" "F.Paste")
			(net "P3V3_SSD8_PG_G1")
		)
	)
	(footprint ""
		(layer "F.Cu")
		(at 380.711456 -290.044632 -90)
		(property "Reference" "R4592"
			(at 0 0 270)
			(layer "F.SilkS")
			(hide yes)
			(effects
				(font
					(size 1.27 1.27)
				)
			)
		)
		(property "Value" ""
			(at 0 0 270)
			(layer "F.Fab")
			(effects
				(font
					(size 1.27 1.27)
				)
			)
		)
		(duplicate_pad_numbers_are_jumpers no)
		(fp_line
			(start -0.7874 0.4064)
			(end -0.7874 -0.4064)
			(stroke
				(width 0.1524)
				(type default)
			)
			(layer "F.SilkS")
		)
		(fp_line
			(start 0.7874 0.4064)
			(end -0.7874 0.4064)
			(stroke
				(width 0.1524)
				(type default)
			)
			(layer "F.SilkS")
		)
		(fp_line
			(start -0.7874 -0.4064)
			(end 0.7874 -0.4064)
			(stroke
				(width 0.1524)
				(type default)
			)
			(layer "F.SilkS")
		)
		(fp_line
			(start 0.7874 -0.4064)
			(end 0.7874 0.4064)
			(stroke
				(width 0.1524)
				(type default)
			)
			(layer "F.SilkS")
		)
		(fp_line
			(start -0.67945 0.3048)
			(end -0.67945 -0.305054)
			(stroke
				(width 0.1)
				(type default)
			)
			(layer "F.Fab")
		)
		(fp_line
			(start -0.12065 0.3048)
			(end -0.67945 0.3048)
			(stroke
				(width 0.1)
				(type default)
			)
			(layer "F.Fab")
		)
		(fp_line
			(start 0.120396 0.3048)
			(end 0.120396 0.2794)
			(stroke
				(width 0.1)
				(type default)
			)
			(layer "F.Fab")
		)
		(fp_line
			(start 0.67945 0.3048)
			(end 0.120396 0.3048)
			(stroke
				(width 0.1)
				(type default)
			)
			(layer "F.Fab")
		)
		(fp_line
			(start -0.12065 0.2794)
			(end -0.12065 0.3048)
			(stroke
				(width 0.1)
				(type default)
			)
			(layer "F.Fab")
		)
		(fp_line
			(start 0.120396 0.2794)
			(end -0.12065 0.2794)
			(stroke
				(width 0.1)
				(type default)
			)
			(layer "F.Fab")
		)
		(fp_line
			(start -0.12065 -0.2794)
			(end 0.12065 -0.2794)
			(stroke
				(width 0.1)
				(type default)
			)
			(layer "F.Fab")
		)
		(fp_line
			(start 0.12065 -0.2794)
			(end 0.12065 -0.3048)
			(stroke
				(width 0.1)
				(type default)
			)
			(layer "F.Fab")
		)
		(fp_line
			(start 0.12065 -0.3048)
			(end 0.67945 -0.3048)
			(stroke
				(width 0.1)
				(type default)
			)
			(layer "F.Fab")
		)
		(fp_line
			(start 0.67945 -0.3048)
			(end 0.67945 0.3048)
			(stroke
				(width 0.1)
				(type default)
			)
			(layer "F.Fab")
		)
		(fp_line
			(start -0.67945 -0.305054)
			(end -0.12065 -0.305054)
			(stroke
				(width 0.1)
				(type default)
			)
			(layer "F.Fab")
		)
		(fp_line
			(start -0.12065 -0.305054)
			(end -0.12065 -0.2794)
			(stroke
				(width 0.1)
				(type default)
			)
			(layer "F.Fab")
		)
		(pad "1" smd circle
			(at -0.40005 0 270)
			(size 0 0)
			(layers "F.Cu" "F.Mask" "F.Paste")
			(net "PCEPLL4_VDDA18_PEX3")
		)
		(pad "2" smd circle
			(at 0.40005 0 270)
			(size 0 0)
			(layers "F.Cu" "F.Mask" "F.Paste")
			(net "PCEPLL4_VDDA18_PEX3_R")
		)
	)
	(footprint ""
		(layer "F.Cu")
		(at 181.55285 -176.966372 180)
		(property "Reference" "C4450"
			(at 0 0 180)
			(layer "F.SilkS")
			(hide yes)
			(effects
				(font
					(size 1.27 1.27)
				)
			)
		)
		(property "Value" ""
			(at 0 0 180)
			(layer "F.Fab")
			(effects
				(font
					(size 1.27 1.27)
				)
			)
		)
		(duplicate_pad_numbers_are_jumpers no)
		(fp_line
			(start 0.7874 0.4064)
			(end -0.7874 0.4064)
			(stroke
				(width 0.1524)
				(type default)
			)
			(layer "F.SilkS")
		)
		(fp_line
			(start 0.7874 -0.4064)
			(end 0.7874 0.4064)
			(stroke
				(width 0.1524)
				(type default)
			)
			(layer "F.SilkS")
		)
		(fp_line
			(start -0.7874 0.4064)
			(end -0.7874 -0.4064)
			(stroke
				(width 0.1524)
				(type default)
			)
			(layer "F.SilkS")
		)
		(fp_line
			(start -0.7874 -0.4064)
			(end 0.7874 -0.4064)
			(stroke
				(width 0.1524)
				(type default)
			)
			(layer "F.SilkS")
		)
		(fp_line
			(start 0.67945 0.3048)
			(end 0.120396 0.3048)
			(stroke
				(width 0.1)
				(type default)
			)
			(layer "F.Fab")
		)
		(fp_line
			(start 0.67945 -0.3048)
			(end 0.67945 0.3048)
			(stroke
				(width 0.1)
				(type default)
			)
			(layer "F.Fab")
		)
		(fp_line
			(start 0.12065 -0.2794)
			(end 0.12065 -0.3048)
			(stroke
				(width 0.1)
				(type default)
			)
			(layer "F.Fab")
		)
		(fp_line
			(start 0.12065 -0.3048)
			(end 0.67945 -0.3048)
			(stroke
				(width 0.1)
				(type default)
			)
			(layer "F.Fab")
		)
		(fp_line
			(start 0.120396 0.3048)
			(end 0.120396 0.2794)
			(stroke
				(width 0.1)
				(type default)
			)
			(layer "F.Fab")
		)
		(fp_line
			(start 0.120396 0.2794)
			(end -0.12065 0.2794)
			(stroke
				(width 0.1)
				(type default)
			)
			(layer "F.Fab")
		)
		(fp_line
			(start -0.12065 0.3048)
			(end -0.67945 0.3048)
			(stroke
				(width 0.1)
				(type default)
			)
			(layer "F.Fab")
		)
		(fp_line
			(start -0.12065 0.2794)
			(end -0.12065 0.3048)
			(stroke
				(width 0.1)
				(type default)
			)
			(layer "F.Fab")
		)
		(fp_line
			(start -0.12065 -0.2794)
			(end 0.12065 -0.2794)
			(stroke
				(width 0.1)
				(type default)
			)
			(layer "F.Fab")
		)
		(fp_line
			(start -0.12065 -0.305054)
			(end -0.12065 -0.2794)
			(stroke
				(width 0.1)
				(type default)
			)
			(layer "F.Fab")
		)
		(fp_line
			(start -0.67945 0.3048)
			(end -0.67945 -0.305054)
			(stroke
				(width 0.1)
				(type default)
			)
			(layer "F.Fab")
		)
		(fp_line
			(start -0.67945 -0.305054)
			(end -0.12065 -0.305054)
			(stroke
				(width 0.1)
				(type default)
			)
			(layer "F.Fab")
		)
		(pad "1" smd circle
			(at -0.40005 0 180)
			(size 0 0)
			(layers "F.Cu" "F.Mask" "F.Paste")
			(net "GND")
		)
		(pad "2" smd circle
			(at 0.40005 0 180)
			(size 0 0)
			(layers "F.Cu" "F.Mask" "F.Paste")
			(net "P3V3_AUX")
		)
	)
	(footprint ""
		(layer "F.Cu")
		(at 215.389968 -72.766682 90)
		(property "Reference" "PR7072"
			(at 0 0 90)
			(layer "F.SilkS")
			(hide yes)
			(effects
				(font
					(size 1.27 1.27)
				)
			)
		)
		(property "Value" ""
			(at 0 0 90)
			(layer "F.Fab")
			(effects
				(font
					(size 1.27 1.27)
				)
			)
		)
		(duplicate_pad_numbers_are_jumpers no)
		(fp_line
			(start 0.7874 -0.4064)
			(end 0.7874 0.4064)
			(stroke
				(width 0.1524)
				(type default)
			)
			(layer "F.SilkS")
		)
		(fp_line
			(start -0.7874 -0.4064)
			(end 0.7874 -0.4064)
			(stroke
				(width 0.1524)
				(type default)
			)
			(layer "F.SilkS")
		)
		(fp_line
			(start 0.7874 0.4064)
			(end -0.7874 0.4064)
			(stroke
				(width 0.1524)
				(type default)
			)
			(layer "F.SilkS")
		)
		(fp_line
			(start -0.7874 0.4064)
			(end -0.7874 -0.4064)
			(stroke
				(width 0.1524)
				(type default)
			)
			(layer "F.SilkS")
		)
		(fp_line
			(start -0.12065 -0.305054)
			(end -0.12065 -0.2794)
			(stroke
				(width 0.1)
				(type default)
			)
			(layer "F.Fab")
		)
		(fp_line
			(start -0.67945 -0.305054)
			(end -0.12065 -0.305054)
			(stroke
				(width 0.1)
				(type default)
			)
			(layer "F.Fab")
		)
		(fp_line
			(start 0.67945 -0.3048)
			(end 0.67945 0.3048)
			(stroke
				(width 0.1)
				(type default)
			)
			(layer "F.Fab")
		)
		(fp_line
			(start 0.12065 -0.3048)
			(end 0.67945 -0.3048)
			(stroke
				(width 0.1)
				(type default)
			)
			(layer "F.Fab")
		)
		(fp_line
			(start 0.12065 -0.2794)
			(end 0.12065 -0.3048)
			(stroke
				(width 0.1)
				(type default)
			)
			(layer "F.Fab")
		)
		(fp_line
			(start -0.12065 -0.2794)
			(end 0.12065 -0.2794)
			(stroke
				(width 0.1)
				(type default)
			)
			(layer "F.Fab")
		)
		(fp_line
			(start 0.120396 0.2794)
			(end -0.12065 0.2794)
			(stroke
				(width 0.1)
				(type default)
			)
			(layer "F.Fab")
		)
		(fp_line
			(start -0.12065 0.2794)
			(end -0.12065 0.3048)
			(stroke
				(width 0.1)
				(type default)
			)
			(layer "F.Fab")
		)
		(fp_line
			(start 0.67945 0.3048)
			(end 0.120396 0.3048)
			(stroke
				(width 0.1)
				(type default)
			)
			(layer "F.Fab")
		)
		(fp_line
			(start 0.120396 0.3048)
			(end 0.120396 0.2794)
			(stroke
				(width 0.1)
				(type default)
			)
			(layer "F.Fab")
		)
		(fp_line
			(start -0.12065 0.3048)
			(end -0.67945 0.3048)
			(stroke
				(width 0.1)
				(type default)
			)
			(layer "F.Fab")
		)
		(fp_line
			(start -0.67945 0.3048)
			(end -0.67945 -0.305054)
			(stroke
				(width 0.1)
				(type default)
			)
			(layer "F.Fab")
		)
		(pad "1" smd circle
			(at -0.40005 0 90)
			(size 0 0)
			(layers "F.Cu" "F.Mask" "F.Paste")
			(net "P12V_SSD7_CO_ILIMIT")
		)
		(pad "2" smd circle
			(at 0.40005 0 90)
			(size 0 0)
			(layers "F.Cu" "F.Mask" "F.Paste")
			(net "GND")
		)
	)
	(footprint ""
		(layer "F.Cu")
		(at 441.387484 -96.811592 90)
		(property "Reference" "R765"
			(at 0 0 90)
			(layer "F.SilkS")
			(hide yes)
			(effects
				(font
					(size 1.27 1.27)
				)
			)
		)
		(property "Value" ""
			(at 0 0 90)
			(layer "F.Fab")
			(effects
				(font
					(size 1.27 1.27)
				)
			)
		)
		(duplicate_pad_numbers_are_jumpers no)
		(fp_line
			(start 0.7874 -0.4064)
			(end 0.7874 0.4064)
			(stroke
				(width 0.1524)
				(type default)
			)
			(layer "F.SilkS")
		)
		(fp_line
			(start -0.7874 -0.4064)
			(end 0.7874 -0.4064)
			(stroke
				(width 0.1524)
				(type default)
			)
			(layer "F.SilkS")
		)
		(fp_line
			(start 0.7874 0.4064)
			(end -0.7874 0.4064)
			(stroke
				(width 0.1524)
				(type default)
			)
			(layer "F.SilkS")
		)
		(fp_line
			(start -0.7874 0.4064)
			(end -0.7874 -0.4064)
			(stroke
				(width 0.1524)
				(type default)
			)
			(layer "F.SilkS")
		)
		(fp_line
			(start -0.12065 -0.305054)
			(end -0.12065 -0.2794)
			(stroke
				(width 0.1)
				(type default)
			)
			(layer "F.Fab")
		)
		(fp_line
			(start -0.67945 -0.305054)
			(end -0.12065 -0.305054)
			(stroke
				(width 0.1)
				(type default)
			)
			(layer "F.Fab")
		)
		(fp_line
			(start 0.67945 -0.3048)
			(end 0.67945 0.3048)
			(stroke
				(width 0.1)
				(type default)
			)
			(layer "F.Fab")
		)
		(fp_line
			(start 0.12065 -0.3048)
			(end 0.67945 -0.3048)
			(stroke
				(width 0.1)
				(type default)
			)
			(layer "F.Fab")
		)
		(fp_line
			(start 0.12065 -0.2794)
			(end 0.12065 -0.3048)
			(stroke
				(width 0.1)
				(type default)
			)
			(layer "F.Fab")
		)
		(fp_line
			(start -0.12065 -0.2794)
			(end 0.12065 -0.2794)
			(stroke
				(width 0.1)
				(type default)
			)
			(layer "F.Fab")
		)
		(fp_line
			(start 0.120396 0.2794)
			(end -0.12065 0.2794)
			(stroke
				(width 0.1)
				(type default)
			)
			(layer "F.Fab")
		)
		(fp_line
			(start -0.12065 0.2794)
			(end -0.12065 0.3048)
			(stroke
				(width 0.1)
				(type default)
			)
			(layer "F.Fab")
		)
		(fp_line
			(start 0.67945 0.3048)
			(end 0.120396 0.3048)
			(stroke
				(width 0.1)
				(type default)
			)
			(layer "F.Fab")
		)
		(fp_line
			(start 0.120396 0.3048)
			(end 0.120396 0.2794)
			(stroke
				(width 0.1)
				(type default)
			)
			(layer "F.Fab")
		)
		(fp_line
			(start -0.12065 0.3048)
			(end -0.67945 0.3048)
			(stroke
				(width 0.1)
				(type default)
			)
			(layer "F.Fab")
		)
		(fp_line
			(start -0.67945 0.3048)
			(end -0.67945 -0.305054)
			(stroke
				(width 0.1)
				(type default)
			)
			(layer "F.Fab")
		)
		(pad "1" smd circle
			(at -0.40005 0 90)
			(size 0 0)
			(layers "F.Cu" "F.Mask" "F.Paste")
			(net "SMB_BIC_I2C6_MUX_NIC_ADC_R_SDA")
		)
		(pad "2" smd circle
			(at 0.40005 0 90)
			(size 0 0)
			(layers "F.Cu" "F.Mask" "F.Paste")
			(net "SMB_NIC7_ADC_SDA")
		)
	)
	(footprint ""
		(layer "F.Cu")
		(at 222.017336 -85.684868 180)
		(property "Reference" "R4266"
			(at 0 0 180)
			(layer "F.SilkS")
			(hide yes)
			(effects
				(font
					(size 1.27 1.27)
				)
			)
		)
		(property "Value" ""
			(at 0 0 180)
			(layer "F.Fab")
			(effects
				(font
					(size 1.27 1.27)
				)
			)
		)
		(duplicate_pad_numbers_are_jumpers no)
		(fp_line
			(start 0.7874 0.4064)
			(end -0.7874 0.4064)
			(stroke
				(width 0.1524)
				(type default)
			)
			(layer "F.SilkS")
		)
		(fp_line
			(start 0.7874 -0.4064)
			(end 0.7874 0.4064)
			(stroke
				(width 0.1524)
				(type default)
			)
			(layer "F.SilkS")
		)
		(fp_line
			(start -0.7874 0.4064)
			(end -0.7874 -0.4064)
			(stroke
				(width 0.1524)
				(type default)
			)
			(layer "F.SilkS")
		)
		(fp_line
			(start -0.7874 -0.4064)
			(end 0.7874 -0.4064)
			(stroke
				(width 0.1524)
				(type default)
			)
			(layer "F.SilkS")
		)
		(fp_line
			(start 0.67945 0.3048)
			(end 0.120396 0.3048)
			(stroke
				(width 0.1)
				(type default)
			)
			(layer "F.Fab")
		)
		(fp_line
			(start 0.67945 -0.3048)
			(end 0.67945 0.3048)
			(stroke
				(width 0.1)
				(type default)
			)
			(layer "F.Fab")
		)
		(fp_line
			(start 0.12065 -0.2794)
			(end 0.12065 -0.3048)
			(stroke
				(width 0.1)
				(type default)
			)
			(layer "F.Fab")
		)
		(fp_line
			(start 0.12065 -0.3048)
			(end 0.67945 -0.3048)
			(stroke
				(width 0.1)
				(type default)
			)
			(layer "F.Fab")
		)
		(fp_line
			(start 0.120396 0.3048)
			(end 0.120396 0.2794)
			(stroke
				(width 0.1)
				(type default)
			)
			(layer "F.Fab")
		)
		(fp_line
			(start 0.120396 0.2794)
			(end -0.12065 0.2794)
			(stroke
				(width 0.1)
				(type default)
			)
			(layer "F.Fab")
		)
		(fp_line
			(start -0.12065 0.3048)
			(end -0.67945 0.3048)
			(stroke
				(width 0.1)
				(type default)
			)
			(layer "F.Fab")
		)
		(fp_line
			(start -0.12065 0.2794)
			(end -0.12065 0.3048)
			(stroke
				(width 0.1)
				(type default)
			)
			(layer "F.Fab")
		)
		(fp_line
			(start -0.12065 -0.2794)
			(end 0.12065 -0.2794)
			(stroke
				(width 0.1)
				(type default)
			)
			(layer "F.Fab")
		)
		(fp_line
			(start -0.12065 -0.305054)
			(end -0.12065 -0.2794)
			(stroke
				(width 0.1)
				(type default)
			)
			(layer "F.Fab")
		)
		(fp_line
			(start -0.67945 0.3048)
			(end -0.67945 -0.305054)
			(stroke
				(width 0.1)
				(type default)
			)
			(layer "F.Fab")
		)
		(fp_line
			(start -0.67945 -0.305054)
			(end -0.12065 -0.305054)
			(stroke
				(width 0.1)
				(type default)
			)
			(layer "F.Fab")
		)
		(pad "1" smd circle
			(at -0.40005 0 180)
			(size 0 0)
			(layers "F.Cu" "F.Mask" "F.Paste")
			(net "SSD_LED_IOEXP_A0")
		)
		(pad "2" smd circle
			(at 0.40005 0 180)
			(size 0 0)
			(layers "F.Cu" "F.Mask" "F.Paste")
			(net "GND")
		)
	)
	(footprint ""
		(layer "F.Cu")
		(at 226.528376 -369.229386 90)
		(property "Reference" "PC13"
			(at 0 0 90)
			(layer "F.SilkS")
			(hide yes)
			(effects
				(font
					(size 1.27 1.27)
				)
			)
		)
		(property "Value" ""
			(at 0 0 90)
			(layer "F.Fab")
			(effects
				(font
					(size 1.27 1.27)
				)
			)
		)
		(duplicate_pad_numbers_are_jumpers no)
		(fp_line
			(start 0.7874 -0.4064)
			(end 0.7874 0.4064)
			(stroke
				(width 0.1524)
				(type default)
			)
			(layer "F.SilkS")
		)
		(fp_line
			(start -0.7874 -0.4064)
			(end 0.7874 -0.4064)
			(stroke
				(width 0.1524)
				(type default)
			)
			(layer "F.SilkS")
		)
		(fp_line
			(start 0.7874 0.4064)
			(end -0.7874 0.4064)
			(stroke
				(width 0.1524)
				(type default)
			)
			(layer "F.SilkS")
		)
		(fp_line
			(start -0.7874 0.4064)
			(end -0.7874 -0.4064)
			(stroke
				(width 0.1524)
				(type default)
			)
			(layer "F.SilkS")
		)
		(fp_line
			(start -0.12065 -0.305054)
			(end -0.12065 -0.2794)
			(stroke
				(width 0.1)
				(type default)
			)
			(layer "F.Fab")
		)
		(fp_line
			(start -0.67945 -0.305054)
			(end -0.12065 -0.305054)
			(stroke
				(width 0.1)
				(type default)
			)
			(layer "F.Fab")
		)
		(fp_line
			(start 0.67945 -0.3048)
			(end 0.67945 0.3048)
			(stroke
				(width 0.1)
				(type default)
			)
			(layer "F.Fab")
		)
		(fp_line
			(start 0.12065 -0.3048)
			(end 0.67945 -0.3048)
			(stroke
				(width 0.1)
				(type default)
			)
			(layer "F.Fab")
		)
		(fp_line
			(start 0.12065 -0.2794)
			(end 0.12065 -0.3048)
			(stroke
				(width 0.1)
				(type default)
			)
			(layer "F.Fab")
		)
		(fp_line
			(start -0.12065 -0.2794)
			(end 0.12065 -0.2794)
			(stroke
				(width 0.1)
				(type default)
			)
			(layer "F.Fab")
		)
		(fp_line
			(start 0.120396 0.2794)
			(end -0.12065 0.2794)
			(stroke
				(width 0.1)
				(type default)
			)
			(layer "F.Fab")
		)
		(fp_line
			(start -0.12065 0.2794)
			(end -0.12065 0.3048)
			(stroke
				(width 0.1)
				(type default)
			)
			(layer "F.Fab")
		)
		(fp_line
			(start 0.67945 0.3048)
			(end 0.120396 0.3048)
			(stroke
				(width 0.1)
				(type default)
			)
			(layer "F.Fab")
		)
		(fp_line
			(start 0.120396 0.3048)
			(end 0.120396 0.2794)
			(stroke
				(width 0.1)
				(type default)
			)
			(layer "F.Fab")
		)
		(fp_line
			(start -0.12065 0.3048)
			(end -0.67945 0.3048)
			(stroke
				(width 0.1)
				(type default)
			)
			(layer "F.Fab")
		)
		(fp_line
			(start -0.67945 0.3048)
			(end -0.67945 -0.305054)
			(stroke
				(width 0.1)
				(type default)
			)
			(layer "F.Fab")
		)
		(pad "1" smd circle
			(at -0.40005 0 90)
			(size 0 0)
			(layers "F.Cu" "F.Mask" "F.Paste")
			(net "HSC_VDD_2")
		)
		(pad "2" smd circle
			(at 0.40005 0 90)
			(size 0 0)
			(layers "F.Cu" "F.Mask" "F.Paste")
			(net "AGND_HSC")
		)
	)
	(footprint ""
		(layer "F.Cu")
		(at 352.232214 -143.51)
		(property "Reference" "R4840"
			(at 0 0 0)
			(layer "F.SilkS")
			(hide yes)
			(effects
				(font
					(size 1.27 1.27)
				)
			)
		)
		(property "Value" ""
			(at 0 0 0)
			(layer "F.Fab")
			(effects
				(font
					(size 1.27 1.27)
				)
			)
		)
		(duplicate_pad_numbers_are_jumpers no)
		(fp_line
			(start -0.7874 -0.4064)
			(end 0.7874 -0.4064)
			(stroke
				(width 0.1524)
				(type default)
			)
			(layer "F.SilkS")
		)
		(fp_line
			(start -0.7874 0.4064)
			(end -0.7874 -0.4064)
			(stroke
				(width 0.1524)
				(type default)
			)
			(layer "F.SilkS")
		)
		(fp_line
			(start 0.7874 -0.4064)
			(end 0.7874 0.4064)
			(stroke
				(width 0.1524)
				(type default)
			)
			(layer "F.SilkS")
		)
		(fp_line
			(start 0.7874 0.4064)
			(end -0.7874 0.4064)
			(stroke
				(width 0.1524)
				(type default)
			)
			(layer "F.SilkS")
		)
		(fp_line
			(start -0.67945 -0.305054)
			(end -0.12065 -0.305054)
			(stroke
				(width 0.1)
				(type default)
			)
			(layer "F.Fab")
		)
		(fp_line
			(start -0.67945 0.3048)
			(end -0.67945 -0.305054)
			(stroke
				(width 0.1)
				(type default)
			)
			(layer "F.Fab")
		)
		(fp_line
			(start -0.12065 -0.305054)
			(end -0.12065 -0.2794)
			(stroke
				(width 0.1)
				(type default)
			)
			(layer "F.Fab")
		)
		(fp_line
			(start -0.12065 -0.2794)
			(end 0.12065 -0.2794)
			(stroke
				(width 0.1)
				(type default)
			)
			(layer "F.Fab")
		)
		(fp_line
			(start -0.12065 0.2794)
			(end -0.12065 0.3048)
			(stroke
				(width 0.1)
				(type default)
			)
			(layer "F.Fab")
		)
		(fp_line
			(start -0.12065 0.3048)
			(end -0.67945 0.3048)
			(stroke
				(width 0.1)
				(type default)
			)
			(layer "F.Fab")
		)
		(fp_line
			(start 0.120396 0.2794)
			(end -0.12065 0.2794)
			(stroke
				(width 0.1)
				(type default)
			)
			(layer "F.Fab")
		)
		(fp_line
			(start 0.120396 0.3048)
			(end 0.120396 0.2794)
			(stroke
				(width 0.1)
				(type default)
			)
			(layer "F.Fab")
		)
		(fp_line
			(start 0.12065 -0.3048)
			(end 0.67945 -0.3048)
			(stroke
				(width 0.1)
				(type default)
			)
			(layer "F.Fab")
		)
		(fp_line
			(start 0.12065 -0.2794)
			(end 0.12065 -0.3048)
			(stroke
				(width 0.1)
				(type default)
			)
			(layer "F.Fab")
		)
		(fp_line
			(start 0.67945 -0.3048)
			(end 0.67945 0.3048)
			(stroke
				(width 0.1)
				(type default)
			)
			(layer "F.Fab")
		)
		(fp_line
			(start 0.67945 0.3048)
			(end 0.120396 0.3048)
			(stroke
				(width 0.1)
				(type default)
			)
			(layer "F.Fab")
		)
		(pad "1" smd circle
			(at -0.40005 0)
			(size 0 0)
			(layers "F.Cu" "F.Mask" "F.Paste")
			(net "NIC7_PEX_PWR_EN")
		)
		(pad "2" smd circle
			(at 0.40005 0)
			(size 0 0)
			(layers "F.Cu" "F.Mask" "F.Paste")
			(net "NIC7_PEX_PWR_EN_R")
		)
	)
	(footprint ""
		(layer "F.Cu")
		(at 321.414394 -311.227978 135)
		(property "Reference" "R1374"
			(at 0 0 135)
			(layer "F.SilkS")
			(hide yes)
			(effects
				(font
					(size 1.27 1.27)
				)
			)
		)
		(property "Value" ""
			(at 0 0 135)
			(layer "F.Fab")
			(effects
				(font
					(size 1.27 1.27)
				)
			)
		)
		(duplicate_pad_numbers_are_jumpers no)
		(fp_line
			(start 0.787389 -0.406267)
			(end 0.787389 0.406267)
			(stroke
				(width 0.1524)
				(type default)
			)
			(layer "F.SilkS")
		)
		(fp_line
			(start 0.787389 0.406267)
			(end -0.787389 0.406267)
			(stroke
				(width 0.1524)
				(type default)
			)
			(layer "F.SilkS")
		)
		(fp_line
			(start -0.787389 -0.406267)
			(end 0.787389 -0.406267)
			(stroke
				(width 0.1524)
				(type default)
			)
			(layer "F.SilkS")
		)
		(fp_line
			(start -0.787389 0.406267)
			(end -0.787389 -0.406267)
			(stroke
				(width 0.1524)
				(type default)
			)
			(layer "F.SilkS")
		)
		(fp_line
			(start 0.679446 -0.30479)
			(end 0.679446 0.30479)
			(stroke
				(width 0.1)
				(type default)
			)
			(layer "F.Fab")
		)
		(fp_line
			(start 0.120515 -0.30479)
			(end 0.679446 -0.30479)
			(stroke
				(width 0.1)
				(type default)
			)
			(layer "F.Fab")
		)
		(fp_line
			(start 0.120695 -0.279466)
			(end 0.120515 -0.30479)
			(stroke
				(width 0.1)
				(type default)
			)
			(layer "F.Fab")
		)
		(fp_line
			(start 0.679446 0.30479)
			(end 0.120515 0.30479)
			(stroke
				(width 0.1)
				(type default)
			)
			(layer "F.Fab")
		)
		(fp_line
			(start -0.120695 -0.304969)
			(end -0.120695 -0.279466)
			(stroke
				(width 0.1)
				(type default)
			)
			(layer "F.Fab")
		)
		(fp_line
			(start -0.120695 -0.279466)
			(end 0.120695 -0.279466)
			(stroke
				(width 0.1)
				(type default)
			)
			(layer "F.Fab")
		)
		(fp_line
			(start 0.120335 0.279466)
			(end -0.120695 0.279466)
			(stroke
				(width 0.1)
				(type default)
			)
			(layer "F.Fab")
		)
		(fp_line
			(start 0.120515 0.30479)
			(end 0.120335 0.279466)
			(stroke
				(width 0.1)
				(type default)
			)
			(layer "F.Fab")
		)
		(fp_line
			(start -0.679446 -0.305149)
			(end -0.120695 -0.304969)
			(stroke
				(width 0.1)
				(type default)
			)
			(layer "F.Fab")
		)
		(fp_line
			(start -0.120695 0.279466)
			(end -0.120515 0.30479)
			(stroke
				(width 0.1)
				(type default)
			)
			(layer "F.Fab")
		)
		(fp_line
			(start -0.120515 0.30479)
			(end -0.679446 0.30479)
			(stroke
				(width 0.1)
				(type default)
			)
			(layer "F.Fab")
		)
		(fp_line
			(start -0.679446 0.30479)
			(end -0.679446 -0.305149)
			(stroke
				(width 0.1)
				(type default)
			)
			(layer "F.Fab")
		)
		(pad "1" smd circle
			(at -0.40005 0 135)
			(size 0 0)
			(layers "F.Cu" "F.Mask" "F.Paste")
			(net "PEX2_SPARE0")
		)
		(pad "2" smd circle
			(at 0.40005 0 135)
			(size 0 0)
			(layers "F.Cu" "F.Mask" "F.Paste")
			(net "P1V8_PEX")
		)
	)
	(footprint ""
		(layer "F.Cu")
		(at 500.158512 -548.965882 180)
		(property "Reference" "HANDLE_1"
			(at -3.6322 -1.402334 0)
			(unlocked yes)
			(layer "B.SilkS")
			(effects
				(font
					(size 0.7874 0.5842)
					(thickness 0.1524)
				)
				(justify mirror)
			)
		)
		(property "Value" ""
			(at 0 0 180)
			(layer "F.Fab")
			(effects
				(font
					(size 1.27 1.27)
				)
			)
		)
		(duplicate_pad_numbers_are_jumpers no)
		(pad "1" thru_hole circle
			(at 0 0 180)
			(size 0.4572 0.4572)
			(drill 0.2032)
			(layers "*.Cu" "*.Mask")
			(remove_unused_layers no)
			(net "Net_9177")
			(clearance 0.127)
			(thermal_gap 0.127)
			(padstack
				(mode front_inner_back)
				(layer "Inner"
					(shape circle)
					(size 0.4572 0.4572)
					(clearance 0.127)
				)
				(layer "B.Cu"
					(shape circle)
					(size 0.508 0.508)
					(clearance 0.1016)
				)
			)
		)
	)
	(footprint ""
		(layer "F.Cu")
		(at 332.085442 -25.1587 -90)
		(property "Reference" "R5758"
			(at 0 0 270)
			(layer "F.SilkS")
			(hide yes)
			(effects
				(font
					(size 1.27 1.27)
				)
			)
		)
		(property "Value" ""
			(at 0 0 270)
			(layer "F.Fab")
			(effects
				(font
					(size 1.27 1.27)
				)
			)
		)
		(duplicate_pad_numbers_are_jumpers no)
		(fp_line
			(start -0.7874 0.4064)
			(end -0.7874 -0.4064)
			(stroke
				(width 0.1524)
				(type default)
			)
			(layer "F.SilkS")
		)
		(fp_line
			(start 0.7874 0.4064)
			(end -0.7874 0.4064)
			(stroke
				(width 0.1524)
				(type default)
			)
			(layer "F.SilkS")
		)
		(fp_line
			(start -0.7874 -0.4064)
			(end 0.7874 -0.4064)
			(stroke
				(width 0.1524)
				(type default)
			)
			(layer "F.SilkS")
		)
		(fp_line
			(start 0.7874 -0.4064)
			(end 0.7874 0.4064)
			(stroke
				(width 0.1524)
				(type default)
			)
			(layer "F.SilkS")
		)
		(fp_line
			(start -0.67945 0.3048)
			(end -0.67945 -0.305054)
			(stroke
				(width 0.1)
				(type default)
			)
			(layer "F.Fab")
		)
		(fp_line
			(start -0.12065 0.3048)
			(end -0.67945 0.3048)
			(stroke
				(width 0.1)
				(type default)
			)
			(layer "F.Fab")
		)
		(fp_line
			(start 0.120396 0.3048)
			(end 0.120396 0.2794)
			(stroke
				(width 0.1)
				(type default)
			)
			(layer "F.Fab")
		)
		(fp_line
			(start 0.67945 0.3048)
			(end 0.120396 0.3048)
			(stroke
				(width 0.1)
				(type default)
			)
			(layer "F.Fab")
		)
		(fp_line
			(start -0.12065 0.2794)
			(end -0.12065 0.3048)
			(stroke
				(width 0.1)
				(type default)
			)
			(layer "F.Fab")
		)
		(fp_line
			(start 0.120396 0.2794)
			(end -0.12065 0.2794)
			(stroke
				(width 0.1)
				(type default)
			)
			(layer "F.Fab")
		)
		(fp_line
			(start -0.12065 -0.2794)
			(end 0.12065 -0.2794)
			(stroke
				(width 0.1)
				(type default)
			)
			(layer "F.Fab")
		)
		(fp_line
			(start 0.12065 -0.2794)
			(end 0.12065 -0.3048)
			(stroke
				(width 0.1)
				(type default)
			)
			(layer "F.Fab")
		)
		(fp_line
			(start 0.12065 -0.3048)
			(end 0.67945 -0.3048)
			(stroke
				(width 0.1)
				(type default)
			)
			(layer "F.Fab")
		)
		(fp_line
			(start 0.67945 -0.3048)
			(end 0.67945 0.3048)
			(stroke
				(width 0.1)
				(type default)
			)
			(layer "F.Fab")
		)
		(fp_line
			(start -0.67945 -0.305054)
			(end -0.12065 -0.305054)
			(stroke
				(width 0.1)
				(type default)
			)
			(layer "F.Fab")
		)
		(fp_line
			(start -0.12065 -0.305054)
			(end -0.12065 -0.2794)
			(stroke
				(width 0.1)
				(type default)
			)
			(layer "F.Fab")
		)
		(pad "1" smd circle
			(at -0.40005 0 270)
			(size 0 0)
			(layers "F.Cu" "F.Mask" "F.Paste")
			(net "SSD11_LED_ISO_N")
		)
		(pad "2" smd circle
			(at 0.40005 0 270)
			(size 0 0)
			(layers "F.Cu" "F.Mask" "F.Paste")
			(net "SSD11_LED_ISO_R_N")
		)
	)
	(footprint ""
		(layer "F.Cu")
		(at 196.359272 -343.952322 90)
		(property "Reference" "C2542"
			(at 0 0 90)
			(layer "F.SilkS")
			(hide yes)
			(effects
				(font
					(size 1.27 1.27)
				)
			)
		)
		(property "Value" ""
			(at 0 0 90)
			(layer "F.Fab")
			(effects
				(font
					(size 1.27 1.27)
				)
			)
		)
		(duplicate_pad_numbers_are_jumpers no)
		(fp_line
			(start 0.299974 -0.150114)
			(end 0.299974 0.150114)
			(stroke
				(width 0.1)
				(type default)
			)
			(layer "F.Fab")
		)
		(fp_line
			(start -0.299974 -0.150114)
			(end 0.299974 -0.150114)
			(stroke
				(width 0.1)
				(type default)
			)
			(layer "F.Fab")
		)
		(fp_line
			(start 0.299974 0.150114)
			(end -0.299974 0.150114)
			(stroke
				(width 0.1)
				(type default)
			)
			(layer "F.Fab")
		)
		(fp_line
			(start -0.299974 0.150114)
			(end -0.299974 -0.150114)
			(stroke
				(width 0.1)
				(type default)
			)
			(layer "F.Fab")
		)
		(pad "1" smd rect
			(at -0.2667 0 90)
			(size 0.3048 0.381)
			(layers "F.Cu" "F.Mask" "F.Paste")
			(net "P5E_PEX1_STN4_TX_DP<64>")
		)
		(pad "2" smd rect
			(at 0.2667 0 90)
			(size 0.3048 0.381)
			(layers "F.Cu" "F.Mask" "F.Paste")
			(net "P5E_PEX1_STN4_TX_C_DP<64>")
		)
	)
	(footprint ""
		(layer "F.Cu")
		(at 377.722384 -252.356874 -90)
		(property "Reference" "R1428"
			(at 0 0 270)
			(layer "F.SilkS")
			(hide yes)
			(effects
				(font
					(size 1.27 1.27)
				)
			)
		)
		(property "Value" ""
			(at 0 0 270)
			(layer "F.Fab")
			(effects
				(font
					(size 1.27 1.27)
				)
			)
		)
		(duplicate_pad_numbers_are_jumpers no)
		(fp_line
			(start -0.7874 0.4064)
			(end -0.7874 -0.4064)
			(stroke
				(width 0.1524)
				(type default)
			)
			(layer "F.SilkS")
		)
		(fp_line
			(start 0.7874 0.4064)
			(end -0.7874 0.4064)
			(stroke
				(width 0.1524)
				(type default)
			)
			(layer "F.SilkS")
		)
		(fp_line
			(start -0.7874 -0.4064)
			(end 0.7874 -0.4064)
			(stroke
				(width 0.1524)
				(type default)
			)
			(layer "F.SilkS")
		)
		(fp_line
			(start 0.7874 -0.4064)
			(end 0.7874 0.4064)
			(stroke
				(width 0.1524)
				(type default)
			)
			(layer "F.SilkS")
		)
		(fp_line
			(start -0.67945 0.3048)
			(end -0.67945 -0.305054)
			(stroke
				(width 0.1)
				(type default)
			)
			(layer "F.Fab")
		)
		(fp_line
			(start -0.12065 0.3048)
			(end -0.67945 0.3048)
			(stroke
				(width 0.1)
				(type default)
			)
			(layer "F.Fab")
		)
		(fp_line
			(start 0.120396 0.3048)
			(end 0.120396 0.2794)
			(stroke
				(width 0.1)
				(type default)
			)
			(layer "F.Fab")
		)
		(fp_line
			(start 0.67945 0.3048)
			(end 0.120396 0.3048)
			(stroke
				(width 0.1)
				(type default)
			)
			(layer "F.Fab")
		)
		(fp_line
			(start -0.12065 0.2794)
			(end -0.12065 0.3048)
			(stroke
				(width 0.1)
				(type default)
			)
			(layer "F.Fab")
		)
		(fp_line
			(start 0.120396 0.2794)
			(end -0.12065 0.2794)
			(stroke
				(width 0.1)
				(type default)
			)
			(layer "F.Fab")
		)
		(fp_line
			(start -0.12065 -0.2794)
			(end 0.12065 -0.2794)
			(stroke
				(width 0.1)
				(type default)
			)
			(layer "F.Fab")
		)
		(fp_line
			(start 0.12065 -0.2794)
			(end 0.12065 -0.3048)
			(stroke
				(width 0.1)
				(type default)
			)
			(layer "F.Fab")
		)
		(fp_line
			(start 0.12065 -0.3048)
			(end 0.67945 -0.3048)
			(stroke
				(width 0.1)
				(type default)
			)
			(layer "F.Fab")
		)
		(fp_line
			(start 0.67945 -0.3048)
			(end 0.67945 0.3048)
			(stroke
				(width 0.1)
				(type default)
			)
			(layer "F.Fab")
		)
		(fp_line
			(start -0.67945 -0.305054)
			(end -0.12065 -0.305054)
			(stroke
				(width 0.1)
				(type default)
			)
			(layer "F.Fab")
		)
		(fp_line
			(start -0.12065 -0.305054)
			(end -0.12065 -0.2794)
			(stroke
				(width 0.1)
				(type default)
			)
			(layer "F.Fab")
		)
		(pad "1" smd circle
			(at -0.40005 0 270)
			(size 0 0)
			(layers "F.Cu" "F.Mask" "F.Paste")
			(net "GND")
		)
		(pad "2" smd circle
			(at 0.40005 0 270)
			(size 0 0)
			(layers "F.Cu" "F.Mask" "F.Paste")
			(net "PEX3_MODE_SEL3")
		)
	)
	(footprint ""
		(layer "F.Cu")
		(at 41.20134 -55.78475 -90)
		(property "Reference" "PD26"
			(at 1.83515 2.23647 90)
			(unlocked yes)
			(layer "F.SilkS")
			(effects
				(font
					(size 0.7874 0.5842)
					(thickness 0.1524)
				)
				(justify left)
			)
		)
		(property "Value" ""
			(at 0 0 270)
			(layer "F.Fab")
			(effects
				(font
					(size 1.27 1.27)
				)
			)
		)
		(duplicate_pad_numbers_are_jumpers no)
		(fp_line
			(start -3.400044 1.459992)
			(end -3.400044 -1.459992)
			(stroke
				(width 0.1524)
				(type default)
			)
			(layer "F.SilkS")
		)
		(fp_line
			(start 4.107942 1.459992)
			(end -3.400044 1.459992)
			(stroke
				(width 0.1524)
				(type default)
			)
			(layer "F.SilkS")
		)
		(fp_line
			(start -3.400044 -1.459992)
			(end 4.107942 -1.459992)
			(stroke
				(width 0.1524)
				(type default)
			)
			(layer "F.SilkS")
		)
		(fp_line
			(start 4.107942 -1.459992)
			(end 4.107942 1.459992)
			(stroke
				(width 0.1524)
				(type default)
			)
			(layer "F.SilkS")
		)
		(fp_poly
			(pts
				(xy 4.107942 -1.459992) (xy 4.107942 1.459992) (xy 3.308096 1.459992) (xy 3.308096 -1.459992)
			)
			(stroke
				(width 0)
				(type default)
			)
			(fill yes)
			(layer "F.SilkS")
		)
		(fp_line
			(start -2.29997 1.459992)
			(end -2.29997 -1.459992)
			(stroke
				(width 0.1)
				(type default)
			)
			(layer "F.Fab")
		)
		(fp_line
			(start 2.29997 1.459992)
			(end -2.29997 1.459992)
			(stroke
				(width 0.1)
				(type default)
			)
			(layer "F.Fab")
		)
		(fp_line
			(start -2.29997 -1.459992)
			(end 2.29997 -1.459992)
			(stroke
				(width 0.1)
				(type default)
			)
			(layer "F.Fab")
		)
		(fp_line
			(start 2.29997 -1.459992)
			(end 2.29997 1.459992)
			(stroke
				(width 0.1)
				(type default)
			)
			(layer "F.Fab")
		)
		(fp_text user "-"
			(at 5.4102 0.29845 90)
			(unlocked yes)
			(layer "F.SilkS")
			(effects
				(font
					(size 1.905 1.4224)
					(thickness 0.1524)
				)
				(justify left)
			)
		)
		(fp_text user "+"
			(at -4.7752 -0.12065 270)
			(unlocked yes)
			(layer "F.SilkS")
			(effects
				(font
					(size 1.905 1.4224)
					(thickness 0.1524)
				)
				(justify left)
			)
		)
		(fp_text user "-"
			(at 5.4102 0.29845 90)
			(unlocked yes)
			(layer "F.Fab")
			(effects
				(font
					(size 1.905 1.4224)
					(thickness 0.1524)
				)
				(justify left)
			)
		)
		(fp_text user "+"
			(at -4.7752 -0.12065 270)
			(unlocked yes)
			(layer "F.Fab")
			(effects
				(font
					(size 1.905 1.4224)
					(thickness 0.1524)
				)
				(justify left)
			)
		)
		(pad "A" smd rect
			(at -1.999996 0)
			(size 1.7018 2.5146)
			(layers "F.Cu" "F.Mask" "F.Paste")
			(net "GND")
		)
		(pad "C" smd rect
			(at 1.999996 0)
			(size 1.7018 2.5146)
			(layers "F.Cu" "F.Mask" "F.Paste")
			(net "P12V_SSD1_R")
		)
	)
	(footprint ""
		(layer "F.Cu")
		(at 277.717504 -395.162532 90)
		(property "Reference" "R1803"
			(at 0 0 90)
			(layer "F.SilkS")
			(hide yes)
			(effects
				(font
					(size 1.27 1.27)
				)
			)
		)
		(property "Value" ""
			(at 0 0 90)
			(layer "F.Fab")
			(effects
				(font
					(size 1.27 1.27)
				)
			)
		)
		(duplicate_pad_numbers_are_jumpers no)
		(fp_line
			(start 0.7874 -0.4064)
			(end 0.7874 0.4064)
			(stroke
				(width 0.1524)
				(type default)
			)
			(layer "F.SilkS")
		)
		(fp_line
			(start -0.7874 -0.4064)
			(end 0.7874 -0.4064)
			(stroke
				(width 0.1524)
				(type default)
			)
			(layer "F.SilkS")
		)
		(fp_line
			(start 0.7874 0.4064)
			(end -0.7874 0.4064)
			(stroke
				(width 0.1524)
				(type default)
			)
			(layer "F.SilkS")
		)
		(fp_line
			(start -0.7874 0.4064)
			(end -0.7874 -0.4064)
			(stroke
				(width 0.1524)
				(type default)
			)
			(layer "F.SilkS")
		)
		(fp_line
			(start -0.12065 -0.305054)
			(end -0.12065 -0.2794)
			(stroke
				(width 0.1)
				(type default)
			)
			(layer "F.Fab")
		)
		(fp_line
			(start -0.67945 -0.305054)
			(end -0.12065 -0.305054)
			(stroke
				(width 0.1)
				(type default)
			)
			(layer "F.Fab")
		)
		(fp_line
			(start 0.67945 -0.3048)
			(end 0.67945 0.3048)
			(stroke
				(width 0.1)
				(type default)
			)
			(layer "F.Fab")
		)
		(fp_line
			(start 0.12065 -0.3048)
			(end 0.67945 -0.3048)
			(stroke
				(width 0.1)
				(type default)
			)
			(layer "F.Fab")
		)
		(fp_line
			(start 0.12065 -0.2794)
			(end 0.12065 -0.3048)
			(stroke
				(width 0.1)
				(type default)
			)
			(layer "F.Fab")
		)
		(fp_line
			(start -0.12065 -0.2794)
			(end 0.12065 -0.2794)
			(stroke
				(width 0.1)
				(type default)
			)
			(layer "F.Fab")
		)
		(fp_line
			(start 0.120396 0.2794)
			(end -0.12065 0.2794)
			(stroke
				(width 0.1)
				(type default)
			)
			(layer "F.Fab")
		)
		(fp_line
			(start -0.12065 0.2794)
			(end -0.12065 0.3048)
			(stroke
				(width 0.1)
				(type default)
			)
			(layer "F.Fab")
		)
		(fp_line
			(start 0.67945 0.3048)
			(end 0.120396 0.3048)
			(stroke
				(width 0.1)
				(type default)
			)
			(layer "F.Fab")
		)
		(fp_line
			(start 0.120396 0.3048)
			(end 0.120396 0.2794)
			(stroke
				(width 0.1)
				(type default)
			)
			(layer "F.Fab")
		)
		(fp_line
			(start -0.12065 0.3048)
			(end -0.67945 0.3048)
			(stroke
				(width 0.1)
				(type default)
			)
			(layer "F.Fab")
		)
		(fp_line
			(start -0.67945 0.3048)
			(end -0.67945 -0.305054)
			(stroke
				(width 0.1)
				(type default)
			)
			(layer "F.Fab")
		)
		(pad "1" smd circle
			(at -0.40005 0 90)
			(size 0 0)
			(layers "F.Cu" "F.Mask" "F.Paste")
			(net "P3V3_AUX")
		)
		(pad "2" smd circle
			(at 0.40005 0 90)
			(size 0 0)
			(layers "F.Cu" "F.Mask" "F.Paste")
			(net "MB_BMC_MON")
		)
	)
	(footprint ""
		(layer "F.Cu")
		(at 318.89319 -304.90795 -90)
		(property "Reference" "R6809"
			(at 0 0 270)
			(layer "F.SilkS")
			(hide yes)
			(effects
				(font
					(size 1.27 1.27)
				)
			)
		)
		(property "Value" ""
			(at 0 0 270)
			(layer "F.Fab")
			(effects
				(font
					(size 1.27 1.27)
				)
			)
		)
		(duplicate_pad_numbers_are_jumpers no)
		(fp_line
			(start -0.7874 0.4064)
			(end -0.7874 -0.4064)
			(stroke
				(width 0.1524)
				(type default)
			)
			(layer "F.SilkS")
		)
		(fp_line
			(start 0.7874 0.4064)
			(end -0.7874 0.4064)
			(stroke
				(width 0.1524)
				(type default)
			)
			(layer "F.SilkS")
		)
		(fp_line
			(start -0.7874 -0.4064)
			(end 0.7874 -0.4064)
			(stroke
				(width 0.1524)
				(type default)
			)
			(layer "F.SilkS")
		)
		(fp_line
			(start 0.7874 -0.4064)
			(end 0.7874 0.4064)
			(stroke
				(width 0.1524)
				(type default)
			)
			(layer "F.SilkS")
		)
		(fp_line
			(start -0.67945 0.3048)
			(end -0.67945 -0.305054)
			(stroke
				(width 0.1)
				(type default)
			)
			(layer "F.Fab")
		)
		(fp_line
			(start -0.12065 0.3048)
			(end -0.67945 0.3048)
			(stroke
				(width 0.1)
				(type default)
			)
			(layer "F.Fab")
		)
		(fp_line
			(start 0.120396 0.3048)
			(end 0.120396 0.2794)
			(stroke
				(width 0.1)
				(type default)
			)
			(layer "F.Fab")
		)
		(fp_line
			(start 0.67945 0.3048)
			(end 0.120396 0.3048)
			(stroke
				(width 0.1)
				(type default)
			)
			(layer "F.Fab")
		)
		(fp_line
			(start -0.12065 0.2794)
			(end -0.12065 0.3048)
			(stroke
				(width 0.1)
				(type default)
			)
			(layer "F.Fab")
		)
		(fp_line
			(start 0.120396 0.2794)
			(end -0.12065 0.2794)
			(stroke
				(width 0.1)
				(type default)
			)
			(layer "F.Fab")
		)
		(fp_line
			(start -0.12065 -0.2794)
			(end 0.12065 -0.2794)
			(stroke
				(width 0.1)
				(type default)
			)
			(layer "F.Fab")
		)
		(fp_line
			(start 0.12065 -0.2794)
			(end 0.12065 -0.3048)
			(stroke
				(width 0.1)
				(type default)
			)
			(layer "F.Fab")
		)
		(fp_line
			(start 0.12065 -0.3048)
			(end 0.67945 -0.3048)
			(stroke
				(width 0.1)
				(type default)
			)
			(layer "F.Fab")
		)
		(fp_line
			(start 0.67945 -0.3048)
			(end 0.67945 0.3048)
			(stroke
				(width 0.1)
				(type default)
			)
			(layer "F.Fab")
		)
		(fp_line
			(start -0.67945 -0.305054)
			(end -0.12065 -0.305054)
			(stroke
				(width 0.1)
				(type default)
			)
			(layer "F.Fab")
		)
		(fp_line
			(start -0.12065 -0.305054)
			(end -0.12065 -0.2794)
			(stroke
				(width 0.1)
				(type default)
			)
			(layer "F.Fab")
		)
		(pad "1" smd circle
			(at -0.40005 0 270)
			(size 0 0)
			(layers "F.Cu" "F.Mask" "F.Paste")
			(net "SMB_PEX2_R_SDA")
		)
		(pad "2" smd circle
			(at 0.40005 0 270)
			(size 0 0)
			(layers "F.Cu" "F.Mask" "F.Paste")
			(net "SMB_PEX2_SDA")
		)
	)
	(footprint ""
		(layer "F.Cu")
		(at 88.475566 -122.931682 -90)
		(property "Reference" "PD54"
			(at 3.497072 2.172208 90)
			(unlocked yes)
			(layer "F.SilkS")
			(effects
				(font
					(size 0.7874 0.5842)
					(thickness 0.1524)
				)
				(justify left)
			)
		)
		(property "Value" ""
			(at 0 0 270)
			(layer "F.Fab")
			(effects
				(font
					(size 1.27 1.27)
				)
			)
		)
		(duplicate_pad_numbers_are_jumpers no)
		(fp_line
			(start -3.400044 1.459992)
			(end -3.400044 -1.459992)
			(stroke
				(width 0.1524)
				(type default)
			)
			(layer "F.SilkS")
		)
		(fp_line
			(start 4.107942 1.459992)
			(end -3.400044 1.459992)
			(stroke
				(width 0.1524)
				(type default)
			)
			(layer "F.SilkS")
		)
		(fp_line
			(start -3.400044 -1.459992)
			(end 4.107942 -1.459992)
			(stroke
				(width 0.1524)
				(type default)
			)
			(layer "F.SilkS")
		)
		(fp_line
			(start 4.107942 -1.459992)
			(end 4.107942 1.459992)
			(stroke
				(width 0.1524)
				(type default)
			)
			(layer "F.SilkS")
		)
		(fp_rect
			(start 4.107942 1.459992)
			(end 3.308096 -1.459992)
			(stroke
				(width 0)
				(type default)
			)
			(fill yes)
			(layer "F.SilkS")
		)
		(fp_line
			(start -2.29997 1.459992)
			(end -2.29997 -1.459992)
			(stroke
				(width 0.1)
				(type default)
			)
			(layer "F.Fab")
		)
		(fp_line
			(start 2.29997 1.459992)
			(end -2.29997 1.459992)
			(stroke
				(width 0.1)
				(type default)
			)
			(layer "F.Fab")
		)
		(fp_line
			(start -2.29997 -1.459992)
			(end 2.29997 -1.459992)
			(stroke
				(width 0.1)
				(type default)
			)
			(layer "F.Fab")
		)
		(fp_line
			(start 2.29997 -1.459992)
			(end 2.29997 1.459992)
			(stroke
				(width 0.1)
				(type default)
			)
			(layer "F.Fab")
		)
		(fp_text user "-"
			(at 5.06222 2.129028 90)
			(unlocked yes)
			(layer "F.SilkS")
			(effects
				(font
					(size 1.905 1.4224)
					(thickness 0.1524)
				)
				(justify left)
			)
		)
		(fp_text user "+"
			(at -4.7752 -0.12065 270)
			(unlocked yes)
			(layer "F.SilkS")
			(effects
				(font
					(size 1.905 1.4224)
					(thickness 0.1524)
				)
				(justify left)
			)
		)
		(fp_text user "-"
			(at 5.4102 0.29845 90)
			(unlocked yes)
			(layer "F.Fab")
			(effects
				(font
					(size 1.905 1.4224)
					(thickness 0.1524)
				)
				(justify left)
			)
		)
		(fp_text user "+"
			(at -4.7752 -0.12065 270)
			(unlocked yes)
			(layer "F.Fab")
			(effects
				(font
					(size 1.905 1.4224)
					(thickness 0.1524)
				)
				(justify left)
			)
		)
		(pad "A" smd rect
			(at -1.999996 0)
			(size 1.7018 2.5146)
			(layers "F.Cu" "F.Mask" "F.Paste")
			(net "GND")
		)
		(pad "C" smd rect
			(at 1.999996 0)
			(size 1.7018 2.5146)
			(layers "F.Cu" "F.Mask" "F.Paste")
			(net "P3V3_NIC1")
		)
	)
	(footprint ""
		(layer "F.Cu")
		(at 452.56704 -57.332626)
		(property "Reference" "R6826"
			(at 0 0 0)
			(layer "F.SilkS")
			(hide yes)
			(effects
				(font
					(size 1.27 1.27)
				)
			)
		)
		(property "Value" ""
			(at 0 0 0)
			(layer "F.Fab")
			(effects
				(font
					(size 1.27 1.27)
				)
			)
		)
		(duplicate_pad_numbers_are_jumpers no)
		(fp_line
			(start -0.7874 -0.4064)
			(end 0.7874 -0.4064)
			(stroke
				(width 0.1524)
				(type default)
			)
			(layer "F.SilkS")
		)
		(fp_line
			(start -0.7874 0.4064)
			(end -0.7874 -0.4064)
			(stroke
				(width 0.1524)
				(type default)
			)
			(layer "F.SilkS")
		)
		(fp_line
			(start 0.7874 -0.4064)
			(end 0.7874 0.4064)
			(stroke
				(width 0.1524)
				(type default)
			)
			(layer "F.SilkS")
		)
		(fp_line
			(start 0.7874 0.4064)
			(end -0.7874 0.4064)
			(stroke
				(width 0.1524)
				(type default)
			)
			(layer "F.SilkS")
		)
		(fp_line
			(start -0.67945 -0.305054)
			(end -0.12065 -0.305054)
			(stroke
				(width 0.1)
				(type default)
			)
			(layer "F.Fab")
		)
		(fp_line
			(start -0.67945 0.3048)
			(end -0.67945 -0.305054)
			(stroke
				(width 0.1)
				(type default)
			)
			(layer "F.Fab")
		)
		(fp_line
			(start -0.12065 -0.305054)
			(end -0.12065 -0.2794)
			(stroke
				(width 0.1)
				(type default)
			)
			(layer "F.Fab")
		)
		(fp_line
			(start -0.12065 -0.2794)
			(end 0.12065 -0.2794)
			(stroke
				(width 0.1)
				(type default)
			)
			(layer "F.Fab")
		)
		(fp_line
			(start -0.12065 0.2794)
			(end -0.12065 0.3048)
			(stroke
				(width 0.1)
				(type default)
			)
			(layer "F.Fab")
		)
		(fp_line
			(start -0.12065 0.3048)
			(end -0.67945 0.3048)
			(stroke
				(width 0.1)
				(type default)
			)
			(layer "F.Fab")
		)
		(fp_line
			(start 0.120396 0.2794)
			(end -0.12065 0.2794)
			(stroke
				(width 0.1)
				(type default)
			)
			(layer "F.Fab")
		)
		(fp_line
			(start 0.120396 0.3048)
			(end 0.120396 0.2794)
			(stroke
				(width 0.1)
				(type default)
			)
			(layer "F.Fab")
		)
		(fp_line
			(start 0.12065 -0.3048)
			(end 0.67945 -0.3048)
			(stroke
				(width 0.1)
				(type default)
			)
			(layer "F.Fab")
		)
		(fp_line
			(start 0.12065 -0.2794)
			(end 0.12065 -0.3048)
			(stroke
				(width 0.1)
				(type default)
			)
			(layer "F.Fab")
		)
		(fp_line
			(start 0.67945 -0.3048)
			(end 0.67945 0.3048)
			(stroke
				(width 0.1)
				(type default)
			)
			(layer "F.Fab")
		)
		(fp_line
			(start 0.67945 0.3048)
			(end 0.120396 0.3048)
			(stroke
				(width 0.1)
				(type default)
			)
			(layer "F.Fab")
		)
		(pad "1" smd circle
			(at -0.40005 0)
			(size 0 0)
			(layers "F.Cu" "F.Mask" "F.Paste")
			(net "SSD15_PWR_EN_R")
		)
		(pad "2" smd circle
			(at 0.40005 0)
			(size 0 0)
			(layers "F.Cu" "F.Mask" "F.Paste")
			(net "GND")
		)
	)
	(footprint ""
		(layer "F.Cu")
		(at 150.602442 -250.070874 -90)
		(property "Reference" "R1280"
			(at 0 0 270)
			(layer "F.SilkS")
			(hide yes)
			(effects
				(font
					(size 1.27 1.27)
				)
			)
		)
		(property "Value" ""
			(at 0 0 270)
			(layer "F.Fab")
			(effects
				(font
					(size 1.27 1.27)
				)
			)
		)
		(duplicate_pad_numbers_are_jumpers no)
		(fp_line
			(start -0.7874 0.4064)
			(end -0.7874 -0.4064)
			(stroke
				(width 0.1524)
				(type default)
			)
			(layer "F.SilkS")
		)
		(fp_line
			(start 0.7874 0.4064)
			(end -0.7874 0.4064)
			(stroke
				(width 0.1524)
				(type default)
			)
			(layer "F.SilkS")
		)
		(fp_line
			(start -0.7874 -0.4064)
			(end 0.7874 -0.4064)
			(stroke
				(width 0.1524)
				(type default)
			)
			(layer "F.SilkS")
		)
		(fp_line
			(start 0.7874 -0.4064)
			(end 0.7874 0.4064)
			(stroke
				(width 0.1524)
				(type default)
			)
			(layer "F.SilkS")
		)
		(fp_line
			(start -0.67945 0.3048)
			(end -0.67945 -0.305054)
			(stroke
				(width 0.1)
				(type default)
			)
			(layer "F.Fab")
		)
		(fp_line
			(start -0.12065 0.3048)
			(end -0.67945 0.3048)
			(stroke
				(width 0.1)
				(type default)
			)
			(layer "F.Fab")
		)
		(fp_line
			(start 0.120396 0.3048)
			(end 0.120396 0.2794)
			(stroke
				(width 0.1)
				(type default)
			)
			(layer "F.Fab")
		)
		(fp_line
			(start 0.67945 0.3048)
			(end 0.120396 0.3048)
			(stroke
				(width 0.1)
				(type default)
			)
			(layer "F.Fab")
		)
		(fp_line
			(start -0.12065 0.2794)
			(end -0.12065 0.3048)
			(stroke
				(width 0.1)
				(type default)
			)
			(layer "F.Fab")
		)
		(fp_line
			(start 0.120396 0.2794)
			(end -0.12065 0.2794)
			(stroke
				(width 0.1)
				(type default)
			)
			(layer "F.Fab")
		)
		(fp_line
			(start -0.12065 -0.2794)
			(end 0.12065 -0.2794)
			(stroke
				(width 0.1)
				(type default)
			)
			(layer "F.Fab")
		)
		(fp_line
			(start 0.12065 -0.2794)
			(end 0.12065 -0.3048)
			(stroke
				(width 0.1)
				(type default)
			)
			(layer "F.Fab")
		)
		(fp_line
			(start 0.12065 -0.3048)
			(end 0.67945 -0.3048)
			(stroke
				(width 0.1)
				(type default)
			)
			(layer "F.Fab")
		)
		(fp_line
			(start 0.67945 -0.3048)
			(end 0.67945 0.3048)
			(stroke
				(width 0.1)
				(type default)
			)
			(layer "F.Fab")
		)
		(fp_line
			(start -0.67945 -0.305054)
			(end -0.12065 -0.305054)
			(stroke
				(width 0.1)
				(type default)
			)
			(layer "F.Fab")
		)
		(fp_line
			(start -0.12065 -0.305054)
			(end -0.12065 -0.2794)
			(stroke
				(width 0.1)
				(type default)
			)
			(layer "F.Fab")
		)
		(pad "1" smd circle
			(at -0.40005 0 270)
			(size 0 0)
			(layers "F.Cu" "F.Mask" "F.Paste")
			(net "PEX1_MODE_SEL11")
		)
		(pad "2" smd circle
			(at 0.40005 0 270)
			(size 0 0)
			(layers "F.Cu" "F.Mask" "F.Paste")
			(net "P1V8_PEX")
		)
	)
	(footprint ""
		(layer "F.Cu")
		(at 386.70738 -350.098614 90)
		(property "Reference" "C776"
			(at 0 0 90)
			(layer "F.SilkS")
			(hide yes)
			(effects
				(font
					(size 1.27 1.27)
				)
			)
		)
		(property "Value" ""
			(at 0 0 90)
			(layer "F.Fab")
			(effects
				(font
					(size 1.27 1.27)
				)
			)
		)
		(duplicate_pad_numbers_are_jumpers no)
		(fp_line
			(start 0.299974 -0.150114)
			(end 0.299974 0.150114)
			(stroke
				(width 0.1)
				(type default)
			)
			(layer "F.Fab")
		)
		(fp_line
			(start -0.299974 -0.150114)
			(end 0.299974 -0.150114)
			(stroke
				(width 0.1)
				(type default)
			)
			(layer "F.Fab")
		)
		(fp_line
			(start 0.299974 0.150114)
			(end -0.299974 0.150114)
			(stroke
				(width 0.1)
				(type default)
			)
			(layer "F.Fab")
		)
		(fp_line
			(start -0.299974 0.150114)
			(end -0.299974 -0.150114)
			(stroke
				(width 0.1)
				(type default)
			)
			(layer "F.Fab")
		)
		(pad "1" smd rect
			(at -0.2667 0 90)
			(size 0.3048 0.381)
			(layers "F.Cu" "F.Mask" "F.Paste")
			(net "P5E_PEX3_STN6_TX_DP<104>")
		)
		(pad "2" smd rect
			(at 0.2667 0 90)
			(size 0.3048 0.381)
			(layers "F.Cu" "F.Mask" "F.Paste")
			(net "P5E_PEX3_STN6_TX_C_DP<104>")
		)
	)
	(footprint ""
		(layer "F.Cu")
		(at 326.012556 -197.250304)
		(property "Reference" "R4245"
			(at 0 0 0)
			(layer "F.SilkS")
			(hide yes)
			(effects
				(font
					(size 1.27 1.27)
				)
			)
		)
		(property "Value" ""
			(at 0 0 0)
			(layer "F.Fab")
			(effects
				(font
					(size 1.27 1.27)
				)
			)
		)
		(duplicate_pad_numbers_are_jumpers no)
		(fp_line
			(start -0.7874 -0.4064)
			(end 0.7874 -0.4064)
			(stroke
				(width 0.1524)
				(type default)
			)
			(layer "F.SilkS")
		)
		(fp_line
			(start -0.7874 0.4064)
			(end -0.7874 -0.4064)
			(stroke
				(width 0.1524)
				(type default)
			)
			(layer "F.SilkS")
		)
		(fp_line
			(start 0.7874 -0.4064)
			(end 0.7874 0.4064)
			(stroke
				(width 0.1524)
				(type default)
			)
			(layer "F.SilkS")
		)
		(fp_line
			(start 0.7874 0.4064)
			(end -0.7874 0.4064)
			(stroke
				(width 0.1524)
				(type default)
			)
			(layer "F.SilkS")
		)
		(fp_line
			(start -0.67945 -0.305054)
			(end -0.12065 -0.305054)
			(stroke
				(width 0.1)
				(type default)
			)
			(layer "F.Fab")
		)
		(fp_line
			(start -0.67945 0.3048)
			(end -0.67945 -0.305054)
			(stroke
				(width 0.1)
				(type default)
			)
			(layer "F.Fab")
		)
		(fp_line
			(start -0.12065 -0.305054)
			(end -0.12065 -0.2794)
			(stroke
				(width 0.1)
				(type default)
			)
			(layer "F.Fab")
		)
		(fp_line
			(start -0.12065 -0.2794)
			(end 0.12065 -0.2794)
			(stroke
				(width 0.1)
				(type default)
			)
			(layer "F.Fab")
		)
		(fp_line
			(start -0.12065 0.2794)
			(end -0.12065 0.3048)
			(stroke
				(width 0.1)
				(type default)
			)
			(layer "F.Fab")
		)
		(fp_line
			(start -0.12065 0.3048)
			(end -0.67945 0.3048)
			(stroke
				(width 0.1)
				(type default)
			)
			(layer "F.Fab")
		)
		(fp_line
			(start 0.120396 0.2794)
			(end -0.12065 0.2794)
			(stroke
				(width 0.1)
				(type default)
			)
			(layer "F.Fab")
		)
		(fp_line
			(start 0.120396 0.3048)
			(end 0.120396 0.2794)
			(stroke
				(width 0.1)
				(type default)
			)
			(layer "F.Fab")
		)
		(fp_line
			(start 0.12065 -0.3048)
			(end 0.67945 -0.3048)
			(stroke
				(width 0.1)
				(type default)
			)
			(layer "F.Fab")
		)
		(fp_line
			(start 0.12065 -0.2794)
			(end 0.12065 -0.3048)
			(stroke
				(width 0.1)
				(type default)
			)
			(layer "F.Fab")
		)
		(fp_line
			(start 0.67945 -0.3048)
			(end 0.67945 0.3048)
			(stroke
				(width 0.1)
				(type default)
			)
			(layer "F.Fab")
		)
		(fp_line
			(start 0.67945 0.3048)
			(end 0.120396 0.3048)
			(stroke
				(width 0.1)
				(type default)
			)
			(layer "F.Fab")
		)
		(pad "1" smd circle
			(at -0.40005 0)
			(size 0 0)
			(layers "F.Cu" "F.Mask" "F.Paste")
			(net "GND")
		)
		(pad "2" smd circle
			(at 0.40005 0)
			(size 0 0)
			(layers "F.Cu" "F.Mask" "F.Paste")
			(net "IOEXP_DBV2_A1")
		)
	)
	(footprint ""
		(layer "F.Cu")
		(at 163.047426 -19.33956)
		(property "Reference" "C3912"
			(at 0 0 0)
			(layer "F.SilkS")
			(hide yes)
			(effects
				(font
					(size 1.27 1.27)
				)
			)
		)
		(property "Value" ""
			(at 0 0 0)
			(layer "F.Fab")
			(effects
				(font
					(size 1.27 1.27)
				)
			)
		)
		(duplicate_pad_numbers_are_jumpers no)
		(fp_line
			(start -0.7874 -0.4064)
			(end 0.7874 -0.4064)
			(stroke
				(width 0.1524)
				(type default)
			)
			(layer "F.SilkS")
		)
		(fp_line
			(start -0.7874 0.4064)
			(end -0.7874 -0.4064)
			(stroke
				(width 0.1524)
				(type default)
			)
			(layer "F.SilkS")
		)
		(fp_line
			(start 0.7874 -0.4064)
			(end 0.7874 0.4064)
			(stroke
				(width 0.1524)
				(type default)
			)
			(layer "F.SilkS")
		)
		(fp_line
			(start 0.7874 0.4064)
			(end -0.7874 0.4064)
			(stroke
				(width 0.1524)
				(type default)
			)
			(layer "F.SilkS")
		)
		(fp_line
			(start -0.67945 -0.305054)
			(end -0.12065 -0.305054)
			(stroke
				(width 0.1)
				(type default)
			)
			(layer "F.Fab")
		)
		(fp_line
			(start -0.67945 0.3048)
			(end -0.67945 -0.305054)
			(stroke
				(width 0.1)
				(type default)
			)
			(layer "F.Fab")
		)
		(fp_line
			(start -0.12065 -0.305054)
			(end -0.12065 -0.2794)
			(stroke
				(width 0.1)
				(type default)
			)
			(layer "F.Fab")
		)
		(fp_line
			(start -0.12065 -0.2794)
			(end 0.12065 -0.2794)
			(stroke
				(width 0.1)
				(type default)
			)
			(layer "F.Fab")
		)
		(fp_line
			(start -0.12065 0.2794)
			(end -0.12065 0.3048)
			(stroke
				(width 0.1)
				(type default)
			)
			(layer "F.Fab")
		)
		(fp_line
			(start -0.12065 0.3048)
			(end -0.67945 0.3048)
			(stroke
				(width 0.1)
				(type default)
			)
			(layer "F.Fab")
		)
		(fp_line
			(start 0.120396 0.2794)
			(end -0.12065 0.2794)
			(stroke
				(width 0.1)
				(type default)
			)
			(layer "F.Fab")
		)
		(fp_line
			(start 0.120396 0.3048)
			(end 0.120396 0.2794)
			(stroke
				(width 0.1)
				(type default)
			)
			(layer "F.Fab")
		)
		(fp_line
			(start 0.12065 -0.3048)
			(end 0.67945 -0.3048)
			(stroke
				(width 0.1)
				(type default)
			)
			(layer "F.Fab")
		)
		(fp_line
			(start 0.12065 -0.2794)
			(end 0.12065 -0.3048)
			(stroke
				(width 0.1)
				(type default)
			)
			(layer "F.Fab")
		)
		(fp_line
			(start 0.67945 -0.3048)
			(end 0.67945 0.3048)
			(stroke
				(width 0.1)
				(type default)
			)
			(layer "F.Fab")
		)
		(fp_line
			(start 0.67945 0.3048)
			(end 0.120396 0.3048)
			(stroke
				(width 0.1)
				(type default)
			)
			(layer "F.Fab")
		)
		(pad "1" smd circle
			(at -0.40005 0)
			(size 0 0)
			(layers "F.Cu" "F.Mask" "F.Paste")
			(net "P12V_SSD5")
		)
		(pad "2" smd circle
			(at 0.40005 0)
			(size 0 0)
			(layers "F.Cu" "F.Mask" "F.Paste")
			(net "GND")
		)
	)
	(footprint ""
		(layer "F.Cu")
		(at 343.027 -234.061 -90)
		(property "Reference" "R3539"
			(at 0 0 270)
			(layer "F.SilkS")
			(hide yes)
			(effects
				(font
					(size 1.27 1.27)
				)
			)
		)
		(property "Value" ""
			(at 0 0 270)
			(layer "F.Fab")
			(effects
				(font
					(size 1.27 1.27)
				)
			)
		)
		(duplicate_pad_numbers_are_jumpers no)
		(fp_line
			(start -0.7874 0.4064)
			(end -0.7874 -0.4064)
			(stroke
				(width 0.1524)
				(type default)
			)
			(layer "F.SilkS")
		)
		(fp_line
			(start 0.7874 0.4064)
			(end -0.7874 0.4064)
			(stroke
				(width 0.1524)
				(type default)
			)
			(layer "F.SilkS")
		)
		(fp_line
			(start -0.7874 -0.4064)
			(end 0.7874 -0.4064)
			(stroke
				(width 0.1524)
				(type default)
			)
			(layer "F.SilkS")
		)
		(fp_line
			(start 0.7874 -0.4064)
			(end 0.7874 0.4064)
			(stroke
				(width 0.1524)
				(type default)
			)
			(layer "F.SilkS")
		)
		(fp_line
			(start -0.67945 0.3048)
			(end -0.67945 -0.305054)
			(stroke
				(width 0.1)
				(type default)
			)
			(layer "F.Fab")
		)
		(fp_line
			(start -0.12065 0.3048)
			(end -0.67945 0.3048)
			(stroke
				(width 0.1)
				(type default)
			)
			(layer "F.Fab")
		)
		(fp_line
			(start 0.120396 0.3048)
			(end 0.120396 0.2794)
			(stroke
				(width 0.1)
				(type default)
			)
			(layer "F.Fab")
		)
		(fp_line
			(start 0.67945 0.3048)
			(end 0.120396 0.3048)
			(stroke
				(width 0.1)
				(type default)
			)
			(layer "F.Fab")
		)
		(fp_line
			(start -0.12065 0.2794)
			(end -0.12065 0.3048)
			(stroke
				(width 0.1)
				(type default)
			)
			(layer "F.Fab")
		)
		(fp_line
			(start 0.120396 0.2794)
			(end -0.12065 0.2794)
			(stroke
				(width 0.1)
				(type default)
			)
			(layer "F.Fab")
		)
		(fp_line
			(start -0.12065 -0.2794)
			(end 0.12065 -0.2794)
			(stroke
				(width 0.1)
				(type default)
			)
			(layer "F.Fab")
		)
		(fp_line
			(start 0.12065 -0.2794)
			(end 0.12065 -0.3048)
			(stroke
				(width 0.1)
				(type default)
			)
			(layer "F.Fab")
		)
		(fp_line
			(start 0.12065 -0.3048)
			(end 0.67945 -0.3048)
			(stroke
				(width 0.1)
				(type default)
			)
			(layer "F.Fab")
		)
		(fp_line
			(start 0.67945 -0.3048)
			(end 0.67945 0.3048)
			(stroke
				(width 0.1)
				(type default)
			)
			(layer "F.Fab")
		)
		(fp_line
			(start -0.67945 -0.305054)
			(end -0.12065 -0.305054)
			(stroke
				(width 0.1)
				(type default)
			)
			(layer "F.Fab")
		)
		(fp_line
			(start -0.12065 -0.305054)
			(end -0.12065 -0.2794)
			(stroke
				(width 0.1)
				(type default)
			)
			(layer "F.Fab")
		)
		(pad "1" smd circle
			(at -0.40005 0 270)
			(size 0 0)
			(layers "F.Cu" "F.Mask" "F.Paste")
			(net "RST_SSD3_PERST_R_N")
		)
		(pad "2" smd circle
			(at 0.40005 0 270)
			(size 0 0)
			(layers "F.Cu" "F.Mask" "F.Paste")
			(net "RST_SSD3_PERST_N")
		)
	)
	(footprint ""
		(layer "F.Cu")
		(at 363.474 -194.691)
		(property "Reference" "R4668"
			(at 0 0 0)
			(layer "F.SilkS")
			(hide yes)
			(effects
				(font
					(size 1.27 1.27)
				)
			)
		)
		(property "Value" ""
			(at 0 0 0)
			(layer "F.Fab")
			(effects
				(font
					(size 1.27 1.27)
				)
			)
		)
		(duplicate_pad_numbers_are_jumpers no)
		(fp_line
			(start -0.7874 -0.4064)
			(end 0.7874 -0.4064)
			(stroke
				(width 0.1524)
				(type default)
			)
			(layer "F.SilkS")
		)
		(fp_line
			(start -0.7874 0.4064)
			(end -0.7874 -0.4064)
			(stroke
				(width 0.1524)
				(type default)
			)
			(layer "F.SilkS")
		)
		(fp_line
			(start 0.7874 -0.4064)
			(end 0.7874 0.4064)
			(stroke
				(width 0.1524)
				(type default)
			)
			(layer "F.SilkS")
		)
		(fp_line
			(start 0.7874 0.4064)
			(end -0.7874 0.4064)
			(stroke
				(width 0.1524)
				(type default)
			)
			(layer "F.SilkS")
		)
		(fp_line
			(start -0.67945 -0.305054)
			(end -0.12065 -0.305054)
			(stroke
				(width 0.1)
				(type default)
			)
			(layer "F.Fab")
		)
		(fp_line
			(start -0.67945 0.3048)
			(end -0.67945 -0.305054)
			(stroke
				(width 0.1)
				(type default)
			)
			(layer "F.Fab")
		)
		(fp_line
			(start -0.12065 -0.305054)
			(end -0.12065 -0.2794)
			(stroke
				(width 0.1)
				(type default)
			)
			(layer "F.Fab")
		)
		(fp_line
			(start -0.12065 -0.2794)
			(end 0.12065 -0.2794)
			(stroke
				(width 0.1)
				(type default)
			)
			(layer "F.Fab")
		)
		(fp_line
			(start -0.12065 0.2794)
			(end -0.12065 0.3048)
			(stroke
				(width 0.1)
				(type default)
			)
			(layer "F.Fab")
		)
		(fp_line
			(start -0.12065 0.3048)
			(end -0.67945 0.3048)
			(stroke
				(width 0.1)
				(type default)
			)
			(layer "F.Fab")
		)
		(fp_line
			(start 0.120396 0.2794)
			(end -0.12065 0.2794)
			(stroke
				(width 0.1)
				(type default)
			)
			(layer "F.Fab")
		)
		(fp_line
			(start 0.120396 0.3048)
			(end 0.120396 0.2794)
			(stroke
				(width 0.1)
				(type default)
			)
			(layer "F.Fab")
		)
		(fp_line
			(start 0.12065 -0.3048)
			(end 0.67945 -0.3048)
			(stroke
				(width 0.1)
				(type default)
			)
			(layer "F.Fab")
		)
		(fp_line
			(start 0.12065 -0.2794)
			(end 0.12065 -0.3048)
			(stroke
				(width 0.1)
				(type default)
			)
			(layer "F.Fab")
		)
		(fp_line
			(start 0.67945 -0.3048)
			(end 0.67945 0.3048)
			(stroke
				(width 0.1)
				(type default)
			)
			(layer "F.Fab")
		)
		(fp_line
			(start 0.67945 0.3048)
			(end 0.120396 0.3048)
			(stroke
				(width 0.1)
				(type default)
			)
			(layer "F.Fab")
		)
		(pad "1" smd circle
			(at -0.40005 0)
			(size 0 0)
			(layers "F.Cu" "F.Mask" "F.Paste")
			(net "P3V3_AUX")
		)
		(pad "2" smd circle
			(at 0.40005 0)
			(size 0 0)
			(layers "F.Cu" "F.Mask" "F.Paste")
			(net "RST_PEX_SSD5_PERST_R_N")
		)
	)
	(footprint ""
		(layer "F.Cu")
		(at 77.806042 -343.952322 90)
		(property "Reference" "C114"
			(at 0 0 90)
			(layer "F.SilkS")
			(hide yes)
			(effects
				(font
					(size 1.27 1.27)
				)
			)
		)
		(property "Value" ""
			(at 0 0 90)
			(layer "F.Fab")
			(effects
				(font
					(size 1.27 1.27)
				)
			)
		)
		(duplicate_pad_numbers_are_jumpers no)
		(fp_line
			(start 0.299974 -0.150114)
			(end 0.299974 0.150114)
			(stroke
				(width 0.1)
				(type default)
			)
			(layer "F.Fab")
		)
		(fp_line
			(start -0.299974 -0.150114)
			(end 0.299974 -0.150114)
			(stroke
				(width 0.1)
				(type default)
			)
			(layer "F.Fab")
		)
		(fp_line
			(start 0.299974 0.150114)
			(end -0.299974 0.150114)
			(stroke
				(width 0.1)
				(type default)
			)
			(layer "F.Fab")
		)
		(fp_line
			(start -0.299974 0.150114)
			(end -0.299974 -0.150114)
			(stroke
				(width 0.1)
				(type default)
			)
			(layer "F.Fab")
		)
		(pad "1" smd rect
			(at -0.2667 0 90)
			(size 0.3048 0.381)
			(layers "F.Cu" "F.Mask" "F.Paste")
			(net "P5E_PEX0_STN5_TX_DN<87>")
		)
		(pad "2" smd rect
			(at 0.2667 0 90)
			(size 0.3048 0.381)
			(layers "F.Cu" "F.Mask" "F.Paste")
			(net "P5E_PEX0_STN5_TX_C_DN<87>")
		)
	)
	(footprint ""
		(layer "F.Cu")
		(at 34.851848 -356.244906 90)
		(property "Reference" "C175"
			(at 0 0 90)
			(layer "F.SilkS")
			(hide yes)
			(effects
				(font
					(size 1.27 1.27)
				)
			)
		)
		(property "Value" ""
			(at 0 0 90)
			(layer "F.Fab")
			(effects
				(font
					(size 1.27 1.27)
				)
			)
		)
		(duplicate_pad_numbers_are_jumpers no)
		(fp_line
			(start 0.299974 -0.150114)
			(end 0.299974 0.150114)
			(stroke
				(width 0.1)
				(type default)
			)
			(layer "F.Fab")
		)
		(fp_line
			(start -0.299974 -0.150114)
			(end 0.299974 -0.150114)
			(stroke
				(width 0.1)
				(type default)
			)
			(layer "F.Fab")
		)
		(fp_line
			(start 0.299974 0.150114)
			(end -0.299974 0.150114)
			(stroke
				(width 0.1)
				(type default)
			)
			(layer "F.Fab")
		)
		(fp_line
			(start -0.299974 0.150114)
			(end -0.299974 -0.150114)
			(stroke
				(width 0.1)
				(type default)
			)
			(layer "F.Fab")
		)
		(pad "1" smd rect
			(at -0.2667 0 90)
			(size 0.3048 0.381)
			(layers "F.Cu" "F.Mask" "F.Paste")
			(net "P5E_PEX0_STN7_TX_DP<120>")
		)
		(pad "2" smd rect
			(at 0.2667 0 90)
			(size 0.3048 0.381)
			(layers "F.Cu" "F.Mask" "F.Paste")
			(net "P5E_PEX0_STN7_TX_C_DP<120>")
		)
	)
	(footprint ""
		(layer "F.Cu")
		(at 367.708434 -142.455392 180)
		(property "Reference" "R748"
			(at 0 0 180)
			(layer "F.SilkS")
			(hide yes)
			(effects
				(font
					(size 1.27 1.27)
				)
			)
		)
		(property "Value" ""
			(at 0 0 180)
			(layer "F.Fab")
			(effects
				(font
					(size 1.27 1.27)
				)
			)
		)
		(duplicate_pad_numbers_are_jumpers no)
		(fp_line
			(start 3.937508 1.8796)
			(end 3.937508 -1.8796)
			(stroke
				(width 0.1524)
				(type default)
			)
			(layer "F.SilkS")
		)
		(fp_line
			(start 3.937508 -1.8796)
			(end -3.937508 -1.8796)
			(stroke
				(width 0.1524)
				(type default)
			)
			(layer "F.SilkS")
		)
		(fp_line
			(start -3.937508 1.8796)
			(end 3.937508 1.8796)
			(stroke
				(width 0.1524)
				(type default)
			)
			(layer "F.SilkS")
		)
		(fp_line
			(start -3.937508 -1.8796)
			(end -3.937508 1.8796)
			(stroke
				(width 0.1524)
				(type default)
			)
			(layer "F.SilkS")
		)
		(fp_line
			(start 3.275076 1.674876)
			(end 3.275076 -1.674876)
			(stroke
				(width 0.1)
				(type default)
			)
			(layer "F.Fab")
		)
		(fp_line
			(start 3.275076 -1.674876)
			(end -3.275076 -1.674876)
			(stroke
				(width 0.1)
				(type default)
			)
			(layer "F.Fab")
		)
		(fp_line
			(start -3.275076 1.674876)
			(end 3.275076 1.674876)
			(stroke
				(width 0.1)
				(type default)
			)
			(layer "F.Fab")
		)
		(fp_line
			(start -3.275076 -1.674876)
			(end -3.275076 1.674876)
			(stroke
				(width 0.1)
				(type default)
			)
			(layer "F.Fab")
		)
		(pad "1" smd rect
			(at -2.350008 0 180)
			(size 2.921 3.5052)
			(layers "F.Cu" "F.Mask" "F.Paste")
			(net "P12V_NIC6")
		)
		(pad "2" smd rect
			(at 2.350008 0 180)
			(size 2.921 3.5052)
			(layers "F.Cu" "F.Mask" "F.Paste")
			(net "P12V_NIC6_R")
		)
	)
	(footprint ""
		(layer "F.Cu")
		(at 330.325222 -42.849038 180)
		(property "Reference" "R634"
			(at 0 0 180)
			(layer "F.SilkS")
			(hide yes)
			(effects
				(font
					(size 1.27 1.27)
				)
			)
		)
		(property "Value" ""
			(at 0 0 180)
			(layer "F.Fab")
			(effects
				(font
					(size 1.27 1.27)
				)
			)
		)
		(duplicate_pad_numbers_are_jumpers no)
		(fp_line
			(start 0.7874 0.4064)
			(end -0.7874 0.4064)
			(stroke
				(width 0.1524)
				(type default)
			)
			(layer "F.SilkS")
		)
		(fp_line
			(start 0.7874 -0.4064)
			(end 0.7874 0.4064)
			(stroke
				(width 0.1524)
				(type default)
			)
			(layer "F.SilkS")
		)
		(fp_line
			(start -0.7874 0.4064)
			(end -0.7874 -0.4064)
			(stroke
				(width 0.1524)
				(type default)
			)
			(layer "F.SilkS")
		)
		(fp_line
			(start -0.7874 -0.4064)
			(end 0.7874 -0.4064)
			(stroke
				(width 0.1524)
				(type default)
			)
			(layer "F.SilkS")
		)
		(fp_line
			(start 0.67945 0.3048)
			(end 0.120396 0.3048)
			(stroke
				(width 0.1)
				(type default)
			)
			(layer "F.Fab")
		)
		(fp_line
			(start 0.67945 -0.3048)
			(end 0.67945 0.3048)
			(stroke
				(width 0.1)
				(type default)
			)
			(layer "F.Fab")
		)
		(fp_line
			(start 0.12065 -0.2794)
			(end 0.12065 -0.3048)
			(stroke
				(width 0.1)
				(type default)
			)
			(layer "F.Fab")
		)
		(fp_line
			(start 0.12065 -0.3048)
			(end 0.67945 -0.3048)
			(stroke
				(width 0.1)
				(type default)
			)
			(layer "F.Fab")
		)
		(fp_line
			(start 0.120396 0.3048)
			(end 0.120396 0.2794)
			(stroke
				(width 0.1)
				(type default)
			)
			(layer "F.Fab")
		)
		(fp_line
			(start 0.120396 0.2794)
			(end -0.12065 0.2794)
			(stroke
				(width 0.1)
				(type default)
			)
			(layer "F.Fab")
		)
		(fp_line
			(start -0.12065 0.3048)
			(end -0.67945 0.3048)
			(stroke
				(width 0.1)
				(type default)
			)
			(layer "F.Fab")
		)
		(fp_line
			(start -0.12065 0.2794)
			(end -0.12065 0.3048)
			(stroke
				(width 0.1)
				(type default)
			)
			(layer "F.Fab")
		)
		(fp_line
			(start -0.12065 -0.2794)
			(end 0.12065 -0.2794)
			(stroke
				(width 0.1)
				(type default)
			)
			(layer "F.Fab")
		)
		(fp_line
			(start -0.12065 -0.305054)
			(end -0.12065 -0.2794)
			(stroke
				(width 0.1)
				(type default)
			)
			(layer "F.Fab")
		)
		(fp_line
			(start -0.67945 0.3048)
			(end -0.67945 -0.305054)
			(stroke
				(width 0.1)
				(type default)
			)
			(layer "F.Fab")
		)
		(fp_line
			(start -0.67945 -0.305054)
			(end -0.12065 -0.305054)
			(stroke
				(width 0.1)
				(type default)
			)
			(layer "F.Fab")
		)
		(pad "1" smd circle
			(at -0.40005 0 180)
			(size 0 0)
			(layers "F.Cu" "F.Mask" "F.Paste")
			(net "P12V_SSD11_R")
		)
		(pad "2" smd circle
			(at 0.40005 0 180)
			(size 0 0)
			(layers "F.Cu" "F.Mask" "F.Paste")
			(net "P12V_SSD11_VIN_P")
		)
	)
	(footprint ""
		(layer "F.Cu")
		(at 319.70218 -389.98779 180)
		(property "Reference" "R6774"
			(at 0 0 180)
			(layer "F.SilkS")
			(hide yes)
			(effects
				(font
					(size 1.27 1.27)
				)
			)
		)
		(property "Value" ""
			(at 0 0 180)
			(layer "F.Fab")
			(effects
				(font
					(size 1.27 1.27)
				)
			)
		)
		(duplicate_pad_numbers_are_jumpers no)
		(fp_line
			(start 0.7874 0.4064)
			(end -0.7874 0.4064)
			(stroke
				(width 0.1524)
				(type default)
			)
			(layer "F.SilkS")
		)
		(fp_line
			(start 0.7874 -0.4064)
			(end 0.7874 0.4064)
			(stroke
				(width 0.1524)
				(type default)
			)
			(layer "F.SilkS")
		)
		(fp_line
			(start -0.7874 0.4064)
			(end -0.7874 -0.4064)
			(stroke
				(width 0.1524)
				(type default)
			)
			(layer "F.SilkS")
		)
		(fp_line
			(start -0.7874 -0.4064)
			(end 0.7874 -0.4064)
			(stroke
				(width 0.1524)
				(type default)
			)
			(layer "F.SilkS")
		)
		(fp_line
			(start 0.67945 0.3048)
			(end 0.120396 0.3048)
			(stroke
				(width 0.1)
				(type default)
			)
			(layer "F.Fab")
		)
		(fp_line
			(start 0.67945 -0.3048)
			(end 0.67945 0.3048)
			(stroke
				(width 0.1)
				(type default)
			)
			(layer "F.Fab")
		)
		(fp_line
			(start 0.12065 -0.2794)
			(end 0.12065 -0.3048)
			(stroke
				(width 0.1)
				(type default)
			)
			(layer "F.Fab")
		)
		(fp_line
			(start 0.12065 -0.3048)
			(end 0.67945 -0.3048)
			(stroke
				(width 0.1)
				(type default)
			)
			(layer "F.Fab")
		)
		(fp_line
			(start 0.120396 0.3048)
			(end 0.120396 0.2794)
			(stroke
				(width 0.1)
				(type default)
			)
			(layer "F.Fab")
		)
		(fp_line
			(start 0.120396 0.2794)
			(end -0.12065 0.2794)
			(stroke
				(width 0.1)
				(type default)
			)
			(layer "F.Fab")
		)
		(fp_line
			(start -0.12065 0.3048)
			(end -0.67945 0.3048)
			(stroke
				(width 0.1)
				(type default)
			)
			(layer "F.Fab")
		)
		(fp_line
			(start -0.12065 0.2794)
			(end -0.12065 0.3048)
			(stroke
				(width 0.1)
				(type default)
			)
			(layer "F.Fab")
		)
		(fp_line
			(start -0.12065 -0.2794)
			(end 0.12065 -0.2794)
			(stroke
				(width 0.1)
				(type default)
			)
			(layer "F.Fab")
		)
		(fp_line
			(start -0.12065 -0.305054)
			(end -0.12065 -0.2794)
			(stroke
				(width 0.1)
				(type default)
			)
			(layer "F.Fab")
		)
		(fp_line
			(start -0.67945 0.3048)
			(end -0.67945 -0.305054)
			(stroke
				(width 0.1)
				(type default)
			)
			(layer "F.Fab")
		)
		(fp_line
			(start -0.67945 -0.305054)
			(end -0.12065 -0.305054)
			(stroke
				(width 0.1)
				(type default)
			)
			(layer "F.Fab")
		)
		(pad "1" smd circle
			(at -0.40005 0 180)
			(size 0 0)
			(layers "F.Cu" "F.Mask" "F.Paste")
			(net "PRSNT_GPU_A2_R_N")
		)
		(pad "2" smd circle
			(at 0.40005 0 180)
			(size 0 0)
			(layers "F.Cu" "F.Mask" "F.Paste")
			(net "PRSNT_GPU_A2_N")
		)
	)
	(footprint ""
		(layer "F.Cu")
		(at 110.49635 -79.822294 90)
		(property "Reference" "R1141"
			(at 0 0 90)
			(layer "F.SilkS")
			(hide yes)
			(effects
				(font
					(size 1.27 1.27)
				)
			)
		)
		(property "Value" ""
			(at 0 0 90)
			(layer "F.Fab")
			(effects
				(font
					(size 1.27 1.27)
				)
			)
		)
		(duplicate_pad_numbers_are_jumpers no)
		(fp_line
			(start 0.7874 0.4064)
			(end -0.7874 0.4064)
			(stroke
				(width 0.1524)
				(type default)
			)
			(layer "F.SilkS")
		)
		(fp_line
			(start -0.12065 -0.305054)
			(end -0.12065 -0.2794)
			(stroke
				(width 0.1)
				(type default)
			)
			(layer "F.Fab")
		)
		(fp_line
			(start -0.67945 -0.305054)
			(end -0.12065 -0.305054)
			(stroke
				(width 0.1)
				(type default)
			)
			(layer "F.Fab")
		)
		(fp_line
			(start 0.67945 -0.3048)
			(end 0.67945 0.3048)
			(stroke
				(width 0.1)
				(type default)
			)
			(layer "F.Fab")
		)
		(fp_line
			(start 0.12065 -0.3048)
			(end 0.67945 -0.3048)
			(stroke
				(width 0.1)
				(type default)
			)
			(layer "F.Fab")
		)
		(fp_line
			(start 0.12065 -0.2794)
			(end 0.12065 -0.3048)
			(stroke
				(width 0.1)
				(type default)
			)
			(layer "F.Fab")
		)
		(fp_line
			(start -0.12065 -0.2794)
			(end 0.12065 -0.2794)
			(stroke
				(width 0.1)
				(type default)
			)
			(layer "F.Fab")
		)
		(fp_line
			(start 0.120396 0.2794)
			(end -0.12065 0.2794)
			(stroke
				(width 0.1)
				(type default)
			)
			(layer "F.Fab")
		)
		(fp_line
			(start -0.12065 0.2794)
			(end -0.12065 0.3048)
			(stroke
				(width 0.1)
				(type default)
			)
			(layer "F.Fab")
		)
		(fp_line
			(start 0.67945 0.3048)
			(end 0.120396 0.3048)
			(stroke
				(width 0.1)
				(type default)
			)
			(layer "F.Fab")
		)
		(fp_line
			(start 0.120396 0.3048)
			(end 0.120396 0.2794)
			(stroke
				(width 0.1)
				(type default)
			)
			(layer "F.Fab")
		)
		(fp_line
			(start -0.12065 0.3048)
			(end -0.67945 0.3048)
			(stroke
				(width 0.1)
				(type default)
			)
			(layer "F.Fab")
		)
		(fp_line
			(start -0.67945 0.3048)
			(end -0.67945 -0.305054)
			(stroke
				(width 0.1)
				(type default)
			)
			(layer "F.Fab")
		)
		(pad "1" smd circle
			(at -0.40005 0 90)
			(size 0 0)
			(layers "F.Cu" "F.Mask" "F.Paste")
			(net "CLK_100M_DB800ZL_SSD2_R_DN")
		)
		(pad "2" smd circle
			(at 0.40005 0 90)
			(size 0 0)
			(layers "F.Cu" "F.Mask" "F.Paste")
			(net "CLK_100M_DB800ZL_SSD2_DN")
		)
	)
	(footprint ""
		(layer "F.Cu")
		(at 314.861448 -156.111194 180)
		(property "Reference" "C423"
			(at 0 0 180)
			(layer "F.SilkS")
			(hide yes)
			(effects
				(font
					(size 1.27 1.27)
				)
			)
		)
		(property "Value" ""
			(at 0 0 180)
			(layer "F.Fab")
			(effects
				(font
					(size 1.27 1.27)
				)
			)
		)
		(duplicate_pad_numbers_are_jumpers no)
		(fp_line
			(start 0.299974 0.150114)
			(end -0.299974 0.150114)
			(stroke
				(width 0.1)
				(type default)
			)
			(layer "F.Fab")
		)
		(fp_line
			(start 0.299974 -0.150114)
			(end 0.299974 0.150114)
			(stroke
				(width 0.1)
				(type default)
			)
			(layer "F.Fab")
		)
		(fp_line
			(start -0.299974 0.150114)
			(end -0.299974 -0.150114)
			(stroke
				(width 0.1)
				(type default)
			)
			(layer "F.Fab")
		)
		(fp_line
			(start -0.299974 -0.150114)
			(end 0.299974 -0.150114)
			(stroke
				(width 0.1)
				(type default)
			)
			(layer "F.Fab")
		)
		(pad "1" smd rect
			(at -0.2667 0 180)
			(size 0.3048 0.381)
			(layers "F.Cu" "F.Mask" "F.Paste")
			(net "P5E_PEX2_STN0_TX_DP<15>")
		)
		(pad "2" smd rect
			(at 0.2667 0 180)
			(size 0.3048 0.381)
			(layers "F.Cu" "F.Mask" "F.Paste")
			(net "P5E_PEX2_STN0_TX_C_DP<15>")
		)
	)
	(footprint ""
		(layer "F.Cu")
		(at 95.79229 -32.739584 180)
		(property "Reference" "C91"
			(at 0 0 180)
			(layer "F.SilkS")
			(hide yes)
			(effects
				(font
					(size 1.27 1.27)
				)
			)
		)
		(property "Value" ""
			(at 0 0 180)
			(layer "F.Fab")
			(effects
				(font
					(size 1.27 1.27)
				)
			)
		)
		(duplicate_pad_numbers_are_jumpers no)
		(fp_line
			(start 0.299974 0.150114)
			(end -0.299974 0.150114)
			(stroke
				(width 0.1)
				(type default)
			)
			(layer "F.Fab")
		)
		(fp_line
			(start 0.299974 -0.150114)
			(end 0.299974 0.150114)
			(stroke
				(width 0.1)
				(type default)
			)
			(layer "F.Fab")
		)
		(fp_line
			(start -0.299974 0.150114)
			(end -0.299974 -0.150114)
			(stroke
				(width 0.1)
				(type default)
			)
			(layer "F.Fab")
		)
		(fp_line
			(start -0.299974 -0.150114)
			(end 0.299974 -0.150114)
			(stroke
				(width 0.1)
				(type default)
			)
			(layer "F.Fab")
		)
		(pad "1" smd rect
			(at -0.2667 0 180)
			(size 0.3048 0.381)
			(layers "F.Cu" "F.Mask" "F.Paste")
			(net "P5E_PEX0_STN2_TX_DP<34>")
		)
		(pad "2" smd rect
			(at 0.2667 0 180)
			(size 0.3048 0.381)
			(layers "F.Cu" "F.Mask" "F.Paste")
			(net "P5E_PEX0_STN2_TX_C_DP<34>")
		)
	)
	(footprint ""
		(layer "F.Cu")
		(at 155.380436 -125.519942)
		(property "Reference" "C253"
			(at 0 0 0)
			(layer "F.SilkS")
			(hide yes)
			(effects
				(font
					(size 1.27 1.27)
				)
			)
		)
		(property "Value" ""
			(at 0 0 0)
			(layer "F.Fab")
			(effects
				(font
					(size 1.27 1.27)
				)
			)
		)
		(duplicate_pad_numbers_are_jumpers no)
		(fp_line
			(start -0.299974 -0.150114)
			(end 0.299974 -0.150114)
			(stroke
				(width 0.1)
				(type default)
			)
			(layer "F.Fab")
		)
		(fp_line
			(start -0.299974 0.150114)
			(end -0.299974 -0.150114)
			(stroke
				(width 0.1)
				(type default)
			)
			(layer "F.Fab")
		)
		(fp_line
			(start 0.299974 -0.150114)
			(end 0.299974 0.150114)
			(stroke
				(width 0.1)
				(type default)
			)
			(layer "F.Fab")
		)
		(fp_line
			(start 0.299974 0.150114)
			(end -0.299974 0.150114)
			(stroke
				(width 0.1)
				(type default)
			)
			(layer "F.Fab")
		)
		(pad "1" smd rect
			(at -0.2667 0)
			(size 0.3048 0.381)
			(layers "F.Cu" "F.Mask" "F.Paste")
			(net "P5E_PEX1_STN1_TX_DP<27>")
		)
		(pad "2" smd rect
			(at 0.2667 0)
			(size 0.3048 0.381)
			(layers "F.Cu" "F.Mask" "F.Paste")
			(net "P5E_PEX1_STN1_TX_C_DP<27>")
		)
	)
	(footprint ""
		(layer "F.Cu")
		(at 286.040068 -32.848042 90)
		(property "Reference" "PC955"
			(at 0 0 90)
			(layer "F.SilkS")
			(hide yes)
			(effects
				(font
					(size 1.27 1.27)
				)
			)
		)
		(property "Value" ""
			(at 0 0 90)
			(layer "F.Fab")
			(effects
				(font
					(size 1.27 1.27)
				)
			)
		)
		(duplicate_pad_numbers_are_jumpers no)
		(fp_line
			(start 0.7874 -0.4064)
			(end 0.7874 0.4064)
			(stroke
				(width 0.1524)
				(type default)
			)
			(layer "F.SilkS")
		)
		(fp_line
			(start -0.7874 -0.4064)
			(end 0.7874 -0.4064)
			(stroke
				(width 0.1524)
				(type default)
			)
			(layer "F.SilkS")
		)
		(fp_line
			(start 0.7874 0.4064)
			(end -0.7874 0.4064)
			(stroke
				(width 0.1524)
				(type default)
			)
			(layer "F.SilkS")
		)
		(fp_line
			(start -0.7874 0.4064)
			(end -0.7874 -0.4064)
			(stroke
				(width 0.1524)
				(type default)
			)
			(layer "F.SilkS")
		)
		(fp_line
			(start -0.12065 -0.305054)
			(end -0.12065 -0.2794)
			(stroke
				(width 0.1)
				(type default)
			)
			(layer "F.Fab")
		)
		(fp_line
			(start -0.67945 -0.305054)
			(end -0.12065 -0.305054)
			(stroke
				(width 0.1)
				(type default)
			)
			(layer "F.Fab")
		)
		(fp_line
			(start 0.67945 -0.3048)
			(end 0.67945 0.3048)
			(stroke
				(width 0.1)
				(type default)
			)
			(layer "F.Fab")
		)
		(fp_line
			(start 0.12065 -0.3048)
			(end 0.67945 -0.3048)
			(stroke
				(width 0.1)
				(type default)
			)
			(layer "F.Fab")
		)
		(fp_line
			(start 0.12065 -0.2794)
			(end 0.12065 -0.3048)
			(stroke
				(width 0.1)
				(type default)
			)
			(layer "F.Fab")
		)
		(fp_line
			(start -0.12065 -0.2794)
			(end 0.12065 -0.2794)
			(stroke
				(width 0.1)
				(type default)
			)
			(layer "F.Fab")
		)
		(fp_line
			(start 0.120396 0.2794)
			(end -0.12065 0.2794)
			(stroke
				(width 0.1)
				(type default)
			)
			(layer "F.Fab")
		)
		(fp_line
			(start -0.12065 0.2794)
			(end -0.12065 0.3048)
			(stroke
				(width 0.1)
				(type default)
			)
			(layer "F.Fab")
		)
		(fp_line
			(start 0.67945 0.3048)
			(end 0.120396 0.3048)
			(stroke
				(width 0.1)
				(type default)
			)
			(layer "F.Fab")
		)
		(fp_line
			(start 0.120396 0.3048)
			(end 0.120396 0.2794)
			(stroke
				(width 0.1)
				(type default)
			)
			(layer "F.Fab")
		)
		(fp_line
			(start -0.12065 0.3048)
			(end -0.67945 0.3048)
			(stroke
				(width 0.1)
				(type default)
			)
			(layer "F.Fab")
		)
		(fp_line
			(start -0.67945 0.3048)
			(end -0.67945 -0.305054)
			(stroke
				(width 0.1)
				(type default)
			)
			(layer "F.Fab")
		)
		(pad "1" smd circle
			(at -0.40005 0 90)
			(size 0 0)
			(layers "F.Cu" "F.Mask" "F.Paste")
			(net "P3V3_SSD10_CO_DV_DT")
		)
		(pad "2" smd circle
			(at 0.40005 0 90)
			(size 0 0)
			(layers "F.Cu" "F.Mask" "F.Paste")
			(net "GND")
		)
	)
	(footprint ""
		(layer "F.Cu")
		(at 384.60553 -238.561118 90)
		(property "Reference" "U70"
			(at -6.050788 4.82727 0)
			(unlocked yes)
			(layer "F.SilkS")
			(effects
				(font
					(size 0.7874 0.5842)
					(thickness 0.1524)
				)
				(justify left)
			)
		)
		(property "Value" ""
			(at 0 0 90)
			(layer "F.Fab")
			(effects
				(font
					(size 1.27 1.27)
				)
			)
		)
		(duplicate_pad_numbers_are_jumpers no)
		(fp_line
			(start 5.050028 -5.050028)
			(end 4.0386 -5.050028)
			(stroke
				(width 0.1524)
				(type default)
			)
			(layer "F.SilkS")
		)
		(fp_line
			(start -4.0386 -5.050028)
			(end -5.050028 -5.050028)
			(stroke
				(width 0.1524)
				(type default)
			)
			(layer "F.SilkS")
		)
		(fp_line
			(start -5.050028 -5.050028)
			(end -5.050028 -4.0386)
			(stroke
				(width 0.1524)
				(type default)
			)
			(layer "F.SilkS")
		)
		(fp_line
			(start 5.050028 -4.0386)
			(end 5.050028 -5.050028)
			(stroke
				(width 0.1524)
				(type default)
			)
			(layer "F.SilkS")
		)
		(fp_line
			(start -5.050028 4.0386)
			(end -5.050028 5.050028)
			(stroke
				(width 0.1524)
				(type default)
			)
			(layer "F.SilkS")
		)
		(fp_line
			(start 5.050028 5.050028)
			(end 5.050028 4.0386)
			(stroke
				(width 0.1524)
				(type default)
			)
			(layer "F.SilkS")
		)
		(fp_line
			(start 4.0386 5.050028)
			(end 5.050028 5.050028)
			(stroke
				(width 0.1524)
				(type default)
			)
			(layer "F.SilkS")
		)
		(fp_line
			(start -5.050028 5.050028)
			(end -4.0386 5.050028)
			(stroke
				(width 0.1524)
				(type default)
			)
			(layer "F.SilkS")
		)
		(fp_poly
			(pts
				(xy -5.535676 -5.262372) (xy -6.551676 -5.262372) (xy -6.043676 -4.246372)
			)
			(stroke
				(width 0)
				(type default)
			)
			(fill yes)
			(layer "F.SilkS")
		)
		(fp_line
			(start 5.050028 -5.050028)
			(end -5.050028 -5.050028)
			(stroke
				(width 0.1)
				(type default)
			)
			(layer "F.Fab")
		)
		(fp_line
			(start -5.050028 -5.050028)
			(end -5.050028 5.050028)
			(stroke
				(width 0.1)
				(type default)
			)
			(layer "F.Fab")
		)
		(fp_line
			(start 5.050028 5.050028)
			(end 5.050028 -5.050028)
			(stroke
				(width 0.1)
				(type default)
			)
			(layer "F.Fab")
		)
		(fp_line
			(start -5.050028 5.050028)
			(end 5.050028 5.050028)
			(stroke
				(width 0.1)
				(type default)
			)
			(layer "F.Fab")
		)
		(fp_poly
			(pts
				(xy -7.62 -4.258056) (xy -7.62 -3.242056) (xy -6.604 -3.750056)
			)
			(stroke
				(width 0)
				(type default)
			)
			(fill yes)
			(layer "F.Fab")
		)
		(pad "1" smd rect
			(at -5.724906 -3.750056)
			(size 0.2794 1.3716)
			(layers "F.Cu" "F.Mask" "F.Paste")
			(net "GND")
		)
		(pad "2" smd rect
			(at -5.724906 -3.24993)
			(size 0.2794 1.3716)
			(layers "F.Cu" "F.Mask" "F.Paste")
			(net "OSC_SDB_IN")
		)
		(pad "3" smd rect
			(at -5.724906 -2.750058)
			(size 0.2794 1.3716)
			(layers "F.Cu" "F.Mask" "F.Paste")
			(net "OSC_SDB_OUT")
		)
		(pad "4" smd rect
			(at -5.724906 -2.249932)
			(size 0.2794 1.3716)
			(layers "F.Cu" "F.Mask" "F.Paste")
			(net "P3V3_SDB_VPHY")
		)
		(pad "5" smd rect
			(at -5.724906 -1.75006)
			(size 0.2794 1.3716)
			(layers "F.Cu" "F.Mask" "F.Paste")
			(net "GND")
		)
		(pad "6" smd rect
			(at -5.724906 -1.249934)
			(size 0.2794 1.3716)
			(layers "F.Cu" "F.Mask" "F.Paste")
			(net "FT4232_SDB_REF")
		)
		(pad "7" smd rect
			(at -5.724906 -0.750062)
			(size 0.2794 1.3716)
			(layers "F.Cu" "F.Mask" "F.Paste")
			(net "USB2_FT4232_SDB_DN")
		)
		(pad "8" smd rect
			(at -5.724906 -0.249936)
			(size 0.2794 1.3716)
			(layers "F.Cu" "F.Mask" "F.Paste")
			(net "USB2_FT4232_SDB_DP")
		)
		(pad "9" smd rect
			(at -5.724906 0.249936)
			(size 0.2794 1.3716)
			(layers "F.Cu" "F.Mask" "F.Paste")
			(net "P3V3_SDB_VPLL")
		)
		(pad "10" smd rect
			(at -5.724906 0.750062)
			(size 0.2794 1.3716)
			(layers "F.Cu" "F.Mask" "F.Paste")
			(net "GND")
		)
		(pad "11" smd rect
			(at -5.724906 1.249934)
			(size 0.2794 1.3716)
			(layers "F.Cu" "F.Mask" "F.Paste")
			(net "GND")
		)
		(pad "12" smd rect
			(at -5.724906 1.75006)
			(size 0.2794 1.3716)
			(layers "F.Cu" "F.Mask" "F.Paste")
			(net "P1V8_SDB_VCORE")
		)
		(pad "13" smd rect
			(at -5.724906 2.249932)
			(size 0.2794 1.3716)
			(layers "F.Cu" "F.Mask" "F.Paste")
			(net "GND")
		)
		(pad "14" smd rect
			(at -5.724906 2.750058)
			(size 0.2794 1.3716)
			(layers "F.Cu" "F.Mask" "F.Paste")
			(net "RST_FT4232_SDB_R_N")
		)
		(pad "15" smd rect
			(at -5.724906 3.24993)
			(size 0.2794 1.3716)
			(layers "F.Cu" "F.Mask" "F.Paste")
			(net "GND")
		)
		(pad "16" smd rect
			(at -5.724906 3.750056)
			(size 0.2794 1.3716)
			(layers "F.Cu" "F.Mask" "F.Paste")
			(net "UART_PEX0_SDB_RX")
		)
		(pad "17" smd rect
			(at -3.750056 5.724906 90)
			(size 0.2794 1.3716)
			(layers "F.Cu" "F.Mask" "F.Paste")
			(net "UART_PEX0_SDB_BUF_TX")
		)
		(pad "18" smd rect
			(at -3.24993 5.724906 90)
			(size 0.2794 1.3716)
			(layers "F.Cu" "F.Mask" "F.Paste")
			(net "Net_8958")
		)
		(pad "19" smd rect
			(at -2.750058 5.724906 90)
			(size 0.2794 1.3716)
			(layers "F.Cu" "F.Mask" "F.Paste")
			(net "Net_8957")
		)
		(pad "20" smd rect
			(at -2.249932 5.724906 90)
			(size 0.2794 1.3716)
			(layers "F.Cu" "F.Mask" "F.Paste")
			(net "P3V3_AUX")
		)
		(pad "21" smd rect
			(at -1.75006 5.724906 90)
			(size 0.2794 1.3716)
			(layers "F.Cu" "F.Mask" "F.Paste")
			(net "Net_8956")
		)
		(pad "22" smd rect
			(at -1.249934 5.724906 90)
			(size 0.2794 1.3716)
			(layers "F.Cu" "F.Mask" "F.Paste")
			(net "Net_8955")
		)
		(pad "23" smd rect
			(at -0.750062 5.724906 90)
			(size 0.2794 1.3716)
			(layers "F.Cu" "F.Mask" "F.Paste")
			(net "Net_8954")
		)
		(pad "24" smd rect
			(at -0.249936 5.724906 90)
			(size 0.2794 1.3716)
			(layers "F.Cu" "F.Mask" "F.Paste")
			(net "Net_8953")
		)
		(pad "25" smd rect
			(at 0.249936 5.724906 90)
			(size 0.2794 1.3716)
			(layers "F.Cu" "F.Mask" "F.Paste")
			(net "GND")
		)
		(pad "26" smd rect
			(at 0.750062 5.724906 90)
			(size 0.2794 1.3716)
			(layers "F.Cu" "F.Mask" "F.Paste")
			(net "UART_PEX1_SDB_RX")
		)
		(pad "27" smd rect
			(at 1.249934 5.724906 90)
			(size 0.2794 1.3716)
			(layers "F.Cu" "F.Mask" "F.Paste")
			(net "UART_PEX1_SDB_BUF_TX")
		)
		(pad "28" smd rect
			(at 1.75006 5.724906 90)
			(size 0.2794 1.3716)
			(layers "F.Cu" "F.Mask" "F.Paste")
			(net "Net_8952")
		)
		(pad "29" smd rect
			(at 2.249932 5.724906 90)
			(size 0.2794 1.3716)
			(layers "F.Cu" "F.Mask" "F.Paste")
			(net "Net_8951")
		)
		(pad "30" smd rect
			(at 2.750058 5.724906 90)
			(size 0.2794 1.3716)
			(layers "F.Cu" "F.Mask" "F.Paste")
			(net "Net_8950")
		)
		(pad "31" smd rect
			(at 3.24993 5.724906 90)
			(size 0.2794 1.3716)
			(layers "F.Cu" "F.Mask" "F.Paste")
			(net "P3V3_AUX")
		)
		(pad "32" smd rect
			(at 3.750056 5.724906 90)
			(size 0.2794 1.3716)
			(layers "F.Cu" "F.Mask" "F.Paste")
			(net "Net_8949")
		)
		(pad "33" smd rect
			(at 5.724906 3.750056)
			(size 0.2794 1.3716)
			(layers "F.Cu" "F.Mask" "F.Paste")
			(net "Net_8948")
		)
		(pad "34" smd rect
			(at 5.724906 3.24993)
			(size 0.2794 1.3716)
			(layers "F.Cu" "F.Mask" "F.Paste")
			(net "Net_8947")
		)
		(pad "35" smd rect
			(at 5.724906 2.750058)
			(size 0.2794 1.3716)
			(layers "F.Cu" "F.Mask" "F.Paste")
			(net "GND")
		)
		(pad "36" smd rect
			(at 5.724906 2.249932)
			(size 0.2794 1.3716)
			(layers "F.Cu" "F.Mask" "F.Paste")
			(net "Net_8933")
		)
		(pad "37" smd rect
			(at 5.724906 1.75006)
			(size 0.2794 1.3716)
			(layers "F.Cu" "F.Mask" "F.Paste")
			(net "P1V8_SDB_VCORE")
		)
		(pad "38" smd rect
			(at 5.724906 1.249934)
			(size 0.2794 1.3716)
			(layers "F.Cu" "F.Mask" "F.Paste")
			(net "UART_PEX2_SDB_RX")
		)
		(pad "39" smd rect
			(at 5.724906 0.750062)
			(size 0.2794 1.3716)
			(layers "F.Cu" "F.Mask" "F.Paste")
			(net "UART_PEX2_SDB_BUF_TX")
		)
		(pad "40" smd rect
			(at 5.724906 0.249936)
			(size 0.2794 1.3716)
			(layers "F.Cu" "F.Mask" "F.Paste")
			(net "Net_8946")
		)
		(pad "41" smd rect
			(at 5.724906 -0.249936)
			(size 0.2794 1.3716)
			(layers "F.Cu" "F.Mask" "F.Paste")
			(net "Net_8945")
		)
		(pad "42" smd rect
			(at 5.724906 -0.750062)
			(size 0.2794 1.3716)
			(layers "F.Cu" "F.Mask" "F.Paste")
			(net "P3V3_AUX")
		)
		(pad "43" smd rect
			(at 5.724906 -1.249934)
			(size 0.2794 1.3716)
			(layers "F.Cu" "F.Mask" "F.Paste")
			(net "Net_8944")
		)
		(pad "44" smd rect
			(at 5.724906 -1.75006)
			(size 0.2794 1.3716)
			(layers "F.Cu" "F.Mask" "F.Paste")
			(net "Net_8943")
		)
		(pad "45" smd rect
			(at 5.724906 -2.249932)
			(size 0.2794 1.3716)
			(layers "F.Cu" "F.Mask" "F.Paste")
			(net "Net_8942")
		)
		(pad "46" smd rect
			(at 5.724906 -2.750058)
			(size 0.2794 1.3716)
			(layers "F.Cu" "F.Mask" "F.Paste")
			(net "Net_8941")
		)
		(pad "47" smd rect
			(at 5.724906 -3.24993)
			(size 0.2794 1.3716)
			(layers "F.Cu" "F.Mask" "F.Paste")
			(net "GND")
		)
		(pad "48" smd rect
			(at 5.724906 -3.750056)
			(size 0.2794 1.3716)
			(layers "F.Cu" "F.Mask" "F.Paste")
			(net "UART_PEX3_SDB_RX")
		)
		(pad "49" smd rect
			(at 3.750056 -5.724906 90)
			(size 0.2794 1.3716)
			(layers "F.Cu" "F.Mask" "F.Paste")
			(net "P1V8_SDB_VCORE")
		)
		(pad "50" smd rect
			(at 3.24993 -5.724906 90)
			(size 0.2794 1.3716)
			(layers "F.Cu" "F.Mask" "F.Paste")
			(net "P3V3_AUX")
		)
		(pad "51" smd rect
			(at 2.750058 -5.724906 90)
			(size 0.2794 1.3716)
			(layers "F.Cu" "F.Mask" "F.Paste")
			(net "GND")
		)
		(pad "52" smd rect
			(at 2.249932 -5.724906 90)
			(size 0.2794 1.3716)
			(layers "F.Cu" "F.Mask" "F.Paste")
			(net "UART_PEX3_SDB_BUF_TX")
		)
		(pad "53" smd rect
			(at 1.75006 -5.724906 90)
			(size 0.2794 1.3716)
			(layers "F.Cu" "F.Mask" "F.Paste")
			(net "Net_8940")
		)
		(pad "54" smd rect
			(at 1.249934 -5.724906 90)
			(size 0.2794 1.3716)
			(layers "F.Cu" "F.Mask" "F.Paste")
			(net "Net_8939")
		)
		(pad "55" smd rect
			(at 0.750062 -5.724906 90)
			(size 0.2794 1.3716)
			(layers "F.Cu" "F.Mask" "F.Paste")
			(net "Net_8938")
		)
		(pad "56" smd rect
			(at 0.249936 -5.724906 90)
			(size 0.2794 1.3716)
			(layers "F.Cu" "F.Mask" "F.Paste")
			(net "P3V3_AUX")
		)
		(pad "57" smd rect
			(at -0.249936 -5.724906 90)
			(size 0.2794 1.3716)
			(layers "F.Cu" "F.Mask" "F.Paste")
			(net "Net_8937")
		)
		(pad "58" smd rect
			(at -0.750062 -5.724906 90)
			(size 0.2794 1.3716)
			(layers "F.Cu" "F.Mask" "F.Paste")
			(net "Net_8936")
		)
		(pad "59" smd rect
			(at -1.249934 -5.724906 90)
			(size 0.2794 1.3716)
			(layers "F.Cu" "F.Mask" "F.Paste")
			(net "Net_8935")
		)
		(pad "60" smd rect
			(at -1.75006 -5.724906 90)
			(size 0.2794 1.3716)
			(layers "F.Cu" "F.Mask" "F.Paste")
			(net "Net_8934")
		)
		(pad "61" smd rect
			(at -2.249932 -5.724906 90)
			(size 0.2794 1.3716)
			(layers "F.Cu" "F.Mask" "F.Paste")
			(net "FT4232_SDB_EEPROM_SDA")
		)
		(pad "62" smd rect
			(at -2.750058 -5.724906 90)
			(size 0.2794 1.3716)
			(layers "F.Cu" "F.Mask" "F.Paste")
			(net "FT4232_SDB_EEPROM_SCL")
		)
		(pad "63" smd rect
			(at -3.24993 -5.724906 90)
			(size 0.2794 1.3716)
			(layers "F.Cu" "F.Mask" "F.Paste")
			(net "FT4232_SDB_EEPROM_CS")
		)
		(pad "64" smd rect
			(at -3.750056 -5.724906 90)
			(size 0.2794 1.3716)
			(layers "F.Cu" "F.Mask" "F.Paste")
			(net "P1V8_SDB_VCORE")
		)
	)
	(footprint ""
		(layer "F.Cu")
		(at 348.04731 -253.178564 180)
		(property "Reference" "PC127"
			(at 0 0 180)
			(layer "F.SilkS")
			(hide yes)
			(effects
				(font
					(size 1.27 1.27)
				)
			)
		)
		(property "Value" ""
			(at 0 0 180)
			(layer "F.Fab")
			(effects
				(font
					(size 1.27 1.27)
				)
			)
		)
		(duplicate_pad_numbers_are_jumpers no)
		(fp_line
			(start 1.524 0.762)
			(end -1.524 0.762)
			(stroke
				(width 0.1524)
				(type default)
			)
			(layer "F.SilkS")
		)
		(fp_line
			(start 1.524 -0.762)
			(end 1.524 0.762)
			(stroke
				(width 0.1524)
				(type default)
			)
			(layer "F.SilkS")
		)
		(fp_line
			(start -1.524 0.762)
			(end -1.524 -0.762)
			(stroke
				(width 0.1524)
				(type default)
			)
			(layer "F.SilkS")
		)
		(fp_line
			(start -1.524 -0.762)
			(end 1.524 -0.762)
			(stroke
				(width 0.1524)
				(type default)
			)
			(layer "F.SilkS")
		)
		(fp_line
			(start 1.1049 0.724916)
			(end 1.1049 -0.724916)
			(stroke
				(width 0.1)
				(type default)
			)
			(layer "F.Fab")
		)
		(fp_line
			(start 1.1049 -0.724916)
			(end -1.1049 -0.724916)
			(stroke
				(width 0.1)
				(type default)
			)
			(layer "F.Fab")
		)
		(fp_line
			(start -1.1049 0.724916)
			(end 1.1049 0.724916)
			(stroke
				(width 0.1)
				(type default)
			)
			(layer "F.Fab")
		)
		(fp_line
			(start -1.1049 -0.724916)
			(end -1.1049 0.724916)
			(stroke
				(width 0.1)
				(type default)
			)
			(layer "F.Fab")
		)
		(pad "1" smd rect
			(at -0.889 0)
			(size 1.016 1.27)
			(layers "F.Cu" "F.Mask" "F.Paste")
			(net "P0V8_PEX2_VREF")
		)
		(pad "2" smd rect
			(at 0.889 0)
			(size 1.016 1.27)
			(layers "F.Cu" "F.Mask" "F.Paste")
			(net "GND")
		)
	)
	(footprint ""
		(layer "F.Cu")
		(at 68.479162 -356.244906 90)
		(property "Reference" "C136"
			(at 0 0 90)
			(layer "F.SilkS")
			(hide yes)
			(effects
				(font
					(size 1.27 1.27)
				)
			)
		)
		(property "Value" ""
			(at 0 0 90)
			(layer "F.Fab")
			(effects
				(font
					(size 1.27 1.27)
				)
			)
		)
		(duplicate_pad_numbers_are_jumpers no)
		(fp_line
			(start 0.299974 -0.150114)
			(end 0.299974 0.150114)
			(stroke
				(width 0.1)
				(type default)
			)
			(layer "F.Fab")
		)
		(fp_line
			(start -0.299974 -0.150114)
			(end 0.299974 -0.150114)
			(stroke
				(width 0.1)
				(type default)
			)
			(layer "F.Fab")
		)
		(fp_line
			(start 0.299974 0.150114)
			(end -0.299974 0.150114)
			(stroke
				(width 0.1)
				(type default)
			)
			(layer "F.Fab")
		)
		(fp_line
			(start -0.299974 0.150114)
			(end -0.299974 -0.150114)
			(stroke
				(width 0.1)
				(type default)
			)
			(layer "F.Fab")
		)
		(pad "1" smd rect
			(at -0.2667 0 90)
			(size 0.3048 0.381)
			(layers "F.Cu" "F.Mask" "F.Paste")
			(net "P5E_PEX0_STN6_TX_DN<108>")
		)
		(pad "2" smd rect
			(at 0.2667 0 90)
			(size 0.3048 0.381)
			(layers "F.Cu" "F.Mask" "F.Paste")
			(net "P5E_PEX0_STN6_TX_C_DN<108>")
		)
	)
	(footprint ""
		(layer "F.Cu")
		(at 1.978406 -26.670254 180)
		(property "Reference" "C2712"
			(at 0 0 180)
			(layer "F.SilkS")
			(hide yes)
			(effects
				(font
					(size 1.27 1.27)
				)
			)
		)
		(property "Value" ""
			(at 0 0 180)
			(layer "F.Fab")
			(effects
				(font
					(size 1.27 1.27)
				)
			)
		)
		(duplicate_pad_numbers_are_jumpers no)
		(fp_line
			(start 0.7874 0.4064)
			(end -0.7874 0.4064)
			(stroke
				(width 0.1524)
				(type default)
			)
			(layer "F.SilkS")
		)
		(fp_line
			(start 0.7874 -0.4064)
			(end 0.7874 0.4064)
			(stroke
				(width 0.1524)
				(type default)
			)
			(layer "F.SilkS")
		)
		(fp_line
			(start -0.7874 0.4064)
			(end -0.7874 -0.4064)
			(stroke
				(width 0.1524)
				(type default)
			)
			(layer "F.SilkS")
		)
		(fp_line
			(start -0.7874 -0.4064)
			(end 0.7874 -0.4064)
			(stroke
				(width 0.1524)
				(type default)
			)
			(layer "F.SilkS")
		)
		(fp_line
			(start 0.67945 0.3048)
			(end 0.120396 0.3048)
			(stroke
				(width 0.1)
				(type default)
			)
			(layer "F.Fab")
		)
		(fp_line
			(start 0.67945 -0.3048)
			(end 0.67945 0.3048)
			(stroke
				(width 0.1)
				(type default)
			)
			(layer "F.Fab")
		)
		(fp_line
			(start 0.12065 -0.2794)
			(end 0.12065 -0.3048)
			(stroke
				(width 0.1)
				(type default)
			)
			(layer "F.Fab")
		)
		(fp_line
			(start 0.12065 -0.3048)
			(end 0.67945 -0.3048)
			(stroke
				(width 0.1)
				(type default)
			)
			(layer "F.Fab")
		)
		(fp_line
			(start 0.120396 0.3048)
			(end 0.120396 0.2794)
			(stroke
				(width 0.1)
				(type default)
			)
			(layer "F.Fab")
		)
		(fp_line
			(start 0.120396 0.2794)
			(end -0.12065 0.2794)
			(stroke
				(width 0.1)
				(type default)
			)
			(layer "F.Fab")
		)
		(fp_line
			(start -0.12065 0.3048)
			(end -0.67945 0.3048)
			(stroke
				(width 0.1)
				(type default)
			)
			(layer "F.Fab")
		)
		(fp_line
			(start -0.12065 0.2794)
			(end -0.12065 0.3048)
			(stroke
				(width 0.1)
				(type default)
			)
			(layer "F.Fab")
		)
		(fp_line
			(start -0.12065 -0.2794)
			(end 0.12065 -0.2794)
			(stroke
				(width 0.1)
				(type default)
			)
			(layer "F.Fab")
		)
		(fp_line
			(start -0.12065 -0.305054)
			(end -0.12065 -0.2794)
			(stroke
				(width 0.1)
				(type default)
			)
			(layer "F.Fab")
		)
		(fp_line
			(start -0.67945 0.3048)
			(end -0.67945 -0.305054)
			(stroke
				(width 0.1)
				(type default)
			)
			(layer "F.Fab")
		)
		(fp_line
			(start -0.67945 -0.305054)
			(end -0.12065 -0.305054)
			(stroke
				(width 0.1)
				(type default)
			)
			(layer "F.Fab")
		)
		(pad "1" smd circle
			(at -0.40005 0 180)
			(size 0 0)
			(layers "F.Cu" "F.Mask" "F.Paste")
			(net "GND")
		)
		(pad "2" smd circle
			(at 0.40005 0 180)
			(size 0 0)
			(layers "F.Cu" "F.Mask" "F.Paste")
			(net "P3V3_SSD0")
		)
	)
	(footprint ""
		(layer "F.Cu")
		(at 338.074 -173.101 180)
		(property "Reference" "R4781"
			(at 0 0 180)
			(layer "F.SilkS")
			(hide yes)
			(effects
				(font
					(size 1.27 1.27)
				)
			)
		)
		(property "Value" ""
			(at 0 0 180)
			(layer "F.Fab")
			(effects
				(font
					(size 1.27 1.27)
				)
			)
		)
		(duplicate_pad_numbers_are_jumpers no)
		(fp_line
			(start 0.7874 0.4064)
			(end -0.7874 0.4064)
			(stroke
				(width 0.1524)
				(type default)
			)
			(layer "F.SilkS")
		)
		(fp_line
			(start 0.7874 -0.4064)
			(end 0.7874 0.4064)
			(stroke
				(width 0.1524)
				(type default)
			)
			(layer "F.SilkS")
		)
		(fp_line
			(start -0.7874 0.4064)
			(end -0.7874 -0.4064)
			(stroke
				(width 0.1524)
				(type default)
			)
			(layer "F.SilkS")
		)
		(fp_line
			(start -0.7874 -0.4064)
			(end 0.7874 -0.4064)
			(stroke
				(width 0.1524)
				(type default)
			)
			(layer "F.SilkS")
		)
		(fp_line
			(start 0.67945 0.3048)
			(end 0.120396 0.3048)
			(stroke
				(width 0.1)
				(type default)
			)
			(layer "F.Fab")
		)
		(fp_line
			(start 0.67945 -0.3048)
			(end 0.67945 0.3048)
			(stroke
				(width 0.1)
				(type default)
			)
			(layer "F.Fab")
		)
		(fp_line
			(start 0.12065 -0.2794)
			(end 0.12065 -0.3048)
			(stroke
				(width 0.1)
				(type default)
			)
			(layer "F.Fab")
		)
		(fp_line
			(start 0.12065 -0.3048)
			(end 0.67945 -0.3048)
			(stroke
				(width 0.1)
				(type default)
			)
			(layer "F.Fab")
		)
		(fp_line
			(start 0.120396 0.3048)
			(end 0.120396 0.2794)
			(stroke
				(width 0.1)
				(type default)
			)
			(layer "F.Fab")
		)
		(fp_line
			(start 0.120396 0.2794)
			(end -0.12065 0.2794)
			(stroke
				(width 0.1)
				(type default)
			)
			(layer "F.Fab")
		)
		(fp_line
			(start -0.12065 0.3048)
			(end -0.67945 0.3048)
			(stroke
				(width 0.1)
				(type default)
			)
			(layer "F.Fab")
		)
		(fp_line
			(start -0.12065 0.2794)
			(end -0.12065 0.3048)
			(stroke
				(width 0.1)
				(type default)
			)
			(layer "F.Fab")
		)
		(fp_line
			(start -0.12065 -0.2794)
			(end 0.12065 -0.2794)
			(stroke
				(width 0.1)
				(type default)
			)
			(layer "F.Fab")
		)
		(fp_line
			(start -0.12065 -0.305054)
			(end -0.12065 -0.2794)
			(stroke
				(width 0.1)
				(type default)
			)
			(layer "F.Fab")
		)
		(fp_line
			(start -0.67945 0.3048)
			(end -0.67945 -0.305054)
			(stroke
				(width 0.1)
				(type default)
			)
			(layer "F.Fab")
		)
		(fp_line
			(start -0.67945 -0.305054)
			(end -0.12065 -0.305054)
			(stroke
				(width 0.1)
				(type default)
			)
			(layer "F.Fab")
		)
		(pad "1" smd circle
			(at -0.40005 0 180)
			(size 0 0)
			(layers "F.Cu" "F.Mask" "F.Paste")
			(net "GND")
		)
		(pad "2" smd circle
			(at 0.40005 0 180)
			(size 0 0)
			(layers "F.Cu" "F.Mask" "F.Paste")
			(net "PCA9555_1_PEX2_A1")
		)
	)
	(footprint ""
		(layer "F.Cu")
		(at 147.394168 -35.264852)
		(property "Reference" "R5668"
			(at 0 0 0)
			(layer "F.SilkS")
			(hide yes)
			(effects
				(font
					(size 1.27 1.27)
				)
			)
		)
		(property "Value" ""
			(at 0 0 0)
			(layer "F.Fab")
			(effects
				(font
					(size 1.27 1.27)
				)
			)
		)
		(duplicate_pad_numbers_are_jumpers no)
		(fp_line
			(start -0.7874 -0.4064)
			(end 0.7874 -0.4064)
			(stroke
				(width 0.1524)
				(type default)
			)
			(layer "F.SilkS")
		)
		(fp_line
			(start -0.7874 0.4064)
			(end -0.7874 -0.4064)
			(stroke
				(width 0.1524)
				(type default)
			)
			(layer "F.SilkS")
		)
		(fp_line
			(start 0.7874 -0.4064)
			(end 0.7874 0.4064)
			(stroke
				(width 0.1524)
				(type default)
			)
			(layer "F.SilkS")
		)
		(fp_line
			(start 0.7874 0.4064)
			(end -0.7874 0.4064)
			(stroke
				(width 0.1524)
				(type default)
			)
			(layer "F.SilkS")
		)
		(fp_line
			(start -0.67945 -0.305054)
			(end -0.12065 -0.305054)
			(stroke
				(width 0.1)
				(type default)
			)
			(layer "F.Fab")
		)
		(fp_line
			(start -0.67945 0.3048)
			(end -0.67945 -0.305054)
			(stroke
				(width 0.1)
				(type default)
			)
			(layer "F.Fab")
		)
		(fp_line
			(start -0.12065 -0.305054)
			(end -0.12065 -0.2794)
			(stroke
				(width 0.1)
				(type default)
			)
			(layer "F.Fab")
		)
		(fp_line
			(start -0.12065 -0.2794)
			(end 0.12065 -0.2794)
			(stroke
				(width 0.1)
				(type default)
			)
			(layer "F.Fab")
		)
		(fp_line
			(start -0.12065 0.2794)
			(end -0.12065 0.3048)
			(stroke
				(width 0.1)
				(type default)
			)
			(layer "F.Fab")
		)
		(fp_line
			(start -0.12065 0.3048)
			(end -0.67945 0.3048)
			(stroke
				(width 0.1)
				(type default)
			)
			(layer "F.Fab")
		)
		(fp_line
			(start 0.120396 0.2794)
			(end -0.12065 0.2794)
			(stroke
				(width 0.1)
				(type default)
			)
			(layer "F.Fab")
		)
		(fp_line
			(start 0.120396 0.3048)
			(end 0.120396 0.2794)
			(stroke
				(width 0.1)
				(type default)
			)
			(layer "F.Fab")
		)
		(fp_line
			(start 0.12065 -0.3048)
			(end 0.67945 -0.3048)
			(stroke
				(width 0.1)
				(type default)
			)
			(layer "F.Fab")
		)
		(fp_line
			(start 0.12065 -0.2794)
			(end 0.12065 -0.3048)
			(stroke
				(width 0.1)
				(type default)
			)
			(layer "F.Fab")
		)
		(fp_line
			(start 0.67945 -0.3048)
			(end 0.67945 0.3048)
			(stroke
				(width 0.1)
				(type default)
			)
			(layer "F.Fab")
		)
		(fp_line
			(start 0.67945 0.3048)
			(end 0.120396 0.3048)
			(stroke
				(width 0.1)
				(type default)
			)
			(layer "F.Fab")
		)
		(pad "1" smd circle
			(at -0.40005 0)
			(size 0 0)
			(layers "F.Cu" "F.Mask" "F.Paste")
			(net "RST_SMB_SSD5_ISO_N")
		)
		(pad "2" smd circle
			(at 0.40005 0)
			(size 0 0)
			(layers "F.Cu" "F.Mask" "F.Paste")
			(net "GND")
		)
	)
	(footprint ""
		(layer "F.Cu")
		(at 93.201236 -55.78475 -90)
		(property "Reference" "PD34"
			(at 3.91795 2.115566 90)
			(unlocked yes)
			(layer "F.SilkS")
			(effects
				(font
					(size 0.7874 0.5842)
					(thickness 0.1524)
				)
				(justify left)
			)
		)
		(property "Value" ""
			(at 0 0 270)
			(layer "F.Fab")
			(effects
				(font
					(size 1.27 1.27)
				)
			)
		)
		(duplicate_pad_numbers_are_jumpers no)
		(fp_line
			(start -3.400044 1.459992)
			(end -3.400044 -1.459992)
			(stroke
				(width 0.1524)
				(type default)
			)
			(layer "F.SilkS")
		)
		(fp_line
			(start 4.107942 1.459992)
			(end -3.400044 1.459992)
			(stroke
				(width 0.1524)
				(type default)
			)
			(layer "F.SilkS")
		)
		(fp_line
			(start -3.400044 -1.459992)
			(end 4.107942 -1.459992)
			(stroke
				(width 0.1524)
				(type default)
			)
			(layer "F.SilkS")
		)
		(fp_line
			(start 4.107942 -1.459992)
			(end 4.107942 1.459992)
			(stroke
				(width 0.1524)
				(type default)
			)
			(layer "F.SilkS")
		)
		(fp_poly
			(pts
				(xy 4.107942 -1.459992) (xy 4.107942 1.459992) (xy 3.308096 1.459992) (xy 3.308096 -1.459992)
			)
			(stroke
				(width 0)
				(type default)
			)
			(fill yes)
			(layer "F.SilkS")
		)
		(fp_line
			(start -2.29997 1.459992)
			(end -2.29997 -1.459992)
			(stroke
				(width 0.1)
				(type default)
			)
			(layer "F.Fab")
		)
		(fp_line
			(start 2.29997 1.459992)
			(end -2.29997 1.459992)
			(stroke
				(width 0.1)
				(type default)
			)
			(layer "F.Fab")
		)
		(fp_line
			(start -2.29997 -1.459992)
			(end 2.29997 -1.459992)
			(stroke
				(width 0.1)
				(type default)
			)
			(layer "F.Fab")
		)
		(fp_line
			(start 2.29997 -1.459992)
			(end 2.29997 1.459992)
			(stroke
				(width 0.1)
				(type default)
			)
			(layer "F.Fab")
		)
		(fp_text user "-"
			(at 5.4102 0.29845 90)
			(unlocked yes)
			(layer "F.SilkS")
			(effects
				(font
					(size 1.905 1.4224)
					(thickness 0.1524)
				)
				(justify left)
			)
		)
		(fp_text user "+"
			(at -4.7752 -0.12065 270)
			(unlocked yes)
			(layer "F.SilkS")
			(effects
				(font
					(size 1.905 1.4224)
					(thickness 0.1524)
				)
				(justify left)
			)
		)
		(fp_text user "-"
			(at 5.4102 0.29845 90)
			(unlocked yes)
			(layer "F.Fab")
			(effects
				(font
					(size 1.905 1.4224)
					(thickness 0.1524)
				)
				(justify left)
			)
		)
		(fp_text user "+"
			(at -4.7752 -0.12065 270)
			(unlocked yes)
			(layer "F.Fab")
			(effects
				(font
					(size 1.905 1.4224)
					(thickness 0.1524)
				)
				(justify left)
			)
		)
		(pad "A" smd rect
			(at -1.999996 0)
			(size 1.7018 2.5146)
			(layers "F.Cu" "F.Mask" "F.Paste")
			(net "GND")
		)
		(pad "C" smd rect
			(at 1.999996 0)
			(size 1.7018 2.5146)
			(layers "F.Cu" "F.Mask" "F.Paste")
			(net "P12V_SSD3_R")
		)
	)
	(footprint ""
		(layer "F.Cu")
		(at 387.35381 -229.87635 -90)
		(property "Reference" "R5776"
			(at 0 0 270)
			(layer "F.SilkS")
			(hide yes)
			(effects
				(font
					(size 1.27 1.27)
				)
			)
		)
		(property "Value" ""
			(at 0 0 270)
			(layer "F.Fab")
			(effects
				(font
					(size 1.27 1.27)
				)
			)
		)
		(duplicate_pad_numbers_are_jumpers no)
		(fp_line
			(start -0.7874 0.4064)
			(end -0.7874 -0.4064)
			(stroke
				(width 0.1524)
				(type default)
			)
			(layer "F.SilkS")
		)
		(fp_line
			(start 0.7874 0.4064)
			(end -0.7874 0.4064)
			(stroke
				(width 0.1524)
				(type default)
			)
			(layer "F.SilkS")
		)
		(fp_line
			(start -0.7874 -0.4064)
			(end 0.7874 -0.4064)
			(stroke
				(width 0.1524)
				(type default)
			)
			(layer "F.SilkS")
		)
		(fp_line
			(start 0.7874 -0.4064)
			(end 0.7874 0.4064)
			(stroke
				(width 0.1524)
				(type default)
			)
			(layer "F.SilkS")
		)
		(fp_line
			(start -0.67945 0.3048)
			(end -0.67945 -0.305054)
			(stroke
				(width 0.1)
				(type default)
			)
			(layer "F.Fab")
		)
		(fp_line
			(start -0.12065 0.3048)
			(end -0.67945 0.3048)
			(stroke
				(width 0.1)
				(type default)
			)
			(layer "F.Fab")
		)
		(fp_line
			(start 0.120396 0.3048)
			(end 0.120396 0.2794)
			(stroke
				(width 0.1)
				(type default)
			)
			(layer "F.Fab")
		)
		(fp_line
			(start 0.67945 0.3048)
			(end 0.120396 0.3048)
			(stroke
				(width 0.1)
				(type default)
			)
			(layer "F.Fab")
		)
		(fp_line
			(start -0.12065 0.2794)
			(end -0.12065 0.3048)
			(stroke
				(width 0.1)
				(type default)
			)
			(layer "F.Fab")
		)
		(fp_line
			(start 0.120396 0.2794)
			(end -0.12065 0.2794)
			(stroke
				(width 0.1)
				(type default)
			)
			(layer "F.Fab")
		)
		(fp_line
			(start -0.12065 -0.2794)
			(end 0.12065 -0.2794)
			(stroke
				(width 0.1)
				(type default)
			)
			(layer "F.Fab")
		)
		(fp_line
			(start 0.12065 -0.2794)
			(end 0.12065 -0.3048)
			(stroke
				(width 0.1)
				(type default)
			)
			(layer "F.Fab")
		)
		(fp_line
			(start 0.12065 -0.3048)
			(end 0.67945 -0.3048)
			(stroke
				(width 0.1)
				(type default)
			)
			(layer "F.Fab")
		)
		(fp_line
			(start 0.67945 -0.3048)
			(end 0.67945 0.3048)
			(stroke
				(width 0.1)
				(type default)
			)
			(layer "F.Fab")
		)
		(fp_line
			(start -0.67945 -0.305054)
			(end -0.12065 -0.305054)
			(stroke
				(width 0.1)
				(type default)
			)
			(layer "F.Fab")
		)
		(fp_line
			(start -0.12065 -0.305054)
			(end -0.12065 -0.2794)
			(stroke
				(width 0.1)
				(type default)
			)
			(layer "F.Fab")
		)
		(pad "1" smd circle
			(at -0.40005 0 270)
			(size 0 0)
			(layers "F.Cu" "F.Mask" "F.Paste")
			(net "RST_FT4232_SDB_R_N")
		)
		(pad "2" smd circle
			(at 0.40005 0 270)
			(size 0 0)
			(layers "F.Cu" "F.Mask" "F.Paste")
			(net "RST_FT4232_R_N")
		)
	)
	(footprint ""
		(layer "F.Cu")
		(at 362.580936 -118.378986 90)
		(property "Reference" "PC915"
			(at 0 0 90)
			(layer "F.SilkS")
			(hide yes)
			(effects
				(font
					(size 1.27 1.27)
				)
			)
		)
		(property "Value" ""
			(at 0 0 90)
			(layer "F.Fab")
			(effects
				(font
					(size 1.27 1.27)
				)
			)
		)
		(duplicate_pad_numbers_are_jumpers no)
		(fp_line
			(start 0.7874 -0.4064)
			(end 0.7874 0.4064)
			(stroke
				(width 0.1524)
				(type default)
			)
			(layer "F.SilkS")
		)
		(fp_line
			(start -0.7874 -0.4064)
			(end 0.7874 -0.4064)
			(stroke
				(width 0.1524)
				(type default)
			)
			(layer "F.SilkS")
		)
		(fp_line
			(start 0.7874 0.4064)
			(end -0.7874 0.4064)
			(stroke
				(width 0.1524)
				(type default)
			)
			(layer "F.SilkS")
		)
		(fp_line
			(start -0.7874 0.4064)
			(end -0.7874 -0.4064)
			(stroke
				(width 0.1524)
				(type default)
			)
			(layer "F.SilkS")
		)
		(fp_line
			(start -0.12065 -0.305054)
			(end -0.12065 -0.2794)
			(stroke
				(width 0.1)
				(type default)
			)
			(layer "F.Fab")
		)
		(fp_line
			(start -0.67945 -0.305054)
			(end -0.12065 -0.305054)
			(stroke
				(width 0.1)
				(type default)
			)
			(layer "F.Fab")
		)
		(fp_line
			(start 0.67945 -0.3048)
			(end 0.67945 0.3048)
			(stroke
				(width 0.1)
				(type default)
			)
			(layer "F.Fab")
		)
		(fp_line
			(start 0.12065 -0.3048)
			(end 0.67945 -0.3048)
			(stroke
				(width 0.1)
				(type default)
			)
			(layer "F.Fab")
		)
		(fp_line
			(start 0.12065 -0.2794)
			(end 0.12065 -0.3048)
			(stroke
				(width 0.1)
				(type default)
			)
			(layer "F.Fab")
		)
		(fp_line
			(start -0.12065 -0.2794)
			(end 0.12065 -0.2794)
			(stroke
				(width 0.1)
				(type default)
			)
			(layer "F.Fab")
		)
		(fp_line
			(start 0.120396 0.2794)
			(end -0.12065 0.2794)
			(stroke
				(width 0.1)
				(type default)
			)
			(layer "F.Fab")
		)
		(fp_line
			(start -0.12065 0.2794)
			(end -0.12065 0.3048)
			(stroke
				(width 0.1)
				(type default)
			)
			(layer "F.Fab")
		)
		(fp_line
			(start 0.67945 0.3048)
			(end 0.120396 0.3048)
			(stroke
				(width 0.1)
				(type default)
			)
			(layer "F.Fab")
		)
		(fp_line
			(start 0.120396 0.3048)
			(end 0.120396 0.2794)
			(stroke
				(width 0.1)
				(type default)
			)
			(layer "F.Fab")
		)
		(fp_line
			(start -0.12065 0.3048)
			(end -0.67945 0.3048)
			(stroke
				(width 0.1)
				(type default)
			)
			(layer "F.Fab")
		)
		(fp_line
			(start -0.67945 0.3048)
			(end -0.67945 -0.305054)
			(stroke
				(width 0.1)
				(type default)
			)
			(layer "F.Fab")
		)
		(pad "1" smd circle
			(at -0.40005 0 90)
			(size 0 0)
			(layers "F.Cu" "F.Mask" "F.Paste")
			(net "P3V3_NIC6_CO_DV_DT")
		)
		(pad "2" smd circle
			(at 0.40005 0 90)
			(size 0 0)
			(layers "F.Cu" "F.Mask" "F.Paste")
			(net "GND")
		)
	)
	(footprint ""
		(layer "F.Cu")
		(at 392.9253 -350.098614 90)
		(property "Reference" "C740"
			(at 0 0 90)
			(layer "F.SilkS")
			(hide yes)
			(effects
				(font
					(size 1.27 1.27)
				)
			)
		)
		(property "Value" ""
			(at 0 0 90)
			(layer "F.Fab")
			(effects
				(font
					(size 1.27 1.27)
				)
			)
		)
		(duplicate_pad_numbers_are_jumpers no)
		(fp_line
			(start 0.299974 -0.150114)
			(end 0.299974 0.150114)
			(stroke
				(width 0.1)
				(type default)
			)
			(layer "F.Fab")
		)
		(fp_line
			(start -0.299974 -0.150114)
			(end 0.299974 -0.150114)
			(stroke
				(width 0.1)
				(type default)
			)
			(layer "F.Fab")
		)
		(fp_line
			(start 0.299974 0.150114)
			(end -0.299974 0.150114)
			(stroke
				(width 0.1)
				(type default)
			)
			(layer "F.Fab")
		)
		(fp_line
			(start -0.299974 0.150114)
			(end -0.299974 -0.150114)
			(stroke
				(width 0.1)
				(type default)
			)
			(layer "F.Fab")
		)
		(pad "1" smd rect
			(at -0.2667 0 90)
			(size 0.3048 0.381)
			(layers "F.Cu" "F.Mask" "F.Paste")
			(net "P5E_PEX3_STN5_TX_DP<90>")
		)
		(pad "2" smd rect
			(at 0.2667 0 90)
			(size 0.3048 0.381)
			(layers "F.Cu" "F.Mask" "F.Paste")
			(net "P5E_PEX3_STN5_TX_C_DP<90>")
		)
	)
	(footprint ""
		(layer "F.Cu")
		(at 168.343834 -46.90491)
		(property "Reference" "R565"
			(at 0 0 0)
			(layer "F.SilkS")
			(hide yes)
			(effects
				(font
					(size 1.27 1.27)
				)
			)
		)
		(property "Value" ""
			(at 0 0 0)
			(layer "F.Fab")
			(effects
				(font
					(size 1.27 1.27)
				)
			)
		)
		(duplicate_pad_numbers_are_jumpers no)
		(fp_line
			(start -0.7874 -0.4064)
			(end 0.7874 -0.4064)
			(stroke
				(width 0.1524)
				(type default)
			)
			(layer "F.SilkS")
		)
		(fp_line
			(start -0.7874 0.4064)
			(end -0.7874 -0.4064)
			(stroke
				(width 0.1524)
				(type default)
			)
			(layer "F.SilkS")
		)
		(fp_line
			(start 0.7874 -0.4064)
			(end 0.7874 0.4064)
			(stroke
				(width 0.1524)
				(type default)
			)
			(layer "F.SilkS")
		)
		(fp_line
			(start 0.7874 0.4064)
			(end -0.7874 0.4064)
			(stroke
				(width 0.1524)
				(type default)
			)
			(layer "F.SilkS")
		)
		(fp_line
			(start -0.67945 -0.305054)
			(end -0.12065 -0.305054)
			(stroke
				(width 0.1)
				(type default)
			)
			(layer "F.Fab")
		)
		(fp_line
			(start -0.67945 0.3048)
			(end -0.67945 -0.305054)
			(stroke
				(width 0.1)
				(type default)
			)
			(layer "F.Fab")
		)
		(fp_line
			(start -0.12065 -0.305054)
			(end -0.12065 -0.2794)
			(stroke
				(width 0.1)
				(type default)
			)
			(layer "F.Fab")
		)
		(fp_line
			(start -0.12065 -0.2794)
			(end 0.12065 -0.2794)
			(stroke
				(width 0.1)
				(type default)
			)
			(layer "F.Fab")
		)
		(fp_line
			(start -0.12065 0.2794)
			(end -0.12065 0.3048)
			(stroke
				(width 0.1)
				(type default)
			)
			(layer "F.Fab")
		)
		(fp_line
			(start -0.12065 0.3048)
			(end -0.67945 0.3048)
			(stroke
				(width 0.1)
				(type default)
			)
			(layer "F.Fab")
		)
		(fp_line
			(start 0.120396 0.2794)
			(end -0.12065 0.2794)
			(stroke
				(width 0.1)
				(type default)
			)
			(layer "F.Fab")
		)
		(fp_line
			(start 0.120396 0.3048)
			(end 0.120396 0.2794)
			(stroke
				(width 0.1)
				(type default)
			)
			(layer "F.Fab")
		)
		(fp_line
			(start 0.12065 -0.3048)
			(end 0.67945 -0.3048)
			(stroke
				(width 0.1)
				(type default)
			)
			(layer "F.Fab")
		)
		(fp_line
			(start 0.12065 -0.2794)
			(end 0.12065 -0.3048)
			(stroke
				(width 0.1)
				(type default)
			)
			(layer "F.Fab")
		)
		(fp_line
			(start 0.67945 -0.3048)
			(end 0.67945 0.3048)
			(stroke
				(width 0.1)
				(type default)
			)
			(layer "F.Fab")
		)
		(fp_line
			(start 0.67945 0.3048)
			(end 0.120396 0.3048)
			(stroke
				(width 0.1)
				(type default)
			)
			(layer "F.Fab")
		)
		(pad "1" smd circle
			(at -0.40005 0)
			(size 0 0)
			(layers "F.Cu" "F.Mask" "F.Paste")
			(net "SSD5_ADC_ALERT_N")
		)
		(pad "2" smd circle
			(at 0.40005 0)
			(size 0 0)
			(layers "F.Cu" "F.Mask" "F.Paste")
			(net "SSD_0_7_ADC_ALERT_N")
		)
	)
	(footprint ""
		(layer "F.Cu")
		(at 17.926558 -25.432004 -90)
		(property "Reference" "C965"
			(at 0 0 270)
			(layer "F.SilkS")
			(hide yes)
			(effects
				(font
					(size 1.27 1.27)
				)
			)
		)
		(property "Value" ""
			(at 0 0 270)
			(layer "F.Fab")
			(effects
				(font
					(size 1.27 1.27)
				)
			)
		)
		(duplicate_pad_numbers_are_jumpers no)
		(fp_line
			(start -0.7874 0.4064)
			(end -0.7874 -0.4064)
			(stroke
				(width 0.1524)
				(type default)
			)
			(layer "F.SilkS")
		)
		(fp_line
			(start 0.7874 0.4064)
			(end -0.7874 0.4064)
			(stroke
				(width 0.1524)
				(type default)
			)
			(layer "F.SilkS")
		)
		(fp_line
			(start -0.7874 -0.4064)
			(end 0.7874 -0.4064)
			(stroke
				(width 0.1524)
				(type default)
			)
			(layer "F.SilkS")
		)
		(fp_line
			(start 0.7874 -0.4064)
			(end 0.7874 0.4064)
			(stroke
				(width 0.1524)
				(type default)
			)
			(layer "F.SilkS")
		)
		(fp_line
			(start -0.67945 0.3048)
			(end -0.67945 -0.305054)
			(stroke
				(width 0.1)
				(type default)
			)
			(layer "F.Fab")
		)
		(fp_line
			(start -0.12065 0.3048)
			(end -0.67945 0.3048)
			(stroke
				(width 0.1)
				(type default)
			)
			(layer "F.Fab")
		)
		(fp_line
			(start 0.120396 0.3048)
			(end 0.120396 0.2794)
			(stroke
				(width 0.1)
				(type default)
			)
			(layer "F.Fab")
		)
		(fp_line
			(start 0.67945 0.3048)
			(end 0.120396 0.3048)
			(stroke
				(width 0.1)
				(type default)
			)
			(layer "F.Fab")
		)
		(fp_line
			(start -0.12065 0.2794)
			(end -0.12065 0.3048)
			(stroke
				(width 0.1)
				(type default)
			)
			(layer "F.Fab")
		)
		(fp_line
			(start 0.120396 0.2794)
			(end -0.12065 0.2794)
			(stroke
				(width 0.1)
				(type default)
			)
			(layer "F.Fab")
		)
		(fp_line
			(start -0.12065 -0.2794)
			(end 0.12065 -0.2794)
			(stroke
				(width 0.1)
				(type default)
			)
			(layer "F.Fab")
		)
		(fp_line
			(start 0.12065 -0.2794)
			(end 0.12065 -0.3048)
			(stroke
				(width 0.1)
				(type default)
			)
			(layer "F.Fab")
		)
		(fp_line
			(start 0.12065 -0.3048)
			(end 0.67945 -0.3048)
			(stroke
				(width 0.1)
				(type default)
			)
			(layer "F.Fab")
		)
		(fp_line
			(start 0.67945 -0.3048)
			(end 0.67945 0.3048)
			(stroke
				(width 0.1)
				(type default)
			)
			(layer "F.Fab")
		)
		(fp_line
			(start -0.67945 -0.305054)
			(end -0.12065 -0.305054)
			(stroke
				(width 0.1)
				(type default)
			)
			(layer "F.Fab")
		)
		(fp_line
			(start -0.12065 -0.305054)
			(end -0.12065 -0.2794)
			(stroke
				(width 0.1)
				(type default)
			)
			(layer "F.Fab")
		)
		(pad "1" smd circle
			(at -0.40005 0 270)
			(size 0 0)
			(layers "F.Cu" "F.Mask" "F.Paste")
			(net "GND")
		)
		(pad "2" smd circle
			(at 0.40005 0 270)
			(size 0 0)
			(layers "F.Cu" "F.Mask" "F.Paste")
			(net "P3V3_SSD0")
		)
	)
	(footprint ""
		(layer "F.Cu")
		(at 334.518 -236.855 90)
		(property "Reference" "R1797"
			(at 0 0 90)
			(layer "F.SilkS")
			(hide yes)
			(effects
				(font
					(size 1.27 1.27)
				)
			)
		)
		(property "Value" ""
			(at 0 0 90)
			(layer "F.Fab")
			(effects
				(font
					(size 1.27 1.27)
				)
			)
		)
		(duplicate_pad_numbers_are_jumpers no)
		(fp_line
			(start 0.7874 -0.4064)
			(end 0.7874 0.4064)
			(stroke
				(width 0.1524)
				(type default)
			)
			(layer "F.SilkS")
		)
		(fp_line
			(start -0.7874 -0.4064)
			(end 0.7874 -0.4064)
			(stroke
				(width 0.1524)
				(type default)
			)
			(layer "F.SilkS")
		)
		(fp_line
			(start 0.7874 0.4064)
			(end -0.7874 0.4064)
			(stroke
				(width 0.1524)
				(type default)
			)
			(layer "F.SilkS")
		)
		(fp_line
			(start -0.7874 0.4064)
			(end -0.7874 -0.4064)
			(stroke
				(width 0.1524)
				(type default)
			)
			(layer "F.SilkS")
		)
		(fp_line
			(start -0.12065 -0.305054)
			(end -0.12065 -0.2794)
			(stroke
				(width 0.1)
				(type default)
			)
			(layer "F.Fab")
		)
		(fp_line
			(start -0.67945 -0.305054)
			(end -0.12065 -0.305054)
			(stroke
				(width 0.1)
				(type default)
			)
			(layer "F.Fab")
		)
		(fp_line
			(start 0.67945 -0.3048)
			(end 0.67945 0.3048)
			(stroke
				(width 0.1)
				(type default)
			)
			(layer "F.Fab")
		)
		(fp_line
			(start 0.12065 -0.3048)
			(end 0.67945 -0.3048)
			(stroke
				(width 0.1)
				(type default)
			)
			(layer "F.Fab")
		)
		(fp_line
			(start 0.12065 -0.2794)
			(end 0.12065 -0.3048)
			(stroke
				(width 0.1)
				(type default)
			)
			(layer "F.Fab")
		)
		(fp_line
			(start -0.12065 -0.2794)
			(end 0.12065 -0.2794)
			(stroke
				(width 0.1)
				(type default)
			)
			(layer "F.Fab")
		)
		(fp_line
			(start 0.120396 0.2794)
			(end -0.12065 0.2794)
			(stroke
				(width 0.1)
				(type default)
			)
			(layer "F.Fab")
		)
		(fp_line
			(start -0.12065 0.2794)
			(end -0.12065 0.3048)
			(stroke
				(width 0.1)
				(type default)
			)
			(layer "F.Fab")
		)
		(fp_line
			(start 0.67945 0.3048)
			(end 0.120396 0.3048)
			(stroke
				(width 0.1)
				(type default)
			)
			(layer "F.Fab")
		)
		(fp_line
			(start 0.120396 0.3048)
			(end 0.120396 0.2794)
			(stroke
				(width 0.1)
				(type default)
			)
			(layer "F.Fab")
		)
		(fp_line
			(start -0.12065 0.3048)
			(end -0.67945 0.3048)
			(stroke
				(width 0.1)
				(type default)
			)
			(layer "F.Fab")
		)
		(fp_line
			(start -0.67945 0.3048)
			(end -0.67945 -0.305054)
			(stroke
				(width 0.1)
				(type default)
			)
			(layer "F.Fab")
		)
		(pad "1" smd circle
			(at -0.40005 0 90)
			(size 0 0)
			(layers "F.Cu" "F.Mask" "F.Paste")
			(net "MB_SWB_PWRGD")
		)
		(pad "2" smd circle
			(at 0.40005 0 90)
			(size 0 0)
			(layers "F.Cu" "F.Mask" "F.Paste")
			(net "MB_SWB_PWRGD_R")
		)
	)
	(footprint ""
		(layer "F.Cu")
		(at 316.500764 -343.952322 90)
		(property "Reference" "C548"
			(at 0 0 90)
			(layer "F.SilkS")
			(hide yes)
			(effects
				(font
					(size 1.27 1.27)
				)
			)
		)
		(property "Value" ""
			(at 0 0 90)
			(layer "F.Fab")
			(effects
				(font
					(size 1.27 1.27)
				)
			)
		)
		(duplicate_pad_numbers_are_jumpers no)
		(fp_line
			(start 0.299974 -0.150114)
			(end 0.299974 0.150114)
			(stroke
				(width 0.1)
				(type default)
			)
			(layer "F.Fab")
		)
		(fp_line
			(start -0.299974 -0.150114)
			(end 0.299974 -0.150114)
			(stroke
				(width 0.1)
				(type default)
			)
			(layer "F.Fab")
		)
		(fp_line
			(start 0.299974 0.150114)
			(end -0.299974 0.150114)
			(stroke
				(width 0.1)
				(type default)
			)
			(layer "F.Fab")
		)
		(fp_line
			(start -0.299974 0.150114)
			(end -0.299974 -0.150114)
			(stroke
				(width 0.1)
				(type default)
			)
			(layer "F.Fab")
		)
		(pad "1" smd rect
			(at -0.2667 0 90)
			(size 0.3048 0.381)
			(layers "F.Cu" "F.Mask" "F.Paste")
			(net "P5E_PEX2_STN5_TX_DN<81>")
		)
		(pad "2" smd rect
			(at 0.2667 0 90)
			(size 0.3048 0.381)
			(layers "F.Cu" "F.Mask" "F.Paste")
			(net "P5E_PEX2_STN5_TX_C_DN<81>")
		)
	)
	(footprint ""
		(layer "F.Cu")
		(at 447.275712 -119.477028 180)
		(property "Reference" "R885"
			(at 0 0 180)
			(layer "F.SilkS")
			(hide yes)
			(effects
				(font
					(size 1.27 1.27)
				)
			)
		)
		(property "Value" ""
			(at 0 0 180)
			(layer "F.Fab")
			(effects
				(font
					(size 1.27 1.27)
				)
			)
		)
		(duplicate_pad_numbers_are_jumpers no)
		(fp_line
			(start 0.7874 0.4064)
			(end -0.7874 0.4064)
			(stroke
				(width 0.1524)
				(type default)
			)
			(layer "F.SilkS")
		)
		(fp_line
			(start 0.7874 -0.4064)
			(end 0.7874 0.4064)
			(stroke
				(width 0.1524)
				(type default)
			)
			(layer "F.SilkS")
		)
		(fp_line
			(start -0.7874 0.4064)
			(end -0.7874 -0.4064)
			(stroke
				(width 0.1524)
				(type default)
			)
			(layer "F.SilkS")
		)
		(fp_line
			(start -0.7874 -0.4064)
			(end 0.7874 -0.4064)
			(stroke
				(width 0.1524)
				(type default)
			)
			(layer "F.SilkS")
		)
		(fp_line
			(start 0.67945 0.3048)
			(end 0.120396 0.3048)
			(stroke
				(width 0.1)
				(type default)
			)
			(layer "F.Fab")
		)
		(fp_line
			(start 0.67945 -0.3048)
			(end 0.67945 0.3048)
			(stroke
				(width 0.1)
				(type default)
			)
			(layer "F.Fab")
		)
		(fp_line
			(start 0.12065 -0.2794)
			(end 0.12065 -0.3048)
			(stroke
				(width 0.1)
				(type default)
			)
			(layer "F.Fab")
		)
		(fp_line
			(start 0.12065 -0.3048)
			(end 0.67945 -0.3048)
			(stroke
				(width 0.1)
				(type default)
			)
			(layer "F.Fab")
		)
		(fp_line
			(start 0.120396 0.3048)
			(end 0.120396 0.2794)
			(stroke
				(width 0.1)
				(type default)
			)
			(layer "F.Fab")
		)
		(fp_line
			(start 0.120396 0.2794)
			(end -0.12065 0.2794)
			(stroke
				(width 0.1)
				(type default)
			)
			(layer "F.Fab")
		)
		(fp_line
			(start -0.12065 0.3048)
			(end -0.67945 0.3048)
			(stroke
				(width 0.1)
				(type default)
			)
			(layer "F.Fab")
		)
		(fp_line
			(start -0.12065 0.2794)
			(end -0.12065 0.3048)
			(stroke
				(width 0.1)
				(type default)
			)
			(layer "F.Fab")
		)
		(fp_line
			(start -0.12065 -0.2794)
			(end 0.12065 -0.2794)
			(stroke
				(width 0.1)
				(type default)
			)
			(layer "F.Fab")
		)
		(fp_line
			(start -0.12065 -0.305054)
			(end -0.12065 -0.2794)
			(stroke
				(width 0.1)
				(type default)
			)
			(layer "F.Fab")
		)
		(fp_line
			(start -0.67945 0.3048)
			(end -0.67945 -0.305054)
			(stroke
				(width 0.1)
				(type default)
			)
			(layer "F.Fab")
		)
		(fp_line
			(start -0.67945 -0.305054)
			(end -0.12065 -0.305054)
			(stroke
				(width 0.1)
				(type default)
			)
			(layer "F.Fab")
		)
		(pad "1" smd circle
			(at -0.40005 0 180)
			(size 0 0)
			(layers "F.Cu" "F.Mask" "F.Paste")
			(net "P3V3_NIC7")
		)
		(pad "2" smd circle
			(at 0.40005 0 180)
			(size 0 0)
			(layers "F.Cu" "F.Mask" "F.Paste")
			(net "PWRGD_P3V3_NIC7")
		)
	)
	(footprint ""
		(layer "F.Cu")
		(at 261.34187 -242.372388 180)
		(property "Reference" "R6582"
			(at 0 0 180)
			(layer "F.SilkS")
			(hide yes)
			(effects
				(font
					(size 1.27 1.27)
				)
			)
		)
		(property "Value" ""
			(at 0 0 180)
			(layer "F.Fab")
			(effects
				(font
					(size 1.27 1.27)
				)
			)
		)
		(duplicate_pad_numbers_are_jumpers no)
		(fp_line
			(start 0.7874 0.4064)
			(end -0.7874 0.4064)
			(stroke
				(width 0.1524)
				(type default)
			)
			(layer "F.SilkS")
		)
		(fp_line
			(start 0.7874 -0.4064)
			(end 0.7874 0.4064)
			(stroke
				(width 0.1524)
				(type default)
			)
			(layer "F.SilkS")
		)
		(fp_line
			(start -0.7874 0.4064)
			(end -0.7874 -0.4064)
			(stroke
				(width 0.1524)
				(type default)
			)
			(layer "F.SilkS")
		)
		(fp_line
			(start -0.7874 -0.4064)
			(end 0.7874 -0.4064)
			(stroke
				(width 0.1524)
				(type default)
			)
			(layer "F.SilkS")
		)
		(fp_line
			(start 0.67945 0.3048)
			(end 0.120396 0.3048)
			(stroke
				(width 0.1)
				(type default)
			)
			(layer "F.Fab")
		)
		(fp_line
			(start 0.67945 -0.3048)
			(end 0.67945 0.3048)
			(stroke
				(width 0.1)
				(type default)
			)
			(layer "F.Fab")
		)
		(fp_line
			(start 0.12065 -0.2794)
			(end 0.12065 -0.3048)
			(stroke
				(width 0.1)
				(type default)
			)
			(layer "F.Fab")
		)
		(fp_line
			(start 0.12065 -0.3048)
			(end 0.67945 -0.3048)
			(stroke
				(width 0.1)
				(type default)
			)
			(layer "F.Fab")
		)
		(fp_line
			(start 0.120396 0.3048)
			(end 0.120396 0.2794)
			(stroke
				(width 0.1)
				(type default)
			)
			(layer "F.Fab")
		)
		(fp_line
			(start 0.120396 0.2794)
			(end -0.12065 0.2794)
			(stroke
				(width 0.1)
				(type default)
			)
			(layer "F.Fab")
		)
		(fp_line
			(start -0.12065 0.3048)
			(end -0.67945 0.3048)
			(stroke
				(width 0.1)
				(type default)
			)
			(layer "F.Fab")
		)
		(fp_line
			(start -0.12065 0.2794)
			(end -0.12065 0.3048)
			(stroke
				(width 0.1)
				(type default)
			)
			(layer "F.Fab")
		)
		(fp_line
			(start -0.12065 -0.2794)
			(end 0.12065 -0.2794)
			(stroke
				(width 0.1)
				(type default)
			)
			(layer "F.Fab")
		)
		(fp_line
			(start -0.12065 -0.305054)
			(end -0.12065 -0.2794)
			(stroke
				(width 0.1)
				(type default)
			)
			(layer "F.Fab")
		)
		(fp_line
			(start -0.67945 0.3048)
			(end -0.67945 -0.305054)
			(stroke
				(width 0.1)
				(type default)
			)
			(layer "F.Fab")
		)
		(fp_line
			(start -0.67945 -0.305054)
			(end -0.12065 -0.305054)
			(stroke
				(width 0.1)
				(type default)
			)
			(layer "F.Fab")
		)
		(pad "1" smd circle
			(at -0.40005 0 180)
			(size 0 0)
			(layers "F.Cu" "F.Mask" "F.Paste")
			(net "PWRGD_PEX2_P1V8_PLL_R")
		)
		(pad "2" smd circle
			(at 0.40005 0 180)
			(size 0 0)
			(layers "F.Cu" "F.Mask" "F.Paste")
			(net "PWRGD_PEX2_P1V8_PLL")
		)
	)
	(footprint ""
		(layer "F.Cu")
		(at 420.03853 -44.341542 90)
		(property "Reference" "C405"
			(at 0 0 90)
			(layer "F.SilkS")
			(hide yes)
			(effects
				(font
					(size 1.27 1.27)
				)
			)
		)
		(property "Value" ""
			(at 0 0 90)
			(layer "F.Fab")
			(effects
				(font
					(size 1.27 1.27)
				)
			)
		)
		(duplicate_pad_numbers_are_jumpers no)
		(fp_line
			(start 0.7874 -0.4064)
			(end 0.7874 0.4064)
			(stroke
				(width 0.1524)
				(type default)
			)
			(layer "F.SilkS")
		)
		(fp_line
			(start -0.7874 -0.4064)
			(end 0.7874 -0.4064)
			(stroke
				(width 0.1524)
				(type default)
			)
			(layer "F.SilkS")
		)
		(fp_line
			(start 0.7874 0.4064)
			(end -0.7874 0.4064)
			(stroke
				(width 0.1524)
				(type default)
			)
			(layer "F.SilkS")
		)
		(fp_line
			(start -0.7874 0.4064)
			(end -0.7874 -0.4064)
			(stroke
				(width 0.1524)
				(type default)
			)
			(layer "F.SilkS")
		)
		(fp_line
			(start -0.12065 -0.305054)
			(end -0.12065 -0.2794)
			(stroke
				(width 0.1)
				(type default)
			)
			(layer "F.Fab")
		)
		(fp_line
			(start -0.67945 -0.305054)
			(end -0.12065 -0.305054)
			(stroke
				(width 0.1)
				(type default)
			)
			(layer "F.Fab")
		)
		(fp_line
			(start 0.67945 -0.3048)
			(end 0.67945 0.3048)
			(stroke
				(width 0.1)
				(type default)
			)
			(layer "F.Fab")
		)
		(fp_line
			(start 0.12065 -0.3048)
			(end 0.67945 -0.3048)
			(stroke
				(width 0.1)
				(type default)
			)
			(layer "F.Fab")
		)
		(fp_line
			(start 0.12065 -0.2794)
			(end 0.12065 -0.3048)
			(stroke
				(width 0.1)
				(type default)
			)
			(layer "F.Fab")
		)
		(fp_line
			(start -0.12065 -0.2794)
			(end 0.12065 -0.2794)
			(stroke
				(width 0.1)
				(type default)
			)
			(layer "F.Fab")
		)
		(fp_line
			(start 0.120396 0.2794)
			(end -0.12065 0.2794)
			(stroke
				(width 0.1)
				(type default)
			)
			(layer "F.Fab")
		)
		(fp_line
			(start -0.12065 0.2794)
			(end -0.12065 0.3048)
			(stroke
				(width 0.1)
				(type default)
			)
			(layer "F.Fab")
		)
		(fp_line
			(start 0.67945 0.3048)
			(end 0.120396 0.3048)
			(stroke
				(width 0.1)
				(type default)
			)
			(layer "F.Fab")
		)
		(fp_line
			(start 0.120396 0.3048)
			(end 0.120396 0.2794)
			(stroke
				(width 0.1)
				(type default)
			)
			(layer "F.Fab")
		)
		(fp_line
			(start -0.12065 0.3048)
			(end -0.67945 0.3048)
			(stroke
				(width 0.1)
				(type default)
			)
			(layer "F.Fab")
		)
		(fp_line
			(start -0.67945 0.3048)
			(end -0.67945 -0.305054)
			(stroke
				(width 0.1)
				(type default)
			)
			(layer "F.Fab")
		)
		(pad "1" smd circle
			(at -0.40005 0 90)
			(size 0 0)
			(layers "F.Cu" "F.Mask" "F.Paste")
			(net "P12V_SSD14_VIN_P")
		)
		(pad "2" smd circle
			(at 0.40005 0 90)
			(size 0 0)
			(layers "F.Cu" "F.Mask" "F.Paste")
			(net "P12V_SSD14_VIN_N")
		)
	)
	(footprint ""
		(layer "F.Cu")
		(at 163.63061 -66.32194 -90)
		(property "Reference" "PC847"
			(at 0 0 270)
			(layer "F.SilkS")
			(hide yes)
			(effects
				(font
					(size 1.27 1.27)
				)
			)
		)
		(property "Value" ""
			(at 0 0 270)
			(layer "F.Fab")
			(effects
				(font
					(size 1.27 1.27)
				)
			)
		)
		(duplicate_pad_numbers_are_jumpers no)
		(fp_line
			(start -0.7874 0.4064)
			(end -0.7874 -0.4064)
			(stroke
				(width 0.1524)
				(type default)
			)
			(layer "F.SilkS")
		)
		(fp_line
			(start 0.7874 0.4064)
			(end -0.7874 0.4064)
			(stroke
				(width 0.1524)
				(type default)
			)
			(layer "F.SilkS")
		)
		(fp_line
			(start -0.7874 -0.4064)
			(end 0.7874 -0.4064)
			(stroke
				(width 0.1524)
				(type default)
			)
			(layer "F.SilkS")
		)
		(fp_line
			(start 0.7874 -0.4064)
			(end 0.7874 0.4064)
			(stroke
				(width 0.1524)
				(type default)
			)
			(layer "F.SilkS")
		)
		(fp_line
			(start -0.67945 0.3048)
			(end -0.67945 -0.305054)
			(stroke
				(width 0.1)
				(type default)
			)
			(layer "F.Fab")
		)
		(fp_line
			(start -0.12065 0.3048)
			(end -0.67945 0.3048)
			(stroke
				(width 0.1)
				(type default)
			)
			(layer "F.Fab")
		)
		(fp_line
			(start 0.120396 0.3048)
			(end 0.120396 0.2794)
			(stroke
				(width 0.1)
				(type default)
			)
			(layer "F.Fab")
		)
		(fp_line
			(start 0.67945 0.3048)
			(end 0.120396 0.3048)
			(stroke
				(width 0.1)
				(type default)
			)
			(layer "F.Fab")
		)
		(fp_line
			(start -0.12065 0.2794)
			(end -0.12065 0.3048)
			(stroke
				(width 0.1)
				(type default)
			)
			(layer "F.Fab")
		)
		(fp_line
			(start 0.120396 0.2794)
			(end -0.12065 0.2794)
			(stroke
				(width 0.1)
				(type default)
			)
			(layer "F.Fab")
		)
		(fp_line
			(start -0.12065 -0.2794)
			(end 0.12065 -0.2794)
			(stroke
				(width 0.1)
				(type default)
			)
			(layer "F.Fab")
		)
		(fp_line
			(start 0.12065 -0.2794)
			(end 0.12065 -0.3048)
			(stroke
				(width 0.1)
				(type default)
			)
			(layer "F.Fab")
		)
		(fp_line
			(start 0.12065 -0.3048)
			(end 0.67945 -0.3048)
			(stroke
				(width 0.1)
				(type default)
			)
			(layer "F.Fab")
		)
		(fp_line
			(start 0.67945 -0.3048)
			(end 0.67945 0.3048)
			(stroke
				(width 0.1)
				(type default)
			)
			(layer "F.Fab")
		)
		(fp_line
			(start -0.67945 -0.305054)
			(end -0.12065 -0.305054)
			(stroke
				(width 0.1)
				(type default)
			)
			(layer "F.Fab")
		)
		(fp_line
			(start -0.12065 -0.305054)
			(end -0.12065 -0.2794)
			(stroke
				(width 0.1)
				(type default)
			)
			(layer "F.Fab")
		)
		(pad "1" smd circle
			(at -0.40005 0 270)
			(size 0 0)
			(layers "F.Cu" "F.Mask" "F.Paste")
			(net "P12V_SSD5_CO_DV_DT")
		)
		(pad "2" smd circle
			(at 0.40005 0 270)
			(size 0 0)
			(layers "F.Cu" "F.Mask" "F.Paste")
			(net "GND")
		)
	)
	(footprint ""
		(layer "F.Cu")
		(at 54.782466 -29.875734)
		(property "Reference" "PU83"
			(at -3.405886 -1.754632 90)
			(unlocked yes)
			(layer "F.SilkS")
			(effects
				(font
					(size 0.7874 0.5842)
					(thickness 0.1524)
				)
			)
		)
		(property "Value" ""
			(at 0 0 0)
			(layer "F.Fab")
			(effects
				(font
					(size 1.27 1.27)
				)
			)
		)
		(duplicate_pad_numbers_are_jumpers no)
		(fp_line
			(start -1.239774 -1.495298)
			(end 1.239774 -1.495298)
			(stroke
				(width 0.1524)
				(type default)
			)
			(layer "F.SilkS")
		)
		(fp_line
			(start -1.239774 1.495298)
			(end -1.239774 -1.495298)
			(stroke
				(width 0.1524)
				(type default)
			)
			(layer "F.SilkS")
		)
		(fp_line
			(start 1.239774 -1.495298)
			(end 1.239774 1.495298)
			(stroke
				(width 0.1524)
				(type default)
			)
			(layer "F.SilkS")
		)
		(fp_line
			(start 1.239774 1.495298)
			(end -1.239774 1.495298)
			(stroke
				(width 0.1524)
				(type default)
			)
			(layer "F.SilkS")
		)
		(fp_poly
			(pts
				(xy -2.24282 -1.504188) (xy -2.961132 -0.785876) (xy -1.88341 -0.42672)
			)
			(stroke
				(width 0)
				(type default)
			)
			(fill yes)
			(layer "F.SilkS")
		)
		(fp_line
			(start -0.8001 -1.050036)
			(end 0.8001 -1.050036)
			(stroke
				(width 0.1)
				(type default)
			)
			(layer "F.Fab")
		)
		(fp_line
			(start -0.8001 1.050036)
			(end -0.8001 -1.050036)
			(stroke
				(width 0.1)
				(type default)
			)
			(layer "F.Fab")
		)
		(fp_line
			(start 0.8001 -1.050036)
			(end 0.8001 1.050036)
			(stroke
				(width 0.1)
				(type default)
			)
			(layer "F.Fab")
		)
		(fp_line
			(start 0.8001 1.050036)
			(end -0.8001 1.050036)
			(stroke
				(width 0.1)
				(type default)
			)
			(layer "F.Fab")
		)
		(fp_poly
			(pts
				(xy -2.458974 -0.508) (xy -2.458974 0.508) (xy -1.442974 0)
			)
			(stroke
				(width 0)
				(type default)
			)
			(fill yes)
			(layer "F.Fab")
		)
		(pad "1_2" smd circle
			(at -0.374904 0 90)
			(size 0 0)
			(layers "F.Cu" "F.Mask" "F.Paste")
			(net "P3V3_AUX")
		)
		(pad "3" smd rect
			(at -0.499872 0.999998)
			(size 0.254 0.7112)
			(layers "F.Cu" "F.Mask" "F.Paste")
			(net "GND")
		)
		(pad "4" smd rect
			(at 0 0.999998)
			(size 0.254 0.7112)
			(layers "F.Cu" "F.Mask" "F.Paste")
			(net "P3V3_SSD2_CO_ILIMIT")
		)
		(pad "5" smd rect
			(at 0.499872 0.999998)
			(size 0.254 0.7112)
			(layers "F.Cu" "F.Mask" "F.Paste")
			(net "P3V3_SSD2_CO_MODE")
		)
		(pad "6_7" smd circle
			(at 0.374904 0 270)
			(size 0 0)
			(layers "F.Cu" "F.Mask" "F.Paste")
			(net "P3V3_SSD2")
		)
		(pad "8" smd rect
			(at 0.499872 -0.999998)
			(size 0.254 0.7112)
			(layers "F.Cu" "F.Mask" "F.Paste")
			(net "P3V3_SSD2_CO_GATE")
		)
		(pad "9" smd rect
			(at 0 -0.999998)
			(size 0.254 0.7112)
			(layers "F.Cu" "F.Mask" "F.Paste")
			(net "P3V3_SSD2_CO_EN")
		)
		(pad "10" smd rect
			(at -0.499872 -0.999998)
			(size 0.254 0.7112)
			(layers "F.Cu" "F.Mask" "F.Paste")
			(net "P3V3_SSD2_CO_DV_DT")
		)
	)
	(footprint ""
		(layer "F.Cu")
		(at 321.223386 -96.811592 -90)
		(property "Reference" "R737"
			(at 0 0 270)
			(layer "F.SilkS")
			(hide yes)
			(effects
				(font
					(size 1.27 1.27)
				)
			)
		)
		(property "Value" ""
			(at 0 0 270)
			(layer "F.Fab")
			(effects
				(font
					(size 1.27 1.27)
				)
			)
		)
		(duplicate_pad_numbers_are_jumpers no)
		(fp_line
			(start -0.7874 0.4064)
			(end -0.7874 -0.4064)
			(stroke
				(width 0.1524)
				(type default)
			)
			(layer "F.SilkS")
		)
		(fp_line
			(start 0.7874 0.4064)
			(end -0.7874 0.4064)
			(stroke
				(width 0.1524)
				(type default)
			)
			(layer "F.SilkS")
		)
		(fp_line
			(start -0.7874 -0.4064)
			(end 0.7874 -0.4064)
			(stroke
				(width 0.1524)
				(type default)
			)
			(layer "F.SilkS")
		)
		(fp_line
			(start 0.7874 -0.4064)
			(end 0.7874 0.4064)
			(stroke
				(width 0.1524)
				(type default)
			)
			(layer "F.SilkS")
		)
		(fp_line
			(start -0.67945 0.3048)
			(end -0.67945 -0.305054)
			(stroke
				(width 0.1)
				(type default)
			)
			(layer "F.Fab")
		)
		(fp_line
			(start -0.12065 0.3048)
			(end -0.67945 0.3048)
			(stroke
				(width 0.1)
				(type default)
			)
			(layer "F.Fab")
		)
		(fp_line
			(start 0.120396 0.3048)
			(end 0.120396 0.2794)
			(stroke
				(width 0.1)
				(type default)
			)
			(layer "F.Fab")
		)
		(fp_line
			(start 0.67945 0.3048)
			(end 0.120396 0.3048)
			(stroke
				(width 0.1)
				(type default)
			)
			(layer "F.Fab")
		)
		(fp_line
			(start -0.12065 0.2794)
			(end -0.12065 0.3048)
			(stroke
				(width 0.1)
				(type default)
			)
			(layer "F.Fab")
		)
		(fp_line
			(start 0.120396 0.2794)
			(end -0.12065 0.2794)
			(stroke
				(width 0.1)
				(type default)
			)
			(layer "F.Fab")
		)
		(fp_line
			(start -0.12065 -0.2794)
			(end 0.12065 -0.2794)
			(stroke
				(width 0.1)
				(type default)
			)
			(layer "F.Fab")
		)
		(fp_line
			(start 0.12065 -0.2794)
			(end 0.12065 -0.3048)
			(stroke
				(width 0.1)
				(type default)
			)
			(layer "F.Fab")
		)
		(fp_line
			(start 0.12065 -0.3048)
			(end 0.67945 -0.3048)
			(stroke
				(width 0.1)
				(type default)
			)
			(layer "F.Fab")
		)
		(fp_line
			(start 0.67945 -0.3048)
			(end 0.67945 0.3048)
			(stroke
				(width 0.1)
				(type default)
			)
			(layer "F.Fab")
		)
		(fp_line
			(start -0.67945 -0.305054)
			(end -0.12065 -0.305054)
			(stroke
				(width 0.1)
				(type default)
			)
			(layer "F.Fab")
		)
		(fp_line
			(start -0.12065 -0.305054)
			(end -0.12065 -0.2794)
			(stroke
				(width 0.1)
				(type default)
			)
			(layer "F.Fab")
		)
		(pad "1" smd circle
			(at -0.40005 0 270)
			(size 0 0)
			(layers "F.Cu" "F.Mask" "F.Paste")
			(net "NIC5_ADC_A0")
		)
		(pad "2" smd circle
			(at 0.40005 0 270)
			(size 0 0)
			(layers "F.Cu" "F.Mask" "F.Paste")
			(net "P3V3_AUX")
		)
	)
	(footprint ""
		(layer "F.Cu")
		(at 344.612976 -89.255346 180)
		(property "Reference" "R1182"
			(at 0 0 180)
			(layer "F.SilkS")
			(hide yes)
			(effects
				(font
					(size 1.27 1.27)
				)
			)
		)
		(property "Value" ""
			(at 0 0 180)
			(layer "F.Fab")
			(effects
				(font
					(size 1.27 1.27)
				)
			)
		)
		(duplicate_pad_numbers_are_jumpers no)
		(fp_line
			(start -0.7874 -0.4064)
			(end 0.7874 -0.4064)
			(stroke
				(width 0.1524)
				(type default)
			)
			(layer "F.SilkS")
		)
		(fp_line
			(start 0.67945 0.3048)
			(end 0.120396 0.3048)
			(stroke
				(width 0.1)
				(type default)
			)
			(layer "F.Fab")
		)
		(fp_line
			(start 0.67945 -0.3048)
			(end 0.67945 0.3048)
			(stroke
				(width 0.1)
				(type default)
			)
			(layer "F.Fab")
		)
		(fp_line
			(start 0.12065 -0.2794)
			(end 0.12065 -0.3048)
			(stroke
				(width 0.1)
				(type default)
			)
			(layer "F.Fab")
		)
		(fp_line
			(start 0.12065 -0.3048)
			(end 0.67945 -0.3048)
			(stroke
				(width 0.1)
				(type default)
			)
			(layer "F.Fab")
		)
		(fp_line
			(start 0.120396 0.3048)
			(end 0.120396 0.2794)
			(stroke
				(width 0.1)
				(type default)
			)
			(layer "F.Fab")
		)
		(fp_line
			(start 0.120396 0.2794)
			(end -0.12065 0.2794)
			(stroke
				(width 0.1)
				(type default)
			)
			(layer "F.Fab")
		)
		(fp_line
			(start -0.12065 0.3048)
			(end -0.67945 0.3048)
			(stroke
				(width 0.1)
				(type default)
			)
			(layer "F.Fab")
		)
		(fp_line
			(start -0.12065 0.2794)
			(end -0.12065 0.3048)
			(stroke
				(width 0.1)
				(type default)
			)
			(layer "F.Fab")
		)
		(fp_line
			(start -0.12065 -0.2794)
			(end 0.12065 -0.2794)
			(stroke
				(width 0.1)
				(type default)
			)
			(layer "F.Fab")
		)
		(fp_line
			(start -0.12065 -0.305054)
			(end -0.12065 -0.2794)
			(stroke
				(width 0.1)
				(type default)
			)
			(layer "F.Fab")
		)
		(fp_line
			(start -0.67945 0.3048)
			(end -0.67945 -0.305054)
			(stroke
				(width 0.1)
				(type default)
			)
			(layer "F.Fab")
		)
		(fp_line
			(start -0.67945 -0.305054)
			(end -0.12065 -0.305054)
			(stroke
				(width 0.1)
				(type default)
			)
			(layer "F.Fab")
		)
		(pad "1" smd circle
			(at -0.40005 0 180)
			(size 0 0)
			(layers "F.Cu" "F.Mask" "F.Paste")
			(net "CLK_100M_DB800ZL_SSD14_R_DP")
		)
		(pad "2" smd circle
			(at 0.40005 0 180)
			(size 0 0)
			(layers "F.Cu" "F.Mask" "F.Paste")
			(net "CLK_100M_DB800ZL_SSD14_DP")
		)
	)
	(footprint ""
		(layer "F.Cu")
		(at 291.194998 -100.766372 180)
		(property "Reference" "R282"
			(at 0 0 180)
			(layer "F.SilkS")
			(hide yes)
			(effects
				(font
					(size 1.27 1.27)
				)
			)
		)
		(property "Value" ""
			(at 0 0 180)
			(layer "F.Fab")
			(effects
				(font
					(size 1.27 1.27)
				)
			)
		)
		(duplicate_pad_numbers_are_jumpers no)
		(fp_line
			(start 0.7874 0.4064)
			(end -0.7874 0.4064)
			(stroke
				(width 0.1524)
				(type default)
			)
			(layer "F.SilkS")
		)
		(fp_line
			(start 0.7874 -0.4064)
			(end 0.7874 0.4064)
			(stroke
				(width 0.1524)
				(type default)
			)
			(layer "F.SilkS")
		)
		(fp_line
			(start -0.7874 0.4064)
			(end -0.7874 -0.4064)
			(stroke
				(width 0.1524)
				(type default)
			)
			(layer "F.SilkS")
		)
		(fp_line
			(start -0.7874 -0.4064)
			(end 0.7874 -0.4064)
			(stroke
				(width 0.1524)
				(type default)
			)
			(layer "F.SilkS")
		)
		(fp_line
			(start 0.67945 0.3048)
			(end 0.120396 0.3048)
			(stroke
				(width 0.1)
				(type default)
			)
			(layer "F.Fab")
		)
		(fp_line
			(start 0.67945 -0.3048)
			(end 0.67945 0.3048)
			(stroke
				(width 0.1)
				(type default)
			)
			(layer "F.Fab")
		)
		(fp_line
			(start 0.12065 -0.2794)
			(end 0.12065 -0.3048)
			(stroke
				(width 0.1)
				(type default)
			)
			(layer "F.Fab")
		)
		(fp_line
			(start 0.12065 -0.3048)
			(end 0.67945 -0.3048)
			(stroke
				(width 0.1)
				(type default)
			)
			(layer "F.Fab")
		)
		(fp_line
			(start 0.120396 0.3048)
			(end 0.120396 0.2794)
			(stroke
				(width 0.1)
				(type default)
			)
			(layer "F.Fab")
		)
		(fp_line
			(start 0.120396 0.2794)
			(end -0.12065 0.2794)
			(stroke
				(width 0.1)
				(type default)
			)
			(layer "F.Fab")
		)
		(fp_line
			(start -0.12065 0.3048)
			(end -0.67945 0.3048)
			(stroke
				(width 0.1)
				(type default)
			)
			(layer "F.Fab")
		)
		(fp_line
			(start -0.12065 0.2794)
			(end -0.12065 0.3048)
			(stroke
				(width 0.1)
				(type default)
			)
			(layer "F.Fab")
		)
		(fp_line
			(start -0.12065 -0.2794)
			(end 0.12065 -0.2794)
			(stroke
				(width 0.1)
				(type default)
			)
			(layer "F.Fab")
		)
		(fp_line
			(start -0.12065 -0.305054)
			(end -0.12065 -0.2794)
			(stroke
				(width 0.1)
				(type default)
			)
			(layer "F.Fab")
		)
		(fp_line
			(start -0.67945 0.3048)
			(end -0.67945 -0.305054)
			(stroke
				(width 0.1)
				(type default)
			)
			(layer "F.Fab")
		)
		(fp_line
			(start -0.67945 -0.305054)
			(end -0.12065 -0.305054)
			(stroke
				(width 0.1)
				(type default)
			)
			(layer "F.Fab")
		)
		(pad "1" smd circle
			(at -0.40005 0 180)
			(size 0 0)
			(layers "F.Cu" "F.Mask" "F.Paste")
			(net "NIC5_SLOT_ID1")
		)
		(pad "2" smd circle
			(at 0.40005 0 180)
			(size 0 0)
			(layers "F.Cu" "F.Mask" "F.Paste")
			(net "P3V3_NIC5")
		)
	)
	(footprint ""
		(layer "F.Cu")
		(at 254.085598 -27.092148 -90)
		(property "Reference" "R5759"
			(at 0 0 270)
			(layer "F.SilkS")
			(hide yes)
			(effects
				(font
					(size 1.27 1.27)
				)
			)
		)
		(property "Value" ""
			(at 0 0 270)
			(layer "F.Fab")
			(effects
				(font
					(size 1.27 1.27)
				)
			)
		)
		(duplicate_pad_numbers_are_jumpers no)
		(fp_line
			(start -0.7874 0.4064)
			(end -0.7874 -0.4064)
			(stroke
				(width 0.1524)
				(type default)
			)
			(layer "F.SilkS")
		)
		(fp_line
			(start 0.7874 0.4064)
			(end -0.7874 0.4064)
			(stroke
				(width 0.1524)
				(type default)
			)
			(layer "F.SilkS")
		)
		(fp_line
			(start -0.7874 -0.4064)
			(end 0.7874 -0.4064)
			(stroke
				(width 0.1524)
				(type default)
			)
			(layer "F.SilkS")
		)
		(fp_line
			(start 0.7874 -0.4064)
			(end 0.7874 0.4064)
			(stroke
				(width 0.1524)
				(type default)
			)
			(layer "F.SilkS")
		)
		(fp_line
			(start -0.67945 0.3048)
			(end -0.67945 -0.305054)
			(stroke
				(width 0.1)
				(type default)
			)
			(layer "F.Fab")
		)
		(fp_line
			(start -0.12065 0.3048)
			(end -0.67945 0.3048)
			(stroke
				(width 0.1)
				(type default)
			)
			(layer "F.Fab")
		)
		(fp_line
			(start 0.120396 0.3048)
			(end 0.120396 0.2794)
			(stroke
				(width 0.1)
				(type default)
			)
			(layer "F.Fab")
		)
		(fp_line
			(start 0.67945 0.3048)
			(end 0.120396 0.3048)
			(stroke
				(width 0.1)
				(type default)
			)
			(layer "F.Fab")
		)
		(fp_line
			(start -0.12065 0.2794)
			(end -0.12065 0.3048)
			(stroke
				(width 0.1)
				(type default)
			)
			(layer "F.Fab")
		)
		(fp_line
			(start 0.120396 0.2794)
			(end -0.12065 0.2794)
			(stroke
				(width 0.1)
				(type default)
			)
			(layer "F.Fab")
		)
		(fp_line
			(start -0.12065 -0.2794)
			(end 0.12065 -0.2794)
			(stroke
				(width 0.1)
				(type default)
			)
			(layer "F.Fab")
		)
		(fp_line
			(start 0.12065 -0.2794)
			(end 0.12065 -0.3048)
			(stroke
				(width 0.1)
				(type default)
			)
			(layer "F.Fab")
		)
		(fp_line
			(start 0.12065 -0.3048)
			(end 0.67945 -0.3048)
			(stroke
				(width 0.1)
				(type default)
			)
			(layer "F.Fab")
		)
		(fp_line
			(start 0.67945 -0.3048)
			(end 0.67945 0.3048)
			(stroke
				(width 0.1)
				(type default)
			)
			(layer "F.Fab")
		)
		(fp_line
			(start -0.67945 -0.305054)
			(end -0.12065 -0.305054)
			(stroke
				(width 0.1)
				(type default)
			)
			(layer "F.Fab")
		)
		(fp_line
			(start -0.12065 -0.305054)
			(end -0.12065 -0.2794)
			(stroke
				(width 0.1)
				(type default)
			)
			(layer "F.Fab")
		)
		(pad "1" smd circle
			(at -0.40005 0 270)
			(size 0 0)
			(layers "F.Cu" "F.Mask" "F.Paste")
			(net "P3V3_SSD8")
		)
		(pad "2" smd circle
			(at 0.40005 0 270)
			(size 0 0)
			(layers "F.Cu" "F.Mask" "F.Paste")
			(net "SSD8_LED_ISO_N")
		)
	)
	(footprint ""
		(layer "F.Cu")
		(at 59.373262 -390.07161 -90)
		(property "Reference" "R1826"
			(at 0 0 270)
			(layer "F.SilkS")
			(hide yes)
			(effects
				(font
					(size 1.27 1.27)
				)
			)
		)
		(property "Value" ""
			(at 0 0 270)
			(layer "F.Fab")
			(effects
				(font
					(size 1.27 1.27)
				)
			)
		)
		(duplicate_pad_numbers_are_jumpers no)
		(fp_line
			(start -0.7874 0.4064)
			(end -0.7874 -0.4064)
			(stroke
				(width 0.1524)
				(type default)
			)
			(layer "F.SilkS")
		)
		(fp_line
			(start 0.7874 0.4064)
			(end -0.7874 0.4064)
			(stroke
				(width 0.1524)
				(type default)
			)
			(layer "F.SilkS")
		)
		(fp_line
			(start -0.7874 -0.4064)
			(end 0.7874 -0.4064)
			(stroke
				(width 0.1524)
				(type default)
			)
			(layer "F.SilkS")
		)
		(fp_line
			(start 0.7874 -0.4064)
			(end 0.7874 0.4064)
			(stroke
				(width 0.1524)
				(type default)
			)
			(layer "F.SilkS")
		)
		(fp_line
			(start -0.67945 0.3048)
			(end -0.67945 -0.305054)
			(stroke
				(width 0.1)
				(type default)
			)
			(layer "F.Fab")
		)
		(fp_line
			(start -0.12065 0.3048)
			(end -0.67945 0.3048)
			(stroke
				(width 0.1)
				(type default)
			)
			(layer "F.Fab")
		)
		(fp_line
			(start 0.120396 0.3048)
			(end 0.120396 0.2794)
			(stroke
				(width 0.1)
				(type default)
			)
			(layer "F.Fab")
		)
		(fp_line
			(start 0.67945 0.3048)
			(end 0.120396 0.3048)
			(stroke
				(width 0.1)
				(type default)
			)
			(layer "F.Fab")
		)
		(fp_line
			(start -0.12065 0.2794)
			(end -0.12065 0.3048)
			(stroke
				(width 0.1)
				(type default)
			)
			(layer "F.Fab")
		)
		(fp_line
			(start 0.120396 0.2794)
			(end -0.12065 0.2794)
			(stroke
				(width 0.1)
				(type default)
			)
			(layer "F.Fab")
		)
		(fp_line
			(start -0.12065 -0.2794)
			(end 0.12065 -0.2794)
			(stroke
				(width 0.1)
				(type default)
			)
			(layer "F.Fab")
		)
		(fp_line
			(start 0.12065 -0.2794)
			(end 0.12065 -0.3048)
			(stroke
				(width 0.1)
				(type default)
			)
			(layer "F.Fab")
		)
		(fp_line
			(start 0.12065 -0.3048)
			(end 0.67945 -0.3048)
			(stroke
				(width 0.1)
				(type default)
			)
			(layer "F.Fab")
		)
		(fp_line
			(start 0.67945 -0.3048)
			(end 0.67945 0.3048)
			(stroke
				(width 0.1)
				(type default)
			)
			(layer "F.Fab")
		)
		(fp_line
			(start -0.67945 -0.305054)
			(end -0.12065 -0.305054)
			(stroke
				(width 0.1)
				(type default)
			)
			(layer "F.Fab")
		)
		(fp_line
			(start -0.12065 -0.305054)
			(end -0.12065 -0.2794)
			(stroke
				(width 0.1)
				(type default)
			)
			(layer "F.Fab")
		)
		(pad "1" smd circle
			(at -0.40005 0 270)
			(size 0 0)
			(layers "F.Cu" "F.Mask" "F.Paste")
			(net "RST_GPU_FPGA_PEX_RST_R_N")
		)
		(pad "2" smd circle
			(at 0.40005 0 270)
			(size 0 0)
			(layers "F.Cu" "F.Mask" "F.Paste")
			(net "RST_GPU_FPGA_PEX_RST_N")
		)
	)
	(footprint ""
		(layer "F.Cu")
		(at 358.013 -214.376)
		(property "Reference" "R4091"
			(at 0 0 0)
			(layer "F.SilkS")
			(hide yes)
			(effects
				(font
					(size 1.27 1.27)
				)
			)
		)
		(property "Value" ""
			(at 0 0 0)
			(layer "F.Fab")
			(effects
				(font
					(size 1.27 1.27)
				)
			)
		)
		(duplicate_pad_numbers_are_jumpers no)
		(fp_line
			(start -0.7874 -0.4064)
			(end 0.7874 -0.4064)
			(stroke
				(width 0.1524)
				(type default)
			)
			(layer "F.SilkS")
		)
		(fp_line
			(start -0.7874 0.4064)
			(end -0.7874 -0.4064)
			(stroke
				(width 0.1524)
				(type default)
			)
			(layer "F.SilkS")
		)
		(fp_line
			(start 0.7874 -0.4064)
			(end 0.7874 0.4064)
			(stroke
				(width 0.1524)
				(type default)
			)
			(layer "F.SilkS")
		)
		(fp_line
			(start 0.7874 0.4064)
			(end -0.7874 0.4064)
			(stroke
				(width 0.1524)
				(type default)
			)
			(layer "F.SilkS")
		)
		(fp_line
			(start -0.67945 -0.305054)
			(end -0.12065 -0.305054)
			(stroke
				(width 0.1)
				(type default)
			)
			(layer "F.Fab")
		)
		(fp_line
			(start -0.67945 0.3048)
			(end -0.67945 -0.305054)
			(stroke
				(width 0.1)
				(type default)
			)
			(layer "F.Fab")
		)
		(fp_line
			(start -0.12065 -0.305054)
			(end -0.12065 -0.2794)
			(stroke
				(width 0.1)
				(type default)
			)
			(layer "F.Fab")
		)
		(fp_line
			(start -0.12065 -0.2794)
			(end 0.12065 -0.2794)
			(stroke
				(width 0.1)
				(type default)
			)
			(layer "F.Fab")
		)
		(fp_line
			(start -0.12065 0.2794)
			(end -0.12065 0.3048)
			(stroke
				(width 0.1)
				(type default)
			)
			(layer "F.Fab")
		)
		(fp_line
			(start -0.12065 0.3048)
			(end -0.67945 0.3048)
			(stroke
				(width 0.1)
				(type default)
			)
			(layer "F.Fab")
		)
		(fp_line
			(start 0.120396 0.2794)
			(end -0.12065 0.2794)
			(stroke
				(width 0.1)
				(type default)
			)
			(layer "F.Fab")
		)
		(fp_line
			(start 0.120396 0.3048)
			(end 0.120396 0.2794)
			(stroke
				(width 0.1)
				(type default)
			)
			(layer "F.Fab")
		)
		(fp_line
			(start 0.12065 -0.3048)
			(end 0.67945 -0.3048)
			(stroke
				(width 0.1)
				(type default)
			)
			(layer "F.Fab")
		)
		(fp_line
			(start 0.12065 -0.2794)
			(end 0.12065 -0.3048)
			(stroke
				(width 0.1)
				(type default)
			)
			(layer "F.Fab")
		)
		(fp_line
			(start 0.67945 -0.3048)
			(end 0.67945 0.3048)
			(stroke
				(width 0.1)
				(type default)
			)
			(layer "F.Fab")
		)
		(fp_line
			(start 0.67945 0.3048)
			(end 0.120396 0.3048)
			(stroke
				(width 0.1)
				(type default)
			)
			(layer "F.Fab")
		)
		(pad "1" smd circle
			(at -0.40005 0)
			(size 0 0)
			(layers "F.Cu" "F.Mask" "F.Paste")
			(net "NIC7_CLK_EN_N")
		)
		(pad "2" smd circle
			(at 0.40005 0)
			(size 0 0)
			(layers "F.Cu" "F.Mask" "F.Paste")
			(net "NIC7_CLK_EN_R_N")
		)
	)
	(footprint ""
		(layer "F.Cu")
		(at 366.955578 -90.642694 180)
		(property "Reference" "R1599"
			(at 0 0 180)
			(layer "F.SilkS")
			(hide yes)
			(effects
				(font
					(size 1.27 1.27)
				)
			)
		)
		(property "Value" ""
			(at 0 0 180)
			(layer "F.Fab")
			(effects
				(font
					(size 1.27 1.27)
				)
			)
		)
		(duplicate_pad_numbers_are_jumpers no)
		(fp_line
			(start 0.7874 0.4064)
			(end -0.7874 0.4064)
			(stroke
				(width 0.1524)
				(type default)
			)
			(layer "F.SilkS")
		)
		(fp_line
			(start 0.7874 -0.4064)
			(end 0.7874 0.4064)
			(stroke
				(width 0.1524)
				(type default)
			)
			(layer "F.SilkS")
		)
		(fp_line
			(start -0.7874 0.4064)
			(end -0.7874 -0.4064)
			(stroke
				(width 0.1524)
				(type default)
			)
			(layer "F.SilkS")
		)
		(fp_line
			(start -0.7874 -0.4064)
			(end 0.7874 -0.4064)
			(stroke
				(width 0.1524)
				(type default)
			)
			(layer "F.SilkS")
		)
		(fp_line
			(start 0.67945 0.3048)
			(end 0.120396 0.3048)
			(stroke
				(width 0.1)
				(type default)
			)
			(layer "F.Fab")
		)
		(fp_line
			(start 0.67945 -0.3048)
			(end 0.67945 0.3048)
			(stroke
				(width 0.1)
				(type default)
			)
			(layer "F.Fab")
		)
		(fp_line
			(start 0.12065 -0.2794)
			(end 0.12065 -0.3048)
			(stroke
				(width 0.1)
				(type default)
			)
			(layer "F.Fab")
		)
		(fp_line
			(start 0.12065 -0.3048)
			(end 0.67945 -0.3048)
			(stroke
				(width 0.1)
				(type default)
			)
			(layer "F.Fab")
		)
		(fp_line
			(start 0.120396 0.3048)
			(end 0.120396 0.2794)
			(stroke
				(width 0.1)
				(type default)
			)
			(layer "F.Fab")
		)
		(fp_line
			(start 0.120396 0.2794)
			(end -0.12065 0.2794)
			(stroke
				(width 0.1)
				(type default)
			)
			(layer "F.Fab")
		)
		(fp_line
			(start -0.12065 0.3048)
			(end -0.67945 0.3048)
			(stroke
				(width 0.1)
				(type default)
			)
			(layer "F.Fab")
		)
		(fp_line
			(start -0.12065 0.2794)
			(end -0.12065 0.3048)
			(stroke
				(width 0.1)
				(type default)
			)
			(layer "F.Fab")
		)
		(fp_line
			(start -0.12065 -0.2794)
			(end 0.12065 -0.2794)
			(stroke
				(width 0.1)
				(type default)
			)
			(layer "F.Fab")
		)
		(fp_line
			(start -0.12065 -0.305054)
			(end -0.12065 -0.2794)
			(stroke
				(width 0.1)
				(type default)
			)
			(layer "F.Fab")
		)
		(fp_line
			(start -0.67945 0.3048)
			(end -0.67945 -0.305054)
			(stroke
				(width 0.1)
				(type default)
			)
			(layer "F.Fab")
		)
		(fp_line
			(start -0.67945 -0.305054)
			(end -0.12065 -0.305054)
			(stroke
				(width 0.1)
				(type default)
			)
			(layer "F.Fab")
		)
		(pad "1" smd circle
			(at -0.40005 0 180)
			(size 0 0)
			(layers "F.Cu" "F.Mask" "F.Paste")
			(net "P3V3_AUX")
		)
		(pad "2" smd circle
			(at 0.40005 0 180)
			(size 0 0)
			(layers "F.Cu" "F.Mask" "F.Paste")
			(net "BIC_I2C9_SSD_MUX1_A2")
		)
	)
	(footprint ""
		(layer "F.Cu")
		(at 337.693 -241.808 -90)
		(property "Reference" "U144"
			(at -2.547366 -2.030984 90)
			(unlocked yes)
			(layer "F.SilkS")
			(effects
				(font
					(size 0.7874 0.5842)
					(thickness 0.1524)
				)
			)
		)
		(property "Value" ""
			(at 0 0 270)
			(layer "F.Fab")
			(effects
				(font
					(size 1.27 1.27)
				)
			)
		)
		(duplicate_pad_numbers_are_jumpers no)
		(fp_line
			(start -1.7272 1.1176)
			(end -1.7272 -1.1176)
			(stroke
				(width 0.1524)
				(type default)
			)
			(layer "F.SilkS")
		)
		(fp_line
			(start 1.7272 1.1176)
			(end -1.7272 1.1176)
			(stroke
				(width 0.1524)
				(type default)
			)
			(layer "F.SilkS")
		)
		(fp_line
			(start 0 -0.7366)
			(end -0.254 -1.1176)
			(stroke
				(width 0.1524)
				(type default)
			)
			(layer "F.SilkS")
		)
		(fp_line
			(start -0.254 -1.1176)
			(end -1.7272 -1.1176)
			(stroke
				(width 0.1524)
				(type default)
			)
			(layer "F.SilkS")
		)
		(fp_line
			(start 0.254 -1.1176)
			(end 0 -0.7366)
			(stroke
				(width 0.1524)
				(type default)
			)
			(layer "F.SilkS")
		)
		(fp_line
			(start 1.7272 -1.1176)
			(end 1.7272 1.1176)
			(stroke
				(width 0.1524)
				(type default)
			)
			(layer "F.SilkS")
		)
		(fp_line
			(start 1.7272 -1.1176)
			(end 0.254 -1.1176)
			(stroke
				(width 0.1524)
				(type default)
			)
			(layer "F.SilkS")
		)
		(fp_poly
			(pts
				(xy -1.9558 -0.649986) (xy -2.7178 -0.268986) (xy -2.7178 -1.030986)
			)
			(stroke
				(width 0)
				(type default)
			)
			(fill yes)
			(layer "F.SilkS")
		)
		(fp_line
			(start -1.5748 1.1176)
			(end 1.5748 1.1176)
			(stroke
				(width 0.1)
				(type default)
			)
			(layer "F.Fab")
		)
		(fp_line
			(start 1.5748 1.1176)
			(end 1.5748 -1.1176)
			(stroke
				(width 0.1)
				(type default)
			)
			(layer "F.Fab")
		)
		(fp_line
			(start -1.5748 -1.1176)
			(end -1.5748 1.1176)
			(stroke
				(width 0.1)
				(type default)
			)
			(layer "F.Fab")
		)
		(fp_line
			(start 1.5748 -1.1176)
			(end -1.5748 -1.1176)
			(stroke
				(width 0.1)
				(type default)
			)
			(layer "F.Fab")
		)
		(fp_poly
			(pts
				(xy -1.9558 -0.649986) (xy -2.7178 -0.268986) (xy -2.7178 -1.030986)
			)
			(stroke
				(width 0)
				(type default)
			)
			(fill yes)
			(layer "F.Fab")
		)
		(pad "1" smd rect
			(at -0.999998 -0.649986 180)
			(size 0.3556 1.1176)
			(layers "F.Cu" "F.Mask" "F.Paste")
			(net "RST_MB_PERST_2_N")
		)
		(pad "2" smd rect
			(at -0.999998 0 180)
			(size 0.3556 1.1176)
			(layers "F.Cu" "F.Mask" "F.Paste")
			(net "GND")
		)
		(pad "3" smd rect
			(at -0.999998 0.649986 180)
			(size 0.3556 1.1176)
			(layers "F.Cu" "F.Mask" "F.Paste")
			(net "MB_SWB_PWR_EN")
		)
		(pad "4" smd rect
			(at 0.999998 0.649986 180)
			(size 0.3556 1.1176)
			(layers "F.Cu" "F.Mask" "F.Paste")
			(net "MB_SWB_PWR_EN_ISO")
		)
		(pad "5" smd rect
			(at 0.999998 0 180)
			(size 0.3556 1.1176)
			(layers "F.Cu" "F.Mask" "F.Paste")
			(net "P3V3_AUX")
		)
		(pad "6" smd rect
			(at 0.999998 -0.649986 180)
			(size 0.3556 1.1176)
			(layers "F.Cu" "F.Mask" "F.Paste")
			(net "RST_MB_PERST_2_ISO_N")
		)
	)
	(footprint ""
		(layer "F.Cu")
		(at 224.074482 -441.524644)
		(property "Reference" "X67"
			(at -0.1778 -1.92913 0)
			(unlocked yes)
			(layer "F.SilkS")
			(effects
				(font
					(size 0.7874 0.5842)
					(thickness 0.1524)
				)
				(justify left)
			)
		)
		(property "Value" ""
			(at 0 0 0)
			(layer "F.Fab")
			(effects
				(font
					(size 1.27 1.27)
				)
			)
		)
		(property "Device Type" "TP_TDR_4P_FTS_MPKT4_H025P0200_IO_TP15_TP_TDR_4P_DIP"
			(at 1.30175 1.27 90)
			(unlocked yes)
			(layer "F.Fab")
			(hide yes)
			(effects
				(font
					(size 0.635 0.4064)
					(thickness 0.1524)
				)
			)
		)
		(property "User Part Number" "TP15"
			(at 1.30175 1.27 90)
			(unlocked yes)
			(layer "Cmts.User")
			(hide yes)
			(effects
				(font
					(size 0.635 0.4064)
					(thickness 0.1524)
				)
			)
		)
		(duplicate_pad_numbers_are_jumpers no)
		(fp_line
			(start 0 -1.27)
			(end 0 -0.635)
			(stroke
				(width 0.1524)
				(type default)
			)
			(layer "F.SilkS")
		)
		(fp_line
			(start 0 0.635)
			(end 0 1.905)
			(stroke
				(width 0.1524)
				(type default)
			)
			(layer "F.SilkS")
		)
		(fp_line
			(start 0 3.175)
			(end 0 3.81)
			(stroke
				(width 0.1524)
				(type default)
			)
			(layer "F.SilkS")
		)
		(fp_line
			(start 0 3.81)
			(end 2.54 3.81)
			(stroke
				(width 0.1524)
				(type default)
			)
			(layer "F.SilkS")
		)
		(fp_line
			(start 2.54 -1.27)
			(end 0 -1.27)
			(stroke
				(width 0.1524)
				(type default)
			)
			(layer "F.SilkS")
		)
		(fp_line
			(start 2.54 -1.1303)
			(end 2.54 -1.27)
			(stroke
				(width 0.1524)
				(type default)
			)
			(layer "F.SilkS")
		)
		(fp_line
			(start 2.54 1.4097)
			(end 2.54 1.1303)
			(stroke
				(width 0.1524)
				(type default)
			)
			(layer "F.SilkS")
		)
		(fp_line
			(start 2.54 3.81)
			(end 2.54 3.6703)
			(stroke
				(width 0.1524)
				(type default)
			)
			(layer "F.SilkS")
		)
		(fp_poly
			(pts
				(xy -0.761746 0) (xy -2.285746 -0.762) (xy -2.285746 0.762)
			)
			(stroke
				(width 0)
				(type default)
			)
			(fill yes)
			(layer "F.SilkS")
		)
		(fp_line
			(start 0 -1.27)
			(end 0 3.81)
			(stroke
				(width 0.1)
				(type default)
			)
			(layer "F.Fab")
		)
		(fp_line
			(start 0 3.81)
			(end 2.54 3.81)
			(stroke
				(width 0.1)
				(type default)
			)
			(layer "F.Fab")
		)
		(fp_line
			(start 2.54 -1.27)
			(end 0 -1.27)
			(stroke
				(width 0.1)
				(type default)
			)
			(layer "F.Fab")
		)
		(fp_line
			(start 2.54 3.81)
			(end 2.54 -1.27)
			(stroke
				(width 0.1)
				(type default)
			)
			(layer "F.Fab")
		)
		(fp_poly
			(pts
				(xy -0.761746 0) (xy -2.285746 -0.762) (xy -2.285746 0.762)
			)
			(stroke
				(width 0)
				(type default)
			)
			(fill yes)
			(layer "F.Fab")
		)
		(pad "1" thru_hole circle
			(at 0 0)
			(size 1.0033 1.0033)
			(drill 0.249936)
			(layers "*.Cu" "*.Mask")
			(remove_unused_layers no)
			(net "TDR_DIFF_100_TOP_DIN")
			(clearance 0.10795)
			(thermal_gap 0.10795)
			(padstack
				(mode front_inner_back)
				(layer "Inner"
					(shape circle)
					(size 0.8001 0.8001)
					(clearance 0.1524)
				)
				(layer "B.Cu"
					(shape circle)
					(size 1.0033 1.0033)
					(clearance 0.10795)
				)
			)
		)
		(pad "2" thru_hole circle
			(at 2.54 0)
			(size 1.9939 1.9939)
			(drill 0.249936)
			(layers "*.Cu" "*.Mask")
			(remove_unused_layers no)
			(net "COUPON_GND1")
			(clearance 0.10795)
			(thermal_gap 0.10795)
			(padstack
				(mode front_inner_back)
				(layer "Inner"
					(shape circle)
					(size 0.8001 0.8001)
					(clearance 0.1524)
				)
				(layer "B.Cu"
					(shape circle)
					(size 1.9939 1.9939)
					(clearance 0.10795)
				)
			)
		)
		(pad "3" thru_hole circle
			(at 2.54 2.54)
			(size 1.9939 1.9939)
			(drill 0.249936)
			(layers "*.Cu" "*.Mask")
			(remove_unused_layers no)
			(net "COUPON_GND1")
			(clearance 0.10795)
			(thermal_gap 0.10795)
			(padstack
				(mode front_inner_back)
				(layer "Inner"
					(shape circle)
					(size 0.8001 0.8001)
					(clearance 0.1524)
				)
				(layer "B.Cu"
					(shape circle)
					(size 1.9939 1.9939)
					(clearance 0.10795)
				)
			)
		)
		(pad "4" thru_hole circle
			(at 0 2.54)
			(size 1.0033 1.0033)
			(drill 0.249936)
			(layers "*.Cu" "*.Mask")
			(remove_unused_layers no)
			(net "TDR_DIFF_100_TOP_DIP")
			(clearance 0.10795)
			(thermal_gap 0.10795)
			(padstack
				(mode front_inner_back)
				(layer "Inner"
					(shape circle)
					(size 0.8001 0.8001)
					(clearance 0.1524)
				)
				(layer "B.Cu"
					(shape circle)
					(size 1.0033 1.0033)
					(clearance 0.10795)
				)
			)
		)
	)
	(footprint ""
		(layer "F.Cu")
		(at 144.149318 -280.994612 -90)
		(property "Reference" "C3194"
			(at 0 0 270)
			(layer "F.SilkS")
			(hide yes)
			(effects
				(font
					(size 1.27 1.27)
				)
			)
		)
		(property "Value" ""
			(at 0 0 270)
			(layer "F.Fab")
			(effects
				(font
					(size 1.27 1.27)
				)
			)
		)
		(duplicate_pad_numbers_are_jumpers no)
		(fp_line
			(start -0.299974 0.150114)
			(end -0.299974 -0.150114)
			(stroke
				(width 0.1)
				(type default)
			)
			(layer "F.Fab")
		)
		(fp_line
			(start 0.299974 0.150114)
			(end -0.299974 0.150114)
			(stroke
				(width 0.1)
				(type default)
			)
			(layer "F.Fab")
		)
		(fp_line
			(start -0.299974 -0.150114)
			(end 0.299974 -0.150114)
			(stroke
				(width 0.1)
				(type default)
			)
			(layer "F.Fab")
		)
		(fp_line
			(start 0.299974 -0.150114)
			(end 0.299974 0.150114)
			(stroke
				(width 0.1)
				(type default)
			)
			(layer "F.Fab")
		)
		(pad "1" smd rect
			(at -0.2667 0 270)
			(size 0.3048 0.381)
			(layers "F.Cu" "F.Mask" "F.Paste")
			(net "P1V8_PLL0_PEX1")
		)
		(pad "2" smd rect
			(at 0.2667 0 270)
			(size 0.3048 0.381)
			(layers "F.Cu" "F.Mask" "F.Paste")
			(net "GND")
		)
	)
	(footprint ""
		(layer "F.Cu")
		(at 430.961546 -135.28675 180)
		(property "Reference" "C651"
			(at 0 0 180)
			(layer "F.SilkS")
			(hide yes)
			(effects
				(font
					(size 1.27 1.27)
				)
			)
		)
		(property "Value" ""
			(at 0 0 180)
			(layer "F.Fab")
			(effects
				(font
					(size 1.27 1.27)
				)
			)
		)
		(duplicate_pad_numbers_are_jumpers no)
		(fp_line
			(start 0.299974 0.150114)
			(end -0.299974 0.150114)
			(stroke
				(width 0.1)
				(type default)
			)
			(layer "F.Fab")
		)
		(fp_line
			(start 0.299974 -0.150114)
			(end 0.299974 0.150114)
			(stroke
				(width 0.1)
				(type default)
			)
			(layer "F.Fab")
		)
		(fp_line
			(start -0.299974 0.150114)
			(end -0.299974 -0.150114)
			(stroke
				(width 0.1)
				(type default)
			)
			(layer "F.Fab")
		)
		(fp_line
			(start -0.299974 -0.150114)
			(end 0.299974 -0.150114)
			(stroke
				(width 0.1)
				(type default)
			)
			(layer "F.Fab")
		)
		(pad "1" smd rect
			(at -0.2667 0 180)
			(size 0.3048 0.381)
			(layers "F.Cu" "F.Mask" "F.Paste")
			(net "P5E_PEX3_STN0_TX_DN<7>")
		)
		(pad "2" smd rect
			(at 0.2667 0 180)
			(size 0.3048 0.381)
			(layers "F.Cu" "F.Mask" "F.Paste")
			(net "P5E_PEX3_STN0_TX_C_DN<7>")
		)
	)
	(footprint ""
		(layer "F.Cu")
		(at 409.600908 -177.778918 180)
		(property "Reference" "R6434"
			(at 0 0 180)
			(layer "F.SilkS")
			(hide yes)
			(effects
				(font
					(size 1.27 1.27)
				)
			)
		)
		(property "Value" ""
			(at 0 0 180)
			(layer "F.Fab")
			(effects
				(font
					(size 1.27 1.27)
				)
			)
		)
		(duplicate_pad_numbers_are_jumpers no)
		(fp_line
			(start 0.7874 0.4064)
			(end -0.7874 0.4064)
			(stroke
				(width 0.1524)
				(type default)
			)
			(layer "F.SilkS")
		)
		(fp_line
			(start 0.7874 -0.4064)
			(end 0.7874 0.4064)
			(stroke
				(width 0.1524)
				(type default)
			)
			(layer "F.SilkS")
		)
		(fp_line
			(start -0.7874 0.4064)
			(end -0.7874 -0.4064)
			(stroke
				(width 0.1524)
				(type default)
			)
			(layer "F.SilkS")
		)
		(fp_line
			(start -0.7874 -0.4064)
			(end 0.7874 -0.4064)
			(stroke
				(width 0.1524)
				(type default)
			)
			(layer "F.SilkS")
		)
		(fp_line
			(start 0.67945 0.3048)
			(end 0.120396 0.3048)
			(stroke
				(width 0.1)
				(type default)
			)
			(layer "F.Fab")
		)
		(fp_line
			(start 0.67945 -0.3048)
			(end 0.67945 0.3048)
			(stroke
				(width 0.1)
				(type default)
			)
			(layer "F.Fab")
		)
		(fp_line
			(start 0.12065 -0.2794)
			(end 0.12065 -0.3048)
			(stroke
				(width 0.1)
				(type default)
			)
			(layer "F.Fab")
		)
		(fp_line
			(start 0.12065 -0.3048)
			(end 0.67945 -0.3048)
			(stroke
				(width 0.1)
				(type default)
			)
			(layer "F.Fab")
		)
		(fp_line
			(start 0.120396 0.3048)
			(end 0.120396 0.2794)
			(stroke
				(width 0.1)
				(type default)
			)
			(layer "F.Fab")
		)
		(fp_line
			(start 0.120396 0.2794)
			(end -0.12065 0.2794)
			(stroke
				(width 0.1)
				(type default)
			)
			(layer "F.Fab")
		)
		(fp_line
			(start -0.12065 0.3048)
			(end -0.67945 0.3048)
			(stroke
				(width 0.1)
				(type default)
			)
			(layer "F.Fab")
		)
		(fp_line
			(start -0.12065 0.2794)
			(end -0.12065 0.3048)
			(stroke
				(width 0.1)
				(type default)
			)
			(layer "F.Fab")
		)
		(fp_line
			(start -0.12065 -0.2794)
			(end 0.12065 -0.2794)
			(stroke
				(width 0.1)
				(type default)
			)
			(layer "F.Fab")
		)
		(fp_line
			(start -0.12065 -0.305054)
			(end -0.12065 -0.2794)
			(stroke
				(width 0.1)
				(type default)
			)
			(layer "F.Fab")
		)
		(fp_line
			(start -0.67945 0.3048)
			(end -0.67945 -0.305054)
			(stroke
				(width 0.1)
				(type default)
			)
			(layer "F.Fab")
		)
		(fp_line
			(start -0.67945 -0.305054)
			(end -0.12065 -0.305054)
			(stroke
				(width 0.1)
				(type default)
			)
			(layer "F.Fab")
		)
		(pad "1" smd circle
			(at -0.40005 0 180)
			(size 0 0)
			(layers "F.Cu" "F.Mask" "F.Paste")
			(net "FPGA_PEX1_MODE_SEL1_ISO")
		)
		(pad "2" smd circle
			(at 0.40005 0 180)
			(size 0 0)
			(layers "F.Cu" "F.Mask" "F.Paste")
			(net "PEX1_MODE_SEL1")
		)
	)
	(footprint ""
		(layer "F.Cu")
		(at 378.561854 -311.007252 -135)
		(property "Reference" "R1460"
			(at 0 0 225)
			(layer "F.SilkS")
			(hide yes)
			(effects
				(font
					(size 1.27 1.27)
				)
			)
		)
		(property "Value" ""
			(at 0 0 225)
			(layer "F.Fab")
			(effects
				(font
					(size 1.27 1.27)
				)
			)
		)
		(duplicate_pad_numbers_are_jumpers no)
		(fp_line
			(start 0.787389 0.406267)
			(end -0.787389 0.406267)
			(stroke
				(width 0.1524)
				(type default)
			)
			(layer "F.SilkS")
		)
		(fp_line
			(start 0.787389 -0.406267)
			(end 0.787389 0.406267)
			(stroke
				(width 0.1524)
				(type default)
			)
			(layer "F.SilkS")
		)
		(fp_line
			(start -0.787389 0.406267)
			(end -0.787389 -0.406267)
			(stroke
				(width 0.1524)
				(type default)
			)
			(layer "F.SilkS")
		)
		(fp_line
			(start -0.787389 -0.406267)
			(end 0.787389 -0.406267)
			(stroke
				(width 0.1524)
				(type default)
			)
			(layer "F.SilkS")
		)
		(fp_line
			(start 0.679446 0.30479)
			(end 0.120515 0.30479)
			(stroke
				(width 0.1)
				(type default)
			)
			(layer "F.Fab")
		)
		(fp_line
			(start 0.120515 0.30479)
			(end 0.120335 0.279466)
			(stroke
				(width 0.1)
				(type default)
			)
			(layer "F.Fab")
		)
		(fp_line
			(start 0.120335 0.279466)
			(end -0.120695 0.279466)
			(stroke
				(width 0.1)
				(type default)
			)
			(layer "F.Fab")
		)
		(fp_line
			(start 0.679446 -0.30479)
			(end 0.679446 0.30479)
			(stroke
				(width 0.1)
				(type default)
			)
			(layer "F.Fab")
		)
		(fp_line
			(start -0.120515 0.30479)
			(end -0.679446 0.30479)
			(stroke
				(width 0.1)
				(type default)
			)
			(layer "F.Fab")
		)
		(fp_line
			(start -0.120695 0.279466)
			(end -0.120515 0.30479)
			(stroke
				(width 0.1)
				(type default)
			)
			(layer "F.Fab")
		)
		(fp_line
			(start 0.120695 -0.279466)
			(end 0.120515 -0.30479)
			(stroke
				(width 0.1)
				(type default)
			)
			(layer "F.Fab")
		)
		(fp_line
			(start 0.120515 -0.30479)
			(end 0.679446 -0.30479)
			(stroke
				(width 0.1)
				(type default)
			)
			(layer "F.Fab")
		)
		(fp_line
			(start -0.679446 0.30479)
			(end -0.679446 -0.305149)
			(stroke
				(width 0.1)
				(type default)
			)
			(layer "F.Fab")
		)
		(fp_line
			(start -0.120695 -0.279466)
			(end 0.120695 -0.279466)
			(stroke
				(width 0.1)
				(type default)
			)
			(layer "F.Fab")
		)
		(fp_line
			(start -0.120695 -0.304969)
			(end -0.120695 -0.279466)
			(stroke
				(width 0.1)
				(type default)
			)
			(layer "F.Fab")
		)
		(fp_line
			(start -0.679446 -0.305149)
			(end -0.120695 -0.304969)
			(stroke
				(width 0.1)
				(type default)
			)
			(layer "F.Fab")
		)
		(pad "1" smd circle
			(at -0.40005 0 225)
			(size 0 0)
			(layers "F.Cu" "F.Mask" "F.Paste")
			(net "PU_PEX3_PAD_TRI_L")
		)
		(pad "2" smd circle
			(at 0.40005 0 225)
			(size 0 0)
			(layers "F.Cu" "F.Mask" "F.Paste")
			(net "P1V8_PEX")
		)
	)
	(footprint ""
		(layer "F.Cu")
		(at 131.27863 -111.377476 -90)
		(property "Reference" "PR7011"
			(at 0 0 270)
			(layer "F.SilkS")
			(hide yes)
			(effects
				(font
					(size 1.27 1.27)
				)
			)
		)
		(property "Value" ""
			(at 0 0 270)
			(layer "F.Fab")
			(effects
				(font
					(size 1.27 1.27)
				)
			)
		)
		(duplicate_pad_numbers_are_jumpers no)
		(fp_line
			(start -0.7874 0.4064)
			(end -0.7874 -0.4064)
			(stroke
				(width 0.1524)
				(type default)
			)
			(layer "F.SilkS")
		)
		(fp_line
			(start 0.7874 0.4064)
			(end -0.7874 0.4064)
			(stroke
				(width 0.1524)
				(type default)
			)
			(layer "F.SilkS")
		)
		(fp_line
			(start -0.7874 -0.4064)
			(end 0.7874 -0.4064)
			(stroke
				(width 0.1524)
				(type default)
			)
			(layer "F.SilkS")
		)
		(fp_line
			(start 0.7874 -0.4064)
			(end 0.7874 0.4064)
			(stroke
				(width 0.1524)
				(type default)
			)
			(layer "F.SilkS")
		)
		(fp_line
			(start -0.67945 0.3048)
			(end -0.67945 -0.305054)
			(stroke
				(width 0.1)
				(type default)
			)
			(layer "F.Fab")
		)
		(fp_line
			(start -0.12065 0.3048)
			(end -0.67945 0.3048)
			(stroke
				(width 0.1)
				(type default)
			)
			(layer "F.Fab")
		)
		(fp_line
			(start 0.120396 0.3048)
			(end 0.120396 0.2794)
			(stroke
				(width 0.1)
				(type default)
			)
			(layer "F.Fab")
		)
		(fp_line
			(start 0.67945 0.3048)
			(end 0.120396 0.3048)
			(stroke
				(width 0.1)
				(type default)
			)
			(layer "F.Fab")
		)
		(fp_line
			(start -0.12065 0.2794)
			(end -0.12065 0.3048)
			(stroke
				(width 0.1)
				(type default)
			)
			(layer "F.Fab")
		)
		(fp_line
			(start 0.120396 0.2794)
			(end -0.12065 0.2794)
			(stroke
				(width 0.1)
				(type default)
			)
			(layer "F.Fab")
		)
		(fp_line
			(start -0.12065 -0.2794)
			(end 0.12065 -0.2794)
			(stroke
				(width 0.1)
				(type default)
			)
			(layer "F.Fab")
		)
		(fp_line
			(start 0.12065 -0.2794)
			(end 0.12065 -0.3048)
			(stroke
				(width 0.1)
				(type default)
			)
			(layer "F.Fab")
		)
		(fp_line
			(start 0.12065 -0.3048)
			(end 0.67945 -0.3048)
			(stroke
				(width 0.1)
				(type default)
			)
			(layer "F.Fab")
		)
		(fp_line
			(start 0.67945 -0.3048)
			(end 0.67945 0.3048)
			(stroke
				(width 0.1)
				(type default)
			)
			(layer "F.Fab")
		)
		(fp_line
			(start -0.67945 -0.305054)
			(end -0.12065 -0.305054)
			(stroke
				(width 0.1)
				(type default)
			)
			(layer "F.Fab")
		)
		(fp_line
			(start -0.12065 -0.305054)
			(end -0.12065 -0.2794)
			(stroke
				(width 0.1)
				(type default)
			)
			(layer "F.Fab")
		)
		(pad "1" smd circle
			(at -0.40005 0 270)
			(size 0 0)
			(layers "F.Cu" "F.Mask" "F.Paste")
			(net "P3V3_NIC2_CO_MODE")
		)
		(pad "2" smd circle
			(at 0.40005 0 270)
			(size 0 0)
			(layers "F.Cu" "F.Mask" "F.Paste")
			(net "GND")
		)
	)
	(footprint ""
		(layer "F.Cu")
		(at 84.50199 -141.150848 -90)
		(property "Reference" "U14"
			(at 2.671318 0.73279 0)
			(unlocked yes)
			(layer "F.SilkS")
			(effects
				(font
					(size 0.7874 0.5842)
					(thickness 0.1524)
				)
			)
		)
		(property "Value" ""
			(at 0 0 270)
			(layer "F.Fab")
			(effects
				(font
					(size 1.27 1.27)
				)
			)
		)
		(duplicate_pad_numbers_are_jumpers no)
		(fp_line
			(start -1.949958 1.610106)
			(end -1.949958 -1.610106)
			(stroke
				(width 0.1524)
				(type default)
			)
			(layer "F.SilkS")
		)
		(fp_line
			(start 1.949958 1.610106)
			(end -1.949958 1.610106)
			(stroke
				(width 0.1524)
				(type default)
			)
			(layer "F.SilkS")
		)
		(fp_line
			(start 1.949958 -1.560068)
			(end 1.949958 1.610106)
			(stroke
				(width 0.1524)
				(type default)
			)
			(layer "F.SilkS")
		)
		(fp_line
			(start -1.949958 -1.610106)
			(end 1.949958 -1.610106)
			(stroke
				(width 0.1524)
				(type default)
			)
			(layer "F.SilkS")
		)
		(fp_line
			(start -0.750062 1.560068)
			(end -0.750062 -1.560068)
			(stroke
				(width 0.1)
				(type default)
			)
			(layer "F.Fab")
		)
		(fp_line
			(start 0.750062 1.560068)
			(end -0.750062 1.560068)
			(stroke
				(width 0.1)
				(type default)
			)
			(layer "F.Fab")
		)
		(fp_line
			(start -0.750062 -1.560068)
			(end 0.750062 -1.560068)
			(stroke
				(width 0.1)
				(type default)
			)
			(layer "F.Fab")
		)
		(fp_line
			(start 0.750062 -1.560068)
			(end 0.750062 1.560068)
			(stroke
				(width 0.1)
				(type default)
			)
			(layer "F.Fab")
		)
		(pad "D" smd rect
			(at 1.100074 0 180)
			(size 1.016 1.4224)
			(layers "F.Cu" "F.Mask" "F.Paste")
			(net "HP_NIC1_EN")
		)
		(pad "G" smd rect
			(at -1.100074 -0.94996 180)
			(size 1.016 1.4224)
			(layers "F.Cu" "F.Mask" "F.Paste")
			(net "PRSNT_NIC1_R_N")
		)
		(pad "S" smd rect
			(at -1.100074 0.94996 180)
			(size 1.016 1.4224)
			(layers "F.Cu" "F.Mask" "F.Paste")
			(net "GND")
		)
	)
	(footprint ""
		(layer "F.Cu")
		(at 358.013 -223.52 180)
		(property "Reference" "R3632"
			(at 0 0 180)
			(layer "F.SilkS")
			(hide yes)
			(effects
				(font
					(size 1.27 1.27)
				)
			)
		)
		(property "Value" ""
			(at 0 0 180)
			(layer "F.Fab")
			(effects
				(font
					(size 1.27 1.27)
				)
			)
		)
		(duplicate_pad_numbers_are_jumpers no)
		(fp_line
			(start 0.7874 0.4064)
			(end -0.7874 0.4064)
			(stroke
				(width 0.1524)
				(type default)
			)
			(layer "F.SilkS")
		)
		(fp_line
			(start 0.7874 -0.4064)
			(end 0.7874 0.4064)
			(stroke
				(width 0.1524)
				(type default)
			)
			(layer "F.SilkS")
		)
		(fp_line
			(start -0.7874 0.4064)
			(end -0.7874 -0.4064)
			(stroke
				(width 0.1524)
				(type default)
			)
			(layer "F.SilkS")
		)
		(fp_line
			(start -0.7874 -0.4064)
			(end 0.7874 -0.4064)
			(stroke
				(width 0.1524)
				(type default)
			)
			(layer "F.SilkS")
		)
		(fp_line
			(start 0.67945 0.3048)
			(end 0.120396 0.3048)
			(stroke
				(width 0.1)
				(type default)
			)
			(layer "F.Fab")
		)
		(fp_line
			(start 0.67945 -0.3048)
			(end 0.67945 0.3048)
			(stroke
				(width 0.1)
				(type default)
			)
			(layer "F.Fab")
		)
		(fp_line
			(start 0.12065 -0.2794)
			(end 0.12065 -0.3048)
			(stroke
				(width 0.1)
				(type default)
			)
			(layer "F.Fab")
		)
		(fp_line
			(start 0.12065 -0.3048)
			(end 0.67945 -0.3048)
			(stroke
				(width 0.1)
				(type default)
			)
			(layer "F.Fab")
		)
		(fp_line
			(start 0.120396 0.3048)
			(end 0.120396 0.2794)
			(stroke
				(width 0.1)
				(type default)
			)
			(layer "F.Fab")
		)
		(fp_line
			(start 0.120396 0.2794)
			(end -0.12065 0.2794)
			(stroke
				(width 0.1)
				(type default)
			)
			(layer "F.Fab")
		)
		(fp_line
			(start -0.12065 0.3048)
			(end -0.67945 0.3048)
			(stroke
				(width 0.1)
				(type default)
			)
			(layer "F.Fab")
		)
		(fp_line
			(start -0.12065 0.2794)
			(end -0.12065 0.3048)
			(stroke
				(width 0.1)
				(type default)
			)
			(layer "F.Fab")
		)
		(fp_line
			(start -0.12065 -0.2794)
			(end 0.12065 -0.2794)
			(stroke
				(width 0.1)
				(type default)
			)
			(layer "F.Fab")
		)
		(fp_line
			(start -0.12065 -0.305054)
			(end -0.12065 -0.2794)
			(stroke
				(width 0.1)
				(type default)
			)
			(layer "F.Fab")
		)
		(fp_line
			(start -0.67945 0.3048)
			(end -0.67945 -0.305054)
			(stroke
				(width 0.1)
				(type default)
			)
			(layer "F.Fab")
		)
		(fp_line
			(start -0.67945 -0.305054)
			(end -0.12065 -0.305054)
			(stroke
				(width 0.1)
				(type default)
			)
			(layer "F.Fab")
		)
		(pad "1" smd circle
			(at -0.40005 0 180)
			(size 0 0)
			(layers "F.Cu" "F.Mask" "F.Paste")
			(net "NIC3_CLK_EN_R_N")
		)
		(pad "2" smd circle
			(at 0.40005 0 180)
			(size 0 0)
			(layers "F.Cu" "F.Mask" "F.Paste")
			(net "NIC3_CLK_EN_N")
		)
	)
	(footprint ""
		(layer "F.Cu")
		(at 144.441926 -27.006296 -90)
		(property "Reference" "PR7110"
			(at 0 0 270)
			(layer "F.SilkS")
			(hide yes)
			(effects
				(font
					(size 1.27 1.27)
				)
			)
		)
		(property "Value" ""
			(at 0 0 270)
			(layer "F.Fab")
			(effects
				(font
					(size 1.27 1.27)
				)
			)
		)
		(duplicate_pad_numbers_are_jumpers no)
		(fp_line
			(start -0.7874 0.4064)
			(end -0.7874 -0.4064)
			(stroke
				(width 0.1524)
				(type default)
			)
			(layer "F.SilkS")
		)
		(fp_line
			(start 0.7874 0.4064)
			(end -0.7874 0.4064)
			(stroke
				(width 0.1524)
				(type default)
			)
			(layer "F.SilkS")
		)
		(fp_line
			(start -0.7874 -0.4064)
			(end 0.7874 -0.4064)
			(stroke
				(width 0.1524)
				(type default)
			)
			(layer "F.SilkS")
		)
		(fp_line
			(start 0.7874 -0.4064)
			(end 0.7874 0.4064)
			(stroke
				(width 0.1524)
				(type default)
			)
			(layer "F.SilkS")
		)
		(fp_line
			(start -0.67945 0.3048)
			(end -0.67945 -0.305054)
			(stroke
				(width 0.1)
				(type default)
			)
			(layer "F.Fab")
		)
		(fp_line
			(start -0.12065 0.3048)
			(end -0.67945 0.3048)
			(stroke
				(width 0.1)
				(type default)
			)
			(layer "F.Fab")
		)
		(fp_line
			(start 0.120396 0.3048)
			(end 0.120396 0.2794)
			(stroke
				(width 0.1)
				(type default)
			)
			(layer "F.Fab")
		)
		(fp_line
			(start 0.67945 0.3048)
			(end 0.120396 0.3048)
			(stroke
				(width 0.1)
				(type default)
			)
			(layer "F.Fab")
		)
		(fp_line
			(start -0.12065 0.2794)
			(end -0.12065 0.3048)
			(stroke
				(width 0.1)
				(type default)
			)
			(layer "F.Fab")
		)
		(fp_line
			(start 0.120396 0.2794)
			(end -0.12065 0.2794)
			(stroke
				(width 0.1)
				(type default)
			)
			(layer "F.Fab")
		)
		(fp_line
			(start -0.12065 -0.2794)
			(end 0.12065 -0.2794)
			(stroke
				(width 0.1)
				(type default)
			)
			(layer "F.Fab")
		)
		(fp_line
			(start 0.12065 -0.2794)
			(end 0.12065 -0.3048)
			(stroke
				(width 0.1)
				(type default)
			)
			(layer "F.Fab")
		)
		(fp_line
			(start 0.12065 -0.3048)
			(end 0.67945 -0.3048)
			(stroke
				(width 0.1)
				(type default)
			)
			(layer "F.Fab")
		)
		(fp_line
			(start 0.67945 -0.3048)
			(end 0.67945 0.3048)
			(stroke
				(width 0.1)
				(type default)
			)
			(layer "F.Fab")
		)
		(fp_line
			(start -0.67945 -0.305054)
			(end -0.12065 -0.305054)
			(stroke
				(width 0.1)
				(type default)
			)
			(layer "F.Fab")
		)
		(fp_line
			(start -0.12065 -0.305054)
			(end -0.12065 -0.2794)
			(stroke
				(width 0.1)
				(type default)
			)
			(layer "F.Fab")
		)
		(pad "1" smd circle
			(at -0.40005 0 270)
			(size 0 0)
			(layers "F.Cu" "F.Mask" "F.Paste")
			(net "P3V3_SSD5_CO_ILIMIT")
		)
		(pad "2" smd circle
			(at 0.40005 0 270)
			(size 0 0)
			(layers "F.Cu" "F.Mask" "F.Paste")
			(net "GND")
		)
	)
	(footprint ""
		(layer "F.Cu")
		(at 412.378652 -343.952322 90)
		(property "Reference" "C2441"
			(at 0 0 90)
			(layer "F.SilkS")
			(hide yes)
			(effects
				(font
					(size 1.27 1.27)
				)
			)
		)
		(property "Value" ""
			(at 0 0 90)
			(layer "F.Fab")
			(effects
				(font
					(size 1.27 1.27)
				)
			)
		)
		(duplicate_pad_numbers_are_jumpers no)
		(fp_line
			(start 0.299974 -0.150114)
			(end 0.299974 0.150114)
			(stroke
				(width 0.1)
				(type default)
			)
			(layer "F.Fab")
		)
		(fp_line
			(start -0.299974 -0.150114)
			(end 0.299974 -0.150114)
			(stroke
				(width 0.1)
				(type default)
			)
			(layer "F.Fab")
		)
		(fp_line
			(start 0.299974 0.150114)
			(end -0.299974 0.150114)
			(stroke
				(width 0.1)
				(type default)
			)
			(layer "F.Fab")
		)
		(fp_line
			(start -0.299974 0.150114)
			(end -0.299974 -0.150114)
			(stroke
				(width 0.1)
				(type default)
			)
			(layer "F.Fab")
		)
		(pad "1" smd rect
			(at -0.2667 0 90)
			(size 0.3048 0.381)
			(layers "F.Cu" "F.Mask" "F.Paste")
			(net "P5E_PEX3_STN4_TX_DP<78>")
		)
		(pad "2" smd rect
			(at 0.2667 0 90)
			(size 0.3048 0.381)
			(layers "F.Cu" "F.Mask" "F.Paste")
			(net "P5E_PEX3_STN4_TX_C_DP<78>")
		)
	)
	(footprint ""
		(layer "F.Cu")
		(at 223.586294 -176.52238)
		(property "Reference" "R3145"
			(at 0 0 0)
			(layer "F.SilkS")
			(hide yes)
			(effects
				(font
					(size 1.27 1.27)
				)
			)
		)
		(property "Value" ""
			(at 0 0 0)
			(layer "F.Fab")
			(effects
				(font
					(size 1.27 1.27)
				)
			)
		)
		(duplicate_pad_numbers_are_jumpers no)
		(fp_line
			(start -0.7874 -0.4064)
			(end 0.7874 -0.4064)
			(stroke
				(width 0.1524)
				(type default)
			)
			(layer "F.SilkS")
		)
		(fp_line
			(start -0.7874 0.4064)
			(end -0.7874 -0.4064)
			(stroke
				(width 0.1524)
				(type default)
			)
			(layer "F.SilkS")
		)
		(fp_line
			(start 0.7874 -0.4064)
			(end 0.7874 0.4064)
			(stroke
				(width 0.1524)
				(type default)
			)
			(layer "F.SilkS")
		)
		(fp_line
			(start 0.7874 0.4064)
			(end -0.7874 0.4064)
			(stroke
				(width 0.1524)
				(type default)
			)
			(layer "F.SilkS")
		)
		(fp_line
			(start -0.67945 -0.305054)
			(end -0.12065 -0.305054)
			(stroke
				(width 0.1)
				(type default)
			)
			(layer "F.Fab")
		)
		(fp_line
			(start -0.67945 0.3048)
			(end -0.67945 -0.305054)
			(stroke
				(width 0.1)
				(type default)
			)
			(layer "F.Fab")
		)
		(fp_line
			(start -0.12065 -0.305054)
			(end -0.12065 -0.2794)
			(stroke
				(width 0.1)
				(type default)
			)
			(layer "F.Fab")
		)
		(fp_line
			(start -0.12065 -0.2794)
			(end 0.12065 -0.2794)
			(stroke
				(width 0.1)
				(type default)
			)
			(layer "F.Fab")
		)
		(fp_line
			(start -0.12065 0.2794)
			(end -0.12065 0.3048)
			(stroke
				(width 0.1)
				(type default)
			)
			(layer "F.Fab")
		)
		(fp_line
			(start -0.12065 0.3048)
			(end -0.67945 0.3048)
			(stroke
				(width 0.1)
				(type default)
			)
			(layer "F.Fab")
		)
		(fp_line
			(start 0.120396 0.2794)
			(end -0.12065 0.2794)
			(stroke
				(width 0.1)
				(type default)
			)
			(layer "F.Fab")
		)
		(fp_line
			(start 0.120396 0.3048)
			(end 0.120396 0.2794)
			(stroke
				(width 0.1)
				(type default)
			)
			(layer "F.Fab")
		)
		(fp_line
			(start 0.12065 -0.3048)
			(end 0.67945 -0.3048)
			(stroke
				(width 0.1)
				(type default)
			)
			(layer "F.Fab")
		)
		(fp_line
			(start 0.12065 -0.2794)
			(end 0.12065 -0.3048)
			(stroke
				(width 0.1)
				(type default)
			)
			(layer "F.Fab")
		)
		(fp_line
			(start 0.67945 -0.3048)
			(end 0.67945 0.3048)
			(stroke
				(width 0.1)
				(type default)
			)
			(layer "F.Fab")
		)
		(fp_line
			(start 0.67945 0.3048)
			(end 0.120396 0.3048)
			(stroke
				(width 0.1)
				(type default)
			)
			(layer "F.Fab")
		)
		(pad "1" smd circle
			(at -0.40005 0)
			(size 0 0)
			(layers "F.Cu" "F.Mask" "F.Paste")
			(net "P3V3_AUX")
		)
		(pad "2" smd circle
			(at 0.40005 0)
			(size 0 0)
			(layers "F.Cu" "F.Mask" "F.Paste")
			(net "ADM1085_CEXT")
		)
	)
	(footprint ""
		(layer "F.Cu")
		(at 364.08487 -391.665968 -90)
		(property "Reference" "R6697"
			(at 0 0 270)
			(layer "F.SilkS")
			(hide yes)
			(effects
				(font
					(size 1.27 1.27)
				)
			)
		)
		(property "Value" ""
			(at 0 0 270)
			(layer "F.Fab")
			(effects
				(font
					(size 1.27 1.27)
				)
			)
		)
		(duplicate_pad_numbers_are_jumpers no)
		(fp_line
			(start -0.7874 0.4064)
			(end -0.7874 -0.4064)
			(stroke
				(width 0.1524)
				(type default)
			)
			(layer "F.SilkS")
		)
		(fp_line
			(start 0.7874 0.4064)
			(end -0.7874 0.4064)
			(stroke
				(width 0.1524)
				(type default)
			)
			(layer "F.SilkS")
		)
		(fp_line
			(start -0.7874 -0.4064)
			(end 0.7874 -0.4064)
			(stroke
				(width 0.1524)
				(type default)
			)
			(layer "F.SilkS")
		)
		(fp_line
			(start 0.7874 -0.4064)
			(end 0.7874 0.4064)
			(stroke
				(width 0.1524)
				(type default)
			)
			(layer "F.SilkS")
		)
		(fp_line
			(start -0.67945 0.3048)
			(end -0.67945 -0.305054)
			(stroke
				(width 0.1)
				(type default)
			)
			(layer "F.Fab")
		)
		(fp_line
			(start -0.12065 0.3048)
			(end -0.67945 0.3048)
			(stroke
				(width 0.1)
				(type default)
			)
			(layer "F.Fab")
		)
		(fp_line
			(start 0.120396 0.3048)
			(end 0.120396 0.2794)
			(stroke
				(width 0.1)
				(type default)
			)
			(layer "F.Fab")
		)
		(fp_line
			(start 0.67945 0.3048)
			(end 0.120396 0.3048)
			(stroke
				(width 0.1)
				(type default)
			)
			(layer "F.Fab")
		)
		(fp_line
			(start -0.12065 0.2794)
			(end -0.12065 0.3048)
			(stroke
				(width 0.1)
				(type default)
			)
			(layer "F.Fab")
		)
		(fp_line
			(start 0.120396 0.2794)
			(end -0.12065 0.2794)
			(stroke
				(width 0.1)
				(type default)
			)
			(layer "F.Fab")
		)
		(fp_line
			(start -0.12065 -0.2794)
			(end 0.12065 -0.2794)
			(stroke
				(width 0.1)
				(type default)
			)
			(layer "F.Fab")
		)
		(fp_line
			(start 0.12065 -0.2794)
			(end 0.12065 -0.3048)
			(stroke
				(width 0.1)
				(type default)
			)
			(layer "F.Fab")
		)
		(fp_line
			(start 0.12065 -0.3048)
			(end 0.67945 -0.3048)
			(stroke
				(width 0.1)
				(type default)
			)
			(layer "F.Fab")
		)
		(fp_line
			(start 0.67945 -0.3048)
			(end 0.67945 0.3048)
			(stroke
				(width 0.1)
				(type default)
			)
			(layer "F.Fab")
		)
		(fp_line
			(start -0.67945 -0.305054)
			(end -0.12065 -0.305054)
			(stroke
				(width 0.1)
				(type default)
			)
			(layer "F.Fab")
		)
		(fp_line
			(start -0.12065 -0.305054)
			(end -0.12065 -0.2794)
			(stroke
				(width 0.1)
				(type default)
			)
			(layer "F.Fab")
		)
		(pad "1" smd circle
			(at -0.40005 0 270)
			(size 0 0)
			(layers "F.Cu" "F.Mask" "F.Paste")
			(net "P3V3_AUX")
		)
		(pad "2" smd circle
			(at 0.40005 0 270)
			(size 0 0)
			(layers "F.Cu" "F.Mask" "F.Paste")
			(net "MB_3V3IO_RSVD1")
		)
	)
	(footprint ""
		(layer "F.Cu")
		(at 414.680908 -180.699918 180)
		(property "Reference" "R6431"
			(at 0 0 180)
			(layer "F.SilkS")
			(hide yes)
			(effects
				(font
					(size 1.27 1.27)
				)
			)
		)
		(property "Value" ""
			(at 0 0 180)
			(layer "F.Fab")
			(effects
				(font
					(size 1.27 1.27)
				)
			)
		)
		(duplicate_pad_numbers_are_jumpers no)
		(fp_line
			(start 0.7874 0.4064)
			(end -0.7874 0.4064)
			(stroke
				(width 0.1524)
				(type default)
			)
			(layer "F.SilkS")
		)
		(fp_line
			(start 0.7874 -0.4064)
			(end 0.7874 0.4064)
			(stroke
				(width 0.1524)
				(type default)
			)
			(layer "F.SilkS")
		)
		(fp_line
			(start -0.7874 0.4064)
			(end -0.7874 -0.4064)
			(stroke
				(width 0.1524)
				(type default)
			)
			(layer "F.SilkS")
		)
		(fp_line
			(start -0.7874 -0.4064)
			(end 0.7874 -0.4064)
			(stroke
				(width 0.1524)
				(type default)
			)
			(layer "F.SilkS")
		)
		(fp_line
			(start 0.67945 0.3048)
			(end 0.120396 0.3048)
			(stroke
				(width 0.1)
				(type default)
			)
			(layer "F.Fab")
		)
		(fp_line
			(start 0.67945 -0.3048)
			(end 0.67945 0.3048)
			(stroke
				(width 0.1)
				(type default)
			)
			(layer "F.Fab")
		)
		(fp_line
			(start 0.12065 -0.2794)
			(end 0.12065 -0.3048)
			(stroke
				(width 0.1)
				(type default)
			)
			(layer "F.Fab")
		)
		(fp_line
			(start 0.12065 -0.3048)
			(end 0.67945 -0.3048)
			(stroke
				(width 0.1)
				(type default)
			)
			(layer "F.Fab")
		)
		(fp_line
			(start 0.120396 0.3048)
			(end 0.120396 0.2794)
			(stroke
				(width 0.1)
				(type default)
			)
			(layer "F.Fab")
		)
		(fp_line
			(start 0.120396 0.2794)
			(end -0.12065 0.2794)
			(stroke
				(width 0.1)
				(type default)
			)
			(layer "F.Fab")
		)
		(fp_line
			(start -0.12065 0.3048)
			(end -0.67945 0.3048)
			(stroke
				(width 0.1)
				(type default)
			)
			(layer "F.Fab")
		)
		(fp_line
			(start -0.12065 0.2794)
			(end -0.12065 0.3048)
			(stroke
				(width 0.1)
				(type default)
			)
			(layer "F.Fab")
		)
		(fp_line
			(start -0.12065 -0.2794)
			(end 0.12065 -0.2794)
			(stroke
				(width 0.1)
				(type default)
			)
			(layer "F.Fab")
		)
		(fp_line
			(start -0.12065 -0.305054)
			(end -0.12065 -0.2794)
			(stroke
				(width 0.1)
				(type default)
			)
			(layer "F.Fab")
		)
		(fp_line
			(start -0.67945 0.3048)
			(end -0.67945 -0.305054)
			(stroke
				(width 0.1)
				(type default)
			)
			(layer "F.Fab")
		)
		(fp_line
			(start -0.67945 -0.305054)
			(end -0.12065 -0.305054)
			(stroke
				(width 0.1)
				(type default)
			)
			(layer "F.Fab")
		)
		(pad "1" smd circle
			(at -0.40005 0 180)
			(size 0 0)
			(layers "F.Cu" "F.Mask" "F.Paste")
			(net "FPGA_PEX1_MODE_SEL1_D_N")
		)
		(pad "2" smd circle
			(at 0.40005 0 180)
			(size 0 0)
			(layers "F.Cu" "F.Mask" "F.Paste")
			(net "P3V3_AUX")
		)
	)
	(footprint ""
		(layer "F.Cu")
		(at 377.156218 -32.848042 -90)
		(property "Reference" "R6103"
			(at 0 0 270)
			(layer "F.SilkS")
			(hide yes)
			(effects
				(font
					(size 1.27 1.27)
				)
			)
		)
		(property "Value" ""
			(at 0 0 270)
			(layer "F.Fab")
			(effects
				(font
					(size 1.27 1.27)
				)
			)
		)
		(duplicate_pad_numbers_are_jumpers no)
		(fp_line
			(start -0.7874 0.4064)
			(end -0.7874 -0.4064)
			(stroke
				(width 0.1524)
				(type default)
			)
			(layer "F.SilkS")
		)
		(fp_line
			(start 0.7874 0.4064)
			(end -0.7874 0.4064)
			(stroke
				(width 0.1524)
				(type default)
			)
			(layer "F.SilkS")
		)
		(fp_line
			(start -0.7874 -0.4064)
			(end 0.7874 -0.4064)
			(stroke
				(width 0.1524)
				(type default)
			)
			(layer "F.SilkS")
		)
		(fp_line
			(start 0.7874 -0.4064)
			(end 0.7874 0.4064)
			(stroke
				(width 0.1524)
				(type default)
			)
			(layer "F.SilkS")
		)
		(fp_line
			(start -0.67945 0.3048)
			(end -0.67945 -0.305054)
			(stroke
				(width 0.1)
				(type default)
			)
			(layer "F.Fab")
		)
		(fp_line
			(start -0.12065 0.3048)
			(end -0.67945 0.3048)
			(stroke
				(width 0.1)
				(type default)
			)
			(layer "F.Fab")
		)
		(fp_line
			(start 0.120396 0.3048)
			(end 0.120396 0.2794)
			(stroke
				(width 0.1)
				(type default)
			)
			(layer "F.Fab")
		)
		(fp_line
			(start 0.67945 0.3048)
			(end 0.120396 0.3048)
			(stroke
				(width 0.1)
				(type default)
			)
			(layer "F.Fab")
		)
		(fp_line
			(start -0.12065 0.2794)
			(end -0.12065 0.3048)
			(stroke
				(width 0.1)
				(type default)
			)
			(layer "F.Fab")
		)
		(fp_line
			(start 0.120396 0.2794)
			(end -0.12065 0.2794)
			(stroke
				(width 0.1)
				(type default)
			)
			(layer "F.Fab")
		)
		(fp_line
			(start -0.12065 -0.2794)
			(end 0.12065 -0.2794)
			(stroke
				(width 0.1)
				(type default)
			)
			(layer "F.Fab")
		)
		(fp_line
			(start 0.12065 -0.2794)
			(end 0.12065 -0.3048)
			(stroke
				(width 0.1)
				(type default)
			)
			(layer "F.Fab")
		)
		(fp_line
			(start 0.12065 -0.3048)
			(end 0.67945 -0.3048)
			(stroke
				(width 0.1)
				(type default)
			)
			(layer "F.Fab")
		)
		(fp_line
			(start 0.67945 -0.3048)
			(end 0.67945 0.3048)
			(stroke
				(width 0.1)
				(type default)
			)
			(layer "F.Fab")
		)
		(fp_line
			(start -0.67945 -0.305054)
			(end -0.12065 -0.305054)
			(stroke
				(width 0.1)
				(type default)
			)
			(layer "F.Fab")
		)
		(fp_line
			(start -0.12065 -0.305054)
			(end -0.12065 -0.2794)
			(stroke
				(width 0.1)
				(type default)
			)
			(layer "F.Fab")
		)
		(pad "1" smd circle
			(at -0.40005 0 270)
			(size 0 0)
			(layers "F.Cu" "F.Mask" "F.Paste")
			(net "SSD13_AUX_P3V3_EN_R")
		)
		(pad "2" smd circle
			(at 0.40005 0 270)
			(size 0 0)
			(layers "F.Cu" "F.Mask" "F.Paste")
			(net "P3V3_SSD13_CO_EN")
		)
	)
	(footprint ""
		(layer "F.Cu")
		(at 221.251272 -140.894562 180)
		(property "Reference" "R4197"
			(at 0 0 180)
			(layer "F.SilkS")
			(hide yes)
			(effects
				(font
					(size 1.27 1.27)
				)
			)
		)
		(property "Value" ""
			(at 0 0 180)
			(layer "F.Fab")
			(effects
				(font
					(size 1.27 1.27)
				)
			)
		)
		(duplicate_pad_numbers_are_jumpers no)
		(fp_line
			(start 0.7874 0.4064)
			(end -0.7874 0.4064)
			(stroke
				(width 0.1524)
				(type default)
			)
			(layer "F.SilkS")
		)
		(fp_line
			(start 0.7874 -0.4064)
			(end 0.7874 0.4064)
			(stroke
				(width 0.1524)
				(type default)
			)
			(layer "F.SilkS")
		)
		(fp_line
			(start -0.7874 0.4064)
			(end -0.7874 -0.4064)
			(stroke
				(width 0.1524)
				(type default)
			)
			(layer "F.SilkS")
		)
		(fp_line
			(start -0.7874 -0.4064)
			(end 0.7874 -0.4064)
			(stroke
				(width 0.1524)
				(type default)
			)
			(layer "F.SilkS")
		)
		(fp_line
			(start 0.67945 0.3048)
			(end 0.120396 0.3048)
			(stroke
				(width 0.1)
				(type default)
			)
			(layer "F.Fab")
		)
		(fp_line
			(start 0.67945 -0.3048)
			(end 0.67945 0.3048)
			(stroke
				(width 0.1)
				(type default)
			)
			(layer "F.Fab")
		)
		(fp_line
			(start 0.12065 -0.2794)
			(end 0.12065 -0.3048)
			(stroke
				(width 0.1)
				(type default)
			)
			(layer "F.Fab")
		)
		(fp_line
			(start 0.12065 -0.3048)
			(end 0.67945 -0.3048)
			(stroke
				(width 0.1)
				(type default)
			)
			(layer "F.Fab")
		)
		(fp_line
			(start 0.120396 0.3048)
			(end 0.120396 0.2794)
			(stroke
				(width 0.1)
				(type default)
			)
			(layer "F.Fab")
		)
		(fp_line
			(start 0.120396 0.2794)
			(end -0.12065 0.2794)
			(stroke
				(width 0.1)
				(type default)
			)
			(layer "F.Fab")
		)
		(fp_line
			(start -0.12065 0.3048)
			(end -0.67945 0.3048)
			(stroke
				(width 0.1)
				(type default)
			)
			(layer "F.Fab")
		)
		(fp_line
			(start -0.12065 0.2794)
			(end -0.12065 0.3048)
			(stroke
				(width 0.1)
				(type default)
			)
			(layer "F.Fab")
		)
		(fp_line
			(start -0.12065 -0.2794)
			(end 0.12065 -0.2794)
			(stroke
				(width 0.1)
				(type default)
			)
			(layer "F.Fab")
		)
		(fp_line
			(start -0.12065 -0.305054)
			(end -0.12065 -0.2794)
			(stroke
				(width 0.1)
				(type default)
			)
			(layer "F.Fab")
		)
		(fp_line
			(start -0.67945 0.3048)
			(end -0.67945 -0.305054)
			(stroke
				(width 0.1)
				(type default)
			)
			(layer "F.Fab")
		)
		(fp_line
			(start -0.67945 -0.305054)
			(end -0.12065 -0.305054)
			(stroke
				(width 0.1)
				(type default)
			)
			(layer "F.Fab")
		)
		(pad "1" smd circle
			(at -0.40005 0 180)
			(size 0 0)
			(layers "F.Cu" "F.Mask" "F.Paste")
			(net "FM_CK440_PEX_DEV_25M_EN")
		)
		(pad "2" smd circle
			(at 0.40005 0 180)
			(size 0 0)
			(layers "F.Cu" "F.Mask" "F.Paste")
			(net "P3V3")
		)
	)
	(footprint ""
		(layer "F.Cu")
		(at 218.156028 -117.90045 90)
		(property "Reference" "PC622"
			(at 0 0 90)
			(layer "F.SilkS")
			(hide yes)
			(effects
				(font
					(size 1.27 1.27)
				)
			)
		)
		(property "Value" ""
			(at 0 0 90)
			(layer "F.Fab")
			(effects
				(font
					(size 1.27 1.27)
				)
			)
		)
		(duplicate_pad_numbers_are_jumpers no)
		(fp_line
			(start 1.524 -0.762)
			(end 1.524 0.762)
			(stroke
				(width 0.1524)
				(type default)
			)
			(layer "F.SilkS")
		)
		(fp_line
			(start -1.524 -0.762)
			(end 1.524 -0.762)
			(stroke
				(width 0.1524)
				(type default)
			)
			(layer "F.SilkS")
		)
		(fp_line
			(start 1.524 0.762)
			(end -1.524 0.762)
			(stroke
				(width 0.1524)
				(type default)
			)
			(layer "F.SilkS")
		)
		(fp_line
			(start -1.524 0.762)
			(end -1.524 -0.762)
			(stroke
				(width 0.1524)
				(type default)
			)
			(layer "F.SilkS")
		)
		(fp_line
			(start 1.1049 -0.724916)
			(end -1.1049 -0.724916)
			(stroke
				(width 0.1)
				(type default)
			)
			(layer "F.Fab")
		)
		(fp_line
			(start -1.1049 -0.724916)
			(end -1.1049 0.724916)
			(stroke
				(width 0.1)
				(type default)
			)
			(layer "F.Fab")
		)
		(fp_line
			(start 1.1049 0.724916)
			(end 1.1049 -0.724916)
			(stroke
				(width 0.1)
				(type default)
			)
			(layer "F.Fab")
		)
		(fp_line
			(start -1.1049 0.724916)
			(end 1.1049 0.724916)
			(stroke
				(width 0.1)
				(type default)
			)
			(layer "F.Fab")
		)
		(pad "1" smd rect
			(at -0.889 0 270)
			(size 1.016 1.27)
			(layers "F.Cu" "F.Mask" "F.Paste")
			(net "P12V_NIC3_R")
		)
		(pad "2" smd rect
			(at 0.889 0 270)
			(size 1.016 1.27)
			(layers "F.Cu" "F.Mask" "F.Paste")
			(net "GND")
		)
	)
	(footprint ""
		(layer "F.Cu")
		(at 366.381792 -293.816786 -90)
		(property "Reference" "PC196"
			(at 0 0 270)
			(layer "F.SilkS")
			(hide yes)
			(effects
				(font
					(size 1.27 1.27)
				)
			)
		)
		(property "Value" ""
			(at 0 0 270)
			(layer "F.Fab")
			(effects
				(font
					(size 1.27 1.27)
				)
			)
		)
		(duplicate_pad_numbers_are_jumpers no)
		(fp_line
			(start -0.7874 0.4064)
			(end -0.7874 -0.4064)
			(stroke
				(width 0.1524)
				(type default)
			)
			(layer "F.SilkS")
		)
		(fp_line
			(start 0.7874 0.4064)
			(end -0.7874 0.4064)
			(stroke
				(width 0.1524)
				(type default)
			)
			(layer "F.SilkS")
		)
		(fp_line
			(start -0.7874 -0.4064)
			(end 0.7874 -0.4064)
			(stroke
				(width 0.1524)
				(type default)
			)
			(layer "F.SilkS")
		)
		(fp_line
			(start 0.7874 -0.4064)
			(end 0.7874 0.4064)
			(stroke
				(width 0.1524)
				(type default)
			)
			(layer "F.SilkS")
		)
		(fp_line
			(start -0.67945 0.3048)
			(end -0.67945 -0.305054)
			(stroke
				(width 0.1)
				(type default)
			)
			(layer "F.Fab")
		)
		(fp_line
			(start -0.12065 0.3048)
			(end -0.67945 0.3048)
			(stroke
				(width 0.1)
				(type default)
			)
			(layer "F.Fab")
		)
		(fp_line
			(start 0.120396 0.3048)
			(end 0.120396 0.2794)
			(stroke
				(width 0.1)
				(type default)
			)
			(layer "F.Fab")
		)
		(fp_line
			(start 0.67945 0.3048)
			(end 0.120396 0.3048)
			(stroke
				(width 0.1)
				(type default)
			)
			(layer "F.Fab")
		)
		(fp_line
			(start -0.12065 0.2794)
			(end -0.12065 0.3048)
			(stroke
				(width 0.1)
				(type default)
			)
			(layer "F.Fab")
		)
		(fp_line
			(start 0.120396 0.2794)
			(end -0.12065 0.2794)
			(stroke
				(width 0.1)
				(type default)
			)
			(layer "F.Fab")
		)
		(fp_line
			(start -0.12065 -0.2794)
			(end 0.12065 -0.2794)
			(stroke
				(width 0.1)
				(type default)
			)
			(layer "F.Fab")
		)
		(fp_line
			(start 0.12065 -0.2794)
			(end 0.12065 -0.3048)
			(stroke
				(width 0.1)
				(type default)
			)
			(layer "F.Fab")
		)
		(fp_line
			(start 0.12065 -0.3048)
			(end 0.67945 -0.3048)
			(stroke
				(width 0.1)
				(type default)
			)
			(layer "F.Fab")
		)
		(fp_line
			(start 0.67945 -0.3048)
			(end 0.67945 0.3048)
			(stroke
				(width 0.1)
				(type default)
			)
			(layer "F.Fab")
		)
		(fp_line
			(start -0.67945 -0.305054)
			(end -0.12065 -0.305054)
			(stroke
				(width 0.1)
				(type default)
			)
			(layer "F.Fab")
		)
		(fp_line
			(start -0.12065 -0.305054)
			(end -0.12065 -0.2794)
			(stroke
				(width 0.1)
				(type default)
			)
			(layer "F.Fab")
		)
		(pad "1" smd circle
			(at -0.40005 0 270)
			(size 0 0)
			(layers "F.Cu" "F.Mask" "F.Paste")
			(net "P0V8_PEX3")
		)
		(pad "2" smd circle
			(at 0.40005 0 270)
			(size 0 0)
			(layers "F.Cu" "F.Mask" "F.Paste")
			(net "GND")
		)
	)
	(footprint ""
		(layer "F.Cu")
		(at 446.734438 -34.546286 180)
		(property "Reference" "C722"
			(at 0 0 180)
			(layer "F.SilkS")
			(hide yes)
			(effects
				(font
					(size 1.27 1.27)
				)
			)
		)
		(property "Value" ""
			(at 0 0 180)
			(layer "F.Fab")
			(effects
				(font
					(size 1.27 1.27)
				)
			)
		)
		(duplicate_pad_numbers_are_jumpers no)
		(fp_line
			(start 0.299974 0.150114)
			(end -0.299974 0.150114)
			(stroke
				(width 0.1)
				(type default)
			)
			(layer "F.Fab")
		)
		(fp_line
			(start 0.299974 -0.150114)
			(end 0.299974 0.150114)
			(stroke
				(width 0.1)
				(type default)
			)
			(layer "F.Fab")
		)
		(fp_line
			(start -0.299974 0.150114)
			(end -0.299974 -0.150114)
			(stroke
				(width 0.1)
				(type default)
			)
			(layer "F.Fab")
		)
		(fp_line
			(start -0.299974 -0.150114)
			(end 0.299974 -0.150114)
			(stroke
				(width 0.1)
				(type default)
			)
			(layer "F.Fab")
		)
		(pad "1" smd rect
			(at -0.2667 0 180)
			(size 0.3048 0.381)
			(layers "F.Cu" "F.Mask" "F.Paste")
			(net "P5E_PEX3_STN2_TX_DP<35>")
		)
		(pad "2" smd rect
			(at 0.2667 0 180)
			(size 0.3048 0.381)
			(layers "F.Cu" "F.Mask" "F.Paste")
			(net "P5E_PEX3_STN2_TX_C_DP<35>")
		)
	)
	(footprint ""
		(layer "F.Cu")
		(at 6.662674 -393.740386 -90)
		(property "Reference" "R6741"
			(at 0 0 270)
			(layer "F.SilkS")
			(hide yes)
			(effects
				(font
					(size 1.27 1.27)
				)
			)
		)
		(property "Value" ""
			(at 0 0 270)
			(layer "F.Fab")
			(effects
				(font
					(size 1.27 1.27)
				)
			)
		)
		(duplicate_pad_numbers_are_jumpers no)
		(fp_line
			(start -0.7874 0.4064)
			(end -0.7874 -0.4064)
			(stroke
				(width 0.1524)
				(type default)
			)
			(layer "F.SilkS")
		)
		(fp_line
			(start 0.7874 0.4064)
			(end -0.7874 0.4064)
			(stroke
				(width 0.1524)
				(type default)
			)
			(layer "F.SilkS")
		)
		(fp_line
			(start -0.7874 -0.4064)
			(end 0.7874 -0.4064)
			(stroke
				(width 0.1524)
				(type default)
			)
			(layer "F.SilkS")
		)
		(fp_line
			(start 0.7874 -0.4064)
			(end 0.7874 0.4064)
			(stroke
				(width 0.1524)
				(type default)
			)
			(layer "F.SilkS")
		)
		(fp_line
			(start -0.67945 0.3048)
			(end -0.67945 -0.305054)
			(stroke
				(width 0.1)
				(type default)
			)
			(layer "F.Fab")
		)
		(fp_line
			(start -0.12065 0.3048)
			(end -0.67945 0.3048)
			(stroke
				(width 0.1)
				(type default)
			)
			(layer "F.Fab")
		)
		(fp_line
			(start 0.120396 0.3048)
			(end 0.120396 0.2794)
			(stroke
				(width 0.1)
				(type default)
			)
			(layer "F.Fab")
		)
		(fp_line
			(start 0.67945 0.3048)
			(end 0.120396 0.3048)
			(stroke
				(width 0.1)
				(type default)
			)
			(layer "F.Fab")
		)
		(fp_line
			(start -0.12065 0.2794)
			(end -0.12065 0.3048)
			(stroke
				(width 0.1)
				(type default)
			)
			(layer "F.Fab")
		)
		(fp_line
			(start 0.120396 0.2794)
			(end -0.12065 0.2794)
			(stroke
				(width 0.1)
				(type default)
			)
			(layer "F.Fab")
		)
		(fp_line
			(start -0.12065 -0.2794)
			(end 0.12065 -0.2794)
			(stroke
				(width 0.1)
				(type default)
			)
			(layer "F.Fab")
		)
		(fp_line
			(start 0.12065 -0.2794)
			(end 0.12065 -0.3048)
			(stroke
				(width 0.1)
				(type default)
			)
			(layer "F.Fab")
		)
		(fp_line
			(start 0.12065 -0.3048)
			(end 0.67945 -0.3048)
			(stroke
				(width 0.1)
				(type default)
			)
			(layer "F.Fab")
		)
		(fp_line
			(start 0.67945 -0.3048)
			(end 0.67945 0.3048)
			(stroke
				(width 0.1)
				(type default)
			)
			(layer "F.Fab")
		)
		(fp_line
			(start -0.67945 -0.305054)
			(end -0.12065 -0.305054)
			(stroke
				(width 0.1)
				(type default)
			)
			(layer "F.Fab")
		)
		(fp_line
			(start -0.12065 -0.305054)
			(end -0.12065 -0.2794)
			(stroke
				(width 0.1)
				(type default)
			)
			(layer "F.Fab")
		)
		(pad "1" smd circle
			(at -0.40005 0 270)
			(size 0 0)
			(layers "F.Cu" "F.Mask" "F.Paste")
			(net "P3V3_USB_8042")
		)
		(pad "2" smd circle
			(at 0.40005 0 270)
			(size 0 0)
			(layers "F.Cu" "F.Mask" "F.Paste")
			(net "BIC_USB_8042_HUB_OVCUR2")
		)
	)
	(footprint ""
		(layer "F.Cu")
		(at 144.10563 -258.511548 -90)
		(property "Reference" "C3248"
			(at 0 0 270)
			(layer "F.SilkS")
			(hide yes)
			(effects
				(font
					(size 1.27 1.27)
				)
			)
		)
		(property "Value" ""
			(at 0 0 270)
			(layer "F.Fab")
			(effects
				(font
					(size 1.27 1.27)
				)
			)
		)
		(duplicate_pad_numbers_are_jumpers no)
		(fp_line
			(start -1.2954 0.5842)
			(end -1.2954 -0.5842)
			(stroke
				(width 0.1524)
				(type default)
			)
			(layer "F.SilkS")
		)
		(fp_line
			(start 1.2954 0.5842)
			(end -1.2954 0.5842)
			(stroke
				(width 0.1524)
				(type default)
			)
			(layer "F.SilkS")
		)
		(fp_line
			(start -1.2954 -0.5842)
			(end 1.2954 -0.5842)
			(stroke
				(width 0.1524)
				(type default)
			)
			(layer "F.SilkS")
		)
		(fp_line
			(start 1.2954 -0.5842)
			(end 1.2954 0.5842)
			(stroke
				(width 0.1524)
				(type default)
			)
			(layer "F.SilkS")
		)
		(fp_line
			(start -0.8636 0.4572)
			(end -0.8636 0.4064)
			(stroke
				(width 0.1)
				(type default)
			)
			(layer "F.Fab")
		)
		(fp_line
			(start 0.8636 0.4572)
			(end -0.8636 0.4572)
			(stroke
				(width 0.1)
				(type default)
			)
			(layer "F.Fab")
		)
		(fp_line
			(start -1.1938 0.4064)
			(end -1.1938 -0.4064)
			(stroke
				(width 0.1)
				(type default)
			)
			(layer "F.Fab")
		)
		(fp_line
			(start -0.8636 0.4064)
			(end -1.1938 0.4064)
			(stroke
				(width 0.1)
				(type default)
			)
			(layer "F.Fab")
		)
		(fp_line
			(start 0.8636 0.4064)
			(end 0.8636 0.4572)
			(stroke
				(width 0.1)
				(type default)
			)
			(layer "F.Fab")
		)
		(fp_line
			(start 1.1938 0.4064)
			(end 0.8636 0.4064)
			(stroke
				(width 0.1)
				(type default)
			)
			(layer "F.Fab")
		)
		(fp_line
			(start -1.1938 -0.4064)
			(end -0.8636 -0.4064)
			(stroke
				(width 0.1)
				(type default)
			)
			(layer "F.Fab")
		)
		(fp_line
			(start -0.8636 -0.4064)
			(end -0.8636 -0.4572)
			(stroke
				(width 0.1)
				(type default)
			)
			(layer "F.Fab")
		)
		(fp_line
			(start 0.8636 -0.4064)
			(end 1.1938 -0.4064)
			(stroke
				(width 0.1)
				(type default)
			)
			(layer "F.Fab")
		)
		(fp_line
			(start 1.1938 -0.4064)
			(end 1.1938 0.4064)
			(stroke
				(width 0.1)
				(type default)
			)
			(layer "F.Fab")
		)
		(fp_line
			(start -0.8636 -0.4572)
			(end 0.8636 -0.4572)
			(stroke
				(width 0.1)
				(type default)
			)
			(layer "F.Fab")
		)
		(fp_line
			(start 0.8636 -0.4572)
			(end 0.8636 -0.4064)
			(stroke
				(width 0.1)
				(type default)
			)
			(layer "F.Fab")
		)
		(pad "1" smd rect
			(at -0.7366 0 180)
			(size 0.7112 0.8128)
			(layers "F.Cu" "F.Mask" "F.Paste")
			(net "P1V8_VDDA_PEX1_R")
		)
		(pad "2" smd rect
			(at 0.7366 0 180)
			(size 0.7112 0.8128)
			(layers "F.Cu" "F.Mask" "F.Paste")
			(net "GND")
		)
	)
	(footprint ""
		(layer "F.Cu")
		(at 142.947898 -191.767968)
		(property "Reference" "R6665"
			(at 0 0 0)
			(layer "F.SilkS")
			(hide yes)
			(effects
				(font
					(size 1.27 1.27)
				)
			)
		)
		(property "Value" ""
			(at 0 0 0)
			(layer "F.Fab")
			(effects
				(font
					(size 1.27 1.27)
				)
			)
		)
		(duplicate_pad_numbers_are_jumpers no)
		(fp_line
			(start -0.7874 -0.4064)
			(end 0.7874 -0.4064)
			(stroke
				(width 0.1524)
				(type default)
			)
			(layer "F.SilkS")
		)
		(fp_line
			(start -0.7874 0.4064)
			(end -0.7874 -0.4064)
			(stroke
				(width 0.1524)
				(type default)
			)
			(layer "F.SilkS")
		)
		(fp_line
			(start 0.7874 -0.4064)
			(end 0.7874 0.4064)
			(stroke
				(width 0.1524)
				(type default)
			)
			(layer "F.SilkS")
		)
		(fp_line
			(start 0.7874 0.4064)
			(end -0.7874 0.4064)
			(stroke
				(width 0.1524)
				(type default)
			)
			(layer "F.SilkS")
		)
		(fp_line
			(start -0.67945 -0.305054)
			(end -0.12065 -0.305054)
			(stroke
				(width 0.1)
				(type default)
			)
			(layer "F.Fab")
		)
		(fp_line
			(start -0.67945 0.3048)
			(end -0.67945 -0.305054)
			(stroke
				(width 0.1)
				(type default)
			)
			(layer "F.Fab")
		)
		(fp_line
			(start -0.12065 -0.305054)
			(end -0.12065 -0.2794)
			(stroke
				(width 0.1)
				(type default)
			)
			(layer "F.Fab")
		)
		(fp_line
			(start -0.12065 -0.2794)
			(end 0.12065 -0.2794)
			(stroke
				(width 0.1)
				(type default)
			)
			(layer "F.Fab")
		)
		(fp_line
			(start -0.12065 0.2794)
			(end -0.12065 0.3048)
			(stroke
				(width 0.1)
				(type default)
			)
			(layer "F.Fab")
		)
		(fp_line
			(start -0.12065 0.3048)
			(end -0.67945 0.3048)
			(stroke
				(width 0.1)
				(type default)
			)
			(layer "F.Fab")
		)
		(fp_line
			(start 0.120396 0.2794)
			(end -0.12065 0.2794)
			(stroke
				(width 0.1)
				(type default)
			)
			(layer "F.Fab")
		)
		(fp_line
			(start 0.120396 0.3048)
			(end 0.120396 0.2794)
			(stroke
				(width 0.1)
				(type default)
			)
			(layer "F.Fab")
		)
		(fp_line
			(start 0.12065 -0.3048)
			(end 0.67945 -0.3048)
			(stroke
				(width 0.1)
				(type default)
			)
			(layer "F.Fab")
		)
		(fp_line
			(start 0.12065 -0.2794)
			(end 0.12065 -0.3048)
			(stroke
				(width 0.1)
				(type default)
			)
			(layer "F.Fab")
		)
		(fp_line
			(start 0.67945 -0.3048)
			(end 0.67945 0.3048)
			(stroke
				(width 0.1)
				(type default)
			)
			(layer "F.Fab")
		)
		(fp_line
			(start 0.67945 0.3048)
			(end 0.120396 0.3048)
			(stroke
				(width 0.1)
				(type default)
			)
			(layer "F.Fab")
		)
		(pad "1" smd circle
			(at -0.40005 0)
			(size 0 0)
			(layers "F.Cu" "F.Mask" "F.Paste")
			(net "NIC4_CLK_EN_BUF_N")
		)
		(pad "2" smd circle
			(at 0.40005 0)
			(size 0 0)
			(layers "F.Cu" "F.Mask" "F.Paste")
			(net "NIC4_CLK_EN_BUF_R_N")
		)
	)
	(footprint ""
		(layer "F.Cu")
		(at 249.20575 -85.209888)
		(property "Reference" "R1061"
			(at 0 0 0)
			(layer "F.SilkS")
			(hide yes)
			(effects
				(font
					(size 1.27 1.27)
				)
			)
		)
		(property "Value" ""
			(at 0 0 0)
			(layer "F.Fab")
			(effects
				(font
					(size 1.27 1.27)
				)
			)
		)
		(duplicate_pad_numbers_are_jumpers no)
		(fp_line
			(start -0.7874 -0.4064)
			(end 0.7874 -0.4064)
			(stroke
				(width 0.1524)
				(type default)
			)
			(layer "F.SilkS")
		)
		(fp_line
			(start -0.7874 0.4064)
			(end -0.7874 -0.4064)
			(stroke
				(width 0.1524)
				(type default)
			)
			(layer "F.SilkS")
		)
		(fp_line
			(start 0.7874 -0.4064)
			(end 0.7874 0.4064)
			(stroke
				(width 0.1524)
				(type default)
			)
			(layer "F.SilkS")
		)
		(fp_line
			(start 0.7874 0.4064)
			(end -0.7874 0.4064)
			(stroke
				(width 0.1524)
				(type default)
			)
			(layer "F.SilkS")
		)
		(fp_line
			(start -0.67945 -0.305054)
			(end -0.12065 -0.305054)
			(stroke
				(width 0.1)
				(type default)
			)
			(layer "F.Fab")
		)
		(fp_line
			(start -0.67945 0.3048)
			(end -0.67945 -0.305054)
			(stroke
				(width 0.1)
				(type default)
			)
			(layer "F.Fab")
		)
		(fp_line
			(start -0.12065 -0.305054)
			(end -0.12065 -0.2794)
			(stroke
				(width 0.1)
				(type default)
			)
			(layer "F.Fab")
		)
		(fp_line
			(start -0.12065 -0.2794)
			(end 0.12065 -0.2794)
			(stroke
				(width 0.1)
				(type default)
			)
			(layer "F.Fab")
		)
		(fp_line
			(start -0.12065 0.2794)
			(end -0.12065 0.3048)
			(stroke
				(width 0.1)
				(type default)
			)
			(layer "F.Fab")
		)
		(fp_line
			(start -0.12065 0.3048)
			(end -0.67945 0.3048)
			(stroke
				(width 0.1)
				(type default)
			)
			(layer "F.Fab")
		)
		(fp_line
			(start 0.120396 0.2794)
			(end -0.12065 0.2794)
			(stroke
				(width 0.1)
				(type default)
			)
			(layer "F.Fab")
		)
		(fp_line
			(start 0.120396 0.3048)
			(end 0.120396 0.2794)
			(stroke
				(width 0.1)
				(type default)
			)
			(layer "F.Fab")
		)
		(fp_line
			(start 0.12065 -0.3048)
			(end 0.67945 -0.3048)
			(stroke
				(width 0.1)
				(type default)
			)
			(layer "F.Fab")
		)
		(fp_line
			(start 0.12065 -0.2794)
			(end 0.12065 -0.3048)
			(stroke
				(width 0.1)
				(type default)
			)
			(layer "F.Fab")
		)
		(fp_line
			(start 0.67945 -0.3048)
			(end 0.67945 0.3048)
			(stroke
				(width 0.1)
				(type default)
			)
			(layer "F.Fab")
		)
		(fp_line
			(start 0.67945 0.3048)
			(end 0.120396 0.3048)
			(stroke
				(width 0.1)
				(type default)
			)
			(layer "F.Fab")
		)
		(pad "1" smd circle
			(at -0.40005 0)
			(size 0 0)
			(layers "F.Cu" "F.Mask" "F.Paste")
			(net "GND")
		)
		(pad "2" smd circle
			(at 0.40005 0)
			(size 0 0)
			(layers "F.Cu" "F.Mask" "F.Paste")
			(net "CLK_CK440_SMB_ADDR1")
		)
	)
	(footprint ""
		(layer "F.Cu")
		(at 216.937844 -98.806 -90)
		(property "Reference" "R718"
			(at 0 0 270)
			(layer "F.SilkS")
			(hide yes)
			(effects
				(font
					(size 1.27 1.27)
				)
			)
		)
		(property "Value" ""
			(at 0 0 270)
			(layer "F.Fab")
			(effects
				(font
					(size 1.27 1.27)
				)
			)
		)
		(duplicate_pad_numbers_are_jumpers no)
		(fp_line
			(start -0.7874 0.4064)
			(end -0.7874 -0.4064)
			(stroke
				(width 0.1524)
				(type default)
			)
			(layer "F.SilkS")
		)
		(fp_line
			(start 0.7874 0.4064)
			(end -0.7874 0.4064)
			(stroke
				(width 0.1524)
				(type default)
			)
			(layer "F.SilkS")
		)
		(fp_line
			(start -0.7874 -0.4064)
			(end 0.7874 -0.4064)
			(stroke
				(width 0.1524)
				(type default)
			)
			(layer "F.SilkS")
		)
		(fp_line
			(start 0.7874 -0.4064)
			(end 0.7874 0.4064)
			(stroke
				(width 0.1524)
				(type default)
			)
			(layer "F.SilkS")
		)
		(fp_line
			(start -0.67945 0.3048)
			(end -0.67945 -0.305054)
			(stroke
				(width 0.1)
				(type default)
			)
			(layer "F.Fab")
		)
		(fp_line
			(start -0.12065 0.3048)
			(end -0.67945 0.3048)
			(stroke
				(width 0.1)
				(type default)
			)
			(layer "F.Fab")
		)
		(fp_line
			(start 0.120396 0.3048)
			(end 0.120396 0.2794)
			(stroke
				(width 0.1)
				(type default)
			)
			(layer "F.Fab")
		)
		(fp_line
			(start 0.67945 0.3048)
			(end 0.120396 0.3048)
			(stroke
				(width 0.1)
				(type default)
			)
			(layer "F.Fab")
		)
		(fp_line
			(start -0.12065 0.2794)
			(end -0.12065 0.3048)
			(stroke
				(width 0.1)
				(type default)
			)
			(layer "F.Fab")
		)
		(fp_line
			(start 0.120396 0.2794)
			(end -0.12065 0.2794)
			(stroke
				(width 0.1)
				(type default)
			)
			(layer "F.Fab")
		)
		(fp_line
			(start -0.12065 -0.2794)
			(end 0.12065 -0.2794)
			(stroke
				(width 0.1)
				(type default)
			)
			(layer "F.Fab")
		)
		(fp_line
			(start 0.12065 -0.2794)
			(end 0.12065 -0.3048)
			(stroke
				(width 0.1)
				(type default)
			)
			(layer "F.Fab")
		)
		(fp_line
			(start 0.12065 -0.3048)
			(end 0.67945 -0.3048)
			(stroke
				(width 0.1)
				(type default)
			)
			(layer "F.Fab")
		)
		(fp_line
			(start 0.67945 -0.3048)
			(end 0.67945 0.3048)
			(stroke
				(width 0.1)
				(type default)
			)
			(layer "F.Fab")
		)
		(fp_line
			(start -0.67945 -0.305054)
			(end -0.12065 -0.305054)
			(stroke
				(width 0.1)
				(type default)
			)
			(layer "F.Fab")
		)
		(fp_line
			(start -0.12065 -0.305054)
			(end -0.12065 -0.2794)
			(stroke
				(width 0.1)
				(type default)
			)
			(layer "F.Fab")
		)
		(pad "1" smd circle
			(at -0.40005 0 270)
			(size 0 0)
			(layers "F.Cu" "F.Mask" "F.Paste")
			(net "NIC3_ADC_A1")
		)
		(pad "2" smd circle
			(at 0.40005 0 270)
			(size 0 0)
			(layers "F.Cu" "F.Mask" "F.Paste")
			(net "GND")
		)
	)
	(footprint ""
		(layer "F.Cu")
		(at 140.074142 -174.881286 180)
		(property "Reference" "R1099"
			(at 0 0 180)
			(layer "F.SilkS")
			(hide yes)
			(effects
				(font
					(size 1.27 1.27)
				)
			)
		)
		(property "Value" ""
			(at 0 0 180)
			(layer "F.Fab")
			(effects
				(font
					(size 1.27 1.27)
				)
			)
		)
		(duplicate_pad_numbers_are_jumpers no)
		(fp_line
			(start 0.7874 0.4064)
			(end -0.7874 0.4064)
			(stroke
				(width 0.1524)
				(type default)
			)
			(layer "F.SilkS")
		)
		(fp_line
			(start 0.67945 0.3048)
			(end 0.120396 0.3048)
			(stroke
				(width 0.1)
				(type default)
			)
			(layer "F.Fab")
		)
		(fp_line
			(start 0.67945 -0.3048)
			(end 0.67945 0.3048)
			(stroke
				(width 0.1)
				(type default)
			)
			(layer "F.Fab")
		)
		(fp_line
			(start 0.12065 -0.2794)
			(end 0.12065 -0.3048)
			(stroke
				(width 0.1)
				(type default)
			)
			(layer "F.Fab")
		)
		(fp_line
			(start 0.12065 -0.3048)
			(end 0.67945 -0.3048)
			(stroke
				(width 0.1)
				(type default)
			)
			(layer "F.Fab")
		)
		(fp_line
			(start 0.120396 0.3048)
			(end 0.120396 0.2794)
			(stroke
				(width 0.1)
				(type default)
			)
			(layer "F.Fab")
		)
		(fp_line
			(start 0.120396 0.2794)
			(end -0.12065 0.2794)
			(stroke
				(width 0.1)
				(type default)
			)
			(layer "F.Fab")
		)
		(fp_line
			(start -0.12065 0.3048)
			(end -0.67945 0.3048)
			(stroke
				(width 0.1)
				(type default)
			)
			(layer "F.Fab")
		)
		(fp_line
			(start -0.12065 0.2794)
			(end -0.12065 0.3048)
			(stroke
				(width 0.1)
				(type default)
			)
			(layer "F.Fab")
		)
		(fp_line
			(start -0.12065 -0.2794)
			(end 0.12065 -0.2794)
			(stroke
				(width 0.1)
				(type default)
			)
			(layer "F.Fab")
		)
		(fp_line
			(start -0.12065 -0.305054)
			(end -0.12065 -0.2794)
			(stroke
				(width 0.1)
				(type default)
			)
			(layer "F.Fab")
		)
		(fp_line
			(start -0.67945 0.3048)
			(end -0.67945 -0.305054)
			(stroke
				(width 0.1)
				(type default)
			)
			(layer "F.Fab")
		)
		(fp_line
			(start -0.67945 -0.305054)
			(end -0.12065 -0.305054)
			(stroke
				(width 0.1)
				(type default)
			)
			(layer "F.Fab")
		)
		(pad "1" smd circle
			(at -0.40005 0 180)
			(size 0 0)
			(layers "F.Cu" "F.Mask" "F.Paste")
			(net "CLK_100M_DB2000QL_NIC2_R_DN")
		)
		(pad "2" smd circle
			(at 0.40005 0 180)
			(size 0 0)
			(layers "F.Cu" "F.Mask" "F.Paste")
			(net "CLK_100M_DB2000QL_NIC2_DN")
		)
	)
	(footprint ""
		(layer "F.Cu")
		(at 31.454344 -250.070874 -90)
		(property "Reference" "R1156"
			(at 0 0 270)
			(layer "F.SilkS")
			(hide yes)
			(effects
				(font
					(size 1.27 1.27)
				)
			)
		)
		(property "Value" ""
			(at 0 0 270)
			(layer "F.Fab")
			(effects
				(font
					(size 1.27 1.27)
				)
			)
		)
		(duplicate_pad_numbers_are_jumpers no)
		(fp_line
			(start -0.7874 0.4064)
			(end -0.7874 -0.4064)
			(stroke
				(width 0.1524)
				(type default)
			)
			(layer "F.SilkS")
		)
		(fp_line
			(start 0.7874 0.4064)
			(end -0.7874 0.4064)
			(stroke
				(width 0.1524)
				(type default)
			)
			(layer "F.SilkS")
		)
		(fp_line
			(start -0.7874 -0.4064)
			(end 0.7874 -0.4064)
			(stroke
				(width 0.1524)
				(type default)
			)
			(layer "F.SilkS")
		)
		(fp_line
			(start 0.7874 -0.4064)
			(end 0.7874 0.4064)
			(stroke
				(width 0.1524)
				(type default)
			)
			(layer "F.SilkS")
		)
		(fp_line
			(start -0.67945 0.3048)
			(end -0.67945 -0.305054)
			(stroke
				(width 0.1)
				(type default)
			)
			(layer "F.Fab")
		)
		(fp_line
			(start -0.12065 0.3048)
			(end -0.67945 0.3048)
			(stroke
				(width 0.1)
				(type default)
			)
			(layer "F.Fab")
		)
		(fp_line
			(start 0.120396 0.3048)
			(end 0.120396 0.2794)
			(stroke
				(width 0.1)
				(type default)
			)
			(layer "F.Fab")
		)
		(fp_line
			(start 0.67945 0.3048)
			(end 0.120396 0.3048)
			(stroke
				(width 0.1)
				(type default)
			)
			(layer "F.Fab")
		)
		(fp_line
			(start -0.12065 0.2794)
			(end -0.12065 0.3048)
			(stroke
				(width 0.1)
				(type default)
			)
			(layer "F.Fab")
		)
		(fp_line
			(start 0.120396 0.2794)
			(end -0.12065 0.2794)
			(stroke
				(width 0.1)
				(type default)
			)
			(layer "F.Fab")
		)
		(fp_line
			(start -0.12065 -0.2794)
			(end 0.12065 -0.2794)
			(stroke
				(width 0.1)
				(type default)
			)
			(layer "F.Fab")
		)
		(fp_line
			(start 0.12065 -0.2794)
			(end 0.12065 -0.3048)
			(stroke
				(width 0.1)
				(type default)
			)
			(layer "F.Fab")
		)
		(fp_line
			(start 0.12065 -0.3048)
			(end 0.67945 -0.3048)
			(stroke
				(width 0.1)
				(type default)
			)
			(layer "F.Fab")
		)
		(fp_line
			(start 0.67945 -0.3048)
			(end 0.67945 0.3048)
			(stroke
				(width 0.1)
				(type default)
			)
			(layer "F.Fab")
		)
		(fp_line
			(start -0.67945 -0.305054)
			(end -0.12065 -0.305054)
			(stroke
				(width 0.1)
				(type default)
			)
			(layer "F.Fab")
		)
		(fp_line
			(start -0.12065 -0.305054)
			(end -0.12065 -0.2794)
			(stroke
				(width 0.1)
				(type default)
			)
			(layer "F.Fab")
		)
		(pad "1" smd circle
			(at -0.40005 0 270)
			(size 0 0)
			(layers "F.Cu" "F.Mask" "F.Paste")
			(net "PEX0_MODE_SEL4")
		)
		(pad "2" smd circle
			(at 0.40005 0 270)
			(size 0 0)
			(layers "F.Cu" "F.Mask" "F.Paste")
			(net "P1V8_PEX")
		)
	)
	(footprint ""
		(layer "F.Cu")
		(at 106.29265 -7.742682)
		(property "Reference" "R1658"
			(at 0 0 0)
			(layer "F.SilkS")
			(hide yes)
			(effects
				(font
					(size 1.27 1.27)
				)
			)
		)
		(property "Value" ""
			(at 0 0 0)
			(layer "F.Fab")
			(effects
				(font
					(size 1.27 1.27)
				)
			)
		)
		(duplicate_pad_numbers_are_jumpers no)
		(fp_line
			(start -0.7874 -0.4064)
			(end 0.7874 -0.4064)
			(stroke
				(width 0.1524)
				(type default)
			)
			(layer "F.SilkS")
		)
		(fp_line
			(start -0.7874 0.4064)
			(end -0.7874 -0.4064)
			(stroke
				(width 0.1524)
				(type default)
			)
			(layer "F.SilkS")
		)
		(fp_line
			(start 0.7874 -0.4064)
			(end 0.7874 0.4064)
			(stroke
				(width 0.1524)
				(type default)
			)
			(layer "F.SilkS")
		)
		(fp_line
			(start 0.7874 0.4064)
			(end -0.7874 0.4064)
			(stroke
				(width 0.1524)
				(type default)
			)
			(layer "F.SilkS")
		)
		(fp_line
			(start -0.67945 -0.305054)
			(end -0.12065 -0.305054)
			(stroke
				(width 0.1)
				(type default)
			)
			(layer "F.Fab")
		)
		(fp_line
			(start -0.67945 0.3048)
			(end -0.67945 -0.305054)
			(stroke
				(width 0.1)
				(type default)
			)
			(layer "F.Fab")
		)
		(fp_line
			(start -0.12065 -0.305054)
			(end -0.12065 -0.2794)
			(stroke
				(width 0.1)
				(type default)
			)
			(layer "F.Fab")
		)
		(fp_line
			(start -0.12065 -0.2794)
			(end 0.12065 -0.2794)
			(stroke
				(width 0.1)
				(type default)
			)
			(layer "F.Fab")
		)
		(fp_line
			(start -0.12065 0.2794)
			(end -0.12065 0.3048)
			(stroke
				(width 0.1)
				(type default)
			)
			(layer "F.Fab")
		)
		(fp_line
			(start -0.12065 0.3048)
			(end -0.67945 0.3048)
			(stroke
				(width 0.1)
				(type default)
			)
			(layer "F.Fab")
		)
		(fp_line
			(start 0.120396 0.2794)
			(end -0.12065 0.2794)
			(stroke
				(width 0.1)
				(type default)
			)
			(layer "F.Fab")
		)
		(fp_line
			(start 0.120396 0.3048)
			(end 0.120396 0.2794)
			(stroke
				(width 0.1)
				(type default)
			)
			(layer "F.Fab")
		)
		(fp_line
			(start 0.12065 -0.3048)
			(end 0.67945 -0.3048)
			(stroke
				(width 0.1)
				(type default)
			)
			(layer "F.Fab")
		)
		(fp_line
			(start 0.12065 -0.2794)
			(end 0.12065 -0.3048)
			(stroke
				(width 0.1)
				(type default)
			)
			(layer "F.Fab")
		)
		(fp_line
			(start 0.67945 -0.3048)
			(end 0.67945 0.3048)
			(stroke
				(width 0.1)
				(type default)
			)
			(layer "F.Fab")
		)
		(fp_line
			(start 0.67945 0.3048)
			(end 0.120396 0.3048)
			(stroke
				(width 0.1)
				(type default)
			)
			(layer "F.Fab")
		)
		(pad "1" smd circle
			(at -0.40005 0)
			(size 0 0)
			(layers "F.Cu" "F.Mask" "F.Paste")
			(net "SMB_BIC_I2C9_MUX0_SSD3_R_SCL")
		)
		(pad "2" smd circle
			(at 0.40005 0)
			(size 0 0)
			(layers "F.Cu" "F.Mask" "F.Paste")
			(net "SMB_ISO_SSD3_SCL")
		)
	)
	(footprint ""
		(layer "F.Cu")
		(at 183.301386 -55.78475 -90)
		(property "Reference" "PD31"
			(at 4.01955 2.147316 90)
			(unlocked yes)
			(layer "F.SilkS")
			(effects
				(font
					(size 0.7874 0.5842)
					(thickness 0.1524)
				)
				(justify left)
			)
		)
		(property "Value" ""
			(at 0 0 270)
			(layer "F.Fab")
			(effects
				(font
					(size 1.27 1.27)
				)
			)
		)
		(duplicate_pad_numbers_are_jumpers no)
		(fp_line
			(start -3.400044 1.459992)
			(end -3.400044 -1.459992)
			(stroke
				(width 0.1524)
				(type default)
			)
			(layer "F.SilkS")
		)
		(fp_line
			(start 4.107942 1.459992)
			(end -3.400044 1.459992)
			(stroke
				(width 0.1524)
				(type default)
			)
			(layer "F.SilkS")
		)
		(fp_line
			(start -3.400044 -1.459992)
			(end 4.107942 -1.459992)
			(stroke
				(width 0.1524)
				(type default)
			)
			(layer "F.SilkS")
		)
		(fp_line
			(start 4.107942 -1.459992)
			(end 4.107942 1.459992)
			(stroke
				(width 0.1524)
				(type default)
			)
			(layer "F.SilkS")
		)
		(fp_poly
			(pts
				(xy 4.107942 -1.459992) (xy 4.107942 1.459992) (xy 3.308096 1.459992) (xy 3.308096 -1.459992)
			)
			(stroke
				(width 0)
				(type default)
			)
			(fill yes)
			(layer "F.SilkS")
		)
		(fp_line
			(start -2.29997 1.459992)
			(end -2.29997 -1.459992)
			(stroke
				(width 0.1)
				(type default)
			)
			(layer "F.Fab")
		)
		(fp_line
			(start 2.29997 1.459992)
			(end -2.29997 1.459992)
			(stroke
				(width 0.1)
				(type default)
			)
			(layer "F.Fab")
		)
		(fp_line
			(start -2.29997 -1.459992)
			(end 2.29997 -1.459992)
			(stroke
				(width 0.1)
				(type default)
			)
			(layer "F.Fab")
		)
		(fp_line
			(start 2.29997 -1.459992)
			(end 2.29997 1.459992)
			(stroke
				(width 0.1)
				(type default)
			)
			(layer "F.Fab")
		)
		(fp_text user "-"
			(at 5.4102 0.29845 90)
			(unlocked yes)
			(layer "F.SilkS")
			(effects
				(font
					(size 1.905 1.4224)
					(thickness 0.1524)
				)
				(justify left)
			)
		)
		(fp_text user "+"
			(at -4.7752 -0.12065 270)
			(unlocked yes)
			(layer "F.SilkS")
			(effects
				(font
					(size 1.905 1.4224)
					(thickness 0.1524)
				)
				(justify left)
			)
		)
		(fp_text user "-"
			(at 5.4102 0.29845 90)
			(unlocked yes)
			(layer "F.Fab")
			(effects
				(font
					(size 1.905 1.4224)
					(thickness 0.1524)
				)
				(justify left)
			)
		)
		(fp_text user "+"
			(at -4.7752 -0.12065 270)
			(unlocked yes)
			(layer "F.Fab")
			(effects
				(font
					(size 1.905 1.4224)
					(thickness 0.1524)
				)
				(justify left)
			)
		)
		(pad "A" smd rect
			(at -1.999996 0)
			(size 1.7018 2.5146)
			(layers "F.Cu" "F.Mask" "F.Paste")
			(net "GND")
		)
		(pad "C" smd rect
			(at 1.999996 0)
			(size 1.7018 2.5146)
			(layers "F.Cu" "F.Mask" "F.Paste")
			(net "P12V_SSD6_R")
		)
	)
	(footprint ""
		(layer "F.Cu")
		(at 443.800484 -450.437758 90)
		(property "Reference" "J52"
			(at -3.5052 -5.552948 90)
			(unlocked yes)
			(layer "F.SilkS")
			(effects
				(font
					(size 0.7874 0.5842)
					(thickness 0.1524)
				)
				(justify left)
			)
		)
		(property "Value" ""
			(at 0 0 90)
			(layer "F.Fab")
			(effects
				(font
					(size 1.27 1.27)
				)
			)
		)
		(duplicate_pad_numbers_are_jumpers no)
		(fp_line
			(start 3.330702 -4.771136)
			(end 0 4.011168)
			(stroke
				(width 0.1524)
				(type default)
			)
			(layer "F.SilkS")
		)
		(fp_line
			(start -3.330702 -4.771136)
			(end 3.330702 -4.771136)
			(stroke
				(width 0.1524)
				(type default)
			)
			(layer "F.SilkS")
		)
		(fp_line
			(start 0 4.011168)
			(end -3.330702 -4.771136)
			(stroke
				(width 0.1524)
				(type default)
			)
			(layer "F.SilkS")
		)
		(fp_line
			(start 3.330702 -4.771136)
			(end 0 4.011168)
			(stroke
				(width 0.1)
				(type default)
			)
			(layer "F.Fab")
		)
		(fp_line
			(start -3.330702 -4.771136)
			(end 3.330702 -4.771136)
			(stroke
				(width 0.1)
				(type default)
			)
			(layer "F.Fab")
		)
		(fp_line
			(start 0 4.011168)
			(end -3.330702 -4.771136)
			(stroke
				(width 0.1)
				(type default)
			)
			(layer "F.Fab")
		)
		(pad "1" thru_hole circle
			(at 0 0 90)
			(size 2.159 2.159)
			(drill 1.7018)
			(layers "*.Cu" "*.Mask")
			(remove_unused_layers no)
			(net "COUPON_GND1")
			(clearance 0.0254)
			(thermal_gap 0.0254)
		)
		(pad "2" thru_hole circle
			(at -1.27 -3.348736 90)
			(size 2.159 2.159)
			(drill 1.7018)
			(layers "*.Cu" "*.Mask")
			(remove_unused_layers no)
			(net "TDR_SE_50_OHM_IN6")
			(clearance 0.0254)
			(thermal_gap 0.0254)
		)
		(pad "3" thru_hole circle
			(at 1.27 -3.348736 90)
			(size 2.159 2.159)
			(drill 1.7018)
			(layers "*.Cu" "*.Mask")
			(remove_unused_layers no)
			(net "TDR_SE_50_OHM_IN6")
			(clearance 0.0254)
			(thermal_gap 0.0254)
		)
	)
	(footprint ""
		(layer "F.Cu")
		(at 355.163628 -244.976142)
		(property "Reference" "J55"
			(at -1.4224 -4.562348 0)
			(unlocked yes)
			(layer "F.SilkS")
			(effects
				(font
					(size 0.7874 0.5842)
					(thickness 0.1524)
				)
				(justify left)
			)
		)
		(property "Value" ""
			(at 0 0 0)
			(layer "F.Fab")
			(effects
				(font
					(size 1.27 1.27)
				)
			)
		)
		(duplicate_pad_numbers_are_jumpers no)
		(fp_line
			(start -1.27 -3.81)
			(end 1.27 -3.81)
			(stroke
				(width 0.1524)
				(type default)
			)
			(layer "F.SilkS")
		)
		(fp_line
			(start -1.27 -0.7747)
			(end -1.27 -3.81)
			(stroke
				(width 0.1524)
				(type default)
			)
			(layer "F.SilkS")
		)
		(fp_line
			(start -1.27 3.81)
			(end -1.27 0.7747)
			(stroke
				(width 0.1524)
				(type default)
			)
			(layer "F.SilkS")
		)
		(fp_line
			(start 1.27 -3.81)
			(end 1.27 -3.3147)
			(stroke
				(width 0.1524)
				(type default)
			)
			(layer "F.SilkS")
		)
		(fp_line
			(start 1.27 -1.7653)
			(end 1.27 1.7653)
			(stroke
				(width 0.1524)
				(type default)
			)
			(layer "F.SilkS")
		)
		(fp_line
			(start 1.27 3.3147)
			(end 1.27 3.81)
			(stroke
				(width 0.1524)
				(type default)
			)
			(layer "F.SilkS")
		)
		(fp_line
			(start 1.27 3.81)
			(end -1.27 3.81)
			(stroke
				(width 0.1524)
				(type default)
			)
			(layer "F.SilkS")
		)
		(fp_poly
			(pts
				(xy 4.3942 -3.048) (xy 4.3942 -2.032) (xy 3.3782 -2.54)
			)
			(stroke
				(width 0)
				(type default)
			)
			(fill yes)
			(layer "F.SilkS")
		)
		(fp_line
			(start -1.27 -3.81)
			(end -1.27 3.81)
			(stroke
				(width 0.1)
				(type default)
			)
			(layer "F.Fab")
		)
		(fp_line
			(start -1.27 3.81)
			(end 1.27 3.81)
			(stroke
				(width 0.1)
				(type default)
			)
			(layer "F.Fab")
		)
		(fp_line
			(start 1.27 -3.81)
			(end -1.27 -3.81)
			(stroke
				(width 0.1)
				(type default)
			)
			(layer "F.Fab")
		)
		(fp_line
			(start 1.27 3.81)
			(end 1.27 -3.81)
			(stroke
				(width 0.1)
				(type default)
			)
			(layer "F.Fab")
		)
		(fp_poly
			(pts
				(xy 4.3942 -3.048) (xy 4.3942 -2.032) (xy 3.3782 -2.54)
			)
			(stroke
				(width 0)
				(type default)
			)
			(fill yes)
			(layer "F.Fab")
		)
		(fp_text user "3"
			(at 3.921252 2.54 90)
			(unlocked yes)
			(layer "F.SilkS")
			(effects
				(font
					(size 0.7874 0.5842)
					(thickness 0.1524)
				)
			)
		)
		(fp_text user "3"
			(at 3.921252 2.54 90)
			(unlocked yes)
			(layer "F.Fab")
			(effects
				(font
					(size 0.7874 0.5842)
					(thickness 0.1524)
				)
			)
		)
		(pad "1" smd rect
			(at 1.459992 -2.54 90)
			(size 1.27 3.429)
			(layers "F.Cu" "F.Mask" "F.Paste")
			(net "Net_986")
		)
		(pad "2" smd rect
			(at -1.459992 0 90)
			(size 1.27 3.429)
			(layers "F.Cu" "F.Mask" "F.Paste")
			(net "JP_FPGA_DEBUG_N")
		)
		(pad "3" smd rect
			(at 1.459992 2.54 90)
			(size 1.27 3.429)
			(layers "F.Cu" "F.Mask" "F.Paste")
			(net "GND")
		)
	)
	(footprint ""
		(layer "F.Cu")
		(at 404.953978 -381.90297 -90)
		(property "Reference" "C3997"
			(at 0 0 270)
			(layer "F.SilkS")
			(hide yes)
			(effects
				(font
					(size 1.27 1.27)
				)
			)
		)
		(property "Value" ""
			(at 0 0 270)
			(layer "F.Fab")
			(effects
				(font
					(size 1.27 1.27)
				)
			)
		)
		(duplicate_pad_numbers_are_jumpers no)
		(fp_line
			(start -0.7874 0.4064)
			(end -0.7874 -0.4064)
			(stroke
				(width 0.1524)
				(type default)
			)
			(layer "F.SilkS")
		)
		(fp_line
			(start 0.7874 0.4064)
			(end -0.7874 0.4064)
			(stroke
				(width 0.1524)
				(type default)
			)
			(layer "F.SilkS")
		)
		(fp_line
			(start -0.7874 -0.4064)
			(end 0.7874 -0.4064)
			(stroke
				(width 0.1524)
				(type default)
			)
			(layer "F.SilkS")
		)
		(fp_line
			(start 0.7874 -0.4064)
			(end 0.7874 0.4064)
			(stroke
				(width 0.1524)
				(type default)
			)
			(layer "F.SilkS")
		)
		(fp_line
			(start -0.67945 0.3048)
			(end -0.67945 -0.305054)
			(stroke
				(width 0.1)
				(type default)
			)
			(layer "F.Fab")
		)
		(fp_line
			(start -0.12065 0.3048)
			(end -0.67945 0.3048)
			(stroke
				(width 0.1)
				(type default)
			)
			(layer "F.Fab")
		)
		(fp_line
			(start 0.120396 0.3048)
			(end 0.120396 0.2794)
			(stroke
				(width 0.1)
				(type default)
			)
			(layer "F.Fab")
		)
		(fp_line
			(start 0.67945 0.3048)
			(end 0.120396 0.3048)
			(stroke
				(width 0.1)
				(type default)
			)
			(layer "F.Fab")
		)
		(fp_line
			(start -0.12065 0.2794)
			(end -0.12065 0.3048)
			(stroke
				(width 0.1)
				(type default)
			)
			(layer "F.Fab")
		)
		(fp_line
			(start 0.120396 0.2794)
			(end -0.12065 0.2794)
			(stroke
				(width 0.1)
				(type default)
			)
			(layer "F.Fab")
		)
		(fp_line
			(start -0.12065 -0.2794)
			(end 0.12065 -0.2794)
			(stroke
				(width 0.1)
				(type default)
			)
			(layer "F.Fab")
		)
		(fp_line
			(start 0.12065 -0.2794)
			(end 0.12065 -0.3048)
			(stroke
				(width 0.1)
				(type default)
			)
			(layer "F.Fab")
		)
		(fp_line
			(start 0.12065 -0.3048)
			(end 0.67945 -0.3048)
			(stroke
				(width 0.1)
				(type default)
			)
			(layer "F.Fab")
		)
		(fp_line
			(start 0.67945 -0.3048)
			(end 0.67945 0.3048)
			(stroke
				(width 0.1)
				(type default)
			)
			(layer "F.Fab")
		)
		(fp_line
			(start -0.67945 -0.305054)
			(end -0.12065 -0.305054)
			(stroke
				(width 0.1)
				(type default)
			)
			(layer "F.Fab")
		)
		(fp_line
			(start -0.12065 -0.305054)
			(end -0.12065 -0.2794)
			(stroke
				(width 0.1)
				(type default)
			)
			(layer "F.Fab")
		)
		(pad "1" smd circle
			(at -0.40005 0 270)
			(size 0 0)
			(layers "F.Cu" "F.Mask" "F.Paste")
			(net "GND")
		)
		(pad "2" smd circle
			(at 0.40005 0 270)
			(size 0 0)
			(layers "F.Cu" "F.Mask" "F.Paste")
			(net "P3V3_AUX")
		)
	)
	(footprint ""
		(layer "F.Cu")
		(at 26.584148 -29.222954 -90)
		(property "Reference" "PC669"
			(at 0 0 270)
			(layer "F.SilkS")
			(hide yes)
			(effects
				(font
					(size 1.27 1.27)
				)
			)
		)
		(property "Value" ""
			(at 0 0 270)
			(layer "F.Fab")
			(effects
				(font
					(size 1.27 1.27)
				)
			)
		)
		(duplicate_pad_numbers_are_jumpers no)
		(fp_line
			(start -0.7874 0.4064)
			(end -0.7874 -0.4064)
			(stroke
				(width 0.1524)
				(type default)
			)
			(layer "F.SilkS")
		)
		(fp_line
			(start 0.7874 0.4064)
			(end -0.7874 0.4064)
			(stroke
				(width 0.1524)
				(type default)
			)
			(layer "F.SilkS")
		)
		(fp_line
			(start -0.7874 -0.4064)
			(end 0.7874 -0.4064)
			(stroke
				(width 0.1524)
				(type default)
			)
			(layer "F.SilkS")
		)
		(fp_line
			(start 0.7874 -0.4064)
			(end 0.7874 0.4064)
			(stroke
				(width 0.1524)
				(type default)
			)
			(layer "F.SilkS")
		)
		(fp_line
			(start -0.67945 0.3048)
			(end -0.67945 -0.305054)
			(stroke
				(width 0.1)
				(type default)
			)
			(layer "F.Fab")
		)
		(fp_line
			(start -0.12065 0.3048)
			(end -0.67945 0.3048)
			(stroke
				(width 0.1)
				(type default)
			)
			(layer "F.Fab")
		)
		(fp_line
			(start 0.120396 0.3048)
			(end 0.120396 0.2794)
			(stroke
				(width 0.1)
				(type default)
			)
			(layer "F.Fab")
		)
		(fp_line
			(start 0.67945 0.3048)
			(end 0.120396 0.3048)
			(stroke
				(width 0.1)
				(type default)
			)
			(layer "F.Fab")
		)
		(fp_line
			(start -0.12065 0.2794)
			(end -0.12065 0.3048)
			(stroke
				(width 0.1)
				(type default)
			)
			(layer "F.Fab")
		)
		(fp_line
			(start 0.120396 0.2794)
			(end -0.12065 0.2794)
			(stroke
				(width 0.1)
				(type default)
			)
			(layer "F.Fab")
		)
		(fp_line
			(start -0.12065 -0.2794)
			(end 0.12065 -0.2794)
			(stroke
				(width 0.1)
				(type default)
			)
			(layer "F.Fab")
		)
		(fp_line
			(start 0.12065 -0.2794)
			(end 0.12065 -0.3048)
			(stroke
				(width 0.1)
				(type default)
			)
			(layer "F.Fab")
		)
		(fp_line
			(start 0.12065 -0.3048)
			(end 0.67945 -0.3048)
			(stroke
				(width 0.1)
				(type default)
			)
			(layer "F.Fab")
		)
		(fp_line
			(start 0.67945 -0.3048)
			(end 0.67945 0.3048)
			(stroke
				(width 0.1)
				(type default)
			)
			(layer "F.Fab")
		)
		(fp_line
			(start -0.67945 -0.305054)
			(end -0.12065 -0.305054)
			(stroke
				(width 0.1)
				(type default)
			)
			(layer "F.Fab")
		)
		(fp_line
			(start -0.12065 -0.305054)
			(end -0.12065 -0.2794)
			(stroke
				(width 0.1)
				(type default)
			)
			(layer "F.Fab")
		)
		(pad "1" smd circle
			(at -0.40005 0 270)
			(size 0 0)
			(layers "F.Cu" "F.Mask" "F.Paste")
			(net "P3V3_AUX")
		)
		(pad "2" smd circle
			(at 0.40005 0 270)
			(size 0 0)
			(layers "F.Cu" "F.Mask" "F.Paste")
			(net "GND")
		)
	)
	(footprint ""
		(layer "F.Cu")
		(at 335.154524 -356.244906 90)
		(property "Reference" "C528"
			(at 0 0 90)
			(layer "F.SilkS")
			(hide yes)
			(effects
				(font
					(size 1.27 1.27)
				)
			)
		)
		(property "Value" ""
			(at 0 0 90)
			(layer "F.Fab")
			(effects
				(font
					(size 1.27 1.27)
				)
			)
		)
		(duplicate_pad_numbers_are_jumpers no)
		(fp_line
			(start 0.299974 -0.150114)
			(end 0.299974 0.150114)
			(stroke
				(width 0.1)
				(type default)
			)
			(layer "F.Fab")
		)
		(fp_line
			(start -0.299974 -0.150114)
			(end 0.299974 -0.150114)
			(stroke
				(width 0.1)
				(type default)
			)
			(layer "F.Fab")
		)
		(fp_line
			(start 0.299974 0.150114)
			(end -0.299974 0.150114)
			(stroke
				(width 0.1)
				(type default)
			)
			(layer "F.Fab")
		)
		(fp_line
			(start -0.299974 0.150114)
			(end -0.299974 -0.150114)
			(stroke
				(width 0.1)
				(type default)
			)
			(layer "F.Fab")
		)
		(pad "1" smd rect
			(at -0.2667 0 90)
			(size 0.3048 0.381)
			(layers "F.Cu" "F.Mask" "F.Paste")
			(net "P5E_PEX2_STN5_TX_DN<91>")
		)
		(pad "2" smd rect
			(at 0.2667 0 90)
			(size 0.3048 0.381)
			(layers "F.Cu" "F.Mask" "F.Paste")
			(net "P5E_PEX2_STN5_TX_C_DN<91>")
		)
	)
	(footprint ""
		(layer "F.Cu")
		(at 153.650442 -250.070874 -90)
		(property "Reference" "R1279"
			(at 0 0 270)
			(layer "F.SilkS")
			(hide yes)
			(effects
				(font
					(size 1.27 1.27)
				)
			)
		)
		(property "Value" ""
			(at 0 0 270)
			(layer "F.Fab")
			(effects
				(font
					(size 1.27 1.27)
				)
			)
		)
		(duplicate_pad_numbers_are_jumpers no)
		(fp_line
			(start -0.7874 0.4064)
			(end -0.7874 -0.4064)
			(stroke
				(width 0.1524)
				(type default)
			)
			(layer "F.SilkS")
		)
		(fp_line
			(start 0.7874 0.4064)
			(end -0.7874 0.4064)
			(stroke
				(width 0.1524)
				(type default)
			)
			(layer "F.SilkS")
		)
		(fp_line
			(start -0.7874 -0.4064)
			(end 0.7874 -0.4064)
			(stroke
				(width 0.1524)
				(type default)
			)
			(layer "F.SilkS")
		)
		(fp_line
			(start 0.7874 -0.4064)
			(end 0.7874 0.4064)
			(stroke
				(width 0.1524)
				(type default)
			)
			(layer "F.SilkS")
		)
		(fp_line
			(start -0.67945 0.3048)
			(end -0.67945 -0.305054)
			(stroke
				(width 0.1)
				(type default)
			)
			(layer "F.Fab")
		)
		(fp_line
			(start -0.12065 0.3048)
			(end -0.67945 0.3048)
			(stroke
				(width 0.1)
				(type default)
			)
			(layer "F.Fab")
		)
		(fp_line
			(start 0.120396 0.3048)
			(end 0.120396 0.2794)
			(stroke
				(width 0.1)
				(type default)
			)
			(layer "F.Fab")
		)
		(fp_line
			(start 0.67945 0.3048)
			(end 0.120396 0.3048)
			(stroke
				(width 0.1)
				(type default)
			)
			(layer "F.Fab")
		)
		(fp_line
			(start -0.12065 0.2794)
			(end -0.12065 0.3048)
			(stroke
				(width 0.1)
				(type default)
			)
			(layer "F.Fab")
		)
		(fp_line
			(start 0.120396 0.2794)
			(end -0.12065 0.2794)
			(stroke
				(width 0.1)
				(type default)
			)
			(layer "F.Fab")
		)
		(fp_line
			(start -0.12065 -0.2794)
			(end 0.12065 -0.2794)
			(stroke
				(width 0.1)
				(type default)
			)
			(layer "F.Fab")
		)
		(fp_line
			(start 0.12065 -0.2794)
			(end 0.12065 -0.3048)
			(stroke
				(width 0.1)
				(type default)
			)
			(layer "F.Fab")
		)
		(fp_line
			(start 0.12065 -0.3048)
			(end 0.67945 -0.3048)
			(stroke
				(width 0.1)
				(type default)
			)
			(layer "F.Fab")
		)
		(fp_line
			(start 0.67945 -0.3048)
			(end 0.67945 0.3048)
			(stroke
				(width 0.1)
				(type default)
			)
			(layer "F.Fab")
		)
		(fp_line
			(start -0.67945 -0.305054)
			(end -0.12065 -0.305054)
			(stroke
				(width 0.1)
				(type default)
			)
			(layer "F.Fab")
		)
		(fp_line
			(start -0.12065 -0.305054)
			(end -0.12065 -0.2794)
			(stroke
				(width 0.1)
				(type default)
			)
			(layer "F.Fab")
		)
		(pad "1" smd circle
			(at -0.40005 0 270)
			(size 0 0)
			(layers "F.Cu" "F.Mask" "F.Paste")
			(net "PEX1_MODE_SEL10")
		)
		(pad "2" smd circle
			(at 0.40005 0 270)
			(size 0 0)
			(layers "F.Cu" "F.Mask" "F.Paste")
			(net "P1V8_PEX")
		)
	)
	(footprint ""
		(layer "F.Cu")
		(at 196.119242 -147.104608 180)
		(property "Reference" "C222"
			(at 0 0 180)
			(layer "F.SilkS")
			(hide yes)
			(effects
				(font
					(size 1.27 1.27)
				)
			)
		)
		(property "Value" ""
			(at 0 0 180)
			(layer "F.Fab")
			(effects
				(font
					(size 1.27 1.27)
				)
			)
		)
		(duplicate_pad_numbers_are_jumpers no)
		(fp_line
			(start 0.299974 0.150114)
			(end -0.299974 0.150114)
			(stroke
				(width 0.1)
				(type default)
			)
			(layer "F.Fab")
		)
		(fp_line
			(start 0.299974 -0.150114)
			(end 0.299974 0.150114)
			(stroke
				(width 0.1)
				(type default)
			)
			(layer "F.Fab")
		)
		(fp_line
			(start -0.299974 0.150114)
			(end -0.299974 -0.150114)
			(stroke
				(width 0.1)
				(type default)
			)
			(layer "F.Fab")
		)
		(fp_line
			(start -0.299974 -0.150114)
			(end 0.299974 -0.150114)
			(stroke
				(width 0.1)
				(type default)
			)
			(layer "F.Fab")
		)
		(pad "1" smd rect
			(at -0.2667 0 180)
			(size 0.3048 0.381)
			(layers "F.Cu" "F.Mask" "F.Paste")
			(net "P5E_PEX1_STN0_TX_DP<10>")
		)
		(pad "2" smd rect
			(at 0.2667 0 180)
			(size 0.3048 0.381)
			(layers "F.Cu" "F.Mask" "F.Paste")
			(net "P5E_PEX1_STN0_TX_C_DP<10>")
		)
	)
	(footprint ""
		(layer "F.Cu")
		(at 408.41041 -63.652146 180)
		(property "Reference" "R6026"
			(at 0 0 180)
			(layer "F.SilkS")
			(hide yes)
			(effects
				(font
					(size 1.27 1.27)
				)
			)
		)
		(property "Value" ""
			(at 0 0 180)
			(layer "F.Fab")
			(effects
				(font
					(size 1.27 1.27)
				)
			)
		)
		(duplicate_pad_numbers_are_jumpers no)
		(fp_line
			(start 0.7874 0.4064)
			(end -0.7874 0.4064)
			(stroke
				(width 0.1524)
				(type default)
			)
			(layer "F.SilkS")
		)
		(fp_line
			(start 0.7874 -0.4064)
			(end 0.7874 0.4064)
			(stroke
				(width 0.1524)
				(type default)
			)
			(layer "F.SilkS")
		)
		(fp_line
			(start -0.7874 0.4064)
			(end -0.7874 -0.4064)
			(stroke
				(width 0.1524)
				(type default)
			)
			(layer "F.SilkS")
		)
		(fp_line
			(start -0.7874 -0.4064)
			(end 0.7874 -0.4064)
			(stroke
				(width 0.1524)
				(type default)
			)
			(layer "F.SilkS")
		)
		(fp_line
			(start 0.67945 0.3048)
			(end 0.120396 0.3048)
			(stroke
				(width 0.1)
				(type default)
			)
			(layer "F.Fab")
		)
		(fp_line
			(start 0.67945 -0.3048)
			(end 0.67945 0.3048)
			(stroke
				(width 0.1)
				(type default)
			)
			(layer "F.Fab")
		)
		(fp_line
			(start 0.12065 -0.2794)
			(end 0.12065 -0.3048)
			(stroke
				(width 0.1)
				(type default)
			)
			(layer "F.Fab")
		)
		(fp_line
			(start 0.12065 -0.3048)
			(end 0.67945 -0.3048)
			(stroke
				(width 0.1)
				(type default)
			)
			(layer "F.Fab")
		)
		(fp_line
			(start 0.120396 0.3048)
			(end 0.120396 0.2794)
			(stroke
				(width 0.1)
				(type default)
			)
			(layer "F.Fab")
		)
		(fp_line
			(start 0.120396 0.2794)
			(end -0.12065 0.2794)
			(stroke
				(width 0.1)
				(type default)
			)
			(layer "F.Fab")
		)
		(fp_line
			(start -0.12065 0.3048)
			(end -0.67945 0.3048)
			(stroke
				(width 0.1)
				(type default)
			)
			(layer "F.Fab")
		)
		(fp_line
			(start -0.12065 0.2794)
			(end -0.12065 0.3048)
			(stroke
				(width 0.1)
				(type default)
			)
			(layer "F.Fab")
		)
		(fp_line
			(start -0.12065 -0.2794)
			(end 0.12065 -0.2794)
			(stroke
				(width 0.1)
				(type default)
			)
			(layer "F.Fab")
		)
		(fp_line
			(start -0.12065 -0.305054)
			(end -0.12065 -0.2794)
			(stroke
				(width 0.1)
				(type default)
			)
			(layer "F.Fab")
		)
		(fp_line
			(start -0.67945 0.3048)
			(end -0.67945 -0.305054)
			(stroke
				(width 0.1)
				(type default)
			)
			(layer "F.Fab")
		)
		(fp_line
			(start -0.67945 -0.305054)
			(end -0.12065 -0.305054)
			(stroke
				(width 0.1)
				(type default)
			)
			(layer "F.Fab")
		)
		(pad "1" smd circle
			(at -0.40005 0 180)
			(size 0 0)
			(layers "F.Cu" "F.Mask" "F.Paste")
			(net "P5V_AUX")
		)
		(pad "2" smd circle
			(at 0.40005 0 180)
			(size 0 0)
			(layers "F.Cu" "F.Mask" "F.Paste")
			(net "P12V_SSD14_PG_G2")
		)
	)
	(footprint ""
		(layer "F.Cu")
		(at 123.67514 -92.605606)
		(property "Reference" "R1583"
			(at 0 0 0)
			(layer "F.SilkS")
			(hide yes)
			(effects
				(font
					(size 1.27 1.27)
				)
			)
		)
		(property "Value" ""
			(at 0 0 0)
			(layer "F.Fab")
			(effects
				(font
					(size 1.27 1.27)
				)
			)
		)
		(duplicate_pad_numbers_are_jumpers no)
		(fp_line
			(start -0.7874 -0.4064)
			(end 0.7874 -0.4064)
			(stroke
				(width 0.1524)
				(type default)
			)
			(layer "F.SilkS")
		)
		(fp_line
			(start -0.7874 0.4064)
			(end -0.7874 -0.4064)
			(stroke
				(width 0.1524)
				(type default)
			)
			(layer "F.SilkS")
		)
		(fp_line
			(start 0.7874 -0.4064)
			(end 0.7874 0.4064)
			(stroke
				(width 0.1524)
				(type default)
			)
			(layer "F.SilkS")
		)
		(fp_line
			(start 0.7874 0.4064)
			(end -0.7874 0.4064)
			(stroke
				(width 0.1524)
				(type default)
			)
			(layer "F.SilkS")
		)
		(fp_line
			(start -0.67945 -0.305054)
			(end -0.12065 -0.305054)
			(stroke
				(width 0.1)
				(type default)
			)
			(layer "F.Fab")
		)
		(fp_line
			(start -0.67945 0.3048)
			(end -0.67945 -0.305054)
			(stroke
				(width 0.1)
				(type default)
			)
			(layer "F.Fab")
		)
		(fp_line
			(start -0.12065 -0.305054)
			(end -0.12065 -0.2794)
			(stroke
				(width 0.1)
				(type default)
			)
			(layer "F.Fab")
		)
		(fp_line
			(start -0.12065 -0.2794)
			(end 0.12065 -0.2794)
			(stroke
				(width 0.1)
				(type default)
			)
			(layer "F.Fab")
		)
		(fp_line
			(start -0.12065 0.2794)
			(end -0.12065 0.3048)
			(stroke
				(width 0.1)
				(type default)
			)
			(layer "F.Fab")
		)
		(fp_line
			(start -0.12065 0.3048)
			(end -0.67945 0.3048)
			(stroke
				(width 0.1)
				(type default)
			)
			(layer "F.Fab")
		)
		(fp_line
			(start 0.120396 0.2794)
			(end -0.12065 0.2794)
			(stroke
				(width 0.1)
				(type default)
			)
			(layer "F.Fab")
		)
		(fp_line
			(start 0.120396 0.3048)
			(end 0.120396 0.2794)
			(stroke
				(width 0.1)
				(type default)
			)
			(layer "F.Fab")
		)
		(fp_line
			(start 0.12065 -0.3048)
			(end 0.67945 -0.3048)
			(stroke
				(width 0.1)
				(type default)
			)
			(layer "F.Fab")
		)
		(fp_line
			(start 0.12065 -0.2794)
			(end 0.12065 -0.3048)
			(stroke
				(width 0.1)
				(type default)
			)
			(layer "F.Fab")
		)
		(fp_line
			(start 0.67945 -0.3048)
			(end 0.67945 0.3048)
			(stroke
				(width 0.1)
				(type default)
			)
			(layer "F.Fab")
		)
		(fp_line
			(start 0.67945 0.3048)
			(end 0.120396 0.3048)
			(stroke
				(width 0.1)
				(type default)
			)
			(layer "F.Fab")
		)
		(pad "1" smd circle
			(at -0.40005 0)
			(size 0 0)
			(layers "F.Cu" "F.Mask" "F.Paste")
			(net "SMB_BIC_I2C9_MUX0_SSD2_R_SDA")
		)
		(pad "2" smd circle
			(at 0.40005 0)
			(size 0 0)
			(layers "F.Cu" "F.Mask" "F.Paste")
			(net "SMB_BIC_I2C9_MUX0_SSD2_SDA")
		)
	)
	(footprint ""
		(layer "F.Cu")
		(at 153.347928 -101.095302)
		(property "Reference" "C272"
			(at 0 0 0)
			(layer "F.SilkS")
			(hide yes)
			(effects
				(font
					(size 1.27 1.27)
				)
			)
		)
		(property "Value" ""
			(at 0 0 0)
			(layer "F.Fab")
			(effects
				(font
					(size 1.27 1.27)
				)
			)
		)
		(duplicate_pad_numbers_are_jumpers no)
		(fp_line
			(start -0.299974 -0.150114)
			(end 0.299974 -0.150114)
			(stroke
				(width 0.1)
				(type default)
			)
			(layer "F.Fab")
		)
		(fp_line
			(start -0.299974 0.150114)
			(end -0.299974 -0.150114)
			(stroke
				(width 0.1)
				(type default)
			)
			(layer "F.Fab")
		)
		(fp_line
			(start 0.299974 -0.150114)
			(end 0.299974 0.150114)
			(stroke
				(width 0.1)
				(type default)
			)
			(layer "F.Fab")
		)
		(fp_line
			(start 0.299974 0.150114)
			(end -0.299974 0.150114)
			(stroke
				(width 0.1)
				(type default)
			)
			(layer "F.Fab")
		)
		(pad "1" smd rect
			(at -0.2667 0)
			(size 0.3048 0.381)
			(layers "F.Cu" "F.Mask" "F.Paste")
			(net "P5E_PEX1_STN1_TX_DN<17>")
		)
		(pad "2" smd rect
			(at 0.2667 0)
			(size 0.3048 0.381)
			(layers "F.Cu" "F.Mask" "F.Paste")
			(net "P5E_PEX1_STN1_TX_C_DN<17>")
		)
	)
	(footprint ""
		(layer "F.Cu")
		(at 302.377856 -83.667092 180)
		(property "Reference" "R487"
			(at 0 0 180)
			(layer "F.SilkS")
			(hide yes)
			(effects
				(font
					(size 1.27 1.27)
				)
			)
		)
		(property "Value" ""
			(at 0 0 180)
			(layer "F.Fab")
			(effects
				(font
					(size 1.27 1.27)
				)
			)
		)
		(duplicate_pad_numbers_are_jumpers no)
		(fp_line
			(start 0.7874 0.4064)
			(end -0.7874 0.4064)
			(stroke
				(width 0.1524)
				(type default)
			)
			(layer "F.SilkS")
		)
		(fp_line
			(start 0.7874 -0.4064)
			(end 0.7874 0.4064)
			(stroke
				(width 0.1524)
				(type default)
			)
			(layer "F.SilkS")
		)
		(fp_line
			(start -0.7874 0.4064)
			(end -0.7874 -0.4064)
			(stroke
				(width 0.1524)
				(type default)
			)
			(layer "F.SilkS")
		)
		(fp_line
			(start -0.7874 -0.4064)
			(end 0.7874 -0.4064)
			(stroke
				(width 0.1524)
				(type default)
			)
			(layer "F.SilkS")
		)
		(fp_line
			(start 0.67945 0.3048)
			(end 0.120396 0.3048)
			(stroke
				(width 0.1)
				(type default)
			)
			(layer "F.Fab")
		)
		(fp_line
			(start 0.67945 -0.3048)
			(end 0.67945 0.3048)
			(stroke
				(width 0.1)
				(type default)
			)
			(layer "F.Fab")
		)
		(fp_line
			(start 0.12065 -0.2794)
			(end 0.12065 -0.3048)
			(stroke
				(width 0.1)
				(type default)
			)
			(layer "F.Fab")
		)
		(fp_line
			(start 0.12065 -0.3048)
			(end 0.67945 -0.3048)
			(stroke
				(width 0.1)
				(type default)
			)
			(layer "F.Fab")
		)
		(fp_line
			(start 0.120396 0.3048)
			(end 0.120396 0.2794)
			(stroke
				(width 0.1)
				(type default)
			)
			(layer "F.Fab")
		)
		(fp_line
			(start 0.120396 0.2794)
			(end -0.12065 0.2794)
			(stroke
				(width 0.1)
				(type default)
			)
			(layer "F.Fab")
		)
		(fp_line
			(start -0.12065 0.3048)
			(end -0.67945 0.3048)
			(stroke
				(width 0.1)
				(type default)
			)
			(layer "F.Fab")
		)
		(fp_line
			(start -0.12065 0.2794)
			(end -0.12065 0.3048)
			(stroke
				(width 0.1)
				(type default)
			)
			(layer "F.Fab")
		)
		(fp_line
			(start -0.12065 -0.2794)
			(end 0.12065 -0.2794)
			(stroke
				(width 0.1)
				(type default)
			)
			(layer "F.Fab")
		)
		(fp_line
			(start -0.12065 -0.305054)
			(end -0.12065 -0.2794)
			(stroke
				(width 0.1)
				(type default)
			)
			(layer "F.Fab")
		)
		(fp_line
			(start -0.67945 0.3048)
			(end -0.67945 -0.305054)
			(stroke
				(width 0.1)
				(type default)
			)
			(layer "F.Fab")
		)
		(fp_line
			(start -0.67945 -0.305054)
			(end -0.12065 -0.305054)
			(stroke
				(width 0.1)
				(type default)
			)
			(layer "F.Fab")
		)
		(pad "1" smd circle
			(at -0.40005 0 180)
			(size 0 0)
			(layers "F.Cu" "F.Mask" "F.Paste")
			(net "SMB_BIC_I2C6_MUX_FRU_R_SCL")
		)
		(pad "2" smd circle
			(at 0.40005 0 180)
			(size 0 0)
			(layers "F.Cu" "F.Mask" "F.Paste")
			(net "SMB_BMC_FRU_SCL")
		)
	)
	(footprint ""
		(layer "F.Cu")
		(at 203.877418 -309.791354 135)
		(property "Reference" "R1310"
			(at 0 0 135)
			(layer "F.SilkS")
			(hide yes)
			(effects
				(font
					(size 1.27 1.27)
				)
			)
		)
		(property "Value" ""
			(at 0 0 135)
			(layer "F.Fab")
			(effects
				(font
					(size 1.27 1.27)
				)
			)
		)
		(duplicate_pad_numbers_are_jumpers no)
		(fp_line
			(start 0.787389 -0.406267)
			(end 0.787389 0.406267)
			(stroke
				(width 0.1524)
				(type default)
			)
			(layer "F.SilkS")
		)
		(fp_line
			(start 0.787389 0.406267)
			(end -0.787389 0.406267)
			(stroke
				(width 0.1524)
				(type default)
			)
			(layer "F.SilkS")
		)
		(fp_line
			(start -0.787389 -0.406267)
			(end 0.787389 -0.406267)
			(stroke
				(width 0.1524)
				(type default)
			)
			(layer "F.SilkS")
		)
		(fp_line
			(start -0.787389 0.406267)
			(end -0.787389 -0.406267)
			(stroke
				(width 0.1524)
				(type default)
			)
			(layer "F.SilkS")
		)
		(fp_line
			(start 0.679446 -0.30479)
			(end 0.679446 0.30479)
			(stroke
				(width 0.1)
				(type default)
			)
			(layer "F.Fab")
		)
		(fp_line
			(start 0.120515 -0.30479)
			(end 0.679446 -0.30479)
			(stroke
				(width 0.1)
				(type default)
			)
			(layer "F.Fab")
		)
		(fp_line
			(start 0.120695 -0.279466)
			(end 0.120515 -0.30479)
			(stroke
				(width 0.1)
				(type default)
			)
			(layer "F.Fab")
		)
		(fp_line
			(start 0.679446 0.30479)
			(end 0.120515 0.30479)
			(stroke
				(width 0.1)
				(type default)
			)
			(layer "F.Fab")
		)
		(fp_line
			(start -0.120695 -0.304969)
			(end -0.120695 -0.279466)
			(stroke
				(width 0.1)
				(type default)
			)
			(layer "F.Fab")
		)
		(fp_line
			(start -0.120695 -0.279466)
			(end 0.120695 -0.279466)
			(stroke
				(width 0.1)
				(type default)
			)
			(layer "F.Fab")
		)
		(fp_line
			(start 0.120335 0.279466)
			(end -0.120695 0.279466)
			(stroke
				(width 0.1)
				(type default)
			)
			(layer "F.Fab")
		)
		(fp_line
			(start 0.120515 0.30479)
			(end 0.120335 0.279466)
			(stroke
				(width 0.1)
				(type default)
			)
			(layer "F.Fab")
		)
		(fp_line
			(start -0.679446 -0.305149)
			(end -0.120695 -0.304969)
			(stroke
				(width 0.1)
				(type default)
			)
			(layer "F.Fab")
		)
		(fp_line
			(start -0.120695 0.279466)
			(end -0.120515 0.30479)
			(stroke
				(width 0.1)
				(type default)
			)
			(layer "F.Fab")
		)
		(fp_line
			(start -0.120515 0.30479)
			(end -0.679446 0.30479)
			(stroke
				(width 0.1)
				(type default)
			)
			(layer "F.Fab")
		)
		(fp_line
			(start -0.679446 0.30479)
			(end -0.679446 -0.305149)
			(stroke
				(width 0.1)
				(type default)
			)
			(layer "F.Fab")
		)
		(pad "1" smd circle
			(at -0.40005 0 135)
			(size 0 0)
			(layers "F.Cu" "F.Mask" "F.Paste")
			(net "PEX1_SPARE7")
		)
		(pad "2" smd circle
			(at 0.40005 0 135)
			(size 0 0)
			(layers "F.Cu" "F.Mask" "F.Paste")
			(net "P1V8_PEX")
		)
	)
	(footprint ""
		(layer "F.Cu")
		(at 236.4486 -116.04752 90)
		(property "Reference" "PR6897"
			(at 0 0 90)
			(layer "F.SilkS")
			(hide yes)
			(effects
				(font
					(size 1.27 1.27)
				)
			)
		)
		(property "Value" ""
			(at 0 0 90)
			(layer "F.Fab")
			(effects
				(font
					(size 1.27 1.27)
				)
			)
		)
		(duplicate_pad_numbers_are_jumpers no)
		(fp_line
			(start 0.7874 -0.4064)
			(end 0.7874 0.4064)
			(stroke
				(width 0.1524)
				(type default)
			)
			(layer "F.SilkS")
		)
		(fp_line
			(start -0.7874 -0.4064)
			(end 0.7874 -0.4064)
			(stroke
				(width 0.1524)
				(type default)
			)
			(layer "F.SilkS")
		)
		(fp_line
			(start 0.7874 0.4064)
			(end -0.7874 0.4064)
			(stroke
				(width 0.1524)
				(type default)
			)
			(layer "F.SilkS")
		)
		(fp_line
			(start -0.7874 0.4064)
			(end -0.7874 -0.4064)
			(stroke
				(width 0.1524)
				(type default)
			)
			(layer "F.SilkS")
		)
		(fp_line
			(start -0.12065 -0.305054)
			(end -0.12065 -0.2794)
			(stroke
				(width 0.1)
				(type default)
			)
			(layer "F.Fab")
		)
		(fp_line
			(start -0.67945 -0.305054)
			(end -0.12065 -0.305054)
			(stroke
				(width 0.1)
				(type default)
			)
			(layer "F.Fab")
		)
		(fp_line
			(start 0.67945 -0.3048)
			(end 0.67945 0.3048)
			(stroke
				(width 0.1)
				(type default)
			)
			(layer "F.Fab")
		)
		(fp_line
			(start 0.12065 -0.3048)
			(end 0.67945 -0.3048)
			(stroke
				(width 0.1)
				(type default)
			)
			(layer "F.Fab")
		)
		(fp_line
			(start 0.12065 -0.2794)
			(end 0.12065 -0.3048)
			(stroke
				(width 0.1)
				(type default)
			)
			(layer "F.Fab")
		)
		(fp_line
			(start -0.12065 -0.2794)
			(end 0.12065 -0.2794)
			(stroke
				(width 0.1)
				(type default)
			)
			(layer "F.Fab")
		)
		(fp_line
			(start 0.120396 0.2794)
			(end -0.12065 0.2794)
			(stroke
				(width 0.1)
				(type default)
			)
			(layer "F.Fab")
		)
		(fp_line
			(start -0.12065 0.2794)
			(end -0.12065 0.3048)
			(stroke
				(width 0.1)
				(type default)
			)
			(layer "F.Fab")
		)
		(fp_line
			(start 0.67945 0.3048)
			(end 0.120396 0.3048)
			(stroke
				(width 0.1)
				(type default)
			)
			(layer "F.Fab")
		)
		(fp_line
			(start 0.120396 0.3048)
			(end 0.120396 0.2794)
			(stroke
				(width 0.1)
				(type default)
			)
			(layer "F.Fab")
		)
		(fp_line
			(start -0.12065 0.3048)
			(end -0.67945 0.3048)
			(stroke
				(width 0.1)
				(type default)
			)
			(layer "F.Fab")
		)
		(fp_line
			(start -0.67945 0.3048)
			(end -0.67945 -0.305054)
			(stroke
				(width 0.1)
				(type default)
			)
			(layer "F.Fab")
		)
		(pad "1" smd circle
			(at -0.40005 0 90)
			(size 0 0)
			(layers "F.Cu" "F.Mask" "F.Paste")
			(net "P12V_NIC3_CO_ISET")
		)
		(pad "2" smd circle
			(at 0.40005 0 90)
			(size 0 0)
			(layers "F.Cu" "F.Mask" "F.Paste")
			(net "P12V_NIC3_CO_ISET_R")
		)
	)
	(footprint ""
		(layer "F.Cu")
		(at 338.074 -167.005 180)
		(property "Reference" "R4772"
			(at 0 0 180)
			(layer "F.SilkS")
			(hide yes)
			(effects
				(font
					(size 1.27 1.27)
				)
			)
		)
		(property "Value" ""
			(at 0 0 180)
			(layer "F.Fab")
			(effects
				(font
					(size 1.27 1.27)
				)
			)
		)
		(duplicate_pad_numbers_are_jumpers no)
		(fp_line
			(start 0.7874 0.4064)
			(end -0.7874 0.4064)
			(stroke
				(width 0.1524)
				(type default)
			)
			(layer "F.SilkS")
		)
		(fp_line
			(start 0.7874 -0.4064)
			(end 0.7874 0.4064)
			(stroke
				(width 0.1524)
				(type default)
			)
			(layer "F.SilkS")
		)
		(fp_line
			(start -0.7874 0.4064)
			(end -0.7874 -0.4064)
			(stroke
				(width 0.1524)
				(type default)
			)
			(layer "F.SilkS")
		)
		(fp_line
			(start -0.7874 -0.4064)
			(end 0.7874 -0.4064)
			(stroke
				(width 0.1524)
				(type default)
			)
			(layer "F.SilkS")
		)
		(fp_line
			(start 0.67945 0.3048)
			(end 0.120396 0.3048)
			(stroke
				(width 0.1)
				(type default)
			)
			(layer "F.Fab")
		)
		(fp_line
			(start 0.67945 -0.3048)
			(end 0.67945 0.3048)
			(stroke
				(width 0.1)
				(type default)
			)
			(layer "F.Fab")
		)
		(fp_line
			(start 0.12065 -0.2794)
			(end 0.12065 -0.3048)
			(stroke
				(width 0.1)
				(type default)
			)
			(layer "F.Fab")
		)
		(fp_line
			(start 0.12065 -0.3048)
			(end 0.67945 -0.3048)
			(stroke
				(width 0.1)
				(type default)
			)
			(layer "F.Fab")
		)
		(fp_line
			(start 0.120396 0.3048)
			(end 0.120396 0.2794)
			(stroke
				(width 0.1)
				(type default)
			)
			(layer "F.Fab")
		)
		(fp_line
			(start 0.120396 0.2794)
			(end -0.12065 0.2794)
			(stroke
				(width 0.1)
				(type default)
			)
			(layer "F.Fab")
		)
		(fp_line
			(start -0.12065 0.3048)
			(end -0.67945 0.3048)
			(stroke
				(width 0.1)
				(type default)
			)
			(layer "F.Fab")
		)
		(fp_line
			(start -0.12065 0.2794)
			(end -0.12065 0.3048)
			(stroke
				(width 0.1)
				(type default)
			)
			(layer "F.Fab")
		)
		(fp_line
			(start -0.12065 -0.2794)
			(end 0.12065 -0.2794)
			(stroke
				(width 0.1)
				(type default)
			)
			(layer "F.Fab")
		)
		(fp_line
			(start -0.12065 -0.305054)
			(end -0.12065 -0.2794)
			(stroke
				(width 0.1)
				(type default)
			)
			(layer "F.Fab")
		)
		(fp_line
			(start -0.67945 0.3048)
			(end -0.67945 -0.305054)
			(stroke
				(width 0.1)
				(type default)
			)
			(layer "F.Fab")
		)
		(fp_line
			(start -0.67945 -0.305054)
			(end -0.12065 -0.305054)
			(stroke
				(width 0.1)
				(type default)
			)
			(layer "F.Fab")
		)
		(pad "1" smd circle
			(at -0.40005 0 180)
			(size 0 0)
			(layers "F.Cu" "F.Mask" "F.Paste")
			(net "PRSNT_SSD11_FPGA_PCA9555_N")
		)
		(pad "2" smd circle
			(at 0.40005 0 180)
			(size 0 0)
			(layers "F.Cu" "F.Mask" "F.Paste")
			(net "PRSNT_SSD11_FPGA_R_N")
		)
	)
	(footprint ""
		(layer "F.Cu")
		(at 202.430888 -354.629212 90)
		(property "Reference" "R6255"
			(at 0 0 90)
			(layer "F.SilkS")
			(hide yes)
			(effects
				(font
					(size 1.27 1.27)
				)
			)
		)
		(property "Value" ""
			(at 0 0 90)
			(layer "F.Fab")
			(effects
				(font
					(size 1.27 1.27)
				)
			)
		)
		(duplicate_pad_numbers_are_jumpers no)
		(fp_line
			(start 0.7874 -0.4064)
			(end 0.7874 0.4064)
			(stroke
				(width 0.1524)
				(type default)
			)
			(layer "F.SilkS")
		)
		(fp_line
			(start -0.7874 -0.4064)
			(end 0.7874 -0.4064)
			(stroke
				(width 0.1524)
				(type default)
			)
			(layer "F.SilkS")
		)
		(fp_line
			(start 0.7874 0.4064)
			(end -0.7874 0.4064)
			(stroke
				(width 0.1524)
				(type default)
			)
			(layer "F.SilkS")
		)
		(fp_line
			(start -0.7874 0.4064)
			(end -0.7874 -0.4064)
			(stroke
				(width 0.1524)
				(type default)
			)
			(layer "F.SilkS")
		)
		(fp_line
			(start -0.12065 -0.305054)
			(end -0.12065 -0.2794)
			(stroke
				(width 0.1)
				(type default)
			)
			(layer "F.Fab")
		)
		(fp_line
			(start -0.67945 -0.305054)
			(end -0.12065 -0.305054)
			(stroke
				(width 0.1)
				(type default)
			)
			(layer "F.Fab")
		)
		(fp_line
			(start 0.67945 -0.3048)
			(end 0.67945 0.3048)
			(stroke
				(width 0.1)
				(type default)
			)
			(layer "F.Fab")
		)
		(fp_line
			(start 0.12065 -0.3048)
			(end 0.67945 -0.3048)
			(stroke
				(width 0.1)
				(type default)
			)
			(layer "F.Fab")
		)
		(fp_line
			(start 0.12065 -0.2794)
			(end 0.12065 -0.3048)
			(stroke
				(width 0.1)
				(type default)
			)
			(layer "F.Fab")
		)
		(fp_line
			(start -0.12065 -0.2794)
			(end 0.12065 -0.2794)
			(stroke
				(width 0.1)
				(type default)
			)
			(layer "F.Fab")
		)
		(fp_line
			(start 0.120396 0.2794)
			(end -0.12065 0.2794)
			(stroke
				(width 0.1)
				(type default)
			)
			(layer "F.Fab")
		)
		(fp_line
			(start -0.12065 0.2794)
			(end -0.12065 0.3048)
			(stroke
				(width 0.1)
				(type default)
			)
			(layer "F.Fab")
		)
		(fp_line
			(start 0.67945 0.3048)
			(end 0.120396 0.3048)
			(stroke
				(width 0.1)
				(type default)
			)
			(layer "F.Fab")
		)
		(fp_line
			(start 0.120396 0.3048)
			(end 0.120396 0.2794)
			(stroke
				(width 0.1)
				(type default)
			)
			(layer "F.Fab")
		)
		(fp_line
			(start -0.12065 0.3048)
			(end -0.67945 0.3048)
			(stroke
				(width 0.1)
				(type default)
			)
			(layer "F.Fab")
		)
		(fp_line
			(start -0.67945 0.3048)
			(end -0.67945 -0.305054)
			(stroke
				(width 0.1)
				(type default)
			)
			(layer "F.Fab")
		)
		(pad "1" smd circle
			(at -0.40005 0 90)
			(size 0 0)
			(layers "F.Cu" "F.Mask" "F.Paste")
			(net "GND")
		)
		(pad "2" smd circle
			(at 0.40005 0 90)
			(size 0 0)
			(layers "F.Cu" "F.Mask" "F.Paste")
			(net "PD_MB_HSC_ISO_D1_EN")
		)
	)
	(footprint ""
		(layer "F.Cu")
		(at 58.686192 -385.718812 180)
		(property "Reference" "R1833"
			(at 0 0 180)
			(layer "F.SilkS")
			(hide yes)
			(effects
				(font
					(size 1.27 1.27)
				)
			)
		)
		(property "Value" ""
			(at 0 0 180)
			(layer "F.Fab")
			(effects
				(font
					(size 1.27 1.27)
				)
			)
		)
		(duplicate_pad_numbers_are_jumpers no)
		(fp_line
			(start 0.7874 0.4064)
			(end -0.7874 0.4064)
			(stroke
				(width 0.1524)
				(type default)
			)
			(layer "F.SilkS")
		)
		(fp_line
			(start 0.7874 -0.4064)
			(end 0.7874 0.4064)
			(stroke
				(width 0.1524)
				(type default)
			)
			(layer "F.SilkS")
		)
		(fp_line
			(start -0.7874 0.4064)
			(end -0.7874 -0.4064)
			(stroke
				(width 0.1524)
				(type default)
			)
			(layer "F.SilkS")
		)
		(fp_line
			(start -0.7874 -0.4064)
			(end 0.7874 -0.4064)
			(stroke
				(width 0.1524)
				(type default)
			)
			(layer "F.SilkS")
		)
		(fp_line
			(start 0.67945 0.3048)
			(end 0.120396 0.3048)
			(stroke
				(width 0.1)
				(type default)
			)
			(layer "F.Fab")
		)
		(fp_line
			(start 0.67945 -0.3048)
			(end 0.67945 0.3048)
			(stroke
				(width 0.1)
				(type default)
			)
			(layer "F.Fab")
		)
		(fp_line
			(start 0.12065 -0.2794)
			(end 0.12065 -0.3048)
			(stroke
				(width 0.1)
				(type default)
			)
			(layer "F.Fab")
		)
		(fp_line
			(start 0.12065 -0.3048)
			(end 0.67945 -0.3048)
			(stroke
				(width 0.1)
				(type default)
			)
			(layer "F.Fab")
		)
		(fp_line
			(start 0.120396 0.3048)
			(end 0.120396 0.2794)
			(stroke
				(width 0.1)
				(type default)
			)
			(layer "F.Fab")
		)
		(fp_line
			(start 0.120396 0.2794)
			(end -0.12065 0.2794)
			(stroke
				(width 0.1)
				(type default)
			)
			(layer "F.Fab")
		)
		(fp_line
			(start -0.12065 0.3048)
			(end -0.67945 0.3048)
			(stroke
				(width 0.1)
				(type default)
			)
			(layer "F.Fab")
		)
		(fp_line
			(start -0.12065 0.2794)
			(end -0.12065 0.3048)
			(stroke
				(width 0.1)
				(type default)
			)
			(layer "F.Fab")
		)
		(fp_line
			(start -0.12065 -0.2794)
			(end 0.12065 -0.2794)
			(stroke
				(width 0.1)
				(type default)
			)
			(layer "F.Fab")
		)
		(fp_line
			(start -0.12065 -0.305054)
			(end -0.12065 -0.2794)
			(stroke
				(width 0.1)
				(type default)
			)
			(layer "F.Fab")
		)
		(fp_line
			(start -0.67945 0.3048)
			(end -0.67945 -0.305054)
			(stroke
				(width 0.1)
				(type default)
			)
			(layer "F.Fab")
		)
		(fp_line
			(start -0.67945 -0.305054)
			(end -0.12065 -0.305054)
			(stroke
				(width 0.1)
				(type default)
			)
			(layer "F.Fab")
		)
		(pad "1" smd circle
			(at -0.40005 0 180)
			(size 0 0)
			(layers "F.Cu" "F.Mask" "F.Paste")
			(net "GPU_BASE_FPGA_READY_R")
		)
		(pad "2" smd circle
			(at 0.40005 0 180)
			(size 0 0)
			(layers "F.Cu" "F.Mask" "F.Paste")
			(net "GPU_BASE_FPGA_READY")
		)
	)
	(footprint ""
		(layer "F.Cu")
		(at 321.035934 -289.230816 90)
		(property "Reference" "R3983"
			(at 0 0 90)
			(layer "F.SilkS")
			(hide yes)
			(effects
				(font
					(size 1.27 1.27)
				)
			)
		)
		(property "Value" ""
			(at 0 0 90)
			(layer "F.Fab")
			(effects
				(font
					(size 1.27 1.27)
				)
			)
		)
		(duplicate_pad_numbers_are_jumpers no)
		(fp_line
			(start 0.7874 -0.4064)
			(end 0.7874 0.4064)
			(stroke
				(width 0.1524)
				(type default)
			)
			(layer "F.SilkS")
		)
		(fp_line
			(start -0.7874 -0.4064)
			(end 0.7874 -0.4064)
			(stroke
				(width 0.1524)
				(type default)
			)
			(layer "F.SilkS")
		)
		(fp_line
			(start 0.7874 0.4064)
			(end -0.7874 0.4064)
			(stroke
				(width 0.1524)
				(type default)
			)
			(layer "F.SilkS")
		)
		(fp_line
			(start -0.7874 0.4064)
			(end -0.7874 -0.4064)
			(stroke
				(width 0.1524)
				(type default)
			)
			(layer "F.SilkS")
		)
		(fp_line
			(start -0.12065 -0.305054)
			(end -0.12065 -0.2794)
			(stroke
				(width 0.1)
				(type default)
			)
			(layer "F.Fab")
		)
		(fp_line
			(start -0.67945 -0.305054)
			(end -0.12065 -0.305054)
			(stroke
				(width 0.1)
				(type default)
			)
			(layer "F.Fab")
		)
		(fp_line
			(start 0.67945 -0.3048)
			(end 0.67945 0.3048)
			(stroke
				(width 0.1)
				(type default)
			)
			(layer "F.Fab")
		)
		(fp_line
			(start 0.12065 -0.3048)
			(end 0.67945 -0.3048)
			(stroke
				(width 0.1)
				(type default)
			)
			(layer "F.Fab")
		)
		(fp_line
			(start 0.12065 -0.2794)
			(end 0.12065 -0.3048)
			(stroke
				(width 0.1)
				(type default)
			)
			(layer "F.Fab")
		)
		(fp_line
			(start -0.12065 -0.2794)
			(end 0.12065 -0.2794)
			(stroke
				(width 0.1)
				(type default)
			)
			(layer "F.Fab")
		)
		(fp_line
			(start 0.120396 0.2794)
			(end -0.12065 0.2794)
			(stroke
				(width 0.1)
				(type default)
			)
			(layer "F.Fab")
		)
		(fp_line
			(start -0.12065 0.2794)
			(end -0.12065 0.3048)
			(stroke
				(width 0.1)
				(type default)
			)
			(layer "F.Fab")
		)
		(fp_line
			(start 0.67945 0.3048)
			(end 0.120396 0.3048)
			(stroke
				(width 0.1)
				(type default)
			)
			(layer "F.Fab")
		)
		(fp_line
			(start 0.120396 0.3048)
			(end 0.120396 0.2794)
			(stroke
				(width 0.1)
				(type default)
			)
			(layer "F.Fab")
		)
		(fp_line
			(start -0.12065 0.3048)
			(end -0.67945 0.3048)
			(stroke
				(width 0.1)
				(type default)
			)
			(layer "F.Fab")
		)
		(fp_line
			(start -0.67945 0.3048)
			(end -0.67945 -0.305054)
			(stroke
				(width 0.1)
				(type default)
			)
			(layer "F.Fab")
		)
		(pad "1" smd circle
			(at -0.40005 0 90)
			(size 0 0)
			(layers "F.Cu" "F.Mask" "F.Paste")
			(net "SMB_PEX2_PCA9555_SDA")
		)
		(pad "2" smd circle
			(at 0.40005 0 90)
			(size 0 0)
			(layers "F.Cu" "F.Mask" "F.Paste")
			(net "SMB_PEX2_HOST_LS_SDA")
		)
	)
	(footprint ""
		(layer "F.Cu")
		(at 205.754732 -353.742752 -90)
		(property "Reference" "U415"
			(at 1.538478 4.90474 0)
			(unlocked yes)
			(layer "F.SilkS")
			(effects
				(font
					(size 0.7874 0.5842)
					(thickness 0.1524)
				)
				(justify left)
			)
		)
		(property "Value" ""
			(at 0 0 270)
			(layer "F.Fab")
			(effects
				(font
					(size 1.27 1.27)
				)
			)
		)
		(duplicate_pad_numbers_are_jumpers no)
		(fp_line
			(start -2.0574 1.651)
			(end -2.0574 -1.651)
			(stroke
				(width 0.1524)
				(type default)
			)
			(layer "F.SilkS")
		)
		(fp_line
			(start 2.0574 1.651)
			(end -2.0574 1.651)
			(stroke
				(width 0.1524)
				(type default)
			)
			(layer "F.SilkS")
		)
		(fp_line
			(start 0 -1.016)
			(end 0.381 -1.651)
			(stroke
				(width 0.1524)
				(type default)
			)
			(layer "F.SilkS")
		)
		(fp_line
			(start -2.0574 -1.651)
			(end -0.381 -1.651)
			(stroke
				(width 0.1524)
				(type default)
			)
			(layer "F.SilkS")
		)
		(fp_line
			(start -0.381 -1.651)
			(end 0 -1.016)
			(stroke
				(width 0.1524)
				(type default)
			)
			(layer "F.SilkS")
		)
		(fp_line
			(start 0.381 -1.651)
			(end 2.0574 -1.651)
			(stroke
				(width 0.1524)
				(type default)
			)
			(layer "F.SilkS")
		)
		(fp_line
			(start 2.0574 -1.651)
			(end 2.0574 1.651)
			(stroke
				(width 0.1524)
				(type default)
			)
			(layer "F.SilkS")
		)
		(fp_poly
			(pts
				(xy -2.71272 -0.719328) (xy -2.71272 -1.344168) (xy -2.159 -1.016)
			)
			(stroke
				(width 0)
				(type default)
			)
			(fill yes)
			(layer "F.SilkS")
		)
		(fp_line
			(start -0.899922 1.549908)
			(end -0.899922 1.199896)
			(stroke
				(width 0.1)
				(type default)
			)
			(layer "F.Fab")
		)
		(fp_line
			(start 0.899922 1.549908)
			(end -0.899922 1.549908)
			(stroke
				(width 0.1)
				(type default)
			)
			(layer "F.Fab")
		)
		(fp_line
			(start -1.599946 1.199896)
			(end -1.599946 -1.199896)
			(stroke
				(width 0.1)
				(type default)
			)
			(layer "F.Fab")
		)
		(fp_line
			(start -0.899922 1.199896)
			(end -1.599946 1.199896)
			(stroke
				(width 0.1)
				(type default)
			)
			(layer "F.Fab")
		)
		(fp_line
			(start 0.899922 1.199896)
			(end 0.899922 1.549908)
			(stroke
				(width 0.1)
				(type default)
			)
			(layer "F.Fab")
		)
		(fp_line
			(start 1.599946 1.199896)
			(end 0.899922 1.199896)
			(stroke
				(width 0.1)
				(type default)
			)
			(layer "F.Fab")
		)
		(fp_line
			(start -1.599946 -1.199896)
			(end -0.899922 -1.199896)
			(stroke
				(width 0.1)
				(type default)
			)
			(layer "F.Fab")
		)
		(fp_line
			(start -0.899922 -1.199896)
			(end -0.899922 -1.549908)
			(stroke
				(width 0.1)
				(type default)
			)
			(layer "F.Fab")
		)
		(fp_line
			(start 0.899922 -1.199896)
			(end 1.599946 -1.199896)
			(stroke
				(width 0.1)
				(type default)
			)
			(layer "F.Fab")
		)
		(fp_line
			(start 1.599946 -1.199896)
			(end 1.599946 1.199896)
			(stroke
				(width 0.1)
				(type default)
			)
			(layer "F.Fab")
		)
		(fp_line
			(start -0.899922 -1.549908)
			(end 0.899922 -1.549908)
			(stroke
				(width 0.1)
				(type default)
			)
			(layer "F.Fab")
		)
		(fp_line
			(start 0.899922 -1.549908)
			(end 0.899922 -1.199896)
			(stroke
				(width 0.1)
				(type default)
			)
			(layer "F.Fab")
		)
		(fp_poly
			(pts
				(xy -2.71272 -0.719328) (xy -2.71272 -1.344168) (xy -2.159 -1.016)
			)
			(stroke
				(width 0)
				(type default)
			)
			(fill yes)
			(layer "F.Fab")
		)
		(pad "1" smd rect
			(at -1.225042 -0.94996 180)
			(size 0.5588 1.3462)
			(layers "F.Cu" "F.Mask" "F.Paste")
			(net "Net_9086")
		)
		(pad "2" smd rect
			(at -1.225042 0 180)
			(size 0.5588 1.3462)
			(layers "F.Cu" "F.Mask" "F.Paste")
			(net "HSC_D_OC_R")
		)
		(pad "3" smd rect
			(at -1.225042 0.94996 180)
			(size 0.5588 1.3462)
			(layers "F.Cu" "F.Mask" "F.Paste")
			(net "GND")
		)
		(pad "4" smd rect
			(at 1.225042 0.94996 180)
			(size 0.5588 1.3462)
			(layers "F.Cu" "F.Mask" "F.Paste")
			(net "HSC_D_OC_BUF_N")
		)
		(pad "5" smd rect
			(at 1.225042 -0.94996 180)
			(size 0.5588 1.3462)
			(layers "F.Cu" "F.Mask" "F.Paste")
			(net "P3V3_AUX")
		)
	)
	(footprint ""
		(layer "F.Cu")
		(at 380.61773 -113.558574 -90)
		(property "Reference" "C4004"
			(at 0 0 270)
			(layer "F.SilkS")
			(hide yes)
			(effects
				(font
					(size 1.27 1.27)
				)
			)
		)
		(property "Value" ""
			(at 0 0 270)
			(layer "F.Fab")
			(effects
				(font
					(size 1.27 1.27)
				)
			)
		)
		(duplicate_pad_numbers_are_jumpers no)
		(fp_line
			(start -0.7874 0.4064)
			(end -0.7874 -0.4064)
			(stroke
				(width 0.1524)
				(type default)
			)
			(layer "F.SilkS")
		)
		(fp_line
			(start 0.7874 0.4064)
			(end -0.7874 0.4064)
			(stroke
				(width 0.1524)
				(type default)
			)
			(layer "F.SilkS")
		)
		(fp_line
			(start -0.7874 -0.4064)
			(end 0.7874 -0.4064)
			(stroke
				(width 0.1524)
				(type default)
			)
			(layer "F.SilkS")
		)
		(fp_line
			(start 0.7874 -0.4064)
			(end 0.7874 0.4064)
			(stroke
				(width 0.1524)
				(type default)
			)
			(layer "F.SilkS")
		)
		(fp_line
			(start -0.67945 0.3048)
			(end -0.67945 -0.305054)
			(stroke
				(width 0.1)
				(type default)
			)
			(layer "F.Fab")
		)
		(fp_line
			(start -0.12065 0.3048)
			(end -0.67945 0.3048)
			(stroke
				(width 0.1)
				(type default)
			)
			(layer "F.Fab")
		)
		(fp_line
			(start 0.120396 0.3048)
			(end 0.120396 0.2794)
			(stroke
				(width 0.1)
				(type default)
			)
			(layer "F.Fab")
		)
		(fp_line
			(start 0.67945 0.3048)
			(end 0.120396 0.3048)
			(stroke
				(width 0.1)
				(type default)
			)
			(layer "F.Fab")
		)
		(fp_line
			(start -0.12065 0.2794)
			(end -0.12065 0.3048)
			(stroke
				(width 0.1)
				(type default)
			)
			(layer "F.Fab")
		)
		(fp_line
			(start 0.120396 0.2794)
			(end -0.12065 0.2794)
			(stroke
				(width 0.1)
				(type default)
			)
			(layer "F.Fab")
		)
		(fp_line
			(start -0.12065 -0.2794)
			(end 0.12065 -0.2794)
			(stroke
				(width 0.1)
				(type default)
			)
			(layer "F.Fab")
		)
		(fp_line
			(start 0.12065 -0.2794)
			(end 0.12065 -0.3048)
			(stroke
				(width 0.1)
				(type default)
			)
			(layer "F.Fab")
		)
		(fp_line
			(start 0.12065 -0.3048)
			(end 0.67945 -0.3048)
			(stroke
				(width 0.1)
				(type default)
			)
			(layer "F.Fab")
		)
		(fp_line
			(start 0.67945 -0.3048)
			(end 0.67945 0.3048)
			(stroke
				(width 0.1)
				(type default)
			)
			(layer "F.Fab")
		)
		(fp_line
			(start -0.67945 -0.305054)
			(end -0.12065 -0.305054)
			(stroke
				(width 0.1)
				(type default)
			)
			(layer "F.Fab")
		)
		(fp_line
			(start -0.12065 -0.305054)
			(end -0.12065 -0.2794)
			(stroke
				(width 0.1)
				(type default)
			)
			(layer "F.Fab")
		)
		(pad "1" smd circle
			(at -0.40005 0 270)
			(size 0 0)
			(layers "F.Cu" "F.Mask" "F.Paste")
			(net "PRSNT_NIC6_R_N")
		)
		(pad "2" smd circle
			(at 0.40005 0 270)
			(size 0 0)
			(layers "F.Cu" "F.Mask" "F.Paste")
			(net "GND")
		)
	)
	(footprint ""
		(layer "F.Cu")
		(at 291.515038 -20.72513)
		(property "Reference" "H113"
			(at 1.748536 -2.613914 0)
			(unlocked yes)
			(layer "B.SilkS")
			(effects
				(font
					(size 0.7874 0.5842)
					(thickness 0.1524)
				)
				(justify left mirror)
			)
		)
		(property "Value" ""
			(at 0 0 0)
			(layer "F.Fab")
			(effects
				(font
					(size 1.27 1.27)
				)
			)
		)
		(duplicate_pad_numbers_are_jumpers no)
		(pad "1" thru_hole rect
			(at 0 0)
			(size 4.2164 5.0038)
			(drill 2.0066
				(offset 0.099822 0)
			)
			(layers "*.Cu" "*.Mask")
			(remove_unused_layers no)
			(net "Net_8550")
			(clearance -0.8509)
			(padstack
				(mode front_inner_back)
				(layer "Inner"
					(shape circle)
					(size 4.0132 4.0132)
					(clearance -0.7493)
				)
				(layer "B.Cu"
					(shape circle)
					(size 4.0132 4.0132)
					(clearance -0.7493)
				)
			)
		)
	)
	(footprint ""
		(layer "F.Cu")
		(at 130.104388 -247.36679)
		(property "Reference" "R6245"
			(at 0 0 0)
			(layer "F.SilkS")
			(hide yes)
			(effects
				(font
					(size 1.27 1.27)
				)
			)
		)
		(property "Value" ""
			(at 0 0 0)
			(layer "F.Fab")
			(effects
				(font
					(size 1.27 1.27)
				)
			)
		)
		(duplicate_pad_numbers_are_jumpers no)
		(fp_line
			(start -0.7874 -0.4064)
			(end 0.7874 -0.4064)
			(stroke
				(width 0.1524)
				(type default)
			)
			(layer "F.SilkS")
		)
		(fp_line
			(start -0.7874 0.4064)
			(end -0.7874 -0.4064)
			(stroke
				(width 0.1524)
				(type default)
			)
			(layer "F.SilkS")
		)
		(fp_line
			(start 0.7874 -0.4064)
			(end 0.7874 0.4064)
			(stroke
				(width 0.1524)
				(type default)
			)
			(layer "F.SilkS")
		)
		(fp_line
			(start 0.7874 0.4064)
			(end -0.7874 0.4064)
			(stroke
				(width 0.1524)
				(type default)
			)
			(layer "F.SilkS")
		)
		(fp_line
			(start -0.67945 -0.305054)
			(end -0.12065 -0.305054)
			(stroke
				(width 0.1)
				(type default)
			)
			(layer "F.Fab")
		)
		(fp_line
			(start -0.67945 0.3048)
			(end -0.67945 -0.305054)
			(stroke
				(width 0.1)
				(type default)
			)
			(layer "F.Fab")
		)
		(fp_line
			(start -0.12065 -0.305054)
			(end -0.12065 -0.2794)
			(stroke
				(width 0.1)
				(type default)
			)
			(layer "F.Fab")
		)
		(fp_line
			(start -0.12065 -0.2794)
			(end 0.12065 -0.2794)
			(stroke
				(width 0.1)
				(type default)
			)
			(layer "F.Fab")
		)
		(fp_line
			(start -0.12065 0.2794)
			(end -0.12065 0.3048)
			(stroke
				(width 0.1)
				(type default)
			)
			(layer "F.Fab")
		)
		(fp_line
			(start -0.12065 0.3048)
			(end -0.67945 0.3048)
			(stroke
				(width 0.1)
				(type default)
			)
			(layer "F.Fab")
		)
		(fp_line
			(start 0.120396 0.2794)
			(end -0.12065 0.2794)
			(stroke
				(width 0.1)
				(type default)
			)
			(layer "F.Fab")
		)
		(fp_line
			(start 0.120396 0.3048)
			(end 0.120396 0.2794)
			(stroke
				(width 0.1)
				(type default)
			)
			(layer "F.Fab")
		)
		(fp_line
			(start 0.12065 -0.3048)
			(end 0.67945 -0.3048)
			(stroke
				(width 0.1)
				(type default)
			)
			(layer "F.Fab")
		)
		(fp_line
			(start 0.12065 -0.2794)
			(end 0.12065 -0.3048)
			(stroke
				(width 0.1)
				(type default)
			)
			(layer "F.Fab")
		)
		(fp_line
			(start 0.67945 -0.3048)
			(end 0.67945 0.3048)
			(stroke
				(width 0.1)
				(type default)
			)
			(layer "F.Fab")
		)
		(fp_line
			(start 0.67945 0.3048)
			(end 0.120396 0.3048)
			(stroke
				(width 0.1)
				(type default)
			)
			(layer "F.Fab")
		)
		(pad "1" smd circle
			(at -0.40005 0)
			(size 0 0)
			(layers "F.Cu" "F.Mask" "F.Paste")
			(net "SMB_BIC_I2C6_MUX_VR_R_SCL")
		)
		(pad "2" smd circle
			(at 0.40005 0)
			(size 0 0)
			(layers "F.Cu" "F.Mask" "F.Paste")
			(net "SMB_HOTSWAP_SCL_R")
		)
	)
	(footprint ""
		(layer "F.Cu")
		(at 404.183596 -61.487812 180)
		(property "Reference" "R6024"
			(at 0 0 180)
			(layer "F.SilkS")
			(hide yes)
			(effects
				(font
					(size 1.27 1.27)
				)
			)
		)
		(property "Value" ""
			(at 0 0 180)
			(layer "F.Fab")
			(effects
				(font
					(size 1.27 1.27)
				)
			)
		)
		(duplicate_pad_numbers_are_jumpers no)
		(fp_line
			(start 0.7874 0.4064)
			(end -0.7874 0.4064)
			(stroke
				(width 0.1524)
				(type default)
			)
			(layer "F.SilkS")
		)
		(fp_line
			(start 0.7874 -0.4064)
			(end 0.7874 0.4064)
			(stroke
				(width 0.1524)
				(type default)
			)
			(layer "F.SilkS")
		)
		(fp_line
			(start -0.7874 0.4064)
			(end -0.7874 -0.4064)
			(stroke
				(width 0.1524)
				(type default)
			)
			(layer "F.SilkS")
		)
		(fp_line
			(start -0.7874 -0.4064)
			(end 0.7874 -0.4064)
			(stroke
				(width 0.1524)
				(type default)
			)
			(layer "F.SilkS")
		)
		(fp_line
			(start 0.67945 0.3048)
			(end 0.120396 0.3048)
			(stroke
				(width 0.1)
				(type default)
			)
			(layer "F.Fab")
		)
		(fp_line
			(start 0.67945 -0.3048)
			(end 0.67945 0.3048)
			(stroke
				(width 0.1)
				(type default)
			)
			(layer "F.Fab")
		)
		(fp_line
			(start 0.12065 -0.2794)
			(end 0.12065 -0.3048)
			(stroke
				(width 0.1)
				(type default)
			)
			(layer "F.Fab")
		)
		(fp_line
			(start 0.12065 -0.3048)
			(end 0.67945 -0.3048)
			(stroke
				(width 0.1)
				(type default)
			)
			(layer "F.Fab")
		)
		(fp_line
			(start 0.120396 0.3048)
			(end 0.120396 0.2794)
			(stroke
				(width 0.1)
				(type default)
			)
			(layer "F.Fab")
		)
		(fp_line
			(start 0.120396 0.2794)
			(end -0.12065 0.2794)
			(stroke
				(width 0.1)
				(type default)
			)
			(layer "F.Fab")
		)
		(fp_line
			(start -0.12065 0.3048)
			(end -0.67945 0.3048)
			(stroke
				(width 0.1)
				(type default)
			)
			(layer "F.Fab")
		)
		(fp_line
			(start -0.12065 0.2794)
			(end -0.12065 0.3048)
			(stroke
				(width 0.1)
				(type default)
			)
			(layer "F.Fab")
		)
		(fp_line
			(start -0.12065 -0.2794)
			(end 0.12065 -0.2794)
			(stroke
				(width 0.1)
				(type default)
			)
			(layer "F.Fab")
		)
		(fp_line
			(start -0.12065 -0.305054)
			(end -0.12065 -0.2794)
			(stroke
				(width 0.1)
				(type default)
			)
			(layer "F.Fab")
		)
		(fp_line
			(start -0.67945 0.3048)
			(end -0.67945 -0.305054)
			(stroke
				(width 0.1)
				(type default)
			)
			(layer "F.Fab")
		)
		(fp_line
			(start -0.67945 -0.305054)
			(end -0.12065 -0.305054)
			(stroke
				(width 0.1)
				(type default)
			)
			(layer "F.Fab")
		)
		(pad "1" smd circle
			(at -0.40005 0 180)
			(size 0 0)
			(layers "F.Cu" "F.Mask" "F.Paste")
			(net "PWRGD_P12V_SSD14_D")
		)
		(pad "2" smd circle
			(at 0.40005 0 180)
			(size 0 0)
			(layers "F.Cu" "F.Mask" "F.Paste")
			(net "PWRGD_P12V_SSD14_R")
		)
	)
	(footprint ""
		(layer "F.Cu")
		(at 375.500392 -256.478786)
		(property "Reference" "C3588"
			(at 0 0 0)
			(layer "F.SilkS")
			(hide yes)
			(effects
				(font
					(size 1.27 1.27)
				)
			)
		)
		(property "Value" ""
			(at 0 0 0)
			(layer "F.Fab")
			(effects
				(font
					(size 1.27 1.27)
				)
			)
		)
		(duplicate_pad_numbers_are_jumpers no)
		(fp_line
			(start -0.299974 -0.150114)
			(end 0.299974 -0.150114)
			(stroke
				(width 0.1)
				(type default)
			)
			(layer "F.Fab")
		)
		(fp_line
			(start -0.299974 0.150114)
			(end -0.299974 -0.150114)
			(stroke
				(width 0.1)
				(type default)
			)
			(layer "F.Fab")
		)
		(fp_line
			(start 0.299974 -0.150114)
			(end 0.299974 0.150114)
			(stroke
				(width 0.1)
				(type default)
			)
			(layer "F.Fab")
		)
		(fp_line
			(start 0.299974 0.150114)
			(end -0.299974 0.150114)
			(stroke
				(width 0.1)
				(type default)
			)
			(layer "F.Fab")
		)
		(pad "1" smd rect
			(at -0.2667 0)
			(size 0.3048 0.381)
			(layers "F.Cu" "F.Mask" "F.Paste")
			(net "P1V8_PLL0_PEX3")
		)
		(pad "2" smd rect
			(at 0.2667 0)
			(size 0.3048 0.381)
			(layers "F.Cu" "F.Mask" "F.Paste")
			(net "GND")
		)
	)
	(footprint ""
		(layer "F.Cu")
		(at 235.623608 -150.959566 180)
		(property "Reference" "R1210"
			(at 0 0 180)
			(layer "F.SilkS")
			(hide yes)
			(effects
				(font
					(size 1.27 1.27)
				)
			)
		)
		(property "Value" ""
			(at 0 0 180)
			(layer "F.Fab")
			(effects
				(font
					(size 1.27 1.27)
				)
			)
		)
		(duplicate_pad_numbers_are_jumpers no)
		(fp_line
			(start -0.7874 -0.4064)
			(end 0.7874 -0.4064)
			(stroke
				(width 0.1524)
				(type default)
			)
			(layer "F.SilkS")
		)
		(fp_line
			(start 0.67945 0.3048)
			(end 0.120396 0.3048)
			(stroke
				(width 0.1)
				(type default)
			)
			(layer "F.Fab")
		)
		(fp_line
			(start 0.67945 -0.3048)
			(end 0.67945 0.3048)
			(stroke
				(width 0.1)
				(type default)
			)
			(layer "F.Fab")
		)
		(fp_line
			(start 0.12065 -0.2794)
			(end 0.12065 -0.3048)
			(stroke
				(width 0.1)
				(type default)
			)
			(layer "F.Fab")
		)
		(fp_line
			(start 0.12065 -0.3048)
			(end 0.67945 -0.3048)
			(stroke
				(width 0.1)
				(type default)
			)
			(layer "F.Fab")
		)
		(fp_line
			(start 0.120396 0.3048)
			(end 0.120396 0.2794)
			(stroke
				(width 0.1)
				(type default)
			)
			(layer "F.Fab")
		)
		(fp_line
			(start 0.120396 0.2794)
			(end -0.12065 0.2794)
			(stroke
				(width 0.1)
				(type default)
			)
			(layer "F.Fab")
		)
		(fp_line
			(start -0.12065 0.3048)
			(end -0.67945 0.3048)
			(stroke
				(width 0.1)
				(type default)
			)
			(layer "F.Fab")
		)
		(fp_line
			(start -0.12065 0.2794)
			(end -0.12065 0.3048)
			(stroke
				(width 0.1)
				(type default)
			)
			(layer "F.Fab")
		)
		(fp_line
			(start -0.12065 -0.2794)
			(end 0.12065 -0.2794)
			(stroke
				(width 0.1)
				(type default)
			)
			(layer "F.Fab")
		)
		(fp_line
			(start -0.12065 -0.305054)
			(end -0.12065 -0.2794)
			(stroke
				(width 0.1)
				(type default)
			)
			(layer "F.Fab")
		)
		(fp_line
			(start -0.67945 0.3048)
			(end -0.67945 -0.305054)
			(stroke
				(width 0.1)
				(type default)
			)
			(layer "F.Fab")
		)
		(fp_line
			(start -0.67945 -0.305054)
			(end -0.12065 -0.305054)
			(stroke
				(width 0.1)
				(type default)
			)
			(layer "F.Fab")
		)
		(pad "1" smd circle
			(at -0.40005 0 180)
			(size 0 0)
			(layers "F.Cu" "F.Mask" "F.Paste")
			(net "CLK_100M_PEX2_REF_R_DN")
		)
		(pad "2" smd circle
			(at 0.40005 0 180)
			(size 0 0)
			(layers "F.Cu" "F.Mask" "F.Paste")
			(net "CLK_100M_PEX2_REF_DN")
		)
	)
	(footprint ""
		(layer "F.Cu")
		(at 394.389356 -242.9764)
		(property "Reference" "R6613"
			(at 0 0 0)
			(layer "F.SilkS")
			(hide yes)
			(effects
				(font
					(size 1.27 1.27)
				)
			)
		)
		(property "Value" ""
			(at 0 0 0)
			(layer "F.Fab")
			(effects
				(font
					(size 1.27 1.27)
				)
			)
		)
		(duplicate_pad_numbers_are_jumpers no)
		(fp_line
			(start -0.7874 -0.4064)
			(end 0.7874 -0.4064)
			(stroke
				(width 0.1524)
				(type default)
			)
			(layer "F.SilkS")
		)
		(fp_line
			(start -0.7874 0.4064)
			(end -0.7874 -0.4064)
			(stroke
				(width 0.1524)
				(type default)
			)
			(layer "F.SilkS")
		)
		(fp_line
			(start 0.7874 -0.4064)
			(end 0.7874 0.4064)
			(stroke
				(width 0.1524)
				(type default)
			)
			(layer "F.SilkS")
		)
		(fp_line
			(start 0.7874 0.4064)
			(end -0.7874 0.4064)
			(stroke
				(width 0.1524)
				(type default)
			)
			(layer "F.SilkS")
		)
		(fp_line
			(start -0.67945 -0.305054)
			(end -0.12065 -0.305054)
			(stroke
				(width 0.1)
				(type default)
			)
			(layer "F.Fab")
		)
		(fp_line
			(start -0.67945 0.3048)
			(end -0.67945 -0.305054)
			(stroke
				(width 0.1)
				(type default)
			)
			(layer "F.Fab")
		)
		(fp_line
			(start -0.12065 -0.305054)
			(end -0.12065 -0.2794)
			(stroke
				(width 0.1)
				(type default)
			)
			(layer "F.Fab")
		)
		(fp_line
			(start -0.12065 -0.2794)
			(end 0.12065 -0.2794)
			(stroke
				(width 0.1)
				(type default)
			)
			(layer "F.Fab")
		)
		(fp_line
			(start -0.12065 0.2794)
			(end -0.12065 0.3048)
			(stroke
				(width 0.1)
				(type default)
			)
			(layer "F.Fab")
		)
		(fp_line
			(start -0.12065 0.3048)
			(end -0.67945 0.3048)
			(stroke
				(width 0.1)
				(type default)
			)
			(layer "F.Fab")
		)
		(fp_line
			(start 0.120396 0.2794)
			(end -0.12065 0.2794)
			(stroke
				(width 0.1)
				(type default)
			)
			(layer "F.Fab")
		)
		(fp_line
			(start 0.120396 0.3048)
			(end 0.120396 0.2794)
			(stroke
				(width 0.1)
				(type default)
			)
			(layer "F.Fab")
		)
		(fp_line
			(start 0.12065 -0.3048)
			(end 0.67945 -0.3048)
			(stroke
				(width 0.1)
				(type default)
			)
			(layer "F.Fab")
		)
		(fp_line
			(start 0.12065 -0.2794)
			(end 0.12065 -0.3048)
			(stroke
				(width 0.1)
				(type default)
			)
			(layer "F.Fab")
		)
		(fp_line
			(start 0.67945 -0.3048)
			(end 0.67945 0.3048)
			(stroke
				(width 0.1)
				(type default)
			)
			(layer "F.Fab")
		)
		(fp_line
			(start 0.67945 0.3048)
			(end 0.120396 0.3048)
			(stroke
				(width 0.1)
				(type default)
			)
			(layer "F.Fab")
		)
		(pad "1" smd circle
			(at -0.40005 0)
			(size 0 0)
			(layers "F.Cu" "F.Mask" "F.Paste")
			(net "UART_PEX1_SDB_R_RX")
		)
		(pad "2" smd circle
			(at 0.40005 0)
			(size 0 0)
			(layers "F.Cu" "F.Mask" "F.Paste")
			(net "UART_PEX1_SDB_R1_RX")
		)
	)
	(footprint ""
		(layer "F.Cu")
		(at 458.394562 -309.334662 90)
		(property "Reference" "PR183"
			(at 0 0 90)
			(layer "F.SilkS")
			(hide yes)
			(effects
				(font
					(size 1.27 1.27)
				)
			)
		)
		(property "Value" ""
			(at 0 0 90)
			(layer "F.Fab")
			(effects
				(font
					(size 1.27 1.27)
				)
			)
		)
		(duplicate_pad_numbers_are_jumpers no)
		(fp_line
			(start 0.7874 -0.4064)
			(end 0.7874 0.4064)
			(stroke
				(width 0.1524)
				(type default)
			)
			(layer "F.SilkS")
		)
		(fp_line
			(start -0.7874 -0.4064)
			(end 0.7874 -0.4064)
			(stroke
				(width 0.1524)
				(type default)
			)
			(layer "F.SilkS")
		)
		(fp_line
			(start 0.7874 0.4064)
			(end -0.7874 0.4064)
			(stroke
				(width 0.1524)
				(type default)
			)
			(layer "F.SilkS")
		)
		(fp_line
			(start -0.7874 0.4064)
			(end -0.7874 -0.4064)
			(stroke
				(width 0.1524)
				(type default)
			)
			(layer "F.SilkS")
		)
		(fp_line
			(start -0.12065 -0.305054)
			(end -0.12065 -0.2794)
			(stroke
				(width 0.1)
				(type default)
			)
			(layer "F.Fab")
		)
		(fp_line
			(start -0.67945 -0.305054)
			(end -0.12065 -0.305054)
			(stroke
				(width 0.1)
				(type default)
			)
			(layer "F.Fab")
		)
		(fp_line
			(start 0.67945 -0.3048)
			(end 0.67945 0.3048)
			(stroke
				(width 0.1)
				(type default)
			)
			(layer "F.Fab")
		)
		(fp_line
			(start 0.12065 -0.3048)
			(end 0.67945 -0.3048)
			(stroke
				(width 0.1)
				(type default)
			)
			(layer "F.Fab")
		)
		(fp_line
			(start 0.12065 -0.2794)
			(end 0.12065 -0.3048)
			(stroke
				(width 0.1)
				(type default)
			)
			(layer "F.Fab")
		)
		(fp_line
			(start -0.12065 -0.2794)
			(end 0.12065 -0.2794)
			(stroke
				(width 0.1)
				(type default)
			)
			(layer "F.Fab")
		)
		(fp_line
			(start 0.120396 0.2794)
			(end -0.12065 0.2794)
			(stroke
				(width 0.1)
				(type default)
			)
			(layer "F.Fab")
		)
		(fp_line
			(start -0.12065 0.2794)
			(end -0.12065 0.3048)
			(stroke
				(width 0.1)
				(type default)
			)
			(layer "F.Fab")
		)
		(fp_line
			(start 0.67945 0.3048)
			(end 0.120396 0.3048)
			(stroke
				(width 0.1)
				(type default)
			)
			(layer "F.Fab")
		)
		(fp_line
			(start 0.120396 0.3048)
			(end 0.120396 0.2794)
			(stroke
				(width 0.1)
				(type default)
			)
			(layer "F.Fab")
		)
		(fp_line
			(start -0.12065 0.3048)
			(end -0.67945 0.3048)
			(stroke
				(width 0.1)
				(type default)
			)
			(layer "F.Fab")
		)
		(fp_line
			(start -0.67945 0.3048)
			(end -0.67945 -0.305054)
			(stroke
				(width 0.1)
				(type default)
			)
			(layer "F.Fab")
		)
		(pad "1" smd circle
			(at -0.40005 0 90)
			(size 0 0)
			(layers "F.Cu" "F.Mask" "F.Paste")
			(net "SH_P1V25_PEX3_FB_N")
		)
		(pad "2" smd circle
			(at 0.40005 0 90)
			(size 0 0)
			(layers "F.Cu" "F.Mask" "F.Paste")
			(net "P1V25_PEX3_FB")
		)
	)
	(footprint ""
		(layer "F.Cu")
		(at 4.140454 -369.232688 90)
		(property "Reference" "Q251"
			(at -1.7018 -2.250948 90)
			(unlocked yes)
			(layer "F.SilkS")
			(effects
				(font
					(size 0.7874 0.5842)
					(thickness 0.1524)
				)
				(justify left)
			)
		)
		(property "Value" ""
			(at 0 0 90)
			(layer "F.Fab")
			(effects
				(font
					(size 1.27 1.27)
				)
			)
		)
		(duplicate_pad_numbers_are_jumpers no)
		(fp_line
			(start 1.584198 -1.519936)
			(end 1.584198 1.519936)
			(stroke
				(width 0.1524)
				(type default)
			)
			(layer "F.SilkS")
		)
		(fp_line
			(start -1.584198 -1.519936)
			(end 1.584198 -1.519936)
			(stroke
				(width 0.1524)
				(type default)
			)
			(layer "F.SilkS")
		)
		(fp_line
			(start 1.584198 1.519936)
			(end -1.584198 1.519936)
			(stroke
				(width 0.1524)
				(type default)
			)
			(layer "F.SilkS")
		)
		(fp_line
			(start -1.584198 1.519936)
			(end -1.584198 -1.519936)
			(stroke
				(width 0.1524)
				(type default)
			)
			(layer "F.SilkS")
		)
		(fp_line
			(start 0.700024 -1.519936)
			(end 0.700024 1.519936)
			(stroke
				(width 0.1)
				(type default)
			)
			(layer "F.Fab")
		)
		(fp_line
			(start -0.700024 -1.519936)
			(end 0.700024 -1.519936)
			(stroke
				(width 0.1)
				(type default)
			)
			(layer "F.Fab")
		)
		(fp_line
			(start 0.700024 1.519936)
			(end -0.700024 1.519936)
			(stroke
				(width 0.1)
				(type default)
			)
			(layer "F.Fab")
		)
		(fp_line
			(start -0.700024 1.519936)
			(end -0.700024 -1.519936)
			(stroke
				(width 0.1)
				(type default)
			)
			(layer "F.Fab")
		)
		(pad "D" smd rect
			(at 0.999998 0)
			(size 0.8128 0.9144)
			(layers "F.Cu" "F.Mask" "F.Paste")
			(net "P3V3_USB_HUB")
		)
		(pad "G" smd rect
			(at -0.999998 -0.94996)
			(size 0.8128 0.9144)
			(layers "F.Cu" "F.Mask" "F.Paste")
			(net "PG12_USB_HUB_N")
		)
		(pad "S" smd rect
			(at -0.999998 0.94996)
			(size 0.8128 0.9144)
			(layers "F.Cu" "F.Mask" "F.Paste")
			(net "P3V3_AUX")
		)
	)
	(footprint ""
		(layer "F.Cu")
		(at 154.860244 -97.1804 180)
		(property "Reference" "R110"
			(at 0 0 180)
			(layer "F.SilkS")
			(hide yes)
			(effects
				(font
					(size 1.27 1.27)
				)
			)
		)
		(property "Value" ""
			(at 0 0 180)
			(layer "F.Fab")
			(effects
				(font
					(size 1.27 1.27)
				)
			)
		)
		(duplicate_pad_numbers_are_jumpers no)
		(fp_line
			(start 0.7874 0.4064)
			(end -0.7874 0.4064)
			(stroke
				(width 0.1524)
				(type default)
			)
			(layer "F.SilkS")
		)
		(fp_line
			(start 0.7874 -0.4064)
			(end 0.7874 0.4064)
			(stroke
				(width 0.1524)
				(type default)
			)
			(layer "F.SilkS")
		)
		(fp_line
			(start -0.7874 0.4064)
			(end -0.7874 -0.4064)
			(stroke
				(width 0.1524)
				(type default)
			)
			(layer "F.SilkS")
		)
		(fp_line
			(start -0.7874 -0.4064)
			(end 0.7874 -0.4064)
			(stroke
				(width 0.1524)
				(type default)
			)
			(layer "F.SilkS")
		)
		(fp_line
			(start 0.67945 0.3048)
			(end 0.120396 0.3048)
			(stroke
				(width 0.1)
				(type default)
			)
			(layer "F.Fab")
		)
		(fp_line
			(start 0.67945 -0.3048)
			(end 0.67945 0.3048)
			(stroke
				(width 0.1)
				(type default)
			)
			(layer "F.Fab")
		)
		(fp_line
			(start 0.12065 -0.2794)
			(end 0.12065 -0.3048)
			(stroke
				(width 0.1)
				(type default)
			)
			(layer "F.Fab")
		)
		(fp_line
			(start 0.12065 -0.3048)
			(end 0.67945 -0.3048)
			(stroke
				(width 0.1)
				(type default)
			)
			(layer "F.Fab")
		)
		(fp_line
			(start 0.120396 0.3048)
			(end 0.120396 0.2794)
			(stroke
				(width 0.1)
				(type default)
			)
			(layer "F.Fab")
		)
		(fp_line
			(start 0.120396 0.2794)
			(end -0.12065 0.2794)
			(stroke
				(width 0.1)
				(type default)
			)
			(layer "F.Fab")
		)
		(fp_line
			(start -0.12065 0.3048)
			(end -0.67945 0.3048)
			(stroke
				(width 0.1)
				(type default)
			)
			(layer "F.Fab")
		)
		(fp_line
			(start -0.12065 0.2794)
			(end -0.12065 0.3048)
			(stroke
				(width 0.1)
				(type default)
			)
			(layer "F.Fab")
		)
		(fp_line
			(start -0.12065 -0.2794)
			(end 0.12065 -0.2794)
			(stroke
				(width 0.1)
				(type default)
			)
			(layer "F.Fab")
		)
		(fp_line
			(start -0.12065 -0.305054)
			(end -0.12065 -0.2794)
			(stroke
				(width 0.1)
				(type default)
			)
			(layer "F.Fab")
		)
		(fp_line
			(start -0.67945 0.3048)
			(end -0.67945 -0.305054)
			(stroke
				(width 0.1)
				(type default)
			)
			(layer "F.Fab")
		)
		(fp_line
			(start -0.67945 -0.305054)
			(end -0.12065 -0.305054)
			(stroke
				(width 0.1)
				(type default)
			)
			(layer "F.Fab")
		)
		(pad "1" smd circle
			(at -0.40005 0 180)
			(size 0 0)
			(layers "F.Cu" "F.Mask" "F.Paste")
			(net "PRSNTB3_NIC2_N")
		)
		(pad "2" smd circle
			(at 0.40005 0 180)
			(size 0 0)
			(layers "F.Cu" "F.Mask" "F.Paste")
			(net "P3V3_AUX")
		)
	)
	(footprint ""
		(layer "F.Cu")
		(at 365.506 -201.803 180)
		(property "Reference" "R4698"
			(at 0 0 180)
			(layer "F.SilkS")
			(hide yes)
			(effects
				(font
					(size 1.27 1.27)
				)
			)
		)
		(property "Value" ""
			(at 0 0 180)
			(layer "F.Fab")
			(effects
				(font
					(size 1.27 1.27)
				)
			)
		)
		(duplicate_pad_numbers_are_jumpers no)
		(fp_line
			(start 0.7874 0.4064)
			(end -0.7874 0.4064)
			(stroke
				(width 0.1524)
				(type default)
			)
			(layer "F.SilkS")
		)
		(fp_line
			(start 0.7874 -0.4064)
			(end 0.7874 0.4064)
			(stroke
				(width 0.1524)
				(type default)
			)
			(layer "F.SilkS")
		)
		(fp_line
			(start -0.7874 0.4064)
			(end -0.7874 -0.4064)
			(stroke
				(width 0.1524)
				(type default)
			)
			(layer "F.SilkS")
		)
		(fp_line
			(start -0.7874 -0.4064)
			(end 0.7874 -0.4064)
			(stroke
				(width 0.1524)
				(type default)
			)
			(layer "F.SilkS")
		)
		(fp_line
			(start 0.67945 0.3048)
			(end 0.120396 0.3048)
			(stroke
				(width 0.1)
				(type default)
			)
			(layer "F.Fab")
		)
		(fp_line
			(start 0.67945 -0.3048)
			(end 0.67945 0.3048)
			(stroke
				(width 0.1)
				(type default)
			)
			(layer "F.Fab")
		)
		(fp_line
			(start 0.12065 -0.2794)
			(end 0.12065 -0.3048)
			(stroke
				(width 0.1)
				(type default)
			)
			(layer "F.Fab")
		)
		(fp_line
			(start 0.12065 -0.3048)
			(end 0.67945 -0.3048)
			(stroke
				(width 0.1)
				(type default)
			)
			(layer "F.Fab")
		)
		(fp_line
			(start 0.120396 0.3048)
			(end 0.120396 0.2794)
			(stroke
				(width 0.1)
				(type default)
			)
			(layer "F.Fab")
		)
		(fp_line
			(start 0.120396 0.2794)
			(end -0.12065 0.2794)
			(stroke
				(width 0.1)
				(type default)
			)
			(layer "F.Fab")
		)
		(fp_line
			(start -0.12065 0.3048)
			(end -0.67945 0.3048)
			(stroke
				(width 0.1)
				(type default)
			)
			(layer "F.Fab")
		)
		(fp_line
			(start -0.12065 0.2794)
			(end -0.12065 0.3048)
			(stroke
				(width 0.1)
				(type default)
			)
			(layer "F.Fab")
		)
		(fp_line
			(start -0.12065 -0.2794)
			(end 0.12065 -0.2794)
			(stroke
				(width 0.1)
				(type default)
			)
			(layer "F.Fab")
		)
		(fp_line
			(start -0.12065 -0.305054)
			(end -0.12065 -0.2794)
			(stroke
				(width 0.1)
				(type default)
			)
			(layer "F.Fab")
		)
		(fp_line
			(start -0.67945 0.3048)
			(end -0.67945 -0.305054)
			(stroke
				(width 0.1)
				(type default)
			)
			(layer "F.Fab")
		)
		(fp_line
			(start -0.67945 -0.305054)
			(end -0.12065 -0.305054)
			(stroke
				(width 0.1)
				(type default)
			)
			(layer "F.Fab")
		)
		(pad "1" smd circle
			(at -0.40005 0 180)
			(size 0 0)
			(layers "F.Cu" "F.Mask" "F.Paste")
			(net "GND")
		)
		(pad "2" smd circle
			(at 0.40005 0 180)
			(size 0 0)
			(layers "F.Cu" "F.Mask" "F.Paste")
			(net "PCA9555_0_PEX1_A2")
		)
	)
	(footprint ""
		(layer "F.Cu")
		(at 361.329478 -280.44902 -90)
		(property "Reference" "PC195"
			(at 0 0 270)
			(layer "F.SilkS")
			(hide yes)
			(effects
				(font
					(size 1.27 1.27)
				)
			)
		)
		(property "Value" ""
			(at 0 0 270)
			(layer "F.Fab")
			(effects
				(font
					(size 1.27 1.27)
				)
			)
		)
		(duplicate_pad_numbers_are_jumpers no)
		(fp_line
			(start -0.7874 0.4064)
			(end -0.7874 -0.4064)
			(stroke
				(width 0.1524)
				(type default)
			)
			(layer "F.SilkS")
		)
		(fp_line
			(start 0.7874 0.4064)
			(end -0.7874 0.4064)
			(stroke
				(width 0.1524)
				(type default)
			)
			(layer "F.SilkS")
		)
		(fp_line
			(start -0.7874 -0.4064)
			(end 0.7874 -0.4064)
			(stroke
				(width 0.1524)
				(type default)
			)
			(layer "F.SilkS")
		)
		(fp_line
			(start 0.7874 -0.4064)
			(end 0.7874 0.4064)
			(stroke
				(width 0.1524)
				(type default)
			)
			(layer "F.SilkS")
		)
		(fp_line
			(start -0.67945 0.3048)
			(end -0.67945 -0.305054)
			(stroke
				(width 0.1)
				(type default)
			)
			(layer "F.Fab")
		)
		(fp_line
			(start -0.12065 0.3048)
			(end -0.67945 0.3048)
			(stroke
				(width 0.1)
				(type default)
			)
			(layer "F.Fab")
		)
		(fp_line
			(start 0.120396 0.3048)
			(end 0.120396 0.2794)
			(stroke
				(width 0.1)
				(type default)
			)
			(layer "F.Fab")
		)
		(fp_line
			(start 0.67945 0.3048)
			(end 0.120396 0.3048)
			(stroke
				(width 0.1)
				(type default)
			)
			(layer "F.Fab")
		)
		(fp_line
			(start -0.12065 0.2794)
			(end -0.12065 0.3048)
			(stroke
				(width 0.1)
				(type default)
			)
			(layer "F.Fab")
		)
		(fp_line
			(start 0.120396 0.2794)
			(end -0.12065 0.2794)
			(stroke
				(width 0.1)
				(type default)
			)
			(layer "F.Fab")
		)
		(fp_line
			(start -0.12065 -0.2794)
			(end 0.12065 -0.2794)
			(stroke
				(width 0.1)
				(type default)
			)
			(layer "F.Fab")
		)
		(fp_line
			(start 0.12065 -0.2794)
			(end 0.12065 -0.3048)
			(stroke
				(width 0.1)
				(type default)
			)
			(layer "F.Fab")
		)
		(fp_line
			(start 0.12065 -0.3048)
			(end 0.67945 -0.3048)
			(stroke
				(width 0.1)
				(type default)
			)
			(layer "F.Fab")
		)
		(fp_line
			(start 0.67945 -0.3048)
			(end 0.67945 0.3048)
			(stroke
				(width 0.1)
				(type default)
			)
			(layer "F.Fab")
		)
		(fp_line
			(start -0.67945 -0.305054)
			(end -0.12065 -0.305054)
			(stroke
				(width 0.1)
				(type default)
			)
			(layer "F.Fab")
		)
		(fp_line
			(start -0.12065 -0.305054)
			(end -0.12065 -0.2794)
			(stroke
				(width 0.1)
				(type default)
			)
			(layer "F.Fab")
		)
		(pad "1" smd circle
			(at -0.40005 0 270)
			(size 0 0)
			(layers "F.Cu" "F.Mask" "F.Paste")
			(net "SW_P0V8_PEX3_PHASE2")
		)
		(pad "2" smd circle
			(at 0.40005 0 270)
			(size 0 0)
			(layers "F.Cu" "F.Mask" "F.Paste")
			(net "SW_P0V8_PEX3_BOOT2_R")
		)
	)
	(footprint ""
		(layer "F.Cu")
		(at 295.881044 -202.518772 -90)
		(property "Reference" "U63"
			(at 1.045972 -3.433826 90)
			(unlocked yes)
			(layer "F.SilkS")
			(effects
				(font
					(size 0.7874 0.5842)
					(thickness 0.1524)
				)
				(justify left)
			)
		)
		(property "Value" ""
			(at 0 0 270)
			(layer "F.Fab")
			(effects
				(font
					(size 1.27 1.27)
				)
			)
		)
		(duplicate_pad_numbers_are_jumpers no)
		(fp_line
			(start -1.868932 2.549906)
			(end 1.868932 2.549906)
			(stroke
				(width 0.1524)
				(type default)
			)
			(layer "F.SilkS")
		)
		(fp_line
			(start 1.868932 2.549906)
			(end 1.868932 -2.549906)
			(stroke
				(width 0.1524)
				(type default)
			)
			(layer "F.SilkS")
		)
		(fp_line
			(start 0 -1.524)
			(end -1.025906 -2.549906)
			(stroke
				(width 0.1524)
				(type default)
			)
			(layer "F.SilkS")
		)
		(fp_line
			(start -1.868932 -2.549906)
			(end -1.868932 2.549906)
			(stroke
				(width 0.1524)
				(type default)
			)
			(layer "F.SilkS")
		)
		(fp_line
			(start -1.025906 -2.549906)
			(end -1.868932 -2.549906)
			(stroke
				(width 0.1524)
				(type default)
			)
			(layer "F.SilkS")
		)
		(fp_line
			(start 1.025906 -2.549906)
			(end 0 -1.524)
			(stroke
				(width 0.1524)
				(type default)
			)
			(layer "F.SilkS")
		)
		(fp_line
			(start 1.868932 -2.549906)
			(end 1.025906 -2.549906)
			(stroke
				(width 0.1524)
				(type default)
			)
			(layer "F.SilkS")
		)
		(fp_poly
			(pts
				(xy -4.7752 -1.787398) (xy -4.7752 -2.803398) (xy -3.7592 -2.295398)
			)
			(stroke
				(width 0)
				(type default)
			)
			(fill yes)
			(layer "F.SilkS")
		)
		(fp_line
			(start -2.249932 2.549906)
			(end 2.249932 2.549906)
			(stroke
				(width 0.1)
				(type default)
			)
			(layer "F.Fab")
		)
		(fp_line
			(start 2.249932 2.549906)
			(end 2.249932 -2.549906)
			(stroke
				(width 0.1)
				(type default)
			)
			(layer "F.Fab")
		)
		(fp_line
			(start -2.249932 -2.549906)
			(end -2.249932 2.549906)
			(stroke
				(width 0.1)
				(type default)
			)
			(layer "F.Fab")
		)
		(fp_line
			(start 2.249932 -2.549906)
			(end -2.249932 -2.549906)
			(stroke
				(width 0.1)
				(type default)
			)
			(layer "F.Fab")
		)
		(fp_poly
			(pts
				(xy -4.7752 -1.787398) (xy -4.7752 -2.803398) (xy -3.7592 -2.295398)
			)
			(stroke
				(width 0)
				(type default)
			)
			(fill yes)
			(layer "F.Fab")
		)
		(pad "1" smd rect
			(at -2.800096 -2.275078 180)
			(size 0.3556 1.6002)
			(layers "F.Cu" "F.Mask" "F.Paste")
			(net "SPI_BIC1_CS0_LS23_N_DIR1")
		)
		(pad "2" smd rect
			(at -2.800096 -1.625092 180)
			(size 0.3556 1.6002)
			(layers "F.Cu" "F.Mask" "F.Paste")
			(net "SPI_BIC1_CLK_LS23_DIR2")
		)
		(pad "3" smd rect
			(at -2.800096 -0.975106 180)
			(size 0.3556 1.6002)
			(layers "F.Cu" "F.Mask" "F.Paste")
			(net "SPI_BIC1_CS0_LS23_N")
		)
		(pad "4" smd rect
			(at -2.800096 -0.32512 180)
			(size 0.3556 1.6002)
			(layers "F.Cu" "F.Mask" "F.Paste")
			(net "SPI_BIC1_CLK_LS23")
		)
		(pad "5" smd rect
			(at -2.800096 0.32512 180)
			(size 0.3556 1.6002)
			(layers "F.Cu" "F.Mask" "F.Paste")
			(net "SPI_BIC1_MOSI_LS23")
		)
		(pad "6" smd rect
			(at -2.800096 0.975106 180)
			(size 0.3556 1.6002)
			(layers "F.Cu" "F.Mask" "F.Paste")
			(net "SPI_BIC1_MISO_LS23")
		)
		(pad "7" smd rect
			(at -2.800096 1.625092 180)
			(size 0.3556 1.6002)
			(layers "F.Cu" "F.Mask" "F.Paste")
			(net "SPI_BIC1_MOSI_LS23_DIR3")
		)
		(pad "8" smd rect
			(at -2.800096 2.275078 180)
			(size 0.3556 1.6002)
			(layers "F.Cu" "F.Mask" "F.Paste")
			(net "SPI_BIC1_MISO_LS23_DIR4")
		)
		(pad "9" smd rect
			(at 2.800096 2.275078 180)
			(size 0.3556 1.6002)
			(layers "F.Cu" "F.Mask" "F.Paste")
			(net "SPI_BIC1_LS23_EN_R_N")
		)
		(pad "10" smd rect
			(at 2.800096 1.625092 180)
			(size 0.3556 1.6002)
			(layers "F.Cu" "F.Mask" "F.Paste")
			(net "GND")
		)
		(pad "11" smd rect
			(at 2.800096 0.975106 180)
			(size 0.3556 1.6002)
			(layers "F.Cu" "F.Mask" "F.Paste")
			(net "SPI_BIC1_MISO_R4")
		)
		(pad "12" smd rect
			(at 2.800096 0.32512 180)
			(size 0.3556 1.6002)
			(layers "F.Cu" "F.Mask" "F.Paste")
			(net "SPI_BIC1_MOSI_R4")
		)
		(pad "13" smd rect
			(at 2.800096 -0.32512 180)
			(size 0.3556 1.6002)
			(layers "F.Cu" "F.Mask" "F.Paste")
			(net "SPI_BIC1_CLK_R4")
		)
		(pad "14" smd rect
			(at 2.800096 -0.975106 180)
			(size 0.3556 1.6002)
			(layers "F.Cu" "F.Mask" "F.Paste")
			(net "SPI_BIC1_CS0_R3_N")
		)
		(pad "15" smd rect
			(at 2.800096 -1.625092 180)
			(size 0.3556 1.6002)
			(layers "F.Cu" "F.Mask" "F.Paste")
			(net "P3V3_AUX")
		)
		(pad "16" smd rect
			(at 2.800096 -2.275078 180)
			(size 0.3556 1.6002)
			(layers "F.Cu" "F.Mask" "F.Paste")
			(net "P1V8_PEX")
		)
	)
	(footprint ""
		(layer "F.Cu")
		(at 222.574866 -254.18542 -90)
		(property "Reference" "C4284"
			(at 0 0 270)
			(layer "F.SilkS")
			(hide yes)
			(effects
				(font
					(size 1.27 1.27)
				)
			)
		)
		(property "Value" ""
			(at 0 0 270)
			(layer "F.Fab")
			(effects
				(font
					(size 1.27 1.27)
				)
			)
		)
		(duplicate_pad_numbers_are_jumpers no)
		(fp_line
			(start -1.2954 0.5842)
			(end -1.2954 -0.5842)
			(stroke
				(width 0.1524)
				(type default)
			)
			(layer "F.SilkS")
		)
		(fp_line
			(start 1.2954 0.5842)
			(end -1.2954 0.5842)
			(stroke
				(width 0.1524)
				(type default)
			)
			(layer "F.SilkS")
		)
		(fp_line
			(start -1.2954 -0.5842)
			(end 1.2954 -0.5842)
			(stroke
				(width 0.1524)
				(type default)
			)
			(layer "F.SilkS")
		)
		(fp_line
			(start 1.2954 -0.5842)
			(end 1.2954 0.5842)
			(stroke
				(width 0.1524)
				(type default)
			)
			(layer "F.SilkS")
		)
		(fp_line
			(start -0.8636 0.4572)
			(end -0.8636 0.4064)
			(stroke
				(width 0.1)
				(type default)
			)
			(layer "F.Fab")
		)
		(fp_line
			(start 0.8636 0.4572)
			(end -0.8636 0.4572)
			(stroke
				(width 0.1)
				(type default)
			)
			(layer "F.Fab")
		)
		(fp_line
			(start -1.1938 0.4064)
			(end -1.1938 -0.4064)
			(stroke
				(width 0.1)
				(type default)
			)
			(layer "F.Fab")
		)
		(fp_line
			(start -0.8636 0.4064)
			(end -1.1938 0.4064)
			(stroke
				(width 0.1)
				(type default)
			)
			(layer "F.Fab")
		)
		(fp_line
			(start 0.8636 0.4064)
			(end 0.8636 0.4572)
			(stroke
				(width 0.1)
				(type default)
			)
			(layer "F.Fab")
		)
		(fp_line
			(start 1.1938 0.4064)
			(end 0.8636 0.4064)
			(stroke
				(width 0.1)
				(type default)
			)
			(layer "F.Fab")
		)
		(fp_line
			(start -1.1938 -0.4064)
			(end -0.8636 -0.4064)
			(stroke
				(width 0.1)
				(type default)
			)
			(layer "F.Fab")
		)
		(fp_line
			(start -0.8636 -0.4064)
			(end -0.8636 -0.4572)
			(stroke
				(width 0.1)
				(type default)
			)
			(layer "F.Fab")
		)
		(fp_line
			(start 0.8636 -0.4064)
			(end 1.1938 -0.4064)
			(stroke
				(width 0.1)
				(type default)
			)
			(layer "F.Fab")
		)
		(fp_line
			(start 1.1938 -0.4064)
			(end 1.1938 0.4064)
			(stroke
				(width 0.1)
				(type default)
			)
			(layer "F.Fab")
		)
		(fp_line
			(start -0.8636 -0.4572)
			(end 0.8636 -0.4572)
			(stroke
				(width 0.1)
				(type default)
			)
			(layer "F.Fab")
		)
		(fp_line
			(start 0.8636 -0.4572)
			(end 0.8636 -0.4064)
			(stroke
				(width 0.1)
				(type default)
			)
			(layer "F.Fab")
		)
		(pad "1" smd rect
			(at -0.7366 0 180)
			(size 0.7112 0.8128)
			(layers "F.Cu" "F.Mask" "F.Paste")
			(net "P1V25_SERDES_VDDPLL_PEX1_C2")
		)
		(pad "2" smd rect
			(at 0.7366 0 180)
			(size 0.7112 0.8128)
			(layers "F.Cu" "F.Mask" "F.Paste")
			(net "GND")
		)
	)
	(footprint ""
		(layer "F.Cu")
		(at 230.749094 -175.70958)
		(property "Reference" "R3150"
			(at 0 0 0)
			(layer "F.SilkS")
			(hide yes)
			(effects
				(font
					(size 1.27 1.27)
				)
			)
		)
		(property "Value" ""
			(at 0 0 0)
			(layer "F.Fab")
			(effects
				(font
					(size 1.27 1.27)
				)
			)
		)
		(duplicate_pad_numbers_are_jumpers no)
		(fp_line
			(start -0.7874 -0.4064)
			(end 0.7874 -0.4064)
			(stroke
				(width 0.1524)
				(type default)
			)
			(layer "F.SilkS")
		)
		(fp_line
			(start -0.7874 0.4064)
			(end -0.7874 -0.4064)
			(stroke
				(width 0.1524)
				(type default)
			)
			(layer "F.SilkS")
		)
		(fp_line
			(start 0.7874 -0.4064)
			(end 0.7874 0.4064)
			(stroke
				(width 0.1524)
				(type default)
			)
			(layer "F.SilkS")
		)
		(fp_line
			(start 0.7874 0.4064)
			(end -0.7874 0.4064)
			(stroke
				(width 0.1524)
				(type default)
			)
			(layer "F.SilkS")
		)
		(fp_line
			(start -0.67945 -0.305054)
			(end -0.12065 -0.305054)
			(stroke
				(width 0.1)
				(type default)
			)
			(layer "F.Fab")
		)
		(fp_line
			(start -0.67945 0.3048)
			(end -0.67945 -0.305054)
			(stroke
				(width 0.1)
				(type default)
			)
			(layer "F.Fab")
		)
		(fp_line
			(start -0.12065 -0.305054)
			(end -0.12065 -0.2794)
			(stroke
				(width 0.1)
				(type default)
			)
			(layer "F.Fab")
		)
		(fp_line
			(start -0.12065 -0.2794)
			(end 0.12065 -0.2794)
			(stroke
				(width 0.1)
				(type default)
			)
			(layer "F.Fab")
		)
		(fp_line
			(start -0.12065 0.2794)
			(end -0.12065 0.3048)
			(stroke
				(width 0.1)
				(type default)
			)
			(layer "F.Fab")
		)
		(fp_line
			(start -0.12065 0.3048)
			(end -0.67945 0.3048)
			(stroke
				(width 0.1)
				(type default)
			)
			(layer "F.Fab")
		)
		(fp_line
			(start 0.120396 0.2794)
			(end -0.12065 0.2794)
			(stroke
				(width 0.1)
				(type default)
			)
			(layer "F.Fab")
		)
		(fp_line
			(start 0.120396 0.3048)
			(end 0.120396 0.2794)
			(stroke
				(width 0.1)
				(type default)
			)
			(layer "F.Fab")
		)
		(fp_line
			(start 0.12065 -0.3048)
			(end 0.67945 -0.3048)
			(stroke
				(width 0.1)
				(type default)
			)
			(layer "F.Fab")
		)
		(fp_line
			(start 0.12065 -0.2794)
			(end 0.12065 -0.3048)
			(stroke
				(width 0.1)
				(type default)
			)
			(layer "F.Fab")
		)
		(fp_line
			(start 0.67945 -0.3048)
			(end 0.67945 0.3048)
			(stroke
				(width 0.1)
				(type default)
			)
			(layer "F.Fab")
		)
		(fp_line
			(start 0.67945 0.3048)
			(end 0.120396 0.3048)
			(stroke
				(width 0.1)
				(type default)
			)
			(layer "F.Fab")
		)
		(pad "1" smd circle
			(at -0.40005 0)
			(size 0 0)
			(layers "F.Cu" "F.Mask" "F.Paste")
			(net "ADM1085_ENOUT")
		)
		(pad "2" smd circle
			(at 0.40005 0)
			(size 0 0)
			(layers "F.Cu" "F.Mask" "F.Paste")
			(net "GND")
		)
	)
	(footprint ""
		(layer "F.Cu")
		(at 142.922752 -311.156604 -90)
		(property "Reference" "R1325"
			(at 0 0 270)
			(layer "F.SilkS")
			(hide yes)
			(effects
				(font
					(size 1.27 1.27)
				)
			)
		)
		(property "Value" ""
			(at 0 0 270)
			(layer "F.Fab")
			(effects
				(font
					(size 1.27 1.27)
				)
			)
		)
		(duplicate_pad_numbers_are_jumpers no)
		(fp_line
			(start -0.7874 0.4064)
			(end -0.7874 -0.4064)
			(stroke
				(width 0.1524)
				(type default)
			)
			(layer "F.SilkS")
		)
		(fp_line
			(start 0.7874 0.4064)
			(end -0.7874 0.4064)
			(stroke
				(width 0.1524)
				(type default)
			)
			(layer "F.SilkS")
		)
		(fp_line
			(start -0.7874 -0.4064)
			(end 0.7874 -0.4064)
			(stroke
				(width 0.1524)
				(type default)
			)
			(layer "F.SilkS")
		)
		(fp_line
			(start 0.7874 -0.4064)
			(end 0.7874 0.4064)
			(stroke
				(width 0.1524)
				(type default)
			)
			(layer "F.SilkS")
		)
		(fp_line
			(start -0.67945 0.3048)
			(end -0.67945 -0.305054)
			(stroke
				(width 0.1)
				(type default)
			)
			(layer "F.Fab")
		)
		(fp_line
			(start -0.12065 0.3048)
			(end -0.67945 0.3048)
			(stroke
				(width 0.1)
				(type default)
			)
			(layer "F.Fab")
		)
		(fp_line
			(start 0.120396 0.3048)
			(end 0.120396 0.2794)
			(stroke
				(width 0.1)
				(type default)
			)
			(layer "F.Fab")
		)
		(fp_line
			(start 0.67945 0.3048)
			(end 0.120396 0.3048)
			(stroke
				(width 0.1)
				(type default)
			)
			(layer "F.Fab")
		)
		(fp_line
			(start -0.12065 0.2794)
			(end -0.12065 0.3048)
			(stroke
				(width 0.1)
				(type default)
			)
			(layer "F.Fab")
		)
		(fp_line
			(start 0.120396 0.2794)
			(end -0.12065 0.2794)
			(stroke
				(width 0.1)
				(type default)
			)
			(layer "F.Fab")
		)
		(fp_line
			(start -0.12065 -0.2794)
			(end 0.12065 -0.2794)
			(stroke
				(width 0.1)
				(type default)
			)
			(layer "F.Fab")
		)
		(fp_line
			(start 0.12065 -0.2794)
			(end 0.12065 -0.3048)
			(stroke
				(width 0.1)
				(type default)
			)
			(layer "F.Fab")
		)
		(fp_line
			(start 0.12065 -0.3048)
			(end 0.67945 -0.3048)
			(stroke
				(width 0.1)
				(type default)
			)
			(layer "F.Fab")
		)
		(fp_line
			(start 0.67945 -0.3048)
			(end 0.67945 0.3048)
			(stroke
				(width 0.1)
				(type default)
			)
			(layer "F.Fab")
		)
		(fp_line
			(start -0.67945 -0.305054)
			(end -0.12065 -0.305054)
			(stroke
				(width 0.1)
				(type default)
			)
			(layer "F.Fab")
		)
		(fp_line
			(start -0.12065 -0.305054)
			(end -0.12065 -0.2794)
			(stroke
				(width 0.1)
				(type default)
			)
			(layer "F.Fab")
		)
		(pad "1" smd circle
			(at -0.40005 0 270)
			(size 0 0)
			(layers "F.Cu" "F.Mask" "F.Paste")
			(net "PU_PEX1_TR_TCK")
		)
		(pad "2" smd circle
			(at 0.40005 0 270)
			(size 0 0)
			(layers "F.Cu" "F.Mask" "F.Paste")
			(net "P1V8_PEX")
		)
	)
	(footprint ""
		(layer "F.Cu")
		(at 270.960342 -117.7544 180)
		(property "Reference" "R209"
			(at 0 0 180)
			(layer "F.SilkS")
			(hide yes)
			(effects
				(font
					(size 1.27 1.27)
				)
			)
		)
		(property "Value" ""
			(at 0 0 180)
			(layer "F.Fab")
			(effects
				(font
					(size 1.27 1.27)
				)
			)
		)
		(duplicate_pad_numbers_are_jumpers no)
		(fp_line
			(start 0.7874 0.4064)
			(end -0.7874 0.4064)
			(stroke
				(width 0.1524)
				(type default)
			)
			(layer "F.SilkS")
		)
		(fp_line
			(start 0.7874 -0.4064)
			(end 0.7874 0.4064)
			(stroke
				(width 0.1524)
				(type default)
			)
			(layer "F.SilkS")
		)
		(fp_line
			(start -0.7874 0.4064)
			(end -0.7874 -0.4064)
			(stroke
				(width 0.1524)
				(type default)
			)
			(layer "F.SilkS")
		)
		(fp_line
			(start -0.7874 -0.4064)
			(end 0.7874 -0.4064)
			(stroke
				(width 0.1524)
				(type default)
			)
			(layer "F.SilkS")
		)
		(fp_line
			(start 0.67945 0.3048)
			(end 0.120396 0.3048)
			(stroke
				(width 0.1)
				(type default)
			)
			(layer "F.Fab")
		)
		(fp_line
			(start 0.67945 -0.3048)
			(end 0.67945 0.3048)
			(stroke
				(width 0.1)
				(type default)
			)
			(layer "F.Fab")
		)
		(fp_line
			(start 0.12065 -0.2794)
			(end 0.12065 -0.3048)
			(stroke
				(width 0.1)
				(type default)
			)
			(layer "F.Fab")
		)
		(fp_line
			(start 0.12065 -0.3048)
			(end 0.67945 -0.3048)
			(stroke
				(width 0.1)
				(type default)
			)
			(layer "F.Fab")
		)
		(fp_line
			(start 0.120396 0.3048)
			(end 0.120396 0.2794)
			(stroke
				(width 0.1)
				(type default)
			)
			(layer "F.Fab")
		)
		(fp_line
			(start 0.120396 0.2794)
			(end -0.12065 0.2794)
			(stroke
				(width 0.1)
				(type default)
			)
			(layer "F.Fab")
		)
		(fp_line
			(start -0.12065 0.3048)
			(end -0.67945 0.3048)
			(stroke
				(width 0.1)
				(type default)
			)
			(layer "F.Fab")
		)
		(fp_line
			(start -0.12065 0.2794)
			(end -0.12065 0.3048)
			(stroke
				(width 0.1)
				(type default)
			)
			(layer "F.Fab")
		)
		(fp_line
			(start -0.12065 -0.2794)
			(end 0.12065 -0.2794)
			(stroke
				(width 0.1)
				(type default)
			)
			(layer "F.Fab")
		)
		(fp_line
			(start -0.12065 -0.305054)
			(end -0.12065 -0.2794)
			(stroke
				(width 0.1)
				(type default)
			)
			(layer "F.Fab")
		)
		(fp_line
			(start -0.67945 0.3048)
			(end -0.67945 -0.305054)
			(stroke
				(width 0.1)
				(type default)
			)
			(layer "F.Fab")
		)
		(fp_line
			(start -0.67945 -0.305054)
			(end -0.12065 -0.305054)
			(stroke
				(width 0.1)
				(type default)
			)
			(layer "F.Fab")
		)
		(pad "1" smd circle
			(at -0.40005 0 180)
			(size 0 0)
			(layers "F.Cu" "F.Mask" "F.Paste")
			(net "PRSNTB0_NIC4_N")
		)
		(pad "2" smd circle
			(at 0.40005 0 180)
			(size 0 0)
			(layers "F.Cu" "F.Mask" "F.Paste")
			(net "P3V3_AUX")
		)
	)
	(footprint ""
		(layer "F.Cu")
		(at 364.790482 -91.356942)
		(property "Reference" "C2710"
			(at 0 0 0)
			(layer "F.SilkS")
			(hide yes)
			(effects
				(font
					(size 1.27 1.27)
				)
			)
		)
		(property "Value" ""
			(at 0 0 0)
			(layer "F.Fab")
			(effects
				(font
					(size 1.27 1.27)
				)
			)
		)
		(duplicate_pad_numbers_are_jumpers no)
		(fp_line
			(start -0.7874 -0.4064)
			(end 0.7874 -0.4064)
			(stroke
				(width 0.1524)
				(type default)
			)
			(layer "F.SilkS")
		)
		(fp_line
			(start -0.7874 0.4064)
			(end -0.7874 -0.4064)
			(stroke
				(width 0.1524)
				(type default)
			)
			(layer "F.SilkS")
		)
		(fp_line
			(start 0.7874 -0.4064)
			(end 0.7874 0.4064)
			(stroke
				(width 0.1524)
				(type default)
			)
			(layer "F.SilkS")
		)
		(fp_line
			(start 0.7874 0.4064)
			(end -0.7874 0.4064)
			(stroke
				(width 0.1524)
				(type default)
			)
			(layer "F.SilkS")
		)
		(fp_line
			(start -0.67945 -0.305054)
			(end -0.12065 -0.305054)
			(stroke
				(width 0.1)
				(type default)
			)
			(layer "F.Fab")
		)
		(fp_line
			(start -0.67945 0.3048)
			(end -0.67945 -0.305054)
			(stroke
				(width 0.1)
				(type default)
			)
			(layer "F.Fab")
		)
		(fp_line
			(start -0.12065 -0.305054)
			(end -0.12065 -0.2794)
			(stroke
				(width 0.1)
				(type default)
			)
			(layer "F.Fab")
		)
		(fp_line
			(start -0.12065 -0.2794)
			(end 0.12065 -0.2794)
			(stroke
				(width 0.1)
				(type default)
			)
			(layer "F.Fab")
		)
		(fp_line
			(start -0.12065 0.2794)
			(end -0.12065 0.3048)
			(stroke
				(width 0.1)
				(type default)
			)
			(layer "F.Fab")
		)
		(fp_line
			(start -0.12065 0.3048)
			(end -0.67945 0.3048)
			(stroke
				(width 0.1)
				(type default)
			)
			(layer "F.Fab")
		)
		(fp_line
			(start 0.120396 0.2794)
			(end -0.12065 0.2794)
			(stroke
				(width 0.1)
				(type default)
			)
			(layer "F.Fab")
		)
		(fp_line
			(start 0.120396 0.3048)
			(end 0.120396 0.2794)
			(stroke
				(width 0.1)
				(type default)
			)
			(layer "F.Fab")
		)
		(fp_line
			(start 0.12065 -0.3048)
			(end 0.67945 -0.3048)
			(stroke
				(width 0.1)
				(type default)
			)
			(layer "F.Fab")
		)
		(fp_line
			(start 0.12065 -0.2794)
			(end 0.12065 -0.3048)
			(stroke
				(width 0.1)
				(type default)
			)
			(layer "F.Fab")
		)
		(fp_line
			(start 0.67945 -0.3048)
			(end 0.67945 0.3048)
			(stroke
				(width 0.1)
				(type default)
			)
			(layer "F.Fab")
		)
		(fp_line
			(start 0.67945 0.3048)
			(end 0.120396 0.3048)
			(stroke
				(width 0.1)
				(type default)
			)
			(layer "F.Fab")
		)
		(pad "1" smd circle
			(at -0.40005 0)
			(size 0 0)
			(layers "F.Cu" "F.Mask" "F.Paste")
			(net "P3V3_AUX")
		)
		(pad "2" smd circle
			(at 0.40005 0)
			(size 0 0)
			(layers "F.Cu" "F.Mask" "F.Paste")
			(net "GND")
		)
	)
	(footprint ""
		(layer "F.Cu")
		(at 159.892492 -29.139642 180)
		(property "Reference" "C290"
			(at 0 0 180)
			(layer "F.SilkS")
			(hide yes)
			(effects
				(font
					(size 1.27 1.27)
				)
			)
		)
		(property "Value" ""
			(at 0 0 180)
			(layer "F.Fab")
			(effects
				(font
					(size 1.27 1.27)
				)
			)
		)
		(duplicate_pad_numbers_are_jumpers no)
		(fp_line
			(start 0.299974 0.150114)
			(end -0.299974 0.150114)
			(stroke
				(width 0.1)
				(type default)
			)
			(layer "F.Fab")
		)
		(fp_line
			(start 0.299974 -0.150114)
			(end 0.299974 0.150114)
			(stroke
				(width 0.1)
				(type default)
			)
			(layer "F.Fab")
		)
		(fp_line
			(start -0.299974 0.150114)
			(end -0.299974 -0.150114)
			(stroke
				(width 0.1)
				(type default)
			)
			(layer "F.Fab")
		)
		(fp_line
			(start -0.299974 -0.150114)
			(end 0.299974 -0.150114)
			(stroke
				(width 0.1)
				(type default)
			)
			(layer "F.Fab")
		)
		(pad "1" smd rect
			(at -0.2667 0 180)
			(size 0.3048 0.381)
			(layers "F.Cu" "F.Mask" "F.Paste")
			(net "P5E_PEX1_STN2_TX_DP<40>")
		)
		(pad "2" smd rect
			(at 0.2667 0 180)
			(size 0.3048 0.381)
			(layers "F.Cu" "F.Mask" "F.Paste")
			(net "P5E_PEX1_STN2_TX_C_DP<40>")
		)
	)
	(footprint ""
		(layer "F.Cu")
		(at 193.711576 -71.458074 -90)
		(property "Reference" "PD100"
			(at 4.300474 -2.733294 90)
			(unlocked yes)
			(layer "F.SilkS")
			(effects
				(font
					(size 0.7874 0.5842)
					(thickness 0.1524)
				)
				(justify left)
			)
		)
		(property "Value" ""
			(at 0 0 270)
			(layer "F.Fab")
			(effects
				(font
					(size 1.27 1.27)
				)
			)
		)
		(duplicate_pad_numbers_are_jumpers no)
		(fp_line
			(start -3.656584 1.970024)
			(end 4.240784 1.970024)
			(stroke
				(width 0.1524)
				(type default)
			)
			(layer "F.SilkS")
		)
		(fp_line
			(start 4.240784 1.970024)
			(end 4.240784 -1.970024)
			(stroke
				(width 0.1524)
				(type default)
			)
			(layer "F.SilkS")
		)
		(fp_line
			(start -3.656584 -1.970024)
			(end -3.656584 1.970024)
			(stroke
				(width 0.1524)
				(type default)
			)
			(layer "F.SilkS")
		)
		(fp_line
			(start 4.240784 -1.970024)
			(end -3.656584 -1.970024)
			(stroke
				(width 0.1524)
				(type default)
			)
			(layer "F.SilkS")
		)
		(fp_poly
			(pts
				(xy 3.580384 1.970024) (xy 3.580384 -1.970024) (xy 4.240784 -1.970024) (xy 4.240784 1.970024)
			)
			(stroke
				(width 0)
				(type default)
			)
			(fill yes)
			(layer "F.SilkS")
		)
		(fp_line
			(start -2.3749 1.970024)
			(end 2.3749 1.970024)
			(stroke
				(width 0.1)
				(type default)
			)
			(layer "F.Fab")
		)
		(fp_line
			(start 2.3749 1.970024)
			(end 2.3749 -1.970024)
			(stroke
				(width 0.1)
				(type default)
			)
			(layer "F.Fab")
		)
		(fp_line
			(start -2.3749 -1.970024)
			(end -2.3749 1.970024)
			(stroke
				(width 0.1)
				(type default)
			)
			(layer "F.Fab")
		)
		(fp_line
			(start 2.3749 -1.970024)
			(end -2.3749 -1.970024)
			(stroke
				(width 0.1)
				(type default)
			)
			(layer "F.Fab")
		)
		(fp_text user "+"
			(at -4.9784 -0.23495 270)
			(unlocked yes)
			(layer "F.Fab")
			(effects
				(font
					(size 1.905 1.4224)
					(thickness 0.1524)
				)
				(justify left)
			)
		)
		(fp_text user "-"
			(at 4.1656 -0.23495 270)
			(unlocked yes)
			(layer "F.Fab")
			(effects
				(font
					(size 1.905 1.4224)
					(thickness 0.1524)
				)
				(justify left)
			)
		)
		(pad "A" smd rect
			(at -2.450084 0 270)
			(size 2.159 2.2606)
			(layers "F.Cu" "F.Mask" "F.Paste")
			(net "GND")
		)
		(pad "C" smd rect
			(at 2.450084 0 270)
			(size 2.159 2.2606)
			(layers "F.Cu" "F.Mask" "F.Paste")
			(net "P12V_AUX")
		)
	)
	(footprint ""
		(layer "F.Cu")
		(at 441.501276 -55.78475 -90)
		(property "Reference" "PD123"
			(at 4.01955 2.130806 90)
			(unlocked yes)
			(layer "F.SilkS")
			(effects
				(font
					(size 0.7874 0.5842)
					(thickness 0.1524)
				)
				(justify left)
			)
		)
		(property "Value" ""
			(at 0 0 270)
			(layer "F.Fab")
			(effects
				(font
					(size 1.27 1.27)
				)
			)
		)
		(duplicate_pad_numbers_are_jumpers no)
		(fp_line
			(start -3.400044 1.459992)
			(end -3.400044 -1.459992)
			(stroke
				(width 0.1524)
				(type default)
			)
			(layer "F.SilkS")
		)
		(fp_line
			(start 4.107942 1.459992)
			(end -3.400044 1.459992)
			(stroke
				(width 0.1524)
				(type default)
			)
			(layer "F.SilkS")
		)
		(fp_line
			(start -3.400044 -1.459992)
			(end 4.107942 -1.459992)
			(stroke
				(width 0.1524)
				(type default)
			)
			(layer "F.SilkS")
		)
		(fp_line
			(start 4.107942 -1.459992)
			(end 4.107942 1.459992)
			(stroke
				(width 0.1524)
				(type default)
			)
			(layer "F.SilkS")
		)
		(fp_poly
			(pts
				(xy 4.107942 -1.459992) (xy 4.107942 1.459992) (xy 3.308096 1.459992) (xy 3.308096 -1.459992)
			)
			(stroke
				(width 0)
				(type default)
			)
			(fill yes)
			(layer "F.SilkS")
		)
		(fp_line
			(start -2.29997 1.459992)
			(end -2.29997 -1.459992)
			(stroke
				(width 0.1)
				(type default)
			)
			(layer "F.Fab")
		)
		(fp_line
			(start 2.29997 1.459992)
			(end -2.29997 1.459992)
			(stroke
				(width 0.1)
				(type default)
			)
			(layer "F.Fab")
		)
		(fp_line
			(start -2.29997 -1.459992)
			(end 2.29997 -1.459992)
			(stroke
				(width 0.1)
				(type default)
			)
			(layer "F.Fab")
		)
		(fp_line
			(start 2.29997 -1.459992)
			(end 2.29997 1.459992)
			(stroke
				(width 0.1)
				(type default)
			)
			(layer "F.Fab")
		)
		(fp_text user "-"
			(at 5.4102 0.29845 90)
			(unlocked yes)
			(layer "F.SilkS")
			(effects
				(font
					(size 1.905 1.4224)
					(thickness 0.1524)
				)
				(justify left)
			)
		)
		(fp_text user "+"
			(at -4.7752 -0.12065 270)
			(unlocked yes)
			(layer "F.SilkS")
			(effects
				(font
					(size 1.905 1.4224)
					(thickness 0.1524)
				)
				(justify left)
			)
		)
		(fp_text user "-"
			(at 5.4102 0.29845 90)
			(unlocked yes)
			(layer "F.Fab")
			(effects
				(font
					(size 1.905 1.4224)
					(thickness 0.1524)
				)
				(justify left)
			)
		)
		(fp_text user "+"
			(at -4.7752 -0.12065 270)
			(unlocked yes)
			(layer "F.Fab")
			(effects
				(font
					(size 1.905 1.4224)
					(thickness 0.1524)
				)
				(justify left)
			)
		)
		(pad "A" smd rect
			(at -1.999996 0)
			(size 1.7018 2.5146)
			(layers "F.Cu" "F.Mask" "F.Paste")
			(net "GND")
		)
		(pad "C" smd rect
			(at 1.999996 0)
			(size 1.7018 2.5146)
			(layers "F.Cu" "F.Mask" "F.Paste")
			(net "P12V_SSD15_R")
		)
	)
	(footprint ""
		(layer "F.Cu")
		(at 209.00009 -289.230816 -90)
		(property "Reference" "R3933"
			(at 0 0 270)
			(layer "F.SilkS")
			(hide yes)
			(effects
				(font
					(size 1.27 1.27)
				)
			)
		)
		(property "Value" ""
			(at 0 0 270)
			(layer "F.Fab")
			(effects
				(font
					(size 1.27 1.27)
				)
			)
		)
		(duplicate_pad_numbers_are_jumpers no)
		(fp_line
			(start -0.7874 0.4064)
			(end -0.7874 -0.4064)
			(stroke
				(width 0.1524)
				(type default)
			)
			(layer "F.SilkS")
		)
		(fp_line
			(start 0.7874 0.4064)
			(end -0.7874 0.4064)
			(stroke
				(width 0.1524)
				(type default)
			)
			(layer "F.SilkS")
		)
		(fp_line
			(start -0.7874 -0.4064)
			(end 0.7874 -0.4064)
			(stroke
				(width 0.1524)
				(type default)
			)
			(layer "F.SilkS")
		)
		(fp_line
			(start 0.7874 -0.4064)
			(end 0.7874 0.4064)
			(stroke
				(width 0.1524)
				(type default)
			)
			(layer "F.SilkS")
		)
		(fp_line
			(start -0.67945 0.3048)
			(end -0.67945 -0.305054)
			(stroke
				(width 0.1)
				(type default)
			)
			(layer "F.Fab")
		)
		(fp_line
			(start -0.12065 0.3048)
			(end -0.67945 0.3048)
			(stroke
				(width 0.1)
				(type default)
			)
			(layer "F.Fab")
		)
		(fp_line
			(start 0.120396 0.3048)
			(end 0.120396 0.2794)
			(stroke
				(width 0.1)
				(type default)
			)
			(layer "F.Fab")
		)
		(fp_line
			(start 0.67945 0.3048)
			(end 0.120396 0.3048)
			(stroke
				(width 0.1)
				(type default)
			)
			(layer "F.Fab")
		)
		(fp_line
			(start -0.12065 0.2794)
			(end -0.12065 0.3048)
			(stroke
				(width 0.1)
				(type default)
			)
			(layer "F.Fab")
		)
		(fp_line
			(start 0.120396 0.2794)
			(end -0.12065 0.2794)
			(stroke
				(width 0.1)
				(type default)
			)
			(layer "F.Fab")
		)
		(fp_line
			(start -0.12065 -0.2794)
			(end 0.12065 -0.2794)
			(stroke
				(width 0.1)
				(type default)
			)
			(layer "F.Fab")
		)
		(fp_line
			(start 0.12065 -0.2794)
			(end 0.12065 -0.3048)
			(stroke
				(width 0.1)
				(type default)
			)
			(layer "F.Fab")
		)
		(fp_line
			(start 0.12065 -0.3048)
			(end 0.67945 -0.3048)
			(stroke
				(width 0.1)
				(type default)
			)
			(layer "F.Fab")
		)
		(fp_line
			(start 0.67945 -0.3048)
			(end 0.67945 0.3048)
			(stroke
				(width 0.1)
				(type default)
			)
			(layer "F.Fab")
		)
		(fp_line
			(start -0.67945 -0.305054)
			(end -0.12065 -0.305054)
			(stroke
				(width 0.1)
				(type default)
			)
			(layer "F.Fab")
		)
		(fp_line
			(start -0.12065 -0.305054)
			(end -0.12065 -0.2794)
			(stroke
				(width 0.1)
				(type default)
			)
			(layer "F.Fab")
		)
		(pad "1" smd circle
			(at -0.40005 0 270)
			(size 0 0)
			(layers "F.Cu" "F.Mask" "F.Paste")
			(net "SMB_PEX1_HOST_LS_SCL")
		)
		(pad "2" smd circle
			(at 0.40005 0 270)
			(size 0 0)
			(layers "F.Cu" "F.Mask" "F.Paste")
			(net "P3V3_AUX")
		)
	)
	(footprint ""
		(layer "F.Cu")
		(at 272.798286 -250.070874 -90)
		(property "Reference" "R1337"
			(at 0 0 270)
			(layer "F.SilkS")
			(hide yes)
			(effects
				(font
					(size 1.27 1.27)
				)
			)
		)
		(property "Value" ""
			(at 0 0 270)
			(layer "F.Fab")
			(effects
				(font
					(size 1.27 1.27)
				)
			)
		)
		(duplicate_pad_numbers_are_jumpers no)
		(fp_line
			(start -0.7874 0.4064)
			(end -0.7874 -0.4064)
			(stroke
				(width 0.1524)
				(type default)
			)
			(layer "F.SilkS")
		)
		(fp_line
			(start 0.7874 0.4064)
			(end -0.7874 0.4064)
			(stroke
				(width 0.1524)
				(type default)
			)
			(layer "F.SilkS")
		)
		(fp_line
			(start -0.7874 -0.4064)
			(end 0.7874 -0.4064)
			(stroke
				(width 0.1524)
				(type default)
			)
			(layer "F.SilkS")
		)
		(fp_line
			(start 0.7874 -0.4064)
			(end 0.7874 0.4064)
			(stroke
				(width 0.1524)
				(type default)
			)
			(layer "F.SilkS")
		)
		(fp_line
			(start -0.67945 0.3048)
			(end -0.67945 -0.305054)
			(stroke
				(width 0.1)
				(type default)
			)
			(layer "F.Fab")
		)
		(fp_line
			(start -0.12065 0.3048)
			(end -0.67945 0.3048)
			(stroke
				(width 0.1)
				(type default)
			)
			(layer "F.Fab")
		)
		(fp_line
			(start 0.120396 0.3048)
			(end 0.120396 0.2794)
			(stroke
				(width 0.1)
				(type default)
			)
			(layer "F.Fab")
		)
		(fp_line
			(start 0.67945 0.3048)
			(end 0.120396 0.3048)
			(stroke
				(width 0.1)
				(type default)
			)
			(layer "F.Fab")
		)
		(fp_line
			(start -0.12065 0.2794)
			(end -0.12065 0.3048)
			(stroke
				(width 0.1)
				(type default)
			)
			(layer "F.Fab")
		)
		(fp_line
			(start 0.120396 0.2794)
			(end -0.12065 0.2794)
			(stroke
				(width 0.1)
				(type default)
			)
			(layer "F.Fab")
		)
		(fp_line
			(start -0.12065 -0.2794)
			(end 0.12065 -0.2794)
			(stroke
				(width 0.1)
				(type default)
			)
			(layer "F.Fab")
		)
		(fp_line
			(start 0.12065 -0.2794)
			(end 0.12065 -0.3048)
			(stroke
				(width 0.1)
				(type default)
			)
			(layer "F.Fab")
		)
		(fp_line
			(start 0.12065 -0.3048)
			(end 0.67945 -0.3048)
			(stroke
				(width 0.1)
				(type default)
			)
			(layer "F.Fab")
		)
		(fp_line
			(start 0.67945 -0.3048)
			(end 0.67945 0.3048)
			(stroke
				(width 0.1)
				(type default)
			)
			(layer "F.Fab")
		)
		(fp_line
			(start -0.67945 -0.305054)
			(end -0.12065 -0.305054)
			(stroke
				(width 0.1)
				(type default)
			)
			(layer "F.Fab")
		)
		(fp_line
			(start -0.12065 -0.305054)
			(end -0.12065 -0.2794)
			(stroke
				(width 0.1)
				(type default)
			)
			(layer "F.Fab")
		)
		(pad "1" smd circle
			(at -0.40005 0 270)
			(size 0 0)
			(layers "F.Cu" "F.Mask" "F.Paste")
			(net "PEX2_MODE_SEL1")
		)
		(pad "2" smd circle
			(at 0.40005 0 270)
			(size 0 0)
			(layers "F.Cu" "F.Mask" "F.Paste")
			(net "P1V8_PEX")
		)
	)
	(footprint ""
		(layer "F.Cu")
		(at 189.382654 -80.739742)
		(property "Reference" "R203"
			(at 0 0 0)
			(layer "F.SilkS")
			(hide yes)
			(effects
				(font
					(size 1.27 1.27)
				)
			)
		)
		(property "Value" ""
			(at 0 0 0)
			(layer "F.Fab")
			(effects
				(font
					(size 1.27 1.27)
				)
			)
		)
		(duplicate_pad_numbers_are_jumpers no)
		(fp_line
			(start -0.7874 -0.4064)
			(end 0.7874 -0.4064)
			(stroke
				(width 0.1524)
				(type default)
			)
			(layer "F.SilkS")
		)
		(fp_line
			(start -0.7874 0.4064)
			(end -0.7874 -0.4064)
			(stroke
				(width 0.1524)
				(type default)
			)
			(layer "F.SilkS")
		)
		(fp_line
			(start 0.7874 -0.4064)
			(end 0.7874 0.4064)
			(stroke
				(width 0.1524)
				(type default)
			)
			(layer "F.SilkS")
		)
		(fp_line
			(start 0.7874 0.4064)
			(end -0.7874 0.4064)
			(stroke
				(width 0.1524)
				(type default)
			)
			(layer "F.SilkS")
		)
		(fp_line
			(start -0.67945 -0.305054)
			(end -0.12065 -0.305054)
			(stroke
				(width 0.1)
				(type default)
			)
			(layer "F.Fab")
		)
		(fp_line
			(start -0.67945 0.3048)
			(end -0.67945 -0.305054)
			(stroke
				(width 0.1)
				(type default)
			)
			(layer "F.Fab")
		)
		(fp_line
			(start -0.12065 -0.305054)
			(end -0.12065 -0.2794)
			(stroke
				(width 0.1)
				(type default)
			)
			(layer "F.Fab")
		)
		(fp_line
			(start -0.12065 -0.2794)
			(end 0.12065 -0.2794)
			(stroke
				(width 0.1)
				(type default)
			)
			(layer "F.Fab")
		)
		(fp_line
			(start -0.12065 0.2794)
			(end -0.12065 0.3048)
			(stroke
				(width 0.1)
				(type default)
			)
			(layer "F.Fab")
		)
		(fp_line
			(start -0.12065 0.3048)
			(end -0.67945 0.3048)
			(stroke
				(width 0.1)
				(type default)
			)
			(layer "F.Fab")
		)
		(fp_line
			(start 0.120396 0.2794)
			(end -0.12065 0.2794)
			(stroke
				(width 0.1)
				(type default)
			)
			(layer "F.Fab")
		)
		(fp_line
			(start 0.120396 0.3048)
			(end 0.120396 0.2794)
			(stroke
				(width 0.1)
				(type default)
			)
			(layer "F.Fab")
		)
		(fp_line
			(start 0.12065 -0.3048)
			(end 0.67945 -0.3048)
			(stroke
				(width 0.1)
				(type default)
			)
			(layer "F.Fab")
		)
		(fp_line
			(start 0.12065 -0.2794)
			(end 0.12065 -0.3048)
			(stroke
				(width 0.1)
				(type default)
			)
			(layer "F.Fab")
		)
		(fp_line
			(start 0.67945 -0.3048)
			(end 0.67945 0.3048)
			(stroke
				(width 0.1)
				(type default)
			)
			(layer "F.Fab")
		)
		(fp_line
			(start 0.67945 0.3048)
			(end 0.120396 0.3048)
			(stroke
				(width 0.1)
				(type default)
			)
			(layer "F.Fab")
		)
		(pad "1" smd circle
			(at -0.40005 0)
			(size 0 0)
			(layers "F.Cu" "F.Mask" "F.Paste")
			(net "P3V3_AUX")
		)
		(pad "2" smd circle
			(at 0.40005 0)
			(size 0 0)
			(layers "F.Cu" "F.Mask" "F.Paste")
			(net "HP_NIC3_HSC_PWRGD_N")
		)
	)
	(footprint ""
		(layer "F.Cu")
		(at 35.766248 -356.244906 90)
		(property "Reference" "C176"
			(at 0 0 90)
			(layer "F.SilkS")
			(hide yes)
			(effects
				(font
					(size 1.27 1.27)
				)
			)
		)
		(property "Value" ""
			(at 0 0 90)
			(layer "F.Fab")
			(effects
				(font
					(size 1.27 1.27)
				)
			)
		)
		(duplicate_pad_numbers_are_jumpers no)
		(fp_line
			(start 0.299974 -0.150114)
			(end 0.299974 0.150114)
			(stroke
				(width 0.1)
				(type default)
			)
			(layer "F.Fab")
		)
		(fp_line
			(start -0.299974 -0.150114)
			(end 0.299974 -0.150114)
			(stroke
				(width 0.1)
				(type default)
			)
			(layer "F.Fab")
		)
		(fp_line
			(start 0.299974 0.150114)
			(end -0.299974 0.150114)
			(stroke
				(width 0.1)
				(type default)
			)
			(layer "F.Fab")
		)
		(fp_line
			(start -0.299974 0.150114)
			(end -0.299974 -0.150114)
			(stroke
				(width 0.1)
				(type default)
			)
			(layer "F.Fab")
		)
		(pad "1" smd rect
			(at -0.2667 0 90)
			(size 0.3048 0.381)
			(layers "F.Cu" "F.Mask" "F.Paste")
			(net "P5E_PEX0_STN7_TX_DN<120>")
		)
		(pad "2" smd rect
			(at 0.2667 0 90)
			(size 0.3048 0.381)
			(layers "F.Cu" "F.Mask" "F.Paste")
			(net "P5E_PEX0_STN7_TX_C_DN<120>")
		)
	)
	(footprint ""
		(layer "F.Cu")
		(at 29.357828 -27.006296 -90)
		(property "Reference" "PR6921"
			(at 0 0 270)
			(layer "F.SilkS")
			(hide yes)
			(effects
				(font
					(size 1.27 1.27)
				)
			)
		)
		(property "Value" ""
			(at 0 0 270)
			(layer "F.Fab")
			(effects
				(font
					(size 1.27 1.27)
				)
			)
		)
		(duplicate_pad_numbers_are_jumpers no)
		(fp_line
			(start -0.7874 0.4064)
			(end -0.7874 -0.4064)
			(stroke
				(width 0.1524)
				(type default)
			)
			(layer "F.SilkS")
		)
		(fp_line
			(start 0.7874 0.4064)
			(end -0.7874 0.4064)
			(stroke
				(width 0.1524)
				(type default)
			)
			(layer "F.SilkS")
		)
		(fp_line
			(start -0.7874 -0.4064)
			(end 0.7874 -0.4064)
			(stroke
				(width 0.1524)
				(type default)
			)
			(layer "F.SilkS")
		)
		(fp_line
			(start 0.7874 -0.4064)
			(end 0.7874 0.4064)
			(stroke
				(width 0.1524)
				(type default)
			)
			(layer "F.SilkS")
		)
		(fp_line
			(start -0.67945 0.3048)
			(end -0.67945 -0.305054)
			(stroke
				(width 0.1)
				(type default)
			)
			(layer "F.Fab")
		)
		(fp_line
			(start -0.12065 0.3048)
			(end -0.67945 0.3048)
			(stroke
				(width 0.1)
				(type default)
			)
			(layer "F.Fab")
		)
		(fp_line
			(start 0.120396 0.3048)
			(end 0.120396 0.2794)
			(stroke
				(width 0.1)
				(type default)
			)
			(layer "F.Fab")
		)
		(fp_line
			(start 0.67945 0.3048)
			(end 0.120396 0.3048)
			(stroke
				(width 0.1)
				(type default)
			)
			(layer "F.Fab")
		)
		(fp_line
			(start -0.12065 0.2794)
			(end -0.12065 0.3048)
			(stroke
				(width 0.1)
				(type default)
			)
			(layer "F.Fab")
		)
		(fp_line
			(start 0.120396 0.2794)
			(end -0.12065 0.2794)
			(stroke
				(width 0.1)
				(type default)
			)
			(layer "F.Fab")
		)
		(fp_line
			(start -0.12065 -0.2794)
			(end 0.12065 -0.2794)
			(stroke
				(width 0.1)
				(type default)
			)
			(layer "F.Fab")
		)
		(fp_line
			(start 0.12065 -0.2794)
			(end 0.12065 -0.3048)
			(stroke
				(width 0.1)
				(type default)
			)
			(layer "F.Fab")
		)
		(fp_line
			(start 0.12065 -0.3048)
			(end 0.67945 -0.3048)
			(stroke
				(width 0.1)
				(type default)
			)
			(layer "F.Fab")
		)
		(fp_line
			(start 0.67945 -0.3048)
			(end 0.67945 0.3048)
			(stroke
				(width 0.1)
				(type default)
			)
			(layer "F.Fab")
		)
		(fp_line
			(start -0.67945 -0.305054)
			(end -0.12065 -0.305054)
			(stroke
				(width 0.1)
				(type default)
			)
			(layer "F.Fab")
		)
		(fp_line
			(start -0.12065 -0.305054)
			(end -0.12065 -0.2794)
			(stroke
				(width 0.1)
				(type default)
			)
			(layer "F.Fab")
		)
		(pad "1" smd circle
			(at -0.40005 0 270)
			(size 0 0)
			(layers "F.Cu" "F.Mask" "F.Paste")
			(net "P3V3_SSD1_CO_MODE")
		)
		(pad "2" smd circle
			(at 0.40005 0 270)
			(size 0 0)
			(layers "F.Cu" "F.Mask" "F.Paste")
			(net "GND")
		)
	)
	(footprint ""
		(layer "F.Cu")
		(at 447.676778 -209.393282)
		(property "Reference" "R1001"
			(at 0 0 0)
			(layer "F.SilkS")
			(hide yes)
			(effects
				(font
					(size 1.27 1.27)
				)
			)
		)
		(property "Value" ""
			(at 0 0 0)
			(layer "F.Fab")
			(effects
				(font
					(size 1.27 1.27)
				)
			)
		)
		(duplicate_pad_numbers_are_jumpers no)
		(fp_line
			(start -0.7874 -0.4064)
			(end 0.7874 -0.4064)
			(stroke
				(width 0.1524)
				(type default)
			)
			(layer "F.SilkS")
		)
		(fp_line
			(start -0.67945 -0.305054)
			(end -0.12065 -0.305054)
			(stroke
				(width 0.1)
				(type default)
			)
			(layer "F.Fab")
		)
		(fp_line
			(start -0.67945 0.3048)
			(end -0.67945 -0.305054)
			(stroke
				(width 0.1)
				(type default)
			)
			(layer "F.Fab")
		)
		(fp_line
			(start -0.12065 -0.305054)
			(end -0.12065 -0.2794)
			(stroke
				(width 0.1)
				(type default)
			)
			(layer "F.Fab")
		)
		(fp_line
			(start -0.12065 -0.2794)
			(end 0.12065 -0.2794)
			(stroke
				(width 0.1)
				(type default)
			)
			(layer "F.Fab")
		)
		(fp_line
			(start -0.12065 0.2794)
			(end -0.12065 0.3048)
			(stroke
				(width 0.1)
				(type default)
			)
			(layer "F.Fab")
		)
		(fp_line
			(start -0.12065 0.3048)
			(end -0.67945 0.3048)
			(stroke
				(width 0.1)
				(type default)
			)
			(layer "F.Fab")
		)
		(fp_line
			(start 0.120396 0.2794)
			(end -0.12065 0.2794)
			(stroke
				(width 0.1)
				(type default)
			)
			(layer "F.Fab")
		)
		(fp_line
			(start 0.120396 0.3048)
			(end 0.120396 0.2794)
			(stroke
				(width 0.1)
				(type default)
			)
			(layer "F.Fab")
		)
		(fp_line
			(start 0.12065 -0.3048)
			(end 0.67945 -0.3048)
			(stroke
				(width 0.1)
				(type default)
			)
			(layer "F.Fab")
		)
		(fp_line
			(start 0.12065 -0.2794)
			(end 0.12065 -0.3048)
			(stroke
				(width 0.1)
				(type default)
			)
			(layer "F.Fab")
		)
		(fp_line
			(start 0.67945 -0.3048)
			(end 0.67945 0.3048)
			(stroke
				(width 0.1)
				(type default)
			)
			(layer "F.Fab")
		)
		(fp_line
			(start 0.67945 0.3048)
			(end 0.120396 0.3048)
			(stroke
				(width 0.1)
				(type default)
			)
			(layer "F.Fab")
		)
		(pad "1" smd circle
			(at -0.40005 0)
			(size 0 0)
			(layers "F.Cu" "F.Mask" "F.Paste")
			(net "USB2_MICRO_DP")
		)
		(pad "2" smd circle
			(at 0.40005 0)
			(size 0 0)
			(layers "F.Cu" "F.Mask" "F.Paste")
			(net "USB2_FT4232_MUX_D_DP")
		)
	)
	(footprint ""
		(layer "F.Cu")
		(at 163.985702 -27.092148 -90)
		(property "Reference" "R5741"
			(at 0 0 270)
			(layer "F.SilkS")
			(hide yes)
			(effects
				(font
					(size 1.27 1.27)
				)
			)
		)
		(property "Value" ""
			(at 0 0 270)
			(layer "F.Fab")
			(effects
				(font
					(size 1.27 1.27)
				)
			)
		)
		(duplicate_pad_numbers_are_jumpers no)
		(fp_line
			(start -0.7874 0.4064)
			(end -0.7874 -0.4064)
			(stroke
				(width 0.1524)
				(type default)
			)
			(layer "F.SilkS")
		)
		(fp_line
			(start 0.7874 0.4064)
			(end -0.7874 0.4064)
			(stroke
				(width 0.1524)
				(type default)
			)
			(layer "F.SilkS")
		)
		(fp_line
			(start -0.7874 -0.4064)
			(end 0.7874 -0.4064)
			(stroke
				(width 0.1524)
				(type default)
			)
			(layer "F.SilkS")
		)
		(fp_line
			(start 0.7874 -0.4064)
			(end 0.7874 0.4064)
			(stroke
				(width 0.1524)
				(type default)
			)
			(layer "F.SilkS")
		)
		(fp_line
			(start -0.67945 0.3048)
			(end -0.67945 -0.305054)
			(stroke
				(width 0.1)
				(type default)
			)
			(layer "F.Fab")
		)
		(fp_line
			(start -0.12065 0.3048)
			(end -0.67945 0.3048)
			(stroke
				(width 0.1)
				(type default)
			)
			(layer "F.Fab")
		)
		(fp_line
			(start 0.120396 0.3048)
			(end 0.120396 0.2794)
			(stroke
				(width 0.1)
				(type default)
			)
			(layer "F.Fab")
		)
		(fp_line
			(start 0.67945 0.3048)
			(end 0.120396 0.3048)
			(stroke
				(width 0.1)
				(type default)
			)
			(layer "F.Fab")
		)
		(fp_line
			(start -0.12065 0.2794)
			(end -0.12065 0.3048)
			(stroke
				(width 0.1)
				(type default)
			)
			(layer "F.Fab")
		)
		(fp_line
			(start 0.120396 0.2794)
			(end -0.12065 0.2794)
			(stroke
				(width 0.1)
				(type default)
			)
			(layer "F.Fab")
		)
		(fp_line
			(start -0.12065 -0.2794)
			(end 0.12065 -0.2794)
			(stroke
				(width 0.1)
				(type default)
			)
			(layer "F.Fab")
		)
		(fp_line
			(start 0.12065 -0.2794)
			(end 0.12065 -0.3048)
			(stroke
				(width 0.1)
				(type default)
			)
			(layer "F.Fab")
		)
		(fp_line
			(start 0.12065 -0.3048)
			(end 0.67945 -0.3048)
			(stroke
				(width 0.1)
				(type default)
			)
			(layer "F.Fab")
		)
		(fp_line
			(start 0.67945 -0.3048)
			(end 0.67945 0.3048)
			(stroke
				(width 0.1)
				(type default)
			)
			(layer "F.Fab")
		)
		(fp_line
			(start -0.67945 -0.305054)
			(end -0.12065 -0.305054)
			(stroke
				(width 0.1)
				(type default)
			)
			(layer "F.Fab")
		)
		(fp_line
			(start -0.12065 -0.305054)
			(end -0.12065 -0.2794)
			(stroke
				(width 0.1)
				(type default)
			)
			(layer "F.Fab")
		)
		(pad "1" smd circle
			(at -0.40005 0 270)
			(size 0 0)
			(layers "F.Cu" "F.Mask" "F.Paste")
			(net "P3V3_SSD5")
		)
		(pad "2" smd circle
			(at 0.40005 0 270)
			(size 0 0)
			(layers "F.Cu" "F.Mask" "F.Paste")
			(net "SSD5_LED_ISO_N")
		)
	)
	(footprint ""
		(layer "F.Cu")
		(at 19.652488 -171.392596 90)
		(property "Reference" "PU4"
			(at -0.807466 1.632712 0)
			(unlocked yes)
			(layer "F.SilkS")
			(effects
				(font
					(size 0.7874 0.5842)
					(thickness 0.1524)
				)
				(justify left)
			)
		)
		(property "Value" ""
			(at 0 0 90)
			(layer "F.Fab")
			(effects
				(font
					(size 1.27 1.27)
				)
			)
		)
		(duplicate_pad_numbers_are_jumpers no)
		(fp_line
			(start 1.55829 -1.02489)
			(end -1.55829 -1.02489)
			(stroke
				(width 0.1524)
				(type default)
			)
			(layer "F.SilkS")
		)
		(fp_line
			(start -1.55829 -1.02489)
			(end -1.55829 1.02489)
			(stroke
				(width 0.1524)
				(type default)
			)
			(layer "F.SilkS")
		)
		(fp_line
			(start 1.55829 1.02489)
			(end 1.55829 -1.02489)
			(stroke
				(width 0.1524)
				(type default)
			)
			(layer "F.SilkS")
		)
		(fp_line
			(start -1.55829 1.02489)
			(end 1.55829 1.02489)
			(stroke
				(width 0.1524)
				(type default)
			)
			(layer "F.SilkS")
		)
		(fp_poly
			(pts
				(xy -1.243076 -1.110996) (xy -1.759712 -1.283208) (xy -1.415288 -1.627632)
			)
			(stroke
				(width 0)
				(type default)
			)
			(fill yes)
			(layer "F.SilkS")
		)
		(fp_line
			(start 1.02489 -1.02489)
			(end -1.02489 -1.02489)
			(stroke
				(width 0.1)
				(type default)
			)
			(layer "F.Fab")
		)
		(fp_line
			(start -1.02489 -1.02489)
			(end -1.02489 1.02489)
			(stroke
				(width 0.1)
				(type default)
			)
			(layer "F.Fab")
		)
		(fp_line
			(start 1.02489 1.02489)
			(end 1.02489 -1.02489)
			(stroke
				(width 0.1)
				(type default)
			)
			(layer "F.Fab")
		)
		(fp_line
			(start -1.02489 1.02489)
			(end 1.02489 1.02489)
			(stroke
				(width 0.1)
				(type default)
			)
			(layer "F.Fab")
		)
		(fp_poly
			(pts
				(xy -1.682496 -0.750062) (xy -2.279904 -0.451104) (xy -2.279904 -1.048766)
			)
			(stroke
				(width 0)
				(type default)
			)
			(fill yes)
			(layer "F.Fab")
		)
		(pad "1" smd rect
			(at -0.999998 -0.750062)
			(size 0.2794 0.8128)
			(layers "F.Cu" "F.Mask" "F.Paste")
			(net "SW_P5V_AUX_PH")
		)
		(pad "2" smd rect
			(at -0.999998 -0.249936)
			(size 0.2794 0.8128)
			(layers "F.Cu" "F.Mask" "F.Paste")
			(net "SW_P12V_P5V_AUX_FLT")
		)
		(pad "3" smd rect
			(at -0.999998 0.249936)
			(size 0.2794 0.8128)
			(layers "F.Cu" "F.Mask" "F.Paste")
			(net "SW_P5V_AUX_BT")
		)
		(pad "4" smd rect
			(at -0.999998 0.750062)
			(size 0.2794 0.8128)
			(layers "F.Cu" "F.Mask" "F.Paste")
			(net "P5V_AUX_EN")
		)
		(pad "5" smd rect
			(at 0.999998 0.750062)
			(size 0.2794 0.8128)
			(layers "F.Cu" "F.Mask" "F.Paste")
			(net "P5V_AUX_FB")
		)
		(pad "6" smd rect
			(at 0.999998 0.249936)
			(size 0.2794 0.8128)
			(layers "F.Cu" "F.Mask" "F.Paste")
			(net "PWRGD_P5V_AUX")
		)
		(pad "7" smd rect
			(at 0.999998 -0.249936)
			(size 0.2794 0.8128)
			(layers "F.Cu" "F.Mask" "F.Paste")
			(net "GND")
		)
		(pad "8" smd rect
			(at 0.999998 -0.750062)
			(size 0.2794 0.8128)
			(layers "F.Cu" "F.Mask" "F.Paste")
			(net "GND")
		)
		(pad "TH" smd rect
			(at 0 0 90)
			(size 0.7112 1.3208)
			(layers "F.Cu" "F.Mask" "F.Paste")
			(net "GND")
		)
		(zone
			(layer "F.Cu")
			(hatch none 0.5)
			(connect_pads
				(clearance 0)
			)
			(min_thickness 0.25)
			(keepout
				(tracks not_allowed)
				(vias allowed)
				(pads allowed)
				(copperpour not_allowed)
				(footprints allowed)
			)
			(placement
				(enabled no)
				(sheetname "")
			)
			(fill
				(thermal_gap 0.5)
				(thermal_bridge_width 0.5)
				(island_removal_mode 0)
			)
			(polygon
				(pts
					(xy 18.636488 -171.925996) (xy 20.668488 -171.925996) (xy 20.668488 -170.859196) (xy 18.636488 -170.859196)
					(xy 18.636488 -171.748196) (xy 18.941288 -171.748196) (xy 18.941288 -170.986196) (xy 20.363688 -170.986196)
					(xy 20.363688 -171.798996) (xy 18.941288 -171.798996) (xy 18.941288 -171.773596) (xy 18.636488 -171.773596)
				)
			)
		)
	)
	(footprint ""
		(layer "F.Cu")
		(at 284.467808 -55.083456)
		(property "Reference" "PC444"
			(at 0 0 0)
			(layer "F.SilkS")
			(hide yes)
			(effects
				(font
					(size 1.27 1.27)
				)
			)
		)
		(property "Value" ""
			(at 0 0 0)
			(layer "F.Fab")
			(effects
				(font
					(size 1.27 1.27)
				)
			)
		)
		(duplicate_pad_numbers_are_jumpers no)
		(fp_line
			(start -0.7874 -0.4064)
			(end 0.7874 -0.4064)
			(stroke
				(width 0.1524)
				(type default)
			)
			(layer "F.SilkS")
		)
		(fp_line
			(start -0.7874 0.4064)
			(end -0.7874 -0.4064)
			(stroke
				(width 0.1524)
				(type default)
			)
			(layer "F.SilkS")
		)
		(fp_line
			(start 0.7874 -0.4064)
			(end 0.7874 0.4064)
			(stroke
				(width 0.1524)
				(type default)
			)
			(layer "F.SilkS")
		)
		(fp_line
			(start 0.7874 0.4064)
			(end -0.7874 0.4064)
			(stroke
				(width 0.1524)
				(type default)
			)
			(layer "F.SilkS")
		)
		(fp_line
			(start -0.67945 -0.305054)
			(end -0.12065 -0.305054)
			(stroke
				(width 0.1)
				(type default)
			)
			(layer "F.Fab")
		)
		(fp_line
			(start -0.67945 0.3048)
			(end -0.67945 -0.305054)
			(stroke
				(width 0.1)
				(type default)
			)
			(layer "F.Fab")
		)
		(fp_line
			(start -0.12065 -0.305054)
			(end -0.12065 -0.2794)
			(stroke
				(width 0.1)
				(type default)
			)
			(layer "F.Fab")
		)
		(fp_line
			(start -0.12065 -0.2794)
			(end 0.12065 -0.2794)
			(stroke
				(width 0.1)
				(type default)
			)
			(layer "F.Fab")
		)
		(fp_line
			(start -0.12065 0.2794)
			(end -0.12065 0.3048)
			(stroke
				(width 0.1)
				(type default)
			)
			(layer "F.Fab")
		)
		(fp_line
			(start -0.12065 0.3048)
			(end -0.67945 0.3048)
			(stroke
				(width 0.1)
				(type default)
			)
			(layer "F.Fab")
		)
		(fp_line
			(start 0.120396 0.2794)
			(end -0.12065 0.2794)
			(stroke
				(width 0.1)
				(type default)
			)
			(layer "F.Fab")
		)
		(fp_line
			(start 0.120396 0.3048)
			(end 0.120396 0.2794)
			(stroke
				(width 0.1)
				(type default)
			)
			(layer "F.Fab")
		)
		(fp_line
			(start 0.12065 -0.3048)
			(end 0.67945 -0.3048)
			(stroke
				(width 0.1)
				(type default)
			)
			(layer "F.Fab")
		)
		(fp_line
			(start 0.12065 -0.2794)
			(end 0.12065 -0.3048)
			(stroke
				(width 0.1)
				(type default)
			)
			(layer "F.Fab")
		)
		(fp_line
			(start 0.67945 -0.3048)
			(end 0.67945 0.3048)
			(stroke
				(width 0.1)
				(type default)
			)
			(layer "F.Fab")
		)
		(fp_line
			(start 0.67945 0.3048)
			(end 0.120396 0.3048)
			(stroke
				(width 0.1)
				(type default)
			)
			(layer "F.Fab")
		)
		(pad "1" smd circle
			(at -0.40005 0)
			(size 0 0)
			(layers "F.Cu" "F.Mask" "F.Paste")
			(net "P5V_AUX")
		)
		(pad "2" smd circle
			(at 0.40005 0)
			(size 0 0)
			(layers "F.Cu" "F.Mask" "F.Paste")
			(net "GND")
		)
	)
	(footprint ""
		(layer "F.Cu")
		(at 6.196584 -14.04747 180)
		(property "Reference" "C3875"
			(at 0 0 180)
			(layer "F.SilkS")
			(hide yes)
			(effects
				(font
					(size 1.27 1.27)
				)
			)
		)
		(property "Value" ""
			(at 0 0 180)
			(layer "F.Fab")
			(effects
				(font
					(size 1.27 1.27)
				)
			)
		)
		(duplicate_pad_numbers_are_jumpers no)
		(fp_line
			(start 0.7874 0.4064)
			(end -0.7874 0.4064)
			(stroke
				(width 0.1524)
				(type default)
			)
			(layer "F.SilkS")
		)
		(fp_line
			(start 0.7874 -0.4064)
			(end 0.7874 0.4064)
			(stroke
				(width 0.1524)
				(type default)
			)
			(layer "F.SilkS")
		)
		(fp_line
			(start -0.7874 0.4064)
			(end -0.7874 -0.4064)
			(stroke
				(width 0.1524)
				(type default)
			)
			(layer "F.SilkS")
		)
		(fp_line
			(start -0.7874 -0.4064)
			(end 0.7874 -0.4064)
			(stroke
				(width 0.1524)
				(type default)
			)
			(layer "F.SilkS")
		)
		(fp_line
			(start 0.67945 0.3048)
			(end 0.120396 0.3048)
			(stroke
				(width 0.1)
				(type default)
			)
			(layer "F.Fab")
		)
		(fp_line
			(start 0.67945 -0.3048)
			(end 0.67945 0.3048)
			(stroke
				(width 0.1)
				(type default)
			)
			(layer "F.Fab")
		)
		(fp_line
			(start 0.12065 -0.2794)
			(end 0.12065 -0.3048)
			(stroke
				(width 0.1)
				(type default)
			)
			(layer "F.Fab")
		)
		(fp_line
			(start 0.12065 -0.3048)
			(end 0.67945 -0.3048)
			(stroke
				(width 0.1)
				(type default)
			)
			(layer "F.Fab")
		)
		(fp_line
			(start 0.120396 0.3048)
			(end 0.120396 0.2794)
			(stroke
				(width 0.1)
				(type default)
			)
			(layer "F.Fab")
		)
		(fp_line
			(start 0.120396 0.2794)
			(end -0.12065 0.2794)
			(stroke
				(width 0.1)
				(type default)
			)
			(layer "F.Fab")
		)
		(fp_line
			(start -0.12065 0.3048)
			(end -0.67945 0.3048)
			(stroke
				(width 0.1)
				(type default)
			)
			(layer "F.Fab")
		)
		(fp_line
			(start -0.12065 0.2794)
			(end -0.12065 0.3048)
			(stroke
				(width 0.1)
				(type default)
			)
			(layer "F.Fab")
		)
		(fp_line
			(start -0.12065 -0.2794)
			(end 0.12065 -0.2794)
			(stroke
				(width 0.1)
				(type default)
			)
			(layer "F.Fab")
		)
		(fp_line
			(start -0.12065 -0.305054)
			(end -0.12065 -0.2794)
			(stroke
				(width 0.1)
				(type default)
			)
			(layer "F.Fab")
		)
		(fp_line
			(start -0.67945 0.3048)
			(end -0.67945 -0.305054)
			(stroke
				(width 0.1)
				(type default)
			)
			(layer "F.Fab")
		)
		(fp_line
			(start -0.67945 -0.305054)
			(end -0.12065 -0.305054)
			(stroke
				(width 0.1)
				(type default)
			)
			(layer "F.Fab")
		)
		(pad "1" smd circle
			(at -0.40005 0 180)
			(size 0 0)
			(layers "F.Cu" "F.Mask" "F.Paste")
			(net "P12V_SSD0")
		)
		(pad "2" smd circle
			(at 0.40005 0 180)
			(size 0 0)
			(layers "F.Cu" "F.Mask" "F.Paste")
			(net "GND")
		)
	)
	(footprint ""
		(layer "F.Cu")
		(at 327.533 -213.233 180)
		(property "Reference" "R4154"
			(at 0 0 180)
			(layer "F.SilkS")
			(hide yes)
			(effects
				(font
					(size 1.27 1.27)
				)
			)
		)
		(property "Value" ""
			(at 0 0 180)
			(layer "F.Fab")
			(effects
				(font
					(size 1.27 1.27)
				)
			)
		)
		(duplicate_pad_numbers_are_jumpers no)
		(fp_line
			(start 0.7874 0.4064)
			(end -0.7874 0.4064)
			(stroke
				(width 0.1524)
				(type default)
			)
			(layer "F.SilkS")
		)
		(fp_line
			(start 0.7874 -0.4064)
			(end 0.7874 0.4064)
			(stroke
				(width 0.1524)
				(type default)
			)
			(layer "F.SilkS")
		)
		(fp_line
			(start -0.7874 0.4064)
			(end -0.7874 -0.4064)
			(stroke
				(width 0.1524)
				(type default)
			)
			(layer "F.SilkS")
		)
		(fp_line
			(start -0.7874 -0.4064)
			(end 0.7874 -0.4064)
			(stroke
				(width 0.1524)
				(type default)
			)
			(layer "F.SilkS")
		)
		(fp_line
			(start 0.67945 0.3048)
			(end 0.120396 0.3048)
			(stroke
				(width 0.1)
				(type default)
			)
			(layer "F.Fab")
		)
		(fp_line
			(start 0.67945 -0.3048)
			(end 0.67945 0.3048)
			(stroke
				(width 0.1)
				(type default)
			)
			(layer "F.Fab")
		)
		(fp_line
			(start 0.12065 -0.2794)
			(end 0.12065 -0.3048)
			(stroke
				(width 0.1)
				(type default)
			)
			(layer "F.Fab")
		)
		(fp_line
			(start 0.12065 -0.3048)
			(end 0.67945 -0.3048)
			(stroke
				(width 0.1)
				(type default)
			)
			(layer "F.Fab")
		)
		(fp_line
			(start 0.120396 0.3048)
			(end 0.120396 0.2794)
			(stroke
				(width 0.1)
				(type default)
			)
			(layer "F.Fab")
		)
		(fp_line
			(start 0.120396 0.2794)
			(end -0.12065 0.2794)
			(stroke
				(width 0.1)
				(type default)
			)
			(layer "F.Fab")
		)
		(fp_line
			(start -0.12065 0.3048)
			(end -0.67945 0.3048)
			(stroke
				(width 0.1)
				(type default)
			)
			(layer "F.Fab")
		)
		(fp_line
			(start -0.12065 0.2794)
			(end -0.12065 0.3048)
			(stroke
				(width 0.1)
				(type default)
			)
			(layer "F.Fab")
		)
		(fp_line
			(start -0.12065 -0.2794)
			(end 0.12065 -0.2794)
			(stroke
				(width 0.1)
				(type default)
			)
			(layer "F.Fab")
		)
		(fp_line
			(start -0.12065 -0.305054)
			(end -0.12065 -0.2794)
			(stroke
				(width 0.1)
				(type default)
			)
			(layer "F.Fab")
		)
		(fp_line
			(start -0.67945 0.3048)
			(end -0.67945 -0.305054)
			(stroke
				(width 0.1)
				(type default)
			)
			(layer "F.Fab")
		)
		(fp_line
			(start -0.67945 -0.305054)
			(end -0.12065 -0.305054)
			(stroke
				(width 0.1)
				(type default)
			)
			(layer "F.Fab")
		)
		(pad "1" smd circle
			(at -0.40005 0 180)
			(size 0 0)
			(layers "F.Cu" "F.Mask" "F.Paste")
			(net "PRSNT_SSD7_FPGA_N")
		)
		(pad "2" smd circle
			(at 0.40005 0 180)
			(size 0 0)
			(layers "F.Cu" "F.Mask" "F.Paste")
			(net "PRSNT_SSD7_FPGA_R_N")
		)
	)
	(footprint ""
		(layer "F.Cu")
		(at 338.074 -170.053 180)
		(property "Reference" "R4769"
			(at 0 0 180)
			(layer "F.SilkS")
			(hide yes)
			(effects
				(font
					(size 1.27 1.27)
				)
			)
		)
		(property "Value" ""
			(at 0 0 180)
			(layer "F.Fab")
			(effects
				(font
					(size 1.27 1.27)
				)
			)
		)
		(duplicate_pad_numbers_are_jumpers no)
		(fp_line
			(start 0.7874 0.4064)
			(end -0.7874 0.4064)
			(stroke
				(width 0.1524)
				(type default)
			)
			(layer "F.SilkS")
		)
		(fp_line
			(start 0.7874 -0.4064)
			(end 0.7874 0.4064)
			(stroke
				(width 0.1524)
				(type default)
			)
			(layer "F.SilkS")
		)
		(fp_line
			(start -0.7874 0.4064)
			(end -0.7874 -0.4064)
			(stroke
				(width 0.1524)
				(type default)
			)
			(layer "F.SilkS")
		)
		(fp_line
			(start -0.7874 -0.4064)
			(end 0.7874 -0.4064)
			(stroke
				(width 0.1524)
				(type default)
			)
			(layer "F.SilkS")
		)
		(fp_line
			(start 0.67945 0.3048)
			(end 0.120396 0.3048)
			(stroke
				(width 0.1)
				(type default)
			)
			(layer "F.Fab")
		)
		(fp_line
			(start 0.67945 -0.3048)
			(end 0.67945 0.3048)
			(stroke
				(width 0.1)
				(type default)
			)
			(layer "F.Fab")
		)
		(fp_line
			(start 0.12065 -0.2794)
			(end 0.12065 -0.3048)
			(stroke
				(width 0.1)
				(type default)
			)
			(layer "F.Fab")
		)
		(fp_line
			(start 0.12065 -0.3048)
			(end 0.67945 -0.3048)
			(stroke
				(width 0.1)
				(type default)
			)
			(layer "F.Fab")
		)
		(fp_line
			(start 0.120396 0.3048)
			(end 0.120396 0.2794)
			(stroke
				(width 0.1)
				(type default)
			)
			(layer "F.Fab")
		)
		(fp_line
			(start 0.120396 0.2794)
			(end -0.12065 0.2794)
			(stroke
				(width 0.1)
				(type default)
			)
			(layer "F.Fab")
		)
		(fp_line
			(start -0.12065 0.3048)
			(end -0.67945 0.3048)
			(stroke
				(width 0.1)
				(type default)
			)
			(layer "F.Fab")
		)
		(fp_line
			(start -0.12065 0.2794)
			(end -0.12065 0.3048)
			(stroke
				(width 0.1)
				(type default)
			)
			(layer "F.Fab")
		)
		(fp_line
			(start -0.12065 -0.2794)
			(end 0.12065 -0.2794)
			(stroke
				(width 0.1)
				(type default)
			)
			(layer "F.Fab")
		)
		(fp_line
			(start -0.12065 -0.305054)
			(end -0.12065 -0.2794)
			(stroke
				(width 0.1)
				(type default)
			)
			(layer "F.Fab")
		)
		(fp_line
			(start -0.67945 0.3048)
			(end -0.67945 -0.305054)
			(stroke
				(width 0.1)
				(type default)
			)
			(layer "F.Fab")
		)
		(fp_line
			(start -0.67945 -0.305054)
			(end -0.12065 -0.305054)
			(stroke
				(width 0.1)
				(type default)
			)
			(layer "F.Fab")
		)
		(pad "1" smd circle
			(at -0.40005 0 180)
			(size 0 0)
			(layers "F.Cu" "F.Mask" "F.Paste")
			(net "SSD10_PEX_PWR_EN")
		)
		(pad "2" smd circle
			(at 0.40005 0 180)
			(size 0 0)
			(layers "F.Cu" "F.Mask" "F.Paste")
			(net "SSD10_PEX_PWR_EN_R")
		)
	)
	(footprint ""
		(layer "F.Cu")
		(at 353.822 -179.578)
		(property "Reference" "R4759"
			(at 0 0 0)
			(layer "F.SilkS")
			(hide yes)
			(effects
				(font
					(size 1.27 1.27)
				)
			)
		)
		(property "Value" ""
			(at 0 0 0)
			(layer "F.Fab")
			(effects
				(font
					(size 1.27 1.27)
				)
			)
		)
		(duplicate_pad_numbers_are_jumpers no)
		(fp_line
			(start -0.7874 -0.4064)
			(end 0.7874 -0.4064)
			(stroke
				(width 0.1524)
				(type default)
			)
			(layer "F.SilkS")
		)
		(fp_line
			(start -0.7874 0.4064)
			(end -0.7874 -0.4064)
			(stroke
				(width 0.1524)
				(type default)
			)
			(layer "F.SilkS")
		)
		(fp_line
			(start 0.7874 -0.4064)
			(end 0.7874 0.4064)
			(stroke
				(width 0.1524)
				(type default)
			)
			(layer "F.SilkS")
		)
		(fp_line
			(start 0.7874 0.4064)
			(end -0.7874 0.4064)
			(stroke
				(width 0.1524)
				(type default)
			)
			(layer "F.SilkS")
		)
		(fp_line
			(start -0.67945 -0.305054)
			(end -0.12065 -0.305054)
			(stroke
				(width 0.1)
				(type default)
			)
			(layer "F.Fab")
		)
		(fp_line
			(start -0.67945 0.3048)
			(end -0.67945 -0.305054)
			(stroke
				(width 0.1)
				(type default)
			)
			(layer "F.Fab")
		)
		(fp_line
			(start -0.12065 -0.305054)
			(end -0.12065 -0.2794)
			(stroke
				(width 0.1)
				(type default)
			)
			(layer "F.Fab")
		)
		(fp_line
			(start -0.12065 -0.2794)
			(end 0.12065 -0.2794)
			(stroke
				(width 0.1)
				(type default)
			)
			(layer "F.Fab")
		)
		(fp_line
			(start -0.12065 0.2794)
			(end -0.12065 0.3048)
			(stroke
				(width 0.1)
				(type default)
			)
			(layer "F.Fab")
		)
		(fp_line
			(start -0.12065 0.3048)
			(end -0.67945 0.3048)
			(stroke
				(width 0.1)
				(type default)
			)
			(layer "F.Fab")
		)
		(fp_line
			(start 0.120396 0.2794)
			(end -0.12065 0.2794)
			(stroke
				(width 0.1)
				(type default)
			)
			(layer "F.Fab")
		)
		(fp_line
			(start 0.120396 0.3048)
			(end 0.120396 0.2794)
			(stroke
				(width 0.1)
				(type default)
			)
			(layer "F.Fab")
		)
		(fp_line
			(start 0.12065 -0.3048)
			(end 0.67945 -0.3048)
			(stroke
				(width 0.1)
				(type default)
			)
			(layer "F.Fab")
		)
		(fp_line
			(start 0.12065 -0.2794)
			(end 0.12065 -0.3048)
			(stroke
				(width 0.1)
				(type default)
			)
			(layer "F.Fab")
		)
		(fp_line
			(start 0.67945 -0.3048)
			(end 0.67945 0.3048)
			(stroke
				(width 0.1)
				(type default)
			)
			(layer "F.Fab")
		)
		(fp_line
			(start 0.67945 0.3048)
			(end 0.120396 0.3048)
			(stroke
				(width 0.1)
				(type default)
			)
			(layer "F.Fab")
		)
		(pad "1" smd circle
			(at -0.40005 0)
			(size 0 0)
			(layers "F.Cu" "F.Mask" "F.Paste")
			(net "RST_PEX_NIC4_PERST_N")
		)
		(pad "2" smd circle
			(at 0.40005 0)
			(size 0 0)
			(layers "F.Cu" "F.Mask" "F.Paste")
			(net "RST_PEX_NIC4_PERST_R_N")
		)
	)
	(footprint ""
		(layer "F.Cu")
		(at 326.007222 -235.075222 90)
		(property "Reference" "R4389"
			(at 0 0 90)
			(layer "F.SilkS")
			(hide yes)
			(effects
				(font
					(size 1.27 1.27)
				)
			)
		)
		(property "Value" ""
			(at 0 0 90)
			(layer "F.Fab")
			(effects
				(font
					(size 1.27 1.27)
				)
			)
		)
		(duplicate_pad_numbers_are_jumpers no)
		(fp_line
			(start 0.7874 -0.4064)
			(end 0.7874 0.4064)
			(stroke
				(width 0.1524)
				(type default)
			)
			(layer "F.SilkS")
		)
		(fp_line
			(start -0.7874 -0.4064)
			(end 0.7874 -0.4064)
			(stroke
				(width 0.1524)
				(type default)
			)
			(layer "F.SilkS")
		)
		(fp_line
			(start 0.7874 0.4064)
			(end -0.7874 0.4064)
			(stroke
				(width 0.1524)
				(type default)
			)
			(layer "F.SilkS")
		)
		(fp_line
			(start -0.7874 0.4064)
			(end -0.7874 -0.4064)
			(stroke
				(width 0.1524)
				(type default)
			)
			(layer "F.SilkS")
		)
		(fp_line
			(start -0.12065 -0.305054)
			(end -0.12065 -0.2794)
			(stroke
				(width 0.1)
				(type default)
			)
			(layer "F.Fab")
		)
		(fp_line
			(start -0.67945 -0.305054)
			(end -0.12065 -0.305054)
			(stroke
				(width 0.1)
				(type default)
			)
			(layer "F.Fab")
		)
		(fp_line
			(start 0.67945 -0.3048)
			(end 0.67945 0.3048)
			(stroke
				(width 0.1)
				(type default)
			)
			(layer "F.Fab")
		)
		(fp_line
			(start 0.12065 -0.3048)
			(end 0.67945 -0.3048)
			(stroke
				(width 0.1)
				(type default)
			)
			(layer "F.Fab")
		)
		(fp_line
			(start 0.12065 -0.2794)
			(end 0.12065 -0.3048)
			(stroke
				(width 0.1)
				(type default)
			)
			(layer "F.Fab")
		)
		(fp_line
			(start -0.12065 -0.2794)
			(end 0.12065 -0.2794)
			(stroke
				(width 0.1)
				(type default)
			)
			(layer "F.Fab")
		)
		(fp_line
			(start 0.120396 0.2794)
			(end -0.12065 0.2794)
			(stroke
				(width 0.1)
				(type default)
			)
			(layer "F.Fab")
		)
		(fp_line
			(start -0.12065 0.2794)
			(end -0.12065 0.3048)
			(stroke
				(width 0.1)
				(type default)
			)
			(layer "F.Fab")
		)
		(fp_line
			(start 0.67945 0.3048)
			(end 0.120396 0.3048)
			(stroke
				(width 0.1)
				(type default)
			)
			(layer "F.Fab")
		)
		(fp_line
			(start 0.120396 0.3048)
			(end 0.120396 0.2794)
			(stroke
				(width 0.1)
				(type default)
			)
			(layer "F.Fab")
		)
		(fp_line
			(start -0.12065 0.3048)
			(end -0.67945 0.3048)
			(stroke
				(width 0.1)
				(type default)
			)
			(layer "F.Fab")
		)
		(fp_line
			(start -0.67945 0.3048)
			(end -0.67945 -0.305054)
			(stroke
				(width 0.1)
				(type default)
			)
			(layer "F.Fab")
		)
		(pad "1" smd circle
			(at -0.40005 0 90)
			(size 0 0)
			(layers "F.Cu" "F.Mask" "F.Paste")
			(net "RST_PEX_SYS_BUF_R_N")
		)
		(pad "2" smd circle
			(at 0.40005 0 90)
			(size 0 0)
			(layers "F.Cu" "F.Mask" "F.Paste")
			(net "RST_PEX2_SYS_N")
		)
	)
	(footprint ""
		(layer "F.Cu")
		(at 304.473864 -72.766682 90)
		(property "Reference" "PR7081"
			(at 0 0 90)
			(layer "F.SilkS")
			(hide yes)
			(effects
				(font
					(size 1.27 1.27)
				)
			)
		)
		(property "Value" ""
			(at 0 0 90)
			(layer "F.Fab")
			(effects
				(font
					(size 1.27 1.27)
				)
			)
		)
		(duplicate_pad_numbers_are_jumpers no)
		(fp_line
			(start 0.7874 -0.4064)
			(end 0.7874 0.4064)
			(stroke
				(width 0.1524)
				(type default)
			)
			(layer "F.SilkS")
		)
		(fp_line
			(start -0.7874 -0.4064)
			(end 0.7874 -0.4064)
			(stroke
				(width 0.1524)
				(type default)
			)
			(layer "F.SilkS")
		)
		(fp_line
			(start 0.7874 0.4064)
			(end -0.7874 0.4064)
			(stroke
				(width 0.1524)
				(type default)
			)
			(layer "F.SilkS")
		)
		(fp_line
			(start -0.7874 0.4064)
			(end -0.7874 -0.4064)
			(stroke
				(width 0.1524)
				(type default)
			)
			(layer "F.SilkS")
		)
		(fp_line
			(start -0.12065 -0.305054)
			(end -0.12065 -0.2794)
			(stroke
				(width 0.1)
				(type default)
			)
			(layer "F.Fab")
		)
		(fp_line
			(start -0.67945 -0.305054)
			(end -0.12065 -0.305054)
			(stroke
				(width 0.1)
				(type default)
			)
			(layer "F.Fab")
		)
		(fp_line
			(start 0.67945 -0.3048)
			(end 0.67945 0.3048)
			(stroke
				(width 0.1)
				(type default)
			)
			(layer "F.Fab")
		)
		(fp_line
			(start 0.12065 -0.3048)
			(end 0.67945 -0.3048)
			(stroke
				(width 0.1)
				(type default)
			)
			(layer "F.Fab")
		)
		(fp_line
			(start 0.12065 -0.2794)
			(end 0.12065 -0.3048)
			(stroke
				(width 0.1)
				(type default)
			)
			(layer "F.Fab")
		)
		(fp_line
			(start -0.12065 -0.2794)
			(end 0.12065 -0.2794)
			(stroke
				(width 0.1)
				(type default)
			)
			(layer "F.Fab")
		)
		(fp_line
			(start 0.120396 0.2794)
			(end -0.12065 0.2794)
			(stroke
				(width 0.1)
				(type default)
			)
			(layer "F.Fab")
		)
		(fp_line
			(start -0.12065 0.2794)
			(end -0.12065 0.3048)
			(stroke
				(width 0.1)
				(type default)
			)
			(layer "F.Fab")
		)
		(fp_line
			(start 0.67945 0.3048)
			(end 0.120396 0.3048)
			(stroke
				(width 0.1)
				(type default)
			)
			(layer "F.Fab")
		)
		(fp_line
			(start 0.120396 0.3048)
			(end 0.120396 0.2794)
			(stroke
				(width 0.1)
				(type default)
			)
			(layer "F.Fab")
		)
		(fp_line
			(start -0.12065 0.3048)
			(end -0.67945 0.3048)
			(stroke
				(width 0.1)
				(type default)
			)
			(layer "F.Fab")
		)
		(fp_line
			(start -0.67945 0.3048)
			(end -0.67945 -0.305054)
			(stroke
				(width 0.1)
				(type default)
			)
			(layer "F.Fab")
		)
		(pad "1" smd circle
			(at -0.40005 0 90)
			(size 0 0)
			(layers "F.Cu" "F.Mask" "F.Paste")
			(net "P12V_SSD10_CO_MODE")
		)
		(pad "2" smd circle
			(at 0.40005 0 90)
			(size 0 0)
			(layers "F.Cu" "F.Mask" "F.Paste")
			(net "GND")
		)
	)
	(footprint ""
		(layer "F.Cu")
		(at 171.929044 -117.5512)
		(property "Reference" "R107"
			(at 0 0 0)
			(layer "F.SilkS")
			(hide yes)
			(effects
				(font
					(size 1.27 1.27)
				)
			)
		)
		(property "Value" ""
			(at 0 0 0)
			(layer "F.Fab")
			(effects
				(font
					(size 1.27 1.27)
				)
			)
		)
		(duplicate_pad_numbers_are_jumpers no)
		(fp_line
			(start -0.7874 -0.4064)
			(end 0.7874 -0.4064)
			(stroke
				(width 0.1524)
				(type default)
			)
			(layer "F.SilkS")
		)
		(fp_line
			(start -0.7874 0.4064)
			(end -0.7874 -0.4064)
			(stroke
				(width 0.1524)
				(type default)
			)
			(layer "F.SilkS")
		)
		(fp_line
			(start 0.7874 -0.4064)
			(end 0.7874 0.4064)
			(stroke
				(width 0.1524)
				(type default)
			)
			(layer "F.SilkS")
		)
		(fp_line
			(start 0.7874 0.4064)
			(end -0.7874 0.4064)
			(stroke
				(width 0.1524)
				(type default)
			)
			(layer "F.SilkS")
		)
		(fp_line
			(start -0.67945 -0.305054)
			(end -0.12065 -0.305054)
			(stroke
				(width 0.1)
				(type default)
			)
			(layer "F.Fab")
		)
		(fp_line
			(start -0.67945 0.3048)
			(end -0.67945 -0.305054)
			(stroke
				(width 0.1)
				(type default)
			)
			(layer "F.Fab")
		)
		(fp_line
			(start -0.12065 -0.305054)
			(end -0.12065 -0.2794)
			(stroke
				(width 0.1)
				(type default)
			)
			(layer "F.Fab")
		)
		(fp_line
			(start -0.12065 -0.2794)
			(end 0.12065 -0.2794)
			(stroke
				(width 0.1)
				(type default)
			)
			(layer "F.Fab")
		)
		(fp_line
			(start -0.12065 0.2794)
			(end -0.12065 0.3048)
			(stroke
				(width 0.1)
				(type default)
			)
			(layer "F.Fab")
		)
		(fp_line
			(start -0.12065 0.3048)
			(end -0.67945 0.3048)
			(stroke
				(width 0.1)
				(type default)
			)
			(layer "F.Fab")
		)
		(fp_line
			(start 0.120396 0.2794)
			(end -0.12065 0.2794)
			(stroke
				(width 0.1)
				(type default)
			)
			(layer "F.Fab")
		)
		(fp_line
			(start 0.120396 0.3048)
			(end 0.120396 0.2794)
			(stroke
				(width 0.1)
				(type default)
			)
			(layer "F.Fab")
		)
		(fp_line
			(start 0.12065 -0.3048)
			(end 0.67945 -0.3048)
			(stroke
				(width 0.1)
				(type default)
			)
			(layer "F.Fab")
		)
		(fp_line
			(start 0.12065 -0.2794)
			(end 0.12065 -0.3048)
			(stroke
				(width 0.1)
				(type default)
			)
			(layer "F.Fab")
		)
		(fp_line
			(start 0.67945 -0.3048)
			(end 0.67945 0.3048)
			(stroke
				(width 0.1)
				(type default)
			)
			(layer "F.Fab")
		)
		(fp_line
			(start 0.67945 0.3048)
			(end 0.120396 0.3048)
			(stroke
				(width 0.1)
				(type default)
			)
			(layer "F.Fab")
		)
		(pad "1" smd circle
			(at -0.40005 0)
			(size 0 0)
			(layers "F.Cu" "F.Mask" "F.Paste")
			(net "PRSNTB1_NIC2_N")
		)
		(pad "2" smd circle
			(at 0.40005 0)
			(size 0 0)
			(layers "F.Cu" "F.Mask" "F.Paste")
			(net "P3V3_AUX")
		)
	)
	(footprint ""
		(layer "F.Cu")
		(at 134.610856 -170.599862 90)
		(property "Reference" "R1095"
			(at 0 0 90)
			(layer "F.SilkS")
			(hide yes)
			(effects
				(font
					(size 1.27 1.27)
				)
			)
		)
		(property "Value" ""
			(at 0 0 90)
			(layer "F.Fab")
			(effects
				(font
					(size 1.27 1.27)
				)
			)
		)
		(duplicate_pad_numbers_are_jumpers no)
		(fp_line
			(start 0.7874 0.4064)
			(end -0.7874 0.4064)
			(stroke
				(width 0.1524)
				(type default)
			)
			(layer "F.SilkS")
		)
		(fp_line
			(start -0.12065 -0.305054)
			(end -0.12065 -0.2794)
			(stroke
				(width 0.1)
				(type default)
			)
			(layer "F.Fab")
		)
		(fp_line
			(start -0.67945 -0.305054)
			(end -0.12065 -0.305054)
			(stroke
				(width 0.1)
				(type default)
			)
			(layer "F.Fab")
		)
		(fp_line
			(start 0.67945 -0.3048)
			(end 0.67945 0.3048)
			(stroke
				(width 0.1)
				(type default)
			)
			(layer "F.Fab")
		)
		(fp_line
			(start 0.12065 -0.3048)
			(end 0.67945 -0.3048)
			(stroke
				(width 0.1)
				(type default)
			)
			(layer "F.Fab")
		)
		(fp_line
			(start 0.12065 -0.2794)
			(end 0.12065 -0.3048)
			(stroke
				(width 0.1)
				(type default)
			)
			(layer "F.Fab")
		)
		(fp_line
			(start -0.12065 -0.2794)
			(end 0.12065 -0.2794)
			(stroke
				(width 0.1)
				(type default)
			)
			(layer "F.Fab")
		)
		(fp_line
			(start 0.120396 0.2794)
			(end -0.12065 0.2794)
			(stroke
				(width 0.1)
				(type default)
			)
			(layer "F.Fab")
		)
		(fp_line
			(start -0.12065 0.2794)
			(end -0.12065 0.3048)
			(stroke
				(width 0.1)
				(type default)
			)
			(layer "F.Fab")
		)
		(fp_line
			(start 0.67945 0.3048)
			(end 0.120396 0.3048)
			(stroke
				(width 0.1)
				(type default)
			)
			(layer "F.Fab")
		)
		(fp_line
			(start 0.120396 0.3048)
			(end 0.120396 0.2794)
			(stroke
				(width 0.1)
				(type default)
			)
			(layer "F.Fab")
		)
		(fp_line
			(start -0.12065 0.3048)
			(end -0.67945 0.3048)
			(stroke
				(width 0.1)
				(type default)
			)
			(layer "F.Fab")
		)
		(fp_line
			(start -0.67945 0.3048)
			(end -0.67945 -0.305054)
			(stroke
				(width 0.1)
				(type default)
			)
			(layer "F.Fab")
		)
		(pad "1" smd circle
			(at -0.40005 0 90)
			(size 0 0)
			(layers "F.Cu" "F.Mask" "F.Paste")
			(net "CLK_100M_DB2000QL_NIC0_R_DN")
		)
		(pad "2" smd circle
			(at 0.40005 0 90)
			(size 0 0)
			(layers "F.Cu" "F.Mask" "F.Paste")
			(net "CLK_100M_DB2000QL_NIC0_DN")
		)
	)
	(footprint ""
		(layer "F.Cu")
		(at 447.166238 -95.263716 -90)
		(property "Reference" "PC336"
			(at 0 0 270)
			(layer "F.SilkS")
			(hide yes)
			(effects
				(font
					(size 1.27 1.27)
				)
			)
		)
		(property "Value" ""
			(at 0 0 270)
			(layer "F.Fab")
			(effects
				(font
					(size 1.27 1.27)
				)
			)
		)
		(duplicate_pad_numbers_are_jumpers no)
		(fp_line
			(start -0.7874 0.4064)
			(end -0.7874 -0.4064)
			(stroke
				(width 0.1524)
				(type default)
			)
			(layer "F.SilkS")
		)
		(fp_line
			(start 0.7874 0.4064)
			(end -0.7874 0.4064)
			(stroke
				(width 0.1524)
				(type default)
			)
			(layer "F.SilkS")
		)
		(fp_line
			(start -0.7874 -0.4064)
			(end 0.7874 -0.4064)
			(stroke
				(width 0.1524)
				(type default)
			)
			(layer "F.SilkS")
		)
		(fp_line
			(start 0.7874 -0.4064)
			(end 0.7874 0.4064)
			(stroke
				(width 0.1524)
				(type default)
			)
			(layer "F.SilkS")
		)
		(fp_line
			(start -0.67945 0.3048)
			(end -0.67945 -0.305054)
			(stroke
				(width 0.1)
				(type default)
			)
			(layer "F.Fab")
		)
		(fp_line
			(start -0.12065 0.3048)
			(end -0.67945 0.3048)
			(stroke
				(width 0.1)
				(type default)
			)
			(layer "F.Fab")
		)
		(fp_line
			(start 0.120396 0.3048)
			(end 0.120396 0.2794)
			(stroke
				(width 0.1)
				(type default)
			)
			(layer "F.Fab")
		)
		(fp_line
			(start 0.67945 0.3048)
			(end 0.120396 0.3048)
			(stroke
				(width 0.1)
				(type default)
			)
			(layer "F.Fab")
		)
		(fp_line
			(start -0.12065 0.2794)
			(end -0.12065 0.3048)
			(stroke
				(width 0.1)
				(type default)
			)
			(layer "F.Fab")
		)
		(fp_line
			(start 0.120396 0.2794)
			(end -0.12065 0.2794)
			(stroke
				(width 0.1)
				(type default)
			)
			(layer "F.Fab")
		)
		(fp_line
			(start -0.12065 -0.2794)
			(end 0.12065 -0.2794)
			(stroke
				(width 0.1)
				(type default)
			)
			(layer "F.Fab")
		)
		(fp_line
			(start 0.12065 -0.2794)
			(end 0.12065 -0.3048)
			(stroke
				(width 0.1)
				(type default)
			)
			(layer "F.Fab")
		)
		(fp_line
			(start 0.12065 -0.3048)
			(end 0.67945 -0.3048)
			(stroke
				(width 0.1)
				(type default)
			)
			(layer "F.Fab")
		)
		(fp_line
			(start 0.67945 -0.3048)
			(end 0.67945 0.3048)
			(stroke
				(width 0.1)
				(type default)
			)
			(layer "F.Fab")
		)
		(fp_line
			(start -0.67945 -0.305054)
			(end -0.12065 -0.305054)
			(stroke
				(width 0.1)
				(type default)
			)
			(layer "F.Fab")
		)
		(fp_line
			(start -0.12065 -0.305054)
			(end -0.12065 -0.2794)
			(stroke
				(width 0.1)
				(type default)
			)
			(layer "F.Fab")
		)
		(pad "1" smd circle
			(at -0.40005 0 270)
			(size 0 0)
			(layers "F.Cu" "F.Mask" "F.Paste")
			(net "P5V_AUX")
		)
		(pad "2" smd circle
			(at 0.40005 0 270)
			(size 0 0)
			(layers "F.Cu" "F.Mask" "F.Paste")
			(net "GND")
		)
	)
	(footprint ""
		(layer "F.Cu")
		(at 230.660956 -86.833456 -90)
		(property "Reference" "R1008"
			(at 0 0 270)
			(layer "F.SilkS")
			(hide yes)
			(effects
				(font
					(size 1.27 1.27)
				)
			)
		)
		(property "Value" ""
			(at 0 0 270)
			(layer "F.Fab")
			(effects
				(font
					(size 1.27 1.27)
				)
			)
		)
		(duplicate_pad_numbers_are_jumpers no)
		(fp_line
			(start -0.7874 -0.4064)
			(end 0.7874 -0.4064)
			(stroke
				(width 0.1524)
				(type default)
			)
			(layer "F.SilkS")
		)
		(fp_line
			(start -0.67945 0.3048)
			(end -0.67945 -0.305054)
			(stroke
				(width 0.1)
				(type default)
			)
			(layer "F.Fab")
		)
		(fp_line
			(start -0.12065 0.3048)
			(end -0.67945 0.3048)
			(stroke
				(width 0.1)
				(type default)
			)
			(layer "F.Fab")
		)
		(fp_line
			(start 0.120396 0.3048)
			(end 0.120396 0.2794)
			(stroke
				(width 0.1)
				(type default)
			)
			(layer "F.Fab")
		)
		(fp_line
			(start 0.67945 0.3048)
			(end 0.120396 0.3048)
			(stroke
				(width 0.1)
				(type default)
			)
			(layer "F.Fab")
		)
		(fp_line
			(start -0.12065 0.2794)
			(end -0.12065 0.3048)
			(stroke
				(width 0.1)
				(type default)
			)
			(layer "F.Fab")
		)
		(fp_line
			(start 0.120396 0.2794)
			(end -0.12065 0.2794)
			(stroke
				(width 0.1)
				(type default)
			)
			(layer "F.Fab")
		)
		(fp_line
			(start -0.12065 -0.2794)
			(end 0.12065 -0.2794)
			(stroke
				(width 0.1)
				(type default)
			)
			(layer "F.Fab")
		)
		(fp_line
			(start 0.12065 -0.2794)
			(end 0.12065 -0.3048)
			(stroke
				(width 0.1)
				(type default)
			)
			(layer "F.Fab")
		)
		(fp_line
			(start 0.12065 -0.3048)
			(end 0.67945 -0.3048)
			(stroke
				(width 0.1)
				(type default)
			)
			(layer "F.Fab")
		)
		(fp_line
			(start 0.67945 -0.3048)
			(end 0.67945 0.3048)
			(stroke
				(width 0.1)
				(type default)
			)
			(layer "F.Fab")
		)
		(fp_line
			(start -0.67945 -0.305054)
			(end -0.12065 -0.305054)
			(stroke
				(width 0.1)
				(type default)
			)
			(layer "F.Fab")
		)
		(fp_line
			(start -0.12065 -0.305054)
			(end -0.12065 -0.2794)
			(stroke
				(width 0.1)
				(type default)
			)
			(layer "F.Fab")
		)
		(pad "1" smd circle
			(at -0.40005 0 270)
			(size 0 0)
			(layers "F.Cu" "F.Mask" "F.Paste")
			(net "USB2_PEX_HUB_R_DP")
		)
		(pad "2" smd circle
			(at 0.40005 0 270)
			(size 0 0)
			(layers "F.Cu" "F.Mask" "F.Paste")
			(net "USB2_PEX_HUB_DP")
		)
	)
	(footprint ""
		(layer "F.Cu")
		(at 95.105728 -238.753904)
		(property "Reference" "R5627"
			(at 0 0 0)
			(layer "F.SilkS")
			(hide yes)
			(effects
				(font
					(size 1.27 1.27)
				)
			)
		)
		(property "Value" ""
			(at 0 0 0)
			(layer "F.Fab")
			(effects
				(font
					(size 1.27 1.27)
				)
			)
		)
		(duplicate_pad_numbers_are_jumpers no)
		(fp_line
			(start -0.7874 -0.4064)
			(end 0.7874 -0.4064)
			(stroke
				(width 0.1524)
				(type default)
			)
			(layer "F.SilkS")
		)
		(fp_line
			(start -0.7874 0.4064)
			(end -0.7874 -0.4064)
			(stroke
				(width 0.1524)
				(type default)
			)
			(layer "F.SilkS")
		)
		(fp_line
			(start 0.7874 -0.4064)
			(end 0.7874 0.4064)
			(stroke
				(width 0.1524)
				(type default)
			)
			(layer "F.SilkS")
		)
		(fp_line
			(start 0.7874 0.4064)
			(end -0.7874 0.4064)
			(stroke
				(width 0.1524)
				(type default)
			)
			(layer "F.SilkS")
		)
		(fp_line
			(start -0.67945 -0.305054)
			(end -0.12065 -0.305054)
			(stroke
				(width 0.1)
				(type default)
			)
			(layer "F.Fab")
		)
		(fp_line
			(start -0.67945 0.3048)
			(end -0.67945 -0.305054)
			(stroke
				(width 0.1)
				(type default)
			)
			(layer "F.Fab")
		)
		(fp_line
			(start -0.12065 -0.305054)
			(end -0.12065 -0.2794)
			(stroke
				(width 0.1)
				(type default)
			)
			(layer "F.Fab")
		)
		(fp_line
			(start -0.12065 -0.2794)
			(end 0.12065 -0.2794)
			(stroke
				(width 0.1)
				(type default)
			)
			(layer "F.Fab")
		)
		(fp_line
			(start -0.12065 0.2794)
			(end -0.12065 0.3048)
			(stroke
				(width 0.1)
				(type default)
			)
			(layer "F.Fab")
		)
		(fp_line
			(start -0.12065 0.3048)
			(end -0.67945 0.3048)
			(stroke
				(width 0.1)
				(type default)
			)
			(layer "F.Fab")
		)
		(fp_line
			(start 0.120396 0.2794)
			(end -0.12065 0.2794)
			(stroke
				(width 0.1)
				(type default)
			)
			(layer "F.Fab")
		)
		(fp_line
			(start 0.120396 0.3048)
			(end 0.120396 0.2794)
			(stroke
				(width 0.1)
				(type default)
			)
			(layer "F.Fab")
		)
		(fp_line
			(start 0.12065 -0.3048)
			(end 0.67945 -0.3048)
			(stroke
				(width 0.1)
				(type default)
			)
			(layer "F.Fab")
		)
		(fp_line
			(start 0.12065 -0.2794)
			(end 0.12065 -0.3048)
			(stroke
				(width 0.1)
				(type default)
			)
			(layer "F.Fab")
		)
		(fp_line
			(start 0.67945 -0.3048)
			(end 0.67945 0.3048)
			(stroke
				(width 0.1)
				(type default)
			)
			(layer "F.Fab")
		)
		(fp_line
			(start 0.67945 0.3048)
			(end 0.120396 0.3048)
			(stroke
				(width 0.1)
				(type default)
			)
			(layer "F.Fab")
		)
		(pad "1" smd circle
			(at -0.40005 0)
			(size 0 0)
			(layers "F.Cu" "F.Mask" "F.Paste")
			(net "PEX_P1V8_ADC_A1")
		)
		(pad "2" smd circle
			(at 0.40005 0)
			(size 0 0)
			(layers "F.Cu" "F.Mask" "F.Paste")
			(net "SMB_PEX_P1V8_ADC_SCL")
		)
	)
	(footprint ""
		(layer "F.Cu")
		(at 447.323718 -106.413808 180)
		(property "Reference" "PD19"
			(at 4.425442 2.137156 0)
			(unlocked yes)
			(layer "F.SilkS")
			(effects
				(font
					(size 0.7874 0.5842)
					(thickness 0.1524)
				)
				(justify left)
			)
		)
		(property "Value" ""
			(at 0 0 180)
			(layer "F.Fab")
			(effects
				(font
					(size 1.27 1.27)
				)
			)
		)
		(duplicate_pad_numbers_are_jumpers no)
		(fp_line
			(start 4.107942 1.459992)
			(end -3.400044 1.459992)
			(stroke
				(width 0.1524)
				(type default)
			)
			(layer "F.SilkS")
		)
		(fp_line
			(start 4.107942 -1.459992)
			(end 4.107942 1.459992)
			(stroke
				(width 0.1524)
				(type default)
			)
			(layer "F.SilkS")
		)
		(fp_line
			(start -3.400044 1.459992)
			(end -3.400044 -1.459992)
			(stroke
				(width 0.1524)
				(type default)
			)
			(layer "F.SilkS")
		)
		(fp_line
			(start -3.400044 -1.459992)
			(end 4.107942 -1.459992)
			(stroke
				(width 0.1524)
				(type default)
			)
			(layer "F.SilkS")
		)
		(fp_rect
			(start 4.107942 -1.459992)
			(end 3.308096 1.459992)
			(stroke
				(width 0)
				(type default)
			)
			(fill yes)
			(layer "F.SilkS")
		)
		(fp_line
			(start 2.29997 1.459992)
			(end -2.29997 1.459992)
			(stroke
				(width 0.1)
				(type default)
			)
			(layer "F.Fab")
		)
		(fp_line
			(start 2.29997 -1.459992)
			(end 2.29997 1.459992)
			(stroke
				(width 0.1)
				(type default)
			)
			(layer "F.Fab")
		)
		(fp_line
			(start -2.29997 1.459992)
			(end -2.29997 -1.459992)
			(stroke
				(width 0.1)
				(type default)
			)
			(layer "F.Fab")
		)
		(fp_line
			(start -2.29997 -1.459992)
			(end 2.29997 -1.459992)
			(stroke
				(width 0.1)
				(type default)
			)
			(layer "F.Fab")
		)
		(fp_text user "-"
			(at 3.91033 -1.53035 0)
			(unlocked yes)
			(layer "F.SilkS")
			(effects
				(font
					(size 1.905 1.4224)
					(thickness 0.1524)
				)
				(justify left)
			)
		)
		(fp_text user "+"
			(at -3.27533 -2.242058 180)
			(unlocked yes)
			(layer "F.SilkS")
			(effects
				(font
					(size 1.905 1.4224)
					(thickness 0.1524)
				)
				(justify left)
			)
		)
		(fp_text user "-"
			(at 5.4102 0.29845 0)
			(unlocked yes)
			(layer "F.Fab")
			(effects
				(font
					(size 1.905 1.4224)
					(thickness 0.1524)
				)
				(justify left)
			)
		)
		(fp_text user "+"
			(at -4.7752 -0.12065 180)
			(unlocked yes)
			(layer "F.Fab")
			(effects
				(font
					(size 1.905 1.4224)
					(thickness 0.1524)
				)
				(justify left)
			)
		)
		(pad "A" smd rect
			(at -1.999996 0 270)
			(size 1.7018 2.5146)
			(layers "F.Cu" "F.Mask" "F.Paste")
			(net "GND")
		)
		(pad "C" smd rect
			(at 1.999996 0 270)
			(size 1.7018 2.5146)
			(layers "F.Cu" "F.Mask" "F.Paste")
			(net "P12V_NIC7_R")
		)
	)
	(footprint ""
		(layer "F.Cu")
		(at 360.213656 -393.247118)
		(property "Reference" "R6700"
			(at 0 0 0)
			(layer "F.SilkS")
			(hide yes)
			(effects
				(font
					(size 1.27 1.27)
				)
			)
		)
		(property "Value" ""
			(at 0 0 0)
			(layer "F.Fab")
			(effects
				(font
					(size 1.27 1.27)
				)
			)
		)
		(duplicate_pad_numbers_are_jumpers no)
		(fp_line
			(start -0.7874 -0.4064)
			(end 0.7874 -0.4064)
			(stroke
				(width 0.1524)
				(type default)
			)
			(layer "F.SilkS")
		)
		(fp_line
			(start -0.7874 0.4064)
			(end -0.7874 -0.4064)
			(stroke
				(width 0.1524)
				(type default)
			)
			(layer "F.SilkS")
		)
		(fp_line
			(start 0.7874 -0.4064)
			(end 0.7874 0.4064)
			(stroke
				(width 0.1524)
				(type default)
			)
			(layer "F.SilkS")
		)
		(fp_line
			(start 0.7874 0.4064)
			(end -0.7874 0.4064)
			(stroke
				(width 0.1524)
				(type default)
			)
			(layer "F.SilkS")
		)
		(fp_line
			(start -0.67945 -0.305054)
			(end -0.12065 -0.305054)
			(stroke
				(width 0.1)
				(type default)
			)
			(layer "F.Fab")
		)
		(fp_line
			(start -0.67945 0.3048)
			(end -0.67945 -0.305054)
			(stroke
				(width 0.1)
				(type default)
			)
			(layer "F.Fab")
		)
		(fp_line
			(start -0.12065 -0.305054)
			(end -0.12065 -0.2794)
			(stroke
				(width 0.1)
				(type default)
			)
			(layer "F.Fab")
		)
		(fp_line
			(start -0.12065 -0.2794)
			(end 0.12065 -0.2794)
			(stroke
				(width 0.1)
				(type default)
			)
			(layer "F.Fab")
		)
		(fp_line
			(start -0.12065 0.2794)
			(end -0.12065 0.3048)
			(stroke
				(width 0.1)
				(type default)
			)
			(layer "F.Fab")
		)
		(fp_line
			(start -0.12065 0.3048)
			(end -0.67945 0.3048)
			(stroke
				(width 0.1)
				(type default)
			)
			(layer "F.Fab")
		)
		(fp_line
			(start 0.120396 0.2794)
			(end -0.12065 0.2794)
			(stroke
				(width 0.1)
				(type default)
			)
			(layer "F.Fab")
		)
		(fp_line
			(start 0.120396 0.3048)
			(end 0.120396 0.2794)
			(stroke
				(width 0.1)
				(type default)
			)
			(layer "F.Fab")
		)
		(fp_line
			(start 0.12065 -0.3048)
			(end 0.67945 -0.3048)
			(stroke
				(width 0.1)
				(type default)
			)
			(layer "F.Fab")
		)
		(fp_line
			(start 0.12065 -0.2794)
			(end 0.12065 -0.3048)
			(stroke
				(width 0.1)
				(type default)
			)
			(layer "F.Fab")
		)
		(fp_line
			(start 0.67945 -0.3048)
			(end 0.67945 0.3048)
			(stroke
				(width 0.1)
				(type default)
			)
			(layer "F.Fab")
		)
		(fp_line
			(start 0.67945 0.3048)
			(end 0.120396 0.3048)
			(stroke
				(width 0.1)
				(type default)
			)
			(layer "F.Fab")
		)
		(pad "1" smd circle
			(at -0.40005 0)
			(size 0 0)
			(layers "F.Cu" "F.Mask" "F.Paste")
			(net "MB_3V3IO_RSVD1_ISO")
		)
		(pad "2" smd circle
			(at 0.40005 0)
			(size 0 0)
			(layers "F.Cu" "F.Mask" "F.Paste")
			(net "MB_3V3IO_RSVD1")
		)
	)
	(footprint ""
		(layer "F.Cu")
		(at 268.402816 -93.542104)
		(property "Reference" "R1054"
			(at 0 0 0)
			(layer "F.SilkS")
			(hide yes)
			(effects
				(font
					(size 1.27 1.27)
				)
			)
		)
		(property "Value" ""
			(at 0 0 0)
			(layer "F.Fab")
			(effects
				(font
					(size 1.27 1.27)
				)
			)
		)
		(duplicate_pad_numbers_are_jumpers no)
		(fp_line
			(start -0.7874 -0.4064)
			(end 0.7874 -0.4064)
			(stroke
				(width 0.1524)
				(type default)
			)
			(layer "F.SilkS")
		)
		(fp_line
			(start -0.7874 0.4064)
			(end -0.7874 -0.4064)
			(stroke
				(width 0.1524)
				(type default)
			)
			(layer "F.SilkS")
		)
		(fp_line
			(start 0.7874 -0.4064)
			(end 0.7874 0.4064)
			(stroke
				(width 0.1524)
				(type default)
			)
			(layer "F.SilkS")
		)
		(fp_line
			(start 0.7874 0.4064)
			(end -0.7874 0.4064)
			(stroke
				(width 0.1524)
				(type default)
			)
			(layer "F.SilkS")
		)
		(fp_line
			(start -0.67945 -0.305054)
			(end -0.12065 -0.305054)
			(stroke
				(width 0.1)
				(type default)
			)
			(layer "F.Fab")
		)
		(fp_line
			(start -0.67945 0.3048)
			(end -0.67945 -0.305054)
			(stroke
				(width 0.1)
				(type default)
			)
			(layer "F.Fab")
		)
		(fp_line
			(start -0.12065 -0.305054)
			(end -0.12065 -0.2794)
			(stroke
				(width 0.1)
				(type default)
			)
			(layer "F.Fab")
		)
		(fp_line
			(start -0.12065 -0.2794)
			(end 0.12065 -0.2794)
			(stroke
				(width 0.1)
				(type default)
			)
			(layer "F.Fab")
		)
		(fp_line
			(start -0.12065 0.2794)
			(end -0.12065 0.3048)
			(stroke
				(width 0.1)
				(type default)
			)
			(layer "F.Fab")
		)
		(fp_line
			(start -0.12065 0.3048)
			(end -0.67945 0.3048)
			(stroke
				(width 0.1)
				(type default)
			)
			(layer "F.Fab")
		)
		(fp_line
			(start 0.120396 0.2794)
			(end -0.12065 0.2794)
			(stroke
				(width 0.1)
				(type default)
			)
			(layer "F.Fab")
		)
		(fp_line
			(start 0.120396 0.3048)
			(end 0.120396 0.2794)
			(stroke
				(width 0.1)
				(type default)
			)
			(layer "F.Fab")
		)
		(fp_line
			(start 0.12065 -0.3048)
			(end 0.67945 -0.3048)
			(stroke
				(width 0.1)
				(type default)
			)
			(layer "F.Fab")
		)
		(fp_line
			(start 0.12065 -0.2794)
			(end 0.12065 -0.3048)
			(stroke
				(width 0.1)
				(type default)
			)
			(layer "F.Fab")
		)
		(fp_line
			(start 0.67945 -0.3048)
			(end 0.67945 0.3048)
			(stroke
				(width 0.1)
				(type default)
			)
			(layer "F.Fab")
		)
		(fp_line
			(start 0.67945 0.3048)
			(end 0.120396 0.3048)
			(stroke
				(width 0.1)
				(type default)
			)
			(layer "F.Fab")
		)
		(pad "1" smd circle
			(at -0.40005 0)
			(size 0 0)
			(layers "F.Cu" "F.Mask" "F.Paste")
			(net "PU_CK440_SHFT_LD_N")
		)
		(pad "2" smd circle
			(at 0.40005 0)
			(size 0 0)
			(layers "F.Cu" "F.Mask" "F.Paste")
			(net "P3V3")
		)
	)
	(footprint ""
		(layer "F.Cu")
		(at 252.350016 -297.369992)
		(property "Reference" "H141"
			(at -1.56845 -4.033774 0)
			(unlocked yes)
			(layer "F.SilkS")
			(effects
				(font
					(size 0.7874 0.5842)
					(thickness 0.1524)
				)
				(justify left)
			)
		)
		(property "Value" ""
			(at 0 0 0)
			(layer "F.Fab")
			(effects
				(font
					(size 1.27 1.27)
				)
			)
		)
		(duplicate_pad_numbers_are_jumpers no)
		(pad "1" thru_hole circle
			(at 0 0)
			(size 6.5024 6.5024)
			(drill 3.2004)
			(layers "*.Cu" "*.Mask")
			(remove_unused_layers no)
			(net "GND")
			(clearance -1.397)
		)
	)
	(footprint ""
		(layer "F.Cu")
		(at 123.71324 -134.042404)
		(property "Reference" "R4452"
			(at 0 0 0)
			(layer "F.SilkS")
			(hide yes)
			(effects
				(font
					(size 1.27 1.27)
				)
			)
		)
		(property "Value" ""
			(at 0 0 0)
			(layer "F.Fab")
			(effects
				(font
					(size 1.27 1.27)
				)
			)
		)
		(duplicate_pad_numbers_are_jumpers no)
		(fp_line
			(start -0.7874 -0.4064)
			(end 0.7874 -0.4064)
			(stroke
				(width 0.1524)
				(type default)
			)
			(layer "F.SilkS")
		)
		(fp_line
			(start -0.7874 0.4064)
			(end -0.7874 -0.4064)
			(stroke
				(width 0.1524)
				(type default)
			)
			(layer "F.SilkS")
		)
		(fp_line
			(start 0.7874 -0.4064)
			(end 0.7874 0.4064)
			(stroke
				(width 0.1524)
				(type default)
			)
			(layer "F.SilkS")
		)
		(fp_line
			(start 0.7874 0.4064)
			(end -0.7874 0.4064)
			(stroke
				(width 0.1524)
				(type default)
			)
			(layer "F.SilkS")
		)
		(fp_line
			(start -0.67945 -0.305054)
			(end -0.12065 -0.305054)
			(stroke
				(width 0.1)
				(type default)
			)
			(layer "F.Fab")
		)
		(fp_line
			(start -0.67945 0.3048)
			(end -0.67945 -0.305054)
			(stroke
				(width 0.1)
				(type default)
			)
			(layer "F.Fab")
		)
		(fp_line
			(start -0.12065 -0.305054)
			(end -0.12065 -0.2794)
			(stroke
				(width 0.1)
				(type default)
			)
			(layer "F.Fab")
		)
		(fp_line
			(start -0.12065 -0.2794)
			(end 0.12065 -0.2794)
			(stroke
				(width 0.1)
				(type default)
			)
			(layer "F.Fab")
		)
		(fp_line
			(start -0.12065 0.2794)
			(end -0.12065 0.3048)
			(stroke
				(width 0.1)
				(type default)
			)
			(layer "F.Fab")
		)
		(fp_line
			(start -0.12065 0.3048)
			(end -0.67945 0.3048)
			(stroke
				(width 0.1)
				(type default)
			)
			(layer "F.Fab")
		)
		(fp_line
			(start 0.120396 0.2794)
			(end -0.12065 0.2794)
			(stroke
				(width 0.1)
				(type default)
			)
			(layer "F.Fab")
		)
		(fp_line
			(start 0.120396 0.3048)
			(end 0.120396 0.2794)
			(stroke
				(width 0.1)
				(type default)
			)
			(layer "F.Fab")
		)
		(fp_line
			(start 0.12065 -0.3048)
			(end 0.67945 -0.3048)
			(stroke
				(width 0.1)
				(type default)
			)
			(layer "F.Fab")
		)
		(fp_line
			(start 0.12065 -0.2794)
			(end 0.12065 -0.3048)
			(stroke
				(width 0.1)
				(type default)
			)
			(layer "F.Fab")
		)
		(fp_line
			(start 0.67945 -0.3048)
			(end 0.67945 0.3048)
			(stroke
				(width 0.1)
				(type default)
			)
			(layer "F.Fab")
		)
		(fp_line
			(start 0.67945 0.3048)
			(end 0.120396 0.3048)
			(stroke
				(width 0.1)
				(type default)
			)
			(layer "F.Fab")
		)
		(pad "1" smd circle
			(at -0.40005 0)
			(size 0 0)
			(layers "F.Cu" "F.Mask" "F.Paste")
			(net "HP_NIC2_EN")
		)
		(pad "2" smd circle
			(at 0.40005 0)
			(size 0 0)
			(layers "F.Cu" "F.Mask" "F.Paste")
			(net "P12V_NIC2_EN_R")
		)
	)
	(footprint ""
		(layer "F.Cu")
		(at 114.802158 -161.106866)
		(property "Reference" "PC39"
			(at 0 0 0)
			(layer "F.SilkS")
			(hide yes)
			(effects
				(font
					(size 1.27 1.27)
				)
			)
		)
		(property "Value" ""
			(at 0 0 0)
			(layer "F.Fab")
			(effects
				(font
					(size 1.27 1.27)
				)
			)
		)
		(duplicate_pad_numbers_are_jumpers no)
		(fp_line
			(start -0.7874 -0.4064)
			(end 0.7874 -0.4064)
			(stroke
				(width 0.1524)
				(type default)
			)
			(layer "F.SilkS")
		)
		(fp_line
			(start -0.7874 0.4064)
			(end -0.7874 -0.4064)
			(stroke
				(width 0.1524)
				(type default)
			)
			(layer "F.SilkS")
		)
		(fp_line
			(start 0.7874 -0.4064)
			(end 0.7874 0.4064)
			(stroke
				(width 0.1524)
				(type default)
			)
			(layer "F.SilkS")
		)
		(fp_line
			(start 0.7874 0.4064)
			(end -0.7874 0.4064)
			(stroke
				(width 0.1524)
				(type default)
			)
			(layer "F.SilkS")
		)
		(fp_line
			(start -0.67945 -0.305054)
			(end -0.12065 -0.305054)
			(stroke
				(width 0.1)
				(type default)
			)
			(layer "F.Fab")
		)
		(fp_line
			(start -0.67945 0.3048)
			(end -0.67945 -0.305054)
			(stroke
				(width 0.1)
				(type default)
			)
			(layer "F.Fab")
		)
		(fp_line
			(start -0.12065 -0.305054)
			(end -0.12065 -0.2794)
			(stroke
				(width 0.1)
				(type default)
			)
			(layer "F.Fab")
		)
		(fp_line
			(start -0.12065 -0.2794)
			(end 0.12065 -0.2794)
			(stroke
				(width 0.1)
				(type default)
			)
			(layer "F.Fab")
		)
		(fp_line
			(start -0.12065 0.2794)
			(end -0.12065 0.3048)
			(stroke
				(width 0.1)
				(type default)
			)
			(layer "F.Fab")
		)
		(fp_line
			(start -0.12065 0.3048)
			(end -0.67945 0.3048)
			(stroke
				(width 0.1)
				(type default)
			)
			(layer "F.Fab")
		)
		(fp_line
			(start 0.120396 0.2794)
			(end -0.12065 0.2794)
			(stroke
				(width 0.1)
				(type default)
			)
			(layer "F.Fab")
		)
		(fp_line
			(start 0.120396 0.3048)
			(end 0.120396 0.2794)
			(stroke
				(width 0.1)
				(type default)
			)
			(layer "F.Fab")
		)
		(fp_line
			(start 0.12065 -0.3048)
			(end 0.67945 -0.3048)
			(stroke
				(width 0.1)
				(type default)
			)
			(layer "F.Fab")
		)
		(fp_line
			(start 0.12065 -0.2794)
			(end 0.12065 -0.3048)
			(stroke
				(width 0.1)
				(type default)
			)
			(layer "F.Fab")
		)
		(fp_line
			(start 0.67945 -0.3048)
			(end 0.67945 0.3048)
			(stroke
				(width 0.1)
				(type default)
			)
			(layer "F.Fab")
		)
		(fp_line
			(start 0.67945 0.3048)
			(end 0.120396 0.3048)
			(stroke
				(width 0.1)
				(type default)
			)
			(layer "F.Fab")
		)
		(pad "1" smd circle
			(at -0.40005 0)
			(size 0 0)
			(layers "F.Cu" "F.Mask" "F.Paste")
			(net "P3V3_AUX_FB")
		)
		(pad "2" smd circle
			(at 0.40005 0)
			(size 0 0)
			(layers "F.Cu" "F.Mask" "F.Paste")
			(net "SH_P3V3_AUX_FB")
		)
	)
	(footprint ""
		(layer "F.Cu")
		(at 23.330408 -343.952322 90)
		(property "Reference" "C190"
			(at 0 0 90)
			(layer "F.SilkS")
			(hide yes)
			(effects
				(font
					(size 1.27 1.27)
				)
			)
		)
		(property "Value" ""
			(at 0 0 90)
			(layer "F.Fab")
			(effects
				(font
					(size 1.27 1.27)
				)
			)
		)
		(duplicate_pad_numbers_are_jumpers no)
		(fp_line
			(start 0.299974 -0.150114)
			(end 0.299974 0.150114)
			(stroke
				(width 0.1)
				(type default)
			)
			(layer "F.Fab")
		)
		(fp_line
			(start -0.299974 -0.150114)
			(end 0.299974 -0.150114)
			(stroke
				(width 0.1)
				(type default)
			)
			(layer "F.Fab")
		)
		(fp_line
			(start 0.299974 0.150114)
			(end -0.299974 0.150114)
			(stroke
				(width 0.1)
				(type default)
			)
			(layer "F.Fab")
		)
		(fp_line
			(start -0.299974 0.150114)
			(end -0.299974 -0.150114)
			(stroke
				(width 0.1)
				(type default)
			)
			(layer "F.Fab")
		)
		(pad "1" smd rect
			(at -0.2667 0 90)
			(size 0.3048 0.381)
			(layers "F.Cu" "F.Mask" "F.Paste")
			(net "P5E_PEX0_STN7_TX_DN<113>")
		)
		(pad "2" smd rect
			(at 0.2667 0 90)
			(size 0.3048 0.381)
			(layers "F.Cu" "F.Mask" "F.Paste")
			(net "P5E_PEX0_STN7_TX_C_DN<113>")
		)
	)
	(footprint ""
		(layer "F.Cu")
		(at 142.343886 -44.87291)
		(property "Reference" "R550"
			(at 0 0 0)
			(layer "F.SilkS")
			(hide yes)
			(effects
				(font
					(size 1.27 1.27)
				)
			)
		)
		(property "Value" ""
			(at 0 0 0)
			(layer "F.Fab")
			(effects
				(font
					(size 1.27 1.27)
				)
			)
		)
		(duplicate_pad_numbers_are_jumpers no)
		(fp_line
			(start -0.7874 -0.4064)
			(end 0.7874 -0.4064)
			(stroke
				(width 0.1524)
				(type default)
			)
			(layer "F.SilkS")
		)
		(fp_line
			(start -0.7874 0.4064)
			(end -0.7874 -0.4064)
			(stroke
				(width 0.1524)
				(type default)
			)
			(layer "F.SilkS")
		)
		(fp_line
			(start 0.7874 -0.4064)
			(end 0.7874 0.4064)
			(stroke
				(width 0.1524)
				(type default)
			)
			(layer "F.SilkS")
		)
		(fp_line
			(start 0.7874 0.4064)
			(end -0.7874 0.4064)
			(stroke
				(width 0.1524)
				(type default)
			)
			(layer "F.SilkS")
		)
		(fp_line
			(start -0.67945 -0.305054)
			(end -0.12065 -0.305054)
			(stroke
				(width 0.1)
				(type default)
			)
			(layer "F.Fab")
		)
		(fp_line
			(start -0.67945 0.3048)
			(end -0.67945 -0.305054)
			(stroke
				(width 0.1)
				(type default)
			)
			(layer "F.Fab")
		)
		(fp_line
			(start -0.12065 -0.305054)
			(end -0.12065 -0.2794)
			(stroke
				(width 0.1)
				(type default)
			)
			(layer "F.Fab")
		)
		(fp_line
			(start -0.12065 -0.2794)
			(end 0.12065 -0.2794)
			(stroke
				(width 0.1)
				(type default)
			)
			(layer "F.Fab")
		)
		(fp_line
			(start -0.12065 0.2794)
			(end -0.12065 0.3048)
			(stroke
				(width 0.1)
				(type default)
			)
			(layer "F.Fab")
		)
		(fp_line
			(start -0.12065 0.3048)
			(end -0.67945 0.3048)
			(stroke
				(width 0.1)
				(type default)
			)
			(layer "F.Fab")
		)
		(fp_line
			(start 0.120396 0.2794)
			(end -0.12065 0.2794)
			(stroke
				(width 0.1)
				(type default)
			)
			(layer "F.Fab")
		)
		(fp_line
			(start 0.120396 0.3048)
			(end 0.120396 0.2794)
			(stroke
				(width 0.1)
				(type default)
			)
			(layer "F.Fab")
		)
		(fp_line
			(start 0.12065 -0.3048)
			(end 0.67945 -0.3048)
			(stroke
				(width 0.1)
				(type default)
			)
			(layer "F.Fab")
		)
		(fp_line
			(start 0.12065 -0.2794)
			(end 0.12065 -0.3048)
			(stroke
				(width 0.1)
				(type default)
			)
			(layer "F.Fab")
		)
		(fp_line
			(start 0.67945 -0.3048)
			(end 0.67945 0.3048)
			(stroke
				(width 0.1)
				(type default)
			)
			(layer "F.Fab")
		)
		(fp_line
			(start 0.67945 0.3048)
			(end 0.120396 0.3048)
			(stroke
				(width 0.1)
				(type default)
			)
			(layer "F.Fab")
		)
		(pad "1" smd circle
			(at -0.40005 0)
			(size 0 0)
			(layers "F.Cu" "F.Mask" "F.Paste")
			(net "SSD4_ADC_A0")
		)
		(pad "2" smd circle
			(at 0.40005 0)
			(size 0 0)
			(layers "F.Cu" "F.Mask" "F.Paste")
			(net "P3V3_AUX")
		)
	)
	(footprint ""
		(layer "F.Cu")
		(at 167.439086 -177.428398 -90)
		(property "Reference" "Q3"
			(at 0.745998 -1.878584 90)
			(unlocked yes)
			(layer "F.SilkS")
			(effects
				(font
					(size 0.7874 0.5842)
					(thickness 0.1524)
				)
				(justify left)
			)
		)
		(property "Value" ""
			(at 0 0 270)
			(layer "F.Fab")
			(effects
				(font
					(size 1.27 1.27)
				)
			)
		)
		(duplicate_pad_numbers_are_jumpers no)
		(fp_line
			(start -1.38176 1.100074)
			(end 1.38176 1.100074)
			(stroke
				(width 0.1524)
				(type default)
			)
			(layer "F.SilkS")
		)
		(fp_line
			(start 1.38176 1.100074)
			(end 1.38176 -1.100074)
			(stroke
				(width 0.1524)
				(type default)
			)
			(layer "F.SilkS")
		)
		(fp_line
			(start 0 -0.508)
			(end -0.592074 -1.100074)
			(stroke
				(width 0.1524)
				(type default)
			)
			(layer "F.SilkS")
		)
		(fp_line
			(start -1.38176 -1.100074)
			(end -1.38176 1.100074)
			(stroke
				(width 0.1524)
				(type default)
			)
			(layer "F.SilkS")
		)
		(fp_line
			(start -0.592074 -1.100074)
			(end -1.38176 -1.100074)
			(stroke
				(width 0.1524)
				(type default)
			)
			(layer "F.SilkS")
		)
		(fp_line
			(start 0.592074 -1.100074)
			(end 0 -0.508)
			(stroke
				(width 0.1524)
				(type default)
			)
			(layer "F.SilkS")
		)
		(fp_line
			(start 1.38176 -1.100074)
			(end 0.592074 -1.100074)
			(stroke
				(width 0.1524)
				(type default)
			)
			(layer "F.SilkS")
		)
		(fp_poly
			(pts
				(xy -1.745234 -1.571498) (xy -1.589278 -1.104392) (xy -2.056638 -1.260094)
			)
			(stroke
				(width 0)
				(type default)
			)
			(fill yes)
			(layer "F.SilkS")
		)
		(fp_line
			(start -0.674878 1.100074)
			(end 0.674878 1.100074)
			(stroke
				(width 0.1)
				(type default)
			)
			(layer "F.Fab")
		)
		(fp_line
			(start 0.674878 1.100074)
			(end 0.674878 -1.100074)
			(stroke
				(width 0.1)
				(type default)
			)
			(layer "F.Fab")
		)
		(fp_line
			(start -0.674878 -1.100074)
			(end -0.674878 1.100074)
			(stroke
				(width 0.1)
				(type default)
			)
			(layer "F.Fab")
		)
		(fp_line
			(start 0.674878 -1.100074)
			(end -0.674878 -1.100074)
			(stroke
				(width 0.1)
				(type default)
			)
			(layer "F.Fab")
		)
		(fp_poly
			(pts
				(xy -1.9431 -0.870204) (xy -1.50241 -0.649986) (xy -1.9431 -0.429768)
			)
			(stroke
				(width 0)
				(type default)
			)
			(fill yes)
			(layer "F.Fab")
		)
		(pad "1" smd rect
			(at -0.94996 -0.649986 180)
			(size 0.4318 0.6096)
			(layers "F.Cu" "F.Mask" "F.Paste")
			(net "GND")
		)
		(pad "2" smd rect
			(at -0.94996 0 180)
			(size 0.4318 0.6096)
			(layers "F.Cu" "F.Mask" "F.Paste")
			(net "HP_NIC2_HSC_PWRGD_N")
		)
		(pad "3" smd rect
			(at -0.94996 0.649986 180)
			(size 0.4318 0.6096)
			(layers "F.Cu" "F.Mask" "F.Paste")
			(net "HP_NIC2_HSC_PWRGD_N")
		)
		(pad "4" smd rect
			(at 0.94996 0.649986 180)
			(size 0.4318 0.6096)
			(layers "F.Cu" "F.Mask" "F.Paste")
			(net "GND")
		)
		(pad "5" smd rect
			(at 0.94996 0 180)
			(size 0.4318 0.6096)
			(layers "F.Cu" "F.Mask" "F.Paste")
			(net "PWRGD_P12V_NIC2_R")
		)
		(pad "6" smd rect
			(at 0.94996 -0.649986 180)
			(size 0.4318 0.6096)
			(layers "F.Cu" "F.Mask" "F.Paste")
			(net "HP_NIC2_PWRGD_R")
		)
	)
	(footprint ""
		(layer "F.Cu")
		(at 85.771736 -24.807418)
		(property "Reference" "R419"
			(at 0 0 0)
			(layer "F.SilkS")
			(hide yes)
			(effects
				(font
					(size 1.27 1.27)
				)
			)
		)
		(property "Value" ""
			(at 0 0 0)
			(layer "F.Fab")
			(effects
				(font
					(size 1.27 1.27)
				)
			)
		)
		(duplicate_pad_numbers_are_jumpers no)
		(fp_line
			(start -0.7874 -0.4064)
			(end 0.7874 -0.4064)
			(stroke
				(width 0.1524)
				(type default)
			)
			(layer "F.SilkS")
		)
		(fp_line
			(start -0.7874 0.4064)
			(end -0.7874 -0.4064)
			(stroke
				(width 0.1524)
				(type default)
			)
			(layer "F.SilkS")
		)
		(fp_line
			(start 0.7874 -0.4064)
			(end 0.7874 0.4064)
			(stroke
				(width 0.1524)
				(type default)
			)
			(layer "F.SilkS")
		)
		(fp_line
			(start 0.7874 0.4064)
			(end -0.7874 0.4064)
			(stroke
				(width 0.1524)
				(type default)
			)
			(layer "F.SilkS")
		)
		(fp_line
			(start -0.67945 -0.305054)
			(end -0.12065 -0.305054)
			(stroke
				(width 0.1)
				(type default)
			)
			(layer "F.Fab")
		)
		(fp_line
			(start -0.67945 0.3048)
			(end -0.67945 -0.305054)
			(stroke
				(width 0.1)
				(type default)
			)
			(layer "F.Fab")
		)
		(fp_line
			(start -0.12065 -0.305054)
			(end -0.12065 -0.2794)
			(stroke
				(width 0.1)
				(type default)
			)
			(layer "F.Fab")
		)
		(fp_line
			(start -0.12065 -0.2794)
			(end 0.12065 -0.2794)
			(stroke
				(width 0.1)
				(type default)
			)
			(layer "F.Fab")
		)
		(fp_line
			(start -0.12065 0.2794)
			(end -0.12065 0.3048)
			(stroke
				(width 0.1)
				(type default)
			)
			(layer "F.Fab")
		)
		(fp_line
			(start -0.12065 0.3048)
			(end -0.67945 0.3048)
			(stroke
				(width 0.1)
				(type default)
			)
			(layer "F.Fab")
		)
		(fp_line
			(start 0.120396 0.2794)
			(end -0.12065 0.2794)
			(stroke
				(width 0.1)
				(type default)
			)
			(layer "F.Fab")
		)
		(fp_line
			(start 0.120396 0.3048)
			(end 0.120396 0.2794)
			(stroke
				(width 0.1)
				(type default)
			)
			(layer "F.Fab")
		)
		(fp_line
			(start 0.12065 -0.3048)
			(end 0.67945 -0.3048)
			(stroke
				(width 0.1)
				(type default)
			)
			(layer "F.Fab")
		)
		(fp_line
			(start 0.12065 -0.2794)
			(end 0.12065 -0.3048)
			(stroke
				(width 0.1)
				(type default)
			)
			(layer "F.Fab")
		)
		(fp_line
			(start 0.67945 -0.3048)
			(end 0.67945 0.3048)
			(stroke
				(width 0.1)
				(type default)
			)
			(layer "F.Fab")
		)
		(fp_line
			(start 0.67945 0.3048)
			(end 0.120396 0.3048)
			(stroke
				(width 0.1)
				(type default)
			)
			(layer "F.Fab")
		)
		(pad "1" smd circle
			(at -0.40005 0)
			(size 0 0)
			(layers "F.Cu" "F.Mask" "F.Paste")
			(net "P3V3_SSD3")
		)
		(pad "2" smd circle
			(at 0.40005 0)
			(size 0 0)
			(layers "F.Cu" "F.Mask" "F.Paste")
			(net "PU_CLKREQ3")
		)
	)
	(footprint ""
		(layer "F.Cu")
		(at 62.808612 -158.080202 90)
		(property "Reference" "R2471"
			(at 0 0 90)
			(layer "F.SilkS")
			(hide yes)
			(effects
				(font
					(size 1.27 1.27)
				)
			)
		)
		(property "Value" ""
			(at 0 0 90)
			(layer "F.Fab")
			(effects
				(font
					(size 1.27 1.27)
				)
			)
		)
		(duplicate_pad_numbers_are_jumpers no)
		(fp_line
			(start 0.7874 -0.4064)
			(end 0.7874 0.4064)
			(stroke
				(width 0.1524)
				(type default)
			)
			(layer "F.SilkS")
		)
		(fp_line
			(start -0.7874 -0.4064)
			(end 0.7874 -0.4064)
			(stroke
				(width 0.1524)
				(type default)
			)
			(layer "F.SilkS")
		)
		(fp_line
			(start 0.7874 0.4064)
			(end -0.7874 0.4064)
			(stroke
				(width 0.1524)
				(type default)
			)
			(layer "F.SilkS")
		)
		(fp_line
			(start -0.7874 0.4064)
			(end -0.7874 -0.4064)
			(stroke
				(width 0.1524)
				(type default)
			)
			(layer "F.SilkS")
		)
		(fp_line
			(start -0.12065 -0.305054)
			(end -0.12065 -0.2794)
			(stroke
				(width 0.1)
				(type default)
			)
			(layer "F.Fab")
		)
		(fp_line
			(start -0.67945 -0.305054)
			(end -0.12065 -0.305054)
			(stroke
				(width 0.1)
				(type default)
			)
			(layer "F.Fab")
		)
		(fp_line
			(start 0.67945 -0.3048)
			(end 0.67945 0.3048)
			(stroke
				(width 0.1)
				(type default)
			)
			(layer "F.Fab")
		)
		(fp_line
			(start 0.12065 -0.3048)
			(end 0.67945 -0.3048)
			(stroke
				(width 0.1)
				(type default)
			)
			(layer "F.Fab")
		)
		(fp_line
			(start 0.12065 -0.2794)
			(end 0.12065 -0.3048)
			(stroke
				(width 0.1)
				(type default)
			)
			(layer "F.Fab")
		)
		(fp_line
			(start -0.12065 -0.2794)
			(end 0.12065 -0.2794)
			(stroke
				(width 0.1)
				(type default)
			)
			(layer "F.Fab")
		)
		(fp_line
			(start 0.120396 0.2794)
			(end -0.12065 0.2794)
			(stroke
				(width 0.1)
				(type default)
			)
			(layer "F.Fab")
		)
		(fp_line
			(start -0.12065 0.2794)
			(end -0.12065 0.3048)
			(stroke
				(width 0.1)
				(type default)
			)
			(layer "F.Fab")
		)
		(fp_line
			(start 0.67945 0.3048)
			(end 0.120396 0.3048)
			(stroke
				(width 0.1)
				(type default)
			)
			(layer "F.Fab")
		)
		(fp_line
			(start 0.120396 0.3048)
			(end 0.120396 0.2794)
			(stroke
				(width 0.1)
				(type default)
			)
			(layer "F.Fab")
		)
		(fp_line
			(start -0.12065 0.3048)
			(end -0.67945 0.3048)
			(stroke
				(width 0.1)
				(type default)
			)
			(layer "F.Fab")
		)
		(fp_line
			(start -0.67945 0.3048)
			(end -0.67945 -0.305054)
			(stroke
				(width 0.1)
				(type default)
			)
			(layer "F.Fab")
		)
		(pad "1" smd circle
			(at -0.40005 0 90)
			(size 0 0)
			(layers "F.Cu" "F.Mask" "F.Paste")
			(net "P3V3_NIC1")
		)
		(pad "2" smd circle
			(at 0.40005 0 90)
			(size 0 0)
			(layers "F.Cu" "F.Mask" "F.Paste")
			(net "NIC1_PWRBRK_N")
		)
	)
	(footprint ""
		(layer "F.Cu")
		(at 378.844302 -93.618304)
		(property "Reference" "R4109"
			(at 0 0 0)
			(layer "F.SilkS")
			(hide yes)
			(effects
				(font
					(size 1.27 1.27)
				)
			)
		)
		(property "Value" ""
			(at 0 0 0)
			(layer "F.Fab")
			(effects
				(font
					(size 1.27 1.27)
				)
			)
		)
		(duplicate_pad_numbers_are_jumpers no)
		(fp_line
			(start -0.7874 -0.4064)
			(end 0.7874 -0.4064)
			(stroke
				(width 0.1524)
				(type default)
			)
			(layer "F.SilkS")
		)
		(fp_line
			(start -0.7874 0.4064)
			(end -0.7874 -0.4064)
			(stroke
				(width 0.1524)
				(type default)
			)
			(layer "F.SilkS")
		)
		(fp_line
			(start 0.7874 -0.4064)
			(end 0.7874 0.4064)
			(stroke
				(width 0.1524)
				(type default)
			)
			(layer "F.SilkS")
		)
		(fp_line
			(start 0.7874 0.4064)
			(end -0.7874 0.4064)
			(stroke
				(width 0.1524)
				(type default)
			)
			(layer "F.SilkS")
		)
		(fp_line
			(start -0.67945 -0.305054)
			(end -0.12065 -0.305054)
			(stroke
				(width 0.1)
				(type default)
			)
			(layer "F.Fab")
		)
		(fp_line
			(start -0.67945 0.3048)
			(end -0.67945 -0.305054)
			(stroke
				(width 0.1)
				(type default)
			)
			(layer "F.Fab")
		)
		(fp_line
			(start -0.12065 -0.305054)
			(end -0.12065 -0.2794)
			(stroke
				(width 0.1)
				(type default)
			)
			(layer "F.Fab")
		)
		(fp_line
			(start -0.12065 -0.2794)
			(end 0.12065 -0.2794)
			(stroke
				(width 0.1)
				(type default)
			)
			(layer "F.Fab")
		)
		(fp_line
			(start -0.12065 0.2794)
			(end -0.12065 0.3048)
			(stroke
				(width 0.1)
				(type default)
			)
			(layer "F.Fab")
		)
		(fp_line
			(start -0.12065 0.3048)
			(end -0.67945 0.3048)
			(stroke
				(width 0.1)
				(type default)
			)
			(layer "F.Fab")
		)
		(fp_line
			(start 0.120396 0.2794)
			(end -0.12065 0.2794)
			(stroke
				(width 0.1)
				(type default)
			)
			(layer "F.Fab")
		)
		(fp_line
			(start 0.120396 0.3048)
			(end 0.120396 0.2794)
			(stroke
				(width 0.1)
				(type default)
			)
			(layer "F.Fab")
		)
		(fp_line
			(start 0.12065 -0.3048)
			(end 0.67945 -0.3048)
			(stroke
				(width 0.1)
				(type default)
			)
			(layer "F.Fab")
		)
		(fp_line
			(start 0.12065 -0.2794)
			(end 0.12065 -0.3048)
			(stroke
				(width 0.1)
				(type default)
			)
			(layer "F.Fab")
		)
		(fp_line
			(start 0.67945 -0.3048)
			(end 0.67945 0.3048)
			(stroke
				(width 0.1)
				(type default)
			)
			(layer "F.Fab")
		)
		(fp_line
			(start 0.67945 0.3048)
			(end 0.120396 0.3048)
			(stroke
				(width 0.1)
				(type default)
			)
			(layer "F.Fab")
		)
		(pad "1" smd circle
			(at -0.40005 0)
			(size 0 0)
			(layers "F.Cu" "F.Mask" "F.Paste")
			(net "SMB_BIC_I2C6_R_SDA")
		)
		(pad "2" smd circle
			(at 0.40005 0)
			(size 0 0)
			(layers "F.Cu" "F.Mask" "F.Paste")
			(net "SMB_BIC_I2C6_SENEOR_SDA")
		)
	)
	(footprint ""
		(layer "F.Cu")
		(at 198.905368 -112.394492 180)
		(property "Reference" "R183"
			(at 0 0 180)
			(layer "F.SilkS")
			(hide yes)
			(effects
				(font
					(size 1.27 1.27)
				)
			)
		)
		(property "Value" ""
			(at 0 0 180)
			(layer "F.Fab")
			(effects
				(font
					(size 1.27 1.27)
				)
			)
		)
		(duplicate_pad_numbers_are_jumpers no)
		(fp_line
			(start 0.7874 0.4064)
			(end -0.7874 0.4064)
			(stroke
				(width 0.1524)
				(type default)
			)
			(layer "F.SilkS")
		)
		(fp_line
			(start 0.7874 -0.4064)
			(end 0.7874 0.4064)
			(stroke
				(width 0.1524)
				(type default)
			)
			(layer "F.SilkS")
		)
		(fp_line
			(start -0.7874 0.4064)
			(end -0.7874 -0.4064)
			(stroke
				(width 0.1524)
				(type default)
			)
			(layer "F.SilkS")
		)
		(fp_line
			(start -0.7874 -0.4064)
			(end 0.7874 -0.4064)
			(stroke
				(width 0.1524)
				(type default)
			)
			(layer "F.SilkS")
		)
		(fp_line
			(start 0.67945 0.3048)
			(end 0.120396 0.3048)
			(stroke
				(width 0.1)
				(type default)
			)
			(layer "F.Fab")
		)
		(fp_line
			(start 0.67945 -0.3048)
			(end 0.67945 0.3048)
			(stroke
				(width 0.1)
				(type default)
			)
			(layer "F.Fab")
		)
		(fp_line
			(start 0.12065 -0.2794)
			(end 0.12065 -0.3048)
			(stroke
				(width 0.1)
				(type default)
			)
			(layer "F.Fab")
		)
		(fp_line
			(start 0.12065 -0.3048)
			(end 0.67945 -0.3048)
			(stroke
				(width 0.1)
				(type default)
			)
			(layer "F.Fab")
		)
		(fp_line
			(start 0.120396 0.3048)
			(end 0.120396 0.2794)
			(stroke
				(width 0.1)
				(type default)
			)
			(layer "F.Fab")
		)
		(fp_line
			(start 0.120396 0.2794)
			(end -0.12065 0.2794)
			(stroke
				(width 0.1)
				(type default)
			)
			(layer "F.Fab")
		)
		(fp_line
			(start -0.12065 0.3048)
			(end -0.67945 0.3048)
			(stroke
				(width 0.1)
				(type default)
			)
			(layer "F.Fab")
		)
		(fp_line
			(start -0.12065 0.2794)
			(end -0.12065 0.3048)
			(stroke
				(width 0.1)
				(type default)
			)
			(layer "F.Fab")
		)
		(fp_line
			(start -0.12065 -0.2794)
			(end 0.12065 -0.2794)
			(stroke
				(width 0.1)
				(type default)
			)
			(layer "F.Fab")
		)
		(fp_line
			(start -0.12065 -0.305054)
			(end -0.12065 -0.2794)
			(stroke
				(width 0.1)
				(type default)
			)
			(layer "F.Fab")
		)
		(fp_line
			(start -0.67945 0.3048)
			(end -0.67945 -0.305054)
			(stroke
				(width 0.1)
				(type default)
			)
			(layer "F.Fab")
		)
		(fp_line
			(start -0.67945 -0.305054)
			(end -0.12065 -0.305054)
			(stroke
				(width 0.1)
				(type default)
			)
			(layer "F.Fab")
		)
		(pad "1" smd circle
			(at -0.40005 0 180)
			(size 0 0)
			(layers "F.Cu" "F.Mask" "F.Paste")
			(net "NIC3_BIF0_N")
		)
		(pad "2" smd circle
			(at 0.40005 0 180)
			(size 0 0)
			(layers "F.Cu" "F.Mask" "F.Paste")
			(net "GND")
		)
	)
	(footprint ""
		(layer "F.Cu")
		(at 19.738594 -44.341542 90)
		(property "Reference" "C203"
			(at 0 0 90)
			(layer "F.SilkS")
			(hide yes)
			(effects
				(font
					(size 1.27 1.27)
				)
			)
		)
		(property "Value" ""
			(at 0 0 90)
			(layer "F.Fab")
			(effects
				(font
					(size 1.27 1.27)
				)
			)
		)
		(duplicate_pad_numbers_are_jumpers no)
		(fp_line
			(start 0.7874 -0.4064)
			(end 0.7874 0.4064)
			(stroke
				(width 0.1524)
				(type default)
			)
			(layer "F.SilkS")
		)
		(fp_line
			(start -0.7874 -0.4064)
			(end 0.7874 -0.4064)
			(stroke
				(width 0.1524)
				(type default)
			)
			(layer "F.SilkS")
		)
		(fp_line
			(start 0.7874 0.4064)
			(end -0.7874 0.4064)
			(stroke
				(width 0.1524)
				(type default)
			)
			(layer "F.SilkS")
		)
		(fp_line
			(start -0.7874 0.4064)
			(end -0.7874 -0.4064)
			(stroke
				(width 0.1524)
				(type default)
			)
			(layer "F.SilkS")
		)
		(fp_line
			(start -0.12065 -0.305054)
			(end -0.12065 -0.2794)
			(stroke
				(width 0.1)
				(type default)
			)
			(layer "F.Fab")
		)
		(fp_line
			(start -0.67945 -0.305054)
			(end -0.12065 -0.305054)
			(stroke
				(width 0.1)
				(type default)
			)
			(layer "F.Fab")
		)
		(fp_line
			(start 0.67945 -0.3048)
			(end 0.67945 0.3048)
			(stroke
				(width 0.1)
				(type default)
			)
			(layer "F.Fab")
		)
		(fp_line
			(start 0.12065 -0.3048)
			(end 0.67945 -0.3048)
			(stroke
				(width 0.1)
				(type default)
			)
			(layer "F.Fab")
		)
		(fp_line
			(start 0.12065 -0.2794)
			(end 0.12065 -0.3048)
			(stroke
				(width 0.1)
				(type default)
			)
			(layer "F.Fab")
		)
		(fp_line
			(start -0.12065 -0.2794)
			(end 0.12065 -0.2794)
			(stroke
				(width 0.1)
				(type default)
			)
			(layer "F.Fab")
		)
		(fp_line
			(start 0.120396 0.2794)
			(end -0.12065 0.2794)
			(stroke
				(width 0.1)
				(type default)
			)
			(layer "F.Fab")
		)
		(fp_line
			(start -0.12065 0.2794)
			(end -0.12065 0.3048)
			(stroke
				(width 0.1)
				(type default)
			)
			(layer "F.Fab")
		)
		(fp_line
			(start 0.67945 0.3048)
			(end 0.120396 0.3048)
			(stroke
				(width 0.1)
				(type default)
			)
			(layer "F.Fab")
		)
		(fp_line
			(start 0.120396 0.3048)
			(end 0.120396 0.2794)
			(stroke
				(width 0.1)
				(type default)
			)
			(layer "F.Fab")
		)
		(fp_line
			(start -0.12065 0.3048)
			(end -0.67945 0.3048)
			(stroke
				(width 0.1)
				(type default)
			)
			(layer "F.Fab")
		)
		(fp_line
			(start -0.67945 0.3048)
			(end -0.67945 -0.305054)
			(stroke
				(width 0.1)
				(type default)
			)
			(layer "F.Fab")
		)
		(pad "1" smd circle
			(at -0.40005 0 90)
			(size 0 0)
			(layers "F.Cu" "F.Mask" "F.Paste")
			(net "P12V_SSD0_VIN_P")
		)
		(pad "2" smd circle
			(at 0.40005 0 90)
			(size 0 0)
			(layers "F.Cu" "F.Mask" "F.Paste")
			(net "P12V_SSD0_VIN_N")
		)
	)
	(footprint ""
		(layer "F.Cu")
		(at 91.044522 -298.624244 -90)
		(property "Reference" "R4013"
			(at 0 0 270)
			(layer "F.SilkS")
			(hide yes)
			(effects
				(font
					(size 1.27 1.27)
				)
			)
		)
		(property "Value" ""
			(at 0 0 270)
			(layer "F.Fab")
			(effects
				(font
					(size 1.27 1.27)
				)
			)
		)
		(duplicate_pad_numbers_are_jumpers no)
		(fp_line
			(start -0.7874 0.4064)
			(end -0.7874 -0.4064)
			(stroke
				(width 0.1524)
				(type default)
			)
			(layer "F.SilkS")
		)
		(fp_line
			(start 0.7874 0.4064)
			(end -0.7874 0.4064)
			(stroke
				(width 0.1524)
				(type default)
			)
			(layer "F.SilkS")
		)
		(fp_line
			(start -0.7874 -0.4064)
			(end 0.7874 -0.4064)
			(stroke
				(width 0.1524)
				(type default)
			)
			(layer "F.SilkS")
		)
		(fp_line
			(start 0.7874 -0.4064)
			(end 0.7874 0.4064)
			(stroke
				(width 0.1524)
				(type default)
			)
			(layer "F.SilkS")
		)
		(fp_line
			(start -0.67945 0.3048)
			(end -0.67945 -0.305054)
			(stroke
				(width 0.1)
				(type default)
			)
			(layer "F.Fab")
		)
		(fp_line
			(start -0.12065 0.3048)
			(end -0.67945 0.3048)
			(stroke
				(width 0.1)
				(type default)
			)
			(layer "F.Fab")
		)
		(fp_line
			(start 0.120396 0.3048)
			(end 0.120396 0.2794)
			(stroke
				(width 0.1)
				(type default)
			)
			(layer "F.Fab")
		)
		(fp_line
			(start 0.67945 0.3048)
			(end 0.120396 0.3048)
			(stroke
				(width 0.1)
				(type default)
			)
			(layer "F.Fab")
		)
		(fp_line
			(start -0.12065 0.2794)
			(end -0.12065 0.3048)
			(stroke
				(width 0.1)
				(type default)
			)
			(layer "F.Fab")
		)
		(fp_line
			(start 0.120396 0.2794)
			(end -0.12065 0.2794)
			(stroke
				(width 0.1)
				(type default)
			)
			(layer "F.Fab")
		)
		(fp_line
			(start -0.12065 -0.2794)
			(end 0.12065 -0.2794)
			(stroke
				(width 0.1)
				(type default)
			)
			(layer "F.Fab")
		)
		(fp_line
			(start 0.12065 -0.2794)
			(end 0.12065 -0.3048)
			(stroke
				(width 0.1)
				(type default)
			)
			(layer "F.Fab")
		)
		(fp_line
			(start 0.12065 -0.3048)
			(end 0.67945 -0.3048)
			(stroke
				(width 0.1)
				(type default)
			)
			(layer "F.Fab")
		)
		(fp_line
			(start 0.67945 -0.3048)
			(end 0.67945 0.3048)
			(stroke
				(width 0.1)
				(type default)
			)
			(layer "F.Fab")
		)
		(fp_line
			(start -0.67945 -0.305054)
			(end -0.12065 -0.305054)
			(stroke
				(width 0.1)
				(type default)
			)
			(layer "F.Fab")
		)
		(fp_line
			(start -0.12065 -0.305054)
			(end -0.12065 -0.2794)
			(stroke
				(width 0.1)
				(type default)
			)
			(layer "F.Fab")
		)
		(pad "1" smd circle
			(at -0.40005 0 270)
			(size 0 0)
			(layers "F.Cu" "F.Mask" "F.Paste")
			(net "P1V8_PEX")
		)
		(pad "2" smd circle
			(at 0.40005 0 270)
			(size 0 0)
			(layers "F.Cu" "F.Mask" "F.Paste")
			(net "I2C_PEX0_HOST_R_SCL")
		)
	)
	(footprint ""
		(layer "F.Cu")
		(at 16.785336 -276.264624)
		(property "Reference" "R768"
			(at 0 0 0)
			(layer "F.SilkS")
			(hide yes)
			(effects
				(font
					(size 1.27 1.27)
				)
			)
		)
		(property "Value" ""
			(at 0 0 0)
			(layer "F.Fab")
			(effects
				(font
					(size 1.27 1.27)
				)
			)
		)
		(duplicate_pad_numbers_are_jumpers no)
		(fp_line
			(start -0.7874 -0.4064)
			(end 0.7874 -0.4064)
			(stroke
				(width 0.1524)
				(type default)
			)
			(layer "F.SilkS")
		)
		(fp_line
			(start -0.7874 0.4064)
			(end -0.7874 -0.4064)
			(stroke
				(width 0.1524)
				(type default)
			)
			(layer "F.SilkS")
		)
		(fp_line
			(start 0.7874 -0.4064)
			(end 0.7874 0.4064)
			(stroke
				(width 0.1524)
				(type default)
			)
			(layer "F.SilkS")
		)
		(fp_line
			(start 0.7874 0.4064)
			(end -0.7874 0.4064)
			(stroke
				(width 0.1524)
				(type default)
			)
			(layer "F.SilkS")
		)
		(fp_line
			(start -0.67945 -0.305054)
			(end -0.12065 -0.305054)
			(stroke
				(width 0.1)
				(type default)
			)
			(layer "F.Fab")
		)
		(fp_line
			(start -0.67945 0.3048)
			(end -0.67945 -0.305054)
			(stroke
				(width 0.1)
				(type default)
			)
			(layer "F.Fab")
		)
		(fp_line
			(start -0.12065 -0.305054)
			(end -0.12065 -0.2794)
			(stroke
				(width 0.1)
				(type default)
			)
			(layer "F.Fab")
		)
		(fp_line
			(start -0.12065 -0.2794)
			(end 0.12065 -0.2794)
			(stroke
				(width 0.1)
				(type default)
			)
			(layer "F.Fab")
		)
		(fp_line
			(start -0.12065 0.2794)
			(end -0.12065 0.3048)
			(stroke
				(width 0.1)
				(type default)
			)
			(layer "F.Fab")
		)
		(fp_line
			(start -0.12065 0.3048)
			(end -0.67945 0.3048)
			(stroke
				(width 0.1)
				(type default)
			)
			(layer "F.Fab")
		)
		(fp_line
			(start 0.120396 0.2794)
			(end -0.12065 0.2794)
			(stroke
				(width 0.1)
				(type default)
			)
			(layer "F.Fab")
		)
		(fp_line
			(start 0.120396 0.3048)
			(end 0.120396 0.2794)
			(stroke
				(width 0.1)
				(type default)
			)
			(layer "F.Fab")
		)
		(fp_line
			(start 0.12065 -0.3048)
			(end 0.67945 -0.3048)
			(stroke
				(width 0.1)
				(type default)
			)
			(layer "F.Fab")
		)
		(fp_line
			(start 0.12065 -0.2794)
			(end 0.12065 -0.3048)
			(stroke
				(width 0.1)
				(type default)
			)
			(layer "F.Fab")
		)
		(fp_line
			(start 0.67945 -0.3048)
			(end 0.67945 0.3048)
			(stroke
				(width 0.1)
				(type default)
			)
			(layer "F.Fab")
		)
		(fp_line
			(start 0.67945 0.3048)
			(end 0.120396 0.3048)
			(stroke
				(width 0.1)
				(type default)
			)
			(layer "F.Fab")
		)
		(pad "1" smd circle
			(at -0.40005 0)
			(size 0 0)
			(layers "F.Cu" "F.Mask" "F.Paste")
			(net "P3V3_AUX")
		)
		(pad "2" smd circle
			(at 0.40005 0)
			(size 0 0)
			(layers "F.Cu" "F.Mask" "F.Paste")
			(net "PEX_ADC_ALERT_N")
		)
	)
	(footprint ""
		(layer "F.Cu")
		(at 430.961546 -144.396714 180)
		(property "Reference" "C647"
			(at 0 0 180)
			(layer "F.SilkS")
			(hide yes)
			(effects
				(font
					(size 1.27 1.27)
				)
			)
		)
		(property "Value" ""
			(at 0 0 180)
			(layer "F.Fab")
			(effects
				(font
					(size 1.27 1.27)
				)
			)
		)
		(duplicate_pad_numbers_are_jumpers no)
		(fp_line
			(start 0.299974 0.150114)
			(end -0.299974 0.150114)
			(stroke
				(width 0.1)
				(type default)
			)
			(layer "F.Fab")
		)
		(fp_line
			(start 0.299974 -0.150114)
			(end 0.299974 0.150114)
			(stroke
				(width 0.1)
				(type default)
			)
			(layer "F.Fab")
		)
		(fp_line
			(start -0.299974 0.150114)
			(end -0.299974 -0.150114)
			(stroke
				(width 0.1)
				(type default)
			)
			(layer "F.Fab")
		)
		(fp_line
			(start -0.299974 -0.150114)
			(end 0.299974 -0.150114)
			(stroke
				(width 0.1)
				(type default)
			)
			(layer "F.Fab")
		)
		(pad "1" smd rect
			(at -0.2667 0 180)
			(size 0.3048 0.381)
			(layers "F.Cu" "F.Mask" "F.Paste")
			(net "P5E_PEX3_STN0_TX_DN<9>")
		)
		(pad "2" smd rect
			(at 0.2667 0 180)
			(size 0.3048 0.381)
			(layers "F.Cu" "F.Mask" "F.Paste")
			(net "P5E_PEX3_STN0_TX_C_DN<9>")
		)
	)
	(footprint ""
		(layer "F.Cu")
		(at 199.49414 -29.507688 -90)
		(property "Reference" "PC933"
			(at 0 0 270)
			(layer "F.SilkS")
			(hide yes)
			(effects
				(font
					(size 1.27 1.27)
				)
			)
		)
		(property "Value" ""
			(at 0 0 270)
			(layer "F.Fab")
			(effects
				(font
					(size 1.27 1.27)
				)
			)
		)
		(duplicate_pad_numbers_are_jumpers no)
		(fp_line
			(start -1.524 0.762)
			(end -1.524 -0.762)
			(stroke
				(width 0.1524)
				(type default)
			)
			(layer "F.SilkS")
		)
		(fp_line
			(start 1.524 0.762)
			(end -1.524 0.762)
			(stroke
				(width 0.1524)
				(type default)
			)
			(layer "F.SilkS")
		)
		(fp_line
			(start -1.524 -0.762)
			(end 1.524 -0.762)
			(stroke
				(width 0.1524)
				(type default)
			)
			(layer "F.SilkS")
		)
		(fp_line
			(start 1.524 -0.762)
			(end 1.524 0.762)
			(stroke
				(width 0.1524)
				(type default)
			)
			(layer "F.SilkS")
		)
		(fp_line
			(start -1.1049 0.724916)
			(end 1.1049 0.724916)
			(stroke
				(width 0.1)
				(type default)
			)
			(layer "F.Fab")
		)
		(fp_line
			(start 1.1049 0.724916)
			(end 1.1049 -0.724916)
			(stroke
				(width 0.1)
				(type default)
			)
			(layer "F.Fab")
		)
		(fp_line
			(start -1.1049 -0.724916)
			(end -1.1049 0.724916)
			(stroke
				(width 0.1)
				(type default)
			)
			(layer "F.Fab")
		)
		(fp_line
			(start 1.1049 -0.724916)
			(end -1.1049 -0.724916)
			(stroke
				(width 0.1)
				(type default)
			)
			(layer "F.Fab")
		)
		(pad "1" smd rect
			(at -0.889 0 90)
			(size 1.016 1.27)
			(layers "F.Cu" "F.Mask" "F.Paste")
			(net "P3V3_SSD7")
		)
		(pad "2" smd rect
			(at 0.889 0 90)
			(size 1.016 1.27)
			(layers "F.Cu" "F.Mask" "F.Paste")
			(net "GND")
		)
	)
	(footprint ""
		(layer "F.Cu")
		(at 236.072172 -32.848042 90)
		(property "Reference" "PC940"
			(at 0 0 90)
			(layer "F.SilkS")
			(hide yes)
			(effects
				(font
					(size 1.27 1.27)
				)
			)
		)
		(property "Value" ""
			(at 0 0 90)
			(layer "F.Fab")
			(effects
				(font
					(size 1.27 1.27)
				)
			)
		)
		(duplicate_pad_numbers_are_jumpers no)
		(fp_line
			(start 0.7874 -0.4064)
			(end 0.7874 0.4064)
			(stroke
				(width 0.1524)
				(type default)
			)
			(layer "F.SilkS")
		)
		(fp_line
			(start -0.7874 -0.4064)
			(end 0.7874 -0.4064)
			(stroke
				(width 0.1524)
				(type default)
			)
			(layer "F.SilkS")
		)
		(fp_line
			(start 0.7874 0.4064)
			(end -0.7874 0.4064)
			(stroke
				(width 0.1524)
				(type default)
			)
			(layer "F.SilkS")
		)
		(fp_line
			(start -0.7874 0.4064)
			(end -0.7874 -0.4064)
			(stroke
				(width 0.1524)
				(type default)
			)
			(layer "F.SilkS")
		)
		(fp_line
			(start -0.12065 -0.305054)
			(end -0.12065 -0.2794)
			(stroke
				(width 0.1)
				(type default)
			)
			(layer "F.Fab")
		)
		(fp_line
			(start -0.67945 -0.305054)
			(end -0.12065 -0.305054)
			(stroke
				(width 0.1)
				(type default)
			)
			(layer "F.Fab")
		)
		(fp_line
			(start 0.67945 -0.3048)
			(end 0.67945 0.3048)
			(stroke
				(width 0.1)
				(type default)
			)
			(layer "F.Fab")
		)
		(fp_line
			(start 0.12065 -0.3048)
			(end 0.67945 -0.3048)
			(stroke
				(width 0.1)
				(type default)
			)
			(layer "F.Fab")
		)
		(fp_line
			(start 0.12065 -0.2794)
			(end 0.12065 -0.3048)
			(stroke
				(width 0.1)
				(type default)
			)
			(layer "F.Fab")
		)
		(fp_line
			(start -0.12065 -0.2794)
			(end 0.12065 -0.2794)
			(stroke
				(width 0.1)
				(type default)
			)
			(layer "F.Fab")
		)
		(fp_line
			(start 0.120396 0.2794)
			(end -0.12065 0.2794)
			(stroke
				(width 0.1)
				(type default)
			)
			(layer "F.Fab")
		)
		(fp_line
			(start -0.12065 0.2794)
			(end -0.12065 0.3048)
			(stroke
				(width 0.1)
				(type default)
			)
			(layer "F.Fab")
		)
		(fp_line
			(start 0.67945 0.3048)
			(end 0.120396 0.3048)
			(stroke
				(width 0.1)
				(type default)
			)
			(layer "F.Fab")
		)
		(fp_line
			(start 0.120396 0.3048)
			(end 0.120396 0.2794)
			(stroke
				(width 0.1)
				(type default)
			)
			(layer "F.Fab")
		)
		(fp_line
			(start -0.12065 0.3048)
			(end -0.67945 0.3048)
			(stroke
				(width 0.1)
				(type default)
			)
			(layer "F.Fab")
		)
		(fp_line
			(start -0.67945 0.3048)
			(end -0.67945 -0.305054)
			(stroke
				(width 0.1)
				(type default)
			)
			(layer "F.Fab")
		)
		(pad "1" smd circle
			(at -0.40005 0 90)
			(size 0 0)
			(layers "F.Cu" "F.Mask" "F.Paste")
			(net "P3V3_SSD8_CO_GATE")
		)
		(pad "2" smd circle
			(at 0.40005 0 90)
			(size 0 0)
			(layers "F.Cu" "F.Mask" "F.Paste")
			(net "GND")
		)
	)
	(footprint ""
		(layer "F.Cu")
		(at 109.403896 -395.746732 -90)
		(property "Reference" "Y8"
			(at -2.314702 0.448818 0)
			(unlocked yes)
			(layer "F.SilkS")
			(effects
				(font
					(size 0.7874 0.5842)
					(thickness 0.1524)
				)
			)
		)
		(property "Value" ""
			(at 0 0 270)
			(layer "F.Fab")
			(effects
				(font
					(size 1.27 1.27)
				)
			)
		)
		(duplicate_pad_numbers_are_jumpers no)
		(fp_line
			(start -1.2446 1.4986)
			(end 1.2446 1.4986)
			(stroke
				(width 0.1524)
				(type default)
			)
			(layer "F.SilkS")
		)
		(fp_line
			(start 1.2446 1.4986)
			(end 1.2446 -1.4986)
			(stroke
				(width 0.1524)
				(type default)
			)
			(layer "F.SilkS")
		)
		(fp_line
			(start -1.2446 -1.4986)
			(end -1.2446 1.4986)
			(stroke
				(width 0.1524)
				(type default)
			)
			(layer "F.SilkS")
		)
		(fp_line
			(start 1.2446 -1.4986)
			(end -1.2446 -1.4986)
			(stroke
				(width 0.1524)
				(type default)
			)
			(layer "F.SilkS")
		)
		(fp_poly
			(pts
				(xy -2.4638 -1.357884) (xy -2.4638 -0.341884) (xy -1.4478 -0.849884)
			)
			(stroke
				(width 0)
				(type default)
			)
			(fill yes)
			(layer "F.SilkS")
		)
		(fp_line
			(start -1.050036 1.299972)
			(end 1.050036 1.299972)
			(stroke
				(width 0.1)
				(type default)
			)
			(layer "F.Fab")
		)
		(fp_line
			(start 1.050036 1.299972)
			(end 1.050036 -1.299972)
			(stroke
				(width 0.1)
				(type default)
			)
			(layer "F.Fab")
		)
		(fp_line
			(start -1.050036 -1.299972)
			(end -1.050036 1.299972)
			(stroke
				(width 0.1)
				(type default)
			)
			(layer "F.Fab")
		)
		(fp_line
			(start 1.050036 -1.299972)
			(end -1.050036 -1.299972)
			(stroke
				(width 0.1)
				(type default)
			)
			(layer "F.Fab")
		)
		(fp_poly
			(pts
				(xy -2.4638 -1.357884) (xy -2.4638 -0.341884) (xy -1.4478 -0.849884)
			)
			(stroke
				(width 0)
				(type default)
			)
			(fill yes)
			(layer "F.Fab")
		)
		(pad "1" smd rect
			(at -0.649986 -0.849884 90)
			(size 0.9144 1.016)
			(layers "F.Cu" "F.Mask" "F.Paste")
			(net "BIC_USB_HUB_XIN")
		)
		(pad "2" smd rect
			(at -0.649986 0.849884 90)
			(size 0.9144 1.016)
			(layers "F.Cu" "F.Mask" "F.Paste")
			(net "GND")
		)
		(pad "3" smd rect
			(at 0.649986 0.849884 90)
			(size 0.9144 1.016)
			(layers "F.Cu" "F.Mask" "F.Paste")
			(net "BIC_USB_HUB_XOUT_R")
		)
		(pad "4" smd rect
			(at 0.649986 -0.849884 90)
			(size 0.9144 1.016)
			(layers "F.Cu" "F.Mask" "F.Paste")
			(net "GND")
		)
	)
	(footprint ""
		(layer "F.Cu")
		(at 141.07033 -262.645652 90)
		(property "Reference" "C3245"
			(at 0 0 90)
			(layer "F.SilkS")
			(hide yes)
			(effects
				(font
					(size 1.27 1.27)
				)
			)
		)
		(property "Value" ""
			(at 0 0 90)
			(layer "F.Fab")
			(effects
				(font
					(size 1.27 1.27)
				)
			)
		)
		(duplicate_pad_numbers_are_jumpers no)
		(fp_line
			(start 0.299974 -0.150114)
			(end 0.299974 0.150114)
			(stroke
				(width 0.1)
				(type default)
			)
			(layer "F.Fab")
		)
		(fp_line
			(start -0.299974 -0.150114)
			(end 0.299974 -0.150114)
			(stroke
				(width 0.1)
				(type default)
			)
			(layer "F.Fab")
		)
		(fp_line
			(start 0.299974 0.150114)
			(end -0.299974 0.150114)
			(stroke
				(width 0.1)
				(type default)
			)
			(layer "F.Fab")
		)
		(fp_line
			(start -0.299974 0.150114)
			(end -0.299974 -0.150114)
			(stroke
				(width 0.1)
				(type default)
			)
			(layer "F.Fab")
		)
		(pad "1" smd rect
			(at -0.2667 0 90)
			(size 0.3048 0.381)
			(layers "F.Cu" "F.Mask" "F.Paste")
			(net "P1V8_VDDA_PEX1")
		)
		(pad "2" smd rect
			(at 0.2667 0 90)
			(size 0.3048 0.381)
			(layers "F.Cu" "F.Mask" "F.Paste")
			(net "GND")
		)
	)
	(footprint ""
		(layer "F.Cu")
		(at 142.50543 -258.582922 90)
		(property "Reference" "L113"
			(at 0 0 90)
			(layer "F.SilkS")
			(hide yes)
			(effects
				(font
					(size 1.27 1.27)
				)
			)
		)
		(property "Value" ""
			(at 0 0 90)
			(layer "F.Fab")
			(effects
				(font
					(size 1.27 1.27)
				)
			)
		)
		(duplicate_pad_numbers_are_jumpers no)
		(fp_line
			(start 1.63576 -0.8128)
			(end 1.63576 0.8128)
			(stroke
				(width 0.1524)
				(type default)
			)
			(layer "F.SilkS")
		)
		(fp_line
			(start -1.63576 -0.8128)
			(end 1.63576 -0.8128)
			(stroke
				(width 0.1524)
				(type default)
			)
			(layer "F.SilkS")
		)
		(fp_line
			(start -1.63576 -0.8128)
			(end -1.63576 0.8128)
			(stroke
				(width 0.1524)
				(type default)
			)
			(layer "F.SilkS")
		)
		(fp_line
			(start 1.63576 0.8128)
			(end -1.63576 0.8128)
			(stroke
				(width 0.1524)
				(type default)
			)
			(layer "F.SilkS")
		)
		(fp_line
			(start 1.560576 -0.738632)
			(end -1.56083 -0.738632)
			(stroke
				(width 0.1)
				(type default)
			)
			(layer "F.Fab")
		)
		(fp_line
			(start -1.56083 -0.738632)
			(end -1.56083 0.7366)
			(stroke
				(width 0.1)
				(type default)
			)
			(layer "F.Fab")
		)
		(fp_line
			(start 1.560576 0.7366)
			(end 1.560576 -0.738632)
			(stroke
				(width 0.1)
				(type default)
			)
			(layer "F.Fab")
		)
		(fp_line
			(start 1.524 0.7366)
			(end 1.560576 0.7366)
			(stroke
				(width 0.1)
				(type default)
			)
			(layer "F.Fab")
		)
		(fp_line
			(start -1.524 0.7366)
			(end 1.524 0.7366)
			(stroke
				(width 0.1)
				(type default)
			)
			(layer "F.Fab")
		)
		(fp_line
			(start -1.56083 0.7366)
			(end -1.524 0.7366)
			(stroke
				(width 0.1)
				(type default)
			)
			(layer "F.Fab")
		)
		(pad "1" smd rect
			(at -0.94996 0 270)
			(size 1.1176 1.3716)
			(layers "F.Cu" "F.Mask" "F.Paste")
			(net "P1V8_PLL0_PEX1")
		)
		(pad "2" smd rect
			(at 0.94996 0 270)
			(size 1.1176 1.3716)
			(layers "F.Cu" "F.Mask" "F.Paste")
			(net "P1V8_VDDA_PEX1")
		)
	)
	(footprint ""
		(layer "F.Cu")
		(at 436.049674 -300.60265 90)
		(property "Reference" "R6400"
			(at 0 0 90)
			(layer "F.SilkS")
			(hide yes)
			(effects
				(font
					(size 1.27 1.27)
				)
			)
		)
		(property "Value" ""
			(at 0 0 90)
			(layer "F.Fab")
			(effects
				(font
					(size 1.27 1.27)
				)
			)
		)
		(duplicate_pad_numbers_are_jumpers no)
		(fp_line
			(start 0.7874 -0.4064)
			(end 0.7874 0.4064)
			(stroke
				(width 0.1524)
				(type default)
			)
			(layer "F.SilkS")
		)
		(fp_line
			(start -0.7874 -0.4064)
			(end 0.7874 -0.4064)
			(stroke
				(width 0.1524)
				(type default)
			)
			(layer "F.SilkS")
		)
		(fp_line
			(start 0.7874 0.4064)
			(end -0.7874 0.4064)
			(stroke
				(width 0.1524)
				(type default)
			)
			(layer "F.SilkS")
		)
		(fp_line
			(start -0.7874 0.4064)
			(end -0.7874 -0.4064)
			(stroke
				(width 0.1524)
				(type default)
			)
			(layer "F.SilkS")
		)
		(fp_line
			(start -0.12065 -0.305054)
			(end -0.12065 -0.2794)
			(stroke
				(width 0.1)
				(type default)
			)
			(layer "F.Fab")
		)
		(fp_line
			(start -0.67945 -0.305054)
			(end -0.12065 -0.305054)
			(stroke
				(width 0.1)
				(type default)
			)
			(layer "F.Fab")
		)
		(fp_line
			(start 0.67945 -0.3048)
			(end 0.67945 0.3048)
			(stroke
				(width 0.1)
				(type default)
			)
			(layer "F.Fab")
		)
		(fp_line
			(start 0.12065 -0.3048)
			(end 0.67945 -0.3048)
			(stroke
				(width 0.1)
				(type default)
			)
			(layer "F.Fab")
		)
		(fp_line
			(start 0.12065 -0.2794)
			(end 0.12065 -0.3048)
			(stroke
				(width 0.1)
				(type default)
			)
			(layer "F.Fab")
		)
		(fp_line
			(start -0.12065 -0.2794)
			(end 0.12065 -0.2794)
			(stroke
				(width 0.1)
				(type default)
			)
			(layer "F.Fab")
		)
		(fp_line
			(start 0.120396 0.2794)
			(end -0.12065 0.2794)
			(stroke
				(width 0.1)
				(type default)
			)
			(layer "F.Fab")
		)
		(fp_line
			(start -0.12065 0.2794)
			(end -0.12065 0.3048)
			(stroke
				(width 0.1)
				(type default)
			)
			(layer "F.Fab")
		)
		(fp_line
			(start 0.67945 0.3048)
			(end 0.120396 0.3048)
			(stroke
				(width 0.1)
				(type default)
			)
			(layer "F.Fab")
		)
		(fp_line
			(start 0.120396 0.3048)
			(end 0.120396 0.2794)
			(stroke
				(width 0.1)
				(type default)
			)
			(layer "F.Fab")
		)
		(fp_line
			(start -0.12065 0.3048)
			(end -0.67945 0.3048)
			(stroke
				(width 0.1)
				(type default)
			)
			(layer "F.Fab")
		)
		(fp_line
			(start -0.67945 0.3048)
			(end -0.67945 -0.305054)
			(stroke
				(width 0.1)
				(type default)
			)
			(layer "F.Fab")
		)
		(pad "1" smd circle
			(at -0.40005 0 90)
			(size 0 0)
			(layers "F.Cu" "F.Mask" "F.Paste")
			(net "RST_PEX3_S1_PERST_N")
		)
		(pad "2" smd circle
			(at 0.40005 0 90)
			(size 0 0)
			(layers "F.Cu" "F.Mask" "F.Paste")
			(net "RST_PEX3_S1_PERST_R_N")
		)
	)
	(footprint ""
		(layer "F.Cu")
		(at 338.074 -171.069 180)
		(property "Reference" "R4768"
			(at 0 0 180)
			(layer "F.SilkS")
			(hide yes)
			(effects
				(font
					(size 1.27 1.27)
				)
			)
		)
		(property "Value" ""
			(at 0 0 180)
			(layer "F.Fab")
			(effects
				(font
					(size 1.27 1.27)
				)
			)
		)
		(duplicate_pad_numbers_are_jumpers no)
		(fp_line
			(start 0.7874 0.4064)
			(end -0.7874 0.4064)
			(stroke
				(width 0.1524)
				(type default)
			)
			(layer "F.SilkS")
		)
		(fp_line
			(start 0.7874 -0.4064)
			(end 0.7874 0.4064)
			(stroke
				(width 0.1524)
				(type default)
			)
			(layer "F.SilkS")
		)
		(fp_line
			(start -0.7874 0.4064)
			(end -0.7874 -0.4064)
			(stroke
				(width 0.1524)
				(type default)
			)
			(layer "F.SilkS")
		)
		(fp_line
			(start -0.7874 -0.4064)
			(end 0.7874 -0.4064)
			(stroke
				(width 0.1524)
				(type default)
			)
			(layer "F.SilkS")
		)
		(fp_line
			(start 0.67945 0.3048)
			(end 0.120396 0.3048)
			(stroke
				(width 0.1)
				(type default)
			)
			(layer "F.Fab")
		)
		(fp_line
			(start 0.67945 -0.3048)
			(end 0.67945 0.3048)
			(stroke
				(width 0.1)
				(type default)
			)
			(layer "F.Fab")
		)
		(fp_line
			(start 0.12065 -0.2794)
			(end 0.12065 -0.3048)
			(stroke
				(width 0.1)
				(type default)
			)
			(layer "F.Fab")
		)
		(fp_line
			(start 0.12065 -0.3048)
			(end 0.67945 -0.3048)
			(stroke
				(width 0.1)
				(type default)
			)
			(layer "F.Fab")
		)
		(fp_line
			(start 0.120396 0.3048)
			(end 0.120396 0.2794)
			(stroke
				(width 0.1)
				(type default)
			)
			(layer "F.Fab")
		)
		(fp_line
			(start 0.120396 0.2794)
			(end -0.12065 0.2794)
			(stroke
				(width 0.1)
				(type default)
			)
			(layer "F.Fab")
		)
		(fp_line
			(start -0.12065 0.3048)
			(end -0.67945 0.3048)
			(stroke
				(width 0.1)
				(type default)
			)
			(layer "F.Fab")
		)
		(fp_line
			(start -0.12065 0.2794)
			(end -0.12065 0.3048)
			(stroke
				(width 0.1)
				(type default)
			)
			(layer "F.Fab")
		)
		(fp_line
			(start -0.12065 -0.2794)
			(end 0.12065 -0.2794)
			(stroke
				(width 0.1)
				(type default)
			)
			(layer "F.Fab")
		)
		(fp_line
			(start -0.12065 -0.305054)
			(end -0.12065 -0.2794)
			(stroke
				(width 0.1)
				(type default)
			)
			(layer "F.Fab")
		)
		(fp_line
			(start -0.67945 0.3048)
			(end -0.67945 -0.305054)
			(stroke
				(width 0.1)
				(type default)
			)
			(layer "F.Fab")
		)
		(fp_line
			(start -0.67945 -0.305054)
			(end -0.12065 -0.305054)
			(stroke
				(width 0.1)
				(type default)
			)
			(layer "F.Fab")
		)
		(pad "1" smd circle
			(at -0.40005 0 180)
			(size 0 0)
			(layers "F.Cu" "F.Mask" "F.Paste")
			(net "PRSNT_SSD10_FPGA_PCA9555_N")
		)
		(pad "2" smd circle
			(at 0.40005 0 180)
			(size 0 0)
			(layers "F.Cu" "F.Mask" "F.Paste")
			(net "PRSNT_SSD10_FPGA_R_N")
		)
	)
	(footprint ""
		(layer "F.Cu")
		(at 207.015842 -309.760366 135)
		(property "Reference" "R1318"
			(at 0 0 135)
			(layer "F.SilkS")
			(hide yes)
			(effects
				(font
					(size 1.27 1.27)
				)
			)
		)
		(property "Value" ""
			(at 0 0 135)
			(layer "F.Fab")
			(effects
				(font
					(size 1.27 1.27)
				)
			)
		)
		(duplicate_pad_numbers_are_jumpers no)
		(fp_line
			(start 0.787389 -0.406267)
			(end 0.787389 0.406267)
			(stroke
				(width 0.1524)
				(type default)
			)
			(layer "F.SilkS")
		)
		(fp_line
			(start 0.787389 0.406267)
			(end -0.787389 0.406267)
			(stroke
				(width 0.1524)
				(type default)
			)
			(layer "F.SilkS")
		)
		(fp_line
			(start -0.787389 -0.406267)
			(end 0.787389 -0.406267)
			(stroke
				(width 0.1524)
				(type default)
			)
			(layer "F.SilkS")
		)
		(fp_line
			(start -0.787389 0.406267)
			(end -0.787389 -0.406267)
			(stroke
				(width 0.1524)
				(type default)
			)
			(layer "F.SilkS")
		)
		(fp_line
			(start 0.679446 -0.30479)
			(end 0.679446 0.30479)
			(stroke
				(width 0.1)
				(type default)
			)
			(layer "F.Fab")
		)
		(fp_line
			(start 0.120515 -0.30479)
			(end 0.679446 -0.30479)
			(stroke
				(width 0.1)
				(type default)
			)
			(layer "F.Fab")
		)
		(fp_line
			(start 0.120695 -0.279466)
			(end 0.120515 -0.30479)
			(stroke
				(width 0.1)
				(type default)
			)
			(layer "F.Fab")
		)
		(fp_line
			(start 0.679446 0.30479)
			(end 0.120515 0.30479)
			(stroke
				(width 0.1)
				(type default)
			)
			(layer "F.Fab")
		)
		(fp_line
			(start -0.120695 -0.304969)
			(end -0.120695 -0.279466)
			(stroke
				(width 0.1)
				(type default)
			)
			(layer "F.Fab")
		)
		(fp_line
			(start -0.120695 -0.279466)
			(end 0.120695 -0.279466)
			(stroke
				(width 0.1)
				(type default)
			)
			(layer "F.Fab")
		)
		(fp_line
			(start 0.120335 0.279466)
			(end -0.120695 0.279466)
			(stroke
				(width 0.1)
				(type default)
			)
			(layer "F.Fab")
		)
		(fp_line
			(start 0.120515 0.30479)
			(end 0.120335 0.279466)
			(stroke
				(width 0.1)
				(type default)
			)
			(layer "F.Fab")
		)
		(fp_line
			(start -0.679446 -0.305149)
			(end -0.120695 -0.304969)
			(stroke
				(width 0.1)
				(type default)
			)
			(layer "F.Fab")
		)
		(fp_line
			(start -0.120695 0.279466)
			(end -0.120515 0.30479)
			(stroke
				(width 0.1)
				(type default)
			)
			(layer "F.Fab")
		)
		(fp_line
			(start -0.120515 0.30479)
			(end -0.679446 0.30479)
			(stroke
				(width 0.1)
				(type default)
			)
			(layer "F.Fab")
		)
		(fp_line
			(start -0.679446 0.30479)
			(end -0.679446 -0.305149)
			(stroke
				(width 0.1)
				(type default)
			)
			(layer "F.Fab")
		)
		(pad "1" smd circle
			(at -0.40005 0 135)
			(size 0 0)
			(layers "F.Cu" "F.Mask" "F.Paste")
			(net "GND")
		)
		(pad "2" smd circle
			(at 0.40005 0 135)
			(size 0 0)
			(layers "F.Cu" "F.Mask" "F.Paste")
			(net "PEX1_SPARE0")
		)
	)
	(footprint ""
		(layer "F.Cu")
		(at 29.422344 -250.070874 -90)
		(property "Reference" "R1155"
			(at 0 0 270)
			(layer "F.SilkS")
			(hide yes)
			(effects
				(font
					(size 1.27 1.27)
				)
			)
		)
		(property "Value" ""
			(at 0 0 270)
			(layer "F.Fab")
			(effects
				(font
					(size 1.27 1.27)
				)
			)
		)
		(duplicate_pad_numbers_are_jumpers no)
		(fp_line
			(start -0.7874 0.4064)
			(end -0.7874 -0.4064)
			(stroke
				(width 0.1524)
				(type default)
			)
			(layer "F.SilkS")
		)
		(fp_line
			(start 0.7874 0.4064)
			(end -0.7874 0.4064)
			(stroke
				(width 0.1524)
				(type default)
			)
			(layer "F.SilkS")
		)
		(fp_line
			(start -0.7874 -0.4064)
			(end 0.7874 -0.4064)
			(stroke
				(width 0.1524)
				(type default)
			)
			(layer "F.SilkS")
		)
		(fp_line
			(start 0.7874 -0.4064)
			(end 0.7874 0.4064)
			(stroke
				(width 0.1524)
				(type default)
			)
			(layer "F.SilkS")
		)
		(fp_line
			(start -0.67945 0.3048)
			(end -0.67945 -0.305054)
			(stroke
				(width 0.1)
				(type default)
			)
			(layer "F.Fab")
		)
		(fp_line
			(start -0.12065 0.3048)
			(end -0.67945 0.3048)
			(stroke
				(width 0.1)
				(type default)
			)
			(layer "F.Fab")
		)
		(fp_line
			(start 0.120396 0.3048)
			(end 0.120396 0.2794)
			(stroke
				(width 0.1)
				(type default)
			)
			(layer "F.Fab")
		)
		(fp_line
			(start 0.67945 0.3048)
			(end 0.120396 0.3048)
			(stroke
				(width 0.1)
				(type default)
			)
			(layer "F.Fab")
		)
		(fp_line
			(start -0.12065 0.2794)
			(end -0.12065 0.3048)
			(stroke
				(width 0.1)
				(type default)
			)
			(layer "F.Fab")
		)
		(fp_line
			(start 0.120396 0.2794)
			(end -0.12065 0.2794)
			(stroke
				(width 0.1)
				(type default)
			)
			(layer "F.Fab")
		)
		(fp_line
			(start -0.12065 -0.2794)
			(end 0.12065 -0.2794)
			(stroke
				(width 0.1)
				(type default)
			)
			(layer "F.Fab")
		)
		(fp_line
			(start 0.12065 -0.2794)
			(end 0.12065 -0.3048)
			(stroke
				(width 0.1)
				(type default)
			)
			(layer "F.Fab")
		)
		(fp_line
			(start 0.12065 -0.3048)
			(end 0.67945 -0.3048)
			(stroke
				(width 0.1)
				(type default)
			)
			(layer "F.Fab")
		)
		(fp_line
			(start 0.67945 -0.3048)
			(end 0.67945 0.3048)
			(stroke
				(width 0.1)
				(type default)
			)
			(layer "F.Fab")
		)
		(fp_line
			(start -0.67945 -0.305054)
			(end -0.12065 -0.305054)
			(stroke
				(width 0.1)
				(type default)
			)
			(layer "F.Fab")
		)
		(fp_line
			(start -0.12065 -0.305054)
			(end -0.12065 -0.2794)
			(stroke
				(width 0.1)
				(type default)
			)
			(layer "F.Fab")
		)
		(pad "1" smd circle
			(at -0.40005 0 270)
			(size 0 0)
			(layers "F.Cu" "F.Mask" "F.Paste")
			(net "PEX0_MODE_SEL3")
		)
		(pad "2" smd circle
			(at 0.40005 0 270)
			(size 0 0)
			(layers "F.Cu" "F.Mask" "F.Paste")
			(net "P1V8_PEX")
		)
	)
	(footprint ""
		(layer "F.Cu")
		(at 316.500764 -350.098614 90)
		(property "Reference" "C554"
			(at 0 0 90)
			(layer "F.SilkS")
			(hide yes)
			(effects
				(font
					(size 1.27 1.27)
				)
			)
		)
		(property "Value" ""
			(at 0 0 90)
			(layer "F.Fab")
			(effects
				(font
					(size 1.27 1.27)
				)
			)
		)
		(duplicate_pad_numbers_are_jumpers no)
		(fp_line
			(start 0.299974 -0.150114)
			(end 0.299974 0.150114)
			(stroke
				(width 0.1)
				(type default)
			)
			(layer "F.Fab")
		)
		(fp_line
			(start -0.299974 -0.150114)
			(end 0.299974 -0.150114)
			(stroke
				(width 0.1)
				(type default)
			)
			(layer "F.Fab")
		)
		(fp_line
			(start 0.299974 0.150114)
			(end -0.299974 0.150114)
			(stroke
				(width 0.1)
				(type default)
			)
			(layer "F.Fab")
		)
		(fp_line
			(start -0.299974 0.150114)
			(end -0.299974 -0.150114)
			(stroke
				(width 0.1)
				(type default)
			)
			(layer "F.Fab")
		)
		(pad "1" smd rect
			(at -0.2667 0 90)
			(size 0.3048 0.381)
			(layers "F.Cu" "F.Mask" "F.Paste")
			(net "P5E_PEX2_STN6_TX_DN<110>")
		)
		(pad "2" smd rect
			(at 0.2667 0 90)
			(size 0.3048 0.381)
			(layers "F.Cu" "F.Mask" "F.Paste")
			(net "P5E_PEX2_STN6_TX_C_DN<110>")
		)
	)
	(footprint ""
		(layer "F.Cu")
		(at 16.837914 -413.969708 90)
		(property "Reference" "R5595"
			(at 0 0 90)
			(layer "F.SilkS")
			(hide yes)
			(effects
				(font
					(size 1.27 1.27)
				)
			)
		)
		(property "Value" ""
			(at 0 0 90)
			(layer "F.Fab")
			(effects
				(font
					(size 1.27 1.27)
				)
			)
		)
		(duplicate_pad_numbers_are_jumpers no)
		(fp_line
			(start 0.7874 -0.4064)
			(end 0.7874 0.4064)
			(stroke
				(width 0.1524)
				(type default)
			)
			(layer "F.SilkS")
		)
		(fp_line
			(start -0.7874 -0.4064)
			(end 0.7874 -0.4064)
			(stroke
				(width 0.1524)
				(type default)
			)
			(layer "F.SilkS")
		)
		(fp_line
			(start 0.7874 0.4064)
			(end -0.7874 0.4064)
			(stroke
				(width 0.1524)
				(type default)
			)
			(layer "F.SilkS")
		)
		(fp_line
			(start -0.7874 0.4064)
			(end -0.7874 -0.4064)
			(stroke
				(width 0.1524)
				(type default)
			)
			(layer "F.SilkS")
		)
		(fp_line
			(start -0.12065 -0.305054)
			(end -0.12065 -0.2794)
			(stroke
				(width 0.1)
				(type default)
			)
			(layer "F.Fab")
		)
		(fp_line
			(start -0.67945 -0.305054)
			(end -0.12065 -0.305054)
			(stroke
				(width 0.1)
				(type default)
			)
			(layer "F.Fab")
		)
		(fp_line
			(start 0.67945 -0.3048)
			(end 0.67945 0.3048)
			(stroke
				(width 0.1)
				(type default)
			)
			(layer "F.Fab")
		)
		(fp_line
			(start 0.12065 -0.3048)
			(end 0.67945 -0.3048)
			(stroke
				(width 0.1)
				(type default)
			)
			(layer "F.Fab")
		)
		(fp_line
			(start 0.12065 -0.2794)
			(end 0.12065 -0.3048)
			(stroke
				(width 0.1)
				(type default)
			)
			(layer "F.Fab")
		)
		(fp_line
			(start -0.12065 -0.2794)
			(end 0.12065 -0.2794)
			(stroke
				(width 0.1)
				(type default)
			)
			(layer "F.Fab")
		)
		(fp_line
			(start 0.120396 0.2794)
			(end -0.12065 0.2794)
			(stroke
				(width 0.1)
				(type default)
			)
			(layer "F.Fab")
		)
		(fp_line
			(start -0.12065 0.2794)
			(end -0.12065 0.3048)
			(stroke
				(width 0.1)
				(type default)
			)
			(layer "F.Fab")
		)
		(fp_line
			(start 0.67945 0.3048)
			(end 0.120396 0.3048)
			(stroke
				(width 0.1)
				(type default)
			)
			(layer "F.Fab")
		)
		(fp_line
			(start 0.120396 0.3048)
			(end 0.120396 0.2794)
			(stroke
				(width 0.1)
				(type default)
			)
			(layer "F.Fab")
		)
		(fp_line
			(start -0.12065 0.3048)
			(end -0.67945 0.3048)
			(stroke
				(width 0.1)
				(type default)
			)
			(layer "F.Fab")
		)
		(fp_line
			(start -0.67945 0.3048)
			(end -0.67945 -0.305054)
			(stroke
				(width 0.1)
				(type default)
			)
			(layer "F.Fab")
		)
		(pad "1" smd circle
			(at -0.40005 0 90)
			(size 0 0)
			(layers "F.Cu" "F.Mask" "F.Paste")
			(net "LM75_0_A0")
		)
		(pad "2" smd circle
			(at 0.40005 0 90)
			(size 0 0)
			(layers "F.Cu" "F.Mask" "F.Paste")
			(net "GND")
		)
	)
	(footprint ""
		(layer "F.Cu")
		(at 303.698402 -66.32194 -90)
		(property "Reference" "PC871"
			(at 0 0 270)
			(layer "F.SilkS")
			(hide yes)
			(effects
				(font
					(size 1.27 1.27)
				)
			)
		)
		(property "Value" ""
			(at 0 0 270)
			(layer "F.Fab")
			(effects
				(font
					(size 1.27 1.27)
				)
			)
		)
		(duplicate_pad_numbers_are_jumpers no)
		(fp_line
			(start -0.7874 0.4064)
			(end -0.7874 -0.4064)
			(stroke
				(width 0.1524)
				(type default)
			)
			(layer "F.SilkS")
		)
		(fp_line
			(start 0.7874 0.4064)
			(end -0.7874 0.4064)
			(stroke
				(width 0.1524)
				(type default)
			)
			(layer "F.SilkS")
		)
		(fp_line
			(start -0.7874 -0.4064)
			(end 0.7874 -0.4064)
			(stroke
				(width 0.1524)
				(type default)
			)
			(layer "F.SilkS")
		)
		(fp_line
			(start 0.7874 -0.4064)
			(end 0.7874 0.4064)
			(stroke
				(width 0.1524)
				(type default)
			)
			(layer "F.SilkS")
		)
		(fp_line
			(start -0.67945 0.3048)
			(end -0.67945 -0.305054)
			(stroke
				(width 0.1)
				(type default)
			)
			(layer "F.Fab")
		)
		(fp_line
			(start -0.12065 0.3048)
			(end -0.67945 0.3048)
			(stroke
				(width 0.1)
				(type default)
			)
			(layer "F.Fab")
		)
		(fp_line
			(start 0.120396 0.3048)
			(end 0.120396 0.2794)
			(stroke
				(width 0.1)
				(type default)
			)
			(layer "F.Fab")
		)
		(fp_line
			(start 0.67945 0.3048)
			(end 0.120396 0.3048)
			(stroke
				(width 0.1)
				(type default)
			)
			(layer "F.Fab")
		)
		(fp_line
			(start -0.12065 0.2794)
			(end -0.12065 0.3048)
			(stroke
				(width 0.1)
				(type default)
			)
			(layer "F.Fab")
		)
		(fp_line
			(start 0.120396 0.2794)
			(end -0.12065 0.2794)
			(stroke
				(width 0.1)
				(type default)
			)
			(layer "F.Fab")
		)
		(fp_line
			(start -0.12065 -0.2794)
			(end 0.12065 -0.2794)
			(stroke
				(width 0.1)
				(type default)
			)
			(layer "F.Fab")
		)
		(fp_line
			(start 0.12065 -0.2794)
			(end 0.12065 -0.3048)
			(stroke
				(width 0.1)
				(type default)
			)
			(layer "F.Fab")
		)
		(fp_line
			(start 0.12065 -0.3048)
			(end 0.67945 -0.3048)
			(stroke
				(width 0.1)
				(type default)
			)
			(layer "F.Fab")
		)
		(fp_line
			(start 0.67945 -0.3048)
			(end 0.67945 0.3048)
			(stroke
				(width 0.1)
				(type default)
			)
			(layer "F.Fab")
		)
		(fp_line
			(start -0.67945 -0.305054)
			(end -0.12065 -0.305054)
			(stroke
				(width 0.1)
				(type default)
			)
			(layer "F.Fab")
		)
		(fp_line
			(start -0.12065 -0.305054)
			(end -0.12065 -0.2794)
			(stroke
				(width 0.1)
				(type default)
			)
			(layer "F.Fab")
		)
		(pad "1" smd circle
			(at -0.40005 0 270)
			(size 0 0)
			(layers "F.Cu" "F.Mask" "F.Paste")
			(net "P12V_SSD10_CO_GATE")
		)
		(pad "2" smd circle
			(at 0.40005 0 270)
			(size 0 0)
			(layers "F.Cu" "F.Mask" "F.Paste")
			(net "GND")
		)
	)
	(footprint ""
		(layer "F.Cu")
		(at 118.441978 -27.006296 -90)
		(property "Reference" "PR7108"
			(at 0 0 270)
			(layer "F.SilkS")
			(hide yes)
			(effects
				(font
					(size 1.27 1.27)
				)
			)
		)
		(property "Value" ""
			(at 0 0 270)
			(layer "F.Fab")
			(effects
				(font
					(size 1.27 1.27)
				)
			)
		)
		(duplicate_pad_numbers_are_jumpers no)
		(fp_line
			(start -0.7874 0.4064)
			(end -0.7874 -0.4064)
			(stroke
				(width 0.1524)
				(type default)
			)
			(layer "F.SilkS")
		)
		(fp_line
			(start 0.7874 0.4064)
			(end -0.7874 0.4064)
			(stroke
				(width 0.1524)
				(type default)
			)
			(layer "F.SilkS")
		)
		(fp_line
			(start -0.7874 -0.4064)
			(end 0.7874 -0.4064)
			(stroke
				(width 0.1524)
				(type default)
			)
			(layer "F.SilkS")
		)
		(fp_line
			(start 0.7874 -0.4064)
			(end 0.7874 0.4064)
			(stroke
				(width 0.1524)
				(type default)
			)
			(layer "F.SilkS")
		)
		(fp_line
			(start -0.67945 0.3048)
			(end -0.67945 -0.305054)
			(stroke
				(width 0.1)
				(type default)
			)
			(layer "F.Fab")
		)
		(fp_line
			(start -0.12065 0.3048)
			(end -0.67945 0.3048)
			(stroke
				(width 0.1)
				(type default)
			)
			(layer "F.Fab")
		)
		(fp_line
			(start 0.120396 0.3048)
			(end 0.120396 0.2794)
			(stroke
				(width 0.1)
				(type default)
			)
			(layer "F.Fab")
		)
		(fp_line
			(start 0.67945 0.3048)
			(end 0.120396 0.3048)
			(stroke
				(width 0.1)
				(type default)
			)
			(layer "F.Fab")
		)
		(fp_line
			(start -0.12065 0.2794)
			(end -0.12065 0.3048)
			(stroke
				(width 0.1)
				(type default)
			)
			(layer "F.Fab")
		)
		(fp_line
			(start 0.120396 0.2794)
			(end -0.12065 0.2794)
			(stroke
				(width 0.1)
				(type default)
			)
			(layer "F.Fab")
		)
		(fp_line
			(start -0.12065 -0.2794)
			(end 0.12065 -0.2794)
			(stroke
				(width 0.1)
				(type default)
			)
			(layer "F.Fab")
		)
		(fp_line
			(start 0.12065 -0.2794)
			(end 0.12065 -0.3048)
			(stroke
				(width 0.1)
				(type default)
			)
			(layer "F.Fab")
		)
		(fp_line
			(start 0.12065 -0.3048)
			(end 0.67945 -0.3048)
			(stroke
				(width 0.1)
				(type default)
			)
			(layer "F.Fab")
		)
		(fp_line
			(start 0.67945 -0.3048)
			(end 0.67945 0.3048)
			(stroke
				(width 0.1)
				(type default)
			)
			(layer "F.Fab")
		)
		(fp_line
			(start -0.67945 -0.305054)
			(end -0.12065 -0.305054)
			(stroke
				(width 0.1)
				(type default)
			)
			(layer "F.Fab")
		)
		(fp_line
			(start -0.12065 -0.305054)
			(end -0.12065 -0.2794)
			(stroke
				(width 0.1)
				(type default)
			)
			(layer "F.Fab")
		)
		(pad "1" smd circle
			(at -0.40005 0 270)
			(size 0 0)
			(layers "F.Cu" "F.Mask" "F.Paste")
			(net "P3V3_SSD4_CO_ILIMIT")
		)
		(pad "2" smd circle
			(at 0.40005 0 270)
			(size 0 0)
			(layers "F.Cu" "F.Mask" "F.Paste")
			(net "GND")
		)
	)
	(footprint ""
		(layer "F.Cu")
		(at 267.718286 -250.070874 -90)
		(property "Reference" "R1348"
			(at 0 0 270)
			(layer "F.SilkS")
			(hide yes)
			(effects
				(font
					(size 1.27 1.27)
				)
			)
		)
		(property "Value" ""
			(at 0 0 270)
			(layer "F.Fab")
			(effects
				(font
					(size 1.27 1.27)
				)
			)
		)
		(duplicate_pad_numbers_are_jumpers no)
		(fp_line
			(start -0.7874 0.4064)
			(end -0.7874 -0.4064)
			(stroke
				(width 0.1524)
				(type default)
			)
			(layer "F.SilkS")
		)
		(fp_line
			(start 0.7874 0.4064)
			(end -0.7874 0.4064)
			(stroke
				(width 0.1524)
				(type default)
			)
			(layer "F.SilkS")
		)
		(fp_line
			(start -0.7874 -0.4064)
			(end 0.7874 -0.4064)
			(stroke
				(width 0.1524)
				(type default)
			)
			(layer "F.SilkS")
		)
		(fp_line
			(start 0.7874 -0.4064)
			(end 0.7874 0.4064)
			(stroke
				(width 0.1524)
				(type default)
			)
			(layer "F.SilkS")
		)
		(fp_line
			(start -0.67945 0.3048)
			(end -0.67945 -0.305054)
			(stroke
				(width 0.1)
				(type default)
			)
			(layer "F.Fab")
		)
		(fp_line
			(start -0.12065 0.3048)
			(end -0.67945 0.3048)
			(stroke
				(width 0.1)
				(type default)
			)
			(layer "F.Fab")
		)
		(fp_line
			(start 0.120396 0.3048)
			(end 0.120396 0.2794)
			(stroke
				(width 0.1)
				(type default)
			)
			(layer "F.Fab")
		)
		(fp_line
			(start 0.67945 0.3048)
			(end 0.120396 0.3048)
			(stroke
				(width 0.1)
				(type default)
			)
			(layer "F.Fab")
		)
		(fp_line
			(start -0.12065 0.2794)
			(end -0.12065 0.3048)
			(stroke
				(width 0.1)
				(type default)
			)
			(layer "F.Fab")
		)
		(fp_line
			(start 0.120396 0.2794)
			(end -0.12065 0.2794)
			(stroke
				(width 0.1)
				(type default)
			)
			(layer "F.Fab")
		)
		(fp_line
			(start -0.12065 -0.2794)
			(end 0.12065 -0.2794)
			(stroke
				(width 0.1)
				(type default)
			)
			(layer "F.Fab")
		)
		(fp_line
			(start 0.12065 -0.2794)
			(end 0.12065 -0.3048)
			(stroke
				(width 0.1)
				(type default)
			)
			(layer "F.Fab")
		)
		(fp_line
			(start 0.12065 -0.3048)
			(end 0.67945 -0.3048)
			(stroke
				(width 0.1)
				(type default)
			)
			(layer "F.Fab")
		)
		(fp_line
			(start 0.67945 -0.3048)
			(end 0.67945 0.3048)
			(stroke
				(width 0.1)
				(type default)
			)
			(layer "F.Fab")
		)
		(fp_line
			(start -0.67945 -0.305054)
			(end -0.12065 -0.305054)
			(stroke
				(width 0.1)
				(type default)
			)
			(layer "F.Fab")
		)
		(fp_line
			(start -0.12065 -0.305054)
			(end -0.12065 -0.2794)
			(stroke
				(width 0.1)
				(type default)
			)
			(layer "F.Fab")
		)
		(pad "1" smd circle
			(at -0.40005 0 270)
			(size 0 0)
			(layers "F.Cu" "F.Mask" "F.Paste")
			(net "PEX2_MODE_SEL12")
		)
		(pad "2" smd circle
			(at 0.40005 0 270)
			(size 0 0)
			(layers "F.Cu" "F.Mask" "F.Paste")
			(net "P1V8_PEX")
		)
	)
	(footprint ""
		(layer "F.Cu")
		(at 312.759344 18.028412 180)
		(property "Reference" "DE03F_1"
			(at 2.853944 2.990342 0)
			(unlocked yes)
			(layer "F.SilkS")
			(effects
				(font
					(size 0.7874 0.5842)
					(thickness 0.1524)
				)
				(justify left)
			)
		)
		(property "Value" ""
			(at 0 0 180)
			(layer "F.Fab")
			(effects
				(font
					(size 1.27 1.27)
				)
			)
		)
		(duplicate_pad_numbers_are_jumpers no)
		(fp_line
			(start 1.2192 2.1082)
			(end -1.2192 2.1082)
			(stroke
				(width 0.1524)
				(type default)
			)
			(layer "F.SilkS")
		)
		(fp_line
			(start 1.2192 -2.1082)
			(end 1.2192 2.1082)
			(stroke
				(width 0.1524)
				(type default)
			)
			(layer "F.SilkS")
		)
		(fp_line
			(start -1.2192 2.1082)
			(end -1.2192 -2.1082)
			(stroke
				(width 0.1524)
				(type default)
			)
			(layer "F.SilkS")
		)
		(fp_line
			(start -1.2192 -2.1082)
			(end 1.2192 -2.1082)
			(stroke
				(width 0.1524)
				(type default)
			)
			(layer "F.SilkS")
		)
		(pad "" np_thru_hole circle
			(at -2.8829 -1.27 90)
			(size 1.0414 1.0414)
			(drill 1.0414)
			(layers "*.Cu" "*.Mask")
			(clearance 0.381)
			(thermal_gap 0.381)
		)
		(pad "" np_thru_hole circle
			(at -2.8829 1.27 90)
			(size 1.0414 1.0414)
			(drill 1.0414)
			(layers "*.Cu" "*.Mask")
			(clearance 0.381)
			(thermal_gap 0.381)
		)
		(pad "" np_thru_hole circle
			(at 3.4671 -1.27 90)
			(size 1.0414 1.0414)
			(drill 1.0414)
			(layers "*.Cu" "*.Mask")
			(clearance 0.381)
			(thermal_gap 0.381)
		)
		(pad "" np_thru_hole circle
			(at 3.4671 1.27 90)
			(size 1.0414 1.0414)
			(drill 1.0414)
			(layers "*.Cu" "*.Mask")
			(clearance 0.381)
			(thermal_gap 0.381)
		)
		(pad "1" smd rect
			(at 0.8255 -0.249936 90)
			(size 0.3048 0.508)
			(layers "F.Cu" "F.Mask" "F.Paste")
			(net "85_5INCH_IN1_DN")
		)
		(pad "2" smd rect
			(at 0.8255 0.249936 90)
			(size 0.3048 0.508)
			(layers "F.Cu" "F.Mask" "F.Paste")
			(net "85_5INCH_IN1_DP")
		)
		(pad "3" smd circle
			(at 0 0 180)
			(size 0 0)
			(layers "F.Cu" "F.Mask" "F.Paste")
			(net "COUPON_GND2")
		)
		(zone
			(layer "F.Cu")
			(hatch none 0.5)
			(connect_pads
				(clearance 0)
			)
			(min_thickness 0.25)
			(keepout
				(tracks not_allowed)
				(vias allowed)
				(pads allowed)
				(copperpour not_allowed)
				(footprints allowed)
			)
			(placement
				(enabled no)
				(sheetname "")
			)
			(fill
				(thermal_gap 0.5)
				(thermal_bridge_width 0.5)
				(island_removal_mode 0)
			)
			(polygon
				(pts
					(xy 311.641744 18.577052) (xy 311.641744 18.481548) (xy 312.238644 18.481548) (xy 312.238644 18.075148)
					(xy 311.641744 18.075148) (xy 311.641744 17.981676) (xy 312.238644 17.981676) (xy 312.238644 17.575276)
					(xy 311.641744 17.575276) (xy 311.641744 17.479772) (xy 312.340244 17.479772) (xy 312.340244 18.577052)
				)
			)
		)
		(zone
			(layers "F.Cu" "B.Cu" "In1.Cu" "In2.Cu" "In3.Cu" "In4.Cu" "In5.Cu" "In6.Cu"
				"In7.Cu" "In8.Cu" "In9.Cu" "In10.Cu" "In11.Cu" "In12.Cu" "In13.Cu" "In14.Cu"
				"In15.Cu" "In16.Cu"
			)
			(hatch none 0.5)
			(connect_pads
				(clearance 0)
			)
			(min_thickness 0.25)
			(keepout
				(tracks not_allowed)
				(vias allowed)
				(pads allowed)
				(copperpour not_allowed)
				(footprints allowed)
			)
			(placement
				(enabled no)
				(sheetname "")
			)
			(fill
				(thermal_gap 0.5)
				(thermal_bridge_width 0.5)
				(island_removal_mode 0)
			)
			(polygon
				(pts
					(arc
						(start 310.219344 16.758412)
						(mid 308.365144 16.758412)
						(end 310.219344 16.758412)
					)
				)
			)
		)
		(zone
			(layers "F.Cu" "B.Cu" "In1.Cu" "In2.Cu" "In3.Cu" "In4.Cu" "In5.Cu" "In6.Cu"
				"In7.Cu" "In8.Cu" "In9.Cu" "In10.Cu" "In11.Cu" "In12.Cu" "In13.Cu" "In14.Cu"
				"In15.Cu" "In16.Cu"
			)
			(hatch none 0.5)
			(connect_pads
				(clearance 0)
			)
			(min_thickness 0.25)
			(keepout
				(tracks not_allowed)
				(vias allowed)
				(pads allowed)
				(copperpour not_allowed)
				(footprints allowed)
			)
			(placement
				(enabled no)
				(sheetname "")
			)
			(fill
				(thermal_gap 0.5)
				(thermal_bridge_width 0.5)
				(island_removal_mode 0)
			)
			(polygon
				(pts
					(arc
						(start 310.219344 19.298412)
						(mid 308.365144 19.298412)
						(end 310.219344 19.298412)
					)
				)
			)
		)
		(zone
			(layers "F.Cu" "B.Cu" "In1.Cu" "In2.Cu" "In3.Cu" "In4.Cu" "In5.Cu" "In6.Cu"
				"In7.Cu" "In8.Cu" "In9.Cu" "In10.Cu" "In11.Cu" "In12.Cu" "In13.Cu" "In14.Cu"
				"In15.Cu" "In16.Cu"
			)
			(hatch none 0.5)
			(connect_pads
				(clearance 0)
			)
			(min_thickness 0.25)
			(keepout
				(tracks not_allowed)
				(vias allowed)
				(pads allowed)
				(copperpour not_allowed)
				(footprints allowed)
			)
			(placement
				(enabled no)
				(sheetname "")
			)
			(fill
				(thermal_gap 0.5)
				(thermal_bridge_width 0.5)
				(island_removal_mode 0)
			)
			(polygon
				(pts
					(arc
						(start 316.569344 16.758412)
						(mid 314.715144 16.758412)
						(end 316.569344 16.758412)
					)
				)
			)
		)
		(zone
			(layers "F.Cu" "B.Cu" "In1.Cu" "In2.Cu" "In3.Cu" "In4.Cu" "In5.Cu" "In6.Cu"
				"In7.Cu" "In8.Cu" "In9.Cu" "In10.Cu" "In11.Cu" "In12.Cu" "In13.Cu" "In14.Cu"
				"In15.Cu" "In16.Cu"
			)
			(hatch none 0.5)
			(connect_pads
				(clearance 0)
			)
			(min_thickness 0.25)
			(keepout
				(tracks not_allowed)
				(vias allowed)
				(pads allowed)
				(copperpour not_allowed)
				(footprints allowed)
			)
			(placement
				(enabled no)
				(sheetname "")
			)
			(fill
				(thermal_gap 0.5)
				(thermal_bridge_width 0.5)
				(island_removal_mode 0)
			)
			(polygon
				(pts
					(arc
						(start 316.569344 19.298412)
						(mid 314.715144 19.298412)
						(end 316.569344 19.298412)
					)
				)
			)
		)
	)
	(footprint ""
		(layer "F.Cu")
		(at 179.777644 -113.251742)
		(property "Reference" "R188"
			(at 0 0 0)
			(layer "F.SilkS")
			(hide yes)
			(effects
				(font
					(size 1.27 1.27)
				)
			)
		)
		(property "Value" ""
			(at 0 0 0)
			(layer "F.Fab")
			(effects
				(font
					(size 1.27 1.27)
				)
			)
		)
		(duplicate_pad_numbers_are_jumpers no)
		(fp_line
			(start -0.7874 -0.4064)
			(end 0.7874 -0.4064)
			(stroke
				(width 0.1524)
				(type default)
			)
			(layer "F.SilkS")
		)
		(fp_line
			(start -0.7874 0.4064)
			(end -0.7874 -0.4064)
			(stroke
				(width 0.1524)
				(type default)
			)
			(layer "F.SilkS")
		)
		(fp_line
			(start 0.7874 -0.4064)
			(end 0.7874 0.4064)
			(stroke
				(width 0.1524)
				(type default)
			)
			(layer "F.SilkS")
		)
		(fp_line
			(start 0.7874 0.4064)
			(end -0.7874 0.4064)
			(stroke
				(width 0.1524)
				(type default)
			)
			(layer "F.SilkS")
		)
		(fp_line
			(start -0.67945 -0.305054)
			(end -0.12065 -0.305054)
			(stroke
				(width 0.1)
				(type default)
			)
			(layer "F.Fab")
		)
		(fp_line
			(start -0.67945 0.3048)
			(end -0.67945 -0.305054)
			(stroke
				(width 0.1)
				(type default)
			)
			(layer "F.Fab")
		)
		(fp_line
			(start -0.12065 -0.305054)
			(end -0.12065 -0.2794)
			(stroke
				(width 0.1)
				(type default)
			)
			(layer "F.Fab")
		)
		(fp_line
			(start -0.12065 -0.2794)
			(end 0.12065 -0.2794)
			(stroke
				(width 0.1)
				(type default)
			)
			(layer "F.Fab")
		)
		(fp_line
			(start -0.12065 0.2794)
			(end -0.12065 0.3048)
			(stroke
				(width 0.1)
				(type default)
			)
			(layer "F.Fab")
		)
		(fp_line
			(start -0.12065 0.3048)
			(end -0.67945 0.3048)
			(stroke
				(width 0.1)
				(type default)
			)
			(layer "F.Fab")
		)
		(fp_line
			(start 0.120396 0.2794)
			(end -0.12065 0.2794)
			(stroke
				(width 0.1)
				(type default)
			)
			(layer "F.Fab")
		)
		(fp_line
			(start 0.120396 0.3048)
			(end 0.120396 0.2794)
			(stroke
				(width 0.1)
				(type default)
			)
			(layer "F.Fab")
		)
		(fp_line
			(start 0.12065 -0.3048)
			(end 0.67945 -0.3048)
			(stroke
				(width 0.1)
				(type default)
			)
			(layer "F.Fab")
		)
		(fp_line
			(start 0.12065 -0.2794)
			(end 0.12065 -0.3048)
			(stroke
				(width 0.1)
				(type default)
			)
			(layer "F.Fab")
		)
		(fp_line
			(start 0.67945 -0.3048)
			(end 0.67945 0.3048)
			(stroke
				(width 0.1)
				(type default)
			)
			(layer "F.Fab")
		)
		(fp_line
			(start 0.67945 0.3048)
			(end 0.120396 0.3048)
			(stroke
				(width 0.1)
				(type default)
			)
			(layer "F.Fab")
		)
		(pad "1" smd circle
			(at -0.40005 0)
			(size 0 0)
			(layers "F.Cu" "F.Mask" "F.Paste")
			(net "RST_SMB_NIC3_MUX_ISO_N")
		)
		(pad "2" smd circle
			(at 0.40005 0)
			(size 0 0)
			(layers "F.Cu" "F.Mask" "F.Paste")
			(net "P3V3_NIC3")
		)
	)
	(footprint ""
		(layer "F.Cu")
		(at 435.02961 -300.62043 90)
		(property "Reference" "R6398"
			(at 0 0 90)
			(layer "F.SilkS")
			(hide yes)
			(effects
				(font
					(size 1.27 1.27)
				)
			)
		)
		(property "Value" ""
			(at 0 0 90)
			(layer "F.Fab")
			(effects
				(font
					(size 1.27 1.27)
				)
			)
		)
		(duplicate_pad_numbers_are_jumpers no)
		(fp_line
			(start 0.7874 -0.4064)
			(end 0.7874 0.4064)
			(stroke
				(width 0.1524)
				(type default)
			)
			(layer "F.SilkS")
		)
		(fp_line
			(start -0.7874 -0.4064)
			(end 0.7874 -0.4064)
			(stroke
				(width 0.1524)
				(type default)
			)
			(layer "F.SilkS")
		)
		(fp_line
			(start 0.7874 0.4064)
			(end -0.7874 0.4064)
			(stroke
				(width 0.1524)
				(type default)
			)
			(layer "F.SilkS")
		)
		(fp_line
			(start -0.7874 0.4064)
			(end -0.7874 -0.4064)
			(stroke
				(width 0.1524)
				(type default)
			)
			(layer "F.SilkS")
		)
		(fp_line
			(start -0.12065 -0.305054)
			(end -0.12065 -0.2794)
			(stroke
				(width 0.1)
				(type default)
			)
			(layer "F.Fab")
		)
		(fp_line
			(start -0.67945 -0.305054)
			(end -0.12065 -0.305054)
			(stroke
				(width 0.1)
				(type default)
			)
			(layer "F.Fab")
		)
		(fp_line
			(start 0.67945 -0.3048)
			(end 0.67945 0.3048)
			(stroke
				(width 0.1)
				(type default)
			)
			(layer "F.Fab")
		)
		(fp_line
			(start 0.12065 -0.3048)
			(end 0.67945 -0.3048)
			(stroke
				(width 0.1)
				(type default)
			)
			(layer "F.Fab")
		)
		(fp_line
			(start 0.12065 -0.2794)
			(end 0.12065 -0.3048)
			(stroke
				(width 0.1)
				(type default)
			)
			(layer "F.Fab")
		)
		(fp_line
			(start -0.12065 -0.2794)
			(end 0.12065 -0.2794)
			(stroke
				(width 0.1)
				(type default)
			)
			(layer "F.Fab")
		)
		(fp_line
			(start 0.120396 0.2794)
			(end -0.12065 0.2794)
			(stroke
				(width 0.1)
				(type default)
			)
			(layer "F.Fab")
		)
		(fp_line
			(start -0.12065 0.2794)
			(end -0.12065 0.3048)
			(stroke
				(width 0.1)
				(type default)
			)
			(layer "F.Fab")
		)
		(fp_line
			(start 0.67945 0.3048)
			(end 0.120396 0.3048)
			(stroke
				(width 0.1)
				(type default)
			)
			(layer "F.Fab")
		)
		(fp_line
			(start 0.120396 0.3048)
			(end 0.120396 0.2794)
			(stroke
				(width 0.1)
				(type default)
			)
			(layer "F.Fab")
		)
		(fp_line
			(start -0.12065 0.3048)
			(end -0.67945 0.3048)
			(stroke
				(width 0.1)
				(type default)
			)
			(layer "F.Fab")
		)
		(fp_line
			(start -0.67945 0.3048)
			(end -0.67945 -0.305054)
			(stroke
				(width 0.1)
				(type default)
			)
			(layer "F.Fab")
		)
		(pad "1" smd circle
			(at -0.40005 0 90)
			(size 0 0)
			(layers "F.Cu" "F.Mask" "F.Paste")
			(net "RST_PEX3_S3_PERST_N")
		)
		(pad "2" smd circle
			(at 0.40005 0 90)
			(size 0 0)
			(layers "F.Cu" "F.Mask" "F.Paste")
			(net "RST_PEX3_S3_PERST_R_N")
		)
	)
	(footprint ""
		(layer "F.Cu")
		(at 442.25464 -124.159264 180)
		(property "Reference" "PC472"
			(at 0 0 180)
			(layer "F.SilkS")
			(hide yes)
			(effects
				(font
					(size 1.27 1.27)
				)
			)
		)
		(property "Value" ""
			(at 0 0 180)
			(layer "F.Fab")
			(effects
				(font
					(size 1.27 1.27)
				)
			)
		)
		(duplicate_pad_numbers_are_jumpers no)
		(fp_line
			(start 0.7874 0.4064)
			(end -0.7874 0.4064)
			(stroke
				(width 0.1524)
				(type default)
			)
			(layer "F.SilkS")
		)
		(fp_line
			(start 0.7874 -0.4064)
			(end 0.7874 0.4064)
			(stroke
				(width 0.1524)
				(type default)
			)
			(layer "F.SilkS")
		)
		(fp_line
			(start -0.7874 0.4064)
			(end -0.7874 -0.4064)
			(stroke
				(width 0.1524)
				(type default)
			)
			(layer "F.SilkS")
		)
		(fp_line
			(start -0.7874 -0.4064)
			(end 0.7874 -0.4064)
			(stroke
				(width 0.1524)
				(type default)
			)
			(layer "F.SilkS")
		)
		(fp_line
			(start 0.67945 0.3048)
			(end 0.120396 0.3048)
			(stroke
				(width 0.1)
				(type default)
			)
			(layer "F.Fab")
		)
		(fp_line
			(start 0.67945 -0.3048)
			(end 0.67945 0.3048)
			(stroke
				(width 0.1)
				(type default)
			)
			(layer "F.Fab")
		)
		(fp_line
			(start 0.12065 -0.2794)
			(end 0.12065 -0.3048)
			(stroke
				(width 0.1)
				(type default)
			)
			(layer "F.Fab")
		)
		(fp_line
			(start 0.12065 -0.3048)
			(end 0.67945 -0.3048)
			(stroke
				(width 0.1)
				(type default)
			)
			(layer "F.Fab")
		)
		(fp_line
			(start 0.120396 0.3048)
			(end 0.120396 0.2794)
			(stroke
				(width 0.1)
				(type default)
			)
			(layer "F.Fab")
		)
		(fp_line
			(start 0.120396 0.2794)
			(end -0.12065 0.2794)
			(stroke
				(width 0.1)
				(type default)
			)
			(layer "F.Fab")
		)
		(fp_line
			(start -0.12065 0.3048)
			(end -0.67945 0.3048)
			(stroke
				(width 0.1)
				(type default)
			)
			(layer "F.Fab")
		)
		(fp_line
			(start -0.12065 0.2794)
			(end -0.12065 0.3048)
			(stroke
				(width 0.1)
				(type default)
			)
			(layer "F.Fab")
		)
		(fp_line
			(start -0.12065 -0.2794)
			(end 0.12065 -0.2794)
			(stroke
				(width 0.1)
				(type default)
			)
			(layer "F.Fab")
		)
		(fp_line
			(start -0.12065 -0.305054)
			(end -0.12065 -0.2794)
			(stroke
				(width 0.1)
				(type default)
			)
			(layer "F.Fab")
		)
		(fp_line
			(start -0.67945 0.3048)
			(end -0.67945 -0.305054)
			(stroke
				(width 0.1)
				(type default)
			)
			(layer "F.Fab")
		)
		(fp_line
			(start -0.67945 -0.305054)
			(end -0.12065 -0.305054)
			(stroke
				(width 0.1)
				(type default)
			)
			(layer "F.Fab")
		)
		(pad "1" smd circle
			(at -0.40005 0 180)
			(size 0 0)
			(layers "F.Cu" "F.Mask" "F.Paste")
			(net "P3V3_AUX")
		)
		(pad "2" smd circle
			(at 0.40005 0 180)
			(size 0 0)
			(layers "F.Cu" "F.Mask" "F.Paste")
			(net "GND")
		)
	)
	(footprint ""
		(layer "F.Cu")
		(at 319.949576 -300.60265 90)
		(property "Reference" "R6396"
			(at 0 0 90)
			(layer "F.SilkS")
			(hide yes)
			(effects
				(font
					(size 1.27 1.27)
				)
			)
		)
		(property "Value" ""
			(at 0 0 90)
			(layer "F.Fab")
			(effects
				(font
					(size 1.27 1.27)
				)
			)
		)
		(duplicate_pad_numbers_are_jumpers no)
		(fp_line
			(start 0.7874 -0.4064)
			(end 0.7874 0.4064)
			(stroke
				(width 0.1524)
				(type default)
			)
			(layer "F.SilkS")
		)
		(fp_line
			(start -0.7874 -0.4064)
			(end 0.7874 -0.4064)
			(stroke
				(width 0.1524)
				(type default)
			)
			(layer "F.SilkS")
		)
		(fp_line
			(start 0.7874 0.4064)
			(end -0.7874 0.4064)
			(stroke
				(width 0.1524)
				(type default)
			)
			(layer "F.SilkS")
		)
		(fp_line
			(start -0.7874 0.4064)
			(end -0.7874 -0.4064)
			(stroke
				(width 0.1524)
				(type default)
			)
			(layer "F.SilkS")
		)
		(fp_line
			(start -0.12065 -0.305054)
			(end -0.12065 -0.2794)
			(stroke
				(width 0.1)
				(type default)
			)
			(layer "F.Fab")
		)
		(fp_line
			(start -0.67945 -0.305054)
			(end -0.12065 -0.305054)
			(stroke
				(width 0.1)
				(type default)
			)
			(layer "F.Fab")
		)
		(fp_line
			(start 0.67945 -0.3048)
			(end 0.67945 0.3048)
			(stroke
				(width 0.1)
				(type default)
			)
			(layer "F.Fab")
		)
		(fp_line
			(start 0.12065 -0.3048)
			(end 0.67945 -0.3048)
			(stroke
				(width 0.1)
				(type default)
			)
			(layer "F.Fab")
		)
		(fp_line
			(start 0.12065 -0.2794)
			(end 0.12065 -0.3048)
			(stroke
				(width 0.1)
				(type default)
			)
			(layer "F.Fab")
		)
		(fp_line
			(start -0.12065 -0.2794)
			(end 0.12065 -0.2794)
			(stroke
				(width 0.1)
				(type default)
			)
			(layer "F.Fab")
		)
		(fp_line
			(start 0.120396 0.2794)
			(end -0.12065 0.2794)
			(stroke
				(width 0.1)
				(type default)
			)
			(layer "F.Fab")
		)
		(fp_line
			(start -0.12065 0.2794)
			(end -0.12065 0.3048)
			(stroke
				(width 0.1)
				(type default)
			)
			(layer "F.Fab")
		)
		(fp_line
			(start 0.67945 0.3048)
			(end 0.120396 0.3048)
			(stroke
				(width 0.1)
				(type default)
			)
			(layer "F.Fab")
		)
		(fp_line
			(start 0.120396 0.3048)
			(end 0.120396 0.2794)
			(stroke
				(width 0.1)
				(type default)
			)
			(layer "F.Fab")
		)
		(fp_line
			(start -0.12065 0.3048)
			(end -0.67945 0.3048)
			(stroke
				(width 0.1)
				(type default)
			)
			(layer "F.Fab")
		)
		(fp_line
			(start -0.67945 0.3048)
			(end -0.67945 -0.305054)
			(stroke
				(width 0.1)
				(type default)
			)
			(layer "F.Fab")
		)
		(pad "1" smd circle
			(at -0.40005 0 90)
			(size 0 0)
			(layers "F.Cu" "F.Mask" "F.Paste")
			(net "RST_PEX2_S1_PERST_N")
		)
		(pad "2" smd circle
			(at 0.40005 0 90)
			(size 0 0)
			(layers "F.Cu" "F.Mask" "F.Paste")
			(net "RST_PEX2_S1_PERST_R_N")
		)
	)
	(footprint ""
		(layer "F.Cu")
		(at 198.76135 -132.601208 180)
		(property "Reference" "C232"
			(at 0 0 180)
			(layer "F.SilkS")
			(hide yes)
			(effects
				(font
					(size 1.27 1.27)
				)
			)
		)
		(property "Value" ""
			(at 0 0 180)
			(layer "F.Fab")
			(effects
				(font
					(size 1.27 1.27)
				)
			)
		)
		(duplicate_pad_numbers_are_jumpers no)
		(fp_line
			(start 0.299974 0.150114)
			(end -0.299974 0.150114)
			(stroke
				(width 0.1)
				(type default)
			)
			(layer "F.Fab")
		)
		(fp_line
			(start 0.299974 -0.150114)
			(end 0.299974 0.150114)
			(stroke
				(width 0.1)
				(type default)
			)
			(layer "F.Fab")
		)
		(fp_line
			(start -0.299974 0.150114)
			(end -0.299974 -0.150114)
			(stroke
				(width 0.1)
				(type default)
			)
			(layer "F.Fab")
		)
		(fp_line
			(start -0.299974 -0.150114)
			(end 0.299974 -0.150114)
			(stroke
				(width 0.1)
				(type default)
			)
			(layer "F.Fab")
		)
		(pad "1" smd rect
			(at -0.2667 0 180)
			(size 0.3048 0.381)
			(layers "F.Cu" "F.Mask" "F.Paste")
			(net "P5E_PEX1_STN0_TX_DP<5>")
		)
		(pad "2" smd rect
			(at 0.2667 0 180)
			(size 0.3048 0.381)
			(layers "F.Cu" "F.Mask" "F.Paste")
			(net "P5E_PEX1_STN0_TX_C_DP<5>")
		)
	)
	(footprint ""
		(layer "F.Cu")
		(at 242.493292 -221.050612 180)
		(property "Reference" "R4853"
			(at 0 0 180)
			(layer "F.SilkS")
			(hide yes)
			(effects
				(font
					(size 1.27 1.27)
				)
			)
		)
		(property "Value" ""
			(at 0 0 180)
			(layer "F.Fab")
			(effects
				(font
					(size 1.27 1.27)
				)
			)
		)
		(duplicate_pad_numbers_are_jumpers no)
		(fp_line
			(start 0.7874 0.4064)
			(end -0.7874 0.4064)
			(stroke
				(width 0.1524)
				(type default)
			)
			(layer "F.SilkS")
		)
		(fp_line
			(start 0.7874 -0.4064)
			(end 0.7874 0.4064)
			(stroke
				(width 0.1524)
				(type default)
			)
			(layer "F.SilkS")
		)
		(fp_line
			(start -0.7874 0.4064)
			(end -0.7874 -0.4064)
			(stroke
				(width 0.1524)
				(type default)
			)
			(layer "F.SilkS")
		)
		(fp_line
			(start -0.7874 -0.4064)
			(end 0.7874 -0.4064)
			(stroke
				(width 0.1524)
				(type default)
			)
			(layer "F.SilkS")
		)
		(fp_line
			(start 0.67945 0.3048)
			(end 0.120396 0.3048)
			(stroke
				(width 0.1)
				(type default)
			)
			(layer "F.Fab")
		)
		(fp_line
			(start 0.67945 -0.3048)
			(end 0.67945 0.3048)
			(stroke
				(width 0.1)
				(type default)
			)
			(layer "F.Fab")
		)
		(fp_line
			(start 0.12065 -0.2794)
			(end 0.12065 -0.3048)
			(stroke
				(width 0.1)
				(type default)
			)
			(layer "F.Fab")
		)
		(fp_line
			(start 0.12065 -0.3048)
			(end 0.67945 -0.3048)
			(stroke
				(width 0.1)
				(type default)
			)
			(layer "F.Fab")
		)
		(fp_line
			(start 0.120396 0.3048)
			(end 0.120396 0.2794)
			(stroke
				(width 0.1)
				(type default)
			)
			(layer "F.Fab")
		)
		(fp_line
			(start 0.120396 0.2794)
			(end -0.12065 0.2794)
			(stroke
				(width 0.1)
				(type default)
			)
			(layer "F.Fab")
		)
		(fp_line
			(start -0.12065 0.3048)
			(end -0.67945 0.3048)
			(stroke
				(width 0.1)
				(type default)
			)
			(layer "F.Fab")
		)
		(fp_line
			(start -0.12065 0.2794)
			(end -0.12065 0.3048)
			(stroke
				(width 0.1)
				(type default)
			)
			(layer "F.Fab")
		)
		(fp_line
			(start -0.12065 -0.2794)
			(end 0.12065 -0.2794)
			(stroke
				(width 0.1)
				(type default)
			)
			(layer "F.Fab")
		)
		(fp_line
			(start -0.12065 -0.305054)
			(end -0.12065 -0.2794)
			(stroke
				(width 0.1)
				(type default)
			)
			(layer "F.Fab")
		)
		(fp_line
			(start -0.67945 0.3048)
			(end -0.67945 -0.305054)
			(stroke
				(width 0.1)
				(type default)
			)
			(layer "F.Fab")
		)
		(fp_line
			(start -0.67945 -0.305054)
			(end -0.12065 -0.305054)
			(stroke
				(width 0.1)
				(type default)
			)
			(layer "F.Fab")
		)
		(pad "1" smd circle
			(at -0.40005 0 180)
			(size 0 0)
			(layers "F.Cu" "F.Mask" "F.Paste")
			(net "PD_BIC_ADCREXT1")
		)
		(pad "2" smd circle
			(at 0.40005 0 180)
			(size 0 0)
			(layers "F.Cu" "F.Mask" "F.Paste")
			(net "GND")
		)
	)
	(footprint ""
		(layer "F.Cu")
		(at 217.583512 -231.416606 -90)
		(property "Reference" "R4553"
			(at 0 0 270)
			(layer "F.SilkS")
			(hide yes)
			(effects
				(font
					(size 1.27 1.27)
				)
			)
		)
		(property "Value" ""
			(at 0 0 270)
			(layer "F.Fab")
			(effects
				(font
					(size 1.27 1.27)
				)
			)
		)
		(duplicate_pad_numbers_are_jumpers no)
		(fp_line
			(start -0.7874 0.4064)
			(end -0.7874 -0.4064)
			(stroke
				(width 0.1524)
				(type default)
			)
			(layer "F.SilkS")
		)
		(fp_line
			(start 0.7874 0.4064)
			(end -0.7874 0.4064)
			(stroke
				(width 0.1524)
				(type default)
			)
			(layer "F.SilkS")
		)
		(fp_line
			(start -0.7874 -0.4064)
			(end 0.7874 -0.4064)
			(stroke
				(width 0.1524)
				(type default)
			)
			(layer "F.SilkS")
		)
		(fp_line
			(start 0.7874 -0.4064)
			(end 0.7874 0.4064)
			(stroke
				(width 0.1524)
				(type default)
			)
			(layer "F.SilkS")
		)
		(fp_line
			(start -0.67945 0.3048)
			(end -0.67945 -0.305054)
			(stroke
				(width 0.1)
				(type default)
			)
			(layer "F.Fab")
		)
		(fp_line
			(start -0.12065 0.3048)
			(end -0.67945 0.3048)
			(stroke
				(width 0.1)
				(type default)
			)
			(layer "F.Fab")
		)
		(fp_line
			(start 0.120396 0.3048)
			(end 0.120396 0.2794)
			(stroke
				(width 0.1)
				(type default)
			)
			(layer "F.Fab")
		)
		(fp_line
			(start 0.67945 0.3048)
			(end 0.120396 0.3048)
			(stroke
				(width 0.1)
				(type default)
			)
			(layer "F.Fab")
		)
		(fp_line
			(start -0.12065 0.2794)
			(end -0.12065 0.3048)
			(stroke
				(width 0.1)
				(type default)
			)
			(layer "F.Fab")
		)
		(fp_line
			(start 0.120396 0.2794)
			(end -0.12065 0.2794)
			(stroke
				(width 0.1)
				(type default)
			)
			(layer "F.Fab")
		)
		(fp_line
			(start -0.12065 -0.2794)
			(end 0.12065 -0.2794)
			(stroke
				(width 0.1)
				(type default)
			)
			(layer "F.Fab")
		)
		(fp_line
			(start 0.12065 -0.2794)
			(end 0.12065 -0.3048)
			(stroke
				(width 0.1)
				(type default)
			)
			(layer "F.Fab")
		)
		(fp_line
			(start 0.12065 -0.3048)
			(end 0.67945 -0.3048)
			(stroke
				(width 0.1)
				(type default)
			)
			(layer "F.Fab")
		)
		(fp_line
			(start 0.67945 -0.3048)
			(end 0.67945 0.3048)
			(stroke
				(width 0.1)
				(type default)
			)
			(layer "F.Fab")
		)
		(fp_line
			(start -0.67945 -0.305054)
			(end -0.12065 -0.305054)
			(stroke
				(width 0.1)
				(type default)
			)
			(layer "F.Fab")
		)
		(fp_line
			(start -0.12065 -0.305054)
			(end -0.12065 -0.2794)
			(stroke
				(width 0.1)
				(type default)
			)
			(layer "F.Fab")
		)
		(pad "1" smd circle
			(at -0.40005 0 270)
			(size 0 0)
			(layers "F.Cu" "F.Mask" "F.Paste")
			(net "GND")
		)
		(pad "2" smd circle
			(at 0.40005 0 270)
			(size 0 0)
			(layers "F.Cu" "F.Mask" "F.Paste")
			(net "BOARD_ID0")
		)
	)
	(footprint ""
		(layer "F.Cu")
		(at 399.362422 -22.955504 -90)
		(property "Reference" "C2741"
			(at 0 0 270)
			(layer "F.SilkS")
			(hide yes)
			(effects
				(font
					(size 1.27 1.27)
				)
			)
		)
		(property "Value" ""
			(at 0 0 270)
			(layer "F.Fab")
			(effects
				(font
					(size 1.27 1.27)
				)
			)
		)
		(duplicate_pad_numbers_are_jumpers no)
		(fp_line
			(start -0.7874 0.4064)
			(end -0.7874 -0.4064)
			(stroke
				(width 0.1524)
				(type default)
			)
			(layer "F.SilkS")
		)
		(fp_line
			(start 0.7874 0.4064)
			(end -0.7874 0.4064)
			(stroke
				(width 0.1524)
				(type default)
			)
			(layer "F.SilkS")
		)
		(fp_line
			(start -0.7874 -0.4064)
			(end 0.7874 -0.4064)
			(stroke
				(width 0.1524)
				(type default)
			)
			(layer "F.SilkS")
		)
		(fp_line
			(start 0.7874 -0.4064)
			(end 0.7874 0.4064)
			(stroke
				(width 0.1524)
				(type default)
			)
			(layer "F.SilkS")
		)
		(fp_line
			(start -0.67945 0.3048)
			(end -0.67945 -0.305054)
			(stroke
				(width 0.1)
				(type default)
			)
			(layer "F.Fab")
		)
		(fp_line
			(start -0.12065 0.3048)
			(end -0.67945 0.3048)
			(stroke
				(width 0.1)
				(type default)
			)
			(layer "F.Fab")
		)
		(fp_line
			(start 0.120396 0.3048)
			(end 0.120396 0.2794)
			(stroke
				(width 0.1)
				(type default)
			)
			(layer "F.Fab")
		)
		(fp_line
			(start 0.67945 0.3048)
			(end 0.120396 0.3048)
			(stroke
				(width 0.1)
				(type default)
			)
			(layer "F.Fab")
		)
		(fp_line
			(start -0.12065 0.2794)
			(end -0.12065 0.3048)
			(stroke
				(width 0.1)
				(type default)
			)
			(layer "F.Fab")
		)
		(fp_line
			(start 0.120396 0.2794)
			(end -0.12065 0.2794)
			(stroke
				(width 0.1)
				(type default)
			)
			(layer "F.Fab")
		)
		(fp_line
			(start -0.12065 -0.2794)
			(end 0.12065 -0.2794)
			(stroke
				(width 0.1)
				(type default)
			)
			(layer "F.Fab")
		)
		(fp_line
			(start 0.12065 -0.2794)
			(end 0.12065 -0.3048)
			(stroke
				(width 0.1)
				(type default)
			)
			(layer "F.Fab")
		)
		(fp_line
			(start 0.12065 -0.3048)
			(end 0.67945 -0.3048)
			(stroke
				(width 0.1)
				(type default)
			)
			(layer "F.Fab")
		)
		(fp_line
			(start 0.67945 -0.3048)
			(end 0.67945 0.3048)
			(stroke
				(width 0.1)
				(type default)
			)
			(layer "F.Fab")
		)
		(fp_line
			(start -0.67945 -0.305054)
			(end -0.12065 -0.305054)
			(stroke
				(width 0.1)
				(type default)
			)
			(layer "F.Fab")
		)
		(fp_line
			(start -0.12065 -0.305054)
			(end -0.12065 -0.2794)
			(stroke
				(width 0.1)
				(type default)
			)
			(layer "F.Fab")
		)
		(pad "1" smd circle
			(at -0.40005 0 270)
			(size 0 0)
			(layers "F.Cu" "F.Mask" "F.Paste")
			(net "GND")
		)
		(pad "2" smd circle
			(at 0.40005 0 270)
			(size 0 0)
			(layers "F.Cu" "F.Mask" "F.Paste")
			(net "P3V3_AUX")
		)
	)
	(footprint ""
		(layer "F.Cu")
		(at 224.022158 -77.563472 180)
		(property "Reference" "R4346"
			(at 0 0 180)
			(layer "F.SilkS")
			(hide yes)
			(effects
				(font
					(size 1.27 1.27)
				)
			)
		)
		(property "Value" ""
			(at 0 0 180)
			(layer "F.Fab")
			(effects
				(font
					(size 1.27 1.27)
				)
			)
		)
		(duplicate_pad_numbers_are_jumpers no)
		(fp_line
			(start 0.7874 0.4064)
			(end -0.7874 0.4064)
			(stroke
				(width 0.1524)
				(type default)
			)
			(layer "F.SilkS")
		)
		(fp_line
			(start 0.7874 -0.4064)
			(end 0.7874 0.4064)
			(stroke
				(width 0.1524)
				(type default)
			)
			(layer "F.SilkS")
		)
		(fp_line
			(start -0.7874 0.4064)
			(end -0.7874 -0.4064)
			(stroke
				(width 0.1524)
				(type default)
			)
			(layer "F.SilkS")
		)
		(fp_line
			(start -0.7874 -0.4064)
			(end 0.7874 -0.4064)
			(stroke
				(width 0.1524)
				(type default)
			)
			(layer "F.SilkS")
		)
		(fp_line
			(start 0.67945 0.3048)
			(end 0.120396 0.3048)
			(stroke
				(width 0.1)
				(type default)
			)
			(layer "F.Fab")
		)
		(fp_line
			(start 0.67945 -0.3048)
			(end 0.67945 0.3048)
			(stroke
				(width 0.1)
				(type default)
			)
			(layer "F.Fab")
		)
		(fp_line
			(start 0.12065 -0.2794)
			(end 0.12065 -0.3048)
			(stroke
				(width 0.1)
				(type default)
			)
			(layer "F.Fab")
		)
		(fp_line
			(start 0.12065 -0.3048)
			(end 0.67945 -0.3048)
			(stroke
				(width 0.1)
				(type default)
			)
			(layer "F.Fab")
		)
		(fp_line
			(start 0.120396 0.3048)
			(end 0.120396 0.2794)
			(stroke
				(width 0.1)
				(type default)
			)
			(layer "F.Fab")
		)
		(fp_line
			(start 0.120396 0.2794)
			(end -0.12065 0.2794)
			(stroke
				(width 0.1)
				(type default)
			)
			(layer "F.Fab")
		)
		(fp_line
			(start -0.12065 0.3048)
			(end -0.67945 0.3048)
			(stroke
				(width 0.1)
				(type default)
			)
			(layer "F.Fab")
		)
		(fp_line
			(start -0.12065 0.2794)
			(end -0.12065 0.3048)
			(stroke
				(width 0.1)
				(type default)
			)
			(layer "F.Fab")
		)
		(fp_line
			(start -0.12065 -0.2794)
			(end 0.12065 -0.2794)
			(stroke
				(width 0.1)
				(type default)
			)
			(layer "F.Fab")
		)
		(fp_line
			(start -0.12065 -0.305054)
			(end -0.12065 -0.2794)
			(stroke
				(width 0.1)
				(type default)
			)
			(layer "F.Fab")
		)
		(fp_line
			(start -0.67945 0.3048)
			(end -0.67945 -0.305054)
			(stroke
				(width 0.1)
				(type default)
			)
			(layer "F.Fab")
		)
		(fp_line
			(start -0.67945 -0.305054)
			(end -0.12065 -0.305054)
			(stroke
				(width 0.1)
				(type default)
			)
			(layer "F.Fab")
		)
		(pad "1" smd circle
			(at -0.40005 0 180)
			(size 0 0)
			(layers "F.Cu" "F.Mask" "F.Paste")
			(net "P3V3_AUX")
		)
		(pad "2" smd circle
			(at 0.40005 0 180)
			(size 0 0)
			(layers "F.Cu" "F.Mask" "F.Paste")
			(net "SSD8_LED_R")
		)
	)
	(footprint ""
		(layer "F.Cu")
		(at 83.65617 -61.487812 180)
		(property "Reference" "R5847"
			(at 0 0 180)
			(layer "F.SilkS")
			(hide yes)
			(effects
				(font
					(size 1.27 1.27)
				)
			)
		)
		(property "Value" ""
			(at 0 0 180)
			(layer "F.Fab")
			(effects
				(font
					(size 1.27 1.27)
				)
			)
		)
		(duplicate_pad_numbers_are_jumpers no)
		(fp_line
			(start 0.7874 0.4064)
			(end -0.7874 0.4064)
			(stroke
				(width 0.1524)
				(type default)
			)
			(layer "F.SilkS")
		)
		(fp_line
			(start 0.7874 -0.4064)
			(end 0.7874 0.4064)
			(stroke
				(width 0.1524)
				(type default)
			)
			(layer "F.SilkS")
		)
		(fp_line
			(start -0.7874 0.4064)
			(end -0.7874 -0.4064)
			(stroke
				(width 0.1524)
				(type default)
			)
			(layer "F.SilkS")
		)
		(fp_line
			(start -0.7874 -0.4064)
			(end 0.7874 -0.4064)
			(stroke
				(width 0.1524)
				(type default)
			)
			(layer "F.SilkS")
		)
		(fp_line
			(start 0.67945 0.3048)
			(end 0.120396 0.3048)
			(stroke
				(width 0.1)
				(type default)
			)
			(layer "F.Fab")
		)
		(fp_line
			(start 0.67945 -0.3048)
			(end 0.67945 0.3048)
			(stroke
				(width 0.1)
				(type default)
			)
			(layer "F.Fab")
		)
		(fp_line
			(start 0.12065 -0.2794)
			(end 0.12065 -0.3048)
			(stroke
				(width 0.1)
				(type default)
			)
			(layer "F.Fab")
		)
		(fp_line
			(start 0.12065 -0.3048)
			(end 0.67945 -0.3048)
			(stroke
				(width 0.1)
				(type default)
			)
			(layer "F.Fab")
		)
		(fp_line
			(start 0.120396 0.3048)
			(end 0.120396 0.2794)
			(stroke
				(width 0.1)
				(type default)
			)
			(layer "F.Fab")
		)
		(fp_line
			(start 0.120396 0.2794)
			(end -0.12065 0.2794)
			(stroke
				(width 0.1)
				(type default)
			)
			(layer "F.Fab")
		)
		(fp_line
			(start -0.12065 0.3048)
			(end -0.67945 0.3048)
			(stroke
				(width 0.1)
				(type default)
			)
			(layer "F.Fab")
		)
		(fp_line
			(start -0.12065 0.2794)
			(end -0.12065 0.3048)
			(stroke
				(width 0.1)
				(type default)
			)
			(layer "F.Fab")
		)
		(fp_line
			(start -0.12065 -0.2794)
			(end 0.12065 -0.2794)
			(stroke
				(width 0.1)
				(type default)
			)
			(layer "F.Fab")
		)
		(fp_line
			(start -0.12065 -0.305054)
			(end -0.12065 -0.2794)
			(stroke
				(width 0.1)
				(type default)
			)
			(layer "F.Fab")
		)
		(fp_line
			(start -0.67945 0.3048)
			(end -0.67945 -0.305054)
			(stroke
				(width 0.1)
				(type default)
			)
			(layer "F.Fab")
		)
		(fp_line
			(start -0.67945 -0.305054)
			(end -0.12065 -0.305054)
			(stroke
				(width 0.1)
				(type default)
			)
			(layer "F.Fab")
		)
		(pad "1" smd circle
			(at -0.40005 0 180)
			(size 0 0)
			(layers "F.Cu" "F.Mask" "F.Paste")
			(net "P3V3_AUX")
		)
		(pad "2" smd circle
			(at 0.40005 0 180)
			(size 0 0)
			(layers "F.Cu" "F.Mask" "F.Paste")
			(net "PWRGD_P12V_SSD3_D")
		)
	)
	(footprint ""
		(layer "F.Cu")
		(at 324.483222 -113.628678)
		(property "Reference" "PC898"
			(at 0 0 0)
			(layer "F.SilkS")
			(hide yes)
			(effects
				(font
					(size 1.27 1.27)
				)
			)
		)
		(property "Value" ""
			(at 0 0 0)
			(layer "F.Fab")
			(effects
				(font
					(size 1.27 1.27)
				)
			)
		)
		(duplicate_pad_numbers_are_jumpers no)
		(fp_line
			(start -0.7874 -0.4064)
			(end 0.7874 -0.4064)
			(stroke
				(width 0.1524)
				(type default)
			)
			(layer "F.SilkS")
		)
		(fp_line
			(start -0.7874 0.4064)
			(end -0.7874 -0.4064)
			(stroke
				(width 0.1524)
				(type default)
			)
			(layer "F.SilkS")
		)
		(fp_line
			(start 0.7874 -0.4064)
			(end 0.7874 0.4064)
			(stroke
				(width 0.1524)
				(type default)
			)
			(layer "F.SilkS")
		)
		(fp_line
			(start 0.7874 0.4064)
			(end -0.7874 0.4064)
			(stroke
				(width 0.1524)
				(type default)
			)
			(layer "F.SilkS")
		)
		(fp_line
			(start -0.67945 -0.305054)
			(end -0.12065 -0.305054)
			(stroke
				(width 0.1)
				(type default)
			)
			(layer "F.Fab")
		)
		(fp_line
			(start -0.67945 0.3048)
			(end -0.67945 -0.305054)
			(stroke
				(width 0.1)
				(type default)
			)
			(layer "F.Fab")
		)
		(fp_line
			(start -0.12065 -0.305054)
			(end -0.12065 -0.2794)
			(stroke
				(width 0.1)
				(type default)
			)
			(layer "F.Fab")
		)
		(fp_line
			(start -0.12065 -0.2794)
			(end 0.12065 -0.2794)
			(stroke
				(width 0.1)
				(type default)
			)
			(layer "F.Fab")
		)
		(fp_line
			(start -0.12065 0.2794)
			(end -0.12065 0.3048)
			(stroke
				(width 0.1)
				(type default)
			)
			(layer "F.Fab")
		)
		(fp_line
			(start -0.12065 0.3048)
			(end -0.67945 0.3048)
			(stroke
				(width 0.1)
				(type default)
			)
			(layer "F.Fab")
		)
		(fp_line
			(start 0.120396 0.2794)
			(end -0.12065 0.2794)
			(stroke
				(width 0.1)
				(type default)
			)
			(layer "F.Fab")
		)
		(fp_line
			(start 0.120396 0.3048)
			(end 0.120396 0.2794)
			(stroke
				(width 0.1)
				(type default)
			)
			(layer "F.Fab")
		)
		(fp_line
			(start 0.12065 -0.3048)
			(end 0.67945 -0.3048)
			(stroke
				(width 0.1)
				(type default)
			)
			(layer "F.Fab")
		)
		(fp_line
			(start 0.12065 -0.2794)
			(end 0.12065 -0.3048)
			(stroke
				(width 0.1)
				(type default)
			)
			(layer "F.Fab")
		)
		(fp_line
			(start 0.67945 -0.3048)
			(end 0.67945 0.3048)
			(stroke
				(width 0.1)
				(type default)
			)
			(layer "F.Fab")
		)
		(fp_line
			(start 0.67945 0.3048)
			(end 0.120396 0.3048)
			(stroke
				(width 0.1)
				(type default)
			)
			(layer "F.Fab")
		)
		(pad "1" smd circle
			(at -0.40005 0)
			(size 0 0)
			(layers "F.Cu" "F.Mask" "F.Paste")
			(net "P3V3_AUX")
		)
		(pad "2" smd circle
			(at 0.40005 0)
			(size 0 0)
			(layers "F.Cu" "F.Mask" "F.Paste")
			(net "GND")
		)
	)
	(footprint ""
		(layer "F.Cu")
		(at 119.0879 -293.816786 -90)
		(property "Reference" "PC100"
			(at 0 0 270)
			(layer "F.SilkS")
			(hide yes)
			(effects
				(font
					(size 1.27 1.27)
				)
			)
		)
		(property "Value" ""
			(at 0 0 270)
			(layer "F.Fab")
			(effects
				(font
					(size 1.27 1.27)
				)
			)
		)
		(duplicate_pad_numbers_are_jumpers no)
		(fp_line
			(start -0.7874 0.4064)
			(end -0.7874 -0.4064)
			(stroke
				(width 0.1524)
				(type default)
			)
			(layer "F.SilkS")
		)
		(fp_line
			(start 0.7874 0.4064)
			(end -0.7874 0.4064)
			(stroke
				(width 0.1524)
				(type default)
			)
			(layer "F.SilkS")
		)
		(fp_line
			(start -0.7874 -0.4064)
			(end 0.7874 -0.4064)
			(stroke
				(width 0.1524)
				(type default)
			)
			(layer "F.SilkS")
		)
		(fp_line
			(start 0.7874 -0.4064)
			(end 0.7874 0.4064)
			(stroke
				(width 0.1524)
				(type default)
			)
			(layer "F.SilkS")
		)
		(fp_line
			(start -0.67945 0.3048)
			(end -0.67945 -0.305054)
			(stroke
				(width 0.1)
				(type default)
			)
			(layer "F.Fab")
		)
		(fp_line
			(start -0.12065 0.3048)
			(end -0.67945 0.3048)
			(stroke
				(width 0.1)
				(type default)
			)
			(layer "F.Fab")
		)
		(fp_line
			(start 0.120396 0.3048)
			(end 0.120396 0.2794)
			(stroke
				(width 0.1)
				(type default)
			)
			(layer "F.Fab")
		)
		(fp_line
			(start 0.67945 0.3048)
			(end 0.120396 0.3048)
			(stroke
				(width 0.1)
				(type default)
			)
			(layer "F.Fab")
		)
		(fp_line
			(start -0.12065 0.2794)
			(end -0.12065 0.3048)
			(stroke
				(width 0.1)
				(type default)
			)
			(layer "F.Fab")
		)
		(fp_line
			(start 0.120396 0.2794)
			(end -0.12065 0.2794)
			(stroke
				(width 0.1)
				(type default)
			)
			(layer "F.Fab")
		)
		(fp_line
			(start -0.12065 -0.2794)
			(end 0.12065 -0.2794)
			(stroke
				(width 0.1)
				(type default)
			)
			(layer "F.Fab")
		)
		(fp_line
			(start 0.12065 -0.2794)
			(end 0.12065 -0.3048)
			(stroke
				(width 0.1)
				(type default)
			)
			(layer "F.Fab")
		)
		(fp_line
			(start 0.12065 -0.3048)
			(end 0.67945 -0.3048)
			(stroke
				(width 0.1)
				(type default)
			)
			(layer "F.Fab")
		)
		(fp_line
			(start 0.67945 -0.3048)
			(end 0.67945 0.3048)
			(stroke
				(width 0.1)
				(type default)
			)
			(layer "F.Fab")
		)
		(fp_line
			(start -0.67945 -0.305054)
			(end -0.12065 -0.305054)
			(stroke
				(width 0.1)
				(type default)
			)
			(layer "F.Fab")
		)
		(fp_line
			(start -0.12065 -0.305054)
			(end -0.12065 -0.2794)
			(stroke
				(width 0.1)
				(type default)
			)
			(layer "F.Fab")
		)
		(pad "1" smd circle
			(at -0.40005 0 270)
			(size 0 0)
			(layers "F.Cu" "F.Mask" "F.Paste")
			(net "P0V8_PEX1")
		)
		(pad "2" smd circle
			(at 0.40005 0 270)
			(size 0 0)
			(layers "F.Cu" "F.Mask" "F.Paste")
			(net "GND")
		)
	)
	(footprint ""
		(layer "F.Cu")
		(at 183.923432 -343.952322 90)
		(property "Reference" "C2532"
			(at 0 0 90)
			(layer "F.SilkS")
			(hide yes)
			(effects
				(font
					(size 1.27 1.27)
				)
			)
		)
		(property "Value" ""
			(at 0 0 90)
			(layer "F.Fab")
			(effects
				(font
					(size 1.27 1.27)
				)
			)
		)
		(duplicate_pad_numbers_are_jumpers no)
		(fp_line
			(start 0.299974 -0.150114)
			(end 0.299974 0.150114)
			(stroke
				(width 0.1)
				(type default)
			)
			(layer "F.Fab")
		)
		(fp_line
			(start -0.299974 -0.150114)
			(end 0.299974 -0.150114)
			(stroke
				(width 0.1)
				(type default)
			)
			(layer "F.Fab")
		)
		(fp_line
			(start 0.299974 0.150114)
			(end -0.299974 0.150114)
			(stroke
				(width 0.1)
				(type default)
			)
			(layer "F.Fab")
		)
		(fp_line
			(start -0.299974 0.150114)
			(end -0.299974 -0.150114)
			(stroke
				(width 0.1)
				(type default)
			)
			(layer "F.Fab")
		)
		(pad "1" smd rect
			(at -0.2667 0 90)
			(size 0.3048 0.381)
			(layers "F.Cu" "F.Mask" "F.Paste")
			(net "P5E_PEX1_STN4_TX_DP<69>")
		)
		(pad "2" smd rect
			(at 0.2667 0 90)
			(size 0.3048 0.381)
			(layers "F.Cu" "F.Mask" "F.Paste")
			(net "P5E_PEX1_STN4_TX_C_DP<69>")
		)
	)
	(footprint ""
		(layer "F.Cu")
		(at 322.959222 -235.075222 90)
		(property "Reference" "R4390"
			(at 0 0 90)
			(layer "F.SilkS")
			(hide yes)
			(effects
				(font
					(size 1.27 1.27)
				)
			)
		)
		(property "Value" ""
			(at 0 0 90)
			(layer "F.Fab")
			(effects
				(font
					(size 1.27 1.27)
				)
			)
		)
		(duplicate_pad_numbers_are_jumpers no)
		(fp_line
			(start 0.7874 -0.4064)
			(end 0.7874 0.4064)
			(stroke
				(width 0.1524)
				(type default)
			)
			(layer "F.SilkS")
		)
		(fp_line
			(start -0.7874 -0.4064)
			(end 0.7874 -0.4064)
			(stroke
				(width 0.1524)
				(type default)
			)
			(layer "F.SilkS")
		)
		(fp_line
			(start 0.7874 0.4064)
			(end -0.7874 0.4064)
			(stroke
				(width 0.1524)
				(type default)
			)
			(layer "F.SilkS")
		)
		(fp_line
			(start -0.7874 0.4064)
			(end -0.7874 -0.4064)
			(stroke
				(width 0.1524)
				(type default)
			)
			(layer "F.SilkS")
		)
		(fp_line
			(start -0.12065 -0.305054)
			(end -0.12065 -0.2794)
			(stroke
				(width 0.1)
				(type default)
			)
			(layer "F.Fab")
		)
		(fp_line
			(start -0.67945 -0.305054)
			(end -0.12065 -0.305054)
			(stroke
				(width 0.1)
				(type default)
			)
			(layer "F.Fab")
		)
		(fp_line
			(start 0.67945 -0.3048)
			(end 0.67945 0.3048)
			(stroke
				(width 0.1)
				(type default)
			)
			(layer "F.Fab")
		)
		(fp_line
			(start 0.12065 -0.3048)
			(end 0.67945 -0.3048)
			(stroke
				(width 0.1)
				(type default)
			)
			(layer "F.Fab")
		)
		(fp_line
			(start 0.12065 -0.2794)
			(end 0.12065 -0.3048)
			(stroke
				(width 0.1)
				(type default)
			)
			(layer "F.Fab")
		)
		(fp_line
			(start -0.12065 -0.2794)
			(end 0.12065 -0.2794)
			(stroke
				(width 0.1)
				(type default)
			)
			(layer "F.Fab")
		)
		(fp_line
			(start 0.120396 0.2794)
			(end -0.12065 0.2794)
			(stroke
				(width 0.1)
				(type default)
			)
			(layer "F.Fab")
		)
		(fp_line
			(start -0.12065 0.2794)
			(end -0.12065 0.3048)
			(stroke
				(width 0.1)
				(type default)
			)
			(layer "F.Fab")
		)
		(fp_line
			(start 0.67945 0.3048)
			(end 0.120396 0.3048)
			(stroke
				(width 0.1)
				(type default)
			)
			(layer "F.Fab")
		)
		(fp_line
			(start 0.120396 0.3048)
			(end 0.120396 0.2794)
			(stroke
				(width 0.1)
				(type default)
			)
			(layer "F.Fab")
		)
		(fp_line
			(start -0.12065 0.3048)
			(end -0.67945 0.3048)
			(stroke
				(width 0.1)
				(type default)
			)
			(layer "F.Fab")
		)
		(fp_line
			(start -0.67945 0.3048)
			(end -0.67945 -0.305054)
			(stroke
				(width 0.1)
				(type default)
			)
			(layer "F.Fab")
		)
		(pad "1" smd circle
			(at -0.40005 0 90)
			(size 0 0)
			(layers "F.Cu" "F.Mask" "F.Paste")
			(net "RST_PEX_SYS_BUF_R_N")
		)
		(pad "2" smd circle
			(at 0.40005 0 90)
			(size 0 0)
			(layers "F.Cu" "F.Mask" "F.Paste")
			(net "RST_PEX3_SYS_N")
		)
	)
	(footprint ""
		(layer "F.Cu")
		(at 11.234166 -137.01776 180)
		(property "Reference" "PU22"
			(at 2.59207 -2.769108 0)
			(unlocked yes)
			(layer "F.SilkS")
			(effects
				(font
					(size 0.7874 0.5842)
					(thickness 0.1524)
				)
				(justify left)
			)
		)
		(property "Value" ""
			(at 0 0 180)
			(layer "F.Fab")
			(effects
				(font
					(size 1.27 1.27)
				)
			)
		)
		(duplicate_pad_numbers_are_jumpers no)
		(fp_line
			(start 1.943608 1.549908)
			(end -1.943608 1.549908)
			(stroke
				(width 0.1524)
				(type default)
			)
			(layer "F.SilkS")
		)
		(fp_line
			(start 1.943608 -1.549908)
			(end 1.943608 1.549908)
			(stroke
				(width 0.1524)
				(type default)
			)
			(layer "F.SilkS")
		)
		(fp_line
			(start -1.943608 1.549908)
			(end -1.943608 -1.549908)
			(stroke
				(width 0.1524)
				(type default)
			)
			(layer "F.SilkS")
		)
		(fp_line
			(start -1.943608 -1.549908)
			(end 1.943608 -1.549908)
			(stroke
				(width 0.1524)
				(type default)
			)
			(layer "F.SilkS")
		)
		(fp_poly
			(pts
				(xy -2.019808 -1.549908) (xy -1.257808 -1.549908) (xy -1.257808 -1.880108) (xy -2.019808 -1.880108)
			)
			(stroke
				(width 0)
				(type default)
			)
			(fill yes)
			(layer "F.SilkS")
		)
		(fp_line
			(start 1.549908 1.549908)
			(end -1.549908 1.549908)
			(stroke
				(width 0.1)
				(type default)
			)
			(layer "F.Fab")
		)
		(fp_line
			(start 1.549908 -1.549908)
			(end 1.549908 1.549908)
			(stroke
				(width 0.1)
				(type default)
			)
			(layer "F.Fab")
		)
		(fp_line
			(start -1.549908 1.549908)
			(end -1.549908 -1.549908)
			(stroke
				(width 0.1)
				(type default)
			)
			(layer "F.Fab")
		)
		(fp_line
			(start -1.549908 -1.549908)
			(end 1.549908 -1.549908)
			(stroke
				(width 0.1)
				(type default)
			)
			(layer "F.Fab")
		)
		(fp_poly
			(pts
				(xy -2.019808 -1.549908) (xy -1.257808 -1.549908) (xy -1.257808 -1.880108) (xy -2.019808 -1.880108)
			)
			(stroke
				(width 0)
				(type default)
			)
			(fill yes)
			(layer "F.Fab")
		)
		(pad "1" smd rect
			(at -1.500124 -1.249934 90)
			(size 0.2794 0.6096)
			(layers "F.Cu" "F.Mask" "F.Paste")
			(net "P12V_NIC0_R")
		)
		(pad "2" smd rect
			(at -1.500124 -0.750062 90)
			(size 0.2794 0.6096)
			(layers "F.Cu" "F.Mask" "F.Paste")
			(net "P12V_NIC0_R")
		)
		(pad "3" smd rect
			(at -1.500124 -0.249936 90)
			(size 0.2794 0.6096)
			(layers "F.Cu" "F.Mask" "F.Paste")
			(net "P12V_NIC0_R")
		)
		(pad "4" smd rect
			(at -1.500124 0.249936 90)
			(size 0.2794 0.6096)
			(layers "F.Cu" "F.Mask" "F.Paste")
			(net "P12V_NIC0_R")
		)
		(pad "5" smd rect
			(at -1.500124 0.750062 90)
			(size 0.2794 0.6096)
			(layers "F.Cu" "F.Mask" "F.Paste")
			(net "P12V_NIC0_R")
		)
		(pad "6" smd rect
			(at -1.500124 1.249934 90)
			(size 0.2794 0.6096)
			(layers "F.Cu" "F.Mask" "F.Paste")
			(net "GND")
		)
		(pad "7" smd rect
			(at 1.500124 1.249934 90)
			(size 0.2794 0.6096)
			(layers "F.Cu" "F.Mask" "F.Paste")
			(net "P12V_NIC0_SS")
		)
		(pad "8" smd rect
			(at 1.500124 0.750062 90)
			(size 0.2794 0.6096)
			(layers "F.Cu" "F.Mask" "F.Paste")
			(net "PWRGD_P12V_NIC0")
		)
		(pad "9" smd rect
			(at 1.500124 0.249936 90)
			(size 0.2794 0.6096)
			(layers "F.Cu" "F.Mask" "F.Paste")
			(net "P12V_NIC0_OCP")
		)
		(pad "10" smd rect
			(at 1.500124 -0.249936 90)
			(size 0.2794 0.6096)
			(layers "F.Cu" "F.Mask" "F.Paste")
			(net "P5V_AUX")
		)
		(pad "11" smd rect
			(at 1.500124 -0.750062 90)
			(size 0.2794 0.6096)
			(layers "F.Cu" "F.Mask" "F.Paste")
			(net "P12V_NIC0_EN_R")
		)
		(pad "12" smd rect
			(at 1.500124 -1.249934 90)
			(size 0.2794 0.6096)
			(layers "F.Cu" "F.Mask" "F.Paste")
			(net "P12V_AUX")
		)
		(pad "13" smd rect
			(at 0 0 180)
			(size 1.9812 2.7178)
			(layers "F.Cu" "F.Mask" "F.Paste")
			(net "P12V_AUX")
		)
		(zone
			(layer "F.Cu")
			(hatch none 0.5)
			(connect_pads
				(clearance 0)
			)
			(min_thickness 0.25)
			(keepout
				(tracks not_allowed)
				(vias allowed)
				(pads allowed)
				(copperpour not_allowed)
				(footprints allowed)
			)
			(placement
				(enabled no)
				(sheetname "")
			)
			(fill
				(thermal_gap 0.5)
				(thermal_bridge_width 0.5)
				(island_removal_mode 0)
			)
			(polygon
				(pts
					(xy 10.091166 -135.46836) (xy 10.091166 -135.59536) (xy 10.091166 -138.56716) (xy 10.091166 -138.567668)
					(xy 12.377166 -138.567668) (xy 12.377166 -138.56716) (xy 12.377166 -138.44016) (xy 12.377166 -137.01776)
					(xy 12.275566 -137.01776) (xy 12.275566 -138.44016) (xy 10.192766 -138.44016) (xy 10.192766 -135.59536)
					(xy 12.275566 -135.59536) (xy 12.275566 -136.99236) (xy 12.377166 -136.99236) (xy 12.377166 -135.59536)
					(xy 12.377166 -135.46836) (xy 12.377166 -135.467852) (xy 10.091166 -135.467852)
				)
			)
		)
	)
	(footprint ""
		(layer "F.Cu")
		(at 240.24971 -157.812994)
		(property "Reference" "R951"
			(at 0 0 0)
			(layer "F.SilkS")
			(hide yes)
			(effects
				(font
					(size 1.27 1.27)
				)
			)
		)
		(property "Value" ""
			(at 0 0 0)
			(layer "F.Fab")
			(effects
				(font
					(size 1.27 1.27)
				)
			)
		)
		(duplicate_pad_numbers_are_jumpers no)
		(fp_line
			(start -0.7874 -0.4064)
			(end 0.7874 -0.4064)
			(stroke
				(width 0.1524)
				(type default)
			)
			(layer "F.SilkS")
		)
		(fp_line
			(start -0.7874 0.4064)
			(end -0.7874 -0.4064)
			(stroke
				(width 0.1524)
				(type default)
			)
			(layer "F.SilkS")
		)
		(fp_line
			(start 0.7874 -0.4064)
			(end 0.7874 0.4064)
			(stroke
				(width 0.1524)
				(type default)
			)
			(layer "F.SilkS")
		)
		(fp_line
			(start 0.7874 0.4064)
			(end -0.7874 0.4064)
			(stroke
				(width 0.1524)
				(type default)
			)
			(layer "F.SilkS")
		)
		(fp_line
			(start -0.67945 -0.305054)
			(end -0.12065 -0.305054)
			(stroke
				(width 0.1)
				(type default)
			)
			(layer "F.Fab")
		)
		(fp_line
			(start -0.67945 0.3048)
			(end -0.67945 -0.305054)
			(stroke
				(width 0.1)
				(type default)
			)
			(layer "F.Fab")
		)
		(fp_line
			(start -0.12065 -0.305054)
			(end -0.12065 -0.2794)
			(stroke
				(width 0.1)
				(type default)
			)
			(layer "F.Fab")
		)
		(fp_line
			(start -0.12065 -0.2794)
			(end 0.12065 -0.2794)
			(stroke
				(width 0.1)
				(type default)
			)
			(layer "F.Fab")
		)
		(fp_line
			(start -0.12065 0.2794)
			(end -0.12065 0.3048)
			(stroke
				(width 0.1)
				(type default)
			)
			(layer "F.Fab")
		)
		(fp_line
			(start -0.12065 0.3048)
			(end -0.67945 0.3048)
			(stroke
				(width 0.1)
				(type default)
			)
			(layer "F.Fab")
		)
		(fp_line
			(start 0.120396 0.2794)
			(end -0.12065 0.2794)
			(stroke
				(width 0.1)
				(type default)
			)
			(layer "F.Fab")
		)
		(fp_line
			(start 0.120396 0.3048)
			(end 0.120396 0.2794)
			(stroke
				(width 0.1)
				(type default)
			)
			(layer "F.Fab")
		)
		(fp_line
			(start 0.12065 -0.3048)
			(end 0.67945 -0.3048)
			(stroke
				(width 0.1)
				(type default)
			)
			(layer "F.Fab")
		)
		(fp_line
			(start 0.12065 -0.2794)
			(end 0.12065 -0.3048)
			(stroke
				(width 0.1)
				(type default)
			)
			(layer "F.Fab")
		)
		(fp_line
			(start 0.67945 -0.3048)
			(end 0.67945 0.3048)
			(stroke
				(width 0.1)
				(type default)
			)
			(layer "F.Fab")
		)
		(fp_line
			(start 0.67945 0.3048)
			(end 0.120396 0.3048)
			(stroke
				(width 0.1)
				(type default)
			)
			(layer "F.Fab")
		)
		(pad "1" smd circle
			(at -0.40005 0)
			(size 0 0)
			(layers "F.Cu" "F.Mask" "F.Paste")
			(net "P3V3_AUX")
		)
		(pad "2" smd circle
			(at 0.40005 0)
			(size 0 0)
			(layers "F.Cu" "F.Mask" "F.Paste")
			(net "PWRGD_P12V_NIC4_CO")
		)
	)
	(footprint ""
		(layer "F.Cu")
		(at 53.462428 -22.937216 90)
		(property "Reference" "R1642"
			(at 0 0 90)
			(layer "F.SilkS")
			(hide yes)
			(effects
				(font
					(size 1.27 1.27)
				)
			)
		)
		(property "Value" ""
			(at 0 0 90)
			(layer "F.Fab")
			(effects
				(font
					(size 1.27 1.27)
				)
			)
		)
		(duplicate_pad_numbers_are_jumpers no)
		(fp_line
			(start 0.7874 -0.4064)
			(end 0.7874 0.4064)
			(stroke
				(width 0.1524)
				(type default)
			)
			(layer "F.SilkS")
		)
		(fp_line
			(start -0.7874 -0.4064)
			(end 0.7874 -0.4064)
			(stroke
				(width 0.1524)
				(type default)
			)
			(layer "F.SilkS")
		)
		(fp_line
			(start 0.7874 0.4064)
			(end -0.7874 0.4064)
			(stroke
				(width 0.1524)
				(type default)
			)
			(layer "F.SilkS")
		)
		(fp_line
			(start -0.7874 0.4064)
			(end -0.7874 -0.4064)
			(stroke
				(width 0.1524)
				(type default)
			)
			(layer "F.SilkS")
		)
		(fp_line
			(start -0.12065 -0.305054)
			(end -0.12065 -0.2794)
			(stroke
				(width 0.1)
				(type default)
			)
			(layer "F.Fab")
		)
		(fp_line
			(start -0.67945 -0.305054)
			(end -0.12065 -0.305054)
			(stroke
				(width 0.1)
				(type default)
			)
			(layer "F.Fab")
		)
		(fp_line
			(start 0.67945 -0.3048)
			(end 0.67945 0.3048)
			(stroke
				(width 0.1)
				(type default)
			)
			(layer "F.Fab")
		)
		(fp_line
			(start 0.12065 -0.3048)
			(end 0.67945 -0.3048)
			(stroke
				(width 0.1)
				(type default)
			)
			(layer "F.Fab")
		)
		(fp_line
			(start 0.12065 -0.2794)
			(end 0.12065 -0.3048)
			(stroke
				(width 0.1)
				(type default)
			)
			(layer "F.Fab")
		)
		(fp_line
			(start -0.12065 -0.2794)
			(end 0.12065 -0.2794)
			(stroke
				(width 0.1)
				(type default)
			)
			(layer "F.Fab")
		)
		(fp_line
			(start 0.120396 0.2794)
			(end -0.12065 0.2794)
			(stroke
				(width 0.1)
				(type default)
			)
			(layer "F.Fab")
		)
		(fp_line
			(start -0.12065 0.2794)
			(end -0.12065 0.3048)
			(stroke
				(width 0.1)
				(type default)
			)
			(layer "F.Fab")
		)
		(fp_line
			(start 0.67945 0.3048)
			(end 0.120396 0.3048)
			(stroke
				(width 0.1)
				(type default)
			)
			(layer "F.Fab")
		)
		(fp_line
			(start 0.120396 0.3048)
			(end 0.120396 0.2794)
			(stroke
				(width 0.1)
				(type default)
			)
			(layer "F.Fab")
		)
		(fp_line
			(start -0.12065 0.3048)
			(end -0.67945 0.3048)
			(stroke
				(width 0.1)
				(type default)
			)
			(layer "F.Fab")
		)
		(fp_line
			(start -0.67945 0.3048)
			(end -0.67945 -0.305054)
			(stroke
				(width 0.1)
				(type default)
			)
			(layer "F.Fab")
		)
		(pad "1" smd circle
			(at -0.40005 0 90)
			(size 0 0)
			(layers "F.Cu" "F.Mask" "F.Paste")
			(net "SMB_BIC_I2C9_MUX0_SSD1_R_SDA")
		)
		(pad "2" smd circle
			(at 0.40005 0 90)
			(size 0 0)
			(layers "F.Cu" "F.Mask" "F.Paste")
			(net "SMB_ISO_SSD1_SDA")
		)
	)
	(footprint ""
		(layer "F.Cu")
		(at 217.235786 -225.490786 180)
		(property "Reference" "R1486"
			(at 0 0 180)
			(layer "F.SilkS")
			(hide yes)
			(effects
				(font
					(size 1.27 1.27)
				)
			)
		)
		(property "Value" ""
			(at 0 0 180)
			(layer "F.Fab")
			(effects
				(font
					(size 1.27 1.27)
				)
			)
		)
		(duplicate_pad_numbers_are_jumpers no)
		(fp_line
			(start 0.7874 0.4064)
			(end -0.7874 0.4064)
			(stroke
				(width 0.1524)
				(type default)
			)
			(layer "F.SilkS")
		)
		(fp_line
			(start 0.7874 -0.4064)
			(end 0.7874 0.4064)
			(stroke
				(width 0.1524)
				(type default)
			)
			(layer "F.SilkS")
		)
		(fp_line
			(start -0.7874 0.4064)
			(end -0.7874 -0.4064)
			(stroke
				(width 0.1524)
				(type default)
			)
			(layer "F.SilkS")
		)
		(fp_line
			(start -0.7874 -0.4064)
			(end 0.7874 -0.4064)
			(stroke
				(width 0.1524)
				(type default)
			)
			(layer "F.SilkS")
		)
		(fp_line
			(start 0.67945 0.3048)
			(end 0.120396 0.3048)
			(stroke
				(width 0.1)
				(type default)
			)
			(layer "F.Fab")
		)
		(fp_line
			(start 0.67945 -0.3048)
			(end 0.67945 0.3048)
			(stroke
				(width 0.1)
				(type default)
			)
			(layer "F.Fab")
		)
		(fp_line
			(start 0.12065 -0.2794)
			(end 0.12065 -0.3048)
			(stroke
				(width 0.1)
				(type default)
			)
			(layer "F.Fab")
		)
		(fp_line
			(start 0.12065 -0.3048)
			(end 0.67945 -0.3048)
			(stroke
				(width 0.1)
				(type default)
			)
			(layer "F.Fab")
		)
		(fp_line
			(start 0.120396 0.3048)
			(end 0.120396 0.2794)
			(stroke
				(width 0.1)
				(type default)
			)
			(layer "F.Fab")
		)
		(fp_line
			(start 0.120396 0.2794)
			(end -0.12065 0.2794)
			(stroke
				(width 0.1)
				(type default)
			)
			(layer "F.Fab")
		)
		(fp_line
			(start -0.12065 0.3048)
			(end -0.67945 0.3048)
			(stroke
				(width 0.1)
				(type default)
			)
			(layer "F.Fab")
		)
		(fp_line
			(start -0.12065 0.2794)
			(end -0.12065 0.3048)
			(stroke
				(width 0.1)
				(type default)
			)
			(layer "F.Fab")
		)
		(fp_line
			(start -0.12065 -0.2794)
			(end 0.12065 -0.2794)
			(stroke
				(width 0.1)
				(type default)
			)
			(layer "F.Fab")
		)
		(fp_line
			(start -0.12065 -0.305054)
			(end -0.12065 -0.2794)
			(stroke
				(width 0.1)
				(type default)
			)
			(layer "F.Fab")
		)
		(fp_line
			(start -0.67945 0.3048)
			(end -0.67945 -0.305054)
			(stroke
				(width 0.1)
				(type default)
			)
			(layer "F.Fab")
		)
		(fp_line
			(start -0.67945 -0.305054)
			(end -0.12065 -0.305054)
			(stroke
				(width 0.1)
				(type default)
			)
			(layer "F.Fab")
		)
		(pad "1" smd circle
			(at -0.40005 0 180)
			(size 0 0)
			(layers "F.Cu" "F.Mask" "F.Paste")
			(net "SMB_NIC3_SCL")
		)
		(pad "2" smd circle
			(at 0.40005 0 180)
			(size 0 0)
			(layers "F.Cu" "F.Mask" "F.Paste")
			(net "SMB_NIC3_R_SCL")
		)
	)
	(footprint ""
		(layer "F.Cu")
		(at 387.06044 -97.1804 180)
		(property "Reference" "R314"
			(at 0 0 180)
			(layer "F.SilkS")
			(hide yes)
			(effects
				(font
					(size 1.27 1.27)
				)
			)
		)
		(property "Value" ""
			(at 0 0 180)
			(layer "F.Fab")
			(effects
				(font
					(size 1.27 1.27)
				)
			)
		)
		(duplicate_pad_numbers_are_jumpers no)
		(fp_line
			(start 0.7874 0.4064)
			(end -0.7874 0.4064)
			(stroke
				(width 0.1524)
				(type default)
			)
			(layer "F.SilkS")
		)
		(fp_line
			(start 0.7874 -0.4064)
			(end 0.7874 0.4064)
			(stroke
				(width 0.1524)
				(type default)
			)
			(layer "F.SilkS")
		)
		(fp_line
			(start -0.7874 0.4064)
			(end -0.7874 -0.4064)
			(stroke
				(width 0.1524)
				(type default)
			)
			(layer "F.SilkS")
		)
		(fp_line
			(start -0.7874 -0.4064)
			(end 0.7874 -0.4064)
			(stroke
				(width 0.1524)
				(type default)
			)
			(layer "F.SilkS")
		)
		(fp_line
			(start 0.67945 0.3048)
			(end 0.120396 0.3048)
			(stroke
				(width 0.1)
				(type default)
			)
			(layer "F.Fab")
		)
		(fp_line
			(start 0.67945 -0.3048)
			(end 0.67945 0.3048)
			(stroke
				(width 0.1)
				(type default)
			)
			(layer "F.Fab")
		)
		(fp_line
			(start 0.12065 -0.2794)
			(end 0.12065 -0.3048)
			(stroke
				(width 0.1)
				(type default)
			)
			(layer "F.Fab")
		)
		(fp_line
			(start 0.12065 -0.3048)
			(end 0.67945 -0.3048)
			(stroke
				(width 0.1)
				(type default)
			)
			(layer "F.Fab")
		)
		(fp_line
			(start 0.120396 0.3048)
			(end 0.120396 0.2794)
			(stroke
				(width 0.1)
				(type default)
			)
			(layer "F.Fab")
		)
		(fp_line
			(start 0.120396 0.2794)
			(end -0.12065 0.2794)
			(stroke
				(width 0.1)
				(type default)
			)
			(layer "F.Fab")
		)
		(fp_line
			(start -0.12065 0.3048)
			(end -0.67945 0.3048)
			(stroke
				(width 0.1)
				(type default)
			)
			(layer "F.Fab")
		)
		(fp_line
			(start -0.12065 0.2794)
			(end -0.12065 0.3048)
			(stroke
				(width 0.1)
				(type default)
			)
			(layer "F.Fab")
		)
		(fp_line
			(start -0.12065 -0.2794)
			(end 0.12065 -0.2794)
			(stroke
				(width 0.1)
				(type default)
			)
			(layer "F.Fab")
		)
		(fp_line
			(start -0.12065 -0.305054)
			(end -0.12065 -0.2794)
			(stroke
				(width 0.1)
				(type default)
			)
			(layer "F.Fab")
		)
		(fp_line
			(start -0.67945 0.3048)
			(end -0.67945 -0.305054)
			(stroke
				(width 0.1)
				(type default)
			)
			(layer "F.Fab")
		)
		(fp_line
			(start -0.67945 -0.305054)
			(end -0.12065 -0.305054)
			(stroke
				(width 0.1)
				(type default)
			)
			(layer "F.Fab")
		)
		(pad "1" smd circle
			(at -0.40005 0 180)
			(size 0 0)
			(layers "F.Cu" "F.Mask" "F.Paste")
			(net "PRSNTB3_NIC6_N")
		)
		(pad "2" smd circle
			(at 0.40005 0 180)
			(size 0 0)
			(layers "F.Cu" "F.Mask" "F.Paste")
			(net "P3V3_AUX")
		)
	)
	(footprint ""
		(layer "F.Cu")
		(at 132.088128 -45.704252 90)
		(property "Reference" "R551"
			(at 0 0 90)
			(layer "F.SilkS")
			(hide yes)
			(effects
				(font
					(size 1.27 1.27)
				)
			)
		)
		(property "Value" ""
			(at 0 0 90)
			(layer "F.Fab")
			(effects
				(font
					(size 1.27 1.27)
				)
			)
		)
		(duplicate_pad_numbers_are_jumpers no)
		(fp_line
			(start 3.937508 -1.8796)
			(end -3.937508 -1.8796)
			(stroke
				(width 0.1524)
				(type default)
			)
			(layer "F.SilkS")
		)
		(fp_line
			(start -3.937508 -1.8796)
			(end -3.937508 1.8796)
			(stroke
				(width 0.1524)
				(type default)
			)
			(layer "F.SilkS")
		)
		(fp_line
			(start 3.937508 1.8796)
			(end 3.937508 -1.8796)
			(stroke
				(width 0.1524)
				(type default)
			)
			(layer "F.SilkS")
		)
		(fp_line
			(start -3.937508 1.8796)
			(end 3.937508 1.8796)
			(stroke
				(width 0.1524)
				(type default)
			)
			(layer "F.SilkS")
		)
		(fp_line
			(start 3.275076 -1.674876)
			(end -3.275076 -1.674876)
			(stroke
				(width 0.1)
				(type default)
			)
			(layer "F.Fab")
		)
		(fp_line
			(start -3.275076 -1.674876)
			(end -3.275076 1.674876)
			(stroke
				(width 0.1)
				(type default)
			)
			(layer "F.Fab")
		)
		(fp_line
			(start 3.275076 1.674876)
			(end 3.275076 -1.674876)
			(stroke
				(width 0.1)
				(type default)
			)
			(layer "F.Fab")
		)
		(fp_line
			(start -3.275076 1.674876)
			(end 3.275076 1.674876)
			(stroke
				(width 0.1)
				(type default)
			)
			(layer "F.Fab")
		)
		(pad "1" smd rect
			(at -2.350008 0 90)
			(size 2.921 3.5052)
			(layers "F.Cu" "F.Mask" "F.Paste")
			(net "P12V_SSD4")
		)
		(pad "2" smd rect
			(at 2.350008 0 90)
			(size 2.921 3.5052)
			(layers "F.Cu" "F.Mask" "F.Paste")
			(net "P12V_SSD4_R")
		)
	)
	(footprint ""
		(layer "F.Cu")
		(at 452.910448 -18.61439 90)
		(property "Reference" "U141"
			(at -1.13919 2.766822 90)
			(unlocked yes)
			(layer "F.SilkS")
			(effects
				(font
					(size 0.7874 0.5842)
					(thickness 0.1524)
				)
				(justify left)
			)
		)
		(property "Value" ""
			(at 0 0 90)
			(layer "F.Fab")
			(effects
				(font
					(size 1.27 1.27)
				)
			)
		)
		(duplicate_pad_numbers_are_jumpers no)
		(fp_line
			(start 1.463548 -1.549908)
			(end 1.463548 1.549908)
			(stroke
				(width 0.1524)
				(type default)
			)
			(layer "F.SilkS")
		)
		(fp_line
			(start 0.762 -1.549908)
			(end 1.463548 -1.549908)
			(stroke
				(width 0.1524)
				(type default)
			)
			(layer "F.SilkS")
		)
		(fp_line
			(start -0.787908 -1.549908)
			(end 0 -0.762)
			(stroke
				(width 0.1524)
				(type default)
			)
			(layer "F.SilkS")
		)
		(fp_line
			(start -1.463548 -1.549908)
			(end -0.787908 -1.549908)
			(stroke
				(width 0.1524)
				(type default)
			)
			(layer "F.SilkS")
		)
		(fp_line
			(start 0 -0.762)
			(end 0.762 -1.549908)
			(stroke
				(width 0.1524)
				(type default)
			)
			(layer "F.SilkS")
		)
		(fp_line
			(start 1.463548 1.549908)
			(end -1.463548 1.549908)
			(stroke
				(width 0.1524)
				(type default)
			)
			(layer "F.SilkS")
		)
		(fp_line
			(start -1.463548 1.549908)
			(end -1.463548 -1.549908)
			(stroke
				(width 0.1524)
				(type default)
			)
			(layer "F.SilkS")
		)
		(fp_poly
			(pts
				(xy -3.4798 -1.359916) (xy -2.86004 -1.050036) (xy -3.4798 -0.740156)
			)
			(stroke
				(width 0)
				(type default)
			)
			(fill yes)
			(layer "F.SilkS")
		)
		(fp_line
			(start 1.549908 -1.549908)
			(end 1.549908 1.549908)
			(stroke
				(width 0.1)
				(type default)
			)
			(layer "F.Fab")
		)
		(fp_line
			(start -1.549908 -1.549908)
			(end 1.549908 -1.549908)
			(stroke
				(width 0.1)
				(type default)
			)
			(layer "F.Fab")
		)
		(fp_line
			(start 1.549908 1.549908)
			(end -1.549908 1.549908)
			(stroke
				(width 0.1)
				(type default)
			)
			(layer "F.Fab")
		)
		(fp_line
			(start -1.549908 1.549908)
			(end -1.549908 -1.549908)
			(stroke
				(width 0.1)
				(type default)
			)
			(layer "F.Fab")
		)
		(fp_poly
			(pts
				(xy -3.4798 -1.359916) (xy -2.86004 -1.050036) (xy -3.4798 -0.740156)
			)
			(stroke
				(width 0)
				(type default)
			)
			(fill yes)
			(layer "F.Fab")
		)
		(pad "1" smd rect
			(at -2.175002 -1.050036 180)
			(size 0.6096 1.1684)
			(layers "F.Cu" "F.Mask" "F.Paste")
			(net "P3V3_SSD15")
		)
		(pad "2" smd rect
			(at -2.175002 -0.32512 180)
			(size 0.4318 1.1684)
			(layers "F.Cu" "F.Mask" "F.Paste")
			(net "SMB_ISO_SSD15_SCL")
		)
		(pad "3" smd rect
			(at -2.175002 0.32512 180)
			(size 0.4318 1.1684)
			(layers "F.Cu" "F.Mask" "F.Paste")
			(net "SMB_ISO_SSD15_SDA")
		)
		(pad "4" smd rect
			(at -2.175002 1.050036 180)
			(size 0.6096 1.1684)
			(layers "F.Cu" "F.Mask" "F.Paste")
			(net "GND")
		)
		(pad "5" smd rect
			(at 2.175002 1.050036 180)
			(size 0.6096 1.1684)
			(layers "F.Cu" "F.Mask" "F.Paste")
			(net "SMB_SSD15_ISO_EN")
		)
		(pad "6" smd rect
			(at 2.175002 0.32512 180)
			(size 0.4318 1.1684)
			(layers "F.Cu" "F.Mask" "F.Paste")
			(net "SMB_BIC_I2C9_MUX1_SSD15_R_SDA")
		)
		(pad "7" smd rect
			(at 2.175002 -0.32512 180)
			(size 0.4318 1.1684)
			(layers "F.Cu" "F.Mask" "F.Paste")
			(net "SMB_BIC_I2C9_MUX1_SSD15_R_SCL")
		)
		(pad "8" smd rect
			(at 2.175002 -1.050036 180)
			(size 0.6096 1.1684)
			(layers "F.Cu" "F.Mask" "F.Paste")
			(net "P3V3_AUX")
		)
	)
	(footprint ""
		(layer "F.Cu")
		(at 379.633988 -3.820922)
		(property "Reference" "R5823"
			(at 0 0 0)
			(layer "F.SilkS")
			(hide yes)
			(effects
				(font
					(size 1.27 1.27)
				)
			)
		)
		(property "Value" ""
			(at 0 0 0)
			(layer "F.Fab")
			(effects
				(font
					(size 1.27 1.27)
				)
			)
		)
		(duplicate_pad_numbers_are_jumpers no)
		(fp_line
			(start -0.7874 -0.4064)
			(end 0.7874 -0.4064)
			(stroke
				(width 0.1524)
				(type default)
			)
			(layer "F.SilkS")
		)
		(fp_line
			(start -0.7874 0.4064)
			(end -0.7874 -0.4064)
			(stroke
				(width 0.1524)
				(type default)
			)
			(layer "F.SilkS")
		)
		(fp_line
			(start 0.7874 -0.4064)
			(end 0.7874 0.4064)
			(stroke
				(width 0.1524)
				(type default)
			)
			(layer "F.SilkS")
		)
		(fp_line
			(start 0.7874 0.4064)
			(end -0.7874 0.4064)
			(stroke
				(width 0.1524)
				(type default)
			)
			(layer "F.SilkS")
		)
		(fp_line
			(start -0.67945 -0.305054)
			(end -0.12065 -0.305054)
			(stroke
				(width 0.1)
				(type default)
			)
			(layer "F.Fab")
		)
		(fp_line
			(start -0.67945 0.3048)
			(end -0.67945 -0.305054)
			(stroke
				(width 0.1)
				(type default)
			)
			(layer "F.Fab")
		)
		(fp_line
			(start -0.12065 -0.305054)
			(end -0.12065 -0.2794)
			(stroke
				(width 0.1)
				(type default)
			)
			(layer "F.Fab")
		)
		(fp_line
			(start -0.12065 -0.2794)
			(end 0.12065 -0.2794)
			(stroke
				(width 0.1)
				(type default)
			)
			(layer "F.Fab")
		)
		(fp_line
			(start -0.12065 0.2794)
			(end -0.12065 0.3048)
			(stroke
				(width 0.1)
				(type default)
			)
			(layer "F.Fab")
		)
		(fp_line
			(start -0.12065 0.3048)
			(end -0.67945 0.3048)
			(stroke
				(width 0.1)
				(type default)
			)
			(layer "F.Fab")
		)
		(fp_line
			(start 0.120396 0.2794)
			(end -0.12065 0.2794)
			(stroke
				(width 0.1)
				(type default)
			)
			(layer "F.Fab")
		)
		(fp_line
			(start 0.120396 0.3048)
			(end 0.120396 0.2794)
			(stroke
				(width 0.1)
				(type default)
			)
			(layer "F.Fab")
		)
		(fp_line
			(start 0.12065 -0.3048)
			(end 0.67945 -0.3048)
			(stroke
				(width 0.1)
				(type default)
			)
			(layer "F.Fab")
		)
		(fp_line
			(start 0.12065 -0.2794)
			(end 0.12065 -0.3048)
			(stroke
				(width 0.1)
				(type default)
			)
			(layer "F.Fab")
		)
		(fp_line
			(start 0.67945 -0.3048)
			(end 0.67945 0.3048)
			(stroke
				(width 0.1)
				(type default)
			)
			(layer "F.Fab")
		)
		(fp_line
			(start 0.67945 0.3048)
			(end 0.120396 0.3048)
			(stroke
				(width 0.1)
				(type default)
			)
			(layer "F.Fab")
		)
		(pad "1" smd circle
			(at -0.40005 0)
			(size 0 0)
			(layers "F.Cu" "F.Mask" "F.Paste")
			(net "LM75_3_A2")
		)
		(pad "2" smd circle
			(at 0.40005 0)
			(size 0 0)
			(layers "F.Cu" "F.Mask" "F.Paste")
			(net "GND")
		)
	)
	(footprint ""
		(layer "F.Cu")
		(at 17.83969 -214.151972 180)
		(property "Reference" "R6569"
			(at 0 0 180)
			(layer "F.SilkS")
			(hide yes)
			(effects
				(font
					(size 1.27 1.27)
				)
			)
		)
		(property "Value" ""
			(at 0 0 180)
			(layer "F.Fab")
			(effects
				(font
					(size 1.27 1.27)
				)
			)
		)
		(duplicate_pad_numbers_are_jumpers no)
		(fp_line
			(start 0.7874 0.4064)
			(end -0.7874 0.4064)
			(stroke
				(width 0.1524)
				(type default)
			)
			(layer "F.SilkS")
		)
		(fp_line
			(start 0.7874 -0.4064)
			(end 0.7874 0.4064)
			(stroke
				(width 0.1524)
				(type default)
			)
			(layer "F.SilkS")
		)
		(fp_line
			(start -0.7874 0.4064)
			(end -0.7874 -0.4064)
			(stroke
				(width 0.1524)
				(type default)
			)
			(layer "F.SilkS")
		)
		(fp_line
			(start -0.7874 -0.4064)
			(end 0.7874 -0.4064)
			(stroke
				(width 0.1524)
				(type default)
			)
			(layer "F.SilkS")
		)
		(fp_line
			(start 0.67945 0.3048)
			(end 0.120396 0.3048)
			(stroke
				(width 0.1)
				(type default)
			)
			(layer "F.Fab")
		)
		(fp_line
			(start 0.67945 -0.3048)
			(end 0.67945 0.3048)
			(stroke
				(width 0.1)
				(type default)
			)
			(layer "F.Fab")
		)
		(fp_line
			(start 0.12065 -0.2794)
			(end 0.12065 -0.3048)
			(stroke
				(width 0.1)
				(type default)
			)
			(layer "F.Fab")
		)
		(fp_line
			(start 0.12065 -0.3048)
			(end 0.67945 -0.3048)
			(stroke
				(width 0.1)
				(type default)
			)
			(layer "F.Fab")
		)
		(fp_line
			(start 0.120396 0.3048)
			(end 0.120396 0.2794)
			(stroke
				(width 0.1)
				(type default)
			)
			(layer "F.Fab")
		)
		(fp_line
			(start 0.120396 0.2794)
			(end -0.12065 0.2794)
			(stroke
				(width 0.1)
				(type default)
			)
			(layer "F.Fab")
		)
		(fp_line
			(start -0.12065 0.3048)
			(end -0.67945 0.3048)
			(stroke
				(width 0.1)
				(type default)
			)
			(layer "F.Fab")
		)
		(fp_line
			(start -0.12065 0.2794)
			(end -0.12065 0.3048)
			(stroke
				(width 0.1)
				(type default)
			)
			(layer "F.Fab")
		)
		(fp_line
			(start -0.12065 -0.2794)
			(end 0.12065 -0.2794)
			(stroke
				(width 0.1)
				(type default)
			)
			(layer "F.Fab")
		)
		(fp_line
			(start -0.12065 -0.305054)
			(end -0.12065 -0.2794)
			(stroke
				(width 0.1)
				(type default)
			)
			(layer "F.Fab")
		)
		(fp_line
			(start -0.67945 0.3048)
			(end -0.67945 -0.305054)
			(stroke
				(width 0.1)
				(type default)
			)
			(layer "F.Fab")
		)
		(fp_line
			(start -0.67945 -0.305054)
			(end -0.12065 -0.305054)
			(stroke
				(width 0.1)
				(type default)
			)
			(layer "F.Fab")
		)
		(pad "1" smd circle
			(at -0.40005 0 180)
			(size 0 0)
			(layers "F.Cu" "F.Mask" "F.Paste")
			(net "PWRGD_PEX0_P1V8_PLL_R")
		)
		(pad "2" smd circle
			(at 0.40005 0 180)
			(size 0 0)
			(layers "F.Cu" "F.Mask" "F.Paste")
			(net "PWRGD_PEX0_P1V8_PLL")
		)
	)
	(footprint ""
		(layer "F.Cu")
		(at 222.220028 -117.90045 90)
		(property "Reference" "PC621"
			(at 0 0 90)
			(layer "F.SilkS")
			(hide yes)
			(effects
				(font
					(size 1.27 1.27)
				)
			)
		)
		(property "Value" ""
			(at 0 0 90)
			(layer "F.Fab")
			(effects
				(font
					(size 1.27 1.27)
				)
			)
		)
		(duplicate_pad_numbers_are_jumpers no)
		(fp_line
			(start 1.524 -0.762)
			(end 1.524 0.762)
			(stroke
				(width 0.1524)
				(type default)
			)
			(layer "F.SilkS")
		)
		(fp_line
			(start -1.524 -0.762)
			(end 1.524 -0.762)
			(stroke
				(width 0.1524)
				(type default)
			)
			(layer "F.SilkS")
		)
		(fp_line
			(start 1.524 0.762)
			(end -1.524 0.762)
			(stroke
				(width 0.1524)
				(type default)
			)
			(layer "F.SilkS")
		)
		(fp_line
			(start -1.524 0.762)
			(end -1.524 -0.762)
			(stroke
				(width 0.1524)
				(type default)
			)
			(layer "F.SilkS")
		)
		(fp_line
			(start 1.1049 -0.724916)
			(end -1.1049 -0.724916)
			(stroke
				(width 0.1)
				(type default)
			)
			(layer "F.Fab")
		)
		(fp_line
			(start -1.1049 -0.724916)
			(end -1.1049 0.724916)
			(stroke
				(width 0.1)
				(type default)
			)
			(layer "F.Fab")
		)
		(fp_line
			(start 1.1049 0.724916)
			(end 1.1049 -0.724916)
			(stroke
				(width 0.1)
				(type default)
			)
			(layer "F.Fab")
		)
		(fp_line
			(start -1.1049 0.724916)
			(end 1.1049 0.724916)
			(stroke
				(width 0.1)
				(type default)
			)
			(layer "F.Fab")
		)
		(pad "1" smd rect
			(at -0.889 0 270)
			(size 1.016 1.27)
			(layers "F.Cu" "F.Mask" "F.Paste")
			(net "P12V_NIC3_R")
		)
		(pad "2" smd rect
			(at 0.889 0 270)
			(size 1.016 1.27)
			(layers "F.Cu" "F.Mask" "F.Paste")
			(net "GND")
		)
	)
	(footprint ""
		(layer "F.Cu")
		(at 63.56731 -171.675806)
		(property "Reference" "R49"
			(at 0 0 0)
			(layer "F.SilkS")
			(hide yes)
			(effects
				(font
					(size 1.27 1.27)
				)
			)
		)
		(property "Value" ""
			(at 0 0 0)
			(layer "F.Fab")
			(effects
				(font
					(size 1.27 1.27)
				)
			)
		)
		(duplicate_pad_numbers_are_jumpers no)
		(fp_line
			(start -0.7874 -0.4064)
			(end 0.7874 -0.4064)
			(stroke
				(width 0.1524)
				(type default)
			)
			(layer "F.SilkS")
		)
		(fp_line
			(start -0.7874 0.4064)
			(end -0.7874 -0.4064)
			(stroke
				(width 0.1524)
				(type default)
			)
			(layer "F.SilkS")
		)
		(fp_line
			(start 0.7874 -0.4064)
			(end 0.7874 0.4064)
			(stroke
				(width 0.1524)
				(type default)
			)
			(layer "F.SilkS")
		)
		(fp_line
			(start 0.7874 0.4064)
			(end -0.7874 0.4064)
			(stroke
				(width 0.1524)
				(type default)
			)
			(layer "F.SilkS")
		)
		(fp_line
			(start -0.67945 -0.305054)
			(end -0.12065 -0.305054)
			(stroke
				(width 0.1)
				(type default)
			)
			(layer "F.Fab")
		)
		(fp_line
			(start -0.67945 0.3048)
			(end -0.67945 -0.305054)
			(stroke
				(width 0.1)
				(type default)
			)
			(layer "F.Fab")
		)
		(fp_line
			(start -0.12065 -0.305054)
			(end -0.12065 -0.2794)
			(stroke
				(width 0.1)
				(type default)
			)
			(layer "F.Fab")
		)
		(fp_line
			(start -0.12065 -0.2794)
			(end 0.12065 -0.2794)
			(stroke
				(width 0.1)
				(type default)
			)
			(layer "F.Fab")
		)
		(fp_line
			(start -0.12065 0.2794)
			(end -0.12065 0.3048)
			(stroke
				(width 0.1)
				(type default)
			)
			(layer "F.Fab")
		)
		(fp_line
			(start -0.12065 0.3048)
			(end -0.67945 0.3048)
			(stroke
				(width 0.1)
				(type default)
			)
			(layer "F.Fab")
		)
		(fp_line
			(start 0.120396 0.2794)
			(end -0.12065 0.2794)
			(stroke
				(width 0.1)
				(type default)
			)
			(layer "F.Fab")
		)
		(fp_line
			(start 0.120396 0.3048)
			(end 0.120396 0.2794)
			(stroke
				(width 0.1)
				(type default)
			)
			(layer "F.Fab")
		)
		(fp_line
			(start 0.12065 -0.3048)
			(end 0.67945 -0.3048)
			(stroke
				(width 0.1)
				(type default)
			)
			(layer "F.Fab")
		)
		(fp_line
			(start 0.12065 -0.2794)
			(end 0.12065 -0.3048)
			(stroke
				(width 0.1)
				(type default)
			)
			(layer "F.Fab")
		)
		(fp_line
			(start 0.67945 -0.3048)
			(end 0.67945 0.3048)
			(stroke
				(width 0.1)
				(type default)
			)
			(layer "F.Fab")
		)
		(fp_line
			(start 0.67945 0.3048)
			(end 0.120396 0.3048)
			(stroke
				(width 0.1)
				(type default)
			)
			(layer "F.Fab")
		)
		(pad "1" smd circle
			(at -0.40005 0)
			(size 0 0)
			(layers "F.Cu" "F.Mask" "F.Paste")
			(net "P3V3_NIC0")
		)
		(pad "2" smd circle
			(at 0.40005 0)
			(size 0 0)
			(layers "F.Cu" "F.Mask" "F.Paste")
			(net "HP_NIC0_PWRGD")
		)
	)
	(footprint ""
		(layer "F.Cu")
		(at 359.422192 -284.834838 90)
		(property "Reference" "PC189"
			(at 0 0 90)
			(layer "F.SilkS")
			(hide yes)
			(effects
				(font
					(size 1.27 1.27)
				)
			)
		)
		(property "Value" ""
			(at 0 0 90)
			(layer "F.Fab")
			(effects
				(font
					(size 1.27 1.27)
				)
			)
		)
		(duplicate_pad_numbers_are_jumpers no)
		(fp_line
			(start 0.7874 -0.4064)
			(end 0.7874 0.4064)
			(stroke
				(width 0.1524)
				(type default)
			)
			(layer "F.SilkS")
		)
		(fp_line
			(start -0.7874 -0.4064)
			(end 0.7874 -0.4064)
			(stroke
				(width 0.1524)
				(type default)
			)
			(layer "F.SilkS")
		)
		(fp_line
			(start 0.7874 0.4064)
			(end -0.7874 0.4064)
			(stroke
				(width 0.1524)
				(type default)
			)
			(layer "F.SilkS")
		)
		(fp_line
			(start -0.7874 0.4064)
			(end -0.7874 -0.4064)
			(stroke
				(width 0.1524)
				(type default)
			)
			(layer "F.SilkS")
		)
		(fp_line
			(start -0.12065 -0.305054)
			(end -0.12065 -0.2794)
			(stroke
				(width 0.1)
				(type default)
			)
			(layer "F.Fab")
		)
		(fp_line
			(start -0.67945 -0.305054)
			(end -0.12065 -0.305054)
			(stroke
				(width 0.1)
				(type default)
			)
			(layer "F.Fab")
		)
		(fp_line
			(start 0.67945 -0.3048)
			(end 0.67945 0.3048)
			(stroke
				(width 0.1)
				(type default)
			)
			(layer "F.Fab")
		)
		(fp_line
			(start 0.12065 -0.3048)
			(end 0.67945 -0.3048)
			(stroke
				(width 0.1)
				(type default)
			)
			(layer "F.Fab")
		)
		(fp_line
			(start 0.12065 -0.2794)
			(end 0.12065 -0.3048)
			(stroke
				(width 0.1)
				(type default)
			)
			(layer "F.Fab")
		)
		(fp_line
			(start -0.12065 -0.2794)
			(end 0.12065 -0.2794)
			(stroke
				(width 0.1)
				(type default)
			)
			(layer "F.Fab")
		)
		(fp_line
			(start 0.120396 0.2794)
			(end -0.12065 0.2794)
			(stroke
				(width 0.1)
				(type default)
			)
			(layer "F.Fab")
		)
		(fp_line
			(start -0.12065 0.2794)
			(end -0.12065 0.3048)
			(stroke
				(width 0.1)
				(type default)
			)
			(layer "F.Fab")
		)
		(fp_line
			(start 0.67945 0.3048)
			(end 0.120396 0.3048)
			(stroke
				(width 0.1)
				(type default)
			)
			(layer "F.Fab")
		)
		(fp_line
			(start 0.120396 0.3048)
			(end 0.120396 0.2794)
			(stroke
				(width 0.1)
				(type default)
			)
			(layer "F.Fab")
		)
		(fp_line
			(start -0.12065 0.3048)
			(end -0.67945 0.3048)
			(stroke
				(width 0.1)
				(type default)
			)
			(layer "F.Fab")
		)
		(fp_line
			(start -0.67945 0.3048)
			(end -0.67945 -0.305054)
			(stroke
				(width 0.1)
				(type default)
			)
			(layer "F.Fab")
		)
		(pad "1" smd circle
			(at -0.40005 0 90)
			(size 0 0)
			(layers "F.Cu" "F.Mask" "F.Paste")
			(net "SW_P12V_P0V8_PEX3_FLT")
		)
		(pad "2" smd circle
			(at 0.40005 0 90)
			(size 0 0)
			(layers "F.Cu" "F.Mask" "F.Paste")
			(net "GND")
		)
	)
	(footprint ""
		(layer "F.Cu")
		(at 214.274908 -48.753014 180)
		(property "Reference" "C312"
			(at 0 0 180)
			(layer "F.SilkS")
			(hide yes)
			(effects
				(font
					(size 1.27 1.27)
				)
			)
		)
		(property "Value" ""
			(at 0 0 180)
			(layer "F.Fab")
			(effects
				(font
					(size 1.27 1.27)
				)
			)
		)
		(duplicate_pad_numbers_are_jumpers no)
		(fp_line
			(start 0.7874 0.4064)
			(end -0.7874 0.4064)
			(stroke
				(width 0.1524)
				(type default)
			)
			(layer "F.SilkS")
		)
		(fp_line
			(start 0.7874 -0.4064)
			(end 0.7874 0.4064)
			(stroke
				(width 0.1524)
				(type default)
			)
			(layer "F.SilkS")
		)
		(fp_line
			(start -0.7874 0.4064)
			(end -0.7874 -0.4064)
			(stroke
				(width 0.1524)
				(type default)
			)
			(layer "F.SilkS")
		)
		(fp_line
			(start -0.7874 -0.4064)
			(end 0.7874 -0.4064)
			(stroke
				(width 0.1524)
				(type default)
			)
			(layer "F.SilkS")
		)
		(fp_line
			(start 0.67945 0.3048)
			(end 0.120396 0.3048)
			(stroke
				(width 0.1)
				(type default)
			)
			(layer "F.Fab")
		)
		(fp_line
			(start 0.67945 -0.3048)
			(end 0.67945 0.3048)
			(stroke
				(width 0.1)
				(type default)
			)
			(layer "F.Fab")
		)
		(fp_line
			(start 0.12065 -0.2794)
			(end 0.12065 -0.3048)
			(stroke
				(width 0.1)
				(type default)
			)
			(layer "F.Fab")
		)
		(fp_line
			(start 0.12065 -0.3048)
			(end 0.67945 -0.3048)
			(stroke
				(width 0.1)
				(type default)
			)
			(layer "F.Fab")
		)
		(fp_line
			(start 0.120396 0.3048)
			(end 0.120396 0.2794)
			(stroke
				(width 0.1)
				(type default)
			)
			(layer "F.Fab")
		)
		(fp_line
			(start 0.120396 0.2794)
			(end -0.12065 0.2794)
			(stroke
				(width 0.1)
				(type default)
			)
			(layer "F.Fab")
		)
		(fp_line
			(start -0.12065 0.3048)
			(end -0.67945 0.3048)
			(stroke
				(width 0.1)
				(type default)
			)
			(layer "F.Fab")
		)
		(fp_line
			(start -0.12065 0.2794)
			(end -0.12065 0.3048)
			(stroke
				(width 0.1)
				(type default)
			)
			(layer "F.Fab")
		)
		(fp_line
			(start -0.12065 -0.2794)
			(end 0.12065 -0.2794)
			(stroke
				(width 0.1)
				(type default)
			)
			(layer "F.Fab")
		)
		(fp_line
			(start -0.12065 -0.305054)
			(end -0.12065 -0.2794)
			(stroke
				(width 0.1)
				(type default)
			)
			(layer "F.Fab")
		)
		(fp_line
			(start -0.67945 0.3048)
			(end -0.67945 -0.305054)
			(stroke
				(width 0.1)
				(type default)
			)
			(layer "F.Fab")
		)
		(fp_line
			(start -0.67945 -0.305054)
			(end -0.12065 -0.305054)
			(stroke
				(width 0.1)
				(type default)
			)
			(layer "F.Fab")
		)
		(pad "1" smd circle
			(at -0.40005 0 180)
			(size 0 0)
			(layers "F.Cu" "F.Mask" "F.Paste")
			(net "P3V3_AUX")
		)
		(pad "2" smd circle
			(at 0.40005 0 180)
			(size 0 0)
			(layers "F.Cu" "F.Mask" "F.Paste")
			(net "GND")
		)
	)
	(footprint ""
		(layer "F.Cu")
		(at 259.590286 -252.356874 -90)
		(property "Reference" "R1361"
			(at 0 0 270)
			(layer "F.SilkS")
			(hide yes)
			(effects
				(font
					(size 1.27 1.27)
				)
			)
		)
		(property "Value" ""
			(at 0 0 270)
			(layer "F.Fab")
			(effects
				(font
					(size 1.27 1.27)
				)
			)
		)
		(duplicate_pad_numbers_are_jumpers no)
		(fp_line
			(start -0.7874 0.4064)
			(end -0.7874 -0.4064)
			(stroke
				(width 0.1524)
				(type default)
			)
			(layer "F.SilkS")
		)
		(fp_line
			(start 0.7874 0.4064)
			(end -0.7874 0.4064)
			(stroke
				(width 0.1524)
				(type default)
			)
			(layer "F.SilkS")
		)
		(fp_line
			(start -0.7874 -0.4064)
			(end 0.7874 -0.4064)
			(stroke
				(width 0.1524)
				(type default)
			)
			(layer "F.SilkS")
		)
		(fp_line
			(start 0.7874 -0.4064)
			(end 0.7874 0.4064)
			(stroke
				(width 0.1524)
				(type default)
			)
			(layer "F.SilkS")
		)
		(fp_line
			(start -0.67945 0.3048)
			(end -0.67945 -0.305054)
			(stroke
				(width 0.1)
				(type default)
			)
			(layer "F.Fab")
		)
		(fp_line
			(start -0.12065 0.3048)
			(end -0.67945 0.3048)
			(stroke
				(width 0.1)
				(type default)
			)
			(layer "F.Fab")
		)
		(fp_line
			(start 0.120396 0.3048)
			(end 0.120396 0.2794)
			(stroke
				(width 0.1)
				(type default)
			)
			(layer "F.Fab")
		)
		(fp_line
			(start 0.67945 0.3048)
			(end 0.120396 0.3048)
			(stroke
				(width 0.1)
				(type default)
			)
			(layer "F.Fab")
		)
		(fp_line
			(start -0.12065 0.2794)
			(end -0.12065 0.3048)
			(stroke
				(width 0.1)
				(type default)
			)
			(layer "F.Fab")
		)
		(fp_line
			(start 0.120396 0.2794)
			(end -0.12065 0.2794)
			(stroke
				(width 0.1)
				(type default)
			)
			(layer "F.Fab")
		)
		(fp_line
			(start -0.12065 -0.2794)
			(end 0.12065 -0.2794)
			(stroke
				(width 0.1)
				(type default)
			)
			(layer "F.Fab")
		)
		(fp_line
			(start 0.12065 -0.2794)
			(end 0.12065 -0.3048)
			(stroke
				(width 0.1)
				(type default)
			)
			(layer "F.Fab")
		)
		(fp_line
			(start 0.12065 -0.3048)
			(end 0.67945 -0.3048)
			(stroke
				(width 0.1)
				(type default)
			)
			(layer "F.Fab")
		)
		(fp_line
			(start 0.67945 -0.3048)
			(end 0.67945 0.3048)
			(stroke
				(width 0.1)
				(type default)
			)
			(layer "F.Fab")
		)
		(fp_line
			(start -0.67945 -0.305054)
			(end -0.12065 -0.305054)
			(stroke
				(width 0.1)
				(type default)
			)
			(layer "F.Fab")
		)
		(fp_line
			(start -0.12065 -0.305054)
			(end -0.12065 -0.2794)
			(stroke
				(width 0.1)
				(type default)
			)
			(layer "F.Fab")
		)
		(pad "1" smd circle
			(at -0.40005 0 270)
			(size 0 0)
			(layers "F.Cu" "F.Mask" "F.Paste")
			(net "GND")
		)
		(pad "2" smd circle
			(at 0.40005 0 270)
			(size 0 0)
			(layers "F.Cu" "F.Mask" "F.Paste")
			(net "PEX2_MODE_SEL5")
		)
	)
	(footprint ""
		(layer "F.Cu")
		(at 145.522442 -250.070874 -90)
		(property "Reference" "R1272"
			(at 0 0 270)
			(layer "F.SilkS")
			(hide yes)
			(effects
				(font
					(size 1.27 1.27)
				)
			)
		)
		(property "Value" ""
			(at 0 0 270)
			(layer "F.Fab")
			(effects
				(font
					(size 1.27 1.27)
				)
			)
		)
		(duplicate_pad_numbers_are_jumpers no)
		(fp_line
			(start -0.7874 0.4064)
			(end -0.7874 -0.4064)
			(stroke
				(width 0.1524)
				(type default)
			)
			(layer "F.SilkS")
		)
		(fp_line
			(start 0.7874 0.4064)
			(end -0.7874 0.4064)
			(stroke
				(width 0.1524)
				(type default)
			)
			(layer "F.SilkS")
		)
		(fp_line
			(start -0.7874 -0.4064)
			(end 0.7874 -0.4064)
			(stroke
				(width 0.1524)
				(type default)
			)
			(layer "F.SilkS")
		)
		(fp_line
			(start 0.7874 -0.4064)
			(end 0.7874 0.4064)
			(stroke
				(width 0.1524)
				(type default)
			)
			(layer "F.SilkS")
		)
		(fp_line
			(start -0.67945 0.3048)
			(end -0.67945 -0.305054)
			(stroke
				(width 0.1)
				(type default)
			)
			(layer "F.Fab")
		)
		(fp_line
			(start -0.12065 0.3048)
			(end -0.67945 0.3048)
			(stroke
				(width 0.1)
				(type default)
			)
			(layer "F.Fab")
		)
		(fp_line
			(start 0.120396 0.3048)
			(end 0.120396 0.2794)
			(stroke
				(width 0.1)
				(type default)
			)
			(layer "F.Fab")
		)
		(fp_line
			(start 0.67945 0.3048)
			(end 0.120396 0.3048)
			(stroke
				(width 0.1)
				(type default)
			)
			(layer "F.Fab")
		)
		(fp_line
			(start -0.12065 0.2794)
			(end -0.12065 0.3048)
			(stroke
				(width 0.1)
				(type default)
			)
			(layer "F.Fab")
		)
		(fp_line
			(start 0.120396 0.2794)
			(end -0.12065 0.2794)
			(stroke
				(width 0.1)
				(type default)
			)
			(layer "F.Fab")
		)
		(fp_line
			(start -0.12065 -0.2794)
			(end 0.12065 -0.2794)
			(stroke
				(width 0.1)
				(type default)
			)
			(layer "F.Fab")
		)
		(fp_line
			(start 0.12065 -0.2794)
			(end 0.12065 -0.3048)
			(stroke
				(width 0.1)
				(type default)
			)
			(layer "F.Fab")
		)
		(fp_line
			(start 0.12065 -0.3048)
			(end 0.67945 -0.3048)
			(stroke
				(width 0.1)
				(type default)
			)
			(layer "F.Fab")
		)
		(fp_line
			(start 0.67945 -0.3048)
			(end 0.67945 0.3048)
			(stroke
				(width 0.1)
				(type default)
			)
			(layer "F.Fab")
		)
		(fp_line
			(start -0.67945 -0.305054)
			(end -0.12065 -0.305054)
			(stroke
				(width 0.1)
				(type default)
			)
			(layer "F.Fab")
		)
		(fp_line
			(start -0.12065 -0.305054)
			(end -0.12065 -0.2794)
			(stroke
				(width 0.1)
				(type default)
			)
			(layer "F.Fab")
		)
		(pad "1" smd circle
			(at -0.40005 0 270)
			(size 0 0)
			(layers "F.Cu" "F.Mask" "F.Paste")
			(net "PEX1_MODE_SEL3")
		)
		(pad "2" smd circle
			(at 0.40005 0 270)
			(size 0 0)
			(layers "F.Cu" "F.Mask" "F.Paste")
			(net "P1V8_PEX")
		)
	)
	(footprint ""
		(layer "F.Cu")
		(at 25.222708 -237.733586)
		(property "Reference" "ME6"
			(at 0 0 0)
			(layer "F.SilkS")
			(hide yes)
			(effects
				(font
					(size 1.27 1.27)
				)
			)
		)
		(property "Value" ""
			(at 0 0 0)
			(layer "F.Fab")
			(effects
				(font
					(size 1.27 1.27)
				)
			)
		)
		(duplicate_pad_numbers_are_jumpers no)
	)
	(footprint ""
		(layer "F.Cu")
		(at 132.459476 -146.642328 -90)
		(property "Reference" "C888"
			(at 0 0 270)
			(layer "F.SilkS")
			(hide yes)
			(effects
				(font
					(size 1.27 1.27)
				)
			)
		)
		(property "Value" ""
			(at 0 0 270)
			(layer "F.Fab")
			(effects
				(font
					(size 1.27 1.27)
				)
			)
		)
		(duplicate_pad_numbers_are_jumpers no)
		(fp_line
			(start -0.7874 0.4064)
			(end -0.7874 -0.4064)
			(stroke
				(width 0.1524)
				(type default)
			)
			(layer "F.SilkS")
		)
		(fp_line
			(start 0.7874 0.4064)
			(end -0.7874 0.4064)
			(stroke
				(width 0.1524)
				(type default)
			)
			(layer "F.SilkS")
		)
		(fp_line
			(start -0.7874 -0.4064)
			(end 0.7874 -0.4064)
			(stroke
				(width 0.1524)
				(type default)
			)
			(layer "F.SilkS")
		)
		(fp_line
			(start 0.7874 -0.4064)
			(end 0.7874 0.4064)
			(stroke
				(width 0.1524)
				(type default)
			)
			(layer "F.SilkS")
		)
		(fp_line
			(start -0.67945 0.3048)
			(end -0.67945 -0.305054)
			(stroke
				(width 0.1)
				(type default)
			)
			(layer "F.Fab")
		)
		(fp_line
			(start -0.12065 0.3048)
			(end -0.67945 0.3048)
			(stroke
				(width 0.1)
				(type default)
			)
			(layer "F.Fab")
		)
		(fp_line
			(start 0.120396 0.3048)
			(end 0.120396 0.2794)
			(stroke
				(width 0.1)
				(type default)
			)
			(layer "F.Fab")
		)
		(fp_line
			(start 0.67945 0.3048)
			(end 0.120396 0.3048)
			(stroke
				(width 0.1)
				(type default)
			)
			(layer "F.Fab")
		)
		(fp_line
			(start -0.12065 0.2794)
			(end -0.12065 0.3048)
			(stroke
				(width 0.1)
				(type default)
			)
			(layer "F.Fab")
		)
		(fp_line
			(start 0.120396 0.2794)
			(end -0.12065 0.2794)
			(stroke
				(width 0.1)
				(type default)
			)
			(layer "F.Fab")
		)
		(fp_line
			(start -0.12065 -0.2794)
			(end 0.12065 -0.2794)
			(stroke
				(width 0.1)
				(type default)
			)
			(layer "F.Fab")
		)
		(fp_line
			(start 0.12065 -0.2794)
			(end 0.12065 -0.3048)
			(stroke
				(width 0.1)
				(type default)
			)
			(layer "F.Fab")
		)
		(fp_line
			(start 0.12065 -0.3048)
			(end 0.67945 -0.3048)
			(stroke
				(width 0.1)
				(type default)
			)
			(layer "F.Fab")
		)
		(fp_line
			(start 0.67945 -0.3048)
			(end 0.67945 0.3048)
			(stroke
				(width 0.1)
				(type default)
			)
			(layer "F.Fab")
		)
		(fp_line
			(start -0.67945 -0.305054)
			(end -0.12065 -0.305054)
			(stroke
				(width 0.1)
				(type default)
			)
			(layer "F.Fab")
		)
		(fp_line
			(start -0.12065 -0.305054)
			(end -0.12065 -0.2794)
			(stroke
				(width 0.1)
				(type default)
			)
			(layer "F.Fab")
		)
		(pad "1" smd circle
			(at -0.40005 0 270)
			(size 0 0)
			(layers "F.Cu" "F.Mask" "F.Paste")
			(net "P3V3_AUX")
		)
		(pad "2" smd circle
			(at 0.40005 0 270)
			(size 0 0)
			(layers "F.Cu" "F.Mask" "F.Paste")
			(net "GND")
		)
	)
	(footprint ""
		(layer "F.Cu")
		(at 459.077822 -365.676688 -90)
		(property "Reference" "C4454"
			(at 0 0 270)
			(layer "F.SilkS")
			(hide yes)
			(effects
				(font
					(size 1.27 1.27)
				)
			)
		)
		(property "Value" ""
			(at 0 0 270)
			(layer "F.Fab")
			(effects
				(font
					(size 1.27 1.27)
				)
			)
		)
		(duplicate_pad_numbers_are_jumpers no)
		(fp_line
			(start -0.299974 0.150114)
			(end -0.299974 -0.150114)
			(stroke
				(width 0.1)
				(type default)
			)
			(layer "F.Fab")
		)
		(fp_line
			(start 0.299974 0.150114)
			(end -0.299974 0.150114)
			(stroke
				(width 0.1)
				(type default)
			)
			(layer "F.Fab")
		)
		(fp_line
			(start -0.299974 -0.150114)
			(end 0.299974 -0.150114)
			(stroke
				(width 0.1)
				(type default)
			)
			(layer "F.Fab")
		)
		(fp_line
			(start 0.299974 -0.150114)
			(end 0.299974 0.150114)
			(stroke
				(width 0.1)
				(type default)
			)
			(layer "F.Fab")
		)
		(pad "1" smd rect
			(at -0.2667 0 270)
			(size 0.3048 0.381)
			(layers "F.Cu" "F.Mask" "F.Paste")
			(net "GPU_3V3IO_RSVD4_ISO")
		)
		(pad "2" smd rect
			(at 0.2667 0 270)
			(size 0.3048 0.381)
			(layers "F.Cu" "F.Mask" "F.Paste")
			(net "GND")
		)
	)
	(footprint ""
		(layer "F.Cu")
		(at 220.559376 -22.955504 90)
		(property "Reference" "R1686"
			(at 0 0 90)
			(layer "F.SilkS")
			(hide yes)
			(effects
				(font
					(size 1.27 1.27)
				)
			)
		)
		(property "Value" ""
			(at 0 0 90)
			(layer "F.Fab")
			(effects
				(font
					(size 1.27 1.27)
				)
			)
		)
		(duplicate_pad_numbers_are_jumpers no)
		(fp_line
			(start 0.7874 -0.4064)
			(end 0.7874 0.4064)
			(stroke
				(width 0.1524)
				(type default)
			)
			(layer "F.SilkS")
		)
		(fp_line
			(start -0.7874 -0.4064)
			(end 0.7874 -0.4064)
			(stroke
				(width 0.1524)
				(type default)
			)
			(layer "F.SilkS")
		)
		(fp_line
			(start 0.7874 0.4064)
			(end -0.7874 0.4064)
			(stroke
				(width 0.1524)
				(type default)
			)
			(layer "F.SilkS")
		)
		(fp_line
			(start -0.7874 0.4064)
			(end -0.7874 -0.4064)
			(stroke
				(width 0.1524)
				(type default)
			)
			(layer "F.SilkS")
		)
		(fp_line
			(start -0.12065 -0.305054)
			(end -0.12065 -0.2794)
			(stroke
				(width 0.1)
				(type default)
			)
			(layer "F.Fab")
		)
		(fp_line
			(start -0.67945 -0.305054)
			(end -0.12065 -0.305054)
			(stroke
				(width 0.1)
				(type default)
			)
			(layer "F.Fab")
		)
		(fp_line
			(start 0.67945 -0.3048)
			(end 0.67945 0.3048)
			(stroke
				(width 0.1)
				(type default)
			)
			(layer "F.Fab")
		)
		(fp_line
			(start 0.12065 -0.3048)
			(end 0.67945 -0.3048)
			(stroke
				(width 0.1)
				(type default)
			)
			(layer "F.Fab")
		)
		(fp_line
			(start 0.12065 -0.2794)
			(end 0.12065 -0.3048)
			(stroke
				(width 0.1)
				(type default)
			)
			(layer "F.Fab")
		)
		(fp_line
			(start -0.12065 -0.2794)
			(end 0.12065 -0.2794)
			(stroke
				(width 0.1)
				(type default)
			)
			(layer "F.Fab")
		)
		(fp_line
			(start 0.120396 0.2794)
			(end -0.12065 0.2794)
			(stroke
				(width 0.1)
				(type default)
			)
			(layer "F.Fab")
		)
		(fp_line
			(start -0.12065 0.2794)
			(end -0.12065 0.3048)
			(stroke
				(width 0.1)
				(type default)
			)
			(layer "F.Fab")
		)
		(fp_line
			(start 0.67945 0.3048)
			(end 0.120396 0.3048)
			(stroke
				(width 0.1)
				(type default)
			)
			(layer "F.Fab")
		)
		(fp_line
			(start 0.120396 0.3048)
			(end 0.120396 0.2794)
			(stroke
				(width 0.1)
				(type default)
			)
			(layer "F.Fab")
		)
		(fp_line
			(start -0.12065 0.3048)
			(end -0.67945 0.3048)
			(stroke
				(width 0.1)
				(type default)
			)
			(layer "F.Fab")
		)
		(fp_line
			(start -0.67945 0.3048)
			(end -0.67945 -0.305054)
			(stroke
				(width 0.1)
				(type default)
			)
			(layer "F.Fab")
		)
		(pad "1" smd circle
			(at -0.40005 0 90)
			(size 0 0)
			(layers "F.Cu" "F.Mask" "F.Paste")
			(net "SMB_BIC_I2C9_MUX0_SSD7_R_SCL")
		)
		(pad "2" smd circle
			(at 0.40005 0 90)
			(size 0 0)
			(layers "F.Cu" "F.Mask" "F.Paste")
			(net "SMB_ISO_SSD7_SCL")
		)
	)
	(footprint ""
		(layer "F.Cu")
		(at 239.813338 -136.328404 180)
		(property "Reference" "PC312"
			(at 0 0 180)
			(layer "F.SilkS")
			(hide yes)
			(effects
				(font
					(size 1.27 1.27)
				)
			)
		)
		(property "Value" ""
			(at 0 0 180)
			(layer "F.Fab")
			(effects
				(font
					(size 1.27 1.27)
				)
			)
		)
		(duplicate_pad_numbers_are_jumpers no)
		(fp_line
			(start 0.7874 0.4064)
			(end -0.7874 0.4064)
			(stroke
				(width 0.1524)
				(type default)
			)
			(layer "F.SilkS")
		)
		(fp_line
			(start 0.7874 -0.4064)
			(end 0.7874 0.4064)
			(stroke
				(width 0.1524)
				(type default)
			)
			(layer "F.SilkS")
		)
		(fp_line
			(start -0.7874 0.4064)
			(end -0.7874 -0.4064)
			(stroke
				(width 0.1524)
				(type default)
			)
			(layer "F.SilkS")
		)
		(fp_line
			(start -0.7874 -0.4064)
			(end 0.7874 -0.4064)
			(stroke
				(width 0.1524)
				(type default)
			)
			(layer "F.SilkS")
		)
		(fp_line
			(start 0.67945 0.3048)
			(end 0.120396 0.3048)
			(stroke
				(width 0.1)
				(type default)
			)
			(layer "F.Fab")
		)
		(fp_line
			(start 0.67945 -0.3048)
			(end 0.67945 0.3048)
			(stroke
				(width 0.1)
				(type default)
			)
			(layer "F.Fab")
		)
		(fp_line
			(start 0.12065 -0.2794)
			(end 0.12065 -0.3048)
			(stroke
				(width 0.1)
				(type default)
			)
			(layer "F.Fab")
		)
		(fp_line
			(start 0.12065 -0.3048)
			(end 0.67945 -0.3048)
			(stroke
				(width 0.1)
				(type default)
			)
			(layer "F.Fab")
		)
		(fp_line
			(start 0.120396 0.3048)
			(end 0.120396 0.2794)
			(stroke
				(width 0.1)
				(type default)
			)
			(layer "F.Fab")
		)
		(fp_line
			(start 0.120396 0.2794)
			(end -0.12065 0.2794)
			(stroke
				(width 0.1)
				(type default)
			)
			(layer "F.Fab")
		)
		(fp_line
			(start -0.12065 0.3048)
			(end -0.67945 0.3048)
			(stroke
				(width 0.1)
				(type default)
			)
			(layer "F.Fab")
		)
		(fp_line
			(start -0.12065 0.2794)
			(end -0.12065 0.3048)
			(stroke
				(width 0.1)
				(type default)
			)
			(layer "F.Fab")
		)
		(fp_line
			(start -0.12065 -0.2794)
			(end 0.12065 -0.2794)
			(stroke
				(width 0.1)
				(type default)
			)
			(layer "F.Fab")
		)
		(fp_line
			(start -0.12065 -0.305054)
			(end -0.12065 -0.2794)
			(stroke
				(width 0.1)
				(type default)
			)
			(layer "F.Fab")
		)
		(fp_line
			(start -0.67945 0.3048)
			(end -0.67945 -0.305054)
			(stroke
				(width 0.1)
				(type default)
			)
			(layer "F.Fab")
		)
		(fp_line
			(start -0.67945 -0.305054)
			(end -0.12065 -0.305054)
			(stroke
				(width 0.1)
				(type default)
			)
			(layer "F.Fab")
		)
		(pad "1" smd circle
			(at -0.40005 0 180)
			(size 0 0)
			(layers "F.Cu" "F.Mask" "F.Paste")
			(net "P5V_AUX")
		)
		(pad "2" smd circle
			(at 0.40005 0 180)
			(size 0 0)
			(layers "F.Cu" "F.Mask" "F.Paste")
			(net "GND")
		)
	)
	(footprint ""
		(layer "F.Cu")
		(at 135.838692 -44.341542 90)
		(property "Reference" "C311"
			(at 0 0 90)
			(layer "F.SilkS")
			(hide yes)
			(effects
				(font
					(size 1.27 1.27)
				)
			)
		)
		(property "Value" ""
			(at 0 0 90)
			(layer "F.Fab")
			(effects
				(font
					(size 1.27 1.27)
				)
			)
		)
		(duplicate_pad_numbers_are_jumpers no)
		(fp_line
			(start 0.7874 -0.4064)
			(end 0.7874 0.4064)
			(stroke
				(width 0.1524)
				(type default)
			)
			(layer "F.SilkS")
		)
		(fp_line
			(start -0.7874 -0.4064)
			(end 0.7874 -0.4064)
			(stroke
				(width 0.1524)
				(type default)
			)
			(layer "F.SilkS")
		)
		(fp_line
			(start 0.7874 0.4064)
			(end -0.7874 0.4064)
			(stroke
				(width 0.1524)
				(type default)
			)
			(layer "F.SilkS")
		)
		(fp_line
			(start -0.7874 0.4064)
			(end -0.7874 -0.4064)
			(stroke
				(width 0.1524)
				(type default)
			)
			(layer "F.SilkS")
		)
		(fp_line
			(start -0.12065 -0.305054)
			(end -0.12065 -0.2794)
			(stroke
				(width 0.1)
				(type default)
			)
			(layer "F.Fab")
		)
		(fp_line
			(start -0.67945 -0.305054)
			(end -0.12065 -0.305054)
			(stroke
				(width 0.1)
				(type default)
			)
			(layer "F.Fab")
		)
		(fp_line
			(start 0.67945 -0.3048)
			(end 0.67945 0.3048)
			(stroke
				(width 0.1)
				(type default)
			)
			(layer "F.Fab")
		)
		(fp_line
			(start 0.12065 -0.3048)
			(end 0.67945 -0.3048)
			(stroke
				(width 0.1)
				(type default)
			)
			(layer "F.Fab")
		)
		(fp_line
			(start 0.12065 -0.2794)
			(end 0.12065 -0.3048)
			(stroke
				(width 0.1)
				(type default)
			)
			(layer "F.Fab")
		)
		(fp_line
			(start -0.12065 -0.2794)
			(end 0.12065 -0.2794)
			(stroke
				(width 0.1)
				(type default)
			)
			(layer "F.Fab")
		)
		(fp_line
			(start 0.120396 0.2794)
			(end -0.12065 0.2794)
			(stroke
				(width 0.1)
				(type default)
			)
			(layer "F.Fab")
		)
		(fp_line
			(start -0.12065 0.2794)
			(end -0.12065 0.3048)
			(stroke
				(width 0.1)
				(type default)
			)
			(layer "F.Fab")
		)
		(fp_line
			(start 0.67945 0.3048)
			(end 0.120396 0.3048)
			(stroke
				(width 0.1)
				(type default)
			)
			(layer "F.Fab")
		)
		(fp_line
			(start 0.120396 0.3048)
			(end 0.120396 0.2794)
			(stroke
				(width 0.1)
				(type default)
			)
			(layer "F.Fab")
		)
		(fp_line
			(start -0.12065 0.3048)
			(end -0.67945 0.3048)
			(stroke
				(width 0.1)
				(type default)
			)
			(layer "F.Fab")
		)
		(fp_line
			(start -0.67945 0.3048)
			(end -0.67945 -0.305054)
			(stroke
				(width 0.1)
				(type default)
			)
			(layer "F.Fab")
		)
		(pad "1" smd circle
			(at -0.40005 0 90)
			(size 0 0)
			(layers "F.Cu" "F.Mask" "F.Paste")
			(net "P12V_SSD4_VIN_P")
		)
		(pad "2" smd circle
			(at 0.40005 0 90)
			(size 0 0)
			(layers "F.Cu" "F.Mask" "F.Paste")
			(net "P12V_SSD4_VIN_N")
		)
	)
	(footprint ""
		(layer "F.Cu")
		(at 341.746586 -285.088584 90)
		(property "Reference" "PC137"
			(at 0 0 90)
			(layer "F.SilkS")
			(hide yes)
			(effects
				(font
					(size 1.27 1.27)
				)
			)
		)
		(property "Value" ""
			(at 0 0 90)
			(layer "F.Fab")
			(effects
				(font
					(size 1.27 1.27)
				)
			)
		)
		(duplicate_pad_numbers_are_jumpers no)
		(fp_line
			(start 0.7874 -0.4064)
			(end 0.7874 0.4064)
			(stroke
				(width 0.1524)
				(type default)
			)
			(layer "F.SilkS")
		)
		(fp_line
			(start -0.7874 -0.4064)
			(end 0.7874 -0.4064)
			(stroke
				(width 0.1524)
				(type default)
			)
			(layer "F.SilkS")
		)
		(fp_line
			(start 0.7874 0.4064)
			(end -0.7874 0.4064)
			(stroke
				(width 0.1524)
				(type default)
			)
			(layer "F.SilkS")
		)
		(fp_line
			(start -0.7874 0.4064)
			(end -0.7874 -0.4064)
			(stroke
				(width 0.1524)
				(type default)
			)
			(layer "F.SilkS")
		)
		(fp_line
			(start -0.12065 -0.305054)
			(end -0.12065 -0.2794)
			(stroke
				(width 0.1)
				(type default)
			)
			(layer "F.Fab")
		)
		(fp_line
			(start -0.67945 -0.305054)
			(end -0.12065 -0.305054)
			(stroke
				(width 0.1)
				(type default)
			)
			(layer "F.Fab")
		)
		(fp_line
			(start 0.67945 -0.3048)
			(end 0.67945 0.3048)
			(stroke
				(width 0.1)
				(type default)
			)
			(layer "F.Fab")
		)
		(fp_line
			(start 0.12065 -0.3048)
			(end 0.67945 -0.3048)
			(stroke
				(width 0.1)
				(type default)
			)
			(layer "F.Fab")
		)
		(fp_line
			(start 0.12065 -0.2794)
			(end 0.12065 -0.3048)
			(stroke
				(width 0.1)
				(type default)
			)
			(layer "F.Fab")
		)
		(fp_line
			(start -0.12065 -0.2794)
			(end 0.12065 -0.2794)
			(stroke
				(width 0.1)
				(type default)
			)
			(layer "F.Fab")
		)
		(fp_line
			(start 0.120396 0.2794)
			(end -0.12065 0.2794)
			(stroke
				(width 0.1)
				(type default)
			)
			(layer "F.Fab")
		)
		(fp_line
			(start -0.12065 0.2794)
			(end -0.12065 0.3048)
			(stroke
				(width 0.1)
				(type default)
			)
			(layer "F.Fab")
		)
		(fp_line
			(start 0.67945 0.3048)
			(end 0.120396 0.3048)
			(stroke
				(width 0.1)
				(type default)
			)
			(layer "F.Fab")
		)
		(fp_line
			(start 0.120396 0.3048)
			(end 0.120396 0.2794)
			(stroke
				(width 0.1)
				(type default)
			)
			(layer "F.Fab")
		)
		(fp_line
			(start -0.12065 0.3048)
			(end -0.67945 0.3048)
			(stroke
				(width 0.1)
				(type default)
			)
			(layer "F.Fab")
		)
		(fp_line
			(start -0.67945 0.3048)
			(end -0.67945 -0.305054)
			(stroke
				(width 0.1)
				(type default)
			)
			(layer "F.Fab")
		)
		(pad "1" smd circle
			(at -0.40005 0 90)
			(size 0 0)
			(layers "F.Cu" "F.Mask" "F.Paste")
			(net "P0V8_PEX2_PVCC")
		)
		(pad "2" smd circle
			(at 0.40005 0 90)
			(size 0 0)
			(layers "F.Cu" "F.Mask" "F.Paste")
			(net "GND")
		)
	)
	(footprint ""
		(layer "F.Cu")
		(at 400.05762 -356.244906 90)
		(property "Reference" "C749"
			(at 0 0 90)
			(layer "F.SilkS")
			(hide yes)
			(effects
				(font
					(size 1.27 1.27)
				)
			)
		)
		(property "Value" ""
			(at 0 0 90)
			(layer "F.Fab")
			(effects
				(font
					(size 1.27 1.27)
				)
			)
		)
		(duplicate_pad_numbers_are_jumpers no)
		(fp_line
			(start 0.299974 -0.150114)
			(end 0.299974 0.150114)
			(stroke
				(width 0.1)
				(type default)
			)
			(layer "F.Fab")
		)
		(fp_line
			(start -0.299974 -0.150114)
			(end 0.299974 -0.150114)
			(stroke
				(width 0.1)
				(type default)
			)
			(layer "F.Fab")
		)
		(fp_line
			(start 0.299974 0.150114)
			(end -0.299974 0.150114)
			(stroke
				(width 0.1)
				(type default)
			)
			(layer "F.Fab")
		)
		(fp_line
			(start -0.299974 0.150114)
			(end -0.299974 -0.150114)
			(stroke
				(width 0.1)
				(type default)
			)
			(layer "F.Fab")
		)
		(pad "1" smd rect
			(at -0.2667 0 90)
			(size 0.3048 0.381)
			(layers "F.Cu" "F.Mask" "F.Paste")
			(net "P5E_PEX3_STN5_TX_DN<86>")
		)
		(pad "2" smd rect
			(at 0.2667 0 90)
			(size 0.3048 0.381)
			(layers "F.Cu" "F.Mask" "F.Paste")
			(net "P5E_PEX3_STN5_TX_C_DN<86>")
		)
	)
	(footprint ""
		(layer "F.Cu")
		(at 174.164244 -139.6238)
		(property "Reference" "R139"
			(at 0 0 0)
			(layer "F.SilkS")
			(hide yes)
			(effects
				(font
					(size 1.27 1.27)
				)
			)
		)
		(property "Value" ""
			(at 0 0 0)
			(layer "F.Fab")
			(effects
				(font
					(size 1.27 1.27)
				)
			)
		)
		(duplicate_pad_numbers_are_jumpers no)
		(fp_line
			(start -0.7874 -0.4064)
			(end 0.7874 -0.4064)
			(stroke
				(width 0.1524)
				(type default)
			)
			(layer "F.SilkS")
		)
		(fp_line
			(start -0.7874 0.4064)
			(end -0.7874 -0.4064)
			(stroke
				(width 0.1524)
				(type default)
			)
			(layer "F.SilkS")
		)
		(fp_line
			(start 0.7874 -0.4064)
			(end 0.7874 0.4064)
			(stroke
				(width 0.1524)
				(type default)
			)
			(layer "F.SilkS")
		)
		(fp_line
			(start 0.7874 0.4064)
			(end -0.7874 0.4064)
			(stroke
				(width 0.1524)
				(type default)
			)
			(layer "F.SilkS")
		)
		(fp_line
			(start -0.67945 -0.305054)
			(end -0.12065 -0.305054)
			(stroke
				(width 0.1)
				(type default)
			)
			(layer "F.Fab")
		)
		(fp_line
			(start -0.67945 0.3048)
			(end -0.67945 -0.305054)
			(stroke
				(width 0.1)
				(type default)
			)
			(layer "F.Fab")
		)
		(fp_line
			(start -0.12065 -0.305054)
			(end -0.12065 -0.2794)
			(stroke
				(width 0.1)
				(type default)
			)
			(layer "F.Fab")
		)
		(fp_line
			(start -0.12065 -0.2794)
			(end 0.12065 -0.2794)
			(stroke
				(width 0.1)
				(type default)
			)
			(layer "F.Fab")
		)
		(fp_line
			(start -0.12065 0.2794)
			(end -0.12065 0.3048)
			(stroke
				(width 0.1)
				(type default)
			)
			(layer "F.Fab")
		)
		(fp_line
			(start -0.12065 0.3048)
			(end -0.67945 0.3048)
			(stroke
				(width 0.1)
				(type default)
			)
			(layer "F.Fab")
		)
		(fp_line
			(start 0.120396 0.2794)
			(end -0.12065 0.2794)
			(stroke
				(width 0.1)
				(type default)
			)
			(layer "F.Fab")
		)
		(fp_line
			(start 0.120396 0.3048)
			(end 0.120396 0.2794)
			(stroke
				(width 0.1)
				(type default)
			)
			(layer "F.Fab")
		)
		(fp_line
			(start 0.12065 -0.3048)
			(end 0.67945 -0.3048)
			(stroke
				(width 0.1)
				(type default)
			)
			(layer "F.Fab")
		)
		(fp_line
			(start 0.12065 -0.2794)
			(end 0.12065 -0.3048)
			(stroke
				(width 0.1)
				(type default)
			)
			(layer "F.Fab")
		)
		(fp_line
			(start 0.67945 -0.3048)
			(end 0.67945 0.3048)
			(stroke
				(width 0.1)
				(type default)
			)
			(layer "F.Fab")
		)
		(fp_line
			(start 0.67945 0.3048)
			(end 0.120396 0.3048)
			(stroke
				(width 0.1)
				(type default)
			)
			(layer "F.Fab")
		)
		(pad "1" smd circle
			(at -0.40005 0)
			(size 0 0)
			(layers "F.Cu" "F.Mask" "F.Paste")
			(net "RST_SMB_NIC2_MUX_ISO_R_N")
		)
		(pad "2" smd circle
			(at 0.40005 0)
			(size 0 0)
			(layers "F.Cu" "F.Mask" "F.Paste")
			(net "RST_SMB_NIC2_MUX_ISO_N")
		)
	)
	(footprint ""
		(layer "F.Cu")
		(at 396.859252 -166.55288)
		(property "Reference" "U40"
			(at -2.041652 1.86055 0)
			(unlocked yes)
			(layer "F.SilkS")
			(effects
				(font
					(size 0.7874 0.5842)
					(thickness 0.1524)
				)
				(justify left)
			)
		)
		(property "Value" ""
			(at 0 0 0)
			(layer "F.Fab")
			(effects
				(font
					(size 1.27 1.27)
				)
			)
		)
		(duplicate_pad_numbers_are_jumpers no)
		(fp_line
			(start -1.684274 -1.074928)
			(end -0.381 -1.074928)
			(stroke
				(width 0.1524)
				(type default)
			)
			(layer "F.SilkS")
		)
		(fp_line
			(start -1.684274 1.074928)
			(end -1.684274 -1.074928)
			(stroke
				(width 0.1524)
				(type default)
			)
			(layer "F.SilkS")
		)
		(fp_line
			(start -0.381 -1.074928)
			(end 0 -0.625094)
			(stroke
				(width 0.1524)
				(type default)
			)
			(layer "F.SilkS")
		)
		(fp_line
			(start 0 -0.625094)
			(end 0.381 -1.074928)
			(stroke
				(width 0.1524)
				(type default)
			)
			(layer "F.SilkS")
		)
		(fp_line
			(start 0.381 -1.074928)
			(end 1.684274 -1.074928)
			(stroke
				(width 0.1524)
				(type default)
			)
			(layer "F.SilkS")
		)
		(fp_line
			(start 1.684274 -1.074928)
			(end 1.684274 1.074928)
			(stroke
				(width 0.1524)
				(type default)
			)
			(layer "F.SilkS")
		)
		(fp_line
			(start 1.684274 1.074928)
			(end -1.684274 1.074928)
			(stroke
				(width 0.1524)
				(type default)
			)
			(layer "F.SilkS")
		)
		(fp_poly
			(pts
				(xy -2.637282 -0.903986) (xy -2.637282 -0.395986) (xy -1.875282 -0.649986)
			)
			(stroke
				(width 0)
				(type default)
			)
			(fill yes)
			(layer "F.SilkS")
		)
		(fp_line
			(start -0.700024 -1.074928)
			(end -0.700024 1.074928)
			(stroke
				(width 0.1)
				(type default)
			)
			(layer "F.Fab")
		)
		(fp_line
			(start -0.700024 1.074928)
			(end 0.700024 1.074928)
			(stroke
				(width 0.1)
				(type default)
			)
			(layer "F.Fab")
		)
		(fp_line
			(start 0.700024 -1.074928)
			(end -0.700024 -1.074928)
			(stroke
				(width 0.1)
				(type default)
			)
			(layer "F.Fab")
		)
		(fp_line
			(start 0.700024 1.074928)
			(end 0.700024 -1.074928)
			(stroke
				(width 0.1)
				(type default)
			)
			(layer "F.Fab")
		)
		(fp_poly
			(pts
				(xy -2.637282 -0.903986) (xy -2.637282 -0.395986) (xy -1.875282 -0.649986)
			)
			(stroke
				(width 0)
				(type default)
			)
			(fill yes)
			(layer "F.Fab")
		)
		(pad "1" smd rect
			(at -1.100074 -0.649986 270)
			(size 0.4064 0.9144)
			(layers "F.Cu" "F.Mask" "F.Paste")
			(net "Net_8450")
		)
		(pad "2" smd rect
			(at -1.100074 0 270)
			(size 0.4064 0.9144)
			(layers "F.Cu" "F.Mask" "F.Paste")
			(net "RST_HP_NIC6_N")
		)
		(pad "3" smd rect
			(at -1.100074 0.649986 270)
			(size 0.4064 0.9144)
			(layers "F.Cu" "F.Mask" "F.Paste")
			(net "GND")
		)
		(pad "4" smd rect
			(at 1.100074 0.649986 270)
			(size 0.4064 0.9144)
			(layers "F.Cu" "F.Mask" "F.Paste")
			(net "RST_HP_NIC6_BUF_N")
		)
		(pad "5" smd rect
			(at 1.100074 -0.649986 270)
			(size 0.4064 0.9144)
			(layers "F.Cu" "F.Mask" "F.Paste")
			(net "P3V3_AUX")
		)
	)
	(footprint ""
		(layer "F.Cu")
		(at 220.34373 -46.90491)
		(property "Reference" "R587"
			(at 0 0 0)
			(layer "F.SilkS")
			(hide yes)
			(effects
				(font
					(size 1.27 1.27)
				)
			)
		)
		(property "Value" ""
			(at 0 0 0)
			(layer "F.Fab")
			(effects
				(font
					(size 1.27 1.27)
				)
			)
		)
		(duplicate_pad_numbers_are_jumpers no)
		(fp_line
			(start -0.7874 -0.4064)
			(end 0.7874 -0.4064)
			(stroke
				(width 0.1524)
				(type default)
			)
			(layer "F.SilkS")
		)
		(fp_line
			(start -0.7874 0.4064)
			(end -0.7874 -0.4064)
			(stroke
				(width 0.1524)
				(type default)
			)
			(layer "F.SilkS")
		)
		(fp_line
			(start 0.7874 -0.4064)
			(end 0.7874 0.4064)
			(stroke
				(width 0.1524)
				(type default)
			)
			(layer "F.SilkS")
		)
		(fp_line
			(start 0.7874 0.4064)
			(end -0.7874 0.4064)
			(stroke
				(width 0.1524)
				(type default)
			)
			(layer "F.SilkS")
		)
		(fp_line
			(start -0.67945 -0.305054)
			(end -0.12065 -0.305054)
			(stroke
				(width 0.1)
				(type default)
			)
			(layer "F.Fab")
		)
		(fp_line
			(start -0.67945 0.3048)
			(end -0.67945 -0.305054)
			(stroke
				(width 0.1)
				(type default)
			)
			(layer "F.Fab")
		)
		(fp_line
			(start -0.12065 -0.305054)
			(end -0.12065 -0.2794)
			(stroke
				(width 0.1)
				(type default)
			)
			(layer "F.Fab")
		)
		(fp_line
			(start -0.12065 -0.2794)
			(end 0.12065 -0.2794)
			(stroke
				(width 0.1)
				(type default)
			)
			(layer "F.Fab")
		)
		(fp_line
			(start -0.12065 0.2794)
			(end -0.12065 0.3048)
			(stroke
				(width 0.1)
				(type default)
			)
			(layer "F.Fab")
		)
		(fp_line
			(start -0.12065 0.3048)
			(end -0.67945 0.3048)
			(stroke
				(width 0.1)
				(type default)
			)
			(layer "F.Fab")
		)
		(fp_line
			(start 0.120396 0.2794)
			(end -0.12065 0.2794)
			(stroke
				(width 0.1)
				(type default)
			)
			(layer "F.Fab")
		)
		(fp_line
			(start 0.120396 0.3048)
			(end 0.120396 0.2794)
			(stroke
				(width 0.1)
				(type default)
			)
			(layer "F.Fab")
		)
		(fp_line
			(start 0.12065 -0.3048)
			(end 0.67945 -0.3048)
			(stroke
				(width 0.1)
				(type default)
			)
			(layer "F.Fab")
		)
		(fp_line
			(start 0.12065 -0.2794)
			(end 0.12065 -0.3048)
			(stroke
				(width 0.1)
				(type default)
			)
			(layer "F.Fab")
		)
		(fp_line
			(start 0.67945 -0.3048)
			(end 0.67945 0.3048)
			(stroke
				(width 0.1)
				(type default)
			)
			(layer "F.Fab")
		)
		(fp_line
			(start 0.67945 0.3048)
			(end 0.120396 0.3048)
			(stroke
				(width 0.1)
				(type default)
			)
			(layer "F.Fab")
		)
		(pad "1" smd circle
			(at -0.40005 0)
			(size 0 0)
			(layers "F.Cu" "F.Mask" "F.Paste")
			(net "SSD7_ADC_ALERT_N")
		)
		(pad "2" smd circle
			(at 0.40005 0)
			(size 0 0)
			(layers "F.Cu" "F.Mask" "F.Paste")
			(net "SSD_0_7_ADC_ALERT_N")
		)
	)
	(footprint ""
		(layer "F.Cu")
		(at 382.786636 -226.435666 90)
		(property "Reference" "Y3"
			(at -2.510536 -0.262636 0)
			(unlocked yes)
			(layer "F.SilkS")
			(effects
				(font
					(size 0.7874 0.5842)
					(thickness 0.1524)
				)
				(justify left)
			)
		)
		(property "Value" ""
			(at 0 0 90)
			(layer "F.Fab")
			(effects
				(font
					(size 1.27 1.27)
				)
			)
		)
		(duplicate_pad_numbers_are_jumpers no)
		(fp_line
			(start 1.6002 -1.9558)
			(end 1.6002 1.9558)
			(stroke
				(width 0.1524)
				(type default)
			)
			(layer "F.SilkS")
		)
		(fp_line
			(start -1.6002 -1.9558)
			(end 1.6002 -1.9558)
			(stroke
				(width 0.1524)
				(type default)
			)
			(layer "F.SilkS")
		)
		(fp_line
			(start 1.6002 1.9558)
			(end -1.6002 1.9558)
			(stroke
				(width 0.1524)
				(type default)
			)
			(layer "F.SilkS")
		)
		(fp_line
			(start -1.6002 1.9558)
			(end -1.6002 -1.9558)
			(stroke
				(width 0.1524)
				(type default)
			)
			(layer "F.SilkS")
		)
		(fp_poly
			(pts
				(xy -1.7145 -1.0668) (xy -2.8067 -1.651) (xy -2.8067 -0.5842)
			)
			(stroke
				(width 0)
				(type default)
			)
			(fill yes)
			(layer "F.SilkS")
		)
		(fp_line
			(start 1.299972 -1.649984)
			(end 1.299972 1.649984)
			(stroke
				(width 0.1)
				(type default)
			)
			(layer "F.Fab")
		)
		(fp_line
			(start -1.299972 -1.649984)
			(end 1.299972 -1.649984)
			(stroke
				(width 0.1)
				(type default)
			)
			(layer "F.Fab")
		)
		(fp_line
			(start 1.299972 1.649984)
			(end -1.299972 1.649984)
			(stroke
				(width 0.1)
				(type default)
			)
			(layer "F.Fab")
		)
		(fp_line
			(start -1.299972 1.649984)
			(end -1.299972 -1.649984)
			(stroke
				(width 0.1)
				(type default)
			)
			(layer "F.Fab")
		)
		(fp_poly
			(pts
				(xy -1.7145 -1.0668) (xy -2.8067 -1.651) (xy -2.8067 -0.5842)
			)
			(stroke
				(width 0)
				(type default)
			)
			(fill yes)
			(layer "F.Fab")
		)
		(pad "1" smd rect
			(at -0.849884 -1.100074 90)
			(size 1.2192 1.4224)
			(layers "F.Cu" "F.Mask" "F.Paste")
			(net "OSC_SDB_IN")
		)
		(pad "2" smd rect
			(at -0.849884 1.100074 90)
			(size 1.2192 1.4224)
			(layers "F.Cu" "F.Mask" "F.Paste")
			(net "GND")
		)
		(pad "3" smd rect
			(at 0.849884 1.100074 90)
			(size 1.2192 1.4224)
			(layers "F.Cu" "F.Mask" "F.Paste")
			(net "OSC_SDB_OUT")
		)
		(pad "4" smd rect
			(at 0.849884 -1.100074 90)
			(size 1.2192 1.4224)
			(layers "F.Cu" "F.Mask" "F.Paste")
			(net "GND")
		)
	)
	(footprint ""
		(layer "F.Cu")
		(at 263.381998 -338.85251)
		(property "Reference" "U449"
			(at -5.058664 -1.037082 0)
			(unlocked yes)
			(layer "F.SilkS")
			(effects
				(font
					(size 0.7874 0.5842)
					(thickness 0.1524)
				)
				(justify left)
			)
		)
		(property "Value" ""
			(at 0 0 0)
			(layer "F.Fab")
			(effects
				(font
					(size 1.27 1.27)
				)
			)
		)
		(duplicate_pad_numbers_are_jumpers no)
		(fp_line
			(start -1.868424 -1.519936)
			(end -1.868424 1.519936)
			(stroke
				(width 0.1524)
				(type default)
			)
			(layer "F.SilkS")
		)
		(fp_line
			(start -1.868424 1.519936)
			(end 1.868424 1.519936)
			(stroke
				(width 0.1524)
				(type default)
			)
			(layer "F.SilkS")
		)
		(fp_line
			(start 1.868424 -1.519936)
			(end -1.868424 -1.519936)
			(stroke
				(width 0.1524)
				(type default)
			)
			(layer "F.SilkS")
		)
		(fp_line
			(start 1.868424 1.519936)
			(end 1.868424 -1.519936)
			(stroke
				(width 0.1524)
				(type default)
			)
			(layer "F.SilkS")
		)
		(fp_line
			(start -0.700024 -1.519936)
			(end -0.700024 1.519936)
			(stroke
				(width 0.1)
				(type default)
			)
			(layer "F.Fab")
		)
		(fp_line
			(start -0.700024 1.519936)
			(end 0.700024 1.519936)
			(stroke
				(width 0.1)
				(type default)
			)
			(layer "F.Fab")
		)
		(fp_line
			(start 0.700024 -1.519936)
			(end -0.700024 -1.519936)
			(stroke
				(width 0.1)
				(type default)
			)
			(layer "F.Fab")
		)
		(fp_line
			(start 0.700024 1.519936)
			(end 0.700024 -1.519936)
			(stroke
				(width 0.1)
				(type default)
			)
			(layer "F.Fab")
		)
		(pad "1" smd rect
			(at -1.18491 -0.94996 270)
			(size 0.6096 1.0668)
			(layers "F.Cu" "F.Mask" "F.Paste")
			(net "OC_P2V5_COMP")
		)
		(pad "2" smd rect
			(at -1.18491 0.94996 270)
			(size 0.6096 1.0668)
			(layers "F.Cu" "F.Mask" "F.Paste")
			(net "GND")
		)
		(pad "3" smd rect
			(at 1.18491 0 270)
			(size 0.6096 1.0668)
			(layers "F.Cu" "F.Mask" "F.Paste")
			(net "Net_9325")
		)
	)
	(footprint ""
		(layer "F.Cu")
		(at 30.438344 -250.070874 -90)
		(property "Reference" "R1152"
			(at 0 0 270)
			(layer "F.SilkS")
			(hide yes)
			(effects
				(font
					(size 1.27 1.27)
				)
			)
		)
		(property "Value" ""
			(at 0 0 270)
			(layer "F.Fab")
			(effects
				(font
					(size 1.27 1.27)
				)
			)
		)
		(duplicate_pad_numbers_are_jumpers no)
		(fp_line
			(start -0.7874 0.4064)
			(end -0.7874 -0.4064)
			(stroke
				(width 0.1524)
				(type default)
			)
			(layer "F.SilkS")
		)
		(fp_line
			(start 0.7874 0.4064)
			(end -0.7874 0.4064)
			(stroke
				(width 0.1524)
				(type default)
			)
			(layer "F.SilkS")
		)
		(fp_line
			(start -0.7874 -0.4064)
			(end 0.7874 -0.4064)
			(stroke
				(width 0.1524)
				(type default)
			)
			(layer "F.SilkS")
		)
		(fp_line
			(start 0.7874 -0.4064)
			(end 0.7874 0.4064)
			(stroke
				(width 0.1524)
				(type default)
			)
			(layer "F.SilkS")
		)
		(fp_line
			(start -0.67945 0.3048)
			(end -0.67945 -0.305054)
			(stroke
				(width 0.1)
				(type default)
			)
			(layer "F.Fab")
		)
		(fp_line
			(start -0.12065 0.3048)
			(end -0.67945 0.3048)
			(stroke
				(width 0.1)
				(type default)
			)
			(layer "F.Fab")
		)
		(fp_line
			(start 0.120396 0.3048)
			(end 0.120396 0.2794)
			(stroke
				(width 0.1)
				(type default)
			)
			(layer "F.Fab")
		)
		(fp_line
			(start 0.67945 0.3048)
			(end 0.120396 0.3048)
			(stroke
				(width 0.1)
				(type default)
			)
			(layer "F.Fab")
		)
		(fp_line
			(start -0.12065 0.2794)
			(end -0.12065 0.3048)
			(stroke
				(width 0.1)
				(type default)
			)
			(layer "F.Fab")
		)
		(fp_line
			(start 0.120396 0.2794)
			(end -0.12065 0.2794)
			(stroke
				(width 0.1)
				(type default)
			)
			(layer "F.Fab")
		)
		(fp_line
			(start -0.12065 -0.2794)
			(end 0.12065 -0.2794)
			(stroke
				(width 0.1)
				(type default)
			)
			(layer "F.Fab")
		)
		(fp_line
			(start 0.12065 -0.2794)
			(end 0.12065 -0.3048)
			(stroke
				(width 0.1)
				(type default)
			)
			(layer "F.Fab")
		)
		(fp_line
			(start 0.12065 -0.3048)
			(end 0.67945 -0.3048)
			(stroke
				(width 0.1)
				(type default)
			)
			(layer "F.Fab")
		)
		(fp_line
			(start 0.67945 -0.3048)
			(end 0.67945 0.3048)
			(stroke
				(width 0.1)
				(type default)
			)
			(layer "F.Fab")
		)
		(fp_line
			(start -0.67945 -0.305054)
			(end -0.12065 -0.305054)
			(stroke
				(width 0.1)
				(type default)
			)
			(layer "F.Fab")
		)
		(fp_line
			(start -0.12065 -0.305054)
			(end -0.12065 -0.2794)
			(stroke
				(width 0.1)
				(type default)
			)
			(layer "F.Fab")
		)
		(pad "1" smd circle
			(at -0.40005 0 270)
			(size 0 0)
			(layers "F.Cu" "F.Mask" "F.Paste")
			(net "PEX0_MODE_SEL0")
		)
		(pad "2" smd circle
			(at 0.40005 0 270)
			(size 0 0)
			(layers "F.Cu" "F.Mask" "F.Paste")
			(net "P1V8_PEX")
		)
	)
	(footprint ""
		(layer "F.Cu")
		(at 168.343834 -48.93691 180)
		(property "Reference" "R567"
			(at 0 0 180)
			(layer "F.SilkS")
			(hide yes)
			(effects
				(font
					(size 1.27 1.27)
				)
			)
		)
		(property "Value" ""
			(at 0 0 180)
			(layer "F.Fab")
			(effects
				(font
					(size 1.27 1.27)
				)
			)
		)
		(duplicate_pad_numbers_are_jumpers no)
		(fp_line
			(start 0.7874 0.4064)
			(end -0.7874 0.4064)
			(stroke
				(width 0.1524)
				(type default)
			)
			(layer "F.SilkS")
		)
		(fp_line
			(start 0.7874 -0.4064)
			(end 0.7874 0.4064)
			(stroke
				(width 0.1524)
				(type default)
			)
			(layer "F.SilkS")
		)
		(fp_line
			(start -0.7874 0.4064)
			(end -0.7874 -0.4064)
			(stroke
				(width 0.1524)
				(type default)
			)
			(layer "F.SilkS")
		)
		(fp_line
			(start -0.7874 -0.4064)
			(end 0.7874 -0.4064)
			(stroke
				(width 0.1524)
				(type default)
			)
			(layer "F.SilkS")
		)
		(fp_line
			(start 0.67945 0.3048)
			(end 0.120396 0.3048)
			(stroke
				(width 0.1)
				(type default)
			)
			(layer "F.Fab")
		)
		(fp_line
			(start 0.67945 -0.3048)
			(end 0.67945 0.3048)
			(stroke
				(width 0.1)
				(type default)
			)
			(layer "F.Fab")
		)
		(fp_line
			(start 0.12065 -0.2794)
			(end 0.12065 -0.3048)
			(stroke
				(width 0.1)
				(type default)
			)
			(layer "F.Fab")
		)
		(fp_line
			(start 0.12065 -0.3048)
			(end 0.67945 -0.3048)
			(stroke
				(width 0.1)
				(type default)
			)
			(layer "F.Fab")
		)
		(fp_line
			(start 0.120396 0.3048)
			(end 0.120396 0.2794)
			(stroke
				(width 0.1)
				(type default)
			)
			(layer "F.Fab")
		)
		(fp_line
			(start 0.120396 0.2794)
			(end -0.12065 0.2794)
			(stroke
				(width 0.1)
				(type default)
			)
			(layer "F.Fab")
		)
		(fp_line
			(start -0.12065 0.3048)
			(end -0.67945 0.3048)
			(stroke
				(width 0.1)
				(type default)
			)
			(layer "F.Fab")
		)
		(fp_line
			(start -0.12065 0.2794)
			(end -0.12065 0.3048)
			(stroke
				(width 0.1)
				(type default)
			)
			(layer "F.Fab")
		)
		(fp_line
			(start -0.12065 -0.2794)
			(end 0.12065 -0.2794)
			(stroke
				(width 0.1)
				(type default)
			)
			(layer "F.Fab")
		)
		(fp_line
			(start -0.12065 -0.305054)
			(end -0.12065 -0.2794)
			(stroke
				(width 0.1)
				(type default)
			)
			(layer "F.Fab")
		)
		(fp_line
			(start -0.67945 0.3048)
			(end -0.67945 -0.305054)
			(stroke
				(width 0.1)
				(type default)
			)
			(layer "F.Fab")
		)
		(fp_line
			(start -0.67945 -0.305054)
			(end -0.12065 -0.305054)
			(stroke
				(width 0.1)
				(type default)
			)
			(layer "F.Fab")
		)
		(pad "1" smd circle
			(at -0.40005 0 180)
			(size 0 0)
			(layers "F.Cu" "F.Mask" "F.Paste")
			(net "SMB_BIC_I2C6_MUX_SSD_0_7_ADC_R_SDA")
		)
		(pad "2" smd circle
			(at 0.40005 0 180)
			(size 0 0)
			(layers "F.Cu" "F.Mask" "F.Paste")
			(net "SMB_SSD5_ADC_SDA")
		)
	)
	(footprint ""
		(layer "F.Cu")
		(at 177.33518 -195.208652)
		(property "Reference" "U50"
			(at -1.36398 -3.367278 0)
			(unlocked yes)
			(layer "F.SilkS")
			(effects
				(font
					(size 0.7874 0.5842)
					(thickness 0.1524)
				)
				(justify left)
			)
		)
		(property "Value" ""
			(at 0 0 0)
			(layer "F.Fab")
			(effects
				(font
					(size 1.27 1.27)
				)
			)
		)
		(duplicate_pad_numbers_are_jumpers no)
		(fp_line
			(start -1.868932 -2.549906)
			(end -1.868932 2.549906)
			(stroke
				(width 0.1524)
				(type default)
			)
			(layer "F.SilkS")
		)
		(fp_line
			(start -1.868932 2.549906)
			(end 1.868932 2.549906)
			(stroke
				(width 0.1524)
				(type default)
			)
			(layer "F.SilkS")
		)
		(fp_line
			(start -1.025906 -2.549906)
			(end -1.868932 -2.549906)
			(stroke
				(width 0.1524)
				(type default)
			)
			(layer "F.SilkS")
		)
		(fp_line
			(start 0 -1.524)
			(end -1.025906 -2.549906)
			(stroke
				(width 0.1524)
				(type default)
			)
			(layer "F.SilkS")
		)
		(fp_line
			(start 1.025906 -2.549906)
			(end 0 -1.524)
			(stroke
				(width 0.1524)
				(type default)
			)
			(layer "F.SilkS")
		)
		(fp_line
			(start 1.868932 -2.549906)
			(end 1.025906 -2.549906)
			(stroke
				(width 0.1524)
				(type default)
			)
			(layer "F.SilkS")
		)
		(fp_line
			(start 1.868932 2.549906)
			(end 1.868932 -2.549906)
			(stroke
				(width 0.1524)
				(type default)
			)
			(layer "F.SilkS")
		)
		(fp_poly
			(pts
				(xy -4.7752 -1.787398) (xy -4.7752 -2.803398) (xy -3.7592 -2.295398)
			)
			(stroke
				(width 0)
				(type default)
			)
			(fill yes)
			(layer "F.SilkS")
		)
		(fp_line
			(start -2.249932 -2.549906)
			(end -2.249932 2.549906)
			(stroke
				(width 0.1)
				(type default)
			)
			(layer "F.Fab")
		)
		(fp_line
			(start -2.249932 2.549906)
			(end 2.249932 2.549906)
			(stroke
				(width 0.1)
				(type default)
			)
			(layer "F.Fab")
		)
		(fp_line
			(start 2.249932 -2.549906)
			(end -2.249932 -2.549906)
			(stroke
				(width 0.1)
				(type default)
			)
			(layer "F.Fab")
		)
		(fp_line
			(start 2.249932 2.549906)
			(end 2.249932 -2.549906)
			(stroke
				(width 0.1)
				(type default)
			)
			(layer "F.Fab")
		)
		(fp_poly
			(pts
				(xy -4.7752 -1.787398) (xy -4.7752 -2.803398) (xy -3.7592 -2.295398)
			)
			(stroke
				(width 0)
				(type default)
			)
			(fill yes)
			(layer "F.Fab")
		)
		(pad "1" smd rect
			(at -2.800096 -2.275078 270)
			(size 0.3556 1.6002)
			(layers "F.Cu" "F.Mask" "F.Paste")
			(net "SPI_BIC1_CS0_LS01_N_DIR1")
		)
		(pad "2" smd rect
			(at -2.800096 -1.625092 270)
			(size 0.3556 1.6002)
			(layers "F.Cu" "F.Mask" "F.Paste")
			(net "SPI_BIC1_CLK_LS01_DIR2")
		)
		(pad "3" smd rect
			(at -2.800096 -0.975106 270)
			(size 0.3556 1.6002)
			(layers "F.Cu" "F.Mask" "F.Paste")
			(net "SPI_BIC1_CS0_LS01_N")
		)
		(pad "4" smd rect
			(at -2.800096 -0.32512 270)
			(size 0.3556 1.6002)
			(layers "F.Cu" "F.Mask" "F.Paste")
			(net "SPI_BIC1_CLK_LS01")
		)
		(pad "5" smd rect
			(at -2.800096 0.32512 270)
			(size 0.3556 1.6002)
			(layers "F.Cu" "F.Mask" "F.Paste")
			(net "SPI_BIC1_MOSI_LS01")
		)
		(pad "6" smd rect
			(at -2.800096 0.975106 270)
			(size 0.3556 1.6002)
			(layers "F.Cu" "F.Mask" "F.Paste")
			(net "SPI_BIC1_MISO_LS01")
		)
		(pad "7" smd rect
			(at -2.800096 1.625092 270)
			(size 0.3556 1.6002)
			(layers "F.Cu" "F.Mask" "F.Paste")
			(net "SPI_BIC1_MOSI_LS01_DIR3")
		)
		(pad "8" smd rect
			(at -2.800096 2.275078 270)
			(size 0.3556 1.6002)
			(layers "F.Cu" "F.Mask" "F.Paste")
			(net "SPI_BIC1_MISO_LS01_DIR4")
		)
		(pad "9" smd rect
			(at 2.800096 2.275078 270)
			(size 0.3556 1.6002)
			(layers "F.Cu" "F.Mask" "F.Paste")
			(net "SPI_BIC1_LS01_EN_R_N")
		)
		(pad "10" smd rect
			(at 2.800096 1.625092 270)
			(size 0.3556 1.6002)
			(layers "F.Cu" "F.Mask" "F.Paste")
			(net "GND")
		)
		(pad "11" smd rect
			(at 2.800096 0.975106 270)
			(size 0.3556 1.6002)
			(layers "F.Cu" "F.Mask" "F.Paste")
			(net "SPI_BIC1_MISO_R3")
		)
		(pad "12" smd rect
			(at 2.800096 0.32512 270)
			(size 0.3556 1.6002)
			(layers "F.Cu" "F.Mask" "F.Paste")
			(net "SPI_BIC1_MOSI_R3")
		)
		(pad "13" smd rect
			(at 2.800096 -0.32512 270)
			(size 0.3556 1.6002)
			(layers "F.Cu" "F.Mask" "F.Paste")
			(net "SPI_BIC1_CLK_R3")
		)
		(pad "14" smd rect
			(at 2.800096 -0.975106 270)
			(size 0.3556 1.6002)
			(layers "F.Cu" "F.Mask" "F.Paste")
			(net "SPI_BIC1_CS0_R2_N")
		)
		(pad "15" smd rect
			(at 2.800096 -1.625092 270)
			(size 0.3556 1.6002)
			(layers "F.Cu" "F.Mask" "F.Paste")
			(net "P3V3_AUX")
		)
		(pad "16" smd rect
			(at 2.800096 -2.275078 270)
			(size 0.3556 1.6002)
			(layers "F.Cu" "F.Mask" "F.Paste")
			(net "P1V8_PEX")
		)
	)
	(footprint ""
		(layer "F.Cu")
		(at 379.2474 -36.686998 90)
		(property "Reference" "C3670"
			(at 0 0 90)
			(layer "F.SilkS")
			(hide yes)
			(effects
				(font
					(size 1.27 1.27)
				)
			)
		)
		(property "Value" ""
			(at 0 0 90)
			(layer "F.Fab")
			(effects
				(font
					(size 1.27 1.27)
				)
			)
		)
		(duplicate_pad_numbers_are_jumpers no)
		(fp_line
			(start 0.7874 -0.4064)
			(end 0.7874 0.4064)
			(stroke
				(width 0.1524)
				(type default)
			)
			(layer "F.SilkS")
		)
		(fp_line
			(start -0.7874 -0.4064)
			(end 0.7874 -0.4064)
			(stroke
				(width 0.1524)
				(type default)
			)
			(layer "F.SilkS")
		)
		(fp_line
			(start 0.7874 0.4064)
			(end -0.7874 0.4064)
			(stroke
				(width 0.1524)
				(type default)
			)
			(layer "F.SilkS")
		)
		(fp_line
			(start -0.7874 0.4064)
			(end -0.7874 -0.4064)
			(stroke
				(width 0.1524)
				(type default)
			)
			(layer "F.SilkS")
		)
		(fp_line
			(start -0.12065 -0.305054)
			(end -0.12065 -0.2794)
			(stroke
				(width 0.1)
				(type default)
			)
			(layer "F.Fab")
		)
		(fp_line
			(start -0.67945 -0.305054)
			(end -0.12065 -0.305054)
			(stroke
				(width 0.1)
				(type default)
			)
			(layer "F.Fab")
		)
		(fp_line
			(start 0.67945 -0.3048)
			(end 0.67945 0.3048)
			(stroke
				(width 0.1)
				(type default)
			)
			(layer "F.Fab")
		)
		(fp_line
			(start 0.12065 -0.3048)
			(end 0.67945 -0.3048)
			(stroke
				(width 0.1)
				(type default)
			)
			(layer "F.Fab")
		)
		(fp_line
			(start 0.12065 -0.2794)
			(end 0.12065 -0.3048)
			(stroke
				(width 0.1)
				(type default)
			)
			(layer "F.Fab")
		)
		(fp_line
			(start -0.12065 -0.2794)
			(end 0.12065 -0.2794)
			(stroke
				(width 0.1)
				(type default)
			)
			(layer "F.Fab")
		)
		(fp_line
			(start 0.120396 0.2794)
			(end -0.12065 0.2794)
			(stroke
				(width 0.1)
				(type default)
			)
			(layer "F.Fab")
		)
		(fp_line
			(start -0.12065 0.2794)
			(end -0.12065 0.3048)
			(stroke
				(width 0.1)
				(type default)
			)
			(layer "F.Fab")
		)
		(fp_line
			(start 0.67945 0.3048)
			(end 0.120396 0.3048)
			(stroke
				(width 0.1)
				(type default)
			)
			(layer "F.Fab")
		)
		(fp_line
			(start 0.120396 0.3048)
			(end 0.120396 0.2794)
			(stroke
				(width 0.1)
				(type default)
			)
			(layer "F.Fab")
		)
		(fp_line
			(start -0.12065 0.3048)
			(end -0.67945 0.3048)
			(stroke
				(width 0.1)
				(type default)
			)
			(layer "F.Fab")
		)
		(fp_line
			(start -0.67945 0.3048)
			(end -0.67945 -0.305054)
			(stroke
				(width 0.1)
				(type default)
			)
			(layer "F.Fab")
		)
		(pad "1" smd circle
			(at -0.40005 0 90)
			(size 0 0)
			(layers "F.Cu" "F.Mask" "F.Paste")
			(net "P3V3_AUX")
		)
		(pad "2" smd circle
			(at 0.40005 0 90)
			(size 0 0)
			(layers "F.Cu" "F.Mask" "F.Paste")
			(net "GND")
		)
	)
	(footprint ""
		(layer "F.Cu")
		(at 413.293052 -343.952322 90)
		(property "Reference" "C2442"
			(at 0 0 90)
			(layer "F.SilkS")
			(hide yes)
			(effects
				(font
					(size 1.27 1.27)
				)
			)
		)
		(property "Value" ""
			(at 0 0 90)
			(layer "F.Fab")
			(effects
				(font
					(size 1.27 1.27)
				)
			)
		)
		(duplicate_pad_numbers_are_jumpers no)
		(fp_line
			(start 0.299974 -0.150114)
			(end 0.299974 0.150114)
			(stroke
				(width 0.1)
				(type default)
			)
			(layer "F.Fab")
		)
		(fp_line
			(start -0.299974 -0.150114)
			(end 0.299974 -0.150114)
			(stroke
				(width 0.1)
				(type default)
			)
			(layer "F.Fab")
		)
		(fp_line
			(start 0.299974 0.150114)
			(end -0.299974 0.150114)
			(stroke
				(width 0.1)
				(type default)
			)
			(layer "F.Fab")
		)
		(fp_line
			(start -0.299974 0.150114)
			(end -0.299974 -0.150114)
			(stroke
				(width 0.1)
				(type default)
			)
			(layer "F.Fab")
		)
		(pad "1" smd rect
			(at -0.2667 0 90)
			(size 0.3048 0.381)
			(layers "F.Cu" "F.Mask" "F.Paste")
			(net "P5E_PEX3_STN4_TX_DN<78>")
		)
		(pad "2" smd rect
			(at 0.2667 0 90)
			(size 0.3048 0.381)
			(layers "F.Cu" "F.Mask" "F.Paste")
			(net "P5E_PEX3_STN4_TX_C_DN<78>")
		)
	)
	(footprint ""
		(layer "F.Cu")
		(at 418.247068 -55.63489 90)
		(property "Reference" "PC892"
			(at 0 0 90)
			(layer "F.SilkS")
			(hide yes)
			(effects
				(font
					(size 1.27 1.27)
				)
			)
		)
		(property "Value" ""
			(at 0 0 90)
			(layer "F.Fab")
			(effects
				(font
					(size 1.27 1.27)
				)
			)
		)
		(duplicate_pad_numbers_are_jumpers no)
		(fp_line
			(start 1.524 -0.762)
			(end 1.524 0.762)
			(stroke
				(width 0.1524)
				(type default)
			)
			(layer "F.SilkS")
		)
		(fp_line
			(start -1.524 -0.762)
			(end 1.524 -0.762)
			(stroke
				(width 0.1524)
				(type default)
			)
			(layer "F.SilkS")
		)
		(fp_line
			(start 1.524 0.762)
			(end -1.524 0.762)
			(stroke
				(width 0.1524)
				(type default)
			)
			(layer "F.SilkS")
		)
		(fp_line
			(start -1.524 0.762)
			(end -1.524 -0.762)
			(stroke
				(width 0.1524)
				(type default)
			)
			(layer "F.SilkS")
		)
		(fp_line
			(start 1.1049 -0.724916)
			(end -1.1049 -0.724916)
			(stroke
				(width 0.1)
				(type default)
			)
			(layer "F.Fab")
		)
		(fp_line
			(start -1.1049 -0.724916)
			(end -1.1049 0.724916)
			(stroke
				(width 0.1)
				(type default)
			)
			(layer "F.Fab")
		)
		(fp_line
			(start 1.1049 0.724916)
			(end 1.1049 -0.724916)
			(stroke
				(width 0.1)
				(type default)
			)
			(layer "F.Fab")
		)
		(fp_line
			(start -1.1049 0.724916)
			(end 1.1049 0.724916)
			(stroke
				(width 0.1)
				(type default)
			)
			(layer "F.Fab")
		)
		(pad "1" smd rect
			(at -0.889 0 270)
			(size 1.016 1.27)
			(layers "F.Cu" "F.Mask" "F.Paste")
			(net "P12V_SSD14_R")
		)
		(pad "2" smd rect
			(at 0.889 0 270)
			(size 1.016 1.27)
			(layers "F.Cu" "F.Mask" "F.Paste")
			(net "GND")
		)
	)
	(footprint ""
		(layer "F.Cu")
		(at 149.315932 -386.66801 90)
		(property "Reference" "C4099"
			(at 0 0 90)
			(layer "F.SilkS")
			(hide yes)
			(effects
				(font
					(size 1.27 1.27)
				)
			)
		)
		(property "Value" ""
			(at 0 0 90)
			(layer "F.Fab")
			(effects
				(font
					(size 1.27 1.27)
				)
			)
		)
		(duplicate_pad_numbers_are_jumpers no)
		(fp_line
			(start 0.7874 -0.4064)
			(end 0.7874 0.4064)
			(stroke
				(width 0.1524)
				(type default)
			)
			(layer "F.SilkS")
		)
		(fp_line
			(start -0.7874 -0.4064)
			(end 0.7874 -0.4064)
			(stroke
				(width 0.1524)
				(type default)
			)
			(layer "F.SilkS")
		)
		(fp_line
			(start 0.7874 0.4064)
			(end -0.7874 0.4064)
			(stroke
				(width 0.1524)
				(type default)
			)
			(layer "F.SilkS")
		)
		(fp_line
			(start -0.7874 0.4064)
			(end -0.7874 -0.4064)
			(stroke
				(width 0.1524)
				(type default)
			)
			(layer "F.SilkS")
		)
		(fp_line
			(start -0.12065 -0.305054)
			(end -0.12065 -0.2794)
			(stroke
				(width 0.1)
				(type default)
			)
			(layer "F.Fab")
		)
		(fp_line
			(start -0.67945 -0.305054)
			(end -0.12065 -0.305054)
			(stroke
				(width 0.1)
				(type default)
			)
			(layer "F.Fab")
		)
		(fp_line
			(start 0.67945 -0.3048)
			(end 0.67945 0.3048)
			(stroke
				(width 0.1)
				(type default)
			)
			(layer "F.Fab")
		)
		(fp_line
			(start 0.12065 -0.3048)
			(end 0.67945 -0.3048)
			(stroke
				(width 0.1)
				(type default)
			)
			(layer "F.Fab")
		)
		(fp_line
			(start 0.12065 -0.2794)
			(end 0.12065 -0.3048)
			(stroke
				(width 0.1)
				(type default)
			)
			(layer "F.Fab")
		)
		(fp_line
			(start -0.12065 -0.2794)
			(end 0.12065 -0.2794)
			(stroke
				(width 0.1)
				(type default)
			)
			(layer "F.Fab")
		)
		(fp_line
			(start 0.120396 0.2794)
			(end -0.12065 0.2794)
			(stroke
				(width 0.1)
				(type default)
			)
			(layer "F.Fab")
		)
		(fp_line
			(start -0.12065 0.2794)
			(end -0.12065 0.3048)
			(stroke
				(width 0.1)
				(type default)
			)
			(layer "F.Fab")
		)
		(fp_line
			(start 0.67945 0.3048)
			(end 0.120396 0.3048)
			(stroke
				(width 0.1)
				(type default)
			)
			(layer "F.Fab")
		)
		(fp_line
			(start 0.120396 0.3048)
			(end 0.120396 0.2794)
			(stroke
				(width 0.1)
				(type default)
			)
			(layer "F.Fab")
		)
		(fp_line
			(start -0.12065 0.3048)
			(end -0.67945 0.3048)
			(stroke
				(width 0.1)
				(type default)
			)
			(layer "F.Fab")
		)
		(fp_line
			(start -0.67945 0.3048)
			(end -0.67945 -0.305054)
			(stroke
				(width 0.1)
				(type default)
			)
			(layer "F.Fab")
		)
		(pad "1" smd circle
			(at -0.40005 0 90)
			(size 0 0)
			(layers "F.Cu" "F.Mask" "F.Paste")
			(net "GND")
		)
		(pad "2" smd circle
			(at 0.40005 0 90)
			(size 0 0)
			(layers "F.Cu" "F.Mask" "F.Paste")
			(net "GPU_BASE_HMC_READY")
		)
	)
	(footprint ""
		(layer "F.Cu")
		(at 281.867864 -18.437098)
		(property "Reference" "R1694"
			(at 0 0 0)
			(layer "F.SilkS")
			(hide yes)
			(effects
				(font
					(size 1.27 1.27)
				)
			)
		)
		(property "Value" ""
			(at 0 0 0)
			(layer "F.Fab")
			(effects
				(font
					(size 1.27 1.27)
				)
			)
		)
		(duplicate_pad_numbers_are_jumpers no)
		(fp_line
			(start -0.7874 -0.4064)
			(end 0.7874 -0.4064)
			(stroke
				(width 0.1524)
				(type default)
			)
			(layer "F.SilkS")
		)
		(fp_line
			(start -0.7874 0.4064)
			(end -0.7874 -0.4064)
			(stroke
				(width 0.1524)
				(type default)
			)
			(layer "F.SilkS")
		)
		(fp_line
			(start 0.7874 -0.4064)
			(end 0.7874 0.4064)
			(stroke
				(width 0.1524)
				(type default)
			)
			(layer "F.SilkS")
		)
		(fp_line
			(start 0.7874 0.4064)
			(end -0.7874 0.4064)
			(stroke
				(width 0.1524)
				(type default)
			)
			(layer "F.SilkS")
		)
		(fp_line
			(start -0.67945 -0.305054)
			(end -0.12065 -0.305054)
			(stroke
				(width 0.1)
				(type default)
			)
			(layer "F.Fab")
		)
		(fp_line
			(start -0.67945 0.3048)
			(end -0.67945 -0.305054)
			(stroke
				(width 0.1)
				(type default)
			)
			(layer "F.Fab")
		)
		(fp_line
			(start -0.12065 -0.305054)
			(end -0.12065 -0.2794)
			(stroke
				(width 0.1)
				(type default)
			)
			(layer "F.Fab")
		)
		(fp_line
			(start -0.12065 -0.2794)
			(end 0.12065 -0.2794)
			(stroke
				(width 0.1)
				(type default)
			)
			(layer "F.Fab")
		)
		(fp_line
			(start -0.12065 0.2794)
			(end -0.12065 0.3048)
			(stroke
				(width 0.1)
				(type default)
			)
			(layer "F.Fab")
		)
		(fp_line
			(start -0.12065 0.3048)
			(end -0.67945 0.3048)
			(stroke
				(width 0.1)
				(type default)
			)
			(layer "F.Fab")
		)
		(fp_line
			(start 0.120396 0.2794)
			(end -0.12065 0.2794)
			(stroke
				(width 0.1)
				(type default)
			)
			(layer "F.Fab")
		)
		(fp_line
			(start 0.120396 0.3048)
			(end 0.120396 0.2794)
			(stroke
				(width 0.1)
				(type default)
			)
			(layer "F.Fab")
		)
		(fp_line
			(start 0.12065 -0.3048)
			(end 0.67945 -0.3048)
			(stroke
				(width 0.1)
				(type default)
			)
			(layer "F.Fab")
		)
		(fp_line
			(start 0.12065 -0.2794)
			(end 0.12065 -0.3048)
			(stroke
				(width 0.1)
				(type default)
			)
			(layer "F.Fab")
		)
		(fp_line
			(start 0.67945 -0.3048)
			(end 0.67945 0.3048)
			(stroke
				(width 0.1)
				(type default)
			)
			(layer "F.Fab")
		)
		(fp_line
			(start 0.67945 0.3048)
			(end 0.120396 0.3048)
			(stroke
				(width 0.1)
				(type default)
			)
			(layer "F.Fab")
		)
		(pad "1" smd circle
			(at -0.40005 0)
			(size 0 0)
			(layers "F.Cu" "F.Mask" "F.Paste")
			(net "SMB_ISO_SSD9_R_SCL")
		)
		(pad "2" smd circle
			(at 0.40005 0)
			(size 0 0)
			(layers "F.Cu" "F.Mask" "F.Paste")
			(net "SMB_ISO_SSD9_SCL")
		)
	)
	(footprint ""
		(layer "F.Cu")
		(at 255.17729 -77.279754 90)
		(property "Reference" "R1068"
			(at 0 0 90)
			(layer "F.SilkS")
			(hide yes)
			(effects
				(font
					(size 1.27 1.27)
				)
			)
		)
		(property "Value" ""
			(at 0 0 90)
			(layer "F.Fab")
			(effects
				(font
					(size 1.27 1.27)
				)
			)
		)
		(duplicate_pad_numbers_are_jumpers no)
		(fp_line
			(start 0.7874 -0.4064)
			(end 0.7874 0.4064)
			(stroke
				(width 0.1524)
				(type default)
			)
			(layer "F.SilkS")
		)
		(fp_line
			(start -0.7874 -0.4064)
			(end 0.7874 -0.4064)
			(stroke
				(width 0.1524)
				(type default)
			)
			(layer "F.SilkS")
		)
		(fp_line
			(start 0.7874 0.4064)
			(end -0.7874 0.4064)
			(stroke
				(width 0.1524)
				(type default)
			)
			(layer "F.SilkS")
		)
		(fp_line
			(start -0.7874 0.4064)
			(end -0.7874 -0.4064)
			(stroke
				(width 0.1524)
				(type default)
			)
			(layer "F.SilkS")
		)
		(fp_line
			(start -0.12065 -0.305054)
			(end -0.12065 -0.2794)
			(stroke
				(width 0.1)
				(type default)
			)
			(layer "F.Fab")
		)
		(fp_line
			(start -0.67945 -0.305054)
			(end -0.12065 -0.305054)
			(stroke
				(width 0.1)
				(type default)
			)
			(layer "F.Fab")
		)
		(fp_line
			(start 0.67945 -0.3048)
			(end 0.67945 0.3048)
			(stroke
				(width 0.1)
				(type default)
			)
			(layer "F.Fab")
		)
		(fp_line
			(start 0.12065 -0.3048)
			(end 0.67945 -0.3048)
			(stroke
				(width 0.1)
				(type default)
			)
			(layer "F.Fab")
		)
		(fp_line
			(start 0.12065 -0.2794)
			(end 0.12065 -0.3048)
			(stroke
				(width 0.1)
				(type default)
			)
			(layer "F.Fab")
		)
		(fp_line
			(start -0.12065 -0.2794)
			(end 0.12065 -0.2794)
			(stroke
				(width 0.1)
				(type default)
			)
			(layer "F.Fab")
		)
		(fp_line
			(start 0.120396 0.2794)
			(end -0.12065 0.2794)
			(stroke
				(width 0.1)
				(type default)
			)
			(layer "F.Fab")
		)
		(fp_line
			(start -0.12065 0.2794)
			(end -0.12065 0.3048)
			(stroke
				(width 0.1)
				(type default)
			)
			(layer "F.Fab")
		)
		(fp_line
			(start 0.67945 0.3048)
			(end 0.120396 0.3048)
			(stroke
				(width 0.1)
				(type default)
			)
			(layer "F.Fab")
		)
		(fp_line
			(start 0.120396 0.3048)
			(end 0.120396 0.2794)
			(stroke
				(width 0.1)
				(type default)
			)
			(layer "F.Fab")
		)
		(fp_line
			(start -0.12065 0.3048)
			(end -0.67945 0.3048)
			(stroke
				(width 0.1)
				(type default)
			)
			(layer "F.Fab")
		)
		(fp_line
			(start -0.67945 0.3048)
			(end -0.67945 -0.305054)
			(stroke
				(width 0.1)
				(type default)
			)
			(layer "F.Fab")
		)
		(pad "1" smd circle
			(at -0.40005 0 90)
			(size 0 0)
			(layers "F.Cu" "F.Mask" "F.Paste")
			(net "GND")
		)
		(pad "2" smd circle
			(at 0.40005 0 90)
			(size 0 0)
			(layers "F.Cu" "F.Mask" "F.Paste")
			(net "FM_CLK_CK440_SS_EN")
		)
	)
	(footprint ""
		(layer "F.Cu")
		(at 330.77531 -69.47916 180)
		(property "Reference" "PU113"
			(at -1.86436 4.02844 90)
			(unlocked yes)
			(layer "F.SilkS")
			(effects
				(font
					(size 0.7874 0.5842)
					(thickness 0.1524)
				)
			)
		)
		(property "Value" ""
			(at 0 0 180)
			(layer "F.Fab")
			(effects
				(font
					(size 1.27 1.27)
				)
			)
		)
		(duplicate_pad_numbers_are_jumpers no)
		(fp_line
			(start 1.239774 1.495298)
			(end -1.239774 1.495298)
			(stroke
				(width 0.1524)
				(type default)
			)
			(layer "F.SilkS")
		)
		(fp_line
			(start 1.239774 -1.495298)
			(end 1.239774 1.495298)
			(stroke
				(width 0.1524)
				(type default)
			)
			(layer "F.SilkS")
		)
		(fp_line
			(start -1.239774 1.495298)
			(end -1.239774 -1.495298)
			(stroke
				(width 0.1524)
				(type default)
			)
			(layer "F.SilkS")
		)
		(fp_line
			(start -1.239774 -1.495298)
			(end 1.239774 -1.495298)
			(stroke
				(width 0.1524)
				(type default)
			)
			(layer "F.SilkS")
		)
		(fp_poly
			(pts
				(xy -1.764792 -1.332738) (xy -2.483104 -0.614172) (xy -1.405382 -0.255016)
			)
			(stroke
				(width 0)
				(type default)
			)
			(fill yes)
			(layer "F.SilkS")
		)
		(fp_line
			(start 0.8001 1.050036)
			(end -0.8001 1.050036)
			(stroke
				(width 0.1)
				(type default)
			)
			(layer "F.Fab")
		)
		(fp_line
			(start 0.8001 -1.050036)
			(end 0.8001 1.050036)
			(stroke
				(width 0.1)
				(type default)
			)
			(layer "F.Fab")
		)
		(fp_line
			(start -0.8001 1.050036)
			(end -0.8001 -1.050036)
			(stroke
				(width 0.1)
				(type default)
			)
			(layer "F.Fab")
		)
		(fp_line
			(start -0.8001 -1.050036)
			(end 0.8001 -1.050036)
			(stroke
				(width 0.1)
				(type default)
			)
			(layer "F.Fab")
		)
		(fp_poly
			(pts
				(xy -2.458974 -0.508) (xy -2.458974 0.508) (xy -1.442974 0)
			)
			(stroke
				(width 0)
				(type default)
			)
			(fill yes)
			(layer "F.Fab")
		)
		(pad "1_2" smd circle
			(at -0.374904 0 270)
			(size 0 0)
			(layers "F.Cu" "F.Mask" "F.Paste")
			(net "P12V_AUX")
		)
		(pad "3" smd rect
			(at -0.499872 0.999998 180)
			(size 0.254 0.7112)
			(layers "F.Cu" "F.Mask" "F.Paste")
			(net "GND")
		)
		(pad "4" smd rect
			(at 0 0.999998 180)
			(size 0.254 0.7112)
			(layers "F.Cu" "F.Mask" "F.Paste")
			(net "P12V_SSD11_CO_ILIMIT")
		)
		(pad "5" smd rect
			(at 0.499872 0.999998 180)
			(size 0.254 0.7112)
			(layers "F.Cu" "F.Mask" "F.Paste")
			(net "P12V_SSD11_CO_MODE")
		)
		(pad "6_7" smd circle
			(at 0.374904 0 90)
			(size 0 0)
			(layers "F.Cu" "F.Mask" "F.Paste")
			(net "P12V_SSD11_R")
		)
		(pad "8" smd rect
			(at 0.499872 -0.999998 180)
			(size 0.254 0.7112)
			(layers "F.Cu" "F.Mask" "F.Paste")
			(net "P12V_SSD11_CO_GATE")
		)
		(pad "9" smd rect
			(at 0 -0.999998 180)
			(size 0.254 0.7112)
			(layers "F.Cu" "F.Mask" "F.Paste")
			(net "P12V_SSD11_CO_EN")
		)
		(pad "10" smd rect
			(at -0.499872 -0.999998 180)
			(size 0.254 0.7112)
			(layers "F.Cu" "F.Mask" "F.Paste")
			(net "P12V_SSD11_CO_DV_DT")
		)
	)
	(footprint ""
		(layer "F.Cu")
		(at 462.465674 -276.64283)
		(property "Reference" "R807"
			(at 0 0 0)
			(layer "F.SilkS")
			(hide yes)
			(effects
				(font
					(size 1.27 1.27)
				)
			)
		)
		(property "Value" ""
			(at 0 0 0)
			(layer "F.Fab")
			(effects
				(font
					(size 1.27 1.27)
				)
			)
		)
		(duplicate_pad_numbers_are_jumpers no)
		(fp_line
			(start -0.7874 -0.4064)
			(end 0.7874 -0.4064)
			(stroke
				(width 0.1524)
				(type default)
			)
			(layer "F.SilkS")
		)
		(fp_line
			(start -0.7874 0.4064)
			(end -0.7874 -0.4064)
			(stroke
				(width 0.1524)
				(type default)
			)
			(layer "F.SilkS")
		)
		(fp_line
			(start 0.7874 -0.4064)
			(end 0.7874 0.4064)
			(stroke
				(width 0.1524)
				(type default)
			)
			(layer "F.SilkS")
		)
		(fp_line
			(start 0.7874 0.4064)
			(end -0.7874 0.4064)
			(stroke
				(width 0.1524)
				(type default)
			)
			(layer "F.SilkS")
		)
		(fp_line
			(start -0.67945 -0.305054)
			(end -0.12065 -0.305054)
			(stroke
				(width 0.1)
				(type default)
			)
			(layer "F.Fab")
		)
		(fp_line
			(start -0.67945 0.3048)
			(end -0.67945 -0.305054)
			(stroke
				(width 0.1)
				(type default)
			)
			(layer "F.Fab")
		)
		(fp_line
			(start -0.12065 -0.305054)
			(end -0.12065 -0.2794)
			(stroke
				(width 0.1)
				(type default)
			)
			(layer "F.Fab")
		)
		(fp_line
			(start -0.12065 -0.2794)
			(end 0.12065 -0.2794)
			(stroke
				(width 0.1)
				(type default)
			)
			(layer "F.Fab")
		)
		(fp_line
			(start -0.12065 0.2794)
			(end -0.12065 0.3048)
			(stroke
				(width 0.1)
				(type default)
			)
			(layer "F.Fab")
		)
		(fp_line
			(start -0.12065 0.3048)
			(end -0.67945 0.3048)
			(stroke
				(width 0.1)
				(type default)
			)
			(layer "F.Fab")
		)
		(fp_line
			(start 0.120396 0.2794)
			(end -0.12065 0.2794)
			(stroke
				(width 0.1)
				(type default)
			)
			(layer "F.Fab")
		)
		(fp_line
			(start 0.120396 0.3048)
			(end 0.120396 0.2794)
			(stroke
				(width 0.1)
				(type default)
			)
			(layer "F.Fab")
		)
		(fp_line
			(start 0.12065 -0.3048)
			(end 0.67945 -0.3048)
			(stroke
				(width 0.1)
				(type default)
			)
			(layer "F.Fab")
		)
		(fp_line
			(start 0.12065 -0.2794)
			(end 0.12065 -0.3048)
			(stroke
				(width 0.1)
				(type default)
			)
			(layer "F.Fab")
		)
		(fp_line
			(start 0.67945 -0.3048)
			(end 0.67945 0.3048)
			(stroke
				(width 0.1)
				(type default)
			)
			(layer "F.Fab")
		)
		(fp_line
			(start 0.67945 0.3048)
			(end 0.120396 0.3048)
			(stroke
				(width 0.1)
				(type default)
			)
			(layer "F.Fab")
		)
		(pad "1" smd circle
			(at -0.40005 0)
			(size 0 0)
			(layers "F.Cu" "F.Mask" "F.Paste")
			(net "PEX3_P1V25_ADC_A0")
		)
		(pad "2" smd circle
			(at 0.40005 0)
			(size 0 0)
			(layers "F.Cu" "F.Mask" "F.Paste")
			(net "GND")
		)
	)
	(footprint ""
		(layer "F.Cu")
		(at 387.580632 -99.288854)
		(property "Reference" "C696"
			(at 0 0 0)
			(layer "F.SilkS")
			(hide yes)
			(effects
				(font
					(size 1.27 1.27)
				)
			)
		)
		(property "Value" ""
			(at 0 0 0)
			(layer "F.Fab")
			(effects
				(font
					(size 1.27 1.27)
				)
			)
		)
		(duplicate_pad_numbers_are_jumpers no)
		(fp_line
			(start -0.299974 -0.150114)
			(end 0.299974 -0.150114)
			(stroke
				(width 0.1)
				(type default)
			)
			(layer "F.Fab")
		)
		(fp_line
			(start -0.299974 0.150114)
			(end -0.299974 -0.150114)
			(stroke
				(width 0.1)
				(type default)
			)
			(layer "F.Fab")
		)
		(fp_line
			(start 0.299974 -0.150114)
			(end 0.299974 0.150114)
			(stroke
				(width 0.1)
				(type default)
			)
			(layer "F.Fab")
		)
		(fp_line
			(start 0.299974 0.150114)
			(end -0.299974 0.150114)
			(stroke
				(width 0.1)
				(type default)
			)
			(layer "F.Fab")
		)
		(pad "1" smd rect
			(at -0.2667 0)
			(size 0.3048 0.381)
			(layers "F.Cu" "F.Mask" "F.Paste")
			(net "P5E_PEX3_STN1_TX_DP<16>")
		)
		(pad "2" smd rect
			(at 0.2667 0)
			(size 0.3048 0.381)
			(layers "F.Cu" "F.Mask" "F.Paste")
			(net "P5E_PEX3_STN1_TX_C_DP<16>")
		)
	)
	(footprint ""
		(layer "F.Cu")
		(at 394.734542 -33.631886 180)
		(property "Reference" "C707"
			(at 0 0 180)
			(layer "F.SilkS")
			(hide yes)
			(effects
				(font
					(size 1.27 1.27)
				)
			)
		)
		(property "Value" ""
			(at 0 0 180)
			(layer "F.Fab")
			(effects
				(font
					(size 1.27 1.27)
				)
			)
		)
		(duplicate_pad_numbers_are_jumpers no)
		(fp_line
			(start 0.299974 0.150114)
			(end -0.299974 0.150114)
			(stroke
				(width 0.1)
				(type default)
			)
			(layer "F.Fab")
		)
		(fp_line
			(start 0.299974 -0.150114)
			(end 0.299974 0.150114)
			(stroke
				(width 0.1)
				(type default)
			)
			(layer "F.Fab")
		)
		(fp_line
			(start -0.299974 0.150114)
			(end -0.299974 -0.150114)
			(stroke
				(width 0.1)
				(type default)
			)
			(layer "F.Fab")
		)
		(fp_line
			(start -0.299974 -0.150114)
			(end 0.299974 -0.150114)
			(stroke
				(width 0.1)
				(type default)
			)
			(layer "F.Fab")
		)
		(pad "1" smd rect
			(at -0.2667 0 180)
			(size 0.3048 0.381)
			(layers "F.Cu" "F.Mask" "F.Paste")
			(net "P5E_PEX3_STN2_TX_DN<43>")
		)
		(pad "2" smd rect
			(at 0.2667 0 180)
			(size 0.3048 0.381)
			(layers "F.Cu" "F.Mask" "F.Paste")
			(net "P5E_PEX3_STN2_TX_C_DN<43>")
		)
	)
	(footprint ""
		(layer "F.Cu")
		(at 241.082322 -215.04529 180)
		(property "Reference" "R477"
			(at 0 0 180)
			(layer "F.SilkS")
			(hide yes)
			(effects
				(font
					(size 1.27 1.27)
				)
			)
		)
		(property "Value" ""
			(at 0 0 180)
			(layer "F.Fab")
			(effects
				(font
					(size 1.27 1.27)
				)
			)
		)
		(duplicate_pad_numbers_are_jumpers no)
		(fp_line
			(start 0.7874 0.4064)
			(end -0.7874 0.4064)
			(stroke
				(width 0.1524)
				(type default)
			)
			(layer "F.SilkS")
		)
		(fp_line
			(start 0.7874 -0.4064)
			(end 0.7874 0.4064)
			(stroke
				(width 0.1524)
				(type default)
			)
			(layer "F.SilkS")
		)
		(fp_line
			(start -0.7874 0.4064)
			(end -0.7874 -0.4064)
			(stroke
				(width 0.1524)
				(type default)
			)
			(layer "F.SilkS")
		)
		(fp_line
			(start -0.7874 -0.4064)
			(end 0.7874 -0.4064)
			(stroke
				(width 0.1524)
				(type default)
			)
			(layer "F.SilkS")
		)
		(fp_line
			(start 0.67945 0.3048)
			(end 0.120396 0.3048)
			(stroke
				(width 0.1)
				(type default)
			)
			(layer "F.Fab")
		)
		(fp_line
			(start 0.67945 -0.3048)
			(end 0.67945 0.3048)
			(stroke
				(width 0.1)
				(type default)
			)
			(layer "F.Fab")
		)
		(fp_line
			(start 0.12065 -0.2794)
			(end 0.12065 -0.3048)
			(stroke
				(width 0.1)
				(type default)
			)
			(layer "F.Fab")
		)
		(fp_line
			(start 0.12065 -0.3048)
			(end 0.67945 -0.3048)
			(stroke
				(width 0.1)
				(type default)
			)
			(layer "F.Fab")
		)
		(fp_line
			(start 0.120396 0.3048)
			(end 0.120396 0.2794)
			(stroke
				(width 0.1)
				(type default)
			)
			(layer "F.Fab")
		)
		(fp_line
			(start 0.120396 0.2794)
			(end -0.12065 0.2794)
			(stroke
				(width 0.1)
				(type default)
			)
			(layer "F.Fab")
		)
		(fp_line
			(start -0.12065 0.3048)
			(end -0.67945 0.3048)
			(stroke
				(width 0.1)
				(type default)
			)
			(layer "F.Fab")
		)
		(fp_line
			(start -0.12065 0.2794)
			(end -0.12065 0.3048)
			(stroke
				(width 0.1)
				(type default)
			)
			(layer "F.Fab")
		)
		(fp_line
			(start -0.12065 -0.2794)
			(end 0.12065 -0.2794)
			(stroke
				(width 0.1)
				(type default)
			)
			(layer "F.Fab")
		)
		(fp_line
			(start -0.12065 -0.305054)
			(end -0.12065 -0.2794)
			(stroke
				(width 0.1)
				(type default)
			)
			(layer "F.Fab")
		)
		(fp_line
			(start -0.67945 0.3048)
			(end -0.67945 -0.305054)
			(stroke
				(width 0.1)
				(type default)
			)
			(layer "F.Fab")
		)
		(fp_line
			(start -0.67945 -0.305054)
			(end -0.12065 -0.305054)
			(stroke
				(width 0.1)
				(type default)
			)
			(layer "F.Fab")
		)
		(pad "1" smd circle
			(at -0.40005 0 180)
			(size 0 0)
			(layers "F.Cu" "F.Mask" "F.Paste")
			(net "P3V3_AUX_SCALED")
		)
		(pad "2" smd circle
			(at 0.40005 0 180)
			(size 0 0)
			(layers "F.Cu" "F.Mask" "F.Paste")
			(net "GND")
		)
	)
	(footprint ""
		(layer "F.Cu")
		(at 405.594058 -34.248852)
		(property "Reference" "R5707"
			(at 0 0 0)
			(layer "F.SilkS")
			(hide yes)
			(effects
				(font
					(size 1.27 1.27)
				)
			)
		)
		(property "Value" ""
			(at 0 0 0)
			(layer "F.Fab")
			(effects
				(font
					(size 1.27 1.27)
				)
			)
		)
		(duplicate_pad_numbers_are_jumpers no)
		(fp_line
			(start -0.7874 -0.4064)
			(end 0.7874 -0.4064)
			(stroke
				(width 0.1524)
				(type default)
			)
			(layer "F.SilkS")
		)
		(fp_line
			(start -0.7874 0.4064)
			(end -0.7874 -0.4064)
			(stroke
				(width 0.1524)
				(type default)
			)
			(layer "F.SilkS")
		)
		(fp_line
			(start 0.7874 -0.4064)
			(end 0.7874 0.4064)
			(stroke
				(width 0.1524)
				(type default)
			)
			(layer "F.SilkS")
		)
		(fp_line
			(start 0.7874 0.4064)
			(end -0.7874 0.4064)
			(stroke
				(width 0.1524)
				(type default)
			)
			(layer "F.SilkS")
		)
		(fp_line
			(start -0.67945 -0.305054)
			(end -0.12065 -0.305054)
			(stroke
				(width 0.1)
				(type default)
			)
			(layer "F.Fab")
		)
		(fp_line
			(start -0.67945 0.3048)
			(end -0.67945 -0.305054)
			(stroke
				(width 0.1)
				(type default)
			)
			(layer "F.Fab")
		)
		(fp_line
			(start -0.12065 -0.305054)
			(end -0.12065 -0.2794)
			(stroke
				(width 0.1)
				(type default)
			)
			(layer "F.Fab")
		)
		(fp_line
			(start -0.12065 -0.2794)
			(end 0.12065 -0.2794)
			(stroke
				(width 0.1)
				(type default)
			)
			(layer "F.Fab")
		)
		(fp_line
			(start -0.12065 0.2794)
			(end -0.12065 0.3048)
			(stroke
				(width 0.1)
				(type default)
			)
			(layer "F.Fab")
		)
		(fp_line
			(start -0.12065 0.3048)
			(end -0.67945 0.3048)
			(stroke
				(width 0.1)
				(type default)
			)
			(layer "F.Fab")
		)
		(fp_line
			(start 0.120396 0.2794)
			(end -0.12065 0.2794)
			(stroke
				(width 0.1)
				(type default)
			)
			(layer "F.Fab")
		)
		(fp_line
			(start 0.120396 0.3048)
			(end 0.120396 0.2794)
			(stroke
				(width 0.1)
				(type default)
			)
			(layer "F.Fab")
		)
		(fp_line
			(start 0.12065 -0.3048)
			(end 0.67945 -0.3048)
			(stroke
				(width 0.1)
				(type default)
			)
			(layer "F.Fab")
		)
		(fp_line
			(start 0.12065 -0.2794)
			(end 0.12065 -0.3048)
			(stroke
				(width 0.1)
				(type default)
			)
			(layer "F.Fab")
		)
		(fp_line
			(start 0.67945 -0.3048)
			(end 0.67945 0.3048)
			(stroke
				(width 0.1)
				(type default)
			)
			(layer "F.Fab")
		)
		(fp_line
			(start 0.67945 0.3048)
			(end 0.120396 0.3048)
			(stroke
				(width 0.1)
				(type default)
			)
			(layer "F.Fab")
		)
		(pad "1" smd circle
			(at -0.40005 0)
			(size 0 0)
			(layers "F.Cu" "F.Mask" "F.Paste")
			(net "RST_SMB_SSD14_ISO_N")
		)
		(pad "2" smd circle
			(at 0.40005 0)
			(size 0 0)
			(layers "F.Cu" "F.Mask" "F.Paste")
			(net "P3V3_SSD14")
		)
	)
	(footprint ""
		(layer "F.Cu")
		(at 325.827644 -350.098614 90)
		(property "Reference" "C538"
			(at 0 0 90)
			(layer "F.SilkS")
			(hide yes)
			(effects
				(font
					(size 1.27 1.27)
				)
			)
		)
		(property "Value" ""
			(at 0 0 90)
			(layer "F.Fab")
			(effects
				(font
					(size 1.27 1.27)
				)
			)
		)
		(duplicate_pad_numbers_are_jumpers no)
		(fp_line
			(start 0.299974 -0.150114)
			(end 0.299974 0.150114)
			(stroke
				(width 0.1)
				(type default)
			)
			(layer "F.Fab")
		)
		(fp_line
			(start -0.299974 -0.150114)
			(end 0.299974 -0.150114)
			(stroke
				(width 0.1)
				(type default)
			)
			(layer "F.Fab")
		)
		(fp_line
			(start 0.299974 0.150114)
			(end -0.299974 0.150114)
			(stroke
				(width 0.1)
				(type default)
			)
			(layer "F.Fab")
		)
		(fp_line
			(start -0.299974 0.150114)
			(end -0.299974 -0.150114)
			(stroke
				(width 0.1)
				(type default)
			)
			(layer "F.Fab")
		)
		(pad "1" smd rect
			(at -0.2667 0 90)
			(size 0.3048 0.381)
			(layers "F.Cu" "F.Mask" "F.Paste")
			(net "P5E_PEX2_STN5_TX_DN<86>")
		)
		(pad "2" smd rect
			(at 0.2667 0 90)
			(size 0.3048 0.381)
			(layers "F.Cu" "F.Mask" "F.Paste")
			(net "P5E_PEX2_STN5_TX_C_DN<86>")
		)
	)
	(footprint ""
		(layer "F.Cu")
		(at 105.581958 -79.822294 90)
		(property "Reference" "R1136"
			(at 0 0 90)
			(layer "F.SilkS")
			(hide yes)
			(effects
				(font
					(size 1.27 1.27)
				)
			)
		)
		(property "Value" ""
			(at 0 0 90)
			(layer "F.Fab")
			(effects
				(font
					(size 1.27 1.27)
				)
			)
		)
		(duplicate_pad_numbers_are_jumpers no)
		(fp_line
			(start -0.7874 -0.4064)
			(end 0.7874 -0.4064)
			(stroke
				(width 0.1524)
				(type default)
			)
			(layer "F.SilkS")
		)
		(fp_line
			(start -0.12065 -0.305054)
			(end -0.12065 -0.2794)
			(stroke
				(width 0.1)
				(type default)
			)
			(layer "F.Fab")
		)
		(fp_line
			(start -0.67945 -0.305054)
			(end -0.12065 -0.305054)
			(stroke
				(width 0.1)
				(type default)
			)
			(layer "F.Fab")
		)
		(fp_line
			(start 0.67945 -0.3048)
			(end 0.67945 0.3048)
			(stroke
				(width 0.1)
				(type default)
			)
			(layer "F.Fab")
		)
		(fp_line
			(start 0.12065 -0.3048)
			(end 0.67945 -0.3048)
			(stroke
				(width 0.1)
				(type default)
			)
			(layer "F.Fab")
		)
		(fp_line
			(start 0.12065 -0.2794)
			(end 0.12065 -0.3048)
			(stroke
				(width 0.1)
				(type default)
			)
			(layer "F.Fab")
		)
		(fp_line
			(start -0.12065 -0.2794)
			(end 0.12065 -0.2794)
			(stroke
				(width 0.1)
				(type default)
			)
			(layer "F.Fab")
		)
		(fp_line
			(start 0.120396 0.2794)
			(end -0.12065 0.2794)
			(stroke
				(width 0.1)
				(type default)
			)
			(layer "F.Fab")
		)
		(fp_line
			(start -0.12065 0.2794)
			(end -0.12065 0.3048)
			(stroke
				(width 0.1)
				(type default)
			)
			(layer "F.Fab")
		)
		(fp_line
			(start 0.67945 0.3048)
			(end 0.120396 0.3048)
			(stroke
				(width 0.1)
				(type default)
			)
			(layer "F.Fab")
		)
		(fp_line
			(start 0.120396 0.3048)
			(end 0.120396 0.2794)
			(stroke
				(width 0.1)
				(type default)
			)
			(layer "F.Fab")
		)
		(fp_line
			(start -0.12065 0.3048)
			(end -0.67945 0.3048)
			(stroke
				(width 0.1)
				(type default)
			)
			(layer "F.Fab")
		)
		(fp_line
			(start -0.67945 0.3048)
			(end -0.67945 -0.305054)
			(stroke
				(width 0.1)
				(type default)
			)
			(layer "F.Fab")
		)
		(pad "1" smd circle
			(at -0.40005 0 90)
			(size 0 0)
			(layers "F.Cu" "F.Mask" "F.Paste")
			(net "CLK_100M_DB800ZL_SSD0_R_DP")
		)
		(pad "2" smd circle
			(at 0.40005 0 90)
			(size 0 0)
			(layers "F.Cu" "F.Mask" "F.Paste")
			(net "CLK_100M_DB800ZL_SSD0_DP")
		)
	)
	(footprint ""
		(layer "F.Cu")
		(at 418.092382 -28.225242 180)
		(property "Reference" "C721"
			(at 0 0 180)
			(layer "F.SilkS")
			(hide yes)
			(effects
				(font
					(size 1.27 1.27)
				)
			)
		)
		(property "Value" ""
			(at 0 0 180)
			(layer "F.Fab")
			(effects
				(font
					(size 1.27 1.27)
				)
			)
		)
		(duplicate_pad_numbers_are_jumpers no)
		(fp_line
			(start 0.299974 0.150114)
			(end -0.299974 0.150114)
			(stroke
				(width 0.1)
				(type default)
			)
			(layer "F.Fab")
		)
		(fp_line
			(start 0.299974 -0.150114)
			(end 0.299974 0.150114)
			(stroke
				(width 0.1)
				(type default)
			)
			(layer "F.Fab")
		)
		(fp_line
			(start -0.299974 0.150114)
			(end -0.299974 -0.150114)
			(stroke
				(width 0.1)
				(type default)
			)
			(layer "F.Fab")
		)
		(fp_line
			(start -0.299974 -0.150114)
			(end 0.299974 -0.150114)
			(stroke
				(width 0.1)
				(type default)
			)
			(layer "F.Fab")
		)
		(pad "1" smd rect
			(at -0.2667 0 180)
			(size 0.3048 0.381)
			(layers "F.Cu" "F.Mask" "F.Paste")
			(net "P5E_PEX3_STN2_TX_DN<36>")
		)
		(pad "2" smd rect
			(at 0.2667 0 180)
			(size 0.3048 0.381)
			(layers "F.Cu" "F.Mask" "F.Paste")
			(net "P5E_PEX3_STN2_TX_C_DN<36>")
		)
	)
	(footprint ""
		(layer "F.Cu")
		(at 225.09988 -254.18542 -90)
		(property "Reference" "C4296"
			(at 0 0 270)
			(layer "F.SilkS")
			(hide yes)
			(effects
				(font
					(size 1.27 1.27)
				)
			)
		)
		(property "Value" ""
			(at 0 0 270)
			(layer "F.Fab")
			(effects
				(font
					(size 1.27 1.27)
				)
			)
		)
		(duplicate_pad_numbers_are_jumpers no)
		(fp_line
			(start -1.2954 0.5842)
			(end -1.2954 -0.5842)
			(stroke
				(width 0.1524)
				(type default)
			)
			(layer "F.SilkS")
		)
		(fp_line
			(start 1.2954 0.5842)
			(end -1.2954 0.5842)
			(stroke
				(width 0.1524)
				(type default)
			)
			(layer "F.SilkS")
		)
		(fp_line
			(start -1.2954 -0.5842)
			(end 1.2954 -0.5842)
			(stroke
				(width 0.1524)
				(type default)
			)
			(layer "F.SilkS")
		)
		(fp_line
			(start 1.2954 -0.5842)
			(end 1.2954 0.5842)
			(stroke
				(width 0.1524)
				(type default)
			)
			(layer "F.SilkS")
		)
		(fp_line
			(start -0.8636 0.4572)
			(end -0.8636 0.4064)
			(stroke
				(width 0.1)
				(type default)
			)
			(layer "F.Fab")
		)
		(fp_line
			(start 0.8636 0.4572)
			(end -0.8636 0.4572)
			(stroke
				(width 0.1)
				(type default)
			)
			(layer "F.Fab")
		)
		(fp_line
			(start -1.1938 0.4064)
			(end -1.1938 -0.4064)
			(stroke
				(width 0.1)
				(type default)
			)
			(layer "F.Fab")
		)
		(fp_line
			(start -0.8636 0.4064)
			(end -1.1938 0.4064)
			(stroke
				(width 0.1)
				(type default)
			)
			(layer "F.Fab")
		)
		(fp_line
			(start 0.8636 0.4064)
			(end 0.8636 0.4572)
			(stroke
				(width 0.1)
				(type default)
			)
			(layer "F.Fab")
		)
		(fp_line
			(start 1.1938 0.4064)
			(end 0.8636 0.4064)
			(stroke
				(width 0.1)
				(type default)
			)
			(layer "F.Fab")
		)
		(fp_line
			(start -1.1938 -0.4064)
			(end -0.8636 -0.4064)
			(stroke
				(width 0.1)
				(type default)
			)
			(layer "F.Fab")
		)
		(fp_line
			(start -0.8636 -0.4064)
			(end -0.8636 -0.4572)
			(stroke
				(width 0.1)
				(type default)
			)
			(layer "F.Fab")
		)
		(fp_line
			(start 0.8636 -0.4064)
			(end 1.1938 -0.4064)
			(stroke
				(width 0.1)
				(type default)
			)
			(layer "F.Fab")
		)
		(fp_line
			(start 1.1938 -0.4064)
			(end 1.1938 0.4064)
			(stroke
				(width 0.1)
				(type default)
			)
			(layer "F.Fab")
		)
		(fp_line
			(start -0.8636 -0.4572)
			(end 0.8636 -0.4572)
			(stroke
				(width 0.1)
				(type default)
			)
			(layer "F.Fab")
		)
		(fp_line
			(start 0.8636 -0.4572)
			(end 0.8636 -0.4064)
			(stroke
				(width 0.1)
				(type default)
			)
			(layer "F.Fab")
		)
		(pad "1" smd rect
			(at -0.7366 0 180)
			(size 0.7112 0.8128)
			(layers "F.Cu" "F.Mask" "F.Paste")
			(net "P1V25_SERDES_VDDPLL_PEX1_C6")
		)
		(pad "2" smd rect
			(at 0.7366 0 180)
			(size 0.7112 0.8128)
			(layers "F.Cu" "F.Mask" "F.Paste")
			(net "GND")
		)
	)
	(footprint ""
		(layer "F.Cu")
		(at 290.548822 -356.244906 90)
		(property "Reference" "C592"
			(at 0 0 90)
			(layer "F.SilkS")
			(hide yes)
			(effects
				(font
					(size 1.27 1.27)
				)
			)
		)
		(property "Value" ""
			(at 0 0 90)
			(layer "F.Fab")
			(effects
				(font
					(size 1.27 1.27)
				)
			)
		)
		(duplicate_pad_numbers_are_jumpers no)
		(fp_line
			(start 0.299974 -0.150114)
			(end 0.299974 0.150114)
			(stroke
				(width 0.1)
				(type default)
			)
			(layer "F.Fab")
		)
		(fp_line
			(start -0.299974 -0.150114)
			(end 0.299974 -0.150114)
			(stroke
				(width 0.1)
				(type default)
			)
			(layer "F.Fab")
		)
		(fp_line
			(start 0.299974 0.150114)
			(end -0.299974 0.150114)
			(stroke
				(width 0.1)
				(type default)
			)
			(layer "F.Fab")
		)
		(fp_line
			(start -0.299974 0.150114)
			(end -0.299974 -0.150114)
			(stroke
				(width 0.1)
				(type default)
			)
			(layer "F.Fab")
		)
		(pad "1" smd rect
			(at -0.2667 0 90)
			(size 0.3048 0.381)
			(layers "F.Cu" "F.Mask" "F.Paste")
			(net "P5E_PEX2_STN7_TX_DN<123>")
		)
		(pad "2" smd rect
			(at 0.2667 0 90)
			(size 0.3048 0.381)
			(layers "F.Cu" "F.Mask" "F.Paste")
			(net "P5E_PEX2_STN7_TX_C_DN<123>")
		)
	)
	(footprint ""
		(layer "F.Cu")
		(at 396.94866 -350.098614 90)
		(property "Reference" "C753"
			(at 0 0 90)
			(layer "F.SilkS")
			(hide yes)
			(effects
				(font
					(size 1.27 1.27)
				)
			)
		)
		(property "Value" ""
			(at 0 0 90)
			(layer "F.Fab")
			(effects
				(font
					(size 1.27 1.27)
				)
			)
		)
		(duplicate_pad_numbers_are_jumpers no)
		(fp_line
			(start 0.299974 -0.150114)
			(end 0.299974 0.150114)
			(stroke
				(width 0.1)
				(type default)
			)
			(layer "F.Fab")
		)
		(fp_line
			(start -0.299974 -0.150114)
			(end 0.299974 -0.150114)
			(stroke
				(width 0.1)
				(type default)
			)
			(layer "F.Fab")
		)
		(fp_line
			(start 0.299974 0.150114)
			(end -0.299974 0.150114)
			(stroke
				(width 0.1)
				(type default)
			)
			(layer "F.Fab")
		)
		(fp_line
			(start -0.299974 0.150114)
			(end -0.299974 -0.150114)
			(stroke
				(width 0.1)
				(type default)
			)
			(layer "F.Fab")
		)
		(pad "1" smd rect
			(at -0.2667 0 90)
			(size 0.3048 0.381)
			(layers "F.Cu" "F.Mask" "F.Paste")
			(net "P5E_PEX3_STN5_TX_DN<84>")
		)
		(pad "2" smd rect
			(at 0.2667 0 90)
			(size 0.3048 0.381)
			(layers "F.Cu" "F.Mask" "F.Paste")
			(net "P5E_PEX3_STN5_TX_C_DN<84>")
		)
	)
	(footprint ""
		(layer "F.Cu")
		(at 455.238612 -254.5969 -90)
		(property "Reference" "C4396"
			(at 0 0 270)
			(layer "F.SilkS")
			(hide yes)
			(effects
				(font
					(size 1.27 1.27)
				)
			)
		)
		(property "Value" ""
			(at 0 0 270)
			(layer "F.Fab")
			(effects
				(font
					(size 1.27 1.27)
				)
			)
		)
		(duplicate_pad_numbers_are_jumpers no)
		(fp_line
			(start -1.2954 0.5842)
			(end -1.2954 -0.5842)
			(stroke
				(width 0.1524)
				(type default)
			)
			(layer "F.SilkS")
		)
		(fp_line
			(start 1.2954 0.5842)
			(end -1.2954 0.5842)
			(stroke
				(width 0.1524)
				(type default)
			)
			(layer "F.SilkS")
		)
		(fp_line
			(start -1.2954 -0.5842)
			(end 1.2954 -0.5842)
			(stroke
				(width 0.1524)
				(type default)
			)
			(layer "F.SilkS")
		)
		(fp_line
			(start 1.2954 -0.5842)
			(end 1.2954 0.5842)
			(stroke
				(width 0.1524)
				(type default)
			)
			(layer "F.SilkS")
		)
		(fp_line
			(start -0.8636 0.4572)
			(end -0.8636 0.4064)
			(stroke
				(width 0.1)
				(type default)
			)
			(layer "F.Fab")
		)
		(fp_line
			(start 0.8636 0.4572)
			(end -0.8636 0.4572)
			(stroke
				(width 0.1)
				(type default)
			)
			(layer "F.Fab")
		)
		(fp_line
			(start -1.1938 0.4064)
			(end -1.1938 -0.4064)
			(stroke
				(width 0.1)
				(type default)
			)
			(layer "F.Fab")
		)
		(fp_line
			(start -0.8636 0.4064)
			(end -1.1938 0.4064)
			(stroke
				(width 0.1)
				(type default)
			)
			(layer "F.Fab")
		)
		(fp_line
			(start 0.8636 0.4064)
			(end 0.8636 0.4572)
			(stroke
				(width 0.1)
				(type default)
			)
			(layer "F.Fab")
		)
		(fp_line
			(start 1.1938 0.4064)
			(end 0.8636 0.4064)
			(stroke
				(width 0.1)
				(type default)
			)
			(layer "F.Fab")
		)
		(fp_line
			(start -1.1938 -0.4064)
			(end -0.8636 -0.4064)
			(stroke
				(width 0.1)
				(type default)
			)
			(layer "F.Fab")
		)
		(fp_line
			(start -0.8636 -0.4064)
			(end -0.8636 -0.4572)
			(stroke
				(width 0.1)
				(type default)
			)
			(layer "F.Fab")
		)
		(fp_line
			(start 0.8636 -0.4064)
			(end 1.1938 -0.4064)
			(stroke
				(width 0.1)
				(type default)
			)
			(layer "F.Fab")
		)
		(fp_line
			(start 1.1938 -0.4064)
			(end 1.1938 0.4064)
			(stroke
				(width 0.1)
				(type default)
			)
			(layer "F.Fab")
		)
		(fp_line
			(start -0.8636 -0.4572)
			(end 0.8636 -0.4572)
			(stroke
				(width 0.1)
				(type default)
			)
			(layer "F.Fab")
		)
		(fp_line
			(start 0.8636 -0.4572)
			(end 0.8636 -0.4064)
			(stroke
				(width 0.1)
				(type default)
			)
			(layer "F.Fab")
		)
		(pad "1" smd rect
			(at -0.7366 0 180)
			(size 0.7112 0.8128)
			(layers "F.Cu" "F.Mask" "F.Paste")
			(net "P1V25_SERDES_VDDPLL_PEX3_C2")
		)
		(pad "2" smd rect
			(at 0.7366 0 180)
			(size 0.7112 0.8128)
			(layers "F.Cu" "F.Mask" "F.Paste")
			(net "GND")
		)
	)
	(footprint ""
		(layer "F.Cu")
		(at 147.107402 -257.439414 -90)
		(property "Reference" "C3226"
			(at 0 0 270)
			(layer "F.SilkS")
			(hide yes)
			(effects
				(font
					(size 1.27 1.27)
				)
			)
		)
		(property "Value" ""
			(at 0 0 270)
			(layer "F.Fab")
			(effects
				(font
					(size 1.27 1.27)
				)
			)
		)
		(duplicate_pad_numbers_are_jumpers no)
		(fp_line
			(start -0.299974 0.150114)
			(end -0.299974 -0.150114)
			(stroke
				(width 0.1)
				(type default)
			)
			(layer "F.Fab")
		)
		(fp_line
			(start 0.299974 0.150114)
			(end -0.299974 0.150114)
			(stroke
				(width 0.1)
				(type default)
			)
			(layer "F.Fab")
		)
		(fp_line
			(start -0.299974 -0.150114)
			(end 0.299974 -0.150114)
			(stroke
				(width 0.1)
				(type default)
			)
			(layer "F.Fab")
		)
		(fp_line
			(start 0.299974 -0.150114)
			(end 0.299974 0.150114)
			(stroke
				(width 0.1)
				(type default)
			)
			(layer "F.Fab")
		)
		(pad "1" smd rect
			(at -0.2667 0 270)
			(size 0.3048 0.381)
			(layers "F.Cu" "F.Mask" "F.Paste")
			(net "P1V8_PLL0_PEX1")
		)
		(pad "2" smd rect
			(at 0.2667 0 270)
			(size 0.3048 0.381)
			(layers "F.Cu" "F.Mask" "F.Paste")
			(net "GND")
		)
	)
	(footprint ""
		(layer "F.Cu")
		(at 165.76802 -18.437098)
		(property "Reference" "R1666"
			(at 0 0 0)
			(layer "F.SilkS")
			(hide yes)
			(effects
				(font
					(size 1.27 1.27)
				)
			)
		)
		(property "Value" ""
			(at 0 0 0)
			(layer "F.Fab")
			(effects
				(font
					(size 1.27 1.27)
				)
			)
		)
		(duplicate_pad_numbers_are_jumpers no)
		(fp_line
			(start -0.7874 -0.4064)
			(end 0.7874 -0.4064)
			(stroke
				(width 0.1524)
				(type default)
			)
			(layer "F.SilkS")
		)
		(fp_line
			(start -0.7874 0.4064)
			(end -0.7874 -0.4064)
			(stroke
				(width 0.1524)
				(type default)
			)
			(layer "F.SilkS")
		)
		(fp_line
			(start 0.7874 -0.4064)
			(end 0.7874 0.4064)
			(stroke
				(width 0.1524)
				(type default)
			)
			(layer "F.SilkS")
		)
		(fp_line
			(start 0.7874 0.4064)
			(end -0.7874 0.4064)
			(stroke
				(width 0.1524)
				(type default)
			)
			(layer "F.SilkS")
		)
		(fp_line
			(start -0.67945 -0.305054)
			(end -0.12065 -0.305054)
			(stroke
				(width 0.1)
				(type default)
			)
			(layer "F.Fab")
		)
		(fp_line
			(start -0.67945 0.3048)
			(end -0.67945 -0.305054)
			(stroke
				(width 0.1)
				(type default)
			)
			(layer "F.Fab")
		)
		(fp_line
			(start -0.12065 -0.305054)
			(end -0.12065 -0.2794)
			(stroke
				(width 0.1)
				(type default)
			)
			(layer "F.Fab")
		)
		(fp_line
			(start -0.12065 -0.2794)
			(end 0.12065 -0.2794)
			(stroke
				(width 0.1)
				(type default)
			)
			(layer "F.Fab")
		)
		(fp_line
			(start -0.12065 0.2794)
			(end -0.12065 0.3048)
			(stroke
				(width 0.1)
				(type default)
			)
			(layer "F.Fab")
		)
		(fp_line
			(start -0.12065 0.3048)
			(end -0.67945 0.3048)
			(stroke
				(width 0.1)
				(type default)
			)
			(layer "F.Fab")
		)
		(fp_line
			(start 0.120396 0.2794)
			(end -0.12065 0.2794)
			(stroke
				(width 0.1)
				(type default)
			)
			(layer "F.Fab")
		)
		(fp_line
			(start 0.120396 0.3048)
			(end 0.120396 0.2794)
			(stroke
				(width 0.1)
				(type default)
			)
			(layer "F.Fab")
		)
		(fp_line
			(start 0.12065 -0.3048)
			(end 0.67945 -0.3048)
			(stroke
				(width 0.1)
				(type default)
			)
			(layer "F.Fab")
		)
		(fp_line
			(start 0.12065 -0.2794)
			(end 0.12065 -0.3048)
			(stroke
				(width 0.1)
				(type default)
			)
			(layer "F.Fab")
		)
		(fp_line
			(start 0.67945 -0.3048)
			(end 0.67945 0.3048)
			(stroke
				(width 0.1)
				(type default)
			)
			(layer "F.Fab")
		)
		(fp_line
			(start 0.67945 0.3048)
			(end 0.120396 0.3048)
			(stroke
				(width 0.1)
				(type default)
			)
			(layer "F.Fab")
		)
		(pad "1" smd circle
			(at -0.40005 0)
			(size 0 0)
			(layers "F.Cu" "F.Mask" "F.Paste")
			(net "SMB_ISO_SSD5_R_SCL")
		)
		(pad "2" smd circle
			(at 0.40005 0)
			(size 0 0)
			(layers "F.Cu" "F.Mask" "F.Paste")
			(net "SMB_ISO_SSD5_SCL")
		)
	)
	(footprint ""
		(layer "F.Cu")
		(at 282.39339 -172.004482 -90)
		(property "Reference" "U31"
			(at 1.722882 -2.44348 90)
			(unlocked yes)
			(layer "F.SilkS")
			(effects
				(font
					(size 0.7874 0.5842)
					(thickness 0.1524)
				)
				(justify left)
			)
		)
		(property "Value" ""
			(at 0 0 270)
			(layer "F.Fab")
			(effects
				(font
					(size 1.27 1.27)
				)
			)
		)
		(duplicate_pad_numbers_are_jumpers no)
		(fp_line
			(start -2.0574 1.651)
			(end -2.0574 -1.651)
			(stroke
				(width 0.1524)
				(type default)
			)
			(layer "F.SilkS")
		)
		(fp_line
			(start 2.0574 1.651)
			(end -2.0574 1.651)
			(stroke
				(width 0.1524)
				(type default)
			)
			(layer "F.SilkS")
		)
		(fp_line
			(start 0 -1.016)
			(end 0.381 -1.651)
			(stroke
				(width 0.1524)
				(type default)
			)
			(layer "F.SilkS")
		)
		(fp_line
			(start -2.0574 -1.651)
			(end -0.381 -1.651)
			(stroke
				(width 0.1524)
				(type default)
			)
			(layer "F.SilkS")
		)
		(fp_line
			(start -0.381 -1.651)
			(end 0 -1.016)
			(stroke
				(width 0.1524)
				(type default)
			)
			(layer "F.SilkS")
		)
		(fp_line
			(start 0.381 -1.651)
			(end 2.0574 -1.651)
			(stroke
				(width 0.1524)
				(type default)
			)
			(layer "F.SilkS")
		)
		(fp_line
			(start 2.0574 -1.651)
			(end 2.0574 1.651)
			(stroke
				(width 0.1524)
				(type default)
			)
			(layer "F.SilkS")
		)
		(fp_poly
			(pts
				(xy -2.71272 -0.719328) (xy -2.71272 -1.344168) (xy -2.159 -1.016)
			)
			(stroke
				(width 0)
				(type default)
			)
			(fill yes)
			(layer "F.SilkS")
		)
		(fp_line
			(start -0.899922 1.549908)
			(end -0.899922 1.199896)
			(stroke
				(width 0.1)
				(type default)
			)
			(layer "F.Fab")
		)
		(fp_line
			(start 0.899922 1.549908)
			(end -0.899922 1.549908)
			(stroke
				(width 0.1)
				(type default)
			)
			(layer "F.Fab")
		)
		(fp_line
			(start -1.599946 1.199896)
			(end -1.599946 -1.199896)
			(stroke
				(width 0.1)
				(type default)
			)
			(layer "F.Fab")
		)
		(fp_line
			(start -0.899922 1.199896)
			(end -1.599946 1.199896)
			(stroke
				(width 0.1)
				(type default)
			)
			(layer "F.Fab")
		)
		(fp_line
			(start 0.899922 1.199896)
			(end 0.899922 1.549908)
			(stroke
				(width 0.1)
				(type default)
			)
			(layer "F.Fab")
		)
		(fp_line
			(start 1.599946 1.199896)
			(end 0.899922 1.199896)
			(stroke
				(width 0.1)
				(type default)
			)
			(layer "F.Fab")
		)
		(fp_line
			(start -1.599946 -1.199896)
			(end -0.899922 -1.199896)
			(stroke
				(width 0.1)
				(type default)
			)
			(layer "F.Fab")
		)
		(fp_line
			(start -0.899922 -1.199896)
			(end -0.899922 -1.549908)
			(stroke
				(width 0.1)
				(type default)
			)
			(layer "F.Fab")
		)
		(fp_line
			(start 0.899922 -1.199896)
			(end 1.599946 -1.199896)
			(stroke
				(width 0.1)
				(type default)
			)
			(layer "F.Fab")
		)
		(fp_line
			(start 1.599946 -1.199896)
			(end 1.599946 1.199896)
			(stroke
				(width 0.1)
				(type default)
			)
			(layer "F.Fab")
		)
		(fp_line
			(start -0.899922 -1.549908)
			(end 0.899922 -1.549908)
			(stroke
				(width 0.1)
				(type default)
			)
			(layer "F.Fab")
		)
		(fp_line
			(start 0.899922 -1.549908)
			(end 0.899922 -1.199896)
			(stroke
				(width 0.1)
				(type default)
			)
			(layer "F.Fab")
		)
		(fp_poly
			(pts
				(xy -2.71272 -0.719328) (xy -2.71272 -1.344168) (xy -2.159 -1.016)
			)
			(stroke
				(width 0)
				(type default)
			)
			(fill yes)
			(layer "F.Fab")
		)
		(pad "1" smd rect
			(at -1.225042 -0.94996 180)
			(size 0.5588 1.3462)
			(layers "F.Cu" "F.Mask" "F.Paste")
			(net "HP_NIC4_PWRGD_R")
		)
		(pad "2" smd rect
			(at -1.225042 0 180)
			(size 0.5588 1.3462)
			(layers "F.Cu" "F.Mask" "F.Paste")
			(net "RST_NIC4_PERST_R_N")
		)
		(pad "3" smd rect
			(at -1.225042 0.94996 180)
			(size 0.5588 1.3462)
			(layers "F.Cu" "F.Mask" "F.Paste")
			(net "GND")
		)
		(pad "4" smd rect
			(at 1.225042 0.94996 180)
			(size 0.5588 1.3462)
			(layers "F.Cu" "F.Mask" "F.Paste")
			(net "RST_HP_NIC4_N")
		)
		(pad "5" smd rect
			(at 1.225042 -0.94996 180)
			(size 0.5588 1.3462)
			(layers "F.Cu" "F.Mask" "F.Paste")
			(net "P3V3_AUX")
		)
	)
	(footprint ""
		(layer "F.Cu")
		(at 34.502344 -252.356874 -90)
		(property "Reference" "R1233"
			(at 0 0 270)
			(layer "F.SilkS")
			(hide yes)
			(effects
				(font
					(size 1.27 1.27)
				)
			)
		)
		(property "Value" ""
			(at 0 0 270)
			(layer "F.Fab")
			(effects
				(font
					(size 1.27 1.27)
				)
			)
		)
		(duplicate_pad_numbers_are_jumpers no)
		(fp_line
			(start -0.7874 0.4064)
			(end -0.7874 -0.4064)
			(stroke
				(width 0.1524)
				(type default)
			)
			(layer "F.SilkS")
		)
		(fp_line
			(start 0.7874 0.4064)
			(end -0.7874 0.4064)
			(stroke
				(width 0.1524)
				(type default)
			)
			(layer "F.SilkS")
		)
		(fp_line
			(start -0.7874 -0.4064)
			(end 0.7874 -0.4064)
			(stroke
				(width 0.1524)
				(type default)
			)
			(layer "F.SilkS")
		)
		(fp_line
			(start 0.7874 -0.4064)
			(end 0.7874 0.4064)
			(stroke
				(width 0.1524)
				(type default)
			)
			(layer "F.SilkS")
		)
		(fp_line
			(start -0.67945 0.3048)
			(end -0.67945 -0.305054)
			(stroke
				(width 0.1)
				(type default)
			)
			(layer "F.Fab")
		)
		(fp_line
			(start -0.12065 0.3048)
			(end -0.67945 0.3048)
			(stroke
				(width 0.1)
				(type default)
			)
			(layer "F.Fab")
		)
		(fp_line
			(start 0.120396 0.3048)
			(end 0.120396 0.2794)
			(stroke
				(width 0.1)
				(type default)
			)
			(layer "F.Fab")
		)
		(fp_line
			(start 0.67945 0.3048)
			(end 0.120396 0.3048)
			(stroke
				(width 0.1)
				(type default)
			)
			(layer "F.Fab")
		)
		(fp_line
			(start -0.12065 0.2794)
			(end -0.12065 0.3048)
			(stroke
				(width 0.1)
				(type default)
			)
			(layer "F.Fab")
		)
		(fp_line
			(start 0.120396 0.2794)
			(end -0.12065 0.2794)
			(stroke
				(width 0.1)
				(type default)
			)
			(layer "F.Fab")
		)
		(fp_line
			(start -0.12065 -0.2794)
			(end 0.12065 -0.2794)
			(stroke
				(width 0.1)
				(type default)
			)
			(layer "F.Fab")
		)
		(fp_line
			(start 0.12065 -0.2794)
			(end 0.12065 -0.3048)
			(stroke
				(width 0.1)
				(type default)
			)
			(layer "F.Fab")
		)
		(fp_line
			(start 0.12065 -0.3048)
			(end 0.67945 -0.3048)
			(stroke
				(width 0.1)
				(type default)
			)
			(layer "F.Fab")
		)
		(fp_line
			(start 0.67945 -0.3048)
			(end 0.67945 0.3048)
			(stroke
				(width 0.1)
				(type default)
			)
			(layer "F.Fab")
		)
		(fp_line
			(start -0.67945 -0.305054)
			(end -0.12065 -0.305054)
			(stroke
				(width 0.1)
				(type default)
			)
			(layer "F.Fab")
		)
		(fp_line
			(start -0.12065 -0.305054)
			(end -0.12065 -0.2794)
			(stroke
				(width 0.1)
				(type default)
			)
			(layer "F.Fab")
		)
		(pad "1" smd circle
			(at -0.40005 0 270)
			(size 0 0)
			(layers "F.Cu" "F.Mask" "F.Paste")
			(net "GND")
		)
		(pad "2" smd circle
			(at 0.40005 0 270)
			(size 0 0)
			(layers "F.Cu" "F.Mask" "F.Paste")
			(net "PEX0_MODE_SEL11")
		)
	)
	(footprint ""
		(layer "F.Cu")
		(at 341.336884 -116.230654 90)
		(property "Reference" "R5967"
			(at 0 0 90)
			(layer "F.SilkS")
			(hide yes)
			(effects
				(font
					(size 1.27 1.27)
				)
			)
		)
		(property "Value" ""
			(at 0 0 90)
			(layer "F.Fab")
			(effects
				(font
					(size 1.27 1.27)
				)
			)
		)
		(duplicate_pad_numbers_are_jumpers no)
		(fp_line
			(start 0.7874 -0.4064)
			(end 0.7874 0.4064)
			(stroke
				(width 0.1524)
				(type default)
			)
			(layer "F.SilkS")
		)
		(fp_line
			(start -0.7874 -0.4064)
			(end 0.7874 -0.4064)
			(stroke
				(width 0.1524)
				(type default)
			)
			(layer "F.SilkS")
		)
		(fp_line
			(start 0.7874 0.4064)
			(end -0.7874 0.4064)
			(stroke
				(width 0.1524)
				(type default)
			)
			(layer "F.SilkS")
		)
		(fp_line
			(start -0.7874 0.4064)
			(end -0.7874 -0.4064)
			(stroke
				(width 0.1524)
				(type default)
			)
			(layer "F.SilkS")
		)
		(fp_line
			(start -0.12065 -0.305054)
			(end -0.12065 -0.2794)
			(stroke
				(width 0.1)
				(type default)
			)
			(layer "F.Fab")
		)
		(fp_line
			(start -0.67945 -0.305054)
			(end -0.12065 -0.305054)
			(stroke
				(width 0.1)
				(type default)
			)
			(layer "F.Fab")
		)
		(fp_line
			(start 0.67945 -0.3048)
			(end 0.67945 0.3048)
			(stroke
				(width 0.1)
				(type default)
			)
			(layer "F.Fab")
		)
		(fp_line
			(start 0.12065 -0.3048)
			(end 0.67945 -0.3048)
			(stroke
				(width 0.1)
				(type default)
			)
			(layer "F.Fab")
		)
		(fp_line
			(start 0.12065 -0.2794)
			(end 0.12065 -0.3048)
			(stroke
				(width 0.1)
				(type default)
			)
			(layer "F.Fab")
		)
		(fp_line
			(start -0.12065 -0.2794)
			(end 0.12065 -0.2794)
			(stroke
				(width 0.1)
				(type default)
			)
			(layer "F.Fab")
		)
		(fp_line
			(start 0.120396 0.2794)
			(end -0.12065 0.2794)
			(stroke
				(width 0.1)
				(type default)
			)
			(layer "F.Fab")
		)
		(fp_line
			(start -0.12065 0.2794)
			(end -0.12065 0.3048)
			(stroke
				(width 0.1)
				(type default)
			)
			(layer "F.Fab")
		)
		(fp_line
			(start 0.67945 0.3048)
			(end 0.120396 0.3048)
			(stroke
				(width 0.1)
				(type default)
			)
			(layer "F.Fab")
		)
		(fp_line
			(start 0.120396 0.3048)
			(end 0.120396 0.2794)
			(stroke
				(width 0.1)
				(type default)
			)
			(layer "F.Fab")
		)
		(fp_line
			(start -0.12065 0.3048)
			(end -0.67945 0.3048)
			(stroke
				(width 0.1)
				(type default)
			)
			(layer "F.Fab")
		)
		(fp_line
			(start -0.67945 0.3048)
			(end -0.67945 -0.305054)
			(stroke
				(width 0.1)
				(type default)
			)
			(layer "F.Fab")
		)
		(pad "1" smd circle
			(at -0.40005 0 90)
			(size 0 0)
			(layers "F.Cu" "F.Mask" "F.Paste")
			(net "PWRGD_P12V_NIC5_CO")
		)
		(pad "2" smd circle
			(at 0.40005 0 90)
			(size 0 0)
			(layers "F.Cu" "F.Mask" "F.Paste")
			(net "PWRGD_P12V_NIC5_R")
		)
	)
	(footprint ""
		(layer "F.Cu")
		(at 325.401178 -55.78475 -90)
		(property "Reference" "PD115"
			(at 3.86715 2.108708 90)
			(unlocked yes)
			(layer "F.SilkS")
			(effects
				(font
					(size 0.7874 0.5842)
					(thickness 0.1524)
				)
				(justify left)
			)
		)
		(property "Value" ""
			(at 0 0 270)
			(layer "F.Fab")
			(effects
				(font
					(size 1.27 1.27)
				)
			)
		)
		(duplicate_pad_numbers_are_jumpers no)
		(fp_line
			(start -3.400044 1.459992)
			(end -3.400044 -1.459992)
			(stroke
				(width 0.1524)
				(type default)
			)
			(layer "F.SilkS")
		)
		(fp_line
			(start 4.107942 1.459992)
			(end -3.400044 1.459992)
			(stroke
				(width 0.1524)
				(type default)
			)
			(layer "F.SilkS")
		)
		(fp_line
			(start -3.400044 -1.459992)
			(end 4.107942 -1.459992)
			(stroke
				(width 0.1524)
				(type default)
			)
			(layer "F.SilkS")
		)
		(fp_line
			(start 4.107942 -1.459992)
			(end 4.107942 1.459992)
			(stroke
				(width 0.1524)
				(type default)
			)
			(layer "F.SilkS")
		)
		(fp_poly
			(pts
				(xy 4.107942 -1.459992) (xy 4.107942 1.459992) (xy 3.308096 1.459992) (xy 3.308096 -1.459992)
			)
			(stroke
				(width 0)
				(type default)
			)
			(fill yes)
			(layer "F.SilkS")
		)
		(fp_line
			(start -2.29997 1.459992)
			(end -2.29997 -1.459992)
			(stroke
				(width 0.1)
				(type default)
			)
			(layer "F.Fab")
		)
		(fp_line
			(start 2.29997 1.459992)
			(end -2.29997 1.459992)
			(stroke
				(width 0.1)
				(type default)
			)
			(layer "F.Fab")
		)
		(fp_line
			(start -2.29997 -1.459992)
			(end 2.29997 -1.459992)
			(stroke
				(width 0.1)
				(type default)
			)
			(layer "F.Fab")
		)
		(fp_line
			(start 2.29997 -1.459992)
			(end 2.29997 1.459992)
			(stroke
				(width 0.1)
				(type default)
			)
			(layer "F.Fab")
		)
		(fp_text user "-"
			(at 5.4102 0.29845 90)
			(unlocked yes)
			(layer "F.SilkS")
			(effects
				(font
					(size 1.905 1.4224)
					(thickness 0.1524)
				)
				(justify left)
			)
		)
		(fp_text user "+"
			(at -4.7752 -0.12065 270)
			(unlocked yes)
			(layer "F.SilkS")
			(effects
				(font
					(size 1.905 1.4224)
					(thickness 0.1524)
				)
				(justify left)
			)
		)
		(fp_text user "-"
			(at 5.4102 0.29845 90)
			(unlocked yes)
			(layer "F.Fab")
			(effects
				(font
					(size 1.905 1.4224)
					(thickness 0.1524)
				)
				(justify left)
			)
		)
		(fp_text user "+"
			(at -4.7752 -0.12065 270)
			(unlocked yes)
			(layer "F.Fab")
			(effects
				(font
					(size 1.905 1.4224)
					(thickness 0.1524)
				)
				(justify left)
			)
		)
		(pad "A" smd rect
			(at -1.999996 0)
			(size 1.7018 2.5146)
			(layers "F.Cu" "F.Mask" "F.Paste")
			(net "GND")
		)
		(pad "C" smd rect
			(at 1.999996 0)
			(size 1.7018 2.5146)
			(layers "F.Cu" "F.Mask" "F.Paste")
			(net "P12V_SSD11_R")
		)
	)
	(footprint ""
		(layer "F.Cu")
		(at 371.14607 -46.4439 180)
		(property "Reference" "U75"
			(at 0.40767 -2.45237 0)
			(unlocked yes)
			(layer "F.SilkS")
			(effects
				(font
					(size 0.7874 0.5842)
					(thickness 0.1524)
				)
			)
		)
		(property "Value" ""
			(at 0 0 180)
			(layer "F.Fab")
			(effects
				(font
					(size 1.27 1.27)
				)
			)
		)
		(duplicate_pad_numbers_are_jumpers no)
		(fp_line
			(start 1.500124 1.500124)
			(end 1.004062 1.500124)
			(stroke
				(width 0.1524)
				(type default)
			)
			(layer "F.SilkS")
		)
		(fp_line
			(start 1.500124 1.004062)
			(end 1.500124 1.500124)
			(stroke
				(width 0.1524)
				(type default)
			)
			(layer "F.SilkS")
		)
		(fp_line
			(start 1.500124 -1.500124)
			(end 1.500124 -1.004062)
			(stroke
				(width 0.1524)
				(type default)
			)
			(layer "F.SilkS")
		)
		(fp_line
			(start 1.004062 -1.500124)
			(end 1.500124 -1.500124)
			(stroke
				(width 0.1524)
				(type default)
			)
			(layer "F.SilkS")
		)
		(fp_line
			(start -1.004062 1.500124)
			(end -1.500124 1.500124)
			(stroke
				(width 0.1524)
				(type default)
			)
			(layer "F.SilkS")
		)
		(fp_line
			(start -1.500124 1.500124)
			(end -1.500124 1.004062)
			(stroke
				(width 0.1524)
				(type default)
			)
			(layer "F.SilkS")
		)
		(fp_line
			(start -1.500124 -1.004062)
			(end -1.500124 -1.500124)
			(stroke
				(width 0.1524)
				(type default)
			)
			(layer "F.SilkS")
		)
		(fp_line
			(start -1.500124 -1.500124)
			(end -1.004062 -1.500124)
			(stroke
				(width 0.1524)
				(type default)
			)
			(layer "F.SilkS")
		)
		(fp_poly
			(pts
				(xy -1.957578 -2.17932) (xy -2.67589 -1.461008) (xy -1.598422 -1.101598)
			)
			(stroke
				(width 0)
				(type default)
			)
			(fill yes)
			(layer "F.SilkS")
		)
		(fp_line
			(start 1.500124 1.500124)
			(end -1.500124 1.500124)
			(stroke
				(width 0.1)
				(type default)
			)
			(layer "F.Fab")
		)
		(fp_line
			(start 1.500124 -1.500124)
			(end 1.500124 1.500124)
			(stroke
				(width 0.1)
				(type default)
			)
			(layer "F.Fab")
		)
		(fp_line
			(start -1.500124 1.500124)
			(end -1.500124 -1.500124)
			(stroke
				(width 0.1)
				(type default)
			)
			(layer "F.Fab")
		)
		(fp_line
			(start -1.500124 -1.500124)
			(end 1.500124 -1.500124)
			(stroke
				(width 0.1)
				(type default)
			)
			(layer "F.Fab")
		)
		(fp_poly
			(pts
				(xy -2.847848 -1.258062) (xy -2.847848 -0.242062) (xy -1.831848 -0.750062)
			)
			(stroke
				(width 0)
				(type default)
			)
			(fill yes)
			(layer "F.Fab")
		)
		(pad "1" smd rect
			(at -1.400048 -0.750062 90)
			(size 0.2286 0.6096)
			(layers "F.Cu" "F.Mask" "F.Paste")
			(net "SSD12_ADC_A1")
		)
		(pad "2" smd rect
			(at -1.400048 -0.249936 90)
			(size 0.2286 0.6096)
			(layers "F.Cu" "F.Mask" "F.Paste")
			(net "SSD12_ADC_A0")
		)
		(pad "3" smd rect
			(at -1.400048 0.249936 90)
			(size 0.2286 0.6096)
			(layers "F.Cu" "F.Mask" "F.Paste")
			(net "SSD12_ADC_ALERT_N")
		)
		(pad "4" smd rect
			(at -1.400048 0.750062 90)
			(size 0.2286 0.6096)
			(layers "F.Cu" "F.Mask" "F.Paste")
			(net "SMB_SSD12_ADC_SDA")
		)
		(pad "5" smd rect
			(at -0.750062 1.400048 180)
			(size 0.2286 0.6096)
			(layers "F.Cu" "F.Mask" "F.Paste")
			(net "SMB_SSD12_ADC_SCL")
		)
		(pad "6" smd rect
			(at -0.249936 1.400048 180)
			(size 0.2286 0.6096)
			(layers "F.Cu" "F.Mask" "F.Paste")
			(net "Net_8690")
		)
		(pad "7" smd rect
			(at 0.249936 1.400048 180)
			(size 0.2286 0.6096)
			(layers "F.Cu" "F.Mask" "F.Paste")
			(net "Net_8689")
		)
		(pad "8" smd rect
			(at 0.750062 1.400048 180)
			(size 0.2286 0.6096)
			(layers "F.Cu" "F.Mask" "F.Paste")
			(net "Net_8688")
		)
		(pad "9" smd rect
			(at 1.400048 0.750062 90)
			(size 0.2286 0.6096)
			(layers "F.Cu" "F.Mask" "F.Paste")
			(net "P3V3_AUX")
		)
		(pad "10" smd rect
			(at 1.400048 0.249936 90)
			(size 0.2286 0.6096)
			(layers "F.Cu" "F.Mask" "F.Paste")
			(net "GND")
		)
		(pad "11" smd rect
			(at 1.400048 -0.249936 90)
			(size 0.2286 0.6096)
			(layers "F.Cu" "F.Mask" "F.Paste")
			(net "P12V_SSD12_R")
		)
		(pad "12" smd rect
			(at 1.400048 -0.750062 90)
			(size 0.2286 0.6096)
			(layers "F.Cu" "F.Mask" "F.Paste")
			(net "P12V_SSD12_VIN_N")
		)
		(pad "13" smd rect
			(at 0.750062 -1.400048 180)
			(size 0.2286 0.6096)
			(layers "F.Cu" "F.Mask" "F.Paste")
			(net "P12V_SSD12_VIN_P")
		)
		(pad "14" smd rect
			(at 0.249936 -1.400048 180)
			(size 0.2286 0.6096)
			(layers "F.Cu" "F.Mask" "F.Paste")
			(net "Net_8687")
		)
		(pad "15" smd rect
			(at -0.249936 -1.400048 180)
			(size 0.2286 0.6096)
			(layers "F.Cu" "F.Mask" "F.Paste")
			(net "Net_8686")
		)
		(pad "16" smd rect
			(at -0.750062 -1.400048 180)
			(size 0.2286 0.6096)
			(layers "F.Cu" "F.Mask" "F.Paste")
			(net "Net_8685")
		)
		(pad "TH" smd rect
			(at 0 0 180)
			(size 1.7018 1.7018)
			(layers "F.Cu" "F.Mask" "F.Paste")
			(net "GND")
		)
		(zone
			(layer "F.Cu")
			(hatch none 0.5)
			(connect_pads
				(clearance 0)
			)
			(min_thickness 0.25)
			(keepout
				(tracks not_allowed)
				(vias allowed)
				(pads allowed)
				(copperpour not_allowed)
				(footprints allowed)
			)
			(placement
				(enabled no)
				(sheetname "")
			)
			(fill
				(thermal_gap 0.5)
				(thermal_bridge_width 0.5)
				(island_removal_mode 0)
			)
			(polygon
				(pts
					(xy 372.190518 -46.4185) (xy 372.190518 -45.399452) (xy 370.101622 -45.399452) (xy 370.101622 -47.488348)
					(xy 372.190518 -47.488348) (xy 372.190518 -46.4439) (xy 372.04777 -46.4439) (xy 372.04777 -47.3456)
					(xy 370.24437 -47.3456) (xy 370.24437 -45.5422) (xy 372.04777 -45.5422) (xy 372.04777 -46.4185)
				)
			)
		)
	)
	(footprint ""
		(layer "F.Cu")
		(at 224.856294 -182.51678 180)
		(property "Reference" "R5491"
			(at 0 0 180)
			(layer "F.SilkS")
			(hide yes)
			(effects
				(font
					(size 1.27 1.27)
				)
			)
		)
		(property "Value" ""
			(at 0 0 180)
			(layer "F.Fab")
			(effects
				(font
					(size 1.27 1.27)
				)
			)
		)
		(duplicate_pad_numbers_are_jumpers no)
		(fp_line
			(start 0.7874 0.4064)
			(end -0.7874 0.4064)
			(stroke
				(width 0.1524)
				(type default)
			)
			(layer "F.SilkS")
		)
		(fp_line
			(start 0.7874 -0.4064)
			(end 0.7874 0.4064)
			(stroke
				(width 0.1524)
				(type default)
			)
			(layer "F.SilkS")
		)
		(fp_line
			(start -0.7874 0.4064)
			(end -0.7874 -0.4064)
			(stroke
				(width 0.1524)
				(type default)
			)
			(layer "F.SilkS")
		)
		(fp_line
			(start -0.7874 -0.4064)
			(end 0.7874 -0.4064)
			(stroke
				(width 0.1524)
				(type default)
			)
			(layer "F.SilkS")
		)
		(fp_line
			(start 0.67945 0.3048)
			(end 0.120396 0.3048)
			(stroke
				(width 0.1)
				(type default)
			)
			(layer "F.Fab")
		)
		(fp_line
			(start 0.67945 -0.3048)
			(end 0.67945 0.3048)
			(stroke
				(width 0.1)
				(type default)
			)
			(layer "F.Fab")
		)
		(fp_line
			(start 0.12065 -0.2794)
			(end 0.12065 -0.3048)
			(stroke
				(width 0.1)
				(type default)
			)
			(layer "F.Fab")
		)
		(fp_line
			(start 0.12065 -0.3048)
			(end 0.67945 -0.3048)
			(stroke
				(width 0.1)
				(type default)
			)
			(layer "F.Fab")
		)
		(fp_line
			(start 0.120396 0.3048)
			(end 0.120396 0.2794)
			(stroke
				(width 0.1)
				(type default)
			)
			(layer "F.Fab")
		)
		(fp_line
			(start 0.120396 0.2794)
			(end -0.12065 0.2794)
			(stroke
				(width 0.1)
				(type default)
			)
			(layer "F.Fab")
		)
		(fp_line
			(start -0.12065 0.3048)
			(end -0.67945 0.3048)
			(stroke
				(width 0.1)
				(type default)
			)
			(layer "F.Fab")
		)
		(fp_line
			(start -0.12065 0.2794)
			(end -0.12065 0.3048)
			(stroke
				(width 0.1)
				(type default)
			)
			(layer "F.Fab")
		)
		(fp_line
			(start -0.12065 -0.2794)
			(end 0.12065 -0.2794)
			(stroke
				(width 0.1)
				(type default)
			)
			(layer "F.Fab")
		)
		(fp_line
			(start -0.12065 -0.305054)
			(end -0.12065 -0.2794)
			(stroke
				(width 0.1)
				(type default)
			)
			(layer "F.Fab")
		)
		(fp_line
			(start -0.67945 0.3048)
			(end -0.67945 -0.305054)
			(stroke
				(width 0.1)
				(type default)
			)
			(layer "F.Fab")
		)
		(fp_line
			(start -0.67945 -0.305054)
			(end -0.12065 -0.305054)
			(stroke
				(width 0.1)
				(type default)
			)
			(layer "F.Fab")
		)
		(pad "1" smd circle
			(at -0.40005 0 180)
			(size 0 0)
			(layers "F.Cu" "F.Mask" "F.Paste")
			(net "P3V3_AUX")
		)
		(pad "2" smd circle
			(at 0.40005 0 180)
			(size 0 0)
			(layers "F.Cu" "F.Mask" "F.Paste")
			(net "RST_BIC_BUF_RSMRST_N_BUF")
		)
	)
	(footprint ""
		(layer "F.Cu")
		(at 336.042 -174.117)
		(property "Reference" "R4738"
			(at 0 0 0)
			(layer "F.SilkS")
			(hide yes)
			(effects
				(font
					(size 1.27 1.27)
				)
			)
		)
		(property "Value" ""
			(at 0 0 0)
			(layer "F.Fab")
			(effects
				(font
					(size 1.27 1.27)
				)
			)
		)
		(duplicate_pad_numbers_are_jumpers no)
		(fp_line
			(start -0.7874 -0.4064)
			(end 0.7874 -0.4064)
			(stroke
				(width 0.1524)
				(type default)
			)
			(layer "F.SilkS")
		)
		(fp_line
			(start -0.7874 0.4064)
			(end -0.7874 -0.4064)
			(stroke
				(width 0.1524)
				(type default)
			)
			(layer "F.SilkS")
		)
		(fp_line
			(start 0.7874 -0.4064)
			(end 0.7874 0.4064)
			(stroke
				(width 0.1524)
				(type default)
			)
			(layer "F.SilkS")
		)
		(fp_line
			(start 0.7874 0.4064)
			(end -0.7874 0.4064)
			(stroke
				(width 0.1524)
				(type default)
			)
			(layer "F.SilkS")
		)
		(fp_line
			(start -0.67945 -0.305054)
			(end -0.12065 -0.305054)
			(stroke
				(width 0.1)
				(type default)
			)
			(layer "F.Fab")
		)
		(fp_line
			(start -0.67945 0.3048)
			(end -0.67945 -0.305054)
			(stroke
				(width 0.1)
				(type default)
			)
			(layer "F.Fab")
		)
		(fp_line
			(start -0.12065 -0.305054)
			(end -0.12065 -0.2794)
			(stroke
				(width 0.1)
				(type default)
			)
			(layer "F.Fab")
		)
		(fp_line
			(start -0.12065 -0.2794)
			(end 0.12065 -0.2794)
			(stroke
				(width 0.1)
				(type default)
			)
			(layer "F.Fab")
		)
		(fp_line
			(start -0.12065 0.2794)
			(end -0.12065 0.3048)
			(stroke
				(width 0.1)
				(type default)
			)
			(layer "F.Fab")
		)
		(fp_line
			(start -0.12065 0.3048)
			(end -0.67945 0.3048)
			(stroke
				(width 0.1)
				(type default)
			)
			(layer "F.Fab")
		)
		(fp_line
			(start 0.120396 0.2794)
			(end -0.12065 0.2794)
			(stroke
				(width 0.1)
				(type default)
			)
			(layer "F.Fab")
		)
		(fp_line
			(start 0.120396 0.3048)
			(end 0.120396 0.2794)
			(stroke
				(width 0.1)
				(type default)
			)
			(layer "F.Fab")
		)
		(fp_line
			(start 0.12065 -0.3048)
			(end 0.67945 -0.3048)
			(stroke
				(width 0.1)
				(type default)
			)
			(layer "F.Fab")
		)
		(fp_line
			(start 0.12065 -0.2794)
			(end 0.12065 -0.3048)
			(stroke
				(width 0.1)
				(type default)
			)
			(layer "F.Fab")
		)
		(fp_line
			(start 0.67945 -0.3048)
			(end 0.67945 0.3048)
			(stroke
				(width 0.1)
				(type default)
			)
			(layer "F.Fab")
		)
		(fp_line
			(start 0.67945 0.3048)
			(end 0.120396 0.3048)
			(stroke
				(width 0.1)
				(type default)
			)
			(layer "F.Fab")
		)
		(pad "1" smd circle
			(at -0.40005 0)
			(size 0 0)
			(layers "F.Cu" "F.Mask" "F.Paste")
			(net "PEX2_PCA9555_INT_N")
		)
		(pad "2" smd circle
			(at 0.40005 0)
			(size 0 0)
			(layers "F.Cu" "F.Mask" "F.Paste")
			(net "PEX2_PCA9555_1_INT_N")
		)
	)
	(footprint ""
		(layer "F.Cu")
		(at 104.851454 -99.177602 -90)
		(property "Reference" "PD12"
			(at 4.334002 -2.693416 90)
			(unlocked yes)
			(layer "F.SilkS")
			(effects
				(font
					(size 0.7874 0.5842)
					(thickness 0.1524)
				)
				(justify left)
			)
		)
		(property "Value" ""
			(at 0 0 270)
			(layer "F.Fab")
			(effects
				(font
					(size 1.27 1.27)
				)
			)
		)
		(duplicate_pad_numbers_are_jumpers no)
		(fp_line
			(start -3.656584 1.970024)
			(end 4.240784 1.970024)
			(stroke
				(width 0.1524)
				(type default)
			)
			(layer "F.SilkS")
		)
		(fp_line
			(start 4.240784 1.970024)
			(end 4.240784 -1.970024)
			(stroke
				(width 0.1524)
				(type default)
			)
			(layer "F.SilkS")
		)
		(fp_line
			(start -3.656584 -1.970024)
			(end -3.656584 1.970024)
			(stroke
				(width 0.1524)
				(type default)
			)
			(layer "F.SilkS")
		)
		(fp_line
			(start 4.240784 -1.970024)
			(end -3.656584 -1.970024)
			(stroke
				(width 0.1524)
				(type default)
			)
			(layer "F.SilkS")
		)
		(fp_rect
			(start 4.240784 1.970024)
			(end 3.580384 -1.970024)
			(stroke
				(width 0)
				(type default)
			)
			(fill yes)
			(layer "F.SilkS")
		)
		(fp_line
			(start -2.3749 1.970024)
			(end 2.3749 1.970024)
			(stroke
				(width 0.1)
				(type default)
			)
			(layer "F.Fab")
		)
		(fp_line
			(start 2.3749 1.970024)
			(end 2.3749 -1.970024)
			(stroke
				(width 0.1)
				(type default)
			)
			(layer "F.Fab")
		)
		(fp_line
			(start -2.3749 -1.970024)
			(end -2.3749 1.970024)
			(stroke
				(width 0.1)
				(type default)
			)
			(layer "F.Fab")
		)
		(fp_line
			(start 2.3749 -1.970024)
			(end -2.3749 -1.970024)
			(stroke
				(width 0.1)
				(type default)
			)
			(layer "F.Fab")
		)
		(fp_text user "+"
			(at -4.9784 -0.23495 270)
			(unlocked yes)
			(layer "F.Fab")
			(effects
				(font
					(size 1.905 1.4224)
					(thickness 0.1524)
				)
				(justify left)
			)
		)
		(fp_text user "-"
			(at 4.1656 -0.23495 270)
			(unlocked yes)
			(layer "F.Fab")
			(effects
				(font
					(size 1.905 1.4224)
					(thickness 0.1524)
				)
				(justify left)
			)
		)
		(pad "A" smd rect
			(at -2.450084 0 270)
			(size 2.159 2.2606)
			(layers "F.Cu" "F.Mask" "F.Paste")
			(net "GND")
		)
		(pad "C" smd rect
			(at 2.450084 0 270)
			(size 2.159 2.2606)
			(layers "F.Cu" "F.Mask" "F.Paste")
			(net "P12V_AUX")
		)
	)
	(footprint ""
		(layer "F.Cu")
		(at 14.207998 -170.632628 180)
		(property "Reference" "PL2"
			(at 3.438398 -4.162298 0)
			(unlocked yes)
			(layer "F.SilkS")
			(effects
				(font
					(size 0.7874 0.5842)
					(thickness 0.1524)
				)
				(justify left)
			)
		)
		(property "Value" ""
			(at 0 0 180)
			(layer "F.Fab")
			(effects
				(font
					(size 1.27 1.27)
				)
			)
		)
		(duplicate_pad_numbers_are_jumpers no)
		(fp_line
			(start 3.400044 3.400044)
			(end -3.400044 3.400044)
			(stroke
				(width 0.1524)
				(type default)
			)
			(layer "F.SilkS")
		)
		(fp_line
			(start 3.400044 1.8923)
			(end 3.400044 3.400044)
			(stroke
				(width 0.1524)
				(type default)
			)
			(layer "F.SilkS")
		)
		(fp_line
			(start 3.400044 -3.400044)
			(end 3.400044 -1.8923)
			(stroke
				(width 0.1524)
				(type default)
			)
			(layer "F.SilkS")
		)
		(fp_line
			(start -3.400044 3.400044)
			(end -3.400044 1.8923)
			(stroke
				(width 0.1524)
				(type default)
			)
			(layer "F.SilkS")
		)
		(fp_line
			(start -3.400044 -1.8923)
			(end -3.400044 -3.400044)
			(stroke
				(width 0.1524)
				(type default)
			)
			(layer "F.SilkS")
		)
		(fp_line
			(start -3.400044 -3.400044)
			(end 3.400044 -3.400044)
			(stroke
				(width 0.1524)
				(type default)
			)
			(layer "F.SilkS")
		)
		(fp_line
			(start 3.400044 3.400044)
			(end -3.400044 3.400044)
			(stroke
				(width 0.1)
				(type default)
			)
			(layer "F.Fab")
		)
		(fp_line
			(start 3.400044 -3.400044)
			(end 3.400044 3.400044)
			(stroke
				(width 0.1)
				(type default)
			)
			(layer "F.Fab")
		)
		(fp_line
			(start -3.400044 3.400044)
			(end -3.400044 -3.400044)
			(stroke
				(width 0.1)
				(type default)
			)
			(layer "F.Fab")
		)
		(fp_line
			(start -3.400044 -3.400044)
			(end 3.400044 -3.400044)
			(stroke
				(width 0.1)
				(type default)
			)
			(layer "F.Fab")
		)
		(pad "1" smd rect
			(at -2.77495 0 180)
			(size 1.8542 3.5052)
			(layers "F.Cu" "F.Mask" "F.Paste")
			(net "SW_P5V_AUX_PH")
		)
		(pad "2" smd rect
			(at 2.77495 0 180)
			(size 1.8542 3.5052)
			(layers "F.Cu" "F.Mask" "F.Paste")
			(net "P5V_AUX")
		)
	)
	(footprint ""
		(layer "F.Cu")
		(at 215.075516 -119.223028)
		(property "Reference" "R4480"
			(at 0 0 0)
			(layer "F.SilkS")
			(hide yes)
			(effects
				(font
					(size 1.27 1.27)
				)
			)
		)
		(property "Value" ""
			(at 0 0 0)
			(layer "F.Fab")
			(effects
				(font
					(size 1.27 1.27)
				)
			)
		)
		(duplicate_pad_numbers_are_jumpers no)
		(fp_line
			(start -0.7874 -0.4064)
			(end 0.7874 -0.4064)
			(stroke
				(width 0.1524)
				(type default)
			)
			(layer "F.SilkS")
		)
		(fp_line
			(start -0.7874 0.4064)
			(end -0.7874 -0.4064)
			(stroke
				(width 0.1524)
				(type default)
			)
			(layer "F.SilkS")
		)
		(fp_line
			(start 0.7874 -0.4064)
			(end 0.7874 0.4064)
			(stroke
				(width 0.1524)
				(type default)
			)
			(layer "F.SilkS")
		)
		(fp_line
			(start 0.7874 0.4064)
			(end -0.7874 0.4064)
			(stroke
				(width 0.1524)
				(type default)
			)
			(layer "F.SilkS")
		)
		(fp_line
			(start -0.67945 -0.305054)
			(end -0.12065 -0.305054)
			(stroke
				(width 0.1)
				(type default)
			)
			(layer "F.Fab")
		)
		(fp_line
			(start -0.67945 0.3048)
			(end -0.67945 -0.305054)
			(stroke
				(width 0.1)
				(type default)
			)
			(layer "F.Fab")
		)
		(fp_line
			(start -0.12065 -0.305054)
			(end -0.12065 -0.2794)
			(stroke
				(width 0.1)
				(type default)
			)
			(layer "F.Fab")
		)
		(fp_line
			(start -0.12065 -0.2794)
			(end 0.12065 -0.2794)
			(stroke
				(width 0.1)
				(type default)
			)
			(layer "F.Fab")
		)
		(fp_line
			(start -0.12065 0.2794)
			(end -0.12065 0.3048)
			(stroke
				(width 0.1)
				(type default)
			)
			(layer "F.Fab")
		)
		(fp_line
			(start -0.12065 0.3048)
			(end -0.67945 0.3048)
			(stroke
				(width 0.1)
				(type default)
			)
			(layer "F.Fab")
		)
		(fp_line
			(start 0.120396 0.2794)
			(end -0.12065 0.2794)
			(stroke
				(width 0.1)
				(type default)
			)
			(layer "F.Fab")
		)
		(fp_line
			(start 0.120396 0.3048)
			(end 0.120396 0.2794)
			(stroke
				(width 0.1)
				(type default)
			)
			(layer "F.Fab")
		)
		(fp_line
			(start 0.12065 -0.3048)
			(end 0.67945 -0.3048)
			(stroke
				(width 0.1)
				(type default)
			)
			(layer "F.Fab")
		)
		(fp_line
			(start 0.12065 -0.2794)
			(end 0.12065 -0.3048)
			(stroke
				(width 0.1)
				(type default)
			)
			(layer "F.Fab")
		)
		(fp_line
			(start 0.67945 -0.3048)
			(end 0.67945 0.3048)
			(stroke
				(width 0.1)
				(type default)
			)
			(layer "F.Fab")
		)
		(fp_line
			(start 0.67945 0.3048)
			(end 0.120396 0.3048)
			(stroke
				(width 0.1)
				(type default)
			)
			(layer "F.Fab")
		)
		(pad "1" smd circle
			(at -0.40005 0)
			(size 0 0)
			(layers "F.Cu" "F.Mask" "F.Paste")
			(net "PWRGD_P3V3_NIC3")
		)
		(pad "2" smd circle
			(at 0.40005 0)
			(size 0 0)
			(layers "F.Cu" "F.Mask" "F.Paste")
			(net "PWRGD_P3V3_NIC3_R")
		)
	)
	(footprint ""
		(layer "F.Cu")
		(at 425.407582 -81.09966)
		(property "Reference" "Q8"
			(at -1.989582 -1.75387 0)
			(unlocked yes)
			(layer "F.SilkS")
			(effects
				(font
					(size 0.7874 0.5842)
					(thickness 0.1524)
				)
				(justify left)
			)
		)
		(property "Value" ""
			(at 0 0 0)
			(layer "F.Fab")
			(effects
				(font
					(size 1.27 1.27)
				)
			)
		)
		(duplicate_pad_numbers_are_jumpers no)
		(fp_line
			(start -1.38176 -1.100074)
			(end -1.38176 1.100074)
			(stroke
				(width 0.1524)
				(type default)
			)
			(layer "F.SilkS")
		)
		(fp_line
			(start -1.38176 1.100074)
			(end 1.38176 1.100074)
			(stroke
				(width 0.1524)
				(type default)
			)
			(layer "F.SilkS")
		)
		(fp_line
			(start -0.592074 -1.100074)
			(end -1.38176 -1.100074)
			(stroke
				(width 0.1524)
				(type default)
			)
			(layer "F.SilkS")
		)
		(fp_line
			(start 0 -0.508)
			(end -0.592074 -1.100074)
			(stroke
				(width 0.1524)
				(type default)
			)
			(layer "F.SilkS")
		)
		(fp_line
			(start 0.592074 -1.100074)
			(end 0 -0.508)
			(stroke
				(width 0.1524)
				(type default)
			)
			(layer "F.SilkS")
		)
		(fp_line
			(start 1.38176 -1.100074)
			(end 0.592074 -1.100074)
			(stroke
				(width 0.1524)
				(type default)
			)
			(layer "F.SilkS")
		)
		(fp_line
			(start 1.38176 1.100074)
			(end 1.38176 -1.100074)
			(stroke
				(width 0.1524)
				(type default)
			)
			(layer "F.SilkS")
		)
		(fp_poly
			(pts
				(xy -1.9431 -0.870204) (xy -1.50241 -0.649986) (xy -1.9431 -0.429768)
			)
			(stroke
				(width 0)
				(type default)
			)
			(fill yes)
			(layer "F.SilkS")
		)
		(fp_line
			(start -0.674878 -1.100074)
			(end -0.674878 1.100074)
			(stroke
				(width 0.1)
				(type default)
			)
			(layer "F.Fab")
		)
		(fp_line
			(start -0.674878 1.100074)
			(end 0.674878 1.100074)
			(stroke
				(width 0.1)
				(type default)
			)
			(layer "F.Fab")
		)
		(fp_line
			(start 0.674878 -1.100074)
			(end -0.674878 -1.100074)
			(stroke
				(width 0.1)
				(type default)
			)
			(layer "F.Fab")
		)
		(fp_line
			(start 0.674878 1.100074)
			(end 0.674878 -1.100074)
			(stroke
				(width 0.1)
				(type default)
			)
			(layer "F.Fab")
		)
		(fp_poly
			(pts
				(xy -1.9431 -0.870204) (xy -1.50241 -0.649986) (xy -1.9431 -0.429768)
			)
			(stroke
				(width 0)
				(type default)
			)
			(fill yes)
			(layer "F.Fab")
		)
		(pad "1" smd rect
			(at -0.94996 -0.649986 270)
			(size 0.4318 0.6096)
			(layers "F.Cu" "F.Mask" "F.Paste")
			(net "GND")
		)
		(pad "2" smd rect
			(at -0.94996 0 270)
			(size 0.4318 0.6096)
			(layers "F.Cu" "F.Mask" "F.Paste")
			(net "HP_NIC7_HSC_PWRGD_N")
		)
		(pad "3" smd rect
			(at -0.94996 0.649986 270)
			(size 0.4318 0.6096)
			(layers "F.Cu" "F.Mask" "F.Paste")
			(net "HP_NIC7_HSC_PWRGD_N")
		)
		(pad "4" smd rect
			(at 0.94996 0.649986 270)
			(size 0.4318 0.6096)
			(layers "F.Cu" "F.Mask" "F.Paste")
			(net "GND")
		)
		(pad "5" smd rect
			(at 0.94996 0 270)
			(size 0.4318 0.6096)
			(layers "F.Cu" "F.Mask" "F.Paste")
			(net "PWRGD_P12V_NIC7_R")
		)
		(pad "6" smd rect
			(at 0.94996 -0.649986 270)
			(size 0.4318 0.6096)
			(layers "F.Cu" "F.Mask" "F.Paste")
			(net "HP_NIC7_PWRGD_R")
		)
	)
	(footprint ""
		(layer "F.Cu")
		(at 159.892492 -31.825184 180)
		(property "Reference" "C287"
			(at 0 0 180)
			(layer "F.SilkS")
			(hide yes)
			(effects
				(font
					(size 1.27 1.27)
				)
			)
		)
		(property "Value" ""
			(at 0 0 180)
			(layer "F.Fab")
			(effects
				(font
					(size 1.27 1.27)
				)
			)
		)
		(duplicate_pad_numbers_are_jumpers no)
		(fp_line
			(start 0.299974 0.150114)
			(end -0.299974 0.150114)
			(stroke
				(width 0.1)
				(type default)
			)
			(layer "F.Fab")
		)
		(fp_line
			(start 0.299974 -0.150114)
			(end 0.299974 0.150114)
			(stroke
				(width 0.1)
				(type default)
			)
			(layer "F.Fab")
		)
		(fp_line
			(start -0.299974 0.150114)
			(end -0.299974 -0.150114)
			(stroke
				(width 0.1)
				(type default)
			)
			(layer "F.Fab")
		)
		(fp_line
			(start -0.299974 -0.150114)
			(end 0.299974 -0.150114)
			(stroke
				(width 0.1)
				(type default)
			)
			(layer "F.Fab")
		)
		(pad "1" smd rect
			(at -0.2667 0 180)
			(size 0.3048 0.381)
			(layers "F.Cu" "F.Mask" "F.Paste")
			(net "P5E_PEX1_STN2_TX_DN<42>")
		)
		(pad "2" smd rect
			(at 0.2667 0 180)
			(size 0.3048 0.381)
			(layers "F.Cu" "F.Mask" "F.Paste")
			(net "P5E_PEX1_STN2_TX_C_DN<42>")
		)
	)
	(footprint ""
		(layer "F.Cu")
		(at 295.670732 -138.864848)
		(property "Reference" "R295"
			(at 0 0 0)
			(layer "F.SilkS")
			(hide yes)
			(effects
				(font
					(size 1.27 1.27)
				)
			)
		)
		(property "Value" ""
			(at 0 0 0)
			(layer "F.Fab")
			(effects
				(font
					(size 1.27 1.27)
				)
			)
		)
		(duplicate_pad_numbers_are_jumpers no)
		(fp_line
			(start -0.7874 -0.4064)
			(end 0.7874 -0.4064)
			(stroke
				(width 0.1524)
				(type default)
			)
			(layer "F.SilkS")
		)
		(fp_line
			(start -0.7874 0.4064)
			(end -0.7874 -0.4064)
			(stroke
				(width 0.1524)
				(type default)
			)
			(layer "F.SilkS")
		)
		(fp_line
			(start 0.7874 -0.4064)
			(end 0.7874 0.4064)
			(stroke
				(width 0.1524)
				(type default)
			)
			(layer "F.SilkS")
		)
		(fp_line
			(start 0.7874 0.4064)
			(end -0.7874 0.4064)
			(stroke
				(width 0.1524)
				(type default)
			)
			(layer "F.SilkS")
		)
		(fp_line
			(start -0.67945 -0.305054)
			(end -0.12065 -0.305054)
			(stroke
				(width 0.1)
				(type default)
			)
			(layer "F.Fab")
		)
		(fp_line
			(start -0.67945 0.3048)
			(end -0.67945 -0.305054)
			(stroke
				(width 0.1)
				(type default)
			)
			(layer "F.Fab")
		)
		(fp_line
			(start -0.12065 -0.305054)
			(end -0.12065 -0.2794)
			(stroke
				(width 0.1)
				(type default)
			)
			(layer "F.Fab")
		)
		(fp_line
			(start -0.12065 -0.2794)
			(end 0.12065 -0.2794)
			(stroke
				(width 0.1)
				(type default)
			)
			(layer "F.Fab")
		)
		(fp_line
			(start -0.12065 0.2794)
			(end -0.12065 0.3048)
			(stroke
				(width 0.1)
				(type default)
			)
			(layer "F.Fab")
		)
		(fp_line
			(start -0.12065 0.3048)
			(end -0.67945 0.3048)
			(stroke
				(width 0.1)
				(type default)
			)
			(layer "F.Fab")
		)
		(fp_line
			(start 0.120396 0.2794)
			(end -0.12065 0.2794)
			(stroke
				(width 0.1)
				(type default)
			)
			(layer "F.Fab")
		)
		(fp_line
			(start 0.120396 0.3048)
			(end 0.120396 0.2794)
			(stroke
				(width 0.1)
				(type default)
			)
			(layer "F.Fab")
		)
		(fp_line
			(start 0.12065 -0.3048)
			(end 0.67945 -0.3048)
			(stroke
				(width 0.1)
				(type default)
			)
			(layer "F.Fab")
		)
		(fp_line
			(start 0.12065 -0.2794)
			(end 0.12065 -0.3048)
			(stroke
				(width 0.1)
				(type default)
			)
			(layer "F.Fab")
		)
		(fp_line
			(start 0.67945 -0.3048)
			(end 0.67945 0.3048)
			(stroke
				(width 0.1)
				(type default)
			)
			(layer "F.Fab")
		)
		(fp_line
			(start 0.67945 0.3048)
			(end 0.120396 0.3048)
			(stroke
				(width 0.1)
				(type default)
			)
			(layer "F.Fab")
		)
		(pad "1" smd circle
			(at -0.40005 0)
			(size 0 0)
			(layers "F.Cu" "F.Mask" "F.Paste")
			(net "PRSNT_NIC5_N")
		)
		(pad "2" smd circle
			(at 0.40005 0)
			(size 0 0)
			(layers "F.Cu" "F.Mask" "F.Paste")
			(net "PRSNTB1_NIC5_N")
		)
	)
	(footprint ""
		(layer "F.Cu")
		(at 322.65366 -232.397046)
		(property "Reference" "R5647"
			(at 0 0 0)
			(layer "F.SilkS")
			(hide yes)
			(effects
				(font
					(size 1.27 1.27)
				)
			)
		)
		(property "Value" ""
			(at 0 0 0)
			(layer "F.Fab")
			(effects
				(font
					(size 1.27 1.27)
				)
			)
		)
		(duplicate_pad_numbers_are_jumpers no)
		(fp_line
			(start -0.7874 -0.4064)
			(end 0.7874 -0.4064)
			(stroke
				(width 0.1524)
				(type default)
			)
			(layer "F.SilkS")
		)
		(fp_line
			(start -0.7874 0.4064)
			(end -0.7874 -0.4064)
			(stroke
				(width 0.1524)
				(type default)
			)
			(layer "F.SilkS")
		)
		(fp_line
			(start 0.7874 -0.4064)
			(end 0.7874 0.4064)
			(stroke
				(width 0.1524)
				(type default)
			)
			(layer "F.SilkS")
		)
		(fp_line
			(start 0.7874 0.4064)
			(end -0.7874 0.4064)
			(stroke
				(width 0.1524)
				(type default)
			)
			(layer "F.SilkS")
		)
		(fp_line
			(start -0.67945 -0.305054)
			(end -0.12065 -0.305054)
			(stroke
				(width 0.1)
				(type default)
			)
			(layer "F.Fab")
		)
		(fp_line
			(start -0.67945 0.3048)
			(end -0.67945 -0.305054)
			(stroke
				(width 0.1)
				(type default)
			)
			(layer "F.Fab")
		)
		(fp_line
			(start -0.12065 -0.305054)
			(end -0.12065 -0.2794)
			(stroke
				(width 0.1)
				(type default)
			)
			(layer "F.Fab")
		)
		(fp_line
			(start -0.12065 -0.2794)
			(end 0.12065 -0.2794)
			(stroke
				(width 0.1)
				(type default)
			)
			(layer "F.Fab")
		)
		(fp_line
			(start -0.12065 0.2794)
			(end -0.12065 0.3048)
			(stroke
				(width 0.1)
				(type default)
			)
			(layer "F.Fab")
		)
		(fp_line
			(start -0.12065 0.3048)
			(end -0.67945 0.3048)
			(stroke
				(width 0.1)
				(type default)
			)
			(layer "F.Fab")
		)
		(fp_line
			(start 0.120396 0.2794)
			(end -0.12065 0.2794)
			(stroke
				(width 0.1)
				(type default)
			)
			(layer "F.Fab")
		)
		(fp_line
			(start 0.120396 0.3048)
			(end 0.120396 0.2794)
			(stroke
				(width 0.1)
				(type default)
			)
			(layer "F.Fab")
		)
		(fp_line
			(start 0.12065 -0.3048)
			(end 0.67945 -0.3048)
			(stroke
				(width 0.1)
				(type default)
			)
			(layer "F.Fab")
		)
		(fp_line
			(start 0.12065 -0.2794)
			(end 0.12065 -0.3048)
			(stroke
				(width 0.1)
				(type default)
			)
			(layer "F.Fab")
		)
		(fp_line
			(start 0.67945 -0.3048)
			(end 0.67945 0.3048)
			(stroke
				(width 0.1)
				(type default)
			)
			(layer "F.Fab")
		)
		(fp_line
			(start 0.67945 0.3048)
			(end 0.120396 0.3048)
			(stroke
				(width 0.1)
				(type default)
			)
			(layer "F.Fab")
		)
		(pad "1" smd circle
			(at -0.40005 0)
			(size 0 0)
			(layers "F.Cu" "F.Mask" "F.Paste")
			(net "SMB_MB_R_SDA")
		)
		(pad "2" smd circle
			(at 0.40005 0)
			(size 0 0)
			(layers "F.Cu" "F.Mask" "F.Paste")
			(net "SMB_MB_BMC_ISO_FPGA_SDA")
		)
	)
	(footprint ""
		(layer "F.Cu")
		(at 336.042 -186.055)
		(property "Reference" "R4736"
			(at 0 0 0)
			(layer "F.SilkS")
			(hide yes)
			(effects
				(font
					(size 1.27 1.27)
				)
			)
		)
		(property "Value" ""
			(at 0 0 0)
			(layer "F.Fab")
			(effects
				(font
					(size 1.27 1.27)
				)
			)
		)
		(duplicate_pad_numbers_are_jumpers no)
		(fp_line
			(start -0.7874 -0.4064)
			(end 0.7874 -0.4064)
			(stroke
				(width 0.1524)
				(type default)
			)
			(layer "F.SilkS")
		)
		(fp_line
			(start -0.7874 0.4064)
			(end -0.7874 -0.4064)
			(stroke
				(width 0.1524)
				(type default)
			)
			(layer "F.SilkS")
		)
		(fp_line
			(start 0.7874 -0.4064)
			(end 0.7874 0.4064)
			(stroke
				(width 0.1524)
				(type default)
			)
			(layer "F.SilkS")
		)
		(fp_line
			(start 0.7874 0.4064)
			(end -0.7874 0.4064)
			(stroke
				(width 0.1524)
				(type default)
			)
			(layer "F.SilkS")
		)
		(fp_line
			(start -0.67945 -0.305054)
			(end -0.12065 -0.305054)
			(stroke
				(width 0.1)
				(type default)
			)
			(layer "F.Fab")
		)
		(fp_line
			(start -0.67945 0.3048)
			(end -0.67945 -0.305054)
			(stroke
				(width 0.1)
				(type default)
			)
			(layer "F.Fab")
		)
		(fp_line
			(start -0.12065 -0.305054)
			(end -0.12065 -0.2794)
			(stroke
				(width 0.1)
				(type default)
			)
			(layer "F.Fab")
		)
		(fp_line
			(start -0.12065 -0.2794)
			(end 0.12065 -0.2794)
			(stroke
				(width 0.1)
				(type default)
			)
			(layer "F.Fab")
		)
		(fp_line
			(start -0.12065 0.2794)
			(end -0.12065 0.3048)
			(stroke
				(width 0.1)
				(type default)
			)
			(layer "F.Fab")
		)
		(fp_line
			(start -0.12065 0.3048)
			(end -0.67945 0.3048)
			(stroke
				(width 0.1)
				(type default)
			)
			(layer "F.Fab")
		)
		(fp_line
			(start 0.120396 0.2794)
			(end -0.12065 0.2794)
			(stroke
				(width 0.1)
				(type default)
			)
			(layer "F.Fab")
		)
		(fp_line
			(start 0.120396 0.3048)
			(end 0.120396 0.2794)
			(stroke
				(width 0.1)
				(type default)
			)
			(layer "F.Fab")
		)
		(fp_line
			(start 0.12065 -0.3048)
			(end 0.67945 -0.3048)
			(stroke
				(width 0.1)
				(type default)
			)
			(layer "F.Fab")
		)
		(fp_line
			(start 0.12065 -0.2794)
			(end 0.12065 -0.3048)
			(stroke
				(width 0.1)
				(type default)
			)
			(layer "F.Fab")
		)
		(fp_line
			(start 0.67945 -0.3048)
			(end 0.67945 0.3048)
			(stroke
				(width 0.1)
				(type default)
			)
			(layer "F.Fab")
		)
		(fp_line
			(start 0.67945 0.3048)
			(end 0.120396 0.3048)
			(stroke
				(width 0.1)
				(type default)
			)
			(layer "F.Fab")
		)
		(pad "1" smd circle
			(at -0.40005 0)
			(size 0 0)
			(layers "F.Cu" "F.Mask" "F.Paste")
			(net "PEX2_PCA9555_INT_N")
		)
		(pad "2" smd circle
			(at 0.40005 0)
			(size 0 0)
			(layers "F.Cu" "F.Mask" "F.Paste")
			(net "PEX2_PCA9555_0_INT_N")
		)
	)
	(footprint ""
		(layer "F.Cu")
		(at 22.408388 -257.102102)
		(property "Reference" "Q12"
			(at -1.218438 -4.390136 90)
			(unlocked yes)
			(layer "F.SilkS")
			(effects
				(font
					(size 0.7874 0.5842)
					(thickness 0.1524)
				)
			)
		)
		(property "Value" ""
			(at 0 0 0)
			(layer "F.Fab")
			(effects
				(font
					(size 1.27 1.27)
				)
			)
		)
		(duplicate_pad_numbers_are_jumpers no)
		(fp_line
			(start -1.376172 -1.199896)
			(end -0.508 -1.199896)
			(stroke
				(width 0.1524)
				(type default)
			)
			(layer "F.SilkS")
		)
		(fp_line
			(start -1.376172 1.199896)
			(end -1.376172 -1.199896)
			(stroke
				(width 0.1524)
				(type default)
			)
			(layer "F.SilkS")
		)
		(fp_line
			(start -0.508 -1.199896)
			(end 0 -0.762)
			(stroke
				(width 0.1524)
				(type default)
			)
			(layer "F.SilkS")
		)
		(fp_line
			(start 0 -0.762)
			(end 0.508 -1.199896)
			(stroke
				(width 0.1524)
				(type default)
			)
			(layer "F.SilkS")
		)
		(fp_line
			(start 0.508 -1.199896)
			(end 1.376172 -1.199896)
			(stroke
				(width 0.1524)
				(type default)
			)
			(layer "F.SilkS")
		)
		(fp_line
			(start 1.376172 -1.199896)
			(end 1.376172 1.199896)
			(stroke
				(width 0.1524)
				(type default)
			)
			(layer "F.SilkS")
		)
		(fp_line
			(start 1.376172 1.199896)
			(end -1.376172 1.199896)
			(stroke
				(width 0.1524)
				(type default)
			)
			(layer "F.SilkS")
		)
		(fp_poly
			(pts
				(xy -1.4605 -0.7493) (xy -2.2225 -1.1303) (xy -2.2225 -0.3683)
			)
			(stroke
				(width 0)
				(type default)
			)
			(fill yes)
			(layer "F.SilkS")
		)
		(fp_line
			(start -0.674878 -1.100074)
			(end 0.674878 -1.100074)
			(stroke
				(width 0.1)
				(type default)
			)
			(layer "F.Fab")
		)
		(fp_line
			(start -0.674878 1.100074)
			(end -0.674878 -1.100074)
			(stroke
				(width 0.1)
				(type default)
			)
			(layer "F.Fab")
		)
		(fp_line
			(start 0.674878 -1.100074)
			(end 0.674878 1.100074)
			(stroke
				(width 0.1)
				(type default)
			)
			(layer "F.Fab")
		)
		(fp_line
			(start 0.674878 1.100074)
			(end -0.674878 1.100074)
			(stroke
				(width 0.1)
				(type default)
			)
			(layer "F.Fab")
		)
		(fp_poly
			(pts
				(xy -1.4605 -0.7493) (xy -2.2225 -1.1303) (xy -2.2225 -0.3683)
			)
			(stroke
				(width 0)
				(type default)
			)
			(fill yes)
			(layer "F.Fab")
		)
		(pad "1" smd rect
			(at -0.899922 -0.750062 270)
			(size 0.6096 0.6096)
			(layers "F.Cu" "F.Mask" "F.Paste")
			(net "GND")
		)
		(pad "2" smd rect
			(at -0.899922 0 270)
			(size 0.4064 0.6096)
			(layers "F.Cu" "F.Mask" "F.Paste")
			(net "PEX0_SYS_ERR_R_N")
		)
		(pad "3" smd rect
			(at -0.899922 0.750062 270)
			(size 0.6096 0.6096)
			(layers "F.Cu" "F.Mask" "F.Paste")
			(net "PEX0_SYS_ERR_3V3_N")
		)
		(pad "4" smd rect
			(at 0.899922 0.750062 270)
			(size 0.6096 0.6096)
			(layers "F.Cu" "F.Mask" "F.Paste")
			(net "GND")
		)
		(pad "5" smd rect
			(at 0.899922 0 270)
			(size 0.4064 0.6096)
			(layers "F.Cu" "F.Mask" "F.Paste")
			(net "PEX0_SYS_ERR_N_G")
		)
		(pad "6" smd rect
			(at 0.899922 -0.750062 270)
			(size 0.6096 0.6096)
			(layers "F.Cu" "F.Mask" "F.Paste")
			(net "PEX0_SYS_ERR_N_G")
		)
	)
	(footprint ""
		(layer "F.Cu")
		(at 214.194136 -179.848256 -90)
		(property "Reference" "R5419"
			(at 0 0 270)
			(layer "F.SilkS")
			(hide yes)
			(effects
				(font
					(size 1.27 1.27)
				)
			)
		)
		(property "Value" ""
			(at 0 0 270)
			(layer "F.Fab")
			(effects
				(font
					(size 1.27 1.27)
				)
			)
		)
		(duplicate_pad_numbers_are_jumpers no)
		(fp_line
			(start -0.7874 0.4064)
			(end -0.7874 -0.4064)
			(stroke
				(width 0.1524)
				(type default)
			)
			(layer "F.SilkS")
		)
		(fp_line
			(start 0.7874 0.4064)
			(end -0.7874 0.4064)
			(stroke
				(width 0.1524)
				(type default)
			)
			(layer "F.SilkS")
		)
		(fp_line
			(start -0.7874 -0.4064)
			(end 0.7874 -0.4064)
			(stroke
				(width 0.1524)
				(type default)
			)
			(layer "F.SilkS")
		)
		(fp_line
			(start 0.7874 -0.4064)
			(end 0.7874 0.4064)
			(stroke
				(width 0.1524)
				(type default)
			)
			(layer "F.SilkS")
		)
		(fp_line
			(start -0.67945 0.3048)
			(end -0.67945 -0.305054)
			(stroke
				(width 0.1)
				(type default)
			)
			(layer "F.Fab")
		)
		(fp_line
			(start -0.12065 0.3048)
			(end -0.67945 0.3048)
			(stroke
				(width 0.1)
				(type default)
			)
			(layer "F.Fab")
		)
		(fp_line
			(start 0.120396 0.3048)
			(end 0.120396 0.2794)
			(stroke
				(width 0.1)
				(type default)
			)
			(layer "F.Fab")
		)
		(fp_line
			(start 0.67945 0.3048)
			(end 0.120396 0.3048)
			(stroke
				(width 0.1)
				(type default)
			)
			(layer "F.Fab")
		)
		(fp_line
			(start -0.12065 0.2794)
			(end -0.12065 0.3048)
			(stroke
				(width 0.1)
				(type default)
			)
			(layer "F.Fab")
		)
		(fp_line
			(start 0.120396 0.2794)
			(end -0.12065 0.2794)
			(stroke
				(width 0.1)
				(type default)
			)
			(layer "F.Fab")
		)
		(fp_line
			(start -0.12065 -0.2794)
			(end 0.12065 -0.2794)
			(stroke
				(width 0.1)
				(type default)
			)
			(layer "F.Fab")
		)
		(fp_line
			(start 0.12065 -0.2794)
			(end 0.12065 -0.3048)
			(stroke
				(width 0.1)
				(type default)
			)
			(layer "F.Fab")
		)
		(fp_line
			(start 0.12065 -0.3048)
			(end 0.67945 -0.3048)
			(stroke
				(width 0.1)
				(type default)
			)
			(layer "F.Fab")
		)
		(fp_line
			(start 0.67945 -0.3048)
			(end 0.67945 0.3048)
			(stroke
				(width 0.1)
				(type default)
			)
			(layer "F.Fab")
		)
		(fp_line
			(start -0.67945 -0.305054)
			(end -0.12065 -0.305054)
			(stroke
				(width 0.1)
				(type default)
			)
			(layer "F.Fab")
		)
		(fp_line
			(start -0.12065 -0.305054)
			(end -0.12065 -0.2794)
			(stroke
				(width 0.1)
				(type default)
			)
			(layer "F.Fab")
		)
		(pad "1" smd circle
			(at -0.40005 0 270)
			(size 0 0)
			(layers "F.Cu" "F.Mask" "F.Paste")
			(net "SEL_FLASH_PEX1_BUF_R")
		)
		(pad "2" smd circle
			(at 0.40005 0 270)
			(size 0 0)
			(layers "F.Cu" "F.Mask" "F.Paste")
			(net "P3V3_AUX")
		)
	)
	(footprint ""
		(layer "F.Cu")
		(at 58.995056 -101.782372 180)
		(property "Reference" "R72"
			(at 0 0 180)
			(layer "F.SilkS")
			(hide yes)
			(effects
				(font
					(size 1.27 1.27)
				)
			)
		)
		(property "Value" ""
			(at 0 0 180)
			(layer "F.Fab")
			(effects
				(font
					(size 1.27 1.27)
				)
			)
		)
		(duplicate_pad_numbers_are_jumpers no)
		(fp_line
			(start 0.7874 0.4064)
			(end -0.7874 0.4064)
			(stroke
				(width 0.1524)
				(type default)
			)
			(layer "F.SilkS")
		)
		(fp_line
			(start 0.7874 -0.4064)
			(end 0.7874 0.4064)
			(stroke
				(width 0.1524)
				(type default)
			)
			(layer "F.SilkS")
		)
		(fp_line
			(start -0.7874 0.4064)
			(end -0.7874 -0.4064)
			(stroke
				(width 0.1524)
				(type default)
			)
			(layer "F.SilkS")
		)
		(fp_line
			(start -0.7874 -0.4064)
			(end 0.7874 -0.4064)
			(stroke
				(width 0.1524)
				(type default)
			)
			(layer "F.SilkS")
		)
		(fp_line
			(start 0.67945 0.3048)
			(end 0.120396 0.3048)
			(stroke
				(width 0.1)
				(type default)
			)
			(layer "F.Fab")
		)
		(fp_line
			(start 0.67945 -0.3048)
			(end 0.67945 0.3048)
			(stroke
				(width 0.1)
				(type default)
			)
			(layer "F.Fab")
		)
		(fp_line
			(start 0.12065 -0.2794)
			(end 0.12065 -0.3048)
			(stroke
				(width 0.1)
				(type default)
			)
			(layer "F.Fab")
		)
		(fp_line
			(start 0.12065 -0.3048)
			(end 0.67945 -0.3048)
			(stroke
				(width 0.1)
				(type default)
			)
			(layer "F.Fab")
		)
		(fp_line
			(start 0.120396 0.3048)
			(end 0.120396 0.2794)
			(stroke
				(width 0.1)
				(type default)
			)
			(layer "F.Fab")
		)
		(fp_line
			(start 0.120396 0.2794)
			(end -0.12065 0.2794)
			(stroke
				(width 0.1)
				(type default)
			)
			(layer "F.Fab")
		)
		(fp_line
			(start -0.12065 0.3048)
			(end -0.67945 0.3048)
			(stroke
				(width 0.1)
				(type default)
			)
			(layer "F.Fab")
		)
		(fp_line
			(start -0.12065 0.2794)
			(end -0.12065 0.3048)
			(stroke
				(width 0.1)
				(type default)
			)
			(layer "F.Fab")
		)
		(fp_line
			(start -0.12065 -0.2794)
			(end 0.12065 -0.2794)
			(stroke
				(width 0.1)
				(type default)
			)
			(layer "F.Fab")
		)
		(fp_line
			(start -0.12065 -0.305054)
			(end -0.12065 -0.2794)
			(stroke
				(width 0.1)
				(type default)
			)
			(layer "F.Fab")
		)
		(fp_line
			(start -0.67945 0.3048)
			(end -0.67945 -0.305054)
			(stroke
				(width 0.1)
				(type default)
			)
			(layer "F.Fab")
		)
		(fp_line
			(start -0.67945 -0.305054)
			(end -0.12065 -0.305054)
			(stroke
				(width 0.1)
				(type default)
			)
			(layer "F.Fab")
		)
		(pad "1" smd circle
			(at -0.40005 0 180)
			(size 0 0)
			(layers "F.Cu" "F.Mask" "F.Paste")
			(net "NCSI_NIC1_TX_EN")
		)
		(pad "2" smd circle
			(at 0.40005 0 180)
			(size 0 0)
			(layers "F.Cu" "F.Mask" "F.Paste")
			(net "GND")
		)
	)
	(footprint ""
		(layer "F.Cu")
		(at 202.829668 -300.62043 90)
		(property "Reference" "R6390"
			(at 0 0 90)
			(layer "F.SilkS")
			(hide yes)
			(effects
				(font
					(size 1.27 1.27)
				)
			)
		)
		(property "Value" ""
			(at 0 0 90)
			(layer "F.Fab")
			(effects
				(font
					(size 1.27 1.27)
				)
			)
		)
		(duplicate_pad_numbers_are_jumpers no)
		(fp_line
			(start 0.7874 -0.4064)
			(end 0.7874 0.4064)
			(stroke
				(width 0.1524)
				(type default)
			)
			(layer "F.SilkS")
		)
		(fp_line
			(start -0.7874 -0.4064)
			(end 0.7874 -0.4064)
			(stroke
				(width 0.1524)
				(type default)
			)
			(layer "F.SilkS")
		)
		(fp_line
			(start 0.7874 0.4064)
			(end -0.7874 0.4064)
			(stroke
				(width 0.1524)
				(type default)
			)
			(layer "F.SilkS")
		)
		(fp_line
			(start -0.7874 0.4064)
			(end -0.7874 -0.4064)
			(stroke
				(width 0.1524)
				(type default)
			)
			(layer "F.SilkS")
		)
		(fp_line
			(start -0.12065 -0.305054)
			(end -0.12065 -0.2794)
			(stroke
				(width 0.1)
				(type default)
			)
			(layer "F.Fab")
		)
		(fp_line
			(start -0.67945 -0.305054)
			(end -0.12065 -0.305054)
			(stroke
				(width 0.1)
				(type default)
			)
			(layer "F.Fab")
		)
		(fp_line
			(start 0.67945 -0.3048)
			(end 0.67945 0.3048)
			(stroke
				(width 0.1)
				(type default)
			)
			(layer "F.Fab")
		)
		(fp_line
			(start 0.12065 -0.3048)
			(end 0.67945 -0.3048)
			(stroke
				(width 0.1)
				(type default)
			)
			(layer "F.Fab")
		)
		(fp_line
			(start 0.12065 -0.2794)
			(end 0.12065 -0.3048)
			(stroke
				(width 0.1)
				(type default)
			)
			(layer "F.Fab")
		)
		(fp_line
			(start -0.12065 -0.2794)
			(end 0.12065 -0.2794)
			(stroke
				(width 0.1)
				(type default)
			)
			(layer "F.Fab")
		)
		(fp_line
			(start 0.120396 0.2794)
			(end -0.12065 0.2794)
			(stroke
				(width 0.1)
				(type default)
			)
			(layer "F.Fab")
		)
		(fp_line
			(start -0.12065 0.2794)
			(end -0.12065 0.3048)
			(stroke
				(width 0.1)
				(type default)
			)
			(layer "F.Fab")
		)
		(fp_line
			(start 0.67945 0.3048)
			(end 0.120396 0.3048)
			(stroke
				(width 0.1)
				(type default)
			)
			(layer "F.Fab")
		)
		(fp_line
			(start 0.120396 0.3048)
			(end 0.120396 0.2794)
			(stroke
				(width 0.1)
				(type default)
			)
			(layer "F.Fab")
		)
		(fp_line
			(start -0.12065 0.3048)
			(end -0.67945 0.3048)
			(stroke
				(width 0.1)
				(type default)
			)
			(layer "F.Fab")
		)
		(fp_line
			(start -0.67945 0.3048)
			(end -0.67945 -0.305054)
			(stroke
				(width 0.1)
				(type default)
			)
			(layer "F.Fab")
		)
		(pad "1" smd circle
			(at -0.40005 0 90)
			(size 0 0)
			(layers "F.Cu" "F.Mask" "F.Paste")
			(net "RST_PEX1_S3_PERST_N")
		)
		(pad "2" smd circle
			(at 0.40005 0 90)
			(size 0 0)
			(layers "F.Cu" "F.Mask" "F.Paste")
			(net "RST_PEX1_S3_PERST_R_N")
		)
	)
	(footprint ""
		(layer "F.Cu")
		(at 59.007756 -212.5726)
		(property "Reference" "J71"
			(at -1.4224 -4.562348 0)
			(unlocked yes)
			(layer "F.SilkS")
			(effects
				(font
					(size 0.7874 0.5842)
					(thickness 0.1524)
				)
				(justify left)
			)
		)
		(property "Value" ""
			(at 0 0 0)
			(layer "F.Fab")
			(effects
				(font
					(size 1.27 1.27)
				)
			)
		)
		(duplicate_pad_numbers_are_jumpers no)
		(fp_line
			(start -1.27 -3.81)
			(end 1.27 -3.81)
			(stroke
				(width 0.1524)
				(type default)
			)
			(layer "F.SilkS")
		)
		(fp_line
			(start -1.27 -0.7747)
			(end -1.27 -3.81)
			(stroke
				(width 0.1524)
				(type default)
			)
			(layer "F.SilkS")
		)
		(fp_line
			(start -1.27 3.81)
			(end -1.27 0.7747)
			(stroke
				(width 0.1524)
				(type default)
			)
			(layer "F.SilkS")
		)
		(fp_line
			(start 1.27 -3.81)
			(end 1.27 -3.3147)
			(stroke
				(width 0.1524)
				(type default)
			)
			(layer "F.SilkS")
		)
		(fp_line
			(start 1.27 -1.7653)
			(end 1.27 1.7653)
			(stroke
				(width 0.1524)
				(type default)
			)
			(layer "F.SilkS")
		)
		(fp_line
			(start 1.27 3.3147)
			(end 1.27 3.81)
			(stroke
				(width 0.1524)
				(type default)
			)
			(layer "F.SilkS")
		)
		(fp_line
			(start 1.27 3.81)
			(end -1.27 3.81)
			(stroke
				(width 0.1524)
				(type default)
			)
			(layer "F.SilkS")
		)
		(fp_poly
			(pts
				(xy 4.3942 -3.048) (xy 4.3942 -2.032) (xy 3.3782 -2.54)
			)
			(stroke
				(width 0)
				(type default)
			)
			(fill yes)
			(layer "F.SilkS")
		)
		(fp_line
			(start -1.27 -3.81)
			(end -1.27 3.81)
			(stroke
				(width 0.1)
				(type default)
			)
			(layer "F.Fab")
		)
		(fp_line
			(start -1.27 3.81)
			(end 1.27 3.81)
			(stroke
				(width 0.1)
				(type default)
			)
			(layer "F.Fab")
		)
		(fp_line
			(start 1.27 -3.81)
			(end -1.27 -3.81)
			(stroke
				(width 0.1)
				(type default)
			)
			(layer "F.Fab")
		)
		(fp_line
			(start 1.27 3.81)
			(end 1.27 -3.81)
			(stroke
				(width 0.1)
				(type default)
			)
			(layer "F.Fab")
		)
		(fp_poly
			(pts
				(xy 4.3942 -3.048) (xy 4.3942 -2.032) (xy 3.3782 -2.54)
			)
			(stroke
				(width 0)
				(type default)
			)
			(fill yes)
			(layer "F.Fab")
		)
		(fp_text user "3"
			(at 3.921252 2.54 90)
			(unlocked yes)
			(layer "F.SilkS")
			(effects
				(font
					(size 0.7874 0.5842)
					(thickness 0.1524)
				)
			)
		)
		(fp_text user "3"
			(at 3.921252 2.54 90)
			(unlocked yes)
			(layer "F.Fab")
			(effects
				(font
					(size 0.7874 0.5842)
					(thickness 0.1524)
				)
			)
		)
		(pad "1" smd rect
			(at 1.459992 -2.54 90)
			(size 1.27 3.429)
			(layers "F.Cu" "F.Mask" "F.Paste")
			(net "GND")
		)
		(pad "2" smd rect
			(at -1.459992 0 90)
			(size 1.27 3.429)
			(layers "F.Cu" "F.Mask" "F.Paste")
			(net "UART_PEX2_CLI_BUF_R1_TX")
		)
		(pad "3" smd rect
			(at 1.459992 2.54 90)
			(size 1.27 3.429)
			(layers "F.Cu" "F.Mask" "F.Paste")
			(net "UART_PEX2_CLI_R1_RX")
		)
	)
	(footprint ""
		(layer "F.Cu")
		(at 30.153356 -294.591232)
		(property "Reference" "L90"
			(at 0 0 0)
			(layer "F.SilkS")
			(hide yes)
			(effects
				(font
					(size 1.27 1.27)
				)
			)
		)
		(property "Value" ""
			(at 0 0 0)
			(layer "F.Fab")
			(effects
				(font
					(size 1.27 1.27)
				)
			)
		)
		(duplicate_pad_numbers_are_jumpers no)
		(fp_line
			(start -1.63576 -0.8128)
			(end -1.63576 0.8128)
			(stroke
				(width 0.1524)
				(type default)
			)
			(layer "F.SilkS")
		)
		(fp_line
			(start -1.63576 -0.8128)
			(end 1.63576 -0.8128)
			(stroke
				(width 0.1524)
				(type default)
			)
			(layer "F.SilkS")
		)
		(fp_line
			(start 1.63576 -0.8128)
			(end 1.63576 0.8128)
			(stroke
				(width 0.1524)
				(type default)
			)
			(layer "F.SilkS")
		)
		(fp_line
			(start 1.63576 0.8128)
			(end -1.63576 0.8128)
			(stroke
				(width 0.1524)
				(type default)
			)
			(layer "F.SilkS")
		)
		(fp_line
			(start -1.56083 -0.738632)
			(end -1.56083 0.7366)
			(stroke
				(width 0.1)
				(type default)
			)
			(layer "F.Fab")
		)
		(fp_line
			(start -1.56083 0.7366)
			(end -1.524 0.7366)
			(stroke
				(width 0.1)
				(type default)
			)
			(layer "F.Fab")
		)
		(fp_line
			(start -1.524 0.7366)
			(end 1.524 0.7366)
			(stroke
				(width 0.1)
				(type default)
			)
			(layer "F.Fab")
		)
		(fp_line
			(start 1.524 0.7366)
			(end 1.560576 0.7366)
			(stroke
				(width 0.1)
				(type default)
			)
			(layer "F.Fab")
		)
		(fp_line
			(start 1.560576 -0.738632)
			(end -1.56083 -0.738632)
			(stroke
				(width 0.1)
				(type default)
			)
			(layer "F.Fab")
		)
		(fp_line
			(start 1.560576 0.7366)
			(end 1.560576 -0.738632)
			(stroke
				(width 0.1)
				(type default)
			)
			(layer "F.Fab")
		)
		(pad "1" smd rect
			(at -0.94996 0 180)
			(size 1.1176 1.3716)
			(layers "F.Cu" "F.Mask" "F.Paste")
			(net "P1V8_PLL0_PEX0")
		)
		(pad "2" smd rect
			(at 0.94996 0 180)
			(size 1.1176 1.3716)
			(layers "F.Cu" "F.Mask" "F.Paste")
			(net "PCEPLL2_VDDA18_PEX0")
		)
	)
	(footprint ""
		(layer "F.Cu")
		(at 62.491874 -161.881566 90)
		(property "Reference" "Q119"
			(at -0.185166 2.025396 90)
			(unlocked yes)
			(layer "F.SilkS")
			(effects
				(font
					(size 0.7874 0.5842)
					(thickness 0.1524)
				)
			)
		)
		(property "Value" ""
			(at 0 0 90)
			(layer "F.Fab")
			(effects
				(font
					(size 1.27 1.27)
				)
			)
		)
		(duplicate_pad_numbers_are_jumpers no)
		(fp_line
			(start 1.376172 -1.199896)
			(end 1.376172 1.199896)
			(stroke
				(width 0.1524)
				(type default)
			)
			(layer "F.SilkS")
		)
		(fp_line
			(start 0.508 -1.199896)
			(end 1.376172 -1.199896)
			(stroke
				(width 0.1524)
				(type default)
			)
			(layer "F.SilkS")
		)
		(fp_line
			(start -0.508 -1.199896)
			(end 0 -0.762)
			(stroke
				(width 0.1524)
				(type default)
			)
			(layer "F.SilkS")
		)
		(fp_line
			(start -1.376172 -1.199896)
			(end -0.508 -1.199896)
			(stroke
				(width 0.1524)
				(type default)
			)
			(layer "F.SilkS")
		)
		(fp_line
			(start 0 -0.762)
			(end 0.508 -1.199896)
			(stroke
				(width 0.1524)
				(type default)
			)
			(layer "F.SilkS")
		)
		(fp_line
			(start 1.376172 1.199896)
			(end -1.376172 1.199896)
			(stroke
				(width 0.1524)
				(type default)
			)
			(layer "F.SilkS")
		)
		(fp_line
			(start -1.376172 1.199896)
			(end -1.376172 -1.199896)
			(stroke
				(width 0.1524)
				(type default)
			)
			(layer "F.SilkS")
		)
		(fp_poly
			(pts
				(xy -1.3208 -1.364488) (xy -1.590294 -2.172716) (xy -2.129028 -1.633982)
			)
			(stroke
				(width 0)
				(type default)
			)
			(fill yes)
			(layer "F.SilkS")
		)
		(fp_line
			(start 0.674878 -1.100074)
			(end 0.674878 1.100074)
			(stroke
				(width 0.1)
				(type default)
			)
			(layer "F.Fab")
		)
		(fp_line
			(start -0.674878 -1.100074)
			(end 0.674878 -1.100074)
			(stroke
				(width 0.1)
				(type default)
			)
			(layer "F.Fab")
		)
		(fp_line
			(start 0.674878 1.100074)
			(end -0.674878 1.100074)
			(stroke
				(width 0.1)
				(type default)
			)
			(layer "F.Fab")
		)
		(fp_line
			(start -0.674878 1.100074)
			(end -0.674878 -1.100074)
			(stroke
				(width 0.1)
				(type default)
			)
			(layer "F.Fab")
		)
		(fp_poly
			(pts
				(xy -1.4605 -0.7493) (xy -2.2225 -1.1303) (xy -2.2225 -0.3683)
			)
			(stroke
				(width 0)
				(type default)
			)
			(fill yes)
			(layer "F.Fab")
		)
		(pad "1" smd rect
			(at -0.899922 -0.750062)
			(size 0.6096 0.6096)
			(layers "F.Cu" "F.Mask" "F.Paste")
			(net "GND")
		)
		(pad "2" smd rect
			(at -0.899922 0)
			(size 0.4064 0.6096)
			(layers "F.Cu" "F.Mask" "F.Paste")
			(net "FM_SYS_THROTTLE_NIC0")
		)
		(pad "3" smd rect
			(at -0.899922 0.750062)
			(size 0.6096 0.6096)
			(layers "F.Cu" "F.Mask" "F.Paste")
			(net "NIC1_PWRBRK_N")
		)
		(pad "4" smd rect
			(at 0.899922 0.750062)
			(size 0.6096 0.6096)
			(layers "F.Cu" "F.Mask" "F.Paste")
			(net "GND")
		)
		(pad "5" smd rect
			(at 0.899922 0)
			(size 0.4064 0.6096)
			(layers "F.Cu" "F.Mask" "F.Paste")
			(net "FM_SYS_THROTTLE_NIC1")
		)
		(pad "6" smd rect
			(at 0.899922 -0.750062)
			(size 0.6096 0.6096)
			(layers "F.Cu" "F.Mask" "F.Paste")
			(net "NIC0_PWRBRK_N")
		)
	)
	(footprint ""
		(layer "F.Cu")
		(at 245.406164 -134.434326)
		(property "Reference" "PC342"
			(at 0 0 0)
			(layer "F.SilkS")
			(hide yes)
			(effects
				(font
					(size 1.27 1.27)
				)
			)
		)
		(property "Value" ""
			(at 0 0 0)
			(layer "F.Fab")
			(effects
				(font
					(size 1.27 1.27)
				)
			)
		)
		(duplicate_pad_numbers_are_jumpers no)
		(fp_line
			(start -0.7874 -0.4064)
			(end 0.7874 -0.4064)
			(stroke
				(width 0.1524)
				(type default)
			)
			(layer "F.SilkS")
		)
		(fp_line
			(start -0.7874 0.4064)
			(end -0.7874 -0.4064)
			(stroke
				(width 0.1524)
				(type default)
			)
			(layer "F.SilkS")
		)
		(fp_line
			(start 0.7874 -0.4064)
			(end 0.7874 0.4064)
			(stroke
				(width 0.1524)
				(type default)
			)
			(layer "F.SilkS")
		)
		(fp_line
			(start 0.7874 0.4064)
			(end -0.7874 0.4064)
			(stroke
				(width 0.1524)
				(type default)
			)
			(layer "F.SilkS")
		)
		(fp_line
			(start -0.67945 -0.305054)
			(end -0.12065 -0.305054)
			(stroke
				(width 0.1)
				(type default)
			)
			(layer "F.Fab")
		)
		(fp_line
			(start -0.67945 0.3048)
			(end -0.67945 -0.305054)
			(stroke
				(width 0.1)
				(type default)
			)
			(layer "F.Fab")
		)
		(fp_line
			(start -0.12065 -0.305054)
			(end -0.12065 -0.2794)
			(stroke
				(width 0.1)
				(type default)
			)
			(layer "F.Fab")
		)
		(fp_line
			(start -0.12065 -0.2794)
			(end 0.12065 -0.2794)
			(stroke
				(width 0.1)
				(type default)
			)
			(layer "F.Fab")
		)
		(fp_line
			(start -0.12065 0.2794)
			(end -0.12065 0.3048)
			(stroke
				(width 0.1)
				(type default)
			)
			(layer "F.Fab")
		)
		(fp_line
			(start -0.12065 0.3048)
			(end -0.67945 0.3048)
			(stroke
				(width 0.1)
				(type default)
			)
			(layer "F.Fab")
		)
		(fp_line
			(start 0.120396 0.2794)
			(end -0.12065 0.2794)
			(stroke
				(width 0.1)
				(type default)
			)
			(layer "F.Fab")
		)
		(fp_line
			(start 0.120396 0.3048)
			(end 0.120396 0.2794)
			(stroke
				(width 0.1)
				(type default)
			)
			(layer "F.Fab")
		)
		(fp_line
			(start 0.12065 -0.3048)
			(end 0.67945 -0.3048)
			(stroke
				(width 0.1)
				(type default)
			)
			(layer "F.Fab")
		)
		(fp_line
			(start 0.12065 -0.2794)
			(end 0.12065 -0.3048)
			(stroke
				(width 0.1)
				(type default)
			)
			(layer "F.Fab")
		)
		(fp_line
			(start 0.67945 -0.3048)
			(end 0.67945 0.3048)
			(stroke
				(width 0.1)
				(type default)
			)
			(layer "F.Fab")
		)
		(fp_line
			(start 0.67945 0.3048)
			(end 0.120396 0.3048)
			(stroke
				(width 0.1)
				(type default)
			)
			(layer "F.Fab")
		)
		(pad "1" smd circle
			(at -0.40005 0)
			(size 0 0)
			(layers "F.Cu" "F.Mask" "F.Paste")
			(net "P12V_AUX")
		)
		(pad "2" smd circle
			(at 0.40005 0)
			(size 0 0)
			(layers "F.Cu" "F.Mask" "F.Paste")
			(net "GND")
		)
	)
	(footprint ""
		(layer "F.Cu")
		(at 380.711456 -293.245032 -90)
		(property "Reference" "R4590"
			(at 0 0 270)
			(layer "F.SilkS")
			(hide yes)
			(effects
				(font
					(size 1.27 1.27)
				)
			)
		)
		(property "Value" ""
			(at 0 0 270)
			(layer "F.Fab")
			(effects
				(font
					(size 1.27 1.27)
				)
			)
		)
		(duplicate_pad_numbers_are_jumpers no)
		(fp_line
			(start -0.7874 0.4064)
			(end -0.7874 -0.4064)
			(stroke
				(width 0.1524)
				(type default)
			)
			(layer "F.SilkS")
		)
		(fp_line
			(start 0.7874 0.4064)
			(end -0.7874 0.4064)
			(stroke
				(width 0.1524)
				(type default)
			)
			(layer "F.SilkS")
		)
		(fp_line
			(start -0.7874 -0.4064)
			(end 0.7874 -0.4064)
			(stroke
				(width 0.1524)
				(type default)
			)
			(layer "F.SilkS")
		)
		(fp_line
			(start 0.7874 -0.4064)
			(end 0.7874 0.4064)
			(stroke
				(width 0.1524)
				(type default)
			)
			(layer "F.SilkS")
		)
		(fp_line
			(start -0.67945 0.3048)
			(end -0.67945 -0.305054)
			(stroke
				(width 0.1)
				(type default)
			)
			(layer "F.Fab")
		)
		(fp_line
			(start -0.12065 0.3048)
			(end -0.67945 0.3048)
			(stroke
				(width 0.1)
				(type default)
			)
			(layer "F.Fab")
		)
		(fp_line
			(start 0.120396 0.3048)
			(end 0.120396 0.2794)
			(stroke
				(width 0.1)
				(type default)
			)
			(layer "F.Fab")
		)
		(fp_line
			(start 0.67945 0.3048)
			(end 0.120396 0.3048)
			(stroke
				(width 0.1)
				(type default)
			)
			(layer "F.Fab")
		)
		(fp_line
			(start -0.12065 0.2794)
			(end -0.12065 0.3048)
			(stroke
				(width 0.1)
				(type default)
			)
			(layer "F.Fab")
		)
		(fp_line
			(start 0.120396 0.2794)
			(end -0.12065 0.2794)
			(stroke
				(width 0.1)
				(type default)
			)
			(layer "F.Fab")
		)
		(fp_line
			(start -0.12065 -0.2794)
			(end 0.12065 -0.2794)
			(stroke
				(width 0.1)
				(type default)
			)
			(layer "F.Fab")
		)
		(fp_line
			(start 0.12065 -0.2794)
			(end 0.12065 -0.3048)
			(stroke
				(width 0.1)
				(type default)
			)
			(layer "F.Fab")
		)
		(fp_line
			(start 0.12065 -0.3048)
			(end 0.67945 -0.3048)
			(stroke
				(width 0.1)
				(type default)
			)
			(layer "F.Fab")
		)
		(fp_line
			(start 0.67945 -0.3048)
			(end 0.67945 0.3048)
			(stroke
				(width 0.1)
				(type default)
			)
			(layer "F.Fab")
		)
		(fp_line
			(start -0.67945 -0.305054)
			(end -0.12065 -0.305054)
			(stroke
				(width 0.1)
				(type default)
			)
			(layer "F.Fab")
		)
		(fp_line
			(start -0.12065 -0.305054)
			(end -0.12065 -0.2794)
			(stroke
				(width 0.1)
				(type default)
			)
			(layer "F.Fab")
		)
		(pad "1" smd circle
			(at -0.40005 0 270)
			(size 0 0)
			(layers "F.Cu" "F.Mask" "F.Paste")
			(net "PCEPLL2_VDDA18_PEX3")
		)
		(pad "2" smd circle
			(at 0.40005 0 270)
			(size 0 0)
			(layers "F.Cu" "F.Mask" "F.Paste")
			(net "PCEPLL2_VDDA18_PEX3_R")
		)
	)
	(footprint ""
		(layer "F.Cu")
		(at 168.12514 -14.735302 180)
		(property "Reference" "C2722"
			(at 0 0 180)
			(layer "F.SilkS")
			(hide yes)
			(effects
				(font
					(size 1.27 1.27)
				)
			)
		)
		(property "Value" ""
			(at 0 0 180)
			(layer "F.Fab")
			(effects
				(font
					(size 1.27 1.27)
				)
			)
		)
		(duplicate_pad_numbers_are_jumpers no)
		(fp_line
			(start 0.7874 0.4064)
			(end -0.7874 0.4064)
			(stroke
				(width 0.1524)
				(type default)
			)
			(layer "F.SilkS")
		)
		(fp_line
			(start 0.7874 -0.4064)
			(end 0.7874 0.4064)
			(stroke
				(width 0.1524)
				(type default)
			)
			(layer "F.SilkS")
		)
		(fp_line
			(start -0.7874 0.4064)
			(end -0.7874 -0.4064)
			(stroke
				(width 0.1524)
				(type default)
			)
			(layer "F.SilkS")
		)
		(fp_line
			(start -0.7874 -0.4064)
			(end 0.7874 -0.4064)
			(stroke
				(width 0.1524)
				(type default)
			)
			(layer "F.SilkS")
		)
		(fp_line
			(start 0.67945 0.3048)
			(end 0.120396 0.3048)
			(stroke
				(width 0.1)
				(type default)
			)
			(layer "F.Fab")
		)
		(fp_line
			(start 0.67945 -0.3048)
			(end 0.67945 0.3048)
			(stroke
				(width 0.1)
				(type default)
			)
			(layer "F.Fab")
		)
		(fp_line
			(start 0.12065 -0.2794)
			(end 0.12065 -0.3048)
			(stroke
				(width 0.1)
				(type default)
			)
			(layer "F.Fab")
		)
		(fp_line
			(start 0.12065 -0.3048)
			(end 0.67945 -0.3048)
			(stroke
				(width 0.1)
				(type default)
			)
			(layer "F.Fab")
		)
		(fp_line
			(start 0.120396 0.3048)
			(end 0.120396 0.2794)
			(stroke
				(width 0.1)
				(type default)
			)
			(layer "F.Fab")
		)
		(fp_line
			(start 0.120396 0.2794)
			(end -0.12065 0.2794)
			(stroke
				(width 0.1)
				(type default)
			)
			(layer "F.Fab")
		)
		(fp_line
			(start -0.12065 0.3048)
			(end -0.67945 0.3048)
			(stroke
				(width 0.1)
				(type default)
			)
			(layer "F.Fab")
		)
		(fp_line
			(start -0.12065 0.2794)
			(end -0.12065 0.3048)
			(stroke
				(width 0.1)
				(type default)
			)
			(layer "F.Fab")
		)
		(fp_line
			(start -0.12065 -0.2794)
			(end 0.12065 -0.2794)
			(stroke
				(width 0.1)
				(type default)
			)
			(layer "F.Fab")
		)
		(fp_line
			(start -0.12065 -0.305054)
			(end -0.12065 -0.2794)
			(stroke
				(width 0.1)
				(type default)
			)
			(layer "F.Fab")
		)
		(fp_line
			(start -0.67945 0.3048)
			(end -0.67945 -0.305054)
			(stroke
				(width 0.1)
				(type default)
			)
			(layer "F.Fab")
		)
		(fp_line
			(start -0.67945 -0.305054)
			(end -0.12065 -0.305054)
			(stroke
				(width 0.1)
				(type default)
			)
			(layer "F.Fab")
		)
		(pad "1" smd circle
			(at -0.40005 0 180)
			(size 0 0)
			(layers "F.Cu" "F.Mask" "F.Paste")
			(net "GND")
		)
		(pad "2" smd circle
			(at 0.40005 0 180)
			(size 0 0)
			(layers "F.Cu" "F.Mask" "F.Paste")
			(net "P3V3_SSD5")
		)
	)
	(footprint ""
		(layer "F.Cu")
		(at 442.767466 -112.903508 90)
		(property "Reference" "PC347"
			(at 0 0 90)
			(layer "F.SilkS")
			(hide yes)
			(effects
				(font
					(size 1.27 1.27)
				)
			)
		)
		(property "Value" ""
			(at 0 0 90)
			(layer "F.Fab")
			(effects
				(font
					(size 1.27 1.27)
				)
			)
		)
		(duplicate_pad_numbers_are_jumpers no)
		(fp_line
			(start 1.524 -0.762)
			(end 1.524 0.762)
			(stroke
				(width 0.1524)
				(type default)
			)
			(layer "F.SilkS")
		)
		(fp_line
			(start -1.524 -0.762)
			(end 1.524 -0.762)
			(stroke
				(width 0.1524)
				(type default)
			)
			(layer "F.SilkS")
		)
		(fp_line
			(start 1.524 0.762)
			(end -1.524 0.762)
			(stroke
				(width 0.1524)
				(type default)
			)
			(layer "F.SilkS")
		)
		(fp_line
			(start -1.524 0.762)
			(end -1.524 -0.762)
			(stroke
				(width 0.1524)
				(type default)
			)
			(layer "F.SilkS")
		)
		(fp_line
			(start 1.1049 -0.724916)
			(end -1.1049 -0.724916)
			(stroke
				(width 0.1)
				(type default)
			)
			(layer "F.Fab")
		)
		(fp_line
			(start -1.1049 -0.724916)
			(end -1.1049 0.724916)
			(stroke
				(width 0.1)
				(type default)
			)
			(layer "F.Fab")
		)
		(fp_line
			(start 1.1049 0.724916)
			(end 1.1049 -0.724916)
			(stroke
				(width 0.1)
				(type default)
			)
			(layer "F.Fab")
		)
		(fp_line
			(start -1.1049 0.724916)
			(end 1.1049 0.724916)
			(stroke
				(width 0.1)
				(type default)
			)
			(layer "F.Fab")
		)
		(pad "1" smd rect
			(at -0.889 0 270)
			(size 1.016 1.27)
			(layers "F.Cu" "F.Mask" "F.Paste")
			(net "P12V_NIC7_R")
		)
		(pad "2" smd rect
			(at 0.889 0 270)
			(size 1.016 1.27)
			(layers "F.Cu" "F.Mask" "F.Paste")
			(net "GND")
		)
	)
	(footprint ""
		(layer "F.Cu")
		(at 327.53173 -224.988882 180)
		(property "Reference" "R4168"
			(at 0 0 180)
			(layer "F.SilkS")
			(hide yes)
			(effects
				(font
					(size 1.27 1.27)
				)
			)
		)
		(property "Value" ""
			(at 0 0 180)
			(layer "F.Fab")
			(effects
				(font
					(size 1.27 1.27)
				)
			)
		)
		(duplicate_pad_numbers_are_jumpers no)
		(fp_line
			(start 0.7874 0.4064)
			(end -0.7874 0.4064)
			(stroke
				(width 0.1524)
				(type default)
			)
			(layer "F.SilkS")
		)
		(fp_line
			(start 0.7874 -0.4064)
			(end 0.7874 0.4064)
			(stroke
				(width 0.1524)
				(type default)
			)
			(layer "F.SilkS")
		)
		(fp_line
			(start -0.7874 0.4064)
			(end -0.7874 -0.4064)
			(stroke
				(width 0.1524)
				(type default)
			)
			(layer "F.SilkS")
		)
		(fp_line
			(start -0.7874 -0.4064)
			(end 0.7874 -0.4064)
			(stroke
				(width 0.1524)
				(type default)
			)
			(layer "F.SilkS")
		)
		(fp_line
			(start 0.67945 0.3048)
			(end 0.120396 0.3048)
			(stroke
				(width 0.1)
				(type default)
			)
			(layer "F.Fab")
		)
		(fp_line
			(start 0.67945 -0.3048)
			(end 0.67945 0.3048)
			(stroke
				(width 0.1)
				(type default)
			)
			(layer "F.Fab")
		)
		(fp_line
			(start 0.12065 -0.2794)
			(end 0.12065 -0.3048)
			(stroke
				(width 0.1)
				(type default)
			)
			(layer "F.Fab")
		)
		(fp_line
			(start 0.12065 -0.3048)
			(end 0.67945 -0.3048)
			(stroke
				(width 0.1)
				(type default)
			)
			(layer "F.Fab")
		)
		(fp_line
			(start 0.120396 0.3048)
			(end 0.120396 0.2794)
			(stroke
				(width 0.1)
				(type default)
			)
			(layer "F.Fab")
		)
		(fp_line
			(start 0.120396 0.2794)
			(end -0.12065 0.2794)
			(stroke
				(width 0.1)
				(type default)
			)
			(layer "F.Fab")
		)
		(fp_line
			(start -0.12065 0.3048)
			(end -0.67945 0.3048)
			(stroke
				(width 0.1)
				(type default)
			)
			(layer "F.Fab")
		)
		(fp_line
			(start -0.12065 0.2794)
			(end -0.12065 0.3048)
			(stroke
				(width 0.1)
				(type default)
			)
			(layer "F.Fab")
		)
		(fp_line
			(start -0.12065 -0.2794)
			(end 0.12065 -0.2794)
			(stroke
				(width 0.1)
				(type default)
			)
			(layer "F.Fab")
		)
		(fp_line
			(start -0.12065 -0.305054)
			(end -0.12065 -0.2794)
			(stroke
				(width 0.1)
				(type default)
			)
			(layer "F.Fab")
		)
		(fp_line
			(start -0.67945 0.3048)
			(end -0.67945 -0.305054)
			(stroke
				(width 0.1)
				(type default)
			)
			(layer "F.Fab")
		)
		(fp_line
			(start -0.67945 -0.305054)
			(end -0.12065 -0.305054)
			(stroke
				(width 0.1)
				(type default)
			)
			(layer "F.Fab")
		)
		(pad "1" smd circle
			(at -0.40005 0 180)
			(size 0 0)
			(layers "F.Cu" "F.Mask" "F.Paste")
			(net "FM_CLK_EN")
		)
		(pad "2" smd circle
			(at 0.40005 0 180)
			(size 0 0)
			(layers "F.Cu" "F.Mask" "F.Paste")
			(net "FM_CLK_EN_R")
		)
	)
	(footprint ""
		(layer "F.Cu")
		(at 369.495578 -81.498694 180)
		(property "Reference" "R1602"
			(at 0 0 180)
			(layer "F.SilkS")
			(hide yes)
			(effects
				(font
					(size 1.27 1.27)
				)
			)
		)
		(property "Value" ""
			(at 0 0 180)
			(layer "F.Fab")
			(effects
				(font
					(size 1.27 1.27)
				)
			)
		)
		(duplicate_pad_numbers_are_jumpers no)
		(fp_line
			(start 0.7874 0.4064)
			(end -0.7874 0.4064)
			(stroke
				(width 0.1524)
				(type default)
			)
			(layer "F.SilkS")
		)
		(fp_line
			(start 0.7874 -0.4064)
			(end 0.7874 0.4064)
			(stroke
				(width 0.1524)
				(type default)
			)
			(layer "F.SilkS")
		)
		(fp_line
			(start -0.7874 0.4064)
			(end -0.7874 -0.4064)
			(stroke
				(width 0.1524)
				(type default)
			)
			(layer "F.SilkS")
		)
		(fp_line
			(start -0.7874 -0.4064)
			(end 0.7874 -0.4064)
			(stroke
				(width 0.1524)
				(type default)
			)
			(layer "F.SilkS")
		)
		(fp_line
			(start 0.67945 0.3048)
			(end 0.120396 0.3048)
			(stroke
				(width 0.1)
				(type default)
			)
			(layer "F.Fab")
		)
		(fp_line
			(start 0.67945 -0.3048)
			(end 0.67945 0.3048)
			(stroke
				(width 0.1)
				(type default)
			)
			(layer "F.Fab")
		)
		(fp_line
			(start 0.12065 -0.2794)
			(end 0.12065 -0.3048)
			(stroke
				(width 0.1)
				(type default)
			)
			(layer "F.Fab")
		)
		(fp_line
			(start 0.12065 -0.3048)
			(end 0.67945 -0.3048)
			(stroke
				(width 0.1)
				(type default)
			)
			(layer "F.Fab")
		)
		(fp_line
			(start 0.120396 0.3048)
			(end 0.120396 0.2794)
			(stroke
				(width 0.1)
				(type default)
			)
			(layer "F.Fab")
		)
		(fp_line
			(start 0.120396 0.2794)
			(end -0.12065 0.2794)
			(stroke
				(width 0.1)
				(type default)
			)
			(layer "F.Fab")
		)
		(fp_line
			(start -0.12065 0.3048)
			(end -0.67945 0.3048)
			(stroke
				(width 0.1)
				(type default)
			)
			(layer "F.Fab")
		)
		(fp_line
			(start -0.12065 0.2794)
			(end -0.12065 0.3048)
			(stroke
				(width 0.1)
				(type default)
			)
			(layer "F.Fab")
		)
		(fp_line
			(start -0.12065 -0.2794)
			(end 0.12065 -0.2794)
			(stroke
				(width 0.1)
				(type default)
			)
			(layer "F.Fab")
		)
		(fp_line
			(start -0.12065 -0.305054)
			(end -0.12065 -0.2794)
			(stroke
				(width 0.1)
				(type default)
			)
			(layer "F.Fab")
		)
		(fp_line
			(start -0.67945 0.3048)
			(end -0.67945 -0.305054)
			(stroke
				(width 0.1)
				(type default)
			)
			(layer "F.Fab")
		)
		(fp_line
			(start -0.67945 -0.305054)
			(end -0.12065 -0.305054)
			(stroke
				(width 0.1)
				(type default)
			)
			(layer "F.Fab")
		)
		(pad "1" smd circle
			(at -0.40005 0 180)
			(size 0 0)
			(layers "F.Cu" "F.Mask" "F.Paste")
			(net "P3V3_AUX")
		)
		(pad "2" smd circle
			(at 0.40005 0 180)
			(size 0 0)
			(layers "F.Cu" "F.Mask" "F.Paste")
			(net "SMB_BIC_I2C9_MUX1_SSD12_R_SDA")
		)
	)
	(footprint ""
		(layer "F.Cu")
		(at 211.506816 -368.007646)
		(property "Reference" "R492"
			(at 0 0 0)
			(layer "F.SilkS")
			(hide yes)
			(effects
				(font
					(size 1.27 1.27)
				)
			)
		)
		(property "Value" ""
			(at 0 0 0)
			(layer "F.Fab")
			(effects
				(font
					(size 1.27 1.27)
				)
			)
		)
		(duplicate_pad_numbers_are_jumpers no)
		(fp_line
			(start -0.7874 -0.4064)
			(end 0.7874 -0.4064)
			(stroke
				(width 0.1524)
				(type default)
			)
			(layer "F.SilkS")
		)
		(fp_line
			(start -0.7874 0.4064)
			(end -0.7874 -0.4064)
			(stroke
				(width 0.1524)
				(type default)
			)
			(layer "F.SilkS")
		)
		(fp_line
			(start 0.7874 -0.4064)
			(end 0.7874 0.4064)
			(stroke
				(width 0.1524)
				(type default)
			)
			(layer "F.SilkS")
		)
		(fp_line
			(start 0.7874 0.4064)
			(end -0.7874 0.4064)
			(stroke
				(width 0.1524)
				(type default)
			)
			(layer "F.SilkS")
		)
		(fp_line
			(start -0.67945 -0.305054)
			(end -0.12065 -0.305054)
			(stroke
				(width 0.1)
				(type default)
			)
			(layer "F.Fab")
		)
		(fp_line
			(start -0.67945 0.3048)
			(end -0.67945 -0.305054)
			(stroke
				(width 0.1)
				(type default)
			)
			(layer "F.Fab")
		)
		(fp_line
			(start -0.12065 -0.305054)
			(end -0.12065 -0.2794)
			(stroke
				(width 0.1)
				(type default)
			)
			(layer "F.Fab")
		)
		(fp_line
			(start -0.12065 -0.2794)
			(end 0.12065 -0.2794)
			(stroke
				(width 0.1)
				(type default)
			)
			(layer "F.Fab")
		)
		(fp_line
			(start -0.12065 0.2794)
			(end -0.12065 0.3048)
			(stroke
				(width 0.1)
				(type default)
			)
			(layer "F.Fab")
		)
		(fp_line
			(start -0.12065 0.3048)
			(end -0.67945 0.3048)
			(stroke
				(width 0.1)
				(type default)
			)
			(layer "F.Fab")
		)
		(fp_line
			(start 0.120396 0.2794)
			(end -0.12065 0.2794)
			(stroke
				(width 0.1)
				(type default)
			)
			(layer "F.Fab")
		)
		(fp_line
			(start 0.120396 0.3048)
			(end 0.120396 0.2794)
			(stroke
				(width 0.1)
				(type default)
			)
			(layer "F.Fab")
		)
		(fp_line
			(start 0.12065 -0.3048)
			(end 0.67945 -0.3048)
			(stroke
				(width 0.1)
				(type default)
			)
			(layer "F.Fab")
		)
		(fp_line
			(start 0.12065 -0.2794)
			(end 0.12065 -0.3048)
			(stroke
				(width 0.1)
				(type default)
			)
			(layer "F.Fab")
		)
		(fp_line
			(start 0.67945 -0.3048)
			(end 0.67945 0.3048)
			(stroke
				(width 0.1)
				(type default)
			)
			(layer "F.Fab")
		)
		(fp_line
			(start 0.67945 0.3048)
			(end 0.120396 0.3048)
			(stroke
				(width 0.1)
				(type default)
			)
			(layer "F.Fab")
		)
		(pad "1" smd circle
			(at -0.40005 0)
			(size 0 0)
			(layers "F.Cu" "F.Mask" "F.Paste")
			(net "HSC_FAULT_N")
		)
		(pad "2" smd circle
			(at 0.40005 0)
			(size 0 0)
			(layers "F.Cu" "F.Mask" "F.Paste")
			(net "FM_HSC_FAULT_N")
		)
	)
	(footprint ""
		(layer "F.Cu")
		(at 263.047734 -40.037258 90)
		(property "Reference" "U373"
			(at 0.501142 2.434336 90)
			(unlocked yes)
			(layer "F.SilkS")
			(effects
				(font
					(size 0.7874 0.5842)
					(thickness 0.1524)
				)
			)
		)
		(property "Value" ""
			(at 0 0 90)
			(layer "F.Fab")
			(effects
				(font
					(size 1.27 1.27)
				)
			)
		)
		(duplicate_pad_numbers_are_jumpers no)
		(fp_line
			(start -1.949958 -1.610106)
			(end 1.949958 -1.610106)
			(stroke
				(width 0.1524)
				(type default)
			)
			(layer "F.SilkS")
		)
		(fp_line
			(start 1.949958 -1.560068)
			(end 1.949958 1.610106)
			(stroke
				(width 0.1524)
				(type default)
			)
			(layer "F.SilkS")
		)
		(fp_line
			(start 1.949958 1.610106)
			(end -1.949958 1.610106)
			(stroke
				(width 0.1524)
				(type default)
			)
			(layer "F.SilkS")
		)
		(fp_line
			(start -1.949958 1.610106)
			(end -1.949958 -1.610106)
			(stroke
				(width 0.1524)
				(type default)
			)
			(layer "F.SilkS")
		)
		(fp_line
			(start 0.750062 -1.560068)
			(end 0.750062 1.560068)
			(stroke
				(width 0.1)
				(type default)
			)
			(layer "F.Fab")
		)
		(fp_line
			(start -0.750062 -1.560068)
			(end 0.750062 -1.560068)
			(stroke
				(width 0.1)
				(type default)
			)
			(layer "F.Fab")
		)
		(fp_line
			(start 0.750062 1.560068)
			(end -0.750062 1.560068)
			(stroke
				(width 0.1)
				(type default)
			)
			(layer "F.Fab")
		)
		(fp_line
			(start -0.750062 1.560068)
			(end -0.750062 -1.560068)
			(stroke
				(width 0.1)
				(type default)
			)
			(layer "F.Fab")
		)
		(pad "D" smd rect
			(at 1.100074 0)
			(size 1.016 1.4224)
			(layers "F.Cu" "F.Mask" "F.Paste")
			(net "SSD9_AUX_P3V3_EN")
		)
		(pad "G" smd rect
			(at -1.100074 -0.94996)
			(size 1.016 1.4224)
			(layers "F.Cu" "F.Mask" "F.Paste")
			(net "PRSNT_SSD9_R1_N")
		)
		(pad "S" smd rect
			(at -1.100074 0.94996)
			(size 1.016 1.4224)
			(layers "F.Cu" "F.Mask" "F.Paste")
			(net "GND")
		)
	)
	(footprint ""
		(layer "F.Cu")
		(at 80.782414 -29.875734)
		(property "Reference" "PU84"
			(at -3.011932 -1.76403 90)
			(unlocked yes)
			(layer "F.SilkS")
			(effects
				(font
					(size 0.7874 0.5842)
					(thickness 0.1524)
				)
			)
		)
		(property "Value" ""
			(at 0 0 0)
			(layer "F.Fab")
			(effects
				(font
					(size 1.27 1.27)
				)
			)
		)
		(duplicate_pad_numbers_are_jumpers no)
		(fp_line
			(start -1.239774 -1.495298)
			(end 1.239774 -1.495298)
			(stroke
				(width 0.1524)
				(type default)
			)
			(layer "F.SilkS")
		)
		(fp_line
			(start -1.239774 1.495298)
			(end -1.239774 -1.495298)
			(stroke
				(width 0.1524)
				(type default)
			)
			(layer "F.SilkS")
		)
		(fp_line
			(start 1.239774 -1.495298)
			(end 1.239774 1.495298)
			(stroke
				(width 0.1524)
				(type default)
			)
			(layer "F.SilkS")
		)
		(fp_line
			(start 1.239774 1.495298)
			(end -1.239774 1.495298)
			(stroke
				(width 0.1524)
				(type default)
			)
			(layer "F.SilkS")
		)
		(fp_poly
			(pts
				(xy -2.221738 -1.606042) (xy -2.94005 -0.887476) (xy -1.862328 -0.52832)
			)
			(stroke
				(width 0)
				(type default)
			)
			(fill yes)
			(layer "F.SilkS")
		)
		(fp_line
			(start -0.8001 -1.050036)
			(end 0.8001 -1.050036)
			(stroke
				(width 0.1)
				(type default)
			)
			(layer "F.Fab")
		)
		(fp_line
			(start -0.8001 1.050036)
			(end -0.8001 -1.050036)
			(stroke
				(width 0.1)
				(type default)
			)
			(layer "F.Fab")
		)
		(fp_line
			(start 0.8001 -1.050036)
			(end 0.8001 1.050036)
			(stroke
				(width 0.1)
				(type default)
			)
			(layer "F.Fab")
		)
		(fp_line
			(start 0.8001 1.050036)
			(end -0.8001 1.050036)
			(stroke
				(width 0.1)
				(type default)
			)
			(layer "F.Fab")
		)
		(fp_poly
			(pts
				(xy -2.458974 -0.508) (xy -2.458974 0.508) (xy -1.442974 0)
			)
			(stroke
				(width 0)
				(type default)
			)
			(fill yes)
			(layer "F.Fab")
		)
		(pad "1_2" smd circle
			(at -0.374904 0 90)
			(size 0 0)
			(layers "F.Cu" "F.Mask" "F.Paste")
			(net "P3V3_AUX")
		)
		(pad "3" smd rect
			(at -0.499872 0.999998)
			(size 0.254 0.7112)
			(layers "F.Cu" "F.Mask" "F.Paste")
			(net "GND")
		)
		(pad "4" smd rect
			(at 0 0.999998)
			(size 0.254 0.7112)
			(layers "F.Cu" "F.Mask" "F.Paste")
			(net "P3V3_SSD3_CO_ILIMIT")
		)
		(pad "5" smd rect
			(at 0.499872 0.999998)
			(size 0.254 0.7112)
			(layers "F.Cu" "F.Mask" "F.Paste")
			(net "P3V3_SSD3_CO_MODE")
		)
		(pad "6_7" smd circle
			(at 0.374904 0 270)
			(size 0 0)
			(layers "F.Cu" "F.Mask" "F.Paste")
			(net "P3V3_SSD3")
		)
		(pad "8" smd rect
			(at 0.499872 -0.999998)
			(size 0.254 0.7112)
			(layers "F.Cu" "F.Mask" "F.Paste")
			(net "P3V3_SSD3_CO_GATE")
		)
		(pad "9" smd rect
			(at 0 -0.999998)
			(size 0.254 0.7112)
			(layers "F.Cu" "F.Mask" "F.Paste")
			(net "P3V3_SSD3_CO_EN")
		)
		(pad "10" smd rect
			(at -0.499872 -0.999998)
			(size 0.254 0.7112)
			(layers "F.Cu" "F.Mask" "F.Paste")
			(net "P3V3_SSD3_CO_DV_DT")
		)
	)
	(footprint ""
		(layer "F.Cu")
		(at 207.523588 -216.886536 -90)
		(property "Reference" "U88"
			(at 1.138936 1.833118 90)
			(unlocked yes)
			(layer "F.SilkS")
			(effects
				(font
					(size 0.7874 0.5842)
					(thickness 0.1524)
				)
				(justify left)
			)
		)
		(property "Value" ""
			(at 0 0 270)
			(layer "F.Fab")
			(effects
				(font
					(size 1.27 1.27)
				)
			)
		)
		(duplicate_pad_numbers_are_jumpers no)
		(fp_line
			(start -0.8636 1.050036)
			(end 0.8636 1.050036)
			(stroke
				(width 0.1524)
				(type default)
			)
			(layer "F.SilkS")
		)
		(fp_line
			(start 0.8636 1.050036)
			(end 0.8636 -1.050036)
			(stroke
				(width 0.1524)
				(type default)
			)
			(layer "F.SilkS")
		)
		(fp_line
			(start 0 -0.508)
			(end -0.542036 -1.050036)
			(stroke
				(width 0.1524)
				(type default)
			)
			(layer "F.SilkS")
		)
		(fp_line
			(start -0.8636 -1.050036)
			(end -0.8636 1.050036)
			(stroke
				(width 0.1524)
				(type default)
			)
			(layer "F.SilkS")
		)
		(fp_line
			(start -0.542036 -1.050036)
			(end -0.8636 -1.050036)
			(stroke
				(width 0.1524)
				(type default)
			)
			(layer "F.SilkS")
		)
		(fp_line
			(start 0.542036 -1.050036)
			(end 0 -0.508)
			(stroke
				(width 0.1524)
				(type default)
			)
			(layer "F.SilkS")
		)
		(fp_line
			(start 0.8636 -1.050036)
			(end 0.542036 -1.050036)
			(stroke
				(width 0.1524)
				(type default)
			)
			(layer "F.SilkS")
		)
		(fp_poly
			(pts
				(xy -2.794 -1.258062) (xy -2.794 -0.242062) (xy -1.778 -0.750062)
			)
			(stroke
				(width 0)
				(type default)
			)
			(fill yes)
			(layer "F.SilkS")
		)
		(fp_line
			(start -1.199896 1.050036)
			(end 1.199896 1.050036)
			(stroke
				(width 0.1)
				(type default)
			)
			(layer "F.Fab")
		)
		(fp_line
			(start 1.199896 1.050036)
			(end 1.199896 -1.050036)
			(stroke
				(width 0.1)
				(type default)
			)
			(layer "F.Fab")
		)
		(fp_line
			(start -1.199896 -1.050036)
			(end -1.199896 1.050036)
			(stroke
				(width 0.1)
				(type default)
			)
			(layer "F.Fab")
		)
		(fp_line
			(start 1.199896 -1.050036)
			(end -1.199896 -1.050036)
			(stroke
				(width 0.1)
				(type default)
			)
			(layer "F.Fab")
		)
		(fp_poly
			(pts
				(xy -2.794 -1.258062) (xy -2.794 -0.242062) (xy -1.778 -0.750062)
			)
			(stroke
				(width 0)
				(type default)
			)
			(fill yes)
			(layer "F.Fab")
		)
		(pad "1" smd rect
			(at -1.35001 -0.750062 180)
			(size 0.2794 0.7112)
			(layers "F.Cu" "F.Mask" "F.Paste")
			(net "TP_FSA3357K8X_B2_RX")
		)
		(pad "2" smd rect
			(at -1.35001 -0.249936 180)
			(size 0.2794 0.7112)
			(layers "F.Cu" "F.Mask" "F.Paste")
			(net "UART_MB_BIC_RX_BUF_R")
		)
		(pad "3" smd rect
			(at -1.35001 0.249936 180)
			(size 0.2794 0.7112)
			(layers "F.Cu" "F.Mask" "F.Paste")
			(net "UART_FIO_DEBUG_R_RX")
		)
		(pad "4" smd rect
			(at -1.35001 0.750062 180)
			(size 0.2794 0.7112)
			(layers "F.Cu" "F.Mask" "F.Paste")
			(net "GND")
		)
		(pad "5" smd rect
			(at 1.35001 0.750062 180)
			(size 0.2794 0.7112)
			(layers "F.Cu" "F.Mask" "F.Paste")
			(net "BIC_UART_SEL2")
		)
		(pad "6" smd rect
			(at 1.35001 0.249936 180)
			(size 0.2794 0.7112)
			(layers "F.Cu" "F.Mask" "F.Paste")
			(net "BIC_UART_SEL1")
		)
		(pad "7" smd rect
			(at 1.35001 -0.249936 180)
			(size 0.2794 0.7112)
			(layers "F.Cu" "F.Mask" "F.Paste")
			(net "UART_BIC_DEBUG_RX")
		)
		(pad "8" smd rect
			(at 1.35001 -0.750062 180)
			(size 0.2794 0.7112)
			(layers "F.Cu" "F.Mask" "F.Paste")
			(net "P3V3_AUX")
		)
	)
	(footprint ""
		(layer "F.Cu")
		(at 344.612976 -83.255358 180)
		(property "Reference" "R1176"
			(at 0 0 180)
			(layer "F.SilkS")
			(hide yes)
			(effects
				(font
					(size 1.27 1.27)
				)
			)
		)
		(property "Value" ""
			(at 0 0 180)
			(layer "F.Fab")
			(effects
				(font
					(size 1.27 1.27)
				)
			)
		)
		(duplicate_pad_numbers_are_jumpers no)
		(fp_line
			(start -0.7874 -0.4064)
			(end 0.7874 -0.4064)
			(stroke
				(width 0.1524)
				(type default)
			)
			(layer "F.SilkS")
		)
		(fp_line
			(start 0.67945 0.3048)
			(end 0.120396 0.3048)
			(stroke
				(width 0.1)
				(type default)
			)
			(layer "F.Fab")
		)
		(fp_line
			(start 0.67945 -0.3048)
			(end 0.67945 0.3048)
			(stroke
				(width 0.1)
				(type default)
			)
			(layer "F.Fab")
		)
		(fp_line
			(start 0.12065 -0.2794)
			(end 0.12065 -0.3048)
			(stroke
				(width 0.1)
				(type default)
			)
			(layer "F.Fab")
		)
		(fp_line
			(start 0.12065 -0.3048)
			(end 0.67945 -0.3048)
			(stroke
				(width 0.1)
				(type default)
			)
			(layer "F.Fab")
		)
		(fp_line
			(start 0.120396 0.3048)
			(end 0.120396 0.2794)
			(stroke
				(width 0.1)
				(type default)
			)
			(layer "F.Fab")
		)
		(fp_line
			(start 0.120396 0.2794)
			(end -0.12065 0.2794)
			(stroke
				(width 0.1)
				(type default)
			)
			(layer "F.Fab")
		)
		(fp_line
			(start -0.12065 0.3048)
			(end -0.67945 0.3048)
			(stroke
				(width 0.1)
				(type default)
			)
			(layer "F.Fab")
		)
		(fp_line
			(start -0.12065 0.2794)
			(end -0.12065 0.3048)
			(stroke
				(width 0.1)
				(type default)
			)
			(layer "F.Fab")
		)
		(fp_line
			(start -0.12065 -0.2794)
			(end 0.12065 -0.2794)
			(stroke
				(width 0.1)
				(type default)
			)
			(layer "F.Fab")
		)
		(fp_line
			(start -0.12065 -0.305054)
			(end -0.12065 -0.2794)
			(stroke
				(width 0.1)
				(type default)
			)
			(layer "F.Fab")
		)
		(fp_line
			(start -0.67945 0.3048)
			(end -0.67945 -0.305054)
			(stroke
				(width 0.1)
				(type default)
			)
			(layer "F.Fab")
		)
		(fp_line
			(start -0.67945 -0.305054)
			(end -0.12065 -0.305054)
			(stroke
				(width 0.1)
				(type default)
			)
			(layer "F.Fab")
		)
		(pad "1" smd circle
			(at -0.40005 0 180)
			(size 0 0)
			(layers "F.Cu" "F.Mask" "F.Paste")
			(net "CLK_100M_DB800ZL_SSD11_R_DP")
		)
		(pad "2" smd circle
			(at 0.40005 0 180)
			(size 0 0)
			(layers "F.Cu" "F.Mask" "F.Paste")
			(net "CLK_100M_DB800ZL_SSD11_DP")
		)
	)
	(footprint ""
		(layer "F.Cu")
		(at 137.622788 -343.952322 90)
		(property "Reference" "C2252"
			(at 0 0 90)
			(layer "F.SilkS")
			(hide yes)
			(effects
				(font
					(size 1.27 1.27)
				)
			)
		)
		(property "Value" ""
			(at 0 0 90)
			(layer "F.Fab")
			(effects
				(font
					(size 1.27 1.27)
				)
			)
		)
		(duplicate_pad_numbers_are_jumpers no)
		(fp_line
			(start 0.299974 -0.150114)
			(end 0.299974 0.150114)
			(stroke
				(width 0.1)
				(type default)
			)
			(layer "F.Fab")
		)
		(fp_line
			(start -0.299974 -0.150114)
			(end 0.299974 -0.150114)
			(stroke
				(width 0.1)
				(type default)
			)
			(layer "F.Fab")
		)
		(fp_line
			(start 0.299974 0.150114)
			(end -0.299974 0.150114)
			(stroke
				(width 0.1)
				(type default)
			)
			(layer "F.Fab")
		)
		(fp_line
			(start -0.299974 0.150114)
			(end -0.299974 -0.150114)
			(stroke
				(width 0.1)
				(type default)
			)
			(layer "F.Fab")
		)
		(pad "1" smd rect
			(at -0.2667 0 90)
			(size 0.3048 0.381)
			(layers "F.Cu" "F.Mask" "F.Paste")
			(net "P5E_PEX1_STN5_TX_DN<91>")
		)
		(pad "2" smd rect
			(at 0.2667 0 90)
			(size 0.3048 0.381)
			(layers "F.Cu" "F.Mask" "F.Paste")
			(net "P5E_PEX1_STN5_TX_C_DN<91>")
		)
	)
	(footprint ""
		(layer "F.Cu")
		(at 52.243736 -46.90491)
		(property "Reference" "R520"
			(at 0 0 0)
			(layer "F.SilkS")
			(hide yes)
			(effects
				(font
					(size 1.27 1.27)
				)
			)
		)
		(property "Value" ""
			(at 0 0 0)
			(layer "F.Fab")
			(effects
				(font
					(size 1.27 1.27)
				)
			)
		)
		(duplicate_pad_numbers_are_jumpers no)
		(fp_line
			(start -0.7874 -0.4064)
			(end 0.7874 -0.4064)
			(stroke
				(width 0.1524)
				(type default)
			)
			(layer "F.SilkS")
		)
		(fp_line
			(start -0.7874 0.4064)
			(end -0.7874 -0.4064)
			(stroke
				(width 0.1524)
				(type default)
			)
			(layer "F.SilkS")
		)
		(fp_line
			(start 0.7874 -0.4064)
			(end 0.7874 0.4064)
			(stroke
				(width 0.1524)
				(type default)
			)
			(layer "F.SilkS")
		)
		(fp_line
			(start 0.7874 0.4064)
			(end -0.7874 0.4064)
			(stroke
				(width 0.1524)
				(type default)
			)
			(layer "F.SilkS")
		)
		(fp_line
			(start -0.67945 -0.305054)
			(end -0.12065 -0.305054)
			(stroke
				(width 0.1)
				(type default)
			)
			(layer "F.Fab")
		)
		(fp_line
			(start -0.67945 0.3048)
			(end -0.67945 -0.305054)
			(stroke
				(width 0.1)
				(type default)
			)
			(layer "F.Fab")
		)
		(fp_line
			(start -0.12065 -0.305054)
			(end -0.12065 -0.2794)
			(stroke
				(width 0.1)
				(type default)
			)
			(layer "F.Fab")
		)
		(fp_line
			(start -0.12065 -0.2794)
			(end 0.12065 -0.2794)
			(stroke
				(width 0.1)
				(type default)
			)
			(layer "F.Fab")
		)
		(fp_line
			(start -0.12065 0.2794)
			(end -0.12065 0.3048)
			(stroke
				(width 0.1)
				(type default)
			)
			(layer "F.Fab")
		)
		(fp_line
			(start -0.12065 0.3048)
			(end -0.67945 0.3048)
			(stroke
				(width 0.1)
				(type default)
			)
			(layer "F.Fab")
		)
		(fp_line
			(start 0.120396 0.2794)
			(end -0.12065 0.2794)
			(stroke
				(width 0.1)
				(type default)
			)
			(layer "F.Fab")
		)
		(fp_line
			(start 0.120396 0.3048)
			(end 0.120396 0.2794)
			(stroke
				(width 0.1)
				(type default)
			)
			(layer "F.Fab")
		)
		(fp_line
			(start 0.12065 -0.3048)
			(end 0.67945 -0.3048)
			(stroke
				(width 0.1)
				(type default)
			)
			(layer "F.Fab")
		)
		(fp_line
			(start 0.12065 -0.2794)
			(end 0.12065 -0.3048)
			(stroke
				(width 0.1)
				(type default)
			)
			(layer "F.Fab")
		)
		(fp_line
			(start 0.67945 -0.3048)
			(end 0.67945 0.3048)
			(stroke
				(width 0.1)
				(type default)
			)
			(layer "F.Fab")
		)
		(fp_line
			(start 0.67945 0.3048)
			(end 0.120396 0.3048)
			(stroke
				(width 0.1)
				(type default)
			)
			(layer "F.Fab")
		)
		(pad "1" smd circle
			(at -0.40005 0)
			(size 0 0)
			(layers "F.Cu" "F.Mask" "F.Paste")
			(net "SSD1_ADC_ALERT_N")
		)
		(pad "2" smd circle
			(at 0.40005 0)
			(size 0 0)
			(layers "F.Cu" "F.Mask" "F.Paste")
			(net "SSD_0_7_ADC_ALERT_N")
		)
	)
	(footprint ""
		(layer "F.Cu")
		(at 121.39422 -34.248852)
		(property "Reference" "R5667"
			(at 0 0 0)
			(layer "F.SilkS")
			(hide yes)
			(effects
				(font
					(size 1.27 1.27)
				)
			)
		)
		(property "Value" ""
			(at 0 0 0)
			(layer "F.Fab")
			(effects
				(font
					(size 1.27 1.27)
				)
			)
		)
		(duplicate_pad_numbers_are_jumpers no)
		(fp_line
			(start -0.7874 -0.4064)
			(end 0.7874 -0.4064)
			(stroke
				(width 0.1524)
				(type default)
			)
			(layer "F.SilkS")
		)
		(fp_line
			(start -0.7874 0.4064)
			(end -0.7874 -0.4064)
			(stroke
				(width 0.1524)
				(type default)
			)
			(layer "F.SilkS")
		)
		(fp_line
			(start 0.7874 -0.4064)
			(end 0.7874 0.4064)
			(stroke
				(width 0.1524)
				(type default)
			)
			(layer "F.SilkS")
		)
		(fp_line
			(start 0.7874 0.4064)
			(end -0.7874 0.4064)
			(stroke
				(width 0.1524)
				(type default)
			)
			(layer "F.SilkS")
		)
		(fp_line
			(start -0.67945 -0.305054)
			(end -0.12065 -0.305054)
			(stroke
				(width 0.1)
				(type default)
			)
			(layer "F.Fab")
		)
		(fp_line
			(start -0.67945 0.3048)
			(end -0.67945 -0.305054)
			(stroke
				(width 0.1)
				(type default)
			)
			(layer "F.Fab")
		)
		(fp_line
			(start -0.12065 -0.305054)
			(end -0.12065 -0.2794)
			(stroke
				(width 0.1)
				(type default)
			)
			(layer "F.Fab")
		)
		(fp_line
			(start -0.12065 -0.2794)
			(end 0.12065 -0.2794)
			(stroke
				(width 0.1)
				(type default)
			)
			(layer "F.Fab")
		)
		(fp_line
			(start -0.12065 0.2794)
			(end -0.12065 0.3048)
			(stroke
				(width 0.1)
				(type default)
			)
			(layer "F.Fab")
		)
		(fp_line
			(start -0.12065 0.3048)
			(end -0.67945 0.3048)
			(stroke
				(width 0.1)
				(type default)
			)
			(layer "F.Fab")
		)
		(fp_line
			(start 0.120396 0.2794)
			(end -0.12065 0.2794)
			(stroke
				(width 0.1)
				(type default)
			)
			(layer "F.Fab")
		)
		(fp_line
			(start 0.120396 0.3048)
			(end 0.120396 0.2794)
			(stroke
				(width 0.1)
				(type default)
			)
			(layer "F.Fab")
		)
		(fp_line
			(start 0.12065 -0.3048)
			(end 0.67945 -0.3048)
			(stroke
				(width 0.1)
				(type default)
			)
			(layer "F.Fab")
		)
		(fp_line
			(start 0.12065 -0.2794)
			(end 0.12065 -0.3048)
			(stroke
				(width 0.1)
				(type default)
			)
			(layer "F.Fab")
		)
		(fp_line
			(start 0.67945 -0.3048)
			(end 0.67945 0.3048)
			(stroke
				(width 0.1)
				(type default)
			)
			(layer "F.Fab")
		)
		(fp_line
			(start 0.67945 0.3048)
			(end 0.120396 0.3048)
			(stroke
				(width 0.1)
				(type default)
			)
			(layer "F.Fab")
		)
		(pad "1" smd circle
			(at -0.40005 0)
			(size 0 0)
			(layers "F.Cu" "F.Mask" "F.Paste")
			(net "RST_SMB_SSD4_ISO_N")
		)
		(pad "2" smd circle
			(at 0.40005 0)
			(size 0 0)
			(layers "F.Cu" "F.Mask" "F.Paste")
			(net "P3V3_SSD4")
		)
	)
	(footprint ""
		(layer "F.Cu")
		(at 196.441822 -27.006296 -90)
		(property "Reference" "PR7114"
			(at 0 0 270)
			(layer "F.SilkS")
			(hide yes)
			(effects
				(font
					(size 1.27 1.27)
				)
			)
		)
		(property "Value" ""
			(at 0 0 270)
			(layer "F.Fab")
			(effects
				(font
					(size 1.27 1.27)
				)
			)
		)
		(duplicate_pad_numbers_are_jumpers no)
		(fp_line
			(start -0.7874 0.4064)
			(end -0.7874 -0.4064)
			(stroke
				(width 0.1524)
				(type default)
			)
			(layer "F.SilkS")
		)
		(fp_line
			(start 0.7874 0.4064)
			(end -0.7874 0.4064)
			(stroke
				(width 0.1524)
				(type default)
			)
			(layer "F.SilkS")
		)
		(fp_line
			(start -0.7874 -0.4064)
			(end 0.7874 -0.4064)
			(stroke
				(width 0.1524)
				(type default)
			)
			(layer "F.SilkS")
		)
		(fp_line
			(start 0.7874 -0.4064)
			(end 0.7874 0.4064)
			(stroke
				(width 0.1524)
				(type default)
			)
			(layer "F.SilkS")
		)
		(fp_line
			(start -0.67945 0.3048)
			(end -0.67945 -0.305054)
			(stroke
				(width 0.1)
				(type default)
			)
			(layer "F.Fab")
		)
		(fp_line
			(start -0.12065 0.3048)
			(end -0.67945 0.3048)
			(stroke
				(width 0.1)
				(type default)
			)
			(layer "F.Fab")
		)
		(fp_line
			(start 0.120396 0.3048)
			(end 0.120396 0.2794)
			(stroke
				(width 0.1)
				(type default)
			)
			(layer "F.Fab")
		)
		(fp_line
			(start 0.67945 0.3048)
			(end 0.120396 0.3048)
			(stroke
				(width 0.1)
				(type default)
			)
			(layer "F.Fab")
		)
		(fp_line
			(start -0.12065 0.2794)
			(end -0.12065 0.3048)
			(stroke
				(width 0.1)
				(type default)
			)
			(layer "F.Fab")
		)
		(fp_line
			(start 0.120396 0.2794)
			(end -0.12065 0.2794)
			(stroke
				(width 0.1)
				(type default)
			)
			(layer "F.Fab")
		)
		(fp_line
			(start -0.12065 -0.2794)
			(end 0.12065 -0.2794)
			(stroke
				(width 0.1)
				(type default)
			)
			(layer "F.Fab")
		)
		(fp_line
			(start 0.12065 -0.2794)
			(end 0.12065 -0.3048)
			(stroke
				(width 0.1)
				(type default)
			)
			(layer "F.Fab")
		)
		(fp_line
			(start 0.12065 -0.3048)
			(end 0.67945 -0.3048)
			(stroke
				(width 0.1)
				(type default)
			)
			(layer "F.Fab")
		)
		(fp_line
			(start 0.67945 -0.3048)
			(end 0.67945 0.3048)
			(stroke
				(width 0.1)
				(type default)
			)
			(layer "F.Fab")
		)
		(fp_line
			(start -0.67945 -0.305054)
			(end -0.12065 -0.305054)
			(stroke
				(width 0.1)
				(type default)
			)
			(layer "F.Fab")
		)
		(fp_line
			(start -0.12065 -0.305054)
			(end -0.12065 -0.2794)
			(stroke
				(width 0.1)
				(type default)
			)
			(layer "F.Fab")
		)
		(pad "1" smd circle
			(at -0.40005 0 270)
			(size 0 0)
			(layers "F.Cu" "F.Mask" "F.Paste")
			(net "P3V3_SSD7_CO_ILIMIT")
		)
		(pad "2" smd circle
			(at 0.40005 0 270)
			(size 0 0)
			(layers "F.Cu" "F.Mask" "F.Paste")
			(net "GND")
		)
	)
	(footprint ""
		(layer "F.Cu")
		(at 369.813586 -254.753364 -90)
		(property "Reference" "R6156"
			(at 0 0 270)
			(layer "F.SilkS")
			(hide yes)
			(effects
				(font
					(size 1.27 1.27)
				)
			)
		)
		(property "Value" ""
			(at 0 0 270)
			(layer "F.Fab")
			(effects
				(font
					(size 1.27 1.27)
				)
			)
		)
		(duplicate_pad_numbers_are_jumpers no)
		(fp_line
			(start -0.7874 0.4064)
			(end -0.7874 -0.4064)
			(stroke
				(width 0.1524)
				(type default)
			)
			(layer "F.SilkS")
		)
		(fp_line
			(start 0.7874 0.4064)
			(end -0.7874 0.4064)
			(stroke
				(width 0.1524)
				(type default)
			)
			(layer "F.SilkS")
		)
		(fp_line
			(start -0.7874 -0.4064)
			(end 0.7874 -0.4064)
			(stroke
				(width 0.1524)
				(type default)
			)
			(layer "F.SilkS")
		)
		(fp_line
			(start 0.7874 -0.4064)
			(end 0.7874 0.4064)
			(stroke
				(width 0.1524)
				(type default)
			)
			(layer "F.SilkS")
		)
		(fp_line
			(start -0.67945 0.3048)
			(end -0.67945 -0.305054)
			(stroke
				(width 0.1)
				(type default)
			)
			(layer "F.Fab")
		)
		(fp_line
			(start -0.12065 0.3048)
			(end -0.67945 0.3048)
			(stroke
				(width 0.1)
				(type default)
			)
			(layer "F.Fab")
		)
		(fp_line
			(start 0.120396 0.3048)
			(end 0.120396 0.2794)
			(stroke
				(width 0.1)
				(type default)
			)
			(layer "F.Fab")
		)
		(fp_line
			(start 0.67945 0.3048)
			(end 0.120396 0.3048)
			(stroke
				(width 0.1)
				(type default)
			)
			(layer "F.Fab")
		)
		(fp_line
			(start -0.12065 0.2794)
			(end -0.12065 0.3048)
			(stroke
				(width 0.1)
				(type default)
			)
			(layer "F.Fab")
		)
		(fp_line
			(start 0.120396 0.2794)
			(end -0.12065 0.2794)
			(stroke
				(width 0.1)
				(type default)
			)
			(layer "F.Fab")
		)
		(fp_line
			(start -0.12065 -0.2794)
			(end 0.12065 -0.2794)
			(stroke
				(width 0.1)
				(type default)
			)
			(layer "F.Fab")
		)
		(fp_line
			(start 0.12065 -0.2794)
			(end 0.12065 -0.3048)
			(stroke
				(width 0.1)
				(type default)
			)
			(layer "F.Fab")
		)
		(fp_line
			(start 0.12065 -0.3048)
			(end 0.67945 -0.3048)
			(stroke
				(width 0.1)
				(type default)
			)
			(layer "F.Fab")
		)
		(fp_line
			(start 0.67945 -0.3048)
			(end 0.67945 0.3048)
			(stroke
				(width 0.1)
				(type default)
			)
			(layer "F.Fab")
		)
		(fp_line
			(start -0.67945 -0.305054)
			(end -0.12065 -0.305054)
			(stroke
				(width 0.1)
				(type default)
			)
			(layer "F.Fab")
		)
		(fp_line
			(start -0.12065 -0.305054)
			(end -0.12065 -0.2794)
			(stroke
				(width 0.1)
				(type default)
			)
			(layer "F.Fab")
		)
		(pad "1" smd circle
			(at -0.40005 0 270)
			(size 0 0)
			(layers "F.Cu" "F.Mask" "F.Paste")
			(net "PEX3_SYS_ERR_R_N")
		)
		(pad "2" smd circle
			(at 0.40005 0 270)
			(size 0 0)
			(layers "F.Cu" "F.Mask" "F.Paste")
			(net "P1V8_PEX")
		)
	)
	(footprint ""
		(layer "F.Cu")
		(at 345.710002 -293.5351 90)
		(property "Reference" "PL13"
			(at -4.920234 22.928072 90)
			(unlocked yes)
			(layer "F.SilkS")
			(effects
				(font
					(size 0.7874 0.5842)
					(thickness 0.1524)
				)
				(justify left)
			)
		)
		(property "Value" ""
			(at 0 0 90)
			(layer "F.Fab")
			(effects
				(font
					(size 1.27 1.27)
				)
			)
		)
		(duplicate_pad_numbers_are_jumpers no)
		(fp_line
			(start 4.800092 -3.199892)
			(end 4.800092 -1.6764)
			(stroke
				(width 0.1524)
				(type default)
			)
			(layer "F.SilkS")
		)
		(fp_line
			(start -4.800092 -3.199892)
			(end 4.800092 -3.199892)
			(stroke
				(width 0.1524)
				(type default)
			)
			(layer "F.SilkS")
		)
		(fp_line
			(start -4.800092 -1.6764)
			(end -4.800092 -3.199892)
			(stroke
				(width 0.1524)
				(type default)
			)
			(layer "F.SilkS")
		)
		(fp_line
			(start 4.800092 1.6764)
			(end 4.800092 3.199892)
			(stroke
				(width 0.1524)
				(type default)
			)
			(layer "F.SilkS")
		)
		(fp_line
			(start 4.800092 3.199892)
			(end -4.800092 3.199892)
			(stroke
				(width 0.1524)
				(type default)
			)
			(layer "F.SilkS")
		)
		(fp_line
			(start -4.800092 3.199892)
			(end -4.800092 1.6764)
			(stroke
				(width 0.1524)
				(type default)
			)
			(layer "F.SilkS")
		)
		(fp_line
			(start 4.800092 -3.199892)
			(end 4.800092 3.199892)
			(stroke
				(width 0.1)
				(type default)
			)
			(layer "F.Fab")
		)
		(fp_line
			(start -4.800092 -3.199892)
			(end 4.800092 -3.199892)
			(stroke
				(width 0.1)
				(type default)
			)
			(layer "F.Fab")
		)
		(fp_line
			(start 4.800092 3.199892)
			(end -4.800092 3.199892)
			(stroke
				(width 0.1)
				(type default)
			)
			(layer "F.Fab")
		)
		(fp_line
			(start -4.800092 3.199892)
			(end -4.800092 -3.199892)
			(stroke
				(width 0.1)
				(type default)
			)
			(layer "F.Fab")
		)
		(pad "1" smd rect
			(at -3.074924 0 180)
			(size 3.0988 3.3528)
			(layers "F.Cu" "F.Mask" "F.Paste")
			(net "SW_P0V8_PEX2_PH2")
		)
		(pad "2" smd rect
			(at 3.074924 0 180)
			(size 3.0988 3.3528)
			(layers "F.Cu" "F.Mask" "F.Paste")
			(net "P0V8_PEX2")
		)
	)
	(footprint ""
		(layer "F.Cu")
		(at 216.480136 -181.613556 -90)
		(property "Reference" "R5297"
			(at 0 0 270)
			(layer "F.SilkS")
			(hide yes)
			(effects
				(font
					(size 1.27 1.27)
				)
			)
		)
		(property "Value" ""
			(at 0 0 270)
			(layer "F.Fab")
			(effects
				(font
					(size 1.27 1.27)
				)
			)
		)
		(duplicate_pad_numbers_are_jumpers no)
		(fp_line
			(start -0.7874 0.4064)
			(end -0.7874 -0.4064)
			(stroke
				(width 0.1524)
				(type default)
			)
			(layer "F.SilkS")
		)
		(fp_line
			(start 0.7874 0.4064)
			(end -0.7874 0.4064)
			(stroke
				(width 0.1524)
				(type default)
			)
			(layer "F.SilkS")
		)
		(fp_line
			(start -0.7874 -0.4064)
			(end 0.7874 -0.4064)
			(stroke
				(width 0.1524)
				(type default)
			)
			(layer "F.SilkS")
		)
		(fp_line
			(start 0.7874 -0.4064)
			(end 0.7874 0.4064)
			(stroke
				(width 0.1524)
				(type default)
			)
			(layer "F.SilkS")
		)
		(fp_line
			(start -0.67945 0.3048)
			(end -0.67945 -0.305054)
			(stroke
				(width 0.1)
				(type default)
			)
			(layer "F.Fab")
		)
		(fp_line
			(start -0.12065 0.3048)
			(end -0.67945 0.3048)
			(stroke
				(width 0.1)
				(type default)
			)
			(layer "F.Fab")
		)
		(fp_line
			(start 0.120396 0.3048)
			(end 0.120396 0.2794)
			(stroke
				(width 0.1)
				(type default)
			)
			(layer "F.Fab")
		)
		(fp_line
			(start 0.67945 0.3048)
			(end 0.120396 0.3048)
			(stroke
				(width 0.1)
				(type default)
			)
			(layer "F.Fab")
		)
		(fp_line
			(start -0.12065 0.2794)
			(end -0.12065 0.3048)
			(stroke
				(width 0.1)
				(type default)
			)
			(layer "F.Fab")
		)
		(fp_line
			(start 0.120396 0.2794)
			(end -0.12065 0.2794)
			(stroke
				(width 0.1)
				(type default)
			)
			(layer "F.Fab")
		)
		(fp_line
			(start -0.12065 -0.2794)
			(end 0.12065 -0.2794)
			(stroke
				(width 0.1)
				(type default)
			)
			(layer "F.Fab")
		)
		(fp_line
			(start 0.12065 -0.2794)
			(end 0.12065 -0.3048)
			(stroke
				(width 0.1)
				(type default)
			)
			(layer "F.Fab")
		)
		(fp_line
			(start 0.12065 -0.3048)
			(end 0.67945 -0.3048)
			(stroke
				(width 0.1)
				(type default)
			)
			(layer "F.Fab")
		)
		(fp_line
			(start 0.67945 -0.3048)
			(end 0.67945 0.3048)
			(stroke
				(width 0.1)
				(type default)
			)
			(layer "F.Fab")
		)
		(fp_line
			(start -0.67945 -0.305054)
			(end -0.12065 -0.305054)
			(stroke
				(width 0.1)
				(type default)
			)
			(layer "F.Fab")
		)
		(fp_line
			(start -0.12065 -0.305054)
			(end -0.12065 -0.2794)
			(stroke
				(width 0.1)
				(type default)
			)
			(layer "F.Fab")
		)
		(pad "1" smd circle
			(at -0.40005 0 270)
			(size 0 0)
			(layers "F.Cu" "F.Mask" "F.Paste")
			(net "SEL_FLASH_PEX0_BUF")
		)
		(pad "2" smd circle
			(at 0.40005 0 270)
			(size 0 0)
			(layers "F.Cu" "F.Mask" "F.Paste")
			(net "SEL_FLASH_PEX0_BUF_R")
		)
	)
	(footprint ""
		(layer "F.Cu")
		(at 190.141352 -350.098614 90)
		(property "Reference" "C374"
			(at 0 0 90)
			(layer "F.SilkS")
			(hide yes)
			(effects
				(font
					(size 1.27 1.27)
				)
			)
		)
		(property "Value" ""
			(at 0 0 90)
			(layer "F.Fab")
			(effects
				(font
					(size 1.27 1.27)
				)
			)
		)
		(duplicate_pad_numbers_are_jumpers no)
		(fp_line
			(start 0.299974 -0.150114)
			(end 0.299974 0.150114)
			(stroke
				(width 0.1)
				(type default)
			)
			(layer "F.Fab")
		)
		(fp_line
			(start -0.299974 -0.150114)
			(end 0.299974 -0.150114)
			(stroke
				(width 0.1)
				(type default)
			)
			(layer "F.Fab")
		)
		(fp_line
			(start 0.299974 0.150114)
			(end -0.299974 0.150114)
			(stroke
				(width 0.1)
				(type default)
			)
			(layer "F.Fab")
		)
		(fp_line
			(start -0.299974 0.150114)
			(end -0.299974 -0.150114)
			(stroke
				(width 0.1)
				(type default)
			)
			(layer "F.Fab")
		)
		(pad "1" smd rect
			(at -0.2667 0 90)
			(size 0.3048 0.381)
			(layers "F.Cu" "F.Mask" "F.Paste")
			(net "P5E_PEX1_STN7_TX_DP<126>")
		)
		(pad "2" smd rect
			(at 0.2667 0 90)
			(size 0.3048 0.381)
			(layers "F.Cu" "F.Mask" "F.Paste")
			(net "P5E_PEX1_STN7_TX_C_DP<126>")
		)
	)
	(footprint ""
		(layer "F.Cu")
		(at 33.287716 -291.619432)
		(property "Reference" "C3042"
			(at 0 0 0)
			(layer "F.SilkS")
			(hide yes)
			(effects
				(font
					(size 1.27 1.27)
				)
			)
		)
		(property "Value" ""
			(at 0 0 0)
			(layer "F.Fab")
			(effects
				(font
					(size 1.27 1.27)
				)
			)
		)
		(duplicate_pad_numbers_are_jumpers no)
		(fp_line
			(start -1.2954 -0.5842)
			(end 1.2954 -0.5842)
			(stroke
				(width 0.1524)
				(type default)
			)
			(layer "F.SilkS")
		)
		(fp_line
			(start -1.2954 0.5842)
			(end -1.2954 -0.5842)
			(stroke
				(width 0.1524)
				(type default)
			)
			(layer "F.SilkS")
		)
		(fp_line
			(start 1.2954 -0.5842)
			(end 1.2954 0.5842)
			(stroke
				(width 0.1524)
				(type default)
			)
			(layer "F.SilkS")
		)
		(fp_line
			(start 1.2954 0.5842)
			(end -1.2954 0.5842)
			(stroke
				(width 0.1524)
				(type default)
			)
			(layer "F.SilkS")
		)
		(fp_line
			(start -1.1938 -0.4064)
			(end -0.8636 -0.4064)
			(stroke
				(width 0.1)
				(type default)
			)
			(layer "F.Fab")
		)
		(fp_line
			(start -1.1938 0.4064)
			(end -1.1938 -0.4064)
			(stroke
				(width 0.1)
				(type default)
			)
			(layer "F.Fab")
		)
		(fp_line
			(start -0.8636 -0.4572)
			(end 0.8636 -0.4572)
			(stroke
				(width 0.1)
				(type default)
			)
			(layer "F.Fab")
		)
		(fp_line
			(start -0.8636 -0.4064)
			(end -0.8636 -0.4572)
			(stroke
				(width 0.1)
				(type default)
			)
			(layer "F.Fab")
		)
		(fp_line
			(start -0.8636 0.4064)
			(end -1.1938 0.4064)
			(stroke
				(width 0.1)
				(type default)
			)
			(layer "F.Fab")
		)
		(fp_line
			(start -0.8636 0.4572)
			(end -0.8636 0.4064)
			(stroke
				(width 0.1)
				(type default)
			)
			(layer "F.Fab")
		)
		(fp_line
			(start 0.8636 -0.4572)
			(end 0.8636 -0.4064)
			(stroke
				(width 0.1)
				(type default)
			)
			(layer "F.Fab")
		)
		(fp_line
			(start 0.8636 -0.4064)
			(end 1.1938 -0.4064)
			(stroke
				(width 0.1)
				(type default)
			)
			(layer "F.Fab")
		)
		(fp_line
			(start 0.8636 0.4064)
			(end 0.8636 0.4572)
			(stroke
				(width 0.1)
				(type default)
			)
			(layer "F.Fab")
		)
		(fp_line
			(start 0.8636 0.4572)
			(end -0.8636 0.4572)
			(stroke
				(width 0.1)
				(type default)
			)
			(layer "F.Fab")
		)
		(fp_line
			(start 1.1938 -0.4064)
			(end 1.1938 0.4064)
			(stroke
				(width 0.1)
				(type default)
			)
			(layer "F.Fab")
		)
		(fp_line
			(start 1.1938 0.4064)
			(end 0.8636 0.4064)
			(stroke
				(width 0.1)
				(type default)
			)
			(layer "F.Fab")
		)
		(pad "1" smd rect
			(at -0.7366 0 270)
			(size 0.7112 0.8128)
			(layers "F.Cu" "F.Mask" "F.Paste")
			(net "PCEPLL4_VDDA18_PEX0")
		)
		(pad "2" smd rect
			(at 0.7366 0 270)
			(size 0.7112 0.8128)
			(layers "F.Cu" "F.Mask" "F.Paste")
			(net "GND")
		)
	)
	(footprint ""
		(layer "F.Cu")
		(at 228.446838 -277.791926 180)
		(property "Reference" "U90"
			(at -2.584958 -6.057392 0)
			(unlocked yes)
			(layer "F.SilkS")
			(effects
				(font
					(size 0.7874 0.5842)
					(thickness 0.1524)
				)
			)
		)
		(property "Value" ""
			(at 0 0 180)
			(layer "F.Fab")
			(effects
				(font
					(size 1.27 1.27)
				)
			)
		)
		(duplicate_pad_numbers_are_jumpers no)
		(fp_line
			(start 1.500124 1.500124)
			(end 1.004062 1.500124)
			(stroke
				(width 0.1524)
				(type default)
			)
			(layer "F.SilkS")
		)
		(fp_line
			(start 1.500124 1.004062)
			(end 1.500124 1.500124)
			(stroke
				(width 0.1524)
				(type default)
			)
			(layer "F.SilkS")
		)
		(fp_line
			(start 1.500124 -1.500124)
			(end 1.500124 -1.004062)
			(stroke
				(width 0.1524)
				(type default)
			)
			(layer "F.SilkS")
		)
		(fp_line
			(start 1.004062 -1.500124)
			(end 1.500124 -1.500124)
			(stroke
				(width 0.1524)
				(type default)
			)
			(layer "F.SilkS")
		)
		(fp_line
			(start -1.004062 1.500124)
			(end -1.500124 1.500124)
			(stroke
				(width 0.1524)
				(type default)
			)
			(layer "F.SilkS")
		)
		(fp_line
			(start -1.500124 1.500124)
			(end -1.500124 1.004062)
			(stroke
				(width 0.1524)
				(type default)
			)
			(layer "F.SilkS")
		)
		(fp_line
			(start -1.500124 -1.004062)
			(end -1.500124 -1.500124)
			(stroke
				(width 0.1524)
				(type default)
			)
			(layer "F.SilkS")
		)
		(fp_line
			(start -1.500124 -1.500124)
			(end -1.004062 -1.500124)
			(stroke
				(width 0.1524)
				(type default)
			)
			(layer "F.SilkS")
		)
		(fp_poly
			(pts
				(xy -1.307084 -2.106676) (xy -2.323084 -2.106676) (xy -1.815084 -1.090676)
			)
			(stroke
				(width 0)
				(type default)
			)
			(fill yes)
			(layer "F.SilkS")
		)
		(fp_line
			(start 1.500124 1.500124)
			(end -1.500124 1.500124)
			(stroke
				(width 0.1)
				(type default)
			)
			(layer "F.Fab")
		)
		(fp_line
			(start 1.500124 -1.500124)
			(end 1.500124 1.500124)
			(stroke
				(width 0.1)
				(type default)
			)
			(layer "F.Fab")
		)
		(fp_line
			(start -1.500124 1.500124)
			(end -1.500124 -1.500124)
			(stroke
				(width 0.1)
				(type default)
			)
			(layer "F.Fab")
		)
		(fp_line
			(start -1.500124 -1.500124)
			(end 1.500124 -1.500124)
			(stroke
				(width 0.1)
				(type default)
			)
			(layer "F.Fab")
		)
		(fp_poly
			(pts
				(xy -2.847848 -1.258062) (xy -2.847848 -0.242062) (xy -1.831848 -0.750062)
			)
			(stroke
				(width 0)
				(type default)
			)
			(fill yes)
			(layer "F.Fab")
		)
		(pad "1" smd rect
			(at -1.400048 -0.750062 90)
			(size 0.2286 0.6096)
			(layers "F.Cu" "F.Mask" "F.Paste")
			(net "PEX1_P1V25_ADC_A1")
		)
		(pad "2" smd rect
			(at -1.400048 -0.249936 90)
			(size 0.2286 0.6096)
			(layers "F.Cu" "F.Mask" "F.Paste")
			(net "PEX1_P1V25_ADC_A0")
		)
		(pad "3" smd rect
			(at -1.400048 0.249936 90)
			(size 0.2286 0.6096)
			(layers "F.Cu" "F.Mask" "F.Paste")
			(net "PEX1_P1V25_ADC_ALERT_N")
		)
		(pad "4" smd rect
			(at -1.400048 0.750062 90)
			(size 0.2286 0.6096)
			(layers "F.Cu" "F.Mask" "F.Paste")
			(net "SMB_PEX1_P1V25_ADC_SDA")
		)
		(pad "5" smd rect
			(at -0.750062 1.400048 180)
			(size 0.2286 0.6096)
			(layers "F.Cu" "F.Mask" "F.Paste")
			(net "SMB_PEX1_P1V25_ADC_SCL")
		)
		(pad "6" smd rect
			(at -0.249936 1.400048 180)
			(size 0.2286 0.6096)
			(layers "F.Cu" "F.Mask" "F.Paste")
			(net "Net_8612")
		)
		(pad "7" smd rect
			(at 0.249936 1.400048 180)
			(size 0.2286 0.6096)
			(layers "F.Cu" "F.Mask" "F.Paste")
			(net "Net_8611")
		)
		(pad "8" smd rect
			(at 0.750062 1.400048 180)
			(size 0.2286 0.6096)
			(layers "F.Cu" "F.Mask" "F.Paste")
			(net "Net_8610")
		)
		(pad "9" smd rect
			(at 1.400048 0.750062 90)
			(size 0.2286 0.6096)
			(layers "F.Cu" "F.Mask" "F.Paste")
			(net "P3V3_AUX")
		)
		(pad "10" smd rect
			(at 1.400048 0.249936 90)
			(size 0.2286 0.6096)
			(layers "F.Cu" "F.Mask" "F.Paste")
			(net "GND")
		)
		(pad "11" smd rect
			(at 1.400048 -0.249936 90)
			(size 0.2286 0.6096)
			(layers "F.Cu" "F.Mask" "F.Paste")
			(net "P1V25_PEX1_R")
		)
		(pad "12" smd rect
			(at 1.400048 -0.750062 90)
			(size 0.2286 0.6096)
			(layers "F.Cu" "F.Mask" "F.Paste")
			(net "P12V_PEX1_P1V25_VIN_N")
		)
		(pad "13" smd rect
			(at 0.750062 -1.400048 180)
			(size 0.2286 0.6096)
			(layers "F.Cu" "F.Mask" "F.Paste")
			(net "P12V_PEX1_P1V25_VIN_P")
		)
		(pad "14" smd rect
			(at 0.249936 -1.400048 180)
			(size 0.2286 0.6096)
			(layers "F.Cu" "F.Mask" "F.Paste")
			(net "Net_8609")
		)
		(pad "15" smd rect
			(at -0.249936 -1.400048 180)
			(size 0.2286 0.6096)
			(layers "F.Cu" "F.Mask" "F.Paste")
			(net "Net_8608")
		)
		(pad "16" smd rect
			(at -0.750062 -1.400048 180)
			(size 0.2286 0.6096)
			(layers "F.Cu" "F.Mask" "F.Paste")
			(net "Net_8607")
		)
		(pad "TH" smd rect
			(at 0 0 180)
			(size 1.7018 1.7018)
			(layers "F.Cu" "F.Mask" "F.Paste")
			(net "GND")
		)
		(zone
			(layer "F.Cu")
			(hatch none 0.5)
			(connect_pads
				(clearance 0)
			)
			(min_thickness 0.25)
			(keepout
				(tracks not_allowed)
				(vias allowed)
				(pads allowed)
				(copperpour not_allowed)
				(footprints allowed)
			)
			(placement
				(enabled no)
				(sheetname "")
			)
			(fill
				(thermal_gap 0.5)
				(thermal_bridge_width 0.5)
				(island_removal_mode 0)
			)
			(polygon
				(pts
					(xy 229.491286 -277.766526) (xy 229.491286 -276.747478) (xy 227.40239 -276.747478) (xy 227.40239 -278.836374)
					(xy 229.491286 -278.836374) (xy 229.491286 -277.791926) (xy 229.348538 -277.791926) (xy 229.348538 -278.693626)
					(xy 227.545138 -278.693626) (xy 227.545138 -276.890226) (xy 229.348538 -276.890226) (xy 229.348538 -277.766526)
				)
			)
		)
	)
	(footprint ""
		(layer "F.Cu")
		(at 358.013 -215.392 180)
		(property "Reference" "R4093"
			(at 0 0 180)
			(layer "F.SilkS")
			(hide yes)
			(effects
				(font
					(size 1.27 1.27)
				)
			)
		)
		(property "Value" ""
			(at 0 0 180)
			(layer "F.Fab")
			(effects
				(font
					(size 1.27 1.27)
				)
			)
		)
		(duplicate_pad_numbers_are_jumpers no)
		(fp_line
			(start 0.7874 0.4064)
			(end -0.7874 0.4064)
			(stroke
				(width 0.1524)
				(type default)
			)
			(layer "F.SilkS")
		)
		(fp_line
			(start 0.7874 -0.4064)
			(end 0.7874 0.4064)
			(stroke
				(width 0.1524)
				(type default)
			)
			(layer "F.SilkS")
		)
		(fp_line
			(start -0.7874 0.4064)
			(end -0.7874 -0.4064)
			(stroke
				(width 0.1524)
				(type default)
			)
			(layer "F.SilkS")
		)
		(fp_line
			(start -0.7874 -0.4064)
			(end 0.7874 -0.4064)
			(stroke
				(width 0.1524)
				(type default)
			)
			(layer "F.SilkS")
		)
		(fp_line
			(start 0.67945 0.3048)
			(end 0.120396 0.3048)
			(stroke
				(width 0.1)
				(type default)
			)
			(layer "F.Fab")
		)
		(fp_line
			(start 0.67945 -0.3048)
			(end 0.67945 0.3048)
			(stroke
				(width 0.1)
				(type default)
			)
			(layer "F.Fab")
		)
		(fp_line
			(start 0.12065 -0.2794)
			(end 0.12065 -0.3048)
			(stroke
				(width 0.1)
				(type default)
			)
			(layer "F.Fab")
		)
		(fp_line
			(start 0.12065 -0.3048)
			(end 0.67945 -0.3048)
			(stroke
				(width 0.1)
				(type default)
			)
			(layer "F.Fab")
		)
		(fp_line
			(start 0.120396 0.3048)
			(end 0.120396 0.2794)
			(stroke
				(width 0.1)
				(type default)
			)
			(layer "F.Fab")
		)
		(fp_line
			(start 0.120396 0.2794)
			(end -0.12065 0.2794)
			(stroke
				(width 0.1)
				(type default)
			)
			(layer "F.Fab")
		)
		(fp_line
			(start -0.12065 0.3048)
			(end -0.67945 0.3048)
			(stroke
				(width 0.1)
				(type default)
			)
			(layer "F.Fab")
		)
		(fp_line
			(start -0.12065 0.2794)
			(end -0.12065 0.3048)
			(stroke
				(width 0.1)
				(type default)
			)
			(layer "F.Fab")
		)
		(fp_line
			(start -0.12065 -0.2794)
			(end 0.12065 -0.2794)
			(stroke
				(width 0.1)
				(type default)
			)
			(layer "F.Fab")
		)
		(fp_line
			(start -0.12065 -0.305054)
			(end -0.12065 -0.2794)
			(stroke
				(width 0.1)
				(type default)
			)
			(layer "F.Fab")
		)
		(fp_line
			(start -0.67945 0.3048)
			(end -0.67945 -0.305054)
			(stroke
				(width 0.1)
				(type default)
			)
			(layer "F.Fab")
		)
		(fp_line
			(start -0.67945 -0.305054)
			(end -0.12065 -0.305054)
			(stroke
				(width 0.1)
				(type default)
			)
			(layer "F.Fab")
		)
		(pad "1" smd circle
			(at -0.40005 0 180)
			(size 0 0)
			(layers "F.Cu" "F.Mask" "F.Paste")
			(net "PRSNT_NIC1_FPGA_R_N")
		)
		(pad "2" smd circle
			(at 0.40005 0 180)
			(size 0 0)
			(layers "F.Cu" "F.Mask" "F.Paste")
			(net "PRSNT_NIC1_FPGA_N")
		)
	)
	(footprint ""
		(layer "F.Cu")
		(at 228.582474 -136.669272 -90)
		(property "Reference" "R4191"
			(at 0 0 270)
			(layer "F.SilkS")
			(hide yes)
			(effects
				(font
					(size 1.27 1.27)
				)
			)
		)
		(property "Value" ""
			(at 0 0 270)
			(layer "F.Fab")
			(effects
				(font
					(size 1.27 1.27)
				)
			)
		)
		(duplicate_pad_numbers_are_jumpers no)
		(fp_line
			(start -0.7874 0.4064)
			(end -0.7874 -0.4064)
			(stroke
				(width 0.1524)
				(type default)
			)
			(layer "F.SilkS")
		)
		(fp_line
			(start 0.7874 0.4064)
			(end -0.7874 0.4064)
			(stroke
				(width 0.1524)
				(type default)
			)
			(layer "F.SilkS")
		)
		(fp_line
			(start -0.7874 -0.4064)
			(end 0.7874 -0.4064)
			(stroke
				(width 0.1524)
				(type default)
			)
			(layer "F.SilkS")
		)
		(fp_line
			(start 0.7874 -0.4064)
			(end 0.7874 0.4064)
			(stroke
				(width 0.1524)
				(type default)
			)
			(layer "F.SilkS")
		)
		(fp_line
			(start -0.67945 0.3048)
			(end -0.67945 -0.305054)
			(stroke
				(width 0.1)
				(type default)
			)
			(layer "F.Fab")
		)
		(fp_line
			(start -0.12065 0.3048)
			(end -0.67945 0.3048)
			(stroke
				(width 0.1)
				(type default)
			)
			(layer "F.Fab")
		)
		(fp_line
			(start 0.120396 0.3048)
			(end 0.120396 0.2794)
			(stroke
				(width 0.1)
				(type default)
			)
			(layer "F.Fab")
		)
		(fp_line
			(start 0.67945 0.3048)
			(end 0.120396 0.3048)
			(stroke
				(width 0.1)
				(type default)
			)
			(layer "F.Fab")
		)
		(fp_line
			(start -0.12065 0.2794)
			(end -0.12065 0.3048)
			(stroke
				(width 0.1)
				(type default)
			)
			(layer "F.Fab")
		)
		(fp_line
			(start 0.120396 0.2794)
			(end -0.12065 0.2794)
			(stroke
				(width 0.1)
				(type default)
			)
			(layer "F.Fab")
		)
		(fp_line
			(start -0.12065 -0.2794)
			(end 0.12065 -0.2794)
			(stroke
				(width 0.1)
				(type default)
			)
			(layer "F.Fab")
		)
		(fp_line
			(start 0.12065 -0.2794)
			(end 0.12065 -0.3048)
			(stroke
				(width 0.1)
				(type default)
			)
			(layer "F.Fab")
		)
		(fp_line
			(start 0.12065 -0.3048)
			(end 0.67945 -0.3048)
			(stroke
				(width 0.1)
				(type default)
			)
			(layer "F.Fab")
		)
		(fp_line
			(start 0.67945 -0.3048)
			(end 0.67945 0.3048)
			(stroke
				(width 0.1)
				(type default)
			)
			(layer "F.Fab")
		)
		(fp_line
			(start -0.67945 -0.305054)
			(end -0.12065 -0.305054)
			(stroke
				(width 0.1)
				(type default)
			)
			(layer "F.Fab")
		)
		(fp_line
			(start -0.12065 -0.305054)
			(end -0.12065 -0.2794)
			(stroke
				(width 0.1)
				(type default)
			)
			(layer "F.Fab")
		)
		(pad "1" smd circle
			(at -0.40005 0 270)
			(size 0 0)
			(layers "F.Cu" "F.Mask" "F.Paste")
			(net "CLK_CK440_PEX_SMB_ADDR0")
		)
		(pad "2" smd circle
			(at 0.40005 0 270)
			(size 0 0)
			(layers "F.Cu" "F.Mask" "F.Paste")
			(net "P3V3")
		)
	)
	(footprint ""
		(layer "F.Cu")
		(at 315.147198 -36.686998 90)
		(property "Reference" "C3671"
			(at 0 0 90)
			(layer "F.SilkS")
			(hide yes)
			(effects
				(font
					(size 1.27 1.27)
				)
			)
		)
		(property "Value" ""
			(at 0 0 90)
			(layer "F.Fab")
			(effects
				(font
					(size 1.27 1.27)
				)
			)
		)
		(duplicate_pad_numbers_are_jumpers no)
		(fp_line
			(start 0.7874 -0.4064)
			(end 0.7874 0.4064)
			(stroke
				(width 0.1524)
				(type default)
			)
			(layer "F.SilkS")
		)
		(fp_line
			(start -0.7874 -0.4064)
			(end 0.7874 -0.4064)
			(stroke
				(width 0.1524)
				(type default)
			)
			(layer "F.SilkS")
		)
		(fp_line
			(start 0.7874 0.4064)
			(end -0.7874 0.4064)
			(stroke
				(width 0.1524)
				(type default)
			)
			(layer "F.SilkS")
		)
		(fp_line
			(start -0.7874 0.4064)
			(end -0.7874 -0.4064)
			(stroke
				(width 0.1524)
				(type default)
			)
			(layer "F.SilkS")
		)
		(fp_line
			(start -0.12065 -0.305054)
			(end -0.12065 -0.2794)
			(stroke
				(width 0.1)
				(type default)
			)
			(layer "F.Fab")
		)
		(fp_line
			(start -0.67945 -0.305054)
			(end -0.12065 -0.305054)
			(stroke
				(width 0.1)
				(type default)
			)
			(layer "F.Fab")
		)
		(fp_line
			(start 0.67945 -0.3048)
			(end 0.67945 0.3048)
			(stroke
				(width 0.1)
				(type default)
			)
			(layer "F.Fab")
		)
		(fp_line
			(start 0.12065 -0.3048)
			(end 0.67945 -0.3048)
			(stroke
				(width 0.1)
				(type default)
			)
			(layer "F.Fab")
		)
		(fp_line
			(start 0.12065 -0.2794)
			(end 0.12065 -0.3048)
			(stroke
				(width 0.1)
				(type default)
			)
			(layer "F.Fab")
		)
		(fp_line
			(start -0.12065 -0.2794)
			(end 0.12065 -0.2794)
			(stroke
				(width 0.1)
				(type default)
			)
			(layer "F.Fab")
		)
		(fp_line
			(start 0.120396 0.2794)
			(end -0.12065 0.2794)
			(stroke
				(width 0.1)
				(type default)
			)
			(layer "F.Fab")
		)
		(fp_line
			(start -0.12065 0.2794)
			(end -0.12065 0.3048)
			(stroke
				(width 0.1)
				(type default)
			)
			(layer "F.Fab")
		)
		(fp_line
			(start 0.67945 0.3048)
			(end 0.120396 0.3048)
			(stroke
				(width 0.1)
				(type default)
			)
			(layer "F.Fab")
		)
		(fp_line
			(start 0.120396 0.3048)
			(end 0.120396 0.2794)
			(stroke
				(width 0.1)
				(type default)
			)
			(layer "F.Fab")
		)
		(fp_line
			(start -0.12065 0.3048)
			(end -0.67945 0.3048)
			(stroke
				(width 0.1)
				(type default)
			)
			(layer "F.Fab")
		)
		(fp_line
			(start -0.67945 0.3048)
			(end -0.67945 -0.305054)
			(stroke
				(width 0.1)
				(type default)
			)
			(layer "F.Fab")
		)
		(pad "1" smd circle
			(at -0.40005 0 90)
			(size 0 0)
			(layers "F.Cu" "F.Mask" "F.Paste")
			(net "P3V3_AUX")
		)
		(pad "2" smd circle
			(at 0.40005 0 90)
			(size 0 0)
			(layers "F.Cu" "F.Mask" "F.Paste")
			(net "GND")
		)
	)
	(footprint ""
		(layer "F.Cu")
		(at 72.487536 -25.342342 -90)
		(property "Reference" "R416"
			(at 0 0 270)
			(layer "F.SilkS")
			(hide yes)
			(effects
				(font
					(size 1.27 1.27)
				)
			)
		)
		(property "Value" ""
			(at 0 0 270)
			(layer "F.Fab")
			(effects
				(font
					(size 1.27 1.27)
				)
			)
		)
		(duplicate_pad_numbers_are_jumpers no)
		(fp_line
			(start -0.7874 0.4064)
			(end -0.7874 -0.4064)
			(stroke
				(width 0.1524)
				(type default)
			)
			(layer "F.SilkS")
		)
		(fp_line
			(start 0.7874 0.4064)
			(end -0.7874 0.4064)
			(stroke
				(width 0.1524)
				(type default)
			)
			(layer "F.SilkS")
		)
		(fp_line
			(start -0.7874 -0.4064)
			(end 0.7874 -0.4064)
			(stroke
				(width 0.1524)
				(type default)
			)
			(layer "F.SilkS")
		)
		(fp_line
			(start 0.7874 -0.4064)
			(end 0.7874 0.4064)
			(stroke
				(width 0.1524)
				(type default)
			)
			(layer "F.SilkS")
		)
		(fp_line
			(start -0.67945 0.3048)
			(end -0.67945 -0.305054)
			(stroke
				(width 0.1)
				(type default)
			)
			(layer "F.Fab")
		)
		(fp_line
			(start -0.12065 0.3048)
			(end -0.67945 0.3048)
			(stroke
				(width 0.1)
				(type default)
			)
			(layer "F.Fab")
		)
		(fp_line
			(start 0.120396 0.3048)
			(end 0.120396 0.2794)
			(stroke
				(width 0.1)
				(type default)
			)
			(layer "F.Fab")
		)
		(fp_line
			(start 0.67945 0.3048)
			(end 0.120396 0.3048)
			(stroke
				(width 0.1)
				(type default)
			)
			(layer "F.Fab")
		)
		(fp_line
			(start -0.12065 0.2794)
			(end -0.12065 0.3048)
			(stroke
				(width 0.1)
				(type default)
			)
			(layer "F.Fab")
		)
		(fp_line
			(start 0.120396 0.2794)
			(end -0.12065 0.2794)
			(stroke
				(width 0.1)
				(type default)
			)
			(layer "F.Fab")
		)
		(fp_line
			(start -0.12065 -0.2794)
			(end 0.12065 -0.2794)
			(stroke
				(width 0.1)
				(type default)
			)
			(layer "F.Fab")
		)
		(fp_line
			(start 0.12065 -0.2794)
			(end 0.12065 -0.3048)
			(stroke
				(width 0.1)
				(type default)
			)
			(layer "F.Fab")
		)
		(fp_line
			(start 0.12065 -0.3048)
			(end 0.67945 -0.3048)
			(stroke
				(width 0.1)
				(type default)
			)
			(layer "F.Fab")
		)
		(fp_line
			(start 0.67945 -0.3048)
			(end 0.67945 0.3048)
			(stroke
				(width 0.1)
				(type default)
			)
			(layer "F.Fab")
		)
		(fp_line
			(start -0.67945 -0.305054)
			(end -0.12065 -0.305054)
			(stroke
				(width 0.1)
				(type default)
			)
			(layer "F.Fab")
		)
		(fp_line
			(start -0.12065 -0.305054)
			(end -0.12065 -0.2794)
			(stroke
				(width 0.1)
				(type default)
			)
			(layer "F.Fab")
		)
		(pad "1" smd circle
			(at -0.40005 0 270)
			(size 0 0)
			(layers "F.Cu" "F.Mask" "F.Paste")
			(net "GND")
		)
		(pad "2" smd circle
			(at 0.40005 0 270)
			(size 0 0)
			(layers "F.Cu" "F.Mask" "F.Paste")
			(net "DUALPORT_N_SSD2")
		)
	)
	(footprint ""
		(layer "F.Cu")
		(at 179.21859 -180.162962)
		(property "Reference" "R6663"
			(at 0 0 0)
			(layer "F.SilkS")
			(hide yes)
			(effects
				(font
					(size 1.27 1.27)
				)
			)
		)
		(property "Value" ""
			(at 0 0 0)
			(layer "F.Fab")
			(effects
				(font
					(size 1.27 1.27)
				)
			)
		)
		(duplicate_pad_numbers_are_jumpers no)
		(fp_line
			(start -0.7874 -0.4064)
			(end 0.7874 -0.4064)
			(stroke
				(width 0.1524)
				(type default)
			)
			(layer "F.SilkS")
		)
		(fp_line
			(start -0.7874 0.4064)
			(end -0.7874 -0.4064)
			(stroke
				(width 0.1524)
				(type default)
			)
			(layer "F.SilkS")
		)
		(fp_line
			(start 0.7874 -0.4064)
			(end 0.7874 0.4064)
			(stroke
				(width 0.1524)
				(type default)
			)
			(layer "F.SilkS")
		)
		(fp_line
			(start 0.7874 0.4064)
			(end -0.7874 0.4064)
			(stroke
				(width 0.1524)
				(type default)
			)
			(layer "F.SilkS")
		)
		(fp_line
			(start -0.67945 -0.305054)
			(end -0.12065 -0.305054)
			(stroke
				(width 0.1)
				(type default)
			)
			(layer "F.Fab")
		)
		(fp_line
			(start -0.67945 0.3048)
			(end -0.67945 -0.305054)
			(stroke
				(width 0.1)
				(type default)
			)
			(layer "F.Fab")
		)
		(fp_line
			(start -0.12065 -0.305054)
			(end -0.12065 -0.2794)
			(stroke
				(width 0.1)
				(type default)
			)
			(layer "F.Fab")
		)
		(fp_line
			(start -0.12065 -0.2794)
			(end 0.12065 -0.2794)
			(stroke
				(width 0.1)
				(type default)
			)
			(layer "F.Fab")
		)
		(fp_line
			(start -0.12065 0.2794)
			(end -0.12065 0.3048)
			(stroke
				(width 0.1)
				(type default)
			)
			(layer "F.Fab")
		)
		(fp_line
			(start -0.12065 0.3048)
			(end -0.67945 0.3048)
			(stroke
				(width 0.1)
				(type default)
			)
			(layer "F.Fab")
		)
		(fp_line
			(start 0.120396 0.2794)
			(end -0.12065 0.2794)
			(stroke
				(width 0.1)
				(type default)
			)
			(layer "F.Fab")
		)
		(fp_line
			(start 0.120396 0.3048)
			(end 0.120396 0.2794)
			(stroke
				(width 0.1)
				(type default)
			)
			(layer "F.Fab")
		)
		(fp_line
			(start 0.12065 -0.3048)
			(end 0.67945 -0.3048)
			(stroke
				(width 0.1)
				(type default)
			)
			(layer "F.Fab")
		)
		(fp_line
			(start 0.12065 -0.2794)
			(end 0.12065 -0.3048)
			(stroke
				(width 0.1)
				(type default)
			)
			(layer "F.Fab")
		)
		(fp_line
			(start 0.67945 -0.3048)
			(end 0.67945 0.3048)
			(stroke
				(width 0.1)
				(type default)
			)
			(layer "F.Fab")
		)
		(fp_line
			(start 0.67945 0.3048)
			(end 0.120396 0.3048)
			(stroke
				(width 0.1)
				(type default)
			)
			(layer "F.Fab")
		)
		(pad "1" smd circle
			(at -0.40005 0)
			(size 0 0)
			(layers "F.Cu" "F.Mask" "F.Paste")
			(net "NIC2_CLK_EN_BUF_N")
		)
		(pad "2" smd circle
			(at 0.40005 0)
			(size 0 0)
			(layers "F.Cu" "F.Mask" "F.Paste")
			(net "NIC2_CLK_EN_BUF_R_N")
		)
	)
	(footprint ""
		(layer "F.Cu")
		(at 304.872898 -22.867366 90)
		(property "Reference" "C3942"
			(at 0 0 90)
			(layer "F.SilkS")
			(hide yes)
			(effects
				(font
					(size 1.27 1.27)
				)
			)
		)
		(property "Value" ""
			(at 0 0 90)
			(layer "F.Fab")
			(effects
				(font
					(size 1.27 1.27)
				)
			)
		)
		(duplicate_pad_numbers_are_jumpers no)
		(fp_line
			(start 0.7874 -0.4064)
			(end 0.7874 0.4064)
			(stroke
				(width 0.1524)
				(type default)
			)
			(layer "F.SilkS")
		)
		(fp_line
			(start -0.7874 -0.4064)
			(end 0.7874 -0.4064)
			(stroke
				(width 0.1524)
				(type default)
			)
			(layer "F.SilkS")
		)
		(fp_line
			(start 0.7874 0.4064)
			(end -0.7874 0.4064)
			(stroke
				(width 0.1524)
				(type default)
			)
			(layer "F.SilkS")
		)
		(fp_line
			(start -0.7874 0.4064)
			(end -0.7874 -0.4064)
			(stroke
				(width 0.1524)
				(type default)
			)
			(layer "F.SilkS")
		)
		(fp_line
			(start -0.12065 -0.305054)
			(end -0.12065 -0.2794)
			(stroke
				(width 0.1)
				(type default)
			)
			(layer "F.Fab")
		)
		(fp_line
			(start -0.67945 -0.305054)
			(end -0.12065 -0.305054)
			(stroke
				(width 0.1)
				(type default)
			)
			(layer "F.Fab")
		)
		(fp_line
			(start 0.67945 -0.3048)
			(end 0.67945 0.3048)
			(stroke
				(width 0.1)
				(type default)
			)
			(layer "F.Fab")
		)
		(fp_line
			(start 0.12065 -0.3048)
			(end 0.67945 -0.3048)
			(stroke
				(width 0.1)
				(type default)
			)
			(layer "F.Fab")
		)
		(fp_line
			(start 0.12065 -0.2794)
			(end 0.12065 -0.3048)
			(stroke
				(width 0.1)
				(type default)
			)
			(layer "F.Fab")
		)
		(fp_line
			(start -0.12065 -0.2794)
			(end 0.12065 -0.2794)
			(stroke
				(width 0.1)
				(type default)
			)
			(layer "F.Fab")
		)
		(fp_line
			(start 0.120396 0.2794)
			(end -0.12065 0.2794)
			(stroke
				(width 0.1)
				(type default)
			)
			(layer "F.Fab")
		)
		(fp_line
			(start -0.12065 0.2794)
			(end -0.12065 0.3048)
			(stroke
				(width 0.1)
				(type default)
			)
			(layer "F.Fab")
		)
		(fp_line
			(start 0.67945 0.3048)
			(end 0.120396 0.3048)
			(stroke
				(width 0.1)
				(type default)
			)
			(layer "F.Fab")
		)
		(fp_line
			(start 0.120396 0.3048)
			(end 0.120396 0.2794)
			(stroke
				(width 0.1)
				(type default)
			)
			(layer "F.Fab")
		)
		(fp_line
			(start -0.12065 0.3048)
			(end -0.67945 0.3048)
			(stroke
				(width 0.1)
				(type default)
			)
			(layer "F.Fab")
		)
		(fp_line
			(start -0.67945 0.3048)
			(end -0.67945 -0.305054)
			(stroke
				(width 0.1)
				(type default)
			)
			(layer "F.Fab")
		)
		(pad "1" smd circle
			(at -0.40005 0 90)
			(size 0 0)
			(layers "F.Cu" "F.Mask" "F.Paste")
			(net "P12V_SSD10")
		)
		(pad "2" smd circle
			(at 0.40005 0 90)
			(size 0 0)
			(layers "F.Cu" "F.Mask" "F.Paste")
			(net "GND")
		)
	)
	(footprint ""
		(layer "F.Cu")
		(at 147.79879 -309.570628 45)
		(property "Reference" "R1284"
			(at 0 0 45)
			(layer "F.SilkS")
			(hide yes)
			(effects
				(font
					(size 1.27 1.27)
				)
			)
		)
		(property "Value" ""
			(at 0 0 45)
			(layer "F.Fab")
			(effects
				(font
					(size 1.27 1.27)
				)
			)
		)
		(duplicate_pad_numbers_are_jumpers no)
		(fp_line
			(start -0.787389 -0.406267)
			(end 0.787389 -0.406267)
			(stroke
				(width 0.1524)
				(type default)
			)
			(layer "F.SilkS")
		)
		(fp_line
			(start -0.787389 0.406267)
			(end -0.787389 -0.406267)
			(stroke
				(width 0.1524)
				(type default)
			)
			(layer "F.SilkS")
		)
		(fp_line
			(start 0.787389 -0.406267)
			(end 0.787389 0.406267)
			(stroke
				(width 0.1524)
				(type default)
			)
			(layer "F.SilkS")
		)
		(fp_line
			(start 0.787389 0.406267)
			(end -0.787389 0.406267)
			(stroke
				(width 0.1524)
				(type default)
			)
			(layer "F.SilkS")
		)
		(fp_line
			(start -0.679446 -0.305149)
			(end -0.120695 -0.304969)
			(stroke
				(width 0.1)
				(type default)
			)
			(layer "F.Fab")
		)
		(fp_line
			(start -0.120695 -0.304969)
			(end -0.120695 -0.279466)
			(stroke
				(width 0.1)
				(type default)
			)
			(layer "F.Fab")
		)
		(fp_line
			(start -0.120695 -0.279466)
			(end 0.120695 -0.279466)
			(stroke
				(width 0.1)
				(type default)
			)
			(layer "F.Fab")
		)
		(fp_line
			(start -0.679446 0.30479)
			(end -0.679446 -0.305149)
			(stroke
				(width 0.1)
				(type default)
			)
			(layer "F.Fab")
		)
		(fp_line
			(start 0.120515 -0.30479)
			(end 0.679446 -0.30479)
			(stroke
				(width 0.1)
				(type default)
			)
			(layer "F.Fab")
		)
		(fp_line
			(start 0.120695 -0.279466)
			(end 0.120515 -0.30479)
			(stroke
				(width 0.1)
				(type default)
			)
			(layer "F.Fab")
		)
		(fp_line
			(start -0.120695 0.279466)
			(end -0.120515 0.30479)
			(stroke
				(width 0.1)
				(type default)
			)
			(layer "F.Fab")
		)
		(fp_line
			(start -0.120515 0.30479)
			(end -0.679446 0.30479)
			(stroke
				(width 0.1)
				(type default)
			)
			(layer "F.Fab")
		)
		(fp_line
			(start 0.679446 -0.30479)
			(end 0.679446 0.30479)
			(stroke
				(width 0.1)
				(type default)
			)
			(layer "F.Fab")
		)
		(fp_line
			(start 0.120335 0.279466)
			(end -0.120695 0.279466)
			(stroke
				(width 0.1)
				(type default)
			)
			(layer "F.Fab")
		)
		(fp_line
			(start 0.120515 0.30479)
			(end 0.120335 0.279466)
			(stroke
				(width 0.1)
				(type default)
			)
			(layer "F.Fab")
		)
		(fp_line
			(start 0.679446 0.30479)
			(end 0.120515 0.30479)
			(stroke
				(width 0.1)
				(type default)
			)
			(layer "F.Fab")
		)
		(pad "1" smd circle
			(at -0.40005 0 45)
			(size 0 0)
			(layers "F.Cu" "F.Mask" "F.Paste")
			(net "GND")
		)
		(pad "2" smd circle
			(at 0.40005 0 45)
			(size 0 0)
			(layers "F.Cu" "F.Mask" "F.Paste")
			(net "PEX1_DBG_MODE0")
		)
	)
	(footprint ""
		(layer "F.Cu")
		(at 310.467756 -51.019456)
		(property "Reference" "PC434"
			(at 0 0 0)
			(layer "F.SilkS")
			(hide yes)
			(effects
				(font
					(size 1.27 1.27)
				)
			)
		)
		(property "Value" ""
			(at 0 0 0)
			(layer "F.Fab")
			(effects
				(font
					(size 1.27 1.27)
				)
			)
		)
		(duplicate_pad_numbers_are_jumpers no)
		(fp_line
			(start -0.7874 -0.4064)
			(end 0.7874 -0.4064)
			(stroke
				(width 0.1524)
				(type default)
			)
			(layer "F.SilkS")
		)
		(fp_line
			(start -0.7874 0.4064)
			(end -0.7874 -0.4064)
			(stroke
				(width 0.1524)
				(type default)
			)
			(layer "F.SilkS")
		)
		(fp_line
			(start 0.7874 -0.4064)
			(end 0.7874 0.4064)
			(stroke
				(width 0.1524)
				(type default)
			)
			(layer "F.SilkS")
		)
		(fp_line
			(start 0.7874 0.4064)
			(end -0.7874 0.4064)
			(stroke
				(width 0.1524)
				(type default)
			)
			(layer "F.SilkS")
		)
		(fp_line
			(start -0.67945 -0.305054)
			(end -0.12065 -0.305054)
			(stroke
				(width 0.1)
				(type default)
			)
			(layer "F.Fab")
		)
		(fp_line
			(start -0.67945 0.3048)
			(end -0.67945 -0.305054)
			(stroke
				(width 0.1)
				(type default)
			)
			(layer "F.Fab")
		)
		(fp_line
			(start -0.12065 -0.305054)
			(end -0.12065 -0.2794)
			(stroke
				(width 0.1)
				(type default)
			)
			(layer "F.Fab")
		)
		(fp_line
			(start -0.12065 -0.2794)
			(end 0.12065 -0.2794)
			(stroke
				(width 0.1)
				(type default)
			)
			(layer "F.Fab")
		)
		(fp_line
			(start -0.12065 0.2794)
			(end -0.12065 0.3048)
			(stroke
				(width 0.1)
				(type default)
			)
			(layer "F.Fab")
		)
		(fp_line
			(start -0.12065 0.3048)
			(end -0.67945 0.3048)
			(stroke
				(width 0.1)
				(type default)
			)
			(layer "F.Fab")
		)
		(fp_line
			(start 0.120396 0.2794)
			(end -0.12065 0.2794)
			(stroke
				(width 0.1)
				(type default)
			)
			(layer "F.Fab")
		)
		(fp_line
			(start 0.120396 0.3048)
			(end 0.120396 0.2794)
			(stroke
				(width 0.1)
				(type default)
			)
			(layer "F.Fab")
		)
		(fp_line
			(start 0.12065 -0.3048)
			(end 0.67945 -0.3048)
			(stroke
				(width 0.1)
				(type default)
			)
			(layer "F.Fab")
		)
		(fp_line
			(start 0.12065 -0.2794)
			(end 0.12065 -0.3048)
			(stroke
				(width 0.1)
				(type default)
			)
			(layer "F.Fab")
		)
		(fp_line
			(start 0.67945 -0.3048)
			(end 0.67945 0.3048)
			(stroke
				(width 0.1)
				(type default)
			)
			(layer "F.Fab")
		)
		(fp_line
			(start 0.67945 0.3048)
			(end 0.120396 0.3048)
			(stroke
				(width 0.1)
				(type default)
			)
			(layer "F.Fab")
		)
		(pad "1" smd circle
			(at -0.40005 0)
			(size 0 0)
			(layers "F.Cu" "F.Mask" "F.Paste")
			(net "P12V_SSD10_SS")
		)
		(pad "2" smd circle
			(at 0.40005 0)
			(size 0 0)
			(layers "F.Cu" "F.Mask" "F.Paste")
			(net "GND")
		)
	)
	(footprint ""
		(layer "F.Cu")
		(at 10.11047 -125.979428)
		(property "Reference" "R878"
			(at 0 0 0)
			(layer "F.SilkS")
			(hide yes)
			(effects
				(font
					(size 1.27 1.27)
				)
			)
		)
		(property "Value" ""
			(at 0 0 0)
			(layer "F.Fab")
			(effects
				(font
					(size 1.27 1.27)
				)
			)
		)
		(duplicate_pad_numbers_are_jumpers no)
		(fp_line
			(start -0.7874 -0.4064)
			(end 0.7874 -0.4064)
			(stroke
				(width 0.1524)
				(type default)
			)
			(layer "F.SilkS")
		)
		(fp_line
			(start -0.7874 0.4064)
			(end -0.7874 -0.4064)
			(stroke
				(width 0.1524)
				(type default)
			)
			(layer "F.SilkS")
		)
		(fp_line
			(start 0.7874 -0.4064)
			(end 0.7874 0.4064)
			(stroke
				(width 0.1524)
				(type default)
			)
			(layer "F.SilkS")
		)
		(fp_line
			(start 0.7874 0.4064)
			(end -0.7874 0.4064)
			(stroke
				(width 0.1524)
				(type default)
			)
			(layer "F.SilkS")
		)
		(fp_line
			(start -0.67945 -0.305054)
			(end -0.12065 -0.305054)
			(stroke
				(width 0.1)
				(type default)
			)
			(layer "F.Fab")
		)
		(fp_line
			(start -0.67945 0.3048)
			(end -0.67945 -0.305054)
			(stroke
				(width 0.1)
				(type default)
			)
			(layer "F.Fab")
		)
		(fp_line
			(start -0.12065 -0.305054)
			(end -0.12065 -0.2794)
			(stroke
				(width 0.1)
				(type default)
			)
			(layer "F.Fab")
		)
		(fp_line
			(start -0.12065 -0.2794)
			(end 0.12065 -0.2794)
			(stroke
				(width 0.1)
				(type default)
			)
			(layer "F.Fab")
		)
		(fp_line
			(start -0.12065 0.2794)
			(end -0.12065 0.3048)
			(stroke
				(width 0.1)
				(type default)
			)
			(layer "F.Fab")
		)
		(fp_line
			(start -0.12065 0.3048)
			(end -0.67945 0.3048)
			(stroke
				(width 0.1)
				(type default)
			)
			(layer "F.Fab")
		)
		(fp_line
			(start 0.120396 0.2794)
			(end -0.12065 0.2794)
			(stroke
				(width 0.1)
				(type default)
			)
			(layer "F.Fab")
		)
		(fp_line
			(start 0.120396 0.3048)
			(end 0.120396 0.2794)
			(stroke
				(width 0.1)
				(type default)
			)
			(layer "F.Fab")
		)
		(fp_line
			(start 0.12065 -0.3048)
			(end 0.67945 -0.3048)
			(stroke
				(width 0.1)
				(type default)
			)
			(layer "F.Fab")
		)
		(fp_line
			(start 0.12065 -0.2794)
			(end 0.12065 -0.3048)
			(stroke
				(width 0.1)
				(type default)
			)
			(layer "F.Fab")
		)
		(fp_line
			(start 0.67945 -0.3048)
			(end 0.67945 0.3048)
			(stroke
				(width 0.1)
				(type default)
			)
			(layer "F.Fab")
		)
		(fp_line
			(start 0.67945 0.3048)
			(end 0.120396 0.3048)
			(stroke
				(width 0.1)
				(type default)
			)
			(layer "F.Fab")
		)
		(pad "1" smd circle
			(at -0.40005 0)
			(size 0 0)
			(layers "F.Cu" "F.Mask" "F.Paste")
			(net "P3V3_NIC0")
		)
		(pad "2" smd circle
			(at 0.40005 0)
			(size 0 0)
			(layers "F.Cu" "F.Mask" "F.Paste")
			(net "PWRGD_P3V3_NIC0")
		)
	)
	(footprint ""
		(layer "F.Cu")
		(at 381.254 -196.342)
		(property "Reference" "R4695"
			(at 0 0 0)
			(layer "F.SilkS")
			(hide yes)
			(effects
				(font
					(size 1.27 1.27)
				)
			)
		)
		(property "Value" ""
			(at 0 0 0)
			(layer "F.Fab")
			(effects
				(font
					(size 1.27 1.27)
				)
			)
		)
		(duplicate_pad_numbers_are_jumpers no)
		(fp_line
			(start -0.7874 -0.4064)
			(end 0.7874 -0.4064)
			(stroke
				(width 0.1524)
				(type default)
			)
			(layer "F.SilkS")
		)
		(fp_line
			(start -0.7874 0.4064)
			(end -0.7874 -0.4064)
			(stroke
				(width 0.1524)
				(type default)
			)
			(layer "F.SilkS")
		)
		(fp_line
			(start 0.7874 -0.4064)
			(end 0.7874 0.4064)
			(stroke
				(width 0.1524)
				(type default)
			)
			(layer "F.SilkS")
		)
		(fp_line
			(start 0.7874 0.4064)
			(end -0.7874 0.4064)
			(stroke
				(width 0.1524)
				(type default)
			)
			(layer "F.SilkS")
		)
		(fp_line
			(start -0.67945 -0.305054)
			(end -0.12065 -0.305054)
			(stroke
				(width 0.1)
				(type default)
			)
			(layer "F.Fab")
		)
		(fp_line
			(start -0.67945 0.3048)
			(end -0.67945 -0.305054)
			(stroke
				(width 0.1)
				(type default)
			)
			(layer "F.Fab")
		)
		(fp_line
			(start -0.12065 -0.305054)
			(end -0.12065 -0.2794)
			(stroke
				(width 0.1)
				(type default)
			)
			(layer "F.Fab")
		)
		(fp_line
			(start -0.12065 -0.2794)
			(end 0.12065 -0.2794)
			(stroke
				(width 0.1)
				(type default)
			)
			(layer "F.Fab")
		)
		(fp_line
			(start -0.12065 0.2794)
			(end -0.12065 0.3048)
			(stroke
				(width 0.1)
				(type default)
			)
			(layer "F.Fab")
		)
		(fp_line
			(start -0.12065 0.3048)
			(end -0.67945 0.3048)
			(stroke
				(width 0.1)
				(type default)
			)
			(layer "F.Fab")
		)
		(fp_line
			(start 0.120396 0.2794)
			(end -0.12065 0.2794)
			(stroke
				(width 0.1)
				(type default)
			)
			(layer "F.Fab")
		)
		(fp_line
			(start 0.120396 0.3048)
			(end 0.120396 0.2794)
			(stroke
				(width 0.1)
				(type default)
			)
			(layer "F.Fab")
		)
		(fp_line
			(start 0.12065 -0.3048)
			(end 0.67945 -0.3048)
			(stroke
				(width 0.1)
				(type default)
			)
			(layer "F.Fab")
		)
		(fp_line
			(start 0.12065 -0.2794)
			(end 0.12065 -0.3048)
			(stroke
				(width 0.1)
				(type default)
			)
			(layer "F.Fab")
		)
		(fp_line
			(start 0.67945 -0.3048)
			(end 0.67945 0.3048)
			(stroke
				(width 0.1)
				(type default)
			)
			(layer "F.Fab")
		)
		(fp_line
			(start 0.67945 0.3048)
			(end 0.120396 0.3048)
			(stroke
				(width 0.1)
				(type default)
			)
			(layer "F.Fab")
		)
		(pad "1" smd circle
			(at -0.40005 0)
			(size 0 0)
			(layers "F.Cu" "F.Mask" "F.Paste")
			(net "NIC2_PEX_PWR_EN")
		)
		(pad "2" smd circle
			(at 0.40005 0)
			(size 0 0)
			(layers "F.Cu" "F.Mask" "F.Paste")
			(net "NIC2_PEX_PWR_EN_R")
		)
	)
	(footprint ""
		(layer "F.Cu")
		(at 351.89668 -271.703546 -90)
		(property "Reference" "PC177"
			(at 0 0 270)
			(layer "F.SilkS")
			(hide yes)
			(effects
				(font
					(size 1.27 1.27)
				)
			)
		)
		(property "Value" ""
			(at 0 0 270)
			(layer "F.Fab")
			(effects
				(font
					(size 1.27 1.27)
				)
			)
		)
		(duplicate_pad_numbers_are_jumpers no)
		(fp_line
			(start -2.146046 3.400044)
			(end -3.400044 2.146046)
			(stroke
				(width 0.1524)
				(type default)
			)
			(layer "F.SilkS")
		)
		(fp_line
			(start 3.400044 3.400044)
			(end -2.146046 3.400044)
			(stroke
				(width 0.1524)
				(type default)
			)
			(layer "F.SilkS")
		)
		(fp_line
			(start -3.400044 2.146046)
			(end -3.400044 0.9398)
			(stroke
				(width 0.1524)
				(type default)
			)
			(layer "F.SilkS")
		)
		(fp_line
			(start 3.400044 0.9398)
			(end 3.400044 3.400044)
			(stroke
				(width 0.1524)
				(type default)
			)
			(layer "F.SilkS")
		)
		(fp_line
			(start 3.400044 -0.9398)
			(end 3.400044 -3.400044)
			(stroke
				(width 0.1524)
				(type default)
			)
			(layer "F.SilkS")
		)
		(fp_line
			(start -3.400044 -2.146046)
			(end -3.400044 -0.9398)
			(stroke
				(width 0.1524)
				(type default)
			)
			(layer "F.SilkS")
		)
		(fp_line
			(start -2.146046 -3.400044)
			(end -3.400044 -2.146046)
			(stroke
				(width 0.1524)
				(type default)
			)
			(layer "F.SilkS")
		)
		(fp_line
			(start 3.400044 -3.400044)
			(end -2.146046 -3.400044)
			(stroke
				(width 0.1524)
				(type default)
			)
			(layer "F.SilkS")
		)
		(fp_line
			(start -3.400044 3.400044)
			(end 3.400044 3.400044)
			(stroke
				(width 0.1)
				(type default)
			)
			(layer "F.Fab")
		)
		(fp_line
			(start 3.400044 3.400044)
			(end 3.400044 -3.400044)
			(stroke
				(width 0.1)
				(type default)
			)
			(layer "F.Fab")
		)
		(fp_line
			(start -3.400044 -3.400044)
			(end -3.400044 3.400044)
			(stroke
				(width 0.1)
				(type default)
			)
			(layer "F.Fab")
		)
		(fp_line
			(start 3.400044 -3.400044)
			(end -3.400044 -3.400044)
			(stroke
				(width 0.1)
				(type default)
			)
			(layer "F.Fab")
		)
		(pad "1" smd rect
			(at -2.70002 0 180)
			(size 1.6002 3.5052)
			(layers "F.Cu" "F.Mask" "F.Paste")
			(net "SW_P12V_P0V8_PEX3_FLT")
		)
		(pad "2" smd rect
			(at 2.70002 0 180)
			(size 1.6002 3.5052)
			(layers "F.Cu" "F.Mask" "F.Paste")
			(net "GND")
		)
	)
	(footprint ""
		(layer "F.Cu")
		(at 166.330884 -198.916798)
		(property "Reference" "R3402"
			(at 0 0 0)
			(layer "F.SilkS")
			(hide yes)
			(effects
				(font
					(size 1.27 1.27)
				)
			)
		)
		(property "Value" ""
			(at 0 0 0)
			(layer "F.Fab")
			(effects
				(font
					(size 1.27 1.27)
				)
			)
		)
		(duplicate_pad_numbers_are_jumpers no)
		(fp_line
			(start -0.7874 -0.4064)
			(end 0.7874 -0.4064)
			(stroke
				(width 0.1524)
				(type default)
			)
			(layer "F.SilkS")
		)
		(fp_line
			(start -0.7874 0.4064)
			(end -0.7874 -0.4064)
			(stroke
				(width 0.1524)
				(type default)
			)
			(layer "F.SilkS")
		)
		(fp_line
			(start 0.7874 -0.4064)
			(end 0.7874 0.4064)
			(stroke
				(width 0.1524)
				(type default)
			)
			(layer "F.SilkS")
		)
		(fp_line
			(start 0.7874 0.4064)
			(end -0.7874 0.4064)
			(stroke
				(width 0.1524)
				(type default)
			)
			(layer "F.SilkS")
		)
		(fp_line
			(start -0.67945 -0.305054)
			(end -0.12065 -0.305054)
			(stroke
				(width 0.1)
				(type default)
			)
			(layer "F.Fab")
		)
		(fp_line
			(start -0.67945 0.3048)
			(end -0.67945 -0.305054)
			(stroke
				(width 0.1)
				(type default)
			)
			(layer "F.Fab")
		)
		(fp_line
			(start -0.12065 -0.305054)
			(end -0.12065 -0.2794)
			(stroke
				(width 0.1)
				(type default)
			)
			(layer "F.Fab")
		)
		(fp_line
			(start -0.12065 -0.2794)
			(end 0.12065 -0.2794)
			(stroke
				(width 0.1)
				(type default)
			)
			(layer "F.Fab")
		)
		(fp_line
			(start -0.12065 0.2794)
			(end -0.12065 0.3048)
			(stroke
				(width 0.1)
				(type default)
			)
			(layer "F.Fab")
		)
		(fp_line
			(start -0.12065 0.3048)
			(end -0.67945 0.3048)
			(stroke
				(width 0.1)
				(type default)
			)
			(layer "F.Fab")
		)
		(fp_line
			(start 0.120396 0.2794)
			(end -0.12065 0.2794)
			(stroke
				(width 0.1)
				(type default)
			)
			(layer "F.Fab")
		)
		(fp_line
			(start 0.120396 0.3048)
			(end 0.120396 0.2794)
			(stroke
				(width 0.1)
				(type default)
			)
			(layer "F.Fab")
		)
		(fp_line
			(start 0.12065 -0.3048)
			(end 0.67945 -0.3048)
			(stroke
				(width 0.1)
				(type default)
			)
			(layer "F.Fab")
		)
		(fp_line
			(start 0.12065 -0.2794)
			(end 0.12065 -0.3048)
			(stroke
				(width 0.1)
				(type default)
			)
			(layer "F.Fab")
		)
		(fp_line
			(start 0.67945 -0.3048)
			(end 0.67945 0.3048)
			(stroke
				(width 0.1)
				(type default)
			)
			(layer "F.Fab")
		)
		(fp_line
			(start 0.67945 0.3048)
			(end 0.120396 0.3048)
			(stroke
				(width 0.1)
				(type default)
			)
			(layer "F.Fab")
		)
		(pad "1" smd circle
			(at -0.40005 0)
			(size 0 0)
			(layers "F.Cu" "F.Mask" "F.Paste")
			(net "SPI_BIC1_CS0_LS01_R1_N")
		)
		(pad "2" smd circle
			(at 0.40005 0)
			(size 0 0)
			(layers "F.Cu" "F.Mask" "F.Paste")
			(net "SPI_BIC1_CS0_LS01_R_N")
		)
	)
	(footprint ""
		(layer "F.Cu")
		(at 15.63497 -247.598184 -90)
		(property "Reference" "C4231"
			(at 0 0 270)
			(layer "F.SilkS")
			(hide yes)
			(effects
				(font
					(size 1.27 1.27)
				)
			)
		)
		(property "Value" ""
			(at 0 0 270)
			(layer "F.Fab")
			(effects
				(font
					(size 1.27 1.27)
				)
			)
		)
		(duplicate_pad_numbers_are_jumpers no)
		(fp_line
			(start -1.524 0.762)
			(end -1.524 -0.762)
			(stroke
				(width 0.1524)
				(type default)
			)
			(layer "F.SilkS")
		)
		(fp_line
			(start 1.524 0.762)
			(end -1.524 0.762)
			(stroke
				(width 0.1524)
				(type default)
			)
			(layer "F.SilkS")
		)
		(fp_line
			(start -1.524 -0.762)
			(end 1.524 -0.762)
			(stroke
				(width 0.1524)
				(type default)
			)
			(layer "F.SilkS")
		)
		(fp_line
			(start 1.524 -0.762)
			(end 1.524 0.762)
			(stroke
				(width 0.1524)
				(type default)
			)
			(layer "F.SilkS")
		)
		(fp_line
			(start -1.1049 0.724916)
			(end 1.1049 0.724916)
			(stroke
				(width 0.1)
				(type default)
			)
			(layer "F.Fab")
		)
		(fp_line
			(start 1.1049 0.724916)
			(end 1.1049 -0.724916)
			(stroke
				(width 0.1)
				(type default)
			)
			(layer "F.Fab")
		)
		(fp_line
			(start -1.1049 -0.724916)
			(end -1.1049 0.724916)
			(stroke
				(width 0.1)
				(type default)
			)
			(layer "F.Fab")
		)
		(fp_line
			(start 1.1049 -0.724916)
			(end -1.1049 -0.724916)
			(stroke
				(width 0.1)
				(type default)
			)
			(layer "F.Fab")
		)
		(pad "1" smd rect
			(at -0.889 0 90)
			(size 1.016 1.27)
			(layers "F.Cu" "F.Mask" "F.Paste")
			(net "P1V25_SERDES_VDDPLL_PEX0_C5")
		)
		(pad "2" smd rect
			(at 0.889 0 90)
			(size 1.016 1.27)
			(layers "F.Cu" "F.Mask" "F.Paste")
			(net "GND")
		)
		(zone
			(layer "F.Cu")
			(hatch none 0.5)
			(connect_pads
				(clearance 0)
			)
			(min_thickness 0.25)
			(keepout
				(tracks not_allowed)
				(vias allowed)
				(pads allowed)
				(copperpour not_allowed)
				(footprints allowed)
			)
			(placement
				(enabled no)
				(sheetname "")
			)
			(fill
				(thermal_gap 0.5)
				(thermal_bridge_width 0.5)
				(island_removal_mode 0)
			)
			(polygon
				(pts
					(xy 16.359886 -247.928384) (xy 14.910054 -247.928384) (xy 14.910054 -247.267984) (xy 16.359886 -247.267984)
				)
			)
		)
	)
	(footprint ""
		(layer "F.Cu")
		(at 237.900464 -227.737416 90)
		(property "Reference" "C4436"
			(at 0 0 90)
			(layer "F.SilkS")
			(hide yes)
			(effects
				(font
					(size 1.27 1.27)
				)
			)
		)
		(property "Value" ""
			(at 0 0 90)
			(layer "F.Fab")
			(effects
				(font
					(size 1.27 1.27)
				)
			)
		)
		(duplicate_pad_numbers_are_jumpers no)
		(fp_line
			(start 0.7874 -0.4064)
			(end 0.7874 0.4064)
			(stroke
				(width 0.1524)
				(type default)
			)
			(layer "F.SilkS")
		)
		(fp_line
			(start -0.7874 -0.4064)
			(end 0.7874 -0.4064)
			(stroke
				(width 0.1524)
				(type default)
			)
			(layer "F.SilkS")
		)
		(fp_line
			(start 0.7874 0.4064)
			(end -0.7874 0.4064)
			(stroke
				(width 0.1524)
				(type default)
			)
			(layer "F.SilkS")
		)
		(fp_line
			(start -0.7874 0.4064)
			(end -0.7874 -0.4064)
			(stroke
				(width 0.1524)
				(type default)
			)
			(layer "F.SilkS")
		)
		(fp_line
			(start -0.12065 -0.305054)
			(end -0.12065 -0.2794)
			(stroke
				(width 0.1)
				(type default)
			)
			(layer "F.Fab")
		)
		(fp_line
			(start -0.67945 -0.305054)
			(end -0.12065 -0.305054)
			(stroke
				(width 0.1)
				(type default)
			)
			(layer "F.Fab")
		)
		(fp_line
			(start 0.67945 -0.3048)
			(end 0.67945 0.3048)
			(stroke
				(width 0.1)
				(type default)
			)
			(layer "F.Fab")
		)
		(fp_line
			(start 0.12065 -0.3048)
			(end 0.67945 -0.3048)
			(stroke
				(width 0.1)
				(type default)
			)
			(layer "F.Fab")
		)
		(fp_line
			(start 0.12065 -0.2794)
			(end 0.12065 -0.3048)
			(stroke
				(width 0.1)
				(type default)
			)
			(layer "F.Fab")
		)
		(fp_line
			(start -0.12065 -0.2794)
			(end 0.12065 -0.2794)
			(stroke
				(width 0.1)
				(type default)
			)
			(layer "F.Fab")
		)
		(fp_line
			(start 0.120396 0.2794)
			(end -0.12065 0.2794)
			(stroke
				(width 0.1)
				(type default)
			)
			(layer "F.Fab")
		)
		(fp_line
			(start -0.12065 0.2794)
			(end -0.12065 0.3048)
			(stroke
				(width 0.1)
				(type default)
			)
			(layer "F.Fab")
		)
		(fp_line
			(start 0.67945 0.3048)
			(end 0.120396 0.3048)
			(stroke
				(width 0.1)
				(type default)
			)
			(layer "F.Fab")
		)
		(fp_line
			(start 0.120396 0.3048)
			(end 0.120396 0.2794)
			(stroke
				(width 0.1)
				(type default)
			)
			(layer "F.Fab")
		)
		(fp_line
			(start -0.12065 0.3048)
			(end -0.67945 0.3048)
			(stroke
				(width 0.1)
				(type default)
			)
			(layer "F.Fab")
		)
		(fp_line
			(start -0.67945 0.3048)
			(end -0.67945 -0.305054)
			(stroke
				(width 0.1)
				(type default)
			)
			(layer "F.Fab")
		)
		(pad "1" smd circle
			(at -0.40005 0 90)
			(size 0 0)
			(layers "F.Cu" "F.Mask" "F.Paste")
			(net "P1V8_PLL0_PEX2_SCALED")
		)
		(pad "2" smd circle
			(at 0.40005 0 90)
			(size 0 0)
			(layers "F.Cu" "F.Mask" "F.Paste")
			(net "GND")
		)
	)
	(footprint ""
		(layer "F.Cu")
		(at 204.85227 -375.060464 180)
		(property "Reference" "PR3"
			(at 0 0 180)
			(layer "F.SilkS")
			(hide yes)
			(effects
				(font
					(size 1.27 1.27)
				)
			)
		)
		(property "Value" ""
			(at 0 0 180)
			(layer "F.Fab")
			(effects
				(font
					(size 1.27 1.27)
				)
			)
		)
		(duplicate_pad_numbers_are_jumpers no)
		(fp_line
			(start 0.7874 0.4064)
			(end -0.7874 0.4064)
			(stroke
				(width 0.1524)
				(type default)
			)
			(layer "F.SilkS")
		)
		(fp_line
			(start 0.7874 -0.4064)
			(end 0.7874 0.4064)
			(stroke
				(width 0.1524)
				(type default)
			)
			(layer "F.SilkS")
		)
		(fp_line
			(start -0.7874 0.4064)
			(end -0.7874 -0.4064)
			(stroke
				(width 0.1524)
				(type default)
			)
			(layer "F.SilkS")
		)
		(fp_line
			(start -0.7874 -0.4064)
			(end 0.7874 -0.4064)
			(stroke
				(width 0.1524)
				(type default)
			)
			(layer "F.SilkS")
		)
		(fp_line
			(start 0.67945 0.3048)
			(end 0.120396 0.3048)
			(stroke
				(width 0.1)
				(type default)
			)
			(layer "F.Fab")
		)
		(fp_line
			(start 0.67945 -0.3048)
			(end 0.67945 0.3048)
			(stroke
				(width 0.1)
				(type default)
			)
			(layer "F.Fab")
		)
		(fp_line
			(start 0.12065 -0.2794)
			(end 0.12065 -0.3048)
			(stroke
				(width 0.1)
				(type default)
			)
			(layer "F.Fab")
		)
		(fp_line
			(start 0.12065 -0.3048)
			(end 0.67945 -0.3048)
			(stroke
				(width 0.1)
				(type default)
			)
			(layer "F.Fab")
		)
		(fp_line
			(start 0.120396 0.3048)
			(end 0.120396 0.2794)
			(stroke
				(width 0.1)
				(type default)
			)
			(layer "F.Fab")
		)
		(fp_line
			(start 0.120396 0.2794)
			(end -0.12065 0.2794)
			(stroke
				(width 0.1)
				(type default)
			)
			(layer "F.Fab")
		)
		(fp_line
			(start -0.12065 0.3048)
			(end -0.67945 0.3048)
			(stroke
				(width 0.1)
				(type default)
			)
			(layer "F.Fab")
		)
		(fp_line
			(start -0.12065 0.2794)
			(end -0.12065 0.3048)
			(stroke
				(width 0.1)
				(type default)
			)
			(layer "F.Fab")
		)
		(fp_line
			(start -0.12065 -0.2794)
			(end 0.12065 -0.2794)
			(stroke
				(width 0.1)
				(type default)
			)
			(layer "F.Fab")
		)
		(fp_line
			(start -0.12065 -0.305054)
			(end -0.12065 -0.2794)
			(stroke
				(width 0.1)
				(type default)
			)
			(layer "F.Fab")
		)
		(fp_line
			(start -0.67945 0.3048)
			(end -0.67945 -0.305054)
			(stroke
				(width 0.1)
				(type default)
			)
			(layer "F.Fab")
		)
		(fp_line
			(start -0.67945 -0.305054)
			(end -0.12065 -0.305054)
			(stroke
				(width 0.1)
				(type default)
			)
			(layer "F.Fab")
		)
		(pad "1" smd circle
			(at -0.40005 0 180)
			(size 0 0)
			(layers "F.Cu" "F.Mask" "F.Paste")
			(net "P12V_STBY")
		)
		(pad "2" smd circle
			(at 0.40005 0 180)
			(size 0 0)
			(layers "F.Cu" "F.Mask" "F.Paste")
			(net "HSC_VINSEN")
		)
	)
	(footprint ""
		(layer "F.Cu")
		(at 95.926402 -25.432004 -90)
		(property "Reference" "C968"
			(at 0 0 270)
			(layer "F.SilkS")
			(hide yes)
			(effects
				(font
					(size 1.27 1.27)
				)
			)
		)
		(property "Value" ""
			(at 0 0 270)
			(layer "F.Fab")
			(effects
				(font
					(size 1.27 1.27)
				)
			)
		)
		(duplicate_pad_numbers_are_jumpers no)
		(fp_line
			(start -0.7874 0.4064)
			(end -0.7874 -0.4064)
			(stroke
				(width 0.1524)
				(type default)
			)
			(layer "F.SilkS")
		)
		(fp_line
			(start 0.7874 0.4064)
			(end -0.7874 0.4064)
			(stroke
				(width 0.1524)
				(type default)
			)
			(layer "F.SilkS")
		)
		(fp_line
			(start -0.7874 -0.4064)
			(end 0.7874 -0.4064)
			(stroke
				(width 0.1524)
				(type default)
			)
			(layer "F.SilkS")
		)
		(fp_line
			(start 0.7874 -0.4064)
			(end 0.7874 0.4064)
			(stroke
				(width 0.1524)
				(type default)
			)
			(layer "F.SilkS")
		)
		(fp_line
			(start -0.67945 0.3048)
			(end -0.67945 -0.305054)
			(stroke
				(width 0.1)
				(type default)
			)
			(layer "F.Fab")
		)
		(fp_line
			(start -0.12065 0.3048)
			(end -0.67945 0.3048)
			(stroke
				(width 0.1)
				(type default)
			)
			(layer "F.Fab")
		)
		(fp_line
			(start 0.120396 0.3048)
			(end 0.120396 0.2794)
			(stroke
				(width 0.1)
				(type default)
			)
			(layer "F.Fab")
		)
		(fp_line
			(start 0.67945 0.3048)
			(end 0.120396 0.3048)
			(stroke
				(width 0.1)
				(type default)
			)
			(layer "F.Fab")
		)
		(fp_line
			(start -0.12065 0.2794)
			(end -0.12065 0.3048)
			(stroke
				(width 0.1)
				(type default)
			)
			(layer "F.Fab")
		)
		(fp_line
			(start 0.120396 0.2794)
			(end -0.12065 0.2794)
			(stroke
				(width 0.1)
				(type default)
			)
			(layer "F.Fab")
		)
		(fp_line
			(start -0.12065 -0.2794)
			(end 0.12065 -0.2794)
			(stroke
				(width 0.1)
				(type default)
			)
			(layer "F.Fab")
		)
		(fp_line
			(start 0.12065 -0.2794)
			(end 0.12065 -0.3048)
			(stroke
				(width 0.1)
				(type default)
			)
			(layer "F.Fab")
		)
		(fp_line
			(start 0.12065 -0.3048)
			(end 0.67945 -0.3048)
			(stroke
				(width 0.1)
				(type default)
			)
			(layer "F.Fab")
		)
		(fp_line
			(start 0.67945 -0.3048)
			(end 0.67945 0.3048)
			(stroke
				(width 0.1)
				(type default)
			)
			(layer "F.Fab")
		)
		(fp_line
			(start -0.67945 -0.305054)
			(end -0.12065 -0.305054)
			(stroke
				(width 0.1)
				(type default)
			)
			(layer "F.Fab")
		)
		(fp_line
			(start -0.12065 -0.305054)
			(end -0.12065 -0.2794)
			(stroke
				(width 0.1)
				(type default)
			)
			(layer "F.Fab")
		)
		(pad "1" smd circle
			(at -0.40005 0 270)
			(size 0 0)
			(layers "F.Cu" "F.Mask" "F.Paste")
			(net "GND")
		)
		(pad "2" smd circle
			(at 0.40005 0 270)
			(size 0 0)
			(layers "F.Cu" "F.Mask" "F.Paste")
			(net "P3V3_SSD3")
		)
	)
	(footprint ""
		(layer "F.Cu")
		(at 432.166776 -52.543456 180)
		(property "Reference" "PC587"
			(at 0 0 180)
			(layer "F.SilkS")
			(hide yes)
			(effects
				(font
					(size 1.27 1.27)
				)
			)
		)
		(property "Value" ""
			(at 0 0 180)
			(layer "F.Fab")
			(effects
				(font
					(size 1.27 1.27)
				)
			)
		)
		(duplicate_pad_numbers_are_jumpers no)
		(fp_line
			(start 0.7874 0.4064)
			(end -0.7874 0.4064)
			(stroke
				(width 0.1524)
				(type default)
			)
			(layer "F.SilkS")
		)
		(fp_line
			(start 0.7874 -0.4064)
			(end 0.7874 0.4064)
			(stroke
				(width 0.1524)
				(type default)
			)
			(layer "F.SilkS")
		)
		(fp_line
			(start -0.7874 0.4064)
			(end -0.7874 -0.4064)
			(stroke
				(width 0.1524)
				(type default)
			)
			(layer "F.SilkS")
		)
		(fp_line
			(start -0.7874 -0.4064)
			(end 0.7874 -0.4064)
			(stroke
				(width 0.1524)
				(type default)
			)
			(layer "F.SilkS")
		)
		(fp_line
			(start 0.67945 0.3048)
			(end 0.120396 0.3048)
			(stroke
				(width 0.1)
				(type default)
			)
			(layer "F.Fab")
		)
		(fp_line
			(start 0.67945 -0.3048)
			(end 0.67945 0.3048)
			(stroke
				(width 0.1)
				(type default)
			)
			(layer "F.Fab")
		)
		(fp_line
			(start 0.12065 -0.2794)
			(end 0.12065 -0.3048)
			(stroke
				(width 0.1)
				(type default)
			)
			(layer "F.Fab")
		)
		(fp_line
			(start 0.12065 -0.3048)
			(end 0.67945 -0.3048)
			(stroke
				(width 0.1)
				(type default)
			)
			(layer "F.Fab")
		)
		(fp_line
			(start 0.120396 0.3048)
			(end 0.120396 0.2794)
			(stroke
				(width 0.1)
				(type default)
			)
			(layer "F.Fab")
		)
		(fp_line
			(start 0.120396 0.2794)
			(end -0.12065 0.2794)
			(stroke
				(width 0.1)
				(type default)
			)
			(layer "F.Fab")
		)
		(fp_line
			(start -0.12065 0.3048)
			(end -0.67945 0.3048)
			(stroke
				(width 0.1)
				(type default)
			)
			(layer "F.Fab")
		)
		(fp_line
			(start -0.12065 0.2794)
			(end -0.12065 0.3048)
			(stroke
				(width 0.1)
				(type default)
			)
			(layer "F.Fab")
		)
		(fp_line
			(start -0.12065 -0.2794)
			(end 0.12065 -0.2794)
			(stroke
				(width 0.1)
				(type default)
			)
			(layer "F.Fab")
		)
		(fp_line
			(start -0.12065 -0.305054)
			(end -0.12065 -0.2794)
			(stroke
				(width 0.1)
				(type default)
			)
			(layer "F.Fab")
		)
		(fp_line
			(start -0.67945 0.3048)
			(end -0.67945 -0.305054)
			(stroke
				(width 0.1)
				(type default)
			)
			(layer "F.Fab")
		)
		(fp_line
			(start -0.67945 -0.305054)
			(end -0.12065 -0.305054)
			(stroke
				(width 0.1)
				(type default)
			)
			(layer "F.Fab")
		)
		(pad "1" smd circle
			(at -0.40005 0 180)
			(size 0 0)
			(layers "F.Cu" "F.Mask" "F.Paste")
			(net "P3V3_SSD15")
		)
		(pad "2" smd circle
			(at 0.40005 0 180)
			(size 0 0)
			(layers "F.Cu" "F.Mask" "F.Paste")
			(net "GND")
		)
	)
	(footprint ""
		(layer "F.Cu")
		(at 290.548822 -350.098614 90)
		(property "Reference" "C2362"
			(at 0 0 90)
			(layer "F.SilkS")
			(hide yes)
			(effects
				(font
					(size 1.27 1.27)
				)
			)
		)
		(property "Value" ""
			(at 0 0 90)
			(layer "F.Fab")
			(effects
				(font
					(size 1.27 1.27)
				)
			)
		)
		(duplicate_pad_numbers_are_jumpers no)
		(fp_line
			(start 0.299974 -0.150114)
			(end 0.299974 0.150114)
			(stroke
				(width 0.1)
				(type default)
			)
			(layer "F.Fab")
		)
		(fp_line
			(start -0.299974 -0.150114)
			(end 0.299974 -0.150114)
			(stroke
				(width 0.1)
				(type default)
			)
			(layer "F.Fab")
		)
		(fp_line
			(start 0.299974 0.150114)
			(end -0.299974 0.150114)
			(stroke
				(width 0.1)
				(type default)
			)
			(layer "F.Fab")
		)
		(fp_line
			(start -0.299974 0.150114)
			(end -0.299974 -0.150114)
			(stroke
				(width 0.1)
				(type default)
			)
			(layer "F.Fab")
		)
		(pad "1" smd rect
			(at -0.2667 0 90)
			(size 0.3048 0.381)
			(layers "F.Cu" "F.Mask" "F.Paste")
			(net "P5E_PEX2_STN4_TX_DN<69>")
		)
		(pad "2" smd rect
			(at 0.2667 0 90)
			(size 0.3048 0.381)
			(layers "F.Cu" "F.Mask" "F.Paste")
			(net "P5E_PEX2_STN4_TX_C_DN<69>")
		)
	)
	(footprint ""
		(layer "F.Cu")
		(at 267.498576 -137.259314 -90)
		(property "Reference" "C913"
			(at 0 0 270)
			(layer "F.SilkS")
			(hide yes)
			(effects
				(font
					(size 1.27 1.27)
				)
			)
		)
		(property "Value" ""
			(at 0 0 270)
			(layer "F.Fab")
			(effects
				(font
					(size 1.27 1.27)
				)
			)
		)
		(duplicate_pad_numbers_are_jumpers no)
		(fp_line
			(start -0.7874 0.4064)
			(end -0.7874 -0.4064)
			(stroke
				(width 0.1524)
				(type default)
			)
			(layer "F.SilkS")
		)
		(fp_line
			(start 0.7874 0.4064)
			(end -0.7874 0.4064)
			(stroke
				(width 0.1524)
				(type default)
			)
			(layer "F.SilkS")
		)
		(fp_line
			(start -0.7874 -0.4064)
			(end 0.7874 -0.4064)
			(stroke
				(width 0.1524)
				(type default)
			)
			(layer "F.SilkS")
		)
		(fp_line
			(start 0.7874 -0.4064)
			(end 0.7874 0.4064)
			(stroke
				(width 0.1524)
				(type default)
			)
			(layer "F.SilkS")
		)
		(fp_line
			(start -0.67945 0.3048)
			(end -0.67945 -0.305054)
			(stroke
				(width 0.1)
				(type default)
			)
			(layer "F.Fab")
		)
		(fp_line
			(start -0.12065 0.3048)
			(end -0.67945 0.3048)
			(stroke
				(width 0.1)
				(type default)
			)
			(layer "F.Fab")
		)
		(fp_line
			(start 0.120396 0.3048)
			(end 0.120396 0.2794)
			(stroke
				(width 0.1)
				(type default)
			)
			(layer "F.Fab")
		)
		(fp_line
			(start 0.67945 0.3048)
			(end 0.120396 0.3048)
			(stroke
				(width 0.1)
				(type default)
			)
			(layer "F.Fab")
		)
		(fp_line
			(start -0.12065 0.2794)
			(end -0.12065 0.3048)
			(stroke
				(width 0.1)
				(type default)
			)
			(layer "F.Fab")
		)
		(fp_line
			(start 0.120396 0.2794)
			(end -0.12065 0.2794)
			(stroke
				(width 0.1)
				(type default)
			)
			(layer "F.Fab")
		)
		(fp_line
			(start -0.12065 -0.2794)
			(end 0.12065 -0.2794)
			(stroke
				(width 0.1)
				(type default)
			)
			(layer "F.Fab")
		)
		(fp_line
			(start 0.12065 -0.2794)
			(end 0.12065 -0.3048)
			(stroke
				(width 0.1)
				(type default)
			)
			(layer "F.Fab")
		)
		(fp_line
			(start 0.12065 -0.3048)
			(end 0.67945 -0.3048)
			(stroke
				(width 0.1)
				(type default)
			)
			(layer "F.Fab")
		)
		(fp_line
			(start 0.67945 -0.3048)
			(end 0.67945 0.3048)
			(stroke
				(width 0.1)
				(type default)
			)
			(layer "F.Fab")
		)
		(fp_line
			(start -0.67945 -0.305054)
			(end -0.12065 -0.305054)
			(stroke
				(width 0.1)
				(type default)
			)
			(layer "F.Fab")
		)
		(fp_line
			(start -0.12065 -0.305054)
			(end -0.12065 -0.2794)
			(stroke
				(width 0.1)
				(type default)
			)
			(layer "F.Fab")
		)
		(pad "1" smd circle
			(at -0.40005 0 270)
			(size 0 0)
			(layers "F.Cu" "F.Mask" "F.Paste")
			(net "P3V3_NIC4")
		)
		(pad "2" smd circle
			(at 0.40005 0 270)
			(size 0 0)
			(layers "F.Cu" "F.Mask" "F.Paste")
			(net "GND")
		)
	)
	(footprint ""
		(layer "F.Cu")
		(at 82.661506 -135.28675 180)
		(property "Reference" "C18"
			(at 0 0 180)
			(layer "F.SilkS")
			(hide yes)
			(effects
				(font
					(size 1.27 1.27)
				)
			)
		)
		(property "Value" ""
			(at 0 0 180)
			(layer "F.Fab")
			(effects
				(font
					(size 1.27 1.27)
				)
			)
		)
		(duplicate_pad_numbers_are_jumpers no)
		(fp_line
			(start 0.299974 0.150114)
			(end -0.299974 0.150114)
			(stroke
				(width 0.1)
				(type default)
			)
			(layer "F.Fab")
		)
		(fp_line
			(start 0.299974 -0.150114)
			(end 0.299974 0.150114)
			(stroke
				(width 0.1)
				(type default)
			)
			(layer "F.Fab")
		)
		(fp_line
			(start -0.299974 0.150114)
			(end -0.299974 -0.150114)
			(stroke
				(width 0.1)
				(type default)
			)
			(layer "F.Fab")
		)
		(fp_line
			(start -0.299974 -0.150114)
			(end 0.299974 -0.150114)
			(stroke
				(width 0.1)
				(type default)
			)
			(layer "F.Fab")
		)
		(pad "1" smd rect
			(at -0.2667 0 180)
			(size 0.3048 0.381)
			(layers "F.Cu" "F.Mask" "F.Paste")
			(net "P5E_PEX0_STN0_TX_DN<7>")
		)
		(pad "2" smd rect
			(at 0.2667 0 180)
			(size 0.3048 0.381)
			(layers "F.Cu" "F.Mask" "F.Paste")
			(net "P5E_PEX0_STN0_TX_C_DN<7>")
		)
	)
	(footprint ""
		(layer "F.Cu")
		(at 455.447908 -296.887646 -90)
		(property "Reference" "PL24"
			(at -5.334 -7.435088 90)
			(unlocked yes)
			(layer "F.SilkS")
			(effects
				(font
					(size 0.7874 0.5842)
					(thickness 0.1524)
				)
			)
		)
		(property "Value" ""
			(at 0 0 270)
			(layer "F.Fab")
			(effects
				(font
					(size 1.27 1.27)
				)
			)
		)
		(duplicate_pad_numbers_are_jumpers no)
		(fp_line
			(start -6.849872 6.450076)
			(end -6.849872 1.9812)
			(stroke
				(width 0.1524)
				(type default)
			)
			(layer "F.SilkS")
		)
		(fp_line
			(start 6.849872 6.450076)
			(end -6.849872 6.450076)
			(stroke
				(width 0.1524)
				(type default)
			)
			(layer "F.SilkS")
		)
		(fp_line
			(start 6.849872 1.9812)
			(end 6.849872 6.450076)
			(stroke
				(width 0.1524)
				(type default)
			)
			(layer "F.SilkS")
		)
		(fp_line
			(start -6.849872 -1.9812)
			(end -6.849872 -6.450076)
			(stroke
				(width 0.1524)
				(type default)
			)
			(layer "F.SilkS")
		)
		(fp_line
			(start -6.849872 -6.450076)
			(end 6.849872 -6.450076)
			(stroke
				(width 0.1524)
				(type default)
			)
			(layer "F.SilkS")
		)
		(fp_line
			(start 6.849872 -6.450076)
			(end 6.849872 -1.9812)
			(stroke
				(width 0.1524)
				(type default)
			)
			(layer "F.SilkS")
		)
		(fp_line
			(start -6.849872 6.450076)
			(end -6.849872 -6.450076)
			(stroke
				(width 0.1)
				(type default)
			)
			(layer "F.Fab")
		)
		(fp_line
			(start 6.849872 6.450076)
			(end -6.849872 6.450076)
			(stroke
				(width 0.1)
				(type default)
			)
			(layer "F.Fab")
		)
		(fp_line
			(start -6.849872 -6.450076)
			(end 6.849872 -6.450076)
			(stroke
				(width 0.1)
				(type default)
			)
			(layer "F.Fab")
		)
		(fp_line
			(start 6.849872 -6.450076)
			(end 6.849872 6.450076)
			(stroke
				(width 0.1)
				(type default)
			)
			(layer "F.Fab")
		)
		(pad "1" smd rect
			(at -5.407406 0 270)
			(size 2.9464 3.7084)
			(layers "F.Cu" "F.Mask" "F.Paste")
			(net "SW_P1V25_PEX3_PH")
		)
		(pad "2" smd rect
			(at 5.407406 0 270)
			(size 2.9464 3.7084)
			(layers "F.Cu" "F.Mask" "F.Paste")
			(net "P1V25_PEX3_R")
		)
	)
	(footprint ""
		(layer "F.Cu")
		(at 365.506 -215.011)
		(property "Reference" "R4619"
			(at 0 0 0)
			(layer "F.SilkS")
			(hide yes)
			(effects
				(font
					(size 1.27 1.27)
				)
			)
		)
		(property "Value" ""
			(at 0 0 0)
			(layer "F.Fab")
			(effects
				(font
					(size 1.27 1.27)
				)
			)
		)
		(duplicate_pad_numbers_are_jumpers no)
		(fp_line
			(start -0.7874 -0.4064)
			(end 0.7874 -0.4064)
			(stroke
				(width 0.1524)
				(type default)
			)
			(layer "F.SilkS")
		)
		(fp_line
			(start -0.7874 0.4064)
			(end -0.7874 -0.4064)
			(stroke
				(width 0.1524)
				(type default)
			)
			(layer "F.SilkS")
		)
		(fp_line
			(start 0.7874 -0.4064)
			(end 0.7874 0.4064)
			(stroke
				(width 0.1524)
				(type default)
			)
			(layer "F.SilkS")
		)
		(fp_line
			(start 0.7874 0.4064)
			(end -0.7874 0.4064)
			(stroke
				(width 0.1524)
				(type default)
			)
			(layer "F.SilkS")
		)
		(fp_line
			(start -0.67945 -0.305054)
			(end -0.12065 -0.305054)
			(stroke
				(width 0.1)
				(type default)
			)
			(layer "F.Fab")
		)
		(fp_line
			(start -0.67945 0.3048)
			(end -0.67945 -0.305054)
			(stroke
				(width 0.1)
				(type default)
			)
			(layer "F.Fab")
		)
		(fp_line
			(start -0.12065 -0.305054)
			(end -0.12065 -0.2794)
			(stroke
				(width 0.1)
				(type default)
			)
			(layer "F.Fab")
		)
		(fp_line
			(start -0.12065 -0.2794)
			(end 0.12065 -0.2794)
			(stroke
				(width 0.1)
				(type default)
			)
			(layer "F.Fab")
		)
		(fp_line
			(start -0.12065 0.2794)
			(end -0.12065 0.3048)
			(stroke
				(width 0.1)
				(type default)
			)
			(layer "F.Fab")
		)
		(fp_line
			(start -0.12065 0.3048)
			(end -0.67945 0.3048)
			(stroke
				(width 0.1)
				(type default)
			)
			(layer "F.Fab")
		)
		(fp_line
			(start 0.120396 0.2794)
			(end -0.12065 0.2794)
			(stroke
				(width 0.1)
				(type default)
			)
			(layer "F.Fab")
		)
		(fp_line
			(start 0.120396 0.3048)
			(end 0.120396 0.2794)
			(stroke
				(width 0.1)
				(type default)
			)
			(layer "F.Fab")
		)
		(fp_line
			(start 0.12065 -0.3048)
			(end 0.67945 -0.3048)
			(stroke
				(width 0.1)
				(type default)
			)
			(layer "F.Fab")
		)
		(fp_line
			(start 0.12065 -0.2794)
			(end 0.12065 -0.3048)
			(stroke
				(width 0.1)
				(type default)
			)
			(layer "F.Fab")
		)
		(fp_line
			(start 0.67945 -0.3048)
			(end 0.67945 0.3048)
			(stroke
				(width 0.1)
				(type default)
			)
			(layer "F.Fab")
		)
		(fp_line
			(start 0.67945 0.3048)
			(end 0.120396 0.3048)
			(stroke
				(width 0.1)
				(type default)
			)
			(layer "F.Fab")
		)
		(pad "1" smd circle
			(at -0.40005 0)
			(size 0 0)
			(layers "F.Cu" "F.Mask" "F.Paste")
			(net "PEX0_PCA9555_0_INT_N")
		)
		(pad "2" smd circle
			(at 0.40005 0)
			(size 0 0)
			(layers "F.Cu" "F.Mask" "F.Paste")
			(net "P1V8_PEX")
		)
	)
	(footprint ""
		(layer "F.Cu")
		(at 242.61191 -253.996444 -90)
		(property "Reference" "C4356"
			(at 0 0 270)
			(layer "F.SilkS")
			(hide yes)
			(effects
				(font
					(size 1.27 1.27)
				)
			)
		)
		(property "Value" ""
			(at 0 0 270)
			(layer "F.Fab")
			(effects
				(font
					(size 1.27 1.27)
				)
			)
		)
		(duplicate_pad_numbers_are_jumpers no)
		(fp_line
			(start -1.524 0.762)
			(end -1.524 -0.762)
			(stroke
				(width 0.1524)
				(type default)
			)
			(layer "F.SilkS")
		)
		(fp_line
			(start 1.524 0.762)
			(end -1.524 0.762)
			(stroke
				(width 0.1524)
				(type default)
			)
			(layer "F.SilkS")
		)
		(fp_line
			(start -1.524 -0.762)
			(end 1.524 -0.762)
			(stroke
				(width 0.1524)
				(type default)
			)
			(layer "F.SilkS")
		)
		(fp_line
			(start 1.524 -0.762)
			(end 1.524 0.762)
			(stroke
				(width 0.1524)
				(type default)
			)
			(layer "F.SilkS")
		)
		(fp_line
			(start -1.1049 0.724916)
			(end 1.1049 0.724916)
			(stroke
				(width 0.1)
				(type default)
			)
			(layer "F.Fab")
		)
		(fp_line
			(start 1.1049 0.724916)
			(end 1.1049 -0.724916)
			(stroke
				(width 0.1)
				(type default)
			)
			(layer "F.Fab")
		)
		(fp_line
			(start -1.1049 -0.724916)
			(end -1.1049 0.724916)
			(stroke
				(width 0.1)
				(type default)
			)
			(layer "F.Fab")
		)
		(fp_line
			(start 1.1049 -0.724916)
			(end -1.1049 -0.724916)
			(stroke
				(width 0.1)
				(type default)
			)
			(layer "F.Fab")
		)
		(pad "1" smd rect
			(at -0.889 0 90)
			(size 1.016 1.27)
			(layers "F.Cu" "F.Mask" "F.Paste")
			(net "P1V25_SERDES_VDDPLL_PEX2_C10")
		)
		(pad "2" smd rect
			(at 0.889 0 90)
			(size 1.016 1.27)
			(layers "F.Cu" "F.Mask" "F.Paste")
			(net "GND")
		)
		(zone
			(layer "F.Cu")
			(hatch none 0.5)
			(connect_pads
				(clearance 0)
			)
			(min_thickness 0.25)
			(keepout
				(tracks not_allowed)
				(vias allowed)
				(pads allowed)
				(copperpour not_allowed)
				(footprints allowed)
			)
			(placement
				(enabled no)
				(sheetname "")
			)
			(fill
				(thermal_gap 0.5)
				(thermal_bridge_width 0.5)
				(island_removal_mode 0)
			)
			(polygon
				(pts
					(xy 243.336826 -254.326644) (xy 241.886994 -254.326644) (xy 241.886994 -253.666244) (xy 243.336826 -253.666244)
				)
			)
		)
	)
	(footprint ""
		(layer "F.Cu")
		(at 206.118206 -306.074572 90)
		(property "Reference" "R1304"
			(at 0 0 90)
			(layer "F.SilkS")
			(hide yes)
			(effects
				(font
					(size 1.27 1.27)
				)
			)
		)
		(property "Value" ""
			(at 0 0 90)
			(layer "F.Fab")
			(effects
				(font
					(size 1.27 1.27)
				)
			)
		)
		(duplicate_pad_numbers_are_jumpers no)
		(fp_line
			(start 0.7874 -0.4064)
			(end 0.7874 0.4064)
			(stroke
				(width 0.1524)
				(type default)
			)
			(layer "F.SilkS")
		)
		(fp_line
			(start -0.7874 -0.4064)
			(end 0.7874 -0.4064)
			(stroke
				(width 0.1524)
				(type default)
			)
			(layer "F.SilkS")
		)
		(fp_line
			(start 0.7874 0.4064)
			(end -0.7874 0.4064)
			(stroke
				(width 0.1524)
				(type default)
			)
			(layer "F.SilkS")
		)
		(fp_line
			(start -0.7874 0.4064)
			(end -0.7874 -0.4064)
			(stroke
				(width 0.1524)
				(type default)
			)
			(layer "F.SilkS")
		)
		(fp_line
			(start -0.12065 -0.305054)
			(end -0.12065 -0.2794)
			(stroke
				(width 0.1)
				(type default)
			)
			(layer "F.Fab")
		)
		(fp_line
			(start -0.67945 -0.305054)
			(end -0.12065 -0.305054)
			(stroke
				(width 0.1)
				(type default)
			)
			(layer "F.Fab")
		)
		(fp_line
			(start 0.67945 -0.3048)
			(end 0.67945 0.3048)
			(stroke
				(width 0.1)
				(type default)
			)
			(layer "F.Fab")
		)
		(fp_line
			(start 0.12065 -0.3048)
			(end 0.67945 -0.3048)
			(stroke
				(width 0.1)
				(type default)
			)
			(layer "F.Fab")
		)
		(fp_line
			(start 0.12065 -0.2794)
			(end 0.12065 -0.3048)
			(stroke
				(width 0.1)
				(type default)
			)
			(layer "F.Fab")
		)
		(fp_line
			(start -0.12065 -0.2794)
			(end 0.12065 -0.2794)
			(stroke
				(width 0.1)
				(type default)
			)
			(layer "F.Fab")
		)
		(fp_line
			(start 0.120396 0.2794)
			(end -0.12065 0.2794)
			(stroke
				(width 0.1)
				(type default)
			)
			(layer "F.Fab")
		)
		(fp_line
			(start -0.12065 0.2794)
			(end -0.12065 0.3048)
			(stroke
				(width 0.1)
				(type default)
			)
			(layer "F.Fab")
		)
		(fp_line
			(start 0.67945 0.3048)
			(end 0.120396 0.3048)
			(stroke
				(width 0.1)
				(type default)
			)
			(layer "F.Fab")
		)
		(fp_line
			(start 0.120396 0.3048)
			(end 0.120396 0.2794)
			(stroke
				(width 0.1)
				(type default)
			)
			(layer "F.Fab")
		)
		(fp_line
			(start -0.12065 0.3048)
			(end -0.67945 0.3048)
			(stroke
				(width 0.1)
				(type default)
			)
			(layer "F.Fab")
		)
		(fp_line
			(start -0.67945 0.3048)
			(end -0.67945 -0.305054)
			(stroke
				(width 0.1)
				(type default)
			)
			(layer "F.Fab")
		)
		(pad "1" smd circle
			(at -0.40005 0 90)
			(size 0 0)
			(layers "F.Cu" "F.Mask" "F.Paste")
			(net "PEX1_SPARE3")
		)
		(pad "2" smd circle
			(at 0.40005 0 90)
			(size 0 0)
			(layers "F.Cu" "F.Mask" "F.Paste")
			(net "P1V8_PEX")
		)
	)
	(footprint ""
		(layer "F.Cu")
		(at 127.185166 -115.549426 -90)
		(property "Reference" "Q214"
			(at 0.182626 1.860296 90)
			(unlocked yes)
			(layer "F.SilkS")
			(effects
				(font
					(size 0.7874 0.5842)
					(thickness 0.1524)
				)
			)
		)
		(property "Value" ""
			(at 0 0 270)
			(layer "F.Fab")
			(effects
				(font
					(size 1.27 1.27)
				)
			)
		)
		(duplicate_pad_numbers_are_jumpers no)
		(fp_line
			(start -1.376172 1.199896)
			(end -1.376172 -1.199896)
			(stroke
				(width 0.1524)
				(type default)
			)
			(layer "F.SilkS")
		)
		(fp_line
			(start 1.376172 1.199896)
			(end -1.376172 1.199896)
			(stroke
				(width 0.1524)
				(type default)
			)
			(layer "F.SilkS")
		)
		(fp_line
			(start 0 -0.762)
			(end 0.508 -1.199896)
			(stroke
				(width 0.1524)
				(type default)
			)
			(layer "F.SilkS")
		)
		(fp_line
			(start -1.376172 -1.199896)
			(end -0.508 -1.199896)
			(stroke
				(width 0.1524)
				(type default)
			)
			(layer "F.SilkS")
		)
		(fp_line
			(start -0.508 -1.199896)
			(end 0 -0.762)
			(stroke
				(width 0.1524)
				(type default)
			)
			(layer "F.SilkS")
		)
		(fp_line
			(start 0.508 -1.199896)
			(end 1.376172 -1.199896)
			(stroke
				(width 0.1524)
				(type default)
			)
			(layer "F.SilkS")
		)
		(fp_line
			(start 1.376172 -1.199896)
			(end 1.376172 1.199896)
			(stroke
				(width 0.1524)
				(type default)
			)
			(layer "F.SilkS")
		)
		(fp_poly
			(pts
				(xy -1.221486 -1.29286) (xy -1.49098 -2.101088) (xy -2.029714 -1.562354)
			)
			(stroke
				(width 0)
				(type default)
			)
			(fill yes)
			(layer "F.SilkS")
		)
		(fp_line
			(start -0.674878 1.100074)
			(end -0.674878 -1.100074)
			(stroke
				(width 0.1)
				(type default)
			)
			(layer "F.Fab")
		)
		(fp_line
			(start 0.674878 1.100074)
			(end -0.674878 1.100074)
			(stroke
				(width 0.1)
				(type default)
			)
			(layer "F.Fab")
		)
		(fp_line
			(start -0.674878 -1.100074)
			(end 0.674878 -1.100074)
			(stroke
				(width 0.1)
				(type default)
			)
			(layer "F.Fab")
		)
		(fp_line
			(start 0.674878 -1.100074)
			(end 0.674878 1.100074)
			(stroke
				(width 0.1)
				(type default)
			)
			(layer "F.Fab")
		)
		(fp_poly
			(pts
				(xy -1.4605 -0.7493) (xy -2.2225 -1.1303) (xy -2.2225 -0.3683)
			)
			(stroke
				(width 0)
				(type default)
			)
			(fill yes)
			(layer "F.Fab")
		)
		(pad "1" smd rect
			(at -0.899922 -0.750062 180)
			(size 0.6096 0.6096)
			(layers "F.Cu" "F.Mask" "F.Paste")
			(net "GND")
		)
		(pad "2" smd rect
			(at -0.899922 0 180)
			(size 0.4064 0.6096)
			(layers "F.Cu" "F.Mask" "F.Paste")
			(net "P3V3_NIC2_PG_G1")
		)
		(pad "3" smd rect
			(at -0.899922 0.750062 180)
			(size 0.6096 0.6096)
			(layers "F.Cu" "F.Mask" "F.Paste")
			(net "PWRGD_P3V3_NIC2_D")
		)
		(pad "4" smd rect
			(at 0.899922 0.750062 180)
			(size 0.6096 0.6096)
			(layers "F.Cu" "F.Mask" "F.Paste")
			(net "GND")
		)
		(pad "5" smd rect
			(at 0.899922 0 180)
			(size 0.4064 0.6096)
			(layers "F.Cu" "F.Mask" "F.Paste")
			(net "P3V3_NIC2_PG_G2")
		)
		(pad "6" smd rect
			(at 0.899922 -0.750062 180)
			(size 0.6096 0.6096)
			(layers "F.Cu" "F.Mask" "F.Paste")
			(net "P3V3_NIC2_PG_G2")
		)
	)
	(footprint ""
		(layer "F.Cu")
		(at 278.775414 -69.47916 180)
		(property "Reference" "PU112"
			(at -1.845056 4.13004 90)
			(unlocked yes)
			(layer "F.SilkS")
			(effects
				(font
					(size 0.7874 0.5842)
					(thickness 0.1524)
				)
			)
		)
		(property "Value" ""
			(at 0 0 180)
			(layer "F.Fab")
			(effects
				(font
					(size 1.27 1.27)
				)
			)
		)
		(duplicate_pad_numbers_are_jumpers no)
		(fp_line
			(start 1.239774 1.495298)
			(end -1.239774 1.495298)
			(stroke
				(width 0.1524)
				(type default)
			)
			(layer "F.SilkS")
		)
		(fp_line
			(start 1.239774 -1.495298)
			(end 1.239774 1.495298)
			(stroke
				(width 0.1524)
				(type default)
			)
			(layer "F.SilkS")
		)
		(fp_line
			(start -1.239774 1.495298)
			(end -1.239774 -1.495298)
			(stroke
				(width 0.1524)
				(type default)
			)
			(layer "F.SilkS")
		)
		(fp_line
			(start -1.239774 -1.495298)
			(end 1.239774 -1.495298)
			(stroke
				(width 0.1524)
				(type default)
			)
			(layer "F.SilkS")
		)
		(fp_poly
			(pts
				(xy -1.640586 -0.884428) (xy -2.358898 -0.166116) (xy -1.28143 0.193294)
			)
			(stroke
				(width 0)
				(type default)
			)
			(fill yes)
			(layer "F.SilkS")
		)
		(fp_line
			(start 0.8001 1.050036)
			(end -0.8001 1.050036)
			(stroke
				(width 0.1)
				(type default)
			)
			(layer "F.Fab")
		)
		(fp_line
			(start 0.8001 -1.050036)
			(end 0.8001 1.050036)
			(stroke
				(width 0.1)
				(type default)
			)
			(layer "F.Fab")
		)
		(fp_line
			(start -0.8001 1.050036)
			(end -0.8001 -1.050036)
			(stroke
				(width 0.1)
				(type default)
			)
			(layer "F.Fab")
		)
		(fp_line
			(start -0.8001 -1.050036)
			(end 0.8001 -1.050036)
			(stroke
				(width 0.1)
				(type default)
			)
			(layer "F.Fab")
		)
		(fp_poly
			(pts
				(xy -2.458974 -0.508) (xy -2.458974 0.508) (xy -1.442974 0)
			)
			(stroke
				(width 0)
				(type default)
			)
			(fill yes)
			(layer "F.Fab")
		)
		(pad "1_2" smd circle
			(at -0.374904 0 270)
			(size 0 0)
			(layers "F.Cu" "F.Mask" "F.Paste")
			(net "P12V_AUX")
		)
		(pad "3" smd rect
			(at -0.499872 0.999998 180)
			(size 0.254 0.7112)
			(layers "F.Cu" "F.Mask" "F.Paste")
			(net "GND")
		)
		(pad "4" smd rect
			(at 0 0.999998 180)
			(size 0.254 0.7112)
			(layers "F.Cu" "F.Mask" "F.Paste")
			(net "P12V_SSD9_CO_ILIMIT")
		)
		(pad "5" smd rect
			(at 0.499872 0.999998 180)
			(size 0.254 0.7112)
			(layers "F.Cu" "F.Mask" "F.Paste")
			(net "P12V_SSD9_CO_MODE")
		)
		(pad "6_7" smd circle
			(at 0.374904 0 90)
			(size 0 0)
			(layers "F.Cu" "F.Mask" "F.Paste")
			(net "P12V_SSD9_R")
		)
		(pad "8" smd rect
			(at 0.499872 -0.999998 180)
			(size 0.254 0.7112)
			(layers "F.Cu" "F.Mask" "F.Paste")
			(net "P12V_SSD9_CO_GATE")
		)
		(pad "9" smd rect
			(at 0 -0.999998 180)
			(size 0.254 0.7112)
			(layers "F.Cu" "F.Mask" "F.Paste")
			(net "P12V_SSD9_CO_EN")
		)
		(pad "10" smd rect
			(at -0.499872 -0.999998 180)
			(size 0.254 0.7112)
			(layers "F.Cu" "F.Mask" "F.Paste")
			(net "P12V_SSD9_CO_DV_DT")
		)
	)
	(footprint ""
		(layer "F.Cu")
		(at 419.557962 -72.766682 90)
		(property "Reference" "PC890"
			(at 0 0 90)
			(layer "F.SilkS")
			(hide yes)
			(effects
				(font
					(size 1.27 1.27)
				)
			)
		)
		(property "Value" ""
			(at 0 0 90)
			(layer "F.Fab")
			(effects
				(font
					(size 1.27 1.27)
				)
			)
		)
		(duplicate_pad_numbers_are_jumpers no)
		(fp_line
			(start 0.7874 -0.4064)
			(end 0.7874 0.4064)
			(stroke
				(width 0.1524)
				(type default)
			)
			(layer "F.SilkS")
		)
		(fp_line
			(start -0.7874 -0.4064)
			(end 0.7874 -0.4064)
			(stroke
				(width 0.1524)
				(type default)
			)
			(layer "F.SilkS")
		)
		(fp_line
			(start 0.7874 0.4064)
			(end -0.7874 0.4064)
			(stroke
				(width 0.1524)
				(type default)
			)
			(layer "F.SilkS")
		)
		(fp_line
			(start -0.7874 0.4064)
			(end -0.7874 -0.4064)
			(stroke
				(width 0.1524)
				(type default)
			)
			(layer "F.SilkS")
		)
		(fp_line
			(start -0.12065 -0.305054)
			(end -0.12065 -0.2794)
			(stroke
				(width 0.1)
				(type default)
			)
			(layer "F.Fab")
		)
		(fp_line
			(start -0.67945 -0.305054)
			(end -0.12065 -0.305054)
			(stroke
				(width 0.1)
				(type default)
			)
			(layer "F.Fab")
		)
		(fp_line
			(start 0.67945 -0.3048)
			(end 0.67945 0.3048)
			(stroke
				(width 0.1)
				(type default)
			)
			(layer "F.Fab")
		)
		(fp_line
			(start 0.12065 -0.3048)
			(end 0.67945 -0.3048)
			(stroke
				(width 0.1)
				(type default)
			)
			(layer "F.Fab")
		)
		(fp_line
			(start 0.12065 -0.2794)
			(end 0.12065 -0.3048)
			(stroke
				(width 0.1)
				(type default)
			)
			(layer "F.Fab")
		)
		(fp_line
			(start -0.12065 -0.2794)
			(end 0.12065 -0.2794)
			(stroke
				(width 0.1)
				(type default)
			)
			(layer "F.Fab")
		)
		(fp_line
			(start 0.120396 0.2794)
			(end -0.12065 0.2794)
			(stroke
				(width 0.1)
				(type default)
			)
			(layer "F.Fab")
		)
		(fp_line
			(start -0.12065 0.2794)
			(end -0.12065 0.3048)
			(stroke
				(width 0.1)
				(type default)
			)
			(layer "F.Fab")
		)
		(fp_line
			(start 0.67945 0.3048)
			(end 0.120396 0.3048)
			(stroke
				(width 0.1)
				(type default)
			)
			(layer "F.Fab")
		)
		(fp_line
			(start 0.120396 0.3048)
			(end 0.120396 0.2794)
			(stroke
				(width 0.1)
				(type default)
			)
			(layer "F.Fab")
		)
		(fp_line
			(start -0.12065 0.3048)
			(end -0.67945 0.3048)
			(stroke
				(width 0.1)
				(type default)
			)
			(layer "F.Fab")
		)
		(fp_line
			(start -0.67945 0.3048)
			(end -0.67945 -0.305054)
			(stroke
				(width 0.1)
				(type default)
			)
			(layer "F.Fab")
		)
		(pad "1" smd circle
			(at -0.40005 0 90)
			(size 0 0)
			(layers "F.Cu" "F.Mask" "F.Paste")
			(net "P12V_SSD14_CO_MODE")
		)
		(pad "2" smd circle
			(at 0.40005 0 90)
			(size 0 0)
			(layers "F.Cu" "F.Mask" "F.Paste")
			(net "GND")
		)
	)
	(footprint ""
		(layer "F.Cu")
		(at 361.335066 -279.101804)
		(property "Reference" "PC188"
			(at 0 0 0)
			(layer "F.SilkS")
			(hide yes)
			(effects
				(font
					(size 1.27 1.27)
				)
			)
		)
		(property "Value" ""
			(at 0 0 0)
			(layer "F.Fab")
			(effects
				(font
					(size 1.27 1.27)
				)
			)
		)
		(duplicate_pad_numbers_are_jumpers no)
		(fp_line
			(start -0.7874 -0.4064)
			(end 0.7874 -0.4064)
			(stroke
				(width 0.1524)
				(type default)
			)
			(layer "F.SilkS")
		)
		(fp_line
			(start -0.7874 0.4064)
			(end -0.7874 -0.4064)
			(stroke
				(width 0.1524)
				(type default)
			)
			(layer "F.SilkS")
		)
		(fp_line
			(start 0.7874 -0.4064)
			(end 0.7874 0.4064)
			(stroke
				(width 0.1524)
				(type default)
			)
			(layer "F.SilkS")
		)
		(fp_line
			(start 0.7874 0.4064)
			(end -0.7874 0.4064)
			(stroke
				(width 0.1524)
				(type default)
			)
			(layer "F.SilkS")
		)
		(fp_line
			(start -0.67945 -0.305054)
			(end -0.12065 -0.305054)
			(stroke
				(width 0.1)
				(type default)
			)
			(layer "F.Fab")
		)
		(fp_line
			(start -0.67945 0.3048)
			(end -0.67945 -0.305054)
			(stroke
				(width 0.1)
				(type default)
			)
			(layer "F.Fab")
		)
		(fp_line
			(start -0.12065 -0.305054)
			(end -0.12065 -0.2794)
			(stroke
				(width 0.1)
				(type default)
			)
			(layer "F.Fab")
		)
		(fp_line
			(start -0.12065 -0.2794)
			(end 0.12065 -0.2794)
			(stroke
				(width 0.1)
				(type default)
			)
			(layer "F.Fab")
		)
		(fp_line
			(start -0.12065 0.2794)
			(end -0.12065 0.3048)
			(stroke
				(width 0.1)
				(type default)
			)
			(layer "F.Fab")
		)
		(fp_line
			(start -0.12065 0.3048)
			(end -0.67945 0.3048)
			(stroke
				(width 0.1)
				(type default)
			)
			(layer "F.Fab")
		)
		(fp_line
			(start 0.120396 0.2794)
			(end -0.12065 0.2794)
			(stroke
				(width 0.1)
				(type default)
			)
			(layer "F.Fab")
		)
		(fp_line
			(start 0.120396 0.3048)
			(end 0.120396 0.2794)
			(stroke
				(width 0.1)
				(type default)
			)
			(layer "F.Fab")
		)
		(fp_line
			(start 0.12065 -0.3048)
			(end 0.67945 -0.3048)
			(stroke
				(width 0.1)
				(type default)
			)
			(layer "F.Fab")
		)
		(fp_line
			(start 0.12065 -0.2794)
			(end 0.12065 -0.3048)
			(stroke
				(width 0.1)
				(type default)
			)
			(layer "F.Fab")
		)
		(fp_line
			(start 0.67945 -0.3048)
			(end 0.67945 0.3048)
			(stroke
				(width 0.1)
				(type default)
			)
			(layer "F.Fab")
		)
		(fp_line
			(start 0.67945 0.3048)
			(end 0.120396 0.3048)
			(stroke
				(width 0.1)
				(type default)
			)
			(layer "F.Fab")
		)
		(pad "1" smd circle
			(at -0.40005 0)
			(size 0 0)
			(layers "F.Cu" "F.Mask" "F.Paste")
			(net "SW_P12V_P0V8_PEX3_FLT")
		)
		(pad "2" smd circle
			(at 0.40005 0)
			(size 0 0)
			(layers "F.Cu" "F.Mask" "F.Paste")
			(net "GND")
		)
	)
	(footprint ""
		(layer "F.Cu")
		(at 87.918544 -302.907954 -90)
		(property "Reference" "R6805"
			(at 0 0 270)
			(layer "F.SilkS")
			(hide yes)
			(effects
				(font
					(size 1.27 1.27)
				)
			)
		)
		(property "Value" ""
			(at 0 0 270)
			(layer "F.Fab")
			(effects
				(font
					(size 1.27 1.27)
				)
			)
		)
		(duplicate_pad_numbers_are_jumpers no)
		(fp_line
			(start -0.7874 0.4064)
			(end -0.7874 -0.4064)
			(stroke
				(width 0.1524)
				(type default)
			)
			(layer "F.SilkS")
		)
		(fp_line
			(start 0.7874 0.4064)
			(end -0.7874 0.4064)
			(stroke
				(width 0.1524)
				(type default)
			)
			(layer "F.SilkS")
		)
		(fp_line
			(start -0.7874 -0.4064)
			(end 0.7874 -0.4064)
			(stroke
				(width 0.1524)
				(type default)
			)
			(layer "F.SilkS")
		)
		(fp_line
			(start 0.7874 -0.4064)
			(end 0.7874 0.4064)
			(stroke
				(width 0.1524)
				(type default)
			)
			(layer "F.SilkS")
		)
		(fp_line
			(start -0.67945 0.3048)
			(end -0.67945 -0.305054)
			(stroke
				(width 0.1)
				(type default)
			)
			(layer "F.Fab")
		)
		(fp_line
			(start -0.12065 0.3048)
			(end -0.67945 0.3048)
			(stroke
				(width 0.1)
				(type default)
			)
			(layer "F.Fab")
		)
		(fp_line
			(start 0.120396 0.3048)
			(end 0.120396 0.2794)
			(stroke
				(width 0.1)
				(type default)
			)
			(layer "F.Fab")
		)
		(fp_line
			(start 0.67945 0.3048)
			(end 0.120396 0.3048)
			(stroke
				(width 0.1)
				(type default)
			)
			(layer "F.Fab")
		)
		(fp_line
			(start -0.12065 0.2794)
			(end -0.12065 0.3048)
			(stroke
				(width 0.1)
				(type default)
			)
			(layer "F.Fab")
		)
		(fp_line
			(start 0.120396 0.2794)
			(end -0.12065 0.2794)
			(stroke
				(width 0.1)
				(type default)
			)
			(layer "F.Fab")
		)
		(fp_line
			(start -0.12065 -0.2794)
			(end 0.12065 -0.2794)
			(stroke
				(width 0.1)
				(type default)
			)
			(layer "F.Fab")
		)
		(fp_line
			(start 0.12065 -0.2794)
			(end 0.12065 -0.3048)
			(stroke
				(width 0.1)
				(type default)
			)
			(layer "F.Fab")
		)
		(fp_line
			(start 0.12065 -0.3048)
			(end 0.67945 -0.3048)
			(stroke
				(width 0.1)
				(type default)
			)
			(layer "F.Fab")
		)
		(fp_line
			(start 0.67945 -0.3048)
			(end 0.67945 0.3048)
			(stroke
				(width 0.1)
				(type default)
			)
			(layer "F.Fab")
		)
		(fp_line
			(start -0.67945 -0.305054)
			(end -0.12065 -0.305054)
			(stroke
				(width 0.1)
				(type default)
			)
			(layer "F.Fab")
		)
		(fp_line
			(start -0.12065 -0.305054)
			(end -0.12065 -0.2794)
			(stroke
				(width 0.1)
				(type default)
			)
			(layer "F.Fab")
		)
		(pad "1" smd circle
			(at -0.40005 0 270)
			(size 0 0)
			(layers "F.Cu" "F.Mask" "F.Paste")
			(net "SMB_PEX0_R_SDA")
		)
		(pad "2" smd circle
			(at 0.40005 0 270)
			(size 0 0)
			(layers "F.Cu" "F.Mask" "F.Paste")
			(net "SMB_PEX0_SDA")
		)
	)
	(footprint ""
		(layer "F.Cu")
		(at 27.126184 -37.929566 90)
		(property "Reference" "R5543"
			(at 0 0 90)
			(layer "F.SilkS")
			(hide yes)
			(effects
				(font
					(size 1.27 1.27)
				)
			)
		)
		(property "Value" ""
			(at 0 0 90)
			(layer "F.Fab")
			(effects
				(font
					(size 1.27 1.27)
				)
			)
		)
		(duplicate_pad_numbers_are_jumpers no)
		(fp_line
			(start 0.7874 -0.4064)
			(end 0.7874 0.4064)
			(stroke
				(width 0.1524)
				(type default)
			)
			(layer "F.SilkS")
		)
		(fp_line
			(start -0.7874 -0.4064)
			(end 0.7874 -0.4064)
			(stroke
				(width 0.1524)
				(type default)
			)
			(layer "F.SilkS")
		)
		(fp_line
			(start 0.7874 0.4064)
			(end -0.7874 0.4064)
			(stroke
				(width 0.1524)
				(type default)
			)
			(layer "F.SilkS")
		)
		(fp_line
			(start -0.7874 0.4064)
			(end -0.7874 -0.4064)
			(stroke
				(width 0.1524)
				(type default)
			)
			(layer "F.SilkS")
		)
		(fp_line
			(start -0.12065 -0.305054)
			(end -0.12065 -0.2794)
			(stroke
				(width 0.1)
				(type default)
			)
			(layer "F.Fab")
		)
		(fp_line
			(start -0.67945 -0.305054)
			(end -0.12065 -0.305054)
			(stroke
				(width 0.1)
				(type default)
			)
			(layer "F.Fab")
		)
		(fp_line
			(start 0.67945 -0.3048)
			(end 0.67945 0.3048)
			(stroke
				(width 0.1)
				(type default)
			)
			(layer "F.Fab")
		)
		(fp_line
			(start 0.12065 -0.3048)
			(end 0.67945 -0.3048)
			(stroke
				(width 0.1)
				(type default)
			)
			(layer "F.Fab")
		)
		(fp_line
			(start 0.12065 -0.2794)
			(end 0.12065 -0.3048)
			(stroke
				(width 0.1)
				(type default)
			)
			(layer "F.Fab")
		)
		(fp_line
			(start -0.12065 -0.2794)
			(end 0.12065 -0.2794)
			(stroke
				(width 0.1)
				(type default)
			)
			(layer "F.Fab")
		)
		(fp_line
			(start 0.120396 0.2794)
			(end -0.12065 0.2794)
			(stroke
				(width 0.1)
				(type default)
			)
			(layer "F.Fab")
		)
		(fp_line
			(start -0.12065 0.2794)
			(end -0.12065 0.3048)
			(stroke
				(width 0.1)
				(type default)
			)
			(layer "F.Fab")
		)
		(fp_line
			(start 0.67945 0.3048)
			(end 0.120396 0.3048)
			(stroke
				(width 0.1)
				(type default)
			)
			(layer "F.Fab")
		)
		(fp_line
			(start 0.120396 0.3048)
			(end 0.120396 0.2794)
			(stroke
				(width 0.1)
				(type default)
			)
			(layer "F.Fab")
		)
		(fp_line
			(start -0.12065 0.3048)
			(end -0.67945 0.3048)
			(stroke
				(width 0.1)
				(type default)
			)
			(layer "F.Fab")
		)
		(fp_line
			(start -0.67945 0.3048)
			(end -0.67945 -0.305054)
			(stroke
				(width 0.1)
				(type default)
			)
			(layer "F.Fab")
		)
		(pad "1" smd circle
			(at -0.40005 0 90)
			(size 0 0)
			(layers "F.Cu" "F.Mask" "F.Paste")
			(net "SSD1_AUX_P3V3_EN_R")
		)
		(pad "2" smd circle
			(at 0.40005 0 90)
			(size 0 0)
			(layers "F.Cu" "F.Mask" "F.Paste")
			(net "SSD1_AUX_P3V3_EN")
		)
	)
	(footprint ""
		(layer "F.Cu")
		(at 7.103364 -59.571636 90)
		(property "Reference" "PR257"
			(at 0 0 90)
			(layer "F.SilkS")
			(hide yes)
			(effects
				(font
					(size 1.27 1.27)
				)
			)
		)
		(property "Value" ""
			(at 0 0 90)
			(layer "F.Fab")
			(effects
				(font
					(size 1.27 1.27)
				)
			)
		)
		(duplicate_pad_numbers_are_jumpers no)
		(fp_line
			(start 0.7874 -0.4064)
			(end 0.7874 0.4064)
			(stroke
				(width 0.1524)
				(type default)
			)
			(layer "F.SilkS")
		)
		(fp_line
			(start -0.7874 -0.4064)
			(end 0.7874 -0.4064)
			(stroke
				(width 0.1524)
				(type default)
			)
			(layer "F.SilkS")
		)
		(fp_line
			(start 0.7874 0.4064)
			(end -0.7874 0.4064)
			(stroke
				(width 0.1524)
				(type default)
			)
			(layer "F.SilkS")
		)
		(fp_line
			(start -0.7874 0.4064)
			(end -0.7874 -0.4064)
			(stroke
				(width 0.1524)
				(type default)
			)
			(layer "F.SilkS")
		)
		(fp_line
			(start -0.12065 -0.305054)
			(end -0.12065 -0.2794)
			(stroke
				(width 0.1)
				(type default)
			)
			(layer "F.Fab")
		)
		(fp_line
			(start -0.67945 -0.305054)
			(end -0.12065 -0.305054)
			(stroke
				(width 0.1)
				(type default)
			)
			(layer "F.Fab")
		)
		(fp_line
			(start 0.67945 -0.3048)
			(end 0.67945 0.3048)
			(stroke
				(width 0.1)
				(type default)
			)
			(layer "F.Fab")
		)
		(fp_line
			(start 0.12065 -0.3048)
			(end 0.67945 -0.3048)
			(stroke
				(width 0.1)
				(type default)
			)
			(layer "F.Fab")
		)
		(fp_line
			(start 0.12065 -0.2794)
			(end 0.12065 -0.3048)
			(stroke
				(width 0.1)
				(type default)
			)
			(layer "F.Fab")
		)
		(fp_line
			(start -0.12065 -0.2794)
			(end 0.12065 -0.2794)
			(stroke
				(width 0.1)
				(type default)
			)
			(layer "F.Fab")
		)
		(fp_line
			(start 0.120396 0.2794)
			(end -0.12065 0.2794)
			(stroke
				(width 0.1)
				(type default)
			)
			(layer "F.Fab")
		)
		(fp_line
			(start -0.12065 0.2794)
			(end -0.12065 0.3048)
			(stroke
				(width 0.1)
				(type default)
			)
			(layer "F.Fab")
		)
		(fp_line
			(start 0.67945 0.3048)
			(end 0.120396 0.3048)
			(stroke
				(width 0.1)
				(type default)
			)
			(layer "F.Fab")
		)
		(fp_line
			(start 0.120396 0.3048)
			(end 0.120396 0.2794)
			(stroke
				(width 0.1)
				(type default)
			)
			(layer "F.Fab")
		)
		(fp_line
			(start -0.12065 0.3048)
			(end -0.67945 0.3048)
			(stroke
				(width 0.1)
				(type default)
			)
			(layer "F.Fab")
		)
		(fp_line
			(start -0.67945 0.3048)
			(end -0.67945 -0.305054)
			(stroke
				(width 0.1)
				(type default)
			)
			(layer "F.Fab")
		)
		(pad "1" smd circle
			(at -0.40005 0 90)
			(size 0 0)
			(layers "F.Cu" "F.Mask" "F.Paste")
			(net "P3V3_SSD0_OCP")
		)
		(pad "2" smd circle
			(at 0.40005 0 90)
			(size 0 0)
			(layers "F.Cu" "F.Mask" "F.Paste")
			(net "GND")
		)
	)
	(footprint ""
		(layer "F.Cu")
		(at 454.125838 -314.192158 180)
		(property "Reference" "PC269"
			(at 0 0 180)
			(layer "F.SilkS")
			(hide yes)
			(effects
				(font
					(size 1.27 1.27)
				)
			)
		)
		(property "Value" ""
			(at 0 0 180)
			(layer "F.Fab")
			(effects
				(font
					(size 1.27 1.27)
				)
			)
		)
		(duplicate_pad_numbers_are_jumpers no)
		(fp_line
			(start 1.524 0.762)
			(end -1.524 0.762)
			(stroke
				(width 0.1524)
				(type default)
			)
			(layer "F.SilkS")
		)
		(fp_line
			(start 1.524 -0.762)
			(end 1.524 0.762)
			(stroke
				(width 0.1524)
				(type default)
			)
			(layer "F.SilkS")
		)
		(fp_line
			(start -1.524 0.762)
			(end -1.524 -0.762)
			(stroke
				(width 0.1524)
				(type default)
			)
			(layer "F.SilkS")
		)
		(fp_line
			(start -1.524 -0.762)
			(end 1.524 -0.762)
			(stroke
				(width 0.1524)
				(type default)
			)
			(layer "F.SilkS")
		)
		(fp_line
			(start 1.1049 0.724916)
			(end 1.1049 -0.724916)
			(stroke
				(width 0.1)
				(type default)
			)
			(layer "F.Fab")
		)
		(fp_line
			(start 1.1049 -0.724916)
			(end -1.1049 -0.724916)
			(stroke
				(width 0.1)
				(type default)
			)
			(layer "F.Fab")
		)
		(fp_line
			(start -1.1049 0.724916)
			(end 1.1049 0.724916)
			(stroke
				(width 0.1)
				(type default)
			)
			(layer "F.Fab")
		)
		(fp_line
			(start -1.1049 -0.724916)
			(end -1.1049 0.724916)
			(stroke
				(width 0.1)
				(type default)
			)
			(layer "F.Fab")
		)
		(pad "1" smd rect
			(at -0.889 0)
			(size 1.016 1.27)
			(layers "F.Cu" "F.Mask" "F.Paste")
			(net "SW_P12V_P1V25_PEX3_FLT")
		)
		(pad "2" smd rect
			(at 0.889 0)
			(size 1.016 1.27)
			(layers "F.Cu" "F.Mask" "F.Paste")
			(net "GND")
		)
	)
	(footprint ""
		(layer "F.Cu")
		(at 227.31476 -316.176914)
		(property "Reference" "PC227"
			(at 0 0 0)
			(layer "F.SilkS")
			(hide yes)
			(effects
				(font
					(size 1.27 1.27)
				)
			)
		)
		(property "Value" ""
			(at 0 0 0)
			(layer "F.Fab")
			(effects
				(font
					(size 1.27 1.27)
				)
			)
		)
		(duplicate_pad_numbers_are_jumpers no)
		(fp_line
			(start -1.524 -0.762)
			(end 1.524 -0.762)
			(stroke
				(width 0.1524)
				(type default)
			)
			(layer "F.SilkS")
		)
		(fp_line
			(start -1.524 0.762)
			(end -1.524 -0.762)
			(stroke
				(width 0.1524)
				(type default)
			)
			(layer "F.SilkS")
		)
		(fp_line
			(start 1.524 -0.762)
			(end 1.524 0.762)
			(stroke
				(width 0.1524)
				(type default)
			)
			(layer "F.SilkS")
		)
		(fp_line
			(start 1.524 0.762)
			(end -1.524 0.762)
			(stroke
				(width 0.1524)
				(type default)
			)
			(layer "F.SilkS")
		)
		(fp_line
			(start -1.1049 -0.724916)
			(end -1.1049 0.724916)
			(stroke
				(width 0.1)
				(type default)
			)
			(layer "F.Fab")
		)
		(fp_line
			(start -1.1049 0.724916)
			(end 1.1049 0.724916)
			(stroke
				(width 0.1)
				(type default)
			)
			(layer "F.Fab")
		)
		(fp_line
			(start 1.1049 -0.724916)
			(end -1.1049 -0.724916)
			(stroke
				(width 0.1)
				(type default)
			)
			(layer "F.Fab")
		)
		(fp_line
			(start 1.1049 0.724916)
			(end 1.1049 -0.724916)
			(stroke
				(width 0.1)
				(type default)
			)
			(layer "F.Fab")
		)
		(pad "1" smd rect
			(at -0.889 0 180)
			(size 1.016 1.27)
			(layers "F.Cu" "F.Mask" "F.Paste")
			(net "SW_P12V_P1V25_PEX1_FLT")
		)
		(pad "2" smd rect
			(at 0.889 0 180)
			(size 1.016 1.27)
			(layers "F.Cu" "F.Mask" "F.Paste")
			(net "GND")
		)
	)
	(footprint ""
		(layer "F.Cu")
		(at 211.051902 -235.756958 90)
		(property "Reference" "R6358"
			(at 0 0 90)
			(layer "F.SilkS")
			(hide yes)
			(effects
				(font
					(size 1.27 1.27)
				)
			)
		)
		(property "Value" ""
			(at 0 0 90)
			(layer "F.Fab")
			(effects
				(font
					(size 1.27 1.27)
				)
			)
		)
		(duplicate_pad_numbers_are_jumpers no)
		(fp_line
			(start 0.7874 -0.4064)
			(end 0.7874 0.4064)
			(stroke
				(width 0.1524)
				(type default)
			)
			(layer "F.SilkS")
		)
		(fp_line
			(start -0.7874 -0.4064)
			(end 0.7874 -0.4064)
			(stroke
				(width 0.1524)
				(type default)
			)
			(layer "F.SilkS")
		)
		(fp_line
			(start 0.7874 0.4064)
			(end -0.7874 0.4064)
			(stroke
				(width 0.1524)
				(type default)
			)
			(layer "F.SilkS")
		)
		(fp_line
			(start -0.7874 0.4064)
			(end -0.7874 -0.4064)
			(stroke
				(width 0.1524)
				(type default)
			)
			(layer "F.SilkS")
		)
		(fp_line
			(start -0.12065 -0.305054)
			(end -0.12065 -0.2794)
			(stroke
				(width 0.1)
				(type default)
			)
			(layer "F.Fab")
		)
		(fp_line
			(start -0.67945 -0.305054)
			(end -0.12065 -0.305054)
			(stroke
				(width 0.1)
				(type default)
			)
			(layer "F.Fab")
		)
		(fp_line
			(start 0.67945 -0.3048)
			(end 0.67945 0.3048)
			(stroke
				(width 0.1)
				(type default)
			)
			(layer "F.Fab")
		)
		(fp_line
			(start 0.12065 -0.3048)
			(end 0.67945 -0.3048)
			(stroke
				(width 0.1)
				(type default)
			)
			(layer "F.Fab")
		)
		(fp_line
			(start 0.12065 -0.2794)
			(end 0.12065 -0.3048)
			(stroke
				(width 0.1)
				(type default)
			)
			(layer "F.Fab")
		)
		(fp_line
			(start -0.12065 -0.2794)
			(end 0.12065 -0.2794)
			(stroke
				(width 0.1)
				(type default)
			)
			(layer "F.Fab")
		)
		(fp_line
			(start 0.120396 0.2794)
			(end -0.12065 0.2794)
			(stroke
				(width 0.1)
				(type default)
			)
			(layer "F.Fab")
		)
		(fp_line
			(start -0.12065 0.2794)
			(end -0.12065 0.3048)
			(stroke
				(width 0.1)
				(type default)
			)
			(layer "F.Fab")
		)
		(fp_line
			(start 0.67945 0.3048)
			(end 0.120396 0.3048)
			(stroke
				(width 0.1)
				(type default)
			)
			(layer "F.Fab")
		)
		(fp_line
			(start 0.120396 0.3048)
			(end 0.120396 0.2794)
			(stroke
				(width 0.1)
				(type default)
			)
			(layer "F.Fab")
		)
		(fp_line
			(start -0.12065 0.3048)
			(end -0.67945 0.3048)
			(stroke
				(width 0.1)
				(type default)
			)
			(layer "F.Fab")
		)
		(fp_line
			(start -0.67945 0.3048)
			(end -0.67945 -0.305054)
			(stroke
				(width 0.1)
				(type default)
			)
			(layer "F.Fab")
		)
		(pad "1" smd circle
			(at -0.40005 0 90)
			(size 0 0)
			(layers "F.Cu" "F.Mask" "F.Paste")
			(net "SMB_PEX_LS_R_SCL")
		)
		(pad "2" smd circle
			(at 0.40005 0 90)
			(size 0 0)
			(layers "F.Cu" "F.Mask" "F.Paste")
			(net "SMB_PEX_LS_SCL")
		)
	)
	(footprint ""
		(layer "F.Cu")
		(at 260.695186 -35.48253)
		(property "Reference" "U390"
			(at -2.528316 0.78613 90)
			(unlocked yes)
			(layer "F.SilkS")
			(effects
				(font
					(size 0.7874 0.5842)
					(thickness 0.1524)
				)
				(justify left)
			)
		)
		(property "Value" ""
			(at 0 0 0)
			(layer "F.Fab")
			(effects
				(font
					(size 1.27 1.27)
				)
			)
		)
		(duplicate_pad_numbers_are_jumpers no)
		(fp_line
			(start -1.3462 -1.1938)
			(end -1.3462 1.1684)
			(stroke
				(width 0.1524)
				(type default)
			)
			(layer "F.SilkS")
		)
		(fp_line
			(start -1.3462 1.1938)
			(end 1.3462 1.1938)
			(stroke
				(width 0.1524)
				(type default)
			)
			(layer "F.SilkS")
		)
		(fp_line
			(start 1.3462 -1.1938)
			(end -1.3462 -1.1938)
			(stroke
				(width 0.1524)
				(type default)
			)
			(layer "F.SilkS")
		)
		(fp_line
			(start 1.3462 1.1938)
			(end 1.3462 -1.1938)
			(stroke
				(width 0.1524)
				(type default)
			)
			(layer "F.SilkS")
		)
		(fp_poly
			(pts
				(xy -1.447038 -0.760476) (xy -2.052066 -0.457962) (xy -2.052066 -1.06299)
			)
			(stroke
				(width 0)
				(type default)
			)
			(fill yes)
			(layer "F.SilkS")
		)
		(fp_line
			(start -0.674878 -1.124966)
			(end -0.674878 1.124966)
			(stroke
				(width 0.1)
				(type default)
			)
			(layer "F.Fab")
		)
		(fp_line
			(start -0.674878 1.124966)
			(end 0.674878 1.124966)
			(stroke
				(width 0.1)
				(type default)
			)
			(layer "F.Fab")
		)
		(fp_line
			(start 0.674878 -1.124966)
			(end -0.674878 -1.124966)
			(stroke
				(width 0.1)
				(type default)
			)
			(layer "F.Fab")
		)
		(fp_line
			(start 0.674878 1.124966)
			(end 0.674878 -1.124966)
			(stroke
				(width 0.1)
				(type default)
			)
			(layer "F.Fab")
		)
		(fp_poly
			(pts
				(xy -1.447038 -0.760476) (xy -2.052066 -0.457962) (xy -2.052066 -1.06299)
			)
			(stroke
				(width 0)
				(type default)
			)
			(fill yes)
			(layer "F.Fab")
		)
		(pad "1" smd rect
			(at -0.899922 -0.750062)
			(size 0.6096 0.6096)
			(layers "F.Cu" "F.Mask" "F.Paste")
			(net "PWRGD_P3V3_SSD9_R")
		)
		(pad "2" smd rect
			(at -0.899922 0 90)
			(size 0.4064 0.6096)
			(layers "F.Cu" "F.Mask" "F.Paste")
			(net "RST_SMB_SSD9_N")
		)
		(pad "3" smd rect
			(at -0.899922 0.750062)
			(size 0.6096 0.6096)
			(layers "F.Cu" "F.Mask" "F.Paste")
			(net "GND")
		)
		(pad "4" smd rect
			(at 0.899922 0.750062)
			(size 0.6096 0.6096)
			(layers "F.Cu" "F.Mask" "F.Paste")
			(net "RST_SMB_SSD9_ISO_N")
		)
		(pad "5" smd rect
			(at 0.899922 -0.750062)
			(size 0.6096 0.6096)
			(layers "F.Cu" "F.Mask" "F.Paste")
			(net "P3V3_AUX")
		)
	)
	(footprint ""
		(layer "F.Cu")
		(at 386.90804 -156.3624 180)
		(property "Reference" "R319"
			(at 0 0 180)
			(layer "F.SilkS")
			(hide yes)
			(effects
				(font
					(size 1.27 1.27)
				)
			)
		)
		(property "Value" ""
			(at 0 0 180)
			(layer "F.Fab")
			(effects
				(font
					(size 1.27 1.27)
				)
			)
		)
		(duplicate_pad_numbers_are_jumpers no)
		(fp_line
			(start 0.7874 0.4064)
			(end -0.7874 0.4064)
			(stroke
				(width 0.1524)
				(type default)
			)
			(layer "F.SilkS")
		)
		(fp_line
			(start 0.7874 -0.4064)
			(end 0.7874 0.4064)
			(stroke
				(width 0.1524)
				(type default)
			)
			(layer "F.SilkS")
		)
		(fp_line
			(start -0.7874 0.4064)
			(end -0.7874 -0.4064)
			(stroke
				(width 0.1524)
				(type default)
			)
			(layer "F.SilkS")
		)
		(fp_line
			(start -0.7874 -0.4064)
			(end 0.7874 -0.4064)
			(stroke
				(width 0.1524)
				(type default)
			)
			(layer "F.SilkS")
		)
		(fp_line
			(start 0.67945 0.3048)
			(end 0.120396 0.3048)
			(stroke
				(width 0.1)
				(type default)
			)
			(layer "F.Fab")
		)
		(fp_line
			(start 0.67945 -0.3048)
			(end 0.67945 0.3048)
			(stroke
				(width 0.1)
				(type default)
			)
			(layer "F.Fab")
		)
		(fp_line
			(start 0.12065 -0.2794)
			(end 0.12065 -0.3048)
			(stroke
				(width 0.1)
				(type default)
			)
			(layer "F.Fab")
		)
		(fp_line
			(start 0.12065 -0.3048)
			(end 0.67945 -0.3048)
			(stroke
				(width 0.1)
				(type default)
			)
			(layer "F.Fab")
		)
		(fp_line
			(start 0.120396 0.3048)
			(end 0.120396 0.2794)
			(stroke
				(width 0.1)
				(type default)
			)
			(layer "F.Fab")
		)
		(fp_line
			(start 0.120396 0.2794)
			(end -0.12065 0.2794)
			(stroke
				(width 0.1)
				(type default)
			)
			(layer "F.Fab")
		)
		(fp_line
			(start -0.12065 0.3048)
			(end -0.67945 0.3048)
			(stroke
				(width 0.1)
				(type default)
			)
			(layer "F.Fab")
		)
		(fp_line
			(start -0.12065 0.2794)
			(end -0.12065 0.3048)
			(stroke
				(width 0.1)
				(type default)
			)
			(layer "F.Fab")
		)
		(fp_line
			(start -0.12065 -0.2794)
			(end 0.12065 -0.2794)
			(stroke
				(width 0.1)
				(type default)
			)
			(layer "F.Fab")
		)
		(fp_line
			(start -0.12065 -0.305054)
			(end -0.12065 -0.2794)
			(stroke
				(width 0.1)
				(type default)
			)
			(layer "F.Fab")
		)
		(fp_line
			(start -0.67945 0.3048)
			(end -0.67945 -0.305054)
			(stroke
				(width 0.1)
				(type default)
			)
			(layer "F.Fab")
		)
		(fp_line
			(start -0.67945 -0.305054)
			(end -0.12065 -0.305054)
			(stroke
				(width 0.1)
				(type default)
			)
			(layer "F.Fab")
		)
		(pad "1" smd circle
			(at -0.40005 0 180)
			(size 0 0)
			(layers "F.Cu" "F.Mask" "F.Paste")
			(net "NIC6_DATA_OUT")
		)
		(pad "2" smd circle
			(at 0.40005 0 180)
			(size 0 0)
			(layers "F.Cu" "F.Mask" "F.Paste")
			(net "GND")
		)
	)
	(footprint ""
		(layer "F.Cu")
		(at 319.937892 -291.102034 180)
		(property "Reference" "R6395"
			(at 0 0 180)
			(layer "F.SilkS")
			(hide yes)
			(effects
				(font
					(size 1.27 1.27)
				)
			)
		)
		(property "Value" ""
			(at 0 0 180)
			(layer "F.Fab")
			(effects
				(font
					(size 1.27 1.27)
				)
			)
		)
		(duplicate_pad_numbers_are_jumpers no)
		(fp_line
			(start 0.7874 0.4064)
			(end -0.7874 0.4064)
			(stroke
				(width 0.1524)
				(type default)
			)
			(layer "F.SilkS")
		)
		(fp_line
			(start 0.7874 -0.4064)
			(end 0.7874 0.4064)
			(stroke
				(width 0.1524)
				(type default)
			)
			(layer "F.SilkS")
		)
		(fp_line
			(start -0.7874 0.4064)
			(end -0.7874 -0.4064)
			(stroke
				(width 0.1524)
				(type default)
			)
			(layer "F.SilkS")
		)
		(fp_line
			(start -0.7874 -0.4064)
			(end 0.7874 -0.4064)
			(stroke
				(width 0.1524)
				(type default)
			)
			(layer "F.SilkS")
		)
		(fp_line
			(start 0.67945 0.3048)
			(end 0.120396 0.3048)
			(stroke
				(width 0.1)
				(type default)
			)
			(layer "F.Fab")
		)
		(fp_line
			(start 0.67945 -0.3048)
			(end 0.67945 0.3048)
			(stroke
				(width 0.1)
				(type default)
			)
			(layer "F.Fab")
		)
		(fp_line
			(start 0.12065 -0.2794)
			(end 0.12065 -0.3048)
			(stroke
				(width 0.1)
				(type default)
			)
			(layer "F.Fab")
		)
		(fp_line
			(start 0.12065 -0.3048)
			(end 0.67945 -0.3048)
			(stroke
				(width 0.1)
				(type default)
			)
			(layer "F.Fab")
		)
		(fp_line
			(start 0.120396 0.3048)
			(end 0.120396 0.2794)
			(stroke
				(width 0.1)
				(type default)
			)
			(layer "F.Fab")
		)
		(fp_line
			(start 0.120396 0.2794)
			(end -0.12065 0.2794)
			(stroke
				(width 0.1)
				(type default)
			)
			(layer "F.Fab")
		)
		(fp_line
			(start -0.12065 0.3048)
			(end -0.67945 0.3048)
			(stroke
				(width 0.1)
				(type default)
			)
			(layer "F.Fab")
		)
		(fp_line
			(start -0.12065 0.2794)
			(end -0.12065 0.3048)
			(stroke
				(width 0.1)
				(type default)
			)
			(layer "F.Fab")
		)
		(fp_line
			(start -0.12065 -0.2794)
			(end 0.12065 -0.2794)
			(stroke
				(width 0.1)
				(type default)
			)
			(layer "F.Fab")
		)
		(fp_line
			(start -0.12065 -0.305054)
			(end -0.12065 -0.2794)
			(stroke
				(width 0.1)
				(type default)
			)
			(layer "F.Fab")
		)
		(fp_line
			(start -0.67945 0.3048)
			(end -0.67945 -0.305054)
			(stroke
				(width 0.1)
				(type default)
			)
			(layer "F.Fab")
		)
		(fp_line
			(start -0.67945 -0.305054)
			(end -0.12065 -0.305054)
			(stroke
				(width 0.1)
				(type default)
			)
			(layer "F.Fab")
		)
		(pad "1" smd circle
			(at -0.40005 0 180)
			(size 0 0)
			(layers "F.Cu" "F.Mask" "F.Paste")
			(net "GND")
		)
		(pad "2" smd circle
			(at 0.40005 0 180)
			(size 0 0)
			(layers "F.Cu" "F.Mask" "F.Paste")
			(net "RST_PEX2_PERST_R_N")
		)
	)
	(footprint ""
		(layer "F.Cu")
		(at 265.335512 -308.13375 -135)
		(property "Reference" "R1332"
			(at 0 0 225)
			(layer "F.SilkS")
			(hide yes)
			(effects
				(font
					(size 1.27 1.27)
				)
			)
		)
		(property "Value" ""
			(at 0 0 225)
			(layer "F.Fab")
			(effects
				(font
					(size 1.27 1.27)
				)
			)
		)
		(duplicate_pad_numbers_are_jumpers no)
		(fp_line
			(start 0.787389 0.406267)
			(end -0.787389 0.406267)
			(stroke
				(width 0.1524)
				(type default)
			)
			(layer "F.SilkS")
		)
		(fp_line
			(start 0.787389 -0.406267)
			(end 0.787389 0.406267)
			(stroke
				(width 0.1524)
				(type default)
			)
			(layer "F.SilkS")
		)
		(fp_line
			(start -0.787389 0.406267)
			(end -0.787389 -0.406267)
			(stroke
				(width 0.1524)
				(type default)
			)
			(layer "F.SilkS")
		)
		(fp_line
			(start -0.787389 -0.406267)
			(end 0.787389 -0.406267)
			(stroke
				(width 0.1524)
				(type default)
			)
			(layer "F.SilkS")
		)
		(fp_line
			(start 0.679446 0.30479)
			(end 0.120515 0.30479)
			(stroke
				(width 0.1)
				(type default)
			)
			(layer "F.Fab")
		)
		(fp_line
			(start 0.120515 0.30479)
			(end 0.120335 0.279466)
			(stroke
				(width 0.1)
				(type default)
			)
			(layer "F.Fab")
		)
		(fp_line
			(start 0.120335 0.279466)
			(end -0.120695 0.279466)
			(stroke
				(width 0.1)
				(type default)
			)
			(layer "F.Fab")
		)
		(fp_line
			(start 0.679446 -0.30479)
			(end 0.679446 0.30479)
			(stroke
				(width 0.1)
				(type default)
			)
			(layer "F.Fab")
		)
		(fp_line
			(start -0.120515 0.30479)
			(end -0.679446 0.30479)
			(stroke
				(width 0.1)
				(type default)
			)
			(layer "F.Fab")
		)
		(fp_line
			(start -0.120695 0.279466)
			(end -0.120515 0.30479)
			(stroke
				(width 0.1)
				(type default)
			)
			(layer "F.Fab")
		)
		(fp_line
			(start 0.120695 -0.279466)
			(end 0.120515 -0.30479)
			(stroke
				(width 0.1)
				(type default)
			)
			(layer "F.Fab")
		)
		(fp_line
			(start 0.120515 -0.30479)
			(end 0.679446 -0.30479)
			(stroke
				(width 0.1)
				(type default)
			)
			(layer "F.Fab")
		)
		(fp_line
			(start -0.679446 0.30479)
			(end -0.679446 -0.305149)
			(stroke
				(width 0.1)
				(type default)
			)
			(layer "F.Fab")
		)
		(fp_line
			(start -0.120695 -0.279466)
			(end 0.120695 -0.279466)
			(stroke
				(width 0.1)
				(type default)
			)
			(layer "F.Fab")
		)
		(fp_line
			(start -0.120695 -0.304969)
			(end -0.120695 -0.279466)
			(stroke
				(width 0.1)
				(type default)
			)
			(layer "F.Fab")
		)
		(fp_line
			(start -0.679446 -0.305149)
			(end -0.120695 -0.304969)
			(stroke
				(width 0.1)
				(type default)
			)
			(layer "F.Fab")
		)
		(pad "1" smd circle
			(at -0.40005 0 225)
			(size 0 0)
			(layers "F.Cu" "F.Mask" "F.Paste")
			(net "PEX2_DBG_MODE1")
		)
		(pad "2" smd circle
			(at 0.40005 0 225)
			(size 0 0)
			(layers "F.Cu" "F.Mask" "F.Paste")
			(net "P1V8_PEX")
		)
	)
	(footprint ""
		(layer "F.Cu")
		(at 377.3805 -350.098614 90)
		(property "Reference" "C784"
			(at 0 0 90)
			(layer "F.SilkS")
			(hide yes)
			(effects
				(font
					(size 1.27 1.27)
				)
			)
		)
		(property "Value" ""
			(at 0 0 90)
			(layer "F.Fab")
			(effects
				(font
					(size 1.27 1.27)
				)
			)
		)
		(duplicate_pad_numbers_are_jumpers no)
		(fp_line
			(start 0.299974 -0.150114)
			(end 0.299974 0.150114)
			(stroke
				(width 0.1)
				(type default)
			)
			(layer "F.Fab")
		)
		(fp_line
			(start -0.299974 -0.150114)
			(end 0.299974 -0.150114)
			(stroke
				(width 0.1)
				(type default)
			)
			(layer "F.Fab")
		)
		(fp_line
			(start 0.299974 0.150114)
			(end -0.299974 0.150114)
			(stroke
				(width 0.1)
				(type default)
			)
			(layer "F.Fab")
		)
		(fp_line
			(start -0.299974 0.150114)
			(end -0.299974 -0.150114)
			(stroke
				(width 0.1)
				(type default)
			)
			(layer "F.Fab")
		)
		(pad "1" smd rect
			(at -0.2667 0 90)
			(size 0.3048 0.381)
			(layers "F.Cu" "F.Mask" "F.Paste")
			(net "P5E_PEX3_STN6_TX_DP<100>")
		)
		(pad "2" smd rect
			(at 0.2667 0 90)
			(size 0.3048 0.381)
			(layers "F.Cu" "F.Mask" "F.Paste")
			(net "P5E_PEX3_STN6_TX_C_DP<100>")
		)
	)
	(footprint ""
		(layer "F.Cu")
		(at 203.92009 -289.230816 -90)
		(property "Reference" "R3934"
			(at 0 0 270)
			(layer "F.SilkS")
			(hide yes)
			(effects
				(font
					(size 1.27 1.27)
				)
			)
		)
		(property "Value" ""
			(at 0 0 270)
			(layer "F.Fab")
			(effects
				(font
					(size 1.27 1.27)
				)
			)
		)
		(duplicate_pad_numbers_are_jumpers no)
		(fp_line
			(start -0.7874 0.4064)
			(end -0.7874 -0.4064)
			(stroke
				(width 0.1524)
				(type default)
			)
			(layer "F.SilkS")
		)
		(fp_line
			(start 0.7874 0.4064)
			(end -0.7874 0.4064)
			(stroke
				(width 0.1524)
				(type default)
			)
			(layer "F.SilkS")
		)
		(fp_line
			(start -0.7874 -0.4064)
			(end 0.7874 -0.4064)
			(stroke
				(width 0.1524)
				(type default)
			)
			(layer "F.SilkS")
		)
		(fp_line
			(start 0.7874 -0.4064)
			(end 0.7874 0.4064)
			(stroke
				(width 0.1524)
				(type default)
			)
			(layer "F.SilkS")
		)
		(fp_line
			(start -0.67945 0.3048)
			(end -0.67945 -0.305054)
			(stroke
				(width 0.1)
				(type default)
			)
			(layer "F.Fab")
		)
		(fp_line
			(start -0.12065 0.3048)
			(end -0.67945 0.3048)
			(stroke
				(width 0.1)
				(type default)
			)
			(layer "F.Fab")
		)
		(fp_line
			(start 0.120396 0.3048)
			(end 0.120396 0.2794)
			(stroke
				(width 0.1)
				(type default)
			)
			(layer "F.Fab")
		)
		(fp_line
			(start 0.67945 0.3048)
			(end 0.120396 0.3048)
			(stroke
				(width 0.1)
				(type default)
			)
			(layer "F.Fab")
		)
		(fp_line
			(start -0.12065 0.2794)
			(end -0.12065 0.3048)
			(stroke
				(width 0.1)
				(type default)
			)
			(layer "F.Fab")
		)
		(fp_line
			(start 0.120396 0.2794)
			(end -0.12065 0.2794)
			(stroke
				(width 0.1)
				(type default)
			)
			(layer "F.Fab")
		)
		(fp_line
			(start -0.12065 -0.2794)
			(end 0.12065 -0.2794)
			(stroke
				(width 0.1)
				(type default)
			)
			(layer "F.Fab")
		)
		(fp_line
			(start 0.12065 -0.2794)
			(end 0.12065 -0.3048)
			(stroke
				(width 0.1)
				(type default)
			)
			(layer "F.Fab")
		)
		(fp_line
			(start 0.12065 -0.3048)
			(end 0.67945 -0.3048)
			(stroke
				(width 0.1)
				(type default)
			)
			(layer "F.Fab")
		)
		(fp_line
			(start 0.67945 -0.3048)
			(end 0.67945 0.3048)
			(stroke
				(width 0.1)
				(type default)
			)
			(layer "F.Fab")
		)
		(fp_line
			(start -0.67945 -0.305054)
			(end -0.12065 -0.305054)
			(stroke
				(width 0.1)
				(type default)
			)
			(layer "F.Fab")
		)
		(fp_line
			(start -0.12065 -0.305054)
			(end -0.12065 -0.2794)
			(stroke
				(width 0.1)
				(type default)
			)
			(layer "F.Fab")
		)
		(pad "1" smd circle
			(at -0.40005 0 270)
			(size 0 0)
			(layers "F.Cu" "F.Mask" "F.Paste")
			(net "SMB_PEX1_HOST_LS_SDA")
		)
		(pad "2" smd circle
			(at 0.40005 0 270)
			(size 0 0)
			(layers "F.Cu" "F.Mask" "F.Paste")
			(net "P3V3_AUX")
		)
	)
	(footprint ""
		(layer "F.Cu")
		(at 344.511884 -113.563654)
		(property "Reference" "PC816"
			(at 0 0 0)
			(layer "F.SilkS")
			(hide yes)
			(effects
				(font
					(size 1.27 1.27)
				)
			)
		)
		(property "Value" ""
			(at 0 0 0)
			(layer "F.Fab")
			(effects
				(font
					(size 1.27 1.27)
				)
			)
		)
		(duplicate_pad_numbers_are_jumpers no)
		(fp_line
			(start -0.7874 -0.4064)
			(end 0.7874 -0.4064)
			(stroke
				(width 0.1524)
				(type default)
			)
			(layer "F.SilkS")
		)
		(fp_line
			(start -0.7874 0.4064)
			(end -0.7874 -0.4064)
			(stroke
				(width 0.1524)
				(type default)
			)
			(layer "F.SilkS")
		)
		(fp_line
			(start 0.7874 -0.4064)
			(end 0.7874 0.4064)
			(stroke
				(width 0.1524)
				(type default)
			)
			(layer "F.SilkS")
		)
		(fp_line
			(start 0.7874 0.4064)
			(end -0.7874 0.4064)
			(stroke
				(width 0.1524)
				(type default)
			)
			(layer "F.SilkS")
		)
		(fp_line
			(start -0.67945 -0.305054)
			(end -0.12065 -0.305054)
			(stroke
				(width 0.1)
				(type default)
			)
			(layer "F.Fab")
		)
		(fp_line
			(start -0.67945 0.3048)
			(end -0.67945 -0.305054)
			(stroke
				(width 0.1)
				(type default)
			)
			(layer "F.Fab")
		)
		(fp_line
			(start -0.12065 -0.305054)
			(end -0.12065 -0.2794)
			(stroke
				(width 0.1)
				(type default)
			)
			(layer "F.Fab")
		)
		(fp_line
			(start -0.12065 -0.2794)
			(end 0.12065 -0.2794)
			(stroke
				(width 0.1)
				(type default)
			)
			(layer "F.Fab")
		)
		(fp_line
			(start -0.12065 0.2794)
			(end -0.12065 0.3048)
			(stroke
				(width 0.1)
				(type default)
			)
			(layer "F.Fab")
		)
		(fp_line
			(start -0.12065 0.3048)
			(end -0.67945 0.3048)
			(stroke
				(width 0.1)
				(type default)
			)
			(layer "F.Fab")
		)
		(fp_line
			(start 0.120396 0.2794)
			(end -0.12065 0.2794)
			(stroke
				(width 0.1)
				(type default)
			)
			(layer "F.Fab")
		)
		(fp_line
			(start 0.120396 0.3048)
			(end 0.120396 0.2794)
			(stroke
				(width 0.1)
				(type default)
			)
			(layer "F.Fab")
		)
		(fp_line
			(start 0.12065 -0.3048)
			(end 0.67945 -0.3048)
			(stroke
				(width 0.1)
				(type default)
			)
			(layer "F.Fab")
		)
		(fp_line
			(start 0.12065 -0.2794)
			(end 0.12065 -0.3048)
			(stroke
				(width 0.1)
				(type default)
			)
			(layer "F.Fab")
		)
		(fp_line
			(start 0.67945 -0.3048)
			(end 0.67945 0.3048)
			(stroke
				(width 0.1)
				(type default)
			)
			(layer "F.Fab")
		)
		(fp_line
			(start 0.67945 0.3048)
			(end 0.120396 0.3048)
			(stroke
				(width 0.1)
				(type default)
			)
			(layer "F.Fab")
		)
		(pad "1" smd circle
			(at -0.40005 0)
			(size 0 0)
			(layers "F.Cu" "F.Mask" "F.Paste")
			(net "P12V_NIC5_CO_SS")
		)
		(pad "2" smd circle
			(at 0.40005 0)
			(size 0 0)
			(layers "F.Cu" "F.Mask" "F.Paste")
			(net "GND")
		)
	)
	(footprint ""
		(layer "F.Cu")
		(at 352.12909 -205.156816 -90)
		(property "Reference" "R5778"
			(at 0 0 270)
			(layer "F.SilkS")
			(hide yes)
			(effects
				(font
					(size 1.27 1.27)
				)
			)
		)
		(property "Value" ""
			(at 0 0 270)
			(layer "F.Fab")
			(effects
				(font
					(size 1.27 1.27)
				)
			)
		)
		(duplicate_pad_numbers_are_jumpers no)
		(fp_line
			(start -0.7874 0.4064)
			(end -0.7874 -0.4064)
			(stroke
				(width 0.1524)
				(type default)
			)
			(layer "F.SilkS")
		)
		(fp_line
			(start 0.7874 0.4064)
			(end -0.7874 0.4064)
			(stroke
				(width 0.1524)
				(type default)
			)
			(layer "F.SilkS")
		)
		(fp_line
			(start -0.7874 -0.4064)
			(end 0.7874 -0.4064)
			(stroke
				(width 0.1524)
				(type default)
			)
			(layer "F.SilkS")
		)
		(fp_line
			(start 0.7874 -0.4064)
			(end 0.7874 0.4064)
			(stroke
				(width 0.1524)
				(type default)
			)
			(layer "F.SilkS")
		)
		(fp_line
			(start -0.67945 0.3048)
			(end -0.67945 -0.305054)
			(stroke
				(width 0.1)
				(type default)
			)
			(layer "F.Fab")
		)
		(fp_line
			(start -0.12065 0.3048)
			(end -0.67945 0.3048)
			(stroke
				(width 0.1)
				(type default)
			)
			(layer "F.Fab")
		)
		(fp_line
			(start 0.120396 0.3048)
			(end 0.120396 0.2794)
			(stroke
				(width 0.1)
				(type default)
			)
			(layer "F.Fab")
		)
		(fp_line
			(start 0.67945 0.3048)
			(end 0.120396 0.3048)
			(stroke
				(width 0.1)
				(type default)
			)
			(layer "F.Fab")
		)
		(fp_line
			(start -0.12065 0.2794)
			(end -0.12065 0.3048)
			(stroke
				(width 0.1)
				(type default)
			)
			(layer "F.Fab")
		)
		(fp_line
			(start 0.120396 0.2794)
			(end -0.12065 0.2794)
			(stroke
				(width 0.1)
				(type default)
			)
			(layer "F.Fab")
		)
		(fp_line
			(start -0.12065 -0.2794)
			(end 0.12065 -0.2794)
			(stroke
				(width 0.1)
				(type default)
			)
			(layer "F.Fab")
		)
		(fp_line
			(start 0.12065 -0.2794)
			(end 0.12065 -0.3048)
			(stroke
				(width 0.1)
				(type default)
			)
			(layer "F.Fab")
		)
		(fp_line
			(start 0.12065 -0.3048)
			(end 0.67945 -0.3048)
			(stroke
				(width 0.1)
				(type default)
			)
			(layer "F.Fab")
		)
		(fp_line
			(start 0.67945 -0.3048)
			(end 0.67945 0.3048)
			(stroke
				(width 0.1)
				(type default)
			)
			(layer "F.Fab")
		)
		(fp_line
			(start -0.67945 -0.305054)
			(end -0.12065 -0.305054)
			(stroke
				(width 0.1)
				(type default)
			)
			(layer "F.Fab")
		)
		(fp_line
			(start -0.12065 -0.305054)
			(end -0.12065 -0.2794)
			(stroke
				(width 0.1)
				(type default)
			)
			(layer "F.Fab")
		)
		(pad "1" smd circle
			(at -0.40005 0 270)
			(size 0 0)
			(layers "F.Cu" "F.Mask" "F.Paste")
			(net "FM_PFR_LED_AMBER")
		)
		(pad "2" smd circle
			(at 0.40005 0 270)
			(size 0 0)
			(layers "F.Cu" "F.Mask" "F.Paste")
			(net "FM_PFR_LED_AMBER_R")
		)
	)
	(footprint ""
		(layer "F.Cu")
		(at 198.62673 -53.697124 -90)
		(property "Reference" "PC496"
			(at 0 0 270)
			(layer "F.SilkS")
			(hide yes)
			(effects
				(font
					(size 1.27 1.27)
				)
			)
		)
		(property "Value" ""
			(at 0 0 270)
			(layer "F.Fab")
			(effects
				(font
					(size 1.27 1.27)
				)
			)
		)
		(duplicate_pad_numbers_are_jumpers no)
		(fp_line
			(start -0.7874 0.4064)
			(end -0.7874 -0.4064)
			(stroke
				(width 0.1524)
				(type default)
			)
			(layer "F.SilkS")
		)
		(fp_line
			(start 0.7874 0.4064)
			(end -0.7874 0.4064)
			(stroke
				(width 0.1524)
				(type default)
			)
			(layer "F.SilkS")
		)
		(fp_line
			(start -0.7874 -0.4064)
			(end 0.7874 -0.4064)
			(stroke
				(width 0.1524)
				(type default)
			)
			(layer "F.SilkS")
		)
		(fp_line
			(start 0.7874 -0.4064)
			(end 0.7874 0.4064)
			(stroke
				(width 0.1524)
				(type default)
			)
			(layer "F.SilkS")
		)
		(fp_line
			(start -0.67945 0.3048)
			(end -0.67945 -0.305054)
			(stroke
				(width 0.1)
				(type default)
			)
			(layer "F.Fab")
		)
		(fp_line
			(start -0.12065 0.3048)
			(end -0.67945 0.3048)
			(stroke
				(width 0.1)
				(type default)
			)
			(layer "F.Fab")
		)
		(fp_line
			(start 0.120396 0.3048)
			(end 0.120396 0.2794)
			(stroke
				(width 0.1)
				(type default)
			)
			(layer "F.Fab")
		)
		(fp_line
			(start 0.67945 0.3048)
			(end 0.120396 0.3048)
			(stroke
				(width 0.1)
				(type default)
			)
			(layer "F.Fab")
		)
		(fp_line
			(start -0.12065 0.2794)
			(end -0.12065 0.3048)
			(stroke
				(width 0.1)
				(type default)
			)
			(layer "F.Fab")
		)
		(fp_line
			(start 0.120396 0.2794)
			(end -0.12065 0.2794)
			(stroke
				(width 0.1)
				(type default)
			)
			(layer "F.Fab")
		)
		(fp_line
			(start -0.12065 -0.2794)
			(end 0.12065 -0.2794)
			(stroke
				(width 0.1)
				(type default)
			)
			(layer "F.Fab")
		)
		(fp_line
			(start 0.12065 -0.2794)
			(end 0.12065 -0.3048)
			(stroke
				(width 0.1)
				(type default)
			)
			(layer "F.Fab")
		)
		(fp_line
			(start 0.12065 -0.3048)
			(end 0.67945 -0.3048)
			(stroke
				(width 0.1)
				(type default)
			)
			(layer "F.Fab")
		)
		(fp_line
			(start 0.67945 -0.3048)
			(end 0.67945 0.3048)
			(stroke
				(width 0.1)
				(type default)
			)
			(layer "F.Fab")
		)
		(fp_line
			(start -0.67945 -0.305054)
			(end -0.12065 -0.305054)
			(stroke
				(width 0.1)
				(type default)
			)
			(layer "F.Fab")
		)
		(fp_line
			(start -0.12065 -0.305054)
			(end -0.12065 -0.2794)
			(stroke
				(width 0.1)
				(type default)
			)
			(layer "F.Fab")
		)
		(pad "1" smd circle
			(at -0.40005 0 270)
			(size 0 0)
			(layers "F.Cu" "F.Mask" "F.Paste")
			(net "P3V3_AUX")
		)
		(pad "2" smd circle
			(at 0.40005 0 270)
			(size 0 0)
			(layers "F.Cu" "F.Mask" "F.Paste")
			(net "GND")
		)
	)
	(footprint ""
		(layer "F.Cu")
		(at 243.564918 -316.176914)
		(property "Reference" "PC247"
			(at 0 0 0)
			(layer "F.SilkS")
			(hide yes)
			(effects
				(font
					(size 1.27 1.27)
				)
			)
		)
		(property "Value" ""
			(at 0 0 0)
			(layer "F.Fab")
			(effects
				(font
					(size 1.27 1.27)
				)
			)
		)
		(duplicate_pad_numbers_are_jumpers no)
		(fp_line
			(start -1.524 -0.762)
			(end 1.524 -0.762)
			(stroke
				(width 0.1524)
				(type default)
			)
			(layer "F.SilkS")
		)
		(fp_line
			(start -1.524 0.762)
			(end -1.524 -0.762)
			(stroke
				(width 0.1524)
				(type default)
			)
			(layer "F.SilkS")
		)
		(fp_line
			(start 1.524 -0.762)
			(end 1.524 0.762)
			(stroke
				(width 0.1524)
				(type default)
			)
			(layer "F.SilkS")
		)
		(fp_line
			(start 1.524 0.762)
			(end -1.524 0.762)
			(stroke
				(width 0.1524)
				(type default)
			)
			(layer "F.SilkS")
		)
		(fp_line
			(start -1.1049 -0.724916)
			(end -1.1049 0.724916)
			(stroke
				(width 0.1)
				(type default)
			)
			(layer "F.Fab")
		)
		(fp_line
			(start -1.1049 0.724916)
			(end 1.1049 0.724916)
			(stroke
				(width 0.1)
				(type default)
			)
			(layer "F.Fab")
		)
		(fp_line
			(start 1.1049 -0.724916)
			(end -1.1049 -0.724916)
			(stroke
				(width 0.1)
				(type default)
			)
			(layer "F.Fab")
		)
		(fp_line
			(start 1.1049 0.724916)
			(end 1.1049 -0.724916)
			(stroke
				(width 0.1)
				(type default)
			)
			(layer "F.Fab")
		)
		(pad "1" smd rect
			(at -0.889 0 180)
			(size 1.016 1.27)
			(layers "F.Cu" "F.Mask" "F.Paste")
			(net "SW_P12V_P1V25_PEX2_FLT")
		)
		(pad "2" smd rect
			(at 0.889 0 180)
			(size 1.016 1.27)
			(layers "F.Cu" "F.Mask" "F.Paste")
			(net "GND")
		)
	)
	(footprint ""
		(layer "F.Cu")
		(at 315.78931 -63.56223)
		(property "Reference" "Q207"
			(at 1.160018 -1.900174 0)
			(unlocked yes)
			(layer "F.SilkS")
			(effects
				(font
					(size 0.7874 0.5842)
					(thickness 0.1524)
				)
			)
		)
		(property "Value" ""
			(at 0 0 0)
			(layer "F.Fab")
			(effects
				(font
					(size 1.27 1.27)
				)
			)
		)
		(duplicate_pad_numbers_are_jumpers no)
		(fp_line
			(start -1.376172 -1.199896)
			(end -0.508 -1.199896)
			(stroke
				(width 0.1524)
				(type default)
			)
			(layer "F.SilkS")
		)
		(fp_line
			(start -1.376172 1.199896)
			(end -1.376172 -1.199896)
			(stroke
				(width 0.1524)
				(type default)
			)
			(layer "F.SilkS")
		)
		(fp_line
			(start -0.508 -1.199896)
			(end 0 -0.762)
			(stroke
				(width 0.1524)
				(type default)
			)
			(layer "F.SilkS")
		)
		(fp_line
			(start 0 -0.762)
			(end 0.508 -1.199896)
			(stroke
				(width 0.1524)
				(type default)
			)
			(layer "F.SilkS")
		)
		(fp_line
			(start 0.508 -1.199896)
			(end 1.376172 -1.199896)
			(stroke
				(width 0.1524)
				(type default)
			)
			(layer "F.SilkS")
		)
		(fp_line
			(start 1.376172 -1.199896)
			(end 1.376172 1.199896)
			(stroke
				(width 0.1524)
				(type default)
			)
			(layer "F.SilkS")
		)
		(fp_line
			(start 1.376172 1.199896)
			(end -1.376172 1.199896)
			(stroke
				(width 0.1524)
				(type default)
			)
			(layer "F.SilkS")
		)
		(fp_poly
			(pts
				(xy -0.994918 -1.301242) (xy -0.613918 -2.063242) (xy -1.375918 -2.063242)
			)
			(stroke
				(width 0)
				(type default)
			)
			(fill yes)
			(layer "F.SilkS")
		)
		(fp_line
			(start -0.674878 -1.100074)
			(end 0.674878 -1.100074)
			(stroke
				(width 0.1)
				(type default)
			)
			(layer "F.Fab")
		)
		(fp_line
			(start -0.674878 1.100074)
			(end -0.674878 -1.100074)
			(stroke
				(width 0.1)
				(type default)
			)
			(layer "F.Fab")
		)
		(fp_line
			(start 0.674878 -1.100074)
			(end 0.674878 1.100074)
			(stroke
				(width 0.1)
				(type default)
			)
			(layer "F.Fab")
		)
		(fp_line
			(start 0.674878 1.100074)
			(end -0.674878 1.100074)
			(stroke
				(width 0.1)
				(type default)
			)
			(layer "F.Fab")
		)
		(fp_poly
			(pts
				(xy -1.4605 -0.7493) (xy -2.2225 -1.1303) (xy -2.2225 -0.3683)
			)
			(stroke
				(width 0)
				(type default)
			)
			(fill yes)
			(layer "F.Fab")
		)
		(pad "1" smd rect
			(at -0.899922 -0.750062 270)
			(size 0.6096 0.6096)
			(layers "F.Cu" "F.Mask" "F.Paste")
			(net "GND")
		)
		(pad "2" smd rect
			(at -0.899922 0 270)
			(size 0.4064 0.6096)
			(layers "F.Cu" "F.Mask" "F.Paste")
			(net "P12V_SSD11_PG_G1")
		)
		(pad "3" smd rect
			(at -0.899922 0.750062 270)
			(size 0.6096 0.6096)
			(layers "F.Cu" "F.Mask" "F.Paste")
			(net "PWRGD_P12V_SSD11_D")
		)
		(pad "4" smd rect
			(at 0.899922 0.750062 270)
			(size 0.6096 0.6096)
			(layers "F.Cu" "F.Mask" "F.Paste")
			(net "GND")
		)
		(pad "5" smd rect
			(at 0.899922 0 270)
			(size 0.4064 0.6096)
			(layers "F.Cu" "F.Mask" "F.Paste")
			(net "P12V_SSD11_PG_G2")
		)
		(pad "6" smd rect
			(at 0.899922 -0.750062 270)
			(size 0.6096 0.6096)
			(layers "F.Cu" "F.Mask" "F.Paste")
			(net "P12V_SSD11_PG_G2")
		)
	)
	(footprint ""
		(layer "F.Cu")
		(at 248.094754 -280.583386 180)
		(property "Reference" "R797"
			(at 0 0 180)
			(layer "F.SilkS")
			(hide yes)
			(effects
				(font
					(size 1.27 1.27)
				)
			)
		)
		(property "Value" ""
			(at 0 0 180)
			(layer "F.Fab")
			(effects
				(font
					(size 1.27 1.27)
				)
			)
		)
		(duplicate_pad_numbers_are_jumpers no)
		(fp_line
			(start 0.7874 0.4064)
			(end -0.7874 0.4064)
			(stroke
				(width 0.1524)
				(type default)
			)
			(layer "F.SilkS")
		)
		(fp_line
			(start 0.7874 -0.4064)
			(end 0.7874 0.4064)
			(stroke
				(width 0.1524)
				(type default)
			)
			(layer "F.SilkS")
		)
		(fp_line
			(start -0.7874 0.4064)
			(end -0.7874 -0.4064)
			(stroke
				(width 0.1524)
				(type default)
			)
			(layer "F.SilkS")
		)
		(fp_line
			(start -0.7874 -0.4064)
			(end 0.7874 -0.4064)
			(stroke
				(width 0.1524)
				(type default)
			)
			(layer "F.SilkS")
		)
		(fp_line
			(start 0.67945 0.3048)
			(end 0.120396 0.3048)
			(stroke
				(width 0.1)
				(type default)
			)
			(layer "F.Fab")
		)
		(fp_line
			(start 0.67945 -0.3048)
			(end 0.67945 0.3048)
			(stroke
				(width 0.1)
				(type default)
			)
			(layer "F.Fab")
		)
		(fp_line
			(start 0.12065 -0.2794)
			(end 0.12065 -0.3048)
			(stroke
				(width 0.1)
				(type default)
			)
			(layer "F.Fab")
		)
		(fp_line
			(start 0.12065 -0.3048)
			(end 0.67945 -0.3048)
			(stroke
				(width 0.1)
				(type default)
			)
			(layer "F.Fab")
		)
		(fp_line
			(start 0.120396 0.3048)
			(end 0.120396 0.2794)
			(stroke
				(width 0.1)
				(type default)
			)
			(layer "F.Fab")
		)
		(fp_line
			(start 0.120396 0.2794)
			(end -0.12065 0.2794)
			(stroke
				(width 0.1)
				(type default)
			)
			(layer "F.Fab")
		)
		(fp_line
			(start -0.12065 0.3048)
			(end -0.67945 0.3048)
			(stroke
				(width 0.1)
				(type default)
			)
			(layer "F.Fab")
		)
		(fp_line
			(start -0.12065 0.2794)
			(end -0.12065 0.3048)
			(stroke
				(width 0.1)
				(type default)
			)
			(layer "F.Fab")
		)
		(fp_line
			(start -0.12065 -0.2794)
			(end 0.12065 -0.2794)
			(stroke
				(width 0.1)
				(type default)
			)
			(layer "F.Fab")
		)
		(fp_line
			(start -0.12065 -0.305054)
			(end -0.12065 -0.2794)
			(stroke
				(width 0.1)
				(type default)
			)
			(layer "F.Fab")
		)
		(fp_line
			(start -0.67945 0.3048)
			(end -0.67945 -0.305054)
			(stroke
				(width 0.1)
				(type default)
			)
			(layer "F.Fab")
		)
		(fp_line
			(start -0.67945 -0.305054)
			(end -0.12065 -0.305054)
			(stroke
				(width 0.1)
				(type default)
			)
			(layer "F.Fab")
		)
		(pad "1" smd circle
			(at -0.40005 0 180)
			(size 0 0)
			(layers "F.Cu" "F.Mask" "F.Paste")
			(net "SMB_BIC_I2C6_MUX_PEX_ADC_R_SCL")
		)
		(pad "2" smd circle
			(at 0.40005 0 180)
			(size 0 0)
			(layers "F.Cu" "F.Mask" "F.Paste")
			(net "SMB_PEX2_P1V25_ADC_SCL")
		)
	)
	(footprint ""
		(layer "F.Cu")
		(at 434.141372 -350.098614 90)
		(property "Reference" "C2463"
			(at 0 0 90)
			(layer "F.SilkS")
			(hide yes)
			(effects
				(font
					(size 1.27 1.27)
				)
			)
		)
		(property "Value" ""
			(at 0 0 90)
			(layer "F.Fab")
			(effects
				(font
					(size 1.27 1.27)
				)
			)
		)
		(duplicate_pad_numbers_are_jumpers no)
		(fp_line
			(start 0.299974 -0.150114)
			(end 0.299974 0.150114)
			(stroke
				(width 0.1)
				(type default)
			)
			(layer "F.Fab")
		)
		(fp_line
			(start -0.299974 -0.150114)
			(end 0.299974 -0.150114)
			(stroke
				(width 0.1)
				(type default)
			)
			(layer "F.Fab")
		)
		(fp_line
			(start 0.299974 0.150114)
			(end -0.299974 0.150114)
			(stroke
				(width 0.1)
				(type default)
			)
			(layer "F.Fab")
		)
		(fp_line
			(start -0.299974 0.150114)
			(end -0.299974 -0.150114)
			(stroke
				(width 0.1)
				(type default)
			)
			(layer "F.Fab")
		)
		(pad "1" smd rect
			(at -0.2667 0 90)
			(size 0.3048 0.381)
			(layers "F.Cu" "F.Mask" "F.Paste")
			(net "P5E_PEX3_STN4_TX_DP<67>")
		)
		(pad "2" smd rect
			(at 0.2667 0 90)
			(size 0.3048 0.381)
			(layers "F.Cu" "F.Mask" "F.Paste")
			(net "P5E_PEX3_STN4_TX_C_DP<67>")
		)
	)
	(footprint ""
		(layer "F.Cu")
		(at 451.977506 -277.291292 90)
		(property "Reference" "R804"
			(at 0 0 90)
			(layer "F.SilkS")
			(hide yes)
			(effects
				(font
					(size 1.27 1.27)
				)
			)
		)
		(property "Value" ""
			(at 0 0 90)
			(layer "F.Fab")
			(effects
				(font
					(size 1.27 1.27)
				)
			)
		)
		(duplicate_pad_numbers_are_jumpers no)
		(fp_line
			(start 3.937508 -1.8796)
			(end -3.937508 -1.8796)
			(stroke
				(width 0.1524)
				(type default)
			)
			(layer "F.SilkS")
		)
		(fp_line
			(start -3.937508 -1.8796)
			(end -3.937508 1.8796)
			(stroke
				(width 0.1524)
				(type default)
			)
			(layer "F.SilkS")
		)
		(fp_line
			(start 3.937508 1.8796)
			(end 3.937508 -1.8796)
			(stroke
				(width 0.1524)
				(type default)
			)
			(layer "F.SilkS")
		)
		(fp_line
			(start -3.937508 1.8796)
			(end 3.937508 1.8796)
			(stroke
				(width 0.1524)
				(type default)
			)
			(layer "F.SilkS")
		)
		(fp_line
			(start 3.275076 -1.674876)
			(end -3.275076 -1.674876)
			(stroke
				(width 0.1)
				(type default)
			)
			(layer "F.Fab")
		)
		(fp_line
			(start -3.275076 -1.674876)
			(end -3.275076 1.674876)
			(stroke
				(width 0.1)
				(type default)
			)
			(layer "F.Fab")
		)
		(fp_line
			(start 3.275076 1.674876)
			(end 3.275076 -1.674876)
			(stroke
				(width 0.1)
				(type default)
			)
			(layer "F.Fab")
		)
		(fp_line
			(start -3.275076 1.674876)
			(end 3.275076 1.674876)
			(stroke
				(width 0.1)
				(type default)
			)
			(layer "F.Fab")
		)
		(pad "1" smd rect
			(at -2.350008 0 90)
			(size 2.921 3.5052)
			(layers "F.Cu" "F.Mask" "F.Paste")
			(net "P1V25_PEX3")
		)
		(pad "2" smd rect
			(at 2.350008 0 90)
			(size 2.921 3.5052)
			(layers "F.Cu" "F.Mask" "F.Paste")
			(net "P1V25_PEX3_R")
		)
	)
	(footprint ""
		(layer "F.Cu")
		(at 270.83004 -366.767364 90)
		(property "Reference" "PR6614"
			(at 0 0 90)
			(layer "F.SilkS")
			(hide yes)
			(effects
				(font
					(size 1.27 1.27)
				)
			)
		)
		(property "Value" ""
			(at 0 0 90)
			(layer "F.Fab")
			(effects
				(font
					(size 1.27 1.27)
				)
			)
		)
		(duplicate_pad_numbers_are_jumpers no)
		(fp_line
			(start 0.7874 -0.4064)
			(end 0.7874 0.4064)
			(stroke
				(width 0.1524)
				(type default)
			)
			(layer "F.SilkS")
		)
		(fp_line
			(start -0.7874 -0.4064)
			(end 0.7874 -0.4064)
			(stroke
				(width 0.1524)
				(type default)
			)
			(layer "F.SilkS")
		)
		(fp_line
			(start 0.7874 0.4064)
			(end -0.7874 0.4064)
			(stroke
				(width 0.1524)
				(type default)
			)
			(layer "F.SilkS")
		)
		(fp_line
			(start -0.7874 0.4064)
			(end -0.7874 -0.4064)
			(stroke
				(width 0.1524)
				(type default)
			)
			(layer "F.SilkS")
		)
		(fp_line
			(start -0.12065 -0.305054)
			(end -0.12065 -0.2794)
			(stroke
				(width 0.1)
				(type default)
			)
			(layer "F.Fab")
		)
		(fp_line
			(start -0.67945 -0.305054)
			(end -0.12065 -0.305054)
			(stroke
				(width 0.1)
				(type default)
			)
			(layer "F.Fab")
		)
		(fp_line
			(start 0.67945 -0.3048)
			(end 0.67945 0.3048)
			(stroke
				(width 0.1)
				(type default)
			)
			(layer "F.Fab")
		)
		(fp_line
			(start 0.12065 -0.3048)
			(end 0.67945 -0.3048)
			(stroke
				(width 0.1)
				(type default)
			)
			(layer "F.Fab")
		)
		(fp_line
			(start 0.12065 -0.2794)
			(end 0.12065 -0.3048)
			(stroke
				(width 0.1)
				(type default)
			)
			(layer "F.Fab")
		)
		(fp_line
			(start -0.12065 -0.2794)
			(end 0.12065 -0.2794)
			(stroke
				(width 0.1)
				(type default)
			)
			(layer "F.Fab")
		)
		(fp_line
			(start 0.120396 0.2794)
			(end -0.12065 0.2794)
			(stroke
				(width 0.1)
				(type default)
			)
			(layer "F.Fab")
		)
		(fp_line
			(start -0.12065 0.2794)
			(end -0.12065 0.3048)
			(stroke
				(width 0.1)
				(type default)
			)
			(layer "F.Fab")
		)
		(fp_line
			(start 0.67945 0.3048)
			(end 0.120396 0.3048)
			(stroke
				(width 0.1)
				(type default)
			)
			(layer "F.Fab")
		)
		(fp_line
			(start 0.120396 0.3048)
			(end 0.120396 0.2794)
			(stroke
				(width 0.1)
				(type default)
			)
			(layer "F.Fab")
		)
		(fp_line
			(start -0.12065 0.3048)
			(end -0.67945 0.3048)
			(stroke
				(width 0.1)
				(type default)
			)
			(layer "F.Fab")
		)
		(fp_line
			(start -0.67945 0.3048)
			(end -0.67945 -0.305054)
			(stroke
				(width 0.1)
				(type default)
			)
			(layer "F.Fab")
		)
		(pad "1" smd circle
			(at -0.40005 0 90)
			(size 0 0)
			(layers "F.Cu" "F.Mask" "F.Paste")
			(net "LTC4282_TEMP_R_D+")
		)
		(pad "2" smd circle
			(at 0.40005 0 90)
			(size 0 0)
			(layers "F.Cu" "F.Mask" "F.Paste")
			(net "LTC4282_TEMP_D+")
		)
	)
	(footprint ""
		(layer "F.Cu")
		(at 396.209266 -87.214202 180)
		(property "Reference" "R1763"
			(at 0 0 180)
			(layer "F.SilkS")
			(hide yes)
			(effects
				(font
					(size 1.27 1.27)
				)
			)
		)
		(property "Value" ""
			(at 0 0 180)
			(layer "F.Fab")
			(effects
				(font
					(size 1.27 1.27)
				)
			)
		)
		(duplicate_pad_numbers_are_jumpers no)
		(fp_line
			(start 0.7874 0.4064)
			(end -0.7874 0.4064)
			(stroke
				(width 0.1524)
				(type default)
			)
			(layer "F.SilkS")
		)
		(fp_line
			(start 0.7874 -0.4064)
			(end 0.7874 0.4064)
			(stroke
				(width 0.1524)
				(type default)
			)
			(layer "F.SilkS")
		)
		(fp_line
			(start -0.7874 0.4064)
			(end -0.7874 -0.4064)
			(stroke
				(width 0.1524)
				(type default)
			)
			(layer "F.SilkS")
		)
		(fp_line
			(start -0.7874 -0.4064)
			(end 0.7874 -0.4064)
			(stroke
				(width 0.1524)
				(type default)
			)
			(layer "F.SilkS")
		)
		(fp_line
			(start 0.67945 0.3048)
			(end 0.120396 0.3048)
			(stroke
				(width 0.1)
				(type default)
			)
			(layer "F.Fab")
		)
		(fp_line
			(start 0.67945 -0.3048)
			(end 0.67945 0.3048)
			(stroke
				(width 0.1)
				(type default)
			)
			(layer "F.Fab")
		)
		(fp_line
			(start 0.12065 -0.2794)
			(end 0.12065 -0.3048)
			(stroke
				(width 0.1)
				(type default)
			)
			(layer "F.Fab")
		)
		(fp_line
			(start 0.12065 -0.3048)
			(end 0.67945 -0.3048)
			(stroke
				(width 0.1)
				(type default)
			)
			(layer "F.Fab")
		)
		(fp_line
			(start 0.120396 0.3048)
			(end 0.120396 0.2794)
			(stroke
				(width 0.1)
				(type default)
			)
			(layer "F.Fab")
		)
		(fp_line
			(start 0.120396 0.2794)
			(end -0.12065 0.2794)
			(stroke
				(width 0.1)
				(type default)
			)
			(layer "F.Fab")
		)
		(fp_line
			(start -0.12065 0.3048)
			(end -0.67945 0.3048)
			(stroke
				(width 0.1)
				(type default)
			)
			(layer "F.Fab")
		)
		(fp_line
			(start -0.12065 0.2794)
			(end -0.12065 0.3048)
			(stroke
				(width 0.1)
				(type default)
			)
			(layer "F.Fab")
		)
		(fp_line
			(start -0.12065 -0.2794)
			(end 0.12065 -0.2794)
			(stroke
				(width 0.1)
				(type default)
			)
			(layer "F.Fab")
		)
		(fp_line
			(start -0.12065 -0.305054)
			(end -0.12065 -0.2794)
			(stroke
				(width 0.1)
				(type default)
			)
			(layer "F.Fab")
		)
		(fp_line
			(start -0.67945 0.3048)
			(end -0.67945 -0.305054)
			(stroke
				(width 0.1)
				(type default)
			)
			(layer "F.Fab")
		)
		(fp_line
			(start -0.67945 -0.305054)
			(end -0.12065 -0.305054)
			(stroke
				(width 0.1)
				(type default)
			)
			(layer "F.Fab")
		)
		(pad "1" smd circle
			(at -0.40005 0 180)
			(size 0 0)
			(layers "F.Cu" "F.Mask" "F.Paste")
			(net "P3V3_AUX")
		)
		(pad "2" smd circle
			(at 0.40005 0 180)
			(size 0 0)
			(layers "F.Cu" "F.Mask" "F.Paste")
			(net "SMB_BIC_I2C6_MUX_FRU_R_SDA")
		)
	)
	(footprint ""
		(layer "F.Cu")
		(at 130.25882 -319.420494 90)
		(property "Reference" "R5790"
			(at 0 0 90)
			(layer "F.SilkS")
			(hide yes)
			(effects
				(font
					(size 1.27 1.27)
				)
			)
		)
		(property "Value" ""
			(at 0 0 90)
			(layer "F.Fab")
			(effects
				(font
					(size 1.27 1.27)
				)
			)
		)
		(duplicate_pad_numbers_are_jumpers no)
		(fp_line
			(start 2.576322 -1.1303)
			(end 2.576322 1.1303)
			(stroke
				(width 0.1524)
				(type default)
			)
			(layer "F.SilkS")
		)
		(fp_line
			(start -2.576322 -1.1303)
			(end 2.576322 -1.1303)
			(stroke
				(width 0.1524)
				(type default)
			)
			(layer "F.SilkS")
		)
		(fp_line
			(start 2.576322 1.1303)
			(end -2.576322 1.1303)
			(stroke
				(width 0.1524)
				(type default)
			)
			(layer "F.SilkS")
		)
		(fp_line
			(start -2.576322 1.1303)
			(end -2.576322 -1.1303)
			(stroke
				(width 0.1524)
				(type default)
			)
			(layer "F.SilkS")
		)
		(fp_line
			(start 1.649984 -0.899922)
			(end -1.649984 -0.899922)
			(stroke
				(width 0.1)
				(type default)
			)
			(layer "F.Fab")
		)
		(fp_line
			(start -1.649984 -0.899922)
			(end -1.649984 0.899922)
			(stroke
				(width 0.1)
				(type default)
			)
			(layer "F.Fab")
		)
		(fp_line
			(start 1.649984 0.899922)
			(end 1.649984 -0.899922)
			(stroke
				(width 0.1)
				(type default)
			)
			(layer "F.Fab")
		)
		(fp_line
			(start -1.649984 0.899922)
			(end 1.649984 0.899922)
			(stroke
				(width 0.1)
				(type default)
			)
			(layer "F.Fab")
		)
		(pad "1A" smd rect
			(at -1.700022 0 90)
			(size 1.4986 2.0066)
			(layers "F.Cu" "F.Mask" "F.Paste")
			(net "P0V8_PEX1")
		)
		(pad "1B" smd rect
			(at -1.077722 0 90)
			(size 0.254 0.508)
			(layers "F.Cu" "F.Mask" "F.Paste")
			(net "P0V8_PEX1")
		)
		(pad "2A" smd rect
			(at 1.700022 0 90)
			(size 1.4986 2.0066)
			(layers "F.Cu" "F.Mask" "F.Paste")
			(net "P0V8_SERDES_VDDA_PEX1")
		)
		(pad "2B" smd rect
			(at 1.077722 0 90)
			(size 0.254 0.508)
			(layers "F.Cu" "F.Mask" "F.Paste")
			(net "P0V8_SERDES_VDDA_PEX1")
		)
	)
	(footprint ""
		(layer "F.Cu")
		(at 314.573666 -27.006296 -90)
		(property "Reference" "PC956"
			(at 0 0 270)
			(layer "F.SilkS")
			(hide yes)
			(effects
				(font
					(size 1.27 1.27)
				)
			)
		)
		(property "Value" ""
			(at 0 0 270)
			(layer "F.Fab")
			(effects
				(font
					(size 1.27 1.27)
				)
			)
		)
		(duplicate_pad_numbers_are_jumpers no)
		(fp_line
			(start -0.7874 0.4064)
			(end -0.7874 -0.4064)
			(stroke
				(width 0.1524)
				(type default)
			)
			(layer "F.SilkS")
		)
		(fp_line
			(start 0.7874 0.4064)
			(end -0.7874 0.4064)
			(stroke
				(width 0.1524)
				(type default)
			)
			(layer "F.SilkS")
		)
		(fp_line
			(start -0.7874 -0.4064)
			(end 0.7874 -0.4064)
			(stroke
				(width 0.1524)
				(type default)
			)
			(layer "F.SilkS")
		)
		(fp_line
			(start 0.7874 -0.4064)
			(end 0.7874 0.4064)
			(stroke
				(width 0.1524)
				(type default)
			)
			(layer "F.SilkS")
		)
		(fp_line
			(start -0.67945 0.3048)
			(end -0.67945 -0.305054)
			(stroke
				(width 0.1)
				(type default)
			)
			(layer "F.Fab")
		)
		(fp_line
			(start -0.12065 0.3048)
			(end -0.67945 0.3048)
			(stroke
				(width 0.1)
				(type default)
			)
			(layer "F.Fab")
		)
		(fp_line
			(start 0.120396 0.3048)
			(end 0.120396 0.2794)
			(stroke
				(width 0.1)
				(type default)
			)
			(layer "F.Fab")
		)
		(fp_line
			(start 0.67945 0.3048)
			(end 0.120396 0.3048)
			(stroke
				(width 0.1)
				(type default)
			)
			(layer "F.Fab")
		)
		(fp_line
			(start -0.12065 0.2794)
			(end -0.12065 0.3048)
			(stroke
				(width 0.1)
				(type default)
			)
			(layer "F.Fab")
		)
		(fp_line
			(start 0.120396 0.2794)
			(end -0.12065 0.2794)
			(stroke
				(width 0.1)
				(type default)
			)
			(layer "F.Fab")
		)
		(fp_line
			(start -0.12065 -0.2794)
			(end 0.12065 -0.2794)
			(stroke
				(width 0.1)
				(type default)
			)
			(layer "F.Fab")
		)
		(fp_line
			(start 0.12065 -0.2794)
			(end 0.12065 -0.3048)
			(stroke
				(width 0.1)
				(type default)
			)
			(layer "F.Fab")
		)
		(fp_line
			(start 0.12065 -0.3048)
			(end 0.67945 -0.3048)
			(stroke
				(width 0.1)
				(type default)
			)
			(layer "F.Fab")
		)
		(fp_line
			(start 0.67945 -0.3048)
			(end 0.67945 0.3048)
			(stroke
				(width 0.1)
				(type default)
			)
			(layer "F.Fab")
		)
		(fp_line
			(start -0.67945 -0.305054)
			(end -0.12065 -0.305054)
			(stroke
				(width 0.1)
				(type default)
			)
			(layer "F.Fab")
		)
		(fp_line
			(start -0.12065 -0.305054)
			(end -0.12065 -0.2794)
			(stroke
				(width 0.1)
				(type default)
			)
			(layer "F.Fab")
		)
		(pad "1" smd circle
			(at -0.40005 0 270)
			(size 0 0)
			(layers "F.Cu" "F.Mask" "F.Paste")
			(net "P3V3_SSD11_CO_MODE")
		)
		(pad "2" smd circle
			(at 0.40005 0 270)
			(size 0 0)
			(layers "F.Cu" "F.Mask" "F.Paste")
			(net "GND")
		)
	)
	(footprint ""
		(layer "F.Cu")
		(at 377.722384 -250.070874 -90)
		(property "Reference" "R1408"
			(at 0 0 270)
			(layer "F.SilkS")
			(hide yes)
			(effects
				(font
					(size 1.27 1.27)
				)
			)
		)
		(property "Value" ""
			(at 0 0 270)
			(layer "F.Fab")
			(effects
				(font
					(size 1.27 1.27)
				)
			)
		)
		(duplicate_pad_numbers_are_jumpers no)
		(fp_line
			(start -0.7874 0.4064)
			(end -0.7874 -0.4064)
			(stroke
				(width 0.1524)
				(type default)
			)
			(layer "F.SilkS")
		)
		(fp_line
			(start 0.7874 0.4064)
			(end -0.7874 0.4064)
			(stroke
				(width 0.1524)
				(type default)
			)
			(layer "F.SilkS")
		)
		(fp_line
			(start -0.7874 -0.4064)
			(end 0.7874 -0.4064)
			(stroke
				(width 0.1524)
				(type default)
			)
			(layer "F.SilkS")
		)
		(fp_line
			(start 0.7874 -0.4064)
			(end 0.7874 0.4064)
			(stroke
				(width 0.1524)
				(type default)
			)
			(layer "F.SilkS")
		)
		(fp_line
			(start -0.67945 0.3048)
			(end -0.67945 -0.305054)
			(stroke
				(width 0.1)
				(type default)
			)
			(layer "F.Fab")
		)
		(fp_line
			(start -0.12065 0.3048)
			(end -0.67945 0.3048)
			(stroke
				(width 0.1)
				(type default)
			)
			(layer "F.Fab")
		)
		(fp_line
			(start 0.120396 0.3048)
			(end 0.120396 0.2794)
			(stroke
				(width 0.1)
				(type default)
			)
			(layer "F.Fab")
		)
		(fp_line
			(start 0.67945 0.3048)
			(end 0.120396 0.3048)
			(stroke
				(width 0.1)
				(type default)
			)
			(layer "F.Fab")
		)
		(fp_line
			(start -0.12065 0.2794)
			(end -0.12065 0.3048)
			(stroke
				(width 0.1)
				(type default)
			)
			(layer "F.Fab")
		)
		(fp_line
			(start 0.120396 0.2794)
			(end -0.12065 0.2794)
			(stroke
				(width 0.1)
				(type default)
			)
			(layer "F.Fab")
		)
		(fp_line
			(start -0.12065 -0.2794)
			(end 0.12065 -0.2794)
			(stroke
				(width 0.1)
				(type default)
			)
			(layer "F.Fab")
		)
		(fp_line
			(start 0.12065 -0.2794)
			(end 0.12065 -0.3048)
			(stroke
				(width 0.1)
				(type default)
			)
			(layer "F.Fab")
		)
		(fp_line
			(start 0.12065 -0.3048)
			(end 0.67945 -0.3048)
			(stroke
				(width 0.1)
				(type default)
			)
			(layer "F.Fab")
		)
		(fp_line
			(start 0.67945 -0.3048)
			(end 0.67945 0.3048)
			(stroke
				(width 0.1)
				(type default)
			)
			(layer "F.Fab")
		)
		(fp_line
			(start -0.67945 -0.305054)
			(end -0.12065 -0.305054)
			(stroke
				(width 0.1)
				(type default)
			)
			(layer "F.Fab")
		)
		(fp_line
			(start -0.12065 -0.305054)
			(end -0.12065 -0.2794)
			(stroke
				(width 0.1)
				(type default)
			)
			(layer "F.Fab")
		)
		(pad "1" smd circle
			(at -0.40005 0 270)
			(size 0 0)
			(layers "F.Cu" "F.Mask" "F.Paste")
			(net "PEX3_MODE_SEL3")
		)
		(pad "2" smd circle
			(at 0.40005 0 270)
			(size 0 0)
			(layers "F.Cu" "F.Mask" "F.Paste")
			(net "P1V8_PEX")
		)
	)
	(footprint ""
		(layer "F.Cu")
		(at 21.513546 -254.753364 -90)
		(property "Reference" "R6153"
			(at 0 0 270)
			(layer "F.SilkS")
			(hide yes)
			(effects
				(font
					(size 1.27 1.27)
				)
			)
		)
		(property "Value" ""
			(at 0 0 270)
			(layer "F.Fab")
			(effects
				(font
					(size 1.27 1.27)
				)
			)
		)
		(duplicate_pad_numbers_are_jumpers no)
		(fp_line
			(start -0.7874 0.4064)
			(end -0.7874 -0.4064)
			(stroke
				(width 0.1524)
				(type default)
			)
			(layer "F.SilkS")
		)
		(fp_line
			(start 0.7874 0.4064)
			(end -0.7874 0.4064)
			(stroke
				(width 0.1524)
				(type default)
			)
			(layer "F.SilkS")
		)
		(fp_line
			(start -0.7874 -0.4064)
			(end 0.7874 -0.4064)
			(stroke
				(width 0.1524)
				(type default)
			)
			(layer "F.SilkS")
		)
		(fp_line
			(start 0.7874 -0.4064)
			(end 0.7874 0.4064)
			(stroke
				(width 0.1524)
				(type default)
			)
			(layer "F.SilkS")
		)
		(fp_line
			(start -0.67945 0.3048)
			(end -0.67945 -0.305054)
			(stroke
				(width 0.1)
				(type default)
			)
			(layer "F.Fab")
		)
		(fp_line
			(start -0.12065 0.3048)
			(end -0.67945 0.3048)
			(stroke
				(width 0.1)
				(type default)
			)
			(layer "F.Fab")
		)
		(fp_line
			(start 0.120396 0.3048)
			(end 0.120396 0.2794)
			(stroke
				(width 0.1)
				(type default)
			)
			(layer "F.Fab")
		)
		(fp_line
			(start 0.67945 0.3048)
			(end 0.120396 0.3048)
			(stroke
				(width 0.1)
				(type default)
			)
			(layer "F.Fab")
		)
		(fp_line
			(start -0.12065 0.2794)
			(end -0.12065 0.3048)
			(stroke
				(width 0.1)
				(type default)
			)
			(layer "F.Fab")
		)
		(fp_line
			(start 0.120396 0.2794)
			(end -0.12065 0.2794)
			(stroke
				(width 0.1)
				(type default)
			)
			(layer "F.Fab")
		)
		(fp_line
			(start -0.12065 -0.2794)
			(end 0.12065 -0.2794)
			(stroke
				(width 0.1)
				(type default)
			)
			(layer "F.Fab")
		)
		(fp_line
			(start 0.12065 -0.2794)
			(end 0.12065 -0.3048)
			(stroke
				(width 0.1)
				(type default)
			)
			(layer "F.Fab")
		)
		(fp_line
			(start 0.12065 -0.3048)
			(end 0.67945 -0.3048)
			(stroke
				(width 0.1)
				(type default)
			)
			(layer "F.Fab")
		)
		(fp_line
			(start 0.67945 -0.3048)
			(end 0.67945 0.3048)
			(stroke
				(width 0.1)
				(type default)
			)
			(layer "F.Fab")
		)
		(fp_line
			(start -0.67945 -0.305054)
			(end -0.12065 -0.305054)
			(stroke
				(width 0.1)
				(type default)
			)
			(layer "F.Fab")
		)
		(fp_line
			(start -0.12065 -0.305054)
			(end -0.12065 -0.2794)
			(stroke
				(width 0.1)
				(type default)
			)
			(layer "F.Fab")
		)
		(pad "1" smd circle
			(at -0.40005 0 270)
			(size 0 0)
			(layers "F.Cu" "F.Mask" "F.Paste")
			(net "PEX0_SYS_ERR_R_N")
		)
		(pad "2" smd circle
			(at 0.40005 0 270)
			(size 0 0)
			(layers "F.Cu" "F.Mask" "F.Paste")
			(net "P1V8_PEX")
		)
	)
	(footprint ""
		(layer "F.Cu")
		(at 333.020416 -70.307454 90)
		(property "Reference" "PC858"
			(at 0 0 90)
			(layer "F.SilkS")
			(hide yes)
			(effects
				(font
					(size 1.27 1.27)
				)
			)
		)
		(property "Value" ""
			(at 0 0 90)
			(layer "F.Fab")
			(effects
				(font
					(size 1.27 1.27)
				)
			)
		)
		(duplicate_pad_numbers_are_jumpers no)
		(fp_line
			(start 0.7874 -0.4064)
			(end 0.7874 0.4064)
			(stroke
				(width 0.1524)
				(type default)
			)
			(layer "F.SilkS")
		)
		(fp_line
			(start -0.7874 -0.4064)
			(end 0.7874 -0.4064)
			(stroke
				(width 0.1524)
				(type default)
			)
			(layer "F.SilkS")
		)
		(fp_line
			(start 0.7874 0.4064)
			(end -0.7874 0.4064)
			(stroke
				(width 0.1524)
				(type default)
			)
			(layer "F.SilkS")
		)
		(fp_line
			(start -0.7874 0.4064)
			(end -0.7874 -0.4064)
			(stroke
				(width 0.1524)
				(type default)
			)
			(layer "F.SilkS")
		)
		(fp_line
			(start -0.12065 -0.305054)
			(end -0.12065 -0.2794)
			(stroke
				(width 0.1)
				(type default)
			)
			(layer "F.Fab")
		)
		(fp_line
			(start -0.67945 -0.305054)
			(end -0.12065 -0.305054)
			(stroke
				(width 0.1)
				(type default)
			)
			(layer "F.Fab")
		)
		(fp_line
			(start 0.67945 -0.3048)
			(end 0.67945 0.3048)
			(stroke
				(width 0.1)
				(type default)
			)
			(layer "F.Fab")
		)
		(fp_line
			(start 0.12065 -0.3048)
			(end 0.67945 -0.3048)
			(stroke
				(width 0.1)
				(type default)
			)
			(layer "F.Fab")
		)
		(fp_line
			(start 0.12065 -0.2794)
			(end 0.12065 -0.3048)
			(stroke
				(width 0.1)
				(type default)
			)
			(layer "F.Fab")
		)
		(fp_line
			(start -0.12065 -0.2794)
			(end 0.12065 -0.2794)
			(stroke
				(width 0.1)
				(type default)
			)
			(layer "F.Fab")
		)
		(fp_line
			(start 0.120396 0.2794)
			(end -0.12065 0.2794)
			(stroke
				(width 0.1)
				(type default)
			)
			(layer "F.Fab")
		)
		(fp_line
			(start -0.12065 0.2794)
			(end -0.12065 0.3048)
			(stroke
				(width 0.1)
				(type default)
			)
			(layer "F.Fab")
		)
		(fp_line
			(start 0.67945 0.3048)
			(end 0.120396 0.3048)
			(stroke
				(width 0.1)
				(type default)
			)
			(layer "F.Fab")
		)
		(fp_line
			(start 0.120396 0.3048)
			(end 0.120396 0.2794)
			(stroke
				(width 0.1)
				(type default)
			)
			(layer "F.Fab")
		)
		(fp_line
			(start -0.12065 0.3048)
			(end -0.67945 0.3048)
			(stroke
				(width 0.1)
				(type default)
			)
			(layer "F.Fab")
		)
		(fp_line
			(start -0.67945 0.3048)
			(end -0.67945 -0.305054)
			(stroke
				(width 0.1)
				(type default)
			)
			(layer "F.Fab")
		)
		(pad "1" smd circle
			(at -0.40005 0 90)
			(size 0 0)
			(layers "F.Cu" "F.Mask" "F.Paste")
			(net "P12V_AUX")
		)
		(pad "2" smd circle
			(at 0.40005 0 90)
			(size 0 0)
			(layers "F.Cu" "F.Mask" "F.Paste")
			(net "GND")
		)
	)
	(footprint ""
		(layer "F.Cu")
		(at 104.243632 -43.85691)
		(property "Reference" "R542"
			(at 0 0 0)
			(layer "F.SilkS")
			(hide yes)
			(effects
				(font
					(size 1.27 1.27)
				)
			)
		)
		(property "Value" ""
			(at 0 0 0)
			(layer "F.Fab")
			(effects
				(font
					(size 1.27 1.27)
				)
			)
		)
		(duplicate_pad_numbers_are_jumpers no)
		(fp_line
			(start -0.7874 -0.4064)
			(end 0.7874 -0.4064)
			(stroke
				(width 0.1524)
				(type default)
			)
			(layer "F.SilkS")
		)
		(fp_line
			(start -0.7874 0.4064)
			(end -0.7874 -0.4064)
			(stroke
				(width 0.1524)
				(type default)
			)
			(layer "F.SilkS")
		)
		(fp_line
			(start 0.7874 -0.4064)
			(end 0.7874 0.4064)
			(stroke
				(width 0.1524)
				(type default)
			)
			(layer "F.SilkS")
		)
		(fp_line
			(start 0.7874 0.4064)
			(end -0.7874 0.4064)
			(stroke
				(width 0.1524)
				(type default)
			)
			(layer "F.SilkS")
		)
		(fp_line
			(start -0.67945 -0.305054)
			(end -0.12065 -0.305054)
			(stroke
				(width 0.1)
				(type default)
			)
			(layer "F.Fab")
		)
		(fp_line
			(start -0.67945 0.3048)
			(end -0.67945 -0.305054)
			(stroke
				(width 0.1)
				(type default)
			)
			(layer "F.Fab")
		)
		(fp_line
			(start -0.12065 -0.305054)
			(end -0.12065 -0.2794)
			(stroke
				(width 0.1)
				(type default)
			)
			(layer "F.Fab")
		)
		(fp_line
			(start -0.12065 -0.2794)
			(end 0.12065 -0.2794)
			(stroke
				(width 0.1)
				(type default)
			)
			(layer "F.Fab")
		)
		(fp_line
			(start -0.12065 0.2794)
			(end -0.12065 0.3048)
			(stroke
				(width 0.1)
				(type default)
			)
			(layer "F.Fab")
		)
		(fp_line
			(start -0.12065 0.3048)
			(end -0.67945 0.3048)
			(stroke
				(width 0.1)
				(type default)
			)
			(layer "F.Fab")
		)
		(fp_line
			(start 0.120396 0.2794)
			(end -0.12065 0.2794)
			(stroke
				(width 0.1)
				(type default)
			)
			(layer "F.Fab")
		)
		(fp_line
			(start 0.120396 0.3048)
			(end 0.120396 0.2794)
			(stroke
				(width 0.1)
				(type default)
			)
			(layer "F.Fab")
		)
		(fp_line
			(start 0.12065 -0.3048)
			(end 0.67945 -0.3048)
			(stroke
				(width 0.1)
				(type default)
			)
			(layer "F.Fab")
		)
		(fp_line
			(start 0.12065 -0.2794)
			(end 0.12065 -0.3048)
			(stroke
				(width 0.1)
				(type default)
			)
			(layer "F.Fab")
		)
		(fp_line
			(start 0.67945 -0.3048)
			(end 0.67945 0.3048)
			(stroke
				(width 0.1)
				(type default)
			)
			(layer "F.Fab")
		)
		(fp_line
			(start 0.67945 0.3048)
			(end 0.120396 0.3048)
			(stroke
				(width 0.1)
				(type default)
			)
			(layer "F.Fab")
		)
		(pad "1" smd circle
			(at -0.40005 0)
			(size 0 0)
			(layers "F.Cu" "F.Mask" "F.Paste")
			(net "SSD3_ADC_A1")
		)
		(pad "2" smd circle
			(at 0.40005 0)
			(size 0 0)
			(layers "F.Cu" "F.Mask" "F.Paste")
			(net "GND")
		)
	)
	(footprint ""
		(layer "F.Cu")
		(at 108.204 -200.1012 -90)
		(property "Reference" "R6629"
			(at 0 0 270)
			(layer "F.SilkS")
			(hide yes)
			(effects
				(font
					(size 1.27 1.27)
				)
			)
		)
		(property "Value" ""
			(at 0 0 270)
			(layer "F.Fab")
			(effects
				(font
					(size 1.27 1.27)
				)
			)
		)
		(duplicate_pad_numbers_are_jumpers no)
		(fp_line
			(start -0.7874 0.4064)
			(end -0.7874 -0.4064)
			(stroke
				(width 0.1524)
				(type default)
			)
			(layer "F.SilkS")
		)
		(fp_line
			(start 0.7874 0.4064)
			(end -0.7874 0.4064)
			(stroke
				(width 0.1524)
				(type default)
			)
			(layer "F.SilkS")
		)
		(fp_line
			(start -0.7874 -0.4064)
			(end 0.7874 -0.4064)
			(stroke
				(width 0.1524)
				(type default)
			)
			(layer "F.SilkS")
		)
		(fp_line
			(start 0.7874 -0.4064)
			(end 0.7874 0.4064)
			(stroke
				(width 0.1524)
				(type default)
			)
			(layer "F.SilkS")
		)
		(fp_line
			(start -0.67945 0.3048)
			(end -0.67945 -0.305054)
			(stroke
				(width 0.1)
				(type default)
			)
			(layer "F.Fab")
		)
		(fp_line
			(start -0.12065 0.3048)
			(end -0.67945 0.3048)
			(stroke
				(width 0.1)
				(type default)
			)
			(layer "F.Fab")
		)
		(fp_line
			(start 0.120396 0.3048)
			(end 0.120396 0.2794)
			(stroke
				(width 0.1)
				(type default)
			)
			(layer "F.Fab")
		)
		(fp_line
			(start 0.67945 0.3048)
			(end 0.120396 0.3048)
			(stroke
				(width 0.1)
				(type default)
			)
			(layer "F.Fab")
		)
		(fp_line
			(start -0.12065 0.2794)
			(end -0.12065 0.3048)
			(stroke
				(width 0.1)
				(type default)
			)
			(layer "F.Fab")
		)
		(fp_line
			(start 0.120396 0.2794)
			(end -0.12065 0.2794)
			(stroke
				(width 0.1)
				(type default)
			)
			(layer "F.Fab")
		)
		(fp_line
			(start -0.12065 -0.2794)
			(end 0.12065 -0.2794)
			(stroke
				(width 0.1)
				(type default)
			)
			(layer "F.Fab")
		)
		(fp_line
			(start 0.12065 -0.2794)
			(end 0.12065 -0.3048)
			(stroke
				(width 0.1)
				(type default)
			)
			(layer "F.Fab")
		)
		(fp_line
			(start 0.12065 -0.3048)
			(end 0.67945 -0.3048)
			(stroke
				(width 0.1)
				(type default)
			)
			(layer "F.Fab")
		)
		(fp_line
			(start 0.67945 -0.3048)
			(end 0.67945 0.3048)
			(stroke
				(width 0.1)
				(type default)
			)
			(layer "F.Fab")
		)
		(fp_line
			(start -0.67945 -0.305054)
			(end -0.12065 -0.305054)
			(stroke
				(width 0.1)
				(type default)
			)
			(layer "F.Fab")
		)
		(fp_line
			(start -0.12065 -0.305054)
			(end -0.12065 -0.2794)
			(stroke
				(width 0.1)
				(type default)
			)
			(layer "F.Fab")
		)
		(pad "1" smd circle
			(at -0.40005 0 270)
			(size 0 0)
			(layers "F.Cu" "F.Mask" "F.Paste")
			(net "UART_PEX1_CLI_BUF_R_TX")
		)
		(pad "2" smd circle
			(at 0.40005 0 270)
			(size 0 0)
			(layers "F.Cu" "F.Mask" "F.Paste")
			(net "UART_PEX1_CLI_CP2108_TX")
		)
	)
	(footprint ""
		(layer "F.Cu")
		(at 240.83391 -156.288994 -90)
		(property "Reference" "PR7029"
			(at 0 0 270)
			(layer "F.SilkS")
			(hide yes)
			(effects
				(font
					(size 1.27 1.27)
				)
			)
		)
		(property "Value" ""
			(at 0 0 270)
			(layer "F.Fab")
			(effects
				(font
					(size 1.27 1.27)
				)
			)
		)
		(duplicate_pad_numbers_are_jumpers no)
		(fp_line
			(start -0.7874 0.4064)
			(end -0.7874 -0.4064)
			(stroke
				(width 0.1524)
				(type default)
			)
			(layer "F.SilkS")
		)
		(fp_line
			(start 0.7874 0.4064)
			(end -0.7874 0.4064)
			(stroke
				(width 0.1524)
				(type default)
			)
			(layer "F.SilkS")
		)
		(fp_line
			(start -0.7874 -0.4064)
			(end 0.7874 -0.4064)
			(stroke
				(width 0.1524)
				(type default)
			)
			(layer "F.SilkS")
		)
		(fp_line
			(start 0.7874 -0.4064)
			(end 0.7874 0.4064)
			(stroke
				(width 0.1524)
				(type default)
			)
			(layer "F.SilkS")
		)
		(fp_line
			(start -0.67945 0.3048)
			(end -0.67945 -0.305054)
			(stroke
				(width 0.1)
				(type default)
			)
			(layer "F.Fab")
		)
		(fp_line
			(start -0.12065 0.3048)
			(end -0.67945 0.3048)
			(stroke
				(width 0.1)
				(type default)
			)
			(layer "F.Fab")
		)
		(fp_line
			(start 0.120396 0.3048)
			(end 0.120396 0.2794)
			(stroke
				(width 0.1)
				(type default)
			)
			(layer "F.Fab")
		)
		(fp_line
			(start 0.67945 0.3048)
			(end 0.120396 0.3048)
			(stroke
				(width 0.1)
				(type default)
			)
			(layer "F.Fab")
		)
		(fp_line
			(start -0.12065 0.2794)
			(end -0.12065 0.3048)
			(stroke
				(width 0.1)
				(type default)
			)
			(layer "F.Fab")
		)
		(fp_line
			(start 0.120396 0.2794)
			(end -0.12065 0.2794)
			(stroke
				(width 0.1)
				(type default)
			)
			(layer "F.Fab")
		)
		(fp_line
			(start -0.12065 -0.2794)
			(end 0.12065 -0.2794)
			(stroke
				(width 0.1)
				(type default)
			)
			(layer "F.Fab")
		)
		(fp_line
			(start 0.12065 -0.2794)
			(end 0.12065 -0.3048)
			(stroke
				(width 0.1)
				(type default)
			)
			(layer "F.Fab")
		)
		(fp_line
			(start 0.12065 -0.3048)
			(end 0.67945 -0.3048)
			(stroke
				(width 0.1)
				(type default)
			)
			(layer "F.Fab")
		)
		(fp_line
			(start 0.67945 -0.3048)
			(end 0.67945 0.3048)
			(stroke
				(width 0.1)
				(type default)
			)
			(layer "F.Fab")
		)
		(fp_line
			(start -0.67945 -0.305054)
			(end -0.12065 -0.305054)
			(stroke
				(width 0.1)
				(type default)
			)
			(layer "F.Fab")
		)
		(fp_line
			(start -0.12065 -0.305054)
			(end -0.12065 -0.2794)
			(stroke
				(width 0.1)
				(type default)
			)
			(layer "F.Fab")
		)
		(pad "1" smd circle
			(at -0.40005 0 270)
			(size 0 0)
			(layers "F.Cu" "F.Mask" "F.Paste")
			(net "P12V_NIC4_CO_OV_FB")
		)
		(pad "2" smd circle
			(at 0.40005 0 270)
			(size 0 0)
			(layers "F.Cu" "F.Mask" "F.Paste")
			(net "GND")
		)
	)
	(footprint ""
		(layer "F.Cu")
		(at 452.543672 -49.95291 180)
		(property "Reference" "R676"
			(at 0 0 180)
			(layer "F.SilkS")
			(hide yes)
			(effects
				(font
					(size 1.27 1.27)
				)
			)
		)
		(property "Value" ""
			(at 0 0 180)
			(layer "F.Fab")
			(effects
				(font
					(size 1.27 1.27)
				)
			)
		)
		(duplicate_pad_numbers_are_jumpers no)
		(fp_line
			(start 0.7874 0.4064)
			(end -0.7874 0.4064)
			(stroke
				(width 0.1524)
				(type default)
			)
			(layer "F.SilkS")
		)
		(fp_line
			(start 0.7874 -0.4064)
			(end 0.7874 0.4064)
			(stroke
				(width 0.1524)
				(type default)
			)
			(layer "F.SilkS")
		)
		(fp_line
			(start -0.7874 0.4064)
			(end -0.7874 -0.4064)
			(stroke
				(width 0.1524)
				(type default)
			)
			(layer "F.SilkS")
		)
		(fp_line
			(start -0.7874 -0.4064)
			(end 0.7874 -0.4064)
			(stroke
				(width 0.1524)
				(type default)
			)
			(layer "F.SilkS")
		)
		(fp_line
			(start 0.67945 0.3048)
			(end 0.120396 0.3048)
			(stroke
				(width 0.1)
				(type default)
			)
			(layer "F.Fab")
		)
		(fp_line
			(start 0.67945 -0.3048)
			(end 0.67945 0.3048)
			(stroke
				(width 0.1)
				(type default)
			)
			(layer "F.Fab")
		)
		(fp_line
			(start 0.12065 -0.2794)
			(end 0.12065 -0.3048)
			(stroke
				(width 0.1)
				(type default)
			)
			(layer "F.Fab")
		)
		(fp_line
			(start 0.12065 -0.3048)
			(end 0.67945 -0.3048)
			(stroke
				(width 0.1)
				(type default)
			)
			(layer "F.Fab")
		)
		(fp_line
			(start 0.120396 0.3048)
			(end 0.120396 0.2794)
			(stroke
				(width 0.1)
				(type default)
			)
			(layer "F.Fab")
		)
		(fp_line
			(start 0.120396 0.2794)
			(end -0.12065 0.2794)
			(stroke
				(width 0.1)
				(type default)
			)
			(layer "F.Fab")
		)
		(fp_line
			(start -0.12065 0.3048)
			(end -0.67945 0.3048)
			(stroke
				(width 0.1)
				(type default)
			)
			(layer "F.Fab")
		)
		(fp_line
			(start -0.12065 0.2794)
			(end -0.12065 0.3048)
			(stroke
				(width 0.1)
				(type default)
			)
			(layer "F.Fab")
		)
		(fp_line
			(start -0.12065 -0.2794)
			(end 0.12065 -0.2794)
			(stroke
				(width 0.1)
				(type default)
			)
			(layer "F.Fab")
		)
		(fp_line
			(start -0.12065 -0.305054)
			(end -0.12065 -0.2794)
			(stroke
				(width 0.1)
				(type default)
			)
			(layer "F.Fab")
		)
		(fp_line
			(start -0.67945 0.3048)
			(end -0.67945 -0.305054)
			(stroke
				(width 0.1)
				(type default)
			)
			(layer "F.Fab")
		)
		(fp_line
			(start -0.67945 -0.305054)
			(end -0.12065 -0.305054)
			(stroke
				(width 0.1)
				(type default)
			)
			(layer "F.Fab")
		)
		(pad "1" smd circle
			(at -0.40005 0 180)
			(size 0 0)
			(layers "F.Cu" "F.Mask" "F.Paste")
			(net "SMB_BIC_I2C6_MUX_SSD_8_15_ADC_R_SCL")
		)
		(pad "2" smd circle
			(at 0.40005 0 180)
			(size 0 0)
			(layers "F.Cu" "F.Mask" "F.Paste")
			(net "SMB_SSD15_ADC_SCL")
		)
	)
	(footprint ""
		(layer "F.Cu")
		(at 461.776572 -268.422882)
		(property "Reference" "C4392"
			(at 0 0 0)
			(layer "F.SilkS")
			(hide yes)
			(effects
				(font
					(size 1.27 1.27)
				)
			)
		)
		(property "Value" ""
			(at 0 0 0)
			(layer "F.Fab")
			(effects
				(font
					(size 1.27 1.27)
				)
			)
		)
		(duplicate_pad_numbers_are_jumpers no)
		(fp_line
			(start -0.299974 -0.150114)
			(end 0.299974 -0.150114)
			(stroke
				(width 0.1)
				(type default)
			)
			(layer "F.Fab")
		)
		(fp_line
			(start -0.299974 0.150114)
			(end -0.299974 -0.150114)
			(stroke
				(width 0.1)
				(type default)
			)
			(layer "F.Fab")
		)
		(fp_line
			(start 0.299974 -0.150114)
			(end 0.299974 0.150114)
			(stroke
				(width 0.1)
				(type default)
			)
			(layer "F.Fab")
		)
		(fp_line
			(start 0.299974 0.150114)
			(end -0.299974 0.150114)
			(stroke
				(width 0.1)
				(type default)
			)
			(layer "F.Fab")
		)
		(pad "1" smd rect
			(at -0.2667 0)
			(size 0.3048 0.381)
			(layers "F.Cu" "F.Mask" "F.Paste")
			(net "P1V25_SERDES_VDDPLL_PEX3")
		)
		(pad "2" smd rect
			(at 0.2667 0)
			(size 0.3048 0.381)
			(layers "F.Cu" "F.Mask" "F.Paste")
			(net "GND")
		)
	)
	(footprint ""
		(layer "F.Cu")
		(at 13.206222 -134.434326)
		(property "Reference" "PC352"
			(at 0 0 0)
			(layer "F.SilkS")
			(hide yes)
			(effects
				(font
					(size 1.27 1.27)
				)
			)
		)
		(property "Value" ""
			(at 0 0 0)
			(layer "F.Fab")
			(effects
				(font
					(size 1.27 1.27)
				)
			)
		)
		(duplicate_pad_numbers_are_jumpers no)
		(fp_line
			(start -0.7874 -0.4064)
			(end 0.7874 -0.4064)
			(stroke
				(width 0.1524)
				(type default)
			)
			(layer "F.SilkS")
		)
		(fp_line
			(start -0.7874 0.4064)
			(end -0.7874 -0.4064)
			(stroke
				(width 0.1524)
				(type default)
			)
			(layer "F.SilkS")
		)
		(fp_line
			(start 0.7874 -0.4064)
			(end 0.7874 0.4064)
			(stroke
				(width 0.1524)
				(type default)
			)
			(layer "F.SilkS")
		)
		(fp_line
			(start 0.7874 0.4064)
			(end -0.7874 0.4064)
			(stroke
				(width 0.1524)
				(type default)
			)
			(layer "F.SilkS")
		)
		(fp_line
			(start -0.67945 -0.305054)
			(end -0.12065 -0.305054)
			(stroke
				(width 0.1)
				(type default)
			)
			(layer "F.Fab")
		)
		(fp_line
			(start -0.67945 0.3048)
			(end -0.67945 -0.305054)
			(stroke
				(width 0.1)
				(type default)
			)
			(layer "F.Fab")
		)
		(fp_line
			(start -0.12065 -0.305054)
			(end -0.12065 -0.2794)
			(stroke
				(width 0.1)
				(type default)
			)
			(layer "F.Fab")
		)
		(fp_line
			(start -0.12065 -0.2794)
			(end 0.12065 -0.2794)
			(stroke
				(width 0.1)
				(type default)
			)
			(layer "F.Fab")
		)
		(fp_line
			(start -0.12065 0.2794)
			(end -0.12065 0.3048)
			(stroke
				(width 0.1)
				(type default)
			)
			(layer "F.Fab")
		)
		(fp_line
			(start -0.12065 0.3048)
			(end -0.67945 0.3048)
			(stroke
				(width 0.1)
				(type default)
			)
			(layer "F.Fab")
		)
		(fp_line
			(start 0.120396 0.2794)
			(end -0.12065 0.2794)
			(stroke
				(width 0.1)
				(type default)
			)
			(layer "F.Fab")
		)
		(fp_line
			(start 0.120396 0.3048)
			(end 0.120396 0.2794)
			(stroke
				(width 0.1)
				(type default)
			)
			(layer "F.Fab")
		)
		(fp_line
			(start 0.12065 -0.3048)
			(end 0.67945 -0.3048)
			(stroke
				(width 0.1)
				(type default)
			)
			(layer "F.Fab")
		)
		(fp_line
			(start 0.12065 -0.2794)
			(end 0.12065 -0.3048)
			(stroke
				(width 0.1)
				(type default)
			)
			(layer "F.Fab")
		)
		(fp_line
			(start 0.67945 -0.3048)
			(end 0.67945 0.3048)
			(stroke
				(width 0.1)
				(type default)
			)
			(layer "F.Fab")
		)
		(fp_line
			(start 0.67945 0.3048)
			(end 0.120396 0.3048)
			(stroke
				(width 0.1)
				(type default)
			)
			(layer "F.Fab")
		)
		(pad "1" smd circle
			(at -0.40005 0)
			(size 0 0)
			(layers "F.Cu" "F.Mask" "F.Paste")
			(net "P12V_AUX")
		)
		(pad "2" smd circle
			(at 0.40005 0)
			(size 0 0)
			(layers "F.Cu" "F.Mask" "F.Paste")
			(net "GND")
		)
	)
	(footprint ""
		(layer "F.Cu")
		(at 102.02926 -277.639272 180)
		(property "Reference" "PC61"
			(at 0 0 180)
			(layer "F.SilkS")
			(hide yes)
			(effects
				(font
					(size 1.27 1.27)
				)
			)
		)
		(property "Value" ""
			(at 0 0 180)
			(layer "F.Fab")
			(effects
				(font
					(size 1.27 1.27)
				)
			)
		)
		(duplicate_pad_numbers_are_jumpers no)
		(fp_line
			(start 1.524 0.762)
			(end -1.524 0.762)
			(stroke
				(width 0.1524)
				(type default)
			)
			(layer "F.SilkS")
		)
		(fp_line
			(start 1.524 -0.762)
			(end 1.524 0.762)
			(stroke
				(width 0.1524)
				(type default)
			)
			(layer "F.SilkS")
		)
		(fp_line
			(start -1.524 0.762)
			(end -1.524 -0.762)
			(stroke
				(width 0.1524)
				(type default)
			)
			(layer "F.SilkS")
		)
		(fp_line
			(start -1.524 -0.762)
			(end 1.524 -0.762)
			(stroke
				(width 0.1524)
				(type default)
			)
			(layer "F.SilkS")
		)
		(fp_line
			(start 1.1049 0.724916)
			(end 1.1049 -0.724916)
			(stroke
				(width 0.1)
				(type default)
			)
			(layer "F.Fab")
		)
		(fp_line
			(start 1.1049 -0.724916)
			(end -1.1049 -0.724916)
			(stroke
				(width 0.1)
				(type default)
			)
			(layer "F.Fab")
		)
		(fp_line
			(start -1.1049 0.724916)
			(end 1.1049 0.724916)
			(stroke
				(width 0.1)
				(type default)
			)
			(layer "F.Fab")
		)
		(fp_line
			(start -1.1049 -0.724916)
			(end -1.1049 0.724916)
			(stroke
				(width 0.1)
				(type default)
			)
			(layer "F.Fab")
		)
		(pad "1" smd rect
			(at -0.889 0)
			(size 1.016 1.27)
			(layers "F.Cu" "F.Mask" "F.Paste")
			(net "SW_P12V_P0V8_PEX0_FLT")
		)
		(pad "2" smd rect
			(at 0.889 0)
			(size 1.016 1.27)
			(layers "F.Cu" "F.Mask" "F.Paste")
			(net "GND")
		)
	)
	(footprint ""
		(layer "F.Cu")
		(at 418.092382 -29.139642 180)
		(property "Reference" "C720"
			(at 0 0 180)
			(layer "F.SilkS")
			(hide yes)
			(effects
				(font
					(size 1.27 1.27)
				)
			)
		)
		(property "Value" ""
			(at 0 0 180)
			(layer "F.Fab")
			(effects
				(font
					(size 1.27 1.27)
				)
			)
		)
		(duplicate_pad_numbers_are_jumpers no)
		(fp_line
			(start 0.299974 0.150114)
			(end -0.299974 0.150114)
			(stroke
				(width 0.1)
				(type default)
			)
			(layer "F.Fab")
		)
		(fp_line
			(start 0.299974 -0.150114)
			(end 0.299974 0.150114)
			(stroke
				(width 0.1)
				(type default)
			)
			(layer "F.Fab")
		)
		(fp_line
			(start -0.299974 0.150114)
			(end -0.299974 -0.150114)
			(stroke
				(width 0.1)
				(type default)
			)
			(layer "F.Fab")
		)
		(fp_line
			(start -0.299974 -0.150114)
			(end 0.299974 -0.150114)
			(stroke
				(width 0.1)
				(type default)
			)
			(layer "F.Fab")
		)
		(pad "1" smd rect
			(at -0.2667 0 180)
			(size 0.3048 0.381)
			(layers "F.Cu" "F.Mask" "F.Paste")
			(net "P5E_PEX3_STN2_TX_DP<36>")
		)
		(pad "2" smd rect
			(at 0.2667 0 180)
			(size 0.3048 0.381)
			(layers "F.Cu" "F.Mask" "F.Paste")
			(net "P5E_PEX3_STN2_TX_C_DP<36>")
		)
	)
	(footprint ""
		(layer "F.Cu")
		(at 194.684142 -29.222954 -90)
		(property "Reference" "PC929"
			(at 0 0 270)
			(layer "F.SilkS")
			(hide yes)
			(effects
				(font
					(size 1.27 1.27)
				)
			)
		)
		(property "Value" ""
			(at 0 0 270)
			(layer "F.Fab")
			(effects
				(font
					(size 1.27 1.27)
				)
			)
		)
		(duplicate_pad_numbers_are_jumpers no)
		(fp_line
			(start -0.7874 0.4064)
			(end -0.7874 -0.4064)
			(stroke
				(width 0.1524)
				(type default)
			)
			(layer "F.SilkS")
		)
		(fp_line
			(start 0.7874 0.4064)
			(end -0.7874 0.4064)
			(stroke
				(width 0.1524)
				(type default)
			)
			(layer "F.SilkS")
		)
		(fp_line
			(start -0.7874 -0.4064)
			(end 0.7874 -0.4064)
			(stroke
				(width 0.1524)
				(type default)
			)
			(layer "F.SilkS")
		)
		(fp_line
			(start 0.7874 -0.4064)
			(end 0.7874 0.4064)
			(stroke
				(width 0.1524)
				(type default)
			)
			(layer "F.SilkS")
		)
		(fp_line
			(start -0.67945 0.3048)
			(end -0.67945 -0.305054)
			(stroke
				(width 0.1)
				(type default)
			)
			(layer "F.Fab")
		)
		(fp_line
			(start -0.12065 0.3048)
			(end -0.67945 0.3048)
			(stroke
				(width 0.1)
				(type default)
			)
			(layer "F.Fab")
		)
		(fp_line
			(start 0.120396 0.3048)
			(end 0.120396 0.2794)
			(stroke
				(width 0.1)
				(type default)
			)
			(layer "F.Fab")
		)
		(fp_line
			(start 0.67945 0.3048)
			(end 0.120396 0.3048)
			(stroke
				(width 0.1)
				(type default)
			)
			(layer "F.Fab")
		)
		(fp_line
			(start -0.12065 0.2794)
			(end -0.12065 0.3048)
			(stroke
				(width 0.1)
				(type default)
			)
			(layer "F.Fab")
		)
		(fp_line
			(start 0.120396 0.2794)
			(end -0.12065 0.2794)
			(stroke
				(width 0.1)
				(type default)
			)
			(layer "F.Fab")
		)
		(fp_line
			(start -0.12065 -0.2794)
			(end 0.12065 -0.2794)
			(stroke
				(width 0.1)
				(type default)
			)
			(layer "F.Fab")
		)
		(fp_line
			(start 0.12065 -0.2794)
			(end 0.12065 -0.3048)
			(stroke
				(width 0.1)
				(type default)
			)
			(layer "F.Fab")
		)
		(fp_line
			(start 0.12065 -0.3048)
			(end 0.67945 -0.3048)
			(stroke
				(width 0.1)
				(type default)
			)
			(layer "F.Fab")
		)
		(fp_line
			(start 0.67945 -0.3048)
			(end 0.67945 0.3048)
			(stroke
				(width 0.1)
				(type default)
			)
			(layer "F.Fab")
		)
		(fp_line
			(start -0.67945 -0.305054)
			(end -0.12065 -0.305054)
			(stroke
				(width 0.1)
				(type default)
			)
			(layer "F.Fab")
		)
		(fp_line
			(start -0.12065 -0.305054)
			(end -0.12065 -0.2794)
			(stroke
				(width 0.1)
				(type default)
			)
			(layer "F.Fab")
		)
		(pad "1" smd circle
			(at -0.40005 0 270)
			(size 0 0)
			(layers "F.Cu" "F.Mask" "F.Paste")
			(net "P3V3_AUX")
		)
		(pad "2" smd circle
			(at 0.40005 0 270)
			(size 0 0)
			(layers "F.Cu" "F.Mask" "F.Paste")
			(net "GND")
		)
	)
	(footprint ""
		(layer "F.Cu")
		(at 148.991066 -55.663846 90)
		(property "Reference" "PU57"
			(at -1.267206 2.93878 90)
			(unlocked yes)
			(layer "F.SilkS")
			(effects
				(font
					(size 0.7874 0.5842)
					(thickness 0.1524)
				)
				(justify left)
			)
		)
		(property "Value" ""
			(at 0 0 90)
			(layer "F.Fab")
			(effects
				(font
					(size 1.27 1.27)
				)
			)
		)
		(duplicate_pad_numbers_are_jumpers no)
		(fp_line
			(start 1.943608 -1.549908)
			(end 1.943608 1.549908)
			(stroke
				(width 0.1524)
				(type default)
			)
			(layer "F.SilkS")
		)
		(fp_line
			(start -1.943608 -1.549908)
			(end 1.943608 -1.549908)
			(stroke
				(width 0.1524)
				(type default)
			)
			(layer "F.SilkS")
		)
		(fp_line
			(start 1.943608 1.549908)
			(end -1.943608 1.549908)
			(stroke
				(width 0.1524)
				(type default)
			)
			(layer "F.SilkS")
		)
		(fp_line
			(start -1.943608 1.549908)
			(end -1.943608 -1.549908)
			(stroke
				(width 0.1524)
				(type default)
			)
			(layer "F.SilkS")
		)
		(fp_poly
			(pts
				(xy -2.019808 -1.549908) (xy -1.257808 -1.549908) (xy -1.257808 -1.880108) (xy -2.019808 -1.880108)
			)
			(stroke
				(width 0)
				(type default)
			)
			(fill yes)
			(layer "F.SilkS")
		)
		(fp_line
			(start 1.549908 -1.549908)
			(end 1.549908 1.549908)
			(stroke
				(width 0.1)
				(type default)
			)
			(layer "F.Fab")
		)
		(fp_line
			(start -1.549908 -1.549908)
			(end 1.549908 -1.549908)
			(stroke
				(width 0.1)
				(type default)
			)
			(layer "F.Fab")
		)
		(fp_line
			(start 1.549908 1.549908)
			(end -1.549908 1.549908)
			(stroke
				(width 0.1)
				(type default)
			)
			(layer "F.Fab")
		)
		(fp_line
			(start -1.549908 1.549908)
			(end -1.549908 -1.549908)
			(stroke
				(width 0.1)
				(type default)
			)
			(layer "F.Fab")
		)
		(fp_poly
			(pts
				(xy -2.019808 -1.549908) (xy -1.257808 -1.549908) (xy -1.257808 -1.880108) (xy -2.019808 -1.880108)
			)
			(stroke
				(width 0)
				(type default)
			)
			(fill yes)
			(layer "F.Fab")
		)
		(pad "1" smd rect
			(at -1.500124 -1.249934)
			(size 0.2794 0.6096)
			(layers "F.Cu" "F.Mask" "F.Paste")
			(net "P3V3_SSD5")
		)
		(pad "2" smd rect
			(at -1.500124 -0.750062)
			(size 0.2794 0.6096)
			(layers "F.Cu" "F.Mask" "F.Paste")
			(net "P3V3_SSD5")
		)
		(pad "3" smd rect
			(at -1.500124 -0.249936)
			(size 0.2794 0.6096)
			(layers "F.Cu" "F.Mask" "F.Paste")
			(net "P3V3_SSD5")
		)
		(pad "4" smd rect
			(at -1.500124 0.249936)
			(size 0.2794 0.6096)
			(layers "F.Cu" "F.Mask" "F.Paste")
			(net "P3V3_SSD5")
		)
		(pad "5" smd rect
			(at -1.500124 0.750062)
			(size 0.2794 0.6096)
			(layers "F.Cu" "F.Mask" "F.Paste")
			(net "P3V3_SSD5")
		)
		(pad "6" smd rect
			(at -1.500124 1.249934)
			(size 0.2794 0.6096)
			(layers "F.Cu" "F.Mask" "F.Paste")
			(net "GND")
		)
		(pad "7" smd rect
			(at 1.500124 1.249934)
			(size 0.2794 0.6096)
			(layers "F.Cu" "F.Mask" "F.Paste")
			(net "P3V3_SSD5_SS")
		)
		(pad "8" smd rect
			(at 1.500124 0.750062)
			(size 0.2794 0.6096)
			(layers "F.Cu" "F.Mask" "F.Paste")
			(net "PWRGD_P3V3_SSD5")
		)
		(pad "9" smd rect
			(at 1.500124 0.249936)
			(size 0.2794 0.6096)
			(layers "F.Cu" "F.Mask" "F.Paste")
			(net "P3V3_SSD5_OCP")
		)
		(pad "10" smd rect
			(at 1.500124 -0.249936)
			(size 0.2794 0.6096)
			(layers "F.Cu" "F.Mask" "F.Paste")
			(net "P5V_AUX")
		)
		(pad "11" smd rect
			(at 1.500124 -0.750062)
			(size 0.2794 0.6096)
			(layers "F.Cu" "F.Mask" "F.Paste")
			(net "SSD5_AUX_P3V3_EN_R")
		)
		(pad "12" smd rect
			(at 1.500124 -1.249934)
			(size 0.2794 0.6096)
			(layers "F.Cu" "F.Mask" "F.Paste")
			(net "P3V3_AUX")
		)
		(pad "13" smd rect
			(at 0 0 90)
			(size 1.9812 2.7178)
			(layers "F.Cu" "F.Mask" "F.Paste")
			(net "P3V3_AUX")
		)
		(zone
			(layer "F.Cu")
			(hatch none 0.5)
			(connect_pads
				(clearance 0)
			)
			(min_thickness 0.25)
			(keepout
				(tracks not_allowed)
				(vias allowed)
				(pads allowed)
				(copperpour not_allowed)
				(footprints allowed)
			)
			(placement
				(enabled no)
				(sheetname "")
			)
			(fill
				(thermal_gap 0.5)
				(thermal_bridge_width 0.5)
				(island_removal_mode 0)
			)
			(polygon
				(pts
					(xy 147.441666 -56.806846) (xy 147.568666 -56.806846) (xy 150.540466 -56.806846) (xy 150.540974 -56.806846)
					(xy 150.540974 -54.520846) (xy 150.540466 -54.520846) (xy 150.413466 -54.520846) (xy 148.991066 -54.520846)
					(xy 148.991066 -54.622446) (xy 150.413466 -54.622446) (xy 150.413466 -56.705246) (xy 147.568666 -56.705246)
					(xy 147.568666 -54.622446) (xy 148.965666 -54.622446) (xy 148.965666 -54.520846) (xy 147.568666 -54.520846)
					(xy 147.441666 -54.520846) (xy 147.441158 -54.520846) (xy 147.441158 -56.806846)
				)
			)
		)
	)
	(footprint ""
		(layer "F.Cu")
		(at 230.156512 -243.22786 90)
		(property "Reference" "R6257"
			(at 0 0 90)
			(layer "F.SilkS")
			(hide yes)
			(effects
				(font
					(size 1.27 1.27)
				)
			)
		)
		(property "Value" ""
			(at 0 0 90)
			(layer "F.Fab")
			(effects
				(font
					(size 1.27 1.27)
				)
			)
		)
		(duplicate_pad_numbers_are_jumpers no)
		(fp_line
			(start 0.7874 -0.4064)
			(end 0.7874 0.4064)
			(stroke
				(width 0.1524)
				(type default)
			)
			(layer "F.SilkS")
		)
		(fp_line
			(start -0.7874 -0.4064)
			(end 0.7874 -0.4064)
			(stroke
				(width 0.1524)
				(type default)
			)
			(layer "F.SilkS")
		)
		(fp_line
			(start 0.7874 0.4064)
			(end -0.7874 0.4064)
			(stroke
				(width 0.1524)
				(type default)
			)
			(layer "F.SilkS")
		)
		(fp_line
			(start -0.7874 0.4064)
			(end -0.7874 -0.4064)
			(stroke
				(width 0.1524)
				(type default)
			)
			(layer "F.SilkS")
		)
		(fp_line
			(start -0.12065 -0.305054)
			(end -0.12065 -0.2794)
			(stroke
				(width 0.1)
				(type default)
			)
			(layer "F.Fab")
		)
		(fp_line
			(start -0.67945 -0.305054)
			(end -0.12065 -0.305054)
			(stroke
				(width 0.1)
				(type default)
			)
			(layer "F.Fab")
		)
		(fp_line
			(start 0.67945 -0.3048)
			(end 0.67945 0.3048)
			(stroke
				(width 0.1)
				(type default)
			)
			(layer "F.Fab")
		)
		(fp_line
			(start 0.12065 -0.3048)
			(end 0.67945 -0.3048)
			(stroke
				(width 0.1)
				(type default)
			)
			(layer "F.Fab")
		)
		(fp_line
			(start 0.12065 -0.2794)
			(end 0.12065 -0.3048)
			(stroke
				(width 0.1)
				(type default)
			)
			(layer "F.Fab")
		)
		(fp_line
			(start -0.12065 -0.2794)
			(end 0.12065 -0.2794)
			(stroke
				(width 0.1)
				(type default)
			)
			(layer "F.Fab")
		)
		(fp_line
			(start 0.120396 0.2794)
			(end -0.12065 0.2794)
			(stroke
				(width 0.1)
				(type default)
			)
			(layer "F.Fab")
		)
		(fp_line
			(start -0.12065 0.2794)
			(end -0.12065 0.3048)
			(stroke
				(width 0.1)
				(type default)
			)
			(layer "F.Fab")
		)
		(fp_line
			(start 0.67945 0.3048)
			(end 0.120396 0.3048)
			(stroke
				(width 0.1)
				(type default)
			)
			(layer "F.Fab")
		)
		(fp_line
			(start 0.120396 0.3048)
			(end 0.120396 0.2794)
			(stroke
				(width 0.1)
				(type default)
			)
			(layer "F.Fab")
		)
		(fp_line
			(start -0.12065 0.3048)
			(end -0.67945 0.3048)
			(stroke
				(width 0.1)
				(type default)
			)
			(layer "F.Fab")
		)
		(fp_line
			(start -0.67945 0.3048)
			(end -0.67945 -0.305054)
			(stroke
				(width 0.1)
				(type default)
			)
			(layer "F.Fab")
		)
		(pad "1" smd circle
			(at -0.40005 0 90)
			(size 0 0)
			(layers "F.Cu" "F.Mask" "F.Paste")
			(net "P3V3_AUX")
		)
		(pad "2" smd circle
			(at 0.40005 0 90)
			(size 0 0)
			(layers "F.Cu" "F.Mask" "F.Paste")
			(net "BIC_UART_BMC_SEL_R")
		)
	)
	(footprint ""
		(layer "F.Cu")
		(at 426.543724 -44.87291)
		(property "Reference" "R660"
			(at 0 0 0)
			(layer "F.SilkS")
			(hide yes)
			(effects
				(font
					(size 1.27 1.27)
				)
			)
		)
		(property "Value" ""
			(at 0 0 0)
			(layer "F.Fab")
			(effects
				(font
					(size 1.27 1.27)
				)
			)
		)
		(duplicate_pad_numbers_are_jumpers no)
		(fp_line
			(start -0.7874 -0.4064)
			(end 0.7874 -0.4064)
			(stroke
				(width 0.1524)
				(type default)
			)
			(layer "F.SilkS")
		)
		(fp_line
			(start -0.7874 0.4064)
			(end -0.7874 -0.4064)
			(stroke
				(width 0.1524)
				(type default)
			)
			(layer "F.SilkS")
		)
		(fp_line
			(start 0.7874 -0.4064)
			(end 0.7874 0.4064)
			(stroke
				(width 0.1524)
				(type default)
			)
			(layer "F.SilkS")
		)
		(fp_line
			(start 0.7874 0.4064)
			(end -0.7874 0.4064)
			(stroke
				(width 0.1524)
				(type default)
			)
			(layer "F.SilkS")
		)
		(fp_line
			(start -0.67945 -0.305054)
			(end -0.12065 -0.305054)
			(stroke
				(width 0.1)
				(type default)
			)
			(layer "F.Fab")
		)
		(fp_line
			(start -0.67945 0.3048)
			(end -0.67945 -0.305054)
			(stroke
				(width 0.1)
				(type default)
			)
			(layer "F.Fab")
		)
		(fp_line
			(start -0.12065 -0.305054)
			(end -0.12065 -0.2794)
			(stroke
				(width 0.1)
				(type default)
			)
			(layer "F.Fab")
		)
		(fp_line
			(start -0.12065 -0.2794)
			(end 0.12065 -0.2794)
			(stroke
				(width 0.1)
				(type default)
			)
			(layer "F.Fab")
		)
		(fp_line
			(start -0.12065 0.2794)
			(end -0.12065 0.3048)
			(stroke
				(width 0.1)
				(type default)
			)
			(layer "F.Fab")
		)
		(fp_line
			(start -0.12065 0.3048)
			(end -0.67945 0.3048)
			(stroke
				(width 0.1)
				(type default)
			)
			(layer "F.Fab")
		)
		(fp_line
			(start 0.120396 0.2794)
			(end -0.12065 0.2794)
			(stroke
				(width 0.1)
				(type default)
			)
			(layer "F.Fab")
		)
		(fp_line
			(start 0.120396 0.3048)
			(end 0.120396 0.2794)
			(stroke
				(width 0.1)
				(type default)
			)
			(layer "F.Fab")
		)
		(fp_line
			(start 0.12065 -0.3048)
			(end 0.67945 -0.3048)
			(stroke
				(width 0.1)
				(type default)
			)
			(layer "F.Fab")
		)
		(fp_line
			(start 0.12065 -0.2794)
			(end 0.12065 -0.3048)
			(stroke
				(width 0.1)
				(type default)
			)
			(layer "F.Fab")
		)
		(fp_line
			(start 0.67945 -0.3048)
			(end 0.67945 0.3048)
			(stroke
				(width 0.1)
				(type default)
			)
			(layer "F.Fab")
		)
		(fp_line
			(start 0.67945 0.3048)
			(end 0.120396 0.3048)
			(stroke
				(width 0.1)
				(type default)
			)
			(layer "F.Fab")
		)
		(pad "1" smd circle
			(at -0.40005 0)
			(size 0 0)
			(layers "F.Cu" "F.Mask" "F.Paste")
			(net "SSD14_ADC_A0")
		)
		(pad "2" smd circle
			(at 0.40005 0)
			(size 0 0)
			(layers "F.Cu" "F.Mask" "F.Paste")
			(net "P3V3_AUX")
		)
	)
	(footprint ""
		(layer "F.Cu")
		(at 284.467808 -56.353456)
		(property "Reference" "C2871"
			(at 0 0 0)
			(layer "F.SilkS")
			(hide yes)
			(effects
				(font
					(size 1.27 1.27)
				)
			)
		)
		(property "Value" ""
			(at 0 0 0)
			(layer "F.Fab")
			(effects
				(font
					(size 1.27 1.27)
				)
			)
		)
		(duplicate_pad_numbers_are_jumpers no)
		(fp_line
			(start -0.7874 -0.4064)
			(end 0.7874 -0.4064)
			(stroke
				(width 0.1524)
				(type default)
			)
			(layer "F.SilkS")
		)
		(fp_line
			(start -0.7874 0.4064)
			(end -0.7874 -0.4064)
			(stroke
				(width 0.1524)
				(type default)
			)
			(layer "F.SilkS")
		)
		(fp_line
			(start 0.7874 -0.4064)
			(end 0.7874 0.4064)
			(stroke
				(width 0.1524)
				(type default)
			)
			(layer "F.SilkS")
		)
		(fp_line
			(start 0.7874 0.4064)
			(end -0.7874 0.4064)
			(stroke
				(width 0.1524)
				(type default)
			)
			(layer "F.SilkS")
		)
		(fp_line
			(start -0.67945 -0.305054)
			(end -0.12065 -0.305054)
			(stroke
				(width 0.1)
				(type default)
			)
			(layer "F.Fab")
		)
		(fp_line
			(start -0.67945 0.3048)
			(end -0.67945 -0.305054)
			(stroke
				(width 0.1)
				(type default)
			)
			(layer "F.Fab")
		)
		(fp_line
			(start -0.12065 -0.305054)
			(end -0.12065 -0.2794)
			(stroke
				(width 0.1)
				(type default)
			)
			(layer "F.Fab")
		)
		(fp_line
			(start -0.12065 -0.2794)
			(end 0.12065 -0.2794)
			(stroke
				(width 0.1)
				(type default)
			)
			(layer "F.Fab")
		)
		(fp_line
			(start -0.12065 0.2794)
			(end -0.12065 0.3048)
			(stroke
				(width 0.1)
				(type default)
			)
			(layer "F.Fab")
		)
		(fp_line
			(start -0.12065 0.3048)
			(end -0.67945 0.3048)
			(stroke
				(width 0.1)
				(type default)
			)
			(layer "F.Fab")
		)
		(fp_line
			(start 0.120396 0.2794)
			(end -0.12065 0.2794)
			(stroke
				(width 0.1)
				(type default)
			)
			(layer "F.Fab")
		)
		(fp_line
			(start 0.120396 0.3048)
			(end 0.120396 0.2794)
			(stroke
				(width 0.1)
				(type default)
			)
			(layer "F.Fab")
		)
		(fp_line
			(start 0.12065 -0.3048)
			(end 0.67945 -0.3048)
			(stroke
				(width 0.1)
				(type default)
			)
			(layer "F.Fab")
		)
		(fp_line
			(start 0.12065 -0.2794)
			(end 0.12065 -0.3048)
			(stroke
				(width 0.1)
				(type default)
			)
			(layer "F.Fab")
		)
		(fp_line
			(start 0.67945 -0.3048)
			(end 0.67945 0.3048)
			(stroke
				(width 0.1)
				(type default)
			)
			(layer "F.Fab")
		)
		(fp_line
			(start 0.67945 0.3048)
			(end 0.120396 0.3048)
			(stroke
				(width 0.1)
				(type default)
			)
			(layer "F.Fab")
		)
		(pad "1" smd circle
			(at -0.40005 0)
			(size 0 0)
			(layers "F.Cu" "F.Mask" "F.Paste")
			(net "SSD9_PWR_EN_R")
		)
		(pad "2" smd circle
			(at 0.40005 0)
			(size 0 0)
			(layers "F.Cu" "F.Mask" "F.Paste")
			(net "GND")
		)
	)
	(footprint ""
		(layer "F.Cu")
		(at 127.624332 -259.145532 180)
		(property "Reference" "PR7165"
			(at 0 0 180)
			(layer "F.SilkS")
			(hide yes)
			(effects
				(font
					(size 1.27 1.27)
				)
			)
		)
		(property "Value" ""
			(at 0 0 180)
			(layer "F.Fab")
			(effects
				(font
					(size 1.27 1.27)
				)
			)
		)
		(duplicate_pad_numbers_are_jumpers no)
		(fp_line
			(start 0.7874 0.4064)
			(end -0.7874 0.4064)
			(stroke
				(width 0.1524)
				(type default)
			)
			(layer "F.SilkS")
		)
		(fp_line
			(start 0.7874 -0.4064)
			(end 0.7874 0.4064)
			(stroke
				(width 0.1524)
				(type default)
			)
			(layer "F.SilkS")
		)
		(fp_line
			(start -0.7874 0.4064)
			(end -0.7874 -0.4064)
			(stroke
				(width 0.1524)
				(type default)
			)
			(layer "F.SilkS")
		)
		(fp_line
			(start -0.7874 -0.4064)
			(end 0.7874 -0.4064)
			(stroke
				(width 0.1524)
				(type default)
			)
			(layer "F.SilkS")
		)
		(fp_line
			(start 0.67945 0.3048)
			(end 0.120396 0.3048)
			(stroke
				(width 0.1)
				(type default)
			)
			(layer "F.Fab")
		)
		(fp_line
			(start 0.67945 -0.3048)
			(end 0.67945 0.3048)
			(stroke
				(width 0.1)
				(type default)
			)
			(layer "F.Fab")
		)
		(fp_line
			(start 0.12065 -0.2794)
			(end 0.12065 -0.3048)
			(stroke
				(width 0.1)
				(type default)
			)
			(layer "F.Fab")
		)
		(fp_line
			(start 0.12065 -0.3048)
			(end 0.67945 -0.3048)
			(stroke
				(width 0.1)
				(type default)
			)
			(layer "F.Fab")
		)
		(fp_line
			(start 0.120396 0.3048)
			(end 0.120396 0.2794)
			(stroke
				(width 0.1)
				(type default)
			)
			(layer "F.Fab")
		)
		(fp_line
			(start 0.120396 0.2794)
			(end -0.12065 0.2794)
			(stroke
				(width 0.1)
				(type default)
			)
			(layer "F.Fab")
		)
		(fp_line
			(start -0.12065 0.3048)
			(end -0.67945 0.3048)
			(stroke
				(width 0.1)
				(type default)
			)
			(layer "F.Fab")
		)
		(fp_line
			(start -0.12065 0.2794)
			(end -0.12065 0.3048)
			(stroke
				(width 0.1)
				(type default)
			)
			(layer "F.Fab")
		)
		(fp_line
			(start -0.12065 -0.2794)
			(end 0.12065 -0.2794)
			(stroke
				(width 0.1)
				(type default)
			)
			(layer "F.Fab")
		)
		(fp_line
			(start -0.12065 -0.305054)
			(end -0.12065 -0.2794)
			(stroke
				(width 0.1)
				(type default)
			)
			(layer "F.Fab")
		)
		(fp_line
			(start -0.67945 0.3048)
			(end -0.67945 -0.305054)
			(stroke
				(width 0.1)
				(type default)
			)
			(layer "F.Fab")
		)
		(fp_line
			(start -0.67945 -0.305054)
			(end -0.12065 -0.305054)
			(stroke
				(width 0.1)
				(type default)
			)
			(layer "F.Fab")
		)
		(pad "1" smd circle
			(at -0.40005 0 180)
			(size 0 0)
			(layers "F.Cu" "F.Mask" "F.Paste")
			(net "GND")
		)
		(pad "2" smd circle
			(at 0.40005 0 180)
			(size 0 0)
			(layers "F.Cu" "F.Mask" "F.Paste")
			(net "NC_P0V8_PEX0_SVID_ALERT_N_R")
		)
	)
	(footprint ""
		(layer "F.Cu")
		(at 276.126448 -25.432004 -90)
		(property "Reference" "C974"
			(at 0 0 270)
			(layer "F.SilkS")
			(hide yes)
			(effects
				(font
					(size 1.27 1.27)
				)
			)
		)
		(property "Value" ""
			(at 0 0 270)
			(layer "F.Fab")
			(effects
				(font
					(size 1.27 1.27)
				)
			)
		)
		(duplicate_pad_numbers_are_jumpers no)
		(fp_line
			(start -0.7874 0.4064)
			(end -0.7874 -0.4064)
			(stroke
				(width 0.1524)
				(type default)
			)
			(layer "F.SilkS")
		)
		(fp_line
			(start 0.7874 0.4064)
			(end -0.7874 0.4064)
			(stroke
				(width 0.1524)
				(type default)
			)
			(layer "F.SilkS")
		)
		(fp_line
			(start -0.7874 -0.4064)
			(end 0.7874 -0.4064)
			(stroke
				(width 0.1524)
				(type default)
			)
			(layer "F.SilkS")
		)
		(fp_line
			(start 0.7874 -0.4064)
			(end 0.7874 0.4064)
			(stroke
				(width 0.1524)
				(type default)
			)
			(layer "F.SilkS")
		)
		(fp_line
			(start -0.67945 0.3048)
			(end -0.67945 -0.305054)
			(stroke
				(width 0.1)
				(type default)
			)
			(layer "F.Fab")
		)
		(fp_line
			(start -0.12065 0.3048)
			(end -0.67945 0.3048)
			(stroke
				(width 0.1)
				(type default)
			)
			(layer "F.Fab")
		)
		(fp_line
			(start 0.120396 0.3048)
			(end 0.120396 0.2794)
			(stroke
				(width 0.1)
				(type default)
			)
			(layer "F.Fab")
		)
		(fp_line
			(start 0.67945 0.3048)
			(end 0.120396 0.3048)
			(stroke
				(width 0.1)
				(type default)
			)
			(layer "F.Fab")
		)
		(fp_line
			(start -0.12065 0.2794)
			(end -0.12065 0.3048)
			(stroke
				(width 0.1)
				(type default)
			)
			(layer "F.Fab")
		)
		(fp_line
			(start 0.120396 0.2794)
			(end -0.12065 0.2794)
			(stroke
				(width 0.1)
				(type default)
			)
			(layer "F.Fab")
		)
		(fp_line
			(start -0.12065 -0.2794)
			(end 0.12065 -0.2794)
			(stroke
				(width 0.1)
				(type default)
			)
			(layer "F.Fab")
		)
		(fp_line
			(start 0.12065 -0.2794)
			(end 0.12065 -0.3048)
			(stroke
				(width 0.1)
				(type default)
			)
			(layer "F.Fab")
		)
		(fp_line
			(start 0.12065 -0.3048)
			(end 0.67945 -0.3048)
			(stroke
				(width 0.1)
				(type default)
			)
			(layer "F.Fab")
		)
		(fp_line
			(start 0.67945 -0.3048)
			(end 0.67945 0.3048)
			(stroke
				(width 0.1)
				(type default)
			)
			(layer "F.Fab")
		)
		(fp_line
			(start -0.67945 -0.305054)
			(end -0.12065 -0.305054)
			(stroke
				(width 0.1)
				(type default)
			)
			(layer "F.Fab")
		)
		(fp_line
			(start -0.12065 -0.305054)
			(end -0.12065 -0.2794)
			(stroke
				(width 0.1)
				(type default)
			)
			(layer "F.Fab")
		)
		(pad "1" smd circle
			(at -0.40005 0 270)
			(size 0 0)
			(layers "F.Cu" "F.Mask" "F.Paste")
			(net "GND")
		)
		(pad "2" smd circle
			(at 0.40005 0 270)
			(size 0 0)
			(layers "F.Cu" "F.Mask" "F.Paste")
			(net "P3V3_SSD9")
		)
	)
	(footprint ""
		(layer "F.Cu")
		(at 389.81634 -356.244906 90)
		(property "Reference" "C742"
			(at 0 0 90)
			(layer "F.SilkS")
			(hide yes)
			(effects
				(font
					(size 1.27 1.27)
				)
			)
		)
		(property "Value" ""
			(at 0 0 90)
			(layer "F.Fab")
			(effects
				(font
					(size 1.27 1.27)
				)
			)
		)
		(duplicate_pad_numbers_are_jumpers no)
		(fp_line
			(start 0.299974 -0.150114)
			(end 0.299974 0.150114)
			(stroke
				(width 0.1)
				(type default)
			)
			(layer "F.Fab")
		)
		(fp_line
			(start -0.299974 -0.150114)
			(end 0.299974 -0.150114)
			(stroke
				(width 0.1)
				(type default)
			)
			(layer "F.Fab")
		)
		(fp_line
			(start 0.299974 0.150114)
			(end -0.299974 0.150114)
			(stroke
				(width 0.1)
				(type default)
			)
			(layer "F.Fab")
		)
		(fp_line
			(start -0.299974 0.150114)
			(end -0.299974 -0.150114)
			(stroke
				(width 0.1)
				(type default)
			)
			(layer "F.Fab")
		)
		(pad "1" smd rect
			(at -0.2667 0 90)
			(size 0.3048 0.381)
			(layers "F.Cu" "F.Mask" "F.Paste")
			(net "P5E_PEX3_STN5_TX_DP<89>")
		)
		(pad "2" smd rect
			(at 0.2667 0 90)
			(size 0.3048 0.381)
			(layers "F.Cu" "F.Mask" "F.Paste")
			(net "P5E_PEX3_STN5_TX_C_DP<89>")
		)
	)
	(footprint ""
		(layer "F.Cu")
		(at 83.109562 -350.098614 90)
		(property "Reference" "C149"
			(at 0 0 90)
			(layer "F.SilkS")
			(hide yes)
			(effects
				(font
					(size 1.27 1.27)
				)
			)
		)
		(property "Value" ""
			(at 0 0 90)
			(layer "F.Fab")
			(effects
				(font
					(size 1.27 1.27)
				)
			)
		)
		(duplicate_pad_numbers_are_jumpers no)
		(fp_line
			(start 0.299974 -0.150114)
			(end 0.299974 0.150114)
			(stroke
				(width 0.1)
				(type default)
			)
			(layer "F.Fab")
		)
		(fp_line
			(start -0.299974 -0.150114)
			(end 0.299974 -0.150114)
			(stroke
				(width 0.1)
				(type default)
			)
			(layer "F.Fab")
		)
		(fp_line
			(start 0.299974 0.150114)
			(end -0.299974 0.150114)
			(stroke
				(width 0.1)
				(type default)
			)
			(layer "F.Fab")
		)
		(fp_line
			(start -0.299974 0.150114)
			(end -0.299974 -0.150114)
			(stroke
				(width 0.1)
				(type default)
			)
			(layer "F.Fab")
		)
		(pad "1" smd rect
			(at -0.2667 0 90)
			(size 0.3048 0.381)
			(layers "F.Cu" "F.Mask" "F.Paste")
			(net "P5E_PEX0_STN6_TX_DP<101>")
		)
		(pad "2" smd rect
			(at 0.2667 0 90)
			(size 0.3048 0.381)
			(layers "F.Cu" "F.Mask" "F.Paste")
			(net "P5E_PEX0_STN6_TX_C_DP<101>")
		)
	)
	(footprint ""
		(layer "F.Cu")
		(at 225.413316 -123.520962 180)
		(property "Reference" "R5961"
			(at 0 0 180)
			(layer "F.SilkS")
			(hide yes)
			(effects
				(font
					(size 1.27 1.27)
				)
			)
		)
		(property "Value" ""
			(at 0 0 180)
			(layer "F.Fab")
			(effects
				(font
					(size 1.27 1.27)
				)
			)
		)
		(duplicate_pad_numbers_are_jumpers no)
		(fp_line
			(start 0.7874 0.4064)
			(end -0.7874 0.4064)
			(stroke
				(width 0.1524)
				(type default)
			)
			(layer "F.SilkS")
		)
		(fp_line
			(start 0.7874 -0.4064)
			(end 0.7874 0.4064)
			(stroke
				(width 0.1524)
				(type default)
			)
			(layer "F.SilkS")
		)
		(fp_line
			(start -0.7874 0.4064)
			(end -0.7874 -0.4064)
			(stroke
				(width 0.1524)
				(type default)
			)
			(layer "F.SilkS")
		)
		(fp_line
			(start -0.7874 -0.4064)
			(end 0.7874 -0.4064)
			(stroke
				(width 0.1524)
				(type default)
			)
			(layer "F.SilkS")
		)
		(fp_line
			(start 0.67945 0.3048)
			(end 0.120396 0.3048)
			(stroke
				(width 0.1)
				(type default)
			)
			(layer "F.Fab")
		)
		(fp_line
			(start 0.67945 -0.3048)
			(end 0.67945 0.3048)
			(stroke
				(width 0.1)
				(type default)
			)
			(layer "F.Fab")
		)
		(fp_line
			(start 0.12065 -0.2794)
			(end 0.12065 -0.3048)
			(stroke
				(width 0.1)
				(type default)
			)
			(layer "F.Fab")
		)
		(fp_line
			(start 0.12065 -0.3048)
			(end 0.67945 -0.3048)
			(stroke
				(width 0.1)
				(type default)
			)
			(layer "F.Fab")
		)
		(fp_line
			(start 0.120396 0.3048)
			(end 0.120396 0.2794)
			(stroke
				(width 0.1)
				(type default)
			)
			(layer "F.Fab")
		)
		(fp_line
			(start 0.120396 0.2794)
			(end -0.12065 0.2794)
			(stroke
				(width 0.1)
				(type default)
			)
			(layer "F.Fab")
		)
		(fp_line
			(start -0.12065 0.3048)
			(end -0.67945 0.3048)
			(stroke
				(width 0.1)
				(type default)
			)
			(layer "F.Fab")
		)
		(fp_line
			(start -0.12065 0.2794)
			(end -0.12065 0.3048)
			(stroke
				(width 0.1)
				(type default)
			)
			(layer "F.Fab")
		)
		(fp_line
			(start -0.12065 -0.2794)
			(end 0.12065 -0.2794)
			(stroke
				(width 0.1)
				(type default)
			)
			(layer "F.Fab")
		)
		(fp_line
			(start -0.12065 -0.305054)
			(end -0.12065 -0.2794)
			(stroke
				(width 0.1)
				(type default)
			)
			(layer "F.Fab")
		)
		(fp_line
			(start -0.67945 0.3048)
			(end -0.67945 -0.305054)
			(stroke
				(width 0.1)
				(type default)
			)
			(layer "F.Fab")
		)
		(fp_line
			(start -0.67945 -0.305054)
			(end -0.12065 -0.305054)
			(stroke
				(width 0.1)
				(type default)
			)
			(layer "F.Fab")
		)
		(pad "1" smd circle
			(at -0.40005 0 180)
			(size 0 0)
			(layers "F.Cu" "F.Mask" "F.Paste")
			(net "P5V_AUX")
		)
		(pad "2" smd circle
			(at 0.40005 0 180)
			(size 0 0)
			(layers "F.Cu" "F.Mask" "F.Paste")
			(net "P3V3_NIC3_PG_G2")
		)
	)
	(footprint ""
		(layer "F.Cu")
		(at 355.968808 -156.288994 -90)
		(property "Reference" "PR7048"
			(at 0 0 270)
			(layer "F.SilkS")
			(hide yes)
			(effects
				(font
					(size 1.27 1.27)
				)
			)
		)
		(property "Value" ""
			(at 0 0 270)
			(layer "F.Fab")
			(effects
				(font
					(size 1.27 1.27)
				)
			)
		)
		(duplicate_pad_numbers_are_jumpers no)
		(fp_line
			(start -0.7874 0.4064)
			(end -0.7874 -0.4064)
			(stroke
				(width 0.1524)
				(type default)
			)
			(layer "F.SilkS")
		)
		(fp_line
			(start 0.7874 0.4064)
			(end -0.7874 0.4064)
			(stroke
				(width 0.1524)
				(type default)
			)
			(layer "F.SilkS")
		)
		(fp_line
			(start -0.7874 -0.4064)
			(end 0.7874 -0.4064)
			(stroke
				(width 0.1524)
				(type default)
			)
			(layer "F.SilkS")
		)
		(fp_line
			(start 0.7874 -0.4064)
			(end 0.7874 0.4064)
			(stroke
				(width 0.1524)
				(type default)
			)
			(layer "F.SilkS")
		)
		(fp_line
			(start -0.67945 0.3048)
			(end -0.67945 -0.305054)
			(stroke
				(width 0.1)
				(type default)
			)
			(layer "F.Fab")
		)
		(fp_line
			(start -0.12065 0.3048)
			(end -0.67945 0.3048)
			(stroke
				(width 0.1)
				(type default)
			)
			(layer "F.Fab")
		)
		(fp_line
			(start 0.120396 0.3048)
			(end 0.120396 0.2794)
			(stroke
				(width 0.1)
				(type default)
			)
			(layer "F.Fab")
		)
		(fp_line
			(start 0.67945 0.3048)
			(end 0.120396 0.3048)
			(stroke
				(width 0.1)
				(type default)
			)
			(layer "F.Fab")
		)
		(fp_line
			(start -0.12065 0.2794)
			(end -0.12065 0.3048)
			(stroke
				(width 0.1)
				(type default)
			)
			(layer "F.Fab")
		)
		(fp_line
			(start 0.120396 0.2794)
			(end -0.12065 0.2794)
			(stroke
				(width 0.1)
				(type default)
			)
			(layer "F.Fab")
		)
		(fp_line
			(start -0.12065 -0.2794)
			(end 0.12065 -0.2794)
			(stroke
				(width 0.1)
				(type default)
			)
			(layer "F.Fab")
		)
		(fp_line
			(start 0.12065 -0.2794)
			(end 0.12065 -0.3048)
			(stroke
				(width 0.1)
				(type default)
			)
			(layer "F.Fab")
		)
		(fp_line
			(start 0.12065 -0.3048)
			(end 0.67945 -0.3048)
			(stroke
				(width 0.1)
				(type default)
			)
			(layer "F.Fab")
		)
		(fp_line
			(start 0.67945 -0.3048)
			(end 0.67945 0.3048)
			(stroke
				(width 0.1)
				(type default)
			)
			(layer "F.Fab")
		)
		(fp_line
			(start -0.67945 -0.305054)
			(end -0.12065 -0.305054)
			(stroke
				(width 0.1)
				(type default)
			)
			(layer "F.Fab")
		)
		(fp_line
			(start -0.12065 -0.305054)
			(end -0.12065 -0.2794)
			(stroke
				(width 0.1)
				(type default)
			)
			(layer "F.Fab")
		)
		(pad "1" smd circle
			(at -0.40005 0 270)
			(size 0 0)
			(layers "F.Cu" "F.Mask" "F.Paste")
			(net "P12V_NIC6_CO_OV_FB")
		)
		(pad "2" smd circle
			(at 0.40005 0 270)
			(size 0 0)
			(layers "F.Cu" "F.Mask" "F.Paste")
			(net "P12V_AUX")
		)
	)
	(footprint ""
		(layer "F.Cu")
		(at 400.264884 -5.999988)
		(property "Reference" "H64"
			(at -4.501388 -5.169154 0)
			(unlocked yes)
			(layer "F.SilkS")
			(effects
				(font
					(size 0.7874 0.5842)
					(thickness 0.1524)
				)
				(justify left)
			)
		)
		(property "Value" ""
			(at 0 0 0)
			(layer "F.Fab")
			(effects
				(font
					(size 1.27 1.27)
				)
			)
		)
		(duplicate_pad_numbers_are_jumpers no)
		(pad "1" thru_hole circle
			(at 0 0)
			(size 10.0076 10.0076)
			(drill 5.6134)
			(layers "*.Cu" "*.Mask")
			(remove_unused_layers no)
			(net "GND")
			(clearance -1.9431)
		)
	)
	(footprint ""
		(layer "F.Cu")
		(at 333.35214 -95.264224 90)
		(property "Reference" "R4449"
			(at 0 0 90)
			(layer "F.SilkS")
			(hide yes)
			(effects
				(font
					(size 1.27 1.27)
				)
			)
		)
		(property "Value" ""
			(at 0 0 90)
			(layer "F.Fab")
			(effects
				(font
					(size 1.27 1.27)
				)
			)
		)
		(duplicate_pad_numbers_are_jumpers no)
		(fp_line
			(start 0.7874 -0.4064)
			(end 0.7874 0.4064)
			(stroke
				(width 0.1524)
				(type default)
			)
			(layer "F.SilkS")
		)
		(fp_line
			(start -0.7874 -0.4064)
			(end 0.7874 -0.4064)
			(stroke
				(width 0.1524)
				(type default)
			)
			(layer "F.SilkS")
		)
		(fp_line
			(start 0.7874 0.4064)
			(end -0.7874 0.4064)
			(stroke
				(width 0.1524)
				(type default)
			)
			(layer "F.SilkS")
		)
		(fp_line
			(start -0.7874 0.4064)
			(end -0.7874 -0.4064)
			(stroke
				(width 0.1524)
				(type default)
			)
			(layer "F.SilkS")
		)
		(fp_line
			(start -0.12065 -0.305054)
			(end -0.12065 -0.2794)
			(stroke
				(width 0.1)
				(type default)
			)
			(layer "F.Fab")
		)
		(fp_line
			(start -0.67945 -0.305054)
			(end -0.12065 -0.305054)
			(stroke
				(width 0.1)
				(type default)
			)
			(layer "F.Fab")
		)
		(fp_line
			(start 0.67945 -0.3048)
			(end 0.67945 0.3048)
			(stroke
				(width 0.1)
				(type default)
			)
			(layer "F.Fab")
		)
		(fp_line
			(start 0.12065 -0.3048)
			(end 0.67945 -0.3048)
			(stroke
				(width 0.1)
				(type default)
			)
			(layer "F.Fab")
		)
		(fp_line
			(start 0.12065 -0.2794)
			(end 0.12065 -0.3048)
			(stroke
				(width 0.1)
				(type default)
			)
			(layer "F.Fab")
		)
		(fp_line
			(start -0.12065 -0.2794)
			(end 0.12065 -0.2794)
			(stroke
				(width 0.1)
				(type default)
			)
			(layer "F.Fab")
		)
		(fp_line
			(start 0.120396 0.2794)
			(end -0.12065 0.2794)
			(stroke
				(width 0.1)
				(type default)
			)
			(layer "F.Fab")
		)
		(fp_line
			(start -0.12065 0.2794)
			(end -0.12065 0.3048)
			(stroke
				(width 0.1)
				(type default)
			)
			(layer "F.Fab")
		)
		(fp_line
			(start 0.67945 0.3048)
			(end 0.120396 0.3048)
			(stroke
				(width 0.1)
				(type default)
			)
			(layer "F.Fab")
		)
		(fp_line
			(start 0.120396 0.3048)
			(end 0.120396 0.2794)
			(stroke
				(width 0.1)
				(type default)
			)
			(layer "F.Fab")
		)
		(fp_line
			(start -0.12065 0.3048)
			(end -0.67945 0.3048)
			(stroke
				(width 0.1)
				(type default)
			)
			(layer "F.Fab")
		)
		(fp_line
			(start -0.67945 0.3048)
			(end -0.67945 -0.305054)
			(stroke
				(width 0.1)
				(type default)
			)
			(layer "F.Fab")
		)
		(pad "1" smd circle
			(at -0.40005 0 90)
			(size 0 0)
			(layers "F.Cu" "F.Mask" "F.Paste")
			(net "HP_NIC5_EN")
		)
		(pad "2" smd circle
			(at 0.40005 0 90)
			(size 0 0)
			(layers "F.Cu" "F.Mask" "F.Paste")
			(net "P12V_NIC5_EN_R")
		)
	)
	(footprint ""
		(layer "F.Cu")
		(at 55.88 -142.9512)
		(property "Reference" "R9"
			(at 0 0 0)
			(layer "F.SilkS")
			(hide yes)
			(effects
				(font
					(size 1.27 1.27)
				)
			)
		)
		(property "Value" ""
			(at 0 0 0)
			(layer "F.Fab")
			(effects
				(font
					(size 1.27 1.27)
				)
			)
		)
		(duplicate_pad_numbers_are_jumpers no)
		(fp_line
			(start -0.7874 -0.4064)
			(end 0.7874 -0.4064)
			(stroke
				(width 0.1524)
				(type default)
			)
			(layer "F.SilkS")
		)
		(fp_line
			(start -0.7874 0.4064)
			(end -0.7874 -0.4064)
			(stroke
				(width 0.1524)
				(type default)
			)
			(layer "F.SilkS")
		)
		(fp_line
			(start 0.7874 -0.4064)
			(end 0.7874 0.4064)
			(stroke
				(width 0.1524)
				(type default)
			)
			(layer "F.SilkS")
		)
		(fp_line
			(start 0.7874 0.4064)
			(end -0.7874 0.4064)
			(stroke
				(width 0.1524)
				(type default)
			)
			(layer "F.SilkS")
		)
		(fp_line
			(start -0.67945 -0.305054)
			(end -0.12065 -0.305054)
			(stroke
				(width 0.1)
				(type default)
			)
			(layer "F.Fab")
		)
		(fp_line
			(start -0.67945 0.3048)
			(end -0.67945 -0.305054)
			(stroke
				(width 0.1)
				(type default)
			)
			(layer "F.Fab")
		)
		(fp_line
			(start -0.12065 -0.305054)
			(end -0.12065 -0.2794)
			(stroke
				(width 0.1)
				(type default)
			)
			(layer "F.Fab")
		)
		(fp_line
			(start -0.12065 -0.2794)
			(end 0.12065 -0.2794)
			(stroke
				(width 0.1)
				(type default)
			)
			(layer "F.Fab")
		)
		(fp_line
			(start -0.12065 0.2794)
			(end -0.12065 0.3048)
			(stroke
				(width 0.1)
				(type default)
			)
			(layer "F.Fab")
		)
		(fp_line
			(start -0.12065 0.3048)
			(end -0.67945 0.3048)
			(stroke
				(width 0.1)
				(type default)
			)
			(layer "F.Fab")
		)
		(fp_line
			(start 0.120396 0.2794)
			(end -0.12065 0.2794)
			(stroke
				(width 0.1)
				(type default)
			)
			(layer "F.Fab")
		)
		(fp_line
			(start 0.120396 0.3048)
			(end 0.120396 0.2794)
			(stroke
				(width 0.1)
				(type default)
			)
			(layer "F.Fab")
		)
		(fp_line
			(start 0.12065 -0.3048)
			(end 0.67945 -0.3048)
			(stroke
				(width 0.1)
				(type default)
			)
			(layer "F.Fab")
		)
		(fp_line
			(start 0.12065 -0.2794)
			(end 0.12065 -0.3048)
			(stroke
				(width 0.1)
				(type default)
			)
			(layer "F.Fab")
		)
		(fp_line
			(start 0.67945 -0.3048)
			(end 0.67945 0.3048)
			(stroke
				(width 0.1)
				(type default)
			)
			(layer "F.Fab")
		)
		(fp_line
			(start 0.67945 0.3048)
			(end 0.120396 0.3048)
			(stroke
				(width 0.1)
				(type default)
			)
			(layer "F.Fab")
		)
		(pad "1" smd circle
			(at -0.40005 0)
			(size 0 0)
			(layers "F.Cu" "F.Mask" "F.Paste")
			(net "SMB_NIC0_R_SCL")
		)
		(pad "2" smd circle
			(at 0.40005 0)
			(size 0 0)
			(layers "F.Cu" "F.Mask" "F.Paste")
			(net "P3V3_NIC0")
		)
	)
	(footprint ""
		(layer "F.Cu")
		(at 2.614168 -24.945594 90)
		(property "Reference" "R1637"
			(at 0 0 90)
			(layer "F.SilkS")
			(hide yes)
			(effects
				(font
					(size 1.27 1.27)
				)
			)
		)
		(property "Value" ""
			(at 0 0 90)
			(layer "F.Fab")
			(effects
				(font
					(size 1.27 1.27)
				)
			)
		)
		(duplicate_pad_numbers_are_jumpers no)
		(fp_line
			(start 0.7874 -0.4064)
			(end 0.7874 0.4064)
			(stroke
				(width 0.1524)
				(type default)
			)
			(layer "F.SilkS")
		)
		(fp_line
			(start -0.7874 -0.4064)
			(end 0.7874 -0.4064)
			(stroke
				(width 0.1524)
				(type default)
			)
			(layer "F.SilkS")
		)
		(fp_line
			(start 0.7874 0.4064)
			(end -0.7874 0.4064)
			(stroke
				(width 0.1524)
				(type default)
			)
			(layer "F.SilkS")
		)
		(fp_line
			(start -0.7874 0.4064)
			(end -0.7874 -0.4064)
			(stroke
				(width 0.1524)
				(type default)
			)
			(layer "F.SilkS")
		)
		(fp_line
			(start -0.12065 -0.305054)
			(end -0.12065 -0.2794)
			(stroke
				(width 0.1)
				(type default)
			)
			(layer "F.Fab")
		)
		(fp_line
			(start -0.67945 -0.305054)
			(end -0.12065 -0.305054)
			(stroke
				(width 0.1)
				(type default)
			)
			(layer "F.Fab")
		)
		(fp_line
			(start 0.67945 -0.3048)
			(end 0.67945 0.3048)
			(stroke
				(width 0.1)
				(type default)
			)
			(layer "F.Fab")
		)
		(fp_line
			(start 0.12065 -0.3048)
			(end 0.67945 -0.3048)
			(stroke
				(width 0.1)
				(type default)
			)
			(layer "F.Fab")
		)
		(fp_line
			(start 0.12065 -0.2794)
			(end 0.12065 -0.3048)
			(stroke
				(width 0.1)
				(type default)
			)
			(layer "F.Fab")
		)
		(fp_line
			(start -0.12065 -0.2794)
			(end 0.12065 -0.2794)
			(stroke
				(width 0.1)
				(type default)
			)
			(layer "F.Fab")
		)
		(fp_line
			(start 0.120396 0.2794)
			(end -0.12065 0.2794)
			(stroke
				(width 0.1)
				(type default)
			)
			(layer "F.Fab")
		)
		(fp_line
			(start -0.12065 0.2794)
			(end -0.12065 0.3048)
			(stroke
				(width 0.1)
				(type default)
			)
			(layer "F.Fab")
		)
		(fp_line
			(start 0.67945 0.3048)
			(end 0.120396 0.3048)
			(stroke
				(width 0.1)
				(type default)
			)
			(layer "F.Fab")
		)
		(fp_line
			(start 0.120396 0.3048)
			(end 0.120396 0.2794)
			(stroke
				(width 0.1)
				(type default)
			)
			(layer "F.Fab")
		)
		(fp_line
			(start -0.12065 0.3048)
			(end -0.67945 0.3048)
			(stroke
				(width 0.1)
				(type default)
			)
			(layer "F.Fab")
		)
		(fp_line
			(start -0.67945 0.3048)
			(end -0.67945 -0.305054)
			(stroke
				(width 0.1)
				(type default)
			)
			(layer "F.Fab")
		)
		(pad "1" smd circle
			(at -0.40005 0 90)
			(size 0 0)
			(layers "F.Cu" "F.Mask" "F.Paste")
			(net "SMB_ISO_SSD0_R_SCL")
		)
		(pad "2" smd circle
			(at 0.40005 0 90)
			(size 0 0)
			(layers "F.Cu" "F.Mask" "F.Paste")
			(net "SMB_ISO_SSD0_SCL")
		)
	)
	(footprint ""
		(layer "F.Cu")
		(at 222.482664 -204.44206 90)
		(property "Reference" "R5536"
			(at 0 0 90)
			(layer "F.SilkS")
			(hide yes)
			(effects
				(font
					(size 1.27 1.27)
				)
			)
		)
		(property "Value" ""
			(at 0 0 90)
			(layer "F.Fab")
			(effects
				(font
					(size 1.27 1.27)
				)
			)
		)
		(duplicate_pad_numbers_are_jumpers no)
		(fp_line
			(start 0.7874 -0.4064)
			(end 0.7874 0.4064)
			(stroke
				(width 0.1524)
				(type default)
			)
			(layer "F.SilkS")
		)
		(fp_line
			(start -0.7874 -0.4064)
			(end 0.7874 -0.4064)
			(stroke
				(width 0.1524)
				(type default)
			)
			(layer "F.SilkS")
		)
		(fp_line
			(start 0.7874 0.4064)
			(end -0.7874 0.4064)
			(stroke
				(width 0.1524)
				(type default)
			)
			(layer "F.SilkS")
		)
		(fp_line
			(start -0.7874 0.4064)
			(end -0.7874 -0.4064)
			(stroke
				(width 0.1524)
				(type default)
			)
			(layer "F.SilkS")
		)
		(fp_line
			(start -0.12065 -0.305054)
			(end -0.12065 -0.2794)
			(stroke
				(width 0.1)
				(type default)
			)
			(layer "F.Fab")
		)
		(fp_line
			(start -0.67945 -0.305054)
			(end -0.12065 -0.305054)
			(stroke
				(width 0.1)
				(type default)
			)
			(layer "F.Fab")
		)
		(fp_line
			(start 0.67945 -0.3048)
			(end 0.67945 0.3048)
			(stroke
				(width 0.1)
				(type default)
			)
			(layer "F.Fab")
		)
		(fp_line
			(start 0.12065 -0.3048)
			(end 0.67945 -0.3048)
			(stroke
				(width 0.1)
				(type default)
			)
			(layer "F.Fab")
		)
		(fp_line
			(start 0.12065 -0.2794)
			(end 0.12065 -0.3048)
			(stroke
				(width 0.1)
				(type default)
			)
			(layer "F.Fab")
		)
		(fp_line
			(start -0.12065 -0.2794)
			(end 0.12065 -0.2794)
			(stroke
				(width 0.1)
				(type default)
			)
			(layer "F.Fab")
		)
		(fp_line
			(start 0.120396 0.2794)
			(end -0.12065 0.2794)
			(stroke
				(width 0.1)
				(type default)
			)
			(layer "F.Fab")
		)
		(fp_line
			(start -0.12065 0.2794)
			(end -0.12065 0.3048)
			(stroke
				(width 0.1)
				(type default)
			)
			(layer "F.Fab")
		)
		(fp_line
			(start 0.67945 0.3048)
			(end 0.120396 0.3048)
			(stroke
				(width 0.1)
				(type default)
			)
			(layer "F.Fab")
		)
		(fp_line
			(start 0.120396 0.3048)
			(end 0.120396 0.2794)
			(stroke
				(width 0.1)
				(type default)
			)
			(layer "F.Fab")
		)
		(fp_line
			(start -0.12065 0.3048)
			(end -0.67945 0.3048)
			(stroke
				(width 0.1)
				(type default)
			)
			(layer "F.Fab")
		)
		(fp_line
			(start -0.67945 0.3048)
			(end -0.67945 -0.305054)
			(stroke
				(width 0.1)
				(type default)
			)
			(layer "F.Fab")
		)
		(pad "1" smd circle
			(at -0.40005 0 90)
			(size 0 0)
			(layers "F.Cu" "F.Mask" "F.Paste")
			(net "P3V3_AUX")
		)
		(pad "2" smd circle
			(at 0.40005 0 90)
			(size 0 0)
			(layers "F.Cu" "F.Mask" "F.Paste")
			(net "SGPIO_BIC_CLK")
		)
	)
	(footprint ""
		(layer "F.Cu")
		(at 259.130038 -287.604708 -90)
		(property "Reference" "C3365"
			(at 0 0 270)
			(layer "F.SilkS")
			(hide yes)
			(effects
				(font
					(size 1.27 1.27)
				)
			)
		)
		(property "Value" ""
			(at 0 0 270)
			(layer "F.Fab")
			(effects
				(font
					(size 1.27 1.27)
				)
			)
		)
		(duplicate_pad_numbers_are_jumpers no)
		(fp_line
			(start -1.2954 0.5842)
			(end -1.2954 -0.5842)
			(stroke
				(width 0.1524)
				(type default)
			)
			(layer "F.SilkS")
		)
		(fp_line
			(start 1.2954 0.5842)
			(end -1.2954 0.5842)
			(stroke
				(width 0.1524)
				(type default)
			)
			(layer "F.SilkS")
		)
		(fp_line
			(start -1.2954 -0.5842)
			(end 1.2954 -0.5842)
			(stroke
				(width 0.1524)
				(type default)
			)
			(layer "F.SilkS")
		)
		(fp_line
			(start 1.2954 -0.5842)
			(end 1.2954 0.5842)
			(stroke
				(width 0.1524)
				(type default)
			)
			(layer "F.SilkS")
		)
		(fp_line
			(start -0.8636 0.4572)
			(end -0.8636 0.4064)
			(stroke
				(width 0.1)
				(type default)
			)
			(layer "F.Fab")
		)
		(fp_line
			(start 0.8636 0.4572)
			(end -0.8636 0.4572)
			(stroke
				(width 0.1)
				(type default)
			)
			(layer "F.Fab")
		)
		(fp_line
			(start -1.1938 0.4064)
			(end -1.1938 -0.4064)
			(stroke
				(width 0.1)
				(type default)
			)
			(layer "F.Fab")
		)
		(fp_line
			(start -0.8636 0.4064)
			(end -1.1938 0.4064)
			(stroke
				(width 0.1)
				(type default)
			)
			(layer "F.Fab")
		)
		(fp_line
			(start 0.8636 0.4064)
			(end 0.8636 0.4572)
			(stroke
				(width 0.1)
				(type default)
			)
			(layer "F.Fab")
		)
		(fp_line
			(start 1.1938 0.4064)
			(end 0.8636 0.4064)
			(stroke
				(width 0.1)
				(type default)
			)
			(layer "F.Fab")
		)
		(fp_line
			(start -1.1938 -0.4064)
			(end -0.8636 -0.4064)
			(stroke
				(width 0.1)
				(type default)
			)
			(layer "F.Fab")
		)
		(fp_line
			(start -0.8636 -0.4064)
			(end -0.8636 -0.4572)
			(stroke
				(width 0.1)
				(type default)
			)
			(layer "F.Fab")
		)
		(fp_line
			(start 0.8636 -0.4064)
			(end 1.1938 -0.4064)
			(stroke
				(width 0.1)
				(type default)
			)
			(layer "F.Fab")
		)
		(fp_line
			(start 1.1938 -0.4064)
			(end 1.1938 0.4064)
			(stroke
				(width 0.1)
				(type default)
			)
			(layer "F.Fab")
		)
		(fp_line
			(start -0.8636 -0.4572)
			(end 0.8636 -0.4572)
			(stroke
				(width 0.1)
				(type default)
			)
			(layer "F.Fab")
		)
		(fp_line
			(start 0.8636 -0.4572)
			(end 0.8636 -0.4064)
			(stroke
				(width 0.1)
				(type default)
			)
			(layer "F.Fab")
		)
		(pad "1" smd rect
			(at -0.7366 0 180)
			(size 0.7112 0.8128)
			(layers "F.Cu" "F.Mask" "F.Paste")
			(net "P1V8_PLL0_PEX2")
		)
		(pad "2" smd rect
			(at 0.7366 0 180)
			(size 0.7112 0.8128)
			(layers "F.Cu" "F.Mask" "F.Paste")
			(net "GND")
		)
	)
	(footprint ""
		(layer "F.Cu")
		(at 404.18004 -139.6492)
		(property "Reference" "R312"
			(at 0 0 0)
			(layer "F.SilkS")
			(hide yes)
			(effects
				(font
					(size 1.27 1.27)
				)
			)
		)
		(property "Value" ""
			(at 0 0 0)
			(layer "F.Fab")
			(effects
				(font
					(size 1.27 1.27)
				)
			)
		)
		(duplicate_pad_numbers_are_jumpers no)
		(fp_line
			(start -0.7874 -0.4064)
			(end 0.7874 -0.4064)
			(stroke
				(width 0.1524)
				(type default)
			)
			(layer "F.SilkS")
		)
		(fp_line
			(start -0.7874 0.4064)
			(end -0.7874 -0.4064)
			(stroke
				(width 0.1524)
				(type default)
			)
			(layer "F.SilkS")
		)
		(fp_line
			(start 0.7874 -0.4064)
			(end 0.7874 0.4064)
			(stroke
				(width 0.1524)
				(type default)
			)
			(layer "F.SilkS")
		)
		(fp_line
			(start 0.7874 0.4064)
			(end -0.7874 0.4064)
			(stroke
				(width 0.1524)
				(type default)
			)
			(layer "F.SilkS")
		)
		(fp_line
			(start -0.67945 -0.305054)
			(end -0.12065 -0.305054)
			(stroke
				(width 0.1)
				(type default)
			)
			(layer "F.Fab")
		)
		(fp_line
			(start -0.67945 0.3048)
			(end -0.67945 -0.305054)
			(stroke
				(width 0.1)
				(type default)
			)
			(layer "F.Fab")
		)
		(fp_line
			(start -0.12065 -0.305054)
			(end -0.12065 -0.2794)
			(stroke
				(width 0.1)
				(type default)
			)
			(layer "F.Fab")
		)
		(fp_line
			(start -0.12065 -0.2794)
			(end 0.12065 -0.2794)
			(stroke
				(width 0.1)
				(type default)
			)
			(layer "F.Fab")
		)
		(fp_line
			(start -0.12065 0.2794)
			(end -0.12065 0.3048)
			(stroke
				(width 0.1)
				(type default)
			)
			(layer "F.Fab")
		)
		(fp_line
			(start -0.12065 0.3048)
			(end -0.67945 0.3048)
			(stroke
				(width 0.1)
				(type default)
			)
			(layer "F.Fab")
		)
		(fp_line
			(start 0.120396 0.2794)
			(end -0.12065 0.2794)
			(stroke
				(width 0.1)
				(type default)
			)
			(layer "F.Fab")
		)
		(fp_line
			(start 0.120396 0.3048)
			(end 0.120396 0.2794)
			(stroke
				(width 0.1)
				(type default)
			)
			(layer "F.Fab")
		)
		(fp_line
			(start 0.12065 -0.3048)
			(end 0.67945 -0.3048)
			(stroke
				(width 0.1)
				(type default)
			)
			(layer "F.Fab")
		)
		(fp_line
			(start 0.12065 -0.2794)
			(end 0.12065 -0.3048)
			(stroke
				(width 0.1)
				(type default)
			)
			(layer "F.Fab")
		)
		(fp_line
			(start 0.67945 -0.3048)
			(end 0.67945 0.3048)
			(stroke
				(width 0.1)
				(type default)
			)
			(layer "F.Fab")
		)
		(fp_line
			(start 0.67945 0.3048)
			(end 0.120396 0.3048)
			(stroke
				(width 0.1)
				(type default)
			)
			(layer "F.Fab")
		)
		(pad "1" smd circle
			(at -0.40005 0)
			(size 0 0)
			(layers "F.Cu" "F.Mask" "F.Paste")
			(net "PRSNTB2_NIC6_N")
		)
		(pad "2" smd circle
			(at 0.40005 0)
			(size 0 0)
			(layers "F.Cu" "F.Mask" "F.Paste")
			(net "P3V3_AUX")
		)
	)
	(footprint ""
		(layer "F.Cu")
		(at 355.913436 -137.344404 180)
		(property "Reference" "PR202"
			(at 0 0 180)
			(layer "F.SilkS")
			(hide yes)
			(effects
				(font
					(size 1.27 1.27)
				)
			)
		)
		(property "Value" ""
			(at 0 0 180)
			(layer "F.Fab")
			(effects
				(font
					(size 1.27 1.27)
				)
			)
		)
		(duplicate_pad_numbers_are_jumpers no)
		(fp_line
			(start 0.7874 0.4064)
			(end -0.7874 0.4064)
			(stroke
				(width 0.1524)
				(type default)
			)
			(layer "F.SilkS")
		)
		(fp_line
			(start 0.7874 -0.4064)
			(end 0.7874 0.4064)
			(stroke
				(width 0.1524)
				(type default)
			)
			(layer "F.SilkS")
		)
		(fp_line
			(start -0.7874 0.4064)
			(end -0.7874 -0.4064)
			(stroke
				(width 0.1524)
				(type default)
			)
			(layer "F.SilkS")
		)
		(fp_line
			(start -0.7874 -0.4064)
			(end 0.7874 -0.4064)
			(stroke
				(width 0.1524)
				(type default)
			)
			(layer "F.SilkS")
		)
		(fp_line
			(start 0.67945 0.3048)
			(end 0.120396 0.3048)
			(stroke
				(width 0.1)
				(type default)
			)
			(layer "F.Fab")
		)
		(fp_line
			(start 0.67945 -0.3048)
			(end 0.67945 0.3048)
			(stroke
				(width 0.1)
				(type default)
			)
			(layer "F.Fab")
		)
		(fp_line
			(start 0.12065 -0.2794)
			(end 0.12065 -0.3048)
			(stroke
				(width 0.1)
				(type default)
			)
			(layer "F.Fab")
		)
		(fp_line
			(start 0.12065 -0.3048)
			(end 0.67945 -0.3048)
			(stroke
				(width 0.1)
				(type default)
			)
			(layer "F.Fab")
		)
		(fp_line
			(start 0.120396 0.3048)
			(end 0.120396 0.2794)
			(stroke
				(width 0.1)
				(type default)
			)
			(layer "F.Fab")
		)
		(fp_line
			(start 0.120396 0.2794)
			(end -0.12065 0.2794)
			(stroke
				(width 0.1)
				(type default)
			)
			(layer "F.Fab")
		)
		(fp_line
			(start -0.12065 0.3048)
			(end -0.67945 0.3048)
			(stroke
				(width 0.1)
				(type default)
			)
			(layer "F.Fab")
		)
		(fp_line
			(start -0.12065 0.2794)
			(end -0.12065 0.3048)
			(stroke
				(width 0.1)
				(type default)
			)
			(layer "F.Fab")
		)
		(fp_line
			(start -0.12065 -0.2794)
			(end 0.12065 -0.2794)
			(stroke
				(width 0.1)
				(type default)
			)
			(layer "F.Fab")
		)
		(fp_line
			(start -0.12065 -0.305054)
			(end -0.12065 -0.2794)
			(stroke
				(width 0.1)
				(type default)
			)
			(layer "F.Fab")
		)
		(fp_line
			(start -0.67945 0.3048)
			(end -0.67945 -0.305054)
			(stroke
				(width 0.1)
				(type default)
			)
			(layer "F.Fab")
		)
		(fp_line
			(start -0.67945 -0.305054)
			(end -0.12065 -0.305054)
			(stroke
				(width 0.1)
				(type default)
			)
			(layer "F.Fab")
		)
		(pad "1" smd circle
			(at -0.40005 0 180)
			(size 0 0)
			(layers "F.Cu" "F.Mask" "F.Paste")
			(net "P12V_NIC6_OCP")
		)
		(pad "2" smd circle
			(at 0.40005 0 180)
			(size 0 0)
			(layers "F.Cu" "F.Mask" "F.Paste")
			(net "GND")
		)
	)
	(footprint ""
		(layer "F.Cu")
		(at 80.828388 -32.820356 -90)
		(property "Reference" "R5879"
			(at 0 0 270)
			(layer "F.SilkS")
			(hide yes)
			(effects
				(font
					(size 1.27 1.27)
				)
			)
		)
		(property "Value" ""
			(at 0 0 270)
			(layer "F.Fab")
			(effects
				(font
					(size 1.27 1.27)
				)
			)
		)
		(duplicate_pad_numbers_are_jumpers no)
		(fp_line
			(start -0.7874 0.4064)
			(end -0.7874 -0.4064)
			(stroke
				(width 0.1524)
				(type default)
			)
			(layer "F.SilkS")
		)
		(fp_line
			(start 0.7874 0.4064)
			(end -0.7874 0.4064)
			(stroke
				(width 0.1524)
				(type default)
			)
			(layer "F.SilkS")
		)
		(fp_line
			(start -0.7874 -0.4064)
			(end 0.7874 -0.4064)
			(stroke
				(width 0.1524)
				(type default)
			)
			(layer "F.SilkS")
		)
		(fp_line
			(start 0.7874 -0.4064)
			(end 0.7874 0.4064)
			(stroke
				(width 0.1524)
				(type default)
			)
			(layer "F.SilkS")
		)
		(fp_line
			(start -0.67945 0.3048)
			(end -0.67945 -0.305054)
			(stroke
				(width 0.1)
				(type default)
			)
			(layer "F.Fab")
		)
		(fp_line
			(start -0.12065 0.3048)
			(end -0.67945 0.3048)
			(stroke
				(width 0.1)
				(type default)
			)
			(layer "F.Fab")
		)
		(fp_line
			(start 0.120396 0.3048)
			(end 0.120396 0.2794)
			(stroke
				(width 0.1)
				(type default)
			)
			(layer "F.Fab")
		)
		(fp_line
			(start 0.67945 0.3048)
			(end 0.120396 0.3048)
			(stroke
				(width 0.1)
				(type default)
			)
			(layer "F.Fab")
		)
		(fp_line
			(start -0.12065 0.2794)
			(end -0.12065 0.3048)
			(stroke
				(width 0.1)
				(type default)
			)
			(layer "F.Fab")
		)
		(fp_line
			(start 0.120396 0.2794)
			(end -0.12065 0.2794)
			(stroke
				(width 0.1)
				(type default)
			)
			(layer "F.Fab")
		)
		(fp_line
			(start -0.12065 -0.2794)
			(end 0.12065 -0.2794)
			(stroke
				(width 0.1)
				(type default)
			)
			(layer "F.Fab")
		)
		(fp_line
			(start 0.12065 -0.2794)
			(end 0.12065 -0.3048)
			(stroke
				(width 0.1)
				(type default)
			)
			(layer "F.Fab")
		)
		(fp_line
			(start 0.12065 -0.3048)
			(end 0.67945 -0.3048)
			(stroke
				(width 0.1)
				(type default)
			)
			(layer "F.Fab")
		)
		(fp_line
			(start 0.67945 -0.3048)
			(end 0.67945 0.3048)
			(stroke
				(width 0.1)
				(type default)
			)
			(layer "F.Fab")
		)
		(fp_line
			(start -0.67945 -0.305054)
			(end -0.12065 -0.305054)
			(stroke
				(width 0.1)
				(type default)
			)
			(layer "F.Fab")
		)
		(fp_line
			(start -0.12065 -0.305054)
			(end -0.12065 -0.2794)
			(stroke
				(width 0.1)
				(type default)
			)
			(layer "F.Fab")
		)
		(pad "1" smd circle
			(at -0.40005 0 270)
			(size 0 0)
			(layers "F.Cu" "F.Mask" "F.Paste")
			(net "SSD3_AUX_P3V3_EN_R")
		)
		(pad "2" smd circle
			(at 0.40005 0 270)
			(size 0 0)
			(layers "F.Cu" "F.Mask" "F.Paste")
			(net "P3V3_SSD3_CO_EN")
		)
	)
	(footprint ""
		(layer "F.Cu")
		(at 449.704968 -254.5969 -90)
		(property "Reference" "C4394"
			(at 0 0 270)
			(layer "F.SilkS")
			(hide yes)
			(effects
				(font
					(size 1.27 1.27)
				)
			)
		)
		(property "Value" ""
			(at 0 0 270)
			(layer "F.Fab")
			(effects
				(font
					(size 1.27 1.27)
				)
			)
		)
		(duplicate_pad_numbers_are_jumpers no)
		(fp_line
			(start -1.2954 0.5842)
			(end -1.2954 -0.5842)
			(stroke
				(width 0.1524)
				(type default)
			)
			(layer "F.SilkS")
		)
		(fp_line
			(start 1.2954 0.5842)
			(end -1.2954 0.5842)
			(stroke
				(width 0.1524)
				(type default)
			)
			(layer "F.SilkS")
		)
		(fp_line
			(start -1.2954 -0.5842)
			(end 1.2954 -0.5842)
			(stroke
				(width 0.1524)
				(type default)
			)
			(layer "F.SilkS")
		)
		(fp_line
			(start 1.2954 -0.5842)
			(end 1.2954 0.5842)
			(stroke
				(width 0.1524)
				(type default)
			)
			(layer "F.SilkS")
		)
		(fp_line
			(start -0.8636 0.4572)
			(end -0.8636 0.4064)
			(stroke
				(width 0.1)
				(type default)
			)
			(layer "F.Fab")
		)
		(fp_line
			(start 0.8636 0.4572)
			(end -0.8636 0.4572)
			(stroke
				(width 0.1)
				(type default)
			)
			(layer "F.Fab")
		)
		(fp_line
			(start -1.1938 0.4064)
			(end -1.1938 -0.4064)
			(stroke
				(width 0.1)
				(type default)
			)
			(layer "F.Fab")
		)
		(fp_line
			(start -0.8636 0.4064)
			(end -1.1938 0.4064)
			(stroke
				(width 0.1)
				(type default)
			)
			(layer "F.Fab")
		)
		(fp_line
			(start 0.8636 0.4064)
			(end 0.8636 0.4572)
			(stroke
				(width 0.1)
				(type default)
			)
			(layer "F.Fab")
		)
		(fp_line
			(start 1.1938 0.4064)
			(end 0.8636 0.4064)
			(stroke
				(width 0.1)
				(type default)
			)
			(layer "F.Fab")
		)
		(fp_line
			(start -1.1938 -0.4064)
			(end -0.8636 -0.4064)
			(stroke
				(width 0.1)
				(type default)
			)
			(layer "F.Fab")
		)
		(fp_line
			(start -0.8636 -0.4064)
			(end -0.8636 -0.4572)
			(stroke
				(width 0.1)
				(type default)
			)
			(layer "F.Fab")
		)
		(fp_line
			(start 0.8636 -0.4064)
			(end 1.1938 -0.4064)
			(stroke
				(width 0.1)
				(type default)
			)
			(layer "F.Fab")
		)
		(fp_line
			(start 1.1938 -0.4064)
			(end 1.1938 0.4064)
			(stroke
				(width 0.1)
				(type default)
			)
			(layer "F.Fab")
		)
		(fp_line
			(start -0.8636 -0.4572)
			(end 0.8636 -0.4572)
			(stroke
				(width 0.1)
				(type default)
			)
			(layer "F.Fab")
		)
		(fp_line
			(start 0.8636 -0.4572)
			(end 0.8636 -0.4064)
			(stroke
				(width 0.1)
				(type default)
			)
			(layer "F.Fab")
		)
		(pad "1" smd rect
			(at -0.7366 0 180)
			(size 0.7112 0.8128)
			(layers "F.Cu" "F.Mask" "F.Paste")
			(net "P1V25_SERDES_VDDPLL_PEX3_C0")
		)
		(pad "2" smd rect
			(at 0.7366 0 180)
			(size 0.7112 0.8128)
			(layers "F.Cu" "F.Mask" "F.Paste")
			(net "GND")
		)
	)
	(footprint ""
		(layer "F.Cu")
		(at 228.562662 -288.017204)
		(property "Reference" "PC236"
			(at 0 0 0)
			(layer "F.SilkS")
			(hide yes)
			(effects
				(font
					(size 1.27 1.27)
				)
			)
		)
		(property "Value" ""
			(at 0 0 0)
			(layer "F.Fab")
			(effects
				(font
					(size 1.27 1.27)
				)
			)
		)
		(duplicate_pad_numbers_are_jumpers no)
		(fp_line
			(start -0.7874 -0.4064)
			(end 0.7874 -0.4064)
			(stroke
				(width 0.1524)
				(type default)
			)
			(layer "F.SilkS")
		)
		(fp_line
			(start -0.7874 0.4064)
			(end -0.7874 -0.4064)
			(stroke
				(width 0.1524)
				(type default)
			)
			(layer "F.SilkS")
		)
		(fp_line
			(start 0.7874 -0.4064)
			(end 0.7874 0.4064)
			(stroke
				(width 0.1524)
				(type default)
			)
			(layer "F.SilkS")
		)
		(fp_line
			(start 0.7874 0.4064)
			(end -0.7874 0.4064)
			(stroke
				(width 0.1524)
				(type default)
			)
			(layer "F.SilkS")
		)
		(fp_line
			(start -0.67945 -0.305054)
			(end -0.12065 -0.305054)
			(stroke
				(width 0.1)
				(type default)
			)
			(layer "F.Fab")
		)
		(fp_line
			(start -0.67945 0.3048)
			(end -0.67945 -0.305054)
			(stroke
				(width 0.1)
				(type default)
			)
			(layer "F.Fab")
		)
		(fp_line
			(start -0.12065 -0.305054)
			(end -0.12065 -0.2794)
			(stroke
				(width 0.1)
				(type default)
			)
			(layer "F.Fab")
		)
		(fp_line
			(start -0.12065 -0.2794)
			(end 0.12065 -0.2794)
			(stroke
				(width 0.1)
				(type default)
			)
			(layer "F.Fab")
		)
		(fp_line
			(start -0.12065 0.2794)
			(end -0.12065 0.3048)
			(stroke
				(width 0.1)
				(type default)
			)
			(layer "F.Fab")
		)
		(fp_line
			(start -0.12065 0.3048)
			(end -0.67945 0.3048)
			(stroke
				(width 0.1)
				(type default)
			)
			(layer "F.Fab")
		)
		(fp_line
			(start 0.120396 0.2794)
			(end -0.12065 0.2794)
			(stroke
				(width 0.1)
				(type default)
			)
			(layer "F.Fab")
		)
		(fp_line
			(start 0.120396 0.3048)
			(end 0.120396 0.2794)
			(stroke
				(width 0.1)
				(type default)
			)
			(layer "F.Fab")
		)
		(fp_line
			(start 0.12065 -0.3048)
			(end 0.67945 -0.3048)
			(stroke
				(width 0.1)
				(type default)
			)
			(layer "F.Fab")
		)
		(fp_line
			(start 0.12065 -0.2794)
			(end 0.12065 -0.3048)
			(stroke
				(width 0.1)
				(type default)
			)
			(layer "F.Fab")
		)
		(fp_line
			(start 0.67945 -0.3048)
			(end 0.67945 0.3048)
			(stroke
				(width 0.1)
				(type default)
			)
			(layer "F.Fab")
		)
		(fp_line
			(start 0.67945 0.3048)
			(end 0.120396 0.3048)
			(stroke
				(width 0.1)
				(type default)
			)
			(layer "F.Fab")
		)
		(pad "1" smd circle
			(at -0.40005 0)
			(size 0 0)
			(layers "F.Cu" "F.Mask" "F.Paste")
			(net "P1V25_PEX1_R")
		)
		(pad "2" smd circle
			(at 0.40005 0)
			(size 0 0)
			(layers "F.Cu" "F.Mask" "F.Paste")
			(net "GND")
		)
	)
	(footprint ""
		(layer "F.Cu")
		(at 392.092434 -32.739584 180)
		(property "Reference" "C708"
			(at 0 0 180)
			(layer "F.SilkS")
			(hide yes)
			(effects
				(font
					(size 1.27 1.27)
				)
			)
		)
		(property "Value" ""
			(at 0 0 180)
			(layer "F.Fab")
			(effects
				(font
					(size 1.27 1.27)
				)
			)
		)
		(duplicate_pad_numbers_are_jumpers no)
		(fp_line
			(start 0.299974 0.150114)
			(end -0.299974 0.150114)
			(stroke
				(width 0.1)
				(type default)
			)
			(layer "F.Fab")
		)
		(fp_line
			(start 0.299974 -0.150114)
			(end 0.299974 0.150114)
			(stroke
				(width 0.1)
				(type default)
			)
			(layer "F.Fab")
		)
		(fp_line
			(start -0.299974 0.150114)
			(end -0.299974 -0.150114)
			(stroke
				(width 0.1)
				(type default)
			)
			(layer "F.Fab")
		)
		(fp_line
			(start -0.299974 -0.150114)
			(end 0.299974 -0.150114)
			(stroke
				(width 0.1)
				(type default)
			)
			(layer "F.Fab")
		)
		(pad "1" smd rect
			(at -0.2667 0 180)
			(size 0.3048 0.381)
			(layers "F.Cu" "F.Mask" "F.Paste")
			(net "P5E_PEX3_STN2_TX_DP<42>")
		)
		(pad "2" smd rect
			(at 0.2667 0 180)
			(size 0.3048 0.381)
			(layers "F.Cu" "F.Mask" "F.Paste")
			(net "P5E_PEX3_STN2_TX_C_DP<42>")
		)
	)
	(footprint ""
		(layer "F.Cu")
		(at 242.316 -216.408 90)
		(property "Reference" "R6590"
			(at 0 0 90)
			(layer "F.SilkS")
			(hide yes)
			(effects
				(font
					(size 1.27 1.27)
				)
			)
		)
		(property "Value" ""
			(at 0 0 90)
			(layer "F.Fab")
			(effects
				(font
					(size 1.27 1.27)
				)
			)
		)
		(duplicate_pad_numbers_are_jumpers no)
		(fp_line
			(start 0.7874 -0.4064)
			(end 0.7874 0.4064)
			(stroke
				(width 0.1524)
				(type default)
			)
			(layer "F.SilkS")
		)
		(fp_line
			(start -0.7874 -0.4064)
			(end 0.7874 -0.4064)
			(stroke
				(width 0.1524)
				(type default)
			)
			(layer "F.SilkS")
		)
		(fp_line
			(start 0.7874 0.4064)
			(end -0.7874 0.4064)
			(stroke
				(width 0.1524)
				(type default)
			)
			(layer "F.SilkS")
		)
		(fp_line
			(start -0.7874 0.4064)
			(end -0.7874 -0.4064)
			(stroke
				(width 0.1524)
				(type default)
			)
			(layer "F.SilkS")
		)
		(fp_line
			(start -0.12065 -0.305054)
			(end -0.12065 -0.2794)
			(stroke
				(width 0.1)
				(type default)
			)
			(layer "F.Fab")
		)
		(fp_line
			(start -0.67945 -0.305054)
			(end -0.12065 -0.305054)
			(stroke
				(width 0.1)
				(type default)
			)
			(layer "F.Fab")
		)
		(fp_line
			(start 0.67945 -0.3048)
			(end 0.67945 0.3048)
			(stroke
				(width 0.1)
				(type default)
			)
			(layer "F.Fab")
		)
		(fp_line
			(start 0.12065 -0.3048)
			(end 0.67945 -0.3048)
			(stroke
				(width 0.1)
				(type default)
			)
			(layer "F.Fab")
		)
		(fp_line
			(start 0.12065 -0.2794)
			(end 0.12065 -0.3048)
			(stroke
				(width 0.1)
				(type default)
			)
			(layer "F.Fab")
		)
		(fp_line
			(start -0.12065 -0.2794)
			(end 0.12065 -0.2794)
			(stroke
				(width 0.1)
				(type default)
			)
			(layer "F.Fab")
		)
		(fp_line
			(start 0.120396 0.2794)
			(end -0.12065 0.2794)
			(stroke
				(width 0.1)
				(type default)
			)
			(layer "F.Fab")
		)
		(fp_line
			(start -0.12065 0.2794)
			(end -0.12065 0.3048)
			(stroke
				(width 0.1)
				(type default)
			)
			(layer "F.Fab")
		)
		(fp_line
			(start 0.67945 0.3048)
			(end 0.120396 0.3048)
			(stroke
				(width 0.1)
				(type default)
			)
			(layer "F.Fab")
		)
		(fp_line
			(start 0.120396 0.3048)
			(end 0.120396 0.2794)
			(stroke
				(width 0.1)
				(type default)
			)
			(layer "F.Fab")
		)
		(fp_line
			(start -0.12065 0.3048)
			(end -0.67945 0.3048)
			(stroke
				(width 0.1)
				(type default)
			)
			(layer "F.Fab")
		)
		(fp_line
			(start -0.67945 0.3048)
			(end -0.67945 -0.305054)
			(stroke
				(width 0.1)
				(type default)
			)
			(layer "F.Fab")
		)
		(pad "1" smd circle
			(at -0.40005 0 90)
			(size 0 0)
			(layers "F.Cu" "F.Mask" "F.Paste")
			(net "P1V8_PLL0_PEX0_SCALED")
		)
		(pad "2" smd circle
			(at 0.40005 0 90)
			(size 0 0)
			(layers "F.Cu" "F.Mask" "F.Paste")
			(net "GND")
		)
	)
	(footprint ""
		(layer "F.Cu")
		(at 9.32942 -273.906488)
		(property "Reference" "R778"
			(at 0 0 0)
			(layer "F.SilkS")
			(hide yes)
			(effects
				(font
					(size 1.27 1.27)
				)
			)
		)
		(property "Value" ""
			(at 0 0 0)
			(layer "F.Fab")
			(effects
				(font
					(size 1.27 1.27)
				)
			)
		)
		(duplicate_pad_numbers_are_jumpers no)
		(fp_line
			(start -0.7874 -0.4064)
			(end 0.7874 -0.4064)
			(stroke
				(width 0.1524)
				(type default)
			)
			(layer "F.SilkS")
		)
		(fp_line
			(start -0.7874 0.4064)
			(end -0.7874 -0.4064)
			(stroke
				(width 0.1524)
				(type default)
			)
			(layer "F.SilkS")
		)
		(fp_line
			(start 0.7874 -0.4064)
			(end 0.7874 0.4064)
			(stroke
				(width 0.1524)
				(type default)
			)
			(layer "F.SilkS")
		)
		(fp_line
			(start 0.7874 0.4064)
			(end -0.7874 0.4064)
			(stroke
				(width 0.1524)
				(type default)
			)
			(layer "F.SilkS")
		)
		(fp_line
			(start -0.67945 -0.305054)
			(end -0.12065 -0.305054)
			(stroke
				(width 0.1)
				(type default)
			)
			(layer "F.Fab")
		)
		(fp_line
			(start -0.67945 0.3048)
			(end -0.67945 -0.305054)
			(stroke
				(width 0.1)
				(type default)
			)
			(layer "F.Fab")
		)
		(fp_line
			(start -0.12065 -0.305054)
			(end -0.12065 -0.2794)
			(stroke
				(width 0.1)
				(type default)
			)
			(layer "F.Fab")
		)
		(fp_line
			(start -0.12065 -0.2794)
			(end 0.12065 -0.2794)
			(stroke
				(width 0.1)
				(type default)
			)
			(layer "F.Fab")
		)
		(fp_line
			(start -0.12065 0.2794)
			(end -0.12065 0.3048)
			(stroke
				(width 0.1)
				(type default)
			)
			(layer "F.Fab")
		)
		(fp_line
			(start -0.12065 0.3048)
			(end -0.67945 0.3048)
			(stroke
				(width 0.1)
				(type default)
			)
			(layer "F.Fab")
		)
		(fp_line
			(start 0.120396 0.2794)
			(end -0.12065 0.2794)
			(stroke
				(width 0.1)
				(type default)
			)
			(layer "F.Fab")
		)
		(fp_line
			(start 0.120396 0.3048)
			(end 0.120396 0.2794)
			(stroke
				(width 0.1)
				(type default)
			)
			(layer "F.Fab")
		)
		(fp_line
			(start 0.12065 -0.3048)
			(end 0.67945 -0.3048)
			(stroke
				(width 0.1)
				(type default)
			)
			(layer "F.Fab")
		)
		(fp_line
			(start 0.12065 -0.2794)
			(end 0.12065 -0.3048)
			(stroke
				(width 0.1)
				(type default)
			)
			(layer "F.Fab")
		)
		(fp_line
			(start 0.67945 -0.3048)
			(end 0.67945 0.3048)
			(stroke
				(width 0.1)
				(type default)
			)
			(layer "F.Fab")
		)
		(fp_line
			(start 0.67945 0.3048)
			(end 0.120396 0.3048)
			(stroke
				(width 0.1)
				(type default)
			)
			(layer "F.Fab")
		)
		(pad "1" smd circle
			(at -0.40005 0)
			(size 0 0)
			(layers "F.Cu" "F.Mask" "F.Paste")
			(net "P1V25_PEX0")
		)
		(pad "2" smd circle
			(at 0.40005 0)
			(size 0 0)
			(layers "F.Cu" "F.Mask" "F.Paste")
			(net "P12V_PEX0_P1V25_VIN_N")
		)
	)
	(footprint ""
		(layer "F.Cu")
		(at 100.136198 -95.264224 -90)
		(property "Reference" "C2855"
			(at 0 0 270)
			(layer "F.SilkS")
			(hide yes)
			(effects
				(font
					(size 1.27 1.27)
				)
			)
		)
		(property "Value" ""
			(at 0 0 270)
			(layer "F.Fab")
			(effects
				(font
					(size 1.27 1.27)
				)
			)
		)
		(duplicate_pad_numbers_are_jumpers no)
		(fp_line
			(start -0.7874 0.4064)
			(end -0.7874 -0.4064)
			(stroke
				(width 0.1524)
				(type default)
			)
			(layer "F.SilkS")
		)
		(fp_line
			(start 0.7874 0.4064)
			(end -0.7874 0.4064)
			(stroke
				(width 0.1524)
				(type default)
			)
			(layer "F.SilkS")
		)
		(fp_line
			(start -0.7874 -0.4064)
			(end 0.7874 -0.4064)
			(stroke
				(width 0.1524)
				(type default)
			)
			(layer "F.SilkS")
		)
		(fp_line
			(start 0.7874 -0.4064)
			(end 0.7874 0.4064)
			(stroke
				(width 0.1524)
				(type default)
			)
			(layer "F.SilkS")
		)
		(fp_line
			(start -0.67945 0.3048)
			(end -0.67945 -0.305054)
			(stroke
				(width 0.1)
				(type default)
			)
			(layer "F.Fab")
		)
		(fp_line
			(start -0.12065 0.3048)
			(end -0.67945 0.3048)
			(stroke
				(width 0.1)
				(type default)
			)
			(layer "F.Fab")
		)
		(fp_line
			(start 0.120396 0.3048)
			(end 0.120396 0.2794)
			(stroke
				(width 0.1)
				(type default)
			)
			(layer "F.Fab")
		)
		(fp_line
			(start 0.67945 0.3048)
			(end 0.120396 0.3048)
			(stroke
				(width 0.1)
				(type default)
			)
			(layer "F.Fab")
		)
		(fp_line
			(start -0.12065 0.2794)
			(end -0.12065 0.3048)
			(stroke
				(width 0.1)
				(type default)
			)
			(layer "F.Fab")
		)
		(fp_line
			(start 0.120396 0.2794)
			(end -0.12065 0.2794)
			(stroke
				(width 0.1)
				(type default)
			)
			(layer "F.Fab")
		)
		(fp_line
			(start -0.12065 -0.2794)
			(end 0.12065 -0.2794)
			(stroke
				(width 0.1)
				(type default)
			)
			(layer "F.Fab")
		)
		(fp_line
			(start 0.12065 -0.2794)
			(end 0.12065 -0.3048)
			(stroke
				(width 0.1)
				(type default)
			)
			(layer "F.Fab")
		)
		(fp_line
			(start 0.12065 -0.3048)
			(end 0.67945 -0.3048)
			(stroke
				(width 0.1)
				(type default)
			)
			(layer "F.Fab")
		)
		(fp_line
			(start 0.67945 -0.3048)
			(end 0.67945 0.3048)
			(stroke
				(width 0.1)
				(type default)
			)
			(layer "F.Fab")
		)
		(fp_line
			(start -0.67945 -0.305054)
			(end -0.12065 -0.305054)
			(stroke
				(width 0.1)
				(type default)
			)
			(layer "F.Fab")
		)
		(fp_line
			(start -0.12065 -0.305054)
			(end -0.12065 -0.2794)
			(stroke
				(width 0.1)
				(type default)
			)
			(layer "F.Fab")
		)
		(pad "1" smd circle
			(at -0.40005 0 270)
			(size 0 0)
			(layers "F.Cu" "F.Mask" "F.Paste")
			(net "P12V_NIC1_EN_R")
		)
		(pad "2" smd circle
			(at 0.40005 0 270)
			(size 0 0)
			(layers "F.Cu" "F.Mask" "F.Paste")
			(net "GND")
		)
	)
	(footprint ""
		(layer "F.Cu")
		(at 122.991118 -55.663846 90)
		(property "Reference" "PU55"
			(at -1.267206 2.608834 90)
			(unlocked yes)
			(layer "F.SilkS")
			(effects
				(font
					(size 0.7874 0.5842)
					(thickness 0.1524)
				)
				(justify left)
			)
		)
		(property "Value" ""
			(at 0 0 90)
			(layer "F.Fab")
			(effects
				(font
					(size 1.27 1.27)
				)
			)
		)
		(duplicate_pad_numbers_are_jumpers no)
		(fp_line
			(start 1.943608 -1.549908)
			(end 1.943608 1.549908)
			(stroke
				(width 0.1524)
				(type default)
			)
			(layer "F.SilkS")
		)
		(fp_line
			(start -1.943608 -1.549908)
			(end 1.943608 -1.549908)
			(stroke
				(width 0.1524)
				(type default)
			)
			(layer "F.SilkS")
		)
		(fp_line
			(start 1.943608 1.549908)
			(end -1.943608 1.549908)
			(stroke
				(width 0.1524)
				(type default)
			)
			(layer "F.SilkS")
		)
		(fp_line
			(start -1.943608 1.549908)
			(end -1.943608 -1.549908)
			(stroke
				(width 0.1524)
				(type default)
			)
			(layer "F.SilkS")
		)
		(fp_poly
			(pts
				(xy -2.019808 -1.549908) (xy -1.257808 -1.549908) (xy -1.257808 -1.880108) (xy -2.019808 -1.880108)
			)
			(stroke
				(width 0)
				(type default)
			)
			(fill yes)
			(layer "F.SilkS")
		)
		(fp_line
			(start 1.549908 -1.549908)
			(end 1.549908 1.549908)
			(stroke
				(width 0.1)
				(type default)
			)
			(layer "F.Fab")
		)
		(fp_line
			(start -1.549908 -1.549908)
			(end 1.549908 -1.549908)
			(stroke
				(width 0.1)
				(type default)
			)
			(layer "F.Fab")
		)
		(fp_line
			(start 1.549908 1.549908)
			(end -1.549908 1.549908)
			(stroke
				(width 0.1)
				(type default)
			)
			(layer "F.Fab")
		)
		(fp_line
			(start -1.549908 1.549908)
			(end -1.549908 -1.549908)
			(stroke
				(width 0.1)
				(type default)
			)
			(layer "F.Fab")
		)
		(fp_poly
			(pts
				(xy -2.019808 -1.549908) (xy -1.257808 -1.549908) (xy -1.257808 -1.880108) (xy -2.019808 -1.880108)
			)
			(stroke
				(width 0)
				(type default)
			)
			(fill yes)
			(layer "F.Fab")
		)
		(pad "1" smd rect
			(at -1.500124 -1.249934)
			(size 0.2794 0.6096)
			(layers "F.Cu" "F.Mask" "F.Paste")
			(net "P3V3_SSD4")
		)
		(pad "2" smd rect
			(at -1.500124 -0.750062)
			(size 0.2794 0.6096)
			(layers "F.Cu" "F.Mask" "F.Paste")
			(net "P3V3_SSD4")
		)
		(pad "3" smd rect
			(at -1.500124 -0.249936)
			(size 0.2794 0.6096)
			(layers "F.Cu" "F.Mask" "F.Paste")
			(net "P3V3_SSD4")
		)
		(pad "4" smd rect
			(at -1.500124 0.249936)
			(size 0.2794 0.6096)
			(layers "F.Cu" "F.Mask" "F.Paste")
			(net "P3V3_SSD4")
		)
		(pad "5" smd rect
			(at -1.500124 0.750062)
			(size 0.2794 0.6096)
			(layers "F.Cu" "F.Mask" "F.Paste")
			(net "P3V3_SSD4")
		)
		(pad "6" smd rect
			(at -1.500124 1.249934)
			(size 0.2794 0.6096)
			(layers "F.Cu" "F.Mask" "F.Paste")
			(net "GND")
		)
		(pad "7" smd rect
			(at 1.500124 1.249934)
			(size 0.2794 0.6096)
			(layers "F.Cu" "F.Mask" "F.Paste")
			(net "P3V3_SSD4_SS")
		)
		(pad "8" smd rect
			(at 1.500124 0.750062)
			(size 0.2794 0.6096)
			(layers "F.Cu" "F.Mask" "F.Paste")
			(net "PWRGD_P3V3_SSD4")
		)
		(pad "9" smd rect
			(at 1.500124 0.249936)
			(size 0.2794 0.6096)
			(layers "F.Cu" "F.Mask" "F.Paste")
			(net "P3V3_SSD4_OCP")
		)
		(pad "10" smd rect
			(at 1.500124 -0.249936)
			(size 0.2794 0.6096)
			(layers "F.Cu" "F.Mask" "F.Paste")
			(net "P5V_AUX")
		)
		(pad "11" smd rect
			(at 1.500124 -0.750062)
			(size 0.2794 0.6096)
			(layers "F.Cu" "F.Mask" "F.Paste")
			(net "SSD4_AUX_P3V3_EN_R")
		)
		(pad "12" smd rect
			(at 1.500124 -1.249934)
			(size 0.2794 0.6096)
			(layers "F.Cu" "F.Mask" "F.Paste")
			(net "P3V3_AUX")
		)
		(pad "13" smd rect
			(at 0 0 90)
			(size 1.9812 2.7178)
			(layers "F.Cu" "F.Mask" "F.Paste")
			(net "P3V3_AUX")
		)
		(zone
			(layer "F.Cu")
			(hatch none 0.5)
			(connect_pads
				(clearance 0)
			)
			(min_thickness 0.25)
			(keepout
				(tracks not_allowed)
				(vias allowed)
				(pads allowed)
				(copperpour not_allowed)
				(footprints allowed)
			)
			(placement
				(enabled no)
				(sheetname "")
			)
			(fill
				(thermal_gap 0.5)
				(thermal_bridge_width 0.5)
				(island_removal_mode 0)
			)
			(polygon
				(pts
					(xy 121.441718 -56.806846) (xy 121.568718 -56.806846) (xy 124.540518 -56.806846) (xy 124.541026 -56.806846)
					(xy 124.541026 -54.520846) (xy 124.540518 -54.520846) (xy 124.413518 -54.520846) (xy 122.991118 -54.520846)
					(xy 122.991118 -54.622446) (xy 124.413518 -54.622446) (xy 124.413518 -56.705246) (xy 121.568718 -56.705246)
					(xy 121.568718 -54.622446) (xy 122.965718 -54.622446) (xy 122.965718 -54.520846) (xy 121.568718 -54.520846)
					(xy 121.441718 -54.520846) (xy 121.44121 -54.520846) (xy 121.44121 -56.806846)
				)
			)
		)
	)
	(footprint ""
		(layer "F.Cu")
		(at 234.355894 -183.02478 180)
		(property "Reference" "D12"
			(at 1.326388 1.601724 0)
			(unlocked yes)
			(layer "F.SilkS")
			(effects
				(font
					(size 0.7874 0.5842)
					(thickness 0.1524)
				)
				(justify left)
			)
		)
		(property "Value" ""
			(at 0 0 180)
			(layer "F.Fab")
			(effects
				(font
					(size 1.27 1.27)
				)
			)
		)
		(duplicate_pad_numbers_are_jumpers no)
		(fp_line
			(start 2.032 0.7112)
			(end -1.651 0.7112)
			(stroke
				(width 0.1524)
				(type default)
			)
			(layer "F.SilkS")
		)
		(fp_line
			(start 2.032 -0.7112)
			(end 2.032 0.7112)
			(stroke
				(width 0.1524)
				(type default)
			)
			(layer "F.SilkS")
		)
		(fp_line
			(start 1.905 -0.6858)
			(end 1.905 0.6858)
			(stroke
				(width 0.1524)
				(type default)
			)
			(layer "F.SilkS")
		)
		(fp_line
			(start 1.778 0.6858)
			(end 1.778 -0.6858)
			(stroke
				(width 0.1524)
				(type default)
			)
			(layer "F.SilkS")
		)
		(fp_line
			(start 1.651 -0.6858)
			(end 1.651 0.6858)
			(stroke
				(width 0.1524)
				(type default)
			)
			(layer "F.SilkS")
		)
		(fp_line
			(start 0.299974 -0.500126)
			(end 0.299974 0.500126)
			(stroke
				(width 0.1524)
				(type default)
			)
			(layer "F.SilkS")
		)
		(fp_line
			(start 0.199898 0)
			(end -0.299974 -0.500126)
			(stroke
				(width 0.1524)
				(type default)
			)
			(layer "F.SilkS")
		)
		(fp_line
			(start -0.299974 0.500126)
			(end 0.199898 0)
			(stroke
				(width 0.1524)
				(type default)
			)
			(layer "F.SilkS")
		)
		(fp_line
			(start -0.299974 -0.500126)
			(end -0.299974 0.500126)
			(stroke
				(width 0.1524)
				(type default)
			)
			(layer "F.SilkS")
		)
		(fp_line
			(start -1.651 0.7112)
			(end -1.651 -0.7112)
			(stroke
				(width 0.1524)
				(type default)
			)
			(layer "F.SilkS")
		)
		(fp_line
			(start -1.651 -0.7112)
			(end 2.032 -0.7112)
			(stroke
				(width 0.1524)
				(type default)
			)
			(layer "F.SilkS")
		)
		(fp_line
			(start 1.35001 0.175006)
			(end 0.899922 0.175006)
			(stroke
				(width 0.1)
				(type default)
			)
			(layer "F.Fab")
		)
		(fp_line
			(start 1.35001 -0.225044)
			(end 1.35001 0.175006)
			(stroke
				(width 0.1)
				(type default)
			)
			(layer "F.Fab")
		)
		(fp_line
			(start 0.899922 0.700024)
			(end -0.899922 0.700024)
			(stroke
				(width 0.1)
				(type default)
			)
			(layer "F.Fab")
		)
		(fp_line
			(start 0.899922 0.175006)
			(end 0.899922 0.700024)
			(stroke
				(width 0.1)
				(type default)
			)
			(layer "F.Fab")
		)
		(fp_line
			(start 0.899922 -0.225044)
			(end 1.35001 -0.225044)
			(stroke
				(width 0.1)
				(type default)
			)
			(layer "F.Fab")
		)
		(fp_line
			(start 0.899922 -0.700024)
			(end 0.899922 -0.225044)
			(stroke
				(width 0.1)
				(type default)
			)
			(layer "F.Fab")
		)
		(fp_line
			(start 0.299974 -0.500126)
			(end 0.299974 0.500126)
			(stroke
				(width 0.1)
				(type default)
			)
			(layer "F.Fab")
		)
		(fp_line
			(start 0.199898 0)
			(end -0.299974 -0.500126)
			(stroke
				(width 0.1)
				(type default)
			)
			(layer "F.Fab")
		)
		(fp_line
			(start -0.299974 0.500126)
			(end 0.199898 0)
			(stroke
				(width 0.1)
				(type default)
			)
			(layer "F.Fab")
		)
		(fp_line
			(start -0.299974 -0.500126)
			(end -0.299974 0.500126)
			(stroke
				(width 0.1)
				(type default)
			)
			(layer "F.Fab")
		)
		(fp_line
			(start -0.899922 0.700024)
			(end -0.899922 0.175006)
			(stroke
				(width 0.1)
				(type default)
			)
			(layer "F.Fab")
		)
		(fp_line
			(start -0.899922 0.175006)
			(end -1.35001 0.175006)
			(stroke
				(width 0.1)
				(type default)
			)
			(layer "F.Fab")
		)
		(fp_line
			(start -0.899922 -0.225044)
			(end -0.899922 -0.700024)
			(stroke
				(width 0.1)
				(type default)
			)
			(layer "F.Fab")
		)
		(fp_line
			(start -0.899922 -0.700024)
			(end 0.899922 -0.700024)
			(stroke
				(width 0.1)
				(type default)
			)
			(layer "F.Fab")
		)
		(fp_line
			(start -1.35001 0.175006)
			(end -1.35001 -0.225044)
			(stroke
				(width 0.1)
				(type default)
			)
			(layer "F.Fab")
		)
		(fp_line
			(start -1.35001 -0.225044)
			(end -0.899922 -0.225044)
			(stroke
				(width 0.1)
				(type default)
			)
			(layer "F.Fab")
		)
		(fp_text user "-"
			(at 1.820418 0.676148 180)
			(unlocked yes)
			(layer "F.SilkS")
			(effects
				(font
					(size 1.905 1.4224)
					(thickness 0.1524)
				)
				(justify left)
			)
		)
		(fp_text user "+"
			(at -2.860294 -1.041908 180)
			(unlocked yes)
			(layer "F.SilkS")
			(effects
				(font
					(size 1.905 1.4224)
					(thickness 0.1524)
				)
				(justify left)
			)
		)
		(fp_text user "-"
			(at 1.8288 -0.24765 180)
			(unlocked yes)
			(layer "F.Fab")
			(effects
				(font
					(size 1.905 1.4224)
					(thickness 0.1524)
				)
				(justify left)
			)
		)
		(fp_text user "+"
			(at -2.794 -0.19685 180)
			(unlocked yes)
			(layer "F.Fab")
			(effects
				(font
					(size 1.905 1.4224)
					(thickness 0.1524)
				)
				(justify left)
			)
		)
		(pad "1" smd rect
			(at -1.0922 0)
			(size 0.8128 0.8636)
			(layers "F.Cu" "F.Mask" "F.Paste")
			(net "RST_BIC_EXTRST_N")
		)
		(pad "2" smd rect
			(at 1.0922 0 180)
			(size 0.8128 0.8636)
			(layers "F.Cu" "F.Mask" "F.Paste")
			(net "RST_FPGA_BIC_R_N")
		)
	)
	(footprint ""
		(layer "F.Cu")
		(at 284.264354 -166.302944 90)
		(property "Reference" "R250"
			(at 0 0 90)
			(layer "F.SilkS")
			(hide yes)
			(effects
				(font
					(size 1.27 1.27)
				)
			)
		)
		(property "Value" ""
			(at 0 0 90)
			(layer "F.Fab")
			(effects
				(font
					(size 1.27 1.27)
				)
			)
		)
		(duplicate_pad_numbers_are_jumpers no)
		(fp_line
			(start 0.7874 -0.4064)
			(end 0.7874 0.4064)
			(stroke
				(width 0.1524)
				(type default)
			)
			(layer "F.SilkS")
		)
		(fp_line
			(start -0.7874 -0.4064)
			(end 0.7874 -0.4064)
			(stroke
				(width 0.1524)
				(type default)
			)
			(layer "F.SilkS")
		)
		(fp_line
			(start 0.7874 0.4064)
			(end -0.7874 0.4064)
			(stroke
				(width 0.1524)
				(type default)
			)
			(layer "F.SilkS")
		)
		(fp_line
			(start -0.7874 0.4064)
			(end -0.7874 -0.4064)
			(stroke
				(width 0.1524)
				(type default)
			)
			(layer "F.SilkS")
		)
		(fp_line
			(start -0.12065 -0.305054)
			(end -0.12065 -0.2794)
			(stroke
				(width 0.1)
				(type default)
			)
			(layer "F.Fab")
		)
		(fp_line
			(start -0.67945 -0.305054)
			(end -0.12065 -0.305054)
			(stroke
				(width 0.1)
				(type default)
			)
			(layer "F.Fab")
		)
		(fp_line
			(start 0.67945 -0.3048)
			(end 0.67945 0.3048)
			(stroke
				(width 0.1)
				(type default)
			)
			(layer "F.Fab")
		)
		(fp_line
			(start 0.12065 -0.3048)
			(end 0.67945 -0.3048)
			(stroke
				(width 0.1)
				(type default)
			)
			(layer "F.Fab")
		)
		(fp_line
			(start 0.12065 -0.2794)
			(end 0.12065 -0.3048)
			(stroke
				(width 0.1)
				(type default)
			)
			(layer "F.Fab")
		)
		(fp_line
			(start -0.12065 -0.2794)
			(end 0.12065 -0.2794)
			(stroke
				(width 0.1)
				(type default)
			)
			(layer "F.Fab")
		)
		(fp_line
			(start 0.120396 0.2794)
			(end -0.12065 0.2794)
			(stroke
				(width 0.1)
				(type default)
			)
			(layer "F.Fab")
		)
		(fp_line
			(start -0.12065 0.2794)
			(end -0.12065 0.3048)
			(stroke
				(width 0.1)
				(type default)
			)
			(layer "F.Fab")
		)
		(fp_line
			(start 0.67945 0.3048)
			(end 0.120396 0.3048)
			(stroke
				(width 0.1)
				(type default)
			)
			(layer "F.Fab")
		)
		(fp_line
			(start 0.120396 0.3048)
			(end 0.120396 0.2794)
			(stroke
				(width 0.1)
				(type default)
			)
			(layer "F.Fab")
		)
		(fp_line
			(start -0.12065 0.3048)
			(end -0.67945 0.3048)
			(stroke
				(width 0.1)
				(type default)
			)
			(layer "F.Fab")
		)
		(fp_line
			(start -0.67945 0.3048)
			(end -0.67945 -0.305054)
			(stroke
				(width 0.1)
				(type default)
			)
			(layer "F.Fab")
		)
		(pad "1" smd circle
			(at -0.40005 0 90)
			(size 0 0)
			(layers "F.Cu" "F.Mask" "F.Paste")
			(net "RST_NIC4_PERST1_R_N")
		)
		(pad "2" smd circle
			(at 0.40005 0 90)
			(size 0 0)
			(layers "F.Cu" "F.Mask" "F.Paste")
			(net "RST_HP_NIC4_BUF_N")
		)
	)
	(footprint ""
		(layer "F.Cu")
		(at 310.443626 -42.84091)
		(property "Reference" "R616"
			(at 0 0 0)
			(layer "F.SilkS")
			(hide yes)
			(effects
				(font
					(size 1.27 1.27)
				)
			)
		)
		(property "Value" ""
			(at 0 0 0)
			(layer "F.Fab")
			(effects
				(font
					(size 1.27 1.27)
				)
			)
		)
		(duplicate_pad_numbers_are_jumpers no)
		(fp_line
			(start -0.7874 -0.4064)
			(end 0.7874 -0.4064)
			(stroke
				(width 0.1524)
				(type default)
			)
			(layer "F.SilkS")
		)
		(fp_line
			(start -0.7874 0.4064)
			(end -0.7874 -0.4064)
			(stroke
				(width 0.1524)
				(type default)
			)
			(layer "F.SilkS")
		)
		(fp_line
			(start 0.7874 -0.4064)
			(end 0.7874 0.4064)
			(stroke
				(width 0.1524)
				(type default)
			)
			(layer "F.SilkS")
		)
		(fp_line
			(start 0.7874 0.4064)
			(end -0.7874 0.4064)
			(stroke
				(width 0.1524)
				(type default)
			)
			(layer "F.SilkS")
		)
		(fp_line
			(start -0.67945 -0.305054)
			(end -0.12065 -0.305054)
			(stroke
				(width 0.1)
				(type default)
			)
			(layer "F.Fab")
		)
		(fp_line
			(start -0.67945 0.3048)
			(end -0.67945 -0.305054)
			(stroke
				(width 0.1)
				(type default)
			)
			(layer "F.Fab")
		)
		(fp_line
			(start -0.12065 -0.305054)
			(end -0.12065 -0.2794)
			(stroke
				(width 0.1)
				(type default)
			)
			(layer "F.Fab")
		)
		(fp_line
			(start -0.12065 -0.2794)
			(end 0.12065 -0.2794)
			(stroke
				(width 0.1)
				(type default)
			)
			(layer "F.Fab")
		)
		(fp_line
			(start -0.12065 0.2794)
			(end -0.12065 0.3048)
			(stroke
				(width 0.1)
				(type default)
			)
			(layer "F.Fab")
		)
		(fp_line
			(start -0.12065 0.3048)
			(end -0.67945 0.3048)
			(stroke
				(width 0.1)
				(type default)
			)
			(layer "F.Fab")
		)
		(fp_line
			(start 0.120396 0.2794)
			(end -0.12065 0.2794)
			(stroke
				(width 0.1)
				(type default)
			)
			(layer "F.Fab")
		)
		(fp_line
			(start 0.120396 0.3048)
			(end 0.120396 0.2794)
			(stroke
				(width 0.1)
				(type default)
			)
			(layer "F.Fab")
		)
		(fp_line
			(start 0.12065 -0.3048)
			(end 0.67945 -0.3048)
			(stroke
				(width 0.1)
				(type default)
			)
			(layer "F.Fab")
		)
		(fp_line
			(start 0.12065 -0.2794)
			(end 0.12065 -0.3048)
			(stroke
				(width 0.1)
				(type default)
			)
			(layer "F.Fab")
		)
		(fp_line
			(start 0.67945 -0.3048)
			(end 0.67945 0.3048)
			(stroke
				(width 0.1)
				(type default)
			)
			(layer "F.Fab")
		)
		(fp_line
			(start 0.67945 0.3048)
			(end 0.120396 0.3048)
			(stroke
				(width 0.1)
				(type default)
			)
			(layer "F.Fab")
		)
		(pad "1" smd circle
			(at -0.40005 0)
			(size 0 0)
			(layers "F.Cu" "F.Mask" "F.Paste")
			(net "SSD10_ADC_A1")
		)
		(pad "2" smd circle
			(at 0.40005 0)
			(size 0 0)
			(layers "F.Cu" "F.Mask" "F.Paste")
			(net "P3V3_AUX")
		)
	)
	(footprint ""
		(layer "F.Cu")
		(at 344.678 -205.232 90)
		(property "Reference" "R4145"
			(at 0 0 90)
			(layer "F.SilkS")
			(hide yes)
			(effects
				(font
					(size 1.27 1.27)
				)
			)
		)
		(property "Value" ""
			(at 0 0 90)
			(layer "F.Fab")
			(effects
				(font
					(size 1.27 1.27)
				)
			)
		)
		(duplicate_pad_numbers_are_jumpers no)
		(fp_line
			(start 0.7874 -0.4064)
			(end 0.7874 0.4064)
			(stroke
				(width 0.1524)
				(type default)
			)
			(layer "F.SilkS")
		)
		(fp_line
			(start -0.7874 -0.4064)
			(end 0.7874 -0.4064)
			(stroke
				(width 0.1524)
				(type default)
			)
			(layer "F.SilkS")
		)
		(fp_line
			(start 0.7874 0.4064)
			(end -0.7874 0.4064)
			(stroke
				(width 0.1524)
				(type default)
			)
			(layer "F.SilkS")
		)
		(fp_line
			(start -0.7874 0.4064)
			(end -0.7874 -0.4064)
			(stroke
				(width 0.1524)
				(type default)
			)
			(layer "F.SilkS")
		)
		(fp_line
			(start -0.12065 -0.305054)
			(end -0.12065 -0.2794)
			(stroke
				(width 0.1)
				(type default)
			)
			(layer "F.Fab")
		)
		(fp_line
			(start -0.67945 -0.305054)
			(end -0.12065 -0.305054)
			(stroke
				(width 0.1)
				(type default)
			)
			(layer "F.Fab")
		)
		(fp_line
			(start 0.67945 -0.3048)
			(end 0.67945 0.3048)
			(stroke
				(width 0.1)
				(type default)
			)
			(layer "F.Fab")
		)
		(fp_line
			(start 0.12065 -0.3048)
			(end 0.67945 -0.3048)
			(stroke
				(width 0.1)
				(type default)
			)
			(layer "F.Fab")
		)
		(fp_line
			(start 0.12065 -0.2794)
			(end 0.12065 -0.3048)
			(stroke
				(width 0.1)
				(type default)
			)
			(layer "F.Fab")
		)
		(fp_line
			(start -0.12065 -0.2794)
			(end 0.12065 -0.2794)
			(stroke
				(width 0.1)
				(type default)
			)
			(layer "F.Fab")
		)
		(fp_line
			(start 0.120396 0.2794)
			(end -0.12065 0.2794)
			(stroke
				(width 0.1)
				(type default)
			)
			(layer "F.Fab")
		)
		(fp_line
			(start -0.12065 0.2794)
			(end -0.12065 0.3048)
			(stroke
				(width 0.1)
				(type default)
			)
			(layer "F.Fab")
		)
		(fp_line
			(start 0.67945 0.3048)
			(end 0.120396 0.3048)
			(stroke
				(width 0.1)
				(type default)
			)
			(layer "F.Fab")
		)
		(fp_line
			(start 0.120396 0.3048)
			(end 0.120396 0.2794)
			(stroke
				(width 0.1)
				(type default)
			)
			(layer "F.Fab")
		)
		(fp_line
			(start -0.12065 0.3048)
			(end -0.67945 0.3048)
			(stroke
				(width 0.1)
				(type default)
			)
			(layer "F.Fab")
		)
		(fp_line
			(start -0.67945 0.3048)
			(end -0.67945 -0.305054)
			(stroke
				(width 0.1)
				(type default)
			)
			(layer "F.Fab")
		)
		(pad "1" smd circle
			(at -0.40005 0 90)
			(size 0 0)
			(layers "F.Cu" "F.Mask" "F.Paste")
			(net "RST_SSD15_PERST_R_N")
		)
		(pad "2" smd circle
			(at 0.40005 0 90)
			(size 0 0)
			(layers "F.Cu" "F.Mask" "F.Paste")
			(net "RST_SSD15_PERST_N")
		)
	)
	(footprint ""
		(layer "F.Cu")
		(at 198.913496 -113.41354 180)
		(property "Reference" "R185"
			(at 0 0 180)
			(layer "F.SilkS")
			(hide yes)
			(effects
				(font
					(size 1.27 1.27)
				)
			)
		)
		(property "Value" ""
			(at 0 0 180)
			(layer "F.Fab")
			(effects
				(font
					(size 1.27 1.27)
				)
			)
		)
		(duplicate_pad_numbers_are_jumpers no)
		(fp_line
			(start 0.7874 0.4064)
			(end -0.7874 0.4064)
			(stroke
				(width 0.1524)
				(type default)
			)
			(layer "F.SilkS")
		)
		(fp_line
			(start 0.7874 -0.4064)
			(end 0.7874 0.4064)
			(stroke
				(width 0.1524)
				(type default)
			)
			(layer "F.SilkS")
		)
		(fp_line
			(start -0.7874 0.4064)
			(end -0.7874 -0.4064)
			(stroke
				(width 0.1524)
				(type default)
			)
			(layer "F.SilkS")
		)
		(fp_line
			(start -0.7874 -0.4064)
			(end 0.7874 -0.4064)
			(stroke
				(width 0.1524)
				(type default)
			)
			(layer "F.SilkS")
		)
		(fp_line
			(start 0.67945 0.3048)
			(end 0.120396 0.3048)
			(stroke
				(width 0.1)
				(type default)
			)
			(layer "F.Fab")
		)
		(fp_line
			(start 0.67945 -0.3048)
			(end 0.67945 0.3048)
			(stroke
				(width 0.1)
				(type default)
			)
			(layer "F.Fab")
		)
		(fp_line
			(start 0.12065 -0.2794)
			(end 0.12065 -0.3048)
			(stroke
				(width 0.1)
				(type default)
			)
			(layer "F.Fab")
		)
		(fp_line
			(start 0.12065 -0.3048)
			(end 0.67945 -0.3048)
			(stroke
				(width 0.1)
				(type default)
			)
			(layer "F.Fab")
		)
		(fp_line
			(start 0.120396 0.3048)
			(end 0.120396 0.2794)
			(stroke
				(width 0.1)
				(type default)
			)
			(layer "F.Fab")
		)
		(fp_line
			(start 0.120396 0.2794)
			(end -0.12065 0.2794)
			(stroke
				(width 0.1)
				(type default)
			)
			(layer "F.Fab")
		)
		(fp_line
			(start -0.12065 0.3048)
			(end -0.67945 0.3048)
			(stroke
				(width 0.1)
				(type default)
			)
			(layer "F.Fab")
		)
		(fp_line
			(start -0.12065 0.2794)
			(end -0.12065 0.3048)
			(stroke
				(width 0.1)
				(type default)
			)
			(layer "F.Fab")
		)
		(fp_line
			(start -0.12065 -0.2794)
			(end 0.12065 -0.2794)
			(stroke
				(width 0.1)
				(type default)
			)
			(layer "F.Fab")
		)
		(fp_line
			(start -0.12065 -0.305054)
			(end -0.12065 -0.2794)
			(stroke
				(width 0.1)
				(type default)
			)
			(layer "F.Fab")
		)
		(fp_line
			(start -0.67945 0.3048)
			(end -0.67945 -0.305054)
			(stroke
				(width 0.1)
				(type default)
			)
			(layer "F.Fab")
		)
		(fp_line
			(start -0.67945 -0.305054)
			(end -0.12065 -0.305054)
			(stroke
				(width 0.1)
				(type default)
			)
			(layer "F.Fab")
		)
		(pad "1" smd circle
			(at -0.40005 0 180)
			(size 0 0)
			(layers "F.Cu" "F.Mask" "F.Paste")
			(net "NIC3_BIF1_N")
		)
		(pad "2" smd circle
			(at 0.40005 0 180)
			(size 0 0)
			(layers "F.Cu" "F.Mask" "F.Paste")
			(net "GND")
		)
	)
	(footprint ""
		(layer "F.Cu")
		(at 341.546942 -38.49116 180)
		(property "Reference" "R6112"
			(at 0 0 180)
			(layer "F.SilkS")
			(hide yes)
			(effects
				(font
					(size 1.27 1.27)
				)
			)
		)
		(property "Value" ""
			(at 0 0 180)
			(layer "F.Fab")
			(effects
				(font
					(size 1.27 1.27)
				)
			)
		)
		(duplicate_pad_numbers_are_jumpers no)
		(fp_line
			(start 0.7874 0.4064)
			(end -0.7874 0.4064)
			(stroke
				(width 0.1524)
				(type default)
			)
			(layer "F.SilkS")
		)
		(fp_line
			(start 0.7874 -0.4064)
			(end 0.7874 0.4064)
			(stroke
				(width 0.1524)
				(type default)
			)
			(layer "F.SilkS")
		)
		(fp_line
			(start -0.7874 0.4064)
			(end -0.7874 -0.4064)
			(stroke
				(width 0.1524)
				(type default)
			)
			(layer "F.SilkS")
		)
		(fp_line
			(start -0.7874 -0.4064)
			(end 0.7874 -0.4064)
			(stroke
				(width 0.1524)
				(type default)
			)
			(layer "F.SilkS")
		)
		(fp_line
			(start 0.67945 0.3048)
			(end 0.120396 0.3048)
			(stroke
				(width 0.1)
				(type default)
			)
			(layer "F.Fab")
		)
		(fp_line
			(start 0.67945 -0.3048)
			(end 0.67945 0.3048)
			(stroke
				(width 0.1)
				(type default)
			)
			(layer "F.Fab")
		)
		(fp_line
			(start 0.12065 -0.2794)
			(end 0.12065 -0.3048)
			(stroke
				(width 0.1)
				(type default)
			)
			(layer "F.Fab")
		)
		(fp_line
			(start 0.12065 -0.3048)
			(end 0.67945 -0.3048)
			(stroke
				(width 0.1)
				(type default)
			)
			(layer "F.Fab")
		)
		(fp_line
			(start 0.120396 0.3048)
			(end 0.120396 0.2794)
			(stroke
				(width 0.1)
				(type default)
			)
			(layer "F.Fab")
		)
		(fp_line
			(start 0.120396 0.2794)
			(end -0.12065 0.2794)
			(stroke
				(width 0.1)
				(type default)
			)
			(layer "F.Fab")
		)
		(fp_line
			(start -0.12065 0.3048)
			(end -0.67945 0.3048)
			(stroke
				(width 0.1)
				(type default)
			)
			(layer "F.Fab")
		)
		(fp_line
			(start -0.12065 0.2794)
			(end -0.12065 0.3048)
			(stroke
				(width 0.1)
				(type default)
			)
			(layer "F.Fab")
		)
		(fp_line
			(start -0.12065 -0.2794)
			(end 0.12065 -0.2794)
			(stroke
				(width 0.1)
				(type default)
			)
			(layer "F.Fab")
		)
		(fp_line
			(start -0.12065 -0.305054)
			(end -0.12065 -0.2794)
			(stroke
				(width 0.1)
				(type default)
			)
			(layer "F.Fab")
		)
		(fp_line
			(start -0.67945 0.3048)
			(end -0.67945 -0.305054)
			(stroke
				(width 0.1)
				(type default)
			)
			(layer "F.Fab")
		)
		(fp_line
			(start -0.67945 -0.305054)
			(end -0.12065 -0.305054)
			(stroke
				(width 0.1)
				(type default)
			)
			(layer "F.Fab")
		)
		(pad "1" smd circle
			(at -0.40005 0 180)
			(size 0 0)
			(layers "F.Cu" "F.Mask" "F.Paste")
			(net "P3V3_SSD12_PG_G1")
		)
		(pad "2" smd circle
			(at 0.40005 0 180)
			(size 0 0)
			(layers "F.Cu" "F.Mask" "F.Paste")
			(net "GND")
		)
	)
	(footprint ""
		(layer "F.Cu")
		(at 234.695238 -35.48253)
		(property "Reference" "U391"
			(at -2.588768 1.34493 90)
			(unlocked yes)
			(layer "F.SilkS")
			(effects
				(font
					(size 0.7874 0.5842)
					(thickness 0.1524)
				)
				(justify left)
			)
		)
		(property "Value" ""
			(at 0 0 0)
			(layer "F.Fab")
			(effects
				(font
					(size 1.27 1.27)
				)
			)
		)
		(duplicate_pad_numbers_are_jumpers no)
		(fp_line
			(start -1.3462 -1.1938)
			(end -1.3462 1.1684)
			(stroke
				(width 0.1524)
				(type default)
			)
			(layer "F.SilkS")
		)
		(fp_line
			(start -1.3462 1.1938)
			(end 1.3462 1.1938)
			(stroke
				(width 0.1524)
				(type default)
			)
			(layer "F.SilkS")
		)
		(fp_line
			(start 1.3462 -1.1938)
			(end -1.3462 -1.1938)
			(stroke
				(width 0.1524)
				(type default)
			)
			(layer "F.SilkS")
		)
		(fp_line
			(start 1.3462 1.1938)
			(end 1.3462 -1.1938)
			(stroke
				(width 0.1524)
				(type default)
			)
			(layer "F.SilkS")
		)
		(fp_poly
			(pts
				(xy -1.447038 -0.760476) (xy -2.052066 -0.457962) (xy -2.052066 -1.06299)
			)
			(stroke
				(width 0)
				(type default)
			)
			(fill yes)
			(layer "F.SilkS")
		)
		(fp_line
			(start -0.674878 -1.124966)
			(end -0.674878 1.124966)
			(stroke
				(width 0.1)
				(type default)
			)
			(layer "F.Fab")
		)
		(fp_line
			(start -0.674878 1.124966)
			(end 0.674878 1.124966)
			(stroke
				(width 0.1)
				(type default)
			)
			(layer "F.Fab")
		)
		(fp_line
			(start 0.674878 -1.124966)
			(end -0.674878 -1.124966)
			(stroke
				(width 0.1)
				(type default)
			)
			(layer "F.Fab")
		)
		(fp_line
			(start 0.674878 1.124966)
			(end 0.674878 -1.124966)
			(stroke
				(width 0.1)
				(type default)
			)
			(layer "F.Fab")
		)
		(fp_poly
			(pts
				(xy -1.447038 -0.760476) (xy -2.052066 -0.457962) (xy -2.052066 -1.06299)
			)
			(stroke
				(width 0)
				(type default)
			)
			(fill yes)
			(layer "F.Fab")
		)
		(pad "1" smd rect
			(at -0.899922 -0.750062)
			(size 0.6096 0.6096)
			(layers "F.Cu" "F.Mask" "F.Paste")
			(net "PWRGD_P3V3_SSD8_R")
		)
		(pad "2" smd rect
			(at -0.899922 0 90)
			(size 0.4064 0.6096)
			(layers "F.Cu" "F.Mask" "F.Paste")
			(net "RST_SMB_SSD8_N")
		)
		(pad "3" smd rect
			(at -0.899922 0.750062)
			(size 0.6096 0.6096)
			(layers "F.Cu" "F.Mask" "F.Paste")
			(net "GND")
		)
		(pad "4" smd rect
			(at 0.899922 0.750062)
			(size 0.6096 0.6096)
			(layers "F.Cu" "F.Mask" "F.Paste")
			(net "RST_SMB_SSD8_ISO_N")
		)
		(pad "5" smd rect
			(at 0.899922 -0.750062)
			(size 0.6096 0.6096)
			(layers "F.Cu" "F.Mask" "F.Paste")
			(net "P3V3_AUX")
		)
	)
	(footprint ""
		(layer "F.Cu")
		(at 340.641432 -303.649634 90)
		(property "Reference" "PC164"
			(at 0 0 90)
			(layer "F.SilkS")
			(hide yes)
			(effects
				(font
					(size 1.27 1.27)
				)
			)
		)
		(property "Value" ""
			(at 0 0 90)
			(layer "F.Fab")
			(effects
				(font
					(size 1.27 1.27)
				)
			)
		)
		(duplicate_pad_numbers_are_jumpers no)
		(fp_line
			(start 1.524 -0.762)
			(end 1.524 0.762)
			(stroke
				(width 0.1524)
				(type default)
			)
			(layer "F.SilkS")
		)
		(fp_line
			(start -1.524 -0.762)
			(end 1.524 -0.762)
			(stroke
				(width 0.1524)
				(type default)
			)
			(layer "F.SilkS")
		)
		(fp_line
			(start 1.524 0.762)
			(end -1.524 0.762)
			(stroke
				(width 0.1524)
				(type default)
			)
			(layer "F.SilkS")
		)
		(fp_line
			(start -1.524 0.762)
			(end -1.524 -0.762)
			(stroke
				(width 0.1524)
				(type default)
			)
			(layer "F.SilkS")
		)
		(fp_line
			(start 1.1049 -0.724916)
			(end -1.1049 -0.724916)
			(stroke
				(width 0.1)
				(type default)
			)
			(layer "F.Fab")
		)
		(fp_line
			(start -1.1049 -0.724916)
			(end -1.1049 0.724916)
			(stroke
				(width 0.1)
				(type default)
			)
			(layer "F.Fab")
		)
		(fp_line
			(start 1.1049 0.724916)
			(end 1.1049 -0.724916)
			(stroke
				(width 0.1)
				(type default)
			)
			(layer "F.Fab")
		)
		(fp_line
			(start -1.1049 0.724916)
			(end 1.1049 0.724916)
			(stroke
				(width 0.1)
				(type default)
			)
			(layer "F.Fab")
		)
		(pad "1" smd rect
			(at -0.889 0 270)
			(size 1.016 1.27)
			(layers "F.Cu" "F.Mask" "F.Paste")
			(net "P0V8_PEX2")
		)
		(pad "2" smd rect
			(at 0.889 0 270)
			(size 1.016 1.27)
			(layers "F.Cu" "F.Mask" "F.Paste")
			(net "GND")
		)
	)
	(footprint ""
		(layer "F.Cu")
		(at 213.17966 -179.843176 -90)
		(property "Reference" "R5420"
			(at 0 0 270)
			(layer "F.SilkS")
			(hide yes)
			(effects
				(font
					(size 1.27 1.27)
				)
			)
		)
		(property "Value" ""
			(at 0 0 270)
			(layer "F.Fab")
			(effects
				(font
					(size 1.27 1.27)
				)
			)
		)
		(duplicate_pad_numbers_are_jumpers no)
		(fp_line
			(start -0.7874 0.4064)
			(end -0.7874 -0.4064)
			(stroke
				(width 0.1524)
				(type default)
			)
			(layer "F.SilkS")
		)
		(fp_line
			(start 0.7874 0.4064)
			(end -0.7874 0.4064)
			(stroke
				(width 0.1524)
				(type default)
			)
			(layer "F.SilkS")
		)
		(fp_line
			(start -0.7874 -0.4064)
			(end 0.7874 -0.4064)
			(stroke
				(width 0.1524)
				(type default)
			)
			(layer "F.SilkS")
		)
		(fp_line
			(start 0.7874 -0.4064)
			(end 0.7874 0.4064)
			(stroke
				(width 0.1524)
				(type default)
			)
			(layer "F.SilkS")
		)
		(fp_line
			(start -0.67945 0.3048)
			(end -0.67945 -0.305054)
			(stroke
				(width 0.1)
				(type default)
			)
			(layer "F.Fab")
		)
		(fp_line
			(start -0.12065 0.3048)
			(end -0.67945 0.3048)
			(stroke
				(width 0.1)
				(type default)
			)
			(layer "F.Fab")
		)
		(fp_line
			(start 0.120396 0.3048)
			(end 0.120396 0.2794)
			(stroke
				(width 0.1)
				(type default)
			)
			(layer "F.Fab")
		)
		(fp_line
			(start 0.67945 0.3048)
			(end 0.120396 0.3048)
			(stroke
				(width 0.1)
				(type default)
			)
			(layer "F.Fab")
		)
		(fp_line
			(start -0.12065 0.2794)
			(end -0.12065 0.3048)
			(stroke
				(width 0.1)
				(type default)
			)
			(layer "F.Fab")
		)
		(fp_line
			(start 0.120396 0.2794)
			(end -0.12065 0.2794)
			(stroke
				(width 0.1)
				(type default)
			)
			(layer "F.Fab")
		)
		(fp_line
			(start -0.12065 -0.2794)
			(end 0.12065 -0.2794)
			(stroke
				(width 0.1)
				(type default)
			)
			(layer "F.Fab")
		)
		(fp_line
			(start 0.12065 -0.2794)
			(end 0.12065 -0.3048)
			(stroke
				(width 0.1)
				(type default)
			)
			(layer "F.Fab")
		)
		(fp_line
			(start 0.12065 -0.3048)
			(end 0.67945 -0.3048)
			(stroke
				(width 0.1)
				(type default)
			)
			(layer "F.Fab")
		)
		(fp_line
			(start 0.67945 -0.3048)
			(end 0.67945 0.3048)
			(stroke
				(width 0.1)
				(type default)
			)
			(layer "F.Fab")
		)
		(fp_line
			(start -0.67945 -0.305054)
			(end -0.12065 -0.305054)
			(stroke
				(width 0.1)
				(type default)
			)
			(layer "F.Fab")
		)
		(fp_line
			(start -0.12065 -0.305054)
			(end -0.12065 -0.2794)
			(stroke
				(width 0.1)
				(type default)
			)
			(layer "F.Fab")
		)
		(pad "1" smd circle
			(at -0.40005 0 270)
			(size 0 0)
			(layers "F.Cu" "F.Mask" "F.Paste")
			(net "SEL_FLASH_PEX2_BUF_R")
		)
		(pad "2" smd circle
			(at 0.40005 0 270)
			(size 0 0)
			(layers "F.Cu" "F.Mask" "F.Paste")
			(net "P3V3_AUX")
		)
	)
	(footprint ""
		(layer "F.Cu")
		(at 407.295096 -103.814372 180)
		(property "Reference" "R375"
			(at 0 0 180)
			(layer "F.SilkS")
			(hide yes)
			(effects
				(font
					(size 1.27 1.27)
				)
			)
		)
		(property "Value" ""
			(at 0 0 180)
			(layer "F.Fab")
			(effects
				(font
					(size 1.27 1.27)
				)
			)
		)
		(duplicate_pad_numbers_are_jumpers no)
		(fp_line
			(start 0.7874 0.4064)
			(end -0.7874 0.4064)
			(stroke
				(width 0.1524)
				(type default)
			)
			(layer "F.SilkS")
		)
		(fp_line
			(start 0.7874 -0.4064)
			(end 0.7874 0.4064)
			(stroke
				(width 0.1524)
				(type default)
			)
			(layer "F.SilkS")
		)
		(fp_line
			(start -0.7874 0.4064)
			(end -0.7874 -0.4064)
			(stroke
				(width 0.1524)
				(type default)
			)
			(layer "F.SilkS")
		)
		(fp_line
			(start -0.7874 -0.4064)
			(end 0.7874 -0.4064)
			(stroke
				(width 0.1524)
				(type default)
			)
			(layer "F.SilkS")
		)
		(fp_line
			(start 0.67945 0.3048)
			(end 0.120396 0.3048)
			(stroke
				(width 0.1)
				(type default)
			)
			(layer "F.Fab")
		)
		(fp_line
			(start 0.67945 -0.3048)
			(end 0.67945 0.3048)
			(stroke
				(width 0.1)
				(type default)
			)
			(layer "F.Fab")
		)
		(fp_line
			(start 0.12065 -0.2794)
			(end 0.12065 -0.3048)
			(stroke
				(width 0.1)
				(type default)
			)
			(layer "F.Fab")
		)
		(fp_line
			(start 0.12065 -0.3048)
			(end 0.67945 -0.3048)
			(stroke
				(width 0.1)
				(type default)
			)
			(layer "F.Fab")
		)
		(fp_line
			(start 0.120396 0.3048)
			(end 0.120396 0.2794)
			(stroke
				(width 0.1)
				(type default)
			)
			(layer "F.Fab")
		)
		(fp_line
			(start 0.120396 0.2794)
			(end -0.12065 0.2794)
			(stroke
				(width 0.1)
				(type default)
			)
			(layer "F.Fab")
		)
		(fp_line
			(start -0.12065 0.3048)
			(end -0.67945 0.3048)
			(stroke
				(width 0.1)
				(type default)
			)
			(layer "F.Fab")
		)
		(fp_line
			(start -0.12065 0.2794)
			(end -0.12065 0.3048)
			(stroke
				(width 0.1)
				(type default)
			)
			(layer "F.Fab")
		)
		(fp_line
			(start -0.12065 -0.2794)
			(end 0.12065 -0.2794)
			(stroke
				(width 0.1)
				(type default)
			)
			(layer "F.Fab")
		)
		(fp_line
			(start -0.12065 -0.305054)
			(end -0.12065 -0.2794)
			(stroke
				(width 0.1)
				(type default)
			)
			(layer "F.Fab")
		)
		(fp_line
			(start -0.67945 0.3048)
			(end -0.67945 -0.305054)
			(stroke
				(width 0.1)
				(type default)
			)
			(layer "F.Fab")
		)
		(fp_line
			(start -0.67945 -0.305054)
			(end -0.12065 -0.305054)
			(stroke
				(width 0.1)
				(type default)
			)
			(layer "F.Fab")
		)
		(pad "1" smd circle
			(at -0.40005 0 180)
			(size 0 0)
			(layers "F.Cu" "F.Mask" "F.Paste")
			(net "NCSI_NIC7_TXD0")
		)
		(pad "2" smd circle
			(at 0.40005 0 180)
			(size 0 0)
			(layers "F.Cu" "F.Mask" "F.Paste")
			(net "GND")
		)
	)
	(footprint ""
		(layer "F.Cu")
		(at 67.564762 -350.098614 90)
		(property "Reference" "C121"
			(at 0 0 90)
			(layer "F.SilkS")
			(hide yes)
			(effects
				(font
					(size 1.27 1.27)
				)
			)
		)
		(property "Value" ""
			(at 0 0 90)
			(layer "F.Fab")
			(effects
				(font
					(size 1.27 1.27)
				)
			)
		)
		(duplicate_pad_numbers_are_jumpers no)
		(fp_line
			(start 0.299974 -0.150114)
			(end 0.299974 0.150114)
			(stroke
				(width 0.1)
				(type default)
			)
			(layer "F.Fab")
		)
		(fp_line
			(start -0.299974 -0.150114)
			(end 0.299974 -0.150114)
			(stroke
				(width 0.1)
				(type default)
			)
			(layer "F.Fab")
		)
		(fp_line
			(start 0.299974 0.150114)
			(end -0.299974 0.150114)
			(stroke
				(width 0.1)
				(type default)
			)
			(layer "F.Fab")
		)
		(fp_line
			(start -0.299974 0.150114)
			(end -0.299974 -0.150114)
			(stroke
				(width 0.1)
				(type default)
			)
			(layer "F.Fab")
		)
		(pad "1" smd rect
			(at -0.2667 0 90)
			(size 0.3048 0.381)
			(layers "F.Cu" "F.Mask" "F.Paste")
			(net "P5E_PEX0_STN5_TX_DP<83>")
		)
		(pad "2" smd rect
			(at 0.2667 0 90)
			(size 0.3048 0.381)
			(layers "F.Cu" "F.Mask" "F.Paste")
			(net "P5E_PEX0_STN5_TX_C_DP<83>")
		)
	)
	(footprint ""
		(layer "F.Cu")
		(at 325.827644 -356.244906 90)
		(property "Reference" "C564"
			(at 0 0 90)
			(layer "F.SilkS")
			(hide yes)
			(effects
				(font
					(size 1.27 1.27)
				)
			)
		)
		(property "Value" ""
			(at 0 0 90)
			(layer "F.Fab")
			(effects
				(font
					(size 1.27 1.27)
				)
			)
		)
		(duplicate_pad_numbers_are_jumpers no)
		(fp_line
			(start 0.299974 -0.150114)
			(end 0.299974 0.150114)
			(stroke
				(width 0.1)
				(type default)
			)
			(layer "F.Fab")
		)
		(fp_line
			(start -0.299974 -0.150114)
			(end 0.299974 -0.150114)
			(stroke
				(width 0.1)
				(type default)
			)
			(layer "F.Fab")
		)
		(fp_line
			(start 0.299974 0.150114)
			(end -0.299974 0.150114)
			(stroke
				(width 0.1)
				(type default)
			)
			(layer "F.Fab")
		)
		(fp_line
			(start -0.299974 0.150114)
			(end -0.299974 -0.150114)
			(stroke
				(width 0.1)
				(type default)
			)
			(layer "F.Fab")
		)
		(pad "1" smd rect
			(at -0.2667 0 90)
			(size 0.3048 0.381)
			(layers "F.Cu" "F.Mask" "F.Paste")
			(net "P5E_PEX2_STN6_TX_DN<105>")
		)
		(pad "2" smd rect
			(at 0.2667 0 90)
			(size 0.3048 0.381)
			(layers "F.Cu" "F.Mask" "F.Paste")
			(net "P5E_PEX2_STN6_TX_C_DN<105>")
		)
	)
	(footprint ""
		(layer "F.Cu")
		(at 288.726626 -53.697124 -90)
		(property "Reference" "PC558"
			(at 0 0 270)
			(layer "F.SilkS")
			(hide yes)
			(effects
				(font
					(size 1.27 1.27)
				)
			)
		)
		(property "Value" ""
			(at 0 0 270)
			(layer "F.Fab")
			(effects
				(font
					(size 1.27 1.27)
				)
			)
		)
		(duplicate_pad_numbers_are_jumpers no)
		(fp_line
			(start -0.7874 0.4064)
			(end -0.7874 -0.4064)
			(stroke
				(width 0.1524)
				(type default)
			)
			(layer "F.SilkS")
		)
		(fp_line
			(start 0.7874 0.4064)
			(end -0.7874 0.4064)
			(stroke
				(width 0.1524)
				(type default)
			)
			(layer "F.SilkS")
		)
		(fp_line
			(start -0.7874 -0.4064)
			(end 0.7874 -0.4064)
			(stroke
				(width 0.1524)
				(type default)
			)
			(layer "F.SilkS")
		)
		(fp_line
			(start 0.7874 -0.4064)
			(end 0.7874 0.4064)
			(stroke
				(width 0.1524)
				(type default)
			)
			(layer "F.SilkS")
		)
		(fp_line
			(start -0.67945 0.3048)
			(end -0.67945 -0.305054)
			(stroke
				(width 0.1)
				(type default)
			)
			(layer "F.Fab")
		)
		(fp_line
			(start -0.12065 0.3048)
			(end -0.67945 0.3048)
			(stroke
				(width 0.1)
				(type default)
			)
			(layer "F.Fab")
		)
		(fp_line
			(start 0.120396 0.3048)
			(end 0.120396 0.2794)
			(stroke
				(width 0.1)
				(type default)
			)
			(layer "F.Fab")
		)
		(fp_line
			(start 0.67945 0.3048)
			(end 0.120396 0.3048)
			(stroke
				(width 0.1)
				(type default)
			)
			(layer "F.Fab")
		)
		(fp_line
			(start -0.12065 0.2794)
			(end -0.12065 0.3048)
			(stroke
				(width 0.1)
				(type default)
			)
			(layer "F.Fab")
		)
		(fp_line
			(start 0.120396 0.2794)
			(end -0.12065 0.2794)
			(stroke
				(width 0.1)
				(type default)
			)
			(layer "F.Fab")
		)
		(fp_line
			(start -0.12065 -0.2794)
			(end 0.12065 -0.2794)
			(stroke
				(width 0.1)
				(type default)
			)
			(layer "F.Fab")
		)
		(fp_line
			(start 0.12065 -0.2794)
			(end 0.12065 -0.3048)
			(stroke
				(width 0.1)
				(type default)
			)
			(layer "F.Fab")
		)
		(fp_line
			(start 0.12065 -0.3048)
			(end 0.67945 -0.3048)
			(stroke
				(width 0.1)
				(type default)
			)
			(layer "F.Fab")
		)
		(fp_line
			(start 0.67945 -0.3048)
			(end 0.67945 0.3048)
			(stroke
				(width 0.1)
				(type default)
			)
			(layer "F.Fab")
		)
		(fp_line
			(start -0.67945 -0.305054)
			(end -0.12065 -0.305054)
			(stroke
				(width 0.1)
				(type default)
			)
			(layer "F.Fab")
		)
		(fp_line
			(start -0.12065 -0.305054)
			(end -0.12065 -0.2794)
			(stroke
				(width 0.1)
				(type default)
			)
			(layer "F.Fab")
		)
		(pad "1" smd circle
			(at -0.40005 0 270)
			(size 0 0)
			(layers "F.Cu" "F.Mask" "F.Paste")
			(net "P3V3_AUX")
		)
		(pad "2" smd circle
			(at 0.40005 0 270)
			(size 0 0)
			(layers "F.Cu" "F.Mask" "F.Paste")
			(net "GND")
		)
	)
	(footprint ""
		(layer "F.Cu")
		(at 101.359208 -224.224342 90)
		(property "Reference" "PC296"
			(at 0 0 90)
			(layer "F.SilkS")
			(hide yes)
			(effects
				(font
					(size 1.27 1.27)
				)
			)
		)
		(property "Value" ""
			(at 0 0 90)
			(layer "F.Fab")
			(effects
				(font
					(size 1.27 1.27)
				)
			)
		)
		(duplicate_pad_numbers_are_jumpers no)
		(fp_line
			(start 0.7874 -0.4064)
			(end 0.7874 0.4064)
			(stroke
				(width 0.1524)
				(type default)
			)
			(layer "F.SilkS")
		)
		(fp_line
			(start -0.7874 -0.4064)
			(end 0.7874 -0.4064)
			(stroke
				(width 0.1524)
				(type default)
			)
			(layer "F.SilkS")
		)
		(fp_line
			(start 0.7874 0.4064)
			(end -0.7874 0.4064)
			(stroke
				(width 0.1524)
				(type default)
			)
			(layer "F.SilkS")
		)
		(fp_line
			(start -0.7874 0.4064)
			(end -0.7874 -0.4064)
			(stroke
				(width 0.1524)
				(type default)
			)
			(layer "F.SilkS")
		)
		(fp_line
			(start -0.12065 -0.305054)
			(end -0.12065 -0.2794)
			(stroke
				(width 0.1)
				(type default)
			)
			(layer "F.Fab")
		)
		(fp_line
			(start -0.67945 -0.305054)
			(end -0.12065 -0.305054)
			(stroke
				(width 0.1)
				(type default)
			)
			(layer "F.Fab")
		)
		(fp_line
			(start 0.67945 -0.3048)
			(end 0.67945 0.3048)
			(stroke
				(width 0.1)
				(type default)
			)
			(layer "F.Fab")
		)
		(fp_line
			(start 0.12065 -0.3048)
			(end 0.67945 -0.3048)
			(stroke
				(width 0.1)
				(type default)
			)
			(layer "F.Fab")
		)
		(fp_line
			(start 0.12065 -0.2794)
			(end 0.12065 -0.3048)
			(stroke
				(width 0.1)
				(type default)
			)
			(layer "F.Fab")
		)
		(fp_line
			(start -0.12065 -0.2794)
			(end 0.12065 -0.2794)
			(stroke
				(width 0.1)
				(type default)
			)
			(layer "F.Fab")
		)
		(fp_line
			(start 0.120396 0.2794)
			(end -0.12065 0.2794)
			(stroke
				(width 0.1)
				(type default)
			)
			(layer "F.Fab")
		)
		(fp_line
			(start -0.12065 0.2794)
			(end -0.12065 0.3048)
			(stroke
				(width 0.1)
				(type default)
			)
			(layer "F.Fab")
		)
		(fp_line
			(start 0.67945 0.3048)
			(end 0.120396 0.3048)
			(stroke
				(width 0.1)
				(type default)
			)
			(layer "F.Fab")
		)
		(fp_line
			(start 0.120396 0.3048)
			(end 0.120396 0.2794)
			(stroke
				(width 0.1)
				(type default)
			)
			(layer "F.Fab")
		)
		(fp_line
			(start -0.12065 0.3048)
			(end -0.67945 0.3048)
			(stroke
				(width 0.1)
				(type default)
			)
			(layer "F.Fab")
		)
		(fp_line
			(start -0.67945 0.3048)
			(end -0.67945 -0.305054)
			(stroke
				(width 0.1)
				(type default)
			)
			(layer "F.Fab")
		)
		(pad "1" smd circle
			(at -0.40005 0 90)
			(size 0 0)
			(layers "F.Cu" "F.Mask" "F.Paste")
			(net "P1V8_PEX_REF")
		)
		(pad "2" smd circle
			(at 0.40005 0 90)
			(size 0 0)
			(layers "F.Cu" "F.Mask" "F.Paste")
			(net "GND")
		)
	)
	(footprint ""
		(layer "F.Cu")
		(at 207.134206 -306.074572 90)
		(property "Reference" "R1306"
			(at 0 0 90)
			(layer "F.SilkS")
			(hide yes)
			(effects
				(font
					(size 1.27 1.27)
				)
			)
		)
		(property "Value" ""
			(at 0 0 90)
			(layer "F.Fab")
			(effects
				(font
					(size 1.27 1.27)
				)
			)
		)
		(duplicate_pad_numbers_are_jumpers no)
		(fp_line
			(start 0.7874 -0.4064)
			(end 0.7874 0.4064)
			(stroke
				(width 0.1524)
				(type default)
			)
			(layer "F.SilkS")
		)
		(fp_line
			(start -0.7874 -0.4064)
			(end 0.7874 -0.4064)
			(stroke
				(width 0.1524)
				(type default)
			)
			(layer "F.SilkS")
		)
		(fp_line
			(start 0.7874 0.4064)
			(end -0.7874 0.4064)
			(stroke
				(width 0.1524)
				(type default)
			)
			(layer "F.SilkS")
		)
		(fp_line
			(start -0.7874 0.4064)
			(end -0.7874 -0.4064)
			(stroke
				(width 0.1524)
				(type default)
			)
			(layer "F.SilkS")
		)
		(fp_line
			(start -0.12065 -0.305054)
			(end -0.12065 -0.2794)
			(stroke
				(width 0.1)
				(type default)
			)
			(layer "F.Fab")
		)
		(fp_line
			(start -0.67945 -0.305054)
			(end -0.12065 -0.305054)
			(stroke
				(width 0.1)
				(type default)
			)
			(layer "F.Fab")
		)
		(fp_line
			(start 0.67945 -0.3048)
			(end 0.67945 0.3048)
			(stroke
				(width 0.1)
				(type default)
			)
			(layer "F.Fab")
		)
		(fp_line
			(start 0.12065 -0.3048)
			(end 0.67945 -0.3048)
			(stroke
				(width 0.1)
				(type default)
			)
			(layer "F.Fab")
		)
		(fp_line
			(start 0.12065 -0.2794)
			(end 0.12065 -0.3048)
			(stroke
				(width 0.1)
				(type default)
			)
			(layer "F.Fab")
		)
		(fp_line
			(start -0.12065 -0.2794)
			(end 0.12065 -0.2794)
			(stroke
				(width 0.1)
				(type default)
			)
			(layer "F.Fab")
		)
		(fp_line
			(start 0.120396 0.2794)
			(end -0.12065 0.2794)
			(stroke
				(width 0.1)
				(type default)
			)
			(layer "F.Fab")
		)
		(fp_line
			(start -0.12065 0.2794)
			(end -0.12065 0.3048)
			(stroke
				(width 0.1)
				(type default)
			)
			(layer "F.Fab")
		)
		(fp_line
			(start 0.67945 0.3048)
			(end 0.120396 0.3048)
			(stroke
				(width 0.1)
				(type default)
			)
			(layer "F.Fab")
		)
		(fp_line
			(start 0.120396 0.3048)
			(end 0.120396 0.2794)
			(stroke
				(width 0.1)
				(type default)
			)
			(layer "F.Fab")
		)
		(fp_line
			(start -0.12065 0.3048)
			(end -0.67945 0.3048)
			(stroke
				(width 0.1)
				(type default)
			)
			(layer "F.Fab")
		)
		(fp_line
			(start -0.67945 0.3048)
			(end -0.67945 -0.305054)
			(stroke
				(width 0.1)
				(type default)
			)
			(layer "F.Fab")
		)
		(pad "1" smd circle
			(at -0.40005 0 90)
			(size 0 0)
			(layers "F.Cu" "F.Mask" "F.Paste")
			(net "PEX1_SPARE1")
		)
		(pad "2" smd circle
			(at 0.40005 0 90)
			(size 0 0)
			(layers "F.Cu" "F.Mask" "F.Paste")
			(net "P1V8_PEX")
		)
	)
	(footprint ""
		(layer "F.Cu")
		(at 453.024494 -119.77624)
		(property "Reference" "Q219"
			(at 0.447294 -1.91008 0)
			(unlocked yes)
			(layer "F.SilkS")
			(effects
				(font
					(size 0.7874 0.5842)
					(thickness 0.1524)
				)
			)
		)
		(property "Value" ""
			(at 0 0 0)
			(layer "F.Fab")
			(effects
				(font
					(size 1.27 1.27)
				)
			)
		)
		(duplicate_pad_numbers_are_jumpers no)
		(fp_line
			(start -1.376172 -1.199896)
			(end -0.508 -1.199896)
			(stroke
				(width 0.1524)
				(type default)
			)
			(layer "F.SilkS")
		)
		(fp_line
			(start -1.376172 1.199896)
			(end -1.376172 -1.199896)
			(stroke
				(width 0.1524)
				(type default)
			)
			(layer "F.SilkS")
		)
		(fp_line
			(start -0.508 -1.199896)
			(end 0 -0.762)
			(stroke
				(width 0.1524)
				(type default)
			)
			(layer "F.SilkS")
		)
		(fp_line
			(start 0 -0.762)
			(end 0.508 -1.199896)
			(stroke
				(width 0.1524)
				(type default)
			)
			(layer "F.SilkS")
		)
		(fp_line
			(start 0.508 -1.199896)
			(end 1.376172 -1.199896)
			(stroke
				(width 0.1524)
				(type default)
			)
			(layer "F.SilkS")
		)
		(fp_line
			(start 1.376172 -1.199896)
			(end 1.376172 1.199896)
			(stroke
				(width 0.1524)
				(type default)
			)
			(layer "F.SilkS")
		)
		(fp_line
			(start 1.376172 1.199896)
			(end -1.376172 1.199896)
			(stroke
				(width 0.1524)
				(type default)
			)
			(layer "F.SilkS")
		)
		(fp_poly
			(pts
				(xy -1.121156 -1.288034) (xy -1.390396 -2.096262) (xy -1.929384 -1.557274)
			)
			(stroke
				(width 0)
				(type default)
			)
			(fill yes)
			(layer "F.SilkS")
		)
		(fp_line
			(start -0.674878 -1.100074)
			(end 0.674878 -1.100074)
			(stroke
				(width 0.1)
				(type default)
			)
			(layer "F.Fab")
		)
		(fp_line
			(start -0.674878 1.100074)
			(end -0.674878 -1.100074)
			(stroke
				(width 0.1)
				(type default)
			)
			(layer "F.Fab")
		)
		(fp_line
			(start 0.674878 -1.100074)
			(end 0.674878 1.100074)
			(stroke
				(width 0.1)
				(type default)
			)
			(layer "F.Fab")
		)
		(fp_line
			(start 0.674878 1.100074)
			(end -0.674878 1.100074)
			(stroke
				(width 0.1)
				(type default)
			)
			(layer "F.Fab")
		)
		(fp_poly
			(pts
				(xy -1.4605 -0.7493) (xy -2.2225 -1.1303) (xy -2.2225 -0.3683)
			)
			(stroke
				(width 0)
				(type default)
			)
			(fill yes)
			(layer "F.Fab")
		)
		(pad "1" smd rect
			(at -0.899922 -0.750062 270)
			(size 0.6096 0.6096)
			(layers "F.Cu" "F.Mask" "F.Paste")
			(net "GND")
		)
		(pad "2" smd rect
			(at -0.899922 0 270)
			(size 0.4064 0.6096)
			(layers "F.Cu" "F.Mask" "F.Paste")
			(net "P3V3_NIC7_PG_G1")
		)
		(pad "3" smd rect
			(at -0.899922 0.750062 270)
			(size 0.6096 0.6096)
			(layers "F.Cu" "F.Mask" "F.Paste")
			(net "PWRGD_P3V3_NIC7_D")
		)
		(pad "4" smd rect
			(at 0.899922 0.750062 270)
			(size 0.6096 0.6096)
			(layers "F.Cu" "F.Mask" "F.Paste")
			(net "GND")
		)
		(pad "5" smd rect
			(at 0.899922 0 270)
			(size 0.4064 0.6096)
			(layers "F.Cu" "F.Mask" "F.Paste")
			(net "P3V3_NIC7_PG_G2")
		)
		(pad "6" smd rect
			(at 0.899922 -0.750062 270)
			(size 0.6096 0.6096)
			(layers "F.Cu" "F.Mask" "F.Paste")
			(net "P3V3_NIC7_PG_G2")
		)
	)
	(footprint ""
		(layer "F.Cu")
		(at 377.175268 -63.086234)
		(property "Reference" "R6019"
			(at 0 0 0)
			(layer "F.SilkS")
			(hide yes)
			(effects
				(font
					(size 1.27 1.27)
				)
			)
		)
		(property "Value" ""
			(at 0 0 0)
			(layer "F.Fab")
			(effects
				(font
					(size 1.27 1.27)
				)
			)
		)
		(duplicate_pad_numbers_are_jumpers no)
		(fp_line
			(start -0.7874 -0.4064)
			(end 0.7874 -0.4064)
			(stroke
				(width 0.1524)
				(type default)
			)
			(layer "F.SilkS")
		)
		(fp_line
			(start -0.7874 0.4064)
			(end -0.7874 -0.4064)
			(stroke
				(width 0.1524)
				(type default)
			)
			(layer "F.SilkS")
		)
		(fp_line
			(start 0.7874 -0.4064)
			(end 0.7874 0.4064)
			(stroke
				(width 0.1524)
				(type default)
			)
			(layer "F.SilkS")
		)
		(fp_line
			(start 0.7874 0.4064)
			(end -0.7874 0.4064)
			(stroke
				(width 0.1524)
				(type default)
			)
			(layer "F.SilkS")
		)
		(fp_line
			(start -0.67945 -0.305054)
			(end -0.12065 -0.305054)
			(stroke
				(width 0.1)
				(type default)
			)
			(layer "F.Fab")
		)
		(fp_line
			(start -0.67945 0.3048)
			(end -0.67945 -0.305054)
			(stroke
				(width 0.1)
				(type default)
			)
			(layer "F.Fab")
		)
		(fp_line
			(start -0.12065 -0.305054)
			(end -0.12065 -0.2794)
			(stroke
				(width 0.1)
				(type default)
			)
			(layer "F.Fab")
		)
		(fp_line
			(start -0.12065 -0.2794)
			(end 0.12065 -0.2794)
			(stroke
				(width 0.1)
				(type default)
			)
			(layer "F.Fab")
		)
		(fp_line
			(start -0.12065 0.2794)
			(end -0.12065 0.3048)
			(stroke
				(width 0.1)
				(type default)
			)
			(layer "F.Fab")
		)
		(fp_line
			(start -0.12065 0.3048)
			(end -0.67945 0.3048)
			(stroke
				(width 0.1)
				(type default)
			)
			(layer "F.Fab")
		)
		(fp_line
			(start 0.120396 0.2794)
			(end -0.12065 0.2794)
			(stroke
				(width 0.1)
				(type default)
			)
			(layer "F.Fab")
		)
		(fp_line
			(start 0.120396 0.3048)
			(end 0.120396 0.2794)
			(stroke
				(width 0.1)
				(type default)
			)
			(layer "F.Fab")
		)
		(fp_line
			(start 0.12065 -0.3048)
			(end 0.67945 -0.3048)
			(stroke
				(width 0.1)
				(type default)
			)
			(layer "F.Fab")
		)
		(fp_line
			(start 0.12065 -0.2794)
			(end 0.12065 -0.3048)
			(stroke
				(width 0.1)
				(type default)
			)
			(layer "F.Fab")
		)
		(fp_line
			(start 0.67945 -0.3048)
			(end 0.67945 0.3048)
			(stroke
				(width 0.1)
				(type default)
			)
			(layer "F.Fab")
		)
		(fp_line
			(start 0.67945 0.3048)
			(end 0.120396 0.3048)
			(stroke
				(width 0.1)
				(type default)
			)
			(layer "F.Fab")
		)
		(pad "1" smd circle
			(at -0.40005 0)
			(size 0 0)
			(layers "F.Cu" "F.Mask" "F.Paste")
			(net "P12V_SSD13_R")
		)
		(pad "2" smd circle
			(at 0.40005 0)
			(size 0 0)
			(layers "F.Cu" "F.Mask" "F.Paste")
			(net "P12V_SSD13_PG_G1")
		)
	)
	(footprint ""
		(layer "F.Cu")
		(at 252.875034 -56.977534 180)
		(property "Reference" "PC400"
			(at 0 0 180)
			(layer "F.SilkS")
			(hide yes)
			(effects
				(font
					(size 1.27 1.27)
				)
			)
		)
		(property "Value" ""
			(at 0 0 180)
			(layer "F.Fab")
			(effects
				(font
					(size 1.27 1.27)
				)
			)
		)
		(duplicate_pad_numbers_are_jumpers no)
		(fp_line
			(start 0.7874 0.4064)
			(end -0.7874 0.4064)
			(stroke
				(width 0.1524)
				(type default)
			)
			(layer "F.SilkS")
		)
		(fp_line
			(start 0.7874 -0.4064)
			(end 0.7874 0.4064)
			(stroke
				(width 0.1524)
				(type default)
			)
			(layer "F.SilkS")
		)
		(fp_line
			(start -0.7874 0.4064)
			(end -0.7874 -0.4064)
			(stroke
				(width 0.1524)
				(type default)
			)
			(layer "F.SilkS")
		)
		(fp_line
			(start -0.7874 -0.4064)
			(end 0.7874 -0.4064)
			(stroke
				(width 0.1524)
				(type default)
			)
			(layer "F.SilkS")
		)
		(fp_line
			(start 0.67945 0.3048)
			(end 0.120396 0.3048)
			(stroke
				(width 0.1)
				(type default)
			)
			(layer "F.Fab")
		)
		(fp_line
			(start 0.67945 -0.3048)
			(end 0.67945 0.3048)
			(stroke
				(width 0.1)
				(type default)
			)
			(layer "F.Fab")
		)
		(fp_line
			(start 0.12065 -0.2794)
			(end 0.12065 -0.3048)
			(stroke
				(width 0.1)
				(type default)
			)
			(layer "F.Fab")
		)
		(fp_line
			(start 0.12065 -0.3048)
			(end 0.67945 -0.3048)
			(stroke
				(width 0.1)
				(type default)
			)
			(layer "F.Fab")
		)
		(fp_line
			(start 0.120396 0.3048)
			(end 0.120396 0.2794)
			(stroke
				(width 0.1)
				(type default)
			)
			(layer "F.Fab")
		)
		(fp_line
			(start 0.120396 0.2794)
			(end -0.12065 0.2794)
			(stroke
				(width 0.1)
				(type default)
			)
			(layer "F.Fab")
		)
		(fp_line
			(start -0.12065 0.3048)
			(end -0.67945 0.3048)
			(stroke
				(width 0.1)
				(type default)
			)
			(layer "F.Fab")
		)
		(fp_line
			(start -0.12065 0.2794)
			(end -0.12065 0.3048)
			(stroke
				(width 0.1)
				(type default)
			)
			(layer "F.Fab")
		)
		(fp_line
			(start -0.12065 -0.2794)
			(end 0.12065 -0.2794)
			(stroke
				(width 0.1)
				(type default)
			)
			(layer "F.Fab")
		)
		(fp_line
			(start -0.12065 -0.305054)
			(end -0.12065 -0.2794)
			(stroke
				(width 0.1)
				(type default)
			)
			(layer "F.Fab")
		)
		(fp_line
			(start -0.67945 0.3048)
			(end -0.67945 -0.305054)
			(stroke
				(width 0.1)
				(type default)
			)
			(layer "F.Fab")
		)
		(fp_line
			(start -0.67945 -0.305054)
			(end -0.12065 -0.305054)
			(stroke
				(width 0.1)
				(type default)
			)
			(layer "F.Fab")
		)
		(pad "1" smd circle
			(at -0.40005 0 180)
			(size 0 0)
			(layers "F.Cu" "F.Mask" "F.Paste")
			(net "P12V_AUX")
		)
		(pad "2" smd circle
			(at 0.40005 0 180)
			(size 0 0)
			(layers "F.Cu" "F.Mask" "F.Paste")
			(net "GND")
		)
	)
	(footprint ""
		(layer "F.Cu")
		(at 400.567906 -52.035456 180)
		(property "Reference" "R872"
			(at 0 0 180)
			(layer "F.SilkS")
			(hide yes)
			(effects
				(font
					(size 1.27 1.27)
				)
			)
		)
		(property "Value" ""
			(at 0 0 180)
			(layer "F.Fab")
			(effects
				(font
					(size 1.27 1.27)
				)
			)
		)
		(duplicate_pad_numbers_are_jumpers no)
		(fp_line
			(start 0.7874 0.4064)
			(end -0.7874 0.4064)
			(stroke
				(width 0.1524)
				(type default)
			)
			(layer "F.SilkS")
		)
		(fp_line
			(start 0.7874 -0.4064)
			(end 0.7874 0.4064)
			(stroke
				(width 0.1524)
				(type default)
			)
			(layer "F.SilkS")
		)
		(fp_line
			(start -0.7874 0.4064)
			(end -0.7874 -0.4064)
			(stroke
				(width 0.1524)
				(type default)
			)
			(layer "F.SilkS")
		)
		(fp_line
			(start -0.7874 -0.4064)
			(end 0.7874 -0.4064)
			(stroke
				(width 0.1524)
				(type default)
			)
			(layer "F.SilkS")
		)
		(fp_line
			(start 0.67945 0.3048)
			(end 0.120396 0.3048)
			(stroke
				(width 0.1)
				(type default)
			)
			(layer "F.Fab")
		)
		(fp_line
			(start 0.67945 -0.3048)
			(end 0.67945 0.3048)
			(stroke
				(width 0.1)
				(type default)
			)
			(layer "F.Fab")
		)
		(fp_line
			(start 0.12065 -0.2794)
			(end 0.12065 -0.3048)
			(stroke
				(width 0.1)
				(type default)
			)
			(layer "F.Fab")
		)
		(fp_line
			(start 0.12065 -0.3048)
			(end 0.67945 -0.3048)
			(stroke
				(width 0.1)
				(type default)
			)
			(layer "F.Fab")
		)
		(fp_line
			(start 0.120396 0.3048)
			(end 0.120396 0.2794)
			(stroke
				(width 0.1)
				(type default)
			)
			(layer "F.Fab")
		)
		(fp_line
			(start 0.120396 0.2794)
			(end -0.12065 0.2794)
			(stroke
				(width 0.1)
				(type default)
			)
			(layer "F.Fab")
		)
		(fp_line
			(start -0.12065 0.3048)
			(end -0.67945 0.3048)
			(stroke
				(width 0.1)
				(type default)
			)
			(layer "F.Fab")
		)
		(fp_line
			(start -0.12065 0.2794)
			(end -0.12065 0.3048)
			(stroke
				(width 0.1)
				(type default)
			)
			(layer "F.Fab")
		)
		(fp_line
			(start -0.12065 -0.2794)
			(end 0.12065 -0.2794)
			(stroke
				(width 0.1)
				(type default)
			)
			(layer "F.Fab")
		)
		(fp_line
			(start -0.12065 -0.305054)
			(end -0.12065 -0.2794)
			(stroke
				(width 0.1)
				(type default)
			)
			(layer "F.Fab")
		)
		(fp_line
			(start -0.67945 0.3048)
			(end -0.67945 -0.305054)
			(stroke
				(width 0.1)
				(type default)
			)
			(layer "F.Fab")
		)
		(fp_line
			(start -0.67945 -0.305054)
			(end -0.12065 -0.305054)
			(stroke
				(width 0.1)
				(type default)
			)
			(layer "F.Fab")
		)
		(pad "1" smd circle
			(at -0.40005 0 180)
			(size 0 0)
			(layers "F.Cu" "F.Mask" "F.Paste")
			(net "P3V3_AUX")
		)
		(pad "2" smd circle
			(at 0.40005 0 180)
			(size 0 0)
			(layers "F.Cu" "F.Mask" "F.Paste")
			(net "PWRGD_P12V_SSD13")
		)
	)
	(footprint ""
		(layer "F.Cu")
		(at 184.837832 -343.952322 90)
		(property "Reference" "C2533"
			(at 0 0 90)
			(layer "F.SilkS")
			(hide yes)
			(effects
				(font
					(size 1.27 1.27)
				)
			)
		)
		(property "Value" ""
			(at 0 0 90)
			(layer "F.Fab")
			(effects
				(font
					(size 1.27 1.27)
				)
			)
		)
		(duplicate_pad_numbers_are_jumpers no)
		(fp_line
			(start 0.299974 -0.150114)
			(end 0.299974 0.150114)
			(stroke
				(width 0.1)
				(type default)
			)
			(layer "F.Fab")
		)
		(fp_line
			(start -0.299974 -0.150114)
			(end 0.299974 -0.150114)
			(stroke
				(width 0.1)
				(type default)
			)
			(layer "F.Fab")
		)
		(fp_line
			(start 0.299974 0.150114)
			(end -0.299974 0.150114)
			(stroke
				(width 0.1)
				(type default)
			)
			(layer "F.Fab")
		)
		(fp_line
			(start -0.299974 0.150114)
			(end -0.299974 -0.150114)
			(stroke
				(width 0.1)
				(type default)
			)
			(layer "F.Fab")
		)
		(pad "1" smd rect
			(at -0.2667 0 90)
			(size 0.3048 0.381)
			(layers "F.Cu" "F.Mask" "F.Paste")
			(net "P5E_PEX1_STN4_TX_DN<69>")
		)
		(pad "2" smd rect
			(at 0.2667 0 90)
			(size 0.3048 0.381)
			(layers "F.Cu" "F.Mask" "F.Paste")
			(net "P5E_PEX1_STN4_TX_C_DN<69>")
		)
	)
	(footprint ""
		(layer "F.Cu")
		(at 210.439 -198.247 180)
		(property "Reference" "R1525"
			(at 0 0 180)
			(layer "F.SilkS")
			(hide yes)
			(effects
				(font
					(size 1.27 1.27)
				)
			)
		)
		(property "Value" ""
			(at 0 0 180)
			(layer "F.Fab")
			(effects
				(font
					(size 1.27 1.27)
				)
			)
		)
		(duplicate_pad_numbers_are_jumpers no)
		(fp_line
			(start 0.7874 0.4064)
			(end -0.7874 0.4064)
			(stroke
				(width 0.1524)
				(type default)
			)
			(layer "F.SilkS")
		)
		(fp_line
			(start 0.7874 -0.4064)
			(end 0.7874 0.4064)
			(stroke
				(width 0.1524)
				(type default)
			)
			(layer "F.SilkS")
		)
		(fp_line
			(start -0.7874 0.4064)
			(end -0.7874 -0.4064)
			(stroke
				(width 0.1524)
				(type default)
			)
			(layer "F.SilkS")
		)
		(fp_line
			(start -0.7874 -0.4064)
			(end 0.7874 -0.4064)
			(stroke
				(width 0.1524)
				(type default)
			)
			(layer "F.SilkS")
		)
		(fp_line
			(start 0.67945 0.3048)
			(end 0.120396 0.3048)
			(stroke
				(width 0.1)
				(type default)
			)
			(layer "F.Fab")
		)
		(fp_line
			(start 0.67945 -0.3048)
			(end 0.67945 0.3048)
			(stroke
				(width 0.1)
				(type default)
			)
			(layer "F.Fab")
		)
		(fp_line
			(start 0.12065 -0.2794)
			(end 0.12065 -0.3048)
			(stroke
				(width 0.1)
				(type default)
			)
			(layer "F.Fab")
		)
		(fp_line
			(start 0.12065 -0.3048)
			(end 0.67945 -0.3048)
			(stroke
				(width 0.1)
				(type default)
			)
			(layer "F.Fab")
		)
		(fp_line
			(start 0.120396 0.3048)
			(end 0.120396 0.2794)
			(stroke
				(width 0.1)
				(type default)
			)
			(layer "F.Fab")
		)
		(fp_line
			(start 0.120396 0.2794)
			(end -0.12065 0.2794)
			(stroke
				(width 0.1)
				(type default)
			)
			(layer "F.Fab")
		)
		(fp_line
			(start -0.12065 0.3048)
			(end -0.67945 0.3048)
			(stroke
				(width 0.1)
				(type default)
			)
			(layer "F.Fab")
		)
		(fp_line
			(start -0.12065 0.2794)
			(end -0.12065 0.3048)
			(stroke
				(width 0.1)
				(type default)
			)
			(layer "F.Fab")
		)
		(fp_line
			(start -0.12065 -0.2794)
			(end 0.12065 -0.2794)
			(stroke
				(width 0.1)
				(type default)
			)
			(layer "F.Fab")
		)
		(fp_line
			(start -0.12065 -0.305054)
			(end -0.12065 -0.2794)
			(stroke
				(width 0.1)
				(type default)
			)
			(layer "F.Fab")
		)
		(fp_line
			(start -0.67945 0.3048)
			(end -0.67945 -0.305054)
			(stroke
				(width 0.1)
				(type default)
			)
			(layer "F.Fab")
		)
		(fp_line
			(start -0.67945 -0.305054)
			(end -0.12065 -0.305054)
			(stroke
				(width 0.1)
				(type default)
			)
			(layer "F.Fab")
		)
		(pad "1" smd circle
			(at -0.40005 0 180)
			(size 0 0)
			(layers "F.Cu" "F.Mask" "F.Paste")
			(net "SMB_NIC6_R_SDA")
		)
		(pad "2" smd circle
			(at 0.40005 0 180)
			(size 0 0)
			(layers "F.Cu" "F.Mask" "F.Paste")
			(net "P1V2_AUX")
		)
	)
	(footprint ""
		(layer "F.Cu")
		(at 33.040066 -256.634234 180)
		(property "Reference" "C3050"
			(at 0 0 180)
			(layer "F.SilkS")
			(hide yes)
			(effects
				(font
					(size 1.27 1.27)
				)
			)
		)
		(property "Value" ""
			(at 0 0 180)
			(layer "F.Fab")
			(effects
				(font
					(size 1.27 1.27)
				)
			)
		)
		(duplicate_pad_numbers_are_jumpers no)
		(fp_line
			(start 1.2954 0.5842)
			(end -1.2954 0.5842)
			(stroke
				(width 0.1524)
				(type default)
			)
			(layer "F.SilkS")
		)
		(fp_line
			(start 1.2954 -0.5842)
			(end 1.2954 0.5842)
			(stroke
				(width 0.1524)
				(type default)
			)
			(layer "F.SilkS")
		)
		(fp_line
			(start -1.2954 0.5842)
			(end -1.2954 -0.5842)
			(stroke
				(width 0.1524)
				(type default)
			)
			(layer "F.SilkS")
		)
		(fp_line
			(start -1.2954 -0.5842)
			(end 1.2954 -0.5842)
			(stroke
				(width 0.1524)
				(type default)
			)
			(layer "F.SilkS")
		)
		(fp_line
			(start 1.1938 0.4064)
			(end 0.8636 0.4064)
			(stroke
				(width 0.1)
				(type default)
			)
			(layer "F.Fab")
		)
		(fp_line
			(start 1.1938 -0.4064)
			(end 1.1938 0.4064)
			(stroke
				(width 0.1)
				(type default)
			)
			(layer "F.Fab")
		)
		(fp_line
			(start 0.8636 0.4572)
			(end -0.8636 0.4572)
			(stroke
				(width 0.1)
				(type default)
			)
			(layer "F.Fab")
		)
		(fp_line
			(start 0.8636 0.4064)
			(end 0.8636 0.4572)
			(stroke
				(width 0.1)
				(type default)
			)
			(layer "F.Fab")
		)
		(fp_line
			(start 0.8636 -0.4064)
			(end 1.1938 -0.4064)
			(stroke
				(width 0.1)
				(type default)
			)
			(layer "F.Fab")
		)
		(fp_line
			(start 0.8636 -0.4572)
			(end 0.8636 -0.4064)
			(stroke
				(width 0.1)
				(type default)
			)
			(layer "F.Fab")
		)
		(fp_line
			(start -0.8636 0.4572)
			(end -0.8636 0.4064)
			(stroke
				(width 0.1)
				(type default)
			)
			(layer "F.Fab")
		)
		(fp_line
			(start -0.8636 0.4064)
			(end -1.1938 0.4064)
			(stroke
				(width 0.1)
				(type default)
			)
			(layer "F.Fab")
		)
		(fp_line
			(start -0.8636 -0.4064)
			(end -0.8636 -0.4572)
			(stroke
				(width 0.1)
				(type default)
			)
			(layer "F.Fab")
		)
		(fp_line
			(start -0.8636 -0.4572)
			(end 0.8636 -0.4572)
			(stroke
				(width 0.1)
				(type default)
			)
			(layer "F.Fab")
		)
		(fp_line
			(start -1.1938 0.4064)
			(end -1.1938 -0.4064)
			(stroke
				(width 0.1)
				(type default)
			)
			(layer "F.Fab")
		)
		(fp_line
			(start -1.1938 -0.4064)
			(end -0.8636 -0.4064)
			(stroke
				(width 0.1)
				(type default)
			)
			(layer "F.Fab")
		)
		(pad "1" smd rect
			(at -0.7366 0 90)
			(size 0.7112 0.8128)
			(layers "F.Cu" "F.Mask" "F.Paste")
			(net "PCEPLL5_VDDA18_PEX0_R")
		)
		(pad "2" smd rect
			(at 0.7366 0 90)
			(size 0.7112 0.8128)
			(layers "F.Cu" "F.Mask" "F.Paste")
			(net "GND")
		)
	)
	(footprint ""
		(layer "F.Cu")
		(at 204.472286 -373.65559 90)
		(property "Reference" "PC2"
			(at 0 0 90)
			(layer "F.SilkS")
			(hide yes)
			(effects
				(font
					(size 1.27 1.27)
				)
			)
		)
		(property "Value" ""
			(at 0 0 90)
			(layer "F.Fab")
			(effects
				(font
					(size 1.27 1.27)
				)
			)
		)
		(duplicate_pad_numbers_are_jumpers no)
		(fp_line
			(start 0.7874 -0.4064)
			(end 0.7874 0.4064)
			(stroke
				(width 0.1524)
				(type default)
			)
			(layer "F.SilkS")
		)
		(fp_line
			(start -0.7874 -0.4064)
			(end 0.7874 -0.4064)
			(stroke
				(width 0.1524)
				(type default)
			)
			(layer "F.SilkS")
		)
		(fp_line
			(start 0.7874 0.4064)
			(end -0.7874 0.4064)
			(stroke
				(width 0.1524)
				(type default)
			)
			(layer "F.SilkS")
		)
		(fp_line
			(start -0.7874 0.4064)
			(end -0.7874 -0.4064)
			(stroke
				(width 0.1524)
				(type default)
			)
			(layer "F.SilkS")
		)
		(fp_line
			(start -0.12065 -0.305054)
			(end -0.12065 -0.2794)
			(stroke
				(width 0.1)
				(type default)
			)
			(layer "F.Fab")
		)
		(fp_line
			(start -0.67945 -0.305054)
			(end -0.12065 -0.305054)
			(stroke
				(width 0.1)
				(type default)
			)
			(layer "F.Fab")
		)
		(fp_line
			(start 0.67945 -0.3048)
			(end 0.67945 0.3048)
			(stroke
				(width 0.1)
				(type default)
			)
			(layer "F.Fab")
		)
		(fp_line
			(start 0.12065 -0.3048)
			(end 0.67945 -0.3048)
			(stroke
				(width 0.1)
				(type default)
			)
			(layer "F.Fab")
		)
		(fp_line
			(start 0.12065 -0.2794)
			(end 0.12065 -0.3048)
			(stroke
				(width 0.1)
				(type default)
			)
			(layer "F.Fab")
		)
		(fp_line
			(start -0.12065 -0.2794)
			(end 0.12065 -0.2794)
			(stroke
				(width 0.1)
				(type default)
			)
			(layer "F.Fab")
		)
		(fp_line
			(start 0.120396 0.2794)
			(end -0.12065 0.2794)
			(stroke
				(width 0.1)
				(type default)
			)
			(layer "F.Fab")
		)
		(fp_line
			(start -0.12065 0.2794)
			(end -0.12065 0.3048)
			(stroke
				(width 0.1)
				(type default)
			)
			(layer "F.Fab")
		)
		(fp_line
			(start 0.67945 0.3048)
			(end 0.120396 0.3048)
			(stroke
				(width 0.1)
				(type default)
			)
			(layer "F.Fab")
		)
		(fp_line
			(start 0.120396 0.3048)
			(end 0.120396 0.2794)
			(stroke
				(width 0.1)
				(type default)
			)
			(layer "F.Fab")
		)
		(fp_line
			(start -0.12065 0.3048)
			(end -0.67945 0.3048)
			(stroke
				(width 0.1)
				(type default)
			)
			(layer "F.Fab")
		)
		(fp_line
			(start -0.67945 0.3048)
			(end -0.67945 -0.305054)
			(stroke
				(width 0.1)
				(type default)
			)
			(layer "F.Fab")
		)
		(pad "1" smd circle
			(at -0.40005 0 90)
			(size 0 0)
			(layers "F.Cu" "F.Mask" "F.Paste")
			(net "HSC_VINSEN")
		)
		(pad "2" smd circle
			(at 0.40005 0 90)
			(size 0 0)
			(layers "F.Cu" "F.Mask" "F.Paste")
			(net "AGND_HSC")
		)
	)
	(footprint ""
		(layer "F.Cu")
		(at 441.36564 -304.036476 90)
		(property "Reference" "R4184"
			(at 0 0 90)
			(layer "F.SilkS")
			(hide yes)
			(effects
				(font
					(size 1.27 1.27)
				)
			)
		)
		(property "Value" ""
			(at 0 0 90)
			(layer "F.Fab")
			(effects
				(font
					(size 1.27 1.27)
				)
			)
		)
		(duplicate_pad_numbers_are_jumpers no)
		(fp_line
			(start 0.7874 -0.4064)
			(end 0.7874 0.4064)
			(stroke
				(width 0.1524)
				(type default)
			)
			(layer "F.SilkS")
		)
		(fp_line
			(start -0.7874 -0.4064)
			(end 0.7874 -0.4064)
			(stroke
				(width 0.1524)
				(type default)
			)
			(layer "F.SilkS")
		)
		(fp_line
			(start 0.7874 0.4064)
			(end -0.7874 0.4064)
			(stroke
				(width 0.1524)
				(type default)
			)
			(layer "F.SilkS")
		)
		(fp_line
			(start -0.7874 0.4064)
			(end -0.7874 -0.4064)
			(stroke
				(width 0.1524)
				(type default)
			)
			(layer "F.SilkS")
		)
		(fp_line
			(start -0.12065 -0.305054)
			(end -0.12065 -0.2794)
			(stroke
				(width 0.1)
				(type default)
			)
			(layer "F.Fab")
		)
		(fp_line
			(start -0.67945 -0.305054)
			(end -0.12065 -0.305054)
			(stroke
				(width 0.1)
				(type default)
			)
			(layer "F.Fab")
		)
		(fp_line
			(start 0.67945 -0.3048)
			(end 0.67945 0.3048)
			(stroke
				(width 0.1)
				(type default)
			)
			(layer "F.Fab")
		)
		(fp_line
			(start 0.12065 -0.3048)
			(end 0.67945 -0.3048)
			(stroke
				(width 0.1)
				(type default)
			)
			(layer "F.Fab")
		)
		(fp_line
			(start 0.12065 -0.2794)
			(end 0.12065 -0.3048)
			(stroke
				(width 0.1)
				(type default)
			)
			(layer "F.Fab")
		)
		(fp_line
			(start -0.12065 -0.2794)
			(end 0.12065 -0.2794)
			(stroke
				(width 0.1)
				(type default)
			)
			(layer "F.Fab")
		)
		(fp_line
			(start 0.120396 0.2794)
			(end -0.12065 0.2794)
			(stroke
				(width 0.1)
				(type default)
			)
			(layer "F.Fab")
		)
		(fp_line
			(start -0.12065 0.2794)
			(end -0.12065 0.3048)
			(stroke
				(width 0.1)
				(type default)
			)
			(layer "F.Fab")
		)
		(fp_line
			(start 0.67945 0.3048)
			(end 0.120396 0.3048)
			(stroke
				(width 0.1)
				(type default)
			)
			(layer "F.Fab")
		)
		(fp_line
			(start 0.120396 0.3048)
			(end 0.120396 0.2794)
			(stroke
				(width 0.1)
				(type default)
			)
			(layer "F.Fab")
		)
		(fp_line
			(start -0.12065 0.3048)
			(end -0.67945 0.3048)
			(stroke
				(width 0.1)
				(type default)
			)
			(layer "F.Fab")
		)
		(fp_line
			(start -0.67945 0.3048)
			(end -0.67945 -0.305054)
			(stroke
				(width 0.1)
				(type default)
			)
			(layer "F.Fab")
		)
		(pad "1" smd circle
			(at -0.40005 0 90)
			(size 0 0)
			(layers "F.Cu" "F.Mask" "F.Paste")
			(net "GND")
		)
		(pad "2" smd circle
			(at 0.40005 0 90)
			(size 0 0)
			(layers "F.Cu" "F.Mask" "F.Paste")
			(net "PEX3_EXT_GPIO_LATCH_N")
		)
	)
	(footprint ""
		(layer "F.Cu")
		(at 106.614214 -217.079576)
		(property "Reference" "PC286"
			(at 0 0 0)
			(layer "F.SilkS")
			(hide yes)
			(effects
				(font
					(size 1.27 1.27)
				)
			)
		)
		(property "Value" ""
			(at 0 0 0)
			(layer "F.Fab")
			(effects
				(font
					(size 1.27 1.27)
				)
			)
		)
		(duplicate_pad_numbers_are_jumpers no)
		(fp_line
			(start -1.524 -0.762)
			(end 1.524 -0.762)
			(stroke
				(width 0.1524)
				(type default)
			)
			(layer "F.SilkS")
		)
		(fp_line
			(start -1.524 0.762)
			(end -1.524 -0.762)
			(stroke
				(width 0.1524)
				(type default)
			)
			(layer "F.SilkS")
		)
		(fp_line
			(start 1.524 -0.762)
			(end 1.524 0.762)
			(stroke
				(width 0.1524)
				(type default)
			)
			(layer "F.SilkS")
		)
		(fp_line
			(start 1.524 0.762)
			(end -1.524 0.762)
			(stroke
				(width 0.1524)
				(type default)
			)
			(layer "F.SilkS")
		)
		(fp_line
			(start -1.1049 -0.724916)
			(end -1.1049 0.724916)
			(stroke
				(width 0.1)
				(type default)
			)
			(layer "F.Fab")
		)
		(fp_line
			(start -1.1049 0.724916)
			(end 1.1049 0.724916)
			(stroke
				(width 0.1)
				(type default)
			)
			(layer "F.Fab")
		)
		(fp_line
			(start 1.1049 -0.724916)
			(end -1.1049 -0.724916)
			(stroke
				(width 0.1)
				(type default)
			)
			(layer "F.Fab")
		)
		(fp_line
			(start 1.1049 0.724916)
			(end 1.1049 -0.724916)
			(stroke
				(width 0.1)
				(type default)
			)
			(layer "F.Fab")
		)
		(pad "1" smd rect
			(at -0.889 0 180)
			(size 1.016 1.27)
			(layers "F.Cu" "F.Mask" "F.Paste")
			(net "SW_P12V_P1V8_PEX_FLT")
		)
		(pad "2" smd rect
			(at 0.889 0 180)
			(size 1.016 1.27)
			(layers "F.Cu" "F.Mask" "F.Paste")
			(net "GND")
		)
	)
	(footprint ""
		(layer "F.Cu")
		(at 352.320098 -147.654518)
		(property "Reference" "R4829"
			(at 0 0 0)
			(layer "F.SilkS")
			(hide yes)
			(effects
				(font
					(size 1.27 1.27)
				)
			)
		)
		(property "Value" ""
			(at 0 0 0)
			(layer "F.Fab")
			(effects
				(font
					(size 1.27 1.27)
				)
			)
		)
		(duplicate_pad_numbers_are_jumpers no)
		(fp_line
			(start -0.7874 -0.4064)
			(end 0.7874 -0.4064)
			(stroke
				(width 0.1524)
				(type default)
			)
			(layer "F.SilkS")
		)
		(fp_line
			(start -0.7874 0.4064)
			(end -0.7874 -0.4064)
			(stroke
				(width 0.1524)
				(type default)
			)
			(layer "F.SilkS")
		)
		(fp_line
			(start 0.7874 -0.4064)
			(end 0.7874 0.4064)
			(stroke
				(width 0.1524)
				(type default)
			)
			(layer "F.SilkS")
		)
		(fp_line
			(start 0.7874 0.4064)
			(end -0.7874 0.4064)
			(stroke
				(width 0.1524)
				(type default)
			)
			(layer "F.SilkS")
		)
		(fp_line
			(start -0.67945 -0.305054)
			(end -0.12065 -0.305054)
			(stroke
				(width 0.1)
				(type default)
			)
			(layer "F.Fab")
		)
		(fp_line
			(start -0.67945 0.3048)
			(end -0.67945 -0.305054)
			(stroke
				(width 0.1)
				(type default)
			)
			(layer "F.Fab")
		)
		(fp_line
			(start -0.12065 -0.305054)
			(end -0.12065 -0.2794)
			(stroke
				(width 0.1)
				(type default)
			)
			(layer "F.Fab")
		)
		(fp_line
			(start -0.12065 -0.2794)
			(end 0.12065 -0.2794)
			(stroke
				(width 0.1)
				(type default)
			)
			(layer "F.Fab")
		)
		(fp_line
			(start -0.12065 0.2794)
			(end -0.12065 0.3048)
			(stroke
				(width 0.1)
				(type default)
			)
			(layer "F.Fab")
		)
		(fp_line
			(start -0.12065 0.3048)
			(end -0.67945 0.3048)
			(stroke
				(width 0.1)
				(type default)
			)
			(layer "F.Fab")
		)
		(fp_line
			(start 0.120396 0.2794)
			(end -0.12065 0.2794)
			(stroke
				(width 0.1)
				(type default)
			)
			(layer "F.Fab")
		)
		(fp_line
			(start 0.120396 0.3048)
			(end 0.120396 0.2794)
			(stroke
				(width 0.1)
				(type default)
			)
			(layer "F.Fab")
		)
		(fp_line
			(start 0.12065 -0.3048)
			(end 0.67945 -0.3048)
			(stroke
				(width 0.1)
				(type default)
			)
			(layer "F.Fab")
		)
		(fp_line
			(start 0.12065 -0.2794)
			(end 0.12065 -0.3048)
			(stroke
				(width 0.1)
				(type default)
			)
			(layer "F.Fab")
		)
		(fp_line
			(start 0.67945 -0.3048)
			(end 0.67945 0.3048)
			(stroke
				(width 0.1)
				(type default)
			)
			(layer "F.Fab")
		)
		(fp_line
			(start 0.67945 0.3048)
			(end 0.120396 0.3048)
			(stroke
				(width 0.1)
				(type default)
			)
			(layer "F.Fab")
		)
		(pad "1" smd circle
			(at -0.40005 0)
			(size 0 0)
			(layers "F.Cu" "F.Mask" "F.Paste")
			(net "PCA9555_1_PEX3_A0")
		)
		(pad "2" smd circle
			(at 0.40005 0)
			(size 0 0)
			(layers "F.Cu" "F.Mask" "F.Paste")
			(net "P3V3_AUX")
		)
	)
	(footprint ""
		(layer "F.Cu")
		(at 336.467704 -56.353456)
		(property "Reference" "C2875"
			(at 0 0 0)
			(layer "F.SilkS")
			(hide yes)
			(effects
				(font
					(size 1.27 1.27)
				)
			)
		)
		(property "Value" ""
			(at 0 0 0)
			(layer "F.Fab")
			(effects
				(font
					(size 1.27 1.27)
				)
			)
		)
		(duplicate_pad_numbers_are_jumpers no)
		(fp_line
			(start -0.7874 -0.4064)
			(end 0.7874 -0.4064)
			(stroke
				(width 0.1524)
				(type default)
			)
			(layer "F.SilkS")
		)
		(fp_line
			(start -0.7874 0.4064)
			(end -0.7874 -0.4064)
			(stroke
				(width 0.1524)
				(type default)
			)
			(layer "F.SilkS")
		)
		(fp_line
			(start 0.7874 -0.4064)
			(end 0.7874 0.4064)
			(stroke
				(width 0.1524)
				(type default)
			)
			(layer "F.SilkS")
		)
		(fp_line
			(start 0.7874 0.4064)
			(end -0.7874 0.4064)
			(stroke
				(width 0.1524)
				(type default)
			)
			(layer "F.SilkS")
		)
		(fp_line
			(start -0.67945 -0.305054)
			(end -0.12065 -0.305054)
			(stroke
				(width 0.1)
				(type default)
			)
			(layer "F.Fab")
		)
		(fp_line
			(start -0.67945 0.3048)
			(end -0.67945 -0.305054)
			(stroke
				(width 0.1)
				(type default)
			)
			(layer "F.Fab")
		)
		(fp_line
			(start -0.12065 -0.305054)
			(end -0.12065 -0.2794)
			(stroke
				(width 0.1)
				(type default)
			)
			(layer "F.Fab")
		)
		(fp_line
			(start -0.12065 -0.2794)
			(end 0.12065 -0.2794)
			(stroke
				(width 0.1)
				(type default)
			)
			(layer "F.Fab")
		)
		(fp_line
			(start -0.12065 0.2794)
			(end -0.12065 0.3048)
			(stroke
				(width 0.1)
				(type default)
			)
			(layer "F.Fab")
		)
		(fp_line
			(start -0.12065 0.3048)
			(end -0.67945 0.3048)
			(stroke
				(width 0.1)
				(type default)
			)
			(layer "F.Fab")
		)
		(fp_line
			(start 0.120396 0.2794)
			(end -0.12065 0.2794)
			(stroke
				(width 0.1)
				(type default)
			)
			(layer "F.Fab")
		)
		(fp_line
			(start 0.120396 0.3048)
			(end 0.120396 0.2794)
			(stroke
				(width 0.1)
				(type default)
			)
			(layer "F.Fab")
		)
		(fp_line
			(start 0.12065 -0.3048)
			(end 0.67945 -0.3048)
			(stroke
				(width 0.1)
				(type default)
			)
			(layer "F.Fab")
		)
		(fp_line
			(start 0.12065 -0.2794)
			(end 0.12065 -0.3048)
			(stroke
				(width 0.1)
				(type default)
			)
			(layer "F.Fab")
		)
		(fp_line
			(start 0.67945 -0.3048)
			(end 0.67945 0.3048)
			(stroke
				(width 0.1)
				(type default)
			)
			(layer "F.Fab")
		)
		(fp_line
			(start 0.67945 0.3048)
			(end 0.120396 0.3048)
			(stroke
				(width 0.1)
				(type default)
			)
			(layer "F.Fab")
		)
		(pad "1" smd circle
			(at -0.40005 0)
			(size 0 0)
			(layers "F.Cu" "F.Mask" "F.Paste")
			(net "SSD11_PWR_EN_R")
		)
		(pad "2" smd circle
			(at 0.40005 0)
			(size 0 0)
			(layers "F.Cu" "F.Mask" "F.Paste")
			(net "GND")
		)
	)
	(footprint ""
		(layer "F.Cu")
		(at 447.247264 -20.35556)
		(property "Reference" "C3981"
			(at 0 0 0)
			(layer "F.SilkS")
			(hide yes)
			(effects
				(font
					(size 1.27 1.27)
				)
			)
		)
		(property "Value" ""
			(at 0 0 0)
			(layer "F.Fab")
			(effects
				(font
					(size 1.27 1.27)
				)
			)
		)
		(duplicate_pad_numbers_are_jumpers no)
		(fp_line
			(start -0.7874 -0.4064)
			(end 0.7874 -0.4064)
			(stroke
				(width 0.1524)
				(type default)
			)
			(layer "F.SilkS")
		)
		(fp_line
			(start -0.7874 0.4064)
			(end -0.7874 -0.4064)
			(stroke
				(width 0.1524)
				(type default)
			)
			(layer "F.SilkS")
		)
		(fp_line
			(start 0.7874 -0.4064)
			(end 0.7874 0.4064)
			(stroke
				(width 0.1524)
				(type default)
			)
			(layer "F.SilkS")
		)
		(fp_line
			(start 0.7874 0.4064)
			(end -0.7874 0.4064)
			(stroke
				(width 0.1524)
				(type default)
			)
			(layer "F.SilkS")
		)
		(fp_line
			(start -0.67945 -0.305054)
			(end -0.12065 -0.305054)
			(stroke
				(width 0.1)
				(type default)
			)
			(layer "F.Fab")
		)
		(fp_line
			(start -0.67945 0.3048)
			(end -0.67945 -0.305054)
			(stroke
				(width 0.1)
				(type default)
			)
			(layer "F.Fab")
		)
		(fp_line
			(start -0.12065 -0.305054)
			(end -0.12065 -0.2794)
			(stroke
				(width 0.1)
				(type default)
			)
			(layer "F.Fab")
		)
		(fp_line
			(start -0.12065 -0.2794)
			(end 0.12065 -0.2794)
			(stroke
				(width 0.1)
				(type default)
			)
			(layer "F.Fab")
		)
		(fp_line
			(start -0.12065 0.2794)
			(end -0.12065 0.3048)
			(stroke
				(width 0.1)
				(type default)
			)
			(layer "F.Fab")
		)
		(fp_line
			(start -0.12065 0.3048)
			(end -0.67945 0.3048)
			(stroke
				(width 0.1)
				(type default)
			)
			(layer "F.Fab")
		)
		(fp_line
			(start 0.120396 0.2794)
			(end -0.12065 0.2794)
			(stroke
				(width 0.1)
				(type default)
			)
			(layer "F.Fab")
		)
		(fp_line
			(start 0.120396 0.3048)
			(end 0.120396 0.2794)
			(stroke
				(width 0.1)
				(type default)
			)
			(layer "F.Fab")
		)
		(fp_line
			(start 0.12065 -0.3048)
			(end 0.67945 -0.3048)
			(stroke
				(width 0.1)
				(type default)
			)
			(layer "F.Fab")
		)
		(fp_line
			(start 0.12065 -0.2794)
			(end 0.12065 -0.3048)
			(stroke
				(width 0.1)
				(type default)
			)
			(layer "F.Fab")
		)
		(fp_line
			(start 0.67945 -0.3048)
			(end 0.67945 0.3048)
			(stroke
				(width 0.1)
				(type default)
			)
			(layer "F.Fab")
		)
		(fp_line
			(start 0.67945 0.3048)
			(end 0.120396 0.3048)
			(stroke
				(width 0.1)
				(type default)
			)
			(layer "F.Fab")
		)
		(pad "1" smd circle
			(at -0.40005 0)
			(size 0 0)
			(layers "F.Cu" "F.Mask" "F.Paste")
			(net "P12V_SSD15")
		)
		(pad "2" smd circle
			(at 0.40005 0)
			(size 0 0)
			(layers "F.Cu" "F.Mask" "F.Paste")
			(net "GND")
		)
	)
	(footprint ""
		(layer "F.Cu")
		(at 364.494826 -111.377476 -90)
		(property "Reference" "PC914"
			(at 0 0 270)
			(layer "F.SilkS")
			(hide yes)
			(effects
				(font
					(size 1.27 1.27)
				)
			)
		)
		(property "Value" ""
			(at 0 0 270)
			(layer "F.Fab")
			(effects
				(font
					(size 1.27 1.27)
				)
			)
		)
		(duplicate_pad_numbers_are_jumpers no)
		(fp_line
			(start -0.7874 0.4064)
			(end -0.7874 -0.4064)
			(stroke
				(width 0.1524)
				(type default)
			)
			(layer "F.SilkS")
		)
		(fp_line
			(start 0.7874 0.4064)
			(end -0.7874 0.4064)
			(stroke
				(width 0.1524)
				(type default)
			)
			(layer "F.SilkS")
		)
		(fp_line
			(start -0.7874 -0.4064)
			(end 0.7874 -0.4064)
			(stroke
				(width 0.1524)
				(type default)
			)
			(layer "F.SilkS")
		)
		(fp_line
			(start 0.7874 -0.4064)
			(end 0.7874 0.4064)
			(stroke
				(width 0.1524)
				(type default)
			)
			(layer "F.SilkS")
		)
		(fp_line
			(start -0.67945 0.3048)
			(end -0.67945 -0.305054)
			(stroke
				(width 0.1)
				(type default)
			)
			(layer "F.Fab")
		)
		(fp_line
			(start -0.12065 0.3048)
			(end -0.67945 0.3048)
			(stroke
				(width 0.1)
				(type default)
			)
			(layer "F.Fab")
		)
		(fp_line
			(start 0.120396 0.3048)
			(end 0.120396 0.2794)
			(stroke
				(width 0.1)
				(type default)
			)
			(layer "F.Fab")
		)
		(fp_line
			(start 0.67945 0.3048)
			(end 0.120396 0.3048)
			(stroke
				(width 0.1)
				(type default)
			)
			(layer "F.Fab")
		)
		(fp_line
			(start -0.12065 0.2794)
			(end -0.12065 0.3048)
			(stroke
				(width 0.1)
				(type default)
			)
			(layer "F.Fab")
		)
		(fp_line
			(start 0.120396 0.2794)
			(end -0.12065 0.2794)
			(stroke
				(width 0.1)
				(type default)
			)
			(layer "F.Fab")
		)
		(fp_line
			(start -0.12065 -0.2794)
			(end 0.12065 -0.2794)
			(stroke
				(width 0.1)
				(type default)
			)
			(layer "F.Fab")
		)
		(fp_line
			(start 0.12065 -0.2794)
			(end 0.12065 -0.3048)
			(stroke
				(width 0.1)
				(type default)
			)
			(layer "F.Fab")
		)
		(fp_line
			(start 0.12065 -0.3048)
			(end 0.67945 -0.3048)
			(stroke
				(width 0.1)
				(type default)
			)
			(layer "F.Fab")
		)
		(fp_line
			(start 0.67945 -0.3048)
			(end 0.67945 0.3048)
			(stroke
				(width 0.1)
				(type default)
			)
			(layer "F.Fab")
		)
		(fp_line
			(start -0.67945 -0.305054)
			(end -0.12065 -0.305054)
			(stroke
				(width 0.1)
				(type default)
			)
			(layer "F.Fab")
		)
		(fp_line
			(start -0.12065 -0.305054)
			(end -0.12065 -0.2794)
			(stroke
				(width 0.1)
				(type default)
			)
			(layer "F.Fab")
		)
		(pad "1" smd circle
			(at -0.40005 0 270)
			(size 0 0)
			(layers "F.Cu" "F.Mask" "F.Paste")
			(net "P3V3_NIC6_CO_MODE")
		)
		(pad "2" smd circle
			(at 0.40005 0 270)
			(size 0 0)
			(layers "F.Cu" "F.Mask" "F.Paste")
			(net "GND")
		)
	)
	(footprint ""
		(layer "F.Cu")
		(at 410.972508 -210.341718 180)
		(property "Reference" "R6443"
			(at 0 0 180)
			(layer "F.SilkS")
			(hide yes)
			(effects
				(font
					(size 1.27 1.27)
				)
			)
		)
		(property "Value" ""
			(at 0 0 180)
			(layer "F.Fab")
			(effects
				(font
					(size 1.27 1.27)
				)
			)
		)
		(duplicate_pad_numbers_are_jumpers no)
		(fp_line
			(start 0.7874 0.4064)
			(end -0.7874 0.4064)
			(stroke
				(width 0.1524)
				(type default)
			)
			(layer "F.SilkS")
		)
		(fp_line
			(start 0.7874 -0.4064)
			(end 0.7874 0.4064)
			(stroke
				(width 0.1524)
				(type default)
			)
			(layer "F.SilkS")
		)
		(fp_line
			(start -0.7874 0.4064)
			(end -0.7874 -0.4064)
			(stroke
				(width 0.1524)
				(type default)
			)
			(layer "F.SilkS")
		)
		(fp_line
			(start -0.7874 -0.4064)
			(end 0.7874 -0.4064)
			(stroke
				(width 0.1524)
				(type default)
			)
			(layer "F.SilkS")
		)
		(fp_line
			(start 0.67945 0.3048)
			(end 0.120396 0.3048)
			(stroke
				(width 0.1)
				(type default)
			)
			(layer "F.Fab")
		)
		(fp_line
			(start 0.67945 -0.3048)
			(end 0.67945 0.3048)
			(stroke
				(width 0.1)
				(type default)
			)
			(layer "F.Fab")
		)
		(fp_line
			(start 0.12065 -0.2794)
			(end 0.12065 -0.3048)
			(stroke
				(width 0.1)
				(type default)
			)
			(layer "F.Fab")
		)
		(fp_line
			(start 0.12065 -0.3048)
			(end 0.67945 -0.3048)
			(stroke
				(width 0.1)
				(type default)
			)
			(layer "F.Fab")
		)
		(fp_line
			(start 0.120396 0.3048)
			(end 0.120396 0.2794)
			(stroke
				(width 0.1)
				(type default)
			)
			(layer "F.Fab")
		)
		(fp_line
			(start 0.120396 0.2794)
			(end -0.12065 0.2794)
			(stroke
				(width 0.1)
				(type default)
			)
			(layer "F.Fab")
		)
		(fp_line
			(start -0.12065 0.3048)
			(end -0.67945 0.3048)
			(stroke
				(width 0.1)
				(type default)
			)
			(layer "F.Fab")
		)
		(fp_line
			(start -0.12065 0.2794)
			(end -0.12065 0.3048)
			(stroke
				(width 0.1)
				(type default)
			)
			(layer "F.Fab")
		)
		(fp_line
			(start -0.12065 -0.2794)
			(end 0.12065 -0.2794)
			(stroke
				(width 0.1)
				(type default)
			)
			(layer "F.Fab")
		)
		(fp_line
			(start -0.12065 -0.305054)
			(end -0.12065 -0.2794)
			(stroke
				(width 0.1)
				(type default)
			)
			(layer "F.Fab")
		)
		(fp_line
			(start -0.67945 0.3048)
			(end -0.67945 -0.305054)
			(stroke
				(width 0.1)
				(type default)
			)
			(layer "F.Fab")
		)
		(fp_line
			(start -0.67945 -0.305054)
			(end -0.12065 -0.305054)
			(stroke
				(width 0.1)
				(type default)
			)
			(layer "F.Fab")
		)
		(pad "1" smd circle
			(at -0.40005 0 180)
			(size 0 0)
			(layers "F.Cu" "F.Mask" "F.Paste")
			(net "FPGA_PEX3_MODE_SEL1_D_N")
		)
		(pad "2" smd circle
			(at 0.40005 0 180)
			(size 0 0)
			(layers "F.Cu" "F.Mask" "F.Paste")
			(net "P3V3_AUX")
		)
	)
	(footprint ""
		(layer "F.Cu")
		(at 78.61046 -18.61439 90)
		(property "Reference" "U128"
			(at -1.49479 2.26441 90)
			(unlocked yes)
			(layer "F.SilkS")
			(effects
				(font
					(size 0.7874 0.5842)
					(thickness 0.1524)
				)
				(justify left)
			)
		)
		(property "Value" ""
			(at 0 0 90)
			(layer "F.Fab")
			(effects
				(font
					(size 1.27 1.27)
				)
			)
		)
		(duplicate_pad_numbers_are_jumpers no)
		(fp_line
			(start 1.463548 -1.549908)
			(end 1.463548 1.549908)
			(stroke
				(width 0.1524)
				(type default)
			)
			(layer "F.SilkS")
		)
		(fp_line
			(start 0.762 -1.549908)
			(end 1.463548 -1.549908)
			(stroke
				(width 0.1524)
				(type default)
			)
			(layer "F.SilkS")
		)
		(fp_line
			(start -0.787908 -1.549908)
			(end 0 -0.762)
			(stroke
				(width 0.1524)
				(type default)
			)
			(layer "F.SilkS")
		)
		(fp_line
			(start -1.463548 -1.549908)
			(end -0.787908 -1.549908)
			(stroke
				(width 0.1524)
				(type default)
			)
			(layer "F.SilkS")
		)
		(fp_line
			(start 0 -0.762)
			(end 0.762 -1.549908)
			(stroke
				(width 0.1524)
				(type default)
			)
			(layer "F.SilkS")
		)
		(fp_line
			(start 1.463548 1.549908)
			(end -1.463548 1.549908)
			(stroke
				(width 0.1524)
				(type default)
			)
			(layer "F.SilkS")
		)
		(fp_line
			(start -1.463548 1.549908)
			(end -1.463548 -1.549908)
			(stroke
				(width 0.1524)
				(type default)
			)
			(layer "F.SilkS")
		)
		(fp_poly
			(pts
				(xy -3.4798 -1.359916) (xy -2.86004 -1.050036) (xy -3.4798 -0.740156)
			)
			(stroke
				(width 0)
				(type default)
			)
			(fill yes)
			(layer "F.SilkS")
		)
		(fp_line
			(start 1.549908 -1.549908)
			(end 1.549908 1.549908)
			(stroke
				(width 0.1)
				(type default)
			)
			(layer "F.Fab")
		)
		(fp_line
			(start -1.549908 -1.549908)
			(end 1.549908 -1.549908)
			(stroke
				(width 0.1)
				(type default)
			)
			(layer "F.Fab")
		)
		(fp_line
			(start 1.549908 1.549908)
			(end -1.549908 1.549908)
			(stroke
				(width 0.1)
				(type default)
			)
			(layer "F.Fab")
		)
		(fp_line
			(start -1.549908 1.549908)
			(end -1.549908 -1.549908)
			(stroke
				(width 0.1)
				(type default)
			)
			(layer "F.Fab")
		)
		(fp_poly
			(pts
				(xy -3.4798 -1.359916) (xy -2.86004 -1.050036) (xy -3.4798 -0.740156)
			)
			(stroke
				(width 0)
				(type default)
			)
			(fill yes)
			(layer "F.Fab")
		)
		(pad "1" smd rect
			(at -2.175002 -1.050036 180)
			(size 0.6096 1.1684)
			(layers "F.Cu" "F.Mask" "F.Paste")
			(net "P3V3_SSD2")
		)
		(pad "2" smd rect
			(at -2.175002 -0.32512 180)
			(size 0.4318 1.1684)
			(layers "F.Cu" "F.Mask" "F.Paste")
			(net "SMB_ISO_SSD2_SCL")
		)
		(pad "3" smd rect
			(at -2.175002 0.32512 180)
			(size 0.4318 1.1684)
			(layers "F.Cu" "F.Mask" "F.Paste")
			(net "SMB_ISO_SSD2_SDA")
		)
		(pad "4" smd rect
			(at -2.175002 1.050036 180)
			(size 0.6096 1.1684)
			(layers "F.Cu" "F.Mask" "F.Paste")
			(net "GND")
		)
		(pad "5" smd rect
			(at 2.175002 1.050036 180)
			(size 0.6096 1.1684)
			(layers "F.Cu" "F.Mask" "F.Paste")
			(net "SMB_SSD2_ISO_EN")
		)
		(pad "6" smd rect
			(at 2.175002 0.32512 180)
			(size 0.4318 1.1684)
			(layers "F.Cu" "F.Mask" "F.Paste")
			(net "SMB_BIC_I2C9_MUX0_SSD2_R_SDA")
		)
		(pad "7" smd rect
			(at 2.175002 -0.32512 180)
			(size 0.4318 1.1684)
			(layers "F.Cu" "F.Mask" "F.Paste")
			(net "SMB_BIC_I2C9_MUX0_SSD2_R_SCL")
		)
		(pad "8" smd rect
			(at 2.175002 -1.050036 180)
			(size 0.6096 1.1684)
			(layers "F.Cu" "F.Mask" "F.Paste")
			(net "P3V3_AUX")
		)
	)
	(footprint ""
		(layer "F.Cu")
		(at 36.638484 -104.695498)
		(property "Reference" "C57"
			(at 0 0 0)
			(layer "F.SilkS")
			(hide yes)
			(effects
				(font
					(size 1.27 1.27)
				)
			)
		)
		(property "Value" ""
			(at 0 0 0)
			(layer "F.Fab")
			(effects
				(font
					(size 1.27 1.27)
				)
			)
		)
		(duplicate_pad_numbers_are_jumpers no)
		(fp_line
			(start -0.299974 -0.150114)
			(end 0.299974 -0.150114)
			(stroke
				(width 0.1)
				(type default)
			)
			(layer "F.Fab")
		)
		(fp_line
			(start -0.299974 0.150114)
			(end -0.299974 -0.150114)
			(stroke
				(width 0.1)
				(type default)
			)
			(layer "F.Fab")
		)
		(fp_line
			(start 0.299974 -0.150114)
			(end 0.299974 0.150114)
			(stroke
				(width 0.1)
				(type default)
			)
			(layer "F.Fab")
		)
		(fp_line
			(start 0.299974 0.150114)
			(end -0.299974 0.150114)
			(stroke
				(width 0.1)
				(type default)
			)
			(layer "F.Fab")
		)
		(pad "1" smd rect
			(at -0.2667 0)
			(size 0.3048 0.381)
			(layers "F.Cu" "F.Mask" "F.Paste")
			(net "P5E_PEX0_STN1_TX_DN<19>")
		)
		(pad "2" smd rect
			(at 0.2667 0)
			(size 0.3048 0.381)
			(layers "F.Cu" "F.Mask" "F.Paste")
			(net "P5E_PEX0_STN1_TX_C_DN<19>")
		)
	)
	(footprint ""
		(layer "F.Cu")
		(at 63.008764 -384.598926)
		(property "Reference" "R6300"
			(at 0 0 0)
			(layer "F.SilkS")
			(hide yes)
			(effects
				(font
					(size 1.27 1.27)
				)
			)
		)
		(property "Value" ""
			(at 0 0 0)
			(layer "F.Fab")
			(effects
				(font
					(size 1.27 1.27)
				)
			)
		)
		(duplicate_pad_numbers_are_jumpers no)
		(fp_line
			(start -0.7874 -0.4064)
			(end 0.7874 -0.4064)
			(stroke
				(width 0.1524)
				(type default)
			)
			(layer "F.SilkS")
		)
		(fp_line
			(start -0.7874 0.4064)
			(end -0.7874 -0.4064)
			(stroke
				(width 0.1524)
				(type default)
			)
			(layer "F.SilkS")
		)
		(fp_line
			(start 0.7874 -0.4064)
			(end 0.7874 0.4064)
			(stroke
				(width 0.1524)
				(type default)
			)
			(layer "F.SilkS")
		)
		(fp_line
			(start 0.7874 0.4064)
			(end -0.7874 0.4064)
			(stroke
				(width 0.1524)
				(type default)
			)
			(layer "F.SilkS")
		)
		(fp_line
			(start -0.67945 -0.305054)
			(end -0.12065 -0.305054)
			(stroke
				(width 0.1)
				(type default)
			)
			(layer "F.Fab")
		)
		(fp_line
			(start -0.67945 0.3048)
			(end -0.67945 -0.305054)
			(stroke
				(width 0.1)
				(type default)
			)
			(layer "F.Fab")
		)
		(fp_line
			(start -0.12065 -0.305054)
			(end -0.12065 -0.2794)
			(stroke
				(width 0.1)
				(type default)
			)
			(layer "F.Fab")
		)
		(fp_line
			(start -0.12065 -0.2794)
			(end 0.12065 -0.2794)
			(stroke
				(width 0.1)
				(type default)
			)
			(layer "F.Fab")
		)
		(fp_line
			(start -0.12065 0.2794)
			(end -0.12065 0.3048)
			(stroke
				(width 0.1)
				(type default)
			)
			(layer "F.Fab")
		)
		(fp_line
			(start -0.12065 0.3048)
			(end -0.67945 0.3048)
			(stroke
				(width 0.1)
				(type default)
			)
			(layer "F.Fab")
		)
		(fp_line
			(start 0.120396 0.2794)
			(end -0.12065 0.2794)
			(stroke
				(width 0.1)
				(type default)
			)
			(layer "F.Fab")
		)
		(fp_line
			(start 0.120396 0.3048)
			(end 0.120396 0.2794)
			(stroke
				(width 0.1)
				(type default)
			)
			(layer "F.Fab")
		)
		(fp_line
			(start 0.12065 -0.3048)
			(end 0.67945 -0.3048)
			(stroke
				(width 0.1)
				(type default)
			)
			(layer "F.Fab")
		)
		(fp_line
			(start 0.12065 -0.2794)
			(end 0.12065 -0.3048)
			(stroke
				(width 0.1)
				(type default)
			)
			(layer "F.Fab")
		)
		(fp_line
			(start 0.67945 -0.3048)
			(end 0.67945 0.3048)
			(stroke
				(width 0.1)
				(type default)
			)
			(layer "F.Fab")
		)
		(fp_line
			(start 0.67945 0.3048)
			(end 0.120396 0.3048)
			(stroke
				(width 0.1)
				(type default)
			)
			(layer "F.Fab")
		)
		(pad "1" smd circle
			(at -0.40005 0)
			(size 0 0)
			(layers "F.Cu" "F.Mask" "F.Paste")
			(net "RST_MB_PERST_1_N")
		)
		(pad "2" smd circle
			(at 0.40005 0)
			(size 0 0)
			(layers "F.Cu" "F.Mask" "F.Paste")
			(net "GND")
		)
	)
	(footprint ""
		(layer "F.Cu")
		(at 334.899 -234.061 90)
		(property "Reference" "R3523"
			(at 0 0 90)
			(layer "F.SilkS")
			(hide yes)
			(effects
				(font
					(size 1.27 1.27)
				)
			)
		)
		(property "Value" ""
			(at 0 0 90)
			(layer "F.Fab")
			(effects
				(font
					(size 1.27 1.27)
				)
			)
		)
		(duplicate_pad_numbers_are_jumpers no)
		(fp_line
			(start 0.7874 -0.4064)
			(end 0.7874 0.4064)
			(stroke
				(width 0.1524)
				(type default)
			)
			(layer "F.SilkS")
		)
		(fp_line
			(start -0.7874 -0.4064)
			(end 0.7874 -0.4064)
			(stroke
				(width 0.1524)
				(type default)
			)
			(layer "F.SilkS")
		)
		(fp_line
			(start 0.7874 0.4064)
			(end -0.7874 0.4064)
			(stroke
				(width 0.1524)
				(type default)
			)
			(layer "F.SilkS")
		)
		(fp_line
			(start -0.7874 0.4064)
			(end -0.7874 -0.4064)
			(stroke
				(width 0.1524)
				(type default)
			)
			(layer "F.SilkS")
		)
		(fp_line
			(start -0.12065 -0.305054)
			(end -0.12065 -0.2794)
			(stroke
				(width 0.1)
				(type default)
			)
			(layer "F.Fab")
		)
		(fp_line
			(start -0.67945 -0.305054)
			(end -0.12065 -0.305054)
			(stroke
				(width 0.1)
				(type default)
			)
			(layer "F.Fab")
		)
		(fp_line
			(start 0.67945 -0.3048)
			(end 0.67945 0.3048)
			(stroke
				(width 0.1)
				(type default)
			)
			(layer "F.Fab")
		)
		(fp_line
			(start 0.12065 -0.3048)
			(end 0.67945 -0.3048)
			(stroke
				(width 0.1)
				(type default)
			)
			(layer "F.Fab")
		)
		(fp_line
			(start 0.12065 -0.2794)
			(end 0.12065 -0.3048)
			(stroke
				(width 0.1)
				(type default)
			)
			(layer "F.Fab")
		)
		(fp_line
			(start -0.12065 -0.2794)
			(end 0.12065 -0.2794)
			(stroke
				(width 0.1)
				(type default)
			)
			(layer "F.Fab")
		)
		(fp_line
			(start 0.120396 0.2794)
			(end -0.12065 0.2794)
			(stroke
				(width 0.1)
				(type default)
			)
			(layer "F.Fab")
		)
		(fp_line
			(start -0.12065 0.2794)
			(end -0.12065 0.3048)
			(stroke
				(width 0.1)
				(type default)
			)
			(layer "F.Fab")
		)
		(fp_line
			(start 0.67945 0.3048)
			(end 0.120396 0.3048)
			(stroke
				(width 0.1)
				(type default)
			)
			(layer "F.Fab")
		)
		(fp_line
			(start 0.120396 0.3048)
			(end 0.120396 0.2794)
			(stroke
				(width 0.1)
				(type default)
			)
			(layer "F.Fab")
		)
		(fp_line
			(start -0.12065 0.3048)
			(end -0.67945 0.3048)
			(stroke
				(width 0.1)
				(type default)
			)
			(layer "F.Fab")
		)
		(fp_line
			(start -0.67945 0.3048)
			(end -0.67945 -0.305054)
			(stroke
				(width 0.1)
				(type default)
			)
			(layer "F.Fab")
		)
		(pad "1" smd circle
			(at -0.40005 0 90)
			(size 0 0)
			(layers "F.Cu" "F.Mask" "F.Paste")
			(net "SSD2_PWRDIS")
		)
		(pad "2" smd circle
			(at 0.40005 0 90)
			(size 0 0)
			(layers "F.Cu" "F.Mask" "F.Paste")
			(net "SSD2_PWRDIS_R")
		)
	)
	(footprint ""
		(layer "F.Cu")
		(at 441.366148 -306.074572 90)
		(property "Reference" "R4183"
			(at 0 0 90)
			(layer "F.SilkS")
			(hide yes)
			(effects
				(font
					(size 1.27 1.27)
				)
			)
		)
		(property "Value" ""
			(at 0 0 90)
			(layer "F.Fab")
			(effects
				(font
					(size 1.27 1.27)
				)
			)
		)
		(duplicate_pad_numbers_are_jumpers no)
		(fp_line
			(start 0.7874 -0.4064)
			(end 0.7874 0.4064)
			(stroke
				(width 0.1524)
				(type default)
			)
			(layer "F.SilkS")
		)
		(fp_line
			(start -0.7874 -0.4064)
			(end 0.7874 -0.4064)
			(stroke
				(width 0.1524)
				(type default)
			)
			(layer "F.SilkS")
		)
		(fp_line
			(start 0.7874 0.4064)
			(end -0.7874 0.4064)
			(stroke
				(width 0.1524)
				(type default)
			)
			(layer "F.SilkS")
		)
		(fp_line
			(start -0.7874 0.4064)
			(end -0.7874 -0.4064)
			(stroke
				(width 0.1524)
				(type default)
			)
			(layer "F.SilkS")
		)
		(fp_line
			(start -0.12065 -0.305054)
			(end -0.12065 -0.2794)
			(stroke
				(width 0.1)
				(type default)
			)
			(layer "F.Fab")
		)
		(fp_line
			(start -0.67945 -0.305054)
			(end -0.12065 -0.305054)
			(stroke
				(width 0.1)
				(type default)
			)
			(layer "F.Fab")
		)
		(fp_line
			(start 0.67945 -0.3048)
			(end 0.67945 0.3048)
			(stroke
				(width 0.1)
				(type default)
			)
			(layer "F.Fab")
		)
		(fp_line
			(start 0.12065 -0.3048)
			(end 0.67945 -0.3048)
			(stroke
				(width 0.1)
				(type default)
			)
			(layer "F.Fab")
		)
		(fp_line
			(start 0.12065 -0.2794)
			(end 0.12065 -0.3048)
			(stroke
				(width 0.1)
				(type default)
			)
			(layer "F.Fab")
		)
		(fp_line
			(start -0.12065 -0.2794)
			(end 0.12065 -0.2794)
			(stroke
				(width 0.1)
				(type default)
			)
			(layer "F.Fab")
		)
		(fp_line
			(start 0.120396 0.2794)
			(end -0.12065 0.2794)
			(stroke
				(width 0.1)
				(type default)
			)
			(layer "F.Fab")
		)
		(fp_line
			(start -0.12065 0.2794)
			(end -0.12065 0.3048)
			(stroke
				(width 0.1)
				(type default)
			)
			(layer "F.Fab")
		)
		(fp_line
			(start 0.67945 0.3048)
			(end 0.120396 0.3048)
			(stroke
				(width 0.1)
				(type default)
			)
			(layer "F.Fab")
		)
		(fp_line
			(start 0.120396 0.3048)
			(end 0.120396 0.2794)
			(stroke
				(width 0.1)
				(type default)
			)
			(layer "F.Fab")
		)
		(fp_line
			(start -0.12065 0.3048)
			(end -0.67945 0.3048)
			(stroke
				(width 0.1)
				(type default)
			)
			(layer "F.Fab")
		)
		(fp_line
			(start -0.67945 0.3048)
			(end -0.67945 -0.305054)
			(stroke
				(width 0.1)
				(type default)
			)
			(layer "F.Fab")
		)
		(pad "1" smd circle
			(at -0.40005 0 90)
			(size 0 0)
			(layers "F.Cu" "F.Mask" "F.Paste")
			(net "PEX3_EXT_GPIO_LATCH_N")
		)
		(pad "2" smd circle
			(at 0.40005 0 90)
			(size 0 0)
			(layers "F.Cu" "F.Mask" "F.Paste")
			(net "P1V8_PEX")
		)
	)
	(footprint ""
		(layer "F.Cu")
		(at 77.107542 -81.09966)
		(property "Reference" "Q2"
			(at -1.263142 1.75133 0)
			(unlocked yes)
			(layer "F.SilkS")
			(effects
				(font
					(size 0.7874 0.5842)
					(thickness 0.1524)
				)
				(justify left)
			)
		)
		(property "Value" ""
			(at 0 0 0)
			(layer "F.Fab")
			(effects
				(font
					(size 1.27 1.27)
				)
			)
		)
		(duplicate_pad_numbers_are_jumpers no)
		(fp_line
			(start -1.38176 -1.100074)
			(end -1.38176 1.100074)
			(stroke
				(width 0.1524)
				(type default)
			)
			(layer "F.SilkS")
		)
		(fp_line
			(start -1.38176 1.100074)
			(end 1.38176 1.100074)
			(stroke
				(width 0.1524)
				(type default)
			)
			(layer "F.SilkS")
		)
		(fp_line
			(start -0.592074 -1.100074)
			(end -1.38176 -1.100074)
			(stroke
				(width 0.1524)
				(type default)
			)
			(layer "F.SilkS")
		)
		(fp_line
			(start 0 -0.508)
			(end -0.592074 -1.100074)
			(stroke
				(width 0.1524)
				(type default)
			)
			(layer "F.SilkS")
		)
		(fp_line
			(start 0.592074 -1.100074)
			(end 0 -0.508)
			(stroke
				(width 0.1524)
				(type default)
			)
			(layer "F.SilkS")
		)
		(fp_line
			(start 1.38176 -1.100074)
			(end 0.592074 -1.100074)
			(stroke
				(width 0.1524)
				(type default)
			)
			(layer "F.SilkS")
		)
		(fp_line
			(start 1.38176 1.100074)
			(end 1.38176 -1.100074)
			(stroke
				(width 0.1524)
				(type default)
			)
			(layer "F.SilkS")
		)
		(fp_poly
			(pts
				(xy -1.9431 -0.870204) (xy -1.50241 -0.649986) (xy -1.9431 -0.429768)
			)
			(stroke
				(width 0)
				(type default)
			)
			(fill yes)
			(layer "F.SilkS")
		)
		(fp_line
			(start -0.674878 -1.100074)
			(end -0.674878 1.100074)
			(stroke
				(width 0.1)
				(type default)
			)
			(layer "F.Fab")
		)
		(fp_line
			(start -0.674878 1.100074)
			(end 0.674878 1.100074)
			(stroke
				(width 0.1)
				(type default)
			)
			(layer "F.Fab")
		)
		(fp_line
			(start 0.674878 -1.100074)
			(end -0.674878 -1.100074)
			(stroke
				(width 0.1)
				(type default)
			)
			(layer "F.Fab")
		)
		(fp_line
			(start 0.674878 1.100074)
			(end 0.674878 -1.100074)
			(stroke
				(width 0.1)
				(type default)
			)
			(layer "F.Fab")
		)
		(fp_poly
			(pts
				(xy -1.9431 -0.870204) (xy -1.50241 -0.649986) (xy -1.9431 -0.429768)
			)
			(stroke
				(width 0)
				(type default)
			)
			(fill yes)
			(layer "F.Fab")
		)
		(pad "1" smd rect
			(at -0.94996 -0.649986 270)
			(size 0.4318 0.6096)
			(layers "F.Cu" "F.Mask" "F.Paste")
			(net "GND")
		)
		(pad "2" smd rect
			(at -0.94996 0 270)
			(size 0.4318 0.6096)
			(layers "F.Cu" "F.Mask" "F.Paste")
			(net "HP_NIC1_HSC_PWRGD_N")
		)
		(pad "3" smd rect
			(at -0.94996 0.649986 270)
			(size 0.4318 0.6096)
			(layers "F.Cu" "F.Mask" "F.Paste")
			(net "HP_NIC1_HSC_PWRGD_N")
		)
		(pad "4" smd rect
			(at 0.94996 0.649986 270)
			(size 0.4318 0.6096)
			(layers "F.Cu" "F.Mask" "F.Paste")
			(net "GND")
		)
		(pad "5" smd rect
			(at 0.94996 0 270)
			(size 0.4318 0.6096)
			(layers "F.Cu" "F.Mask" "F.Paste")
			(net "PWRGD_P12V_NIC1_R")
		)
		(pad "6" smd rect
			(at 0.94996 -0.649986 270)
			(size 0.4318 0.6096)
			(layers "F.Cu" "F.Mask" "F.Paste")
			(net "HP_NIC1_PWRGD_R")
		)
	)
	(footprint ""
		(layer "F.Cu")
		(at 420.8145 -66.32194 90)
		(property "Reference" "R6020"
			(at 0 0 90)
			(layer "F.SilkS")
			(hide yes)
			(effects
				(font
					(size 1.27 1.27)
				)
			)
		)
		(property "Value" ""
			(at 0 0 90)
			(layer "F.Fab")
			(effects
				(font
					(size 1.27 1.27)
				)
			)
		)
		(duplicate_pad_numbers_are_jumpers no)
		(fp_line
			(start 0.7874 -0.4064)
			(end 0.7874 0.4064)
			(stroke
				(width 0.1524)
				(type default)
			)
			(layer "F.SilkS")
		)
		(fp_line
			(start -0.7874 -0.4064)
			(end 0.7874 -0.4064)
			(stroke
				(width 0.1524)
				(type default)
			)
			(layer "F.SilkS")
		)
		(fp_line
			(start 0.7874 0.4064)
			(end -0.7874 0.4064)
			(stroke
				(width 0.1524)
				(type default)
			)
			(layer "F.SilkS")
		)
		(fp_line
			(start -0.7874 0.4064)
			(end -0.7874 -0.4064)
			(stroke
				(width 0.1524)
				(type default)
			)
			(layer "F.SilkS")
		)
		(fp_line
			(start -0.12065 -0.305054)
			(end -0.12065 -0.2794)
			(stroke
				(width 0.1)
				(type default)
			)
			(layer "F.Fab")
		)
		(fp_line
			(start -0.67945 -0.305054)
			(end -0.12065 -0.305054)
			(stroke
				(width 0.1)
				(type default)
			)
			(layer "F.Fab")
		)
		(fp_line
			(start 0.67945 -0.3048)
			(end 0.67945 0.3048)
			(stroke
				(width 0.1)
				(type default)
			)
			(layer "F.Fab")
		)
		(fp_line
			(start 0.12065 -0.3048)
			(end 0.67945 -0.3048)
			(stroke
				(width 0.1)
				(type default)
			)
			(layer "F.Fab")
		)
		(fp_line
			(start 0.12065 -0.2794)
			(end 0.12065 -0.3048)
			(stroke
				(width 0.1)
				(type default)
			)
			(layer "F.Fab")
		)
		(fp_line
			(start -0.12065 -0.2794)
			(end 0.12065 -0.2794)
			(stroke
				(width 0.1)
				(type default)
			)
			(layer "F.Fab")
		)
		(fp_line
			(start 0.120396 0.2794)
			(end -0.12065 0.2794)
			(stroke
				(width 0.1)
				(type default)
			)
			(layer "F.Fab")
		)
		(fp_line
			(start -0.12065 0.2794)
			(end -0.12065 0.3048)
			(stroke
				(width 0.1)
				(type default)
			)
			(layer "F.Fab")
		)
		(fp_line
			(start 0.67945 0.3048)
			(end 0.120396 0.3048)
			(stroke
				(width 0.1)
				(type default)
			)
			(layer "F.Fab")
		)
		(fp_line
			(start 0.120396 0.3048)
			(end 0.120396 0.2794)
			(stroke
				(width 0.1)
				(type default)
			)
			(layer "F.Fab")
		)
		(fp_line
			(start -0.12065 0.3048)
			(end -0.67945 0.3048)
			(stroke
				(width 0.1)
				(type default)
			)
			(layer "F.Fab")
		)
		(fp_line
			(start -0.67945 0.3048)
			(end -0.67945 -0.305054)
			(stroke
				(width 0.1)
				(type default)
			)
			(layer "F.Fab")
		)
		(pad "1" smd circle
			(at -0.40005 0 90)
			(size 0 0)
			(layers "F.Cu" "F.Mask" "F.Paste")
			(net "SSD14_PWR_EN_R")
		)
		(pad "2" smd circle
			(at 0.40005 0 90)
			(size 0 0)
			(layers "F.Cu" "F.Mask" "F.Paste")
			(net "P12V_SSD14_CO_EN")
		)
	)
	(footprint ""
		(layer "F.Cu")
		(at 329.83297 -98.968052 -90)
		(property "Reference" "PU25"
			(at 1.270762 2.350516 90)
			(unlocked yes)
			(layer "F.SilkS")
			(effects
				(font
					(size 0.7874 0.5842)
					(thickness 0.1524)
				)
				(justify left)
			)
		)
		(property "Value" ""
			(at 0 0 270)
			(layer "F.Fab")
			(effects
				(font
					(size 1.27 1.27)
				)
			)
		)
		(duplicate_pad_numbers_are_jumpers no)
		(fp_line
			(start -1.943608 1.549908)
			(end -1.943608 -1.549908)
			(stroke
				(width 0.1524)
				(type default)
			)
			(layer "F.SilkS")
		)
		(fp_line
			(start 1.943608 1.549908)
			(end -1.943608 1.549908)
			(stroke
				(width 0.1524)
				(type default)
			)
			(layer "F.SilkS")
		)
		(fp_line
			(start -1.943608 -1.549908)
			(end 1.943608 -1.549908)
			(stroke
				(width 0.1524)
				(type default)
			)
			(layer "F.SilkS")
		)
		(fp_line
			(start 1.943608 -1.549908)
			(end 1.943608 1.549908)
			(stroke
				(width 0.1524)
				(type default)
			)
			(layer "F.SilkS")
		)
		(fp_poly
			(pts
				(xy -2.019808 -1.549908) (xy -1.257808 -1.549908) (xy -1.257808 -1.880108) (xy -2.019808 -1.880108)
			)
			(stroke
				(width 0)
				(type default)
			)
			(fill yes)
			(layer "F.SilkS")
		)
		(fp_line
			(start -1.549908 1.549908)
			(end -1.549908 -1.549908)
			(stroke
				(width 0.1)
				(type default)
			)
			(layer "F.Fab")
		)
		(fp_line
			(start 1.549908 1.549908)
			(end -1.549908 1.549908)
			(stroke
				(width 0.1)
				(type default)
			)
			(layer "F.Fab")
		)
		(fp_line
			(start -1.549908 -1.549908)
			(end 1.549908 -1.549908)
			(stroke
				(width 0.1)
				(type default)
			)
			(layer "F.Fab")
		)
		(fp_line
			(start 1.549908 -1.549908)
			(end 1.549908 1.549908)
			(stroke
				(width 0.1)
				(type default)
			)
			(layer "F.Fab")
		)
		(fp_poly
			(pts
				(xy -2.019808 -1.549908) (xy -1.257808 -1.549908) (xy -1.257808 -1.880108) (xy -2.019808 -1.880108)
			)
			(stroke
				(width 0)
				(type default)
			)
			(fill yes)
			(layer "F.Fab")
		)
		(pad "1" smd rect
			(at -1.500124 -1.249934 180)
			(size 0.2794 0.6096)
			(layers "F.Cu" "F.Mask" "F.Paste")
			(net "P12V_NIC5_R")
		)
		(pad "2" smd rect
			(at -1.500124 -0.750062 180)
			(size 0.2794 0.6096)
			(layers "F.Cu" "F.Mask" "F.Paste")
			(net "P12V_NIC5_R")
		)
		(pad "3" smd rect
			(at -1.500124 -0.249936 180)
			(size 0.2794 0.6096)
			(layers "F.Cu" "F.Mask" "F.Paste")
			(net "P12V_NIC5_R")
		)
		(pad "4" smd rect
			(at -1.500124 0.249936 180)
			(size 0.2794 0.6096)
			(layers "F.Cu" "F.Mask" "F.Paste")
			(net "P12V_NIC5_R")
		)
		(pad "5" smd rect
			(at -1.500124 0.750062 180)
			(size 0.2794 0.6096)
			(layers "F.Cu" "F.Mask" "F.Paste")
			(net "P12V_NIC5_R")
		)
		(pad "6" smd rect
			(at -1.500124 1.249934 180)
			(size 0.2794 0.6096)
			(layers "F.Cu" "F.Mask" "F.Paste")
			(net "GND")
		)
		(pad "7" smd rect
			(at 1.500124 1.249934 180)
			(size 0.2794 0.6096)
			(layers "F.Cu" "F.Mask" "F.Paste")
			(net "P12V_NIC5_SS")
		)
		(pad "8" smd rect
			(at 1.500124 0.750062 180)
			(size 0.2794 0.6096)
			(layers "F.Cu" "F.Mask" "F.Paste")
			(net "PWRGD_P12V_NIC5")
		)
		(pad "9" smd rect
			(at 1.500124 0.249936 180)
			(size 0.2794 0.6096)
			(layers "F.Cu" "F.Mask" "F.Paste")
			(net "P12V_NIC5_OCP")
		)
		(pad "10" smd rect
			(at 1.500124 -0.249936 180)
			(size 0.2794 0.6096)
			(layers "F.Cu" "F.Mask" "F.Paste")
			(net "P5V_AUX")
		)
		(pad "11" smd rect
			(at 1.500124 -0.750062 180)
			(size 0.2794 0.6096)
			(layers "F.Cu" "F.Mask" "F.Paste")
			(net "P12V_NIC5_EN_R")
		)
		(pad "12" smd rect
			(at 1.500124 -1.249934 180)
			(size 0.2794 0.6096)
			(layers "F.Cu" "F.Mask" "F.Paste")
			(net "P12V_AUX")
		)
		(pad "13" smd rect
			(at 0 0 270)
			(size 1.9812 2.7178)
			(layers "F.Cu" "F.Mask" "F.Paste")
			(net "P12V_AUX")
		)
		(zone
			(layer "F.Cu")
			(hatch none 0.5)
			(connect_pads
				(clearance 0)
			)
			(min_thickness 0.25)
			(keepout
				(tracks not_allowed)
				(vias allowed)
				(pads allowed)
				(copperpour not_allowed)
				(footprints allowed)
			)
			(placement
				(enabled no)
				(sheetname "")
			)
			(fill
				(thermal_gap 0.5)
				(thermal_bridge_width 0.5)
				(island_removal_mode 0)
			)
			(polygon
				(pts
					(xy 331.38237 -97.825052) (xy 331.25537 -97.825052) (xy 328.28357 -97.825052) (xy 328.283062 -97.825052)
					(xy 328.283062 -100.111052) (xy 328.28357 -100.111052) (xy 328.41057 -100.111052) (xy 329.83297 -100.111052)
					(xy 329.83297 -100.009452) (xy 328.41057 -100.009452) (xy 328.41057 -97.926652) (xy 331.25537 -97.926652)
					(xy 331.25537 -100.009452) (xy 329.85837 -100.009452) (xy 329.85837 -100.111052) (xy 331.25537 -100.111052)
					(xy 331.38237 -100.111052) (xy 331.382878 -100.111052) (xy 331.382878 -97.825052)
				)
			)
		)
	)
	(footprint ""
		(layer "F.Cu")
		(at 452.374 -227.4316)
		(property "Reference" "U434"
			(at 6.531356 -0.596138 0)
			(unlocked yes)
			(layer "F.SilkS")
			(effects
				(font
					(size 0.7874 0.5842)
					(thickness 0.1524)
				)
				(justify left)
			)
		)
		(property "Value" ""
			(at 0 0 0)
			(layer "F.Fab")
			(effects
				(font
					(size 1.27 1.27)
				)
			)
		)
		(duplicate_pad_numbers_are_jumpers no)
		(fp_line
			(start -6.1214 0.750062)
			(end -5.1054 0.750062)
			(stroke
				(width 0.1524)
				(type default)
			)
			(layer "F.SilkS")
		)
		(fp_line
			(start -5.08 -1.75006)
			(end -5.588 -1.75006)
			(stroke
				(width 0.1524)
				(type default)
			)
			(layer "F.SilkS")
		)
		(fp_line
			(start -5.08 3.24993)
			(end -5.588 3.24993)
			(stroke
				(width 0.1524)
				(type default)
			)
			(layer "F.SilkS")
		)
		(fp_line
			(start -4.500118 -4.500118)
			(end -4.500118 -4.0386)
			(stroke
				(width 0.1524)
				(type default)
			)
			(layer "F.SilkS")
		)
		(fp_line
			(start -4.500118 4.0386)
			(end -4.500118 4.500118)
			(stroke
				(width 0.1524)
				(type default)
			)
			(layer "F.SilkS")
		)
		(fp_line
			(start -4.500118 4.500118)
			(end -4.0386 4.500118)
			(stroke
				(width 0.1524)
				(type default)
			)
			(layer "F.SilkS")
		)
		(fp_line
			(start -4.0386 -4.500118)
			(end -4.500118 -4.500118)
			(stroke
				(width 0.1524)
				(type default)
			)
			(layer "F.SilkS")
		)
		(fp_line
			(start -2.249932 5.0292)
			(end -2.249932 6.0452)
			(stroke
				(width 0.1524)
				(type default)
			)
			(layer "F.SilkS")
		)
		(fp_line
			(start -1.75006 -6.0706)
			(end -1.75006 -5.0546)
			(stroke
				(width 0.1524)
				(type default)
			)
			(layer "F.SilkS")
		)
		(fp_line
			(start 0.249936 5.0292)
			(end 0.249936 5.5372)
			(stroke
				(width 0.1524)
				(type default)
			)
			(layer "F.SilkS")
		)
		(fp_line
			(start 0.750062 -5.588)
			(end 0.750062 -5.08)
			(stroke
				(width 0.1524)
				(type default)
			)
			(layer "F.SilkS")
		)
		(fp_line
			(start 2.750058 5.0546)
			(end 2.750058 6.0706)
			(stroke
				(width 0.1524)
				(type default)
			)
			(layer "F.SilkS")
		)
		(fp_line
			(start 3.24993 -6.0706)
			(end 3.24993 -5.0546)
			(stroke
				(width 0.1524)
				(type default)
			)
			(layer "F.SilkS")
		)
		(fp_line
			(start 4.0386 4.500118)
			(end 4.500118 4.500118)
			(stroke
				(width 0.1524)
				(type default)
			)
			(layer "F.SilkS")
		)
		(fp_line
			(start 4.500118 -4.500118)
			(end 4.0386 -4.500118)
			(stroke
				(width 0.1524)
				(type default)
			)
			(layer "F.SilkS")
		)
		(fp_line
			(start 4.500118 -4.0386)
			(end 4.500118 -4.500118)
			(stroke
				(width 0.1524)
				(type default)
			)
			(layer "F.SilkS")
		)
		(fp_line
			(start 4.500118 4.500118)
			(end 4.500118 4.0386)
			(stroke
				(width 0.1524)
				(type default)
			)
			(layer "F.SilkS")
		)
		(fp_line
			(start 5.0292 0.249936)
			(end 6.0452 0.249936)
			(stroke
				(width 0.1524)
				(type default)
			)
			(layer "F.SilkS")
		)
		(fp_line
			(start 5.5372 -2.249932)
			(end 5.0292 -2.249932)
			(stroke
				(width 0.1524)
				(type default)
			)
			(layer "F.SilkS")
		)
		(fp_line
			(start 5.5372 2.750058)
			(end 5.0292 2.750058)
			(stroke
				(width 0.1524)
				(type default)
			)
			(layer "F.SilkS")
		)
		(fp_poly
			(pts
				(xy -6.442964 -3.7338) (xy -6.066028 -2.790444) (xy -5.31114 -3.639312)
			)
			(stroke
				(width 0)
				(type default)
			)
			(fill yes)
			(layer "F.SilkS")
		)
		(fp_line
			(start -6.1214 0.750062)
			(end -5.1054 0.750062)
			(stroke
				(width 0.1)
				(type default)
			)
			(layer "F.Fab")
		)
		(fp_line
			(start -5.08 -1.75006)
			(end -5.588 -1.75006)
			(stroke
				(width 0.1)
				(type default)
			)
			(layer "F.Fab")
		)
		(fp_line
			(start -5.08 3.24993)
			(end -5.588 3.24993)
			(stroke
				(width 0.1)
				(type default)
			)
			(layer "F.Fab")
		)
		(fp_line
			(start -4.500118 -4.500118)
			(end -4.500118 4.500118)
			(stroke
				(width 0.1)
				(type default)
			)
			(layer "F.Fab")
		)
		(fp_line
			(start -4.500118 4.500118)
			(end 4.500118 4.500118)
			(stroke
				(width 0.1)
				(type default)
			)
			(layer "F.Fab")
		)
		(fp_line
			(start -2.249932 5.0292)
			(end -2.249932 6.0452)
			(stroke
				(width 0.1)
				(type default)
			)
			(layer "F.Fab")
		)
		(fp_line
			(start -1.75006 -6.0706)
			(end -1.75006 -5.0546)
			(stroke
				(width 0.1)
				(type default)
			)
			(layer "F.Fab")
		)
		(fp_line
			(start 0.249936 5.0292)
			(end 0.249936 5.5372)
			(stroke
				(width 0.1)
				(type default)
			)
			(layer "F.Fab")
		)
		(fp_line
			(start 0.750062 -5.588)
			(end 0.750062 -5.08)
			(stroke
				(width 0.1)
				(type default)
			)
			(layer "F.Fab")
		)
		(fp_line
			(start 2.750058 5.0546)
			(end 2.750058 6.0706)
			(stroke
				(width 0.1)
				(type default)
			)
			(layer "F.Fab")
		)
		(fp_line
			(start 3.24993 -6.0706)
			(end 3.24993 -5.0546)
			(stroke
				(width 0.1)
				(type default)
			)
			(layer "F.Fab")
		)
		(fp_line
			(start 4.500118 -4.500118)
			(end -4.500118 -4.500118)
			(stroke
				(width 0.1)
				(type default)
			)
			(layer "F.Fab")
		)
		(fp_line
			(start 4.500118 4.500118)
			(end 4.500118 -4.500118)
			(stroke
				(width 0.1)
				(type default)
			)
			(layer "F.Fab")
		)
		(fp_line
			(start 5.0292 0.249936)
			(end 6.0452 0.249936)
			(stroke
				(width 0.1)
				(type default)
			)
			(layer "F.Fab")
		)
		(fp_line
			(start 5.5372 -2.249932)
			(end 5.0292 -2.249932)
			(stroke
				(width 0.1)
				(type default)
			)
			(layer "F.Fab")
		)
		(fp_line
			(start 5.5372 2.750058)
			(end 5.0292 2.750058)
			(stroke
				(width 0.1)
				(type default)
			)
			(layer "F.Fab")
		)
		(fp_poly
			(pts
				(xy -6.0452 -4.258056) (xy -6.0452 -3.242056) (xy -5.0292 -3.750056)
			)
			(stroke
				(width 0)
				(type default)
			)
			(fill yes)
			(layer "F.Fab")
		)
		(fp_text user "16"
			(at -6.116828 5.878068 270)
			(unlocked yes)
			(layer "F.SilkS")
			(effects
				(font
					(size 0.7874 0.5842)
					(thickness 0.1524)
				)
			)
		)
		(fp_text user "64"
			(at -4.703826 -4.99872 0)
			(unlocked yes)
			(layer "F.SilkS")
			(effects
				(font
					(size 0.7874 0.5842)
					(thickness 0.1524)
				)
			)
		)
		(fp_text user "17"
			(at -4.350004 6.070092 0)
			(unlocked yes)
			(layer "F.SilkS")
			(effects
				(font
					(size 0.7874 0.5842)
					(thickness 0.1524)
				)
			)
		)
		(fp_text user "32"
			(at 4.445 5.496052 0)
			(unlocked yes)
			(layer "F.SilkS")
			(effects
				(font
					(size 0.7874 0.5842)
					(thickness 0.1524)
				)
			)
		)
		(fp_text user "49"
			(at 5.167884 -5.369052 0)
			(unlocked yes)
			(layer "F.SilkS")
			(effects
				(font
					(size 0.7874 0.5842)
					(thickness 0.1524)
				)
			)
		)
		(fp_text user "33"
			(at 5.425948 4.318 270)
			(unlocked yes)
			(layer "F.SilkS")
			(effects
				(font
					(size 0.7874 0.5842)
					(thickness 0.1524)
				)
			)
		)
		(fp_text user "48"
			(at 6.353302 -5.121656 270)
			(unlocked yes)
			(layer "F.SilkS")
			(effects
				(font
					(size 0.7874 0.5842)
					(thickness 0.1524)
				)
			)
		)
		(fp_text user "16"
			(at -5.496052 4.318 270)
			(unlocked yes)
			(layer "F.Fab")
			(effects
				(font
					(size 0.7874 0.5842)
					(thickness 0.1524)
				)
			)
		)
		(fp_text user "64"
			(at -4.572 -5.298948 0)
			(unlocked yes)
			(layer "F.Fab")
			(effects
				(font
					(size 0.7874 0.5842)
					(thickness 0.1524)
				)
			)
		)
		(fp_text user "17"
			(at -4.572 5.496052 0)
			(unlocked yes)
			(layer "F.Fab")
			(effects
				(font
					(size 0.7874 0.5842)
					(thickness 0.1524)
				)
			)
		)
		(fp_text user "49"
			(at 4.445 -5.298948 0)
			(unlocked yes)
			(layer "F.Fab")
			(effects
				(font
					(size 0.7874 0.5842)
					(thickness 0.1524)
				)
			)
		)
		(fp_text user "32"
			(at 4.445 5.496052 0)
			(unlocked yes)
			(layer "F.Fab")
			(effects
				(font
					(size 0.7874 0.5842)
					(thickness 0.1524)
				)
			)
		)
		(fp_text user "48"
			(at 5.425948 -4.445 270)
			(unlocked yes)
			(layer "F.Fab")
			(effects
				(font
					(size 0.7874 0.5842)
					(thickness 0.1524)
				)
			)
		)
		(fp_text user "33"
			(at 5.425948 4.318 270)
			(unlocked yes)
			(layer "F.Fab")
			(effects
				(font
					(size 0.7874 0.5842)
					(thickness 0.1524)
				)
			)
		)
		(pad "1" smd circle
			(at -4.45008 -3.750056 270)
			(size 0 0)
			(layers "F.Cu" "F.Mask" "F.Paste")
			(net "UART_PEX3_SDB_CP2108_TX")
		)
		(pad "2" smd circle
			(at -4.45008 -3.24993 270)
			(size 0 0)
			(layers "F.Cu" "F.Mask" "F.Paste")
			(net "GND")
		)
		(pad "3" smd circle
			(at -4.45008 -2.750058 270)
			(size 0 0)
			(layers "F.Cu" "F.Mask" "F.Paste")
			(net "P3V3_AUX")
		)
		(pad "4" smd circle
			(at -4.45008 -2.249932 270)
			(size 0 0)
			(layers "F.Cu" "F.Mask" "F.Paste")
			(net "UART_PEX3_SDB_CP2108_RX")
		)
		(pad "5" smd circle
			(at -4.45008 -1.75006 270)
			(size 0 0)
			(layers "F.Cu" "F.Mask" "F.Paste")
			(net "Net_9287")
		)
		(pad "6" smd circle
			(at -4.45008 -1.249934 270)
			(size 0 0)
			(layers "F.Cu" "F.Mask" "F.Paste")
			(net "Net_9249")
		)
		(pad "7" smd circle
			(at -4.45008 -0.750062 270)
			(size 0 0)
			(layers "F.Cu" "F.Mask" "F.Paste")
			(net "Net_9253")
		)
		(pad "8" smd circle
			(at -4.45008 -0.249936 270)
			(size 0 0)
			(layers "F.Cu" "F.Mask" "F.Paste")
			(net "Net_9283")
		)
		(pad "9" smd circle
			(at -4.45008 0.249936 270)
			(size 0 0)
			(layers "F.Cu" "F.Mask" "F.Paste")
			(net "Net_9279")
		)
		(pad "10" smd circle
			(at -4.45008 0.750062 270)
			(size 0 0)
			(layers "F.Cu" "F.Mask" "F.Paste")
			(net "Net_9275")
		)
		(pad "11" smd circle
			(at -4.45008 1.249934 270)
			(size 0 0)
			(layers "F.Cu" "F.Mask" "F.Paste")
			(net "Net_9254")
		)
		(pad "12" smd circle
			(at -4.45008 1.75006 270)
			(size 0 0)
			(layers "F.Cu" "F.Mask" "F.Paste")
			(net "Net_9284")
		)
		(pad "13" smd circle
			(at -4.45008 2.249932 270)
			(size 0 0)
			(layers "F.Cu" "F.Mask" "F.Paste")
			(net "Net_9288")
		)
		(pad "14" smd circle
			(at -4.45008 2.750058 270)
			(size 0 0)
			(layers "F.Cu" "F.Mask" "F.Paste")
			(net "Net_9250")
		)
		(pad "15" smd circle
			(at -4.45008 3.24993 270)
			(size 0 0)
			(layers "F.Cu" "F.Mask" "F.Paste")
			(net "UART_PEX2_SDB_CP2108_TX")
		)
		(pad "16" smd circle
			(at -4.45008 3.750056 270)
			(size 0 0)
			(layers "F.Cu" "F.Mask" "F.Paste")
			(net "UART_PEX2_SDB_CP2108_RX")
		)
		(pad "17" smd circle
			(at -3.750056 4.45008)
			(size 0 0)
			(layers "F.Cu" "F.Mask" "F.Paste")
			(net "Net_9280")
		)
		(pad "18" smd circle
			(at -3.24993 4.45008)
			(size 0 0)
			(layers "F.Cu" "F.Mask" "F.Paste")
			(net "Net_9276")
		)
		(pad "19" smd circle
			(at -2.750058 4.45008)
			(size 0 0)
			(layers "F.Cu" "F.Mask" "F.Paste")
			(net "Net_9247")
		)
		(pad "20" smd circle
			(at -2.249932 4.45008)
			(size 0 0)
			(layers "F.Cu" "F.Mask" "F.Paste")
			(net "Net_9248")
		)
		(pad "21" smd circle
			(at -1.75006 4.45008)
			(size 0 0)
			(layers "F.Cu" "F.Mask" "F.Paste")
			(net "Net_9267")
		)
		(pad "22" smd circle
			(at -1.249934 4.45008)
			(size 0 0)
			(layers "F.Cu" "F.Mask" "F.Paste")
			(net "Net_9268")
		)
		(pad "23" smd circle
			(at -0.750062 4.45008)
			(size 0 0)
			(layers "F.Cu" "F.Mask" "F.Paste")
			(net "Net_9269")
		)
		(pad "24" smd circle
			(at -0.249936 4.45008)
			(size 0 0)
			(layers "F.Cu" "F.Mask" "F.Paste")
			(net "P3V3_AUX")
		)
		(pad "25" smd circle
			(at 0.249936 4.45008)
			(size 0 0)
			(layers "F.Cu" "F.Mask" "F.Paste")
			(net "GND")
		)
		(pad "26" smd circle
			(at 0.750062 4.45008)
			(size 0 0)
			(layers "F.Cu" "F.Mask" "F.Paste")
			(net "Net_9270")
		)
		(pad "27" smd circle
			(at 1.249934 4.45008)
			(size 0 0)
			(layers "F.Cu" "F.Mask" "F.Paste")
			(net "Net_9271")
		)
		(pad "28" smd circle
			(at 1.75006 4.45008)
			(size 0 0)
			(layers "F.Cu" "F.Mask" "F.Paste")
			(net "Net_9272")
		)
		(pad "29" smd circle
			(at 2.249932 4.45008)
			(size 0 0)
			(layers "F.Cu" "F.Mask" "F.Paste")
			(net "Net_9259")
		)
		(pad "30" smd circle
			(at 2.750058 4.45008)
			(size 0 0)
			(layers "F.Cu" "F.Mask" "F.Paste")
			(net "Net_9260")
		)
		(pad "31" smd circle
			(at 3.24993 4.45008)
			(size 0 0)
			(layers "F.Cu" "F.Mask" "F.Paste")
			(net "Net_9261")
		)
		(pad "32" smd circle
			(at 3.750056 4.45008)
			(size 0 0)
			(layers "F.Cu" "F.Mask" "F.Paste")
			(net "Net_9262")
		)
		(pad "33" smd circle
			(at 4.45008 3.750056 90)
			(size 0 0)
			(layers "F.Cu" "F.Mask" "F.Paste")
			(net "Net_9263")
		)
		(pad "34" smd circle
			(at 4.45008 3.24993 90)
			(size 0 0)
			(layers "F.Cu" "F.Mask" "F.Paste")
			(net "Net_9264")
		)
		(pad "35" smd circle
			(at 4.45008 2.750058 90)
			(size 0 0)
			(layers "F.Cu" "F.Mask" "F.Paste")
			(net "Net_9258")
		)
		(pad "36" smd circle
			(at 4.45008 2.249932 90)
			(size 0 0)
			(layers "F.Cu" "F.Mask" "F.Paste")
			(net "Net_9257")
		)
		(pad "37" smd circle
			(at 4.45008 1.75006 90)
			(size 0 0)
			(layers "F.Cu" "F.Mask" "F.Paste")
			(net "Net_9265")
		)
		(pad "38" smd circle
			(at 4.45008 1.249934 90)
			(size 0 0)
			(layers "F.Cu" "F.Mask" "F.Paste")
			(net "Net_9266")
		)
		(pad "39" smd circle
			(at 4.45008 0.750062 90)
			(size 0 0)
			(layers "F.Cu" "F.Mask" "F.Paste")
			(net "P3V3_AUX")
		)
		(pad "40" smd circle
			(at 4.45008 0.249936 90)
			(size 0 0)
			(layers "F.Cu" "F.Mask" "F.Paste")
			(net "Net_9273")
		)
		(pad "41" smd circle
			(at 4.45008 -0.249936 90)
			(size 0 0)
			(layers "F.Cu" "F.Mask" "F.Paste")
			(net "Net_9274")
		)
		(pad "42" smd circle
			(at 4.45008 -0.750062 90)
			(size 0 0)
			(layers "F.Cu" "F.Mask" "F.Paste")
			(net "Net_9255")
		)
		(pad "43" smd circle
			(at 4.45008 -1.249934 90)
			(size 0 0)
			(layers "F.Cu" "F.Mask" "F.Paste")
			(net "Net_9285")
		)
		(pad "44" smd circle
			(at 4.45008 -1.75006 90)
			(size 0 0)
			(layers "F.Cu" "F.Mask" "F.Paste")
			(net "Net_9281")
		)
		(pad "45" smd circle
			(at 4.45008 -2.249932 90)
			(size 0 0)
			(layers "F.Cu" "F.Mask" "F.Paste")
			(net "Net_9277")
		)
		(pad "46" smd circle
			(at 4.45008 -2.750058 90)
			(size 0 0)
			(layers "F.Cu" "F.Mask" "F.Paste")
			(net "Net_9289")
		)
		(pad "47" smd circle
			(at 4.45008 -3.24993 90)
			(size 0 0)
			(layers "F.Cu" "F.Mask" "F.Paste")
			(net "Net_9251")
		)
		(pad "48" smd circle
			(at 4.45008 -3.750056 90)
			(size 0 0)
			(layers "F.Cu" "F.Mask" "F.Paste")
			(net "UART_PEX1_SDB_CP2108_TX")
		)
		(pad "49" smd circle
			(at 3.750056 -4.45008 180)
			(size 0 0)
			(layers "F.Cu" "F.Mask" "F.Paste")
			(net "UART_PEX1_SDB_CP2108_RX")
		)
		(pad "50" smd circle
			(at 3.24993 -4.45008 180)
			(size 0 0)
			(layers "F.Cu" "F.Mask" "F.Paste")
			(net "Net_9256")
		)
		(pad "51" smd circle
			(at 2.750058 -4.45008 180)
			(size 0 0)
			(layers "F.Cu" "F.Mask" "F.Paste")
			(net "Net_9286")
		)
		(pad "52" smd circle
			(at 2.249932 -4.45008 180)
			(size 0 0)
			(layers "F.Cu" "F.Mask" "F.Paste")
			(net "Net_9282")
		)
		(pad "53" smd circle
			(at 1.75006 -4.45008 180)
			(size 0 0)
			(layers "F.Cu" "F.Mask" "F.Paste")
			(net "Net_9278")
		)
		(pad "54" smd circle
			(at 1.249934 -4.45008 180)
			(size 0 0)
			(layers "F.Cu" "F.Mask" "F.Paste")
			(net "Net_9290")
		)
		(pad "55" smd circle
			(at 0.750062 -4.45008 180)
			(size 0 0)
			(layers "F.Cu" "F.Mask" "F.Paste")
			(net "Net_9252")
		)
		(pad "56" smd circle
			(at 0.249936 -4.45008 180)
			(size 0 0)
			(layers "F.Cu" "F.Mask" "F.Paste")
			(net "UART_PEX0_SDB_CP2108_TX")
		)
		(pad "57" smd circle
			(at -0.249936 -4.45008 180)
			(size 0 0)
			(layers "F.Cu" "F.Mask" "F.Paste")
			(net "UART_PEX0_SDB_CP2108_RX")
		)
		(pad "58" smd circle
			(at -0.750062 -4.45008 180)
			(size 0 0)
			(layers "F.Cu" "F.Mask" "F.Paste")
			(net "P3V3_AUX")
		)
		(pad "59" smd circle
			(at -1.249934 -4.45008 180)
			(size 0 0)
			(layers "F.Cu" "F.Mask" "F.Paste")
			(net "GND")
		)
		(pad "60" smd circle
			(at -1.75006 -4.45008 180)
			(size 0 0)
			(layers "F.Cu" "F.Mask" "F.Paste")
			(net "P3V3_AUX")
		)
		(pad "61" smd circle
			(at -2.249932 -4.45008 180)
			(size 0 0)
			(layers "F.Cu" "F.Mask" "F.Paste")
			(net "P3V3_AUX")
		)
		(pad "62" smd circle
			(at -2.750058 -4.45008 180)
			(size 0 0)
			(layers "F.Cu" "F.Mask" "F.Paste")
			(net "USB2_CP2108_SDB_DP")
		)
		(pad "63" smd circle
			(at -3.24993 -4.45008 180)
			(size 0 0)
			(layers "F.Cu" "F.Mask" "F.Paste")
			(net "USB2_CP2108_SDB_DN")
		)
		(pad "64" smd circle
			(at -3.750056 -4.45008 180)
			(size 0 0)
			(layers "F.Cu" "F.Mask" "F.Paste")
			(net "RST_CP2108_SDB_R_N")
		)
		(pad "TH" smd rect
			(at 0 0)
			(size 4.2672 4.2672)
			(layers "F.Cu" "F.Mask" "F.Paste")
			(net "GND")
		)
		(zone
			(layer "F.Cu")
			(hatch none 0.5)
			(connect_pads
				(clearance 0)
			)
			(min_thickness 0.25)
			(keepout
				(tracks not_allowed)
				(vias allowed)
				(pads allowed)
				(copperpour not_allowed)
				(footprints allowed)
			)
			(placement
				(enabled no)
				(sheetname "")
			)
			(fill
				(thermal_gap 0.5)
				(thermal_bridge_width 0.5)
				(island_removal_mode 0)
			)
			(polygon
				(pts
					(xy 448.4116 -228.1936) (xy 448.4116 -223.4692) (xy 456.3364 -223.4692) (xy 456.3364 -231.394)
					(xy 448.4116 -231.394) (xy 448.4116 -228.219) (xy 450.1896 -228.219) (xy 450.1896 -229.616) (xy 454.5584 -229.616)
					(xy 454.5584 -225.2472) (xy 450.1896 -225.2472) (xy 450.1896 -228.1936)
				)
			)
		)
	)
	(footprint ""
		(layer "F.Cu")
		(at 192.582038 -37.025072)
		(property "Reference" "R5673"
			(at 0 0 0)
			(layer "F.SilkS")
			(hide yes)
			(effects
				(font
					(size 1.27 1.27)
				)
			)
		)
		(property "Value" ""
			(at 0 0 0)
			(layer "F.Fab")
			(effects
				(font
					(size 1.27 1.27)
				)
			)
		)
		(duplicate_pad_numbers_are_jumpers no)
		(fp_line
			(start -0.7874 -0.4064)
			(end 0.7874 -0.4064)
			(stroke
				(width 0.1524)
				(type default)
			)
			(layer "F.SilkS")
		)
		(fp_line
			(start -0.7874 0.4064)
			(end -0.7874 -0.4064)
			(stroke
				(width 0.1524)
				(type default)
			)
			(layer "F.SilkS")
		)
		(fp_line
			(start 0.7874 -0.4064)
			(end 0.7874 0.4064)
			(stroke
				(width 0.1524)
				(type default)
			)
			(layer "F.SilkS")
		)
		(fp_line
			(start 0.7874 0.4064)
			(end -0.7874 0.4064)
			(stroke
				(width 0.1524)
				(type default)
			)
			(layer "F.SilkS")
		)
		(fp_line
			(start -0.67945 -0.305054)
			(end -0.12065 -0.305054)
			(stroke
				(width 0.1)
				(type default)
			)
			(layer "F.Fab")
		)
		(fp_line
			(start -0.67945 0.3048)
			(end -0.67945 -0.305054)
			(stroke
				(width 0.1)
				(type default)
			)
			(layer "F.Fab")
		)
		(fp_line
			(start -0.12065 -0.305054)
			(end -0.12065 -0.2794)
			(stroke
				(width 0.1)
				(type default)
			)
			(layer "F.Fab")
		)
		(fp_line
			(start -0.12065 -0.2794)
			(end 0.12065 -0.2794)
			(stroke
				(width 0.1)
				(type default)
			)
			(layer "F.Fab")
		)
		(fp_line
			(start -0.12065 0.2794)
			(end -0.12065 0.3048)
			(stroke
				(width 0.1)
				(type default)
			)
			(layer "F.Fab")
		)
		(fp_line
			(start -0.12065 0.3048)
			(end -0.67945 0.3048)
			(stroke
				(width 0.1)
				(type default)
			)
			(layer "F.Fab")
		)
		(fp_line
			(start 0.120396 0.2794)
			(end -0.12065 0.2794)
			(stroke
				(width 0.1)
				(type default)
			)
			(layer "F.Fab")
		)
		(fp_line
			(start 0.120396 0.3048)
			(end 0.120396 0.2794)
			(stroke
				(width 0.1)
				(type default)
			)
			(layer "F.Fab")
		)
		(fp_line
			(start 0.12065 -0.3048)
			(end 0.67945 -0.3048)
			(stroke
				(width 0.1)
				(type default)
			)
			(layer "F.Fab")
		)
		(fp_line
			(start 0.12065 -0.2794)
			(end 0.12065 -0.3048)
			(stroke
				(width 0.1)
				(type default)
			)
			(layer "F.Fab")
		)
		(fp_line
			(start 0.67945 -0.3048)
			(end 0.67945 0.3048)
			(stroke
				(width 0.1)
				(type default)
			)
			(layer "F.Fab")
		)
		(fp_line
			(start 0.67945 0.3048)
			(end 0.120396 0.3048)
			(stroke
				(width 0.1)
				(type default)
			)
			(layer "F.Fab")
		)
		(pad "1" smd circle
			(at -0.40005 0)
			(size 0 0)
			(layers "F.Cu" "F.Mask" "F.Paste")
			(net "RST_SMB_SSD_R_N")
		)
		(pad "2" smd circle
			(at 0.40005 0)
			(size 0 0)
			(layers "F.Cu" "F.Mask" "F.Paste")
			(net "RST_SMB_SSD7_N")
		)
	)
	(footprint ""
		(layer "F.Cu")
		(at 228.6508 -231.4194 -90)
		(property "Reference" "R4538"
			(at 0 0 270)
			(layer "F.SilkS")
			(hide yes)
			(effects
				(font
					(size 1.27 1.27)
				)
			)
		)
		(property "Value" ""
			(at 0 0 270)
			(layer "F.Fab")
			(effects
				(font
					(size 1.27 1.27)
				)
			)
		)
		(duplicate_pad_numbers_are_jumpers no)
		(fp_line
			(start -0.7874 0.4064)
			(end -0.7874 -0.4064)
			(stroke
				(width 0.1524)
				(type default)
			)
			(layer "F.SilkS")
		)
		(fp_line
			(start 0.7874 0.4064)
			(end -0.7874 0.4064)
			(stroke
				(width 0.1524)
				(type default)
			)
			(layer "F.SilkS")
		)
		(fp_line
			(start -0.7874 -0.4064)
			(end 0.7874 -0.4064)
			(stroke
				(width 0.1524)
				(type default)
			)
			(layer "F.SilkS")
		)
		(fp_line
			(start 0.7874 -0.4064)
			(end 0.7874 0.4064)
			(stroke
				(width 0.1524)
				(type default)
			)
			(layer "F.SilkS")
		)
		(fp_line
			(start -0.67945 0.3048)
			(end -0.67945 -0.305054)
			(stroke
				(width 0.1)
				(type default)
			)
			(layer "F.Fab")
		)
		(fp_line
			(start -0.12065 0.3048)
			(end -0.67945 0.3048)
			(stroke
				(width 0.1)
				(type default)
			)
			(layer "F.Fab")
		)
		(fp_line
			(start 0.120396 0.3048)
			(end 0.120396 0.2794)
			(stroke
				(width 0.1)
				(type default)
			)
			(layer "F.Fab")
		)
		(fp_line
			(start 0.67945 0.3048)
			(end 0.120396 0.3048)
			(stroke
				(width 0.1)
				(type default)
			)
			(layer "F.Fab")
		)
		(fp_line
			(start -0.12065 0.2794)
			(end -0.12065 0.3048)
			(stroke
				(width 0.1)
				(type default)
			)
			(layer "F.Fab")
		)
		(fp_line
			(start 0.120396 0.2794)
			(end -0.12065 0.2794)
			(stroke
				(width 0.1)
				(type default)
			)
			(layer "F.Fab")
		)
		(fp_line
			(start -0.12065 -0.2794)
			(end 0.12065 -0.2794)
			(stroke
				(width 0.1)
				(type default)
			)
			(layer "F.Fab")
		)
		(fp_line
			(start 0.12065 -0.2794)
			(end 0.12065 -0.3048)
			(stroke
				(width 0.1)
				(type default)
			)
			(layer "F.Fab")
		)
		(fp_line
			(start 0.12065 -0.3048)
			(end 0.67945 -0.3048)
			(stroke
				(width 0.1)
				(type default)
			)
			(layer "F.Fab")
		)
		(fp_line
			(start 0.67945 -0.3048)
			(end 0.67945 0.3048)
			(stroke
				(width 0.1)
				(type default)
			)
			(layer "F.Fab")
		)
		(fp_line
			(start -0.67945 -0.305054)
			(end -0.12065 -0.305054)
			(stroke
				(width 0.1)
				(type default)
			)
			(layer "F.Fab")
		)
		(fp_line
			(start -0.12065 -0.305054)
			(end -0.12065 -0.2794)
			(stroke
				(width 0.1)
				(type default)
			)
			(layer "F.Fab")
		)
		(pad "1" smd circle
			(at -0.40005 0 270)
			(size 0 0)
			(layers "F.Cu" "F.Mask" "F.Paste")
			(net "NIC2_MAIN_PWR_BIC_EN_R")
		)
		(pad "2" smd circle
			(at 0.40005 0 270)
			(size 0 0)
			(layers "F.Cu" "F.Mask" "F.Paste")
			(net "NIC2_MAIN_PWR_BIC_EN")
		)
	)
	(footprint ""
		(layer "F.Cu")
		(at 392.24712 -55.63489 90)
		(property "Reference" "PC419"
			(at 0 0 90)
			(layer "F.SilkS")
			(hide yes)
			(effects
				(font
					(size 1.27 1.27)
				)
			)
		)
		(property "Value" ""
			(at 0 0 90)
			(layer "F.Fab")
			(effects
				(font
					(size 1.27 1.27)
				)
			)
		)
		(duplicate_pad_numbers_are_jumpers no)
		(fp_line
			(start 1.524 -0.762)
			(end 1.524 0.762)
			(stroke
				(width 0.1524)
				(type default)
			)
			(layer "F.SilkS")
		)
		(fp_line
			(start -1.524 -0.762)
			(end 1.524 -0.762)
			(stroke
				(width 0.1524)
				(type default)
			)
			(layer "F.SilkS")
		)
		(fp_line
			(start 1.524 0.762)
			(end -1.524 0.762)
			(stroke
				(width 0.1524)
				(type default)
			)
			(layer "F.SilkS")
		)
		(fp_line
			(start -1.524 0.762)
			(end -1.524 -0.762)
			(stroke
				(width 0.1524)
				(type default)
			)
			(layer "F.SilkS")
		)
		(fp_line
			(start 1.1049 -0.724916)
			(end -1.1049 -0.724916)
			(stroke
				(width 0.1)
				(type default)
			)
			(layer "F.Fab")
		)
		(fp_line
			(start -1.1049 -0.724916)
			(end -1.1049 0.724916)
			(stroke
				(width 0.1)
				(type default)
			)
			(layer "F.Fab")
		)
		(fp_line
			(start 1.1049 0.724916)
			(end 1.1049 -0.724916)
			(stroke
				(width 0.1)
				(type default)
			)
			(layer "F.Fab")
		)
		(fp_line
			(start -1.1049 0.724916)
			(end 1.1049 0.724916)
			(stroke
				(width 0.1)
				(type default)
			)
			(layer "F.Fab")
		)
		(pad "1" smd rect
			(at -0.889 0 270)
			(size 1.016 1.27)
			(layers "F.Cu" "F.Mask" "F.Paste")
			(net "P12V_SSD13_R")
		)
		(pad "2" smd rect
			(at 0.889 0 270)
			(size 1.016 1.27)
			(layers "F.Cu" "F.Mask" "F.Paste")
			(net "GND")
		)
	)
	(footprint ""
		(layer "F.Cu")
		(at 161.83864 -44.341542 90)
		(property "Reference" "C314"
			(at 0 0 90)
			(layer "F.SilkS")
			(hide yes)
			(effects
				(font
					(size 1.27 1.27)
				)
			)
		)
		(property "Value" ""
			(at 0 0 90)
			(layer "F.Fab")
			(effects
				(font
					(size 1.27 1.27)
				)
			)
		)
		(duplicate_pad_numbers_are_jumpers no)
		(fp_line
			(start 0.7874 -0.4064)
			(end 0.7874 0.4064)
			(stroke
				(width 0.1524)
				(type default)
			)
			(layer "F.SilkS")
		)
		(fp_line
			(start -0.7874 -0.4064)
			(end 0.7874 -0.4064)
			(stroke
				(width 0.1524)
				(type default)
			)
			(layer "F.SilkS")
		)
		(fp_line
			(start 0.7874 0.4064)
			(end -0.7874 0.4064)
			(stroke
				(width 0.1524)
				(type default)
			)
			(layer "F.SilkS")
		)
		(fp_line
			(start -0.7874 0.4064)
			(end -0.7874 -0.4064)
			(stroke
				(width 0.1524)
				(type default)
			)
			(layer "F.SilkS")
		)
		(fp_line
			(start -0.12065 -0.305054)
			(end -0.12065 -0.2794)
			(stroke
				(width 0.1)
				(type default)
			)
			(layer "F.Fab")
		)
		(fp_line
			(start -0.67945 -0.305054)
			(end -0.12065 -0.305054)
			(stroke
				(width 0.1)
				(type default)
			)
			(layer "F.Fab")
		)
		(fp_line
			(start 0.67945 -0.3048)
			(end 0.67945 0.3048)
			(stroke
				(width 0.1)
				(type default)
			)
			(layer "F.Fab")
		)
		(fp_line
			(start 0.12065 -0.3048)
			(end 0.67945 -0.3048)
			(stroke
				(width 0.1)
				(type default)
			)
			(layer "F.Fab")
		)
		(fp_line
			(start 0.12065 -0.2794)
			(end 0.12065 -0.3048)
			(stroke
				(width 0.1)
				(type default)
			)
			(layer "F.Fab")
		)
		(fp_line
			(start -0.12065 -0.2794)
			(end 0.12065 -0.2794)
			(stroke
				(width 0.1)
				(type default)
			)
			(layer "F.Fab")
		)
		(fp_line
			(start 0.120396 0.2794)
			(end -0.12065 0.2794)
			(stroke
				(width 0.1)
				(type default)
			)
			(layer "F.Fab")
		)
		(fp_line
			(start -0.12065 0.2794)
			(end -0.12065 0.3048)
			(stroke
				(width 0.1)
				(type default)
			)
			(layer "F.Fab")
		)
		(fp_line
			(start 0.67945 0.3048)
			(end 0.120396 0.3048)
			(stroke
				(width 0.1)
				(type default)
			)
			(layer "F.Fab")
		)
		(fp_line
			(start 0.120396 0.3048)
			(end 0.120396 0.2794)
			(stroke
				(width 0.1)
				(type default)
			)
			(layer "F.Fab")
		)
		(fp_line
			(start -0.12065 0.3048)
			(end -0.67945 0.3048)
			(stroke
				(width 0.1)
				(type default)
			)
			(layer "F.Fab")
		)
		(fp_line
			(start -0.67945 0.3048)
			(end -0.67945 -0.305054)
			(stroke
				(width 0.1)
				(type default)
			)
			(layer "F.Fab")
		)
		(pad "1" smd circle
			(at -0.40005 0 90)
			(size 0 0)
			(layers "F.Cu" "F.Mask" "F.Paste")
			(net "P12V_SSD5_VIN_P")
		)
		(pad "2" smd circle
			(at 0.40005 0 90)
			(size 0 0)
			(layers "F.Cu" "F.Mask" "F.Paste")
			(net "P12V_SSD5_VIN_N")
		)
	)
	(footprint ""
		(layer "F.Cu")
		(at 351.17532 -64.102234 180)
		(property "Reference" "PR7091"
			(at 0 0 180)
			(layer "F.SilkS")
			(hide yes)
			(effects
				(font
					(size 1.27 1.27)
				)
			)
		)
		(property "Value" ""
			(at 0 0 180)
			(layer "F.Fab")
			(effects
				(font
					(size 1.27 1.27)
				)
			)
		)
		(duplicate_pad_numbers_are_jumpers no)
		(fp_line
			(start 0.7874 0.4064)
			(end -0.7874 0.4064)
			(stroke
				(width 0.1524)
				(type default)
			)
			(layer "F.SilkS")
		)
		(fp_line
			(start 0.7874 -0.4064)
			(end 0.7874 0.4064)
			(stroke
				(width 0.1524)
				(type default)
			)
			(layer "F.SilkS")
		)
		(fp_line
			(start -0.7874 0.4064)
			(end -0.7874 -0.4064)
			(stroke
				(width 0.1524)
				(type default)
			)
			(layer "F.SilkS")
		)
		(fp_line
			(start -0.7874 -0.4064)
			(end 0.7874 -0.4064)
			(stroke
				(width 0.1524)
				(type default)
			)
			(layer "F.SilkS")
		)
		(fp_line
			(start 0.67945 0.3048)
			(end 0.120396 0.3048)
			(stroke
				(width 0.1)
				(type default)
			)
			(layer "F.Fab")
		)
		(fp_line
			(start 0.67945 -0.3048)
			(end 0.67945 0.3048)
			(stroke
				(width 0.1)
				(type default)
			)
			(layer "F.Fab")
		)
		(fp_line
			(start 0.12065 -0.2794)
			(end 0.12065 -0.3048)
			(stroke
				(width 0.1)
				(type default)
			)
			(layer "F.Fab")
		)
		(fp_line
			(start 0.12065 -0.3048)
			(end 0.67945 -0.3048)
			(stroke
				(width 0.1)
				(type default)
			)
			(layer "F.Fab")
		)
		(fp_line
			(start 0.120396 0.3048)
			(end 0.120396 0.2794)
			(stroke
				(width 0.1)
				(type default)
			)
			(layer "F.Fab")
		)
		(fp_line
			(start 0.120396 0.2794)
			(end -0.12065 0.2794)
			(stroke
				(width 0.1)
				(type default)
			)
			(layer "F.Fab")
		)
		(fp_line
			(start -0.12065 0.3048)
			(end -0.67945 0.3048)
			(stroke
				(width 0.1)
				(type default)
			)
			(layer "F.Fab")
		)
		(fp_line
			(start -0.12065 0.2794)
			(end -0.12065 0.3048)
			(stroke
				(width 0.1)
				(type default)
			)
			(layer "F.Fab")
		)
		(fp_line
			(start -0.12065 -0.2794)
			(end 0.12065 -0.2794)
			(stroke
				(width 0.1)
				(type default)
			)
			(layer "F.Fab")
		)
		(fp_line
			(start -0.12065 -0.305054)
			(end -0.12065 -0.2794)
			(stroke
				(width 0.1)
				(type default)
			)
			(layer "F.Fab")
		)
		(fp_line
			(start -0.67945 0.3048)
			(end -0.67945 -0.305054)
			(stroke
				(width 0.1)
				(type default)
			)
			(layer "F.Fab")
		)
		(fp_line
			(start -0.67945 -0.305054)
			(end -0.12065 -0.305054)
			(stroke
				(width 0.1)
				(type default)
			)
			(layer "F.Fab")
		)
		(pad "1" smd circle
			(at -0.40005 0 180)
			(size 0 0)
			(layers "F.Cu" "F.Mask" "F.Paste")
			(net "P12V_SSD12_PG_G1")
		)
		(pad "2" smd circle
			(at 0.40005 0 180)
			(size 0 0)
			(layers "F.Cu" "F.Mask" "F.Paste")
			(net "GND")
		)
	)
	(footprint ""
		(layer "F.Cu")
		(at 258.574286 -252.356874 -90)
		(property "Reference" "R1358"
			(at 0 0 270)
			(layer "F.SilkS")
			(hide yes)
			(effects
				(font
					(size 1.27 1.27)
				)
			)
		)
		(property "Value" ""
			(at 0 0 270)
			(layer "F.Fab")
			(effects
				(font
					(size 1.27 1.27)
				)
			)
		)
		(duplicate_pad_numbers_are_jumpers no)
		(fp_line
			(start -0.7874 0.4064)
			(end -0.7874 -0.4064)
			(stroke
				(width 0.1524)
				(type default)
			)
			(layer "F.SilkS")
		)
		(fp_line
			(start 0.7874 0.4064)
			(end -0.7874 0.4064)
			(stroke
				(width 0.1524)
				(type default)
			)
			(layer "F.SilkS")
		)
		(fp_line
			(start -0.7874 -0.4064)
			(end 0.7874 -0.4064)
			(stroke
				(width 0.1524)
				(type default)
			)
			(layer "F.SilkS")
		)
		(fp_line
			(start 0.7874 -0.4064)
			(end 0.7874 0.4064)
			(stroke
				(width 0.1524)
				(type default)
			)
			(layer "F.SilkS")
		)
		(fp_line
			(start -0.67945 0.3048)
			(end -0.67945 -0.305054)
			(stroke
				(width 0.1)
				(type default)
			)
			(layer "F.Fab")
		)
		(fp_line
			(start -0.12065 0.3048)
			(end -0.67945 0.3048)
			(stroke
				(width 0.1)
				(type default)
			)
			(layer "F.Fab")
		)
		(fp_line
			(start 0.120396 0.3048)
			(end 0.120396 0.2794)
			(stroke
				(width 0.1)
				(type default)
			)
			(layer "F.Fab")
		)
		(fp_line
			(start 0.67945 0.3048)
			(end 0.120396 0.3048)
			(stroke
				(width 0.1)
				(type default)
			)
			(layer "F.Fab")
		)
		(fp_line
			(start -0.12065 0.2794)
			(end -0.12065 0.3048)
			(stroke
				(width 0.1)
				(type default)
			)
			(layer "F.Fab")
		)
		(fp_line
			(start 0.120396 0.2794)
			(end -0.12065 0.2794)
			(stroke
				(width 0.1)
				(type default)
			)
			(layer "F.Fab")
		)
		(fp_line
			(start -0.12065 -0.2794)
			(end 0.12065 -0.2794)
			(stroke
				(width 0.1)
				(type default)
			)
			(layer "F.Fab")
		)
		(fp_line
			(start 0.12065 -0.2794)
			(end 0.12065 -0.3048)
			(stroke
				(width 0.1)
				(type default)
			)
			(layer "F.Fab")
		)
		(fp_line
			(start 0.12065 -0.3048)
			(end 0.67945 -0.3048)
			(stroke
				(width 0.1)
				(type default)
			)
			(layer "F.Fab")
		)
		(fp_line
			(start 0.67945 -0.3048)
			(end 0.67945 0.3048)
			(stroke
				(width 0.1)
				(type default)
			)
			(layer "F.Fab")
		)
		(fp_line
			(start -0.67945 -0.305054)
			(end -0.12065 -0.305054)
			(stroke
				(width 0.1)
				(type default)
			)
			(layer "F.Fab")
		)
		(fp_line
			(start -0.12065 -0.305054)
			(end -0.12065 -0.2794)
			(stroke
				(width 0.1)
				(type default)
			)
			(layer "F.Fab")
		)
		(pad "1" smd circle
			(at -0.40005 0 270)
			(size 0 0)
			(layers "F.Cu" "F.Mask" "F.Paste")
			(net "GND")
		)
		(pad "2" smd circle
			(at 0.40005 0 270)
			(size 0 0)
			(layers "F.Cu" "F.Mask" "F.Paste")
			(net "PEX2_MODE_SEL2")
		)
	)
	(footprint ""
		(layer "F.Cu")
		(at 413.588708 -193.730118 180)
		(property "Reference" "R6437"
			(at 0 0 180)
			(layer "F.SilkS")
			(hide yes)
			(effects
				(font
					(size 1.27 1.27)
				)
			)
		)
		(property "Value" ""
			(at 0 0 180)
			(layer "F.Fab")
			(effects
				(font
					(size 1.27 1.27)
				)
			)
		)
		(duplicate_pad_numbers_are_jumpers no)
		(fp_line
			(start 0.7874 0.4064)
			(end -0.7874 0.4064)
			(stroke
				(width 0.1524)
				(type default)
			)
			(layer "F.SilkS")
		)
		(fp_line
			(start 0.7874 -0.4064)
			(end 0.7874 0.4064)
			(stroke
				(width 0.1524)
				(type default)
			)
			(layer "F.SilkS")
		)
		(fp_line
			(start -0.7874 0.4064)
			(end -0.7874 -0.4064)
			(stroke
				(width 0.1524)
				(type default)
			)
			(layer "F.SilkS")
		)
		(fp_line
			(start -0.7874 -0.4064)
			(end 0.7874 -0.4064)
			(stroke
				(width 0.1524)
				(type default)
			)
			(layer "F.SilkS")
		)
		(fp_line
			(start 0.67945 0.3048)
			(end 0.120396 0.3048)
			(stroke
				(width 0.1)
				(type default)
			)
			(layer "F.Fab")
		)
		(fp_line
			(start 0.67945 -0.3048)
			(end 0.67945 0.3048)
			(stroke
				(width 0.1)
				(type default)
			)
			(layer "F.Fab")
		)
		(fp_line
			(start 0.12065 -0.2794)
			(end 0.12065 -0.3048)
			(stroke
				(width 0.1)
				(type default)
			)
			(layer "F.Fab")
		)
		(fp_line
			(start 0.12065 -0.3048)
			(end 0.67945 -0.3048)
			(stroke
				(width 0.1)
				(type default)
			)
			(layer "F.Fab")
		)
		(fp_line
			(start 0.120396 0.3048)
			(end 0.120396 0.2794)
			(stroke
				(width 0.1)
				(type default)
			)
			(layer "F.Fab")
		)
		(fp_line
			(start 0.120396 0.2794)
			(end -0.12065 0.2794)
			(stroke
				(width 0.1)
				(type default)
			)
			(layer "F.Fab")
		)
		(fp_line
			(start -0.12065 0.3048)
			(end -0.67945 0.3048)
			(stroke
				(width 0.1)
				(type default)
			)
			(layer "F.Fab")
		)
		(fp_line
			(start -0.12065 0.2794)
			(end -0.12065 0.3048)
			(stroke
				(width 0.1)
				(type default)
			)
			(layer "F.Fab")
		)
		(fp_line
			(start -0.12065 -0.2794)
			(end 0.12065 -0.2794)
			(stroke
				(width 0.1)
				(type default)
			)
			(layer "F.Fab")
		)
		(fp_line
			(start -0.12065 -0.305054)
			(end -0.12065 -0.2794)
			(stroke
				(width 0.1)
				(type default)
			)
			(layer "F.Fab")
		)
		(fp_line
			(start -0.67945 0.3048)
			(end -0.67945 -0.305054)
			(stroke
				(width 0.1)
				(type default)
			)
			(layer "F.Fab")
		)
		(fp_line
			(start -0.67945 -0.305054)
			(end -0.12065 -0.305054)
			(stroke
				(width 0.1)
				(type default)
			)
			(layer "F.Fab")
		)
		(pad "1" smd circle
			(at -0.40005 0 180)
			(size 0 0)
			(layers "F.Cu" "F.Mask" "F.Paste")
			(net "FPGA_PEX2_MODE_SEL1_D_N")
		)
		(pad "2" smd circle
			(at 0.40005 0 180)
			(size 0 0)
			(layers "F.Cu" "F.Mask" "F.Paste")
			(net "P3V3_AUX")
		)
	)
	(footprint ""
		(layer "F.Cu")
		(at 56.18861 -386.725668)
		(property "Reference" "C4042"
			(at 0 0 0)
			(layer "F.SilkS")
			(hide yes)
			(effects
				(font
					(size 1.27 1.27)
				)
			)
		)
		(property "Value" ""
			(at 0 0 0)
			(layer "F.Fab")
			(effects
				(font
					(size 1.27 1.27)
				)
			)
		)
		(duplicate_pad_numbers_are_jumpers no)
		(fp_line
			(start -0.7874 -0.4064)
			(end 0.7874 -0.4064)
			(stroke
				(width 0.1524)
				(type default)
			)
			(layer "F.SilkS")
		)
		(fp_line
			(start -0.7874 0.4064)
			(end -0.7874 -0.4064)
			(stroke
				(width 0.1524)
				(type default)
			)
			(layer "F.SilkS")
		)
		(fp_line
			(start 0.7874 -0.4064)
			(end 0.7874 0.4064)
			(stroke
				(width 0.1524)
				(type default)
			)
			(layer "F.SilkS")
		)
		(fp_line
			(start 0.7874 0.4064)
			(end -0.7874 0.4064)
			(stroke
				(width 0.1524)
				(type default)
			)
			(layer "F.SilkS")
		)
		(fp_line
			(start -0.67945 -0.305054)
			(end -0.12065 -0.305054)
			(stroke
				(width 0.1)
				(type default)
			)
			(layer "F.Fab")
		)
		(fp_line
			(start -0.67945 0.3048)
			(end -0.67945 -0.305054)
			(stroke
				(width 0.1)
				(type default)
			)
			(layer "F.Fab")
		)
		(fp_line
			(start -0.12065 -0.305054)
			(end -0.12065 -0.2794)
			(stroke
				(width 0.1)
				(type default)
			)
			(layer "F.Fab")
		)
		(fp_line
			(start -0.12065 -0.2794)
			(end 0.12065 -0.2794)
			(stroke
				(width 0.1)
				(type default)
			)
			(layer "F.Fab")
		)
		(fp_line
			(start -0.12065 0.2794)
			(end -0.12065 0.3048)
			(stroke
				(width 0.1)
				(type default)
			)
			(layer "F.Fab")
		)
		(fp_line
			(start -0.12065 0.3048)
			(end -0.67945 0.3048)
			(stroke
				(width 0.1)
				(type default)
			)
			(layer "F.Fab")
		)
		(fp_line
			(start 0.120396 0.2794)
			(end -0.12065 0.2794)
			(stroke
				(width 0.1)
				(type default)
			)
			(layer "F.Fab")
		)
		(fp_line
			(start 0.120396 0.3048)
			(end 0.120396 0.2794)
			(stroke
				(width 0.1)
				(type default)
			)
			(layer "F.Fab")
		)
		(fp_line
			(start 0.12065 -0.3048)
			(end 0.67945 -0.3048)
			(stroke
				(width 0.1)
				(type default)
			)
			(layer "F.Fab")
		)
		(fp_line
			(start 0.12065 -0.2794)
			(end 0.12065 -0.3048)
			(stroke
				(width 0.1)
				(type default)
			)
			(layer "F.Fab")
		)
		(fp_line
			(start 0.67945 -0.3048)
			(end 0.67945 0.3048)
			(stroke
				(width 0.1)
				(type default)
			)
			(layer "F.Fab")
		)
		(fp_line
			(start 0.67945 0.3048)
			(end 0.120396 0.3048)
			(stroke
				(width 0.1)
				(type default)
			)
			(layer "F.Fab")
		)
		(pad "1" smd circle
			(at -0.40005 0)
			(size 0 0)
			(layers "F.Cu" "F.Mask" "F.Paste")
			(net "GND")
		)
		(pad "2" smd circle
			(at 0.40005 0)
			(size 0 0)
			(layers "F.Cu" "F.Mask" "F.Paste")
			(net "GPU_BASE_ID0")
		)
	)
	(footprint ""
		(layer "F.Cu")
		(at 163.075112 -356.244906 90)
		(property "Reference" "C401"
			(at 0 0 90)
			(layer "F.SilkS")
			(hide yes)
			(effects
				(font
					(size 1.27 1.27)
				)
			)
		)
		(property "Value" ""
			(at 0 0 90)
			(layer "F.Fab")
			(effects
				(font
					(size 1.27 1.27)
				)
			)
		)
		(duplicate_pad_numbers_are_jumpers no)
		(fp_line
			(start 0.299974 -0.150114)
			(end 0.299974 0.150114)
			(stroke
				(width 0.1)
				(type default)
			)
			(layer "F.Fab")
		)
		(fp_line
			(start -0.299974 -0.150114)
			(end 0.299974 -0.150114)
			(stroke
				(width 0.1)
				(type default)
			)
			(layer "F.Fab")
		)
		(fp_line
			(start 0.299974 0.150114)
			(end -0.299974 0.150114)
			(stroke
				(width 0.1)
				(type default)
			)
			(layer "F.Fab")
		)
		(fp_line
			(start -0.299974 0.150114)
			(end -0.299974 -0.150114)
			(stroke
				(width 0.1)
				(type default)
			)
			(layer "F.Fab")
		)
		(pad "1" smd rect
			(at -0.2667 0 90)
			(size 0.3048 0.381)
			(layers "F.Cu" "F.Mask" "F.Paste")
			(net "P5E_PEX1_STN7_TX_DN<113>")
		)
		(pad "2" smd rect
			(at 0.2667 0 90)
			(size 0.3048 0.381)
			(layers "F.Cu" "F.Mask" "F.Paste")
			(net "P5E_PEX1_STN7_TX_C_DN<113>")
		)
	)
	(footprint ""
		(layer "F.Cu")
		(at 422.327832 -35.876738)
		(property "Reference" "R6119"
			(at 0 0 0)
			(layer "F.SilkS")
			(hide yes)
			(effects
				(font
					(size 1.27 1.27)
				)
			)
		)
		(property "Value" ""
			(at 0 0 0)
			(layer "F.Fab")
			(effects
				(font
					(size 1.27 1.27)
				)
			)
		)
		(duplicate_pad_numbers_are_jumpers no)
		(fp_line
			(start -0.7874 -0.4064)
			(end 0.7874 -0.4064)
			(stroke
				(width 0.1524)
				(type default)
			)
			(layer "F.SilkS")
		)
		(fp_line
			(start -0.7874 0.4064)
			(end -0.7874 -0.4064)
			(stroke
				(width 0.1524)
				(type default)
			)
			(layer "F.SilkS")
		)
		(fp_line
			(start 0.7874 -0.4064)
			(end 0.7874 0.4064)
			(stroke
				(width 0.1524)
				(type default)
			)
			(layer "F.SilkS")
		)
		(fp_line
			(start 0.7874 0.4064)
			(end -0.7874 0.4064)
			(stroke
				(width 0.1524)
				(type default)
			)
			(layer "F.SilkS")
		)
		(fp_line
			(start -0.67945 -0.305054)
			(end -0.12065 -0.305054)
			(stroke
				(width 0.1)
				(type default)
			)
			(layer "F.Fab")
		)
		(fp_line
			(start -0.67945 0.3048)
			(end -0.67945 -0.305054)
			(stroke
				(width 0.1)
				(type default)
			)
			(layer "F.Fab")
		)
		(fp_line
			(start -0.12065 -0.305054)
			(end -0.12065 -0.2794)
			(stroke
				(width 0.1)
				(type default)
			)
			(layer "F.Fab")
		)
		(fp_line
			(start -0.12065 -0.2794)
			(end 0.12065 -0.2794)
			(stroke
				(width 0.1)
				(type default)
			)
			(layer "F.Fab")
		)
		(fp_line
			(start -0.12065 0.2794)
			(end -0.12065 0.3048)
			(stroke
				(width 0.1)
				(type default)
			)
			(layer "F.Fab")
		)
		(fp_line
			(start -0.12065 0.3048)
			(end -0.67945 0.3048)
			(stroke
				(width 0.1)
				(type default)
			)
			(layer "F.Fab")
		)
		(fp_line
			(start 0.120396 0.2794)
			(end -0.12065 0.2794)
			(stroke
				(width 0.1)
				(type default)
			)
			(layer "F.Fab")
		)
		(fp_line
			(start 0.120396 0.3048)
			(end 0.120396 0.2794)
			(stroke
				(width 0.1)
				(type default)
			)
			(layer "F.Fab")
		)
		(fp_line
			(start 0.12065 -0.3048)
			(end 0.67945 -0.3048)
			(stroke
				(width 0.1)
				(type default)
			)
			(layer "F.Fab")
		)
		(fp_line
			(start 0.12065 -0.2794)
			(end 0.12065 -0.3048)
			(stroke
				(width 0.1)
				(type default)
			)
			(layer "F.Fab")
		)
		(fp_line
			(start 0.67945 -0.3048)
			(end 0.67945 0.3048)
			(stroke
				(width 0.1)
				(type default)
			)
			(layer "F.Fab")
		)
		(fp_line
			(start 0.67945 0.3048)
			(end 0.120396 0.3048)
			(stroke
				(width 0.1)
				(type default)
			)
			(layer "F.Fab")
		)
		(pad "1" smd circle
			(at -0.40005 0)
			(size 0 0)
			(layers "F.Cu" "F.Mask" "F.Paste")
			(net "PWRGD_P3V3_SSD15_D")
		)
		(pad "2" smd circle
			(at 0.40005 0)
			(size 0 0)
			(layers "F.Cu" "F.Mask" "F.Paste")
			(net "PWRGD_P3V3_SSD15_R")
		)
	)
	(footprint ""
		(layer "F.Cu")
		(at 424.78198 -37.025072)
		(property "Reference" "R5705"
			(at 0 0 0)
			(layer "F.SilkS")
			(hide yes)
			(effects
				(font
					(size 1.27 1.27)
				)
			)
		)
		(property "Value" ""
			(at 0 0 0)
			(layer "F.Fab")
			(effects
				(font
					(size 1.27 1.27)
				)
			)
		)
		(duplicate_pad_numbers_are_jumpers no)
		(fp_line
			(start -0.7874 -0.4064)
			(end 0.7874 -0.4064)
			(stroke
				(width 0.1524)
				(type default)
			)
			(layer "F.SilkS")
		)
		(fp_line
			(start -0.7874 0.4064)
			(end -0.7874 -0.4064)
			(stroke
				(width 0.1524)
				(type default)
			)
			(layer "F.SilkS")
		)
		(fp_line
			(start 0.7874 -0.4064)
			(end 0.7874 0.4064)
			(stroke
				(width 0.1524)
				(type default)
			)
			(layer "F.SilkS")
		)
		(fp_line
			(start 0.7874 0.4064)
			(end -0.7874 0.4064)
			(stroke
				(width 0.1524)
				(type default)
			)
			(layer "F.SilkS")
		)
		(fp_line
			(start -0.67945 -0.305054)
			(end -0.12065 -0.305054)
			(stroke
				(width 0.1)
				(type default)
			)
			(layer "F.Fab")
		)
		(fp_line
			(start -0.67945 0.3048)
			(end -0.67945 -0.305054)
			(stroke
				(width 0.1)
				(type default)
			)
			(layer "F.Fab")
		)
		(fp_line
			(start -0.12065 -0.305054)
			(end -0.12065 -0.2794)
			(stroke
				(width 0.1)
				(type default)
			)
			(layer "F.Fab")
		)
		(fp_line
			(start -0.12065 -0.2794)
			(end 0.12065 -0.2794)
			(stroke
				(width 0.1)
				(type default)
			)
			(layer "F.Fab")
		)
		(fp_line
			(start -0.12065 0.2794)
			(end -0.12065 0.3048)
			(stroke
				(width 0.1)
				(type default)
			)
			(layer "F.Fab")
		)
		(fp_line
			(start -0.12065 0.3048)
			(end -0.67945 0.3048)
			(stroke
				(width 0.1)
				(type default)
			)
			(layer "F.Fab")
		)
		(fp_line
			(start 0.120396 0.2794)
			(end -0.12065 0.2794)
			(stroke
				(width 0.1)
				(type default)
			)
			(layer "F.Fab")
		)
		(fp_line
			(start 0.120396 0.3048)
			(end 0.120396 0.2794)
			(stroke
				(width 0.1)
				(type default)
			)
			(layer "F.Fab")
		)
		(fp_line
			(start 0.12065 -0.3048)
			(end 0.67945 -0.3048)
			(stroke
				(width 0.1)
				(type default)
			)
			(layer "F.Fab")
		)
		(fp_line
			(start 0.12065 -0.2794)
			(end 0.12065 -0.3048)
			(stroke
				(width 0.1)
				(type default)
			)
			(layer "F.Fab")
		)
		(fp_line
			(start 0.67945 -0.3048)
			(end 0.67945 0.3048)
			(stroke
				(width 0.1)
				(type default)
			)
			(layer "F.Fab")
		)
		(fp_line
			(start 0.67945 0.3048)
			(end 0.120396 0.3048)
			(stroke
				(width 0.1)
				(type default)
			)
			(layer "F.Fab")
		)
		(pad "1" smd circle
			(at -0.40005 0)
			(size 0 0)
			(layers "F.Cu" "F.Mask" "F.Paste")
			(net "RST_SMB_SSD_R_N")
		)
		(pad "2" smd circle
			(at 0.40005 0)
			(size 0 0)
			(layers "F.Cu" "F.Mask" "F.Paste")
			(net "RST_SMB_SSD15_N")
		)
	)
	(footprint ""
		(layer "F.Cu")
		(at 270.807942 -159.4104 180)
		(property "Reference" "R206"
			(at 0 0 180)
			(layer "F.SilkS")
			(hide yes)
			(effects
				(font
					(size 1.27 1.27)
				)
			)
		)
		(property "Value" ""
			(at 0 0 180)
			(layer "F.Fab")
			(effects
				(font
					(size 1.27 1.27)
				)
			)
		)
		(duplicate_pad_numbers_are_jumpers no)
		(fp_line
			(start 0.7874 0.4064)
			(end -0.7874 0.4064)
			(stroke
				(width 0.1524)
				(type default)
			)
			(layer "F.SilkS")
		)
		(fp_line
			(start 0.7874 -0.4064)
			(end 0.7874 0.4064)
			(stroke
				(width 0.1524)
				(type default)
			)
			(layer "F.SilkS")
		)
		(fp_line
			(start -0.7874 0.4064)
			(end -0.7874 -0.4064)
			(stroke
				(width 0.1524)
				(type default)
			)
			(layer "F.SilkS")
		)
		(fp_line
			(start -0.7874 -0.4064)
			(end 0.7874 -0.4064)
			(stroke
				(width 0.1524)
				(type default)
			)
			(layer "F.SilkS")
		)
		(fp_line
			(start 0.67945 0.3048)
			(end 0.120396 0.3048)
			(stroke
				(width 0.1)
				(type default)
			)
			(layer "F.Fab")
		)
		(fp_line
			(start 0.67945 -0.3048)
			(end 0.67945 0.3048)
			(stroke
				(width 0.1)
				(type default)
			)
			(layer "F.Fab")
		)
		(fp_line
			(start 0.12065 -0.2794)
			(end 0.12065 -0.3048)
			(stroke
				(width 0.1)
				(type default)
			)
			(layer "F.Fab")
		)
		(fp_line
			(start 0.12065 -0.3048)
			(end 0.67945 -0.3048)
			(stroke
				(width 0.1)
				(type default)
			)
			(layer "F.Fab")
		)
		(fp_line
			(start 0.120396 0.3048)
			(end 0.120396 0.2794)
			(stroke
				(width 0.1)
				(type default)
			)
			(layer "F.Fab")
		)
		(fp_line
			(start 0.120396 0.2794)
			(end -0.12065 0.2794)
			(stroke
				(width 0.1)
				(type default)
			)
			(layer "F.Fab")
		)
		(fp_line
			(start -0.12065 0.3048)
			(end -0.67945 0.3048)
			(stroke
				(width 0.1)
				(type default)
			)
			(layer "F.Fab")
		)
		(fp_line
			(start -0.12065 0.2794)
			(end -0.12065 0.3048)
			(stroke
				(width 0.1)
				(type default)
			)
			(layer "F.Fab")
		)
		(fp_line
			(start -0.12065 -0.2794)
			(end 0.12065 -0.2794)
			(stroke
				(width 0.1)
				(type default)
			)
			(layer "F.Fab")
		)
		(fp_line
			(start -0.12065 -0.305054)
			(end -0.12065 -0.2794)
			(stroke
				(width 0.1)
				(type default)
			)
			(layer "F.Fab")
		)
		(fp_line
			(start -0.67945 0.3048)
			(end -0.67945 -0.305054)
			(stroke
				(width 0.1)
				(type default)
			)
			(layer "F.Fab")
		)
		(fp_line
			(start -0.67945 -0.305054)
			(end -0.12065 -0.305054)
			(stroke
				(width 0.1)
				(type default)
			)
			(layer "F.Fab")
		)
		(pad "1" smd circle
			(at -0.40005 0 180)
			(size 0 0)
			(layers "F.Cu" "F.Mask" "F.Paste")
			(net "NIC4_MAIN_PWR_EN_R")
		)
		(pad "2" smd circle
			(at 0.40005 0 180)
			(size 0 0)
			(layers "F.Cu" "F.Mask" "F.Paste")
			(net "NIC4_MAIN_PWR_EN")
		)
	)
	(footprint ""
		(layer "F.Cu")
		(at 460.611982 -113.563654)
		(property "Reference" "PC835"
			(at 0 0 0)
			(layer "F.SilkS")
			(hide yes)
			(effects
				(font
					(size 1.27 1.27)
				)
			)
		)
		(property "Value" ""
			(at 0 0 0)
			(layer "F.Fab")
			(effects
				(font
					(size 1.27 1.27)
				)
			)
		)
		(duplicate_pad_numbers_are_jumpers no)
		(fp_line
			(start -0.7874 -0.4064)
			(end 0.7874 -0.4064)
			(stroke
				(width 0.1524)
				(type default)
			)
			(layer "F.SilkS")
		)
		(fp_line
			(start -0.7874 0.4064)
			(end -0.7874 -0.4064)
			(stroke
				(width 0.1524)
				(type default)
			)
			(layer "F.SilkS")
		)
		(fp_line
			(start 0.7874 -0.4064)
			(end 0.7874 0.4064)
			(stroke
				(width 0.1524)
				(type default)
			)
			(layer "F.SilkS")
		)
		(fp_line
			(start 0.7874 0.4064)
			(end -0.7874 0.4064)
			(stroke
				(width 0.1524)
				(type default)
			)
			(layer "F.SilkS")
		)
		(fp_line
			(start -0.67945 -0.305054)
			(end -0.12065 -0.305054)
			(stroke
				(width 0.1)
				(type default)
			)
			(layer "F.Fab")
		)
		(fp_line
			(start -0.67945 0.3048)
			(end -0.67945 -0.305054)
			(stroke
				(width 0.1)
				(type default)
			)
			(layer "F.Fab")
		)
		(fp_line
			(start -0.12065 -0.305054)
			(end -0.12065 -0.2794)
			(stroke
				(width 0.1)
				(type default)
			)
			(layer "F.Fab")
		)
		(fp_line
			(start -0.12065 -0.2794)
			(end 0.12065 -0.2794)
			(stroke
				(width 0.1)
				(type default)
			)
			(layer "F.Fab")
		)
		(fp_line
			(start -0.12065 0.2794)
			(end -0.12065 0.3048)
			(stroke
				(width 0.1)
				(type default)
			)
			(layer "F.Fab")
		)
		(fp_line
			(start -0.12065 0.3048)
			(end -0.67945 0.3048)
			(stroke
				(width 0.1)
				(type default)
			)
			(layer "F.Fab")
		)
		(fp_line
			(start 0.120396 0.2794)
			(end -0.12065 0.2794)
			(stroke
				(width 0.1)
				(type default)
			)
			(layer "F.Fab")
		)
		(fp_line
			(start 0.120396 0.3048)
			(end 0.120396 0.2794)
			(stroke
				(width 0.1)
				(type default)
			)
			(layer "F.Fab")
		)
		(fp_line
			(start 0.12065 -0.3048)
			(end 0.67945 -0.3048)
			(stroke
				(width 0.1)
				(type default)
			)
			(layer "F.Fab")
		)
		(fp_line
			(start 0.12065 -0.2794)
			(end 0.12065 -0.3048)
			(stroke
				(width 0.1)
				(type default)
			)
			(layer "F.Fab")
		)
		(fp_line
			(start 0.67945 -0.3048)
			(end 0.67945 0.3048)
			(stroke
				(width 0.1)
				(type default)
			)
			(layer "F.Fab")
		)
		(fp_line
			(start 0.67945 0.3048)
			(end 0.120396 0.3048)
			(stroke
				(width 0.1)
				(type default)
			)
			(layer "F.Fab")
		)
		(pad "1" smd circle
			(at -0.40005 0)
			(size 0 0)
			(layers "F.Cu" "F.Mask" "F.Paste")
			(net "P12V_NIC7_CO_SS")
		)
		(pad "2" smd circle
			(at 0.40005 0)
			(size 0 0)
			(layers "F.Cu" "F.Mask" "F.Paste")
			(net "GND")
		)
	)
	(footprint ""
		(layer "F.Cu")
		(at 248.094754 -276.519386)
		(property "Reference" "R796"
			(at 0 0 0)
			(layer "F.SilkS")
			(hide yes)
			(effects
				(font
					(size 1.27 1.27)
				)
			)
		)
		(property "Value" ""
			(at 0 0 0)
			(layer "F.Fab")
			(effects
				(font
					(size 1.27 1.27)
				)
			)
		)
		(duplicate_pad_numbers_are_jumpers no)
		(fp_line
			(start -0.7874 -0.4064)
			(end 0.7874 -0.4064)
			(stroke
				(width 0.1524)
				(type default)
			)
			(layer "F.SilkS")
		)
		(fp_line
			(start -0.7874 0.4064)
			(end -0.7874 -0.4064)
			(stroke
				(width 0.1524)
				(type default)
			)
			(layer "F.SilkS")
		)
		(fp_line
			(start 0.7874 -0.4064)
			(end 0.7874 0.4064)
			(stroke
				(width 0.1524)
				(type default)
			)
			(layer "F.SilkS")
		)
		(fp_line
			(start 0.7874 0.4064)
			(end -0.7874 0.4064)
			(stroke
				(width 0.1524)
				(type default)
			)
			(layer "F.SilkS")
		)
		(fp_line
			(start -0.67945 -0.305054)
			(end -0.12065 -0.305054)
			(stroke
				(width 0.1)
				(type default)
			)
			(layer "F.Fab")
		)
		(fp_line
			(start -0.67945 0.3048)
			(end -0.67945 -0.305054)
			(stroke
				(width 0.1)
				(type default)
			)
			(layer "F.Fab")
		)
		(fp_line
			(start -0.12065 -0.305054)
			(end -0.12065 -0.2794)
			(stroke
				(width 0.1)
				(type default)
			)
			(layer "F.Fab")
		)
		(fp_line
			(start -0.12065 -0.2794)
			(end 0.12065 -0.2794)
			(stroke
				(width 0.1)
				(type default)
			)
			(layer "F.Fab")
		)
		(fp_line
			(start -0.12065 0.2794)
			(end -0.12065 0.3048)
			(stroke
				(width 0.1)
				(type default)
			)
			(layer "F.Fab")
		)
		(fp_line
			(start -0.12065 0.3048)
			(end -0.67945 0.3048)
			(stroke
				(width 0.1)
				(type default)
			)
			(layer "F.Fab")
		)
		(fp_line
			(start 0.120396 0.2794)
			(end -0.12065 0.2794)
			(stroke
				(width 0.1)
				(type default)
			)
			(layer "F.Fab")
		)
		(fp_line
			(start 0.120396 0.3048)
			(end 0.120396 0.2794)
			(stroke
				(width 0.1)
				(type default)
			)
			(layer "F.Fab")
		)
		(fp_line
			(start 0.12065 -0.3048)
			(end 0.67945 -0.3048)
			(stroke
				(width 0.1)
				(type default)
			)
			(layer "F.Fab")
		)
		(fp_line
			(start 0.12065 -0.2794)
			(end 0.12065 -0.3048)
			(stroke
				(width 0.1)
				(type default)
			)
			(layer "F.Fab")
		)
		(fp_line
			(start 0.67945 -0.3048)
			(end 0.67945 0.3048)
			(stroke
				(width 0.1)
				(type default)
			)
			(layer "F.Fab")
		)
		(fp_line
			(start 0.67945 0.3048)
			(end 0.120396 0.3048)
			(stroke
				(width 0.1)
				(type default)
			)
			(layer "F.Fab")
		)
		(pad "1" smd circle
			(at -0.40005 0)
			(size 0 0)
			(layers "F.Cu" "F.Mask" "F.Paste")
			(net "PEX2_P1V25_ADC_A0")
		)
		(pad "2" smd circle
			(at 0.40005 0)
			(size 0 0)
			(layers "F.Cu" "F.Mask" "F.Paste")
			(net "GND")
		)
	)
	(footprint ""
		(layer "F.Cu")
		(at 205.31455 -311.227978 135)
		(property "Reference" "R1307"
			(at 0 0 135)
			(layer "F.SilkS")
			(hide yes)
			(effects
				(font
					(size 1.27 1.27)
				)
			)
		)
		(property "Value" ""
			(at 0 0 135)
			(layer "F.Fab")
			(effects
				(font
					(size 1.27 1.27)
				)
			)
		)
		(duplicate_pad_numbers_are_jumpers no)
		(fp_line
			(start 0.787389 -0.406267)
			(end 0.787389 0.406267)
			(stroke
				(width 0.1524)
				(type default)
			)
			(layer "F.SilkS")
		)
		(fp_line
			(start 0.787389 0.406267)
			(end -0.787389 0.406267)
			(stroke
				(width 0.1524)
				(type default)
			)
			(layer "F.SilkS")
		)
		(fp_line
			(start -0.787389 -0.406267)
			(end 0.787389 -0.406267)
			(stroke
				(width 0.1524)
				(type default)
			)
			(layer "F.SilkS")
		)
		(fp_line
			(start -0.787389 0.406267)
			(end -0.787389 -0.406267)
			(stroke
				(width 0.1524)
				(type default)
			)
			(layer "F.SilkS")
		)
		(fp_line
			(start 0.679446 -0.30479)
			(end 0.679446 0.30479)
			(stroke
				(width 0.1)
				(type default)
			)
			(layer "F.Fab")
		)
		(fp_line
			(start 0.120515 -0.30479)
			(end 0.679446 -0.30479)
			(stroke
				(width 0.1)
				(type default)
			)
			(layer "F.Fab")
		)
		(fp_line
			(start 0.120695 -0.279466)
			(end 0.120515 -0.30479)
			(stroke
				(width 0.1)
				(type default)
			)
			(layer "F.Fab")
		)
		(fp_line
			(start 0.679446 0.30479)
			(end 0.120515 0.30479)
			(stroke
				(width 0.1)
				(type default)
			)
			(layer "F.Fab")
		)
		(fp_line
			(start -0.120695 -0.304969)
			(end -0.120695 -0.279466)
			(stroke
				(width 0.1)
				(type default)
			)
			(layer "F.Fab")
		)
		(fp_line
			(start -0.120695 -0.279466)
			(end 0.120695 -0.279466)
			(stroke
				(width 0.1)
				(type default)
			)
			(layer "F.Fab")
		)
		(fp_line
			(start 0.120335 0.279466)
			(end -0.120695 0.279466)
			(stroke
				(width 0.1)
				(type default)
			)
			(layer "F.Fab")
		)
		(fp_line
			(start 0.120515 0.30479)
			(end 0.120335 0.279466)
			(stroke
				(width 0.1)
				(type default)
			)
			(layer "F.Fab")
		)
		(fp_line
			(start -0.679446 -0.305149)
			(end -0.120695 -0.304969)
			(stroke
				(width 0.1)
				(type default)
			)
			(layer "F.Fab")
		)
		(fp_line
			(start -0.120695 0.279466)
			(end -0.120515 0.30479)
			(stroke
				(width 0.1)
				(type default)
			)
			(layer "F.Fab")
		)
		(fp_line
			(start -0.120515 0.30479)
			(end -0.679446 0.30479)
			(stroke
				(width 0.1)
				(type default)
			)
			(layer "F.Fab")
		)
		(fp_line
			(start -0.679446 0.30479)
			(end -0.679446 -0.305149)
			(stroke
				(width 0.1)
				(type default)
			)
			(layer "F.Fab")
		)
		(pad "1" smd circle
			(at -0.40005 0 135)
			(size 0 0)
			(layers "F.Cu" "F.Mask" "F.Paste")
			(net "PEX1_SPARE0")
		)
		(pad "2" smd circle
			(at 0.40005 0 135)
			(size 0 0)
			(layers "F.Cu" "F.Mask" "F.Paste")
			(net "P1V8_PEX")
		)
	)
	(footprint ""
		(layer "F.Cu")
		(at 145.924016 -190.978536 90)
		(property "Reference" "R6674"
			(at 0 0 90)
			(layer "F.SilkS")
			(hide yes)
			(effects
				(font
					(size 1.27 1.27)
				)
			)
		)
		(property "Value" ""
			(at 0 0 90)
			(layer "F.Fab")
			(effects
				(font
					(size 1.27 1.27)
				)
			)
		)
		(duplicate_pad_numbers_are_jumpers no)
		(fp_line
			(start 0.7874 -0.4064)
			(end 0.7874 0.4064)
			(stroke
				(width 0.1524)
				(type default)
			)
			(layer "F.SilkS")
		)
		(fp_line
			(start -0.7874 -0.4064)
			(end 0.7874 -0.4064)
			(stroke
				(width 0.1524)
				(type default)
			)
			(layer "F.SilkS")
		)
		(fp_line
			(start 0.7874 0.4064)
			(end -0.7874 0.4064)
			(stroke
				(width 0.1524)
				(type default)
			)
			(layer "F.SilkS")
		)
		(fp_line
			(start -0.7874 0.4064)
			(end -0.7874 -0.4064)
			(stroke
				(width 0.1524)
				(type default)
			)
			(layer "F.SilkS")
		)
		(fp_line
			(start -0.12065 -0.305054)
			(end -0.12065 -0.2794)
			(stroke
				(width 0.1)
				(type default)
			)
			(layer "F.Fab")
		)
		(fp_line
			(start -0.67945 -0.305054)
			(end -0.12065 -0.305054)
			(stroke
				(width 0.1)
				(type default)
			)
			(layer "F.Fab")
		)
		(fp_line
			(start 0.67945 -0.3048)
			(end 0.67945 0.3048)
			(stroke
				(width 0.1)
				(type default)
			)
			(layer "F.Fab")
		)
		(fp_line
			(start 0.12065 -0.3048)
			(end 0.67945 -0.3048)
			(stroke
				(width 0.1)
				(type default)
			)
			(layer "F.Fab")
		)
		(fp_line
			(start 0.12065 -0.2794)
			(end 0.12065 -0.3048)
			(stroke
				(width 0.1)
				(type default)
			)
			(layer "F.Fab")
		)
		(fp_line
			(start -0.12065 -0.2794)
			(end 0.12065 -0.2794)
			(stroke
				(width 0.1)
				(type default)
			)
			(layer "F.Fab")
		)
		(fp_line
			(start 0.120396 0.2794)
			(end -0.12065 0.2794)
			(stroke
				(width 0.1)
				(type default)
			)
			(layer "F.Fab")
		)
		(fp_line
			(start -0.12065 0.2794)
			(end -0.12065 0.3048)
			(stroke
				(width 0.1)
				(type default)
			)
			(layer "F.Fab")
		)
		(fp_line
			(start 0.67945 0.3048)
			(end 0.120396 0.3048)
			(stroke
				(width 0.1)
				(type default)
			)
			(layer "F.Fab")
		)
		(fp_line
			(start 0.120396 0.3048)
			(end 0.120396 0.2794)
			(stroke
				(width 0.1)
				(type default)
			)
			(layer "F.Fab")
		)
		(fp_line
			(start -0.12065 0.3048)
			(end -0.67945 0.3048)
			(stroke
				(width 0.1)
				(type default)
			)
			(layer "F.Fab")
		)
		(fp_line
			(start -0.67945 0.3048)
			(end -0.67945 -0.305054)
			(stroke
				(width 0.1)
				(type default)
			)
			(layer "F.Fab")
		)
		(pad "1" smd circle
			(at -0.40005 0 90)
			(size 0 0)
			(layers "F.Cu" "F.Mask" "F.Paste")
			(net "NIC5_CLK_EN_BUF_R_N")
		)
		(pad "2" smd circle
			(at 0.40005 0 90)
			(size 0 0)
			(layers "F.Cu" "F.Mask" "F.Paste")
			(net "P3V3")
		)
	)
	(footprint ""
		(layer "F.Cu")
		(at 238.124746 -117.714268)
		(property "Reference" "PC633"
			(at 0 0 0)
			(layer "F.SilkS")
			(hide yes)
			(effects
				(font
					(size 1.27 1.27)
				)
			)
		)
		(property "Value" ""
			(at 0 0 0)
			(layer "F.Fab")
			(effects
				(font
					(size 1.27 1.27)
				)
			)
		)
		(duplicate_pad_numbers_are_jumpers no)
		(fp_line
			(start -0.7874 -0.4064)
			(end 0.7874 -0.4064)
			(stroke
				(width 0.1524)
				(type default)
			)
			(layer "F.SilkS")
		)
		(fp_line
			(start -0.7874 0.4064)
			(end -0.7874 -0.4064)
			(stroke
				(width 0.1524)
				(type default)
			)
			(layer "F.SilkS")
		)
		(fp_line
			(start 0.7874 -0.4064)
			(end 0.7874 0.4064)
			(stroke
				(width 0.1524)
				(type default)
			)
			(layer "F.SilkS")
		)
		(fp_line
			(start 0.7874 0.4064)
			(end -0.7874 0.4064)
			(stroke
				(width 0.1524)
				(type default)
			)
			(layer "F.SilkS")
		)
		(fp_line
			(start -0.67945 -0.305054)
			(end -0.12065 -0.305054)
			(stroke
				(width 0.1)
				(type default)
			)
			(layer "F.Fab")
		)
		(fp_line
			(start -0.67945 0.3048)
			(end -0.67945 -0.305054)
			(stroke
				(width 0.1)
				(type default)
			)
			(layer "F.Fab")
		)
		(fp_line
			(start -0.12065 -0.305054)
			(end -0.12065 -0.2794)
			(stroke
				(width 0.1)
				(type default)
			)
			(layer "F.Fab")
		)
		(fp_line
			(start -0.12065 -0.2794)
			(end 0.12065 -0.2794)
			(stroke
				(width 0.1)
				(type default)
			)
			(layer "F.Fab")
		)
		(fp_line
			(start -0.12065 0.2794)
			(end -0.12065 0.3048)
			(stroke
				(width 0.1)
				(type default)
			)
			(layer "F.Fab")
		)
		(fp_line
			(start -0.12065 0.3048)
			(end -0.67945 0.3048)
			(stroke
				(width 0.1)
				(type default)
			)
			(layer "F.Fab")
		)
		(fp_line
			(start 0.120396 0.2794)
			(end -0.12065 0.2794)
			(stroke
				(width 0.1)
				(type default)
			)
			(layer "F.Fab")
		)
		(fp_line
			(start 0.120396 0.3048)
			(end 0.120396 0.2794)
			(stroke
				(width 0.1)
				(type default)
			)
			(layer "F.Fab")
		)
		(fp_line
			(start 0.12065 -0.3048)
			(end 0.67945 -0.3048)
			(stroke
				(width 0.1)
				(type default)
			)
			(layer "F.Fab")
		)
		(fp_line
			(start 0.12065 -0.2794)
			(end 0.12065 -0.3048)
			(stroke
				(width 0.1)
				(type default)
			)
			(layer "F.Fab")
		)
		(fp_line
			(start 0.67945 -0.3048)
			(end 0.67945 0.3048)
			(stroke
				(width 0.1)
				(type default)
			)
			(layer "F.Fab")
		)
		(fp_line
			(start 0.67945 0.3048)
			(end 0.120396 0.3048)
			(stroke
				(width 0.1)
				(type default)
			)
			(layer "F.Fab")
		)
		(pad "1" smd circle
			(at -0.40005 0)
			(size 0 0)
			(layers "F.Cu" "F.Mask" "F.Paste")
			(net "P12V_NIC3_CO_SS")
		)
		(pad "2" smd circle
			(at 0.40005 0)
			(size 0 0)
			(layers "F.Cu" "F.Mask" "F.Paste")
			(net "GND")
		)
	)
	(footprint ""
		(layer "F.Cu")
		(at 448.516502 -100.178108 90)
		(property "Reference" "PC330"
			(at 0 0 90)
			(layer "F.SilkS")
			(hide yes)
			(effects
				(font
					(size 1.27 1.27)
				)
			)
		)
		(property "Value" ""
			(at 0 0 90)
			(layer "F.Fab")
			(effects
				(font
					(size 1.27 1.27)
				)
			)
		)
		(duplicate_pad_numbers_are_jumpers no)
		(fp_line
			(start 0.7874 -0.4064)
			(end 0.7874 0.4064)
			(stroke
				(width 0.1524)
				(type default)
			)
			(layer "F.SilkS")
		)
		(fp_line
			(start -0.7874 -0.4064)
			(end 0.7874 -0.4064)
			(stroke
				(width 0.1524)
				(type default)
			)
			(layer "F.SilkS")
		)
		(fp_line
			(start 0.7874 0.4064)
			(end -0.7874 0.4064)
			(stroke
				(width 0.1524)
				(type default)
			)
			(layer "F.SilkS")
		)
		(fp_line
			(start -0.7874 0.4064)
			(end -0.7874 -0.4064)
			(stroke
				(width 0.1524)
				(type default)
			)
			(layer "F.SilkS")
		)
		(fp_line
			(start -0.12065 -0.305054)
			(end -0.12065 -0.2794)
			(stroke
				(width 0.1)
				(type default)
			)
			(layer "F.Fab")
		)
		(fp_line
			(start -0.67945 -0.305054)
			(end -0.12065 -0.305054)
			(stroke
				(width 0.1)
				(type default)
			)
			(layer "F.Fab")
		)
		(fp_line
			(start 0.67945 -0.3048)
			(end 0.67945 0.3048)
			(stroke
				(width 0.1)
				(type default)
			)
			(layer "F.Fab")
		)
		(fp_line
			(start 0.12065 -0.3048)
			(end 0.67945 -0.3048)
			(stroke
				(width 0.1)
				(type default)
			)
			(layer "F.Fab")
		)
		(fp_line
			(start 0.12065 -0.2794)
			(end 0.12065 -0.3048)
			(stroke
				(width 0.1)
				(type default)
			)
			(layer "F.Fab")
		)
		(fp_line
			(start -0.12065 -0.2794)
			(end 0.12065 -0.2794)
			(stroke
				(width 0.1)
				(type default)
			)
			(layer "F.Fab")
		)
		(fp_line
			(start 0.120396 0.2794)
			(end -0.12065 0.2794)
			(stroke
				(width 0.1)
				(type default)
			)
			(layer "F.Fab")
		)
		(fp_line
			(start -0.12065 0.2794)
			(end -0.12065 0.3048)
			(stroke
				(width 0.1)
				(type default)
			)
			(layer "F.Fab")
		)
		(fp_line
			(start 0.67945 0.3048)
			(end 0.120396 0.3048)
			(stroke
				(width 0.1)
				(type default)
			)
			(layer "F.Fab")
		)
		(fp_line
			(start 0.120396 0.3048)
			(end 0.120396 0.2794)
			(stroke
				(width 0.1)
				(type default)
			)
			(layer "F.Fab")
		)
		(fp_line
			(start -0.12065 0.3048)
			(end -0.67945 0.3048)
			(stroke
				(width 0.1)
				(type default)
			)
			(layer "F.Fab")
		)
		(fp_line
			(start -0.67945 0.3048)
			(end -0.67945 -0.305054)
			(stroke
				(width 0.1)
				(type default)
			)
			(layer "F.Fab")
		)
		(pad "1" smd circle
			(at -0.40005 0 90)
			(size 0 0)
			(layers "F.Cu" "F.Mask" "F.Paste")
			(net "P12V_AUX")
		)
		(pad "2" smd circle
			(at 0.40005 0 90)
			(size 0 0)
			(layers "F.Cu" "F.Mask" "F.Paste")
			(net "GND")
		)
	)
	(footprint ""
		(layer "F.Cu")
		(at 331.192378 -241.848894 -90)
		(property "Reference" "U143"
			(at 0.142494 1.753108 90)
			(unlocked yes)
			(layer "F.SilkS")
			(effects
				(font
					(size 0.7874 0.5842)
					(thickness 0.1524)
				)
			)
		)
		(property "Value" ""
			(at 0 0 270)
			(layer "F.Fab")
			(effects
				(font
					(size 1.27 1.27)
				)
			)
		)
		(duplicate_pad_numbers_are_jumpers no)
		(fp_line
			(start -1.7272 1.1176)
			(end -1.7272 -1.1176)
			(stroke
				(width 0.1524)
				(type default)
			)
			(layer "F.SilkS")
		)
		(fp_line
			(start 1.7272 1.1176)
			(end -1.7272 1.1176)
			(stroke
				(width 0.1524)
				(type default)
			)
			(layer "F.SilkS")
		)
		(fp_line
			(start 0 -0.7366)
			(end -0.254 -1.1176)
			(stroke
				(width 0.1524)
				(type default)
			)
			(layer "F.SilkS")
		)
		(fp_line
			(start -0.254 -1.1176)
			(end -1.7272 -1.1176)
			(stroke
				(width 0.1524)
				(type default)
			)
			(layer "F.SilkS")
		)
		(fp_line
			(start 0.254 -1.1176)
			(end 0 -0.7366)
			(stroke
				(width 0.1524)
				(type default)
			)
			(layer "F.SilkS")
		)
		(fp_line
			(start 1.7272 -1.1176)
			(end 1.7272 1.1176)
			(stroke
				(width 0.1524)
				(type default)
			)
			(layer "F.SilkS")
		)
		(fp_line
			(start 1.7272 -1.1176)
			(end 0.254 -1.1176)
			(stroke
				(width 0.1524)
				(type default)
			)
			(layer "F.SilkS")
		)
		(fp_poly
			(pts
				(xy -1.9558 -0.649986) (xy -2.7178 -0.268986) (xy -2.7178 -1.030986)
			)
			(stroke
				(width 0)
				(type default)
			)
			(fill yes)
			(layer "F.SilkS")
		)
		(fp_line
			(start -1.5748 1.1176)
			(end 1.5748 1.1176)
			(stroke
				(width 0.1)
				(type default)
			)
			(layer "F.Fab")
		)
		(fp_line
			(start 1.5748 1.1176)
			(end 1.5748 -1.1176)
			(stroke
				(width 0.1)
				(type default)
			)
			(layer "F.Fab")
		)
		(fp_line
			(start -1.5748 -1.1176)
			(end -1.5748 1.1176)
			(stroke
				(width 0.1)
				(type default)
			)
			(layer "F.Fab")
		)
		(fp_line
			(start 1.5748 -1.1176)
			(end -1.5748 -1.1176)
			(stroke
				(width 0.1)
				(type default)
			)
			(layer "F.Fab")
		)
		(fp_poly
			(pts
				(xy -1.9558 -0.649986) (xy -2.7178 -0.268986) (xy -2.7178 -1.030986)
			)
			(stroke
				(width 0)
				(type default)
			)
			(fill yes)
			(layer "F.Fab")
		)
		(pad "1" smd rect
			(at -0.999998 -0.649986 180)
			(size 0.3556 1.1176)
			(layers "F.Cu" "F.Mask" "F.Paste")
			(net "RST_MB_PERST_0_N")
		)
		(pad "2" smd rect
			(at -0.999998 0 180)
			(size 0.3556 1.1176)
			(layers "F.Cu" "F.Mask" "F.Paste")
			(net "GND")
		)
		(pad "3" smd rect
			(at -0.999998 0.649986 180)
			(size 0.3556 1.1176)
			(layers "F.Cu" "F.Mask" "F.Paste")
			(net "RST_MB_PERST_1_N")
		)
		(pad "4" smd rect
			(at 0.999998 0.649986 180)
			(size 0.3556 1.1176)
			(layers "F.Cu" "F.Mask" "F.Paste")
			(net "RST_MB_PERST_1_ISO_N")
		)
		(pad "5" smd rect
			(at 0.999998 0 180)
			(size 0.3556 1.1176)
			(layers "F.Cu" "F.Mask" "F.Paste")
			(net "P3V3_AUX")
		)
		(pad "6" smd rect
			(at 0.999998 -0.649986 180)
			(size 0.3556 1.1176)
			(layers "F.Cu" "F.Mask" "F.Paste")
			(net "RST_MB_PERST_0_ISO_N")
		)
	)
	(footprint ""
		(layer "F.Cu")
		(at 336.042 -164.973)
		(property "Reference" "R4733"
			(at 0 0 0)
			(layer "F.SilkS")
			(hide yes)
			(effects
				(font
					(size 1.27 1.27)
				)
			)
		)
		(property "Value" ""
			(at 0 0 0)
			(layer "F.Fab")
			(effects
				(font
					(size 1.27 1.27)
				)
			)
		)
		(duplicate_pad_numbers_are_jumpers no)
		(fp_line
			(start -0.7874 -0.4064)
			(end 0.7874 -0.4064)
			(stroke
				(width 0.1524)
				(type default)
			)
			(layer "F.SilkS")
		)
		(fp_line
			(start -0.7874 0.4064)
			(end -0.7874 -0.4064)
			(stroke
				(width 0.1524)
				(type default)
			)
			(layer "F.SilkS")
		)
		(fp_line
			(start 0.7874 -0.4064)
			(end 0.7874 0.4064)
			(stroke
				(width 0.1524)
				(type default)
			)
			(layer "F.SilkS")
		)
		(fp_line
			(start 0.7874 0.4064)
			(end -0.7874 0.4064)
			(stroke
				(width 0.1524)
				(type default)
			)
			(layer "F.SilkS")
		)
		(fp_line
			(start -0.67945 -0.305054)
			(end -0.12065 -0.305054)
			(stroke
				(width 0.1)
				(type default)
			)
			(layer "F.Fab")
		)
		(fp_line
			(start -0.67945 0.3048)
			(end -0.67945 -0.305054)
			(stroke
				(width 0.1)
				(type default)
			)
			(layer "F.Fab")
		)
		(fp_line
			(start -0.12065 -0.305054)
			(end -0.12065 -0.2794)
			(stroke
				(width 0.1)
				(type default)
			)
			(layer "F.Fab")
		)
		(fp_line
			(start -0.12065 -0.2794)
			(end 0.12065 -0.2794)
			(stroke
				(width 0.1)
				(type default)
			)
			(layer "F.Fab")
		)
		(fp_line
			(start -0.12065 0.2794)
			(end -0.12065 0.3048)
			(stroke
				(width 0.1)
				(type default)
			)
			(layer "F.Fab")
		)
		(fp_line
			(start -0.12065 0.3048)
			(end -0.67945 0.3048)
			(stroke
				(width 0.1)
				(type default)
			)
			(layer "F.Fab")
		)
		(fp_line
			(start 0.120396 0.2794)
			(end -0.12065 0.2794)
			(stroke
				(width 0.1)
				(type default)
			)
			(layer "F.Fab")
		)
		(fp_line
			(start 0.120396 0.3048)
			(end 0.120396 0.2794)
			(stroke
				(width 0.1)
				(type default)
			)
			(layer "F.Fab")
		)
		(fp_line
			(start 0.12065 -0.3048)
			(end 0.67945 -0.3048)
			(stroke
				(width 0.1)
				(type default)
			)
			(layer "F.Fab")
		)
		(fp_line
			(start 0.12065 -0.2794)
			(end 0.12065 -0.3048)
			(stroke
				(width 0.1)
				(type default)
			)
			(layer "F.Fab")
		)
		(fp_line
			(start 0.67945 -0.3048)
			(end 0.67945 0.3048)
			(stroke
				(width 0.1)
				(type default)
			)
			(layer "F.Fab")
		)
		(fp_line
			(start 0.67945 0.3048)
			(end 0.120396 0.3048)
			(stroke
				(width 0.1)
				(type default)
			)
			(layer "F.Fab")
		)
		(pad "1" smd circle
			(at -0.40005 0)
			(size 0 0)
			(layers "F.Cu" "F.Mask" "F.Paste")
			(net "P3V3_AUX")
		)
		(pad "2" smd circle
			(at 0.40005 0)
			(size 0 0)
			(layers "F.Cu" "F.Mask" "F.Paste")
			(net "RST_PEX_SSD11_PERST_R_N")
		)
	)
	(footprint ""
		(layer "F.Cu")
		(at 394.97508 -56.977534 180)
		(property "Reference" "PC424"
			(at 0 0 180)
			(layer "F.SilkS")
			(hide yes)
			(effects
				(font
					(size 1.27 1.27)
				)
			)
		)
		(property "Value" ""
			(at 0 0 180)
			(layer "F.Fab")
			(effects
				(font
					(size 1.27 1.27)
				)
			)
		)
		(duplicate_pad_numbers_are_jumpers no)
		(fp_line
			(start 0.7874 0.4064)
			(end -0.7874 0.4064)
			(stroke
				(width 0.1524)
				(type default)
			)
			(layer "F.SilkS")
		)
		(fp_line
			(start 0.7874 -0.4064)
			(end 0.7874 0.4064)
			(stroke
				(width 0.1524)
				(type default)
			)
			(layer "F.SilkS")
		)
		(fp_line
			(start -0.7874 0.4064)
			(end -0.7874 -0.4064)
			(stroke
				(width 0.1524)
				(type default)
			)
			(layer "F.SilkS")
		)
		(fp_line
			(start -0.7874 -0.4064)
			(end 0.7874 -0.4064)
			(stroke
				(width 0.1524)
				(type default)
			)
			(layer "F.SilkS")
		)
		(fp_line
			(start 0.67945 0.3048)
			(end 0.120396 0.3048)
			(stroke
				(width 0.1)
				(type default)
			)
			(layer "F.Fab")
		)
		(fp_line
			(start 0.67945 -0.3048)
			(end 0.67945 0.3048)
			(stroke
				(width 0.1)
				(type default)
			)
			(layer "F.Fab")
		)
		(fp_line
			(start 0.12065 -0.2794)
			(end 0.12065 -0.3048)
			(stroke
				(width 0.1)
				(type default)
			)
			(layer "F.Fab")
		)
		(fp_line
			(start 0.12065 -0.3048)
			(end 0.67945 -0.3048)
			(stroke
				(width 0.1)
				(type default)
			)
			(layer "F.Fab")
		)
		(fp_line
			(start 0.120396 0.3048)
			(end 0.120396 0.2794)
			(stroke
				(width 0.1)
				(type default)
			)
			(layer "F.Fab")
		)
		(fp_line
			(start 0.120396 0.2794)
			(end -0.12065 0.2794)
			(stroke
				(width 0.1)
				(type default)
			)
			(layer "F.Fab")
		)
		(fp_line
			(start -0.12065 0.3048)
			(end -0.67945 0.3048)
			(stroke
				(width 0.1)
				(type default)
			)
			(layer "F.Fab")
		)
		(fp_line
			(start -0.12065 0.2794)
			(end -0.12065 0.3048)
			(stroke
				(width 0.1)
				(type default)
			)
			(layer "F.Fab")
		)
		(fp_line
			(start -0.12065 -0.2794)
			(end 0.12065 -0.2794)
			(stroke
				(width 0.1)
				(type default)
			)
			(layer "F.Fab")
		)
		(fp_line
			(start -0.12065 -0.305054)
			(end -0.12065 -0.2794)
			(stroke
				(width 0.1)
				(type default)
			)
			(layer "F.Fab")
		)
		(fp_line
			(start -0.67945 0.3048)
			(end -0.67945 -0.305054)
			(stroke
				(width 0.1)
				(type default)
			)
			(layer "F.Fab")
		)
		(fp_line
			(start -0.67945 -0.305054)
			(end -0.12065 -0.305054)
			(stroke
				(width 0.1)
				(type default)
			)
			(layer "F.Fab")
		)
		(pad "1" smd circle
			(at -0.40005 0 180)
			(size 0 0)
			(layers "F.Cu" "F.Mask" "F.Paste")
			(net "P12V_AUX")
		)
		(pad "2" smd circle
			(at 0.40005 0 180)
			(size 0 0)
			(layers "F.Cu" "F.Mask" "F.Paste")
			(net "GND")
		)
	)
	(footprint ""
		(layer "F.Cu")
		(at 361.188 -180.086 180)
		(property "Reference" "R4717"
			(at 0 0 180)
			(layer "F.SilkS")
			(hide yes)
			(effects
				(font
					(size 1.27 1.27)
				)
			)
		)
		(property "Value" ""
			(at 0 0 180)
			(layer "F.Fab")
			(effects
				(font
					(size 1.27 1.27)
				)
			)
		)
		(duplicate_pad_numbers_are_jumpers no)
		(fp_line
			(start 0.7874 0.4064)
			(end -0.7874 0.4064)
			(stroke
				(width 0.1524)
				(type default)
			)
			(layer "F.SilkS")
		)
		(fp_line
			(start 0.7874 -0.4064)
			(end 0.7874 0.4064)
			(stroke
				(width 0.1524)
				(type default)
			)
			(layer "F.SilkS")
		)
		(fp_line
			(start -0.7874 0.4064)
			(end -0.7874 -0.4064)
			(stroke
				(width 0.1524)
				(type default)
			)
			(layer "F.SilkS")
		)
		(fp_line
			(start -0.7874 -0.4064)
			(end 0.7874 -0.4064)
			(stroke
				(width 0.1524)
				(type default)
			)
			(layer "F.SilkS")
		)
		(fp_line
			(start 0.67945 0.3048)
			(end 0.120396 0.3048)
			(stroke
				(width 0.1)
				(type default)
			)
			(layer "F.Fab")
		)
		(fp_line
			(start 0.67945 -0.3048)
			(end 0.67945 0.3048)
			(stroke
				(width 0.1)
				(type default)
			)
			(layer "F.Fab")
		)
		(fp_line
			(start 0.12065 -0.2794)
			(end 0.12065 -0.3048)
			(stroke
				(width 0.1)
				(type default)
			)
			(layer "F.Fab")
		)
		(fp_line
			(start 0.12065 -0.3048)
			(end 0.67945 -0.3048)
			(stroke
				(width 0.1)
				(type default)
			)
			(layer "F.Fab")
		)
		(fp_line
			(start 0.120396 0.3048)
			(end 0.120396 0.2794)
			(stroke
				(width 0.1)
				(type default)
			)
			(layer "F.Fab")
		)
		(fp_line
			(start 0.120396 0.2794)
			(end -0.12065 0.2794)
			(stroke
				(width 0.1)
				(type default)
			)
			(layer "F.Fab")
		)
		(fp_line
			(start -0.12065 0.3048)
			(end -0.67945 0.3048)
			(stroke
				(width 0.1)
				(type default)
			)
			(layer "F.Fab")
		)
		(fp_line
			(start -0.12065 0.2794)
			(end -0.12065 0.3048)
			(stroke
				(width 0.1)
				(type default)
			)
			(layer "F.Fab")
		)
		(fp_line
			(start -0.12065 -0.2794)
			(end 0.12065 -0.2794)
			(stroke
				(width 0.1)
				(type default)
			)
			(layer "F.Fab")
		)
		(fp_line
			(start -0.12065 -0.305054)
			(end -0.12065 -0.2794)
			(stroke
				(width 0.1)
				(type default)
			)
			(layer "F.Fab")
		)
		(fp_line
			(start -0.67945 0.3048)
			(end -0.67945 -0.305054)
			(stroke
				(width 0.1)
				(type default)
			)
			(layer "F.Fab")
		)
		(fp_line
			(start -0.67945 -0.305054)
			(end -0.12065 -0.305054)
			(stroke
				(width 0.1)
				(type default)
			)
			(layer "F.Fab")
		)
		(pad "1" smd circle
			(at -0.40005 0 180)
			(size 0 0)
			(layers "F.Cu" "F.Mask" "F.Paste")
			(net "GND")
		)
		(pad "2" smd circle
			(at 0.40005 0 180)
			(size 0 0)
			(layers "F.Cu" "F.Mask" "F.Paste")
			(net "PCA9555_1_PEX1_A2")
		)
	)
	(footprint ""
		(layer "F.Cu")
		(at 7.613396 -137.344404 180)
		(property "Reference" "PR193"
			(at 0 0 180)
			(layer "F.SilkS")
			(hide yes)
			(effects
				(font
					(size 1.27 1.27)
				)
			)
		)
		(property "Value" ""
			(at 0 0 180)
			(layer "F.Fab")
			(effects
				(font
					(size 1.27 1.27)
				)
			)
		)
		(duplicate_pad_numbers_are_jumpers no)
		(fp_line
			(start 0.7874 0.4064)
			(end -0.7874 0.4064)
			(stroke
				(width 0.1524)
				(type default)
			)
			(layer "F.SilkS")
		)
		(fp_line
			(start 0.7874 -0.4064)
			(end 0.7874 0.4064)
			(stroke
				(width 0.1524)
				(type default)
			)
			(layer "F.SilkS")
		)
		(fp_line
			(start -0.7874 0.4064)
			(end -0.7874 -0.4064)
			(stroke
				(width 0.1524)
				(type default)
			)
			(layer "F.SilkS")
		)
		(fp_line
			(start -0.7874 -0.4064)
			(end 0.7874 -0.4064)
			(stroke
				(width 0.1524)
				(type default)
			)
			(layer "F.SilkS")
		)
		(fp_line
			(start 0.67945 0.3048)
			(end 0.120396 0.3048)
			(stroke
				(width 0.1)
				(type default)
			)
			(layer "F.Fab")
		)
		(fp_line
			(start 0.67945 -0.3048)
			(end 0.67945 0.3048)
			(stroke
				(width 0.1)
				(type default)
			)
			(layer "F.Fab")
		)
		(fp_line
			(start 0.12065 -0.2794)
			(end 0.12065 -0.3048)
			(stroke
				(width 0.1)
				(type default)
			)
			(layer "F.Fab")
		)
		(fp_line
			(start 0.12065 -0.3048)
			(end 0.67945 -0.3048)
			(stroke
				(width 0.1)
				(type default)
			)
			(layer "F.Fab")
		)
		(fp_line
			(start 0.120396 0.3048)
			(end 0.120396 0.2794)
			(stroke
				(width 0.1)
				(type default)
			)
			(layer "F.Fab")
		)
		(fp_line
			(start 0.120396 0.2794)
			(end -0.12065 0.2794)
			(stroke
				(width 0.1)
				(type default)
			)
			(layer "F.Fab")
		)
		(fp_line
			(start -0.12065 0.3048)
			(end -0.67945 0.3048)
			(stroke
				(width 0.1)
				(type default)
			)
			(layer "F.Fab")
		)
		(fp_line
			(start -0.12065 0.2794)
			(end -0.12065 0.3048)
			(stroke
				(width 0.1)
				(type default)
			)
			(layer "F.Fab")
		)
		(fp_line
			(start -0.12065 -0.2794)
			(end 0.12065 -0.2794)
			(stroke
				(width 0.1)
				(type default)
			)
			(layer "F.Fab")
		)
		(fp_line
			(start -0.12065 -0.305054)
			(end -0.12065 -0.2794)
			(stroke
				(width 0.1)
				(type default)
			)
			(layer "F.Fab")
		)
		(fp_line
			(start -0.67945 0.3048)
			(end -0.67945 -0.305054)
			(stroke
				(width 0.1)
				(type default)
			)
			(layer "F.Fab")
		)
		(fp_line
			(start -0.67945 -0.305054)
			(end -0.12065 -0.305054)
			(stroke
				(width 0.1)
				(type default)
			)
			(layer "F.Fab")
		)
		(pad "1" smd circle
			(at -0.40005 0 180)
			(size 0 0)
			(layers "F.Cu" "F.Mask" "F.Paste")
			(net "P12V_NIC0_OCP")
		)
		(pad "2" smd circle
			(at 0.40005 0 180)
			(size 0 0)
			(layers "F.Cu" "F.Mask" "F.Paste")
			(net "GND")
		)
	)
	(footprint ""
		(layer "F.Cu")
		(at 287.075118 -64.102234 180)
		(property "Reference" "PR7085"
			(at 0 0 180)
			(layer "F.SilkS")
			(hide yes)
			(effects
				(font
					(size 1.27 1.27)
				)
			)
		)
		(property "Value" ""
			(at 0 0 180)
			(layer "F.Fab")
			(effects
				(font
					(size 1.27 1.27)
				)
			)
		)
		(duplicate_pad_numbers_are_jumpers no)
		(fp_line
			(start 0.7874 0.4064)
			(end -0.7874 0.4064)
			(stroke
				(width 0.1524)
				(type default)
			)
			(layer "F.SilkS")
		)
		(fp_line
			(start 0.7874 -0.4064)
			(end 0.7874 0.4064)
			(stroke
				(width 0.1524)
				(type default)
			)
			(layer "F.SilkS")
		)
		(fp_line
			(start -0.7874 0.4064)
			(end -0.7874 -0.4064)
			(stroke
				(width 0.1524)
				(type default)
			)
			(layer "F.SilkS")
		)
		(fp_line
			(start -0.7874 -0.4064)
			(end 0.7874 -0.4064)
			(stroke
				(width 0.1524)
				(type default)
			)
			(layer "F.SilkS")
		)
		(fp_line
			(start 0.67945 0.3048)
			(end 0.120396 0.3048)
			(stroke
				(width 0.1)
				(type default)
			)
			(layer "F.Fab")
		)
		(fp_line
			(start 0.67945 -0.3048)
			(end 0.67945 0.3048)
			(stroke
				(width 0.1)
				(type default)
			)
			(layer "F.Fab")
		)
		(fp_line
			(start 0.12065 -0.2794)
			(end 0.12065 -0.3048)
			(stroke
				(width 0.1)
				(type default)
			)
			(layer "F.Fab")
		)
		(fp_line
			(start 0.12065 -0.3048)
			(end 0.67945 -0.3048)
			(stroke
				(width 0.1)
				(type default)
			)
			(layer "F.Fab")
		)
		(fp_line
			(start 0.120396 0.3048)
			(end 0.120396 0.2794)
			(stroke
				(width 0.1)
				(type default)
			)
			(layer "F.Fab")
		)
		(fp_line
			(start 0.120396 0.2794)
			(end -0.12065 0.2794)
			(stroke
				(width 0.1)
				(type default)
			)
			(layer "F.Fab")
		)
		(fp_line
			(start -0.12065 0.3048)
			(end -0.67945 0.3048)
			(stroke
				(width 0.1)
				(type default)
			)
			(layer "F.Fab")
		)
		(fp_line
			(start -0.12065 0.2794)
			(end -0.12065 0.3048)
			(stroke
				(width 0.1)
				(type default)
			)
			(layer "F.Fab")
		)
		(fp_line
			(start -0.12065 -0.2794)
			(end 0.12065 -0.2794)
			(stroke
				(width 0.1)
				(type default)
			)
			(layer "F.Fab")
		)
		(fp_line
			(start -0.12065 -0.305054)
			(end -0.12065 -0.2794)
			(stroke
				(width 0.1)
				(type default)
			)
			(layer "F.Fab")
		)
		(fp_line
			(start -0.67945 0.3048)
			(end -0.67945 -0.305054)
			(stroke
				(width 0.1)
				(type default)
			)
			(layer "F.Fab")
		)
		(fp_line
			(start -0.67945 -0.305054)
			(end -0.12065 -0.305054)
			(stroke
				(width 0.1)
				(type default)
			)
			(layer "F.Fab")
		)
		(pad "1" smd circle
			(at -0.40005 0 180)
			(size 0 0)
			(layers "F.Cu" "F.Mask" "F.Paste")
			(net "P12V_SSD10_PG_G1")
		)
		(pad "2" smd circle
			(at 0.40005 0 180)
			(size 0 0)
			(layers "F.Cu" "F.Mask" "F.Paste")
			(net "GND")
		)
	)
	(footprint ""
		(layer "F.Cu")
		(at 244.264434 -250.759722 -90)
		(property "Reference" "R6226"
			(at 0 0 270)
			(layer "F.SilkS")
			(hide yes)
			(effects
				(font
					(size 1.27 1.27)
				)
			)
		)
		(property "Value" ""
			(at 0 0 270)
			(layer "F.Fab")
			(effects
				(font
					(size 1.27 1.27)
				)
			)
		)
		(duplicate_pad_numbers_are_jumpers no)
		(fp_line
			(start -0.7874 0.4064)
			(end -0.7874 -0.4064)
			(stroke
				(width 0.1524)
				(type default)
			)
			(layer "F.SilkS")
		)
		(fp_line
			(start 0.7874 0.4064)
			(end -0.7874 0.4064)
			(stroke
				(width 0.1524)
				(type default)
			)
			(layer "F.SilkS")
		)
		(fp_line
			(start -0.7874 -0.4064)
			(end 0.7874 -0.4064)
			(stroke
				(width 0.1524)
				(type default)
			)
			(layer "F.SilkS")
		)
		(fp_line
			(start 0.7874 -0.4064)
			(end 0.7874 0.4064)
			(stroke
				(width 0.1524)
				(type default)
			)
			(layer "F.SilkS")
		)
		(fp_line
			(start -0.67945 0.3048)
			(end -0.67945 -0.305054)
			(stroke
				(width 0.1)
				(type default)
			)
			(layer "F.Fab")
		)
		(fp_line
			(start -0.12065 0.3048)
			(end -0.67945 0.3048)
			(stroke
				(width 0.1)
				(type default)
			)
			(layer "F.Fab")
		)
		(fp_line
			(start 0.120396 0.3048)
			(end 0.120396 0.2794)
			(stroke
				(width 0.1)
				(type default)
			)
			(layer "F.Fab")
		)
		(fp_line
			(start 0.67945 0.3048)
			(end 0.120396 0.3048)
			(stroke
				(width 0.1)
				(type default)
			)
			(layer "F.Fab")
		)
		(fp_line
			(start -0.12065 0.2794)
			(end -0.12065 0.3048)
			(stroke
				(width 0.1)
				(type default)
			)
			(layer "F.Fab")
		)
		(fp_line
			(start 0.120396 0.2794)
			(end -0.12065 0.2794)
			(stroke
				(width 0.1)
				(type default)
			)
			(layer "F.Fab")
		)
		(fp_line
			(start -0.12065 -0.2794)
			(end 0.12065 -0.2794)
			(stroke
				(width 0.1)
				(type default)
			)
			(layer "F.Fab")
		)
		(fp_line
			(start 0.12065 -0.2794)
			(end 0.12065 -0.3048)
			(stroke
				(width 0.1)
				(type default)
			)
			(layer "F.Fab")
		)
		(fp_line
			(start 0.12065 -0.3048)
			(end 0.67945 -0.3048)
			(stroke
				(width 0.1)
				(type default)
			)
			(layer "F.Fab")
		)
		(fp_line
			(start 0.67945 -0.3048)
			(end 0.67945 0.3048)
			(stroke
				(width 0.1)
				(type default)
			)
			(layer "F.Fab")
		)
		(fp_line
			(start -0.67945 -0.305054)
			(end -0.12065 -0.305054)
			(stroke
				(width 0.1)
				(type default)
			)
			(layer "F.Fab")
		)
		(fp_line
			(start -0.12065 -0.305054)
			(end -0.12065 -0.2794)
			(stroke
				(width 0.1)
				(type default)
			)
			(layer "F.Fab")
		)
		(pad "1" smd circle
			(at -0.40005 0 270)
			(size 0 0)
			(layers "F.Cu" "F.Mask" "F.Paste")
			(net "P3V3_AUX")
		)
		(pad "2" smd circle
			(at 0.40005 0 270)
			(size 0 0)
			(layers "F.Cu" "F.Mask" "F.Paste")
			(net "BIC_RECOVER_IOEXP_A1")
		)
	)
	(footprint ""
		(layer "F.Cu")
		(at 447.147188 -415.621216 90)
		(property "Reference" "R5599"
			(at 0 0 90)
			(layer "F.SilkS")
			(hide yes)
			(effects
				(font
					(size 1.27 1.27)
				)
			)
		)
		(property "Value" ""
			(at 0 0 90)
			(layer "F.Fab")
			(effects
				(font
					(size 1.27 1.27)
				)
			)
		)
		(duplicate_pad_numbers_are_jumpers no)
		(fp_line
			(start 0.7874 -0.4064)
			(end 0.7874 0.4064)
			(stroke
				(width 0.1524)
				(type default)
			)
			(layer "F.SilkS")
		)
		(fp_line
			(start -0.7874 -0.4064)
			(end 0.7874 -0.4064)
			(stroke
				(width 0.1524)
				(type default)
			)
			(layer "F.SilkS")
		)
		(fp_line
			(start 0.7874 0.4064)
			(end -0.7874 0.4064)
			(stroke
				(width 0.1524)
				(type default)
			)
			(layer "F.SilkS")
		)
		(fp_line
			(start -0.7874 0.4064)
			(end -0.7874 -0.4064)
			(stroke
				(width 0.1524)
				(type default)
			)
			(layer "F.SilkS")
		)
		(fp_line
			(start -0.12065 -0.305054)
			(end -0.12065 -0.2794)
			(stroke
				(width 0.1)
				(type default)
			)
			(layer "F.Fab")
		)
		(fp_line
			(start -0.67945 -0.305054)
			(end -0.12065 -0.305054)
			(stroke
				(width 0.1)
				(type default)
			)
			(layer "F.Fab")
		)
		(fp_line
			(start 0.67945 -0.3048)
			(end 0.67945 0.3048)
			(stroke
				(width 0.1)
				(type default)
			)
			(layer "F.Fab")
		)
		(fp_line
			(start 0.12065 -0.3048)
			(end 0.67945 -0.3048)
			(stroke
				(width 0.1)
				(type default)
			)
			(layer "F.Fab")
		)
		(fp_line
			(start 0.12065 -0.2794)
			(end 0.12065 -0.3048)
			(stroke
				(width 0.1)
				(type default)
			)
			(layer "F.Fab")
		)
		(fp_line
			(start -0.12065 -0.2794)
			(end 0.12065 -0.2794)
			(stroke
				(width 0.1)
				(type default)
			)
			(layer "F.Fab")
		)
		(fp_line
			(start 0.120396 0.2794)
			(end -0.12065 0.2794)
			(stroke
				(width 0.1)
				(type default)
			)
			(layer "F.Fab")
		)
		(fp_line
			(start -0.12065 0.2794)
			(end -0.12065 0.3048)
			(stroke
				(width 0.1)
				(type default)
			)
			(layer "F.Fab")
		)
		(fp_line
			(start 0.67945 0.3048)
			(end 0.120396 0.3048)
			(stroke
				(width 0.1)
				(type default)
			)
			(layer "F.Fab")
		)
		(fp_line
			(start 0.120396 0.3048)
			(end 0.120396 0.2794)
			(stroke
				(width 0.1)
				(type default)
			)
			(layer "F.Fab")
		)
		(fp_line
			(start -0.12065 0.3048)
			(end -0.67945 0.3048)
			(stroke
				(width 0.1)
				(type default)
			)
			(layer "F.Fab")
		)
		(fp_line
			(start -0.67945 0.3048)
			(end -0.67945 -0.305054)
			(stroke
				(width 0.1)
				(type default)
			)
			(layer "F.Fab")
		)
		(pad "1" smd circle
			(at -0.40005 0 90)
			(size 0 0)
			(layers "F.Cu" "F.Mask" "F.Paste")
			(net "LM75_1_A0")
		)
		(pad "2" smd circle
			(at 0.40005 0 90)
			(size 0 0)
			(layers "F.Cu" "F.Mask" "F.Paste")
			(net "P3V3_AUX")
		)
	)
	(footprint ""
		(layer "F.Cu")
		(at 237.587028 -277.078694 90)
		(property "Reference" "R792"
			(at 0 0 90)
			(layer "F.SilkS")
			(hide yes)
			(effects
				(font
					(size 1.27 1.27)
				)
			)
		)
		(property "Value" ""
			(at 0 0 90)
			(layer "F.Fab")
			(effects
				(font
					(size 1.27 1.27)
				)
			)
		)
		(duplicate_pad_numbers_are_jumpers no)
		(fp_line
			(start 3.937508 -1.8796)
			(end -3.937508 -1.8796)
			(stroke
				(width 0.1524)
				(type default)
			)
			(layer "F.SilkS")
		)
		(fp_line
			(start -3.937508 -1.8796)
			(end -3.937508 1.8796)
			(stroke
				(width 0.1524)
				(type default)
			)
			(layer "F.SilkS")
		)
		(fp_line
			(start 3.937508 1.8796)
			(end 3.937508 -1.8796)
			(stroke
				(width 0.1524)
				(type default)
			)
			(layer "F.SilkS")
		)
		(fp_line
			(start -3.937508 1.8796)
			(end 3.937508 1.8796)
			(stroke
				(width 0.1524)
				(type default)
			)
			(layer "F.SilkS")
		)
		(fp_line
			(start 3.275076 -1.674876)
			(end -3.275076 -1.674876)
			(stroke
				(width 0.1)
				(type default)
			)
			(layer "F.Fab")
		)
		(fp_line
			(start -3.275076 -1.674876)
			(end -3.275076 1.674876)
			(stroke
				(width 0.1)
				(type default)
			)
			(layer "F.Fab")
		)
		(fp_line
			(start 3.275076 1.674876)
			(end 3.275076 -1.674876)
			(stroke
				(width 0.1)
				(type default)
			)
			(layer "F.Fab")
		)
		(fp_line
			(start -3.275076 1.674876)
			(end 3.275076 1.674876)
			(stroke
				(width 0.1)
				(type default)
			)
			(layer "F.Fab")
		)
		(pad "1" smd rect
			(at -2.350008 0 90)
			(size 2.921 3.5052)
			(layers "F.Cu" "F.Mask" "F.Paste")
			(net "P1V25_PEX2")
		)
		(pad "2" smd rect
			(at 2.350008 0 90)
			(size 2.921 3.5052)
			(layers "F.Cu" "F.Mask" "F.Paste")
			(net "P1V25_PEX2_R")
		)
	)
	(footprint ""
		(layer "F.Cu")
		(at 271.480534 -135.815324)
		(property "Reference" "C455"
			(at 0 0 0)
			(layer "F.SilkS")
			(hide yes)
			(effects
				(font
					(size 1.27 1.27)
				)
			)
		)
		(property "Value" ""
			(at 0 0 0)
			(layer "F.Fab")
			(effects
				(font
					(size 1.27 1.27)
				)
			)
		)
		(duplicate_pad_numbers_are_jumpers no)
		(fp_line
			(start -0.299974 -0.150114)
			(end 0.299974 -0.150114)
			(stroke
				(width 0.1)
				(type default)
			)
			(layer "F.Fab")
		)
		(fp_line
			(start -0.299974 0.150114)
			(end -0.299974 -0.150114)
			(stroke
				(width 0.1)
				(type default)
			)
			(layer "F.Fab")
		)
		(fp_line
			(start 0.299974 -0.150114)
			(end 0.299974 0.150114)
			(stroke
				(width 0.1)
				(type default)
			)
			(layer "F.Fab")
		)
		(fp_line
			(start 0.299974 0.150114)
			(end -0.299974 0.150114)
			(stroke
				(width 0.1)
				(type default)
			)
			(layer "F.Fab")
		)
		(pad "1" smd rect
			(at -0.2667 0)
			(size 0.3048 0.381)
			(layers "F.Cu" "F.Mask" "F.Paste")
			(net "P5E_PEX2_STN1_TX_DN<31>")
		)
		(pad "2" smd rect
			(at 0.2667 0)
			(size 0.3048 0.381)
			(layers "F.Cu" "F.Mask" "F.Paste")
			(net "P5E_PEX2_STN1_TX_C_DN<31>")
		)
	)
	(footprint ""
		(layer "F.Cu")
		(at 408.071828 -24.807418)
		(property "Reference" "R453"
			(at 0 0 0)
			(layer "F.SilkS")
			(hide yes)
			(effects
				(font
					(size 1.27 1.27)
				)
			)
		)
		(property "Value" ""
			(at 0 0 0)
			(layer "F.Fab")
			(effects
				(font
					(size 1.27 1.27)
				)
			)
		)
		(duplicate_pad_numbers_are_jumpers no)
		(fp_line
			(start -0.7874 -0.4064)
			(end 0.7874 -0.4064)
			(stroke
				(width 0.1524)
				(type default)
			)
			(layer "F.SilkS")
		)
		(fp_line
			(start -0.7874 0.4064)
			(end -0.7874 -0.4064)
			(stroke
				(width 0.1524)
				(type default)
			)
			(layer "F.SilkS")
		)
		(fp_line
			(start 0.7874 -0.4064)
			(end 0.7874 0.4064)
			(stroke
				(width 0.1524)
				(type default)
			)
			(layer "F.SilkS")
		)
		(fp_line
			(start 0.7874 0.4064)
			(end -0.7874 0.4064)
			(stroke
				(width 0.1524)
				(type default)
			)
			(layer "F.SilkS")
		)
		(fp_line
			(start -0.67945 -0.305054)
			(end -0.12065 -0.305054)
			(stroke
				(width 0.1)
				(type default)
			)
			(layer "F.Fab")
		)
		(fp_line
			(start -0.67945 0.3048)
			(end -0.67945 -0.305054)
			(stroke
				(width 0.1)
				(type default)
			)
			(layer "F.Fab")
		)
		(fp_line
			(start -0.12065 -0.305054)
			(end -0.12065 -0.2794)
			(stroke
				(width 0.1)
				(type default)
			)
			(layer "F.Fab")
		)
		(fp_line
			(start -0.12065 -0.2794)
			(end 0.12065 -0.2794)
			(stroke
				(width 0.1)
				(type default)
			)
			(layer "F.Fab")
		)
		(fp_line
			(start -0.12065 0.2794)
			(end -0.12065 0.3048)
			(stroke
				(width 0.1)
				(type default)
			)
			(layer "F.Fab")
		)
		(fp_line
			(start -0.12065 0.3048)
			(end -0.67945 0.3048)
			(stroke
				(width 0.1)
				(type default)
			)
			(layer "F.Fab")
		)
		(fp_line
			(start 0.120396 0.2794)
			(end -0.12065 0.2794)
			(stroke
				(width 0.1)
				(type default)
			)
			(layer "F.Fab")
		)
		(fp_line
			(start 0.120396 0.3048)
			(end 0.120396 0.2794)
			(stroke
				(width 0.1)
				(type default)
			)
			(layer "F.Fab")
		)
		(fp_line
			(start 0.12065 -0.3048)
			(end 0.67945 -0.3048)
			(stroke
				(width 0.1)
				(type default)
			)
			(layer "F.Fab")
		)
		(fp_line
			(start 0.12065 -0.2794)
			(end 0.12065 -0.3048)
			(stroke
				(width 0.1)
				(type default)
			)
			(layer "F.Fab")
		)
		(fp_line
			(start 0.67945 -0.3048)
			(end 0.67945 0.3048)
			(stroke
				(width 0.1)
				(type default)
			)
			(layer "F.Fab")
		)
		(fp_line
			(start 0.67945 0.3048)
			(end 0.120396 0.3048)
			(stroke
				(width 0.1)
				(type default)
			)
			(layer "F.Fab")
		)
		(pad "1" smd circle
			(at -0.40005 0)
			(size 0 0)
			(layers "F.Cu" "F.Mask" "F.Paste")
			(net "P3V3_SSD14")
		)
		(pad "2" smd circle
			(at 0.40005 0)
			(size 0 0)
			(layers "F.Cu" "F.Mask" "F.Paste")
			(net "PU_CLKREQ14")
		)
	)
	(footprint ""
		(layer "F.Cu")
		(at 86.94039 -141.404848 -90)
		(property "Reference" "R94"
			(at 0 0 270)
			(layer "F.SilkS")
			(hide yes)
			(effects
				(font
					(size 1.27 1.27)
				)
			)
		)
		(property "Value" ""
			(at 0 0 270)
			(layer "F.Fab")
			(effects
				(font
					(size 1.27 1.27)
				)
			)
		)
		(duplicate_pad_numbers_are_jumpers no)
		(fp_line
			(start -0.7874 0.4064)
			(end -0.7874 -0.4064)
			(stroke
				(width 0.1524)
				(type default)
			)
			(layer "F.SilkS")
		)
		(fp_line
			(start 0.7874 0.4064)
			(end -0.7874 0.4064)
			(stroke
				(width 0.1524)
				(type default)
			)
			(layer "F.SilkS")
		)
		(fp_line
			(start -0.7874 -0.4064)
			(end 0.7874 -0.4064)
			(stroke
				(width 0.1524)
				(type default)
			)
			(layer "F.SilkS")
		)
		(fp_line
			(start 0.7874 -0.4064)
			(end 0.7874 0.4064)
			(stroke
				(width 0.1524)
				(type default)
			)
			(layer "F.SilkS")
		)
		(fp_line
			(start -0.67945 0.3048)
			(end -0.67945 -0.305054)
			(stroke
				(width 0.1)
				(type default)
			)
			(layer "F.Fab")
		)
		(fp_line
			(start -0.12065 0.3048)
			(end -0.67945 0.3048)
			(stroke
				(width 0.1)
				(type default)
			)
			(layer "F.Fab")
		)
		(fp_line
			(start 0.120396 0.3048)
			(end 0.120396 0.2794)
			(stroke
				(width 0.1)
				(type default)
			)
			(layer "F.Fab")
		)
		(fp_line
			(start 0.67945 0.3048)
			(end 0.120396 0.3048)
			(stroke
				(width 0.1)
				(type default)
			)
			(layer "F.Fab")
		)
		(fp_line
			(start -0.12065 0.2794)
			(end -0.12065 0.3048)
			(stroke
				(width 0.1)
				(type default)
			)
			(layer "F.Fab")
		)
		(fp_line
			(start 0.120396 0.2794)
			(end -0.12065 0.2794)
			(stroke
				(width 0.1)
				(type default)
			)
			(layer "F.Fab")
		)
		(fp_line
			(start -0.12065 -0.2794)
			(end 0.12065 -0.2794)
			(stroke
				(width 0.1)
				(type default)
			)
			(layer "F.Fab")
		)
		(fp_line
			(start 0.12065 -0.2794)
			(end 0.12065 -0.3048)
			(stroke
				(width 0.1)
				(type default)
			)
			(layer "F.Fab")
		)
		(fp_line
			(start 0.12065 -0.3048)
			(end 0.67945 -0.3048)
			(stroke
				(width 0.1)
				(type default)
			)
			(layer "F.Fab")
		)
		(fp_line
			(start 0.67945 -0.3048)
			(end 0.67945 0.3048)
			(stroke
				(width 0.1)
				(type default)
			)
			(layer "F.Fab")
		)
		(fp_line
			(start -0.67945 -0.305054)
			(end -0.12065 -0.305054)
			(stroke
				(width 0.1)
				(type default)
			)
			(layer "F.Fab")
		)
		(fp_line
			(start -0.12065 -0.305054)
			(end -0.12065 -0.2794)
			(stroke
				(width 0.1)
				(type default)
			)
			(layer "F.Fab")
		)
		(pad "1" smd circle
			(at -0.40005 0 270)
			(size 0 0)
			(layers "F.Cu" "F.Mask" "F.Paste")
			(net "PRSNT_NIC1_R_N")
		)
		(pad "2" smd circle
			(at 0.40005 0 270)
			(size 0 0)
			(layers "F.Cu" "F.Mask" "F.Paste")
			(net "PRSNT_NIC1_N")
		)
	)
	(footprint ""
		(layer "F.Cu")
		(at 254.60833 -257.102102)
		(property "Reference" "Q15"
			(at -2.42062 0.870712 90)
			(unlocked yes)
			(layer "F.SilkS")
			(effects
				(font
					(size 0.7874 0.5842)
					(thickness 0.1524)
				)
			)
		)
		(property "Value" ""
			(at 0 0 0)
			(layer "F.Fab")
			(effects
				(font
					(size 1.27 1.27)
				)
			)
		)
		(duplicate_pad_numbers_are_jumpers no)
		(fp_line
			(start -1.376172 -1.199896)
			(end -0.508 -1.199896)
			(stroke
				(width 0.1524)
				(type default)
			)
			(layer "F.SilkS")
		)
		(fp_line
			(start -1.376172 1.199896)
			(end -1.376172 -1.199896)
			(stroke
				(width 0.1524)
				(type default)
			)
			(layer "F.SilkS")
		)
		(fp_line
			(start -0.508 -1.199896)
			(end 0 -0.762)
			(stroke
				(width 0.1524)
				(type default)
			)
			(layer "F.SilkS")
		)
		(fp_line
			(start 0 -0.762)
			(end 0.508 -1.199896)
			(stroke
				(width 0.1524)
				(type default)
			)
			(layer "F.SilkS")
		)
		(fp_line
			(start 0.508 -1.199896)
			(end 1.376172 -1.199896)
			(stroke
				(width 0.1524)
				(type default)
			)
			(layer "F.SilkS")
		)
		(fp_line
			(start 1.376172 -1.199896)
			(end 1.376172 1.199896)
			(stroke
				(width 0.1524)
				(type default)
			)
			(layer "F.SilkS")
		)
		(fp_line
			(start 1.376172 1.199896)
			(end -1.376172 1.199896)
			(stroke
				(width 0.1524)
				(type default)
			)
			(layer "F.SilkS")
		)
		(fp_poly
			(pts
				(xy -1.4605 -0.7493) (xy -2.2225 -1.1303) (xy -2.2225 -0.3683)
			)
			(stroke
				(width 0)
				(type default)
			)
			(fill yes)
			(layer "F.SilkS")
		)
		(fp_line
			(start -0.674878 -1.100074)
			(end 0.674878 -1.100074)
			(stroke
				(width 0.1)
				(type default)
			)
			(layer "F.Fab")
		)
		(fp_line
			(start -0.674878 1.100074)
			(end -0.674878 -1.100074)
			(stroke
				(width 0.1)
				(type default)
			)
			(layer "F.Fab")
		)
		(fp_line
			(start 0.674878 -1.100074)
			(end 0.674878 1.100074)
			(stroke
				(width 0.1)
				(type default)
			)
			(layer "F.Fab")
		)
		(fp_line
			(start 0.674878 1.100074)
			(end -0.674878 1.100074)
			(stroke
				(width 0.1)
				(type default)
			)
			(layer "F.Fab")
		)
		(fp_poly
			(pts
				(xy -1.4605 -0.7493) (xy -2.2225 -1.1303) (xy -2.2225 -0.3683)
			)
			(stroke
				(width 0)
				(type default)
			)
			(fill yes)
			(layer "F.Fab")
		)
		(pad "1" smd rect
			(at -0.899922 -0.750062 270)
			(size 0.6096 0.6096)
			(layers "F.Cu" "F.Mask" "F.Paste")
			(net "GND")
		)
		(pad "2" smd rect
			(at -0.899922 0 270)
			(size 0.4064 0.6096)
			(layers "F.Cu" "F.Mask" "F.Paste")
			(net "PEX2_SYS_ERR_R_N")
		)
		(pad "3" smd rect
			(at -0.899922 0.750062 270)
			(size 0.6096 0.6096)
			(layers "F.Cu" "F.Mask" "F.Paste")
			(net "PEX2_SYS_ERR_3V3_N")
		)
		(pad "4" smd rect
			(at 0.899922 0.750062 270)
			(size 0.6096 0.6096)
			(layers "F.Cu" "F.Mask" "F.Paste")
			(net "GND")
		)
		(pad "5" smd rect
			(at 0.899922 0 270)
			(size 0.4064 0.6096)
			(layers "F.Cu" "F.Mask" "F.Paste")
			(net "PEX2_SYS_ERR_N_G")
		)
		(pad "6" smd rect
			(at 0.899922 -0.750062 270)
			(size 0.6096 0.6096)
			(layers "F.Cu" "F.Mask" "F.Paste")
			(net "PEX2_SYS_ERR_N_G")
		)
	)
	(footprint ""
		(layer "F.Cu")
		(at 167.148256 -166.302944 90)
		(property "Reference" "R147"
			(at 0 0 90)
			(layer "F.SilkS")
			(hide yes)
			(effects
				(font
					(size 1.27 1.27)
				)
			)
		)
		(property "Value" ""
			(at 0 0 90)
			(layer "F.Fab")
			(effects
				(font
					(size 1.27 1.27)
				)
			)
		)
		(duplicate_pad_numbers_are_jumpers no)
		(fp_line
			(start 0.7874 -0.4064)
			(end 0.7874 0.4064)
			(stroke
				(width 0.1524)
				(type default)
			)
			(layer "F.SilkS")
		)
		(fp_line
			(start -0.7874 -0.4064)
			(end 0.7874 -0.4064)
			(stroke
				(width 0.1524)
				(type default)
			)
			(layer "F.SilkS")
		)
		(fp_line
			(start 0.7874 0.4064)
			(end -0.7874 0.4064)
			(stroke
				(width 0.1524)
				(type default)
			)
			(layer "F.SilkS")
		)
		(fp_line
			(start -0.7874 0.4064)
			(end -0.7874 -0.4064)
			(stroke
				(width 0.1524)
				(type default)
			)
			(layer "F.SilkS")
		)
		(fp_line
			(start -0.12065 -0.305054)
			(end -0.12065 -0.2794)
			(stroke
				(width 0.1)
				(type default)
			)
			(layer "F.Fab")
		)
		(fp_line
			(start -0.67945 -0.305054)
			(end -0.12065 -0.305054)
			(stroke
				(width 0.1)
				(type default)
			)
			(layer "F.Fab")
		)
		(fp_line
			(start 0.67945 -0.3048)
			(end 0.67945 0.3048)
			(stroke
				(width 0.1)
				(type default)
			)
			(layer "F.Fab")
		)
		(fp_line
			(start 0.12065 -0.3048)
			(end 0.67945 -0.3048)
			(stroke
				(width 0.1)
				(type default)
			)
			(layer "F.Fab")
		)
		(fp_line
			(start 0.12065 -0.2794)
			(end 0.12065 -0.3048)
			(stroke
				(width 0.1)
				(type default)
			)
			(layer "F.Fab")
		)
		(fp_line
			(start -0.12065 -0.2794)
			(end 0.12065 -0.2794)
			(stroke
				(width 0.1)
				(type default)
			)
			(layer "F.Fab")
		)
		(fp_line
			(start 0.120396 0.2794)
			(end -0.12065 0.2794)
			(stroke
				(width 0.1)
				(type default)
			)
			(layer "F.Fab")
		)
		(fp_line
			(start -0.12065 0.2794)
			(end -0.12065 0.3048)
			(stroke
				(width 0.1)
				(type default)
			)
			(layer "F.Fab")
		)
		(fp_line
			(start 0.67945 0.3048)
			(end 0.120396 0.3048)
			(stroke
				(width 0.1)
				(type default)
			)
			(layer "F.Fab")
		)
		(fp_line
			(start 0.120396 0.3048)
			(end 0.120396 0.2794)
			(stroke
				(width 0.1)
				(type default)
			)
			(layer "F.Fab")
		)
		(fp_line
			(start -0.12065 0.3048)
			(end -0.67945 0.3048)
			(stroke
				(width 0.1)
				(type default)
			)
			(layer "F.Fab")
		)
		(fp_line
			(start -0.67945 0.3048)
			(end -0.67945 -0.305054)
			(stroke
				(width 0.1)
				(type default)
			)
			(layer "F.Fab")
		)
		(pad "1" smd circle
			(at -0.40005 0 90)
			(size 0 0)
			(layers "F.Cu" "F.Mask" "F.Paste")
			(net "RST_NIC2_PERST0_R_N")
		)
		(pad "2" smd circle
			(at 0.40005 0 90)
			(size 0 0)
			(layers "F.Cu" "F.Mask" "F.Paste")
			(net "RST_HP_NIC2_BUF_N")
		)
	)
	(footprint ""
		(layer "F.Cu")
		(at 395.247368 -19.33956)
		(property "Reference" "C3967"
			(at 0 0 0)
			(layer "F.SilkS")
			(hide yes)
			(effects
				(font
					(size 1.27 1.27)
				)
			)
		)
		(property "Value" ""
			(at 0 0 0)
			(layer "F.Fab")
			(effects
				(font
					(size 1.27 1.27)
				)
			)
		)
		(duplicate_pad_numbers_are_jumpers no)
		(fp_line
			(start -0.7874 -0.4064)
			(end 0.7874 -0.4064)
			(stroke
				(width 0.1524)
				(type default)
			)
			(layer "F.SilkS")
		)
		(fp_line
			(start -0.7874 0.4064)
			(end -0.7874 -0.4064)
			(stroke
				(width 0.1524)
				(type default)
			)
			(layer "F.SilkS")
		)
		(fp_line
			(start 0.7874 -0.4064)
			(end 0.7874 0.4064)
			(stroke
				(width 0.1524)
				(type default)
			)
			(layer "F.SilkS")
		)
		(fp_line
			(start 0.7874 0.4064)
			(end -0.7874 0.4064)
			(stroke
				(width 0.1524)
				(type default)
			)
			(layer "F.SilkS")
		)
		(fp_line
			(start -0.67945 -0.305054)
			(end -0.12065 -0.305054)
			(stroke
				(width 0.1)
				(type default)
			)
			(layer "F.Fab")
		)
		(fp_line
			(start -0.67945 0.3048)
			(end -0.67945 -0.305054)
			(stroke
				(width 0.1)
				(type default)
			)
			(layer "F.Fab")
		)
		(fp_line
			(start -0.12065 -0.305054)
			(end -0.12065 -0.2794)
			(stroke
				(width 0.1)
				(type default)
			)
			(layer "F.Fab")
		)
		(fp_line
			(start -0.12065 -0.2794)
			(end 0.12065 -0.2794)
			(stroke
				(width 0.1)
				(type default)
			)
			(layer "F.Fab")
		)
		(fp_line
			(start -0.12065 0.2794)
			(end -0.12065 0.3048)
			(stroke
				(width 0.1)
				(type default)
			)
			(layer "F.Fab")
		)
		(fp_line
			(start -0.12065 0.3048)
			(end -0.67945 0.3048)
			(stroke
				(width 0.1)
				(type default)
			)
			(layer "F.Fab")
		)
		(fp_line
			(start 0.120396 0.2794)
			(end -0.12065 0.2794)
			(stroke
				(width 0.1)
				(type default)
			)
			(layer "F.Fab")
		)
		(fp_line
			(start 0.120396 0.3048)
			(end 0.120396 0.2794)
			(stroke
				(width 0.1)
				(type default)
			)
			(layer "F.Fab")
		)
		(fp_line
			(start 0.12065 -0.3048)
			(end 0.67945 -0.3048)
			(stroke
				(width 0.1)
				(type default)
			)
			(layer "F.Fab")
		)
		(fp_line
			(start 0.12065 -0.2794)
			(end 0.12065 -0.3048)
			(stroke
				(width 0.1)
				(type default)
			)
			(layer "F.Fab")
		)
		(fp_line
			(start 0.67945 -0.3048)
			(end 0.67945 0.3048)
			(stroke
				(width 0.1)
				(type default)
			)
			(layer "F.Fab")
		)
		(fp_line
			(start 0.67945 0.3048)
			(end 0.120396 0.3048)
			(stroke
				(width 0.1)
				(type default)
			)
			(layer "F.Fab")
		)
		(pad "1" smd circle
			(at -0.40005 0)
			(size 0 0)
			(layers "F.Cu" "F.Mask" "F.Paste")
			(net "P12V_SSD13")
		)
		(pad "2" smd circle
			(at 0.40005 0)
			(size 0 0)
			(layers "F.Cu" "F.Mask" "F.Paste")
			(net "GND")
		)
	)
	(footprint ""
		(layer "F.Cu")
		(at 369.495578 -90.642694)
		(property "Reference" "R1609"
			(at 0 0 0)
			(layer "F.SilkS")
			(hide yes)
			(effects
				(font
					(size 1.27 1.27)
				)
			)
		)
		(property "Value" ""
			(at 0 0 0)
			(layer "F.Fab")
			(effects
				(font
					(size 1.27 1.27)
				)
			)
		)
		(duplicate_pad_numbers_are_jumpers no)
		(fp_line
			(start -0.7874 -0.4064)
			(end 0.7874 -0.4064)
			(stroke
				(width 0.1524)
				(type default)
			)
			(layer "F.SilkS")
		)
		(fp_line
			(start -0.7874 0.4064)
			(end -0.7874 -0.4064)
			(stroke
				(width 0.1524)
				(type default)
			)
			(layer "F.SilkS")
		)
		(fp_line
			(start 0.7874 -0.4064)
			(end 0.7874 0.4064)
			(stroke
				(width 0.1524)
				(type default)
			)
			(layer "F.SilkS")
		)
		(fp_line
			(start 0.7874 0.4064)
			(end -0.7874 0.4064)
			(stroke
				(width 0.1524)
				(type default)
			)
			(layer "F.SilkS")
		)
		(fp_line
			(start -0.67945 -0.305054)
			(end -0.12065 -0.305054)
			(stroke
				(width 0.1)
				(type default)
			)
			(layer "F.Fab")
		)
		(fp_line
			(start -0.67945 0.3048)
			(end -0.67945 -0.305054)
			(stroke
				(width 0.1)
				(type default)
			)
			(layer "F.Fab")
		)
		(fp_line
			(start -0.12065 -0.305054)
			(end -0.12065 -0.2794)
			(stroke
				(width 0.1)
				(type default)
			)
			(layer "F.Fab")
		)
		(fp_line
			(start -0.12065 -0.2794)
			(end 0.12065 -0.2794)
			(stroke
				(width 0.1)
				(type default)
			)
			(layer "F.Fab")
		)
		(fp_line
			(start -0.12065 0.2794)
			(end -0.12065 0.3048)
			(stroke
				(width 0.1)
				(type default)
			)
			(layer "F.Fab")
		)
		(fp_line
			(start -0.12065 0.3048)
			(end -0.67945 0.3048)
			(stroke
				(width 0.1)
				(type default)
			)
			(layer "F.Fab")
		)
		(fp_line
			(start 0.120396 0.2794)
			(end -0.12065 0.2794)
			(stroke
				(width 0.1)
				(type default)
			)
			(layer "F.Fab")
		)
		(fp_line
			(start 0.120396 0.3048)
			(end 0.120396 0.2794)
			(stroke
				(width 0.1)
				(type default)
			)
			(layer "F.Fab")
		)
		(fp_line
			(start 0.12065 -0.3048)
			(end 0.67945 -0.3048)
			(stroke
				(width 0.1)
				(type default)
			)
			(layer "F.Fab")
		)
		(fp_line
			(start 0.12065 -0.2794)
			(end 0.12065 -0.3048)
			(stroke
				(width 0.1)
				(type default)
			)
			(layer "F.Fab")
		)
		(fp_line
			(start 0.67945 -0.3048)
			(end 0.67945 0.3048)
			(stroke
				(width 0.1)
				(type default)
			)
			(layer "F.Fab")
		)
		(fp_line
			(start 0.67945 0.3048)
			(end 0.120396 0.3048)
			(stroke
				(width 0.1)
				(type default)
			)
			(layer "F.Fab")
		)
		(pad "1" smd circle
			(at -0.40005 0)
			(size 0 0)
			(layers "F.Cu" "F.Mask" "F.Paste")
			(net "BIC_I2C9_SSD_MUX1_A2")
		)
		(pad "2" smd circle
			(at 0.40005 0)
			(size 0 0)
			(layers "F.Cu" "F.Mask" "F.Paste")
			(net "GND")
		)
	)
	(footprint ""
		(layer "F.Cu")
		(at 444.247016 -55.63489 90)
		(property "Reference" "PC894"
			(at 0 0 90)
			(layer "F.SilkS")
			(hide yes)
			(effects
				(font
					(size 1.27 1.27)
				)
			)
		)
		(property "Value" ""
			(at 0 0 90)
			(layer "F.Fab")
			(effects
				(font
					(size 1.27 1.27)
				)
			)
		)
		(duplicate_pad_numbers_are_jumpers no)
		(fp_line
			(start 1.524 -0.762)
			(end 1.524 0.762)
			(stroke
				(width 0.1524)
				(type default)
			)
			(layer "F.SilkS")
		)
		(fp_line
			(start -1.524 -0.762)
			(end 1.524 -0.762)
			(stroke
				(width 0.1524)
				(type default)
			)
			(layer "F.SilkS")
		)
		(fp_line
			(start 1.524 0.762)
			(end -1.524 0.762)
			(stroke
				(width 0.1524)
				(type default)
			)
			(layer "F.SilkS")
		)
		(fp_line
			(start -1.524 0.762)
			(end -1.524 -0.762)
			(stroke
				(width 0.1524)
				(type default)
			)
			(layer "F.SilkS")
		)
		(fp_line
			(start 1.1049 -0.724916)
			(end -1.1049 -0.724916)
			(stroke
				(width 0.1)
				(type default)
			)
			(layer "F.Fab")
		)
		(fp_line
			(start -1.1049 -0.724916)
			(end -1.1049 0.724916)
			(stroke
				(width 0.1)
				(type default)
			)
			(layer "F.Fab")
		)
		(fp_line
			(start 1.1049 0.724916)
			(end 1.1049 -0.724916)
			(stroke
				(width 0.1)
				(type default)
			)
			(layer "F.Fab")
		)
		(fp_line
			(start -1.1049 0.724916)
			(end 1.1049 0.724916)
			(stroke
				(width 0.1)
				(type default)
			)
			(layer "F.Fab")
		)
		(pad "1" smd rect
			(at -0.889 0 270)
			(size 1.016 1.27)
			(layers "F.Cu" "F.Mask" "F.Paste")
			(net "P12V_SSD15_R")
		)
		(pad "2" smd rect
			(at 0.889 0 270)
			(size 1.016 1.27)
			(layers "F.Cu" "F.Mask" "F.Paste")
			(net "GND")
		)
	)
	(footprint ""
		(layer "F.Cu")
		(at 324.25005 -306.074572 90)
		(property "Reference" "R1376"
			(at 0 0 90)
			(layer "F.SilkS")
			(hide yes)
			(effects
				(font
					(size 1.27 1.27)
				)
			)
		)
		(property "Value" ""
			(at 0 0 90)
			(layer "F.Fab")
			(effects
				(font
					(size 1.27 1.27)
				)
			)
		)
		(duplicate_pad_numbers_are_jumpers no)
		(fp_line
			(start 0.7874 -0.4064)
			(end 0.7874 0.4064)
			(stroke
				(width 0.1524)
				(type default)
			)
			(layer "F.SilkS")
		)
		(fp_line
			(start -0.7874 -0.4064)
			(end 0.7874 -0.4064)
			(stroke
				(width 0.1524)
				(type default)
			)
			(layer "F.SilkS")
		)
		(fp_line
			(start 0.7874 0.4064)
			(end -0.7874 0.4064)
			(stroke
				(width 0.1524)
				(type default)
			)
			(layer "F.SilkS")
		)
		(fp_line
			(start -0.7874 0.4064)
			(end -0.7874 -0.4064)
			(stroke
				(width 0.1524)
				(type default)
			)
			(layer "F.SilkS")
		)
		(fp_line
			(start -0.12065 -0.305054)
			(end -0.12065 -0.2794)
			(stroke
				(width 0.1)
				(type default)
			)
			(layer "F.Fab")
		)
		(fp_line
			(start -0.67945 -0.305054)
			(end -0.12065 -0.305054)
			(stroke
				(width 0.1)
				(type default)
			)
			(layer "F.Fab")
		)
		(fp_line
			(start 0.67945 -0.3048)
			(end 0.67945 0.3048)
			(stroke
				(width 0.1)
				(type default)
			)
			(layer "F.Fab")
		)
		(fp_line
			(start 0.12065 -0.3048)
			(end 0.67945 -0.3048)
			(stroke
				(width 0.1)
				(type default)
			)
			(layer "F.Fab")
		)
		(fp_line
			(start 0.12065 -0.2794)
			(end 0.12065 -0.3048)
			(stroke
				(width 0.1)
				(type default)
			)
			(layer "F.Fab")
		)
		(fp_line
			(start -0.12065 -0.2794)
			(end 0.12065 -0.2794)
			(stroke
				(width 0.1)
				(type default)
			)
			(layer "F.Fab")
		)
		(fp_line
			(start 0.120396 0.2794)
			(end -0.12065 0.2794)
			(stroke
				(width 0.1)
				(type default)
			)
			(layer "F.Fab")
		)
		(fp_line
			(start -0.12065 0.2794)
			(end -0.12065 0.3048)
			(stroke
				(width 0.1)
				(type default)
			)
			(layer "F.Fab")
		)
		(fp_line
			(start 0.67945 0.3048)
			(end 0.120396 0.3048)
			(stroke
				(width 0.1)
				(type default)
			)
			(layer "F.Fab")
		)
		(fp_line
			(start 0.120396 0.3048)
			(end 0.120396 0.2794)
			(stroke
				(width 0.1)
				(type default)
			)
			(layer "F.Fab")
		)
		(fp_line
			(start -0.12065 0.3048)
			(end -0.67945 0.3048)
			(stroke
				(width 0.1)
				(type default)
			)
			(layer "F.Fab")
		)
		(fp_line
			(start -0.67945 0.3048)
			(end -0.67945 -0.305054)
			(stroke
				(width 0.1)
				(type default)
			)
			(layer "F.Fab")
		)
		(pad "1" smd circle
			(at -0.40005 0 90)
			(size 0 0)
			(layers "F.Cu" "F.Mask" "F.Paste")
			(net "PEX2_SPARE6")
		)
		(pad "2" smd circle
			(at 0.40005 0 90)
			(size 0 0)
			(layers "F.Cu" "F.Mask" "F.Paste")
			(net "P1V8_PEX")
		)
	)
	(footprint ""
		(layer "F.Cu")
		(at 333.502 -201.168 -90)
		(property "Reference" "R4115"
			(at 0 0 270)
			(layer "F.SilkS")
			(hide yes)
			(effects
				(font
					(size 1.27 1.27)
				)
			)
		)
		(property "Value" ""
			(at 0 0 270)
			(layer "F.Fab")
			(effects
				(font
					(size 1.27 1.27)
				)
			)
		)
		(duplicate_pad_numbers_are_jumpers no)
		(fp_line
			(start -0.7874 0.4064)
			(end -0.7874 -0.4064)
			(stroke
				(width 0.1524)
				(type default)
			)
			(layer "F.SilkS")
		)
		(fp_line
			(start 0.7874 0.4064)
			(end -0.7874 0.4064)
			(stroke
				(width 0.1524)
				(type default)
			)
			(layer "F.SilkS")
		)
		(fp_line
			(start -0.7874 -0.4064)
			(end 0.7874 -0.4064)
			(stroke
				(width 0.1524)
				(type default)
			)
			(layer "F.SilkS")
		)
		(fp_line
			(start 0.7874 -0.4064)
			(end 0.7874 0.4064)
			(stroke
				(width 0.1524)
				(type default)
			)
			(layer "F.SilkS")
		)
		(fp_line
			(start -0.67945 0.3048)
			(end -0.67945 -0.305054)
			(stroke
				(width 0.1)
				(type default)
			)
			(layer "F.Fab")
		)
		(fp_line
			(start -0.12065 0.3048)
			(end -0.67945 0.3048)
			(stroke
				(width 0.1)
				(type default)
			)
			(layer "F.Fab")
		)
		(fp_line
			(start 0.120396 0.3048)
			(end 0.120396 0.2794)
			(stroke
				(width 0.1)
				(type default)
			)
			(layer "F.Fab")
		)
		(fp_line
			(start 0.67945 0.3048)
			(end 0.120396 0.3048)
			(stroke
				(width 0.1)
				(type default)
			)
			(layer "F.Fab")
		)
		(fp_line
			(start -0.12065 0.2794)
			(end -0.12065 0.3048)
			(stroke
				(width 0.1)
				(type default)
			)
			(layer "F.Fab")
		)
		(fp_line
			(start 0.120396 0.2794)
			(end -0.12065 0.2794)
			(stroke
				(width 0.1)
				(type default)
			)
			(layer "F.Fab")
		)
		(fp_line
			(start -0.12065 -0.2794)
			(end 0.12065 -0.2794)
			(stroke
				(width 0.1)
				(type default)
			)
			(layer "F.Fab")
		)
		(fp_line
			(start 0.12065 -0.2794)
			(end 0.12065 -0.3048)
			(stroke
				(width 0.1)
				(type default)
			)
			(layer "F.Fab")
		)
		(fp_line
			(start 0.12065 -0.3048)
			(end 0.67945 -0.3048)
			(stroke
				(width 0.1)
				(type default)
			)
			(layer "F.Fab")
		)
		(fp_line
			(start 0.67945 -0.3048)
			(end 0.67945 0.3048)
			(stroke
				(width 0.1)
				(type default)
			)
			(layer "F.Fab")
		)
		(fp_line
			(start -0.67945 -0.305054)
			(end -0.12065 -0.305054)
			(stroke
				(width 0.1)
				(type default)
			)
			(layer "F.Fab")
		)
		(fp_line
			(start -0.12065 -0.305054)
			(end -0.12065 -0.2794)
			(stroke
				(width 0.1)
				(type default)
			)
			(layer "F.Fab")
		)
		(pad "1" smd circle
			(at -0.40005 0 270)
			(size 0 0)
			(layers "F.Cu" "F.Mask" "F.Paste")
			(net "SSD8_PWR_EN")
		)
		(pad "2" smd circle
			(at 0.40005 0 270)
			(size 0 0)
			(layers "F.Cu" "F.Mask" "F.Paste")
			(net "SSD8_PWR_EN_R")
		)
	)
	(footprint ""
		(layer "F.Cu")
		(at 373.641874 -261.026402 180)
		(property "Reference" "C3592"
			(at 0 0 180)
			(layer "F.SilkS")
			(hide yes)
			(effects
				(font
					(size 1.27 1.27)
				)
			)
		)
		(property "Value" ""
			(at 0 0 180)
			(layer "F.Fab")
			(effects
				(font
					(size 1.27 1.27)
				)
			)
		)
		(duplicate_pad_numbers_are_jumpers no)
		(fp_line
			(start 1.2954 0.5842)
			(end -1.2954 0.5842)
			(stroke
				(width 0.1524)
				(type default)
			)
			(layer "F.SilkS")
		)
		(fp_line
			(start 1.2954 -0.5842)
			(end 1.2954 0.5842)
			(stroke
				(width 0.1524)
				(type default)
			)
			(layer "F.SilkS")
		)
		(fp_line
			(start -1.2954 0.5842)
			(end -1.2954 -0.5842)
			(stroke
				(width 0.1524)
				(type default)
			)
			(layer "F.SilkS")
		)
		(fp_line
			(start -1.2954 -0.5842)
			(end 1.2954 -0.5842)
			(stroke
				(width 0.1524)
				(type default)
			)
			(layer "F.SilkS")
		)
		(fp_line
			(start 1.1938 0.4064)
			(end 0.8636 0.4064)
			(stroke
				(width 0.1)
				(type default)
			)
			(layer "F.Fab")
		)
		(fp_line
			(start 1.1938 -0.4064)
			(end 1.1938 0.4064)
			(stroke
				(width 0.1)
				(type default)
			)
			(layer "F.Fab")
		)
		(fp_line
			(start 0.8636 0.4572)
			(end -0.8636 0.4572)
			(stroke
				(width 0.1)
				(type default)
			)
			(layer "F.Fab")
		)
		(fp_line
			(start 0.8636 0.4064)
			(end 0.8636 0.4572)
			(stroke
				(width 0.1)
				(type default)
			)
			(layer "F.Fab")
		)
		(fp_line
			(start 0.8636 -0.4064)
			(end 1.1938 -0.4064)
			(stroke
				(width 0.1)
				(type default)
			)
			(layer "F.Fab")
		)
		(fp_line
			(start 0.8636 -0.4572)
			(end 0.8636 -0.4064)
			(stroke
				(width 0.1)
				(type default)
			)
			(layer "F.Fab")
		)
		(fp_line
			(start -0.8636 0.4572)
			(end -0.8636 0.4064)
			(stroke
				(width 0.1)
				(type default)
			)
			(layer "F.Fab")
		)
		(fp_line
			(start -0.8636 0.4064)
			(end -1.1938 0.4064)
			(stroke
				(width 0.1)
				(type default)
			)
			(layer "F.Fab")
		)
		(fp_line
			(start -0.8636 -0.4064)
			(end -0.8636 -0.4572)
			(stroke
				(width 0.1)
				(type default)
			)
			(layer "F.Fab")
		)
		(fp_line
			(start -0.8636 -0.4572)
			(end 0.8636 -0.4572)
			(stroke
				(width 0.1)
				(type default)
			)
			(layer "F.Fab")
		)
		(fp_line
			(start -1.1938 0.4064)
			(end -1.1938 -0.4064)
			(stroke
				(width 0.1)
				(type default)
			)
			(layer "F.Fab")
		)
		(fp_line
			(start -1.1938 -0.4064)
			(end -0.8636 -0.4064)
			(stroke
				(width 0.1)
				(type default)
			)
			(layer "F.Fab")
		)
		(pad "1" smd rect
			(at -0.7366 0 90)
			(size 0.7112 0.8128)
			(layers "F.Cu" "F.Mask" "F.Paste")
			(net "P1V8_VDDA_PEX3")
		)
		(pad "2" smd rect
			(at 0.7366 0 90)
			(size 0.7112 0.8128)
			(layers "F.Cu" "F.Mask" "F.Paste")
			(net "GND")
		)
	)
	(footprint ""
		(layer "F.Cu")
		(at 417.219892 -232.979214 180)
		(property "Reference" "R6618"
			(at 0 0 180)
			(layer "F.SilkS")
			(hide yes)
			(effects
				(font
					(size 1.27 1.27)
				)
			)
		)
		(property "Value" ""
			(at 0 0 180)
			(layer "F.Fab")
			(effects
				(font
					(size 1.27 1.27)
				)
			)
		)
		(duplicate_pad_numbers_are_jumpers no)
		(fp_line
			(start 0.7874 0.4064)
			(end -0.7874 0.4064)
			(stroke
				(width 0.1524)
				(type default)
			)
			(layer "F.SilkS")
		)
		(fp_line
			(start 0.7874 -0.4064)
			(end 0.7874 0.4064)
			(stroke
				(width 0.1524)
				(type default)
			)
			(layer "F.SilkS")
		)
		(fp_line
			(start -0.7874 0.4064)
			(end -0.7874 -0.4064)
			(stroke
				(width 0.1524)
				(type default)
			)
			(layer "F.SilkS")
		)
		(fp_line
			(start -0.7874 -0.4064)
			(end 0.7874 -0.4064)
			(stroke
				(width 0.1524)
				(type default)
			)
			(layer "F.SilkS")
		)
		(fp_line
			(start 0.67945 0.3048)
			(end 0.120396 0.3048)
			(stroke
				(width 0.1)
				(type default)
			)
			(layer "F.Fab")
		)
		(fp_line
			(start 0.67945 -0.3048)
			(end 0.67945 0.3048)
			(stroke
				(width 0.1)
				(type default)
			)
			(layer "F.Fab")
		)
		(fp_line
			(start 0.12065 -0.2794)
			(end 0.12065 -0.3048)
			(stroke
				(width 0.1)
				(type default)
			)
			(layer "F.Fab")
		)
		(fp_line
			(start 0.12065 -0.3048)
			(end 0.67945 -0.3048)
			(stroke
				(width 0.1)
				(type default)
			)
			(layer "F.Fab")
		)
		(fp_line
			(start 0.120396 0.3048)
			(end 0.120396 0.2794)
			(stroke
				(width 0.1)
				(type default)
			)
			(layer "F.Fab")
		)
		(fp_line
			(start 0.120396 0.2794)
			(end -0.12065 0.2794)
			(stroke
				(width 0.1)
				(type default)
			)
			(layer "F.Fab")
		)
		(fp_line
			(start -0.12065 0.3048)
			(end -0.67945 0.3048)
			(stroke
				(width 0.1)
				(type default)
			)
			(layer "F.Fab")
		)
		(fp_line
			(start -0.12065 0.2794)
			(end -0.12065 0.3048)
			(stroke
				(width 0.1)
				(type default)
			)
			(layer "F.Fab")
		)
		(fp_line
			(start -0.12065 -0.2794)
			(end 0.12065 -0.2794)
			(stroke
				(width 0.1)
				(type default)
			)
			(layer "F.Fab")
		)
		(fp_line
			(start -0.12065 -0.305054)
			(end -0.12065 -0.2794)
			(stroke
				(width 0.1)
				(type default)
			)
			(layer "F.Fab")
		)
		(fp_line
			(start -0.67945 0.3048)
			(end -0.67945 -0.305054)
			(stroke
				(width 0.1)
				(type default)
			)
			(layer "F.Fab")
		)
		(fp_line
			(start -0.67945 -0.305054)
			(end -0.12065 -0.305054)
			(stroke
				(width 0.1)
				(type default)
			)
			(layer "F.Fab")
		)
		(pad "1" smd circle
			(at -0.40005 0 180)
			(size 0 0)
			(layers "F.Cu" "F.Mask" "F.Paste")
			(net "UART_PEX3_SDB_BUF_R_TX")
		)
		(pad "2" smd circle
			(at 0.40005 0 180)
			(size 0 0)
			(layers "F.Cu" "F.Mask" "F.Paste")
			(net "UART_PEX3_SDB_BUF_R1_TX")
		)
	)
	(footprint ""
		(layer "F.Cu")
		(at 123.975114 -252.416564 90)
		(property "Reference" "R829"
			(at 0 0 90)
			(layer "F.SilkS")
			(hide yes)
			(effects
				(font
					(size 1.27 1.27)
				)
			)
		)
		(property "Value" ""
			(at 0 0 90)
			(layer "F.Fab")
			(effects
				(font
					(size 1.27 1.27)
				)
			)
		)
		(duplicate_pad_numbers_are_jumpers no)
		(fp_line
			(start 0.7874 -0.4064)
			(end 0.7874 0.4064)
			(stroke
				(width 0.1524)
				(type default)
			)
			(layer "F.SilkS")
		)
		(fp_line
			(start -0.7874 -0.4064)
			(end 0.7874 -0.4064)
			(stroke
				(width 0.1524)
				(type default)
			)
			(layer "F.SilkS")
		)
		(fp_line
			(start 0.7874 0.4064)
			(end -0.7874 0.4064)
			(stroke
				(width 0.1524)
				(type default)
			)
			(layer "F.SilkS")
		)
		(fp_line
			(start -0.7874 0.4064)
			(end -0.7874 -0.4064)
			(stroke
				(width 0.1524)
				(type default)
			)
			(layer "F.SilkS")
		)
		(fp_line
			(start -0.12065 -0.305054)
			(end -0.12065 -0.2794)
			(stroke
				(width 0.1)
				(type default)
			)
			(layer "F.Fab")
		)
		(fp_line
			(start -0.67945 -0.305054)
			(end -0.12065 -0.305054)
			(stroke
				(width 0.1)
				(type default)
			)
			(layer "F.Fab")
		)
		(fp_line
			(start 0.67945 -0.3048)
			(end 0.67945 0.3048)
			(stroke
				(width 0.1)
				(type default)
			)
			(layer "F.Fab")
		)
		(fp_line
			(start 0.12065 -0.3048)
			(end 0.67945 -0.3048)
			(stroke
				(width 0.1)
				(type default)
			)
			(layer "F.Fab")
		)
		(fp_line
			(start 0.12065 -0.2794)
			(end 0.12065 -0.3048)
			(stroke
				(width 0.1)
				(type default)
			)
			(layer "F.Fab")
		)
		(fp_line
			(start -0.12065 -0.2794)
			(end 0.12065 -0.2794)
			(stroke
				(width 0.1)
				(type default)
			)
			(layer "F.Fab")
		)
		(fp_line
			(start 0.120396 0.2794)
			(end -0.12065 0.2794)
			(stroke
				(width 0.1)
				(type default)
			)
			(layer "F.Fab")
		)
		(fp_line
			(start -0.12065 0.2794)
			(end -0.12065 0.3048)
			(stroke
				(width 0.1)
				(type default)
			)
			(layer "F.Fab")
		)
		(fp_line
			(start 0.67945 0.3048)
			(end 0.120396 0.3048)
			(stroke
				(width 0.1)
				(type default)
			)
			(layer "F.Fab")
		)
		(fp_line
			(start 0.120396 0.3048)
			(end 0.120396 0.2794)
			(stroke
				(width 0.1)
				(type default)
			)
			(layer "F.Fab")
		)
		(fp_line
			(start -0.12065 0.3048)
			(end -0.67945 0.3048)
			(stroke
				(width 0.1)
				(type default)
			)
			(layer "F.Fab")
		)
		(fp_line
			(start -0.67945 0.3048)
			(end -0.67945 -0.305054)
			(stroke
				(width 0.1)
				(type default)
			)
			(layer "F.Fab")
		)
		(pad "1" smd circle
			(at -0.40005 0 90)
			(size 0 0)
			(layers "F.Cu" "F.Mask" "F.Paste")
			(net "SMB_BIC_I2C6_MUX_VR_R_SDA")
		)
		(pad "2" smd circle
			(at 0.40005 0 90)
			(size 0 0)
			(layers "F.Cu" "F.Mask" "F.Paste")
			(net "SMB_VR_P0V8_PEX0_SDA")
		)
	)
	(footprint ""
		(layer "F.Cu")
		(at 336.042 -158.75)
		(property "Reference" "R4787"
			(at 0 0 0)
			(layer "F.SilkS")
			(hide yes)
			(effects
				(font
					(size 1.27 1.27)
				)
			)
		)
		(property "Value" ""
			(at 0 0 0)
			(layer "F.Fab")
			(effects
				(font
					(size 1.27 1.27)
				)
			)
		)
		(duplicate_pad_numbers_are_jumpers no)
		(fp_line
			(start -0.7874 -0.4064)
			(end 0.7874 -0.4064)
			(stroke
				(width 0.1524)
				(type default)
			)
			(layer "F.SilkS")
		)
		(fp_line
			(start -0.7874 0.4064)
			(end -0.7874 -0.4064)
			(stroke
				(width 0.1524)
				(type default)
			)
			(layer "F.SilkS")
		)
		(fp_line
			(start 0.7874 -0.4064)
			(end 0.7874 0.4064)
			(stroke
				(width 0.1524)
				(type default)
			)
			(layer "F.SilkS")
		)
		(fp_line
			(start 0.7874 0.4064)
			(end -0.7874 0.4064)
			(stroke
				(width 0.1524)
				(type default)
			)
			(layer "F.SilkS")
		)
		(fp_line
			(start -0.67945 -0.305054)
			(end -0.12065 -0.305054)
			(stroke
				(width 0.1)
				(type default)
			)
			(layer "F.Fab")
		)
		(fp_line
			(start -0.67945 0.3048)
			(end -0.67945 -0.305054)
			(stroke
				(width 0.1)
				(type default)
			)
			(layer "F.Fab")
		)
		(fp_line
			(start -0.12065 -0.305054)
			(end -0.12065 -0.2794)
			(stroke
				(width 0.1)
				(type default)
			)
			(layer "F.Fab")
		)
		(fp_line
			(start -0.12065 -0.2794)
			(end 0.12065 -0.2794)
			(stroke
				(width 0.1)
				(type default)
			)
			(layer "F.Fab")
		)
		(fp_line
			(start -0.12065 0.2794)
			(end -0.12065 0.3048)
			(stroke
				(width 0.1)
				(type default)
			)
			(layer "F.Fab")
		)
		(fp_line
			(start -0.12065 0.3048)
			(end -0.67945 0.3048)
			(stroke
				(width 0.1)
				(type default)
			)
			(layer "F.Fab")
		)
		(fp_line
			(start 0.120396 0.2794)
			(end -0.12065 0.2794)
			(stroke
				(width 0.1)
				(type default)
			)
			(layer "F.Fab")
		)
		(fp_line
			(start 0.120396 0.3048)
			(end 0.120396 0.2794)
			(stroke
				(width 0.1)
				(type default)
			)
			(layer "F.Fab")
		)
		(fp_line
			(start 0.12065 -0.3048)
			(end 0.67945 -0.3048)
			(stroke
				(width 0.1)
				(type default)
			)
			(layer "F.Fab")
		)
		(fp_line
			(start 0.12065 -0.2794)
			(end 0.12065 -0.3048)
			(stroke
				(width 0.1)
				(type default)
			)
			(layer "F.Fab")
		)
		(fp_line
			(start 0.67945 -0.3048)
			(end 0.67945 0.3048)
			(stroke
				(width 0.1)
				(type default)
			)
			(layer "F.Fab")
		)
		(fp_line
			(start 0.67945 0.3048)
			(end 0.120396 0.3048)
			(stroke
				(width 0.1)
				(type default)
			)
			(layer "F.Fab")
		)
		(pad "1" smd circle
			(at -0.40005 0)
			(size 0 0)
			(layers "F.Cu" "F.Mask" "F.Paste")
			(net "P3V3_AUX")
		)
		(pad "2" smd circle
			(at 0.40005 0)
			(size 0 0)
			(layers "F.Cu" "F.Mask" "F.Paste")
			(net "SSD12_PEX_PWR_EN_R")
		)
	)
	(footprint ""
		(layer "F.Cu")
		(at 361.188 -185.166 180)
		(property "Reference" "R4647"
			(at 0 0 180)
			(layer "F.SilkS")
			(hide yes)
			(effects
				(font
					(size 1.27 1.27)
				)
			)
		)
		(property "Value" ""
			(at 0 0 180)
			(layer "F.Fab")
			(effects
				(font
					(size 1.27 1.27)
				)
			)
		)
		(duplicate_pad_numbers_are_jumpers no)
		(fp_line
			(start 0.7874 0.4064)
			(end -0.7874 0.4064)
			(stroke
				(width 0.1524)
				(type default)
			)
			(layer "F.SilkS")
		)
		(fp_line
			(start 0.7874 -0.4064)
			(end 0.7874 0.4064)
			(stroke
				(width 0.1524)
				(type default)
			)
			(layer "F.SilkS")
		)
		(fp_line
			(start -0.7874 0.4064)
			(end -0.7874 -0.4064)
			(stroke
				(width 0.1524)
				(type default)
			)
			(layer "F.SilkS")
		)
		(fp_line
			(start -0.7874 -0.4064)
			(end 0.7874 -0.4064)
			(stroke
				(width 0.1524)
				(type default)
			)
			(layer "F.SilkS")
		)
		(fp_line
			(start 0.67945 0.3048)
			(end 0.120396 0.3048)
			(stroke
				(width 0.1)
				(type default)
			)
			(layer "F.Fab")
		)
		(fp_line
			(start 0.67945 -0.3048)
			(end 0.67945 0.3048)
			(stroke
				(width 0.1)
				(type default)
			)
			(layer "F.Fab")
		)
		(fp_line
			(start 0.12065 -0.2794)
			(end 0.12065 -0.3048)
			(stroke
				(width 0.1)
				(type default)
			)
			(layer "F.Fab")
		)
		(fp_line
			(start 0.12065 -0.3048)
			(end 0.67945 -0.3048)
			(stroke
				(width 0.1)
				(type default)
			)
			(layer "F.Fab")
		)
		(fp_line
			(start 0.120396 0.3048)
			(end 0.120396 0.2794)
			(stroke
				(width 0.1)
				(type default)
			)
			(layer "F.Fab")
		)
		(fp_line
			(start 0.120396 0.2794)
			(end -0.12065 0.2794)
			(stroke
				(width 0.1)
				(type default)
			)
			(layer "F.Fab")
		)
		(fp_line
			(start -0.12065 0.3048)
			(end -0.67945 0.3048)
			(stroke
				(width 0.1)
				(type default)
			)
			(layer "F.Fab")
		)
		(fp_line
			(start -0.12065 0.2794)
			(end -0.12065 0.3048)
			(stroke
				(width 0.1)
				(type default)
			)
			(layer "F.Fab")
		)
		(fp_line
			(start -0.12065 -0.2794)
			(end 0.12065 -0.2794)
			(stroke
				(width 0.1)
				(type default)
			)
			(layer "F.Fab")
		)
		(fp_line
			(start -0.12065 -0.305054)
			(end -0.12065 -0.2794)
			(stroke
				(width 0.1)
				(type default)
			)
			(layer "F.Fab")
		)
		(fp_line
			(start -0.67945 0.3048)
			(end -0.67945 -0.305054)
			(stroke
				(width 0.1)
				(type default)
			)
			(layer "F.Fab")
		)
		(fp_line
			(start -0.67945 -0.305054)
			(end -0.12065 -0.305054)
			(stroke
				(width 0.1)
				(type default)
			)
			(layer "F.Fab")
		)
		(pad "1" smd circle
			(at -0.40005 0 180)
			(size 0 0)
			(layers "F.Cu" "F.Mask" "F.Paste")
			(net "SSD3_PEX_PWR_EN")
		)
		(pad "2" smd circle
			(at 0.40005 0 180)
			(size 0 0)
			(layers "F.Cu" "F.Mask" "F.Paste")
			(net "SSD3_PEX_PWR_EN_R")
		)
	)
	(footprint ""
		(layer "F.Cu")
		(at 310.443626 -44.87291)
		(property "Reference" "R617"
			(at 0 0 0)
			(layer "F.SilkS")
			(hide yes)
			(effects
				(font
					(size 1.27 1.27)
				)
			)
		)
		(property "Value" ""
			(at 0 0 0)
			(layer "F.Fab")
			(effects
				(font
					(size 1.27 1.27)
				)
			)
		)
		(duplicate_pad_numbers_are_jumpers no)
		(fp_line
			(start -0.7874 -0.4064)
			(end 0.7874 -0.4064)
			(stroke
				(width 0.1524)
				(type default)
			)
			(layer "F.SilkS")
		)
		(fp_line
			(start -0.7874 0.4064)
			(end -0.7874 -0.4064)
			(stroke
				(width 0.1524)
				(type default)
			)
			(layer "F.SilkS")
		)
		(fp_line
			(start 0.7874 -0.4064)
			(end 0.7874 0.4064)
			(stroke
				(width 0.1524)
				(type default)
			)
			(layer "F.SilkS")
		)
		(fp_line
			(start 0.7874 0.4064)
			(end -0.7874 0.4064)
			(stroke
				(width 0.1524)
				(type default)
			)
			(layer "F.SilkS")
		)
		(fp_line
			(start -0.67945 -0.305054)
			(end -0.12065 -0.305054)
			(stroke
				(width 0.1)
				(type default)
			)
			(layer "F.Fab")
		)
		(fp_line
			(start -0.67945 0.3048)
			(end -0.67945 -0.305054)
			(stroke
				(width 0.1)
				(type default)
			)
			(layer "F.Fab")
		)
		(fp_line
			(start -0.12065 -0.305054)
			(end -0.12065 -0.2794)
			(stroke
				(width 0.1)
				(type default)
			)
			(layer "F.Fab")
		)
		(fp_line
			(start -0.12065 -0.2794)
			(end 0.12065 -0.2794)
			(stroke
				(width 0.1)
				(type default)
			)
			(layer "F.Fab")
		)
		(fp_line
			(start -0.12065 0.2794)
			(end -0.12065 0.3048)
			(stroke
				(width 0.1)
				(type default)
			)
			(layer "F.Fab")
		)
		(fp_line
			(start -0.12065 0.3048)
			(end -0.67945 0.3048)
			(stroke
				(width 0.1)
				(type default)
			)
			(layer "F.Fab")
		)
		(fp_line
			(start 0.120396 0.2794)
			(end -0.12065 0.2794)
			(stroke
				(width 0.1)
				(type default)
			)
			(layer "F.Fab")
		)
		(fp_line
			(start 0.120396 0.3048)
			(end 0.120396 0.2794)
			(stroke
				(width 0.1)
				(type default)
			)
			(layer "F.Fab")
		)
		(fp_line
			(start 0.12065 -0.3048)
			(end 0.67945 -0.3048)
			(stroke
				(width 0.1)
				(type default)
			)
			(layer "F.Fab")
		)
		(fp_line
			(start 0.12065 -0.2794)
			(end 0.12065 -0.3048)
			(stroke
				(width 0.1)
				(type default)
			)
			(layer "F.Fab")
		)
		(fp_line
			(start 0.67945 -0.3048)
			(end 0.67945 0.3048)
			(stroke
				(width 0.1)
				(type default)
			)
			(layer "F.Fab")
		)
		(fp_line
			(start 0.67945 0.3048)
			(end 0.120396 0.3048)
			(stroke
				(width 0.1)
				(type default)
			)
			(layer "F.Fab")
		)
		(pad "1" smd circle
			(at -0.40005 0)
			(size 0 0)
			(layers "F.Cu" "F.Mask" "F.Paste")
			(net "SSD10_ADC_A0")
		)
		(pad "2" smd circle
			(at 0.40005 0)
			(size 0 0)
			(layers "F.Cu" "F.Mask" "F.Paste")
			(net "P3V3_AUX")
		)
	)
	(footprint ""
		(layer "F.Cu")
		(at 226.19716 -266.794996)
		(property "Reference" "L100"
			(at 0 0 0)
			(layer "F.SilkS")
			(hide yes)
			(effects
				(font
					(size 1.27 1.27)
				)
			)
		)
		(property "Value" ""
			(at 0 0 0)
			(layer "F.Fab")
			(effects
				(font
					(size 1.27 1.27)
				)
			)
		)
		(duplicate_pad_numbers_are_jumpers no)
		(fp_line
			(start -2.248154 -4.9911)
			(end -2.248154 -1.761236)
			(stroke
				(width 0.1524)
				(type default)
			)
			(layer "F.SilkS")
		)
		(fp_line
			(start -2.248154 1.62052)
			(end -2.248154 4.9911)
			(stroke
				(width 0.1524)
				(type default)
			)
			(layer "F.SilkS")
		)
		(fp_line
			(start -2.248154 4.9911)
			(end 2.248154 4.9911)
			(stroke
				(width 0.1524)
				(type default)
			)
			(layer "F.SilkS")
		)
		(fp_line
			(start 2.248154 -4.9911)
			(end -2.248154 -4.9911)
			(stroke
				(width 0.1524)
				(type default)
			)
			(layer "F.SilkS")
		)
		(fp_line
			(start 2.248154 -1.783334)
			(end 2.248154 -4.9911)
			(stroke
				(width 0.1524)
				(type default)
			)
			(layer "F.SilkS")
		)
		(fp_line
			(start 2.248154 4.9911)
			(end 2.248154 1.477518)
			(stroke
				(width 0.1524)
				(type default)
			)
			(layer "F.SilkS")
		)
		(fp_line
			(start -1.700022 -0.899922)
			(end -1.700022 0.899922)
			(stroke
				(width 0.1)
				(type default)
			)
			(layer "F.Fab")
		)
		(fp_line
			(start -1.700022 0.899922)
			(end 1.700022 0.899922)
			(stroke
				(width 0.1)
				(type default)
			)
			(layer "F.Fab")
		)
		(fp_line
			(start 1.700022 -0.899922)
			(end -1.700022 -0.899922)
			(stroke
				(width 0.1)
				(type default)
			)
			(layer "F.Fab")
		)
		(fp_line
			(start 1.700022 0.899922)
			(end 1.700022 -0.899922)
			(stroke
				(width 0.1)
				(type default)
			)
			(layer "F.Fab")
		)
		(pad "1" smd rect
			(at -1.575054 0)
			(size 1.1684 9.8044)
			(layers "F.Cu" "F.Mask" "F.Paste")
			(net "P1V25_PEX1")
		)
		(pad "2" smd rect
			(at 1.575054 0)
			(size 1.1684 9.8044)
			(layers "F.Cu" "F.Mask" "F.Paste")
			(net "P1V25_SERDES_VDDPLL_PEX1")
		)
	)
	(footprint ""
		(layer "F.Cu")
		(at 441.200032 -289.230816 -90)
		(property "Reference" "R3997"
			(at 0 0 270)
			(layer "F.SilkS")
			(hide yes)
			(effects
				(font
					(size 1.27 1.27)
				)
			)
		)
		(property "Value" ""
			(at 0 0 270)
			(layer "F.Fab")
			(effects
				(font
					(size 1.27 1.27)
				)
			)
		)
		(duplicate_pad_numbers_are_jumpers no)
		(fp_line
			(start -0.7874 0.4064)
			(end -0.7874 -0.4064)
			(stroke
				(width 0.1524)
				(type default)
			)
			(layer "F.SilkS")
		)
		(fp_line
			(start 0.7874 0.4064)
			(end -0.7874 0.4064)
			(stroke
				(width 0.1524)
				(type default)
			)
			(layer "F.SilkS")
		)
		(fp_line
			(start -0.7874 -0.4064)
			(end 0.7874 -0.4064)
			(stroke
				(width 0.1524)
				(type default)
			)
			(layer "F.SilkS")
		)
		(fp_line
			(start 0.7874 -0.4064)
			(end 0.7874 0.4064)
			(stroke
				(width 0.1524)
				(type default)
			)
			(layer "F.SilkS")
		)
		(fp_line
			(start -0.67945 0.3048)
			(end -0.67945 -0.305054)
			(stroke
				(width 0.1)
				(type default)
			)
			(layer "F.Fab")
		)
		(fp_line
			(start -0.12065 0.3048)
			(end -0.67945 0.3048)
			(stroke
				(width 0.1)
				(type default)
			)
			(layer "F.Fab")
		)
		(fp_line
			(start 0.120396 0.3048)
			(end 0.120396 0.2794)
			(stroke
				(width 0.1)
				(type default)
			)
			(layer "F.Fab")
		)
		(fp_line
			(start 0.67945 0.3048)
			(end 0.120396 0.3048)
			(stroke
				(width 0.1)
				(type default)
			)
			(layer "F.Fab")
		)
		(fp_line
			(start -0.12065 0.2794)
			(end -0.12065 0.3048)
			(stroke
				(width 0.1)
				(type default)
			)
			(layer "F.Fab")
		)
		(fp_line
			(start 0.120396 0.2794)
			(end -0.12065 0.2794)
			(stroke
				(width 0.1)
				(type default)
			)
			(layer "F.Fab")
		)
		(fp_line
			(start -0.12065 -0.2794)
			(end 0.12065 -0.2794)
			(stroke
				(width 0.1)
				(type default)
			)
			(layer "F.Fab")
		)
		(fp_line
			(start 0.12065 -0.2794)
			(end 0.12065 -0.3048)
			(stroke
				(width 0.1)
				(type default)
			)
			(layer "F.Fab")
		)
		(fp_line
			(start 0.12065 -0.3048)
			(end 0.67945 -0.3048)
			(stroke
				(width 0.1)
				(type default)
			)
			(layer "F.Fab")
		)
		(fp_line
			(start 0.67945 -0.3048)
			(end 0.67945 0.3048)
			(stroke
				(width 0.1)
				(type default)
			)
			(layer "F.Fab")
		)
		(fp_line
			(start -0.67945 -0.305054)
			(end -0.12065 -0.305054)
			(stroke
				(width 0.1)
				(type default)
			)
			(layer "F.Fab")
		)
		(fp_line
			(start -0.12065 -0.305054)
			(end -0.12065 -0.2794)
			(stroke
				(width 0.1)
				(type default)
			)
			(layer "F.Fab")
		)
		(pad "1" smd circle
			(at -0.40005 0 270)
			(size 0 0)
			(layers "F.Cu" "F.Mask" "F.Paste")
			(net "SMB_PEX3_HOST_LS_SCL")
		)
		(pad "2" smd circle
			(at 0.40005 0 270)
			(size 0 0)
			(layers "F.Cu" "F.Mask" "F.Paste")
			(net "P3V3_AUX")
		)
	)
	(footprint ""
		(layer "F.Cu")
		(at 221.251272 -145.974562 180)
		(property "Reference" "R4193"
			(at 0 0 180)
			(layer "F.SilkS")
			(hide yes)
			(effects
				(font
					(size 1.27 1.27)
				)
			)
		)
		(property "Value" ""
			(at 0 0 180)
			(layer "F.Fab")
			(effects
				(font
					(size 1.27 1.27)
				)
			)
		)
		(duplicate_pad_numbers_are_jumpers no)
		(fp_line
			(start 0.7874 0.4064)
			(end -0.7874 0.4064)
			(stroke
				(width 0.1524)
				(type default)
			)
			(layer "F.SilkS")
		)
		(fp_line
			(start 0.7874 -0.4064)
			(end 0.7874 0.4064)
			(stroke
				(width 0.1524)
				(type default)
			)
			(layer "F.SilkS")
		)
		(fp_line
			(start -0.7874 0.4064)
			(end -0.7874 -0.4064)
			(stroke
				(width 0.1524)
				(type default)
			)
			(layer "F.SilkS")
		)
		(fp_line
			(start -0.7874 -0.4064)
			(end 0.7874 -0.4064)
			(stroke
				(width 0.1524)
				(type default)
			)
			(layer "F.SilkS")
		)
		(fp_line
			(start 0.67945 0.3048)
			(end 0.120396 0.3048)
			(stroke
				(width 0.1)
				(type default)
			)
			(layer "F.Fab")
		)
		(fp_line
			(start 0.67945 -0.3048)
			(end 0.67945 0.3048)
			(stroke
				(width 0.1)
				(type default)
			)
			(layer "F.Fab")
		)
		(fp_line
			(start 0.12065 -0.2794)
			(end 0.12065 -0.3048)
			(stroke
				(width 0.1)
				(type default)
			)
			(layer "F.Fab")
		)
		(fp_line
			(start 0.12065 -0.3048)
			(end 0.67945 -0.3048)
			(stroke
				(width 0.1)
				(type default)
			)
			(layer "F.Fab")
		)
		(fp_line
			(start 0.120396 0.3048)
			(end 0.120396 0.2794)
			(stroke
				(width 0.1)
				(type default)
			)
			(layer "F.Fab")
		)
		(fp_line
			(start 0.120396 0.2794)
			(end -0.12065 0.2794)
			(stroke
				(width 0.1)
				(type default)
			)
			(layer "F.Fab")
		)
		(fp_line
			(start -0.12065 0.3048)
			(end -0.67945 0.3048)
			(stroke
				(width 0.1)
				(type default)
			)
			(layer "F.Fab")
		)
		(fp_line
			(start -0.12065 0.2794)
			(end -0.12065 0.3048)
			(stroke
				(width 0.1)
				(type default)
			)
			(layer "F.Fab")
		)
		(fp_line
			(start -0.12065 -0.2794)
			(end 0.12065 -0.2794)
			(stroke
				(width 0.1)
				(type default)
			)
			(layer "F.Fab")
		)
		(fp_line
			(start -0.12065 -0.305054)
			(end -0.12065 -0.2794)
			(stroke
				(width 0.1)
				(type default)
			)
			(layer "F.Fab")
		)
		(fp_line
			(start -0.67945 0.3048)
			(end -0.67945 -0.305054)
			(stroke
				(width 0.1)
				(type default)
			)
			(layer "F.Fab")
		)
		(fp_line
			(start -0.67945 -0.305054)
			(end -0.12065 -0.305054)
			(stroke
				(width 0.1)
				(type default)
			)
			(layer "F.Fab")
		)
		(pad "1" smd circle
			(at -0.40005 0 180)
			(size 0 0)
			(layers "F.Cu" "F.Mask" "F.Paste")
			(net "PU_CK440_PEX_SHFT_LD_N")
		)
		(pad "2" smd circle
			(at 0.40005 0 180)
			(size 0 0)
			(layers "F.Cu" "F.Mask" "F.Paste")
			(net "P3V3")
		)
	)
	(footprint ""
		(layer "F.Cu")
		(at 70.673722 -356.244906 90)
		(property "Reference" "C117"
			(at 0 0 90)
			(layer "F.SilkS")
			(hide yes)
			(effects
				(font
					(size 1.27 1.27)
				)
			)
		)
		(property "Value" ""
			(at 0 0 90)
			(layer "F.Fab")
			(effects
				(font
					(size 1.27 1.27)
				)
			)
		)
		(duplicate_pad_numbers_are_jumpers no)
		(fp_line
			(start 0.299974 -0.150114)
			(end 0.299974 0.150114)
			(stroke
				(width 0.1)
				(type default)
			)
			(layer "F.Fab")
		)
		(fp_line
			(start -0.299974 -0.150114)
			(end 0.299974 -0.150114)
			(stroke
				(width 0.1)
				(type default)
			)
			(layer "F.Fab")
		)
		(fp_line
			(start 0.299974 0.150114)
			(end -0.299974 0.150114)
			(stroke
				(width 0.1)
				(type default)
			)
			(layer "F.Fab")
		)
		(fp_line
			(start -0.299974 0.150114)
			(end -0.299974 -0.150114)
			(stroke
				(width 0.1)
				(type default)
			)
			(layer "F.Fab")
		)
		(pad "1" smd rect
			(at -0.2667 0 90)
			(size 0.3048 0.381)
			(layers "F.Cu" "F.Mask" "F.Paste")
			(net "P5E_PEX0_STN5_TX_DP<85>")
		)
		(pad "2" smd rect
			(at 0.2667 0 90)
			(size 0.3048 0.381)
			(layers "F.Cu" "F.Mask" "F.Paste")
			(net "P5E_PEX0_STN5_TX_C_DP<85>")
		)
	)
	(footprint ""
		(layer "F.Cu")
		(at 420.959534 -61.612526)
		(property "Reference" "PD121"
			(at -3.7084 -2.733548 0)
			(unlocked yes)
			(layer "F.SilkS")
			(effects
				(font
					(size 0.7874 0.5842)
					(thickness 0.1524)
				)
				(justify left)
			)
		)
		(property "Value" ""
			(at 0 0 0)
			(layer "F.Fab")
			(effects
				(font
					(size 1.27 1.27)
				)
			)
		)
		(duplicate_pad_numbers_are_jumpers no)
		(fp_line
			(start -3.656584 -1.970024)
			(end -3.656584 1.970024)
			(stroke
				(width 0.1524)
				(type default)
			)
			(layer "F.SilkS")
		)
		(fp_line
			(start -3.656584 1.970024)
			(end 4.240784 1.970024)
			(stroke
				(width 0.1524)
				(type default)
			)
			(layer "F.SilkS")
		)
		(fp_line
			(start 4.240784 -1.970024)
			(end -3.656584 -1.970024)
			(stroke
				(width 0.1524)
				(type default)
			)
			(layer "F.SilkS")
		)
		(fp_line
			(start 4.240784 1.970024)
			(end 4.240784 -1.970024)
			(stroke
				(width 0.1524)
				(type default)
			)
			(layer "F.SilkS")
		)
		(fp_poly
			(pts
				(xy 3.580384 1.970024) (xy 3.580384 -1.970024) (xy 4.240784 -1.970024) (xy 4.240784 1.970024)
			)
			(stroke
				(width 0)
				(type default)
			)
			(fill yes)
			(layer "F.SilkS")
		)
		(fp_line
			(start -2.3749 -1.970024)
			(end -2.3749 1.970024)
			(stroke
				(width 0.1)
				(type default)
			)
			(layer "F.Fab")
		)
		(fp_line
			(start -2.3749 1.970024)
			(end 2.3749 1.970024)
			(stroke
				(width 0.1)
				(type default)
			)
			(layer "F.Fab")
		)
		(fp_line
			(start 2.3749 -1.970024)
			(end -2.3749 -1.970024)
			(stroke
				(width 0.1)
				(type default)
			)
			(layer "F.Fab")
		)
		(fp_line
			(start 2.3749 1.970024)
			(end 2.3749 -1.970024)
			(stroke
				(width 0.1)
				(type default)
			)
			(layer "F.Fab")
		)
		(fp_text user "+"
			(at -4.9784 -0.23495 0)
			(unlocked yes)
			(layer "F.Fab")
			(effects
				(font
					(size 1.905 1.4224)
					(thickness 0.1524)
				)
				(justify left)
			)
		)
		(fp_text user "-"
			(at 4.1656 -0.23495 0)
			(unlocked yes)
			(layer "F.Fab")
			(effects
				(font
					(size 1.905 1.4224)
					(thickness 0.1524)
				)
				(justify left)
			)
		)
		(pad "A" smd rect
			(at -2.450084 0)
			(size 2.159 2.2606)
			(layers "F.Cu" "F.Mask" "F.Paste")
			(net "GND")
		)
		(pad "C" smd rect
			(at 2.450084 0)
			(size 2.159 2.2606)
			(layers "F.Cu" "F.Mask" "F.Paste")
			(net "P12V_AUX")
		)
	)
	(footprint ""
		(layer "F.Cu")
		(at 131.422648 -193.143378 90)
		(property "Reference" "C4448"
			(at 0 0 90)
			(layer "F.SilkS")
			(hide yes)
			(effects
				(font
					(size 1.27 1.27)
				)
			)
		)
		(property "Value" ""
			(at 0 0 90)
			(layer "F.Fab")
			(effects
				(font
					(size 1.27 1.27)
				)
			)
		)
		(duplicate_pad_numbers_are_jumpers no)
		(fp_line
			(start 0.7874 -0.4064)
			(end 0.7874 0.4064)
			(stroke
				(width 0.1524)
				(type default)
			)
			(layer "F.SilkS")
		)
		(fp_line
			(start -0.7874 -0.4064)
			(end 0.7874 -0.4064)
			(stroke
				(width 0.1524)
				(type default)
			)
			(layer "F.SilkS")
		)
		(fp_line
			(start 0.7874 0.4064)
			(end -0.7874 0.4064)
			(stroke
				(width 0.1524)
				(type default)
			)
			(layer "F.SilkS")
		)
		(fp_line
			(start -0.7874 0.4064)
			(end -0.7874 -0.4064)
			(stroke
				(width 0.1524)
				(type default)
			)
			(layer "F.SilkS")
		)
		(fp_line
			(start -0.12065 -0.305054)
			(end -0.12065 -0.2794)
			(stroke
				(width 0.1)
				(type default)
			)
			(layer "F.Fab")
		)
		(fp_line
			(start -0.67945 -0.305054)
			(end -0.12065 -0.305054)
			(stroke
				(width 0.1)
				(type default)
			)
			(layer "F.Fab")
		)
		(fp_line
			(start 0.67945 -0.3048)
			(end 0.67945 0.3048)
			(stroke
				(width 0.1)
				(type default)
			)
			(layer "F.Fab")
		)
		(fp_line
			(start 0.12065 -0.3048)
			(end 0.67945 -0.3048)
			(stroke
				(width 0.1)
				(type default)
			)
			(layer "F.Fab")
		)
		(fp_line
			(start 0.12065 -0.2794)
			(end 0.12065 -0.3048)
			(stroke
				(width 0.1)
				(type default)
			)
			(layer "F.Fab")
		)
		(fp_line
			(start -0.12065 -0.2794)
			(end 0.12065 -0.2794)
			(stroke
				(width 0.1)
				(type default)
			)
			(layer "F.Fab")
		)
		(fp_line
			(start 0.120396 0.2794)
			(end -0.12065 0.2794)
			(stroke
				(width 0.1)
				(type default)
			)
			(layer "F.Fab")
		)
		(fp_line
			(start -0.12065 0.2794)
			(end -0.12065 0.3048)
			(stroke
				(width 0.1)
				(type default)
			)
			(layer "F.Fab")
		)
		(fp_line
			(start 0.67945 0.3048)
			(end 0.120396 0.3048)
			(stroke
				(width 0.1)
				(type default)
			)
			(layer "F.Fab")
		)
		(fp_line
			(start 0.120396 0.3048)
			(end 0.120396 0.2794)
			(stroke
				(width 0.1)
				(type default)
			)
			(layer "F.Fab")
		)
		(fp_line
			(start -0.12065 0.3048)
			(end -0.67945 0.3048)
			(stroke
				(width 0.1)
				(type default)
			)
			(layer "F.Fab")
		)
		(fp_line
			(start -0.67945 0.3048)
			(end -0.67945 -0.305054)
			(stroke
				(width 0.1)
				(type default)
			)
			(layer "F.Fab")
		)
		(pad "1" smd circle
			(at -0.40005 0 90)
			(size 0 0)
			(layers "F.Cu" "F.Mask" "F.Paste")
			(net "GND")
		)
		(pad "2" smd circle
			(at 0.40005 0 90)
			(size 0 0)
			(layers "F.Cu" "F.Mask" "F.Paste")
			(net "P3V3_AUX")
		)
	)
	(footprint ""
		(layer "F.Cu")
		(at 235.871512 -231.416606 90)
		(property "Reference" "R4521"
			(at 0 0 90)
			(layer "F.SilkS")
			(hide yes)
			(effects
				(font
					(size 1.27 1.27)
				)
			)
		)
		(property "Value" ""
			(at 0 0 90)
			(layer "F.Fab")
			(effects
				(font
					(size 1.27 1.27)
				)
			)
		)
		(duplicate_pad_numbers_are_jumpers no)
		(fp_line
			(start 0.7874 -0.4064)
			(end 0.7874 0.4064)
			(stroke
				(width 0.1524)
				(type default)
			)
			(layer "F.SilkS")
		)
		(fp_line
			(start -0.7874 -0.4064)
			(end 0.7874 -0.4064)
			(stroke
				(width 0.1524)
				(type default)
			)
			(layer "F.SilkS")
		)
		(fp_line
			(start 0.7874 0.4064)
			(end -0.7874 0.4064)
			(stroke
				(width 0.1524)
				(type default)
			)
			(layer "F.SilkS")
		)
		(fp_line
			(start -0.7874 0.4064)
			(end -0.7874 -0.4064)
			(stroke
				(width 0.1524)
				(type default)
			)
			(layer "F.SilkS")
		)
		(fp_line
			(start -0.12065 -0.305054)
			(end -0.12065 -0.2794)
			(stroke
				(width 0.1)
				(type default)
			)
			(layer "F.Fab")
		)
		(fp_line
			(start -0.67945 -0.305054)
			(end -0.12065 -0.305054)
			(stroke
				(width 0.1)
				(type default)
			)
			(layer "F.Fab")
		)
		(fp_line
			(start 0.67945 -0.3048)
			(end 0.67945 0.3048)
			(stroke
				(width 0.1)
				(type default)
			)
			(layer "F.Fab")
		)
		(fp_line
			(start 0.12065 -0.3048)
			(end 0.67945 -0.3048)
			(stroke
				(width 0.1)
				(type default)
			)
			(layer "F.Fab")
		)
		(fp_line
			(start 0.12065 -0.2794)
			(end 0.12065 -0.3048)
			(stroke
				(width 0.1)
				(type default)
			)
			(layer "F.Fab")
		)
		(fp_line
			(start -0.12065 -0.2794)
			(end 0.12065 -0.2794)
			(stroke
				(width 0.1)
				(type default)
			)
			(layer "F.Fab")
		)
		(fp_line
			(start 0.120396 0.2794)
			(end -0.12065 0.2794)
			(stroke
				(width 0.1)
				(type default)
			)
			(layer "F.Fab")
		)
		(fp_line
			(start -0.12065 0.2794)
			(end -0.12065 0.3048)
			(stroke
				(width 0.1)
				(type default)
			)
			(layer "F.Fab")
		)
		(fp_line
			(start 0.67945 0.3048)
			(end 0.120396 0.3048)
			(stroke
				(width 0.1)
				(type default)
			)
			(layer "F.Fab")
		)
		(fp_line
			(start 0.120396 0.3048)
			(end 0.120396 0.2794)
			(stroke
				(width 0.1)
				(type default)
			)
			(layer "F.Fab")
		)
		(fp_line
			(start -0.12065 0.3048)
			(end -0.67945 0.3048)
			(stroke
				(width 0.1)
				(type default)
			)
			(layer "F.Fab")
		)
		(fp_line
			(start -0.67945 0.3048)
			(end -0.67945 -0.305054)
			(stroke
				(width 0.1)
				(type default)
			)
			(layer "F.Fab")
		)
		(pad "1" smd circle
			(at -0.40005 0 90)
			(size 0 0)
			(layers "F.Cu" "F.Mask" "F.Paste")
			(net "SSD7_PWRDIS_BIC")
		)
		(pad "2" smd circle
			(at 0.40005 0 90)
			(size 0 0)
			(layers "F.Cu" "F.Mask" "F.Paste")
			(net "SSD7_PWRDIS_BIC_R")
		)
	)
	(footprint ""
		(layer "F.Cu")
		(at 360.401362 -118.343426 -90)
		(property "Reference" "R6050"
			(at 0 0 270)
			(layer "F.SilkS")
			(hide yes)
			(effects
				(font
					(size 1.27 1.27)
				)
			)
		)
		(property "Value" ""
			(at 0 0 270)
			(layer "F.Fab")
			(effects
				(font
					(size 1.27 1.27)
				)
			)
		)
		(duplicate_pad_numbers_are_jumpers no)
		(fp_line
			(start -0.7874 0.4064)
			(end -0.7874 -0.4064)
			(stroke
				(width 0.1524)
				(type default)
			)
			(layer "F.SilkS")
		)
		(fp_line
			(start 0.7874 0.4064)
			(end -0.7874 0.4064)
			(stroke
				(width 0.1524)
				(type default)
			)
			(layer "F.SilkS")
		)
		(fp_line
			(start -0.7874 -0.4064)
			(end 0.7874 -0.4064)
			(stroke
				(width 0.1524)
				(type default)
			)
			(layer "F.SilkS")
		)
		(fp_line
			(start 0.7874 -0.4064)
			(end 0.7874 0.4064)
			(stroke
				(width 0.1524)
				(type default)
			)
			(layer "F.SilkS")
		)
		(fp_line
			(start -0.67945 0.3048)
			(end -0.67945 -0.305054)
			(stroke
				(width 0.1)
				(type default)
			)
			(layer "F.Fab")
		)
		(fp_line
			(start -0.12065 0.3048)
			(end -0.67945 0.3048)
			(stroke
				(width 0.1)
				(type default)
			)
			(layer "F.Fab")
		)
		(fp_line
			(start 0.120396 0.3048)
			(end 0.120396 0.2794)
			(stroke
				(width 0.1)
				(type default)
			)
			(layer "F.Fab")
		)
		(fp_line
			(start 0.67945 0.3048)
			(end 0.120396 0.3048)
			(stroke
				(width 0.1)
				(type default)
			)
			(layer "F.Fab")
		)
		(fp_line
			(start -0.12065 0.2794)
			(end -0.12065 0.3048)
			(stroke
				(width 0.1)
				(type default)
			)
			(layer "F.Fab")
		)
		(fp_line
			(start 0.120396 0.2794)
			(end -0.12065 0.2794)
			(stroke
				(width 0.1)
				(type default)
			)
			(layer "F.Fab")
		)
		(fp_line
			(start -0.12065 -0.2794)
			(end 0.12065 -0.2794)
			(stroke
				(width 0.1)
				(type default)
			)
			(layer "F.Fab")
		)
		(fp_line
			(start 0.12065 -0.2794)
			(end 0.12065 -0.3048)
			(stroke
				(width 0.1)
				(type default)
			)
			(layer "F.Fab")
		)
		(fp_line
			(start 0.12065 -0.3048)
			(end 0.67945 -0.3048)
			(stroke
				(width 0.1)
				(type default)
			)
			(layer "F.Fab")
		)
		(fp_line
			(start 0.67945 -0.3048)
			(end 0.67945 0.3048)
			(stroke
				(width 0.1)
				(type default)
			)
			(layer "F.Fab")
		)
		(fp_line
			(start -0.67945 -0.305054)
			(end -0.12065 -0.305054)
			(stroke
				(width 0.1)
				(type default)
			)
			(layer "F.Fab")
		)
		(fp_line
			(start -0.12065 -0.305054)
			(end -0.12065 -0.2794)
			(stroke
				(width 0.1)
				(type default)
			)
			(layer "F.Fab")
		)
		(pad "1" smd circle
			(at -0.40005 0 270)
			(size 0 0)
			(layers "F.Cu" "F.Mask" "F.Paste")
			(net "P3V3_NIC6")
		)
		(pad "2" smd circle
			(at 0.40005 0 270)
			(size 0 0)
			(layers "F.Cu" "F.Mask" "F.Paste")
			(net "P3V3_NIC6_PG_G1")
		)
	)
	(footprint ""
		(layer "F.Cu")
		(at 359.156 -182.118)
		(property "Reference" "R4681"
			(at 0 0 0)
			(layer "F.SilkS")
			(hide yes)
			(effects
				(font
					(size 1.27 1.27)
				)
			)
		)
		(property "Value" ""
			(at 0 0 0)
			(layer "F.Fab")
			(effects
				(font
					(size 1.27 1.27)
				)
			)
		)
		(duplicate_pad_numbers_are_jumpers no)
		(fp_line
			(start -0.7874 -0.4064)
			(end 0.7874 -0.4064)
			(stroke
				(width 0.1524)
				(type default)
			)
			(layer "F.SilkS")
		)
		(fp_line
			(start -0.7874 0.4064)
			(end -0.7874 -0.4064)
			(stroke
				(width 0.1524)
				(type default)
			)
			(layer "F.SilkS")
		)
		(fp_line
			(start 0.7874 -0.4064)
			(end 0.7874 0.4064)
			(stroke
				(width 0.1524)
				(type default)
			)
			(layer "F.SilkS")
		)
		(fp_line
			(start 0.7874 0.4064)
			(end -0.7874 0.4064)
			(stroke
				(width 0.1524)
				(type default)
			)
			(layer "F.SilkS")
		)
		(fp_line
			(start -0.67945 -0.305054)
			(end -0.12065 -0.305054)
			(stroke
				(width 0.1)
				(type default)
			)
			(layer "F.Fab")
		)
		(fp_line
			(start -0.67945 0.3048)
			(end -0.67945 -0.305054)
			(stroke
				(width 0.1)
				(type default)
			)
			(layer "F.Fab")
		)
		(fp_line
			(start -0.12065 -0.305054)
			(end -0.12065 -0.2794)
			(stroke
				(width 0.1)
				(type default)
			)
			(layer "F.Fab")
		)
		(fp_line
			(start -0.12065 -0.2794)
			(end 0.12065 -0.2794)
			(stroke
				(width 0.1)
				(type default)
			)
			(layer "F.Fab")
		)
		(fp_line
			(start -0.12065 0.2794)
			(end -0.12065 0.3048)
			(stroke
				(width 0.1)
				(type default)
			)
			(layer "F.Fab")
		)
		(fp_line
			(start -0.12065 0.3048)
			(end -0.67945 0.3048)
			(stroke
				(width 0.1)
				(type default)
			)
			(layer "F.Fab")
		)
		(fp_line
			(start 0.120396 0.2794)
			(end -0.12065 0.2794)
			(stroke
				(width 0.1)
				(type default)
			)
			(layer "F.Fab")
		)
		(fp_line
			(start 0.120396 0.3048)
			(end 0.120396 0.2794)
			(stroke
				(width 0.1)
				(type default)
			)
			(layer "F.Fab")
		)
		(fp_line
			(start 0.12065 -0.3048)
			(end 0.67945 -0.3048)
			(stroke
				(width 0.1)
				(type default)
			)
			(layer "F.Fab")
		)
		(fp_line
			(start 0.12065 -0.2794)
			(end 0.12065 -0.3048)
			(stroke
				(width 0.1)
				(type default)
			)
			(layer "F.Fab")
		)
		(fp_line
			(start 0.67945 -0.3048)
			(end 0.67945 0.3048)
			(stroke
				(width 0.1)
				(type default)
			)
			(layer "F.Fab")
		)
		(fp_line
			(start 0.67945 0.3048)
			(end 0.120396 0.3048)
			(stroke
				(width 0.1)
				(type default)
			)
			(layer "F.Fab")
		)
		(pad "1" smd circle
			(at -0.40005 0)
			(size 0 0)
			(layers "F.Cu" "F.Mask" "F.Paste")
			(net "PEX1_PCA9555_INT_N")
		)
		(pad "2" smd circle
			(at 0.40005 0)
			(size 0 0)
			(layers "F.Cu" "F.Mask" "F.Paste")
			(net "PEX1_PCA9555_1_INT_N")
		)
	)
	(footprint ""
		(layer "F.Cu")
		(at 336.467704 -51.019456)
		(property "Reference" "PC446"
			(at 0 0 0)
			(layer "F.SilkS")
			(hide yes)
			(effects
				(font
					(size 1.27 1.27)
				)
			)
		)
		(property "Value" ""
			(at 0 0 0)
			(layer "F.Fab")
			(effects
				(font
					(size 1.27 1.27)
				)
			)
		)
		(duplicate_pad_numbers_are_jumpers no)
		(fp_line
			(start -0.7874 -0.4064)
			(end 0.7874 -0.4064)
			(stroke
				(width 0.1524)
				(type default)
			)
			(layer "F.SilkS")
		)
		(fp_line
			(start -0.7874 0.4064)
			(end -0.7874 -0.4064)
			(stroke
				(width 0.1524)
				(type default)
			)
			(layer "F.SilkS")
		)
		(fp_line
			(start 0.7874 -0.4064)
			(end 0.7874 0.4064)
			(stroke
				(width 0.1524)
				(type default)
			)
			(layer "F.SilkS")
		)
		(fp_line
			(start 0.7874 0.4064)
			(end -0.7874 0.4064)
			(stroke
				(width 0.1524)
				(type default)
			)
			(layer "F.SilkS")
		)
		(fp_line
			(start -0.67945 -0.305054)
			(end -0.12065 -0.305054)
			(stroke
				(width 0.1)
				(type default)
			)
			(layer "F.Fab")
		)
		(fp_line
			(start -0.67945 0.3048)
			(end -0.67945 -0.305054)
			(stroke
				(width 0.1)
				(type default)
			)
			(layer "F.Fab")
		)
		(fp_line
			(start -0.12065 -0.305054)
			(end -0.12065 -0.2794)
			(stroke
				(width 0.1)
				(type default)
			)
			(layer "F.Fab")
		)
		(fp_line
			(start -0.12065 -0.2794)
			(end 0.12065 -0.2794)
			(stroke
				(width 0.1)
				(type default)
			)
			(layer "F.Fab")
		)
		(fp_line
			(start -0.12065 0.2794)
			(end -0.12065 0.3048)
			(stroke
				(width 0.1)
				(type default)
			)
			(layer "F.Fab")
		)
		(fp_line
			(start -0.12065 0.3048)
			(end -0.67945 0.3048)
			(stroke
				(width 0.1)
				(type default)
			)
			(layer "F.Fab")
		)
		(fp_line
			(start 0.120396 0.2794)
			(end -0.12065 0.2794)
			(stroke
				(width 0.1)
				(type default)
			)
			(layer "F.Fab")
		)
		(fp_line
			(start 0.120396 0.3048)
			(end 0.120396 0.2794)
			(stroke
				(width 0.1)
				(type default)
			)
			(layer "F.Fab")
		)
		(fp_line
			(start 0.12065 -0.3048)
			(end 0.67945 -0.3048)
			(stroke
				(width 0.1)
				(type default)
			)
			(layer "F.Fab")
		)
		(fp_line
			(start 0.12065 -0.2794)
			(end 0.12065 -0.3048)
			(stroke
				(width 0.1)
				(type default)
			)
			(layer "F.Fab")
		)
		(fp_line
			(start 0.67945 -0.3048)
			(end 0.67945 0.3048)
			(stroke
				(width 0.1)
				(type default)
			)
			(layer "F.Fab")
		)
		(fp_line
			(start 0.67945 0.3048)
			(end 0.120396 0.3048)
			(stroke
				(width 0.1)
				(type default)
			)
			(layer "F.Fab")
		)
		(pad "1" smd circle
			(at -0.40005 0)
			(size 0 0)
			(layers "F.Cu" "F.Mask" "F.Paste")
			(net "P12V_SSD11_SS")
		)
		(pad "2" smd circle
			(at 0.40005 0)
			(size 0 0)
			(layers "F.Cu" "F.Mask" "F.Paste")
			(net "GND")
		)
	)
	(footprint ""
		(layer "F.Cu")
		(at 443.571376 -121.291858)
		(property "Reference" "PU53"
			(at -0.973836 2.865628 0)
			(unlocked yes)
			(layer "F.SilkS")
			(effects
				(font
					(size 0.7874 0.5842)
					(thickness 0.1524)
				)
				(justify left)
			)
		)
		(property "Value" ""
			(at 0 0 0)
			(layer "F.Fab")
			(effects
				(font
					(size 1.27 1.27)
				)
			)
		)
		(duplicate_pad_numbers_are_jumpers no)
		(fp_line
			(start -1.943608 -1.549908)
			(end 1.943608 -1.549908)
			(stroke
				(width 0.1524)
				(type default)
			)
			(layer "F.SilkS")
		)
		(fp_line
			(start -1.943608 1.549908)
			(end -1.943608 -1.549908)
			(stroke
				(width 0.1524)
				(type default)
			)
			(layer "F.SilkS")
		)
		(fp_line
			(start 1.943608 -1.549908)
			(end 1.943608 1.549908)
			(stroke
				(width 0.1524)
				(type default)
			)
			(layer "F.SilkS")
		)
		(fp_line
			(start 1.943608 1.549908)
			(end -1.943608 1.549908)
			(stroke
				(width 0.1524)
				(type default)
			)
			(layer "F.SilkS")
		)
		(fp_poly
			(pts
				(xy -2.019808 -1.549908) (xy -1.257808 -1.549908) (xy -1.257808 -1.880108) (xy -2.019808 -1.880108)
			)
			(stroke
				(width 0)
				(type default)
			)
			(fill yes)
			(layer "F.SilkS")
		)
		(fp_line
			(start -1.549908 -1.549908)
			(end 1.549908 -1.549908)
			(stroke
				(width 0.1)
				(type default)
			)
			(layer "F.Fab")
		)
		(fp_line
			(start -1.549908 1.549908)
			(end -1.549908 -1.549908)
			(stroke
				(width 0.1)
				(type default)
			)
			(layer "F.Fab")
		)
		(fp_line
			(start 1.549908 -1.549908)
			(end 1.549908 1.549908)
			(stroke
				(width 0.1)
				(type default)
			)
			(layer "F.Fab")
		)
		(fp_line
			(start 1.549908 1.549908)
			(end -1.549908 1.549908)
			(stroke
				(width 0.1)
				(type default)
			)
			(layer "F.Fab")
		)
		(fp_poly
			(pts
				(xy -2.019808 -1.549908) (xy -1.257808 -1.549908) (xy -1.257808 -1.880108) (xy -2.019808 -1.880108)
			)
			(stroke
				(width 0)
				(type default)
			)
			(fill yes)
			(layer "F.Fab")
		)
		(pad "1" smd rect
			(at -1.500124 -1.249934 270)
			(size 0.2794 0.6096)
			(layers "F.Cu" "F.Mask" "F.Paste")
			(net "P3V3_NIC7")
		)
		(pad "2" smd rect
			(at -1.500124 -0.750062 270)
			(size 0.2794 0.6096)
			(layers "F.Cu" "F.Mask" "F.Paste")
			(net "P3V3_NIC7")
		)
		(pad "3" smd rect
			(at -1.500124 -0.249936 270)
			(size 0.2794 0.6096)
			(layers "F.Cu" "F.Mask" "F.Paste")
			(net "P3V3_NIC7")
		)
		(pad "4" smd rect
			(at -1.500124 0.249936 270)
			(size 0.2794 0.6096)
			(layers "F.Cu" "F.Mask" "F.Paste")
			(net "P3V3_NIC7")
		)
		(pad "5" smd rect
			(at -1.500124 0.750062 270)
			(size 0.2794 0.6096)
			(layers "F.Cu" "F.Mask" "F.Paste")
			(net "P3V3_NIC7")
		)
		(pad "6" smd rect
			(at -1.500124 1.249934 270)
			(size 0.2794 0.6096)
			(layers "F.Cu" "F.Mask" "F.Paste")
			(net "GND")
		)
		(pad "7" smd rect
			(at 1.500124 1.249934 270)
			(size 0.2794 0.6096)
			(layers "F.Cu" "F.Mask" "F.Paste")
			(net "P3V3_NIC7_SS")
		)
		(pad "8" smd rect
			(at 1.500124 0.750062 270)
			(size 0.2794 0.6096)
			(layers "F.Cu" "F.Mask" "F.Paste")
			(net "PWRGD_P3V3_NIC7")
		)
		(pad "9" smd rect
			(at 1.500124 0.249936 270)
			(size 0.2794 0.6096)
			(layers "F.Cu" "F.Mask" "F.Paste")
			(net "P3V3_NIC7_OCP")
		)
		(pad "10" smd rect
			(at 1.500124 -0.249936 270)
			(size 0.2794 0.6096)
			(layers "F.Cu" "F.Mask" "F.Paste")
			(net "P5V_AUX")
		)
		(pad "11" smd rect
			(at 1.500124 -0.750062 270)
			(size 0.2794 0.6096)
			(layers "F.Cu" "F.Mask" "F.Paste")
			(net "HP_NIC7_EN")
		)
		(pad "12" smd rect
			(at 1.500124 -1.249934 270)
			(size 0.2794 0.6096)
			(layers "F.Cu" "F.Mask" "F.Paste")
			(net "P3V3_AUX")
		)
		(pad "13" smd rect
			(at 0 0)
			(size 1.9812 2.7178)
			(layers "F.Cu" "F.Mask" "F.Paste")
			(net "P3V3_AUX")
		)
		(zone
			(layer "F.Cu")
			(hatch none 0.5)
			(connect_pads
				(clearance 0)
			)
			(min_thickness 0.25)
			(keepout
				(tracks not_allowed)
				(vias allowed)
				(pads allowed)
				(copperpour not_allowed)
				(footprints allowed)
			)
			(placement
				(enabled no)
				(sheetname "")
			)
			(fill
				(thermal_gap 0.5)
				(thermal_bridge_width 0.5)
				(island_removal_mode 0)
			)
			(polygon
				(pts
					(xy 444.714376 -122.841258) (xy 444.714376 -122.714258) (xy 444.714376 -119.742458) (xy 444.714376 -119.74195)
					(xy 442.428376 -119.74195) (xy 442.428376 -119.742458) (xy 442.428376 -119.869458) (xy 442.428376 -121.291858)
					(xy 442.529976 -121.291858) (xy 442.529976 -119.869458) (xy 444.612776 -119.869458) (xy 444.612776 -122.714258)
					(xy 442.529976 -122.714258) (xy 442.529976 -121.317258) (xy 442.428376 -121.317258) (xy 442.428376 -122.714258)
					(xy 442.428376 -122.841258) (xy 442.428376 -122.841766) (xy 444.714376 -122.841766)
				)
			)
		)
	)
	(footprint ""
		(layer "F.Cu")
		(at 200.809098 -26.03373)
		(property "Reference" "R4066"
			(at 0 0 0)
			(layer "F.SilkS")
			(hide yes)
			(effects
				(font
					(size 1.27 1.27)
				)
			)
		)
		(property "Value" ""
			(at 0 0 0)
			(layer "F.Fab")
			(effects
				(font
					(size 1.27 1.27)
				)
			)
		)
		(duplicate_pad_numbers_are_jumpers no)
		(fp_line
			(start -0.7874 -0.4064)
			(end 0.7874 -0.4064)
			(stroke
				(width 0.1524)
				(type default)
			)
			(layer "F.SilkS")
		)
		(fp_line
			(start -0.7874 0.4064)
			(end -0.7874 -0.4064)
			(stroke
				(width 0.1524)
				(type default)
			)
			(layer "F.SilkS")
		)
		(fp_line
			(start 0.7874 -0.4064)
			(end 0.7874 0.4064)
			(stroke
				(width 0.1524)
				(type default)
			)
			(layer "F.SilkS")
		)
		(fp_line
			(start 0.7874 0.4064)
			(end -0.7874 0.4064)
			(stroke
				(width 0.1524)
				(type default)
			)
			(layer "F.SilkS")
		)
		(fp_line
			(start -0.67945 -0.305054)
			(end -0.12065 -0.305054)
			(stroke
				(width 0.1)
				(type default)
			)
			(layer "F.Fab")
		)
		(fp_line
			(start -0.67945 0.3048)
			(end -0.67945 -0.305054)
			(stroke
				(width 0.1)
				(type default)
			)
			(layer "F.Fab")
		)
		(fp_line
			(start -0.12065 -0.305054)
			(end -0.12065 -0.2794)
			(stroke
				(width 0.1)
				(type default)
			)
			(layer "F.Fab")
		)
		(fp_line
			(start -0.12065 -0.2794)
			(end 0.12065 -0.2794)
			(stroke
				(width 0.1)
				(type default)
			)
			(layer "F.Fab")
		)
		(fp_line
			(start -0.12065 0.2794)
			(end -0.12065 0.3048)
			(stroke
				(width 0.1)
				(type default)
			)
			(layer "F.Fab")
		)
		(fp_line
			(start -0.12065 0.3048)
			(end -0.67945 0.3048)
			(stroke
				(width 0.1)
				(type default)
			)
			(layer "F.Fab")
		)
		(fp_line
			(start 0.120396 0.2794)
			(end -0.12065 0.2794)
			(stroke
				(width 0.1)
				(type default)
			)
			(layer "F.Fab")
		)
		(fp_line
			(start 0.120396 0.3048)
			(end 0.120396 0.2794)
			(stroke
				(width 0.1)
				(type default)
			)
			(layer "F.Fab")
		)
		(fp_line
			(start 0.12065 -0.3048)
			(end 0.67945 -0.3048)
			(stroke
				(width 0.1)
				(type default)
			)
			(layer "F.Fab")
		)
		(fp_line
			(start 0.12065 -0.2794)
			(end 0.12065 -0.3048)
			(stroke
				(width 0.1)
				(type default)
			)
			(layer "F.Fab")
		)
		(fp_line
			(start 0.67945 -0.3048)
			(end 0.67945 0.3048)
			(stroke
				(width 0.1)
				(type default)
			)
			(layer "F.Fab")
		)
		(fp_line
			(start 0.67945 0.3048)
			(end 0.120396 0.3048)
			(stroke
				(width 0.1)
				(type default)
			)
			(layer "F.Fab")
		)
		(pad "1" smd circle
			(at -0.40005 0)
			(size 0 0)
			(layers "F.Cu" "F.Mask" "F.Paste")
			(net "P3V3_AUX")
		)
		(pad "2" smd circle
			(at 0.40005 0)
			(size 0 0)
			(layers "F.Cu" "F.Mask" "F.Paste")
			(net "PRSNT_SSD7_R_N")
		)
	)
	(footprint ""
		(layer "F.Cu")
		(at 416.402012 -350.098614 90)
		(property "Reference" "C2446"
			(at 0 0 90)
			(layer "F.SilkS")
			(hide yes)
			(effects
				(font
					(size 1.27 1.27)
				)
			)
		)
		(property "Value" ""
			(at 0 0 90)
			(layer "F.Fab")
			(effects
				(font
					(size 1.27 1.27)
				)
			)
		)
		(duplicate_pad_numbers_are_jumpers no)
		(fp_line
			(start 0.299974 -0.150114)
			(end 0.299974 0.150114)
			(stroke
				(width 0.1)
				(type default)
			)
			(layer "F.Fab")
		)
		(fp_line
			(start -0.299974 -0.150114)
			(end 0.299974 -0.150114)
			(stroke
				(width 0.1)
				(type default)
			)
			(layer "F.Fab")
		)
		(fp_line
			(start 0.299974 0.150114)
			(end -0.299974 0.150114)
			(stroke
				(width 0.1)
				(type default)
			)
			(layer "F.Fab")
		)
		(fp_line
			(start -0.299974 0.150114)
			(end -0.299974 -0.150114)
			(stroke
				(width 0.1)
				(type default)
			)
			(layer "F.Fab")
		)
		(pad "1" smd rect
			(at -0.2667 0 90)
			(size 0.3048 0.381)
			(layers "F.Cu" "F.Mask" "F.Paste")
			(net "P5E_PEX3_STN4_TX_DN<76>")
		)
		(pad "2" smd rect
			(at 0.2667 0 90)
			(size 0.3048 0.381)
			(layers "F.Cu" "F.Mask" "F.Paste")
			(net "P5E_PEX3_STN4_TX_C_DN<76>")
		)
	)
	(footprint ""
		(layer "F.Cu")
		(at 173.394116 -35.264852)
		(property "Reference" "R5679"
			(at 0 0 0)
			(layer "F.SilkS")
			(hide yes)
			(effects
				(font
					(size 1.27 1.27)
				)
			)
		)
		(property "Value" ""
			(at 0 0 0)
			(layer "F.Fab")
			(effects
				(font
					(size 1.27 1.27)
				)
			)
		)
		(duplicate_pad_numbers_are_jumpers no)
		(fp_line
			(start -0.7874 -0.4064)
			(end 0.7874 -0.4064)
			(stroke
				(width 0.1524)
				(type default)
			)
			(layer "F.SilkS")
		)
		(fp_line
			(start -0.7874 0.4064)
			(end -0.7874 -0.4064)
			(stroke
				(width 0.1524)
				(type default)
			)
			(layer "F.SilkS")
		)
		(fp_line
			(start 0.7874 -0.4064)
			(end 0.7874 0.4064)
			(stroke
				(width 0.1524)
				(type default)
			)
			(layer "F.SilkS")
		)
		(fp_line
			(start 0.7874 0.4064)
			(end -0.7874 0.4064)
			(stroke
				(width 0.1524)
				(type default)
			)
			(layer "F.SilkS")
		)
		(fp_line
			(start -0.67945 -0.305054)
			(end -0.12065 -0.305054)
			(stroke
				(width 0.1)
				(type default)
			)
			(layer "F.Fab")
		)
		(fp_line
			(start -0.67945 0.3048)
			(end -0.67945 -0.305054)
			(stroke
				(width 0.1)
				(type default)
			)
			(layer "F.Fab")
		)
		(fp_line
			(start -0.12065 -0.305054)
			(end -0.12065 -0.2794)
			(stroke
				(width 0.1)
				(type default)
			)
			(layer "F.Fab")
		)
		(fp_line
			(start -0.12065 -0.2794)
			(end 0.12065 -0.2794)
			(stroke
				(width 0.1)
				(type default)
			)
			(layer "F.Fab")
		)
		(fp_line
			(start -0.12065 0.2794)
			(end -0.12065 0.3048)
			(stroke
				(width 0.1)
				(type default)
			)
			(layer "F.Fab")
		)
		(fp_line
			(start -0.12065 0.3048)
			(end -0.67945 0.3048)
			(stroke
				(width 0.1)
				(type default)
			)
			(layer "F.Fab")
		)
		(fp_line
			(start 0.120396 0.2794)
			(end -0.12065 0.2794)
			(stroke
				(width 0.1)
				(type default)
			)
			(layer "F.Fab")
		)
		(fp_line
			(start 0.120396 0.3048)
			(end 0.120396 0.2794)
			(stroke
				(width 0.1)
				(type default)
			)
			(layer "F.Fab")
		)
		(fp_line
			(start 0.12065 -0.3048)
			(end 0.67945 -0.3048)
			(stroke
				(width 0.1)
				(type default)
			)
			(layer "F.Fab")
		)
		(fp_line
			(start 0.12065 -0.2794)
			(end 0.12065 -0.3048)
			(stroke
				(width 0.1)
				(type default)
			)
			(layer "F.Fab")
		)
		(fp_line
			(start 0.67945 -0.3048)
			(end 0.67945 0.3048)
			(stroke
				(width 0.1)
				(type default)
			)
			(layer "F.Fab")
		)
		(fp_line
			(start 0.67945 0.3048)
			(end 0.120396 0.3048)
			(stroke
				(width 0.1)
				(type default)
			)
			(layer "F.Fab")
		)
		(pad "1" smd circle
			(at -0.40005 0)
			(size 0 0)
			(layers "F.Cu" "F.Mask" "F.Paste")
			(net "RST_SMB_SSD6_ISO_N")
		)
		(pad "2" smd circle
			(at 0.40005 0)
			(size 0 0)
			(layers "F.Cu" "F.Mask" "F.Paste")
			(net "GND")
		)
	)
	(footprint ""
		(layer "F.Cu")
		(at 48.202088 -356.244906 90)
		(property "Reference" "C164"
			(at 0 0 90)
			(layer "F.SilkS")
			(hide yes)
			(effects
				(font
					(size 1.27 1.27)
				)
			)
		)
		(property "Value" ""
			(at 0 0 90)
			(layer "F.Fab")
			(effects
				(font
					(size 1.27 1.27)
				)
			)
		)
		(duplicate_pad_numbers_are_jumpers no)
		(fp_line
			(start 0.299974 -0.150114)
			(end 0.299974 0.150114)
			(stroke
				(width 0.1)
				(type default)
			)
			(layer "F.Fab")
		)
		(fp_line
			(start -0.299974 -0.150114)
			(end 0.299974 -0.150114)
			(stroke
				(width 0.1)
				(type default)
			)
			(layer "F.Fab")
		)
		(fp_line
			(start 0.299974 0.150114)
			(end -0.299974 0.150114)
			(stroke
				(width 0.1)
				(type default)
			)
			(layer "F.Fab")
		)
		(fp_line
			(start -0.299974 0.150114)
			(end -0.299974 -0.150114)
			(stroke
				(width 0.1)
				(type default)
			)
			(layer "F.Fab")
		)
		(pad "1" smd rect
			(at -0.2667 0 90)
			(size 0.3048 0.381)
			(layers "F.Cu" "F.Mask" "F.Paste")
			(net "P5E_PEX0_STN7_TX_DN<126>")
		)
		(pad "2" smd rect
			(at 0.2667 0 90)
			(size 0.3048 0.381)
			(layers "F.Cu" "F.Mask" "F.Paste")
			(net "P5E_PEX0_STN7_TX_C_DN<126>")
		)
	)
	(footprint ""
		(layer "F.Cu")
		(at 330.872846 -22.867366 90)
		(property "Reference" "C3949"
			(at 0 0 90)
			(layer "F.SilkS")
			(hide yes)
			(effects
				(font
					(size 1.27 1.27)
				)
			)
		)
		(property "Value" ""
			(at 0 0 90)
			(layer "F.Fab")
			(effects
				(font
					(size 1.27 1.27)
				)
			)
		)
		(duplicate_pad_numbers_are_jumpers no)
		(fp_line
			(start 0.7874 -0.4064)
			(end 0.7874 0.4064)
			(stroke
				(width 0.1524)
				(type default)
			)
			(layer "F.SilkS")
		)
		(fp_line
			(start -0.7874 -0.4064)
			(end 0.7874 -0.4064)
			(stroke
				(width 0.1524)
				(type default)
			)
			(layer "F.SilkS")
		)
		(fp_line
			(start 0.7874 0.4064)
			(end -0.7874 0.4064)
			(stroke
				(width 0.1524)
				(type default)
			)
			(layer "F.SilkS")
		)
		(fp_line
			(start -0.7874 0.4064)
			(end -0.7874 -0.4064)
			(stroke
				(width 0.1524)
				(type default)
			)
			(layer "F.SilkS")
		)
		(fp_line
			(start -0.12065 -0.305054)
			(end -0.12065 -0.2794)
			(stroke
				(width 0.1)
				(type default)
			)
			(layer "F.Fab")
		)
		(fp_line
			(start -0.67945 -0.305054)
			(end -0.12065 -0.305054)
			(stroke
				(width 0.1)
				(type default)
			)
			(layer "F.Fab")
		)
		(fp_line
			(start 0.67945 -0.3048)
			(end 0.67945 0.3048)
			(stroke
				(width 0.1)
				(type default)
			)
			(layer "F.Fab")
		)
		(fp_line
			(start 0.12065 -0.3048)
			(end 0.67945 -0.3048)
			(stroke
				(width 0.1)
				(type default)
			)
			(layer "F.Fab")
		)
		(fp_line
			(start 0.12065 -0.2794)
			(end 0.12065 -0.3048)
			(stroke
				(width 0.1)
				(type default)
			)
			(layer "F.Fab")
		)
		(fp_line
			(start -0.12065 -0.2794)
			(end 0.12065 -0.2794)
			(stroke
				(width 0.1)
				(type default)
			)
			(layer "F.Fab")
		)
		(fp_line
			(start 0.120396 0.2794)
			(end -0.12065 0.2794)
			(stroke
				(width 0.1)
				(type default)
			)
			(layer "F.Fab")
		)
		(fp_line
			(start -0.12065 0.2794)
			(end -0.12065 0.3048)
			(stroke
				(width 0.1)
				(type default)
			)
			(layer "F.Fab")
		)
		(fp_line
			(start 0.67945 0.3048)
			(end 0.120396 0.3048)
			(stroke
				(width 0.1)
				(type default)
			)
			(layer "F.Fab")
		)
		(fp_line
			(start 0.120396 0.3048)
			(end 0.120396 0.2794)
			(stroke
				(width 0.1)
				(type default)
			)
			(layer "F.Fab")
		)
		(fp_line
			(start -0.12065 0.3048)
			(end -0.67945 0.3048)
			(stroke
				(width 0.1)
				(type default)
			)
			(layer "F.Fab")
		)
		(fp_line
			(start -0.67945 0.3048)
			(end -0.67945 -0.305054)
			(stroke
				(width 0.1)
				(type default)
			)
			(layer "F.Fab")
		)
		(pad "1" smd circle
			(at -0.40005 0 90)
			(size 0 0)
			(layers "F.Cu" "F.Mask" "F.Paste")
			(net "P12V_SSD11")
		)
		(pad "2" smd circle
			(at 0.40005 0 90)
			(size 0 0)
			(layers "F.Cu" "F.Mask" "F.Paste")
			(net "GND")
		)
	)
	(footprint ""
		(layer "F.Cu")
		(at 140.074142 -175.897286 180)
		(property "Reference" "R1100"
			(at 0 0 180)
			(layer "F.SilkS")
			(hide yes)
			(effects
				(font
					(size 1.27 1.27)
				)
			)
		)
		(property "Value" ""
			(at 0 0 180)
			(layer "F.Fab")
			(effects
				(font
					(size 1.27 1.27)
				)
			)
		)
		(duplicate_pad_numbers_are_jumpers no)
		(fp_line
			(start -0.7874 -0.4064)
			(end 0.7874 -0.4064)
			(stroke
				(width 0.1524)
				(type default)
			)
			(layer "F.SilkS")
		)
		(fp_line
			(start 0.67945 0.3048)
			(end 0.120396 0.3048)
			(stroke
				(width 0.1)
				(type default)
			)
			(layer "F.Fab")
		)
		(fp_line
			(start 0.67945 -0.3048)
			(end 0.67945 0.3048)
			(stroke
				(width 0.1)
				(type default)
			)
			(layer "F.Fab")
		)
		(fp_line
			(start 0.12065 -0.2794)
			(end 0.12065 -0.3048)
			(stroke
				(width 0.1)
				(type default)
			)
			(layer "F.Fab")
		)
		(fp_line
			(start 0.12065 -0.3048)
			(end 0.67945 -0.3048)
			(stroke
				(width 0.1)
				(type default)
			)
			(layer "F.Fab")
		)
		(fp_line
			(start 0.120396 0.3048)
			(end 0.120396 0.2794)
			(stroke
				(width 0.1)
				(type default)
			)
			(layer "F.Fab")
		)
		(fp_line
			(start 0.120396 0.2794)
			(end -0.12065 0.2794)
			(stroke
				(width 0.1)
				(type default)
			)
			(layer "F.Fab")
		)
		(fp_line
			(start -0.12065 0.3048)
			(end -0.67945 0.3048)
			(stroke
				(width 0.1)
				(type default)
			)
			(layer "F.Fab")
		)
		(fp_line
			(start -0.12065 0.2794)
			(end -0.12065 0.3048)
			(stroke
				(width 0.1)
				(type default)
			)
			(layer "F.Fab")
		)
		(fp_line
			(start -0.12065 -0.2794)
			(end 0.12065 -0.2794)
			(stroke
				(width 0.1)
				(type default)
			)
			(layer "F.Fab")
		)
		(fp_line
			(start -0.12065 -0.305054)
			(end -0.12065 -0.2794)
			(stroke
				(width 0.1)
				(type default)
			)
			(layer "F.Fab")
		)
		(fp_line
			(start -0.67945 0.3048)
			(end -0.67945 -0.305054)
			(stroke
				(width 0.1)
				(type default)
			)
			(layer "F.Fab")
		)
		(fp_line
			(start -0.67945 -0.305054)
			(end -0.12065 -0.305054)
			(stroke
				(width 0.1)
				(type default)
			)
			(layer "F.Fab")
		)
		(pad "1" smd circle
			(at -0.40005 0 180)
			(size 0 0)
			(layers "F.Cu" "F.Mask" "F.Paste")
			(net "CLK_100M_DB2000QL_NIC3_R_DP")
		)
		(pad "2" smd circle
			(at 0.40005 0 180)
			(size 0 0)
			(layers "F.Cu" "F.Mask" "F.Paste")
			(net "CLK_100M_DB2000QL_NIC3_DP")
		)
	)
	(footprint ""
		(layer "F.Cu")
		(at 238.235998 -48.77689 180)
		(property "Reference" "PC548"
			(at 0 0 180)
			(layer "F.SilkS")
			(hide yes)
			(effects
				(font
					(size 1.27 1.27)
				)
			)
		)
		(property "Value" ""
			(at 0 0 180)
			(layer "F.Fab")
			(effects
				(font
					(size 1.27 1.27)
				)
			)
		)
		(duplicate_pad_numbers_are_jumpers no)
		(fp_line
			(start 0.7874 0.4064)
			(end -0.7874 0.4064)
			(stroke
				(width 0.1524)
				(type default)
			)
			(layer "F.SilkS")
		)
		(fp_line
			(start 0.7874 -0.4064)
			(end 0.7874 0.4064)
			(stroke
				(width 0.1524)
				(type default)
			)
			(layer "F.SilkS")
		)
		(fp_line
			(start -0.7874 0.4064)
			(end -0.7874 -0.4064)
			(stroke
				(width 0.1524)
				(type default)
			)
			(layer "F.SilkS")
		)
		(fp_line
			(start -0.7874 -0.4064)
			(end 0.7874 -0.4064)
			(stroke
				(width 0.1524)
				(type default)
			)
			(layer "F.SilkS")
		)
		(fp_line
			(start 0.67945 0.3048)
			(end 0.120396 0.3048)
			(stroke
				(width 0.1)
				(type default)
			)
			(layer "F.Fab")
		)
		(fp_line
			(start 0.67945 -0.3048)
			(end 0.67945 0.3048)
			(stroke
				(width 0.1)
				(type default)
			)
			(layer "F.Fab")
		)
		(fp_line
			(start 0.12065 -0.2794)
			(end 0.12065 -0.3048)
			(stroke
				(width 0.1)
				(type default)
			)
			(layer "F.Fab")
		)
		(fp_line
			(start 0.12065 -0.3048)
			(end 0.67945 -0.3048)
			(stroke
				(width 0.1)
				(type default)
			)
			(layer "F.Fab")
		)
		(fp_line
			(start 0.120396 0.3048)
			(end 0.120396 0.2794)
			(stroke
				(width 0.1)
				(type default)
			)
			(layer "F.Fab")
		)
		(fp_line
			(start 0.120396 0.2794)
			(end -0.12065 0.2794)
			(stroke
				(width 0.1)
				(type default)
			)
			(layer "F.Fab")
		)
		(fp_line
			(start -0.12065 0.3048)
			(end -0.67945 0.3048)
			(stroke
				(width 0.1)
				(type default)
			)
			(layer "F.Fab")
		)
		(fp_line
			(start -0.12065 0.2794)
			(end -0.12065 0.3048)
			(stroke
				(width 0.1)
				(type default)
			)
			(layer "F.Fab")
		)
		(fp_line
			(start -0.12065 -0.2794)
			(end 0.12065 -0.2794)
			(stroke
				(width 0.1)
				(type default)
			)
			(layer "F.Fab")
		)
		(fp_line
			(start -0.12065 -0.305054)
			(end -0.12065 -0.2794)
			(stroke
				(width 0.1)
				(type default)
			)
			(layer "F.Fab")
		)
		(fp_line
			(start -0.67945 0.3048)
			(end -0.67945 -0.305054)
			(stroke
				(width 0.1)
				(type default)
			)
			(layer "F.Fab")
		)
		(fp_line
			(start -0.67945 -0.305054)
			(end -0.12065 -0.305054)
			(stroke
				(width 0.1)
				(type default)
			)
			(layer "F.Fab")
		)
		(pad "1" smd circle
			(at -0.40005 0 180)
			(size 0 0)
			(layers "F.Cu" "F.Mask" "F.Paste")
			(net "P3V3_SSD8")
		)
		(pad "2" smd circle
			(at 0.40005 0 180)
			(size 0 0)
			(layers "F.Cu" "F.Mask" "F.Paste")
			(net "GND")
		)
	)
	(footprint ""
		(layer "F.Cu")
		(at 312.21934 -133.480302 180)
		(property "Reference" "C442"
			(at 0 0 180)
			(layer "F.SilkS")
			(hide yes)
			(effects
				(font
					(size 1.27 1.27)
				)
			)
		)
		(property "Value" ""
			(at 0 0 180)
			(layer "F.Fab")
			(effects
				(font
					(size 1.27 1.27)
				)
			)
		)
		(duplicate_pad_numbers_are_jumpers no)
		(fp_line
			(start 0.299974 0.150114)
			(end -0.299974 0.150114)
			(stroke
				(width 0.1)
				(type default)
			)
			(layer "F.Fab")
		)
		(fp_line
			(start 0.299974 -0.150114)
			(end 0.299974 0.150114)
			(stroke
				(width 0.1)
				(type default)
			)
			(layer "F.Fab")
		)
		(fp_line
			(start -0.299974 0.150114)
			(end -0.299974 -0.150114)
			(stroke
				(width 0.1)
				(type default)
			)
			(layer "F.Fab")
		)
		(fp_line
			(start -0.299974 -0.150114)
			(end 0.299974 -0.150114)
			(stroke
				(width 0.1)
				(type default)
			)
			(layer "F.Fab")
		)
		(pad "1" smd rect
			(at -0.2667 0 180)
			(size 0.3048 0.381)
			(layers "F.Cu" "F.Mask" "F.Paste")
			(net "P5E_PEX2_STN0_TX_DN<6>")
		)
		(pad "2" smd rect
			(at 0.2667 0 180)
			(size 0.3048 0.381)
			(layers "F.Cu" "F.Mask" "F.Paste")
			(net "P5E_PEX2_STN0_TX_C_DN<6>")
		)
	)
	(footprint ""
		(layer "F.Cu")
		(at 382.154176 -307.415438 45)
		(property "Reference" "R1421"
			(at 0 0 45)
			(layer "F.SilkS")
			(hide yes)
			(effects
				(font
					(size 1.27 1.27)
				)
			)
		)
		(property "Value" ""
			(at 0 0 45)
			(layer "F.Fab")
			(effects
				(font
					(size 1.27 1.27)
				)
			)
		)
		(duplicate_pad_numbers_are_jumpers no)
		(fp_line
			(start -0.787389 -0.406267)
			(end 0.787389 -0.406267)
			(stroke
				(width 0.1524)
				(type default)
			)
			(layer "F.SilkS")
		)
		(fp_line
			(start -0.787389 0.406267)
			(end -0.787389 -0.406267)
			(stroke
				(width 0.1524)
				(type default)
			)
			(layer "F.SilkS")
		)
		(fp_line
			(start 0.787389 -0.406267)
			(end 0.787389 0.406267)
			(stroke
				(width 0.1524)
				(type default)
			)
			(layer "F.SilkS")
		)
		(fp_line
			(start 0.787389 0.406267)
			(end -0.787389 0.406267)
			(stroke
				(width 0.1524)
				(type default)
			)
			(layer "F.SilkS")
		)
		(fp_line
			(start -0.679446 -0.305149)
			(end -0.120695 -0.304969)
			(stroke
				(width 0.1)
				(type default)
			)
			(layer "F.Fab")
		)
		(fp_line
			(start -0.120695 -0.304969)
			(end -0.120695 -0.279466)
			(stroke
				(width 0.1)
				(type default)
			)
			(layer "F.Fab")
		)
		(fp_line
			(start -0.120695 -0.279466)
			(end 0.120695 -0.279466)
			(stroke
				(width 0.1)
				(type default)
			)
			(layer "F.Fab")
		)
		(fp_line
			(start -0.679446 0.30479)
			(end -0.679446 -0.305149)
			(stroke
				(width 0.1)
				(type default)
			)
			(layer "F.Fab")
		)
		(fp_line
			(start 0.120515 -0.30479)
			(end 0.679446 -0.30479)
			(stroke
				(width 0.1)
				(type default)
			)
			(layer "F.Fab")
		)
		(fp_line
			(start 0.120695 -0.279466)
			(end 0.120515 -0.30479)
			(stroke
				(width 0.1)
				(type default)
			)
			(layer "F.Fab")
		)
		(fp_line
			(start -0.120695 0.279466)
			(end -0.120515 0.30479)
			(stroke
				(width 0.1)
				(type default)
			)
			(layer "F.Fab")
		)
		(fp_line
			(start -0.120515 0.30479)
			(end -0.679446 0.30479)
			(stroke
				(width 0.1)
				(type default)
			)
			(layer "F.Fab")
		)
		(fp_line
			(start 0.679446 -0.30479)
			(end 0.679446 0.30479)
			(stroke
				(width 0.1)
				(type default)
			)
			(layer "F.Fab")
		)
		(fp_line
			(start 0.120335 0.279466)
			(end -0.120695 0.279466)
			(stroke
				(width 0.1)
				(type default)
			)
			(layer "F.Fab")
		)
		(fp_line
			(start 0.120515 0.30479)
			(end 0.120335 0.279466)
			(stroke
				(width 0.1)
				(type default)
			)
			(layer "F.Fab")
		)
		(fp_line
			(start 0.679446 0.30479)
			(end 0.120515 0.30479)
			(stroke
				(width 0.1)
				(type default)
			)
			(layer "F.Fab")
		)
		(pad "1" smd circle
			(at -0.40005 0 45)
			(size 0 0)
			(layers "F.Cu" "F.Mask" "F.Paste")
			(net "GND")
		)
		(pad "2" smd circle
			(at 0.40005 0 45)
			(size 0 0)
			(layers "F.Cu" "F.Mask" "F.Paste")
			(net "PEX3_DBG_MODE1")
		)
	)
	(footprint ""
		(layer "F.Cu")
		(at 335.915 -234.061 -90)
		(property "Reference" "R6283"
			(at 0 0 270)
			(layer "F.SilkS")
			(hide yes)
			(effects
				(font
					(size 1.27 1.27)
				)
			)
		)
		(property "Value" ""
			(at 0 0 270)
			(layer "F.Fab")
			(effects
				(font
					(size 1.27 1.27)
				)
			)
		)
		(duplicate_pad_numbers_are_jumpers no)
		(fp_line
			(start -0.7874 0.4064)
			(end -0.7874 -0.4064)
			(stroke
				(width 0.1524)
				(type default)
			)
			(layer "F.SilkS")
		)
		(fp_line
			(start 0.7874 0.4064)
			(end -0.7874 0.4064)
			(stroke
				(width 0.1524)
				(type default)
			)
			(layer "F.SilkS")
		)
		(fp_line
			(start -0.7874 -0.4064)
			(end 0.7874 -0.4064)
			(stroke
				(width 0.1524)
				(type default)
			)
			(layer "F.SilkS")
		)
		(fp_line
			(start 0.7874 -0.4064)
			(end 0.7874 0.4064)
			(stroke
				(width 0.1524)
				(type default)
			)
			(layer "F.SilkS")
		)
		(fp_line
			(start -0.67945 0.3048)
			(end -0.67945 -0.305054)
			(stroke
				(width 0.1)
				(type default)
			)
			(layer "F.Fab")
		)
		(fp_line
			(start -0.12065 0.3048)
			(end -0.67945 0.3048)
			(stroke
				(width 0.1)
				(type default)
			)
			(layer "F.Fab")
		)
		(fp_line
			(start 0.120396 0.3048)
			(end 0.120396 0.2794)
			(stroke
				(width 0.1)
				(type default)
			)
			(layer "F.Fab")
		)
		(fp_line
			(start 0.67945 0.3048)
			(end 0.120396 0.3048)
			(stroke
				(width 0.1)
				(type default)
			)
			(layer "F.Fab")
		)
		(fp_line
			(start -0.12065 0.2794)
			(end -0.12065 0.3048)
			(stroke
				(width 0.1)
				(type default)
			)
			(layer "F.Fab")
		)
		(fp_line
			(start 0.120396 0.2794)
			(end -0.12065 0.2794)
			(stroke
				(width 0.1)
				(type default)
			)
			(layer "F.Fab")
		)
		(fp_line
			(start -0.12065 -0.2794)
			(end 0.12065 -0.2794)
			(stroke
				(width 0.1)
				(type default)
			)
			(layer "F.Fab")
		)
		(fp_line
			(start 0.12065 -0.2794)
			(end 0.12065 -0.3048)
			(stroke
				(width 0.1)
				(type default)
			)
			(layer "F.Fab")
		)
		(fp_line
			(start 0.12065 -0.3048)
			(end 0.67945 -0.3048)
			(stroke
				(width 0.1)
				(type default)
			)
			(layer "F.Fab")
		)
		(fp_line
			(start 0.67945 -0.3048)
			(end 0.67945 0.3048)
			(stroke
				(width 0.1)
				(type default)
			)
			(layer "F.Fab")
		)
		(fp_line
			(start -0.67945 -0.305054)
			(end -0.12065 -0.305054)
			(stroke
				(width 0.1)
				(type default)
			)
			(layer "F.Fab")
		)
		(fp_line
			(start -0.12065 -0.305054)
			(end -0.12065 -0.2794)
			(stroke
				(width 0.1)
				(type default)
			)
			(layer "F.Fab")
		)
		(pad "1" smd circle
			(at -0.40005 0 270)
			(size 0 0)
			(layers "F.Cu" "F.Mask" "F.Paste")
			(net "P3V3_AUX")
		)
		(pad "2" smd circle
			(at 0.40005 0 270)
			(size 0 0)
			(layers "F.Cu" "F.Mask" "F.Paste")
			(net "SYS_PWR_READY_R_N")
		)
	)
	(footprint ""
		(layer "F.Cu")
		(at 166.184072 -350.098614 90)
		(property "Reference" "C399"
			(at 0 0 90)
			(layer "F.SilkS")
			(hide yes)
			(effects
				(font
					(size 1.27 1.27)
				)
			)
		)
		(property "Value" ""
			(at 0 0 90)
			(layer "F.Fab")
			(effects
				(font
					(size 1.27 1.27)
				)
			)
		)
		(duplicate_pad_numbers_are_jumpers no)
		(fp_line
			(start 0.299974 -0.150114)
			(end 0.299974 0.150114)
			(stroke
				(width 0.1)
				(type default)
			)
			(layer "F.Fab")
		)
		(fp_line
			(start -0.299974 -0.150114)
			(end 0.299974 -0.150114)
			(stroke
				(width 0.1)
				(type default)
			)
			(layer "F.Fab")
		)
		(fp_line
			(start 0.299974 0.150114)
			(end -0.299974 0.150114)
			(stroke
				(width 0.1)
				(type default)
			)
			(layer "F.Fab")
		)
		(fp_line
			(start -0.299974 0.150114)
			(end -0.299974 -0.150114)
			(stroke
				(width 0.1)
				(type default)
			)
			(layer "F.Fab")
		)
		(pad "1" smd rect
			(at -0.2667 0 90)
			(size 0.3048 0.381)
			(layers "F.Cu" "F.Mask" "F.Paste")
			(net "P5E_PEX1_STN7_TX_DN<114>")
		)
		(pad "2" smd rect
			(at 0.2667 0 90)
			(size 0.3048 0.381)
			(layers "F.Cu" "F.Mask" "F.Paste")
			(net "P5E_PEX1_STN7_TX_C_DN<114>")
		)
	)
	(footprint ""
		(layer "F.Cu")
		(at 403.16658 -356.244906 90)
		(property "Reference" "C731"
			(at 0 0 90)
			(layer "F.SilkS")
			(hide yes)
			(effects
				(font
					(size 1.27 1.27)
				)
			)
		)
		(property "Value" ""
			(at 0 0 90)
			(layer "F.Fab")
			(effects
				(font
					(size 1.27 1.27)
				)
			)
		)
		(duplicate_pad_numbers_are_jumpers no)
		(fp_line
			(start 0.299974 -0.150114)
			(end 0.299974 0.150114)
			(stroke
				(width 0.1)
				(type default)
			)
			(layer "F.Fab")
		)
		(fp_line
			(start -0.299974 -0.150114)
			(end 0.299974 -0.150114)
			(stroke
				(width 0.1)
				(type default)
			)
			(layer "F.Fab")
		)
		(fp_line
			(start 0.299974 0.150114)
			(end -0.299974 0.150114)
			(stroke
				(width 0.1)
				(type default)
			)
			(layer "F.Fab")
		)
		(fp_line
			(start -0.299974 0.150114)
			(end -0.299974 -0.150114)
			(stroke
				(width 0.1)
				(type default)
			)
			(layer "F.Fab")
		)
		(pad "1" smd rect
			(at -0.2667 0 90)
			(size 0.3048 0.381)
			(layers "F.Cu" "F.Mask" "F.Paste")
			(net "P5E_PEX3_STN5_TX_DN<95>")
		)
		(pad "2" smd rect
			(at 0.2667 0 90)
			(size 0.3048 0.381)
			(layers "F.Cu" "F.Mask" "F.Paste")
			(net "P5E_PEX3_STN5_TX_C_DN<95>")
		)
	)
	(footprint ""
		(layer "F.Cu")
		(at 398.574006 -26.31186 -90)
		(property "Reference" "U409"
			(at 0.14986 -2.442464 90)
			(unlocked yes)
			(layer "F.SilkS")
			(effects
				(font
					(size 0.7874 0.5842)
					(thickness 0.1524)
				)
			)
		)
		(property "Value" ""
			(at 0 0 270)
			(layer "F.Fab")
			(effects
				(font
					(size 1.27 1.27)
				)
			)
		)
		(duplicate_pad_numbers_are_jumpers no)
		(fp_line
			(start -1.949958 1.610106)
			(end -1.949958 -1.610106)
			(stroke
				(width 0.1524)
				(type default)
			)
			(layer "F.SilkS")
		)
		(fp_line
			(start 1.949958 1.610106)
			(end -1.949958 1.610106)
			(stroke
				(width 0.1524)
				(type default)
			)
			(layer "F.SilkS")
		)
		(fp_line
			(start 1.949958 -1.560068)
			(end 1.949958 1.610106)
			(stroke
				(width 0.1524)
				(type default)
			)
			(layer "F.SilkS")
		)
		(fp_line
			(start -1.949958 -1.610106)
			(end 1.949958 -1.610106)
			(stroke
				(width 0.1524)
				(type default)
			)
			(layer "F.SilkS")
		)
		(fp_line
			(start -0.750062 1.560068)
			(end -0.750062 -1.560068)
			(stroke
				(width 0.1)
				(type default)
			)
			(layer "F.Fab")
		)
		(fp_line
			(start 0.750062 1.560068)
			(end -0.750062 1.560068)
			(stroke
				(width 0.1)
				(type default)
			)
			(layer "F.Fab")
		)
		(fp_line
			(start -0.750062 -1.560068)
			(end 0.750062 -1.560068)
			(stroke
				(width 0.1)
				(type default)
			)
			(layer "F.Fab")
		)
		(fp_line
			(start 0.750062 -1.560068)
			(end 0.750062 1.560068)
			(stroke
				(width 0.1)
				(type default)
			)
			(layer "F.Fab")
		)
		(pad "D" smd rect
			(at 1.100074 0 180)
			(size 1.016 1.4224)
			(layers "F.Cu" "F.Mask" "F.Paste")
			(net "SSD13_LED_ISO_N")
		)
		(pad "G" smd rect
			(at -1.100074 -0.94996 180)
			(size 1.016 1.4224)
			(layers "F.Cu" "F.Mask" "F.Paste")
			(net "SSD13_LED_R")
		)
		(pad "S" smd rect
			(at -1.100074 0.94996 180)
			(size 1.016 1.4224)
			(layers "F.Cu" "F.Mask" "F.Paste")
			(net "GND")
		)
	)
	(footprint ""
		(layer "F.Cu")
		(at 38.608 -160.380934)
		(property "Reference" "R23"
			(at 0 0 0)
			(layer "F.SilkS")
			(hide yes)
			(effects
				(font
					(size 1.27 1.27)
				)
			)
		)
		(property "Value" ""
			(at 0 0 0)
			(layer "F.Fab")
			(effects
				(font
					(size 1.27 1.27)
				)
			)
		)
		(duplicate_pad_numbers_are_jumpers no)
		(fp_line
			(start -0.7874 -0.4064)
			(end 0.7874 -0.4064)
			(stroke
				(width 0.1524)
				(type default)
			)
			(layer "F.SilkS")
		)
		(fp_line
			(start -0.7874 0.4064)
			(end -0.7874 -0.4064)
			(stroke
				(width 0.1524)
				(type default)
			)
			(layer "F.SilkS")
		)
		(fp_line
			(start 0.7874 -0.4064)
			(end 0.7874 0.4064)
			(stroke
				(width 0.1524)
				(type default)
			)
			(layer "F.SilkS")
		)
		(fp_line
			(start 0.7874 0.4064)
			(end -0.7874 0.4064)
			(stroke
				(width 0.1524)
				(type default)
			)
			(layer "F.SilkS")
		)
		(fp_line
			(start -0.67945 -0.305054)
			(end -0.12065 -0.305054)
			(stroke
				(width 0.1)
				(type default)
			)
			(layer "F.Fab")
		)
		(fp_line
			(start -0.67945 0.3048)
			(end -0.67945 -0.305054)
			(stroke
				(width 0.1)
				(type default)
			)
			(layer "F.Fab")
		)
		(fp_line
			(start -0.12065 -0.305054)
			(end -0.12065 -0.2794)
			(stroke
				(width 0.1)
				(type default)
			)
			(layer "F.Fab")
		)
		(fp_line
			(start -0.12065 -0.2794)
			(end 0.12065 -0.2794)
			(stroke
				(width 0.1)
				(type default)
			)
			(layer "F.Fab")
		)
		(fp_line
			(start -0.12065 0.2794)
			(end -0.12065 0.3048)
			(stroke
				(width 0.1)
				(type default)
			)
			(layer "F.Fab")
		)
		(fp_line
			(start -0.12065 0.3048)
			(end -0.67945 0.3048)
			(stroke
				(width 0.1)
				(type default)
			)
			(layer "F.Fab")
		)
		(fp_line
			(start 0.120396 0.2794)
			(end -0.12065 0.2794)
			(stroke
				(width 0.1)
				(type default)
			)
			(layer "F.Fab")
		)
		(fp_line
			(start 0.120396 0.3048)
			(end 0.120396 0.2794)
			(stroke
				(width 0.1)
				(type default)
			)
			(layer "F.Fab")
		)
		(fp_line
			(start 0.12065 -0.3048)
			(end 0.67945 -0.3048)
			(stroke
				(width 0.1)
				(type default)
			)
			(layer "F.Fab")
		)
		(fp_line
			(start 0.12065 -0.2794)
			(end 0.12065 -0.3048)
			(stroke
				(width 0.1)
				(type default)
			)
			(layer "F.Fab")
		)
		(fp_line
			(start 0.67945 -0.3048)
			(end 0.67945 0.3048)
			(stroke
				(width 0.1)
				(type default)
			)
			(layer "F.Fab")
		)
		(fp_line
			(start 0.67945 0.3048)
			(end 0.120396 0.3048)
			(stroke
				(width 0.1)
				(type default)
			)
			(layer "F.Fab")
		)
		(pad "1" smd circle
			(at -0.40005 0)
			(size 0 0)
			(layers "F.Cu" "F.Mask" "F.Paste")
			(net "NIC0_MAIN_PWR_EN")
		)
		(pad "2" smd circle
			(at 0.40005 0)
			(size 0 0)
			(layers "F.Cu" "F.Mask" "F.Paste")
			(net "GND")
		)
	)
	(footprint ""
		(layer "F.Cu")
		(at 141.931644 -390.171686 -90)
		(property "Reference" "R4106"
			(at 0 0 270)
			(layer "F.SilkS")
			(hide yes)
			(effects
				(font
					(size 1.27 1.27)
				)
			)
		)
		(property "Value" ""
			(at 0 0 270)
			(layer "F.Fab")
			(effects
				(font
					(size 1.27 1.27)
				)
			)
		)
		(duplicate_pad_numbers_are_jumpers no)
		(fp_line
			(start -0.7874 0.4064)
			(end -0.7874 -0.4064)
			(stroke
				(width 0.1524)
				(type default)
			)
			(layer "F.SilkS")
		)
		(fp_line
			(start 0.7874 0.4064)
			(end -0.7874 0.4064)
			(stroke
				(width 0.1524)
				(type default)
			)
			(layer "F.SilkS")
		)
		(fp_line
			(start -0.7874 -0.4064)
			(end 0.7874 -0.4064)
			(stroke
				(width 0.1524)
				(type default)
			)
			(layer "F.SilkS")
		)
		(fp_line
			(start 0.7874 -0.4064)
			(end 0.7874 0.4064)
			(stroke
				(width 0.1524)
				(type default)
			)
			(layer "F.SilkS")
		)
		(fp_line
			(start -0.67945 0.3048)
			(end -0.67945 -0.305054)
			(stroke
				(width 0.1)
				(type default)
			)
			(layer "F.Fab")
		)
		(fp_line
			(start -0.12065 0.3048)
			(end -0.67945 0.3048)
			(stroke
				(width 0.1)
				(type default)
			)
			(layer "F.Fab")
		)
		(fp_line
			(start 0.120396 0.3048)
			(end 0.120396 0.2794)
			(stroke
				(width 0.1)
				(type default)
			)
			(layer "F.Fab")
		)
		(fp_line
			(start 0.67945 0.3048)
			(end 0.120396 0.3048)
			(stroke
				(width 0.1)
				(type default)
			)
			(layer "F.Fab")
		)
		(fp_line
			(start -0.12065 0.2794)
			(end -0.12065 0.3048)
			(stroke
				(width 0.1)
				(type default)
			)
			(layer "F.Fab")
		)
		(fp_line
			(start 0.120396 0.2794)
			(end -0.12065 0.2794)
			(stroke
				(width 0.1)
				(type default)
			)
			(layer "F.Fab")
		)
		(fp_line
			(start -0.12065 -0.2794)
			(end 0.12065 -0.2794)
			(stroke
				(width 0.1)
				(type default)
			)
			(layer "F.Fab")
		)
		(fp_line
			(start 0.12065 -0.2794)
			(end 0.12065 -0.3048)
			(stroke
				(width 0.1)
				(type default)
			)
			(layer "F.Fab")
		)
		(fp_line
			(start 0.12065 -0.3048)
			(end 0.67945 -0.3048)
			(stroke
				(width 0.1)
				(type default)
			)
			(layer "F.Fab")
		)
		(fp_line
			(start 0.67945 -0.3048)
			(end 0.67945 0.3048)
			(stroke
				(width 0.1)
				(type default)
			)
			(layer "F.Fab")
		)
		(fp_line
			(start -0.67945 -0.305054)
			(end -0.12065 -0.305054)
			(stroke
				(width 0.1)
				(type default)
			)
			(layer "F.Fab")
		)
		(fp_line
			(start -0.12065 -0.305054)
			(end -0.12065 -0.2794)
			(stroke
				(width 0.1)
				(type default)
			)
			(layer "F.Fab")
		)
		(pad "1" smd circle
			(at -0.40005 0 270)
			(size 0 0)
			(layers "F.Cu" "F.Mask" "F.Paste")
			(net "SMB_MB_BMC_SDA")
		)
		(pad "2" smd circle
			(at 0.40005 0 270)
			(size 0 0)
			(layers "F.Cu" "F.Mask" "F.Paste")
			(net "SMB_MB_BMC_R_SDA")
		)
	)
	(footprint ""
		(layer "F.Cu")
		(at 252.971046 -145.189956 180)
		(property "Reference" "R734"
			(at 0 0 180)
			(layer "F.SilkS")
			(hide yes)
			(effects
				(font
					(size 1.27 1.27)
				)
			)
		)
		(property "Value" ""
			(at 0 0 180)
			(layer "F.Fab")
			(effects
				(font
					(size 1.27 1.27)
				)
			)
		)
		(duplicate_pad_numbers_are_jumpers no)
		(fp_line
			(start 0.7874 0.4064)
			(end -0.7874 0.4064)
			(stroke
				(width 0.1524)
				(type default)
			)
			(layer "F.SilkS")
		)
		(fp_line
			(start 0.7874 -0.4064)
			(end 0.7874 0.4064)
			(stroke
				(width 0.1524)
				(type default)
			)
			(layer "F.SilkS")
		)
		(fp_line
			(start -0.7874 0.4064)
			(end -0.7874 -0.4064)
			(stroke
				(width 0.1524)
				(type default)
			)
			(layer "F.SilkS")
		)
		(fp_line
			(start -0.7874 -0.4064)
			(end 0.7874 -0.4064)
			(stroke
				(width 0.1524)
				(type default)
			)
			(layer "F.SilkS")
		)
		(fp_line
			(start 0.67945 0.3048)
			(end 0.120396 0.3048)
			(stroke
				(width 0.1)
				(type default)
			)
			(layer "F.Fab")
		)
		(fp_line
			(start 0.67945 -0.3048)
			(end 0.67945 0.3048)
			(stroke
				(width 0.1)
				(type default)
			)
			(layer "F.Fab")
		)
		(fp_line
			(start 0.12065 -0.2794)
			(end 0.12065 -0.3048)
			(stroke
				(width 0.1)
				(type default)
			)
			(layer "F.Fab")
		)
		(fp_line
			(start 0.12065 -0.3048)
			(end 0.67945 -0.3048)
			(stroke
				(width 0.1)
				(type default)
			)
			(layer "F.Fab")
		)
		(fp_line
			(start 0.120396 0.3048)
			(end 0.120396 0.2794)
			(stroke
				(width 0.1)
				(type default)
			)
			(layer "F.Fab")
		)
		(fp_line
			(start 0.120396 0.2794)
			(end -0.12065 0.2794)
			(stroke
				(width 0.1)
				(type default)
			)
			(layer "F.Fab")
		)
		(fp_line
			(start -0.12065 0.3048)
			(end -0.67945 0.3048)
			(stroke
				(width 0.1)
				(type default)
			)
			(layer "F.Fab")
		)
		(fp_line
			(start -0.12065 0.2794)
			(end -0.12065 0.3048)
			(stroke
				(width 0.1)
				(type default)
			)
			(layer "F.Fab")
		)
		(fp_line
			(start -0.12065 -0.2794)
			(end 0.12065 -0.2794)
			(stroke
				(width 0.1)
				(type default)
			)
			(layer "F.Fab")
		)
		(fp_line
			(start -0.12065 -0.305054)
			(end -0.12065 -0.2794)
			(stroke
				(width 0.1)
				(type default)
			)
			(layer "F.Fab")
		)
		(fp_line
			(start -0.67945 0.3048)
			(end -0.67945 -0.305054)
			(stroke
				(width 0.1)
				(type default)
			)
			(layer "F.Fab")
		)
		(fp_line
			(start -0.67945 -0.305054)
			(end -0.12065 -0.305054)
			(stroke
				(width 0.1)
				(type default)
			)
			(layer "F.Fab")
		)
		(pad "1" smd circle
			(at -0.40005 0 180)
			(size 0 0)
			(layers "F.Cu" "F.Mask" "F.Paste")
			(net "P12V_NIC4")
		)
		(pad "2" smd circle
			(at 0.40005 0 180)
			(size 0 0)
			(layers "F.Cu" "F.Mask" "F.Paste")
			(net "P12V_NIC4_VIN_N")
		)
	)
	(footprint ""
		(layer "F.Cu")
		(at 119.084344 -137.565638 -90)
		(property "Reference" "PC36"
			(at 0 0 270)
			(layer "F.SilkS")
			(hide yes)
			(effects
				(font
					(size 1.27 1.27)
				)
			)
		)
		(property "Value" ""
			(at 0 0 270)
			(layer "F.Fab")
			(effects
				(font
					(size 1.27 1.27)
				)
			)
		)
		(duplicate_pad_numbers_are_jumpers no)
		(fp_line
			(start -0.7874 0.4064)
			(end -0.7874 -0.4064)
			(stroke
				(width 0.1524)
				(type default)
			)
			(layer "F.SilkS")
		)
		(fp_line
			(start 0.7874 0.4064)
			(end -0.7874 0.4064)
			(stroke
				(width 0.1524)
				(type default)
			)
			(layer "F.SilkS")
		)
		(fp_line
			(start -0.7874 -0.4064)
			(end 0.7874 -0.4064)
			(stroke
				(width 0.1524)
				(type default)
			)
			(layer "F.SilkS")
		)
		(fp_line
			(start 0.7874 -0.4064)
			(end 0.7874 0.4064)
			(stroke
				(width 0.1524)
				(type default)
			)
			(layer "F.SilkS")
		)
		(fp_line
			(start -0.67945 0.3048)
			(end -0.67945 -0.305054)
			(stroke
				(width 0.1)
				(type default)
			)
			(layer "F.Fab")
		)
		(fp_line
			(start -0.12065 0.3048)
			(end -0.67945 0.3048)
			(stroke
				(width 0.1)
				(type default)
			)
			(layer "F.Fab")
		)
		(fp_line
			(start 0.120396 0.3048)
			(end 0.120396 0.2794)
			(stroke
				(width 0.1)
				(type default)
			)
			(layer "F.Fab")
		)
		(fp_line
			(start 0.67945 0.3048)
			(end 0.120396 0.3048)
			(stroke
				(width 0.1)
				(type default)
			)
			(layer "F.Fab")
		)
		(fp_line
			(start -0.12065 0.2794)
			(end -0.12065 0.3048)
			(stroke
				(width 0.1)
				(type default)
			)
			(layer "F.Fab")
		)
		(fp_line
			(start 0.120396 0.2794)
			(end -0.12065 0.2794)
			(stroke
				(width 0.1)
				(type default)
			)
			(layer "F.Fab")
		)
		(fp_line
			(start -0.12065 -0.2794)
			(end 0.12065 -0.2794)
			(stroke
				(width 0.1)
				(type default)
			)
			(layer "F.Fab")
		)
		(fp_line
			(start 0.12065 -0.2794)
			(end 0.12065 -0.3048)
			(stroke
				(width 0.1)
				(type default)
			)
			(layer "F.Fab")
		)
		(fp_line
			(start 0.12065 -0.3048)
			(end 0.67945 -0.3048)
			(stroke
				(width 0.1)
				(type default)
			)
			(layer "F.Fab")
		)
		(fp_line
			(start 0.67945 -0.3048)
			(end 0.67945 0.3048)
			(stroke
				(width 0.1)
				(type default)
			)
			(layer "F.Fab")
		)
		(fp_line
			(start -0.67945 -0.305054)
			(end -0.12065 -0.305054)
			(stroke
				(width 0.1)
				(type default)
			)
			(layer "F.Fab")
		)
		(fp_line
			(start -0.12065 -0.305054)
			(end -0.12065 -0.2794)
			(stroke
				(width 0.1)
				(type default)
			)
			(layer "F.Fab")
		)
		(pad "1" smd circle
			(at -0.40005 0 270)
			(size 0 0)
			(layers "F.Cu" "F.Mask" "F.Paste")
			(net "P3V3_AUX")
		)
		(pad "2" smd circle
			(at 0.40005 0 270)
			(size 0 0)
			(layers "F.Cu" "F.Mask" "F.Paste")
			(net "GND")
		)
	)
	(footprint ""
		(layer "F.Cu")
		(at 199.399906 -393.100052)
		(property "Reference" "H58"
			(at -4.9784 -4.985766 0)
			(unlocked yes)
			(layer "F.SilkS")
			(effects
				(font
					(size 0.7874 0.5842)
					(thickness 0.1524)
				)
				(justify left)
			)
		)
		(property "Value" ""
			(at 0 0 0)
			(layer "F.Fab")
			(effects
				(font
					(size 1.27 1.27)
				)
			)
		)
		(duplicate_pad_numbers_are_jumpers no)
		(pad "1" thru_hole circle
			(at 0 0)
			(size 10.0076 10.0076)
			(drill 5.6134)
			(layers "*.Cu" "*.Mask")
			(remove_unused_layers no)
			(net "GND")
			(clearance -1.9431)
		)
	)
	(footprint ""
		(layer "F.Cu")
		(at 270.807942 -156.3624 180)
		(property "Reference" "R217"
			(at 0 0 180)
			(layer "F.SilkS")
			(hide yes)
			(effects
				(font
					(size 1.27 1.27)
				)
			)
		)
		(property "Value" ""
			(at 0 0 180)
			(layer "F.Fab")
			(effects
				(font
					(size 1.27 1.27)
				)
			)
		)
		(duplicate_pad_numbers_are_jumpers no)
		(fp_line
			(start 0.7874 0.4064)
			(end -0.7874 0.4064)
			(stroke
				(width 0.1524)
				(type default)
			)
			(layer "F.SilkS")
		)
		(fp_line
			(start 0.7874 -0.4064)
			(end 0.7874 0.4064)
			(stroke
				(width 0.1524)
				(type default)
			)
			(layer "F.SilkS")
		)
		(fp_line
			(start -0.7874 0.4064)
			(end -0.7874 -0.4064)
			(stroke
				(width 0.1524)
				(type default)
			)
			(layer "F.SilkS")
		)
		(fp_line
			(start -0.7874 -0.4064)
			(end 0.7874 -0.4064)
			(stroke
				(width 0.1524)
				(type default)
			)
			(layer "F.SilkS")
		)
		(fp_line
			(start 0.67945 0.3048)
			(end 0.120396 0.3048)
			(stroke
				(width 0.1)
				(type default)
			)
			(layer "F.Fab")
		)
		(fp_line
			(start 0.67945 -0.3048)
			(end 0.67945 0.3048)
			(stroke
				(width 0.1)
				(type default)
			)
			(layer "F.Fab")
		)
		(fp_line
			(start 0.12065 -0.2794)
			(end 0.12065 -0.3048)
			(stroke
				(width 0.1)
				(type default)
			)
			(layer "F.Fab")
		)
		(fp_line
			(start 0.12065 -0.3048)
			(end 0.67945 -0.3048)
			(stroke
				(width 0.1)
				(type default)
			)
			(layer "F.Fab")
		)
		(fp_line
			(start 0.120396 0.3048)
			(end 0.120396 0.2794)
			(stroke
				(width 0.1)
				(type default)
			)
			(layer "F.Fab")
		)
		(fp_line
			(start 0.120396 0.2794)
			(end -0.12065 0.2794)
			(stroke
				(width 0.1)
				(type default)
			)
			(layer "F.Fab")
		)
		(fp_line
			(start -0.12065 0.3048)
			(end -0.67945 0.3048)
			(stroke
				(width 0.1)
				(type default)
			)
			(layer "F.Fab")
		)
		(fp_line
			(start -0.12065 0.2794)
			(end -0.12065 0.3048)
			(stroke
				(width 0.1)
				(type default)
			)
			(layer "F.Fab")
		)
		(fp_line
			(start -0.12065 -0.2794)
			(end 0.12065 -0.2794)
			(stroke
				(width 0.1)
				(type default)
			)
			(layer "F.Fab")
		)
		(fp_line
			(start -0.12065 -0.305054)
			(end -0.12065 -0.2794)
			(stroke
				(width 0.1)
				(type default)
			)
			(layer "F.Fab")
		)
		(fp_line
			(start -0.67945 0.3048)
			(end -0.67945 -0.305054)
			(stroke
				(width 0.1)
				(type default)
			)
			(layer "F.Fab")
		)
		(fp_line
			(start -0.67945 -0.305054)
			(end -0.12065 -0.305054)
			(stroke
				(width 0.1)
				(type default)
			)
			(layer "F.Fab")
		)
		(pad "1" smd circle
			(at -0.40005 0 180)
			(size 0 0)
			(layers "F.Cu" "F.Mask" "F.Paste")
			(net "NIC4_DATA_OUT")
		)
		(pad "2" smd circle
			(at 0.40005 0 180)
			(size 0 0)
			(layers "F.Cu" "F.Mask" "F.Paste")
			(net "GND")
		)
	)
	(footprint ""
		(layer "F.Cu")
		(at 402.25218 -343.952322 90)
		(property "Reference" "C732"
			(at 0 0 90)
			(layer "F.SilkS")
			(hide yes)
			(effects
				(font
					(size 1.27 1.27)
				)
			)
		)
		(property "Value" ""
			(at 0 0 90)
			(layer "F.Fab")
			(effects
				(font
					(size 1.27 1.27)
				)
			)
		)
		(duplicate_pad_numbers_are_jumpers no)
		(fp_line
			(start 0.299974 -0.150114)
			(end 0.299974 0.150114)
			(stroke
				(width 0.1)
				(type default)
			)
			(layer "F.Fab")
		)
		(fp_line
			(start -0.299974 -0.150114)
			(end 0.299974 -0.150114)
			(stroke
				(width 0.1)
				(type default)
			)
			(layer "F.Fab")
		)
		(fp_line
			(start 0.299974 0.150114)
			(end -0.299974 0.150114)
			(stroke
				(width 0.1)
				(type default)
			)
			(layer "F.Fab")
		)
		(fp_line
			(start -0.299974 0.150114)
			(end -0.299974 -0.150114)
			(stroke
				(width 0.1)
				(type default)
			)
			(layer "F.Fab")
		)
		(pad "1" smd rect
			(at -0.2667 0 90)
			(size 0.3048 0.381)
			(layers "F.Cu" "F.Mask" "F.Paste")
			(net "P5E_PEX3_STN5_TX_DP<94>")
		)
		(pad "2" smd rect
			(at 0.2667 0 90)
			(size 0.3048 0.381)
			(layers "F.Cu" "F.Mask" "F.Paste")
			(net "P5E_PEX3_STN5_TX_C_DP<94>")
		)
	)
	(footprint ""
		(layer "F.Cu")
		(at 100.955094 -397.512286 -90)
		(property "Reference" "R5452"
			(at 0 0 270)
			(layer "F.SilkS")
			(hide yes)
			(effects
				(font
					(size 1.27 1.27)
				)
			)
		)
		(property "Value" ""
			(at 0 0 270)
			(layer "F.Fab")
			(effects
				(font
					(size 1.27 1.27)
				)
			)
		)
		(duplicate_pad_numbers_are_jumpers no)
		(fp_line
			(start -0.7874 0.4064)
			(end -0.7874 -0.4064)
			(stroke
				(width 0.1524)
				(type default)
			)
			(layer "F.SilkS")
		)
		(fp_line
			(start 0.7874 0.4064)
			(end -0.7874 0.4064)
			(stroke
				(width 0.1524)
				(type default)
			)
			(layer "F.SilkS")
		)
		(fp_line
			(start -0.7874 -0.4064)
			(end 0.7874 -0.4064)
			(stroke
				(width 0.1524)
				(type default)
			)
			(layer "F.SilkS")
		)
		(fp_line
			(start 0.7874 -0.4064)
			(end 0.7874 0.4064)
			(stroke
				(width 0.1524)
				(type default)
			)
			(layer "F.SilkS")
		)
		(fp_line
			(start -0.67945 0.3048)
			(end -0.67945 -0.305054)
			(stroke
				(width 0.1)
				(type default)
			)
			(layer "F.Fab")
		)
		(fp_line
			(start -0.12065 0.3048)
			(end -0.67945 0.3048)
			(stroke
				(width 0.1)
				(type default)
			)
			(layer "F.Fab")
		)
		(fp_line
			(start 0.120396 0.3048)
			(end 0.120396 0.2794)
			(stroke
				(width 0.1)
				(type default)
			)
			(layer "F.Fab")
		)
		(fp_line
			(start 0.67945 0.3048)
			(end 0.120396 0.3048)
			(stroke
				(width 0.1)
				(type default)
			)
			(layer "F.Fab")
		)
		(fp_line
			(start -0.12065 0.2794)
			(end -0.12065 0.3048)
			(stroke
				(width 0.1)
				(type default)
			)
			(layer "F.Fab")
		)
		(fp_line
			(start 0.120396 0.2794)
			(end -0.12065 0.2794)
			(stroke
				(width 0.1)
				(type default)
			)
			(layer "F.Fab")
		)
		(fp_line
			(start -0.12065 -0.2794)
			(end 0.12065 -0.2794)
			(stroke
				(width 0.1)
				(type default)
			)
			(layer "F.Fab")
		)
		(fp_line
			(start 0.12065 -0.2794)
			(end 0.12065 -0.3048)
			(stroke
				(width 0.1)
				(type default)
			)
			(layer "F.Fab")
		)
		(fp_line
			(start 0.12065 -0.3048)
			(end 0.67945 -0.3048)
			(stroke
				(width 0.1)
				(type default)
			)
			(layer "F.Fab")
		)
		(fp_line
			(start 0.67945 -0.3048)
			(end 0.67945 0.3048)
			(stroke
				(width 0.1)
				(type default)
			)
			(layer "F.Fab")
		)
		(fp_line
			(start -0.67945 -0.305054)
			(end -0.12065 -0.305054)
			(stroke
				(width 0.1)
				(type default)
			)
			(layer "F.Fab")
		)
		(fp_line
			(start -0.12065 -0.305054)
			(end -0.12065 -0.2794)
			(stroke
				(width 0.1)
				(type default)
			)
			(layer "F.Fab")
		)
		(pad "1" smd circle
			(at -0.40005 0 270)
			(size 0 0)
			(layers "F.Cu" "F.Mask" "F.Paste")
			(net "P3V3_AUX")
		)
		(pad "2" smd circle
			(at 0.40005 0 270)
			(size 0 0)
			(layers "F.Cu" "F.Mask" "F.Paste")
			(net "BIC_USB_HUB_OVCUR3")
		)
	)
	(footprint ""
		(layer "F.Cu")
		(at 86.218522 -356.244906 90)
		(property "Reference" "C153"
			(at 0 0 90)
			(layer "F.SilkS")
			(hide yes)
			(effects
				(font
					(size 1.27 1.27)
				)
			)
		)
		(property "Value" ""
			(at 0 0 90)
			(layer "F.Fab")
			(effects
				(font
					(size 1.27 1.27)
				)
			)
		)
		(duplicate_pad_numbers_are_jumpers no)
		(fp_line
			(start 0.299974 -0.150114)
			(end 0.299974 0.150114)
			(stroke
				(width 0.1)
				(type default)
			)
			(layer "F.Fab")
		)
		(fp_line
			(start -0.299974 -0.150114)
			(end 0.299974 -0.150114)
			(stroke
				(width 0.1)
				(type default)
			)
			(layer "F.Fab")
		)
		(fp_line
			(start 0.299974 0.150114)
			(end -0.299974 0.150114)
			(stroke
				(width 0.1)
				(type default)
			)
			(layer "F.Fab")
		)
		(fp_line
			(start -0.299974 0.150114)
			(end -0.299974 -0.150114)
			(stroke
				(width 0.1)
				(type default)
			)
			(layer "F.Fab")
		)
		(pad "1" smd rect
			(at -0.2667 0 90)
			(size 0.3048 0.381)
			(layers "F.Cu" "F.Mask" "F.Paste")
			(net "P5E_PEX0_STN6_TX_DP<99>")
		)
		(pad "2" smd rect
			(at 0.2667 0 90)
			(size 0.3048 0.381)
			(layers "F.Cu" "F.Mask" "F.Paste")
			(net "P5E_PEX0_STN6_TX_C_DP<99>")
		)
	)
	(footprint ""
		(layer "F.Cu")
		(at 422.185592 -25.1587 -90)
		(property "Reference" "R5748"
			(at 0 0 270)
			(layer "F.SilkS")
			(hide yes)
			(effects
				(font
					(size 1.27 1.27)
				)
			)
		)
		(property "Value" ""
			(at 0 0 270)
			(layer "F.Fab")
			(effects
				(font
					(size 1.27 1.27)
				)
			)
		)
		(duplicate_pad_numbers_are_jumpers no)
		(fp_line
			(start -0.7874 0.4064)
			(end -0.7874 -0.4064)
			(stroke
				(width 0.1524)
				(type default)
			)
			(layer "F.SilkS")
		)
		(fp_line
			(start 0.7874 0.4064)
			(end -0.7874 0.4064)
			(stroke
				(width 0.1524)
				(type default)
			)
			(layer "F.SilkS")
		)
		(fp_line
			(start -0.7874 -0.4064)
			(end 0.7874 -0.4064)
			(stroke
				(width 0.1524)
				(type default)
			)
			(layer "F.SilkS")
		)
		(fp_line
			(start 0.7874 -0.4064)
			(end 0.7874 0.4064)
			(stroke
				(width 0.1524)
				(type default)
			)
			(layer "F.SilkS")
		)
		(fp_line
			(start -0.67945 0.3048)
			(end -0.67945 -0.305054)
			(stroke
				(width 0.1)
				(type default)
			)
			(layer "F.Fab")
		)
		(fp_line
			(start -0.12065 0.3048)
			(end -0.67945 0.3048)
			(stroke
				(width 0.1)
				(type default)
			)
			(layer "F.Fab")
		)
		(fp_line
			(start 0.120396 0.3048)
			(end 0.120396 0.2794)
			(stroke
				(width 0.1)
				(type default)
			)
			(layer "F.Fab")
		)
		(fp_line
			(start 0.67945 0.3048)
			(end 0.120396 0.3048)
			(stroke
				(width 0.1)
				(type default)
			)
			(layer "F.Fab")
		)
		(fp_line
			(start -0.12065 0.2794)
			(end -0.12065 0.3048)
			(stroke
				(width 0.1)
				(type default)
			)
			(layer "F.Fab")
		)
		(fp_line
			(start 0.120396 0.2794)
			(end -0.12065 0.2794)
			(stroke
				(width 0.1)
				(type default)
			)
			(layer "F.Fab")
		)
		(fp_line
			(start -0.12065 -0.2794)
			(end 0.12065 -0.2794)
			(stroke
				(width 0.1)
				(type default)
			)
			(layer "F.Fab")
		)
		(fp_line
			(start 0.12065 -0.2794)
			(end 0.12065 -0.3048)
			(stroke
				(width 0.1)
				(type default)
			)
			(layer "F.Fab")
		)
		(fp_line
			(start 0.12065 -0.3048)
			(end 0.67945 -0.3048)
			(stroke
				(width 0.1)
				(type default)
			)
			(layer "F.Fab")
		)
		(fp_line
			(start 0.67945 -0.3048)
			(end 0.67945 0.3048)
			(stroke
				(width 0.1)
				(type default)
			)
			(layer "F.Fab")
		)
		(fp_line
			(start -0.67945 -0.305054)
			(end -0.12065 -0.305054)
			(stroke
				(width 0.1)
				(type default)
			)
			(layer "F.Fab")
		)
		(fp_line
			(start -0.12065 -0.305054)
			(end -0.12065 -0.2794)
			(stroke
				(width 0.1)
				(type default)
			)
			(layer "F.Fab")
		)
		(pad "1" smd circle
			(at -0.40005 0 270)
			(size 0 0)
			(layers "F.Cu" "F.Mask" "F.Paste")
			(net "SSD14_LED_ISO_N")
		)
		(pad "2" smd circle
			(at 0.40005 0 270)
			(size 0 0)
			(layers "F.Cu" "F.Mask" "F.Paste")
			(net "SSD14_LED_ISO_R_N")
		)
	)
	(footprint ""
		(layer "F.Cu")
		(at 141.70533 -189.778132)
		(property "Reference" "U440"
			(at -3.61315 1.373632 0)
			(unlocked yes)
			(layer "F.SilkS")
			(effects
				(font
					(size 0.7874 0.5842)
					(thickness 0.1524)
				)
			)
		)
		(property "Value" ""
			(at 0 0 0)
			(layer "F.Fab")
			(effects
				(font
					(size 1.27 1.27)
				)
			)
		)
		(duplicate_pad_numbers_are_jumpers no)
		(fp_line
			(start -1.7272 1.1176)
			(end -1.7272 -1.1176)
			(stroke
				(width 0.1524)
				(type default)
			)
			(layer "F.SilkS")
		)
		(fp_line
			(start -0.254 -1.1176)
			(end -1.7272 -1.1176)
			(stroke
				(width 0.1524)
				(type default)
			)
			(layer "F.SilkS")
		)
		(fp_line
			(start 0 -0.7366)
			(end -0.254 -1.1176)
			(stroke
				(width 0.1524)
				(type default)
			)
			(layer "F.SilkS")
		)
		(fp_line
			(start 0.254 -1.1176)
			(end 0 -0.7366)
			(stroke
				(width 0.1524)
				(type default)
			)
			(layer "F.SilkS")
		)
		(fp_line
			(start 1.7272 -1.1176)
			(end 0.254 -1.1176)
			(stroke
				(width 0.1524)
				(type default)
			)
			(layer "F.SilkS")
		)
		(fp_line
			(start 1.7272 -1.1176)
			(end 1.7272 1.1176)
			(stroke
				(width 0.1524)
				(type default)
			)
			(layer "F.SilkS")
		)
		(fp_line
			(start 1.7272 1.1176)
			(end -1.7272 1.1176)
			(stroke
				(width 0.1524)
				(type default)
			)
			(layer "F.SilkS")
		)
		(fp_poly
			(pts
				(xy -1.9558 -0.649986) (xy -2.7178 -0.268986) (xy -2.7178 -1.030986)
			)
			(stroke
				(width 0)
				(type default)
			)
			(fill yes)
			(layer "F.SilkS")
		)
		(fp_line
			(start -1.5748 -1.1176)
			(end -1.5748 1.1176)
			(stroke
				(width 0.1)
				(type default)
			)
			(layer "F.Fab")
		)
		(fp_line
			(start -1.5748 1.1176)
			(end 1.5748 1.1176)
			(stroke
				(width 0.1)
				(type default)
			)
			(layer "F.Fab")
		)
		(fp_line
			(start 1.5748 -1.1176)
			(end -1.5748 -1.1176)
			(stroke
				(width 0.1)
				(type default)
			)
			(layer "F.Fab")
		)
		(fp_line
			(start 1.5748 1.1176)
			(end 1.5748 -1.1176)
			(stroke
				(width 0.1)
				(type default)
			)
			(layer "F.Fab")
		)
		(fp_poly
			(pts
				(xy -1.9558 -0.649986) (xy -2.7178 -0.268986) (xy -2.7178 -1.030986)
			)
			(stroke
				(width 0)
				(type default)
			)
			(fill yes)
			(layer "F.Fab")
		)
		(pad "1" smd rect
			(at -0.999998 -0.649986 270)
			(size 0.3556 1.1176)
			(layers "F.Cu" "F.Mask" "F.Paste")
			(net "NIC4_CLK_EN_R_N")
		)
		(pad "2" smd rect
			(at -0.999998 0 270)
			(size 0.3556 1.1176)
			(layers "F.Cu" "F.Mask" "F.Paste")
			(net "GND")
		)
		(pad "3" smd rect
			(at -0.999998 0.649986 270)
			(size 0.3556 1.1176)
			(layers "F.Cu" "F.Mask" "F.Paste")
			(net "NIC5_CLK_EN_R_N")
		)
		(pad "4" smd rect
			(at 0.999998 0.649986 270)
			(size 0.3556 1.1176)
			(layers "F.Cu" "F.Mask" "F.Paste")
			(net "NIC5_CLK_EN_BUF_N")
		)
		(pad "5" smd rect
			(at 0.999998 0 270)
			(size 0.3556 1.1176)
			(layers "F.Cu" "F.Mask" "F.Paste")
			(net "P3V3_AUX")
		)
		(pad "6" smd rect
			(at 0.999998 -0.649986 270)
			(size 0.3556 1.1176)
			(layers "F.Cu" "F.Mask" "F.Paste")
			(net "NIC4_CLK_EN_BUF_N")
		)
	)
	(footprint ""
		(layer "F.Cu")
		(at 367.415318 -239.30102)
		(property "Reference" "U429"
			(at -1.0922 -2.174748 0)
			(unlocked yes)
			(layer "F.SilkS")
			(effects
				(font
					(size 0.7874 0.5842)
					(thickness 0.1524)
				)
				(justify left)
			)
		)
		(property "Value" ""
			(at 0 0 0)
			(layer "F.Fab")
			(effects
				(font
					(size 1.27 1.27)
				)
			)
		)
		(duplicate_pad_numbers_are_jumpers no)
		(fp_line
			(start -1.0414 -1.575054)
			(end -0.254 -1.575054)
			(stroke
				(width 0.1524)
				(type default)
			)
			(layer "F.SilkS")
		)
		(fp_line
			(start -1.0414 1.575054)
			(end -1.0414 -1.575054)
			(stroke
				(width 0.1524)
				(type default)
			)
			(layer "F.SilkS")
		)
		(fp_line
			(start 0 -1.272032)
			(end -0.254 -1.575054)
			(stroke
				(width 0.1524)
				(type default)
			)
			(layer "F.SilkS")
		)
		(fp_line
			(start 0.2286 -1.575054)
			(end 0 -1.272032)
			(stroke
				(width 0.1524)
				(type default)
			)
			(layer "F.SilkS")
		)
		(fp_line
			(start 0.254 -1.575054)
			(end 1.0414 -1.575054)
			(stroke
				(width 0.1524)
				(type default)
			)
			(layer "F.SilkS")
		)
		(fp_line
			(start 1.0414 -1.575054)
			(end 1.0414 1.575054)
			(stroke
				(width 0.1524)
				(type default)
			)
			(layer "F.SilkS")
		)
		(fp_line
			(start 1.0414 1.575054)
			(end -1.0414 1.575054)
			(stroke
				(width 0.1524)
				(type default)
			)
			(layer "F.SilkS")
		)
		(fp_poly
			(pts
				(xy -3.064256 -1.629156) (xy -3.423412 -2.706878) (xy -4.141724 -1.988312)
			)
			(stroke
				(width 0)
				(type default)
			)
			(fill yes)
			(layer "F.SilkS")
		)
		(fp_line
			(start -2.5654 -1.2192)
			(end -1.4478 -1.2192)
			(stroke
				(width 0.1)
				(type default)
			)
			(layer "F.Fab")
		)
		(fp_line
			(start -2.5654 1.2192)
			(end -2.5654 -1.2192)
			(stroke
				(width 0.1)
				(type default)
			)
			(layer "F.Fab")
		)
		(fp_line
			(start -1.4478 -1.5748)
			(end 1.4478 -1.5748)
			(stroke
				(width 0.1)
				(type default)
			)
			(layer "F.Fab")
		)
		(fp_line
			(start -1.4478 -1.2192)
			(end -1.4478 -1.5748)
			(stroke
				(width 0.1)
				(type default)
			)
			(layer "F.Fab")
		)
		(fp_line
			(start -1.4478 1.2192)
			(end -2.5654 1.2192)
			(stroke
				(width 0.1)
				(type default)
			)
			(layer "F.Fab")
		)
		(fp_line
			(start -1.4478 1.5748)
			(end -1.4478 1.2192)
			(stroke
				(width 0.1)
				(type default)
			)
			(layer "F.Fab")
		)
		(fp_line
			(start 1.4478 -1.5748)
			(end 1.4478 -1.2192)
			(stroke
				(width 0.1)
				(type default)
			)
			(layer "F.Fab")
		)
		(fp_line
			(start 1.4478 -1.2192)
			(end 2.5654 -1.2192)
			(stroke
				(width 0.1)
				(type default)
			)
			(layer "F.Fab")
		)
		(fp_line
			(start 1.4478 1.2192)
			(end 1.4478 1.5748)
			(stroke
				(width 0.1)
				(type default)
			)
			(layer "F.Fab")
		)
		(fp_line
			(start 1.4478 1.5748)
			(end -1.4478 1.5748)
			(stroke
				(width 0.1)
				(type default)
			)
			(layer "F.Fab")
		)
		(fp_line
			(start 2.5654 -1.2192)
			(end 2.5654 1.2192)
			(stroke
				(width 0.1)
				(type default)
			)
			(layer "F.Fab")
		)
		(fp_line
			(start 2.5654 1.2192)
			(end 1.4478 1.2192)
			(stroke
				(width 0.1)
				(type default)
			)
			(layer "F.Fab")
		)
		(fp_poly
			(pts
				(xy -2.710688 -0.975106) (xy -3.726688 -1.483106) (xy -3.726688 -0.467106)
			)
			(stroke
				(width 0)
				(type default)
			)
			(fill yes)
			(layer "F.Fab")
		)
		(pad "1" smd rect
			(at -1.849882 -0.975106 270)
			(size 0.3556 1.3208)
			(layers "F.Cu" "F.Mask" "F.Paste")
			(net "PWRGD_P12V_AUX_R1")
		)
		(pad "2" smd rect
			(at -1.849882 -0.32512 270)
			(size 0.3556 1.3208)
			(layers "F.Cu" "F.Mask" "F.Paste")
			(net "PWRGD_P3V3_AUX_BUF")
		)
		(pad "3" smd rect
			(at -1.849882 0.32512 270)
			(size 0.3556 1.3208)
			(layers "F.Cu" "F.Mask" "F.Paste")
			(net "PWRGD_P5V_AUX_R2")
		)
		(pad "4" smd rect
			(at -1.849882 0.975106 270)
			(size 0.3556 1.3208)
			(layers "F.Cu" "F.Mask" "F.Paste")
			(net "GND")
		)
		(pad "5" smd rect
			(at 1.849882 0.975106 270)
			(size 0.3556 1.3208)
			(layers "F.Cu" "F.Mask" "F.Paste")
			(net "PWRGD_P5V_AUX_BUF")
		)
		(pad "6" smd rect
			(at 1.849882 0.32512 270)
			(size 0.3556 1.3208)
			(layers "F.Cu" "F.Mask" "F.Paste")
			(net "PWRGD_P3V3_AUX_R2")
		)
		(pad "7" smd rect
			(at 1.849882 -0.32512 270)
			(size 0.3556 1.3208)
			(layers "F.Cu" "F.Mask" "F.Paste")
			(net "PWRGD_P12V_AUX_BUF")
		)
		(pad "8" smd rect
			(at 1.849882 -0.975106 270)
			(size 0.3556 1.3208)
			(layers "F.Cu" "F.Mask" "F.Paste")
			(net "P3V3_AUX")
		)
	)
	(footprint ""
		(layer "F.Cu")
		(at 327.53173 -226.000818)
		(property "Reference" "R6178"
			(at 0 0 0)
			(layer "F.SilkS")
			(hide yes)
			(effects
				(font
					(size 1.27 1.27)
				)
			)
		)
		(property "Value" ""
			(at 0 0 0)
			(layer "F.Fab")
			(effects
				(font
					(size 1.27 1.27)
				)
			)
		)
		(duplicate_pad_numbers_are_jumpers no)
		(fp_line
			(start -0.7874 -0.4064)
			(end 0.7874 -0.4064)
			(stroke
				(width 0.1524)
				(type default)
			)
			(layer "F.SilkS")
		)
		(fp_line
			(start -0.7874 0.4064)
			(end -0.7874 -0.4064)
			(stroke
				(width 0.1524)
				(type default)
			)
			(layer "F.SilkS")
		)
		(fp_line
			(start 0.7874 -0.4064)
			(end 0.7874 0.4064)
			(stroke
				(width 0.1524)
				(type default)
			)
			(layer "F.SilkS")
		)
		(fp_line
			(start 0.7874 0.4064)
			(end -0.7874 0.4064)
			(stroke
				(width 0.1524)
				(type default)
			)
			(layer "F.SilkS")
		)
		(fp_line
			(start -0.67945 -0.305054)
			(end -0.12065 -0.305054)
			(stroke
				(width 0.1)
				(type default)
			)
			(layer "F.Fab")
		)
		(fp_line
			(start -0.67945 0.3048)
			(end -0.67945 -0.305054)
			(stroke
				(width 0.1)
				(type default)
			)
			(layer "F.Fab")
		)
		(fp_line
			(start -0.12065 -0.305054)
			(end -0.12065 -0.2794)
			(stroke
				(width 0.1)
				(type default)
			)
			(layer "F.Fab")
		)
		(fp_line
			(start -0.12065 -0.2794)
			(end 0.12065 -0.2794)
			(stroke
				(width 0.1)
				(type default)
			)
			(layer "F.Fab")
		)
		(fp_line
			(start -0.12065 0.2794)
			(end -0.12065 0.3048)
			(stroke
				(width 0.1)
				(type default)
			)
			(layer "F.Fab")
		)
		(fp_line
			(start -0.12065 0.3048)
			(end -0.67945 0.3048)
			(stroke
				(width 0.1)
				(type default)
			)
			(layer "F.Fab")
		)
		(fp_line
			(start 0.120396 0.2794)
			(end -0.12065 0.2794)
			(stroke
				(width 0.1)
				(type default)
			)
			(layer "F.Fab")
		)
		(fp_line
			(start 0.120396 0.3048)
			(end 0.120396 0.2794)
			(stroke
				(width 0.1)
				(type default)
			)
			(layer "F.Fab")
		)
		(fp_line
			(start 0.12065 -0.3048)
			(end 0.67945 -0.3048)
			(stroke
				(width 0.1)
				(type default)
			)
			(layer "F.Fab")
		)
		(fp_line
			(start 0.12065 -0.2794)
			(end 0.12065 -0.3048)
			(stroke
				(width 0.1)
				(type default)
			)
			(layer "F.Fab")
		)
		(fp_line
			(start 0.67945 -0.3048)
			(end 0.67945 0.3048)
			(stroke
				(width 0.1)
				(type default)
			)
			(layer "F.Fab")
		)
		(fp_line
			(start 0.67945 0.3048)
			(end 0.120396 0.3048)
			(stroke
				(width 0.1)
				(type default)
			)
			(layer "F.Fab")
		)
		(pad "1" smd circle
			(at -0.40005 0)
			(size 0 0)
			(layers "F.Cu" "F.Mask" "F.Paste")
			(net "GND")
		)
		(pad "2" smd circle
			(at 0.40005 0)
			(size 0 0)
			(layers "F.Cu" "F.Mask" "F.Paste")
			(net "PWR_EN_PEX")
		)
	)
	(footprint ""
		(layer "F.Cu")
		(at 130.88239 -184.656984 -90)
		(property "Reference" "R1116"
			(at 0 0 270)
			(layer "F.SilkS")
			(hide yes)
			(effects
				(font
					(size 1.27 1.27)
				)
			)
		)
		(property "Value" ""
			(at 0 0 270)
			(layer "F.Fab")
			(effects
				(font
					(size 1.27 1.27)
				)
			)
		)
		(duplicate_pad_numbers_are_jumpers no)
		(fp_line
			(start -0.7874 -0.4064)
			(end 0.7874 -0.4064)
			(stroke
				(width 0.1524)
				(type default)
			)
			(layer "F.SilkS")
		)
		(fp_line
			(start -0.67945 0.3048)
			(end -0.67945 -0.305054)
			(stroke
				(width 0.1)
				(type default)
			)
			(layer "F.Fab")
		)
		(fp_line
			(start -0.12065 0.3048)
			(end -0.67945 0.3048)
			(stroke
				(width 0.1)
				(type default)
			)
			(layer "F.Fab")
		)
		(fp_line
			(start 0.120396 0.3048)
			(end 0.120396 0.2794)
			(stroke
				(width 0.1)
				(type default)
			)
			(layer "F.Fab")
		)
		(fp_line
			(start 0.67945 0.3048)
			(end 0.120396 0.3048)
			(stroke
				(width 0.1)
				(type default)
			)
			(layer "F.Fab")
		)
		(fp_line
			(start -0.12065 0.2794)
			(end -0.12065 0.3048)
			(stroke
				(width 0.1)
				(type default)
			)
			(layer "F.Fab")
		)
		(fp_line
			(start 0.120396 0.2794)
			(end -0.12065 0.2794)
			(stroke
				(width 0.1)
				(type default)
			)
			(layer "F.Fab")
		)
		(fp_line
			(start -0.12065 -0.2794)
			(end 0.12065 -0.2794)
			(stroke
				(width 0.1)
				(type default)
			)
			(layer "F.Fab")
		)
		(fp_line
			(start 0.12065 -0.2794)
			(end 0.12065 -0.3048)
			(stroke
				(width 0.1)
				(type default)
			)
			(layer "F.Fab")
		)
		(fp_line
			(start 0.12065 -0.3048)
			(end 0.67945 -0.3048)
			(stroke
				(width 0.1)
				(type default)
			)
			(layer "F.Fab")
		)
		(fp_line
			(start 0.67945 -0.3048)
			(end 0.67945 0.3048)
			(stroke
				(width 0.1)
				(type default)
			)
			(layer "F.Fab")
		)
		(fp_line
			(start -0.67945 -0.305054)
			(end -0.12065 -0.305054)
			(stroke
				(width 0.1)
				(type default)
			)
			(layer "F.Fab")
		)
		(fp_line
			(start -0.12065 -0.305054)
			(end -0.12065 -0.2794)
			(stroke
				(width 0.1)
				(type default)
			)
			(layer "F.Fab")
		)
		(pad "1" smd circle
			(at -0.40005 0 270)
			(size 0 0)
			(layers "F.Cu" "F.Mask" "F.Paste")
			(net "CLK_100M_DB2000QL_GPU_REF2_R_DP")
		)
		(pad "2" smd circle
			(at 0.40005 0 270)
			(size 0 0)
			(layers "F.Cu" "F.Mask" "F.Paste")
			(net "CLK_100M_DB2000QL_GPU_REF2_DP")
		)
	)
	(footprint ""
		(layer "F.Cu")
		(at 75.65644 -17.419574 180)
		(property "Reference" "R1646"
			(at 0 0 180)
			(layer "F.SilkS")
			(hide yes)
			(effects
				(font
					(size 1.27 1.27)
				)
			)
		)
		(property "Value" ""
			(at 0 0 180)
			(layer "F.Fab")
			(effects
				(font
					(size 1.27 1.27)
				)
			)
		)
		(duplicate_pad_numbers_are_jumpers no)
		(fp_line
			(start 0.7874 0.4064)
			(end -0.7874 0.4064)
			(stroke
				(width 0.1524)
				(type default)
			)
			(layer "F.SilkS")
		)
		(fp_line
			(start 0.7874 -0.4064)
			(end 0.7874 0.4064)
			(stroke
				(width 0.1524)
				(type default)
			)
			(layer "F.SilkS")
		)
		(fp_line
			(start -0.7874 0.4064)
			(end -0.7874 -0.4064)
			(stroke
				(width 0.1524)
				(type default)
			)
			(layer "F.SilkS")
		)
		(fp_line
			(start -0.7874 -0.4064)
			(end 0.7874 -0.4064)
			(stroke
				(width 0.1524)
				(type default)
			)
			(layer "F.SilkS")
		)
		(fp_line
			(start 0.67945 0.3048)
			(end 0.120396 0.3048)
			(stroke
				(width 0.1)
				(type default)
			)
			(layer "F.Fab")
		)
		(fp_line
			(start 0.67945 -0.3048)
			(end 0.67945 0.3048)
			(stroke
				(width 0.1)
				(type default)
			)
			(layer "F.Fab")
		)
		(fp_line
			(start 0.12065 -0.2794)
			(end 0.12065 -0.3048)
			(stroke
				(width 0.1)
				(type default)
			)
			(layer "F.Fab")
		)
		(fp_line
			(start 0.12065 -0.3048)
			(end 0.67945 -0.3048)
			(stroke
				(width 0.1)
				(type default)
			)
			(layer "F.Fab")
		)
		(fp_line
			(start 0.120396 0.3048)
			(end 0.120396 0.2794)
			(stroke
				(width 0.1)
				(type default)
			)
			(layer "F.Fab")
		)
		(fp_line
			(start 0.120396 0.2794)
			(end -0.12065 0.2794)
			(stroke
				(width 0.1)
				(type default)
			)
			(layer "F.Fab")
		)
		(fp_line
			(start -0.12065 0.3048)
			(end -0.67945 0.3048)
			(stroke
				(width 0.1)
				(type default)
			)
			(layer "F.Fab")
		)
		(fp_line
			(start -0.12065 0.2794)
			(end -0.12065 0.3048)
			(stroke
				(width 0.1)
				(type default)
			)
			(layer "F.Fab")
		)
		(fp_line
			(start -0.12065 -0.2794)
			(end 0.12065 -0.2794)
			(stroke
				(width 0.1)
				(type default)
			)
			(layer "F.Fab")
		)
		(fp_line
			(start -0.12065 -0.305054)
			(end -0.12065 -0.2794)
			(stroke
				(width 0.1)
				(type default)
			)
			(layer "F.Fab")
		)
		(fp_line
			(start -0.67945 0.3048)
			(end -0.67945 -0.305054)
			(stroke
				(width 0.1)
				(type default)
			)
			(layer "F.Fab")
		)
		(fp_line
			(start -0.67945 -0.305054)
			(end -0.12065 -0.305054)
			(stroke
				(width 0.1)
				(type default)
			)
			(layer "F.Fab")
		)
		(pad "1" smd circle
			(at -0.40005 0 180)
			(size 0 0)
			(layers "F.Cu" "F.Mask" "F.Paste")
			(net "P3V3_SSD2")
		)
		(pad "2" smd circle
			(at 0.40005 0 180)
			(size 0 0)
			(layers "F.Cu" "F.Mask" "F.Paste")
			(net "SMB_ISO_SSD2_SCL")
		)
	)
	(footprint ""
		(layer "F.Cu")
		(at 262.08355 -61.487812 180)
		(property "Reference" "R5995"
			(at 0 0 180)
			(layer "F.SilkS")
			(hide yes)
			(effects
				(font
					(size 1.27 1.27)
				)
			)
		)
		(property "Value" ""
			(at 0 0 180)
			(layer "F.Fab")
			(effects
				(font
					(size 1.27 1.27)
				)
			)
		)
		(duplicate_pad_numbers_are_jumpers no)
		(fp_line
			(start 0.7874 0.4064)
			(end -0.7874 0.4064)
			(stroke
				(width 0.1524)
				(type default)
			)
			(layer "F.SilkS")
		)
		(fp_line
			(start 0.7874 -0.4064)
			(end 0.7874 0.4064)
			(stroke
				(width 0.1524)
				(type default)
			)
			(layer "F.SilkS")
		)
		(fp_line
			(start -0.7874 0.4064)
			(end -0.7874 -0.4064)
			(stroke
				(width 0.1524)
				(type default)
			)
			(layer "F.SilkS")
		)
		(fp_line
			(start -0.7874 -0.4064)
			(end 0.7874 -0.4064)
			(stroke
				(width 0.1524)
				(type default)
			)
			(layer "F.SilkS")
		)
		(fp_line
			(start 0.67945 0.3048)
			(end 0.120396 0.3048)
			(stroke
				(width 0.1)
				(type default)
			)
			(layer "F.Fab")
		)
		(fp_line
			(start 0.67945 -0.3048)
			(end 0.67945 0.3048)
			(stroke
				(width 0.1)
				(type default)
			)
			(layer "F.Fab")
		)
		(fp_line
			(start 0.12065 -0.2794)
			(end 0.12065 -0.3048)
			(stroke
				(width 0.1)
				(type default)
			)
			(layer "F.Fab")
		)
		(fp_line
			(start 0.12065 -0.3048)
			(end 0.67945 -0.3048)
			(stroke
				(width 0.1)
				(type default)
			)
			(layer "F.Fab")
		)
		(fp_line
			(start 0.120396 0.3048)
			(end 0.120396 0.2794)
			(stroke
				(width 0.1)
				(type default)
			)
			(layer "F.Fab")
		)
		(fp_line
			(start 0.120396 0.2794)
			(end -0.12065 0.2794)
			(stroke
				(width 0.1)
				(type default)
			)
			(layer "F.Fab")
		)
		(fp_line
			(start -0.12065 0.3048)
			(end -0.67945 0.3048)
			(stroke
				(width 0.1)
				(type default)
			)
			(layer "F.Fab")
		)
		(fp_line
			(start -0.12065 0.2794)
			(end -0.12065 0.3048)
			(stroke
				(width 0.1)
				(type default)
			)
			(layer "F.Fab")
		)
		(fp_line
			(start -0.12065 -0.2794)
			(end 0.12065 -0.2794)
			(stroke
				(width 0.1)
				(type default)
			)
			(layer "F.Fab")
		)
		(fp_line
			(start -0.12065 -0.305054)
			(end -0.12065 -0.2794)
			(stroke
				(width 0.1)
				(type default)
			)
			(layer "F.Fab")
		)
		(fp_line
			(start -0.67945 0.3048)
			(end -0.67945 -0.305054)
			(stroke
				(width 0.1)
				(type default)
			)
			(layer "F.Fab")
		)
		(fp_line
			(start -0.67945 -0.305054)
			(end -0.12065 -0.305054)
			(stroke
				(width 0.1)
				(type default)
			)
			(layer "F.Fab")
		)
		(pad "1" smd circle
			(at -0.40005 0 180)
			(size 0 0)
			(layers "F.Cu" "F.Mask" "F.Paste")
			(net "PWRGD_P12V_SSD9_D")
		)
		(pad "2" smd circle
			(at 0.40005 0 180)
			(size 0 0)
			(layers "F.Cu" "F.Mask" "F.Paste")
			(net "PWRGD_P12V_SSD9_R")
		)
	)
	(footprint ""
		(layer "F.Cu")
		(at 226.804474 -136.669272 -90)
		(property "Reference" "R4190"
			(at 0 0 270)
			(layer "F.SilkS")
			(hide yes)
			(effects
				(font
					(size 1.27 1.27)
				)
			)
		)
		(property "Value" ""
			(at 0 0 270)
			(layer "F.Fab")
			(effects
				(font
					(size 1.27 1.27)
				)
			)
		)
		(duplicate_pad_numbers_are_jumpers no)
		(fp_line
			(start -0.7874 0.4064)
			(end -0.7874 -0.4064)
			(stroke
				(width 0.1524)
				(type default)
			)
			(layer "F.SilkS")
		)
		(fp_line
			(start 0.7874 0.4064)
			(end -0.7874 0.4064)
			(stroke
				(width 0.1524)
				(type default)
			)
			(layer "F.SilkS")
		)
		(fp_line
			(start -0.7874 -0.4064)
			(end 0.7874 -0.4064)
			(stroke
				(width 0.1524)
				(type default)
			)
			(layer "F.SilkS")
		)
		(fp_line
			(start 0.7874 -0.4064)
			(end 0.7874 0.4064)
			(stroke
				(width 0.1524)
				(type default)
			)
			(layer "F.SilkS")
		)
		(fp_line
			(start -0.67945 0.3048)
			(end -0.67945 -0.305054)
			(stroke
				(width 0.1)
				(type default)
			)
			(layer "F.Fab")
		)
		(fp_line
			(start -0.12065 0.3048)
			(end -0.67945 0.3048)
			(stroke
				(width 0.1)
				(type default)
			)
			(layer "F.Fab")
		)
		(fp_line
			(start 0.120396 0.3048)
			(end 0.120396 0.2794)
			(stroke
				(width 0.1)
				(type default)
			)
			(layer "F.Fab")
		)
		(fp_line
			(start 0.67945 0.3048)
			(end 0.120396 0.3048)
			(stroke
				(width 0.1)
				(type default)
			)
			(layer "F.Fab")
		)
		(fp_line
			(start -0.12065 0.2794)
			(end -0.12065 0.3048)
			(stroke
				(width 0.1)
				(type default)
			)
			(layer "F.Fab")
		)
		(fp_line
			(start 0.120396 0.2794)
			(end -0.12065 0.2794)
			(stroke
				(width 0.1)
				(type default)
			)
			(layer "F.Fab")
		)
		(fp_line
			(start -0.12065 -0.2794)
			(end 0.12065 -0.2794)
			(stroke
				(width 0.1)
				(type default)
			)
			(layer "F.Fab")
		)
		(fp_line
			(start 0.12065 -0.2794)
			(end 0.12065 -0.3048)
			(stroke
				(width 0.1)
				(type default)
			)
			(layer "F.Fab")
		)
		(fp_line
			(start 0.12065 -0.3048)
			(end 0.67945 -0.3048)
			(stroke
				(width 0.1)
				(type default)
			)
			(layer "F.Fab")
		)
		(fp_line
			(start 0.67945 -0.3048)
			(end 0.67945 0.3048)
			(stroke
				(width 0.1)
				(type default)
			)
			(layer "F.Fab")
		)
		(fp_line
			(start -0.67945 -0.305054)
			(end -0.12065 -0.305054)
			(stroke
				(width 0.1)
				(type default)
			)
			(layer "F.Fab")
		)
		(fp_line
			(start -0.12065 -0.305054)
			(end -0.12065 -0.2794)
			(stroke
				(width 0.1)
				(type default)
			)
			(layer "F.Fab")
		)
		(pad "1" smd circle
			(at -0.40005 0 270)
			(size 0 0)
			(layers "F.Cu" "F.Mask" "F.Paste")
			(net "CLK_CK440_PEX_SMB_ADDR1")
		)
		(pad "2" smd circle
			(at 0.40005 0 270)
			(size 0 0)
			(layers "F.Cu" "F.Mask" "F.Paste")
			(net "P3V3")
		)
	)
	(footprint ""
		(layer "F.Cu")
		(at 206.623158 -82.643472)
		(property "Reference" "R4304"
			(at 0 0 0)
			(layer "F.SilkS")
			(hide yes)
			(effects
				(font
					(size 1.27 1.27)
				)
			)
		)
		(property "Value" ""
			(at 0 0 0)
			(layer "F.Fab")
			(effects
				(font
					(size 1.27 1.27)
				)
			)
		)
		(duplicate_pad_numbers_are_jumpers no)
		(fp_line
			(start -0.7874 -0.4064)
			(end 0.7874 -0.4064)
			(stroke
				(width 0.1524)
				(type default)
			)
			(layer "F.SilkS")
		)
		(fp_line
			(start -0.7874 0.4064)
			(end -0.7874 -0.4064)
			(stroke
				(width 0.1524)
				(type default)
			)
			(layer "F.SilkS")
		)
		(fp_line
			(start 0.7874 -0.4064)
			(end 0.7874 0.4064)
			(stroke
				(width 0.1524)
				(type default)
			)
			(layer "F.SilkS")
		)
		(fp_line
			(start 0.7874 0.4064)
			(end -0.7874 0.4064)
			(stroke
				(width 0.1524)
				(type default)
			)
			(layer "F.SilkS")
		)
		(fp_line
			(start -0.67945 -0.305054)
			(end -0.12065 -0.305054)
			(stroke
				(width 0.1)
				(type default)
			)
			(layer "F.Fab")
		)
		(fp_line
			(start -0.67945 0.3048)
			(end -0.67945 -0.305054)
			(stroke
				(width 0.1)
				(type default)
			)
			(layer "F.Fab")
		)
		(fp_line
			(start -0.12065 -0.305054)
			(end -0.12065 -0.2794)
			(stroke
				(width 0.1)
				(type default)
			)
			(layer "F.Fab")
		)
		(fp_line
			(start -0.12065 -0.2794)
			(end 0.12065 -0.2794)
			(stroke
				(width 0.1)
				(type default)
			)
			(layer "F.Fab")
		)
		(fp_line
			(start -0.12065 0.2794)
			(end -0.12065 0.3048)
			(stroke
				(width 0.1)
				(type default)
			)
			(layer "F.Fab")
		)
		(fp_line
			(start -0.12065 0.3048)
			(end -0.67945 0.3048)
			(stroke
				(width 0.1)
				(type default)
			)
			(layer "F.Fab")
		)
		(fp_line
			(start 0.120396 0.2794)
			(end -0.12065 0.2794)
			(stroke
				(width 0.1)
				(type default)
			)
			(layer "F.Fab")
		)
		(fp_line
			(start 0.120396 0.3048)
			(end 0.120396 0.2794)
			(stroke
				(width 0.1)
				(type default)
			)
			(layer "F.Fab")
		)
		(fp_line
			(start 0.12065 -0.3048)
			(end 0.67945 -0.3048)
			(stroke
				(width 0.1)
				(type default)
			)
			(layer "F.Fab")
		)
		(fp_line
			(start 0.12065 -0.2794)
			(end 0.12065 -0.3048)
			(stroke
				(width 0.1)
				(type default)
			)
			(layer "F.Fab")
		)
		(fp_line
			(start 0.67945 -0.3048)
			(end 0.67945 0.3048)
			(stroke
				(width 0.1)
				(type default)
			)
			(layer "F.Fab")
		)
		(fp_line
			(start 0.67945 0.3048)
			(end 0.120396 0.3048)
			(stroke
				(width 0.1)
				(type default)
			)
			(layer "F.Fab")
		)
		(pad "1" smd circle
			(at -0.40005 0)
			(size 0 0)
			(layers "F.Cu" "F.Mask" "F.Paste")
			(net "SSD2_LED_R")
		)
		(pad "2" smd circle
			(at 0.40005 0)
			(size 0 0)
			(layers "F.Cu" "F.Mask" "F.Paste")
			(net "SSD2_LED")
		)
	)
	(footprint ""
		(layer "F.Cu")
		(at 110.321344 -177.469546 -90)
		(property "Reference" "PL3"
			(at 2.311146 -3.014726 90)
			(unlocked yes)
			(layer "F.SilkS")
			(effects
				(font
					(size 0.7874 0.5842)
					(thickness 0.1524)
				)
				(justify left)
			)
		)
		(property "Value" ""
			(at 0 0 270)
			(layer "F.Fab")
			(effects
				(font
					(size 1.27 1.27)
				)
			)
		)
		(duplicate_pad_numbers_are_jumpers no)
		(fp_line
			(start -2.249932 2.249932)
			(end -2.249932 1.3843)
			(stroke
				(width 0.1524)
				(type default)
			)
			(layer "F.SilkS")
		)
		(fp_line
			(start 2.249932 2.249932)
			(end -2.249932 2.249932)
			(stroke
				(width 0.1524)
				(type default)
			)
			(layer "F.SilkS")
		)
		(fp_line
			(start 2.249932 1.3843)
			(end 2.249932 2.249932)
			(stroke
				(width 0.1524)
				(type default)
			)
			(layer "F.SilkS")
		)
		(fp_line
			(start -2.249932 -1.3843)
			(end -2.249932 -2.249932)
			(stroke
				(width 0.1524)
				(type default)
			)
			(layer "F.SilkS")
		)
		(fp_line
			(start -2.249932 -2.249932)
			(end 2.249932 -2.249932)
			(stroke
				(width 0.1524)
				(type default)
			)
			(layer "F.SilkS")
		)
		(fp_line
			(start 2.249932 -2.249932)
			(end 2.249932 -1.3843)
			(stroke
				(width 0.1524)
				(type default)
			)
			(layer "F.SilkS")
		)
		(fp_line
			(start -2.249932 2.249932)
			(end -2.249932 -2.249932)
			(stroke
				(width 0.1)
				(type default)
			)
			(layer "F.Fab")
		)
		(fp_line
			(start 2.249932 2.249932)
			(end -2.249932 2.249932)
			(stroke
				(width 0.1)
				(type default)
			)
			(layer "F.Fab")
		)
		(fp_line
			(start -2.249932 -2.249932)
			(end 2.249932 -2.249932)
			(stroke
				(width 0.1)
				(type default)
			)
			(layer "F.Fab")
		)
		(fp_line
			(start 2.249932 -2.249932)
			(end 2.249932 2.249932)
			(stroke
				(width 0.1)
				(type default)
			)
			(layer "F.Fab")
		)
		(pad "1" smd rect
			(at -1.82499 0 270)
			(size 1.0668 2.5146)
			(layers "F.Cu" "F.Mask" "F.Paste")
			(net "P12V_AUX")
		)
		(pad "2" smd rect
			(at 1.82499 0 270)
			(size 1.0668 2.5146)
			(layers "F.Cu" "F.Mask" "F.Paste")
			(net "SW_P12V_P3V3_AUX_FLT")
		)
	)
	(footprint ""
		(layer "F.Cu")
		(at 358.405684 -285.088584 90)
		(property "Reference" "PC170"
			(at 0 0 90)
			(layer "F.SilkS")
			(hide yes)
			(effects
				(font
					(size 1.27 1.27)
				)
			)
		)
		(property "Value" ""
			(at 0 0 90)
			(layer "F.Fab")
			(effects
				(font
					(size 1.27 1.27)
				)
			)
		)
		(duplicate_pad_numbers_are_jumpers no)
		(fp_line
			(start 0.7874 -0.4064)
			(end 0.7874 0.4064)
			(stroke
				(width 0.1524)
				(type default)
			)
			(layer "F.SilkS")
		)
		(fp_line
			(start -0.7874 -0.4064)
			(end 0.7874 -0.4064)
			(stroke
				(width 0.1524)
				(type default)
			)
			(layer "F.SilkS")
		)
		(fp_line
			(start 0.7874 0.4064)
			(end -0.7874 0.4064)
			(stroke
				(width 0.1524)
				(type default)
			)
			(layer "F.SilkS")
		)
		(fp_line
			(start -0.7874 0.4064)
			(end -0.7874 -0.4064)
			(stroke
				(width 0.1524)
				(type default)
			)
			(layer "F.SilkS")
		)
		(fp_line
			(start -0.12065 -0.305054)
			(end -0.12065 -0.2794)
			(stroke
				(width 0.1)
				(type default)
			)
			(layer "F.Fab")
		)
		(fp_line
			(start -0.67945 -0.305054)
			(end -0.12065 -0.305054)
			(stroke
				(width 0.1)
				(type default)
			)
			(layer "F.Fab")
		)
		(fp_line
			(start 0.67945 -0.3048)
			(end 0.67945 0.3048)
			(stroke
				(width 0.1)
				(type default)
			)
			(layer "F.Fab")
		)
		(fp_line
			(start 0.12065 -0.3048)
			(end 0.67945 -0.3048)
			(stroke
				(width 0.1)
				(type default)
			)
			(layer "F.Fab")
		)
		(fp_line
			(start 0.12065 -0.2794)
			(end 0.12065 -0.3048)
			(stroke
				(width 0.1)
				(type default)
			)
			(layer "F.Fab")
		)
		(fp_line
			(start -0.12065 -0.2794)
			(end 0.12065 -0.2794)
			(stroke
				(width 0.1)
				(type default)
			)
			(layer "F.Fab")
		)
		(fp_line
			(start 0.120396 0.2794)
			(end -0.12065 0.2794)
			(stroke
				(width 0.1)
				(type default)
			)
			(layer "F.Fab")
		)
		(fp_line
			(start -0.12065 0.2794)
			(end -0.12065 0.3048)
			(stroke
				(width 0.1)
				(type default)
			)
			(layer "F.Fab")
		)
		(fp_line
			(start 0.67945 0.3048)
			(end 0.120396 0.3048)
			(stroke
				(width 0.1)
				(type default)
			)
			(layer "F.Fab")
		)
		(fp_line
			(start 0.120396 0.3048)
			(end 0.120396 0.2794)
			(stroke
				(width 0.1)
				(type default)
			)
			(layer "F.Fab")
		)
		(fp_line
			(start -0.12065 0.3048)
			(end -0.67945 0.3048)
			(stroke
				(width 0.1)
				(type default)
			)
			(layer "F.Fab")
		)
		(fp_line
			(start -0.67945 0.3048)
			(end -0.67945 -0.305054)
			(stroke
				(width 0.1)
				(type default)
			)
			(layer "F.Fab")
		)
		(pad "1" smd circle
			(at -0.40005 0 90)
			(size 0 0)
			(layers "F.Cu" "F.Mask" "F.Paste")
			(net "P0V8_PEX3_PVCC")
		)
		(pad "2" smd circle
			(at 0.40005 0 90)
			(size 0 0)
			(layers "F.Cu" "F.Mask" "F.Paste")
			(net "GND")
		)
	)
	(footprint ""
		(layer "F.Cu")
		(at 409.677108 -186.033918 180)
		(property "Reference" "R6426"
			(at 0 0 180)
			(layer "F.SilkS")
			(hide yes)
			(effects
				(font
					(size 1.27 1.27)
				)
			)
		)
		(property "Value" ""
			(at 0 0 180)
			(layer "F.Fab")
			(effects
				(font
					(size 1.27 1.27)
				)
			)
		)
		(duplicate_pad_numbers_are_jumpers no)
		(fp_line
			(start 0.7874 0.4064)
			(end -0.7874 0.4064)
			(stroke
				(width 0.1524)
				(type default)
			)
			(layer "F.SilkS")
		)
		(fp_line
			(start 0.7874 -0.4064)
			(end 0.7874 0.4064)
			(stroke
				(width 0.1524)
				(type default)
			)
			(layer "F.SilkS")
		)
		(fp_line
			(start -0.7874 0.4064)
			(end -0.7874 -0.4064)
			(stroke
				(width 0.1524)
				(type default)
			)
			(layer "F.SilkS")
		)
		(fp_line
			(start -0.7874 -0.4064)
			(end 0.7874 -0.4064)
			(stroke
				(width 0.1524)
				(type default)
			)
			(layer "F.SilkS")
		)
		(fp_line
			(start 0.67945 0.3048)
			(end 0.120396 0.3048)
			(stroke
				(width 0.1)
				(type default)
			)
			(layer "F.Fab")
		)
		(fp_line
			(start 0.67945 -0.3048)
			(end 0.67945 0.3048)
			(stroke
				(width 0.1)
				(type default)
			)
			(layer "F.Fab")
		)
		(fp_line
			(start 0.12065 -0.2794)
			(end 0.12065 -0.3048)
			(stroke
				(width 0.1)
				(type default)
			)
			(layer "F.Fab")
		)
		(fp_line
			(start 0.12065 -0.3048)
			(end 0.67945 -0.3048)
			(stroke
				(width 0.1)
				(type default)
			)
			(layer "F.Fab")
		)
		(fp_line
			(start 0.120396 0.3048)
			(end 0.120396 0.2794)
			(stroke
				(width 0.1)
				(type default)
			)
			(layer "F.Fab")
		)
		(fp_line
			(start 0.120396 0.2794)
			(end -0.12065 0.2794)
			(stroke
				(width 0.1)
				(type default)
			)
			(layer "F.Fab")
		)
		(fp_line
			(start -0.12065 0.3048)
			(end -0.67945 0.3048)
			(stroke
				(width 0.1)
				(type default)
			)
			(layer "F.Fab")
		)
		(fp_line
			(start -0.12065 0.2794)
			(end -0.12065 0.3048)
			(stroke
				(width 0.1)
				(type default)
			)
			(layer "F.Fab")
		)
		(fp_line
			(start -0.12065 -0.2794)
			(end 0.12065 -0.2794)
			(stroke
				(width 0.1)
				(type default)
			)
			(layer "F.Fab")
		)
		(fp_line
			(start -0.12065 -0.305054)
			(end -0.12065 -0.2794)
			(stroke
				(width 0.1)
				(type default)
			)
			(layer "F.Fab")
		)
		(fp_line
			(start -0.67945 0.3048)
			(end -0.67945 -0.305054)
			(stroke
				(width 0.1)
				(type default)
			)
			(layer "F.Fab")
		)
		(fp_line
			(start -0.67945 -0.305054)
			(end -0.12065 -0.305054)
			(stroke
				(width 0.1)
				(type default)
			)
			(layer "F.Fab")
		)
		(pad "1" smd circle
			(at -0.40005 0 180)
			(size 0 0)
			(layers "F.Cu" "F.Mask" "F.Paste")
			(net "FPGA_PEX0_MODE_SEL2_ISO")
		)
		(pad "2" smd circle
			(at 0.40005 0 180)
			(size 0 0)
			(layers "F.Cu" "F.Mask" "F.Paste")
			(net "PEX0_MODE_SEL2")
		)
	)
	(footprint ""
		(layer "F.Cu")
		(at 312.21934 -119.584724 180)
		(property "Reference" "C453"
			(at 0 0 180)
			(layer "F.SilkS")
			(hide yes)
			(effects
				(font
					(size 1.27 1.27)
				)
			)
		)
		(property "Value" ""
			(at 0 0 180)
			(layer "F.Fab")
			(effects
				(font
					(size 1.27 1.27)
				)
			)
		)
		(duplicate_pad_numbers_are_jumpers no)
		(fp_line
			(start 0.299974 0.150114)
			(end -0.299974 0.150114)
			(stroke
				(width 0.1)
				(type default)
			)
			(layer "F.Fab")
		)
		(fp_line
			(start 0.299974 -0.150114)
			(end 0.299974 0.150114)
			(stroke
				(width 0.1)
				(type default)
			)
			(layer "F.Fab")
		)
		(fp_line
			(start -0.299974 0.150114)
			(end -0.299974 -0.150114)
			(stroke
				(width 0.1)
				(type default)
			)
			(layer "F.Fab")
		)
		(fp_line
			(start -0.299974 -0.150114)
			(end 0.299974 -0.150114)
			(stroke
				(width 0.1)
				(type default)
			)
			(layer "F.Fab")
		)
		(pad "1" smd rect
			(at -0.2667 0 180)
			(size 0.3048 0.381)
			(layers "F.Cu" "F.Mask" "F.Paste")
			(net "P5E_PEX2_STN0_TX_DP<0>")
		)
		(pad "2" smd rect
			(at 0.2667 0 180)
			(size 0.3048 0.381)
			(layers "F.Cu" "F.Mask" "F.Paste")
			(net "P5E_PEX2_STN0_TX_C_DP<0>")
		)
	)
	(footprint ""
		(layer "F.Cu")
		(at 144.149318 -284.195012 -90)
		(property "Reference" "C3190"
			(at 0 0 270)
			(layer "F.SilkS")
			(hide yes)
			(effects
				(font
					(size 1.27 1.27)
				)
			)
		)
		(property "Value" ""
			(at 0 0 270)
			(layer "F.Fab")
			(effects
				(font
					(size 1.27 1.27)
				)
			)
		)
		(duplicate_pad_numbers_are_jumpers no)
		(fp_line
			(start -0.299974 0.150114)
			(end -0.299974 -0.150114)
			(stroke
				(width 0.1)
				(type default)
			)
			(layer "F.Fab")
		)
		(fp_line
			(start 0.299974 0.150114)
			(end -0.299974 0.150114)
			(stroke
				(width 0.1)
				(type default)
			)
			(layer "F.Fab")
		)
		(fp_line
			(start -0.299974 -0.150114)
			(end 0.299974 -0.150114)
			(stroke
				(width 0.1)
				(type default)
			)
			(layer "F.Fab")
		)
		(fp_line
			(start 0.299974 -0.150114)
			(end 0.299974 0.150114)
			(stroke
				(width 0.1)
				(type default)
			)
			(layer "F.Fab")
		)
		(pad "1" smd rect
			(at -0.2667 0 270)
			(size 0.3048 0.381)
			(layers "F.Cu" "F.Mask" "F.Paste")
			(net "P1V8_PLL0_PEX1")
		)
		(pad "2" smd rect
			(at 0.2667 0 270)
			(size 0.3048 0.381)
			(layers "F.Cu" "F.Mask" "F.Paste")
			(net "GND")
		)
	)
	(footprint ""
		(layer "F.Cu")
		(at 243.3828 -213.3854 90)
		(property "Reference" "R6591"
			(at 0 0 90)
			(layer "F.SilkS")
			(hide yes)
			(effects
				(font
					(size 1.27 1.27)
				)
			)
		)
		(property "Value" ""
			(at 0 0 90)
			(layer "F.Fab")
			(effects
				(font
					(size 1.27 1.27)
				)
			)
		)
		(duplicate_pad_numbers_are_jumpers no)
		(fp_line
			(start 0.7874 -0.4064)
			(end 0.7874 0.4064)
			(stroke
				(width 0.1524)
				(type default)
			)
			(layer "F.SilkS")
		)
		(fp_line
			(start -0.7874 -0.4064)
			(end 0.7874 -0.4064)
			(stroke
				(width 0.1524)
				(type default)
			)
			(layer "F.SilkS")
		)
		(fp_line
			(start 0.7874 0.4064)
			(end -0.7874 0.4064)
			(stroke
				(width 0.1524)
				(type default)
			)
			(layer "F.SilkS")
		)
		(fp_line
			(start -0.7874 0.4064)
			(end -0.7874 -0.4064)
			(stroke
				(width 0.1524)
				(type default)
			)
			(layer "F.SilkS")
		)
		(fp_line
			(start -0.12065 -0.305054)
			(end -0.12065 -0.2794)
			(stroke
				(width 0.1)
				(type default)
			)
			(layer "F.Fab")
		)
		(fp_line
			(start -0.67945 -0.305054)
			(end -0.12065 -0.305054)
			(stroke
				(width 0.1)
				(type default)
			)
			(layer "F.Fab")
		)
		(fp_line
			(start 0.67945 -0.3048)
			(end 0.67945 0.3048)
			(stroke
				(width 0.1)
				(type default)
			)
			(layer "F.Fab")
		)
		(fp_line
			(start 0.12065 -0.3048)
			(end 0.67945 -0.3048)
			(stroke
				(width 0.1)
				(type default)
			)
			(layer "F.Fab")
		)
		(fp_line
			(start 0.12065 -0.2794)
			(end 0.12065 -0.3048)
			(stroke
				(width 0.1)
				(type default)
			)
			(layer "F.Fab")
		)
		(fp_line
			(start -0.12065 -0.2794)
			(end 0.12065 -0.2794)
			(stroke
				(width 0.1)
				(type default)
			)
			(layer "F.Fab")
		)
		(fp_line
			(start 0.120396 0.2794)
			(end -0.12065 0.2794)
			(stroke
				(width 0.1)
				(type default)
			)
			(layer "F.Fab")
		)
		(fp_line
			(start -0.12065 0.2794)
			(end -0.12065 0.3048)
			(stroke
				(width 0.1)
				(type default)
			)
			(layer "F.Fab")
		)
		(fp_line
			(start 0.67945 0.3048)
			(end 0.120396 0.3048)
			(stroke
				(width 0.1)
				(type default)
			)
			(layer "F.Fab")
		)
		(fp_line
			(start 0.120396 0.3048)
			(end 0.120396 0.2794)
			(stroke
				(width 0.1)
				(type default)
			)
			(layer "F.Fab")
		)
		(fp_line
			(start -0.12065 0.3048)
			(end -0.67945 0.3048)
			(stroke
				(width 0.1)
				(type default)
			)
			(layer "F.Fab")
		)
		(fp_line
			(start -0.67945 0.3048)
			(end -0.67945 -0.305054)
			(stroke
				(width 0.1)
				(type default)
			)
			(layer "F.Fab")
		)
		(pad "1" smd circle
			(at -0.40005 0 90)
			(size 0 0)
			(layers "F.Cu" "F.Mask" "F.Paste")
			(net "P1V8_PLL0_PEX1")
		)
		(pad "2" smd circle
			(at 0.40005 0 90)
			(size 0 0)
			(layers "F.Cu" "F.Mask" "F.Paste")
			(net "P1V8_PLL0_PEX1_SCALED")
		)
	)
	(footprint ""
		(layer "F.Cu")
		(at 121.854468 -48.21809)
		(property "Reference" "PD61"
			(at -3.490468 2.24536 0)
			(unlocked yes)
			(layer "F.SilkS")
			(effects
				(font
					(size 0.7874 0.5842)
					(thickness 0.1524)
				)
				(justify left)
			)
		)
		(property "Value" ""
			(at 0 0 0)
			(layer "F.Fab")
			(effects
				(font
					(size 1.27 1.27)
				)
			)
		)
		(duplicate_pad_numbers_are_jumpers no)
		(fp_line
			(start -3.400044 -1.459992)
			(end 4.107942 -1.459992)
			(stroke
				(width 0.1524)
				(type default)
			)
			(layer "F.SilkS")
		)
		(fp_line
			(start -3.400044 1.459992)
			(end -3.400044 -1.459992)
			(stroke
				(width 0.1524)
				(type default)
			)
			(layer "F.SilkS")
		)
		(fp_line
			(start 4.107942 -1.459992)
			(end 4.107942 1.459992)
			(stroke
				(width 0.1524)
				(type default)
			)
			(layer "F.SilkS")
		)
		(fp_line
			(start 4.107942 1.459992)
			(end -3.400044 1.459992)
			(stroke
				(width 0.1524)
				(type default)
			)
			(layer "F.SilkS")
		)
		(fp_poly
			(pts
				(xy 4.107942 -1.459992) (xy 4.107942 1.459992) (xy 3.308096 1.459992) (xy 3.308096 -1.459992)
			)
			(stroke
				(width 0)
				(type default)
			)
			(fill yes)
			(layer "F.SilkS")
		)
		(fp_line
			(start -2.29997 -1.459992)
			(end 2.29997 -1.459992)
			(stroke
				(width 0.1)
				(type default)
			)
			(layer "F.Fab")
		)
		(fp_line
			(start -2.29997 1.459992)
			(end -2.29997 -1.459992)
			(stroke
				(width 0.1)
				(type default)
			)
			(layer "F.Fab")
		)
		(fp_line
			(start 2.29997 -1.459992)
			(end 2.29997 1.459992)
			(stroke
				(width 0.1)
				(type default)
			)
			(layer "F.Fab")
		)
		(fp_line
			(start 2.29997 1.459992)
			(end -2.29997 1.459992)
			(stroke
				(width 0.1)
				(type default)
			)
			(layer "F.Fab")
		)
		(fp_text user "+"
			(at -4.7752 -0.12065 0)
			(unlocked yes)
			(layer "F.SilkS")
			(effects
				(font
					(size 1.905 1.4224)
					(thickness 0.1524)
				)
				(justify left)
			)
		)
		(fp_text user "-"
			(at 5.4102 0.29845 180)
			(unlocked yes)
			(layer "F.SilkS")
			(effects
				(font
					(size 1.905 1.4224)
					(thickness 0.1524)
				)
				(justify left)
			)
		)
		(fp_text user "+"
			(at -4.7752 -0.12065 0)
			(unlocked yes)
			(layer "F.Fab")
			(effects
				(font
					(size 1.905 1.4224)
					(thickness 0.1524)
				)
				(justify left)
			)
		)
		(fp_text user "-"
			(at 5.4102 0.29845 180)
			(unlocked yes)
			(layer "F.Fab")
			(effects
				(font
					(size 1.905 1.4224)
					(thickness 0.1524)
				)
				(justify left)
			)
		)
		(pad "A" smd rect
			(at -1.999996 0 90)
			(size 1.7018 2.5146)
			(layers "F.Cu" "F.Mask" "F.Paste")
			(net "GND")
		)
		(pad "C" smd rect
			(at 1.999996 0 90)
			(size 1.7018 2.5146)
			(layers "F.Cu" "F.Mask" "F.Paste")
			(net "P3V3_SSD4")
		)
	)
	(footprint ""
		(layer "F.Cu")
		(at 217.235786 -220.334586 180)
		(property "Reference" "R1499"
			(at 0 0 180)
			(layer "F.SilkS")
			(hide yes)
			(effects
				(font
					(size 1.27 1.27)
				)
			)
		)
		(property "Value" ""
			(at 0 0 180)
			(layer "F.Fab")
			(effects
				(font
					(size 1.27 1.27)
				)
			)
		)
		(duplicate_pad_numbers_are_jumpers no)
		(fp_line
			(start 0.7874 0.4064)
			(end -0.7874 0.4064)
			(stroke
				(width 0.1524)
				(type default)
			)
			(layer "F.SilkS")
		)
		(fp_line
			(start 0.7874 -0.4064)
			(end 0.7874 0.4064)
			(stroke
				(width 0.1524)
				(type default)
			)
			(layer "F.SilkS")
		)
		(fp_line
			(start -0.7874 0.4064)
			(end -0.7874 -0.4064)
			(stroke
				(width 0.1524)
				(type default)
			)
			(layer "F.SilkS")
		)
		(fp_line
			(start -0.7874 -0.4064)
			(end 0.7874 -0.4064)
			(stroke
				(width 0.1524)
				(type default)
			)
			(layer "F.SilkS")
		)
		(fp_line
			(start 0.67945 0.3048)
			(end 0.120396 0.3048)
			(stroke
				(width 0.1)
				(type default)
			)
			(layer "F.Fab")
		)
		(fp_line
			(start 0.67945 -0.3048)
			(end 0.67945 0.3048)
			(stroke
				(width 0.1)
				(type default)
			)
			(layer "F.Fab")
		)
		(fp_line
			(start 0.12065 -0.2794)
			(end 0.12065 -0.3048)
			(stroke
				(width 0.1)
				(type default)
			)
			(layer "F.Fab")
		)
		(fp_line
			(start 0.12065 -0.3048)
			(end 0.67945 -0.3048)
			(stroke
				(width 0.1)
				(type default)
			)
			(layer "F.Fab")
		)
		(fp_line
			(start 0.120396 0.3048)
			(end 0.120396 0.2794)
			(stroke
				(width 0.1)
				(type default)
			)
			(layer "F.Fab")
		)
		(fp_line
			(start 0.120396 0.2794)
			(end -0.12065 0.2794)
			(stroke
				(width 0.1)
				(type default)
			)
			(layer "F.Fab")
		)
		(fp_line
			(start -0.12065 0.3048)
			(end -0.67945 0.3048)
			(stroke
				(width 0.1)
				(type default)
			)
			(layer "F.Fab")
		)
		(fp_line
			(start -0.12065 0.2794)
			(end -0.12065 0.3048)
			(stroke
				(width 0.1)
				(type default)
			)
			(layer "F.Fab")
		)
		(fp_line
			(start -0.12065 -0.2794)
			(end 0.12065 -0.2794)
			(stroke
				(width 0.1)
				(type default)
			)
			(layer "F.Fab")
		)
		(fp_line
			(start -0.12065 -0.305054)
			(end -0.12065 -0.2794)
			(stroke
				(width 0.1)
				(type default)
			)
			(layer "F.Fab")
		)
		(fp_line
			(start -0.67945 0.3048)
			(end -0.67945 -0.305054)
			(stroke
				(width 0.1)
				(type default)
			)
			(layer "F.Fab")
		)
		(fp_line
			(start -0.67945 -0.305054)
			(end -0.12065 -0.305054)
			(stroke
				(width 0.1)
				(type default)
			)
			(layer "F.Fab")
		)
		(pad "1" smd circle
			(at -0.40005 0 180)
			(size 0 0)
			(layers "F.Cu" "F.Mask" "F.Paste")
			(net "SMB_NIC4_SDA")
		)
		(pad "2" smd circle
			(at 0.40005 0 180)
			(size 0 0)
			(layers "F.Cu" "F.Mask" "F.Paste")
			(net "SMB_NIC4_R_SDA")
		)
	)
	(footprint ""
		(layer "F.Cu")
		(at 387.580632 -106.488738)
		(property "Reference" "C688"
			(at 0 0 0)
			(layer "F.SilkS")
			(hide yes)
			(effects
				(font
					(size 1.27 1.27)
				)
			)
		)
		(property "Value" ""
			(at 0 0 0)
			(layer "F.Fab")
			(effects
				(font
					(size 1.27 1.27)
				)
			)
		)
		(duplicate_pad_numbers_are_jumpers no)
		(fp_line
			(start -0.299974 -0.150114)
			(end 0.299974 -0.150114)
			(stroke
				(width 0.1)
				(type default)
			)
			(layer "F.Fab")
		)
		(fp_line
			(start -0.299974 0.150114)
			(end -0.299974 -0.150114)
			(stroke
				(width 0.1)
				(type default)
			)
			(layer "F.Fab")
		)
		(fp_line
			(start 0.299974 -0.150114)
			(end 0.299974 0.150114)
			(stroke
				(width 0.1)
				(type default)
			)
			(layer "F.Fab")
		)
		(fp_line
			(start 0.299974 0.150114)
			(end -0.299974 0.150114)
			(stroke
				(width 0.1)
				(type default)
			)
			(layer "F.Fab")
		)
		(pad "1" smd rect
			(at -0.2667 0)
			(size 0.3048 0.381)
			(layers "F.Cu" "F.Mask" "F.Paste")
			(net "P5E_PEX3_STN1_TX_DP<20>")
		)
		(pad "2" smd rect
			(at 0.2667 0)
			(size 0.3048 0.381)
			(layers "F.Cu" "F.Mask" "F.Paste")
			(net "P5E_PEX3_STN1_TX_C_DP<20>")
		)
	)
	(footprint ""
		(layer "F.Cu")
		(at 462.465674 -280.70683 180)
		(property "Reference" "R808"
			(at 0 0 180)
			(layer "F.SilkS")
			(hide yes)
			(effects
				(font
					(size 1.27 1.27)
				)
			)
		)
		(property "Value" ""
			(at 0 0 180)
			(layer "F.Fab")
			(effects
				(font
					(size 1.27 1.27)
				)
			)
		)
		(duplicate_pad_numbers_are_jumpers no)
		(fp_line
			(start 0.7874 0.4064)
			(end -0.7874 0.4064)
			(stroke
				(width 0.1524)
				(type default)
			)
			(layer "F.SilkS")
		)
		(fp_line
			(start 0.7874 -0.4064)
			(end 0.7874 0.4064)
			(stroke
				(width 0.1524)
				(type default)
			)
			(layer "F.SilkS")
		)
		(fp_line
			(start -0.7874 0.4064)
			(end -0.7874 -0.4064)
			(stroke
				(width 0.1524)
				(type default)
			)
			(layer "F.SilkS")
		)
		(fp_line
			(start -0.7874 -0.4064)
			(end 0.7874 -0.4064)
			(stroke
				(width 0.1524)
				(type default)
			)
			(layer "F.SilkS")
		)
		(fp_line
			(start 0.67945 0.3048)
			(end 0.120396 0.3048)
			(stroke
				(width 0.1)
				(type default)
			)
			(layer "F.Fab")
		)
		(fp_line
			(start 0.67945 -0.3048)
			(end 0.67945 0.3048)
			(stroke
				(width 0.1)
				(type default)
			)
			(layer "F.Fab")
		)
		(fp_line
			(start 0.12065 -0.2794)
			(end 0.12065 -0.3048)
			(stroke
				(width 0.1)
				(type default)
			)
			(layer "F.Fab")
		)
		(fp_line
			(start 0.12065 -0.3048)
			(end 0.67945 -0.3048)
			(stroke
				(width 0.1)
				(type default)
			)
			(layer "F.Fab")
		)
		(fp_line
			(start 0.120396 0.3048)
			(end 0.120396 0.2794)
			(stroke
				(width 0.1)
				(type default)
			)
			(layer "F.Fab")
		)
		(fp_line
			(start 0.120396 0.2794)
			(end -0.12065 0.2794)
			(stroke
				(width 0.1)
				(type default)
			)
			(layer "F.Fab")
		)
		(fp_line
			(start -0.12065 0.3048)
			(end -0.67945 0.3048)
			(stroke
				(width 0.1)
				(type default)
			)
			(layer "F.Fab")
		)
		(fp_line
			(start -0.12065 0.2794)
			(end -0.12065 0.3048)
			(stroke
				(width 0.1)
				(type default)
			)
			(layer "F.Fab")
		)
		(fp_line
			(start -0.12065 -0.2794)
			(end 0.12065 -0.2794)
			(stroke
				(width 0.1)
				(type default)
			)
			(layer "F.Fab")
		)
		(fp_line
			(start -0.12065 -0.305054)
			(end -0.12065 -0.2794)
			(stroke
				(width 0.1)
				(type default)
			)
			(layer "F.Fab")
		)
		(fp_line
			(start -0.67945 0.3048)
			(end -0.67945 -0.305054)
			(stroke
				(width 0.1)
				(type default)
			)
			(layer "F.Fab")
		)
		(fp_line
			(start -0.67945 -0.305054)
			(end -0.12065 -0.305054)
			(stroke
				(width 0.1)
				(type default)
			)
			(layer "F.Fab")
		)
		(pad "1" smd circle
			(at -0.40005 0 180)
			(size 0 0)
			(layers "F.Cu" "F.Mask" "F.Paste")
			(net "SMB_BIC_I2C6_MUX_PEX_ADC_R_SCL")
		)
		(pad "2" smd circle
			(at 0.40005 0 180)
			(size 0 0)
			(layers "F.Cu" "F.Mask" "F.Paste")
			(net "SMB_PEX3_P1V25_ADC_SCL")
		)
	)
	(footprint ""
		(layer "F.Cu")
		(at 149.387814 -291.619432)
		(property "Reference" "C3216"
			(at 0 0 0)
			(layer "F.SilkS")
			(hide yes)
			(effects
				(font
					(size 1.27 1.27)
				)
			)
		)
		(property "Value" ""
			(at 0 0 0)
			(layer "F.Fab")
			(effects
				(font
					(size 1.27 1.27)
				)
			)
		)
		(duplicate_pad_numbers_are_jumpers no)
		(fp_line
			(start -1.2954 -0.5842)
			(end 1.2954 -0.5842)
			(stroke
				(width 0.1524)
				(type default)
			)
			(layer "F.SilkS")
		)
		(fp_line
			(start -1.2954 0.5842)
			(end -1.2954 -0.5842)
			(stroke
				(width 0.1524)
				(type default)
			)
			(layer "F.SilkS")
		)
		(fp_line
			(start 1.2954 -0.5842)
			(end 1.2954 0.5842)
			(stroke
				(width 0.1524)
				(type default)
			)
			(layer "F.SilkS")
		)
		(fp_line
			(start 1.2954 0.5842)
			(end -1.2954 0.5842)
			(stroke
				(width 0.1524)
				(type default)
			)
			(layer "F.SilkS")
		)
		(fp_line
			(start -1.1938 -0.4064)
			(end -0.8636 -0.4064)
			(stroke
				(width 0.1)
				(type default)
			)
			(layer "F.Fab")
		)
		(fp_line
			(start -1.1938 0.4064)
			(end -1.1938 -0.4064)
			(stroke
				(width 0.1)
				(type default)
			)
			(layer "F.Fab")
		)
		(fp_line
			(start -0.8636 -0.4572)
			(end 0.8636 -0.4572)
			(stroke
				(width 0.1)
				(type default)
			)
			(layer "F.Fab")
		)
		(fp_line
			(start -0.8636 -0.4064)
			(end -0.8636 -0.4572)
			(stroke
				(width 0.1)
				(type default)
			)
			(layer "F.Fab")
		)
		(fp_line
			(start -0.8636 0.4064)
			(end -1.1938 0.4064)
			(stroke
				(width 0.1)
				(type default)
			)
			(layer "F.Fab")
		)
		(fp_line
			(start -0.8636 0.4572)
			(end -0.8636 0.4064)
			(stroke
				(width 0.1)
				(type default)
			)
			(layer "F.Fab")
		)
		(fp_line
			(start 0.8636 -0.4572)
			(end 0.8636 -0.4064)
			(stroke
				(width 0.1)
				(type default)
			)
			(layer "F.Fab")
		)
		(fp_line
			(start 0.8636 -0.4064)
			(end 1.1938 -0.4064)
			(stroke
				(width 0.1)
				(type default)
			)
			(layer "F.Fab")
		)
		(fp_line
			(start 0.8636 0.4064)
			(end 0.8636 0.4572)
			(stroke
				(width 0.1)
				(type default)
			)
			(layer "F.Fab")
		)
		(fp_line
			(start 0.8636 0.4572)
			(end -0.8636 0.4572)
			(stroke
				(width 0.1)
				(type default)
			)
			(layer "F.Fab")
		)
		(fp_line
			(start 1.1938 -0.4064)
			(end 1.1938 0.4064)
			(stroke
				(width 0.1)
				(type default)
			)
			(layer "F.Fab")
		)
		(fp_line
			(start 1.1938 0.4064)
			(end 0.8636 0.4064)
			(stroke
				(width 0.1)
				(type default)
			)
			(layer "F.Fab")
		)
		(pad "1" smd rect
			(at -0.7366 0 270)
			(size 0.7112 0.8128)
			(layers "F.Cu" "F.Mask" "F.Paste")
			(net "PCEPLL4_VDDA18_PEX1")
		)
		(pad "2" smd rect
			(at 0.7366 0 270)
			(size 0.7112 0.8128)
			(layers "F.Cu" "F.Mask" "F.Paste")
			(net "GND")
		)
	)
	(footprint ""
		(layer "F.Cu")
		(at 179.924456 -158.080202 90)
		(property "Reference" "R2474"
			(at 0 0 90)
			(layer "F.SilkS")
			(hide yes)
			(effects
				(font
					(size 1.27 1.27)
				)
			)
		)
		(property "Value" ""
			(at 0 0 90)
			(layer "F.Fab")
			(effects
				(font
					(size 1.27 1.27)
				)
			)
		)
		(duplicate_pad_numbers_are_jumpers no)
		(fp_line
			(start 0.7874 -0.4064)
			(end 0.7874 0.4064)
			(stroke
				(width 0.1524)
				(type default)
			)
			(layer "F.SilkS")
		)
		(fp_line
			(start -0.7874 -0.4064)
			(end 0.7874 -0.4064)
			(stroke
				(width 0.1524)
				(type default)
			)
			(layer "F.SilkS")
		)
		(fp_line
			(start 0.7874 0.4064)
			(end -0.7874 0.4064)
			(stroke
				(width 0.1524)
				(type default)
			)
			(layer "F.SilkS")
		)
		(fp_line
			(start -0.7874 0.4064)
			(end -0.7874 -0.4064)
			(stroke
				(width 0.1524)
				(type default)
			)
			(layer "F.SilkS")
		)
		(fp_line
			(start -0.12065 -0.305054)
			(end -0.12065 -0.2794)
			(stroke
				(width 0.1)
				(type default)
			)
			(layer "F.Fab")
		)
		(fp_line
			(start -0.67945 -0.305054)
			(end -0.12065 -0.305054)
			(stroke
				(width 0.1)
				(type default)
			)
			(layer "F.Fab")
		)
		(fp_line
			(start 0.67945 -0.3048)
			(end 0.67945 0.3048)
			(stroke
				(width 0.1)
				(type default)
			)
			(layer "F.Fab")
		)
		(fp_line
			(start 0.12065 -0.3048)
			(end 0.67945 -0.3048)
			(stroke
				(width 0.1)
				(type default)
			)
			(layer "F.Fab")
		)
		(fp_line
			(start 0.12065 -0.2794)
			(end 0.12065 -0.3048)
			(stroke
				(width 0.1)
				(type default)
			)
			(layer "F.Fab")
		)
		(fp_line
			(start -0.12065 -0.2794)
			(end 0.12065 -0.2794)
			(stroke
				(width 0.1)
				(type default)
			)
			(layer "F.Fab")
		)
		(fp_line
			(start 0.120396 0.2794)
			(end -0.12065 0.2794)
			(stroke
				(width 0.1)
				(type default)
			)
			(layer "F.Fab")
		)
		(fp_line
			(start -0.12065 0.2794)
			(end -0.12065 0.3048)
			(stroke
				(width 0.1)
				(type default)
			)
			(layer "F.Fab")
		)
		(fp_line
			(start 0.67945 0.3048)
			(end 0.120396 0.3048)
			(stroke
				(width 0.1)
				(type default)
			)
			(layer "F.Fab")
		)
		(fp_line
			(start 0.120396 0.3048)
			(end 0.120396 0.2794)
			(stroke
				(width 0.1)
				(type default)
			)
			(layer "F.Fab")
		)
		(fp_line
			(start -0.12065 0.3048)
			(end -0.67945 0.3048)
			(stroke
				(width 0.1)
				(type default)
			)
			(layer "F.Fab")
		)
		(fp_line
			(start -0.67945 0.3048)
			(end -0.67945 -0.305054)
			(stroke
				(width 0.1)
				(type default)
			)
			(layer "F.Fab")
		)
		(pad "1" smd circle
			(at -0.40005 0 90)
			(size 0 0)
			(layers "F.Cu" "F.Mask" "F.Paste")
			(net "NIC3_PWRBRK_R_N")
		)
		(pad "2" smd circle
			(at 0.40005 0 90)
			(size 0 0)
			(layers "F.Cu" "F.Mask" "F.Paste")
			(net "NIC3_PWRBRK_N")
		)
	)
	(footprint ""
		(layer "F.Cu")
		(at 101.703886 -218.57589)
		(property "Reference" "R4439"
			(at 0 0 0)
			(layer "F.SilkS")
			(hide yes)
			(effects
				(font
					(size 1.27 1.27)
				)
			)
		)
		(property "Value" ""
			(at 0 0 0)
			(layer "F.Fab")
			(effects
				(font
					(size 1.27 1.27)
				)
			)
		)
		(duplicate_pad_numbers_are_jumpers no)
		(fp_line
			(start -0.7874 -0.4064)
			(end 0.7874 -0.4064)
			(stroke
				(width 0.1524)
				(type default)
			)
			(layer "F.SilkS")
		)
		(fp_line
			(start -0.7874 0.4064)
			(end -0.7874 -0.4064)
			(stroke
				(width 0.1524)
				(type default)
			)
			(layer "F.SilkS")
		)
		(fp_line
			(start 0.7874 -0.4064)
			(end 0.7874 0.4064)
			(stroke
				(width 0.1524)
				(type default)
			)
			(layer "F.SilkS")
		)
		(fp_line
			(start 0.7874 0.4064)
			(end -0.7874 0.4064)
			(stroke
				(width 0.1524)
				(type default)
			)
			(layer "F.SilkS")
		)
		(fp_line
			(start -0.67945 -0.305054)
			(end -0.12065 -0.305054)
			(stroke
				(width 0.1)
				(type default)
			)
			(layer "F.Fab")
		)
		(fp_line
			(start -0.67945 0.3048)
			(end -0.67945 -0.305054)
			(stroke
				(width 0.1)
				(type default)
			)
			(layer "F.Fab")
		)
		(fp_line
			(start -0.12065 -0.305054)
			(end -0.12065 -0.2794)
			(stroke
				(width 0.1)
				(type default)
			)
			(layer "F.Fab")
		)
		(fp_line
			(start -0.12065 -0.2794)
			(end 0.12065 -0.2794)
			(stroke
				(width 0.1)
				(type default)
			)
			(layer "F.Fab")
		)
		(fp_line
			(start -0.12065 0.2794)
			(end -0.12065 0.3048)
			(stroke
				(width 0.1)
				(type default)
			)
			(layer "F.Fab")
		)
		(fp_line
			(start -0.12065 0.3048)
			(end -0.67945 0.3048)
			(stroke
				(width 0.1)
				(type default)
			)
			(layer "F.Fab")
		)
		(fp_line
			(start 0.120396 0.2794)
			(end -0.12065 0.2794)
			(stroke
				(width 0.1)
				(type default)
			)
			(layer "F.Fab")
		)
		(fp_line
			(start 0.120396 0.3048)
			(end 0.120396 0.2794)
			(stroke
				(width 0.1)
				(type default)
			)
			(layer "F.Fab")
		)
		(fp_line
			(start 0.12065 -0.3048)
			(end 0.67945 -0.3048)
			(stroke
				(width 0.1)
				(type default)
			)
			(layer "F.Fab")
		)
		(fp_line
			(start 0.12065 -0.2794)
			(end 0.12065 -0.3048)
			(stroke
				(width 0.1)
				(type default)
			)
			(layer "F.Fab")
		)
		(fp_line
			(start 0.67945 -0.3048)
			(end 0.67945 0.3048)
			(stroke
				(width 0.1)
				(type default)
			)
			(layer "F.Fab")
		)
		(fp_line
			(start 0.67945 0.3048)
			(end 0.120396 0.3048)
			(stroke
				(width 0.1)
				(type default)
			)
			(layer "F.Fab")
		)
		(pad "1" smd circle
			(at -0.40005 0)
			(size 0 0)
			(layers "F.Cu" "F.Mask" "F.Paste")
			(net "PWRGD_P1V8_PEX_R")
		)
		(pad "2" smd circle
			(at 0.40005 0)
			(size 0 0)
			(layers "F.Cu" "F.Mask" "F.Paste")
			(net "PWRGD_P1V8_PEX")
		)
	)
	(footprint ""
		(layer "F.Cu")
		(at 288.079942 -138.6332 180)
		(property "Reference" "R245"
			(at 0 0 180)
			(layer "F.SilkS")
			(hide yes)
			(effects
				(font
					(size 1.27 1.27)
				)
			)
		)
		(property "Value" ""
			(at 0 0 180)
			(layer "F.Fab")
			(effects
				(font
					(size 1.27 1.27)
				)
			)
		)
		(duplicate_pad_numbers_are_jumpers no)
		(fp_line
			(start 0.7874 0.4064)
			(end -0.7874 0.4064)
			(stroke
				(width 0.1524)
				(type default)
			)
			(layer "F.SilkS")
		)
		(fp_line
			(start 0.7874 -0.4064)
			(end 0.7874 0.4064)
			(stroke
				(width 0.1524)
				(type default)
			)
			(layer "F.SilkS")
		)
		(fp_line
			(start -0.7874 0.4064)
			(end -0.7874 -0.4064)
			(stroke
				(width 0.1524)
				(type default)
			)
			(layer "F.SilkS")
		)
		(fp_line
			(start -0.7874 -0.4064)
			(end 0.7874 -0.4064)
			(stroke
				(width 0.1524)
				(type default)
			)
			(layer "F.SilkS")
		)
		(fp_line
			(start 0.67945 0.3048)
			(end 0.120396 0.3048)
			(stroke
				(width 0.1)
				(type default)
			)
			(layer "F.Fab")
		)
		(fp_line
			(start 0.67945 -0.3048)
			(end 0.67945 0.3048)
			(stroke
				(width 0.1)
				(type default)
			)
			(layer "F.Fab")
		)
		(fp_line
			(start 0.12065 -0.2794)
			(end 0.12065 -0.3048)
			(stroke
				(width 0.1)
				(type default)
			)
			(layer "F.Fab")
		)
		(fp_line
			(start 0.12065 -0.3048)
			(end 0.67945 -0.3048)
			(stroke
				(width 0.1)
				(type default)
			)
			(layer "F.Fab")
		)
		(fp_line
			(start 0.120396 0.3048)
			(end 0.120396 0.2794)
			(stroke
				(width 0.1)
				(type default)
			)
			(layer "F.Fab")
		)
		(fp_line
			(start 0.120396 0.2794)
			(end -0.12065 0.2794)
			(stroke
				(width 0.1)
				(type default)
			)
			(layer "F.Fab")
		)
		(fp_line
			(start -0.12065 0.3048)
			(end -0.67945 0.3048)
			(stroke
				(width 0.1)
				(type default)
			)
			(layer "F.Fab")
		)
		(fp_line
			(start -0.12065 0.2794)
			(end -0.12065 0.3048)
			(stroke
				(width 0.1)
				(type default)
			)
			(layer "F.Fab")
		)
		(fp_line
			(start -0.12065 -0.2794)
			(end 0.12065 -0.2794)
			(stroke
				(width 0.1)
				(type default)
			)
			(layer "F.Fab")
		)
		(fp_line
			(start -0.12065 -0.305054)
			(end -0.12065 -0.2794)
			(stroke
				(width 0.1)
				(type default)
			)
			(layer "F.Fab")
		)
		(fp_line
			(start -0.67945 0.3048)
			(end -0.67945 -0.305054)
			(stroke
				(width 0.1)
				(type default)
			)
			(layer "F.Fab")
		)
		(fp_line
			(start -0.67945 -0.305054)
			(end -0.12065 -0.305054)
			(stroke
				(width 0.1)
				(type default)
			)
			(layer "F.Fab")
		)
		(pad "1" smd circle
			(at -0.40005 0 180)
			(size 0 0)
			(layers "F.Cu" "F.Mask" "F.Paste")
			(net "PRSNT_NIC4_N")
		)
		(pad "2" smd circle
			(at 0.40005 0 180)
			(size 0 0)
			(layers "F.Cu" "F.Mask" "F.Paste")
			(net "PRSNTB2_NIC4_N")
		)
	)
	(footprint ""
		(layer "F.Cu")
		(at 426.9105 -18.61439 90)
		(property "Reference" "U140"
			(at -1.44399 2.35077 90)
			(unlocked yes)
			(layer "F.SilkS")
			(effects
				(font
					(size 0.7874 0.5842)
					(thickness 0.1524)
				)
				(justify left)
			)
		)
		(property "Value" ""
			(at 0 0 90)
			(layer "F.Fab")
			(effects
				(font
					(size 1.27 1.27)
				)
			)
		)
		(duplicate_pad_numbers_are_jumpers no)
		(fp_line
			(start 1.463548 -1.549908)
			(end 1.463548 1.549908)
			(stroke
				(width 0.1524)
				(type default)
			)
			(layer "F.SilkS")
		)
		(fp_line
			(start 0.762 -1.549908)
			(end 1.463548 -1.549908)
			(stroke
				(width 0.1524)
				(type default)
			)
			(layer "F.SilkS")
		)
		(fp_line
			(start -0.787908 -1.549908)
			(end 0 -0.762)
			(stroke
				(width 0.1524)
				(type default)
			)
			(layer "F.SilkS")
		)
		(fp_line
			(start -1.463548 -1.549908)
			(end -0.787908 -1.549908)
			(stroke
				(width 0.1524)
				(type default)
			)
			(layer "F.SilkS")
		)
		(fp_line
			(start 0 -0.762)
			(end 0.762 -1.549908)
			(stroke
				(width 0.1524)
				(type default)
			)
			(layer "F.SilkS")
		)
		(fp_line
			(start 1.463548 1.549908)
			(end -1.463548 1.549908)
			(stroke
				(width 0.1524)
				(type default)
			)
			(layer "F.SilkS")
		)
		(fp_line
			(start -1.463548 1.549908)
			(end -1.463548 -1.549908)
			(stroke
				(width 0.1524)
				(type default)
			)
			(layer "F.SilkS")
		)
		(fp_poly
			(pts
				(xy -3.4798 -1.359916) (xy -2.86004 -1.050036) (xy -3.4798 -0.740156)
			)
			(stroke
				(width 0)
				(type default)
			)
			(fill yes)
			(layer "F.SilkS")
		)
		(fp_line
			(start 1.549908 -1.549908)
			(end 1.549908 1.549908)
			(stroke
				(width 0.1)
				(type default)
			)
			(layer "F.Fab")
		)
		(fp_line
			(start -1.549908 -1.549908)
			(end 1.549908 -1.549908)
			(stroke
				(width 0.1)
				(type default)
			)
			(layer "F.Fab")
		)
		(fp_line
			(start 1.549908 1.549908)
			(end -1.549908 1.549908)
			(stroke
				(width 0.1)
				(type default)
			)
			(layer "F.Fab")
		)
		(fp_line
			(start -1.549908 1.549908)
			(end -1.549908 -1.549908)
			(stroke
				(width 0.1)
				(type default)
			)
			(layer "F.Fab")
		)
		(fp_poly
			(pts
				(xy -3.4798 -1.359916) (xy -2.86004 -1.050036) (xy -3.4798 -0.740156)
			)
			(stroke
				(width 0)
				(type default)
			)
			(fill yes)
			(layer "F.Fab")
		)
		(pad "1" smd rect
			(at -2.175002 -1.050036 180)
			(size 0.6096 1.1684)
			(layers "F.Cu" "F.Mask" "F.Paste")
			(net "P3V3_SSD14")
		)
		(pad "2" smd rect
			(at -2.175002 -0.32512 180)
			(size 0.4318 1.1684)
			(layers "F.Cu" "F.Mask" "F.Paste")
			(net "SMB_ISO_SSD14_SCL")
		)
		(pad "3" smd rect
			(at -2.175002 0.32512 180)
			(size 0.4318 1.1684)
			(layers "F.Cu" "F.Mask" "F.Paste")
			(net "SMB_ISO_SSD14_SDA")
		)
		(pad "4" smd rect
			(at -2.175002 1.050036 180)
			(size 0.6096 1.1684)
			(layers "F.Cu" "F.Mask" "F.Paste")
			(net "GND")
		)
		(pad "5" smd rect
			(at 2.175002 1.050036 180)
			(size 0.6096 1.1684)
			(layers "F.Cu" "F.Mask" "F.Paste")
			(net "SMB_SSD14_ISO_EN")
		)
		(pad "6" smd rect
			(at 2.175002 0.32512 180)
			(size 0.4318 1.1684)
			(layers "F.Cu" "F.Mask" "F.Paste")
			(net "SMB_BIC_I2C9_MUX1_SSD14_R_SDA")
		)
		(pad "7" smd rect
			(at 2.175002 -0.32512 180)
			(size 0.4318 1.1684)
			(layers "F.Cu" "F.Mask" "F.Paste")
			(net "SMB_BIC_I2C9_MUX1_SSD14_R_SCL")
		)
		(pad "8" smd rect
			(at 2.175002 -1.050036 180)
			(size 0.6096 1.1684)
			(layers "F.Cu" "F.Mask" "F.Paste")
			(net "P3V3_AUX")
		)
	)
	(footprint ""
		(layer "F.Cu")
		(at 98.048318 -392.0998)
		(property "Reference" "R5450"
			(at 0 0 0)
			(layer "F.SilkS")
			(hide yes)
			(effects
				(font
					(size 1.27 1.27)
				)
			)
		)
		(property "Value" ""
			(at 0 0 0)
			(layer "F.Fab")
			(effects
				(font
					(size 1.27 1.27)
				)
			)
		)
		(duplicate_pad_numbers_are_jumpers no)
		(fp_line
			(start -0.7874 -0.4064)
			(end 0.7874 -0.4064)
			(stroke
				(width 0.1524)
				(type default)
			)
			(layer "F.SilkS")
		)
		(fp_line
			(start -0.7874 0.4064)
			(end -0.7874 -0.4064)
			(stroke
				(width 0.1524)
				(type default)
			)
			(layer "F.SilkS")
		)
		(fp_line
			(start 0.7874 -0.4064)
			(end 0.7874 0.4064)
			(stroke
				(width 0.1524)
				(type default)
			)
			(layer "F.SilkS")
		)
		(fp_line
			(start 0.7874 0.4064)
			(end -0.7874 0.4064)
			(stroke
				(width 0.1524)
				(type default)
			)
			(layer "F.SilkS")
		)
		(fp_line
			(start -0.67945 -0.305054)
			(end -0.12065 -0.305054)
			(stroke
				(width 0.1)
				(type default)
			)
			(layer "F.Fab")
		)
		(fp_line
			(start -0.67945 0.3048)
			(end -0.67945 -0.305054)
			(stroke
				(width 0.1)
				(type default)
			)
			(layer "F.Fab")
		)
		(fp_line
			(start -0.12065 -0.305054)
			(end -0.12065 -0.2794)
			(stroke
				(width 0.1)
				(type default)
			)
			(layer "F.Fab")
		)
		(fp_line
			(start -0.12065 -0.2794)
			(end 0.12065 -0.2794)
			(stroke
				(width 0.1)
				(type default)
			)
			(layer "F.Fab")
		)
		(fp_line
			(start -0.12065 0.2794)
			(end -0.12065 0.3048)
			(stroke
				(width 0.1)
				(type default)
			)
			(layer "F.Fab")
		)
		(fp_line
			(start -0.12065 0.3048)
			(end -0.67945 0.3048)
			(stroke
				(width 0.1)
				(type default)
			)
			(layer "F.Fab")
		)
		(fp_line
			(start 0.120396 0.2794)
			(end -0.12065 0.2794)
			(stroke
				(width 0.1)
				(type default)
			)
			(layer "F.Fab")
		)
		(fp_line
			(start 0.120396 0.3048)
			(end 0.120396 0.2794)
			(stroke
				(width 0.1)
				(type default)
			)
			(layer "F.Fab")
		)
		(fp_line
			(start 0.12065 -0.3048)
			(end 0.67945 -0.3048)
			(stroke
				(width 0.1)
				(type default)
			)
			(layer "F.Fab")
		)
		(fp_line
			(start 0.12065 -0.2794)
			(end 0.12065 -0.3048)
			(stroke
				(width 0.1)
				(type default)
			)
			(layer "F.Fab")
		)
		(fp_line
			(start 0.67945 -0.3048)
			(end 0.67945 0.3048)
			(stroke
				(width 0.1)
				(type default)
			)
			(layer "F.Fab")
		)
		(fp_line
			(start 0.67945 0.3048)
			(end 0.120396 0.3048)
			(stroke
				(width 0.1)
				(type default)
			)
			(layer "F.Fab")
		)
		(pad "1" smd circle
			(at -0.40005 0)
			(size 0 0)
			(layers "F.Cu" "F.Mask" "F.Paste")
			(net "P3V3_AUX")
		)
		(pad "2" smd circle
			(at 0.40005 0)
			(size 0 0)
			(layers "F.Cu" "F.Mask" "F.Paste")
			(net "BIC_USB_HUB_OVCUR2")
		)
	)
	(footprint ""
		(layer "F.Cu")
		(at 211.177886 -233.881422 -90)
		(property "Reference" "R1547"
			(at 0 0 270)
			(layer "F.SilkS")
			(hide yes)
			(effects
				(font
					(size 1.27 1.27)
				)
			)
		)
		(property "Value" ""
			(at 0 0 270)
			(layer "F.Fab")
			(effects
				(font
					(size 1.27 1.27)
				)
			)
		)
		(duplicate_pad_numbers_are_jumpers no)
		(fp_line
			(start -0.7874 0.4064)
			(end -0.7874 -0.4064)
			(stroke
				(width 0.1524)
				(type default)
			)
			(layer "F.SilkS")
		)
		(fp_line
			(start 0.7874 0.4064)
			(end -0.7874 0.4064)
			(stroke
				(width 0.1524)
				(type default)
			)
			(layer "F.SilkS")
		)
		(fp_line
			(start -0.7874 -0.4064)
			(end 0.7874 -0.4064)
			(stroke
				(width 0.1524)
				(type default)
			)
			(layer "F.SilkS")
		)
		(fp_line
			(start 0.7874 -0.4064)
			(end 0.7874 0.4064)
			(stroke
				(width 0.1524)
				(type default)
			)
			(layer "F.SilkS")
		)
		(fp_line
			(start -0.67945 0.3048)
			(end -0.67945 -0.305054)
			(stroke
				(width 0.1)
				(type default)
			)
			(layer "F.Fab")
		)
		(fp_line
			(start -0.12065 0.3048)
			(end -0.67945 0.3048)
			(stroke
				(width 0.1)
				(type default)
			)
			(layer "F.Fab")
		)
		(fp_line
			(start 0.120396 0.3048)
			(end 0.120396 0.2794)
			(stroke
				(width 0.1)
				(type default)
			)
			(layer "F.Fab")
		)
		(fp_line
			(start 0.67945 0.3048)
			(end 0.120396 0.3048)
			(stroke
				(width 0.1)
				(type default)
			)
			(layer "F.Fab")
		)
		(fp_line
			(start -0.12065 0.2794)
			(end -0.12065 0.3048)
			(stroke
				(width 0.1)
				(type default)
			)
			(layer "F.Fab")
		)
		(fp_line
			(start 0.120396 0.2794)
			(end -0.12065 0.2794)
			(stroke
				(width 0.1)
				(type default)
			)
			(layer "F.Fab")
		)
		(fp_line
			(start -0.12065 -0.2794)
			(end 0.12065 -0.2794)
			(stroke
				(width 0.1)
				(type default)
			)
			(layer "F.Fab")
		)
		(fp_line
			(start 0.12065 -0.2794)
			(end 0.12065 -0.3048)
			(stroke
				(width 0.1)
				(type default)
			)
			(layer "F.Fab")
		)
		(fp_line
			(start 0.12065 -0.3048)
			(end 0.67945 -0.3048)
			(stroke
				(width 0.1)
				(type default)
			)
			(layer "F.Fab")
		)
		(fp_line
			(start 0.67945 -0.3048)
			(end 0.67945 0.3048)
			(stroke
				(width 0.1)
				(type default)
			)
			(layer "F.Fab")
		)
		(fp_line
			(start -0.67945 -0.305054)
			(end -0.12065 -0.305054)
			(stroke
				(width 0.1)
				(type default)
			)
			(layer "F.Fab")
		)
		(fp_line
			(start -0.12065 -0.305054)
			(end -0.12065 -0.2794)
			(stroke
				(width 0.1)
				(type default)
			)
			(layer "F.Fab")
		)
		(pad "1" smd circle
			(at -0.40005 0 270)
			(size 0 0)
			(layers "F.Cu" "F.Mask" "F.Paste")
			(net "SMB_PEX_LS_R_SCL")
		)
		(pad "2" smd circle
			(at 0.40005 0 270)
			(size 0 0)
			(layers "F.Cu" "F.Mask" "F.Paste")
			(net "SMB_PEX2_SCL")
		)
	)
	(footprint ""
		(layer "F.Cu")
		(at 378.673868 -27.006296 -90)
		(property "Reference" "PC964"
			(at 0 0 270)
			(layer "F.SilkS")
			(hide yes)
			(effects
				(font
					(size 1.27 1.27)
				)
			)
		)
		(property "Value" ""
			(at 0 0 270)
			(layer "F.Fab")
			(effects
				(font
					(size 1.27 1.27)
				)
			)
		)
		(duplicate_pad_numbers_are_jumpers no)
		(fp_line
			(start -0.7874 0.4064)
			(end -0.7874 -0.4064)
			(stroke
				(width 0.1524)
				(type default)
			)
			(layer "F.SilkS")
		)
		(fp_line
			(start 0.7874 0.4064)
			(end -0.7874 0.4064)
			(stroke
				(width 0.1524)
				(type default)
			)
			(layer "F.SilkS")
		)
		(fp_line
			(start -0.7874 -0.4064)
			(end 0.7874 -0.4064)
			(stroke
				(width 0.1524)
				(type default)
			)
			(layer "F.SilkS")
		)
		(fp_line
			(start 0.7874 -0.4064)
			(end 0.7874 0.4064)
			(stroke
				(width 0.1524)
				(type default)
			)
			(layer "F.SilkS")
		)
		(fp_line
			(start -0.67945 0.3048)
			(end -0.67945 -0.305054)
			(stroke
				(width 0.1)
				(type default)
			)
			(layer "F.Fab")
		)
		(fp_line
			(start -0.12065 0.3048)
			(end -0.67945 0.3048)
			(stroke
				(width 0.1)
				(type default)
			)
			(layer "F.Fab")
		)
		(fp_line
			(start 0.120396 0.3048)
			(end 0.120396 0.2794)
			(stroke
				(width 0.1)
				(type default)
			)
			(layer "F.Fab")
		)
		(fp_line
			(start 0.67945 0.3048)
			(end 0.120396 0.3048)
			(stroke
				(width 0.1)
				(type default)
			)
			(layer "F.Fab")
		)
		(fp_line
			(start -0.12065 0.2794)
			(end -0.12065 0.3048)
			(stroke
				(width 0.1)
				(type default)
			)
			(layer "F.Fab")
		)
		(fp_line
			(start 0.120396 0.2794)
			(end -0.12065 0.2794)
			(stroke
				(width 0.1)
				(type default)
			)
			(layer "F.Fab")
		)
		(fp_line
			(start -0.12065 -0.2794)
			(end 0.12065 -0.2794)
			(stroke
				(width 0.1)
				(type default)
			)
			(layer "F.Fab")
		)
		(fp_line
			(start 0.12065 -0.2794)
			(end 0.12065 -0.3048)
			(stroke
				(width 0.1)
				(type default)
			)
			(layer "F.Fab")
		)
		(fp_line
			(start 0.12065 -0.3048)
			(end 0.67945 -0.3048)
			(stroke
				(width 0.1)
				(type default)
			)
			(layer "F.Fab")
		)
		(fp_line
			(start 0.67945 -0.3048)
			(end 0.67945 0.3048)
			(stroke
				(width 0.1)
				(type default)
			)
			(layer "F.Fab")
		)
		(fp_line
			(start -0.67945 -0.305054)
			(end -0.12065 -0.305054)
			(stroke
				(width 0.1)
				(type default)
			)
			(layer "F.Fab")
		)
		(fp_line
			(start -0.12065 -0.305054)
			(end -0.12065 -0.2794)
			(stroke
				(width 0.1)
				(type default)
			)
			(layer "F.Fab")
		)
		(pad "1" smd circle
			(at -0.40005 0 270)
			(size 0 0)
			(layers "F.Cu" "F.Mask" "F.Paste")
			(net "P3V3_SSD13_CO_MODE")
		)
		(pad "2" smd circle
			(at 0.40005 0 270)
			(size 0 0)
			(layers "F.Cu" "F.Mask" "F.Paste")
			(net "GND")
		)
	)
	(footprint ""
		(layer "F.Cu")
		(at 38.875208 -343.952322 90)
		(property "Reference" "C2169"
			(at 0 0 90)
			(layer "F.SilkS")
			(hide yes)
			(effects
				(font
					(size 1.27 1.27)
				)
			)
		)
		(property "Value" ""
			(at 0 0 90)
			(layer "F.Fab")
			(effects
				(font
					(size 1.27 1.27)
				)
			)
		)
		(duplicate_pad_numbers_are_jumpers no)
		(fp_line
			(start 0.299974 -0.150114)
			(end 0.299974 0.150114)
			(stroke
				(width 0.1)
				(type default)
			)
			(layer "F.Fab")
		)
		(fp_line
			(start -0.299974 -0.150114)
			(end 0.299974 -0.150114)
			(stroke
				(width 0.1)
				(type default)
			)
			(layer "F.Fab")
		)
		(fp_line
			(start 0.299974 0.150114)
			(end -0.299974 0.150114)
			(stroke
				(width 0.1)
				(type default)
			)
			(layer "F.Fab")
		)
		(fp_line
			(start -0.299974 0.150114)
			(end -0.299974 -0.150114)
			(stroke
				(width 0.1)
				(type default)
			)
			(layer "F.Fab")
		)
		(pad "1" smd rect
			(at -0.2667 0 90)
			(size 0.3048 0.381)
			(layers "F.Cu" "F.Mask" "F.Paste")
			(net "P5E_PEX0_STN4_TX_DN<71>")
		)
		(pad "2" smd rect
			(at 0.2667 0 90)
			(size 0.3048 0.381)
			(layers "F.Cu" "F.Mask" "F.Paste")
			(net "P5E_PEX0_STN4_TX_C_DN<71>")
		)
	)
	(footprint ""
		(layer "F.Cu")
		(at 328.106024 8.116824)
		(property "Reference" "DE14T_2"
			(at -3.6068 -2.962148 0)
			(unlocked yes)
			(layer "F.SilkS")
			(effects
				(font
					(size 0.7874 0.5842)
					(thickness 0.1524)
				)
				(justify left)
			)
		)
		(property "Value" ""
			(at 0 0 0)
			(layer "F.Fab")
			(effects
				(font
					(size 1.27 1.27)
				)
			)
		)
		(duplicate_pad_numbers_are_jumpers no)
		(fp_line
			(start -1.2192 -2.1082)
			(end 1.2192 -2.1082)
			(stroke
				(width 0.1524)
				(type default)
			)
			(layer "F.SilkS")
		)
		(fp_line
			(start -1.2192 2.1082)
			(end -1.2192 -2.1082)
			(stroke
				(width 0.1524)
				(type default)
			)
			(layer "F.SilkS")
		)
		(fp_line
			(start 1.2192 -2.1082)
			(end 1.2192 2.1082)
			(stroke
				(width 0.1524)
				(type default)
			)
			(layer "F.SilkS")
		)
		(fp_line
			(start 1.2192 2.1082)
			(end -1.2192 2.1082)
			(stroke
				(width 0.1524)
				(type default)
			)
			(layer "F.SilkS")
		)
		(pad "" np_thru_hole circle
			(at -2.8829 -1.27 270)
			(size 1.0414 1.0414)
			(drill 1.0414)
			(layers "*.Cu" "*.Mask")
			(clearance 0.381)
			(thermal_gap 0.381)
		)
		(pad "" np_thru_hole circle
			(at -2.8829 1.27 270)
			(size 1.0414 1.0414)
			(drill 1.0414)
			(layers "*.Cu" "*.Mask")
			(clearance 0.381)
			(thermal_gap 0.381)
		)
		(pad "" np_thru_hole circle
			(at 3.4671 -1.27 270)
			(size 1.0414 1.0414)
			(drill 1.0414)
			(layers "*.Cu" "*.Mask")
			(clearance 0.381)
			(thermal_gap 0.381)
		)
		(pad "" np_thru_hole circle
			(at 3.4671 1.27 270)
			(size 1.0414 1.0414)
			(drill 1.0414)
			(layers "*.Cu" "*.Mask")
			(clearance 0.381)
			(thermal_gap 0.381)
		)
		(pad "1" smd rect
			(at 0.8255 -0.249936 270)
			(size 0.3048 0.508)
			(layers "F.Cu" "F.Mask" "F.Paste")
			(net "85_10INCH_IN2_DN")
		)
		(pad "2" smd rect
			(at 0.8255 0.249936 270)
			(size 0.3048 0.508)
			(layers "F.Cu" "F.Mask" "F.Paste")
			(net "85_10INCH_IN2_DP")
		)
		(pad "3" smd circle
			(at 0 0)
			(size 0 0)
			(layers "F.Cu" "F.Mask" "F.Paste")
			(net "COUPON_GND2")
		)
		(zone
			(layer "F.Cu")
			(hatch none 0.5)
			(connect_pads
				(clearance 0)
			)
			(min_thickness 0.25)
			(keepout
				(tracks not_allowed)
				(vias allowed)
				(pads allowed)
				(copperpour not_allowed)
				(footprints allowed)
			)
			(placement
				(enabled no)
				(sheetname "")
			)
			(fill
				(thermal_gap 0.5)
				(thermal_bridge_width 0.5)
				(island_removal_mode 0)
			)
			(polygon
				(pts
					(xy 329.223624 7.568184) (xy 329.223624 7.663688) (xy 328.626724 7.663688) (xy 328.626724 8.070088)
					(xy 329.223624 8.070088) (xy 329.223624 8.16356) (xy 328.626724 8.16356) (xy 328.626724 8.56996)
					(xy 329.223624 8.56996) (xy 329.223624 8.665464) (xy 328.525124 8.665464) (xy 328.525124 7.568184)
				)
			)
		)
		(zone
			(layers "F.Cu" "B.Cu" "In1.Cu" "In2.Cu" "In3.Cu" "In4.Cu" "In5.Cu" "In6.Cu"
				"In7.Cu" "In8.Cu" "In9.Cu" "In10.Cu" "In11.Cu" "In12.Cu" "In13.Cu" "In14.Cu"
				"In15.Cu" "In16.Cu"
			)
			(hatch none 0.5)
			(connect_pads
				(clearance 0)
			)
			(min_thickness 0.25)
			(keepout
				(tracks not_allowed)
				(vias allowed)
				(pads allowed)
				(copperpour not_allowed)
				(footprints allowed)
			)
			(placement
				(enabled no)
				(sheetname "")
			)
			(fill
				(thermal_gap 0.5)
				(thermal_bridge_width 0.5)
				(island_removal_mode 0)
			)
			(polygon
				(pts
					(arc
						(start 326.150224 6.846824)
						(mid 324.296024 6.846824)
						(end 326.150224 6.846824)
					)
				)
			)
		)
		(zone
			(layers "F.Cu" "B.Cu" "In1.Cu" "In2.Cu" "In3.Cu" "In4.Cu" "In5.Cu" "In6.Cu"
				"In7.Cu" "In8.Cu" "In9.Cu" "In10.Cu" "In11.Cu" "In12.Cu" "In13.Cu" "In14.Cu"
				"In15.Cu" "In16.Cu"
			)
			(hatch none 0.5)
			(connect_pads
				(clearance 0)
			)
			(min_thickness 0.25)
			(keepout
				(tracks not_allowed)
				(vias allowed)
				(pads allowed)
				(copperpour not_allowed)
				(footprints allowed)
			)
			(placement
				(enabled no)
				(sheetname "")
			)
			(fill
				(thermal_gap 0.5)
				(thermal_bridge_width 0.5)
				(island_removal_mode 0)
			)
			(polygon
				(pts
					(arc
						(start 326.150224 9.386824)
						(mid 324.296024 9.386824)
						(end 326.150224 9.386824)
					)
				)
			)
		)
		(zone
			(layers "F.Cu" "B.Cu" "In1.Cu" "In2.Cu" "In3.Cu" "In4.Cu" "In5.Cu" "In6.Cu"
				"In7.Cu" "In8.Cu" "In9.Cu" "In10.Cu" "In11.Cu" "In12.Cu" "In13.Cu" "In14.Cu"
				"In15.Cu" "In16.Cu"
			)
			(hatch none 0.5)
			(connect_pads
				(clearance 0)
			)
			(min_thickness 0.25)
			(keepout
				(tracks not_allowed)
				(vias allowed)
				(pads allowed)
				(copperpour not_allowed)
				(footprints allowed)
			)
			(placement
				(enabled no)
				(sheetname "")
			)
			(fill
				(thermal_gap 0.5)
				(thermal_bridge_width 0.5)
				(island_removal_mode 0)
			)
			(polygon
				(pts
					(arc
						(start 332.500224 6.846824)
						(mid 330.646024 6.846824)
						(end 332.500224 6.846824)
					)
				)
			)
		)
		(zone
			(layers "F.Cu" "B.Cu" "In1.Cu" "In2.Cu" "In3.Cu" "In4.Cu" "In5.Cu" "In6.Cu"
				"In7.Cu" "In8.Cu" "In9.Cu" "In10.Cu" "In11.Cu" "In12.Cu" "In13.Cu" "In14.Cu"
				"In15.Cu" "In16.Cu"
			)
			(hatch none 0.5)
			(connect_pads
				(clearance 0)
			)
			(min_thickness 0.25)
			(keepout
				(tracks not_allowed)
				(vias allowed)
				(pads allowed)
				(copperpour not_allowed)
				(footprints allowed)
			)
			(placement
				(enabled no)
				(sheetname "")
			)
			(fill
				(thermal_gap 0.5)
				(thermal_bridge_width 0.5)
				(island_removal_mode 0)
			)
			(polygon
				(pts
					(arc
						(start 332.500224 9.386824)
						(mid 330.646024 9.386824)
						(end 332.500224 9.386824)
					)
				)
			)
		)
	)
	(footprint ""
		(layer "F.Cu")
		(at 228.161088 -37.951156)
		(property "Reference" "Q224"
			(at 0.403352 -2.925064 0)
			(unlocked yes)
			(layer "F.SilkS")
			(effects
				(font
					(size 0.7874 0.5842)
					(thickness 0.1524)
				)
			)
		)
		(property "Value" ""
			(at 0 0 0)
			(layer "F.Fab")
			(effects
				(font
					(size 1.27 1.27)
				)
			)
		)
		(duplicate_pad_numbers_are_jumpers no)
		(fp_line
			(start -1.376172 -1.199896)
			(end -0.508 -1.199896)
			(stroke
				(width 0.1524)
				(type default)
			)
			(layer "F.SilkS")
		)
		(fp_line
			(start -1.376172 1.199896)
			(end -1.376172 -1.199896)
			(stroke
				(width 0.1524)
				(type default)
			)
			(layer "F.SilkS")
		)
		(fp_line
			(start -0.508 -1.199896)
			(end 0 -0.762)
			(stroke
				(width 0.1524)
				(type default)
			)
			(layer "F.SilkS")
		)
		(fp_line
			(start 0 -0.762)
			(end 0.508 -1.199896)
			(stroke
				(width 0.1524)
				(type default)
			)
			(layer "F.SilkS")
		)
		(fp_line
			(start 0.508 -1.199896)
			(end 1.376172 -1.199896)
			(stroke
				(width 0.1524)
				(type default)
			)
			(layer "F.SilkS")
		)
		(fp_line
			(start 1.376172 -1.199896)
			(end 1.376172 1.199896)
			(stroke
				(width 0.1524)
				(type default)
			)
			(layer "F.SilkS")
		)
		(fp_line
			(start 1.376172 1.199896)
			(end -1.376172 1.199896)
			(stroke
				(width 0.1524)
				(type default)
			)
			(layer "F.SilkS")
		)
		(fp_poly
			(pts
				(xy -1.40716 -1.405636) (xy -1.6764 -2.213864) (xy -2.215388 -1.674876)
			)
			(stroke
				(width 0)
				(type default)
			)
			(fill yes)
			(layer "F.SilkS")
		)
		(fp_line
			(start -0.674878 -1.100074)
			(end 0.674878 -1.100074)
			(stroke
				(width 0.1)
				(type default)
			)
			(layer "F.Fab")
		)
		(fp_line
			(start -0.674878 1.100074)
			(end -0.674878 -1.100074)
			(stroke
				(width 0.1)
				(type default)
			)
			(layer "F.Fab")
		)
		(fp_line
			(start 0.674878 -1.100074)
			(end 0.674878 1.100074)
			(stroke
				(width 0.1)
				(type default)
			)
			(layer "F.Fab")
		)
		(fp_line
			(start 0.674878 1.100074)
			(end -0.674878 1.100074)
			(stroke
				(width 0.1)
				(type default)
			)
			(layer "F.Fab")
		)
		(fp_poly
			(pts
				(xy -1.4605 -0.7493) (xy -2.2225 -1.1303) (xy -2.2225 -0.3683)
			)
			(stroke
				(width 0)
				(type default)
			)
			(fill yes)
			(layer "F.Fab")
		)
		(pad "1" smd rect
			(at -0.899922 -0.750062 270)
			(size 0.6096 0.6096)
			(layers "F.Cu" "F.Mask" "F.Paste")
			(net "GND")
		)
		(pad "2" smd rect
			(at -0.899922 0 270)
			(size 0.4064 0.6096)
			(layers "F.Cu" "F.Mask" "F.Paste")
			(net "P3V3_SSD8_PG_G1")
		)
		(pad "3" smd rect
			(at -0.899922 0.750062 270)
			(size 0.6096 0.6096)
			(layers "F.Cu" "F.Mask" "F.Paste")
			(net "PWRGD_P3V3_SSD8_D")
		)
		(pad "4" smd rect
			(at 0.899922 0.750062 270)
			(size 0.6096 0.6096)
			(layers "F.Cu" "F.Mask" "F.Paste")
			(net "GND")
		)
		(pad "5" smd rect
			(at 0.899922 0 270)
			(size 0.4064 0.6096)
			(layers "F.Cu" "F.Mask" "F.Paste")
			(net "P3V3_SSD8_PG_G2")
		)
		(pad "6" smd rect
			(at 0.899922 -0.750062 270)
			(size 0.6096 0.6096)
			(layers "F.Cu" "F.Mask" "F.Paste")
			(net "P3V3_SSD8_PG_G2")
		)
	)
	(footprint ""
		(layer "F.Cu")
		(at 93.142562 -70.844918 -90)
		(property "Reference" "PD91"
			(at 3.890518 2.158492 90)
			(unlocked yes)
			(layer "F.SilkS")
			(effects
				(font
					(size 0.7874 0.5842)
					(thickness 0.1524)
				)
				(justify left)
			)
		)
		(property "Value" ""
			(at 0 0 270)
			(layer "F.Fab")
			(effects
				(font
					(size 1.27 1.27)
				)
			)
		)
		(duplicate_pad_numbers_are_jumpers no)
		(fp_line
			(start -3.400044 1.459992)
			(end -3.400044 -1.459992)
			(stroke
				(width 0.1524)
				(type default)
			)
			(layer "F.SilkS")
		)
		(fp_line
			(start 4.107942 1.459992)
			(end -3.400044 1.459992)
			(stroke
				(width 0.1524)
				(type default)
			)
			(layer "F.SilkS")
		)
		(fp_line
			(start -3.400044 -1.459992)
			(end 4.107942 -1.459992)
			(stroke
				(width 0.1524)
				(type default)
			)
			(layer "F.SilkS")
		)
		(fp_line
			(start 4.107942 -1.459992)
			(end 4.107942 1.459992)
			(stroke
				(width 0.1524)
				(type default)
			)
			(layer "F.SilkS")
		)
		(fp_poly
			(pts
				(xy 4.107942 -1.459992) (xy 4.107942 1.459992) (xy 3.308096 1.459992) (xy 3.308096 -1.459992)
			)
			(stroke
				(width 0)
				(type default)
			)
			(fill yes)
			(layer "F.SilkS")
		)
		(fp_line
			(start -2.29997 1.459992)
			(end -2.29997 -1.459992)
			(stroke
				(width 0.1)
				(type default)
			)
			(layer "F.Fab")
		)
		(fp_line
			(start 2.29997 1.459992)
			(end -2.29997 1.459992)
			(stroke
				(width 0.1)
				(type default)
			)
			(layer "F.Fab")
		)
		(fp_line
			(start -2.29997 -1.459992)
			(end 2.29997 -1.459992)
			(stroke
				(width 0.1)
				(type default)
			)
			(layer "F.Fab")
		)
		(fp_line
			(start 2.29997 -1.459992)
			(end 2.29997 1.459992)
			(stroke
				(width 0.1)
				(type default)
			)
			(layer "F.Fab")
		)
		(fp_text user "-"
			(at 5.4102 0.29845 90)
			(unlocked yes)
			(layer "F.SilkS")
			(effects
				(font
					(size 1.905 1.4224)
					(thickness 0.1524)
				)
				(justify left)
			)
		)
		(fp_text user "+"
			(at -5.202682 -0.214376 270)
			(unlocked yes)
			(layer "F.SilkS")
			(effects
				(font
					(size 1.905 1.4224)
					(thickness 0.1524)
				)
				(justify left)
			)
		)
		(fp_text user "-"
			(at 5.4102 0.29845 90)
			(unlocked yes)
			(layer "F.Fab")
			(effects
				(font
					(size 1.905 1.4224)
					(thickness 0.1524)
				)
				(justify left)
			)
		)
		(fp_text user "+"
			(at -4.7752 -0.12065 270)
			(unlocked yes)
			(layer "F.Fab")
			(effects
				(font
					(size 1.905 1.4224)
					(thickness 0.1524)
				)
				(justify left)
			)
		)
		(pad "A" smd rect
			(at -1.999996 0)
			(size 1.7018 2.5146)
			(layers "F.Cu" "F.Mask" "F.Paste")
			(net "GND")
		)
		(pad "C" smd rect
			(at 1.999996 0)
			(size 1.7018 2.5146)
			(layers "F.Cu" "F.Mask" "F.Paste")
			(net "P12V_SSD3_R")
		)
	)
	(footprint ""
		(layer "F.Cu")
		(at 387.580632 -103.803196)
		(property "Reference" "C693"
			(at 0 0 0)
			(layer "F.SilkS")
			(hide yes)
			(effects
				(font
					(size 1.27 1.27)
				)
			)
		)
		(property "Value" ""
			(at 0 0 0)
			(layer "F.Fab")
			(effects
				(font
					(size 1.27 1.27)
				)
			)
		)
		(duplicate_pad_numbers_are_jumpers no)
		(fp_line
			(start -0.299974 -0.150114)
			(end 0.299974 -0.150114)
			(stroke
				(width 0.1)
				(type default)
			)
			(layer "F.Fab")
		)
		(fp_line
			(start -0.299974 0.150114)
			(end -0.299974 -0.150114)
			(stroke
				(width 0.1)
				(type default)
			)
			(layer "F.Fab")
		)
		(fp_line
			(start 0.299974 -0.150114)
			(end 0.299974 0.150114)
			(stroke
				(width 0.1)
				(type default)
			)
			(layer "F.Fab")
		)
		(fp_line
			(start 0.299974 0.150114)
			(end -0.299974 0.150114)
			(stroke
				(width 0.1)
				(type default)
			)
			(layer "F.Fab")
		)
		(pad "1" smd rect
			(at -0.2667 0)
			(size 0.3048 0.381)
			(layers "F.Cu" "F.Mask" "F.Paste")
			(net "P5E_PEX3_STN1_TX_DN<18>")
		)
		(pad "2" smd rect
			(at 0.2667 0)
			(size 0.3048 0.381)
			(layers "F.Cu" "F.Mask" "F.Paste")
			(net "P5E_PEX3_STN1_TX_C_DN<18>")
		)
	)
	(footprint ""
		(layer "F.Cu")
		(at 421.247316 -19.33956)
		(property "Reference" "C3975"
			(at 0 0 0)
			(layer "F.SilkS")
			(hide yes)
			(effects
				(font
					(size 1.27 1.27)
				)
			)
		)
		(property "Value" ""
			(at 0 0 0)
			(layer "F.Fab")
			(effects
				(font
					(size 1.27 1.27)
				)
			)
		)
		(duplicate_pad_numbers_are_jumpers no)
		(fp_line
			(start -0.7874 -0.4064)
			(end 0.7874 -0.4064)
			(stroke
				(width 0.1524)
				(type default)
			)
			(layer "F.SilkS")
		)
		(fp_line
			(start -0.7874 0.4064)
			(end -0.7874 -0.4064)
			(stroke
				(width 0.1524)
				(type default)
			)
			(layer "F.SilkS")
		)
		(fp_line
			(start 0.7874 -0.4064)
			(end 0.7874 0.4064)
			(stroke
				(width 0.1524)
				(type default)
			)
			(layer "F.SilkS")
		)
		(fp_line
			(start 0.7874 0.4064)
			(end -0.7874 0.4064)
			(stroke
				(width 0.1524)
				(type default)
			)
			(layer "F.SilkS")
		)
		(fp_line
			(start -0.67945 -0.305054)
			(end -0.12065 -0.305054)
			(stroke
				(width 0.1)
				(type default)
			)
			(layer "F.Fab")
		)
		(fp_line
			(start -0.67945 0.3048)
			(end -0.67945 -0.305054)
			(stroke
				(width 0.1)
				(type default)
			)
			(layer "F.Fab")
		)
		(fp_line
			(start -0.12065 -0.305054)
			(end -0.12065 -0.2794)
			(stroke
				(width 0.1)
				(type default)
			)
			(layer "F.Fab")
		)
		(fp_line
			(start -0.12065 -0.2794)
			(end 0.12065 -0.2794)
			(stroke
				(width 0.1)
				(type default)
			)
			(layer "F.Fab")
		)
		(fp_line
			(start -0.12065 0.2794)
			(end -0.12065 0.3048)
			(stroke
				(width 0.1)
				(type default)
			)
			(layer "F.Fab")
		)
		(fp_line
			(start -0.12065 0.3048)
			(end -0.67945 0.3048)
			(stroke
				(width 0.1)
				(type default)
			)
			(layer "F.Fab")
		)
		(fp_line
			(start 0.120396 0.2794)
			(end -0.12065 0.2794)
			(stroke
				(width 0.1)
				(type default)
			)
			(layer "F.Fab")
		)
		(fp_line
			(start 0.120396 0.3048)
			(end 0.120396 0.2794)
			(stroke
				(width 0.1)
				(type default)
			)
			(layer "F.Fab")
		)
		(fp_line
			(start 0.12065 -0.3048)
			(end 0.67945 -0.3048)
			(stroke
				(width 0.1)
				(type default)
			)
			(layer "F.Fab")
		)
		(fp_line
			(start 0.12065 -0.2794)
			(end 0.12065 -0.3048)
			(stroke
				(width 0.1)
				(type default)
			)
			(layer "F.Fab")
		)
		(fp_line
			(start 0.67945 -0.3048)
			(end 0.67945 0.3048)
			(stroke
				(width 0.1)
				(type default)
			)
			(layer "F.Fab")
		)
		(fp_line
			(start 0.67945 0.3048)
			(end 0.120396 0.3048)
			(stroke
				(width 0.1)
				(type default)
			)
			(layer "F.Fab")
		)
		(pad "1" smd circle
			(at -0.40005 0)
			(size 0 0)
			(layers "F.Cu" "F.Mask" "F.Paste")
			(net "P12V_SSD14")
		)
		(pad "2" smd circle
			(at 0.40005 0)
			(size 0 0)
			(layers "F.Cu" "F.Mask" "F.Paste")
			(net "GND")
		)
	)
	(footprint ""
		(layer "F.Cu")
		(at 238.804958 -89.225374 180)
		(property "Reference" "R1019"
			(at 0 0 180)
			(layer "F.SilkS")
			(hide yes)
			(effects
				(font
					(size 1.27 1.27)
				)
			)
		)
		(property "Value" ""
			(at 0 0 180)
			(layer "F.Fab")
			(effects
				(font
					(size 1.27 1.27)
				)
			)
		)
		(duplicate_pad_numbers_are_jumpers no)
		(fp_line
			(start 0.7874 0.4064)
			(end -0.7874 0.4064)
			(stroke
				(width 0.1524)
				(type default)
			)
			(layer "F.SilkS")
		)
		(fp_line
			(start 0.7874 -0.4064)
			(end 0.7874 0.4064)
			(stroke
				(width 0.1524)
				(type default)
			)
			(layer "F.SilkS")
		)
		(fp_line
			(start -0.7874 0.4064)
			(end -0.7874 -0.4064)
			(stroke
				(width 0.1524)
				(type default)
			)
			(layer "F.SilkS")
		)
		(fp_line
			(start -0.7874 -0.4064)
			(end 0.7874 -0.4064)
			(stroke
				(width 0.1524)
				(type default)
			)
			(layer "F.SilkS")
		)
		(fp_line
			(start 0.67945 0.3048)
			(end 0.120396 0.3048)
			(stroke
				(width 0.1)
				(type default)
			)
			(layer "F.Fab")
		)
		(fp_line
			(start 0.67945 -0.3048)
			(end 0.67945 0.3048)
			(stroke
				(width 0.1)
				(type default)
			)
			(layer "F.Fab")
		)
		(fp_line
			(start 0.12065 -0.2794)
			(end 0.12065 -0.3048)
			(stroke
				(width 0.1)
				(type default)
			)
			(layer "F.Fab")
		)
		(fp_line
			(start 0.12065 -0.3048)
			(end 0.67945 -0.3048)
			(stroke
				(width 0.1)
				(type default)
			)
			(layer "F.Fab")
		)
		(fp_line
			(start 0.120396 0.3048)
			(end 0.120396 0.2794)
			(stroke
				(width 0.1)
				(type default)
			)
			(layer "F.Fab")
		)
		(fp_line
			(start 0.120396 0.2794)
			(end -0.12065 0.2794)
			(stroke
				(width 0.1)
				(type default)
			)
			(layer "F.Fab")
		)
		(fp_line
			(start -0.12065 0.3048)
			(end -0.67945 0.3048)
			(stroke
				(width 0.1)
				(type default)
			)
			(layer "F.Fab")
		)
		(fp_line
			(start -0.12065 0.2794)
			(end -0.12065 0.3048)
			(stroke
				(width 0.1)
				(type default)
			)
			(layer "F.Fab")
		)
		(fp_line
			(start -0.12065 -0.2794)
			(end 0.12065 -0.2794)
			(stroke
				(width 0.1)
				(type default)
			)
			(layer "F.Fab")
		)
		(fp_line
			(start -0.12065 -0.305054)
			(end -0.12065 -0.2794)
			(stroke
				(width 0.1)
				(type default)
			)
			(layer "F.Fab")
		)
		(fp_line
			(start -0.67945 0.3048)
			(end -0.67945 -0.305054)
			(stroke
				(width 0.1)
				(type default)
			)
			(layer "F.Fab")
		)
		(fp_line
			(start -0.67945 -0.305054)
			(end -0.12065 -0.305054)
			(stroke
				(width 0.1)
				(type default)
			)
			(layer "F.Fab")
		)
		(pad "1" smd circle
			(at -0.40005 0 180)
			(size 0 0)
			(layers "F.Cu" "F.Mask" "F.Paste")
			(net "GND")
		)
		(pad "2" smd circle
			(at 0.40005 0 180)
			(size 0 0)
			(layers "F.Cu" "F.Mask" "F.Paste")
			(net "PEX_USB_HUB_RREF")
		)
	)
	(footprint ""
		(layer "F.Cu")
		(at 426.32503 -14.735302 180)
		(property "Reference" "C2740"
			(at 0 0 180)
			(layer "F.SilkS")
			(hide yes)
			(effects
				(font
					(size 1.27 1.27)
				)
			)
		)
		(property "Value" ""
			(at 0 0 180)
			(layer "F.Fab")
			(effects
				(font
					(size 1.27 1.27)
				)
			)
		)
		(duplicate_pad_numbers_are_jumpers no)
		(fp_line
			(start 0.7874 0.4064)
			(end -0.7874 0.4064)
			(stroke
				(width 0.1524)
				(type default)
			)
			(layer "F.SilkS")
		)
		(fp_line
			(start 0.7874 -0.4064)
			(end 0.7874 0.4064)
			(stroke
				(width 0.1524)
				(type default)
			)
			(layer "F.SilkS")
		)
		(fp_line
			(start -0.7874 0.4064)
			(end -0.7874 -0.4064)
			(stroke
				(width 0.1524)
				(type default)
			)
			(layer "F.SilkS")
		)
		(fp_line
			(start -0.7874 -0.4064)
			(end 0.7874 -0.4064)
			(stroke
				(width 0.1524)
				(type default)
			)
			(layer "F.SilkS")
		)
		(fp_line
			(start 0.67945 0.3048)
			(end 0.120396 0.3048)
			(stroke
				(width 0.1)
				(type default)
			)
			(layer "F.Fab")
		)
		(fp_line
			(start 0.67945 -0.3048)
			(end 0.67945 0.3048)
			(stroke
				(width 0.1)
				(type default)
			)
			(layer "F.Fab")
		)
		(fp_line
			(start 0.12065 -0.2794)
			(end 0.12065 -0.3048)
			(stroke
				(width 0.1)
				(type default)
			)
			(layer "F.Fab")
		)
		(fp_line
			(start 0.12065 -0.3048)
			(end 0.67945 -0.3048)
			(stroke
				(width 0.1)
				(type default)
			)
			(layer "F.Fab")
		)
		(fp_line
			(start 0.120396 0.3048)
			(end 0.120396 0.2794)
			(stroke
				(width 0.1)
				(type default)
			)
			(layer "F.Fab")
		)
		(fp_line
			(start 0.120396 0.2794)
			(end -0.12065 0.2794)
			(stroke
				(width 0.1)
				(type default)
			)
			(layer "F.Fab")
		)
		(fp_line
			(start -0.12065 0.3048)
			(end -0.67945 0.3048)
			(stroke
				(width 0.1)
				(type default)
			)
			(layer "F.Fab")
		)
		(fp_line
			(start -0.12065 0.2794)
			(end -0.12065 0.3048)
			(stroke
				(width 0.1)
				(type default)
			)
			(layer "F.Fab")
		)
		(fp_line
			(start -0.12065 -0.2794)
			(end 0.12065 -0.2794)
			(stroke
				(width 0.1)
				(type default)
			)
			(layer "F.Fab")
		)
		(fp_line
			(start -0.12065 -0.305054)
			(end -0.12065 -0.2794)
			(stroke
				(width 0.1)
				(type default)
			)
			(layer "F.Fab")
		)
		(fp_line
			(start -0.67945 0.3048)
			(end -0.67945 -0.305054)
			(stroke
				(width 0.1)
				(type default)
			)
			(layer "F.Fab")
		)
		(fp_line
			(start -0.67945 -0.305054)
			(end -0.12065 -0.305054)
			(stroke
				(width 0.1)
				(type default)
			)
			(layer "F.Fab")
		)
		(pad "1" smd circle
			(at -0.40005 0 180)
			(size 0 0)
			(layers "F.Cu" "F.Mask" "F.Paste")
			(net "GND")
		)
		(pad "2" smd circle
			(at 0.40005 0 180)
			(size 0 0)
			(layers "F.Cu" "F.Mask" "F.Paste")
			(net "P3V3_SSD14")
		)
	)
	(footprint ""
		(layer "F.Cu")
		(at 436.95239 -115.400836)
		(property "Reference" "R6043"
			(at 0 0 0)
			(layer "F.SilkS")
			(hide yes)
			(effects
				(font
					(size 1.27 1.27)
				)
			)
		)
		(property "Value" ""
			(at 0 0 0)
			(layer "F.Fab")
			(effects
				(font
					(size 1.27 1.27)
				)
			)
		)
		(duplicate_pad_numbers_are_jumpers no)
		(fp_line
			(start -0.7874 -0.4064)
			(end 0.7874 -0.4064)
			(stroke
				(width 0.1524)
				(type default)
			)
			(layer "F.SilkS")
		)
		(fp_line
			(start -0.7874 0.4064)
			(end -0.7874 -0.4064)
			(stroke
				(width 0.1524)
				(type default)
			)
			(layer "F.SilkS")
		)
		(fp_line
			(start 0.7874 -0.4064)
			(end 0.7874 0.4064)
			(stroke
				(width 0.1524)
				(type default)
			)
			(layer "F.SilkS")
		)
		(fp_line
			(start 0.7874 0.4064)
			(end -0.7874 0.4064)
			(stroke
				(width 0.1524)
				(type default)
			)
			(layer "F.SilkS")
		)
		(fp_line
			(start -0.67945 -0.305054)
			(end -0.12065 -0.305054)
			(stroke
				(width 0.1)
				(type default)
			)
			(layer "F.Fab")
		)
		(fp_line
			(start -0.67945 0.3048)
			(end -0.67945 -0.305054)
			(stroke
				(width 0.1)
				(type default)
			)
			(layer "F.Fab")
		)
		(fp_line
			(start -0.12065 -0.305054)
			(end -0.12065 -0.2794)
			(stroke
				(width 0.1)
				(type default)
			)
			(layer "F.Fab")
		)
		(fp_line
			(start -0.12065 -0.2794)
			(end 0.12065 -0.2794)
			(stroke
				(width 0.1)
				(type default)
			)
			(layer "F.Fab")
		)
		(fp_line
			(start -0.12065 0.2794)
			(end -0.12065 0.3048)
			(stroke
				(width 0.1)
				(type default)
			)
			(layer "F.Fab")
		)
		(fp_line
			(start -0.12065 0.3048)
			(end -0.67945 0.3048)
			(stroke
				(width 0.1)
				(type default)
			)
			(layer "F.Fab")
		)
		(fp_line
			(start 0.120396 0.2794)
			(end -0.12065 0.2794)
			(stroke
				(width 0.1)
				(type default)
			)
			(layer "F.Fab")
		)
		(fp_line
			(start 0.120396 0.3048)
			(end 0.120396 0.2794)
			(stroke
				(width 0.1)
				(type default)
			)
			(layer "F.Fab")
		)
		(fp_line
			(start 0.12065 -0.3048)
			(end 0.67945 -0.3048)
			(stroke
				(width 0.1)
				(type default)
			)
			(layer "F.Fab")
		)
		(fp_line
			(start 0.12065 -0.2794)
			(end 0.12065 -0.3048)
			(stroke
				(width 0.1)
				(type default)
			)
			(layer "F.Fab")
		)
		(fp_line
			(start 0.67945 -0.3048)
			(end 0.67945 0.3048)
			(stroke
				(width 0.1)
				(type default)
			)
			(layer "F.Fab")
		)
		(fp_line
			(start 0.67945 0.3048)
			(end 0.120396 0.3048)
			(stroke
				(width 0.1)
				(type default)
			)
			(layer "F.Fab")
		)
		(pad "1" smd circle
			(at -0.40005 0)
			(size 0 0)
			(layers "F.Cu" "F.Mask" "F.Paste")
			(net "HP_NIC7_EN")
		)
		(pad "2" smd circle
			(at 0.40005 0)
			(size 0 0)
			(layers "F.Cu" "F.Mask" "F.Paste")
			(net "P3V3_NIC7_CO_EN")
		)
	)
	(footprint ""
		(layer "F.Cu")
		(at 238.775748 -36.915598 -90)
		(property "Reference" "R5565"
			(at 0 0 270)
			(layer "F.SilkS")
			(hide yes)
			(effects
				(font
					(size 1.27 1.27)
				)
			)
		)
		(property "Value" ""
			(at 0 0 270)
			(layer "F.Fab")
			(effects
				(font
					(size 1.27 1.27)
				)
			)
		)
		(duplicate_pad_numbers_are_jumpers no)
		(fp_line
			(start -0.7874 0.4064)
			(end -0.7874 -0.4064)
			(stroke
				(width 0.1524)
				(type default)
			)
			(layer "F.SilkS")
		)
		(fp_line
			(start 0.7874 0.4064)
			(end -0.7874 0.4064)
			(stroke
				(width 0.1524)
				(type default)
			)
			(layer "F.SilkS")
		)
		(fp_line
			(start -0.7874 -0.4064)
			(end 0.7874 -0.4064)
			(stroke
				(width 0.1524)
				(type default)
			)
			(layer "F.SilkS")
		)
		(fp_line
			(start 0.7874 -0.4064)
			(end 0.7874 0.4064)
			(stroke
				(width 0.1524)
				(type default)
			)
			(layer "F.SilkS")
		)
		(fp_line
			(start -0.67945 0.3048)
			(end -0.67945 -0.305054)
			(stroke
				(width 0.1)
				(type default)
			)
			(layer "F.Fab")
		)
		(fp_line
			(start -0.12065 0.3048)
			(end -0.67945 0.3048)
			(stroke
				(width 0.1)
				(type default)
			)
			(layer "F.Fab")
		)
		(fp_line
			(start 0.120396 0.3048)
			(end 0.120396 0.2794)
			(stroke
				(width 0.1)
				(type default)
			)
			(layer "F.Fab")
		)
		(fp_line
			(start 0.67945 0.3048)
			(end 0.120396 0.3048)
			(stroke
				(width 0.1)
				(type default)
			)
			(layer "F.Fab")
		)
		(fp_line
			(start -0.12065 0.2794)
			(end -0.12065 0.3048)
			(stroke
				(width 0.1)
				(type default)
			)
			(layer "F.Fab")
		)
		(fp_line
			(start 0.120396 0.2794)
			(end -0.12065 0.2794)
			(stroke
				(width 0.1)
				(type default)
			)
			(layer "F.Fab")
		)
		(fp_line
			(start -0.12065 -0.2794)
			(end 0.12065 -0.2794)
			(stroke
				(width 0.1)
				(type default)
			)
			(layer "F.Fab")
		)
		(fp_line
			(start 0.12065 -0.2794)
			(end 0.12065 -0.3048)
			(stroke
				(width 0.1)
				(type default)
			)
			(layer "F.Fab")
		)
		(fp_line
			(start 0.12065 -0.3048)
			(end 0.67945 -0.3048)
			(stroke
				(width 0.1)
				(type default)
			)
			(layer "F.Fab")
		)
		(fp_line
			(start 0.67945 -0.3048)
			(end 0.67945 0.3048)
			(stroke
				(width 0.1)
				(type default)
			)
			(layer "F.Fab")
		)
		(fp_line
			(start -0.67945 -0.305054)
			(end -0.12065 -0.305054)
			(stroke
				(width 0.1)
				(type default)
			)
			(layer "F.Fab")
		)
		(fp_line
			(start -0.12065 -0.305054)
			(end -0.12065 -0.2794)
			(stroke
				(width 0.1)
				(type default)
			)
			(layer "F.Fab")
		)
		(pad "1" smd circle
			(at -0.40005 0 270)
			(size 0 0)
			(layers "F.Cu" "F.Mask" "F.Paste")
			(net "PRSNT_SSD8_R1_N")
		)
		(pad "2" smd circle
			(at 0.40005 0 270)
			(size 0 0)
			(layers "F.Cu" "F.Mask" "F.Paste")
			(net "PRSNT_SSD8_R_N")
		)
	)
	(footprint ""
		(layer "F.Cu")
		(at 211.491322 -227.225606 -90)
		(property "Reference" "R2742"
			(at 0 0 270)
			(layer "F.SilkS")
			(hide yes)
			(effects
				(font
					(size 1.27 1.27)
				)
			)
		)
		(property "Value" ""
			(at 0 0 270)
			(layer "F.Fab")
			(effects
				(font
					(size 1.27 1.27)
				)
			)
		)
		(duplicate_pad_numbers_are_jumpers no)
		(fp_line
			(start -0.7874 0.4064)
			(end -0.7874 -0.4064)
			(stroke
				(width 0.1524)
				(type default)
			)
			(layer "F.SilkS")
		)
		(fp_line
			(start 0.7874 0.4064)
			(end -0.7874 0.4064)
			(stroke
				(width 0.1524)
				(type default)
			)
			(layer "F.SilkS")
		)
		(fp_line
			(start -0.7874 -0.4064)
			(end 0.7874 -0.4064)
			(stroke
				(width 0.1524)
				(type default)
			)
			(layer "F.SilkS")
		)
		(fp_line
			(start 0.7874 -0.4064)
			(end 0.7874 0.4064)
			(stroke
				(width 0.1524)
				(type default)
			)
			(layer "F.SilkS")
		)
		(fp_line
			(start -0.67945 0.3048)
			(end -0.67945 -0.305054)
			(stroke
				(width 0.1)
				(type default)
			)
			(layer "F.Fab")
		)
		(fp_line
			(start -0.12065 0.3048)
			(end -0.67945 0.3048)
			(stroke
				(width 0.1)
				(type default)
			)
			(layer "F.Fab")
		)
		(fp_line
			(start 0.120396 0.3048)
			(end 0.120396 0.2794)
			(stroke
				(width 0.1)
				(type default)
			)
			(layer "F.Fab")
		)
		(fp_line
			(start 0.67945 0.3048)
			(end 0.120396 0.3048)
			(stroke
				(width 0.1)
				(type default)
			)
			(layer "F.Fab")
		)
		(fp_line
			(start -0.12065 0.2794)
			(end -0.12065 0.3048)
			(stroke
				(width 0.1)
				(type default)
			)
			(layer "F.Fab")
		)
		(fp_line
			(start 0.120396 0.2794)
			(end -0.12065 0.2794)
			(stroke
				(width 0.1)
				(type default)
			)
			(layer "F.Fab")
		)
		(fp_line
			(start -0.12065 -0.2794)
			(end 0.12065 -0.2794)
			(stroke
				(width 0.1)
				(type default)
			)
			(layer "F.Fab")
		)
		(fp_line
			(start 0.12065 -0.2794)
			(end 0.12065 -0.3048)
			(stroke
				(width 0.1)
				(type default)
			)
			(layer "F.Fab")
		)
		(fp_line
			(start 0.12065 -0.3048)
			(end 0.67945 -0.3048)
			(stroke
				(width 0.1)
				(type default)
			)
			(layer "F.Fab")
		)
		(fp_line
			(start 0.67945 -0.3048)
			(end 0.67945 0.3048)
			(stroke
				(width 0.1)
				(type default)
			)
			(layer "F.Fab")
		)
		(fp_line
			(start -0.67945 -0.305054)
			(end -0.12065 -0.305054)
			(stroke
				(width 0.1)
				(type default)
			)
			(layer "F.Fab")
		)
		(fp_line
			(start -0.12065 -0.305054)
			(end -0.12065 -0.2794)
			(stroke
				(width 0.1)
				(type default)
			)
			(layer "F.Fab")
		)
		(pad "1" smd circle
			(at -0.40005 0 270)
			(size 0 0)
			(layers "F.Cu" "F.Mask" "F.Paste")
			(net "UART_MB_BIC_TX_BUF_R")
		)
		(pad "2" smd circle
			(at 0.40005 0 270)
			(size 0 0)
			(layers "F.Cu" "F.Mask" "F.Paste")
			(net "UART_MB_BIC_TX_BUF")
		)
	)
	(footprint ""
		(layer "F.Cu")
		(at 242.460018 -236.682026 90)
		(property "Reference" "R6225"
			(at 0 0 90)
			(layer "F.SilkS")
			(hide yes)
			(effects
				(font
					(size 1.27 1.27)
				)
			)
		)
		(property "Value" ""
			(at 0 0 90)
			(layer "F.Fab")
			(effects
				(font
					(size 1.27 1.27)
				)
			)
		)
		(duplicate_pad_numbers_are_jumpers no)
		(fp_line
			(start 0.7874 -0.4064)
			(end 0.7874 0.4064)
			(stroke
				(width 0.1524)
				(type default)
			)
			(layer "F.SilkS")
		)
		(fp_line
			(start -0.7874 -0.4064)
			(end 0.7874 -0.4064)
			(stroke
				(width 0.1524)
				(type default)
			)
			(layer "F.SilkS")
		)
		(fp_line
			(start 0.7874 0.4064)
			(end -0.7874 0.4064)
			(stroke
				(width 0.1524)
				(type default)
			)
			(layer "F.SilkS")
		)
		(fp_line
			(start -0.7874 0.4064)
			(end -0.7874 -0.4064)
			(stroke
				(width 0.1524)
				(type default)
			)
			(layer "F.SilkS")
		)
		(fp_line
			(start -0.12065 -0.305054)
			(end -0.12065 -0.2794)
			(stroke
				(width 0.1)
				(type default)
			)
			(layer "F.Fab")
		)
		(fp_line
			(start -0.67945 -0.305054)
			(end -0.12065 -0.305054)
			(stroke
				(width 0.1)
				(type default)
			)
			(layer "F.Fab")
		)
		(fp_line
			(start 0.67945 -0.3048)
			(end 0.67945 0.3048)
			(stroke
				(width 0.1)
				(type default)
			)
			(layer "F.Fab")
		)
		(fp_line
			(start 0.12065 -0.3048)
			(end 0.67945 -0.3048)
			(stroke
				(width 0.1)
				(type default)
			)
			(layer "F.Fab")
		)
		(fp_line
			(start 0.12065 -0.2794)
			(end 0.12065 -0.3048)
			(stroke
				(width 0.1)
				(type default)
			)
			(layer "F.Fab")
		)
		(fp_line
			(start -0.12065 -0.2794)
			(end 0.12065 -0.2794)
			(stroke
				(width 0.1)
				(type default)
			)
			(layer "F.Fab")
		)
		(fp_line
			(start 0.120396 0.2794)
			(end -0.12065 0.2794)
			(stroke
				(width 0.1)
				(type default)
			)
			(layer "F.Fab")
		)
		(fp_line
			(start -0.12065 0.2794)
			(end -0.12065 0.3048)
			(stroke
				(width 0.1)
				(type default)
			)
			(layer "F.Fab")
		)
		(fp_line
			(start 0.67945 0.3048)
			(end 0.120396 0.3048)
			(stroke
				(width 0.1)
				(type default)
			)
			(layer "F.Fab")
		)
		(fp_line
			(start 0.120396 0.3048)
			(end 0.120396 0.2794)
			(stroke
				(width 0.1)
				(type default)
			)
			(layer "F.Fab")
		)
		(fp_line
			(start -0.12065 0.3048)
			(end -0.67945 0.3048)
			(stroke
				(width 0.1)
				(type default)
			)
			(layer "F.Fab")
		)
		(fp_line
			(start -0.67945 0.3048)
			(end -0.67945 -0.305054)
			(stroke
				(width 0.1)
				(type default)
			)
			(layer "F.Fab")
		)
		(pad "1" smd circle
			(at -0.40005 0 90)
			(size 0 0)
			(layers "F.Cu" "F.Mask" "F.Paste")
			(net "P3V3_AUX")
		)
		(pad "2" smd circle
			(at 0.40005 0 90)
			(size 0 0)
			(layers "F.Cu" "F.Mask" "F.Paste")
			(net "BIC_RECOVER_IOEXP_A0")
		)
	)
	(footprint ""
		(layer "F.Cu")
		(at 302.82007 -15.649956 180)
		(property "Reference" "H121"
			(at -3.525012 -2.4257 0)
			(unlocked yes)
			(layer "B.SilkS")
			(effects
				(font
					(size 0.7874 0.5842)
					(thickness 0.1524)
				)
				(justify left mirror)
			)
		)
		(property "Value" ""
			(at 0 0 180)
			(layer "F.Fab")
			(effects
				(font
					(size 1.27 1.27)
				)
			)
		)
		(duplicate_pad_numbers_are_jumpers no)
		(pad "1" thru_hole rect
			(at 0 0 180)
			(size 4.2164 5.0038)
			(drill 2.0066
				(offset 0.099822 0)
			)
			(layers "*.Cu" "*.Mask")
			(remove_unused_layers no)
			(net "Net_8542")
			(clearance -0.8509)
			(padstack
				(mode front_inner_back)
				(layer "Inner"
					(shape circle)
					(size 4.0132 4.0132)
					(clearance -0.7493)
				)
				(layer "B.Cu"
					(shape circle)
					(size 4.0132 4.0132)
					(clearance -0.7493)
				)
			)
		)
	)
	(footprint ""
		(layer "F.Cu")
		(at 330.424028 -236.871256 -90)
		(property "Reference" "R1788"
			(at 0 0 270)
			(layer "F.SilkS")
			(hide yes)
			(effects
				(font
					(size 1.27 1.27)
				)
			)
		)
		(property "Value" ""
			(at 0 0 270)
			(layer "F.Fab")
			(effects
				(font
					(size 1.27 1.27)
				)
			)
		)
		(duplicate_pad_numbers_are_jumpers no)
		(fp_line
			(start -0.7874 0.4064)
			(end -0.7874 -0.4064)
			(stroke
				(width 0.1524)
				(type default)
			)
			(layer "F.SilkS")
		)
		(fp_line
			(start 0.7874 0.4064)
			(end -0.7874 0.4064)
			(stroke
				(width 0.1524)
				(type default)
			)
			(layer "F.SilkS")
		)
		(fp_line
			(start -0.7874 -0.4064)
			(end 0.7874 -0.4064)
			(stroke
				(width 0.1524)
				(type default)
			)
			(layer "F.SilkS")
		)
		(fp_line
			(start 0.7874 -0.4064)
			(end 0.7874 0.4064)
			(stroke
				(width 0.1524)
				(type default)
			)
			(layer "F.SilkS")
		)
		(fp_line
			(start -0.67945 0.3048)
			(end -0.67945 -0.305054)
			(stroke
				(width 0.1)
				(type default)
			)
			(layer "F.Fab")
		)
		(fp_line
			(start -0.12065 0.3048)
			(end -0.67945 0.3048)
			(stroke
				(width 0.1)
				(type default)
			)
			(layer "F.Fab")
		)
		(fp_line
			(start 0.120396 0.3048)
			(end 0.120396 0.2794)
			(stroke
				(width 0.1)
				(type default)
			)
			(layer "F.Fab")
		)
		(fp_line
			(start 0.67945 0.3048)
			(end 0.120396 0.3048)
			(stroke
				(width 0.1)
				(type default)
			)
			(layer "F.Fab")
		)
		(fp_line
			(start -0.12065 0.2794)
			(end -0.12065 0.3048)
			(stroke
				(width 0.1)
				(type default)
			)
			(layer "F.Fab")
		)
		(fp_line
			(start 0.120396 0.2794)
			(end -0.12065 0.2794)
			(stroke
				(width 0.1)
				(type default)
			)
			(layer "F.Fab")
		)
		(fp_line
			(start -0.12065 -0.2794)
			(end 0.12065 -0.2794)
			(stroke
				(width 0.1)
				(type default)
			)
			(layer "F.Fab")
		)
		(fp_line
			(start 0.12065 -0.2794)
			(end 0.12065 -0.3048)
			(stroke
				(width 0.1)
				(type default)
			)
			(layer "F.Fab")
		)
		(fp_line
			(start 0.12065 -0.3048)
			(end 0.67945 -0.3048)
			(stroke
				(width 0.1)
				(type default)
			)
			(layer "F.Fab")
		)
		(fp_line
			(start 0.67945 -0.3048)
			(end 0.67945 0.3048)
			(stroke
				(width 0.1)
				(type default)
			)
			(layer "F.Fab")
		)
		(fp_line
			(start -0.67945 -0.305054)
			(end -0.12065 -0.305054)
			(stroke
				(width 0.1)
				(type default)
			)
			(layer "F.Fab")
		)
		(fp_line
			(start -0.12065 -0.305054)
			(end -0.12065 -0.2794)
			(stroke
				(width 0.1)
				(type default)
			)
			(layer "F.Fab")
		)
		(pad "1" smd circle
			(at -0.40005 0 270)
			(size 0 0)
			(layers "F.Cu" "F.Mask" "F.Paste")
			(net "RST_MB_PERST_0_ISO_N")
		)
		(pad "2" smd circle
			(at 0.40005 0 270)
			(size 0 0)
			(layers "F.Cu" "F.Mask" "F.Paste")
			(net "RST_MB_PERST_0_ISO_R_N")
		)
	)
	(footprint ""
		(layer "F.Cu")
		(at 124.272548 -356.244906 90)
		(property "Reference" "C352"
			(at 0 0 90)
			(layer "F.SilkS")
			(hide yes)
			(effects
				(font
					(size 1.27 1.27)
				)
			)
		)
		(property "Value" ""
			(at 0 0 90)
			(layer "F.Fab")
			(effects
				(font
					(size 1.27 1.27)
				)
			)
		)
		(duplicate_pad_numbers_are_jumpers no)
		(fp_line
			(start 0.299974 -0.150114)
			(end 0.299974 0.150114)
			(stroke
				(width 0.1)
				(type default)
			)
			(layer "F.Fab")
		)
		(fp_line
			(start -0.299974 -0.150114)
			(end 0.299974 -0.150114)
			(stroke
				(width 0.1)
				(type default)
			)
			(layer "F.Fab")
		)
		(fp_line
			(start 0.299974 0.150114)
			(end -0.299974 0.150114)
			(stroke
				(width 0.1)
				(type default)
			)
			(layer "F.Fab")
		)
		(fp_line
			(start -0.299974 0.150114)
			(end -0.299974 -0.150114)
			(stroke
				(width 0.1)
				(type default)
			)
			(layer "F.Fab")
		)
		(pad "1" smd rect
			(at -0.2667 0 90)
			(size 0.3048 0.381)
			(layers "F.Cu" "F.Mask" "F.Paste")
			(net "P5E_PEX1_STN6_TX_DP<105>")
		)
		(pad "2" smd rect
			(at 0.2667 0 90)
			(size 0.3048 0.381)
			(layers "F.Cu" "F.Mask" "F.Paste")
			(net "P5E_PEX1_STN6_TX_C_DP<105>")
		)
	)
	(footprint ""
		(layer "F.Cu")
		(at 176.311052 -61.386974)
		(property "Reference" "R4490"
			(at 0 0 0)
			(layer "F.SilkS")
			(hide yes)
			(effects
				(font
					(size 1.27 1.27)
				)
			)
		)
		(property "Value" ""
			(at 0 0 0)
			(layer "F.Fab")
			(effects
				(font
					(size 1.27 1.27)
				)
			)
		)
		(duplicate_pad_numbers_are_jumpers no)
		(fp_line
			(start -0.7874 -0.4064)
			(end 0.7874 -0.4064)
			(stroke
				(width 0.1524)
				(type default)
			)
			(layer "F.SilkS")
		)
		(fp_line
			(start -0.7874 0.4064)
			(end -0.7874 -0.4064)
			(stroke
				(width 0.1524)
				(type default)
			)
			(layer "F.SilkS")
		)
		(fp_line
			(start 0.7874 -0.4064)
			(end 0.7874 0.4064)
			(stroke
				(width 0.1524)
				(type default)
			)
			(layer "F.SilkS")
		)
		(fp_line
			(start 0.7874 0.4064)
			(end -0.7874 0.4064)
			(stroke
				(width 0.1524)
				(type default)
			)
			(layer "F.SilkS")
		)
		(fp_line
			(start -0.67945 -0.305054)
			(end -0.12065 -0.305054)
			(stroke
				(width 0.1)
				(type default)
			)
			(layer "F.Fab")
		)
		(fp_line
			(start -0.67945 0.3048)
			(end -0.67945 -0.305054)
			(stroke
				(width 0.1)
				(type default)
			)
			(layer "F.Fab")
		)
		(fp_line
			(start -0.12065 -0.305054)
			(end -0.12065 -0.2794)
			(stroke
				(width 0.1)
				(type default)
			)
			(layer "F.Fab")
		)
		(fp_line
			(start -0.12065 -0.2794)
			(end 0.12065 -0.2794)
			(stroke
				(width 0.1)
				(type default)
			)
			(layer "F.Fab")
		)
		(fp_line
			(start -0.12065 0.2794)
			(end -0.12065 0.3048)
			(stroke
				(width 0.1)
				(type default)
			)
			(layer "F.Fab")
		)
		(fp_line
			(start -0.12065 0.3048)
			(end -0.67945 0.3048)
			(stroke
				(width 0.1)
				(type default)
			)
			(layer "F.Fab")
		)
		(fp_line
			(start 0.120396 0.2794)
			(end -0.12065 0.2794)
			(stroke
				(width 0.1)
				(type default)
			)
			(layer "F.Fab")
		)
		(fp_line
			(start 0.120396 0.3048)
			(end 0.120396 0.2794)
			(stroke
				(width 0.1)
				(type default)
			)
			(layer "F.Fab")
		)
		(fp_line
			(start 0.12065 -0.3048)
			(end 0.67945 -0.3048)
			(stroke
				(width 0.1)
				(type default)
			)
			(layer "F.Fab")
		)
		(fp_line
			(start 0.12065 -0.2794)
			(end 0.12065 -0.3048)
			(stroke
				(width 0.1)
				(type default)
			)
			(layer "F.Fab")
		)
		(fp_line
			(start 0.67945 -0.3048)
			(end 0.67945 0.3048)
			(stroke
				(width 0.1)
				(type default)
			)
			(layer "F.Fab")
		)
		(fp_line
			(start 0.67945 0.3048)
			(end 0.120396 0.3048)
			(stroke
				(width 0.1)
				(type default)
			)
			(layer "F.Fab")
		)
		(pad "1" smd circle
			(at -0.40005 0)
			(size 0 0)
			(layers "F.Cu" "F.Mask" "F.Paste")
			(net "PWRGD_P3V3_SSD6")
		)
		(pad "2" smd circle
			(at 0.40005 0)
			(size 0 0)
			(layers "F.Cu" "F.Mask" "F.Paste")
			(net "PWRGD_P3V3_SSD6_R")
		)
	)
	(footprint ""
		(layer "F.Cu")
		(at 105.7783 -222.706692)
		(property "Reference" "PU20"
			(at -1.340612 5.197094 90)
			(unlocked yes)
			(layer "F.SilkS")
			(effects
				(font
					(size 0.7874 0.5842)
					(thickness 0.1524)
				)
				(justify left)
			)
		)
		(property "Value" ""
			(at 0 0 0)
			(layer "F.Fab")
			(effects
				(font
					(size 1.27 1.27)
				)
			)
		)
		(duplicate_pad_numbers_are_jumpers no)
		(fp_line
			(start -1.9812 0)
			(end -2.3622 0)
			(stroke
				(width 0.1524)
				(type default)
			)
			(layer "F.SilkS")
		)
		(fp_line
			(start -1.549908 -2.050034)
			(end -1.549908 -1.9812)
			(stroke
				(width 0.1524)
				(type default)
			)
			(layer "F.SilkS")
		)
		(fp_line
			(start -1.549908 1.9812)
			(end -1.549908 2.050034)
			(stroke
				(width 0.1524)
				(type default)
			)
			(layer "F.SilkS")
		)
		(fp_line
			(start -1.549908 2.050034)
			(end -0.5842 2.050034)
			(stroke
				(width 0.1524)
				(type default)
			)
			(layer "F.SilkS")
		)
		(fp_line
			(start -0.5842 -2.050034)
			(end -1.549908 -2.050034)
			(stroke
				(width 0.1524)
				(type default)
			)
			(layer "F.SilkS")
		)
		(fp_line
			(start -0.3048 2.4638)
			(end -0.3048 3.2258)
			(stroke
				(width 0.1524)
				(type default)
			)
			(layer "F.SilkS")
		)
		(fp_line
			(start 0 2.050034)
			(end 1.549908 2.050034)
			(stroke
				(width 0.1524)
				(type default)
			)
			(layer "F.SilkS")
		)
		(fp_line
			(start 0.3048 -2.4638)
			(end 0.3048 -3.2258)
			(stroke
				(width 0.1524)
				(type default)
			)
			(layer "F.SilkS")
		)
		(fp_line
			(start 1.549908 -2.050034)
			(end 0.5842 -2.050034)
			(stroke
				(width 0.1524)
				(type default)
			)
			(layer "F.SilkS")
		)
		(fp_line
			(start 1.549908 -1.9812)
			(end 1.549908 -2.050034)
			(stroke
				(width 0.1524)
				(type default)
			)
			(layer "F.SilkS")
		)
		(fp_line
			(start 1.549908 2.050034)
			(end 1.549908 1.9304)
			(stroke
				(width 0.1524)
				(type default)
			)
			(layer "F.SilkS")
		)
		(fp_poly
			(pts
				(xy -2.9464 -2.208022) (xy -2.9464 -1.192022) (xy -1.9304 -1.700022)
			)
			(stroke
				(width 0)
				(type default)
			)
			(fill yes)
			(layer "F.SilkS")
		)
		(fp_line
			(start -1.9812 0)
			(end -2.3622 0)
			(stroke
				(width 0.1)
				(type default)
			)
			(layer "F.Fab")
		)
		(fp_line
			(start -1.549908 -2.050034)
			(end -1.549908 2.050034)
			(stroke
				(width 0.1)
				(type default)
			)
			(layer "F.Fab")
		)
		(fp_line
			(start -1.549908 2.050034)
			(end 1.549908 2.050034)
			(stroke
				(width 0.1)
				(type default)
			)
			(layer "F.Fab")
		)
		(fp_line
			(start -0.3048 2.4638)
			(end -0.3048 3.2258)
			(stroke
				(width 0.1)
				(type default)
			)
			(layer "F.Fab")
		)
		(fp_line
			(start 0.3048 -2.4638)
			(end 0.3048 -3.2258)
			(stroke
				(width 0.1)
				(type default)
			)
			(layer "F.Fab")
		)
		(fp_line
			(start 1.549908 -2.050034)
			(end -1.549908 -2.050034)
			(stroke
				(width 0.1)
				(type default)
			)
			(layer "F.Fab")
		)
		(fp_line
			(start 1.549908 2.050034)
			(end 1.549908 -2.050034)
			(stroke
				(width 0.1)
				(type default)
			)
			(layer "F.Fab")
		)
		(fp_poly
			(pts
				(xy -2.9464 -2.208022) (xy -2.9464 -1.192022) (xy -1.9304 -1.700022)
			)
			(stroke
				(width 0)
				(type default)
			)
			(fill yes)
			(layer "F.Fab")
		)
		(fp_text user "9"
			(at -2.338832 2.0574 270)
			(unlocked yes)
			(layer "F.SilkS")
			(effects
				(font
					(size 0.635 0.4064)
					(thickness 0.1524)
				)
			)
		)
		(fp_text user "19"
			(at 1.89865 -2.616708 270)
			(unlocked yes)
			(layer "F.SilkS")
			(effects
				(font
					(size 0.635 0.4064)
					(thickness 0.1524)
				)
			)
		)
		(fp_text user "11_18"
			(at 2.512568 0.9906 270)
			(unlocked yes)
			(layer "F.SilkS")
			(effects
				(font
					(size 0.635 0.4064)
					(thickness 0.1524)
				)
			)
		)
		(fp_text user "9"
			(at -2.338832 2.0574 270)
			(unlocked yes)
			(layer "F.Fab")
			(effects
				(font
					(size 0.635 0.4064)
					(thickness 0.1524)
				)
			)
		)
		(fp_text user "19"
			(at 2.410968 -2.159 270)
			(unlocked yes)
			(layer "F.Fab")
			(effects
				(font
					(size 0.635 0.4064)
					(thickness 0.1524)
				)
			)
		)
		(fp_text user "11_18"
			(at 2.512568 0.9906 270)
			(unlocked yes)
			(layer "F.Fab")
			(effects
				(font
					(size 0.635 0.4064)
					(thickness 0.1524)
				)
			)
		)
		(pad "1" smd rect
			(at -1.35001 -1.700022 90)
			(size 0.3048 0.9144)
			(layers "F.Cu" "F.Mask" "F.Paste")
			(net "SW_P1V8_PEX_BT")
		)
		(pad "2" smd rect
			(at -1.400048 -1.199896 90)
			(size 0.1778 0.8128)
			(layers "F.Cu" "F.Mask" "F.Paste")
			(net "GND")
		)
		(pad "3" smd rect
			(at -1.400048 -0.8001 90)
			(size 0.1778 0.8128)
			(layers "F.Cu" "F.Mask" "F.Paste")
			(net "P1V8_PEX_CS")
		)
		(pad "4" smd rect
			(at -1.400048 -0.40005 90)
			(size 0.1778 0.8128)
			(layers "F.Cu" "F.Mask" "F.Paste")
			(net "GND")
		)
		(pad "5" smd rect
			(at -1.400048 0 90)
			(size 0.1778 0.8128)
			(layers "F.Cu" "F.Mask" "F.Paste")
			(net "P1V8_PEX_REF")
		)
		(pad "6" smd rect
			(at -1.400048 0.40005 90)
			(size 0.1778 0.8128)
			(layers "F.Cu" "F.Mask" "F.Paste")
			(net "GND")
		)
		(pad "7" smd rect
			(at -1.400048 0.8001 90)
			(size 0.1778 0.8128)
			(layers "F.Cu" "F.Mask" "F.Paste")
			(net "P1V8_PEX_FB")
		)
		(pad "8" smd rect
			(at -1.400048 1.199896 90)
			(size 0.1778 0.8128)
			(layers "F.Cu" "F.Mask" "F.Paste")
			(net "P1V8_PEX_EN")
		)
		(pad "9" smd rect
			(at -1.400048 1.700022 90)
			(size 0.3048 0.8128)
			(layers "F.Cu" "F.Mask" "F.Paste")
			(net "PWRGD_P1V8_PEX")
		)
		(pad "10" smd rect
			(at -0.299974 1.299972)
			(size 0.3048 2.0066)
			(layers "F.Cu" "F.Mask" "F.Paste")
			(net "SW_P12V_P1V8_PEX_FLT")
		)
		(pad "11_18" smd circle
			(at 1.175004 0.275082)
			(size 0 0)
			(layers "F.Cu" "F.Mask" "F.Paste")
			(net "GND")
		)
		(pad "19" smd rect
			(at 1.400048 -1.700022 270)
			(size 0.3048 0.8128)
			(layers "F.Cu" "F.Mask" "F.Paste")
			(net "P1V8_PEX_VCC")
		)
		(pad "20" smd rect
			(at 0.299974 -1.299972)
			(size 0.3048 2.0066)
			(layers "F.Cu" "F.Mask" "F.Paste")
			(net "SW_P1V8_PEX_PH")
		)
		(pad "21" smd rect
			(at -0.299974 -1.299972)
			(size 0.3048 2.0066)
			(layers "F.Cu" "F.Mask" "F.Paste")
			(net "SW_P12V_P1V8_PEX_FLT")
		)
	)
	(footprint ""
		(layer "F.Cu")
		(at 197.702932 -414.452054 90)
		(property "Reference" "R6781"
			(at 0 0 90)
			(layer "F.SilkS")
			(hide yes)
			(effects
				(font
					(size 1.27 1.27)
				)
			)
		)
		(property "Value" ""
			(at 0 0 90)
			(layer "F.Fab")
			(effects
				(font
					(size 1.27 1.27)
				)
			)
		)
		(duplicate_pad_numbers_are_jumpers no)
		(fp_line
			(start 0.7874 -0.4064)
			(end 0.7874 0.4064)
			(stroke
				(width 0.1524)
				(type default)
			)
			(layer "F.SilkS")
		)
		(fp_line
			(start -0.7874 -0.4064)
			(end 0.7874 -0.4064)
			(stroke
				(width 0.1524)
				(type default)
			)
			(layer "F.SilkS")
		)
		(fp_line
			(start 0.7874 0.4064)
			(end -0.7874 0.4064)
			(stroke
				(width 0.1524)
				(type default)
			)
			(layer "F.SilkS")
		)
		(fp_line
			(start -0.7874 0.4064)
			(end -0.7874 -0.4064)
			(stroke
				(width 0.1524)
				(type default)
			)
			(layer "F.SilkS")
		)
		(fp_line
			(start -0.12065 -0.305054)
			(end -0.12065 -0.2794)
			(stroke
				(width 0.1)
				(type default)
			)
			(layer "F.Fab")
		)
		(fp_line
			(start -0.67945 -0.305054)
			(end -0.12065 -0.305054)
			(stroke
				(width 0.1)
				(type default)
			)
			(layer "F.Fab")
		)
		(fp_line
			(start 0.67945 -0.3048)
			(end 0.67945 0.3048)
			(stroke
				(width 0.1)
				(type default)
			)
			(layer "F.Fab")
		)
		(fp_line
			(start 0.12065 -0.3048)
			(end 0.67945 -0.3048)
			(stroke
				(width 0.1)
				(type default)
			)
			(layer "F.Fab")
		)
		(fp_line
			(start 0.12065 -0.2794)
			(end 0.12065 -0.3048)
			(stroke
				(width 0.1)
				(type default)
			)
			(layer "F.Fab")
		)
		(fp_line
			(start -0.12065 -0.2794)
			(end 0.12065 -0.2794)
			(stroke
				(width 0.1)
				(type default)
			)
			(layer "F.Fab")
		)
		(fp_line
			(start 0.120396 0.2794)
			(end -0.12065 0.2794)
			(stroke
				(width 0.1)
				(type default)
			)
			(layer "F.Fab")
		)
		(fp_line
			(start -0.12065 0.2794)
			(end -0.12065 0.3048)
			(stroke
				(width 0.1)
				(type default)
			)
			(layer "F.Fab")
		)
		(fp_line
			(start 0.67945 0.3048)
			(end 0.120396 0.3048)
			(stroke
				(width 0.1)
				(type default)
			)
			(layer "F.Fab")
		)
		(fp_line
			(start 0.120396 0.3048)
			(end 0.120396 0.2794)
			(stroke
				(width 0.1)
				(type default)
			)
			(layer "F.Fab")
		)
		(fp_line
			(start -0.12065 0.3048)
			(end -0.67945 0.3048)
			(stroke
				(width 0.1)
				(type default)
			)
			(layer "F.Fab")
		)
		(fp_line
			(start -0.67945 0.3048)
			(end -0.67945 -0.305054)
			(stroke
				(width 0.1)
				(type default)
			)
			(layer "F.Fab")
		)
		(pad "1" smd circle
			(at -0.40005 0 90)
			(size 0 0)
			(layers "F.Cu" "F.Mask" "F.Paste")
			(net "P3V3_AUX")
		)
		(pad "2" smd circle
			(at 0.40005 0 90)
			(size 0 0)
			(layers "F.Cu" "F.Mask" "F.Paste")
			(net "UV_P2V5_COMP")
		)
	)
	(footprint ""
		(layer "F.Cu")
		(at 118.969028 -343.952322 90)
		(property "Reference" "C345"
			(at 0 0 90)
			(layer "F.SilkS")
			(hide yes)
			(effects
				(font
					(size 1.27 1.27)
				)
			)
		)
		(property "Value" ""
			(at 0 0 90)
			(layer "F.Fab")
			(effects
				(font
					(size 1.27 1.27)
				)
			)
		)
		(duplicate_pad_numbers_are_jumpers no)
		(fp_line
			(start 0.299974 -0.150114)
			(end 0.299974 0.150114)
			(stroke
				(width 0.1)
				(type default)
			)
			(layer "F.Fab")
		)
		(fp_line
			(start -0.299974 -0.150114)
			(end 0.299974 -0.150114)
			(stroke
				(width 0.1)
				(type default)
			)
			(layer "F.Fab")
		)
		(fp_line
			(start 0.299974 0.150114)
			(end -0.299974 0.150114)
			(stroke
				(width 0.1)
				(type default)
			)
			(layer "F.Fab")
		)
		(fp_line
			(start -0.299974 0.150114)
			(end -0.299974 -0.150114)
			(stroke
				(width 0.1)
				(type default)
			)
			(layer "F.Fab")
		)
		(pad "1" smd rect
			(at -0.2667 0 90)
			(size 0.3048 0.381)
			(layers "F.Cu" "F.Mask" "F.Paste")
			(net "P5E_PEX1_STN6_TX_DN<109>")
		)
		(pad "2" smd rect
			(at 0.2667 0 90)
			(size 0.3048 0.381)
			(layers "F.Cu" "F.Mask" "F.Paste")
			(net "P5E_PEX1_STN6_TX_C_DN<109>")
		)
	)
	(footprint ""
		(layer "F.Cu")
		(at 103.167942 -114.833654 90)
		(property "Reference" "PR6867"
			(at 0 0 90)
			(layer "F.SilkS")
			(hide yes)
			(effects
				(font
					(size 1.27 1.27)
				)
			)
		)
		(property "Value" ""
			(at 0 0 90)
			(layer "F.Fab")
			(effects
				(font
					(size 1.27 1.27)
				)
			)
		)
		(duplicate_pad_numbers_are_jumpers no)
		(fp_line
			(start 1.2954 -0.5842)
			(end 1.2954 0.5842)
			(stroke
				(width 0.1524)
				(type default)
			)
			(layer "F.SilkS")
		)
		(fp_line
			(start -1.2954 -0.5842)
			(end 1.2954 -0.5842)
			(stroke
				(width 0.1524)
				(type default)
			)
			(layer "F.SilkS")
		)
		(fp_line
			(start 1.2954 0.5842)
			(end -1.2954 0.5842)
			(stroke
				(width 0.1524)
				(type default)
			)
			(layer "F.SilkS")
		)
		(fp_line
			(start -1.2954 0.5842)
			(end -1.2954 -0.5842)
			(stroke
				(width 0.1524)
				(type default)
			)
			(layer "F.SilkS")
		)
		(fp_line
			(start 0.8636 -0.4572)
			(end 0.8636 -0.406654)
			(stroke
				(width 0.1)
				(type default)
			)
			(layer "F.Fab")
		)
		(fp_line
			(start -0.8636 -0.4572)
			(end 0.8636 -0.4572)
			(stroke
				(width 0.1)
				(type default)
			)
			(layer "F.Fab")
		)
		(fp_line
			(start 1.1938 -0.406654)
			(end 1.1938 0.4064)
			(stroke
				(width 0.1)
				(type default)
			)
			(layer "F.Fab")
		)
		(fp_line
			(start 0.8636 -0.406654)
			(end 1.1938 -0.406654)
			(stroke
				(width 0.1)
				(type default)
			)
			(layer "F.Fab")
		)
		(fp_line
			(start -0.8636 -0.406654)
			(end -0.8636 -0.4572)
			(stroke
				(width 0.1)
				(type default)
			)
			(layer "F.Fab")
		)
		(fp_line
			(start -1.1938 -0.406654)
			(end -0.8636 -0.406654)
			(stroke
				(width 0.1)
				(type default)
			)
			(layer "F.Fab")
		)
		(fp_line
			(start 1.1938 0.4064)
			(end 0.8636 0.4064)
			(stroke
				(width 0.1)
				(type default)
			)
			(layer "F.Fab")
		)
		(fp_line
			(start 0.8636 0.4064)
			(end 0.8636 0.4572)
			(stroke
				(width 0.1)
				(type default)
			)
			(layer "F.Fab")
		)
		(fp_line
			(start -0.8636 0.4064)
			(end -1.1938 0.4064)
			(stroke
				(width 0.1)
				(type default)
			)
			(layer "F.Fab")
		)
		(fp_line
			(start -1.1938 0.4064)
			(end -1.1938 -0.406654)
			(stroke
				(width 0.1)
				(type default)
			)
			(layer "F.Fab")
		)
		(fp_line
			(start -0.8636 0.4318)
			(end -0.8636 0.4064)
			(stroke
				(width 0.1)
				(type default)
			)
			(layer "F.Fab")
		)
		(fp_line
			(start 0.8636 0.4572)
			(end -0.8636 0.4572)
			(stroke
				(width 0.1)
				(type default)
			)
			(layer "F.Fab")
		)
		(fp_line
			(start -0.8636 0.4572)
			(end -0.8636 0.4318)
			(stroke
				(width 0.1)
				(type default)
			)
			(layer "F.Fab")
		)
		(pad "1" smd rect
			(at -0.7366 0)
			(size 0.7112 0.8128)
			(layers "F.Cu" "F.Mask" "F.Paste")
			(net "P12V_NIC1_CO_AVIN_PD")
		)
		(pad "2" smd rect
			(at 0.7366 0)
			(size 0.7112 0.8128)
			(layers "F.Cu" "F.Mask" "F.Paste")
			(net "P12V_AUX")
		)
	)
	(footprint ""
		(layer "F.Cu")
		(at 109.136942 -116.230654 90)
		(property "Reference" "R5831"
			(at 0 0 90)
			(layer "F.SilkS")
			(hide yes)
			(effects
				(font
					(size 1.27 1.27)
				)
			)
		)
		(property "Value" ""
			(at 0 0 90)
			(layer "F.Fab")
			(effects
				(font
					(size 1.27 1.27)
				)
			)
		)
		(duplicate_pad_numbers_are_jumpers no)
		(fp_line
			(start 0.7874 -0.4064)
			(end 0.7874 0.4064)
			(stroke
				(width 0.1524)
				(type default)
			)
			(layer "F.SilkS")
		)
		(fp_line
			(start -0.7874 -0.4064)
			(end 0.7874 -0.4064)
			(stroke
				(width 0.1524)
				(type default)
			)
			(layer "F.SilkS")
		)
		(fp_line
			(start 0.7874 0.4064)
			(end -0.7874 0.4064)
			(stroke
				(width 0.1524)
				(type default)
			)
			(layer "F.SilkS")
		)
		(fp_line
			(start -0.7874 0.4064)
			(end -0.7874 -0.4064)
			(stroke
				(width 0.1524)
				(type default)
			)
			(layer "F.SilkS")
		)
		(fp_line
			(start -0.12065 -0.305054)
			(end -0.12065 -0.2794)
			(stroke
				(width 0.1)
				(type default)
			)
			(layer "F.Fab")
		)
		(fp_line
			(start -0.67945 -0.305054)
			(end -0.12065 -0.305054)
			(stroke
				(width 0.1)
				(type default)
			)
			(layer "F.Fab")
		)
		(fp_line
			(start 0.67945 -0.3048)
			(end 0.67945 0.3048)
			(stroke
				(width 0.1)
				(type default)
			)
			(layer "F.Fab")
		)
		(fp_line
			(start 0.12065 -0.3048)
			(end 0.67945 -0.3048)
			(stroke
				(width 0.1)
				(type default)
			)
			(layer "F.Fab")
		)
		(fp_line
			(start 0.12065 -0.2794)
			(end 0.12065 -0.3048)
			(stroke
				(width 0.1)
				(type default)
			)
			(layer "F.Fab")
		)
		(fp_line
			(start -0.12065 -0.2794)
			(end 0.12065 -0.2794)
			(stroke
				(width 0.1)
				(type default)
			)
			(layer "F.Fab")
		)
		(fp_line
			(start 0.120396 0.2794)
			(end -0.12065 0.2794)
			(stroke
				(width 0.1)
				(type default)
			)
			(layer "F.Fab")
		)
		(fp_line
			(start -0.12065 0.2794)
			(end -0.12065 0.3048)
			(stroke
				(width 0.1)
				(type default)
			)
			(layer "F.Fab")
		)
		(fp_line
			(start 0.67945 0.3048)
			(end 0.120396 0.3048)
			(stroke
				(width 0.1)
				(type default)
			)
			(layer "F.Fab")
		)
		(fp_line
			(start 0.120396 0.3048)
			(end 0.120396 0.2794)
			(stroke
				(width 0.1)
				(type default)
			)
			(layer "F.Fab")
		)
		(fp_line
			(start -0.12065 0.3048)
			(end -0.67945 0.3048)
			(stroke
				(width 0.1)
				(type default)
			)
			(layer "F.Fab")
		)
		(fp_line
			(start -0.67945 0.3048)
			(end -0.67945 -0.305054)
			(stroke
				(width 0.1)
				(type default)
			)
			(layer "F.Fab")
		)
		(pad "1" smd circle
			(at -0.40005 0 90)
			(size 0 0)
			(layers "F.Cu" "F.Mask" "F.Paste")
			(net "PWRGD_P12V_NIC1_CO")
		)
		(pad "2" smd circle
			(at 0.40005 0 90)
			(size 0 0)
			(layers "F.Cu" "F.Mask" "F.Paste")
			(net "PWRGD_P12V_NIC1_R")
		)
	)
	(footprint ""
		(layer "F.Cu")
		(at 39.280592 -135.815324)
		(property "Reference" "C33"
			(at 0 0 0)
			(layer "F.SilkS")
			(hide yes)
			(effects
				(font
					(size 1.27 1.27)
				)
			)
		)
		(property "Value" ""
			(at 0 0 0)
			(layer "F.Fab")
			(effects
				(font
					(size 1.27 1.27)
				)
			)
		)
		(duplicate_pad_numbers_are_jumpers no)
		(fp_line
			(start -0.299974 -0.150114)
			(end 0.299974 -0.150114)
			(stroke
				(width 0.1)
				(type default)
			)
			(layer "F.Fab")
		)
		(fp_line
			(start -0.299974 0.150114)
			(end -0.299974 -0.150114)
			(stroke
				(width 0.1)
				(type default)
			)
			(layer "F.Fab")
		)
		(fp_line
			(start 0.299974 -0.150114)
			(end 0.299974 0.150114)
			(stroke
				(width 0.1)
				(type default)
			)
			(layer "F.Fab")
		)
		(fp_line
			(start 0.299974 0.150114)
			(end -0.299974 0.150114)
			(stroke
				(width 0.1)
				(type default)
			)
			(layer "F.Fab")
		)
		(pad "1" smd rect
			(at -0.2667 0)
			(size 0.3048 0.381)
			(layers "F.Cu" "F.Mask" "F.Paste")
			(net "P5E_PEX0_STN1_TX_DN<31>")
		)
		(pad "2" smd rect
			(at 0.2667 0)
			(size 0.3048 0.381)
			(layers "F.Cu" "F.Mask" "F.Paste")
			(net "P5E_PEX0_STN1_TX_C_DN<31>")
		)
	)
	(footprint ""
		(layer "F.Cu")
		(at 393.8397 -343.952322 90)
		(property "Reference" "C757"
			(at 0 0 90)
			(layer "F.SilkS")
			(hide yes)
			(effects
				(font
					(size 1.27 1.27)
				)
			)
		)
		(property "Value" ""
			(at 0 0 90)
			(layer "F.Fab")
			(effects
				(font
					(size 1.27 1.27)
				)
			)
		)
		(duplicate_pad_numbers_are_jumpers no)
		(fp_line
			(start 0.299974 -0.150114)
			(end 0.299974 0.150114)
			(stroke
				(width 0.1)
				(type default)
			)
			(layer "F.Fab")
		)
		(fp_line
			(start -0.299974 -0.150114)
			(end 0.299974 -0.150114)
			(stroke
				(width 0.1)
				(type default)
			)
			(layer "F.Fab")
		)
		(fp_line
			(start 0.299974 0.150114)
			(end -0.299974 0.150114)
			(stroke
				(width 0.1)
				(type default)
			)
			(layer "F.Fab")
		)
		(fp_line
			(start -0.299974 0.150114)
			(end -0.299974 -0.150114)
			(stroke
				(width 0.1)
				(type default)
			)
			(layer "F.Fab")
		)
		(pad "1" smd rect
			(at -0.2667 0 90)
			(size 0.3048 0.381)
			(layers "F.Cu" "F.Mask" "F.Paste")
			(net "P5E_PEX3_STN5_TX_DN<82>")
		)
		(pad "2" smd rect
			(at 0.2667 0 90)
			(size 0.3048 0.381)
			(layers "F.Cu" "F.Mask" "F.Paste")
			(net "P5E_PEX3_STN5_TX_C_DN<82>")
		)
	)
	(footprint ""
		(layer "F.Cu")
		(at 69.83984 -70.52437 90)
		(property "Reference" "PC381"
			(at 0 0 90)
			(layer "F.SilkS")
			(hide yes)
			(effects
				(font
					(size 1.27 1.27)
				)
			)
		)
		(property "Value" ""
			(at 0 0 90)
			(layer "F.Fab")
			(effects
				(font
					(size 1.27 1.27)
				)
			)
		)
		(duplicate_pad_numbers_are_jumpers no)
		(fp_line
			(start 1.524 -0.762)
			(end 1.524 0.762)
			(stroke
				(width 0.1524)
				(type default)
			)
			(layer "F.SilkS")
		)
		(fp_line
			(start -1.524 -0.762)
			(end 1.524 -0.762)
			(stroke
				(width 0.1524)
				(type default)
			)
			(layer "F.SilkS")
		)
		(fp_line
			(start 1.524 0.762)
			(end -1.524 0.762)
			(stroke
				(width 0.1524)
				(type default)
			)
			(layer "F.SilkS")
		)
		(fp_line
			(start -1.524 0.762)
			(end -1.524 -0.762)
			(stroke
				(width 0.1524)
				(type default)
			)
			(layer "F.SilkS")
		)
		(fp_line
			(start 1.1049 -0.724916)
			(end -1.1049 -0.724916)
			(stroke
				(width 0.1)
				(type default)
			)
			(layer "F.Fab")
		)
		(fp_line
			(start -1.1049 -0.724916)
			(end -1.1049 0.724916)
			(stroke
				(width 0.1)
				(type default)
			)
			(layer "F.Fab")
		)
		(fp_line
			(start 1.1049 0.724916)
			(end 1.1049 -0.724916)
			(stroke
				(width 0.1)
				(type default)
			)
			(layer "F.Fab")
		)
		(fp_line
			(start -1.1049 0.724916)
			(end 1.1049 0.724916)
			(stroke
				(width 0.1)
				(type default)
			)
			(layer "F.Fab")
		)
		(pad "1" smd rect
			(at -0.889 0 270)
			(size 1.016 1.27)
			(layers "F.Cu" "F.Mask" "F.Paste")
			(net "P12V_SSD2_R")
		)
		(pad "2" smd rect
			(at 0.889 0 270)
			(size 1.016 1.27)
			(layers "F.Cu" "F.Mask" "F.Paste")
			(net "GND")
		)
	)
	(footprint ""
		(layer "F.Cu")
		(at 437.949848 -320.900044)
		(property "Reference" "H93"
			(at -7.113016 -7.203948 0)
			(unlocked yes)
			(layer "F.SilkS")
			(effects
				(font
					(size 0.7874 0.5842)
					(thickness 0.1524)
				)
				(justify left)
			)
		)
		(property "Value" ""
			(at 0 0 0)
			(layer "F.Fab")
			(effects
				(font
					(size 1.27 1.27)
				)
			)
		)
		(duplicate_pad_numbers_are_jumpers no)
		(fp_arc
			(start -7.999222 0.106172)
			(mid -0.053035 -7.999859)
			(end 7.999984 0)
			(stroke
				(width 0.1524)
				(type default)
			)
			(layer "F.SilkS")
		)
		(fp_arc
			(start 0.757174 7.963662)
			(mid -2.506424 7.596956)
			(end -5.347716 5.94995)
			(stroke
				(width 0.1524)
				(type default)
			)
			(layer "F.SilkS")
		)
		(fp_arc
			(start 7.999984 0)
			(mid 6.349365 4.866218)
			(end 2.079244 7.724648)
			(stroke
				(width 0.1524)
				(type default)
			)
			(layer "F.SilkS")
		)
		(fp_arc
			(start -7.997698 0.186436)
			(mid -0.093172 -7.999437)
			(end 7.999984 0)
			(stroke
				(width 0.1524)
				(type default)
			)
			(layer "B.SilkS")
		)
		(fp_arc
			(start 7.999984 0)
			(mid 3.365899 7.257353)
			(end -5.16763 6.106922)
			(stroke
				(width 0.1524)
				(type default)
			)
			(layer "B.SilkS")
		)
		(fp_circle
			(center 0 0)
			(end 7.999984 0)
			(stroke
				(width 0.1)
				(type default)
			)
			(fill no)
			(layer "B.Fab")
		)
		(fp_circle
			(center 0 0)
			(end 7.999984 0)
			(stroke
				(width 0.1)
				(type default)
			)
			(fill no)
			(layer "F.Fab")
		)
		(pad "" np_thru_hole circle
			(at 0 0)
			(size 4.5212 4.5212)
			(drill 4.5212)
			(layers "*.Cu" "*.Mask")
			(clearance 0.381)
			(thermal_gap 0.381)
		)
		(pad "2" thru_hole circle
			(at 3.6322 0)
			(size 0.762 0.762)
			(drill 0.5588)
			(layers "*.Cu" "*.Mask")
			(remove_unused_layers no)
			(net "GND")
			(clearance 0.1524)
			(thermal_gap 0.1524)
		)
		(pad "3" thru_hole circle
			(at 2.568448 -2.568448)
			(size 0.762 0.762)
			(drill 0.5588)
			(layers "*.Cu" "*.Mask")
			(remove_unused_layers no)
			(net "GND")
			(clearance 0.1524)
			(thermal_gap 0.1524)
		)
		(pad "4" thru_hole circle
			(at 0 -3.6322)
			(size 0.762 0.762)
			(drill 0.5588)
			(layers "*.Cu" "*.Mask")
			(remove_unused_layers no)
			(net "GND")
			(clearance 0.1524)
			(thermal_gap 0.1524)
		)
		(pad "5" thru_hole circle
			(at -2.568448 -2.568448)
			(size 0.762 0.762)
			(drill 0.5588)
			(layers "*.Cu" "*.Mask")
			(remove_unused_layers no)
			(net "GND")
			(clearance 0.1524)
			(thermal_gap 0.1524)
		)
		(pad "6" thru_hole circle
			(at -3.6322 0)
			(size 0.762 0.762)
			(drill 0.5588)
			(layers "*.Cu" "*.Mask")
			(remove_unused_layers no)
			(net "GND")
			(clearance 0.1524)
			(thermal_gap 0.1524)
		)
		(pad "7" thru_hole circle
			(at -2.568448 2.568448)
			(size 0.762 0.762)
			(drill 0.5588)
			(layers "*.Cu" "*.Mask")
			(remove_unused_layers no)
			(net "GND")
			(clearance 0.1524)
			(thermal_gap 0.1524)
		)
		(pad "8" thru_hole circle
			(at 0 3.6322)
			(size 0.762 0.762)
			(drill 0.5588)
			(layers "*.Cu" "*.Mask")
			(remove_unused_layers no)
			(net "GND")
			(clearance 0.1524)
			(thermal_gap 0.1524)
		)
		(pad "9" thru_hole circle
			(at 2.568448 2.568448)
			(size 0.762 0.762)
			(drill 0.5588)
			(layers "*.Cu" "*.Mask")
			(remove_unused_layers no)
			(net "GND")
			(clearance 0.1524)
			(thermal_gap 0.1524)
		)
		(zone
			(layer "F.Cu")
			(hatch none 0.5)
			(connect_pads
				(clearance 0)
			)
			(min_thickness 0.25)
			(keepout
				(tracks not_allowed)
				(vias allowed)
				(pads allowed)
				(copperpour not_allowed)
				(footprints allowed)
			)
			(placement
				(enabled no)
				(sheetname "")
			)
			(fill
				(thermal_gap 0.5)
				(thermal_bridge_width 0.5)
				(island_removal_mode 0)
			)
			(polygon
				(pts
					(arc
						(start 437.949848 -312.90006)
						(mid 429.949864 -320.900044)
						(end 437.949848 -328.900028)
					)
					(arc
						(start 437.949848 -325.649844)
						(mid 433.200048 -320.900044)
						(end 437.949848 -316.150244)
					)
				)
			)
		)
		(zone
			(layer "F.Cu")
			(hatch none 0.5)
			(connect_pads
				(clearance 0)
			)
			(min_thickness 0.25)
			(keepout
				(tracks not_allowed)
				(vias allowed)
				(pads allowed)
				(copperpour not_allowed)
				(footprints allowed)
			)
			(placement
				(enabled no)
				(sheetname "")
			)
			(fill
				(thermal_gap 0.5)
				(thermal_bridge_width 0.5)
				(island_removal_mode 0)
			)
			(polygon
				(pts
					(arc
						(start 437.949848 -312.90006)
						(mid 445.949832 -320.900044)
						(end 437.949848 -328.900028)
					)
					(arc
						(start 437.949848 -325.649844)
						(mid 442.699648 -320.900044)
						(end 437.949848 -316.150244)
					)
				)
			)
		)
		(zone
			(layers "F.Cu" "B.Cu" "In1.Cu" "In2.Cu" "In3.Cu" "In4.Cu" "In5.Cu" "In6.Cu"
				"In7.Cu" "In8.Cu" "In9.Cu" "In10.Cu" "In11.Cu" "In12.Cu" "In13.Cu" "In14.Cu"
				"In15.Cu" "In16.Cu"
			)
			(hatch none 0.5)
			(connect_pads
				(clearance 0)
			)
			(min_thickness 0.25)
			(keepout
				(tracks not_allowed)
				(vias allowed)
				(pads allowed)
				(copperpour not_allowed)
				(footprints allowed)
			)
			(placement
				(enabled no)
				(sheetname "")
			)
			(fill
				(thermal_gap 0.5)
				(thermal_bridge_width 0.5)
				(island_removal_mode 0)
			)
			(polygon
				(pts
					(arc
						(start 440.715908 -320.900044)
						(mid 435.183788 -320.900044)
						(end 440.715908 -320.900044)
					)
				)
			)
		)
		(zone
			(layer "B.Cu")
			(hatch none 0.5)
			(connect_pads
				(clearance 0)
			)
			(min_thickness 0.25)
			(keepout
				(tracks not_allowed)
				(vias allowed)
				(pads allowed)
				(copperpour not_allowed)
				(footprints allowed)
			)
			(placement
				(enabled no)
				(sheetname "")
			)
			(fill
				(thermal_gap 0.5)
				(thermal_bridge_width 0.5)
				(island_removal_mode 0)
			)
			(polygon
				(pts
					(arc
						(start 437.949848 -315.896244)
						(mid 432.946048 -320.900044)
						(end 437.949848 -325.903844)
					)
					(arc
						(start 437.949848 -325.421244)
						(mid 433.428648 -320.900044)
						(end 437.949848 -316.378844)
					)
				)
			)
		)
		(zone
			(layer "B.Cu")
			(hatch none 0.5)
			(connect_pads
				(clearance 0)
			)
			(min_thickness 0.25)
			(keepout
				(tracks not_allowed)
				(vias allowed)
				(pads allowed)
				(copperpour not_allowed)
				(footprints allowed)
			)
			(placement
				(enabled no)
				(sheetname "")
			)
			(fill
				(thermal_gap 0.5)
				(thermal_bridge_width 0.5)
				(island_removal_mode 0)
			)
			(polygon
				(pts
					(arc
						(start 437.949848 -315.896244)
						(mid 442.953648 -320.900044)
						(end 437.949848 -325.903844)
					)
					(arc
						(start 437.949848 -325.421244)
						(mid 442.471048 -320.900044)
						(end 437.949848 -316.378844)
					)
				)
			)
		)
	)
	(footprint ""
		(layer "F.Cu")
		(at 241.076988 -296.764202 -90)
		(property "Reference" "PL22"
			(at -3.521202 -7.653528 90)
			(unlocked yes)
			(layer "F.SilkS")
			(effects
				(font
					(size 0.7874 0.5842)
					(thickness 0.1524)
				)
				(justify left)
			)
		)
		(property "Value" ""
			(at 0 0 270)
			(layer "F.Fab")
			(effects
				(font
					(size 1.27 1.27)
				)
			)
		)
		(duplicate_pad_numbers_are_jumpers no)
		(fp_line
			(start -6.849872 6.450076)
			(end -6.849872 1.9812)
			(stroke
				(width 0.1524)
				(type default)
			)
			(layer "F.SilkS")
		)
		(fp_line
			(start 6.849872 6.450076)
			(end -6.849872 6.450076)
			(stroke
				(width 0.1524)
				(type default)
			)
			(layer "F.SilkS")
		)
		(fp_line
			(start 6.849872 1.9812)
			(end 6.849872 6.450076)
			(stroke
				(width 0.1524)
				(type default)
			)
			(layer "F.SilkS")
		)
		(fp_line
			(start -6.849872 -1.9812)
			(end -6.849872 -6.450076)
			(stroke
				(width 0.1524)
				(type default)
			)
			(layer "F.SilkS")
		)
		(fp_line
			(start -6.849872 -6.450076)
			(end 6.849872 -6.450076)
			(stroke
				(width 0.1524)
				(type default)
			)
			(layer "F.SilkS")
		)
		(fp_line
			(start 6.849872 -6.450076)
			(end 6.849872 -1.9812)
			(stroke
				(width 0.1524)
				(type default)
			)
			(layer "F.SilkS")
		)
		(fp_line
			(start -6.849872 6.450076)
			(end -6.849872 -6.450076)
			(stroke
				(width 0.1)
				(type default)
			)
			(layer "F.Fab")
		)
		(fp_line
			(start 6.849872 6.450076)
			(end -6.849872 6.450076)
			(stroke
				(width 0.1)
				(type default)
			)
			(layer "F.Fab")
		)
		(fp_line
			(start -6.849872 -6.450076)
			(end 6.849872 -6.450076)
			(stroke
				(width 0.1)
				(type default)
			)
			(layer "F.Fab")
		)
		(fp_line
			(start 6.849872 -6.450076)
			(end 6.849872 6.450076)
			(stroke
				(width 0.1)
				(type default)
			)
			(layer "F.Fab")
		)
		(pad "1" smd rect
			(at -5.407406 0 270)
			(size 2.9464 3.7084)
			(layers "F.Cu" "F.Mask" "F.Paste")
			(net "SW_P1V25_PEX2_PH")
		)
		(pad "2" smd rect
			(at 5.407406 0 270)
			(size 2.9464 3.7084)
			(layers "F.Cu" "F.Mask" "F.Paste")
			(net "P1V25_PEX2_R")
		)
	)
	(footprint ""
		(layer "F.Cu")
		(at 407.4033 -59.571636 90)
		(property "Reference" "PR282"
			(at 0 0 90)
			(layer "F.SilkS")
			(hide yes)
			(effects
				(font
					(size 1.27 1.27)
				)
			)
		)
		(property "Value" ""
			(at 0 0 90)
			(layer "F.Fab")
			(effects
				(font
					(size 1.27 1.27)
				)
			)
		)
		(duplicate_pad_numbers_are_jumpers no)
		(fp_line
			(start 0.7874 -0.4064)
			(end 0.7874 0.4064)
			(stroke
				(width 0.1524)
				(type default)
			)
			(layer "F.SilkS")
		)
		(fp_line
			(start -0.7874 -0.4064)
			(end 0.7874 -0.4064)
			(stroke
				(width 0.1524)
				(type default)
			)
			(layer "F.SilkS")
		)
		(fp_line
			(start 0.7874 0.4064)
			(end -0.7874 0.4064)
			(stroke
				(width 0.1524)
				(type default)
			)
			(layer "F.SilkS")
		)
		(fp_line
			(start -0.7874 0.4064)
			(end -0.7874 -0.4064)
			(stroke
				(width 0.1524)
				(type default)
			)
			(layer "F.SilkS")
		)
		(fp_line
			(start -0.12065 -0.305054)
			(end -0.12065 -0.2794)
			(stroke
				(width 0.1)
				(type default)
			)
			(layer "F.Fab")
		)
		(fp_line
			(start -0.67945 -0.305054)
			(end -0.12065 -0.305054)
			(stroke
				(width 0.1)
				(type default)
			)
			(layer "F.Fab")
		)
		(fp_line
			(start 0.67945 -0.3048)
			(end 0.67945 0.3048)
			(stroke
				(width 0.1)
				(type default)
			)
			(layer "F.Fab")
		)
		(fp_line
			(start 0.12065 -0.3048)
			(end 0.67945 -0.3048)
			(stroke
				(width 0.1)
				(type default)
			)
			(layer "F.Fab")
		)
		(fp_line
			(start 0.12065 -0.2794)
			(end 0.12065 -0.3048)
			(stroke
				(width 0.1)
				(type default)
			)
			(layer "F.Fab")
		)
		(fp_line
			(start -0.12065 -0.2794)
			(end 0.12065 -0.2794)
			(stroke
				(width 0.1)
				(type default)
			)
			(layer "F.Fab")
		)
		(fp_line
			(start 0.120396 0.2794)
			(end -0.12065 0.2794)
			(stroke
				(width 0.1)
				(type default)
			)
			(layer "F.Fab")
		)
		(fp_line
			(start -0.12065 0.2794)
			(end -0.12065 0.3048)
			(stroke
				(width 0.1)
				(type default)
			)
			(layer "F.Fab")
		)
		(fp_line
			(start 0.67945 0.3048)
			(end 0.120396 0.3048)
			(stroke
				(width 0.1)
				(type default)
			)
			(layer "F.Fab")
		)
		(fp_line
			(start 0.120396 0.3048)
			(end 0.120396 0.2794)
			(stroke
				(width 0.1)
				(type default)
			)
			(layer "F.Fab")
		)
		(fp_line
			(start -0.12065 0.3048)
			(end -0.67945 0.3048)
			(stroke
				(width 0.1)
				(type default)
			)
			(layer "F.Fab")
		)
		(fp_line
			(start -0.67945 0.3048)
			(end -0.67945 -0.305054)
			(stroke
				(width 0.1)
				(type default)
			)
			(layer "F.Fab")
		)
		(pad "1" smd circle
			(at -0.40005 0 90)
			(size 0 0)
			(layers "F.Cu" "F.Mask" "F.Paste")
			(net "P3V3_SSD14_OCP")
		)
		(pad "2" smd circle
			(at 0.40005 0 90)
			(size 0 0)
			(layers "F.Cu" "F.Mask" "F.Paste")
			(net "GND")
		)
	)
	(footprint ""
		(layer "F.Cu")
		(at 359.156 -178.054)
		(property "Reference" "R4663"
			(at 0 0 0)
			(layer "F.SilkS")
			(hide yes)
			(effects
				(font
					(size 1.27 1.27)
				)
			)
		)
		(property "Value" ""
			(at 0 0 0)
			(layer "F.Fab")
			(effects
				(font
					(size 1.27 1.27)
				)
			)
		)
		(duplicate_pad_numbers_are_jumpers no)
		(fp_line
			(start -0.7874 -0.4064)
			(end 0.7874 -0.4064)
			(stroke
				(width 0.1524)
				(type default)
			)
			(layer "F.SilkS")
		)
		(fp_line
			(start -0.7874 0.4064)
			(end -0.7874 -0.4064)
			(stroke
				(width 0.1524)
				(type default)
			)
			(layer "F.SilkS")
		)
		(fp_line
			(start 0.7874 -0.4064)
			(end 0.7874 0.4064)
			(stroke
				(width 0.1524)
				(type default)
			)
			(layer "F.SilkS")
		)
		(fp_line
			(start 0.7874 0.4064)
			(end -0.7874 0.4064)
			(stroke
				(width 0.1524)
				(type default)
			)
			(layer "F.SilkS")
		)
		(fp_line
			(start -0.67945 -0.305054)
			(end -0.12065 -0.305054)
			(stroke
				(width 0.1)
				(type default)
			)
			(layer "F.Fab")
		)
		(fp_line
			(start -0.67945 0.3048)
			(end -0.67945 -0.305054)
			(stroke
				(width 0.1)
				(type default)
			)
			(layer "F.Fab")
		)
		(fp_line
			(start -0.12065 -0.305054)
			(end -0.12065 -0.2794)
			(stroke
				(width 0.1)
				(type default)
			)
			(layer "F.Fab")
		)
		(fp_line
			(start -0.12065 -0.2794)
			(end 0.12065 -0.2794)
			(stroke
				(width 0.1)
				(type default)
			)
			(layer "F.Fab")
		)
		(fp_line
			(start -0.12065 0.2794)
			(end -0.12065 0.3048)
			(stroke
				(width 0.1)
				(type default)
			)
			(layer "F.Fab")
		)
		(fp_line
			(start -0.12065 0.3048)
			(end -0.67945 0.3048)
			(stroke
				(width 0.1)
				(type default)
			)
			(layer "F.Fab")
		)
		(fp_line
			(start 0.120396 0.2794)
			(end -0.12065 0.2794)
			(stroke
				(width 0.1)
				(type default)
			)
			(layer "F.Fab")
		)
		(fp_line
			(start 0.120396 0.3048)
			(end 0.120396 0.2794)
			(stroke
				(width 0.1)
				(type default)
			)
			(layer "F.Fab")
		)
		(fp_line
			(start 0.12065 -0.3048)
			(end 0.67945 -0.3048)
			(stroke
				(width 0.1)
				(type default)
			)
			(layer "F.Fab")
		)
		(fp_line
			(start 0.12065 -0.2794)
			(end 0.12065 -0.3048)
			(stroke
				(width 0.1)
				(type default)
			)
			(layer "F.Fab")
		)
		(fp_line
			(start 0.67945 -0.3048)
			(end 0.67945 0.3048)
			(stroke
				(width 0.1)
				(type default)
			)
			(layer "F.Fab")
		)
		(fp_line
			(start 0.67945 0.3048)
			(end 0.120396 0.3048)
			(stroke
				(width 0.1)
				(type default)
			)
			(layer "F.Fab")
		)
		(pad "1" smd circle
			(at -0.40005 0)
			(size 0 0)
			(layers "F.Cu" "F.Mask" "F.Paste")
			(net "P3V3_AUX")
		)
		(pad "2" smd circle
			(at 0.40005 0)
			(size 0 0)
			(layers "F.Cu" "F.Mask" "F.Paste")
			(net "SSD6_PEX_PWR_EN_R")
		)
	)
	(footprint ""
		(layer "F.Cu")
		(at 363.474 -202.819 180)
		(property "Reference" "R4683"
			(at 0 0 180)
			(layer "F.SilkS")
			(hide yes)
			(effects
				(font
					(size 1.27 1.27)
				)
			)
		)
		(property "Value" ""
			(at 0 0 180)
			(layer "F.Fab")
			(effects
				(font
					(size 1.27 1.27)
				)
			)
		)
		(duplicate_pad_numbers_are_jumpers no)
		(fp_line
			(start 0.7874 0.4064)
			(end -0.7874 0.4064)
			(stroke
				(width 0.1524)
				(type default)
			)
			(layer "F.SilkS")
		)
		(fp_line
			(start 0.7874 -0.4064)
			(end 0.7874 0.4064)
			(stroke
				(width 0.1524)
				(type default)
			)
			(layer "F.SilkS")
		)
		(fp_line
			(start -0.7874 0.4064)
			(end -0.7874 -0.4064)
			(stroke
				(width 0.1524)
				(type default)
			)
			(layer "F.SilkS")
		)
		(fp_line
			(start -0.7874 -0.4064)
			(end 0.7874 -0.4064)
			(stroke
				(width 0.1524)
				(type default)
			)
			(layer "F.SilkS")
		)
		(fp_line
			(start 0.67945 0.3048)
			(end 0.120396 0.3048)
			(stroke
				(width 0.1)
				(type default)
			)
			(layer "F.Fab")
		)
		(fp_line
			(start 0.67945 -0.3048)
			(end 0.67945 0.3048)
			(stroke
				(width 0.1)
				(type default)
			)
			(layer "F.Fab")
		)
		(fp_line
			(start 0.12065 -0.2794)
			(end 0.12065 -0.3048)
			(stroke
				(width 0.1)
				(type default)
			)
			(layer "F.Fab")
		)
		(fp_line
			(start 0.12065 -0.3048)
			(end 0.67945 -0.3048)
			(stroke
				(width 0.1)
				(type default)
			)
			(layer "F.Fab")
		)
		(fp_line
			(start 0.120396 0.3048)
			(end 0.120396 0.2794)
			(stroke
				(width 0.1)
				(type default)
			)
			(layer "F.Fab")
		)
		(fp_line
			(start 0.120396 0.2794)
			(end -0.12065 0.2794)
			(stroke
				(width 0.1)
				(type default)
			)
			(layer "F.Fab")
		)
		(fp_line
			(start -0.12065 0.3048)
			(end -0.67945 0.3048)
			(stroke
				(width 0.1)
				(type default)
			)
			(layer "F.Fab")
		)
		(fp_line
			(start -0.12065 0.2794)
			(end -0.12065 0.3048)
			(stroke
				(width 0.1)
				(type default)
			)
			(layer "F.Fab")
		)
		(fp_line
			(start -0.12065 -0.2794)
			(end 0.12065 -0.2794)
			(stroke
				(width 0.1)
				(type default)
			)
			(layer "F.Fab")
		)
		(fp_line
			(start -0.12065 -0.305054)
			(end -0.12065 -0.2794)
			(stroke
				(width 0.1)
				(type default)
			)
			(layer "F.Fab")
		)
		(fp_line
			(start -0.67945 0.3048)
			(end -0.67945 -0.305054)
			(stroke
				(width 0.1)
				(type default)
			)
			(layer "F.Fab")
		)
		(fp_line
			(start -0.67945 -0.305054)
			(end -0.12065 -0.305054)
			(stroke
				(width 0.1)
				(type default)
			)
			(layer "F.Fab")
		)
		(pad "1" smd circle
			(at -0.40005 0 180)
			(size 0 0)
			(layers "F.Cu" "F.Mask" "F.Paste")
			(net "PCA9555_0_PEX1_A1")
		)
		(pad "2" smd circle
			(at 0.40005 0 180)
			(size 0 0)
			(layers "F.Cu" "F.Mask" "F.Paste")
			(net "P3V3_AUX")
		)
	)
	(footprint ""
		(layer "F.Cu")
		(at 107.02925 -105.253536)
		(property "Reference" "PD77"
			(at 1.17475 2.791206 0)
			(unlocked yes)
			(layer "F.SilkS")
			(effects
				(font
					(size 0.7874 0.5842)
					(thickness 0.1524)
				)
				(justify left)
			)
		)
		(property "Value" ""
			(at 0 0 0)
			(layer "F.Fab")
			(effects
				(font
					(size 1.27 1.27)
				)
			)
		)
		(duplicate_pad_numbers_are_jumpers no)
		(fp_line
			(start -3.656584 -1.970024)
			(end -3.656584 1.970024)
			(stroke
				(width 0.1524)
				(type default)
			)
			(layer "F.SilkS")
		)
		(fp_line
			(start -3.656584 1.970024)
			(end 4.240784 1.970024)
			(stroke
				(width 0.1524)
				(type default)
			)
			(layer "F.SilkS")
		)
		(fp_line
			(start 4.240784 -1.970024)
			(end -3.656584 -1.970024)
			(stroke
				(width 0.1524)
				(type default)
			)
			(layer "F.SilkS")
		)
		(fp_line
			(start 4.240784 1.970024)
			(end 4.240784 -1.970024)
			(stroke
				(width 0.1524)
				(type default)
			)
			(layer "F.SilkS")
		)
		(fp_rect
			(start 3.580384 1.970024)
			(end 4.240784 -1.970024)
			(stroke
				(width 0)
				(type default)
			)
			(fill yes)
			(layer "F.SilkS")
		)
		(fp_line
			(start -2.3749 -1.970024)
			(end -2.3749 1.970024)
			(stroke
				(width 0.1)
				(type default)
			)
			(layer "F.Fab")
		)
		(fp_line
			(start -2.3749 1.970024)
			(end 2.3749 1.970024)
			(stroke
				(width 0.1)
				(type default)
			)
			(layer "F.Fab")
		)
		(fp_line
			(start 2.3749 -1.970024)
			(end -2.3749 -1.970024)
			(stroke
				(width 0.1)
				(type default)
			)
			(layer "F.Fab")
		)
		(fp_line
			(start 2.3749 1.970024)
			(end 2.3749 -1.970024)
			(stroke
				(width 0.1)
				(type default)
			)
			(layer "F.Fab")
		)
		(fp_text user "+"
			(at -4.9784 -0.23495 0)
			(unlocked yes)
			(layer "F.Fab")
			(effects
				(font
					(size 1.905 1.4224)
					(thickness 0.1524)
				)
				(justify left)
			)
		)
		(fp_text user "-"
			(at 4.1656 -0.23495 0)
			(unlocked yes)
			(layer "F.Fab")
			(effects
				(font
					(size 1.905 1.4224)
					(thickness 0.1524)
				)
				(justify left)
			)
		)
		(pad "A" smd rect
			(at -2.450084 0)
			(size 2.159 2.2606)
			(layers "F.Cu" "F.Mask" "F.Paste")
			(net "GND")
		)
		(pad "C" smd rect
			(at 2.450084 0)
			(size 2.159 2.2606)
			(layers "F.Cu" "F.Mask" "F.Paste")
			(net "P12V_AUX")
		)
	)
	(footprint ""
		(layer "F.Cu")
		(at 176.220628 -26.666444 -90)
		(property "Reference" "R4065"
			(at 0 0 270)
			(layer "F.SilkS")
			(hide yes)
			(effects
				(font
					(size 1.27 1.27)
				)
			)
		)
		(property "Value" ""
			(at 0 0 270)
			(layer "F.Fab")
			(effects
				(font
					(size 1.27 1.27)
				)
			)
		)
		(duplicate_pad_numbers_are_jumpers no)
		(fp_line
			(start -0.7874 0.4064)
			(end -0.7874 -0.4064)
			(stroke
				(width 0.1524)
				(type default)
			)
			(layer "F.SilkS")
		)
		(fp_line
			(start 0.7874 0.4064)
			(end -0.7874 0.4064)
			(stroke
				(width 0.1524)
				(type default)
			)
			(layer "F.SilkS")
		)
		(fp_line
			(start -0.7874 -0.4064)
			(end 0.7874 -0.4064)
			(stroke
				(width 0.1524)
				(type default)
			)
			(layer "F.SilkS")
		)
		(fp_line
			(start 0.7874 -0.4064)
			(end 0.7874 0.4064)
			(stroke
				(width 0.1524)
				(type default)
			)
			(layer "F.SilkS")
		)
		(fp_line
			(start -0.67945 0.3048)
			(end -0.67945 -0.305054)
			(stroke
				(width 0.1)
				(type default)
			)
			(layer "F.Fab")
		)
		(fp_line
			(start -0.12065 0.3048)
			(end -0.67945 0.3048)
			(stroke
				(width 0.1)
				(type default)
			)
			(layer "F.Fab")
		)
		(fp_line
			(start 0.120396 0.3048)
			(end 0.120396 0.2794)
			(stroke
				(width 0.1)
				(type default)
			)
			(layer "F.Fab")
		)
		(fp_line
			(start 0.67945 0.3048)
			(end 0.120396 0.3048)
			(stroke
				(width 0.1)
				(type default)
			)
			(layer "F.Fab")
		)
		(fp_line
			(start -0.12065 0.2794)
			(end -0.12065 0.3048)
			(stroke
				(width 0.1)
				(type default)
			)
			(layer "F.Fab")
		)
		(fp_line
			(start 0.120396 0.2794)
			(end -0.12065 0.2794)
			(stroke
				(width 0.1)
				(type default)
			)
			(layer "F.Fab")
		)
		(fp_line
			(start -0.12065 -0.2794)
			(end 0.12065 -0.2794)
			(stroke
				(width 0.1)
				(type default)
			)
			(layer "F.Fab")
		)
		(fp_line
			(start 0.12065 -0.2794)
			(end 0.12065 -0.3048)
			(stroke
				(width 0.1)
				(type default)
			)
			(layer "F.Fab")
		)
		(fp_line
			(start 0.12065 -0.3048)
			(end 0.67945 -0.3048)
			(stroke
				(width 0.1)
				(type default)
			)
			(layer "F.Fab")
		)
		(fp_line
			(start 0.67945 -0.3048)
			(end 0.67945 0.3048)
			(stroke
				(width 0.1)
				(type default)
			)
			(layer "F.Fab")
		)
		(fp_line
			(start -0.67945 -0.305054)
			(end -0.12065 -0.305054)
			(stroke
				(width 0.1)
				(type default)
			)
			(layer "F.Fab")
		)
		(fp_line
			(start -0.12065 -0.305054)
			(end -0.12065 -0.2794)
			(stroke
				(width 0.1)
				(type default)
			)
			(layer "F.Fab")
		)
		(pad "1" smd circle
			(at -0.40005 0 270)
			(size 0 0)
			(layers "F.Cu" "F.Mask" "F.Paste")
			(net "PRSNT_SSD6_R_N")
		)
		(pad "2" smd circle
			(at 0.40005 0 270)
			(size 0 0)
			(layers "F.Cu" "F.Mask" "F.Paste")
			(net "PRSNT_SSD6_N")
		)
	)
	(footprint ""
		(layer "F.Cu")
		(at 25.964896 -17.999964)
		(property "Reference" "H71"
			(at -4.208018 -5.095748 0)
			(unlocked yes)
			(layer "F.SilkS")
			(effects
				(font
					(size 0.7874 0.5842)
					(thickness 0.1524)
				)
				(justify left)
			)
		)
		(property "Value" ""
			(at 0 0 0)
			(layer "F.Fab")
			(effects
				(font
					(size 1.27 1.27)
				)
			)
		)
		(duplicate_pad_numbers_are_jumpers no)
		(pad "1" thru_hole circle
			(at 0 0)
			(size 10.0076 10.0076)
			(drill 5.6134)
			(layers "*.Cu" "*.Mask")
			(remove_unused_layers no)
			(net "GND")
			(clearance -1.9431)
		)
	)
	(footprint ""
		(layer "F.Cu")
		(at 279.14727 -19.33956)
		(property "Reference" "C3936"
			(at 0 0 0)
			(layer "F.SilkS")
			(hide yes)
			(effects
				(font
					(size 1.27 1.27)
				)
			)
		)
		(property "Value" ""
			(at 0 0 0)
			(layer "F.Fab")
			(effects
				(font
					(size 1.27 1.27)
				)
			)
		)
		(duplicate_pad_numbers_are_jumpers no)
		(fp_line
			(start -0.7874 -0.4064)
			(end 0.7874 -0.4064)
			(stroke
				(width 0.1524)
				(type default)
			)
			(layer "F.SilkS")
		)
		(fp_line
			(start -0.7874 0.4064)
			(end -0.7874 -0.4064)
			(stroke
				(width 0.1524)
				(type default)
			)
			(layer "F.SilkS")
		)
		(fp_line
			(start 0.7874 -0.4064)
			(end 0.7874 0.4064)
			(stroke
				(width 0.1524)
				(type default)
			)
			(layer "F.SilkS")
		)
		(fp_line
			(start 0.7874 0.4064)
			(end -0.7874 0.4064)
			(stroke
				(width 0.1524)
				(type default)
			)
			(layer "F.SilkS")
		)
		(fp_line
			(start -0.67945 -0.305054)
			(end -0.12065 -0.305054)
			(stroke
				(width 0.1)
				(type default)
			)
			(layer "F.Fab")
		)
		(fp_line
			(start -0.67945 0.3048)
			(end -0.67945 -0.305054)
			(stroke
				(width 0.1)
				(type default)
			)
			(layer "F.Fab")
		)
		(fp_line
			(start -0.12065 -0.305054)
			(end -0.12065 -0.2794)
			(stroke
				(width 0.1)
				(type default)
			)
			(layer "F.Fab")
		)
		(fp_line
			(start -0.12065 -0.2794)
			(end 0.12065 -0.2794)
			(stroke
				(width 0.1)
				(type default)
			)
			(layer "F.Fab")
		)
		(fp_line
			(start -0.12065 0.2794)
			(end -0.12065 0.3048)
			(stroke
				(width 0.1)
				(type default)
			)
			(layer "F.Fab")
		)
		(fp_line
			(start -0.12065 0.3048)
			(end -0.67945 0.3048)
			(stroke
				(width 0.1)
				(type default)
			)
			(layer "F.Fab")
		)
		(fp_line
			(start 0.120396 0.2794)
			(end -0.12065 0.2794)
			(stroke
				(width 0.1)
				(type default)
			)
			(layer "F.Fab")
		)
		(fp_line
			(start 0.120396 0.3048)
			(end 0.120396 0.2794)
			(stroke
				(width 0.1)
				(type default)
			)
			(layer "F.Fab")
		)
		(fp_line
			(start 0.12065 -0.3048)
			(end 0.67945 -0.3048)
			(stroke
				(width 0.1)
				(type default)
			)
			(layer "F.Fab")
		)
		(fp_line
			(start 0.12065 -0.2794)
			(end 0.12065 -0.3048)
			(stroke
				(width 0.1)
				(type default)
			)
			(layer "F.Fab")
		)
		(fp_line
			(start 0.67945 -0.3048)
			(end 0.67945 0.3048)
			(stroke
				(width 0.1)
				(type default)
			)
			(layer "F.Fab")
		)
		(fp_line
			(start 0.67945 0.3048)
			(end 0.120396 0.3048)
			(stroke
				(width 0.1)
				(type default)
			)
			(layer "F.Fab")
		)
		(pad "1" smd circle
			(at -0.40005 0)
			(size 0 0)
			(layers "F.Cu" "F.Mask" "F.Paste")
			(net "P12V_SSD9")
		)
		(pad "2" smd circle
			(at 0.40005 0)
			(size 0 0)
			(layers "F.Cu" "F.Mask" "F.Paste")
			(net "GND")
		)
	)
	(footprint ""
		(layer "F.Cu")
		(at 65.370202 -356.244906 90)
		(property "Reference" "C124"
			(at 0 0 90)
			(layer "F.SilkS")
			(hide yes)
			(effects
				(font
					(size 1.27 1.27)
				)
			)
		)
		(property "Value" ""
			(at 0 0 90)
			(layer "F.Fab")
			(effects
				(font
					(size 1.27 1.27)
				)
			)
		)
		(duplicate_pad_numbers_are_jumpers no)
		(fp_line
			(start 0.299974 -0.150114)
			(end 0.299974 0.150114)
			(stroke
				(width 0.1)
				(type default)
			)
			(layer "F.Fab")
		)
		(fp_line
			(start -0.299974 -0.150114)
			(end 0.299974 -0.150114)
			(stroke
				(width 0.1)
				(type default)
			)
			(layer "F.Fab")
		)
		(fp_line
			(start 0.299974 0.150114)
			(end -0.299974 0.150114)
			(stroke
				(width 0.1)
				(type default)
			)
			(layer "F.Fab")
		)
		(fp_line
			(start -0.299974 0.150114)
			(end -0.299974 -0.150114)
			(stroke
				(width 0.1)
				(type default)
			)
			(layer "F.Fab")
		)
		(pad "1" smd rect
			(at -0.2667 0 90)
			(size 0.3048 0.381)
			(layers "F.Cu" "F.Mask" "F.Paste")
			(net "P5E_PEX0_STN5_TX_DN<82>")
		)
		(pad "2" smd rect
			(at 0.2667 0 90)
			(size 0.3048 0.381)
			(layers "F.Cu" "F.Mask" "F.Paste")
			(net "P5E_PEX0_STN5_TX_C_DN<82>")
		)
	)
	(footprint ""
		(layer "F.Cu")
		(at 436.262272 -306.023772 90)
		(property "Reference" "R3993"
			(at 0 0 90)
			(layer "F.SilkS")
			(hide yes)
			(effects
				(font
					(size 1.27 1.27)
				)
			)
		)
		(property "Value" ""
			(at 0 0 90)
			(layer "F.Fab")
			(effects
				(font
					(size 1.27 1.27)
				)
			)
		)
		(duplicate_pad_numbers_are_jumpers no)
		(fp_line
			(start 0.7874 -0.4064)
			(end 0.7874 0.4064)
			(stroke
				(width 0.1524)
				(type default)
			)
			(layer "F.SilkS")
		)
		(fp_line
			(start -0.7874 -0.4064)
			(end 0.7874 -0.4064)
			(stroke
				(width 0.1524)
				(type default)
			)
			(layer "F.SilkS")
		)
		(fp_line
			(start 0.7874 0.4064)
			(end -0.7874 0.4064)
			(stroke
				(width 0.1524)
				(type default)
			)
			(layer "F.SilkS")
		)
		(fp_line
			(start -0.7874 0.4064)
			(end -0.7874 -0.4064)
			(stroke
				(width 0.1524)
				(type default)
			)
			(layer "F.SilkS")
		)
		(fp_line
			(start -0.12065 -0.305054)
			(end -0.12065 -0.2794)
			(stroke
				(width 0.1)
				(type default)
			)
			(layer "F.Fab")
		)
		(fp_line
			(start -0.67945 -0.305054)
			(end -0.12065 -0.305054)
			(stroke
				(width 0.1)
				(type default)
			)
			(layer "F.Fab")
		)
		(fp_line
			(start 0.67945 -0.3048)
			(end 0.67945 0.3048)
			(stroke
				(width 0.1)
				(type default)
			)
			(layer "F.Fab")
		)
		(fp_line
			(start 0.12065 -0.3048)
			(end 0.67945 -0.3048)
			(stroke
				(width 0.1)
				(type default)
			)
			(layer "F.Fab")
		)
		(fp_line
			(start 0.12065 -0.2794)
			(end 0.12065 -0.3048)
			(stroke
				(width 0.1)
				(type default)
			)
			(layer "F.Fab")
		)
		(fp_line
			(start -0.12065 -0.2794)
			(end 0.12065 -0.2794)
			(stroke
				(width 0.1)
				(type default)
			)
			(layer "F.Fab")
		)
		(fp_line
			(start 0.120396 0.2794)
			(end -0.12065 0.2794)
			(stroke
				(width 0.1)
				(type default)
			)
			(layer "F.Fab")
		)
		(fp_line
			(start -0.12065 0.2794)
			(end -0.12065 0.3048)
			(stroke
				(width 0.1)
				(type default)
			)
			(layer "F.Fab")
		)
		(fp_line
			(start 0.67945 0.3048)
			(end 0.120396 0.3048)
			(stroke
				(width 0.1)
				(type default)
			)
			(layer "F.Fab")
		)
		(fp_line
			(start 0.120396 0.3048)
			(end 0.120396 0.2794)
			(stroke
				(width 0.1)
				(type default)
			)
			(layer "F.Fab")
		)
		(fp_line
			(start -0.12065 0.3048)
			(end -0.67945 0.3048)
			(stroke
				(width 0.1)
				(type default)
			)
			(layer "F.Fab")
		)
		(fp_line
			(start -0.67945 0.3048)
			(end -0.67945 -0.305054)
			(stroke
				(width 0.1)
				(type default)
			)
			(layer "F.Fab")
		)
		(pad "1" smd circle
			(at -0.40005 0 90)
			(size 0 0)
			(layers "F.Cu" "F.Mask" "F.Paste")
			(net "SMB_PEX3_SLAVE_SDA")
		)
		(pad "2" smd circle
			(at 0.40005 0 90)
			(size 0 0)
			(layers "F.Cu" "F.Mask" "F.Paste")
			(net "SMB_PEX3_R_SDA")
		)
	)
	(footprint ""
		(layer "F.Cu")
		(at 214.43823 -222.378778 180)
		(property "Reference" "R4884"
			(at 0 0 180)
			(layer "F.SilkS")
			(hide yes)
			(effects
				(font
					(size 1.27 1.27)
				)
			)
		)
		(property "Value" ""
			(at 0 0 180)
			(layer "F.Fab")
			(effects
				(font
					(size 1.27 1.27)
				)
			)
		)
		(duplicate_pad_numbers_are_jumpers no)
		(fp_line
			(start 0.7874 0.4064)
			(end -0.7874 0.4064)
			(stroke
				(width 0.1524)
				(type default)
			)
			(layer "F.SilkS")
		)
		(fp_line
			(start 0.7874 -0.4064)
			(end 0.7874 0.4064)
			(stroke
				(width 0.1524)
				(type default)
			)
			(layer "F.SilkS")
		)
		(fp_line
			(start -0.7874 0.4064)
			(end -0.7874 -0.4064)
			(stroke
				(width 0.1524)
				(type default)
			)
			(layer "F.SilkS")
		)
		(fp_line
			(start -0.7874 -0.4064)
			(end 0.7874 -0.4064)
			(stroke
				(width 0.1524)
				(type default)
			)
			(layer "F.SilkS")
		)
		(fp_line
			(start 0.67945 0.3048)
			(end 0.120396 0.3048)
			(stroke
				(width 0.1)
				(type default)
			)
			(layer "F.Fab")
		)
		(fp_line
			(start 0.67945 -0.3048)
			(end 0.67945 0.3048)
			(stroke
				(width 0.1)
				(type default)
			)
			(layer "F.Fab")
		)
		(fp_line
			(start 0.12065 -0.2794)
			(end 0.12065 -0.3048)
			(stroke
				(width 0.1)
				(type default)
			)
			(layer "F.Fab")
		)
		(fp_line
			(start 0.12065 -0.3048)
			(end 0.67945 -0.3048)
			(stroke
				(width 0.1)
				(type default)
			)
			(layer "F.Fab")
		)
		(fp_line
			(start 0.120396 0.3048)
			(end 0.120396 0.2794)
			(stroke
				(width 0.1)
				(type default)
			)
			(layer "F.Fab")
		)
		(fp_line
			(start 0.120396 0.2794)
			(end -0.12065 0.2794)
			(stroke
				(width 0.1)
				(type default)
			)
			(layer "F.Fab")
		)
		(fp_line
			(start -0.12065 0.3048)
			(end -0.67945 0.3048)
			(stroke
				(width 0.1)
				(type default)
			)
			(layer "F.Fab")
		)
		(fp_line
			(start -0.12065 0.2794)
			(end -0.12065 0.3048)
			(stroke
				(width 0.1)
				(type default)
			)
			(layer "F.Fab")
		)
		(fp_line
			(start -0.12065 -0.2794)
			(end 0.12065 -0.2794)
			(stroke
				(width 0.1)
				(type default)
			)
			(layer "F.Fab")
		)
		(fp_line
			(start -0.12065 -0.305054)
			(end -0.12065 -0.2794)
			(stroke
				(width 0.1)
				(type default)
			)
			(layer "F.Fab")
		)
		(fp_line
			(start -0.67945 0.3048)
			(end -0.67945 -0.305054)
			(stroke
				(width 0.1)
				(type default)
			)
			(layer "F.Fab")
		)
		(fp_line
			(start -0.67945 -0.305054)
			(end -0.12065 -0.305054)
			(stroke
				(width 0.1)
				(type default)
			)
			(layer "F.Fab")
		)
		(pad "1" smd circle
			(at -0.40005 0 180)
			(size 0 0)
			(layers "F.Cu" "F.Mask" "F.Paste")
			(net "SMB_BIC_FPGA_R_SDA")
		)
		(pad "2" smd circle
			(at 0.40005 0 180)
			(size 0 0)
			(layers "F.Cu" "F.Mask" "F.Paste")
			(net "P3V3_AUX")
		)
	)
	(footprint ""
		(layer "F.Cu")
		(at 358.44988 -148.872702)
		(property "Reference" "PD15"
			(at -3.4544 -2.225548 0)
			(unlocked yes)
			(layer "F.SilkS")
			(effects
				(font
					(size 0.7874 0.5842)
					(thickness 0.1524)
				)
				(justify left)
			)
		)
		(property "Value" ""
			(at 0 0 0)
			(layer "F.Fab")
			(effects
				(font
					(size 1.27 1.27)
				)
			)
		)
		(duplicate_pad_numbers_are_jumpers no)
		(fp_line
			(start -3.400044 -1.459992)
			(end 4.107942 -1.459992)
			(stroke
				(width 0.1524)
				(type default)
			)
			(layer "F.SilkS")
		)
		(fp_line
			(start -3.400044 1.459992)
			(end -3.400044 -1.459992)
			(stroke
				(width 0.1524)
				(type default)
			)
			(layer "F.SilkS")
		)
		(fp_line
			(start 4.107942 -1.459992)
			(end 4.107942 1.459992)
			(stroke
				(width 0.1524)
				(type default)
			)
			(layer "F.SilkS")
		)
		(fp_line
			(start 4.107942 1.459992)
			(end -3.400044 1.459992)
			(stroke
				(width 0.1524)
				(type default)
			)
			(layer "F.SilkS")
		)
		(fp_poly
			(pts
				(xy 4.107942 -1.459992) (xy 4.107942 1.459992) (xy 3.308096 1.459992) (xy 3.308096 -1.459992)
			)
			(stroke
				(width 0)
				(type default)
			)
			(fill yes)
			(layer "F.SilkS")
		)
		(fp_line
			(start -2.29997 -1.459992)
			(end 2.29997 -1.459992)
			(stroke
				(width 0.1)
				(type default)
			)
			(layer "F.Fab")
		)
		(fp_line
			(start -2.29997 1.459992)
			(end -2.29997 -1.459992)
			(stroke
				(width 0.1)
				(type default)
			)
			(layer "F.Fab")
		)
		(fp_line
			(start 2.29997 -1.459992)
			(end 2.29997 1.459992)
			(stroke
				(width 0.1)
				(type default)
			)
			(layer "F.Fab")
		)
		(fp_line
			(start 2.29997 1.459992)
			(end -2.29997 1.459992)
			(stroke
				(width 0.1)
				(type default)
			)
			(layer "F.Fab")
		)
		(fp_text user "+"
			(at -4.7752 -0.12065 0)
			(unlocked yes)
			(layer "F.SilkS")
			(effects
				(font
					(size 1.905 1.4224)
					(thickness 0.1524)
				)
				(justify left)
			)
		)
		(fp_text user "-"
			(at 5.4102 0.29845 180)
			(unlocked yes)
			(layer "F.SilkS")
			(effects
				(font
					(size 1.905 1.4224)
					(thickness 0.1524)
				)
				(justify left)
			)
		)
		(fp_text user "+"
			(at -4.7752 -0.12065 0)
			(unlocked yes)
			(layer "F.Fab")
			(effects
				(font
					(size 1.905 1.4224)
					(thickness 0.1524)
				)
				(justify left)
			)
		)
		(fp_text user "-"
			(at 5.4102 0.29845 180)
			(unlocked yes)
			(layer "F.Fab")
			(effects
				(font
					(size 1.905 1.4224)
					(thickness 0.1524)
				)
				(justify left)
			)
		)
		(pad "A" smd rect
			(at -1.999996 0 90)
			(size 1.7018 2.5146)
			(layers "F.Cu" "F.Mask" "F.Paste")
			(net "GND")
		)
		(pad "C" smd rect
			(at 1.999996 0 90)
			(size 1.7018 2.5146)
			(layers "F.Cu" "F.Mask" "F.Paste")
			(net "P12V_NIC6_R")
		)
	)
	(footprint ""
		(layer "F.Cu")
		(at 204.591158 -82.643472)
		(property "Reference" "R4332"
			(at 0 0 0)
			(layer "F.SilkS")
			(hide yes)
			(effects
				(font
					(size 1.27 1.27)
				)
			)
		)
		(property "Value" ""
			(at 0 0 0)
			(layer "F.Fab")
			(effects
				(font
					(size 1.27 1.27)
				)
			)
		)
		(duplicate_pad_numbers_are_jumpers no)
		(fp_line
			(start -0.7874 -0.4064)
			(end 0.7874 -0.4064)
			(stroke
				(width 0.1524)
				(type default)
			)
			(layer "F.SilkS")
		)
		(fp_line
			(start -0.7874 0.4064)
			(end -0.7874 -0.4064)
			(stroke
				(width 0.1524)
				(type default)
			)
			(layer "F.SilkS")
		)
		(fp_line
			(start 0.7874 -0.4064)
			(end 0.7874 0.4064)
			(stroke
				(width 0.1524)
				(type default)
			)
			(layer "F.SilkS")
		)
		(fp_line
			(start 0.7874 0.4064)
			(end -0.7874 0.4064)
			(stroke
				(width 0.1524)
				(type default)
			)
			(layer "F.SilkS")
		)
		(fp_line
			(start -0.67945 -0.305054)
			(end -0.12065 -0.305054)
			(stroke
				(width 0.1)
				(type default)
			)
			(layer "F.Fab")
		)
		(fp_line
			(start -0.67945 0.3048)
			(end -0.67945 -0.305054)
			(stroke
				(width 0.1)
				(type default)
			)
			(layer "F.Fab")
		)
		(fp_line
			(start -0.12065 -0.305054)
			(end -0.12065 -0.2794)
			(stroke
				(width 0.1)
				(type default)
			)
			(layer "F.Fab")
		)
		(fp_line
			(start -0.12065 -0.2794)
			(end 0.12065 -0.2794)
			(stroke
				(width 0.1)
				(type default)
			)
			(layer "F.Fab")
		)
		(fp_line
			(start -0.12065 0.2794)
			(end -0.12065 0.3048)
			(stroke
				(width 0.1)
				(type default)
			)
			(layer "F.Fab")
		)
		(fp_line
			(start -0.12065 0.3048)
			(end -0.67945 0.3048)
			(stroke
				(width 0.1)
				(type default)
			)
			(layer "F.Fab")
		)
		(fp_line
			(start 0.120396 0.2794)
			(end -0.12065 0.2794)
			(stroke
				(width 0.1)
				(type default)
			)
			(layer "F.Fab")
		)
		(fp_line
			(start 0.120396 0.3048)
			(end 0.120396 0.2794)
			(stroke
				(width 0.1)
				(type default)
			)
			(layer "F.Fab")
		)
		(fp_line
			(start 0.12065 -0.3048)
			(end 0.67945 -0.3048)
			(stroke
				(width 0.1)
				(type default)
			)
			(layer "F.Fab")
		)
		(fp_line
			(start 0.12065 -0.2794)
			(end 0.12065 -0.3048)
			(stroke
				(width 0.1)
				(type default)
			)
			(layer "F.Fab")
		)
		(fp_line
			(start 0.67945 -0.3048)
			(end 0.67945 0.3048)
			(stroke
				(width 0.1)
				(type default)
			)
			(layer "F.Fab")
		)
		(fp_line
			(start 0.67945 0.3048)
			(end 0.120396 0.3048)
			(stroke
				(width 0.1)
				(type default)
			)
			(layer "F.Fab")
		)
		(pad "1" smd circle
			(at -0.40005 0)
			(size 0 0)
			(layers "F.Cu" "F.Mask" "F.Paste")
			(net "P3V3_AUX")
		)
		(pad "2" smd circle
			(at 0.40005 0)
			(size 0 0)
			(layers "F.Cu" "F.Mask" "F.Paste")
			(net "SSD2_LED_R")
		)
	)
	(footprint ""
		(layer "F.Cu")
		(at 214.454486 -216.270586)
		(property "Reference" "R4877"
			(at 0 0 0)
			(layer "F.SilkS")
			(hide yes)
			(effects
				(font
					(size 1.27 1.27)
				)
			)
		)
		(property "Value" ""
			(at 0 0 0)
			(layer "F.Fab")
			(effects
				(font
					(size 1.27 1.27)
				)
			)
		)
		(duplicate_pad_numbers_are_jumpers no)
		(fp_line
			(start -0.7874 -0.4064)
			(end 0.7874 -0.4064)
			(stroke
				(width 0.1524)
				(type default)
			)
			(layer "F.SilkS")
		)
		(fp_line
			(start -0.7874 0.4064)
			(end -0.7874 -0.4064)
			(stroke
				(width 0.1524)
				(type default)
			)
			(layer "F.SilkS")
		)
		(fp_line
			(start 0.7874 -0.4064)
			(end 0.7874 0.4064)
			(stroke
				(width 0.1524)
				(type default)
			)
			(layer "F.SilkS")
		)
		(fp_line
			(start 0.7874 0.4064)
			(end -0.7874 0.4064)
			(stroke
				(width 0.1524)
				(type default)
			)
			(layer "F.SilkS")
		)
		(fp_line
			(start -0.67945 -0.305054)
			(end -0.12065 -0.305054)
			(stroke
				(width 0.1)
				(type default)
			)
			(layer "F.Fab")
		)
		(fp_line
			(start -0.67945 0.3048)
			(end -0.67945 -0.305054)
			(stroke
				(width 0.1)
				(type default)
			)
			(layer "F.Fab")
		)
		(fp_line
			(start -0.12065 -0.305054)
			(end -0.12065 -0.2794)
			(stroke
				(width 0.1)
				(type default)
			)
			(layer "F.Fab")
		)
		(fp_line
			(start -0.12065 -0.2794)
			(end 0.12065 -0.2794)
			(stroke
				(width 0.1)
				(type default)
			)
			(layer "F.Fab")
		)
		(fp_line
			(start -0.12065 0.2794)
			(end -0.12065 0.3048)
			(stroke
				(width 0.1)
				(type default)
			)
			(layer "F.Fab")
		)
		(fp_line
			(start -0.12065 0.3048)
			(end -0.67945 0.3048)
			(stroke
				(width 0.1)
				(type default)
			)
			(layer "F.Fab")
		)
		(fp_line
			(start 0.120396 0.2794)
			(end -0.12065 0.2794)
			(stroke
				(width 0.1)
				(type default)
			)
			(layer "F.Fab")
		)
		(fp_line
			(start 0.120396 0.3048)
			(end 0.120396 0.2794)
			(stroke
				(width 0.1)
				(type default)
			)
			(layer "F.Fab")
		)
		(fp_line
			(start 0.12065 -0.3048)
			(end 0.67945 -0.3048)
			(stroke
				(width 0.1)
				(type default)
			)
			(layer "F.Fab")
		)
		(fp_line
			(start 0.12065 -0.2794)
			(end 0.12065 -0.3048)
			(stroke
				(width 0.1)
				(type default)
			)
			(layer "F.Fab")
		)
		(fp_line
			(start 0.67945 -0.3048)
			(end 0.67945 0.3048)
			(stroke
				(width 0.1)
				(type default)
			)
			(layer "F.Fab")
		)
		(fp_line
			(start 0.67945 0.3048)
			(end 0.120396 0.3048)
			(stroke
				(width 0.1)
				(type default)
			)
			(layer "F.Fab")
		)
		(pad "1" smd circle
			(at -0.40005 0)
			(size 0 0)
			(layers "F.Cu" "F.Mask" "F.Paste")
			(net "P1V2_AUX")
		)
		(pad "2" smd circle
			(at 0.40005 0)
			(size 0 0)
			(layers "F.Cu" "F.Mask" "F.Paste")
			(net "SMB_NIC6_SCL")
		)
	)
	(footprint ""
		(layer "F.Cu")
		(at 368.475006 -48.753014 180)
		(property "Reference" "C333"
			(at 0 0 180)
			(layer "F.SilkS")
			(hide yes)
			(effects
				(font
					(size 1.27 1.27)
				)
			)
		)
		(property "Value" ""
			(at 0 0 180)
			(layer "F.Fab")
			(effects
				(font
					(size 1.27 1.27)
				)
			)
		)
		(duplicate_pad_numbers_are_jumpers no)
		(fp_line
			(start 0.7874 0.4064)
			(end -0.7874 0.4064)
			(stroke
				(width 0.1524)
				(type default)
			)
			(layer "F.SilkS")
		)
		(fp_line
			(start 0.7874 -0.4064)
			(end 0.7874 0.4064)
			(stroke
				(width 0.1524)
				(type default)
			)
			(layer "F.SilkS")
		)
		(fp_line
			(start -0.7874 0.4064)
			(end -0.7874 -0.4064)
			(stroke
				(width 0.1524)
				(type default)
			)
			(layer "F.SilkS")
		)
		(fp_line
			(start -0.7874 -0.4064)
			(end 0.7874 -0.4064)
			(stroke
				(width 0.1524)
				(type default)
			)
			(layer "F.SilkS")
		)
		(fp_line
			(start 0.67945 0.3048)
			(end 0.120396 0.3048)
			(stroke
				(width 0.1)
				(type default)
			)
			(layer "F.Fab")
		)
		(fp_line
			(start 0.67945 -0.3048)
			(end 0.67945 0.3048)
			(stroke
				(width 0.1)
				(type default)
			)
			(layer "F.Fab")
		)
		(fp_line
			(start 0.12065 -0.2794)
			(end 0.12065 -0.3048)
			(stroke
				(width 0.1)
				(type default)
			)
			(layer "F.Fab")
		)
		(fp_line
			(start 0.12065 -0.3048)
			(end 0.67945 -0.3048)
			(stroke
				(width 0.1)
				(type default)
			)
			(layer "F.Fab")
		)
		(fp_line
			(start 0.120396 0.3048)
			(end 0.120396 0.2794)
			(stroke
				(width 0.1)
				(type default)
			)
			(layer "F.Fab")
		)
		(fp_line
			(start 0.120396 0.2794)
			(end -0.12065 0.2794)
			(stroke
				(width 0.1)
				(type default)
			)
			(layer "F.Fab")
		)
		(fp_line
			(start -0.12065 0.3048)
			(end -0.67945 0.3048)
			(stroke
				(width 0.1)
				(type default)
			)
			(layer "F.Fab")
		)
		(fp_line
			(start -0.12065 0.2794)
			(end -0.12065 0.3048)
			(stroke
				(width 0.1)
				(type default)
			)
			(layer "F.Fab")
		)
		(fp_line
			(start -0.12065 -0.2794)
			(end 0.12065 -0.2794)
			(stroke
				(width 0.1)
				(type default)
			)
			(layer "F.Fab")
		)
		(fp_line
			(start -0.12065 -0.305054)
			(end -0.12065 -0.2794)
			(stroke
				(width 0.1)
				(type default)
			)
			(layer "F.Fab")
		)
		(fp_line
			(start -0.67945 0.3048)
			(end -0.67945 -0.305054)
			(stroke
				(width 0.1)
				(type default)
			)
			(layer "F.Fab")
		)
		(fp_line
			(start -0.67945 -0.305054)
			(end -0.12065 -0.305054)
			(stroke
				(width 0.1)
				(type default)
			)
			(layer "F.Fab")
		)
		(pad "1" smd circle
			(at -0.40005 0 180)
			(size 0 0)
			(layers "F.Cu" "F.Mask" "F.Paste")
			(net "P3V3_AUX")
		)
		(pad "2" smd circle
			(at 0.40005 0 180)
			(size 0 0)
			(layers "F.Cu" "F.Mask" "F.Paste")
			(net "GND")
		)
	)
	(footprint ""
		(layer "F.Cu")
		(at 378.852684 -83.1088)
		(property "Reference" "R1775"
			(at 0 0 0)
			(layer "F.SilkS")
			(hide yes)
			(effects
				(font
					(size 1.27 1.27)
				)
			)
		)
		(property "Value" ""
			(at 0 0 0)
			(layer "F.Fab")
			(effects
				(font
					(size 1.27 1.27)
				)
			)
		)
		(duplicate_pad_numbers_are_jumpers no)
		(fp_line
			(start -0.7874 -0.4064)
			(end 0.7874 -0.4064)
			(stroke
				(width 0.1524)
				(type default)
			)
			(layer "F.SilkS")
		)
		(fp_line
			(start -0.7874 0.4064)
			(end -0.7874 -0.4064)
			(stroke
				(width 0.1524)
				(type default)
			)
			(layer "F.SilkS")
		)
		(fp_line
			(start 0.7874 -0.4064)
			(end 0.7874 0.4064)
			(stroke
				(width 0.1524)
				(type default)
			)
			(layer "F.SilkS")
		)
		(fp_line
			(start 0.7874 0.4064)
			(end -0.7874 0.4064)
			(stroke
				(width 0.1524)
				(type default)
			)
			(layer "F.SilkS")
		)
		(fp_line
			(start -0.67945 -0.305054)
			(end -0.12065 -0.305054)
			(stroke
				(width 0.1)
				(type default)
			)
			(layer "F.Fab")
		)
		(fp_line
			(start -0.67945 0.3048)
			(end -0.67945 -0.305054)
			(stroke
				(width 0.1)
				(type default)
			)
			(layer "F.Fab")
		)
		(fp_line
			(start -0.12065 -0.305054)
			(end -0.12065 -0.2794)
			(stroke
				(width 0.1)
				(type default)
			)
			(layer "F.Fab")
		)
		(fp_line
			(start -0.12065 -0.2794)
			(end 0.12065 -0.2794)
			(stroke
				(width 0.1)
				(type default)
			)
			(layer "F.Fab")
		)
		(fp_line
			(start -0.12065 0.2794)
			(end -0.12065 0.3048)
			(stroke
				(width 0.1)
				(type default)
			)
			(layer "F.Fab")
		)
		(fp_line
			(start -0.12065 0.3048)
			(end -0.67945 0.3048)
			(stroke
				(width 0.1)
				(type default)
			)
			(layer "F.Fab")
		)
		(fp_line
			(start 0.120396 0.2794)
			(end -0.12065 0.2794)
			(stroke
				(width 0.1)
				(type default)
			)
			(layer "F.Fab")
		)
		(fp_line
			(start 0.120396 0.3048)
			(end 0.120396 0.2794)
			(stroke
				(width 0.1)
				(type default)
			)
			(layer "F.Fab")
		)
		(fp_line
			(start 0.12065 -0.3048)
			(end 0.67945 -0.3048)
			(stroke
				(width 0.1)
				(type default)
			)
			(layer "F.Fab")
		)
		(fp_line
			(start 0.12065 -0.2794)
			(end 0.12065 -0.3048)
			(stroke
				(width 0.1)
				(type default)
			)
			(layer "F.Fab")
		)
		(fp_line
			(start 0.67945 -0.3048)
			(end 0.67945 0.3048)
			(stroke
				(width 0.1)
				(type default)
			)
			(layer "F.Fab")
		)
		(fp_line
			(start 0.67945 0.3048)
			(end 0.120396 0.3048)
			(stroke
				(width 0.1)
				(type default)
			)
			(layer "F.Fab")
		)
		(pad "1" smd circle
			(at -0.40005 0)
			(size 0 0)
			(layers "F.Cu" "F.Mask" "F.Paste")
			(net "SMB_BIC_I2C6_MUX_THERMAL_R_SCL")
		)
		(pad "2" smd circle
			(at 0.40005 0)
			(size 0 0)
			(layers "F.Cu" "F.Mask" "F.Paste")
			(net "SMB_BIC_I2C6_MUX_THERMAL_SCL")
		)
	)
	(footprint ""
		(layer "F.Cu")
		(at 136.445244 -88.956642 180)
		(property "Reference" "R1578"
			(at 0 0 180)
			(layer "F.SilkS")
			(hide yes)
			(effects
				(font
					(size 1.27 1.27)
				)
			)
		)
		(property "Value" ""
			(at 0 0 180)
			(layer "F.Fab")
			(effects
				(font
					(size 1.27 1.27)
				)
			)
		)
		(duplicate_pad_numbers_are_jumpers no)
		(fp_line
			(start 0.7874 0.4064)
			(end -0.7874 0.4064)
			(stroke
				(width 0.1524)
				(type default)
			)
			(layer "F.SilkS")
		)
		(fp_line
			(start 0.7874 -0.4064)
			(end 0.7874 0.4064)
			(stroke
				(width 0.1524)
				(type default)
			)
			(layer "F.SilkS")
		)
		(fp_line
			(start -0.7874 0.4064)
			(end -0.7874 -0.4064)
			(stroke
				(width 0.1524)
				(type default)
			)
			(layer "F.SilkS")
		)
		(fp_line
			(start -0.7874 -0.4064)
			(end 0.7874 -0.4064)
			(stroke
				(width 0.1524)
				(type default)
			)
			(layer "F.SilkS")
		)
		(fp_line
			(start 0.67945 0.3048)
			(end 0.120396 0.3048)
			(stroke
				(width 0.1)
				(type default)
			)
			(layer "F.Fab")
		)
		(fp_line
			(start 0.67945 -0.3048)
			(end 0.67945 0.3048)
			(stroke
				(width 0.1)
				(type default)
			)
			(layer "F.Fab")
		)
		(fp_line
			(start 0.12065 -0.2794)
			(end 0.12065 -0.3048)
			(stroke
				(width 0.1)
				(type default)
			)
			(layer "F.Fab")
		)
		(fp_line
			(start 0.12065 -0.3048)
			(end 0.67945 -0.3048)
			(stroke
				(width 0.1)
				(type default)
			)
			(layer "F.Fab")
		)
		(fp_line
			(start 0.120396 0.3048)
			(end 0.120396 0.2794)
			(stroke
				(width 0.1)
				(type default)
			)
			(layer "F.Fab")
		)
		(fp_line
			(start 0.120396 0.2794)
			(end -0.12065 0.2794)
			(stroke
				(width 0.1)
				(type default)
			)
			(layer "F.Fab")
		)
		(fp_line
			(start -0.12065 0.3048)
			(end -0.67945 0.3048)
			(stroke
				(width 0.1)
				(type default)
			)
			(layer "F.Fab")
		)
		(fp_line
			(start -0.12065 0.2794)
			(end -0.12065 0.3048)
			(stroke
				(width 0.1)
				(type default)
			)
			(layer "F.Fab")
		)
		(fp_line
			(start -0.12065 -0.2794)
			(end 0.12065 -0.2794)
			(stroke
				(width 0.1)
				(type default)
			)
			(layer "F.Fab")
		)
		(fp_line
			(start -0.12065 -0.305054)
			(end -0.12065 -0.2794)
			(stroke
				(width 0.1)
				(type default)
			)
			(layer "F.Fab")
		)
		(fp_line
			(start -0.67945 0.3048)
			(end -0.67945 -0.305054)
			(stroke
				(width 0.1)
				(type default)
			)
			(layer "F.Fab")
		)
		(fp_line
			(start -0.67945 -0.305054)
			(end -0.12065 -0.305054)
			(stroke
				(width 0.1)
				(type default)
			)
			(layer "F.Fab")
		)
		(pad "1" smd circle
			(at -0.40005 0 180)
			(size 0 0)
			(layers "F.Cu" "F.Mask" "F.Paste")
			(net "SMB_BIC_I2C9_MUX0_SSD4_R_SCL")
		)
		(pad "2" smd circle
			(at 0.40005 0 180)
			(size 0 0)
			(layers "F.Cu" "F.Mask" "F.Paste")
			(net "SMB_BIC_I2C9_MUX0_SSD4_SCL")
		)
	)
	(footprint ""
		(layer "F.Cu")
		(at 154.707844 -156.3624 180)
		(property "Reference" "R115"
			(at 0 0 180)
			(layer "F.SilkS")
			(hide yes)
			(effects
				(font
					(size 1.27 1.27)
				)
			)
		)
		(property "Value" ""
			(at 0 0 180)
			(layer "F.Fab")
			(effects
				(font
					(size 1.27 1.27)
				)
			)
		)
		(duplicate_pad_numbers_are_jumpers no)
		(fp_line
			(start 0.7874 0.4064)
			(end -0.7874 0.4064)
			(stroke
				(width 0.1524)
				(type default)
			)
			(layer "F.SilkS")
		)
		(fp_line
			(start 0.7874 -0.4064)
			(end 0.7874 0.4064)
			(stroke
				(width 0.1524)
				(type default)
			)
			(layer "F.SilkS")
		)
		(fp_line
			(start -0.7874 0.4064)
			(end -0.7874 -0.4064)
			(stroke
				(width 0.1524)
				(type default)
			)
			(layer "F.SilkS")
		)
		(fp_line
			(start -0.7874 -0.4064)
			(end 0.7874 -0.4064)
			(stroke
				(width 0.1524)
				(type default)
			)
			(layer "F.SilkS")
		)
		(fp_line
			(start 0.67945 0.3048)
			(end 0.120396 0.3048)
			(stroke
				(width 0.1)
				(type default)
			)
			(layer "F.Fab")
		)
		(fp_line
			(start 0.67945 -0.3048)
			(end 0.67945 0.3048)
			(stroke
				(width 0.1)
				(type default)
			)
			(layer "F.Fab")
		)
		(fp_line
			(start 0.12065 -0.2794)
			(end 0.12065 -0.3048)
			(stroke
				(width 0.1)
				(type default)
			)
			(layer "F.Fab")
		)
		(fp_line
			(start 0.12065 -0.3048)
			(end 0.67945 -0.3048)
			(stroke
				(width 0.1)
				(type default)
			)
			(layer "F.Fab")
		)
		(fp_line
			(start 0.120396 0.3048)
			(end 0.120396 0.2794)
			(stroke
				(width 0.1)
				(type default)
			)
			(layer "F.Fab")
		)
		(fp_line
			(start 0.120396 0.2794)
			(end -0.12065 0.2794)
			(stroke
				(width 0.1)
				(type default)
			)
			(layer "F.Fab")
		)
		(fp_line
			(start -0.12065 0.3048)
			(end -0.67945 0.3048)
			(stroke
				(width 0.1)
				(type default)
			)
			(layer "F.Fab")
		)
		(fp_line
			(start -0.12065 0.2794)
			(end -0.12065 0.3048)
			(stroke
				(width 0.1)
				(type default)
			)
			(layer "F.Fab")
		)
		(fp_line
			(start -0.12065 -0.2794)
			(end 0.12065 -0.2794)
			(stroke
				(width 0.1)
				(type default)
			)
			(layer "F.Fab")
		)
		(fp_line
			(start -0.12065 -0.305054)
			(end -0.12065 -0.2794)
			(stroke
				(width 0.1)
				(type default)
			)
			(layer "F.Fab")
		)
		(fp_line
			(start -0.67945 0.3048)
			(end -0.67945 -0.305054)
			(stroke
				(width 0.1)
				(type default)
			)
			(layer "F.Fab")
		)
		(fp_line
			(start -0.67945 -0.305054)
			(end -0.12065 -0.305054)
			(stroke
				(width 0.1)
				(type default)
			)
			(layer "F.Fab")
		)
		(pad "1" smd circle
			(at -0.40005 0 180)
			(size 0 0)
			(layers "F.Cu" "F.Mask" "F.Paste")
			(net "NIC2_DATA_OUT")
		)
		(pad "2" smd circle
			(at 0.40005 0 180)
			(size 0 0)
			(layers "F.Cu" "F.Mask" "F.Paste")
			(net "GND")
		)
	)
	(footprint ""
		(layer "F.Cu")
		(at 113.561114 -261.687564 180)
		(property "Reference" "PR84"
			(at 0 0 180)
			(layer "F.SilkS")
			(hide yes)
			(effects
				(font
					(size 1.27 1.27)
				)
			)
		)
		(property "Value" ""
			(at 0 0 180)
			(layer "F.Fab")
			(effects
				(font
					(size 1.27 1.27)
				)
			)
		)
		(duplicate_pad_numbers_are_jumpers no)
		(fp_line
			(start 0.7874 0.4064)
			(end -0.7874 0.4064)
			(stroke
				(width 0.1524)
				(type default)
			)
			(layer "F.SilkS")
		)
		(fp_line
			(start 0.7874 -0.4064)
			(end 0.7874 0.4064)
			(stroke
				(width 0.1524)
				(type default)
			)
			(layer "F.SilkS")
		)
		(fp_line
			(start -0.7874 0.4064)
			(end -0.7874 -0.4064)
			(stroke
				(width 0.1524)
				(type default)
			)
			(layer "F.SilkS")
		)
		(fp_line
			(start -0.7874 -0.4064)
			(end 0.7874 -0.4064)
			(stroke
				(width 0.1524)
				(type default)
			)
			(layer "F.SilkS")
		)
		(fp_line
			(start 0.67945 0.3048)
			(end 0.120396 0.3048)
			(stroke
				(width 0.1)
				(type default)
			)
			(layer "F.Fab")
		)
		(fp_line
			(start 0.67945 -0.3048)
			(end 0.67945 0.3048)
			(stroke
				(width 0.1)
				(type default)
			)
			(layer "F.Fab")
		)
		(fp_line
			(start 0.12065 -0.2794)
			(end 0.12065 -0.3048)
			(stroke
				(width 0.1)
				(type default)
			)
			(layer "F.Fab")
		)
		(fp_line
			(start 0.12065 -0.3048)
			(end 0.67945 -0.3048)
			(stroke
				(width 0.1)
				(type default)
			)
			(layer "F.Fab")
		)
		(fp_line
			(start 0.120396 0.3048)
			(end 0.120396 0.2794)
			(stroke
				(width 0.1)
				(type default)
			)
			(layer "F.Fab")
		)
		(fp_line
			(start 0.120396 0.2794)
			(end -0.12065 0.2794)
			(stroke
				(width 0.1)
				(type default)
			)
			(layer "F.Fab")
		)
		(fp_line
			(start -0.12065 0.3048)
			(end -0.67945 0.3048)
			(stroke
				(width 0.1)
				(type default)
			)
			(layer "F.Fab")
		)
		(fp_line
			(start -0.12065 0.2794)
			(end -0.12065 0.3048)
			(stroke
				(width 0.1)
				(type default)
			)
			(layer "F.Fab")
		)
		(fp_line
			(start -0.12065 -0.2794)
			(end 0.12065 -0.2794)
			(stroke
				(width 0.1)
				(type default)
			)
			(layer "F.Fab")
		)
		(fp_line
			(start -0.12065 -0.305054)
			(end -0.12065 -0.2794)
			(stroke
				(width 0.1)
				(type default)
			)
			(layer "F.Fab")
		)
		(fp_line
			(start -0.67945 0.3048)
			(end -0.67945 -0.305054)
			(stroke
				(width 0.1)
				(type default)
			)
			(layer "F.Fab")
		)
		(fp_line
			(start -0.67945 -0.305054)
			(end -0.12065 -0.305054)
			(stroke
				(width 0.1)
				(type default)
			)
			(layer "F.Fab")
		)
		(pad "1" smd circle
			(at -0.40005 0 180)
			(size 0 0)
			(layers "F.Cu" "F.Mask" "F.Paste")
			(net "P0V8_PEX0_VR_CONFIG")
		)
		(pad "2" smd circle
			(at 0.40005 0 180)
			(size 0 0)
			(layers "F.Cu" "F.Mask" "F.Paste")
			(net "GND")
		)
	)
	(footprint ""
		(layer "F.Cu")
		(at 208.286858 -220.79077 90)
		(property "Reference" "C3644"
			(at 0 0 90)
			(layer "F.SilkS")
			(hide yes)
			(effects
				(font
					(size 1.27 1.27)
				)
			)
		)
		(property "Value" ""
			(at 0 0 90)
			(layer "F.Fab")
			(effects
				(font
					(size 1.27 1.27)
				)
			)
		)
		(duplicate_pad_numbers_are_jumpers no)
		(fp_line
			(start 0.7874 -0.4064)
			(end 0.7874 0.4064)
			(stroke
				(width 0.1524)
				(type default)
			)
			(layer "F.SilkS")
		)
		(fp_line
			(start -0.7874 -0.4064)
			(end 0.7874 -0.4064)
			(stroke
				(width 0.1524)
				(type default)
			)
			(layer "F.SilkS")
		)
		(fp_line
			(start 0.7874 0.4064)
			(end -0.7874 0.4064)
			(stroke
				(width 0.1524)
				(type default)
			)
			(layer "F.SilkS")
		)
		(fp_line
			(start -0.7874 0.4064)
			(end -0.7874 -0.4064)
			(stroke
				(width 0.1524)
				(type default)
			)
			(layer "F.SilkS")
		)
		(fp_line
			(start -0.12065 -0.305054)
			(end -0.12065 -0.2794)
			(stroke
				(width 0.1)
				(type default)
			)
			(layer "F.Fab")
		)
		(fp_line
			(start -0.67945 -0.305054)
			(end -0.12065 -0.305054)
			(stroke
				(width 0.1)
				(type default)
			)
			(layer "F.Fab")
		)
		(fp_line
			(start 0.67945 -0.3048)
			(end 0.67945 0.3048)
			(stroke
				(width 0.1)
				(type default)
			)
			(layer "F.Fab")
		)
		(fp_line
			(start 0.12065 -0.3048)
			(end 0.67945 -0.3048)
			(stroke
				(width 0.1)
				(type default)
			)
			(layer "F.Fab")
		)
		(fp_line
			(start 0.12065 -0.2794)
			(end 0.12065 -0.3048)
			(stroke
				(width 0.1)
				(type default)
			)
			(layer "F.Fab")
		)
		(fp_line
			(start -0.12065 -0.2794)
			(end 0.12065 -0.2794)
			(stroke
				(width 0.1)
				(type default)
			)
			(layer "F.Fab")
		)
		(fp_line
			(start 0.120396 0.2794)
			(end -0.12065 0.2794)
			(stroke
				(width 0.1)
				(type default)
			)
			(layer "F.Fab")
		)
		(fp_line
			(start -0.12065 0.2794)
			(end -0.12065 0.3048)
			(stroke
				(width 0.1)
				(type default)
			)
			(layer "F.Fab")
		)
		(fp_line
			(start 0.67945 0.3048)
			(end 0.120396 0.3048)
			(stroke
				(width 0.1)
				(type default)
			)
			(layer "F.Fab")
		)
		(fp_line
			(start 0.120396 0.3048)
			(end 0.120396 0.2794)
			(stroke
				(width 0.1)
				(type default)
			)
			(layer "F.Fab")
		)
		(fp_line
			(start -0.12065 0.3048)
			(end -0.67945 0.3048)
			(stroke
				(width 0.1)
				(type default)
			)
			(layer "F.Fab")
		)
		(fp_line
			(start -0.67945 0.3048)
			(end -0.67945 -0.305054)
			(stroke
				(width 0.1)
				(type default)
			)
			(layer "F.Fab")
		)
		(pad "1" smd circle
			(at -0.40005 0 90)
			(size 0 0)
			(layers "F.Cu" "F.Mask" "F.Paste")
			(net "GND")
		)
		(pad "2" smd circle
			(at 0.40005 0 90)
			(size 0 0)
			(layers "F.Cu" "F.Mask" "F.Paste")
			(net "P3V3_AUX")
		)
	)
	(footprint ""
		(layer "F.Cu")
		(at 5.04317 -34.896298 90)
		(property "Reference" "R1631"
			(at 0 0 90)
			(layer "F.SilkS")
			(hide yes)
			(effects
				(font
					(size 1.27 1.27)
				)
			)
		)
		(property "Value" ""
			(at 0 0 90)
			(layer "F.Fab")
			(effects
				(font
					(size 1.27 1.27)
				)
			)
		)
		(duplicate_pad_numbers_are_jumpers no)
		(fp_line
			(start 0.7874 -0.4064)
			(end 0.7874 0.4064)
			(stroke
				(width 0.1524)
				(type default)
			)
			(layer "F.SilkS")
		)
		(fp_line
			(start -0.7874 -0.4064)
			(end 0.7874 -0.4064)
			(stroke
				(width 0.1524)
				(type default)
			)
			(layer "F.SilkS")
		)
		(fp_line
			(start 0.7874 0.4064)
			(end -0.7874 0.4064)
			(stroke
				(width 0.1524)
				(type default)
			)
			(layer "F.SilkS")
		)
		(fp_line
			(start -0.7874 0.4064)
			(end -0.7874 -0.4064)
			(stroke
				(width 0.1524)
				(type default)
			)
			(layer "F.SilkS")
		)
		(fp_line
			(start -0.12065 -0.305054)
			(end -0.12065 -0.2794)
			(stroke
				(width 0.1)
				(type default)
			)
			(layer "F.Fab")
		)
		(fp_line
			(start -0.67945 -0.305054)
			(end -0.12065 -0.305054)
			(stroke
				(width 0.1)
				(type default)
			)
			(layer "F.Fab")
		)
		(fp_line
			(start 0.67945 -0.3048)
			(end 0.67945 0.3048)
			(stroke
				(width 0.1)
				(type default)
			)
			(layer "F.Fab")
		)
		(fp_line
			(start 0.12065 -0.3048)
			(end 0.67945 -0.3048)
			(stroke
				(width 0.1)
				(type default)
			)
			(layer "F.Fab")
		)
		(fp_line
			(start 0.12065 -0.2794)
			(end 0.12065 -0.3048)
			(stroke
				(width 0.1)
				(type default)
			)
			(layer "F.Fab")
		)
		(fp_line
			(start -0.12065 -0.2794)
			(end 0.12065 -0.2794)
			(stroke
				(width 0.1)
				(type default)
			)
			(layer "F.Fab")
		)
		(fp_line
			(start 0.120396 0.2794)
			(end -0.12065 0.2794)
			(stroke
				(width 0.1)
				(type default)
			)
			(layer "F.Fab")
		)
		(fp_line
			(start -0.12065 0.2794)
			(end -0.12065 0.3048)
			(stroke
				(width 0.1)
				(type default)
			)
			(layer "F.Fab")
		)
		(fp_line
			(start 0.67945 0.3048)
			(end 0.120396 0.3048)
			(stroke
				(width 0.1)
				(type default)
			)
			(layer "F.Fab")
		)
		(fp_line
			(start 0.120396 0.3048)
			(end 0.120396 0.2794)
			(stroke
				(width 0.1)
				(type default)
			)
			(layer "F.Fab")
		)
		(fp_line
			(start -0.12065 0.3048)
			(end -0.67945 0.3048)
			(stroke
				(width 0.1)
				(type default)
			)
			(layer "F.Fab")
		)
		(fp_line
			(start -0.67945 0.3048)
			(end -0.67945 -0.305054)
			(stroke
				(width 0.1)
				(type default)
			)
			(layer "F.Fab")
		)
		(pad "1" smd circle
			(at -0.40005 0 90)
			(size 0 0)
			(layers "F.Cu" "F.Mask" "F.Paste")
			(net "SMB_SSD0_ISO_EN")
		)
		(pad "2" smd circle
			(at 0.40005 0 90)
			(size 0 0)
			(layers "F.Cu" "F.Mask" "F.Paste")
			(net "P3V3_AUX")
		)
	)
	(footprint ""
		(layer "F.Cu")
		(at 29.872178 -32.848042 90)
		(property "Reference" "PC672"
			(at 0 0 90)
			(layer "F.SilkS")
			(hide yes)
			(effects
				(font
					(size 1.27 1.27)
				)
			)
		)
		(property "Value" ""
			(at 0 0 90)
			(layer "F.Fab")
			(effects
				(font
					(size 1.27 1.27)
				)
			)
		)
		(duplicate_pad_numbers_are_jumpers no)
		(fp_line
			(start 0.7874 -0.4064)
			(end 0.7874 0.4064)
			(stroke
				(width 0.1524)
				(type default)
			)
			(layer "F.SilkS")
		)
		(fp_line
			(start -0.7874 -0.4064)
			(end 0.7874 -0.4064)
			(stroke
				(width 0.1524)
				(type default)
			)
			(layer "F.SilkS")
		)
		(fp_line
			(start 0.7874 0.4064)
			(end -0.7874 0.4064)
			(stroke
				(width 0.1524)
				(type default)
			)
			(layer "F.SilkS")
		)
		(fp_line
			(start -0.7874 0.4064)
			(end -0.7874 -0.4064)
			(stroke
				(width 0.1524)
				(type default)
			)
			(layer "F.SilkS")
		)
		(fp_line
			(start -0.12065 -0.305054)
			(end -0.12065 -0.2794)
			(stroke
				(width 0.1)
				(type default)
			)
			(layer "F.Fab")
		)
		(fp_line
			(start -0.67945 -0.305054)
			(end -0.12065 -0.305054)
			(stroke
				(width 0.1)
				(type default)
			)
			(layer "F.Fab")
		)
		(fp_line
			(start 0.67945 -0.3048)
			(end 0.67945 0.3048)
			(stroke
				(width 0.1)
				(type default)
			)
			(layer "F.Fab")
		)
		(fp_line
			(start 0.12065 -0.3048)
			(end 0.67945 -0.3048)
			(stroke
				(width 0.1)
				(type default)
			)
			(layer "F.Fab")
		)
		(fp_line
			(start 0.12065 -0.2794)
			(end 0.12065 -0.3048)
			(stroke
				(width 0.1)
				(type default)
			)
			(layer "F.Fab")
		)
		(fp_line
			(start -0.12065 -0.2794)
			(end 0.12065 -0.2794)
			(stroke
				(width 0.1)
				(type default)
			)
			(layer "F.Fab")
		)
		(fp_line
			(start 0.120396 0.2794)
			(end -0.12065 0.2794)
			(stroke
				(width 0.1)
				(type default)
			)
			(layer "F.Fab")
		)
		(fp_line
			(start -0.12065 0.2794)
			(end -0.12065 0.3048)
			(stroke
				(width 0.1)
				(type default)
			)
			(layer "F.Fab")
		)
		(fp_line
			(start 0.67945 0.3048)
			(end 0.120396 0.3048)
			(stroke
				(width 0.1)
				(type default)
			)
			(layer "F.Fab")
		)
		(fp_line
			(start 0.120396 0.3048)
			(end 0.120396 0.2794)
			(stroke
				(width 0.1)
				(type default)
			)
			(layer "F.Fab")
		)
		(fp_line
			(start -0.12065 0.3048)
			(end -0.67945 0.3048)
			(stroke
				(width 0.1)
				(type default)
			)
			(layer "F.Fab")
		)
		(fp_line
			(start -0.67945 0.3048)
			(end -0.67945 -0.305054)
			(stroke
				(width 0.1)
				(type default)
			)
			(layer "F.Fab")
		)
		(pad "1" smd circle
			(at -0.40005 0 90)
			(size 0 0)
			(layers "F.Cu" "F.Mask" "F.Paste")
			(net "P3V3_SSD1_CO_GATE")
		)
		(pad "2" smd circle
			(at 0.40005 0 90)
			(size 0 0)
			(layers "F.Cu" "F.Mask" "F.Paste")
			(net "GND")
		)
	)
	(footprint ""
		(layer "F.Cu")
		(at 136.708388 -350.098614 90)
		(property "Reference" "C2265"
			(at 0 0 90)
			(layer "F.SilkS")
			(hide yes)
			(effects
				(font
					(size 1.27 1.27)
				)
			)
		)
		(property "Value" ""
			(at 0 0 90)
			(layer "F.Fab")
			(effects
				(font
					(size 1.27 1.27)
				)
			)
		)
		(duplicate_pad_numbers_are_jumpers no)
		(fp_line
			(start 0.299974 -0.150114)
			(end 0.299974 0.150114)
			(stroke
				(width 0.1)
				(type default)
			)
			(layer "F.Fab")
		)
		(fp_line
			(start -0.299974 -0.150114)
			(end 0.299974 -0.150114)
			(stroke
				(width 0.1)
				(type default)
			)
			(layer "F.Fab")
		)
		(fp_line
			(start 0.299974 0.150114)
			(end -0.299974 0.150114)
			(stroke
				(width 0.1)
				(type default)
			)
			(layer "F.Fab")
		)
		(fp_line
			(start -0.299974 0.150114)
			(end -0.299974 -0.150114)
			(stroke
				(width 0.1)
				(type default)
			)
			(layer "F.Fab")
		)
		(pad "1" smd rect
			(at -0.2667 0 90)
			(size 0.3048 0.381)
			(layers "F.Cu" "F.Mask" "F.Paste")
			(net "P5E_PEX1_STN5_TX_DP<84>")
		)
		(pad "2" smd rect
			(at 0.2667 0 90)
			(size 0.3048 0.381)
			(layers "F.Cu" "F.Mask" "F.Paste")
			(net "P5E_PEX1_STN5_TX_C_DP<84>")
		)
	)
	(footprint ""
		(layer "F.Cu")
		(at 323.917818 -220.849698 180)
		(property "Reference" "R2982"
			(at 0 0 180)
			(layer "F.SilkS")
			(hide yes)
			(effects
				(font
					(size 1.27 1.27)
				)
			)
		)
		(property "Value" ""
			(at 0 0 180)
			(layer "F.Fab")
			(effects
				(font
					(size 1.27 1.27)
				)
			)
		)
		(duplicate_pad_numbers_are_jumpers no)
		(fp_line
			(start 0.7874 0.4064)
			(end -0.7874 0.4064)
			(stroke
				(width 0.1524)
				(type default)
			)
			(layer "F.SilkS")
		)
		(fp_line
			(start 0.7874 -0.4064)
			(end 0.7874 0.4064)
			(stroke
				(width 0.1524)
				(type default)
			)
			(layer "F.SilkS")
		)
		(fp_line
			(start -0.7874 0.4064)
			(end -0.7874 -0.4064)
			(stroke
				(width 0.1524)
				(type default)
			)
			(layer "F.SilkS")
		)
		(fp_line
			(start -0.7874 -0.4064)
			(end 0.7874 -0.4064)
			(stroke
				(width 0.1524)
				(type default)
			)
			(layer "F.SilkS")
		)
		(fp_line
			(start 0.67945 0.3048)
			(end 0.120396 0.3048)
			(stroke
				(width 0.1)
				(type default)
			)
			(layer "F.Fab")
		)
		(fp_line
			(start 0.67945 -0.3048)
			(end 0.67945 0.3048)
			(stroke
				(width 0.1)
				(type default)
			)
			(layer "F.Fab")
		)
		(fp_line
			(start 0.12065 -0.2794)
			(end 0.12065 -0.3048)
			(stroke
				(width 0.1)
				(type default)
			)
			(layer "F.Fab")
		)
		(fp_line
			(start 0.12065 -0.3048)
			(end 0.67945 -0.3048)
			(stroke
				(width 0.1)
				(type default)
			)
			(layer "F.Fab")
		)
		(fp_line
			(start 0.120396 0.3048)
			(end 0.120396 0.2794)
			(stroke
				(width 0.1)
				(type default)
			)
			(layer "F.Fab")
		)
		(fp_line
			(start 0.120396 0.2794)
			(end -0.12065 0.2794)
			(stroke
				(width 0.1)
				(type default)
			)
			(layer "F.Fab")
		)
		(fp_line
			(start -0.12065 0.3048)
			(end -0.67945 0.3048)
			(stroke
				(width 0.1)
				(type default)
			)
			(layer "F.Fab")
		)
		(fp_line
			(start -0.12065 0.2794)
			(end -0.12065 0.3048)
			(stroke
				(width 0.1)
				(type default)
			)
			(layer "F.Fab")
		)
		(fp_line
			(start -0.12065 -0.2794)
			(end 0.12065 -0.2794)
			(stroke
				(width 0.1)
				(type default)
			)
			(layer "F.Fab")
		)
		(fp_line
			(start -0.12065 -0.305054)
			(end -0.12065 -0.2794)
			(stroke
				(width 0.1)
				(type default)
			)
			(layer "F.Fab")
		)
		(fp_line
			(start -0.67945 0.3048)
			(end -0.67945 -0.305054)
			(stroke
				(width 0.1)
				(type default)
			)
			(layer "F.Fab")
		)
		(fp_line
			(start -0.67945 -0.305054)
			(end -0.12065 -0.305054)
			(stroke
				(width 0.1)
				(type default)
			)
			(layer "F.Fab")
		)
		(pad "1" smd circle
			(at -0.40005 0 180)
			(size 0 0)
			(layers "F.Cu" "F.Mask" "F.Paste")
			(net "LED_POSTCODE_4")
		)
		(pad "2" smd circle
			(at 0.40005 0 180)
			(size 0 0)
			(layers "F.Cu" "F.Mask" "F.Paste")
			(net "LED_POSTCODE_R_4")
		)
	)
	(footprint ""
		(layer "F.Cu")
		(at 319.696084 -387.942836 180)
		(property "Reference" "R1852"
			(at 0 0 180)
			(layer "F.SilkS")
			(hide yes)
			(effects
				(font
					(size 1.27 1.27)
				)
			)
		)
		(property "Value" ""
			(at 0 0 180)
			(layer "F.Fab")
			(effects
				(font
					(size 1.27 1.27)
				)
			)
		)
		(duplicate_pad_numbers_are_jumpers no)
		(fp_line
			(start 0.7874 0.4064)
			(end -0.7874 0.4064)
			(stroke
				(width 0.1524)
				(type default)
			)
			(layer "F.SilkS")
		)
		(fp_line
			(start 0.7874 -0.4064)
			(end 0.7874 0.4064)
			(stroke
				(width 0.1524)
				(type default)
			)
			(layer "F.SilkS")
		)
		(fp_line
			(start -0.7874 0.4064)
			(end -0.7874 -0.4064)
			(stroke
				(width 0.1524)
				(type default)
			)
			(layer "F.SilkS")
		)
		(fp_line
			(start -0.7874 -0.4064)
			(end 0.7874 -0.4064)
			(stroke
				(width 0.1524)
				(type default)
			)
			(layer "F.SilkS")
		)
		(fp_line
			(start 0.67945 0.3048)
			(end 0.120396 0.3048)
			(stroke
				(width 0.1)
				(type default)
			)
			(layer "F.Fab")
		)
		(fp_line
			(start 0.67945 -0.3048)
			(end 0.67945 0.3048)
			(stroke
				(width 0.1)
				(type default)
			)
			(layer "F.Fab")
		)
		(fp_line
			(start 0.12065 -0.2794)
			(end 0.12065 -0.3048)
			(stroke
				(width 0.1)
				(type default)
			)
			(layer "F.Fab")
		)
		(fp_line
			(start 0.12065 -0.3048)
			(end 0.67945 -0.3048)
			(stroke
				(width 0.1)
				(type default)
			)
			(layer "F.Fab")
		)
		(fp_line
			(start 0.120396 0.3048)
			(end 0.120396 0.2794)
			(stroke
				(width 0.1)
				(type default)
			)
			(layer "F.Fab")
		)
		(fp_line
			(start 0.120396 0.2794)
			(end -0.12065 0.2794)
			(stroke
				(width 0.1)
				(type default)
			)
			(layer "F.Fab")
		)
		(fp_line
			(start -0.12065 0.3048)
			(end -0.67945 0.3048)
			(stroke
				(width 0.1)
				(type default)
			)
			(layer "F.Fab")
		)
		(fp_line
			(start -0.12065 0.2794)
			(end -0.12065 0.3048)
			(stroke
				(width 0.1)
				(type default)
			)
			(layer "F.Fab")
		)
		(fp_line
			(start -0.12065 -0.2794)
			(end 0.12065 -0.2794)
			(stroke
				(width 0.1)
				(type default)
			)
			(layer "F.Fab")
		)
		(fp_line
			(start -0.12065 -0.305054)
			(end -0.12065 -0.2794)
			(stroke
				(width 0.1)
				(type default)
			)
			(layer "F.Fab")
		)
		(fp_line
			(start -0.67945 0.3048)
			(end -0.67945 -0.305054)
			(stroke
				(width 0.1)
				(type default)
			)
			(layer "F.Fab")
		)
		(fp_line
			(start -0.67945 -0.305054)
			(end -0.12065 -0.305054)
			(stroke
				(width 0.1)
				(type default)
			)
			(layer "F.Fab")
		)
		(pad "1" smd circle
			(at -0.40005 0 180)
			(size 0 0)
			(layers "F.Cu" "F.Mask" "F.Paste")
			(net "GPU_FPGA_OVERT_R_N")
		)
		(pad "2" smd circle
			(at 0.40005 0 180)
			(size 0 0)
			(layers "F.Cu" "F.Mask" "F.Paste")
			(net "GPU_FPGA_OVERT_N")
		)
	)
	(footprint ""
		(layer "F.Cu")
		(at 403.156166 -32.848042 -90)
		(property "Reference" "R6114"
			(at 0 0 270)
			(layer "F.SilkS")
			(hide yes)
			(effects
				(font
					(size 1.27 1.27)
				)
			)
		)
		(property "Value" ""
			(at 0 0 270)
			(layer "F.Fab")
			(effects
				(font
					(size 1.27 1.27)
				)
			)
		)
		(duplicate_pad_numbers_are_jumpers no)
		(fp_line
			(start -0.7874 0.4064)
			(end -0.7874 -0.4064)
			(stroke
				(width 0.1524)
				(type default)
			)
			(layer "F.SilkS")
		)
		(fp_line
			(start 0.7874 0.4064)
			(end -0.7874 0.4064)
			(stroke
				(width 0.1524)
				(type default)
			)
			(layer "F.SilkS")
		)
		(fp_line
			(start -0.7874 -0.4064)
			(end 0.7874 -0.4064)
			(stroke
				(width 0.1524)
				(type default)
			)
			(layer "F.SilkS")
		)
		(fp_line
			(start 0.7874 -0.4064)
			(end 0.7874 0.4064)
			(stroke
				(width 0.1524)
				(type default)
			)
			(layer "F.SilkS")
		)
		(fp_line
			(start -0.67945 0.3048)
			(end -0.67945 -0.305054)
			(stroke
				(width 0.1)
				(type default)
			)
			(layer "F.Fab")
		)
		(fp_line
			(start -0.12065 0.3048)
			(end -0.67945 0.3048)
			(stroke
				(width 0.1)
				(type default)
			)
			(layer "F.Fab")
		)
		(fp_line
			(start 0.120396 0.3048)
			(end 0.120396 0.2794)
			(stroke
				(width 0.1)
				(type default)
			)
			(layer "F.Fab")
		)
		(fp_line
			(start 0.67945 0.3048)
			(end 0.120396 0.3048)
			(stroke
				(width 0.1)
				(type default)
			)
			(layer "F.Fab")
		)
		(fp_line
			(start -0.12065 0.2794)
			(end -0.12065 0.3048)
			(stroke
				(width 0.1)
				(type default)
			)
			(layer "F.Fab")
		)
		(fp_line
			(start 0.120396 0.2794)
			(end -0.12065 0.2794)
			(stroke
				(width 0.1)
				(type default)
			)
			(layer "F.Fab")
		)
		(fp_line
			(start -0.12065 -0.2794)
			(end 0.12065 -0.2794)
			(stroke
				(width 0.1)
				(type default)
			)
			(layer "F.Fab")
		)
		(fp_line
			(start 0.12065 -0.2794)
			(end 0.12065 -0.3048)
			(stroke
				(width 0.1)
				(type default)
			)
			(layer "F.Fab")
		)
		(fp_line
			(start 0.12065 -0.3048)
			(end 0.67945 -0.3048)
			(stroke
				(width 0.1)
				(type default)
			)
			(layer "F.Fab")
		)
		(fp_line
			(start 0.67945 -0.3048)
			(end 0.67945 0.3048)
			(stroke
				(width 0.1)
				(type default)
			)
			(layer "F.Fab")
		)
		(fp_line
			(start -0.67945 -0.305054)
			(end -0.12065 -0.305054)
			(stroke
				(width 0.1)
				(type default)
			)
			(layer "F.Fab")
		)
		(fp_line
			(start -0.12065 -0.305054)
			(end -0.12065 -0.2794)
			(stroke
				(width 0.1)
				(type default)
			)
			(layer "F.Fab")
		)
		(pad "1" smd circle
			(at -0.40005 0 270)
			(size 0 0)
			(layers "F.Cu" "F.Mask" "F.Paste")
			(net "SSD14_AUX_P3V3_EN_R")
		)
		(pad "2" smd circle
			(at 0.40005 0 270)
			(size 0 0)
			(layers "F.Cu" "F.Mask" "F.Paste")
			(net "P3V3_SSD14_CO_EN")
		)
	)
	(footprint ""
		(layer "F.Cu")
		(at 363.474 -198.755)
		(property "Reference" "R4667"
			(at 0 0 0)
			(layer "F.SilkS")
			(hide yes)
			(effects
				(font
					(size 1.27 1.27)
				)
			)
		)
		(property "Value" ""
			(at 0 0 0)
			(layer "F.Fab")
			(effects
				(font
					(size 1.27 1.27)
				)
			)
		)
		(duplicate_pad_numbers_are_jumpers no)
		(fp_line
			(start -0.7874 -0.4064)
			(end 0.7874 -0.4064)
			(stroke
				(width 0.1524)
				(type default)
			)
			(layer "F.SilkS")
		)
		(fp_line
			(start -0.7874 0.4064)
			(end -0.7874 -0.4064)
			(stroke
				(width 0.1524)
				(type default)
			)
			(layer "F.SilkS")
		)
		(fp_line
			(start 0.7874 -0.4064)
			(end 0.7874 0.4064)
			(stroke
				(width 0.1524)
				(type default)
			)
			(layer "F.SilkS")
		)
		(fp_line
			(start 0.7874 0.4064)
			(end -0.7874 0.4064)
			(stroke
				(width 0.1524)
				(type default)
			)
			(layer "F.SilkS")
		)
		(fp_line
			(start -0.67945 -0.305054)
			(end -0.12065 -0.305054)
			(stroke
				(width 0.1)
				(type default)
			)
			(layer "F.Fab")
		)
		(fp_line
			(start -0.67945 0.3048)
			(end -0.67945 -0.305054)
			(stroke
				(width 0.1)
				(type default)
			)
			(layer "F.Fab")
		)
		(fp_line
			(start -0.12065 -0.305054)
			(end -0.12065 -0.2794)
			(stroke
				(width 0.1)
				(type default)
			)
			(layer "F.Fab")
		)
		(fp_line
			(start -0.12065 -0.2794)
			(end 0.12065 -0.2794)
			(stroke
				(width 0.1)
				(type default)
			)
			(layer "F.Fab")
		)
		(fp_line
			(start -0.12065 0.2794)
			(end -0.12065 0.3048)
			(stroke
				(width 0.1)
				(type default)
			)
			(layer "F.Fab")
		)
		(fp_line
			(start -0.12065 0.3048)
			(end -0.67945 0.3048)
			(stroke
				(width 0.1)
				(type default)
			)
			(layer "F.Fab")
		)
		(fp_line
			(start 0.120396 0.2794)
			(end -0.12065 0.2794)
			(stroke
				(width 0.1)
				(type default)
			)
			(layer "F.Fab")
		)
		(fp_line
			(start 0.120396 0.3048)
			(end 0.120396 0.2794)
			(stroke
				(width 0.1)
				(type default)
			)
			(layer "F.Fab")
		)
		(fp_line
			(start 0.12065 -0.3048)
			(end 0.67945 -0.3048)
			(stroke
				(width 0.1)
				(type default)
			)
			(layer "F.Fab")
		)
		(fp_line
			(start 0.12065 -0.2794)
			(end 0.12065 -0.3048)
			(stroke
				(width 0.1)
				(type default)
			)
			(layer "F.Fab")
		)
		(fp_line
			(start 0.67945 -0.3048)
			(end 0.67945 0.3048)
			(stroke
				(width 0.1)
				(type default)
			)
			(layer "F.Fab")
		)
		(fp_line
			(start 0.67945 0.3048)
			(end 0.120396 0.3048)
			(stroke
				(width 0.1)
				(type default)
			)
			(layer "F.Fab")
		)
		(pad "1" smd circle
			(at -0.40005 0)
			(size 0 0)
			(layers "F.Cu" "F.Mask" "F.Paste")
			(net "P3V3_AUX")
		)
		(pad "2" smd circle
			(at 0.40005 0)
			(size 0 0)
			(layers "F.Cu" "F.Mask" "F.Paste")
			(net "RST_PEX_SSD4_PERST_R_N")
		)
	)
	(footprint ""
		(layer "F.Cu")
		(at 48.202088 -350.098614 90)
		(property "Reference" "C2179"
			(at 0 0 90)
			(layer "F.SilkS")
			(hide yes)
			(effects
				(font
					(size 1.27 1.27)
				)
			)
		)
		(property "Value" ""
			(at 0 0 90)
			(layer "F.Fab")
			(effects
				(font
					(size 1.27 1.27)
				)
			)
		)
		(duplicate_pad_numbers_are_jumpers no)
		(fp_line
			(start 0.299974 -0.150114)
			(end 0.299974 0.150114)
			(stroke
				(width 0.1)
				(type default)
			)
			(layer "F.Fab")
		)
		(fp_line
			(start -0.299974 -0.150114)
			(end 0.299974 -0.150114)
			(stroke
				(width 0.1)
				(type default)
			)
			(layer "F.Fab")
		)
		(fp_line
			(start 0.299974 0.150114)
			(end -0.299974 0.150114)
			(stroke
				(width 0.1)
				(type default)
			)
			(layer "F.Fab")
		)
		(fp_line
			(start -0.299974 0.150114)
			(end -0.299974 -0.150114)
			(stroke
				(width 0.1)
				(type default)
			)
			(layer "F.Fab")
		)
		(pad "1" smd rect
			(at -0.2667 0 90)
			(size 0.3048 0.381)
			(layers "F.Cu" "F.Mask" "F.Paste")
			(net "P5E_PEX0_STN4_TX_DN<66>")
		)
		(pad "2" smd rect
			(at 0.2667 0 90)
			(size 0.3048 0.381)
			(layers "F.Cu" "F.Mask" "F.Paste")
			(net "P5E_PEX0_STN4_TX_C_DN<66>")
		)
	)
	(footprint ""
		(layer "F.Cu")
		(at 256.992628 -257.148838 -90)
		(property "Reference" "R1396"
			(at 0 0 270)
			(layer "F.SilkS")
			(hide yes)
			(effects
				(font
					(size 1.27 1.27)
				)
			)
		)
		(property "Value" ""
			(at 0 0 270)
			(layer "F.Fab")
			(effects
				(font
					(size 1.27 1.27)
				)
			)
		)
		(duplicate_pad_numbers_are_jumpers no)
		(fp_line
			(start -0.7874 0.4064)
			(end -0.7874 -0.4064)
			(stroke
				(width 0.1524)
				(type default)
			)
			(layer "F.SilkS")
		)
		(fp_line
			(start 0.7874 0.4064)
			(end -0.7874 0.4064)
			(stroke
				(width 0.1524)
				(type default)
			)
			(layer "F.SilkS")
		)
		(fp_line
			(start -0.7874 -0.4064)
			(end 0.7874 -0.4064)
			(stroke
				(width 0.1524)
				(type default)
			)
			(layer "F.SilkS")
		)
		(fp_line
			(start 0.7874 -0.4064)
			(end 0.7874 0.4064)
			(stroke
				(width 0.1524)
				(type default)
			)
			(layer "F.SilkS")
		)
		(fp_line
			(start -0.67945 0.3048)
			(end -0.67945 -0.305054)
			(stroke
				(width 0.1)
				(type default)
			)
			(layer "F.Fab")
		)
		(fp_line
			(start -0.12065 0.3048)
			(end -0.67945 0.3048)
			(stroke
				(width 0.1)
				(type default)
			)
			(layer "F.Fab")
		)
		(fp_line
			(start 0.120396 0.3048)
			(end 0.120396 0.2794)
			(stroke
				(width 0.1)
				(type default)
			)
			(layer "F.Fab")
		)
		(fp_line
			(start 0.67945 0.3048)
			(end 0.120396 0.3048)
			(stroke
				(width 0.1)
				(type default)
			)
			(layer "F.Fab")
		)
		(fp_line
			(start -0.12065 0.2794)
			(end -0.12065 0.3048)
			(stroke
				(width 0.1)
				(type default)
			)
			(layer "F.Fab")
		)
		(fp_line
			(start 0.120396 0.2794)
			(end -0.12065 0.2794)
			(stroke
				(width 0.1)
				(type default)
			)
			(layer "F.Fab")
		)
		(fp_line
			(start -0.12065 -0.2794)
			(end 0.12065 -0.2794)
			(stroke
				(width 0.1)
				(type default)
			)
			(layer "F.Fab")
		)
		(fp_line
			(start 0.12065 -0.2794)
			(end 0.12065 -0.3048)
			(stroke
				(width 0.1)
				(type default)
			)
			(layer "F.Fab")
		)
		(fp_line
			(start 0.12065 -0.3048)
			(end 0.67945 -0.3048)
			(stroke
				(width 0.1)
				(type default)
			)
			(layer "F.Fab")
		)
		(fp_line
			(start 0.67945 -0.3048)
			(end 0.67945 0.3048)
			(stroke
				(width 0.1)
				(type default)
			)
			(layer "F.Fab")
		)
		(fp_line
			(start -0.67945 -0.305054)
			(end -0.12065 -0.305054)
			(stroke
				(width 0.1)
				(type default)
			)
			(layer "F.Fab")
		)
		(fp_line
			(start -0.12065 -0.305054)
			(end -0.12065 -0.2794)
			(stroke
				(width 0.1)
				(type default)
			)
			(layer "F.Fab")
		)
		(pad "1" smd circle
			(at -0.40005 0 270)
			(size 0 0)
			(layers "F.Cu" "F.Mask" "F.Paste")
			(net "P3V3_LED")
		)
		(pad "2" smd circle
			(at 0.40005 0 270)
			(size 0 0)
			(layers "F.Cu" "F.Mask" "F.Paste")
			(net "LED_PEX2_SYS_ERR_N")
		)
	)
	(footprint ""
		(layer "F.Cu")
		(at 104.267762 -55.083456)
		(property "Reference" "PC373"
			(at 0 0 0)
			(layer "F.SilkS")
			(hide yes)
			(effects
				(font
					(size 1.27 1.27)
				)
			)
		)
		(property "Value" ""
			(at 0 0 0)
			(layer "F.Fab")
			(effects
				(font
					(size 1.27 1.27)
				)
			)
		)
		(duplicate_pad_numbers_are_jumpers no)
		(fp_line
			(start -0.7874 -0.4064)
			(end 0.7874 -0.4064)
			(stroke
				(width 0.1524)
				(type default)
			)
			(layer "F.SilkS")
		)
		(fp_line
			(start -0.7874 0.4064)
			(end -0.7874 -0.4064)
			(stroke
				(width 0.1524)
				(type default)
			)
			(layer "F.SilkS")
		)
		(fp_line
			(start 0.7874 -0.4064)
			(end 0.7874 0.4064)
			(stroke
				(width 0.1524)
				(type default)
			)
			(layer "F.SilkS")
		)
		(fp_line
			(start 0.7874 0.4064)
			(end -0.7874 0.4064)
			(stroke
				(width 0.1524)
				(type default)
			)
			(layer "F.SilkS")
		)
		(fp_line
			(start -0.67945 -0.305054)
			(end -0.12065 -0.305054)
			(stroke
				(width 0.1)
				(type default)
			)
			(layer "F.Fab")
		)
		(fp_line
			(start -0.67945 0.3048)
			(end -0.67945 -0.305054)
			(stroke
				(width 0.1)
				(type default)
			)
			(layer "F.Fab")
		)
		(fp_line
			(start -0.12065 -0.305054)
			(end -0.12065 -0.2794)
			(stroke
				(width 0.1)
				(type default)
			)
			(layer "F.Fab")
		)
		(fp_line
			(start -0.12065 -0.2794)
			(end 0.12065 -0.2794)
			(stroke
				(width 0.1)
				(type default)
			)
			(layer "F.Fab")
		)
		(fp_line
			(start -0.12065 0.2794)
			(end -0.12065 0.3048)
			(stroke
				(width 0.1)
				(type default)
			)
			(layer "F.Fab")
		)
		(fp_line
			(start -0.12065 0.3048)
			(end -0.67945 0.3048)
			(stroke
				(width 0.1)
				(type default)
			)
			(layer "F.Fab")
		)
		(fp_line
			(start 0.120396 0.2794)
			(end -0.12065 0.2794)
			(stroke
				(width 0.1)
				(type default)
			)
			(layer "F.Fab")
		)
		(fp_line
			(start 0.120396 0.3048)
			(end 0.120396 0.2794)
			(stroke
				(width 0.1)
				(type default)
			)
			(layer "F.Fab")
		)
		(fp_line
			(start 0.12065 -0.3048)
			(end 0.67945 -0.3048)
			(stroke
				(width 0.1)
				(type default)
			)
			(layer "F.Fab")
		)
		(fp_line
			(start 0.12065 -0.2794)
			(end 0.12065 -0.3048)
			(stroke
				(width 0.1)
				(type default)
			)
			(layer "F.Fab")
		)
		(fp_line
			(start 0.67945 -0.3048)
			(end 0.67945 0.3048)
			(stroke
				(width 0.1)
				(type default)
			)
			(layer "F.Fab")
		)
		(fp_line
			(start 0.67945 0.3048)
			(end 0.120396 0.3048)
			(stroke
				(width 0.1)
				(type default)
			)
			(layer "F.Fab")
		)
		(pad "1" smd circle
			(at -0.40005 0)
			(size 0 0)
			(layers "F.Cu" "F.Mask" "F.Paste")
			(net "P5V_AUX")
		)
		(pad "2" smd circle
			(at 0.40005 0)
			(size 0 0)
			(layers "F.Cu" "F.Mask" "F.Paste")
			(net "GND")
		)
	)
	(footprint ""
		(layer "F.Cu")
		(at 30.081982 -283.389832 180)
		(property "Reference" "C3062"
			(at 0 0 180)
			(layer "F.SilkS")
			(hide yes)
			(effects
				(font
					(size 1.27 1.27)
				)
			)
		)
		(property "Value" ""
			(at 0 0 180)
			(layer "F.Fab")
			(effects
				(font
					(size 1.27 1.27)
				)
			)
		)
		(duplicate_pad_numbers_are_jumpers no)
		(fp_line
			(start 1.2954 0.5842)
			(end -1.2954 0.5842)
			(stroke
				(width 0.1524)
				(type default)
			)
			(layer "F.SilkS")
		)
		(fp_line
			(start 1.2954 -0.5842)
			(end 1.2954 0.5842)
			(stroke
				(width 0.1524)
				(type default)
			)
			(layer "F.SilkS")
		)
		(fp_line
			(start -1.2954 0.5842)
			(end -1.2954 -0.5842)
			(stroke
				(width 0.1524)
				(type default)
			)
			(layer "F.SilkS")
		)
		(fp_line
			(start -1.2954 -0.5842)
			(end 1.2954 -0.5842)
			(stroke
				(width 0.1524)
				(type default)
			)
			(layer "F.SilkS")
		)
		(fp_line
			(start 1.1938 0.4064)
			(end 0.8636 0.4064)
			(stroke
				(width 0.1)
				(type default)
			)
			(layer "F.Fab")
		)
		(fp_line
			(start 1.1938 -0.4064)
			(end 1.1938 0.4064)
			(stroke
				(width 0.1)
				(type default)
			)
			(layer "F.Fab")
		)
		(fp_line
			(start 0.8636 0.4572)
			(end -0.8636 0.4572)
			(stroke
				(width 0.1)
				(type default)
			)
			(layer "F.Fab")
		)
		(fp_line
			(start 0.8636 0.4064)
			(end 0.8636 0.4572)
			(stroke
				(width 0.1)
				(type default)
			)
			(layer "F.Fab")
		)
		(fp_line
			(start 0.8636 -0.4064)
			(end 1.1938 -0.4064)
			(stroke
				(width 0.1)
				(type default)
			)
			(layer "F.Fab")
		)
		(fp_line
			(start 0.8636 -0.4572)
			(end 0.8636 -0.4064)
			(stroke
				(width 0.1)
				(type default)
			)
			(layer "F.Fab")
		)
		(fp_line
			(start -0.8636 0.4572)
			(end -0.8636 0.4064)
			(stroke
				(width 0.1)
				(type default)
			)
			(layer "F.Fab")
		)
		(fp_line
			(start -0.8636 0.4064)
			(end -1.1938 0.4064)
			(stroke
				(width 0.1)
				(type default)
			)
			(layer "F.Fab")
		)
		(fp_line
			(start -0.8636 -0.4064)
			(end -0.8636 -0.4572)
			(stroke
				(width 0.1)
				(type default)
			)
			(layer "F.Fab")
		)
		(fp_line
			(start -0.8636 -0.4572)
			(end 0.8636 -0.4572)
			(stroke
				(width 0.1)
				(type default)
			)
			(layer "F.Fab")
		)
		(fp_line
			(start -1.1938 0.4064)
			(end -1.1938 -0.4064)
			(stroke
				(width 0.1)
				(type default)
			)
			(layer "F.Fab")
		)
		(fp_line
			(start -1.1938 -0.4064)
			(end -0.8636 -0.4064)
			(stroke
				(width 0.1)
				(type default)
			)
			(layer "F.Fab")
		)
		(pad "1" smd rect
			(at -0.7366 0 90)
			(size 0.7112 0.8128)
			(layers "F.Cu" "F.Mask" "F.Paste")
			(net "PCEPLL7_VDDA18_PEX0_R")
		)
		(pad "2" smd rect
			(at 0.7366 0 90)
			(size 0.7112 0.8128)
			(layers "F.Cu" "F.Mask" "F.Paste")
			(net "GND")
		)
	)
	(footprint ""
		(layer "F.Cu")
		(at 327.533 -219.329 180)
		(property "Reference" "R4161"
			(at 0 0 180)
			(layer "F.SilkS")
			(hide yes)
			(effects
				(font
					(size 1.27 1.27)
				)
			)
		)
		(property "Value" ""
			(at 0 0 180)
			(layer "F.Fab")
			(effects
				(font
					(size 1.27 1.27)
				)
			)
		)
		(duplicate_pad_numbers_are_jumpers no)
		(fp_line
			(start 0.7874 0.4064)
			(end -0.7874 0.4064)
			(stroke
				(width 0.1524)
				(type default)
			)
			(layer "F.SilkS")
		)
		(fp_line
			(start 0.7874 -0.4064)
			(end 0.7874 0.4064)
			(stroke
				(width 0.1524)
				(type default)
			)
			(layer "F.SilkS")
		)
		(fp_line
			(start -0.7874 0.4064)
			(end -0.7874 -0.4064)
			(stroke
				(width 0.1524)
				(type default)
			)
			(layer "F.SilkS")
		)
		(fp_line
			(start -0.7874 -0.4064)
			(end 0.7874 -0.4064)
			(stroke
				(width 0.1524)
				(type default)
			)
			(layer "F.SilkS")
		)
		(fp_line
			(start 0.67945 0.3048)
			(end 0.120396 0.3048)
			(stroke
				(width 0.1)
				(type default)
			)
			(layer "F.Fab")
		)
		(fp_line
			(start 0.67945 -0.3048)
			(end 0.67945 0.3048)
			(stroke
				(width 0.1)
				(type default)
			)
			(layer "F.Fab")
		)
		(fp_line
			(start 0.12065 -0.2794)
			(end 0.12065 -0.3048)
			(stroke
				(width 0.1)
				(type default)
			)
			(layer "F.Fab")
		)
		(fp_line
			(start 0.12065 -0.3048)
			(end 0.67945 -0.3048)
			(stroke
				(width 0.1)
				(type default)
			)
			(layer "F.Fab")
		)
		(fp_line
			(start 0.120396 0.3048)
			(end 0.120396 0.2794)
			(stroke
				(width 0.1)
				(type default)
			)
			(layer "F.Fab")
		)
		(fp_line
			(start 0.120396 0.2794)
			(end -0.12065 0.2794)
			(stroke
				(width 0.1)
				(type default)
			)
			(layer "F.Fab")
		)
		(fp_line
			(start -0.12065 0.3048)
			(end -0.67945 0.3048)
			(stroke
				(width 0.1)
				(type default)
			)
			(layer "F.Fab")
		)
		(fp_line
			(start -0.12065 0.2794)
			(end -0.12065 0.3048)
			(stroke
				(width 0.1)
				(type default)
			)
			(layer "F.Fab")
		)
		(fp_line
			(start -0.12065 -0.2794)
			(end 0.12065 -0.2794)
			(stroke
				(width 0.1)
				(type default)
			)
			(layer "F.Fab")
		)
		(fp_line
			(start -0.12065 -0.305054)
			(end -0.12065 -0.2794)
			(stroke
				(width 0.1)
				(type default)
			)
			(layer "F.Fab")
		)
		(fp_line
			(start -0.67945 0.3048)
			(end -0.67945 -0.305054)
			(stroke
				(width 0.1)
				(type default)
			)
			(layer "F.Fab")
		)
		(fp_line
			(start -0.67945 -0.305054)
			(end -0.12065 -0.305054)
			(stroke
				(width 0.1)
				(type default)
			)
			(layer "F.Fab")
		)
		(pad "1" smd circle
			(at -0.40005 0 180)
			(size 0 0)
			(layers "F.Cu" "F.Mask" "F.Paste")
			(net "PRSNT_SSD14_FPGA_N")
		)
		(pad "2" smd circle
			(at 0.40005 0 180)
			(size 0 0)
			(layers "F.Cu" "F.Mask" "F.Paste")
			(net "PRSNT_SSD14_FPGA_R_N")
		)
	)
	(footprint ""
		(layer "F.Cu")
		(at 321.84975 -320.900044)
		(property "Reference" "H90"
			(at -6.735826 -7.279386 0)
			(unlocked yes)
			(layer "F.SilkS")
			(effects
				(font
					(size 0.7874 0.5842)
					(thickness 0.1524)
				)
				(justify left)
			)
		)
		(property "Value" ""
			(at 0 0 0)
			(layer "F.Fab")
			(effects
				(font
					(size 1.27 1.27)
				)
			)
		)
		(duplicate_pad_numbers_are_jumpers no)
		(fp_arc
			(start -7.98576 0.476504)
			(mid -0.238348 -7.996428)
			(end 7.999984 0)
			(stroke
				(width 0.1524)
				(type default)
			)
			(layer "F.SilkS")
		)
		(fp_arc
			(start 7.999984 0)
			(mid 3.094955 7.376969)
			(end -5.605272 5.707888)
			(stroke
				(width 0.1524)
				(type default)
			)
			(layer "F.SilkS")
		)
		(fp_arc
			(start -7.996428 0.240284)
			(mid -0.120206 -7.99904)
			(end 7.999984 0)
			(stroke
				(width 0.1524)
				(type default)
			)
			(layer "B.SilkS")
		)
		(fp_arc
			(start 7.999984 0)
			(mid 3.188675 7.336913)
			(end -5.457952 5.848858)
			(stroke
				(width 0.1524)
				(type default)
			)
			(layer "B.SilkS")
		)
		(fp_circle
			(center 0 0)
			(end 7.999984 0)
			(stroke
				(width 0.1)
				(type default)
			)
			(fill no)
			(layer "B.Fab")
		)
		(fp_circle
			(center 0 0)
			(end 7.999984 0)
			(stroke
				(width 0.1)
				(type default)
			)
			(fill no)
			(layer "F.Fab")
		)
		(pad "" np_thru_hole circle
			(at 0 0)
			(size 4.5212 4.5212)
			(drill 4.5212)
			(layers "*.Cu" "*.Mask")
			(clearance 0.381)
			(thermal_gap 0.381)
		)
		(pad "2" thru_hole circle
			(at 3.6322 0)
			(size 0.762 0.762)
			(drill 0.5588)
			(layers "*.Cu" "*.Mask")
			(remove_unused_layers no)
			(net "GND")
			(clearance 0.1524)
			(thermal_gap 0.1524)
		)
		(pad "3" thru_hole circle
			(at 2.568448 -2.568448)
			(size 0.762 0.762)
			(drill 0.5588)
			(layers "*.Cu" "*.Mask")
			(remove_unused_layers no)
			(net "GND")
			(clearance 0.1524)
			(thermal_gap 0.1524)
		)
		(pad "4" thru_hole circle
			(at 0 -3.6322)
			(size 0.762 0.762)
			(drill 0.5588)
			(layers "*.Cu" "*.Mask")
			(remove_unused_layers no)
			(net "GND")
			(clearance 0.1524)
			(thermal_gap 0.1524)
		)
		(pad "5" thru_hole circle
			(at -2.568448 -2.568448)
			(size 0.762 0.762)
			(drill 0.5588)
			(layers "*.Cu" "*.Mask")
			(remove_unused_layers no)
			(net "GND")
			(clearance 0.1524)
			(thermal_gap 0.1524)
		)
		(pad "6" thru_hole circle
			(at -3.6322 0)
			(size 0.762 0.762)
			(drill 0.5588)
			(layers "*.Cu" "*.Mask")
			(remove_unused_layers no)
			(net "GND")
			(clearance 0.1524)
			(thermal_gap 0.1524)
		)
		(pad "7" thru_hole circle
			(at -2.568448 2.568448)
			(size 0.762 0.762)
			(drill 0.5588)
			(layers "*.Cu" "*.Mask")
			(remove_unused_layers no)
			(net "GND")
			(clearance 0.1524)
			(thermal_gap 0.1524)
		)
		(pad "8" thru_hole circle
			(at 0 3.6322)
			(size 0.762 0.762)
			(drill 0.5588)
			(layers "*.Cu" "*.Mask")
			(remove_unused_layers no)
			(net "GND")
			(clearance 0.1524)
			(thermal_gap 0.1524)
		)
		(pad "9" thru_hole circle
			(at 2.568448 2.568448)
			(size 0.762 0.762)
			(drill 0.5588)
			(layers "*.Cu" "*.Mask")
			(remove_unused_layers no)
			(net "GND")
			(clearance 0.1524)
			(thermal_gap 0.1524)
		)
		(zone
			(layer "F.Cu")
			(hatch none 0.5)
			(connect_pads
				(clearance 0)
			)
			(min_thickness 0.25)
			(keepout
				(tracks not_allowed)
				(vias allowed)
				(pads allowed)
				(copperpour not_allowed)
				(footprints allowed)
			)
			(placement
				(enabled no)
				(sheetname "")
			)
			(fill
				(thermal_gap 0.5)
				(thermal_bridge_width 0.5)
				(island_removal_mode 0)
			)
			(polygon
				(pts
					(arc
						(start 321.84975 -312.90006)
						(mid 313.849766 -320.900044)
						(end 321.84975 -328.900028)
					)
					(arc
						(start 321.84975 -325.649844)
						(mid 317.09995 -320.900044)
						(end 321.84975 -316.150244)
					)
				)
			)
		)
		(zone
			(layer "F.Cu")
			(hatch none 0.5)
			(connect_pads
				(clearance 0)
			)
			(min_thickness 0.25)
			(keepout
				(tracks not_allowed)
				(vias allowed)
				(pads allowed)
				(copperpour not_allowed)
				(footprints allowed)
			)
			(placement
				(enabled no)
				(sheetname "")
			)
			(fill
				(thermal_gap 0.5)
				(thermal_bridge_width 0.5)
				(island_removal_mode 0)
			)
			(polygon
				(pts
					(arc
						(start 321.84975 -312.90006)
						(mid 329.849734 -320.900044)
						(end 321.84975 -328.900028)
					)
					(arc
						(start 321.84975 -325.649844)
						(mid 326.59955 -320.900044)
						(end 321.84975 -316.150244)
					)
				)
			)
		)
		(zone
			(layers "F.Cu" "B.Cu" "In1.Cu" "In2.Cu" "In3.Cu" "In4.Cu" "In5.Cu" "In6.Cu"
				"In7.Cu" "In8.Cu" "In9.Cu" "In10.Cu" "In11.Cu" "In12.Cu" "In13.Cu" "In14.Cu"
				"In15.Cu" "In16.Cu"
			)
			(hatch none 0.5)
			(connect_pads
				(clearance 0)
			)
			(min_thickness 0.25)
			(keepout
				(tracks not_allowed)
				(vias allowed)
				(pads allowed)
				(copperpour not_allowed)
				(footprints allowed)
			)
			(placement
				(enabled no)
				(sheetname "")
			)
			(fill
				(thermal_gap 0.5)
				(thermal_bridge_width 0.5)
				(island_removal_mode 0)
			)
			(polygon
				(pts
					(arc
						(start 324.61581 -320.900044)
						(mid 319.08369 -320.900044)
						(end 324.61581 -320.900044)
					)
				)
			)
		)
		(zone
			(layer "B.Cu")
			(hatch none 0.5)
			(connect_pads
				(clearance 0)
			)
			(min_thickness 0.25)
			(keepout
				(tracks not_allowed)
				(vias allowed)
				(pads allowed)
				(copperpour not_allowed)
				(footprints allowed)
			)
			(placement
				(enabled no)
				(sheetname "")
			)
			(fill
				(thermal_gap 0.5)
				(thermal_bridge_width 0.5)
				(island_removal_mode 0)
			)
			(polygon
				(pts
					(arc
						(start 321.84975 -315.896244)
						(mid 316.84595 -320.900044)
						(end 321.84975 -325.903844)
					)
					(arc
						(start 321.84975 -325.421244)
						(mid 317.32855 -320.900044)
						(end 321.84975 -316.378844)
					)
				)
			)
		)
		(zone
			(layer "B.Cu")
			(hatch none 0.5)
			(connect_pads
				(clearance 0)
			)
			(min_thickness 0.25)
			(keepout
				(tracks not_allowed)
				(vias allowed)
				(pads allowed)
				(copperpour not_allowed)
				(footprints allowed)
			)
			(placement
				(enabled no)
				(sheetname "")
			)
			(fill
				(thermal_gap 0.5)
				(thermal_bridge_width 0.5)
				(island_removal_mode 0)
			)
			(polygon
				(pts
					(arc
						(start 321.84975 -315.896244)
						(mid 326.85355 -320.900044)
						(end 321.84975 -325.903844)
					)
					(arc
						(start 321.84975 -325.421244)
						(mid 326.37095 -320.900044)
						(end 321.84975 -316.378844)
					)
				)
			)
		)
	)
	(footprint ""
		(layer "F.Cu")
		(at 361.89031 -254.194564 180)
		(property "Reference" "R833"
			(at 0 0 180)
			(layer "F.SilkS")
			(hide yes)
			(effects
				(font
					(size 1.27 1.27)
				)
			)
		)
		(property "Value" ""
			(at 0 0 180)
			(layer "F.Fab")
			(effects
				(font
					(size 1.27 1.27)
				)
			)
		)
		(duplicate_pad_numbers_are_jumpers no)
		(fp_line
			(start 0.7874 0.4064)
			(end -0.7874 0.4064)
			(stroke
				(width 0.1524)
				(type default)
			)
			(layer "F.SilkS")
		)
		(fp_line
			(start 0.7874 -0.4064)
			(end 0.7874 0.4064)
			(stroke
				(width 0.1524)
				(type default)
			)
			(layer "F.SilkS")
		)
		(fp_line
			(start -0.7874 0.4064)
			(end -0.7874 -0.4064)
			(stroke
				(width 0.1524)
				(type default)
			)
			(layer "F.SilkS")
		)
		(fp_line
			(start -0.7874 -0.4064)
			(end 0.7874 -0.4064)
			(stroke
				(width 0.1524)
				(type default)
			)
			(layer "F.SilkS")
		)
		(fp_line
			(start 0.67945 0.3048)
			(end 0.120396 0.3048)
			(stroke
				(width 0.1)
				(type default)
			)
			(layer "F.Fab")
		)
		(fp_line
			(start 0.67945 -0.3048)
			(end 0.67945 0.3048)
			(stroke
				(width 0.1)
				(type default)
			)
			(layer "F.Fab")
		)
		(fp_line
			(start 0.12065 -0.2794)
			(end 0.12065 -0.3048)
			(stroke
				(width 0.1)
				(type default)
			)
			(layer "F.Fab")
		)
		(fp_line
			(start 0.12065 -0.3048)
			(end 0.67945 -0.3048)
			(stroke
				(width 0.1)
				(type default)
			)
			(layer "F.Fab")
		)
		(fp_line
			(start 0.120396 0.3048)
			(end 0.120396 0.2794)
			(stroke
				(width 0.1)
				(type default)
			)
			(layer "F.Fab")
		)
		(fp_line
			(start 0.120396 0.2794)
			(end -0.12065 0.2794)
			(stroke
				(width 0.1)
				(type default)
			)
			(layer "F.Fab")
		)
		(fp_line
			(start -0.12065 0.3048)
			(end -0.67945 0.3048)
			(stroke
				(width 0.1)
				(type default)
			)
			(layer "F.Fab")
		)
		(fp_line
			(start -0.12065 0.2794)
			(end -0.12065 0.3048)
			(stroke
				(width 0.1)
				(type default)
			)
			(layer "F.Fab")
		)
		(fp_line
			(start -0.12065 -0.2794)
			(end 0.12065 -0.2794)
			(stroke
				(width 0.1)
				(type default)
			)
			(layer "F.Fab")
		)
		(fp_line
			(start -0.12065 -0.305054)
			(end -0.12065 -0.2794)
			(stroke
				(width 0.1)
				(type default)
			)
			(layer "F.Fab")
		)
		(fp_line
			(start -0.67945 0.3048)
			(end -0.67945 -0.305054)
			(stroke
				(width 0.1)
				(type default)
			)
			(layer "F.Fab")
		)
		(fp_line
			(start -0.67945 -0.305054)
			(end -0.12065 -0.305054)
			(stroke
				(width 0.1)
				(type default)
			)
			(layer "F.Fab")
		)
		(pad "1" smd circle
			(at -0.40005 0 180)
			(size 0 0)
			(layers "F.Cu" "F.Mask" "F.Paste")
			(net "P3V3_AUX")
		)
		(pad "2" smd circle
			(at 0.40005 0 180)
			(size 0 0)
			(layers "F.Cu" "F.Mask" "F.Paste")
			(net "P0V8_PEX2_AVRRDY")
		)
	)
	(footprint ""
		(layer "F.Cu")
		(at 78.243684 -49.95291 180)
		(property "Reference" "R533"
			(at 0 0 180)
			(layer "F.SilkS")
			(hide yes)
			(effects
				(font
					(size 1.27 1.27)
				)
			)
		)
		(property "Value" ""
			(at 0 0 180)
			(layer "F.Fab")
			(effects
				(font
					(size 1.27 1.27)
				)
			)
		)
		(duplicate_pad_numbers_are_jumpers no)
		(fp_line
			(start 0.7874 0.4064)
			(end -0.7874 0.4064)
			(stroke
				(width 0.1524)
				(type default)
			)
			(layer "F.SilkS")
		)
		(fp_line
			(start 0.7874 -0.4064)
			(end 0.7874 0.4064)
			(stroke
				(width 0.1524)
				(type default)
			)
			(layer "F.SilkS")
		)
		(fp_line
			(start -0.7874 0.4064)
			(end -0.7874 -0.4064)
			(stroke
				(width 0.1524)
				(type default)
			)
			(layer "F.SilkS")
		)
		(fp_line
			(start -0.7874 -0.4064)
			(end 0.7874 -0.4064)
			(stroke
				(width 0.1524)
				(type default)
			)
			(layer "F.SilkS")
		)
		(fp_line
			(start 0.67945 0.3048)
			(end 0.120396 0.3048)
			(stroke
				(width 0.1)
				(type default)
			)
			(layer "F.Fab")
		)
		(fp_line
			(start 0.67945 -0.3048)
			(end 0.67945 0.3048)
			(stroke
				(width 0.1)
				(type default)
			)
			(layer "F.Fab")
		)
		(fp_line
			(start 0.12065 -0.2794)
			(end 0.12065 -0.3048)
			(stroke
				(width 0.1)
				(type default)
			)
			(layer "F.Fab")
		)
		(fp_line
			(start 0.12065 -0.3048)
			(end 0.67945 -0.3048)
			(stroke
				(width 0.1)
				(type default)
			)
			(layer "F.Fab")
		)
		(fp_line
			(start 0.120396 0.3048)
			(end 0.120396 0.2794)
			(stroke
				(width 0.1)
				(type default)
			)
			(layer "F.Fab")
		)
		(fp_line
			(start 0.120396 0.2794)
			(end -0.12065 0.2794)
			(stroke
				(width 0.1)
				(type default)
			)
			(layer "F.Fab")
		)
		(fp_line
			(start -0.12065 0.3048)
			(end -0.67945 0.3048)
			(stroke
				(width 0.1)
				(type default)
			)
			(layer "F.Fab")
		)
		(fp_line
			(start -0.12065 0.2794)
			(end -0.12065 0.3048)
			(stroke
				(width 0.1)
				(type default)
			)
			(layer "F.Fab")
		)
		(fp_line
			(start -0.12065 -0.2794)
			(end 0.12065 -0.2794)
			(stroke
				(width 0.1)
				(type default)
			)
			(layer "F.Fab")
		)
		(fp_line
			(start -0.12065 -0.305054)
			(end -0.12065 -0.2794)
			(stroke
				(width 0.1)
				(type default)
			)
			(layer "F.Fab")
		)
		(fp_line
			(start -0.67945 0.3048)
			(end -0.67945 -0.305054)
			(stroke
				(width 0.1)
				(type default)
			)
			(layer "F.Fab")
		)
		(fp_line
			(start -0.67945 -0.305054)
			(end -0.12065 -0.305054)
			(stroke
				(width 0.1)
				(type default)
			)
			(layer "F.Fab")
		)
		(pad "1" smd circle
			(at -0.40005 0 180)
			(size 0 0)
			(layers "F.Cu" "F.Mask" "F.Paste")
			(net "SMB_BIC_I2C6_MUX_SSD_0_7_ADC_R_SCL")
		)
		(pad "2" smd circle
			(at 0.40005 0 180)
			(size 0 0)
			(layers "F.Cu" "F.Mask" "F.Paste")
			(net "SMB_SSD2_ADC_SCL")
		)
	)
	(footprint ""
		(layer "F.Cu")
		(at 334.130396 -119.77624)
		(property "Reference" "R6033"
			(at 0 0 0)
			(layer "F.SilkS")
			(hide yes)
			(effects
				(font
					(size 1.27 1.27)
				)
			)
		)
		(property "Value" ""
			(at 0 0 0)
			(layer "F.Fab")
			(effects
				(font
					(size 1.27 1.27)
				)
			)
		)
		(duplicate_pad_numbers_are_jumpers no)
		(fp_line
			(start -0.7874 -0.4064)
			(end 0.7874 -0.4064)
			(stroke
				(width 0.1524)
				(type default)
			)
			(layer "F.SilkS")
		)
		(fp_line
			(start -0.7874 0.4064)
			(end -0.7874 -0.4064)
			(stroke
				(width 0.1524)
				(type default)
			)
			(layer "F.SilkS")
		)
		(fp_line
			(start 0.7874 -0.4064)
			(end 0.7874 0.4064)
			(stroke
				(width 0.1524)
				(type default)
			)
			(layer "F.SilkS")
		)
		(fp_line
			(start 0.7874 0.4064)
			(end -0.7874 0.4064)
			(stroke
				(width 0.1524)
				(type default)
			)
			(layer "F.SilkS")
		)
		(fp_line
			(start -0.67945 -0.305054)
			(end -0.12065 -0.305054)
			(stroke
				(width 0.1)
				(type default)
			)
			(layer "F.Fab")
		)
		(fp_line
			(start -0.67945 0.3048)
			(end -0.67945 -0.305054)
			(stroke
				(width 0.1)
				(type default)
			)
			(layer "F.Fab")
		)
		(fp_line
			(start -0.12065 -0.305054)
			(end -0.12065 -0.2794)
			(stroke
				(width 0.1)
				(type default)
			)
			(layer "F.Fab")
		)
		(fp_line
			(start -0.12065 -0.2794)
			(end 0.12065 -0.2794)
			(stroke
				(width 0.1)
				(type default)
			)
			(layer "F.Fab")
		)
		(fp_line
			(start -0.12065 0.2794)
			(end -0.12065 0.3048)
			(stroke
				(width 0.1)
				(type default)
			)
			(layer "F.Fab")
		)
		(fp_line
			(start -0.12065 0.3048)
			(end -0.67945 0.3048)
			(stroke
				(width 0.1)
				(type default)
			)
			(layer "F.Fab")
		)
		(fp_line
			(start 0.120396 0.2794)
			(end -0.12065 0.2794)
			(stroke
				(width 0.1)
				(type default)
			)
			(layer "F.Fab")
		)
		(fp_line
			(start 0.120396 0.3048)
			(end 0.120396 0.2794)
			(stroke
				(width 0.1)
				(type default)
			)
			(layer "F.Fab")
		)
		(fp_line
			(start 0.12065 -0.3048)
			(end 0.67945 -0.3048)
			(stroke
				(width 0.1)
				(type default)
			)
			(layer "F.Fab")
		)
		(fp_line
			(start 0.12065 -0.2794)
			(end 0.12065 -0.3048)
			(stroke
				(width 0.1)
				(type default)
			)
			(layer "F.Fab")
		)
		(fp_line
			(start 0.67945 -0.3048)
			(end 0.67945 0.3048)
			(stroke
				(width 0.1)
				(type default)
			)
			(layer "F.Fab")
		)
		(fp_line
			(start 0.67945 0.3048)
			(end 0.120396 0.3048)
			(stroke
				(width 0.1)
				(type default)
			)
			(layer "F.Fab")
		)
		(pad "1" smd circle
			(at -0.40005 0)
			(size 0 0)
			(layers "F.Cu" "F.Mask" "F.Paste")
			(net "P3V3_AUX")
		)
		(pad "2" smd circle
			(at 0.40005 0)
			(size 0 0)
			(layers "F.Cu" "F.Mask" "F.Paste")
			(net "PWRGD_P3V3_NIC5_D")
		)
	)
	(footprint ""
		(layer "F.Cu")
		(at 251.979684 -225.49993 180)
		(property "Reference" "U319"
			(at 0.468884 -6.9088 0)
			(unlocked yes)
			(layer "F.SilkS")
			(effects
				(font
					(size 0.7874 0.5842)
					(thickness 0.1524)
				)
				(justify left)
			)
		)
		(property "Value" ""
			(at 0 0 180)
			(layer "F.Fab")
			(effects
				(font
					(size 1.27 1.27)
				)
			)
		)
		(duplicate_pad_numbers_are_jumpers no)
		(fp_line
			(start 3.795014 5.2451)
			(end 3.795014 -5.2451)
			(stroke
				(width 0.1524)
				(type default)
			)
			(layer "F.SilkS")
		)
		(fp_line
			(start 3.795014 -5.2451)
			(end 1.9431 -5.2451)
			(stroke
				(width 0.1524)
				(type default)
			)
			(layer "F.SilkS")
		)
		(fp_line
			(start 1.9431 -5.2451)
			(end 0 -3.302)
			(stroke
				(width 0.1524)
				(type default)
			)
			(layer "F.SilkS")
		)
		(fp_line
			(start 0 -3.302)
			(end -1.9431 -5.2451)
			(stroke
				(width 0.1524)
				(type default)
			)
			(layer "F.SilkS")
		)
		(fp_line
			(start -1.9431 -5.2451)
			(end -3.795014 -5.2451)
			(stroke
				(width 0.1524)
				(type default)
			)
			(layer "F.SilkS")
		)
		(fp_line
			(start -3.795014 5.2451)
			(end 3.795014 5.2451)
			(stroke
				(width 0.1524)
				(type default)
			)
			(layer "F.SilkS")
		)
		(fp_line
			(start -3.795014 -5.2451)
			(end -3.795014 5.2451)
			(stroke
				(width 0.1524)
				(type default)
			)
			(layer "F.SilkS")
		)
		(fp_poly
			(pts
				(xy -5.976366 -4.445) (xy -7.239 -3.81381) (xy -7.239 -5.07619)
			)
			(stroke
				(width 0)
				(type default)
			)
			(fill yes)
			(layer "F.SilkS")
		)
		(fp_line
			(start 3.795014 5.2451)
			(end 3.795014 -5.2451)
			(stroke
				(width 0.1)
				(type default)
			)
			(layer "F.Fab")
		)
		(fp_line
			(start 3.795014 -5.2451)
			(end -3.795014 -5.2451)
			(stroke
				(width 0.1)
				(type default)
			)
			(layer "F.Fab")
		)
		(fp_line
			(start -3.795014 5.2451)
			(end 3.795014 5.2451)
			(stroke
				(width 0.1)
				(type default)
			)
			(layer "F.Fab")
		)
		(fp_line
			(start -3.795014 -5.2451)
			(end -3.795014 5.2451)
			(stroke
				(width 0.1)
				(type default)
			)
			(layer "F.Fab")
		)
		(fp_poly
			(pts
				(xy -5.976366 -4.445) (xy -7.239 -3.81381) (xy -7.239 -5.07619)
			)
			(stroke
				(width 0)
				(type default)
			)
			(fill yes)
			(layer "F.Fab")
		)
		(pad "1" smd rect
			(at -4.880102 -4.445 90)
			(size 0.8128 1.905)
			(layers "F.Cu" "F.Mask" "F.Paste")
			(net "SPI_PEX2_SDIO3_R1")
		)
		(pad "2" smd rect
			(at -4.880102 -3.175 90)
			(size 0.8128 1.905)
			(layers "F.Cu" "F.Mask" "F.Paste")
			(net "P1V8_PEX")
		)
		(pad "3" smd rect
			(at -4.880102 -1.905 90)
			(size 0.8128 1.905)
			(layers "F.Cu" "F.Mask" "F.Paste")
			(net "SPI_PEX2_RST_R_N")
		)
		(pad "4" smd rect
			(at -4.880102 -0.635 90)
			(size 0.8128 1.905)
			(layers "F.Cu" "F.Mask" "F.Paste")
			(net "Net_9014")
		)
		(pad "5" smd rect
			(at -4.880102 0.635 90)
			(size 0.8128 1.905)
			(layers "F.Cu" "F.Mask" "F.Paste")
			(net "Net_9013")
		)
		(pad "6" smd rect
			(at -4.880102 1.905 90)
			(size 0.8128 1.905)
			(layers "F.Cu" "F.Mask" "F.Paste")
			(net "Net_9012")
		)
		(pad "7" smd rect
			(at -4.880102 3.175 90)
			(size 0.8128 1.905)
			(layers "F.Cu" "F.Mask" "F.Paste")
			(net "SPI_PEX2_CS_MUX_R_N")
		)
		(pad "8" smd rect
			(at -4.880102 4.445 90)
			(size 0.8128 1.905)
			(layers "F.Cu" "F.Mask" "F.Paste")
			(net "SPI_PEX2_SDIO1_MUX_R")
		)
		(pad "9" smd rect
			(at 4.880102 4.445 270)
			(size 0.8128 1.905)
			(layers "F.Cu" "F.Mask" "F.Paste")
			(net "SPI_PEX2_SDIO2_R1")
		)
		(pad "10" smd rect
			(at 4.880102 3.175 270)
			(size 0.8128 1.905)
			(layers "F.Cu" "F.Mask" "F.Paste")
			(net "GND")
		)
		(pad "11" smd rect
			(at 4.880102 1.905 270)
			(size 0.8128 1.905)
			(layers "F.Cu" "F.Mask" "F.Paste")
			(net "Net_9011")
		)
		(pad "12" smd rect
			(at 4.880102 0.635 270)
			(size 0.8128 1.905)
			(layers "F.Cu" "F.Mask" "F.Paste")
			(net "Net_9010")
		)
		(pad "13" smd rect
			(at 4.880102 -0.635 270)
			(size 0.8128 1.905)
			(layers "F.Cu" "F.Mask" "F.Paste")
			(net "Net_9009")
		)
		(pad "14" smd rect
			(at 4.880102 -1.905 270)
			(size 0.8128 1.905)
			(layers "F.Cu" "F.Mask" "F.Paste")
			(net "Net_9008")
		)
		(pad "15" smd rect
			(at 4.880102 -3.175 270)
			(size 0.8128 1.905)
			(layers "F.Cu" "F.Mask" "F.Paste")
			(net "SPI_PEX2_SDIO0_MUX_R")
		)
		(pad "16" smd rect
			(at 4.880102 -4.445 270)
			(size 0.8128 1.905)
			(layers "F.Cu" "F.Mask" "F.Paste")
			(net "SPI_PEX2_CLK_MUX_R")
		)
	)
	(footprint ""
		(layer "F.Cu")
		(at 362.462826 -111.377476 -90)
		(property "Reference" "PR7104"
			(at 0 0 270)
			(layer "F.SilkS")
			(hide yes)
			(effects
				(font
					(size 1.27 1.27)
				)
			)
		)
		(property "Value" ""
			(at 0 0 270)
			(layer "F.Fab")
			(effects
				(font
					(size 1.27 1.27)
				)
			)
		)
		(duplicate_pad_numbers_are_jumpers no)
		(fp_line
			(start -0.7874 0.4064)
			(end -0.7874 -0.4064)
			(stroke
				(width 0.1524)
				(type default)
			)
			(layer "F.SilkS")
		)
		(fp_line
			(start 0.7874 0.4064)
			(end -0.7874 0.4064)
			(stroke
				(width 0.1524)
				(type default)
			)
			(layer "F.SilkS")
		)
		(fp_line
			(start -0.7874 -0.4064)
			(end 0.7874 -0.4064)
			(stroke
				(width 0.1524)
				(type default)
			)
			(layer "F.SilkS")
		)
		(fp_line
			(start 0.7874 -0.4064)
			(end 0.7874 0.4064)
			(stroke
				(width 0.1524)
				(type default)
			)
			(layer "F.SilkS")
		)
		(fp_line
			(start -0.67945 0.3048)
			(end -0.67945 -0.305054)
			(stroke
				(width 0.1)
				(type default)
			)
			(layer "F.Fab")
		)
		(fp_line
			(start -0.12065 0.3048)
			(end -0.67945 0.3048)
			(stroke
				(width 0.1)
				(type default)
			)
			(layer "F.Fab")
		)
		(fp_line
			(start 0.120396 0.3048)
			(end 0.120396 0.2794)
			(stroke
				(width 0.1)
				(type default)
			)
			(layer "F.Fab")
		)
		(fp_line
			(start 0.67945 0.3048)
			(end 0.120396 0.3048)
			(stroke
				(width 0.1)
				(type default)
			)
			(layer "F.Fab")
		)
		(fp_line
			(start -0.12065 0.2794)
			(end -0.12065 0.3048)
			(stroke
				(width 0.1)
				(type default)
			)
			(layer "F.Fab")
		)
		(fp_line
			(start 0.120396 0.2794)
			(end -0.12065 0.2794)
			(stroke
				(width 0.1)
				(type default)
			)
			(layer "F.Fab")
		)
		(fp_line
			(start -0.12065 -0.2794)
			(end 0.12065 -0.2794)
			(stroke
				(width 0.1)
				(type default)
			)
			(layer "F.Fab")
		)
		(fp_line
			(start 0.12065 -0.2794)
			(end 0.12065 -0.3048)
			(stroke
				(width 0.1)
				(type default)
			)
			(layer "F.Fab")
		)
		(fp_line
			(start 0.12065 -0.3048)
			(end 0.67945 -0.3048)
			(stroke
				(width 0.1)
				(type default)
			)
			(layer "F.Fab")
		)
		(fp_line
			(start 0.67945 -0.3048)
			(end 0.67945 0.3048)
			(stroke
				(width 0.1)
				(type default)
			)
			(layer "F.Fab")
		)
		(fp_line
			(start -0.67945 -0.305054)
			(end -0.12065 -0.305054)
			(stroke
				(width 0.1)
				(type default)
			)
			(layer "F.Fab")
		)
		(fp_line
			(start -0.12065 -0.305054)
			(end -0.12065 -0.2794)
			(stroke
				(width 0.1)
				(type default)
			)
			(layer "F.Fab")
		)
		(pad "1" smd circle
			(at -0.40005 0 270)
			(size 0 0)
			(layers "F.Cu" "F.Mask" "F.Paste")
			(net "P3V3_NIC6_CO_ILIMIT")
		)
		(pad "2" smd circle
			(at 0.40005 0 270)
			(size 0 0)
			(layers "F.Cu" "F.Mask" "F.Paste")
			(net "GND")
		)
	)
	(footprint ""
		(layer "F.Cu")
		(at 341.870792 -240.691162 90)
		(property "Reference" "R3581"
			(at 0 0 90)
			(layer "F.SilkS")
			(hide yes)
			(effects
				(font
					(size 1.27 1.27)
				)
			)
		)
		(property "Value" ""
			(at 0 0 90)
			(layer "F.Fab")
			(effects
				(font
					(size 1.27 1.27)
				)
			)
		)
		(duplicate_pad_numbers_are_jumpers no)
		(fp_line
			(start 0.7874 -0.4064)
			(end 0.7874 0.4064)
			(stroke
				(width 0.1524)
				(type default)
			)
			(layer "F.SilkS")
		)
		(fp_line
			(start -0.7874 -0.4064)
			(end 0.7874 -0.4064)
			(stroke
				(width 0.1524)
				(type default)
			)
			(layer "F.SilkS")
		)
		(fp_line
			(start 0.7874 0.4064)
			(end -0.7874 0.4064)
			(stroke
				(width 0.1524)
				(type default)
			)
			(layer "F.SilkS")
		)
		(fp_line
			(start -0.7874 0.4064)
			(end -0.7874 -0.4064)
			(stroke
				(width 0.1524)
				(type default)
			)
			(layer "F.SilkS")
		)
		(fp_line
			(start -0.12065 -0.305054)
			(end -0.12065 -0.2794)
			(stroke
				(width 0.1)
				(type default)
			)
			(layer "F.Fab")
		)
		(fp_line
			(start -0.67945 -0.305054)
			(end -0.12065 -0.305054)
			(stroke
				(width 0.1)
				(type default)
			)
			(layer "F.Fab")
		)
		(fp_line
			(start 0.67945 -0.3048)
			(end 0.67945 0.3048)
			(stroke
				(width 0.1)
				(type default)
			)
			(layer "F.Fab")
		)
		(fp_line
			(start 0.12065 -0.3048)
			(end 0.67945 -0.3048)
			(stroke
				(width 0.1)
				(type default)
			)
			(layer "F.Fab")
		)
		(fp_line
			(start 0.12065 -0.2794)
			(end 0.12065 -0.3048)
			(stroke
				(width 0.1)
				(type default)
			)
			(layer "F.Fab")
		)
		(fp_line
			(start -0.12065 -0.2794)
			(end 0.12065 -0.2794)
			(stroke
				(width 0.1)
				(type default)
			)
			(layer "F.Fab")
		)
		(fp_line
			(start 0.120396 0.2794)
			(end -0.12065 0.2794)
			(stroke
				(width 0.1)
				(type default)
			)
			(layer "F.Fab")
		)
		(fp_line
			(start -0.12065 0.2794)
			(end -0.12065 0.3048)
			(stroke
				(width 0.1)
				(type default)
			)
			(layer "F.Fab")
		)
		(fp_line
			(start 0.67945 0.3048)
			(end 0.120396 0.3048)
			(stroke
				(width 0.1)
				(type default)
			)
			(layer "F.Fab")
		)
		(fp_line
			(start 0.120396 0.3048)
			(end 0.120396 0.2794)
			(stroke
				(width 0.1)
				(type default)
			)
			(layer "F.Fab")
		)
		(fp_line
			(start -0.12065 0.3048)
			(end -0.67945 0.3048)
			(stroke
				(width 0.1)
				(type default)
			)
			(layer "F.Fab")
		)
		(fp_line
			(start -0.67945 0.3048)
			(end -0.67945 -0.305054)
			(stroke
				(width 0.1)
				(type default)
			)
			(layer "F.Fab")
		)
		(pad "1" smd circle
			(at -0.40005 0 90)
			(size 0 0)
			(layers "F.Cu" "F.Mask" "F.Paste")
			(net "SSD0_PWR_EN")
		)
		(pad "2" smd circle
			(at 0.40005 0 90)
			(size 0 0)
			(layers "F.Cu" "F.Mask" "F.Paste")
			(net "SSD0_PWR_EN_R")
		)
	)
	(footprint ""
		(layer "F.Cu")
		(at 452.472806 -254.5969 -90)
		(property "Reference" "C4411"
			(at 0 0 270)
			(layer "F.SilkS")
			(hide yes)
			(effects
				(font
					(size 1.27 1.27)
				)
			)
		)
		(property "Value" ""
			(at 0 0 270)
			(layer "F.Fab")
			(effects
				(font
					(size 1.27 1.27)
				)
			)
		)
		(duplicate_pad_numbers_are_jumpers no)
		(fp_line
			(start -1.2954 0.5842)
			(end -1.2954 -0.5842)
			(stroke
				(width 0.1524)
				(type default)
			)
			(layer "F.SilkS")
		)
		(fp_line
			(start 1.2954 0.5842)
			(end -1.2954 0.5842)
			(stroke
				(width 0.1524)
				(type default)
			)
			(layer "F.SilkS")
		)
		(fp_line
			(start -1.2954 -0.5842)
			(end 1.2954 -0.5842)
			(stroke
				(width 0.1524)
				(type default)
			)
			(layer "F.SilkS")
		)
		(fp_line
			(start 1.2954 -0.5842)
			(end 1.2954 0.5842)
			(stroke
				(width 0.1524)
				(type default)
			)
			(layer "F.SilkS")
		)
		(fp_line
			(start -0.8636 0.4572)
			(end -0.8636 0.4064)
			(stroke
				(width 0.1)
				(type default)
			)
			(layer "F.Fab")
		)
		(fp_line
			(start 0.8636 0.4572)
			(end -0.8636 0.4572)
			(stroke
				(width 0.1)
				(type default)
			)
			(layer "F.Fab")
		)
		(fp_line
			(start -1.1938 0.4064)
			(end -1.1938 -0.4064)
			(stroke
				(width 0.1)
				(type default)
			)
			(layer "F.Fab")
		)
		(fp_line
			(start -0.8636 0.4064)
			(end -1.1938 0.4064)
			(stroke
				(width 0.1)
				(type default)
			)
			(layer "F.Fab")
		)
		(fp_line
			(start 0.8636 0.4064)
			(end 0.8636 0.4572)
			(stroke
				(width 0.1)
				(type default)
			)
			(layer "F.Fab")
		)
		(fp_line
			(start 1.1938 0.4064)
			(end 0.8636 0.4064)
			(stroke
				(width 0.1)
				(type default)
			)
			(layer "F.Fab")
		)
		(fp_line
			(start -1.1938 -0.4064)
			(end -0.8636 -0.4064)
			(stroke
				(width 0.1)
				(type default)
			)
			(layer "F.Fab")
		)
		(fp_line
			(start -0.8636 -0.4064)
			(end -0.8636 -0.4572)
			(stroke
				(width 0.1)
				(type default)
			)
			(layer "F.Fab")
		)
		(fp_line
			(start 0.8636 -0.4064)
			(end 1.1938 -0.4064)
			(stroke
				(width 0.1)
				(type default)
			)
			(layer "F.Fab")
		)
		(fp_line
			(start 1.1938 -0.4064)
			(end 1.1938 0.4064)
			(stroke
				(width 0.1)
				(type default)
			)
			(layer "F.Fab")
		)
		(fp_line
			(start -0.8636 -0.4572)
			(end 0.8636 -0.4572)
			(stroke
				(width 0.1)
				(type default)
			)
			(layer "F.Fab")
		)
		(fp_line
			(start 0.8636 -0.4572)
			(end 0.8636 -0.4064)
			(stroke
				(width 0.1)
				(type default)
			)
			(layer "F.Fab")
		)
		(pad "1" smd rect
			(at -0.7366 0 180)
			(size 0.7112 0.8128)
			(layers "F.Cu" "F.Mask" "F.Paste")
			(net "P1V25_SERDES_VDDPLL_PEX3_C9")
		)
		(pad "2" smd rect
			(at 0.7366 0 180)
			(size 0.7112 0.8128)
			(layers "F.Cu" "F.Mask" "F.Paste")
			(net "GND")
		)
	)
	(footprint ""
		(layer "F.Cu")
		(at 359.23474 -303.649634 90)
		(property "Reference" "PC197"
			(at 0 0 90)
			(layer "F.SilkS")
			(hide yes)
			(effects
				(font
					(size 1.27 1.27)
				)
			)
		)
		(property "Value" ""
			(at 0 0 90)
			(layer "F.Fab")
			(effects
				(font
					(size 1.27 1.27)
				)
			)
		)
		(duplicate_pad_numbers_are_jumpers no)
		(fp_line
			(start 1.524 -0.762)
			(end 1.524 0.762)
			(stroke
				(width 0.1524)
				(type default)
			)
			(layer "F.SilkS")
		)
		(fp_line
			(start -1.524 -0.762)
			(end 1.524 -0.762)
			(stroke
				(width 0.1524)
				(type default)
			)
			(layer "F.SilkS")
		)
		(fp_line
			(start 1.524 0.762)
			(end -1.524 0.762)
			(stroke
				(width 0.1524)
				(type default)
			)
			(layer "F.SilkS")
		)
		(fp_line
			(start -1.524 0.762)
			(end -1.524 -0.762)
			(stroke
				(width 0.1524)
				(type default)
			)
			(layer "F.SilkS")
		)
		(fp_line
			(start 1.1049 -0.724916)
			(end -1.1049 -0.724916)
			(stroke
				(width 0.1)
				(type default)
			)
			(layer "F.Fab")
		)
		(fp_line
			(start -1.1049 -0.724916)
			(end -1.1049 0.724916)
			(stroke
				(width 0.1)
				(type default)
			)
			(layer "F.Fab")
		)
		(fp_line
			(start 1.1049 0.724916)
			(end 1.1049 -0.724916)
			(stroke
				(width 0.1)
				(type default)
			)
			(layer "F.Fab")
		)
		(fp_line
			(start -1.1049 0.724916)
			(end 1.1049 0.724916)
			(stroke
				(width 0.1)
				(type default)
			)
			(layer "F.Fab")
		)
		(pad "1" smd rect
			(at -0.889 0 270)
			(size 1.016 1.27)
			(layers "F.Cu" "F.Mask" "F.Paste")
			(net "P0V8_PEX3")
		)
		(pad "2" smd rect
			(at 0.889 0 270)
			(size 1.016 1.27)
			(layers "F.Cu" "F.Mask" "F.Paste")
			(net "GND")
		)
	)
	(footprint ""
		(layer "F.Cu")
		(at 251.854716 -22.867366 90)
		(property "Reference" "C3934"
			(at 0 0 90)
			(layer "F.SilkS")
			(hide yes)
			(effects
				(font
					(size 1.27 1.27)
				)
			)
		)
		(property "Value" ""
			(at 0 0 90)
			(layer "F.Fab")
			(effects
				(font
					(size 1.27 1.27)
				)
			)
		)
		(duplicate_pad_numbers_are_jumpers no)
		(fp_line
			(start 0.7874 -0.4064)
			(end 0.7874 0.4064)
			(stroke
				(width 0.1524)
				(type default)
			)
			(layer "F.SilkS")
		)
		(fp_line
			(start -0.7874 -0.4064)
			(end 0.7874 -0.4064)
			(stroke
				(width 0.1524)
				(type default)
			)
			(layer "F.SilkS")
		)
		(fp_line
			(start 0.7874 0.4064)
			(end -0.7874 0.4064)
			(stroke
				(width 0.1524)
				(type default)
			)
			(layer "F.SilkS")
		)
		(fp_line
			(start -0.7874 0.4064)
			(end -0.7874 -0.4064)
			(stroke
				(width 0.1524)
				(type default)
			)
			(layer "F.SilkS")
		)
		(fp_line
			(start -0.12065 -0.305054)
			(end -0.12065 -0.2794)
			(stroke
				(width 0.1)
				(type default)
			)
			(layer "F.Fab")
		)
		(fp_line
			(start -0.67945 -0.305054)
			(end -0.12065 -0.305054)
			(stroke
				(width 0.1)
				(type default)
			)
			(layer "F.Fab")
		)
		(fp_line
			(start 0.67945 -0.3048)
			(end 0.67945 0.3048)
			(stroke
				(width 0.1)
				(type default)
			)
			(layer "F.Fab")
		)
		(fp_line
			(start 0.12065 -0.3048)
			(end 0.67945 -0.3048)
			(stroke
				(width 0.1)
				(type default)
			)
			(layer "F.Fab")
		)
		(fp_line
			(start 0.12065 -0.2794)
			(end 0.12065 -0.3048)
			(stroke
				(width 0.1)
				(type default)
			)
			(layer "F.Fab")
		)
		(fp_line
			(start -0.12065 -0.2794)
			(end 0.12065 -0.2794)
			(stroke
				(width 0.1)
				(type default)
			)
			(layer "F.Fab")
		)
		(fp_line
			(start 0.120396 0.2794)
			(end -0.12065 0.2794)
			(stroke
				(width 0.1)
				(type default)
			)
			(layer "F.Fab")
		)
		(fp_line
			(start -0.12065 0.2794)
			(end -0.12065 0.3048)
			(stroke
				(width 0.1)
				(type default)
			)
			(layer "F.Fab")
		)
		(fp_line
			(start 0.67945 0.3048)
			(end 0.120396 0.3048)
			(stroke
				(width 0.1)
				(type default)
			)
			(layer "F.Fab")
		)
		(fp_line
			(start 0.120396 0.3048)
			(end 0.120396 0.2794)
			(stroke
				(width 0.1)
				(type default)
			)
			(layer "F.Fab")
		)
		(fp_line
			(start -0.12065 0.3048)
			(end -0.67945 0.3048)
			(stroke
				(width 0.1)
				(type default)
			)
			(layer "F.Fab")
		)
		(fp_line
			(start -0.67945 0.3048)
			(end -0.67945 -0.305054)
			(stroke
				(width 0.1)
				(type default)
			)
			(layer "F.Fab")
		)
		(pad "1" smd circle
			(at -0.40005 0 90)
			(size 0 0)
			(layers "F.Cu" "F.Mask" "F.Paste")
			(net "P12V_SSD8")
		)
		(pad "2" smd circle
			(at 0.40005 0 90)
			(size 0 0)
			(layers "F.Cu" "F.Mask" "F.Paste")
			(net "GND")
		)
	)
	(footprint ""
		(layer "F.Cu")
		(at 58.995056 -96.702372 180)
		(property "Reference" "R98"
			(at 0 0 180)
			(layer "F.SilkS")
			(hide yes)
			(effects
				(font
					(size 1.27 1.27)
				)
			)
		)
		(property "Value" ""
			(at 0 0 180)
			(layer "F.Fab")
			(effects
				(font
					(size 1.27 1.27)
				)
			)
		)
		(duplicate_pad_numbers_are_jumpers no)
		(fp_line
			(start 0.7874 0.4064)
			(end -0.7874 0.4064)
			(stroke
				(width 0.1524)
				(type default)
			)
			(layer "F.SilkS")
		)
		(fp_line
			(start 0.7874 -0.4064)
			(end 0.7874 0.4064)
			(stroke
				(width 0.1524)
				(type default)
			)
			(layer "F.SilkS")
		)
		(fp_line
			(start -0.7874 0.4064)
			(end -0.7874 -0.4064)
			(stroke
				(width 0.1524)
				(type default)
			)
			(layer "F.SilkS")
		)
		(fp_line
			(start -0.7874 -0.4064)
			(end 0.7874 -0.4064)
			(stroke
				(width 0.1524)
				(type default)
			)
			(layer "F.SilkS")
		)
		(fp_line
			(start 0.67945 0.3048)
			(end 0.120396 0.3048)
			(stroke
				(width 0.1)
				(type default)
			)
			(layer "F.Fab")
		)
		(fp_line
			(start 0.67945 -0.3048)
			(end 0.67945 0.3048)
			(stroke
				(width 0.1)
				(type default)
			)
			(layer "F.Fab")
		)
		(fp_line
			(start 0.12065 -0.2794)
			(end 0.12065 -0.3048)
			(stroke
				(width 0.1)
				(type default)
			)
			(layer "F.Fab")
		)
		(fp_line
			(start 0.12065 -0.3048)
			(end 0.67945 -0.3048)
			(stroke
				(width 0.1)
				(type default)
			)
			(layer "F.Fab")
		)
		(fp_line
			(start 0.120396 0.3048)
			(end 0.120396 0.2794)
			(stroke
				(width 0.1)
				(type default)
			)
			(layer "F.Fab")
		)
		(fp_line
			(start 0.120396 0.2794)
			(end -0.12065 0.2794)
			(stroke
				(width 0.1)
				(type default)
			)
			(layer "F.Fab")
		)
		(fp_line
			(start -0.12065 0.3048)
			(end -0.67945 0.3048)
			(stroke
				(width 0.1)
				(type default)
			)
			(layer "F.Fab")
		)
		(fp_line
			(start -0.12065 0.2794)
			(end -0.12065 0.3048)
			(stroke
				(width 0.1)
				(type default)
			)
			(layer "F.Fab")
		)
		(fp_line
			(start -0.12065 -0.2794)
			(end 0.12065 -0.2794)
			(stroke
				(width 0.1)
				(type default)
			)
			(layer "F.Fab")
		)
		(fp_line
			(start -0.12065 -0.305054)
			(end -0.12065 -0.2794)
			(stroke
				(width 0.1)
				(type default)
			)
			(layer "F.Fab")
		)
		(fp_line
			(start -0.67945 0.3048)
			(end -0.67945 -0.305054)
			(stroke
				(width 0.1)
				(type default)
			)
			(layer "F.Fab")
		)
		(fp_line
			(start -0.67945 -0.305054)
			(end -0.12065 -0.305054)
			(stroke
				(width 0.1)
				(type default)
			)
			(layer "F.Fab")
		)
		(pad "1" smd circle
			(at -0.40005 0 180)
			(size 0 0)
			(layers "F.Cu" "F.Mask" "F.Paste")
			(net "RST_NIC1_PERST2_R_N")
		)
		(pad "2" smd circle
			(at 0.40005 0 180)
			(size 0 0)
			(layers "F.Cu" "F.Mask" "F.Paste")
			(net "RST_HP_NIC1_BUF_N")
		)
	)
	(footprint ""
		(layer "F.Cu")
		(at 440.359292 -350.098614 90)
		(property "Reference" "C2469"
			(at 0 0 90)
			(layer "F.SilkS")
			(hide yes)
			(effects
				(font
					(size 1.27 1.27)
				)
			)
		)
		(property "Value" ""
			(at 0 0 90)
			(layer "F.Fab")
			(effects
				(font
					(size 1.27 1.27)
				)
			)
		)
		(duplicate_pad_numbers_are_jumpers no)
		(fp_line
			(start 0.299974 -0.150114)
			(end 0.299974 0.150114)
			(stroke
				(width 0.1)
				(type default)
			)
			(layer "F.Fab")
		)
		(fp_line
			(start -0.299974 -0.150114)
			(end 0.299974 -0.150114)
			(stroke
				(width 0.1)
				(type default)
			)
			(layer "F.Fab")
		)
		(fp_line
			(start 0.299974 0.150114)
			(end -0.299974 0.150114)
			(stroke
				(width 0.1)
				(type default)
			)
			(layer "F.Fab")
		)
		(fp_line
			(start -0.299974 0.150114)
			(end -0.299974 -0.150114)
			(stroke
				(width 0.1)
				(type default)
			)
			(layer "F.Fab")
		)
		(pad "1" smd rect
			(at -0.2667 0 90)
			(size 0.3048 0.381)
			(layers "F.Cu" "F.Mask" "F.Paste")
			(net "P5E_PEX3_STN4_TX_DP<64>")
		)
		(pad "2" smd rect
			(at 0.2667 0 90)
			(size 0.3048 0.381)
			(layers "F.Cu" "F.Mask" "F.Paste")
			(net "P5E_PEX3_STN4_TX_C_DP<64>")
		)
	)
	(footprint ""
		(layer "F.Cu")
		(at 17.191736 -152.71115 90)
		(property "Reference" "R680"
			(at 0 0 90)
			(layer "F.SilkS")
			(hide yes)
			(effects
				(font
					(size 1.27 1.27)
				)
			)
		)
		(property "Value" ""
			(at 0 0 90)
			(layer "F.Fab")
			(effects
				(font
					(size 1.27 1.27)
				)
			)
		)
		(duplicate_pad_numbers_are_jumpers no)
		(fp_line
			(start 0.7874 -0.4064)
			(end 0.7874 0.4064)
			(stroke
				(width 0.1524)
				(type default)
			)
			(layer "F.SilkS")
		)
		(fp_line
			(start -0.7874 -0.4064)
			(end 0.7874 -0.4064)
			(stroke
				(width 0.1524)
				(type default)
			)
			(layer "F.SilkS")
		)
		(fp_line
			(start 0.7874 0.4064)
			(end -0.7874 0.4064)
			(stroke
				(width 0.1524)
				(type default)
			)
			(layer "F.SilkS")
		)
		(fp_line
			(start -0.7874 0.4064)
			(end -0.7874 -0.4064)
			(stroke
				(width 0.1524)
				(type default)
			)
			(layer "F.SilkS")
		)
		(fp_line
			(start -0.12065 -0.305054)
			(end -0.12065 -0.2794)
			(stroke
				(width 0.1)
				(type default)
			)
			(layer "F.Fab")
		)
		(fp_line
			(start -0.67945 -0.305054)
			(end -0.12065 -0.305054)
			(stroke
				(width 0.1)
				(type default)
			)
			(layer "F.Fab")
		)
		(fp_line
			(start 0.67945 -0.3048)
			(end 0.67945 0.3048)
			(stroke
				(width 0.1)
				(type default)
			)
			(layer "F.Fab")
		)
		(fp_line
			(start 0.12065 -0.3048)
			(end 0.67945 -0.3048)
			(stroke
				(width 0.1)
				(type default)
			)
			(layer "F.Fab")
		)
		(fp_line
			(start 0.12065 -0.2794)
			(end 0.12065 -0.3048)
			(stroke
				(width 0.1)
				(type default)
			)
			(layer "F.Fab")
		)
		(fp_line
			(start -0.12065 -0.2794)
			(end 0.12065 -0.2794)
			(stroke
				(width 0.1)
				(type default)
			)
			(layer "F.Fab")
		)
		(fp_line
			(start 0.120396 0.2794)
			(end -0.12065 0.2794)
			(stroke
				(width 0.1)
				(type default)
			)
			(layer "F.Fab")
		)
		(fp_line
			(start -0.12065 0.2794)
			(end -0.12065 0.3048)
			(stroke
				(width 0.1)
				(type default)
			)
			(layer "F.Fab")
		)
		(fp_line
			(start 0.67945 0.3048)
			(end 0.120396 0.3048)
			(stroke
				(width 0.1)
				(type default)
			)
			(layer "F.Fab")
		)
		(fp_line
			(start 0.120396 0.3048)
			(end 0.120396 0.2794)
			(stroke
				(width 0.1)
				(type default)
			)
			(layer "F.Fab")
		)
		(fp_line
			(start -0.12065 0.3048)
			(end -0.67945 0.3048)
			(stroke
				(width 0.1)
				(type default)
			)
			(layer "F.Fab")
		)
		(fp_line
			(start -0.67945 0.3048)
			(end -0.67945 -0.305054)
			(stroke
				(width 0.1)
				(type default)
			)
			(layer "F.Fab")
		)
		(pad "1" smd circle
			(at -0.40005 0 90)
			(size 0 0)
			(layers "F.Cu" "F.Mask" "F.Paste")
			(net "P3V3_AUX")
		)
		(pad "2" smd circle
			(at 0.40005 0 90)
			(size 0 0)
			(layers "F.Cu" "F.Mask" "F.Paste")
			(net "NIC_ADC_ALERT_N")
		)
	)
	(footprint ""
		(layer "F.Cu")
		(at 317.971678 -24.807418)
		(property "Reference" "R444"
			(at 0 0 0)
			(layer "F.SilkS")
			(hide yes)
			(effects
				(font
					(size 1.27 1.27)
				)
			)
		)
		(property "Value" ""
			(at 0 0 0)
			(layer "F.Fab")
			(effects
				(font
					(size 1.27 1.27)
				)
			)
		)
		(duplicate_pad_numbers_are_jumpers no)
		(fp_line
			(start -0.7874 -0.4064)
			(end 0.7874 -0.4064)
			(stroke
				(width 0.1524)
				(type default)
			)
			(layer "F.SilkS")
		)
		(fp_line
			(start -0.7874 0.4064)
			(end -0.7874 -0.4064)
			(stroke
				(width 0.1524)
				(type default)
			)
			(layer "F.SilkS")
		)
		(fp_line
			(start 0.7874 -0.4064)
			(end 0.7874 0.4064)
			(stroke
				(width 0.1524)
				(type default)
			)
			(layer "F.SilkS")
		)
		(fp_line
			(start 0.7874 0.4064)
			(end -0.7874 0.4064)
			(stroke
				(width 0.1524)
				(type default)
			)
			(layer "F.SilkS")
		)
		(fp_line
			(start -0.67945 -0.305054)
			(end -0.12065 -0.305054)
			(stroke
				(width 0.1)
				(type default)
			)
			(layer "F.Fab")
		)
		(fp_line
			(start -0.67945 0.3048)
			(end -0.67945 -0.305054)
			(stroke
				(width 0.1)
				(type default)
			)
			(layer "F.Fab")
		)
		(fp_line
			(start -0.12065 -0.305054)
			(end -0.12065 -0.2794)
			(stroke
				(width 0.1)
				(type default)
			)
			(layer "F.Fab")
		)
		(fp_line
			(start -0.12065 -0.2794)
			(end 0.12065 -0.2794)
			(stroke
				(width 0.1)
				(type default)
			)
			(layer "F.Fab")
		)
		(fp_line
			(start -0.12065 0.2794)
			(end -0.12065 0.3048)
			(stroke
				(width 0.1)
				(type default)
			)
			(layer "F.Fab")
		)
		(fp_line
			(start -0.12065 0.3048)
			(end -0.67945 0.3048)
			(stroke
				(width 0.1)
				(type default)
			)
			(layer "F.Fab")
		)
		(fp_line
			(start 0.120396 0.2794)
			(end -0.12065 0.2794)
			(stroke
				(width 0.1)
				(type default)
			)
			(layer "F.Fab")
		)
		(fp_line
			(start 0.120396 0.3048)
			(end 0.120396 0.2794)
			(stroke
				(width 0.1)
				(type default)
			)
			(layer "F.Fab")
		)
		(fp_line
			(start 0.12065 -0.3048)
			(end 0.67945 -0.3048)
			(stroke
				(width 0.1)
				(type default)
			)
			(layer "F.Fab")
		)
		(fp_line
			(start 0.12065 -0.2794)
			(end 0.12065 -0.3048)
			(stroke
				(width 0.1)
				(type default)
			)
			(layer "F.Fab")
		)
		(fp_line
			(start 0.67945 -0.3048)
			(end 0.67945 0.3048)
			(stroke
				(width 0.1)
				(type default)
			)
			(layer "F.Fab")
		)
		(fp_line
			(start 0.67945 0.3048)
			(end 0.120396 0.3048)
			(stroke
				(width 0.1)
				(type default)
			)
			(layer "F.Fab")
		)
		(pad "1" smd circle
			(at -0.40005 0)
			(size 0 0)
			(layers "F.Cu" "F.Mask" "F.Paste")
			(net "P3V3_SSD11")
		)
		(pad "2" smd circle
			(at 0.40005 0)
			(size 0 0)
			(layers "F.Cu" "F.Mask" "F.Paste")
			(net "PU_CLKREQ11")
		)
	)
	(footprint ""
		(layer "F.Cu")
		(at 436.120032 -289.230816 -90)
		(property "Reference" "R3998"
			(at 0 0 270)
			(layer "F.SilkS")
			(hide yes)
			(effects
				(font
					(size 1.27 1.27)
				)
			)
		)
		(property "Value" ""
			(at 0 0 270)
			(layer "F.Fab")
			(effects
				(font
					(size 1.27 1.27)
				)
			)
		)
		(duplicate_pad_numbers_are_jumpers no)
		(fp_line
			(start -0.7874 0.4064)
			(end -0.7874 -0.4064)
			(stroke
				(width 0.1524)
				(type default)
			)
			(layer "F.SilkS")
		)
		(fp_line
			(start 0.7874 0.4064)
			(end -0.7874 0.4064)
			(stroke
				(width 0.1524)
				(type default)
			)
			(layer "F.SilkS")
		)
		(fp_line
			(start -0.7874 -0.4064)
			(end 0.7874 -0.4064)
			(stroke
				(width 0.1524)
				(type default)
			)
			(layer "F.SilkS")
		)
		(fp_line
			(start 0.7874 -0.4064)
			(end 0.7874 0.4064)
			(stroke
				(width 0.1524)
				(type default)
			)
			(layer "F.SilkS")
		)
		(fp_line
			(start -0.67945 0.3048)
			(end -0.67945 -0.305054)
			(stroke
				(width 0.1)
				(type default)
			)
			(layer "F.Fab")
		)
		(fp_line
			(start -0.12065 0.3048)
			(end -0.67945 0.3048)
			(stroke
				(width 0.1)
				(type default)
			)
			(layer "F.Fab")
		)
		(fp_line
			(start 0.120396 0.3048)
			(end 0.120396 0.2794)
			(stroke
				(width 0.1)
				(type default)
			)
			(layer "F.Fab")
		)
		(fp_line
			(start 0.67945 0.3048)
			(end 0.120396 0.3048)
			(stroke
				(width 0.1)
				(type default)
			)
			(layer "F.Fab")
		)
		(fp_line
			(start -0.12065 0.2794)
			(end -0.12065 0.3048)
			(stroke
				(width 0.1)
				(type default)
			)
			(layer "F.Fab")
		)
		(fp_line
			(start 0.120396 0.2794)
			(end -0.12065 0.2794)
			(stroke
				(width 0.1)
				(type default)
			)
			(layer "F.Fab")
		)
		(fp_line
			(start -0.12065 -0.2794)
			(end 0.12065 -0.2794)
			(stroke
				(width 0.1)
				(type default)
			)
			(layer "F.Fab")
		)
		(fp_line
			(start 0.12065 -0.2794)
			(end 0.12065 -0.3048)
			(stroke
				(width 0.1)
				(type default)
			)
			(layer "F.Fab")
		)
		(fp_line
			(start 0.12065 -0.3048)
			(end 0.67945 -0.3048)
			(stroke
				(width 0.1)
				(type default)
			)
			(layer "F.Fab")
		)
		(fp_line
			(start 0.67945 -0.3048)
			(end 0.67945 0.3048)
			(stroke
				(width 0.1)
				(type default)
			)
			(layer "F.Fab")
		)
		(fp_line
			(start -0.67945 -0.305054)
			(end -0.12065 -0.305054)
			(stroke
				(width 0.1)
				(type default)
			)
			(layer "F.Fab")
		)
		(fp_line
			(start -0.12065 -0.305054)
			(end -0.12065 -0.2794)
			(stroke
				(width 0.1)
				(type default)
			)
			(layer "F.Fab")
		)
		(pad "1" smd circle
			(at -0.40005 0 270)
			(size 0 0)
			(layers "F.Cu" "F.Mask" "F.Paste")
			(net "SMB_PEX3_HOST_LS_SDA")
		)
		(pad "2" smd circle
			(at 0.40005 0 270)
			(size 0 0)
			(layers "F.Cu" "F.Mask" "F.Paste")
			(net "P3V3_AUX")
		)
	)
	(footprint ""
		(layer "F.Cu")
		(at 126.210314 -121.661428 180)
		(property "Reference" "C2881"
			(at 0 0 180)
			(layer "F.SilkS")
			(hide yes)
			(effects
				(font
					(size 1.27 1.27)
				)
			)
		)
		(property "Value" ""
			(at 0 0 180)
			(layer "F.Fab")
			(effects
				(font
					(size 1.27 1.27)
				)
			)
		)
		(duplicate_pad_numbers_are_jumpers no)
		(fp_line
			(start 0.7874 0.4064)
			(end -0.7874 0.4064)
			(stroke
				(width 0.1524)
				(type default)
			)
			(layer "F.SilkS")
		)
		(fp_line
			(start 0.7874 -0.4064)
			(end 0.7874 0.4064)
			(stroke
				(width 0.1524)
				(type default)
			)
			(layer "F.SilkS")
		)
		(fp_line
			(start -0.7874 0.4064)
			(end -0.7874 -0.4064)
			(stroke
				(width 0.1524)
				(type default)
			)
			(layer "F.SilkS")
		)
		(fp_line
			(start -0.7874 -0.4064)
			(end 0.7874 -0.4064)
			(stroke
				(width 0.1524)
				(type default)
			)
			(layer "F.SilkS")
		)
		(fp_line
			(start 0.67945 0.3048)
			(end 0.120396 0.3048)
			(stroke
				(width 0.1)
				(type default)
			)
			(layer "F.Fab")
		)
		(fp_line
			(start 0.67945 -0.3048)
			(end 0.67945 0.3048)
			(stroke
				(width 0.1)
				(type default)
			)
			(layer "F.Fab")
		)
		(fp_line
			(start 0.12065 -0.2794)
			(end 0.12065 -0.3048)
			(stroke
				(width 0.1)
				(type default)
			)
			(layer "F.Fab")
		)
		(fp_line
			(start 0.12065 -0.3048)
			(end 0.67945 -0.3048)
			(stroke
				(width 0.1)
				(type default)
			)
			(layer "F.Fab")
		)
		(fp_line
			(start 0.120396 0.3048)
			(end 0.120396 0.2794)
			(stroke
				(width 0.1)
				(type default)
			)
			(layer "F.Fab")
		)
		(fp_line
			(start 0.120396 0.2794)
			(end -0.12065 0.2794)
			(stroke
				(width 0.1)
				(type default)
			)
			(layer "F.Fab")
		)
		(fp_line
			(start -0.12065 0.3048)
			(end -0.67945 0.3048)
			(stroke
				(width 0.1)
				(type default)
			)
			(layer "F.Fab")
		)
		(fp_line
			(start -0.12065 0.2794)
			(end -0.12065 0.3048)
			(stroke
				(width 0.1)
				(type default)
			)
			(layer "F.Fab")
		)
		(fp_line
			(start -0.12065 -0.2794)
			(end 0.12065 -0.2794)
			(stroke
				(width 0.1)
				(type default)
			)
			(layer "F.Fab")
		)
		(fp_line
			(start -0.12065 -0.305054)
			(end -0.12065 -0.2794)
			(stroke
				(width 0.1)
				(type default)
			)
			(layer "F.Fab")
		)
		(fp_line
			(start -0.67945 0.3048)
			(end -0.67945 -0.305054)
			(stroke
				(width 0.1)
				(type default)
			)
			(layer "F.Fab")
		)
		(fp_line
			(start -0.67945 -0.305054)
			(end -0.12065 -0.305054)
			(stroke
				(width 0.1)
				(type default)
			)
			(layer "F.Fab")
		)
		(pad "1" smd circle
			(at -0.40005 0 180)
			(size 0 0)
			(layers "F.Cu" "F.Mask" "F.Paste")
			(net "HP_NIC2_EN")
		)
		(pad "2" smd circle
			(at 0.40005 0 180)
			(size 0 0)
			(layers "F.Cu" "F.Mask" "F.Paste")
			(net "GND")
		)
	)
	(footprint ""
		(layer "F.Cu")
		(at 261.743698 -311.725564 45)
		(property "Reference" "R1350"
			(at 0 0 45)
			(layer "F.SilkS")
			(hide yes)
			(effects
				(font
					(size 1.27 1.27)
				)
			)
		)
		(property "Value" ""
			(at 0 0 45)
			(layer "F.Fab")
			(effects
				(font
					(size 1.27 1.27)
				)
			)
		)
		(duplicate_pad_numbers_are_jumpers no)
		(fp_line
			(start -0.787389 -0.406267)
			(end 0.787389 -0.406267)
			(stroke
				(width 0.1524)
				(type default)
			)
			(layer "F.SilkS")
		)
		(fp_line
			(start -0.787389 0.406267)
			(end -0.787389 -0.406267)
			(stroke
				(width 0.1524)
				(type default)
			)
			(layer "F.SilkS")
		)
		(fp_line
			(start 0.787389 -0.406267)
			(end 0.787389 0.406267)
			(stroke
				(width 0.1524)
				(type default)
			)
			(layer "F.SilkS")
		)
		(fp_line
			(start 0.787389 0.406267)
			(end -0.787389 0.406267)
			(stroke
				(width 0.1524)
				(type default)
			)
			(layer "F.SilkS")
		)
		(fp_line
			(start -0.679446 -0.305149)
			(end -0.120695 -0.304969)
			(stroke
				(width 0.1)
				(type default)
			)
			(layer "F.Fab")
		)
		(fp_line
			(start -0.120695 -0.304969)
			(end -0.120695 -0.279466)
			(stroke
				(width 0.1)
				(type default)
			)
			(layer "F.Fab")
		)
		(fp_line
			(start -0.120695 -0.279466)
			(end 0.120695 -0.279466)
			(stroke
				(width 0.1)
				(type default)
			)
			(layer "F.Fab")
		)
		(fp_line
			(start -0.679446 0.30479)
			(end -0.679446 -0.305149)
			(stroke
				(width 0.1)
				(type default)
			)
			(layer "F.Fab")
		)
		(fp_line
			(start 0.120515 -0.30479)
			(end 0.679446 -0.30479)
			(stroke
				(width 0.1)
				(type default)
			)
			(layer "F.Fab")
		)
		(fp_line
			(start 0.120695 -0.279466)
			(end 0.120515 -0.30479)
			(stroke
				(width 0.1)
				(type default)
			)
			(layer "F.Fab")
		)
		(fp_line
			(start -0.120695 0.279466)
			(end -0.120515 0.30479)
			(stroke
				(width 0.1)
				(type default)
			)
			(layer "F.Fab")
		)
		(fp_line
			(start -0.120515 0.30479)
			(end -0.679446 0.30479)
			(stroke
				(width 0.1)
				(type default)
			)
			(layer "F.Fab")
		)
		(fp_line
			(start 0.679446 -0.30479)
			(end 0.679446 0.30479)
			(stroke
				(width 0.1)
				(type default)
			)
			(layer "F.Fab")
		)
		(fp_line
			(start 0.120335 0.279466)
			(end -0.120695 0.279466)
			(stroke
				(width 0.1)
				(type default)
			)
			(layer "F.Fab")
		)
		(fp_line
			(start 0.120515 0.30479)
			(end 0.120335 0.279466)
			(stroke
				(width 0.1)
				(type default)
			)
			(layer "F.Fab")
		)
		(fp_line
			(start 0.679446 0.30479)
			(end 0.120515 0.30479)
			(stroke
				(width 0.1)
				(type default)
			)
			(layer "F.Fab")
		)
		(pad "1" smd circle
			(at -0.40005 0 45)
			(size 0 0)
			(layers "F.Cu" "F.Mask" "F.Paste")
			(net "GND")
		)
		(pad "2" smd circle
			(at 0.40005 0 45)
			(size 0 0)
			(layers "F.Cu" "F.Mask" "F.Paste")
			(net "PEX2_DBG_SEL1")
		)
	)
	(footprint ""
		(layer "F.Cu")
		(at 342.555322 -35.876738)
		(property "Reference" "R6104"
			(at 0 0 0)
			(layer "F.SilkS")
			(hide yes)
			(effects
				(font
					(size 1.27 1.27)
				)
			)
		)
		(property "Value" ""
			(at 0 0 0)
			(layer "F.Fab")
			(effects
				(font
					(size 1.27 1.27)
				)
			)
		)
		(duplicate_pad_numbers_are_jumpers no)
		(fp_line
			(start -0.7874 -0.4064)
			(end 0.7874 -0.4064)
			(stroke
				(width 0.1524)
				(type default)
			)
			(layer "F.SilkS")
		)
		(fp_line
			(start -0.7874 0.4064)
			(end -0.7874 -0.4064)
			(stroke
				(width 0.1524)
				(type default)
			)
			(layer "F.SilkS")
		)
		(fp_line
			(start 0.7874 -0.4064)
			(end 0.7874 0.4064)
			(stroke
				(width 0.1524)
				(type default)
			)
			(layer "F.SilkS")
		)
		(fp_line
			(start 0.7874 0.4064)
			(end -0.7874 0.4064)
			(stroke
				(width 0.1524)
				(type default)
			)
			(layer "F.SilkS")
		)
		(fp_line
			(start -0.67945 -0.305054)
			(end -0.12065 -0.305054)
			(stroke
				(width 0.1)
				(type default)
			)
			(layer "F.Fab")
		)
		(fp_line
			(start -0.67945 0.3048)
			(end -0.67945 -0.305054)
			(stroke
				(width 0.1)
				(type default)
			)
			(layer "F.Fab")
		)
		(fp_line
			(start -0.12065 -0.305054)
			(end -0.12065 -0.2794)
			(stroke
				(width 0.1)
				(type default)
			)
			(layer "F.Fab")
		)
		(fp_line
			(start -0.12065 -0.2794)
			(end 0.12065 -0.2794)
			(stroke
				(width 0.1)
				(type default)
			)
			(layer "F.Fab")
		)
		(fp_line
			(start -0.12065 0.2794)
			(end -0.12065 0.3048)
			(stroke
				(width 0.1)
				(type default)
			)
			(layer "F.Fab")
		)
		(fp_line
			(start -0.12065 0.3048)
			(end -0.67945 0.3048)
			(stroke
				(width 0.1)
				(type default)
			)
			(layer "F.Fab")
		)
		(fp_line
			(start 0.120396 0.2794)
			(end -0.12065 0.2794)
			(stroke
				(width 0.1)
				(type default)
			)
			(layer "F.Fab")
		)
		(fp_line
			(start 0.120396 0.3048)
			(end 0.120396 0.2794)
			(stroke
				(width 0.1)
				(type default)
			)
			(layer "F.Fab")
		)
		(fp_line
			(start 0.12065 -0.3048)
			(end 0.67945 -0.3048)
			(stroke
				(width 0.1)
				(type default)
			)
			(layer "F.Fab")
		)
		(fp_line
			(start 0.12065 -0.2794)
			(end 0.12065 -0.3048)
			(stroke
				(width 0.1)
				(type default)
			)
			(layer "F.Fab")
		)
		(fp_line
			(start 0.67945 -0.3048)
			(end 0.67945 0.3048)
			(stroke
				(width 0.1)
				(type default)
			)
			(layer "F.Fab")
		)
		(fp_line
			(start 0.67945 0.3048)
			(end 0.120396 0.3048)
			(stroke
				(width 0.1)
				(type default)
			)
			(layer "F.Fab")
		)
		(pad "1" smd circle
			(at -0.40005 0)
			(size 0 0)
			(layers "F.Cu" "F.Mask" "F.Paste")
			(net "P3V3_AUX")
		)
		(pad "2" smd circle
			(at 0.40005 0)
			(size 0 0)
			(layers "F.Cu" "F.Mask" "F.Paste")
			(net "PWRGD_P3V3_SSD12_D")
		)
	)
	(footprint ""
		(layer "F.Cu")
		(at 258.535932 -207.021684)
		(property "Reference" "R4902"
			(at 0 0 0)
			(layer "F.SilkS")
			(hide yes)
			(effects
				(font
					(size 1.27 1.27)
				)
			)
		)
		(property "Value" ""
			(at 0 0 0)
			(layer "F.Fab")
			(effects
				(font
					(size 1.27 1.27)
				)
			)
		)
		(duplicate_pad_numbers_are_jumpers no)
		(fp_line
			(start -0.7874 -0.4064)
			(end 0.7874 -0.4064)
			(stroke
				(width 0.1524)
				(type default)
			)
			(layer "F.SilkS")
		)
		(fp_line
			(start -0.7874 0.4064)
			(end -0.7874 -0.4064)
			(stroke
				(width 0.1524)
				(type default)
			)
			(layer "F.SilkS")
		)
		(fp_line
			(start 0.7874 -0.4064)
			(end 0.7874 0.4064)
			(stroke
				(width 0.1524)
				(type default)
			)
			(layer "F.SilkS")
		)
		(fp_line
			(start 0.7874 0.4064)
			(end -0.7874 0.4064)
			(stroke
				(width 0.1524)
				(type default)
			)
			(layer "F.SilkS")
		)
		(fp_line
			(start -0.67945 -0.305054)
			(end -0.12065 -0.305054)
			(stroke
				(width 0.1)
				(type default)
			)
			(layer "F.Fab")
		)
		(fp_line
			(start -0.67945 0.3048)
			(end -0.67945 -0.305054)
			(stroke
				(width 0.1)
				(type default)
			)
			(layer "F.Fab")
		)
		(fp_line
			(start -0.12065 -0.305054)
			(end -0.12065 -0.2794)
			(stroke
				(width 0.1)
				(type default)
			)
			(layer "F.Fab")
		)
		(fp_line
			(start -0.12065 -0.2794)
			(end 0.12065 -0.2794)
			(stroke
				(width 0.1)
				(type default)
			)
			(layer "F.Fab")
		)
		(fp_line
			(start -0.12065 0.2794)
			(end -0.12065 0.3048)
			(stroke
				(width 0.1)
				(type default)
			)
			(layer "F.Fab")
		)
		(fp_line
			(start -0.12065 0.3048)
			(end -0.67945 0.3048)
			(stroke
				(width 0.1)
				(type default)
			)
			(layer "F.Fab")
		)
		(fp_line
			(start 0.120396 0.2794)
			(end -0.12065 0.2794)
			(stroke
				(width 0.1)
				(type default)
			)
			(layer "F.Fab")
		)
		(fp_line
			(start 0.120396 0.3048)
			(end 0.120396 0.2794)
			(stroke
				(width 0.1)
				(type default)
			)
			(layer "F.Fab")
		)
		(fp_line
			(start 0.12065 -0.3048)
			(end 0.67945 -0.3048)
			(stroke
				(width 0.1)
				(type default)
			)
			(layer "F.Fab")
		)
		(fp_line
			(start 0.12065 -0.2794)
			(end 0.12065 -0.3048)
			(stroke
				(width 0.1)
				(type default)
			)
			(layer "F.Fab")
		)
		(fp_line
			(start 0.67945 -0.3048)
			(end 0.67945 0.3048)
			(stroke
				(width 0.1)
				(type default)
			)
			(layer "F.Fab")
		)
		(fp_line
			(start 0.67945 0.3048)
			(end 0.120396 0.3048)
			(stroke
				(width 0.1)
				(type default)
			)
			(layer "F.Fab")
		)
		(pad "1" smd circle
			(at -0.40005 0)
			(size 0 0)
			(layers "F.Cu" "F.Mask" "F.Paste")
			(net "JTAG_FPGA_TDO")
		)
		(pad "2" smd circle
			(at 0.40005 0)
			(size 0 0)
			(layers "F.Cu" "F.Mask" "F.Paste")
			(net "JTAG_CONN_TDO")
		)
	)
	(footprint ""
		(layer "F.Cu")
		(at 131.63296 -114.933476)
		(property "Reference" "PU101"
			(at -2.39649 3.529076 90)
			(unlocked yes)
			(layer "F.SilkS")
			(effects
				(font
					(size 0.7874 0.5842)
					(thickness 0.1524)
				)
			)
		)
		(property "Value" ""
			(at 0 0 0)
			(layer "F.Fab")
			(effects
				(font
					(size 1.27 1.27)
				)
			)
		)
		(duplicate_pad_numbers_are_jumpers no)
		(fp_line
			(start -1.239774 -1.495298)
			(end 1.239774 -1.495298)
			(stroke
				(width 0.1524)
				(type default)
			)
			(layer "F.SilkS")
		)
		(fp_line
			(start -1.239774 1.495298)
			(end -1.239774 -1.495298)
			(stroke
				(width 0.1524)
				(type default)
			)
			(layer "F.SilkS")
		)
		(fp_line
			(start 1.239774 -1.495298)
			(end 1.239774 1.495298)
			(stroke
				(width 0.1524)
				(type default)
			)
			(layer "F.SilkS")
		)
		(fp_line
			(start 1.239774 1.495298)
			(end -1.239774 1.495298)
			(stroke
				(width 0.1524)
				(type default)
			)
			(layer "F.SilkS")
		)
		(fp_poly
			(pts
				(xy -1.83007 -1.771142) (xy -2.548382 -1.05283) (xy -1.470914 -0.693674)
			)
			(stroke
				(width 0)
				(type default)
			)
			(fill yes)
			(layer "F.SilkS")
		)
		(fp_line
			(start -0.8001 -1.050036)
			(end 0.8001 -1.050036)
			(stroke
				(width 0.1)
				(type default)
			)
			(layer "F.Fab")
		)
		(fp_line
			(start -0.8001 1.050036)
			(end -0.8001 -1.050036)
			(stroke
				(width 0.1)
				(type default)
			)
			(layer "F.Fab")
		)
		(fp_line
			(start 0.8001 -1.050036)
			(end 0.8001 1.050036)
			(stroke
				(width 0.1)
				(type default)
			)
			(layer "F.Fab")
		)
		(fp_line
			(start 0.8001 1.050036)
			(end -0.8001 1.050036)
			(stroke
				(width 0.1)
				(type default)
			)
			(layer "F.Fab")
		)
		(fp_poly
			(pts
				(xy -2.458974 -0.508) (xy -2.458974 0.508) (xy -1.442974 0)
			)
			(stroke
				(width 0)
				(type default)
			)
			(fill yes)
			(layer "F.Fab")
		)
		(pad "1_2" smd circle
			(at -0.374904 0 90)
			(size 0 0)
			(layers "F.Cu" "F.Mask" "F.Paste")
			(net "P3V3_AUX")
		)
		(pad "3" smd rect
			(at -0.499872 0.999998)
			(size 0.254 0.7112)
			(layers "F.Cu" "F.Mask" "F.Paste")
			(net "GND")
		)
		(pad "4" smd rect
			(at 0 0.999998)
			(size 0.254 0.7112)
			(layers "F.Cu" "F.Mask" "F.Paste")
			(net "P3V3_NIC2_CO_ILIMIT")
		)
		(pad "5" smd rect
			(at 0.499872 0.999998)
			(size 0.254 0.7112)
			(layers "F.Cu" "F.Mask" "F.Paste")
			(net "P3V3_NIC2_CO_MODE")
		)
		(pad "6_7" smd circle
			(at 0.374904 0 270)
			(size 0 0)
			(layers "F.Cu" "F.Mask" "F.Paste")
			(net "P3V3_NIC2")
		)
		(pad "8" smd rect
			(at 0.499872 -0.999998)
			(size 0.254 0.7112)
			(layers "F.Cu" "F.Mask" "F.Paste")
			(net "P3V3_NIC2_CO_GATE")
		)
		(pad "9" smd rect
			(at 0 -0.999998)
			(size 0.254 0.7112)
			(layers "F.Cu" "F.Mask" "F.Paste")
			(net "P3V3_NIC2_CO_EN")
		)
		(pad "10" smd rect
			(at -0.499872 -0.999998)
			(size 0.254 0.7112)
			(layers "F.Cu" "F.Mask" "F.Paste")
			(net "P3V3_NIC2_CO_DV_DT")
		)
	)
	(footprint ""
		(layer "F.Cu")
		(at 219.202 -193.04)
		(property "Reference" "R1530"
			(at 0 0 0)
			(layer "F.SilkS")
			(hide yes)
			(effects
				(font
					(size 1.27 1.27)
				)
			)
		)
		(property "Value" ""
			(at 0 0 0)
			(layer "F.Fab")
			(effects
				(font
					(size 1.27 1.27)
				)
			)
		)
		(duplicate_pad_numbers_are_jumpers no)
		(fp_line
			(start -0.7874 -0.4064)
			(end 0.7874 -0.4064)
			(stroke
				(width 0.1524)
				(type default)
			)
			(layer "F.SilkS")
		)
		(fp_line
			(start -0.7874 0.4064)
			(end -0.7874 -0.4064)
			(stroke
				(width 0.1524)
				(type default)
			)
			(layer "F.SilkS")
		)
		(fp_line
			(start 0.7874 -0.4064)
			(end 0.7874 0.4064)
			(stroke
				(width 0.1524)
				(type default)
			)
			(layer "F.SilkS")
		)
		(fp_line
			(start 0.7874 0.4064)
			(end -0.7874 0.4064)
			(stroke
				(width 0.1524)
				(type default)
			)
			(layer "F.SilkS")
		)
		(fp_line
			(start -0.67945 -0.305054)
			(end -0.12065 -0.305054)
			(stroke
				(width 0.1)
				(type default)
			)
			(layer "F.Fab")
		)
		(fp_line
			(start -0.67945 0.3048)
			(end -0.67945 -0.305054)
			(stroke
				(width 0.1)
				(type default)
			)
			(layer "F.Fab")
		)
		(fp_line
			(start -0.12065 -0.305054)
			(end -0.12065 -0.2794)
			(stroke
				(width 0.1)
				(type default)
			)
			(layer "F.Fab")
		)
		(fp_line
			(start -0.12065 -0.2794)
			(end 0.12065 -0.2794)
			(stroke
				(width 0.1)
				(type default)
			)
			(layer "F.Fab")
		)
		(fp_line
			(start -0.12065 0.2794)
			(end -0.12065 0.3048)
			(stroke
				(width 0.1)
				(type default)
			)
			(layer "F.Fab")
		)
		(fp_line
			(start -0.12065 0.3048)
			(end -0.67945 0.3048)
			(stroke
				(width 0.1)
				(type default)
			)
			(layer "F.Fab")
		)
		(fp_line
			(start 0.120396 0.2794)
			(end -0.12065 0.2794)
			(stroke
				(width 0.1)
				(type default)
			)
			(layer "F.Fab")
		)
		(fp_line
			(start 0.120396 0.3048)
			(end 0.120396 0.2794)
			(stroke
				(width 0.1)
				(type default)
			)
			(layer "F.Fab")
		)
		(fp_line
			(start 0.12065 -0.3048)
			(end 0.67945 -0.3048)
			(stroke
				(width 0.1)
				(type default)
			)
			(layer "F.Fab")
		)
		(fp_line
			(start 0.12065 -0.2794)
			(end 0.12065 -0.3048)
			(stroke
				(width 0.1)
				(type default)
			)
			(layer "F.Fab")
		)
		(fp_line
			(start 0.67945 -0.3048)
			(end 0.67945 0.3048)
			(stroke
				(width 0.1)
				(type default)
			)
			(layer "F.Fab")
		)
		(fp_line
			(start 0.67945 0.3048)
			(end 0.120396 0.3048)
			(stroke
				(width 0.1)
				(type default)
			)
			(layer "F.Fab")
		)
		(pad "1" smd circle
			(at -0.40005 0)
			(size 0 0)
			(layers "F.Cu" "F.Mask" "F.Paste")
			(net "SMB_NIC7_LS_R_SCL")
		)
		(pad "2" smd circle
			(at 0.40005 0)
			(size 0 0)
			(layers "F.Cu" "F.Mask" "F.Paste")
			(net "P3V3_NIC7")
		)
	)
	(footprint ""
		(layer "F.Cu")
		(at 277.698454 -66.32194 -90)
		(property "Reference" "PC863"
			(at 0 0 270)
			(layer "F.SilkS")
			(hide yes)
			(effects
				(font
					(size 1.27 1.27)
				)
			)
		)
		(property "Value" ""
			(at 0 0 270)
			(layer "F.Fab")
			(effects
				(font
					(size 1.27 1.27)
				)
			)
		)
		(duplicate_pad_numbers_are_jumpers no)
		(fp_line
			(start -0.7874 0.4064)
			(end -0.7874 -0.4064)
			(stroke
				(width 0.1524)
				(type default)
			)
			(layer "F.SilkS")
		)
		(fp_line
			(start 0.7874 0.4064)
			(end -0.7874 0.4064)
			(stroke
				(width 0.1524)
				(type default)
			)
			(layer "F.SilkS")
		)
		(fp_line
			(start -0.7874 -0.4064)
			(end 0.7874 -0.4064)
			(stroke
				(width 0.1524)
				(type default)
			)
			(layer "F.SilkS")
		)
		(fp_line
			(start 0.7874 -0.4064)
			(end 0.7874 0.4064)
			(stroke
				(width 0.1524)
				(type default)
			)
			(layer "F.SilkS")
		)
		(fp_line
			(start -0.67945 0.3048)
			(end -0.67945 -0.305054)
			(stroke
				(width 0.1)
				(type default)
			)
			(layer "F.Fab")
		)
		(fp_line
			(start -0.12065 0.3048)
			(end -0.67945 0.3048)
			(stroke
				(width 0.1)
				(type default)
			)
			(layer "F.Fab")
		)
		(fp_line
			(start 0.120396 0.3048)
			(end 0.120396 0.2794)
			(stroke
				(width 0.1)
				(type default)
			)
			(layer "F.Fab")
		)
		(fp_line
			(start 0.67945 0.3048)
			(end 0.120396 0.3048)
			(stroke
				(width 0.1)
				(type default)
			)
			(layer "F.Fab")
		)
		(fp_line
			(start -0.12065 0.2794)
			(end -0.12065 0.3048)
			(stroke
				(width 0.1)
				(type default)
			)
			(layer "F.Fab")
		)
		(fp_line
			(start 0.120396 0.2794)
			(end -0.12065 0.2794)
			(stroke
				(width 0.1)
				(type default)
			)
			(layer "F.Fab")
		)
		(fp_line
			(start -0.12065 -0.2794)
			(end 0.12065 -0.2794)
			(stroke
				(width 0.1)
				(type default)
			)
			(layer "F.Fab")
		)
		(fp_line
			(start 0.12065 -0.2794)
			(end 0.12065 -0.3048)
			(stroke
				(width 0.1)
				(type default)
			)
			(layer "F.Fab")
		)
		(fp_line
			(start 0.12065 -0.3048)
			(end 0.67945 -0.3048)
			(stroke
				(width 0.1)
				(type default)
			)
			(layer "F.Fab")
		)
		(fp_line
			(start 0.67945 -0.3048)
			(end 0.67945 0.3048)
			(stroke
				(width 0.1)
				(type default)
			)
			(layer "F.Fab")
		)
		(fp_line
			(start -0.67945 -0.305054)
			(end -0.12065 -0.305054)
			(stroke
				(width 0.1)
				(type default)
			)
			(layer "F.Fab")
		)
		(fp_line
			(start -0.12065 -0.305054)
			(end -0.12065 -0.2794)
			(stroke
				(width 0.1)
				(type default)
			)
			(layer "F.Fab")
		)
		(pad "1" smd circle
			(at -0.40005 0 270)
			(size 0 0)
			(layers "F.Cu" "F.Mask" "F.Paste")
			(net "P12V_SSD9_CO_GATE")
		)
		(pad "2" smd circle
			(at 0.40005 0 270)
			(size 0 0)
			(layers "F.Cu" "F.Mask" "F.Paste")
			(net "GND")
		)
	)
	(footprint ""
		(layer "F.Cu")
		(at 401.762468 -22.937216 90)
		(property "Reference" "R1726"
			(at 0 0 90)
			(layer "F.SilkS")
			(hide yes)
			(effects
				(font
					(size 1.27 1.27)
				)
			)
		)
		(property "Value" ""
			(at 0 0 90)
			(layer "F.Fab")
			(effects
				(font
					(size 1.27 1.27)
				)
			)
		)
		(duplicate_pad_numbers_are_jumpers no)
		(fp_line
			(start 0.7874 -0.4064)
			(end 0.7874 0.4064)
			(stroke
				(width 0.1524)
				(type default)
			)
			(layer "F.SilkS")
		)
		(fp_line
			(start -0.7874 -0.4064)
			(end 0.7874 -0.4064)
			(stroke
				(width 0.1524)
				(type default)
			)
			(layer "F.SilkS")
		)
		(fp_line
			(start 0.7874 0.4064)
			(end -0.7874 0.4064)
			(stroke
				(width 0.1524)
				(type default)
			)
			(layer "F.SilkS")
		)
		(fp_line
			(start -0.7874 0.4064)
			(end -0.7874 -0.4064)
			(stroke
				(width 0.1524)
				(type default)
			)
			(layer "F.SilkS")
		)
		(fp_line
			(start -0.12065 -0.305054)
			(end -0.12065 -0.2794)
			(stroke
				(width 0.1)
				(type default)
			)
			(layer "F.Fab")
		)
		(fp_line
			(start -0.67945 -0.305054)
			(end -0.12065 -0.305054)
			(stroke
				(width 0.1)
				(type default)
			)
			(layer "F.Fab")
		)
		(fp_line
			(start 0.67945 -0.3048)
			(end 0.67945 0.3048)
			(stroke
				(width 0.1)
				(type default)
			)
			(layer "F.Fab")
		)
		(fp_line
			(start 0.12065 -0.3048)
			(end 0.67945 -0.3048)
			(stroke
				(width 0.1)
				(type default)
			)
			(layer "F.Fab")
		)
		(fp_line
			(start 0.12065 -0.2794)
			(end 0.12065 -0.3048)
			(stroke
				(width 0.1)
				(type default)
			)
			(layer "F.Fab")
		)
		(fp_line
			(start -0.12065 -0.2794)
			(end 0.12065 -0.2794)
			(stroke
				(width 0.1)
				(type default)
			)
			(layer "F.Fab")
		)
		(fp_line
			(start 0.120396 0.2794)
			(end -0.12065 0.2794)
			(stroke
				(width 0.1)
				(type default)
			)
			(layer "F.Fab")
		)
		(fp_line
			(start -0.12065 0.2794)
			(end -0.12065 0.3048)
			(stroke
				(width 0.1)
				(type default)
			)
			(layer "F.Fab")
		)
		(fp_line
			(start 0.67945 0.3048)
			(end 0.120396 0.3048)
			(stroke
				(width 0.1)
				(type default)
			)
			(layer "F.Fab")
		)
		(fp_line
			(start 0.120396 0.3048)
			(end 0.120396 0.2794)
			(stroke
				(width 0.1)
				(type default)
			)
			(layer "F.Fab")
		)
		(fp_line
			(start -0.12065 0.3048)
			(end -0.67945 0.3048)
			(stroke
				(width 0.1)
				(type default)
			)
			(layer "F.Fab")
		)
		(fp_line
			(start -0.67945 0.3048)
			(end -0.67945 -0.305054)
			(stroke
				(width 0.1)
				(type default)
			)
			(layer "F.Fab")
		)
		(pad "1" smd circle
			(at -0.40005 0 90)
			(size 0 0)
			(layers "F.Cu" "F.Mask" "F.Paste")
			(net "SMB_BIC_I2C9_MUX1_SSD13_R_SDA")
		)
		(pad "2" smd circle
			(at 0.40005 0 90)
			(size 0 0)
			(layers "F.Cu" "F.Mask" "F.Paste")
			(net "SMB_ISO_SSD13_SDA")
		)
	)
	(footprint ""
		(layer "F.Cu")
		(at 310.443626 -47.92091)
		(property "Reference" "R614"
			(at 0 0 0)
			(layer "F.SilkS")
			(hide yes)
			(effects
				(font
					(size 1.27 1.27)
				)
			)
		)
		(property "Value" ""
			(at 0 0 0)
			(layer "F.Fab")
			(effects
				(font
					(size 1.27 1.27)
				)
			)
		)
		(duplicate_pad_numbers_are_jumpers no)
		(fp_line
			(start -0.7874 -0.4064)
			(end 0.7874 -0.4064)
			(stroke
				(width 0.1524)
				(type default)
			)
			(layer "F.SilkS")
		)
		(fp_line
			(start -0.7874 0.4064)
			(end -0.7874 -0.4064)
			(stroke
				(width 0.1524)
				(type default)
			)
			(layer "F.SilkS")
		)
		(fp_line
			(start 0.7874 -0.4064)
			(end 0.7874 0.4064)
			(stroke
				(width 0.1524)
				(type default)
			)
			(layer "F.SilkS")
		)
		(fp_line
			(start 0.7874 0.4064)
			(end -0.7874 0.4064)
			(stroke
				(width 0.1524)
				(type default)
			)
			(layer "F.SilkS")
		)
		(fp_line
			(start -0.67945 -0.305054)
			(end -0.12065 -0.305054)
			(stroke
				(width 0.1)
				(type default)
			)
			(layer "F.Fab")
		)
		(fp_line
			(start -0.67945 0.3048)
			(end -0.67945 -0.305054)
			(stroke
				(width 0.1)
				(type default)
			)
			(layer "F.Fab")
		)
		(fp_line
			(start -0.12065 -0.305054)
			(end -0.12065 -0.2794)
			(stroke
				(width 0.1)
				(type default)
			)
			(layer "F.Fab")
		)
		(fp_line
			(start -0.12065 -0.2794)
			(end 0.12065 -0.2794)
			(stroke
				(width 0.1)
				(type default)
			)
			(layer "F.Fab")
		)
		(fp_line
			(start -0.12065 0.2794)
			(end -0.12065 0.3048)
			(stroke
				(width 0.1)
				(type default)
			)
			(layer "F.Fab")
		)
		(fp_line
			(start -0.12065 0.3048)
			(end -0.67945 0.3048)
			(stroke
				(width 0.1)
				(type default)
			)
			(layer "F.Fab")
		)
		(fp_line
			(start 0.120396 0.2794)
			(end -0.12065 0.2794)
			(stroke
				(width 0.1)
				(type default)
			)
			(layer "F.Fab")
		)
		(fp_line
			(start 0.120396 0.3048)
			(end 0.120396 0.2794)
			(stroke
				(width 0.1)
				(type default)
			)
			(layer "F.Fab")
		)
		(fp_line
			(start 0.12065 -0.3048)
			(end 0.67945 -0.3048)
			(stroke
				(width 0.1)
				(type default)
			)
			(layer "F.Fab")
		)
		(fp_line
			(start 0.12065 -0.2794)
			(end 0.12065 -0.3048)
			(stroke
				(width 0.1)
				(type default)
			)
			(layer "F.Fab")
		)
		(fp_line
			(start 0.67945 -0.3048)
			(end 0.67945 0.3048)
			(stroke
				(width 0.1)
				(type default)
			)
			(layer "F.Fab")
		)
		(fp_line
			(start 0.67945 0.3048)
			(end 0.120396 0.3048)
			(stroke
				(width 0.1)
				(type default)
			)
			(layer "F.Fab")
		)
		(pad "1" smd circle
			(at -0.40005 0)
			(size 0 0)
			(layers "F.Cu" "F.Mask" "F.Paste")
			(net "P3V3_AUX")
		)
		(pad "2" smd circle
			(at 0.40005 0)
			(size 0 0)
			(layers "F.Cu" "F.Mask" "F.Paste")
			(net "SSD_8_15_ADC_ALERT_N")
		)
	)
	(footprint ""
		(layer "F.Cu")
		(at 175.0949 -102.798372 180)
		(property "Reference" "R172"
			(at 0 0 180)
			(layer "F.SilkS")
			(hide yes)
			(effects
				(font
					(size 1.27 1.27)
				)
			)
		)
		(property "Value" ""
			(at 0 0 180)
			(layer "F.Fab")
			(effects
				(font
					(size 1.27 1.27)
				)
			)
		)
		(duplicate_pad_numbers_are_jumpers no)
		(fp_line
			(start 0.7874 0.4064)
			(end -0.7874 0.4064)
			(stroke
				(width 0.1524)
				(type default)
			)
			(layer "F.SilkS")
		)
		(fp_line
			(start 0.7874 -0.4064)
			(end 0.7874 0.4064)
			(stroke
				(width 0.1524)
				(type default)
			)
			(layer "F.SilkS")
		)
		(fp_line
			(start -0.7874 0.4064)
			(end -0.7874 -0.4064)
			(stroke
				(width 0.1524)
				(type default)
			)
			(layer "F.SilkS")
		)
		(fp_line
			(start -0.7874 -0.4064)
			(end 0.7874 -0.4064)
			(stroke
				(width 0.1524)
				(type default)
			)
			(layer "F.SilkS")
		)
		(fp_line
			(start 0.67945 0.3048)
			(end 0.120396 0.3048)
			(stroke
				(width 0.1)
				(type default)
			)
			(layer "F.Fab")
		)
		(fp_line
			(start 0.67945 -0.3048)
			(end 0.67945 0.3048)
			(stroke
				(width 0.1)
				(type default)
			)
			(layer "F.Fab")
		)
		(fp_line
			(start 0.12065 -0.2794)
			(end 0.12065 -0.3048)
			(stroke
				(width 0.1)
				(type default)
			)
			(layer "F.Fab")
		)
		(fp_line
			(start 0.12065 -0.3048)
			(end 0.67945 -0.3048)
			(stroke
				(width 0.1)
				(type default)
			)
			(layer "F.Fab")
		)
		(fp_line
			(start 0.120396 0.3048)
			(end 0.120396 0.2794)
			(stroke
				(width 0.1)
				(type default)
			)
			(layer "F.Fab")
		)
		(fp_line
			(start 0.120396 0.2794)
			(end -0.12065 0.2794)
			(stroke
				(width 0.1)
				(type default)
			)
			(layer "F.Fab")
		)
		(fp_line
			(start -0.12065 0.3048)
			(end -0.67945 0.3048)
			(stroke
				(width 0.1)
				(type default)
			)
			(layer "F.Fab")
		)
		(fp_line
			(start -0.12065 0.2794)
			(end -0.12065 0.3048)
			(stroke
				(width 0.1)
				(type default)
			)
			(layer "F.Fab")
		)
		(fp_line
			(start -0.12065 -0.2794)
			(end 0.12065 -0.2794)
			(stroke
				(width 0.1)
				(type default)
			)
			(layer "F.Fab")
		)
		(fp_line
			(start -0.12065 -0.305054)
			(end -0.12065 -0.2794)
			(stroke
				(width 0.1)
				(type default)
			)
			(layer "F.Fab")
		)
		(fp_line
			(start -0.67945 0.3048)
			(end -0.67945 -0.305054)
			(stroke
				(width 0.1)
				(type default)
			)
			(layer "F.Fab")
		)
		(fp_line
			(start -0.67945 -0.305054)
			(end -0.12065 -0.305054)
			(stroke
				(width 0.1)
				(type default)
			)
			(layer "F.Fab")
		)
		(pad "1" smd circle
			(at -0.40005 0 180)
			(size 0 0)
			(layers "F.Cu" "F.Mask" "F.Paste")
			(net "NCSI_NIC3_TXD1")
		)
		(pad "2" smd circle
			(at 0.40005 0 180)
			(size 0 0)
			(layers "F.Cu" "F.Mask" "F.Paste")
			(net "GND")
		)
	)
	(footprint ""
		(layer "F.Cu")
		(at 85.103208 -59.571636 90)
		(property "Reference" "PR270"
			(at 0 0 90)
			(layer "F.SilkS")
			(hide yes)
			(effects
				(font
					(size 1.27 1.27)
				)
			)
		)
		(property "Value" ""
			(at 0 0 90)
			(layer "F.Fab")
			(effects
				(font
					(size 1.27 1.27)
				)
			)
		)
		(duplicate_pad_numbers_are_jumpers no)
		(fp_line
			(start 0.7874 -0.4064)
			(end 0.7874 0.4064)
			(stroke
				(width 0.1524)
				(type default)
			)
			(layer "F.SilkS")
		)
		(fp_line
			(start -0.7874 -0.4064)
			(end 0.7874 -0.4064)
			(stroke
				(width 0.1524)
				(type default)
			)
			(layer "F.SilkS")
		)
		(fp_line
			(start 0.7874 0.4064)
			(end -0.7874 0.4064)
			(stroke
				(width 0.1524)
				(type default)
			)
			(layer "F.SilkS")
		)
		(fp_line
			(start -0.7874 0.4064)
			(end -0.7874 -0.4064)
			(stroke
				(width 0.1524)
				(type default)
			)
			(layer "F.SilkS")
		)
		(fp_line
			(start -0.12065 -0.305054)
			(end -0.12065 -0.2794)
			(stroke
				(width 0.1)
				(type default)
			)
			(layer "F.Fab")
		)
		(fp_line
			(start -0.67945 -0.305054)
			(end -0.12065 -0.305054)
			(stroke
				(width 0.1)
				(type default)
			)
			(layer "F.Fab")
		)
		(fp_line
			(start 0.67945 -0.3048)
			(end 0.67945 0.3048)
			(stroke
				(width 0.1)
				(type default)
			)
			(layer "F.Fab")
		)
		(fp_line
			(start 0.12065 -0.3048)
			(end 0.67945 -0.3048)
			(stroke
				(width 0.1)
				(type default)
			)
			(layer "F.Fab")
		)
		(fp_line
			(start 0.12065 -0.2794)
			(end 0.12065 -0.3048)
			(stroke
				(width 0.1)
				(type default)
			)
			(layer "F.Fab")
		)
		(fp_line
			(start -0.12065 -0.2794)
			(end 0.12065 -0.2794)
			(stroke
				(width 0.1)
				(type default)
			)
			(layer "F.Fab")
		)
		(fp_line
			(start 0.120396 0.2794)
			(end -0.12065 0.2794)
			(stroke
				(width 0.1)
				(type default)
			)
			(layer "F.Fab")
		)
		(fp_line
			(start -0.12065 0.2794)
			(end -0.12065 0.3048)
			(stroke
				(width 0.1)
				(type default)
			)
			(layer "F.Fab")
		)
		(fp_line
			(start 0.67945 0.3048)
			(end 0.120396 0.3048)
			(stroke
				(width 0.1)
				(type default)
			)
			(layer "F.Fab")
		)
		(fp_line
			(start 0.120396 0.3048)
			(end 0.120396 0.2794)
			(stroke
				(width 0.1)
				(type default)
			)
			(layer "F.Fab")
		)
		(fp_line
			(start -0.12065 0.3048)
			(end -0.67945 0.3048)
			(stroke
				(width 0.1)
				(type default)
			)
			(layer "F.Fab")
		)
		(fp_line
			(start -0.67945 0.3048)
			(end -0.67945 -0.305054)
			(stroke
				(width 0.1)
				(type default)
			)
			(layer "F.Fab")
		)
		(pad "1" smd circle
			(at -0.40005 0 90)
			(size 0 0)
			(layers "F.Cu" "F.Mask" "F.Paste")
			(net "P3V3_SSD3_OCP")
		)
		(pad "2" smd circle
			(at 0.40005 0 90)
			(size 0 0)
			(layers "F.Cu" "F.Mask" "F.Paste")
			(net "GND")
		)
	)
	(footprint ""
		(layer "F.Cu")
		(at 358.013 -229.616)
		(property "Reference" "R3615"
			(at 0 0 0)
			(layer "F.SilkS")
			(hide yes)
			(effects
				(font
					(size 1.27 1.27)
				)
			)
		)
		(property "Value" ""
			(at 0 0 0)
			(layer "F.Fab")
			(effects
				(font
					(size 1.27 1.27)
				)
			)
		)
		(duplicate_pad_numbers_are_jumpers no)
		(fp_line
			(start -0.7874 -0.4064)
			(end 0.7874 -0.4064)
			(stroke
				(width 0.1524)
				(type default)
			)
			(layer "F.SilkS")
		)
		(fp_line
			(start -0.7874 0.4064)
			(end -0.7874 -0.4064)
			(stroke
				(width 0.1524)
				(type default)
			)
			(layer "F.SilkS")
		)
		(fp_line
			(start 0.7874 -0.4064)
			(end 0.7874 0.4064)
			(stroke
				(width 0.1524)
				(type default)
			)
			(layer "F.SilkS")
		)
		(fp_line
			(start 0.7874 0.4064)
			(end -0.7874 0.4064)
			(stroke
				(width 0.1524)
				(type default)
			)
			(layer "F.SilkS")
		)
		(fp_line
			(start -0.67945 -0.305054)
			(end -0.12065 -0.305054)
			(stroke
				(width 0.1)
				(type default)
			)
			(layer "F.Fab")
		)
		(fp_line
			(start -0.67945 0.3048)
			(end -0.67945 -0.305054)
			(stroke
				(width 0.1)
				(type default)
			)
			(layer "F.Fab")
		)
		(fp_line
			(start -0.12065 -0.305054)
			(end -0.12065 -0.2794)
			(stroke
				(width 0.1)
				(type default)
			)
			(layer "F.Fab")
		)
		(fp_line
			(start -0.12065 -0.2794)
			(end 0.12065 -0.2794)
			(stroke
				(width 0.1)
				(type default)
			)
			(layer "F.Fab")
		)
		(fp_line
			(start -0.12065 0.2794)
			(end -0.12065 0.3048)
			(stroke
				(width 0.1)
				(type default)
			)
			(layer "F.Fab")
		)
		(fp_line
			(start -0.12065 0.3048)
			(end -0.67945 0.3048)
			(stroke
				(width 0.1)
				(type default)
			)
			(layer "F.Fab")
		)
		(fp_line
			(start 0.120396 0.2794)
			(end -0.12065 0.2794)
			(stroke
				(width 0.1)
				(type default)
			)
			(layer "F.Fab")
		)
		(fp_line
			(start 0.120396 0.3048)
			(end 0.120396 0.2794)
			(stroke
				(width 0.1)
				(type default)
			)
			(layer "F.Fab")
		)
		(fp_line
			(start 0.12065 -0.3048)
			(end 0.67945 -0.3048)
			(stroke
				(width 0.1)
				(type default)
			)
			(layer "F.Fab")
		)
		(fp_line
			(start 0.12065 -0.2794)
			(end 0.12065 -0.3048)
			(stroke
				(width 0.1)
				(type default)
			)
			(layer "F.Fab")
		)
		(fp_line
			(start 0.67945 -0.3048)
			(end 0.67945 0.3048)
			(stroke
				(width 0.1)
				(type default)
			)
			(layer "F.Fab")
		)
		(fp_line
			(start 0.67945 0.3048)
			(end 0.120396 0.3048)
			(stroke
				(width 0.1)
				(type default)
			)
			(layer "F.Fab")
		)
		(pad "1" smd circle
			(at -0.40005 0)
			(size 0 0)
			(layers "F.Cu" "F.Mask" "F.Paste")
			(net "RST_NIC1_PERST_N")
		)
		(pad "2" smd circle
			(at 0.40005 0)
			(size 0 0)
			(layers "F.Cu" "F.Mask" "F.Paste")
			(net "RST_NIC1_PERST_R_N")
		)
	)
	(footprint ""
		(layer "F.Cu")
		(at 264.582402 -332.609698)
		(property "Reference" "R6795"
			(at 0 0 0)
			(layer "F.SilkS")
			(hide yes)
			(effects
				(font
					(size 1.27 1.27)
				)
			)
		)
		(property "Value" ""
			(at 0 0 0)
			(layer "F.Fab")
			(effects
				(font
					(size 1.27 1.27)
				)
			)
		)
		(duplicate_pad_numbers_are_jumpers no)
		(fp_line
			(start -0.7874 -0.4064)
			(end 0.7874 -0.4064)
			(stroke
				(width 0.1524)
				(type default)
			)
			(layer "F.SilkS")
		)
		(fp_line
			(start -0.7874 0.4064)
			(end -0.7874 -0.4064)
			(stroke
				(width 0.1524)
				(type default)
			)
			(layer "F.SilkS")
		)
		(fp_line
			(start 0.7874 -0.4064)
			(end 0.7874 0.4064)
			(stroke
				(width 0.1524)
				(type default)
			)
			(layer "F.SilkS")
		)
		(fp_line
			(start 0.7874 0.4064)
			(end -0.7874 0.4064)
			(stroke
				(width 0.1524)
				(type default)
			)
			(layer "F.SilkS")
		)
		(fp_line
			(start -0.67945 -0.305054)
			(end -0.12065 -0.305054)
			(stroke
				(width 0.1)
				(type default)
			)
			(layer "F.Fab")
		)
		(fp_line
			(start -0.67945 0.3048)
			(end -0.67945 -0.305054)
			(stroke
				(width 0.1)
				(type default)
			)
			(layer "F.Fab")
		)
		(fp_line
			(start -0.12065 -0.305054)
			(end -0.12065 -0.2794)
			(stroke
				(width 0.1)
				(type default)
			)
			(layer "F.Fab")
		)
		(fp_line
			(start -0.12065 -0.2794)
			(end 0.12065 -0.2794)
			(stroke
				(width 0.1)
				(type default)
			)
			(layer "F.Fab")
		)
		(fp_line
			(start -0.12065 0.2794)
			(end -0.12065 0.3048)
			(stroke
				(width 0.1)
				(type default)
			)
			(layer "F.Fab")
		)
		(fp_line
			(start -0.12065 0.3048)
			(end -0.67945 0.3048)
			(stroke
				(width 0.1)
				(type default)
			)
			(layer "F.Fab")
		)
		(fp_line
			(start 0.120396 0.2794)
			(end -0.12065 0.2794)
			(stroke
				(width 0.1)
				(type default)
			)
			(layer "F.Fab")
		)
		(fp_line
			(start 0.120396 0.3048)
			(end 0.120396 0.2794)
			(stroke
				(width 0.1)
				(type default)
			)
			(layer "F.Fab")
		)
		(fp_line
			(start 0.12065 -0.3048)
			(end 0.67945 -0.3048)
			(stroke
				(width 0.1)
				(type default)
			)
			(layer "F.Fab")
		)
		(fp_line
			(start 0.12065 -0.2794)
			(end 0.12065 -0.3048)
			(stroke
				(width 0.1)
				(type default)
			)
			(layer "F.Fab")
		)
		(fp_line
			(start 0.67945 -0.3048)
			(end 0.67945 0.3048)
			(stroke
				(width 0.1)
				(type default)
			)
			(layer "F.Fab")
		)
		(fp_line
			(start 0.67945 0.3048)
			(end 0.120396 0.3048)
			(stroke
				(width 0.1)
				(type default)
			)
			(layer "F.Fab")
		)
		(pad "1" smd circle
			(at -0.40005 0)
			(size 0 0)
			(layers "F.Cu" "F.Mask" "F.Paste")
			(net "HSC_OC_VOL")
		)
		(pad "2" smd circle
			(at 0.40005 0)
			(size 0 0)
			(layers "F.Cu" "F.Mask" "F.Paste")
			(net "HSC_D_OC_R2")
		)
	)
	(footprint ""
		(layer "F.Cu")
		(at 106.091228 -268.278102 -90)
		(property "Reference" "PC982"
			(at 0 0 270)
			(layer "F.SilkS")
			(hide yes)
			(effects
				(font
					(size 1.27 1.27)
				)
			)
		)
		(property "Value" ""
			(at 0 0 270)
			(layer "F.Fab")
			(effects
				(font
					(size 1.27 1.27)
				)
			)
		)
		(duplicate_pad_numbers_are_jumpers no)
		(fp_line
			(start -0.7874 0.4064)
			(end -0.7874 -0.4064)
			(stroke
				(width 0.1524)
				(type default)
			)
			(layer "F.SilkS")
		)
		(fp_line
			(start 0.7874 0.4064)
			(end -0.7874 0.4064)
			(stroke
				(width 0.1524)
				(type default)
			)
			(layer "F.SilkS")
		)
		(fp_line
			(start -0.7874 -0.4064)
			(end 0.7874 -0.4064)
			(stroke
				(width 0.1524)
				(type default)
			)
			(layer "F.SilkS")
		)
		(fp_line
			(start 0.7874 -0.4064)
			(end 0.7874 0.4064)
			(stroke
				(width 0.1524)
				(type default)
			)
			(layer "F.SilkS")
		)
		(fp_line
			(start -0.67945 0.3048)
			(end -0.67945 -0.305054)
			(stroke
				(width 0.1)
				(type default)
			)
			(layer "F.Fab")
		)
		(fp_line
			(start -0.12065 0.3048)
			(end -0.67945 0.3048)
			(stroke
				(width 0.1)
				(type default)
			)
			(layer "F.Fab")
		)
		(fp_line
			(start 0.120396 0.3048)
			(end 0.120396 0.2794)
			(stroke
				(width 0.1)
				(type default)
			)
			(layer "F.Fab")
		)
		(fp_line
			(start 0.67945 0.3048)
			(end 0.120396 0.3048)
			(stroke
				(width 0.1)
				(type default)
			)
			(layer "F.Fab")
		)
		(fp_line
			(start -0.12065 0.2794)
			(end -0.12065 0.3048)
			(stroke
				(width 0.1)
				(type default)
			)
			(layer "F.Fab")
		)
		(fp_line
			(start 0.120396 0.2794)
			(end -0.12065 0.2794)
			(stroke
				(width 0.1)
				(type default)
			)
			(layer "F.Fab")
		)
		(fp_line
			(start -0.12065 -0.2794)
			(end 0.12065 -0.2794)
			(stroke
				(width 0.1)
				(type default)
			)
			(layer "F.Fab")
		)
		(fp_line
			(start 0.12065 -0.2794)
			(end 0.12065 -0.3048)
			(stroke
				(width 0.1)
				(type default)
			)
			(layer "F.Fab")
		)
		(fp_line
			(start 0.12065 -0.3048)
			(end 0.67945 -0.3048)
			(stroke
				(width 0.1)
				(type default)
			)
			(layer "F.Fab")
		)
		(fp_line
			(start 0.67945 -0.3048)
			(end 0.67945 0.3048)
			(stroke
				(width 0.1)
				(type default)
			)
			(layer "F.Fab")
		)
		(fp_line
			(start -0.67945 -0.305054)
			(end -0.12065 -0.305054)
			(stroke
				(width 0.1)
				(type default)
			)
			(layer "F.Fab")
		)
		(fp_line
			(start -0.12065 -0.305054)
			(end -0.12065 -0.2794)
			(stroke
				(width 0.1)
				(type default)
			)
			(layer "F.Fab")
		)
		(pad "1" smd circle
			(at -0.40005 0 270)
			(size 0 0)
			(layers "F.Cu" "F.Mask" "F.Paste")
			(net "P12V_AUX")
		)
		(pad "2" smd circle
			(at 0.40005 0 270)
			(size 0 0)
			(layers "F.Cu" "F.Mask" "F.Paste")
			(net "GND")
		)
	)
	(footprint ""
		(layer "F.Cu")
		(at 286.541718 -27.006296 -90)
		(property "Reference" "PR7120"
			(at 0 0 270)
			(layer "F.SilkS")
			(hide yes)
			(effects
				(font
					(size 1.27 1.27)
				)
			)
		)
		(property "Value" ""
			(at 0 0 270)
			(layer "F.Fab")
			(effects
				(font
					(size 1.27 1.27)
				)
			)
		)
		(duplicate_pad_numbers_are_jumpers no)
		(fp_line
			(start -0.7874 0.4064)
			(end -0.7874 -0.4064)
			(stroke
				(width 0.1524)
				(type default)
			)
			(layer "F.SilkS")
		)
		(fp_line
			(start 0.7874 0.4064)
			(end -0.7874 0.4064)
			(stroke
				(width 0.1524)
				(type default)
			)
			(layer "F.SilkS")
		)
		(fp_line
			(start -0.7874 -0.4064)
			(end 0.7874 -0.4064)
			(stroke
				(width 0.1524)
				(type default)
			)
			(layer "F.SilkS")
		)
		(fp_line
			(start 0.7874 -0.4064)
			(end 0.7874 0.4064)
			(stroke
				(width 0.1524)
				(type default)
			)
			(layer "F.SilkS")
		)
		(fp_line
			(start -0.67945 0.3048)
			(end -0.67945 -0.305054)
			(stroke
				(width 0.1)
				(type default)
			)
			(layer "F.Fab")
		)
		(fp_line
			(start -0.12065 0.3048)
			(end -0.67945 0.3048)
			(stroke
				(width 0.1)
				(type default)
			)
			(layer "F.Fab")
		)
		(fp_line
			(start 0.120396 0.3048)
			(end 0.120396 0.2794)
			(stroke
				(width 0.1)
				(type default)
			)
			(layer "F.Fab")
		)
		(fp_line
			(start 0.67945 0.3048)
			(end 0.120396 0.3048)
			(stroke
				(width 0.1)
				(type default)
			)
			(layer "F.Fab")
		)
		(fp_line
			(start -0.12065 0.2794)
			(end -0.12065 0.3048)
			(stroke
				(width 0.1)
				(type default)
			)
			(layer "F.Fab")
		)
		(fp_line
			(start 0.120396 0.2794)
			(end -0.12065 0.2794)
			(stroke
				(width 0.1)
				(type default)
			)
			(layer "F.Fab")
		)
		(fp_line
			(start -0.12065 -0.2794)
			(end 0.12065 -0.2794)
			(stroke
				(width 0.1)
				(type default)
			)
			(layer "F.Fab")
		)
		(fp_line
			(start 0.12065 -0.2794)
			(end 0.12065 -0.3048)
			(stroke
				(width 0.1)
				(type default)
			)
			(layer "F.Fab")
		)
		(fp_line
			(start 0.12065 -0.3048)
			(end 0.67945 -0.3048)
			(stroke
				(width 0.1)
				(type default)
			)
			(layer "F.Fab")
		)
		(fp_line
			(start 0.67945 -0.3048)
			(end 0.67945 0.3048)
			(stroke
				(width 0.1)
				(type default)
			)
			(layer "F.Fab")
		)
		(fp_line
			(start -0.67945 -0.305054)
			(end -0.12065 -0.305054)
			(stroke
				(width 0.1)
				(type default)
			)
			(layer "F.Fab")
		)
		(fp_line
			(start -0.12065 -0.305054)
			(end -0.12065 -0.2794)
			(stroke
				(width 0.1)
				(type default)
			)
			(layer "F.Fab")
		)
		(pad "1" smd circle
			(at -0.40005 0 270)
			(size 0 0)
			(layers "F.Cu" "F.Mask" "F.Paste")
			(net "P3V3_SSD10_CO_ILIMIT")
		)
		(pad "2" smd circle
			(at 0.40005 0 270)
			(size 0 0)
			(layers "F.Cu" "F.Mask" "F.Paste")
			(net "GND")
		)
	)
	(footprint ""
		(layer "F.Cu")
		(at 381.587756 -285.218632)
		(property "Reference" "C3580"
			(at 0 0 0)
			(layer "F.SilkS")
			(hide yes)
			(effects
				(font
					(size 1.27 1.27)
				)
			)
		)
		(property "Value" ""
			(at 0 0 0)
			(layer "F.Fab")
			(effects
				(font
					(size 1.27 1.27)
				)
			)
		)
		(duplicate_pad_numbers_are_jumpers no)
		(fp_line
			(start -1.2954 -0.5842)
			(end 1.2954 -0.5842)
			(stroke
				(width 0.1524)
				(type default)
			)
			(layer "F.SilkS")
		)
		(fp_line
			(start -1.2954 0.5842)
			(end -1.2954 -0.5842)
			(stroke
				(width 0.1524)
				(type default)
			)
			(layer "F.SilkS")
		)
		(fp_line
			(start 1.2954 -0.5842)
			(end 1.2954 0.5842)
			(stroke
				(width 0.1524)
				(type default)
			)
			(layer "F.SilkS")
		)
		(fp_line
			(start 1.2954 0.5842)
			(end -1.2954 0.5842)
			(stroke
				(width 0.1524)
				(type default)
			)
			(layer "F.SilkS")
		)
		(fp_line
			(start -1.1938 -0.4064)
			(end -0.8636 -0.4064)
			(stroke
				(width 0.1)
				(type default)
			)
			(layer "F.Fab")
		)
		(fp_line
			(start -1.1938 0.4064)
			(end -1.1938 -0.4064)
			(stroke
				(width 0.1)
				(type default)
			)
			(layer "F.Fab")
		)
		(fp_line
			(start -0.8636 -0.4572)
			(end 0.8636 -0.4572)
			(stroke
				(width 0.1)
				(type default)
			)
			(layer "F.Fab")
		)
		(fp_line
			(start -0.8636 -0.4064)
			(end -0.8636 -0.4572)
			(stroke
				(width 0.1)
				(type default)
			)
			(layer "F.Fab")
		)
		(fp_line
			(start -0.8636 0.4064)
			(end -1.1938 0.4064)
			(stroke
				(width 0.1)
				(type default)
			)
			(layer "F.Fab")
		)
		(fp_line
			(start -0.8636 0.4572)
			(end -0.8636 0.4064)
			(stroke
				(width 0.1)
				(type default)
			)
			(layer "F.Fab")
		)
		(fp_line
			(start 0.8636 -0.4572)
			(end 0.8636 -0.4064)
			(stroke
				(width 0.1)
				(type default)
			)
			(layer "F.Fab")
		)
		(fp_line
			(start 0.8636 -0.4064)
			(end 1.1938 -0.4064)
			(stroke
				(width 0.1)
				(type default)
			)
			(layer "F.Fab")
		)
		(fp_line
			(start 0.8636 0.4064)
			(end 0.8636 0.4572)
			(stroke
				(width 0.1)
				(type default)
			)
			(layer "F.Fab")
		)
		(fp_line
			(start 0.8636 0.4572)
			(end -0.8636 0.4572)
			(stroke
				(width 0.1)
				(type default)
			)
			(layer "F.Fab")
		)
		(fp_line
			(start 1.1938 -0.4064)
			(end 1.1938 0.4064)
			(stroke
				(width 0.1)
				(type default)
			)
			(layer "F.Fab")
		)
		(fp_line
			(start 1.1938 0.4064)
			(end 0.8636 0.4064)
			(stroke
				(width 0.1)
				(type default)
			)
			(layer "F.Fab")
		)
		(pad "1" smd rect
			(at -0.7366 0 270)
			(size 0.7112 0.8128)
			(layers "F.Cu" "F.Mask" "F.Paste")
			(net "PCEPLL7_VDDA18_PEX3")
		)
		(pad "2" smd rect
			(at 0.7366 0 270)
			(size 0.7112 0.8128)
			(layers "F.Cu" "F.Mask" "F.Paste")
			(net "GND")
		)
	)
	(footprint ""
		(layer "F.Cu")
		(at 195.414646 -81.36001 -90)
		(property "Reference" "R204"
			(at 0 0 270)
			(layer "F.SilkS")
			(hide yes)
			(effects
				(font
					(size 1.27 1.27)
				)
			)
		)
		(property "Value" ""
			(at 0 0 270)
			(layer "F.Fab")
			(effects
				(font
					(size 1.27 1.27)
				)
			)
		)
		(duplicate_pad_numbers_are_jumpers no)
		(fp_line
			(start -0.7874 0.4064)
			(end -0.7874 -0.4064)
			(stroke
				(width 0.1524)
				(type default)
			)
			(layer "F.SilkS")
		)
		(fp_line
			(start 0.7874 0.4064)
			(end -0.7874 0.4064)
			(stroke
				(width 0.1524)
				(type default)
			)
			(layer "F.SilkS")
		)
		(fp_line
			(start -0.7874 -0.4064)
			(end 0.7874 -0.4064)
			(stroke
				(width 0.1524)
				(type default)
			)
			(layer "F.SilkS")
		)
		(fp_line
			(start 0.7874 -0.4064)
			(end 0.7874 0.4064)
			(stroke
				(width 0.1524)
				(type default)
			)
			(layer "F.SilkS")
		)
		(fp_line
			(start -0.67945 0.3048)
			(end -0.67945 -0.305054)
			(stroke
				(width 0.1)
				(type default)
			)
			(layer "F.Fab")
		)
		(fp_line
			(start -0.12065 0.3048)
			(end -0.67945 0.3048)
			(stroke
				(width 0.1)
				(type default)
			)
			(layer "F.Fab")
		)
		(fp_line
			(start 0.120396 0.3048)
			(end 0.120396 0.2794)
			(stroke
				(width 0.1)
				(type default)
			)
			(layer "F.Fab")
		)
		(fp_line
			(start 0.67945 0.3048)
			(end 0.120396 0.3048)
			(stroke
				(width 0.1)
				(type default)
			)
			(layer "F.Fab")
		)
		(fp_line
			(start -0.12065 0.2794)
			(end -0.12065 0.3048)
			(stroke
				(width 0.1)
				(type default)
			)
			(layer "F.Fab")
		)
		(fp_line
			(start 0.120396 0.2794)
			(end -0.12065 0.2794)
			(stroke
				(width 0.1)
				(type default)
			)
			(layer "F.Fab")
		)
		(fp_line
			(start -0.12065 -0.2794)
			(end 0.12065 -0.2794)
			(stroke
				(width 0.1)
				(type default)
			)
			(layer "F.Fab")
		)
		(fp_line
			(start 0.12065 -0.2794)
			(end 0.12065 -0.3048)
			(stroke
				(width 0.1)
				(type default)
			)
			(layer "F.Fab")
		)
		(fp_line
			(start 0.12065 -0.3048)
			(end 0.67945 -0.3048)
			(stroke
				(width 0.1)
				(type default)
			)
			(layer "F.Fab")
		)
		(fp_line
			(start 0.67945 -0.3048)
			(end 0.67945 0.3048)
			(stroke
				(width 0.1)
				(type default)
			)
			(layer "F.Fab")
		)
		(fp_line
			(start -0.67945 -0.305054)
			(end -0.12065 -0.305054)
			(stroke
				(width 0.1)
				(type default)
			)
			(layer "F.Fab")
		)
		(fp_line
			(start -0.12065 -0.305054)
			(end -0.12065 -0.2794)
			(stroke
				(width 0.1)
				(type default)
			)
			(layer "F.Fab")
		)
		(pad "1" smd circle
			(at -0.40005 0 270)
			(size 0 0)
			(layers "F.Cu" "F.Mask" "F.Paste")
			(net "HP_NIC3_PWRGD_R")
		)
		(pad "2" smd circle
			(at 0.40005 0 270)
			(size 0 0)
			(layers "F.Cu" "F.Mask" "F.Paste")
			(net "HP_NIC3_PWRGD")
		)
	)
	(footprint ""
		(layer "F.Cu")
		(at 123.71324 -137.344404 180)
		(property "Reference" "PR201"
			(at 0 0 180)
			(layer "F.SilkS")
			(hide yes)
			(effects
				(font
					(size 1.27 1.27)
				)
			)
		)
		(property "Value" ""
			(at 0 0 180)
			(layer "F.Fab")
			(effects
				(font
					(size 1.27 1.27)
				)
			)
		)
		(duplicate_pad_numbers_are_jumpers no)
		(fp_line
			(start 0.7874 0.4064)
			(end -0.7874 0.4064)
			(stroke
				(width 0.1524)
				(type default)
			)
			(layer "F.SilkS")
		)
		(fp_line
			(start 0.7874 -0.4064)
			(end 0.7874 0.4064)
			(stroke
				(width 0.1524)
				(type default)
			)
			(layer "F.SilkS")
		)
		(fp_line
			(start -0.7874 0.4064)
			(end -0.7874 -0.4064)
			(stroke
				(width 0.1524)
				(type default)
			)
			(layer "F.SilkS")
		)
		(fp_line
			(start -0.7874 -0.4064)
			(end 0.7874 -0.4064)
			(stroke
				(width 0.1524)
				(type default)
			)
			(layer "F.SilkS")
		)
		(fp_line
			(start 0.67945 0.3048)
			(end 0.120396 0.3048)
			(stroke
				(width 0.1)
				(type default)
			)
			(layer "F.Fab")
		)
		(fp_line
			(start 0.67945 -0.3048)
			(end 0.67945 0.3048)
			(stroke
				(width 0.1)
				(type default)
			)
			(layer "F.Fab")
		)
		(fp_line
			(start 0.12065 -0.2794)
			(end 0.12065 -0.3048)
			(stroke
				(width 0.1)
				(type default)
			)
			(layer "F.Fab")
		)
		(fp_line
			(start 0.12065 -0.3048)
			(end 0.67945 -0.3048)
			(stroke
				(width 0.1)
				(type default)
			)
			(layer "F.Fab")
		)
		(fp_line
			(start 0.120396 0.3048)
			(end 0.120396 0.2794)
			(stroke
				(width 0.1)
				(type default)
			)
			(layer "F.Fab")
		)
		(fp_line
			(start 0.120396 0.2794)
			(end -0.12065 0.2794)
			(stroke
				(width 0.1)
				(type default)
			)
			(layer "F.Fab")
		)
		(fp_line
			(start -0.12065 0.3048)
			(end -0.67945 0.3048)
			(stroke
				(width 0.1)
				(type default)
			)
			(layer "F.Fab")
		)
		(fp_line
			(start -0.12065 0.2794)
			(end -0.12065 0.3048)
			(stroke
				(width 0.1)
				(type default)
			)
			(layer "F.Fab")
		)
		(fp_line
			(start -0.12065 -0.2794)
			(end 0.12065 -0.2794)
			(stroke
				(width 0.1)
				(type default)
			)
			(layer "F.Fab")
		)
		(fp_line
			(start -0.12065 -0.305054)
			(end -0.12065 -0.2794)
			(stroke
				(width 0.1)
				(type default)
			)
			(layer "F.Fab")
		)
		(fp_line
			(start -0.67945 0.3048)
			(end -0.67945 -0.305054)
			(stroke
				(width 0.1)
				(type default)
			)
			(layer "F.Fab")
		)
		(fp_line
			(start -0.67945 -0.305054)
			(end -0.12065 -0.305054)
			(stroke
				(width 0.1)
				(type default)
			)
			(layer "F.Fab")
		)
		(pad "1" smd circle
			(at -0.40005 0 180)
			(size 0 0)
			(layers "F.Cu" "F.Mask" "F.Paste")
			(net "P12V_NIC2_OCP")
		)
		(pad "2" smd circle
			(at 0.40005 0 180)
			(size 0 0)
			(layers "F.Cu" "F.Mask" "F.Paste")
			(net "GND")
		)
	)
	(footprint ""
		(layer "F.Cu")
		(at 122.630692 -284.8991 180)
		(property "Reference" "PU9"
			(at -15.980918 -1.567688 90)
			(unlocked yes)
			(layer "F.SilkS")
			(effects
				(font
					(size 0.7874 0.5842)
					(thickness 0.1524)
				)
			)
		)
		(property "Value" ""
			(at 0 0 180)
			(layer "F.Fab")
			(effects
				(font
					(size 1.27 1.27)
				)
			)
		)
		(duplicate_pad_numbers_are_jumpers no)
		(fp_line
			(start 2.500122 2.999994)
			(end 2.2987 2.999994)
			(stroke
				(width 0.1524)
				(type default)
			)
			(layer "F.SilkS")
		)
		(fp_line
			(start 2.500122 2.339594)
			(end 2.500122 2.999994)
			(stroke
				(width 0.1524)
				(type default)
			)
			(layer "F.SilkS")
		)
		(fp_line
			(start 2.500122 -2.999994)
			(end 2.500122 -2.44348)
			(stroke
				(width 0.1524)
				(type default)
			)
			(layer "F.SilkS")
		)
		(fp_line
			(start 2.31394 -2.999994)
			(end 2.500122 -2.999994)
			(stroke
				(width 0.1524)
				(type default)
			)
			(layer "F.SilkS")
		)
		(fp_line
			(start -2.2987 2.999994)
			(end -2.500122 2.999994)
			(stroke
				(width 0.1524)
				(type default)
			)
			(layer "F.SilkS")
		)
		(fp_line
			(start -2.500122 2.999994)
			(end -2.500122 2.339594)
			(stroke
				(width 0.1524)
				(type default)
			)
			(layer "F.SilkS")
		)
		(fp_line
			(start -2.500122 0.6604)
			(end -2.500122 0.229108)
			(stroke
				(width 0.1524)
				(type default)
			)
			(layer "F.SilkS")
		)
		(fp_line
			(start -2.500122 -2.529078)
			(end -2.500122 -2.999994)
			(stroke
				(width 0.1524)
				(type default)
			)
			(layer "F.SilkS")
		)
		(fp_line
			(start -2.500122 -2.999994)
			(end -2.24409 -2.999994)
			(stroke
				(width 0.1524)
				(type default)
			)
			(layer "F.SilkS")
		)
		(fp_poly
			(pts
				(xy -2.347722 -3.580384) (xy -3.363722 -3.580384) (xy -2.855722 -2.564384)
			)
			(stroke
				(width 0)
				(type default)
			)
			(fill yes)
			(layer "F.SilkS")
		)
		(fp_line
			(start 2.500122 2.999994)
			(end -2.500122 2.999994)
			(stroke
				(width 0.1)
				(type default)
			)
			(layer "F.Fab")
		)
		(fp_line
			(start 2.500122 -2.999994)
			(end 2.500122 2.999994)
			(stroke
				(width 0.1)
				(type default)
			)
			(layer "F.Fab")
		)
		(fp_line
			(start -2.500122 2.999994)
			(end -2.500122 -2.999994)
			(stroke
				(width 0.1)
				(type default)
			)
			(layer "F.Fab")
		)
		(fp_line
			(start -2.500122 -2.999994)
			(end 2.500122 -2.999994)
			(stroke
				(width 0.1)
				(type default)
			)
			(layer "F.Fab")
		)
		(fp_poly
			(pts
				(xy -4.218432 -2.783078) (xy -4.218432 -1.767078) (xy -3.202432 -2.275078)
			)
			(stroke
				(width 0)
				(type default)
			)
			(fill yes)
			(layer "F.Fab")
		)
		(pad "1" smd rect
			(at -2.400046 -2.275078 270)
			(size 0.2286 0.6096)
			(layers "F.Cu" "F.Mask" "F.Paste")
			(net "SW_P0V8_PEX1_VOS1")
		)
		(pad "2" smd rect
			(at -2.400046 -1.82499 270)
			(size 0.2286 0.6096)
			(layers "F.Cu" "F.Mask" "F.Paste")
			(net "GND")
		)
		(pad "3" smd rect
			(at -2.400046 -1.374902 270)
			(size 0.2286 0.6096)
			(layers "F.Cu" "F.Mask" "F.Paste")
			(net "P0V8_PEX1_VCC1")
		)
		(pad "4" smd rect
			(at -2.400046 -0.925068 270)
			(size 0.2286 0.6096)
			(layers "F.Cu" "F.Mask" "F.Paste")
			(net "P0V8_PEX1_PVCC")
		)
		(pad "5" smd rect
			(at -2.400046 -0.47498 270)
			(size 0.2286 0.6096)
			(layers "F.Cu" "F.Mask" "F.Paste")
			(net "GND")
		)
		(pad "6" smd rect
			(at -2.400046 -0.024892 270)
			(size 0.2286 0.6096)
			(layers "F.Cu" "F.Mask" "F.Paste")
			(net "NC_P0V8_PEX1_PH1_NC1")
		)
		(pad "7_9-20_24" smd circle
			(at 0 1.150112 270)
			(size 0 0)
			(layers "F.Cu" "F.Mask" "F.Paste")
			(net "GND")
		)
		(pad "10_19" smd rect
			(at 0 2.899918 270)
			(size 0.6096 4.318)
			(layers "F.Cu" "F.Mask" "F.Paste")
			(net "SW_P0V8_PEX1_PH1")
		)
		(pad "25_29" smd rect
			(at 1.549908 -1.279906 90)
			(size 2.0574 2.3114)
			(layers "F.Cu" "F.Mask" "F.Paste")
			(net "SW_P12V_P0V8_PEX1_FLT")
		)
		(pad "30" smd rect
			(at 2.05994 -2.899918 180)
			(size 0.2286 0.6096)
			(layers "F.Cu" "F.Mask" "F.Paste")
			(net "SW_P12V_P0V8_PEX1_FLT")
		)
		(pad "31" smd rect
			(at 1.610106 -2.899918 180)
			(size 0.2286 0.6096)
			(layers "F.Cu" "F.Mask" "F.Paste")
			(net "NC_P0V8_PEX1_PH1_NC3")
		)
		(pad "32" smd rect
			(at 1.160018 -2.899918 180)
			(size 0.2286 0.6096)
			(layers "F.Cu" "F.Mask" "F.Paste")
			(net "SW_P0V8_PEX1_PHASE1")
		)
		(pad "33" smd rect
			(at 0.70993 -2.899918 180)
			(size 0.2286 0.6096)
			(layers "F.Cu" "F.Mask" "F.Paste")
			(net "SW_P0V8_PEX1_BOOT1")
		)
		(pad "34" smd rect
			(at 0.260096 -2.899918 180)
			(size 0.2286 0.6096)
			(layers "F.Cu" "F.Mask" "F.Paste")
			(net "P0V8_PEX1_PWM1")
		)
		(pad "35" smd rect
			(at -0.189992 -2.899918 180)
			(size 0.2286 0.6096)
			(layers "F.Cu" "F.Mask" "F.Paste")
			(net "P0V8_PEX0_EN3")
		)
		(pad "36" smd rect
			(at -0.64008 -2.899918 180)
			(size 0.2286 0.6096)
			(layers "F.Cu" "F.Mask" "F.Paste")
			(net "P0V8_PEX1_TSEN")
		)
		(pad "37" smd rect
			(at -1.089914 -2.899918 180)
			(size 0.2286 0.6096)
			(layers "F.Cu" "F.Mask" "F.Paste")
			(net "P0V8_PEX1_LSET1")
		)
		(pad "38" smd rect
			(at -1.540002 -2.899918 180)
			(size 0.2286 0.6096)
			(layers "F.Cu" "F.Mask" "F.Paste")
			(net "P0V8_PEX1_ISEN1")
		)
		(pad "39" smd rect
			(at -1.99009 -2.899918 180)
			(size 0.2286 0.6096)
			(layers "F.Cu" "F.Mask" "F.Paste")
			(net "P0V8_PEX0_VREF")
		)
		(pad "40" smd rect
			(at -0.87503 -1.27508 180)
			(size 1.7526 1.9558)
			(layers "F.Cu" "F.Mask" "F.Paste")
			(net "GND")
		)
		(pad "41" smd rect
			(at -1.525016 0.249936 90)
			(size 0.3048 0.4572)
			(layers "F.Cu" "F.Mask" "F.Paste")
			(net "NC_P0V8_PEX1_PH1_NC2")
		)
		(zone
			(layer "F.Cu")
			(hatch none 0.5)
			(connect_pads
				(clearance 0)
			)
			(min_thickness 0.25)
			(keepout
				(tracks not_allowed)
				(vias allowed)
				(pads allowed)
				(copperpour not_allowed)
				(footprints allowed)
			)
			(placement
				(enabled no)
				(sheetname "")
			)
			(fill
				(thermal_gap 0.5)
				(thermal_bridge_width 0.5)
				(island_removal_mode 0)
			)
			(polygon
				(pts
					(xy 125.130814 -287.899094) (xy 125.130814 -287.149794) (xy 120.13057 -287.149794) (xy 120.13057 -287.899094)
					(xy 120.420892 -287.899094) (xy 120.420892 -287.443418) (xy 124.840492 -287.443418) (xy 124.840492 -287.899094)
				)
			)
		)
	)
	(footprint ""
		(layer "F.Cu")
		(at 359.85831 -254.194564)
		(property "Reference" "C834"
			(at 0 0 0)
			(layer "F.SilkS")
			(hide yes)
			(effects
				(font
					(size 1.27 1.27)
				)
			)
		)
		(property "Value" ""
			(at 0 0 0)
			(layer "F.Fab")
			(effects
				(font
					(size 1.27 1.27)
				)
			)
		)
		(duplicate_pad_numbers_are_jumpers no)
		(fp_line
			(start -0.7874 -0.4064)
			(end 0.7874 -0.4064)
			(stroke
				(width 0.1524)
				(type default)
			)
			(layer "F.SilkS")
		)
		(fp_line
			(start -0.7874 0.4064)
			(end -0.7874 -0.4064)
			(stroke
				(width 0.1524)
				(type default)
			)
			(layer "F.SilkS")
		)
		(fp_line
			(start 0.7874 -0.4064)
			(end 0.7874 0.4064)
			(stroke
				(width 0.1524)
				(type default)
			)
			(layer "F.SilkS")
		)
		(fp_line
			(start 0.7874 0.4064)
			(end -0.7874 0.4064)
			(stroke
				(width 0.1524)
				(type default)
			)
			(layer "F.SilkS")
		)
		(fp_line
			(start -0.67945 -0.305054)
			(end -0.12065 -0.305054)
			(stroke
				(width 0.1)
				(type default)
			)
			(layer "F.Fab")
		)
		(fp_line
			(start -0.67945 0.3048)
			(end -0.67945 -0.305054)
			(stroke
				(width 0.1)
				(type default)
			)
			(layer "F.Fab")
		)
		(fp_line
			(start -0.12065 -0.305054)
			(end -0.12065 -0.2794)
			(stroke
				(width 0.1)
				(type default)
			)
			(layer "F.Fab")
		)
		(fp_line
			(start -0.12065 -0.2794)
			(end 0.12065 -0.2794)
			(stroke
				(width 0.1)
				(type default)
			)
			(layer "F.Fab")
		)
		(fp_line
			(start -0.12065 0.2794)
			(end -0.12065 0.3048)
			(stroke
				(width 0.1)
				(type default)
			)
			(layer "F.Fab")
		)
		(fp_line
			(start -0.12065 0.3048)
			(end -0.67945 0.3048)
			(stroke
				(width 0.1)
				(type default)
			)
			(layer "F.Fab")
		)
		(fp_line
			(start 0.120396 0.2794)
			(end -0.12065 0.2794)
			(stroke
				(width 0.1)
				(type default)
			)
			(layer "F.Fab")
		)
		(fp_line
			(start 0.120396 0.3048)
			(end 0.120396 0.2794)
			(stroke
				(width 0.1)
				(type default)
			)
			(layer "F.Fab")
		)
		(fp_line
			(start 0.12065 -0.3048)
			(end 0.67945 -0.3048)
			(stroke
				(width 0.1)
				(type default)
			)
			(layer "F.Fab")
		)
		(fp_line
			(start 0.12065 -0.2794)
			(end 0.12065 -0.3048)
			(stroke
				(width 0.1)
				(type default)
			)
			(layer "F.Fab")
		)
		(fp_line
			(start 0.67945 -0.3048)
			(end 0.67945 0.3048)
			(stroke
				(width 0.1)
				(type default)
			)
			(layer "F.Fab")
		)
		(fp_line
			(start 0.67945 0.3048)
			(end 0.120396 0.3048)
			(stroke
				(width 0.1)
				(type default)
			)
			(layer "F.Fab")
		)
		(pad "1" smd circle
			(at -0.40005 0)
			(size 0 0)
			(layers "F.Cu" "F.Mask" "F.Paste")
			(net "P0V8_PEX2_AVRRDY")
		)
		(pad "2" smd circle
			(at 0.40005 0)
			(size 0 0)
			(layers "F.Cu" "F.Mask" "F.Paste")
			(net "GND")
		)
	)
	(footprint ""
		(layer "F.Cu")
		(at 26.162254 -262.645652 90)
		(property "Reference" "C3018"
			(at 0 0 90)
			(layer "F.SilkS")
			(hide yes)
			(effects
				(font
					(size 1.27 1.27)
				)
			)
		)
		(property "Value" ""
			(at 0 0 90)
			(layer "F.Fab")
			(effects
				(font
					(size 1.27 1.27)
				)
			)
		)
		(duplicate_pad_numbers_are_jumpers no)
		(fp_line
			(start 0.299974 -0.150114)
			(end 0.299974 0.150114)
			(stroke
				(width 0.1)
				(type default)
			)
			(layer "F.Fab")
		)
		(fp_line
			(start -0.299974 -0.150114)
			(end 0.299974 -0.150114)
			(stroke
				(width 0.1)
				(type default)
			)
			(layer "F.Fab")
		)
		(fp_line
			(start 0.299974 0.150114)
			(end -0.299974 0.150114)
			(stroke
				(width 0.1)
				(type default)
			)
			(layer "F.Fab")
		)
		(fp_line
			(start -0.299974 0.150114)
			(end -0.299974 -0.150114)
			(stroke
				(width 0.1)
				(type default)
			)
			(layer "F.Fab")
		)
		(pad "1" smd rect
			(at -0.2667 0 90)
			(size 0.3048 0.381)
			(layers "F.Cu" "F.Mask" "F.Paste")
			(net "P1V8_PLL0_PEX0")
		)
		(pad "2" smd rect
			(at 0.2667 0 90)
			(size 0.3048 0.381)
			(layers "F.Cu" "F.Mask" "F.Paste")
			(net "GND")
		)
	)
	(footprint ""
		(layer "F.Cu")
		(at 312.21934 -123.184666 180)
		(property "Reference" "C449"
			(at 0 0 180)
			(layer "F.SilkS")
			(hide yes)
			(effects
				(font
					(size 1.27 1.27)
				)
			)
		)
		(property "Value" ""
			(at 0 0 180)
			(layer "F.Fab")
			(effects
				(font
					(size 1.27 1.27)
				)
			)
		)
		(duplicate_pad_numbers_are_jumpers no)
		(fp_line
			(start 0.299974 0.150114)
			(end -0.299974 0.150114)
			(stroke
				(width 0.1)
				(type default)
			)
			(layer "F.Fab")
		)
		(fp_line
			(start 0.299974 -0.150114)
			(end 0.299974 0.150114)
			(stroke
				(width 0.1)
				(type default)
			)
			(layer "F.Fab")
		)
		(fp_line
			(start -0.299974 0.150114)
			(end -0.299974 -0.150114)
			(stroke
				(width 0.1)
				(type default)
			)
			(layer "F.Fab")
		)
		(fp_line
			(start -0.299974 -0.150114)
			(end 0.299974 -0.150114)
			(stroke
				(width 0.1)
				(type default)
			)
			(layer "F.Fab")
		)
		(pad "1" smd rect
			(at -0.2667 0 180)
			(size 0.3048 0.381)
			(layers "F.Cu" "F.Mask" "F.Paste")
			(net "P5E_PEX2_STN0_TX_DP<2>")
		)
		(pad "2" smd rect
			(at 0.2667 0 180)
			(size 0.3048 0.381)
			(layers "F.Cu" "F.Mask" "F.Paste")
			(net "P5E_PEX2_STN0_TX_C_DP<2>")
		)
	)
	(footprint ""
		(layer "F.Cu")
		(at 34.110422 -63.652146 180)
		(property "Reference" "R5841"
			(at 0 0 180)
			(layer "F.SilkS")
			(hide yes)
			(effects
				(font
					(size 1.27 1.27)
				)
			)
		)
		(property "Value" ""
			(at 0 0 180)
			(layer "F.Fab")
			(effects
				(font
					(size 1.27 1.27)
				)
			)
		)
		(duplicate_pad_numbers_are_jumpers no)
		(fp_line
			(start 0.7874 0.4064)
			(end -0.7874 0.4064)
			(stroke
				(width 0.1524)
				(type default)
			)
			(layer "F.SilkS")
		)
		(fp_line
			(start 0.7874 -0.4064)
			(end 0.7874 0.4064)
			(stroke
				(width 0.1524)
				(type default)
			)
			(layer "F.SilkS")
		)
		(fp_line
			(start -0.7874 0.4064)
			(end -0.7874 -0.4064)
			(stroke
				(width 0.1524)
				(type default)
			)
			(layer "F.SilkS")
		)
		(fp_line
			(start -0.7874 -0.4064)
			(end 0.7874 -0.4064)
			(stroke
				(width 0.1524)
				(type default)
			)
			(layer "F.SilkS")
		)
		(fp_line
			(start 0.67945 0.3048)
			(end 0.120396 0.3048)
			(stroke
				(width 0.1)
				(type default)
			)
			(layer "F.Fab")
		)
		(fp_line
			(start 0.67945 -0.3048)
			(end 0.67945 0.3048)
			(stroke
				(width 0.1)
				(type default)
			)
			(layer "F.Fab")
		)
		(fp_line
			(start 0.12065 -0.2794)
			(end 0.12065 -0.3048)
			(stroke
				(width 0.1)
				(type default)
			)
			(layer "F.Fab")
		)
		(fp_line
			(start 0.12065 -0.3048)
			(end 0.67945 -0.3048)
			(stroke
				(width 0.1)
				(type default)
			)
			(layer "F.Fab")
		)
		(fp_line
			(start 0.120396 0.3048)
			(end 0.120396 0.2794)
			(stroke
				(width 0.1)
				(type default)
			)
			(layer "F.Fab")
		)
		(fp_line
			(start 0.120396 0.2794)
			(end -0.12065 0.2794)
			(stroke
				(width 0.1)
				(type default)
			)
			(layer "F.Fab")
		)
		(fp_line
			(start -0.12065 0.3048)
			(end -0.67945 0.3048)
			(stroke
				(width 0.1)
				(type default)
			)
			(layer "F.Fab")
		)
		(fp_line
			(start -0.12065 0.2794)
			(end -0.12065 0.3048)
			(stroke
				(width 0.1)
				(type default)
			)
			(layer "F.Fab")
		)
		(fp_line
			(start -0.12065 -0.2794)
			(end 0.12065 -0.2794)
			(stroke
				(width 0.1)
				(type default)
			)
			(layer "F.Fab")
		)
		(fp_line
			(start -0.12065 -0.305054)
			(end -0.12065 -0.2794)
			(stroke
				(width 0.1)
				(type default)
			)
			(layer "F.Fab")
		)
		(fp_line
			(start -0.67945 0.3048)
			(end -0.67945 -0.305054)
			(stroke
				(width 0.1)
				(type default)
			)
			(layer "F.Fab")
		)
		(fp_line
			(start -0.67945 -0.305054)
			(end -0.12065 -0.305054)
			(stroke
				(width 0.1)
				(type default)
			)
			(layer "F.Fab")
		)
		(pad "1" smd circle
			(at -0.40005 0 180)
			(size 0 0)
			(layers "F.Cu" "F.Mask" "F.Paste")
			(net "P5V_AUX")
		)
		(pad "2" smd circle
			(at 0.40005 0 180)
			(size 0 0)
			(layers "F.Cu" "F.Mask" "F.Paste")
			(net "P12V_SSD1_PG_G2")
		)
	)
	(footprint ""
		(layer "F.Cu")
		(at 434.510942 -61.386974)
		(property "Reference" "R4510"
			(at 0 0 0)
			(layer "F.SilkS")
			(hide yes)
			(effects
				(font
					(size 1.27 1.27)
				)
			)
		)
		(property "Value" ""
			(at 0 0 0)
			(layer "F.Fab")
			(effects
				(font
					(size 1.27 1.27)
				)
			)
		)
		(duplicate_pad_numbers_are_jumpers no)
		(fp_line
			(start -0.7874 -0.4064)
			(end 0.7874 -0.4064)
			(stroke
				(width 0.1524)
				(type default)
			)
			(layer "F.SilkS")
		)
		(fp_line
			(start -0.7874 0.4064)
			(end -0.7874 -0.4064)
			(stroke
				(width 0.1524)
				(type default)
			)
			(layer "F.SilkS")
		)
		(fp_line
			(start 0.7874 -0.4064)
			(end 0.7874 0.4064)
			(stroke
				(width 0.1524)
				(type default)
			)
			(layer "F.SilkS")
		)
		(fp_line
			(start 0.7874 0.4064)
			(end -0.7874 0.4064)
			(stroke
				(width 0.1524)
				(type default)
			)
			(layer "F.SilkS")
		)
		(fp_line
			(start -0.67945 -0.305054)
			(end -0.12065 -0.305054)
			(stroke
				(width 0.1)
				(type default)
			)
			(layer "F.Fab")
		)
		(fp_line
			(start -0.67945 0.3048)
			(end -0.67945 -0.305054)
			(stroke
				(width 0.1)
				(type default)
			)
			(layer "F.Fab")
		)
		(fp_line
			(start -0.12065 -0.305054)
			(end -0.12065 -0.2794)
			(stroke
				(width 0.1)
				(type default)
			)
			(layer "F.Fab")
		)
		(fp_line
			(start -0.12065 -0.2794)
			(end 0.12065 -0.2794)
			(stroke
				(width 0.1)
				(type default)
			)
			(layer "F.Fab")
		)
		(fp_line
			(start -0.12065 0.2794)
			(end -0.12065 0.3048)
			(stroke
				(width 0.1)
				(type default)
			)
			(layer "F.Fab")
		)
		(fp_line
			(start -0.12065 0.3048)
			(end -0.67945 0.3048)
			(stroke
				(width 0.1)
				(type default)
			)
			(layer "F.Fab")
		)
		(fp_line
			(start 0.120396 0.2794)
			(end -0.12065 0.2794)
			(stroke
				(width 0.1)
				(type default)
			)
			(layer "F.Fab")
		)
		(fp_line
			(start 0.120396 0.3048)
			(end 0.120396 0.2794)
			(stroke
				(width 0.1)
				(type default)
			)
			(layer "F.Fab")
		)
		(fp_line
			(start 0.12065 -0.3048)
			(end 0.67945 -0.3048)
			(stroke
				(width 0.1)
				(type default)
			)
			(layer "F.Fab")
		)
		(fp_line
			(start 0.12065 -0.2794)
			(end 0.12065 -0.3048)
			(stroke
				(width 0.1)
				(type default)
			)
			(layer "F.Fab")
		)
		(fp_line
			(start 0.67945 -0.3048)
			(end 0.67945 0.3048)
			(stroke
				(width 0.1)
				(type default)
			)
			(layer "F.Fab")
		)
		(fp_line
			(start 0.67945 0.3048)
			(end 0.120396 0.3048)
			(stroke
				(width 0.1)
				(type default)
			)
			(layer "F.Fab")
		)
		(pad "1" smd circle
			(at -0.40005 0)
			(size 0 0)
			(layers "F.Cu" "F.Mask" "F.Paste")
			(net "PWRGD_P3V3_SSD15")
		)
		(pad "2" smd circle
			(at 0.40005 0)
			(size 0 0)
			(layers "F.Cu" "F.Mask" "F.Paste")
			(net "PWRGD_P3V3_SSD15_R")
		)
	)
	(footprint ""
		(layer "F.Cu")
		(at 98.975672 -121.509028)
		(property "Reference" "PR245"
			(at 0 0 0)
			(layer "F.SilkS")
			(hide yes)
			(effects
				(font
					(size 1.27 1.27)
				)
			)
		)
		(property "Value" ""
			(at 0 0 0)
			(layer "F.Fab")
			(effects
				(font
					(size 1.27 1.27)
				)
			)
		)
		(duplicate_pad_numbers_are_jumpers no)
		(fp_line
			(start -0.7874 -0.4064)
			(end 0.7874 -0.4064)
			(stroke
				(width 0.1524)
				(type default)
			)
			(layer "F.SilkS")
		)
		(fp_line
			(start -0.7874 0.4064)
			(end -0.7874 -0.4064)
			(stroke
				(width 0.1524)
				(type default)
			)
			(layer "F.SilkS")
		)
		(fp_line
			(start 0.7874 -0.4064)
			(end 0.7874 0.4064)
			(stroke
				(width 0.1524)
				(type default)
			)
			(layer "F.SilkS")
		)
		(fp_line
			(start 0.7874 0.4064)
			(end -0.7874 0.4064)
			(stroke
				(width 0.1524)
				(type default)
			)
			(layer "F.SilkS")
		)
		(fp_line
			(start -0.67945 -0.305054)
			(end -0.12065 -0.305054)
			(stroke
				(width 0.1)
				(type default)
			)
			(layer "F.Fab")
		)
		(fp_line
			(start -0.67945 0.3048)
			(end -0.67945 -0.305054)
			(stroke
				(width 0.1)
				(type default)
			)
			(layer "F.Fab")
		)
		(fp_line
			(start -0.12065 -0.305054)
			(end -0.12065 -0.2794)
			(stroke
				(width 0.1)
				(type default)
			)
			(layer "F.Fab")
		)
		(fp_line
			(start -0.12065 -0.2794)
			(end 0.12065 -0.2794)
			(stroke
				(width 0.1)
				(type default)
			)
			(layer "F.Fab")
		)
		(fp_line
			(start -0.12065 0.2794)
			(end -0.12065 0.3048)
			(stroke
				(width 0.1)
				(type default)
			)
			(layer "F.Fab")
		)
		(fp_line
			(start -0.12065 0.3048)
			(end -0.67945 0.3048)
			(stroke
				(width 0.1)
				(type default)
			)
			(layer "F.Fab")
		)
		(fp_line
			(start 0.120396 0.2794)
			(end -0.12065 0.2794)
			(stroke
				(width 0.1)
				(type default)
			)
			(layer "F.Fab")
		)
		(fp_line
			(start 0.120396 0.3048)
			(end 0.120396 0.2794)
			(stroke
				(width 0.1)
				(type default)
			)
			(layer "F.Fab")
		)
		(fp_line
			(start 0.12065 -0.3048)
			(end 0.67945 -0.3048)
			(stroke
				(width 0.1)
				(type default)
			)
			(layer "F.Fab")
		)
		(fp_line
			(start 0.12065 -0.2794)
			(end 0.12065 -0.3048)
			(stroke
				(width 0.1)
				(type default)
			)
			(layer "F.Fab")
		)
		(fp_line
			(start 0.67945 -0.3048)
			(end 0.67945 0.3048)
			(stroke
				(width 0.1)
				(type default)
			)
			(layer "F.Fab")
		)
		(fp_line
			(start 0.67945 0.3048)
			(end 0.120396 0.3048)
			(stroke
				(width 0.1)
				(type default)
			)
			(layer "F.Fab")
		)
		(pad "1" smd circle
			(at -0.40005 0)
			(size 0 0)
			(layers "F.Cu" "F.Mask" "F.Paste")
			(net "P3V3_NIC1_OCP")
		)
		(pad "2" smd circle
			(at 0.40005 0)
			(size 0 0)
			(layers "F.Cu" "F.Mask" "F.Paste")
			(net "GND")
		)
	)
	(footprint ""
		(layer "F.Cu")
		(at 108.601764 -224.137982 -90)
		(property "Reference" "PC295"
			(at 0 0 270)
			(layer "F.SilkS")
			(hide yes)
			(effects
				(font
					(size 1.27 1.27)
				)
			)
		)
		(property "Value" ""
			(at 0 0 270)
			(layer "F.Fab")
			(effects
				(font
					(size 1.27 1.27)
				)
			)
		)
		(duplicate_pad_numbers_are_jumpers no)
		(fp_line
			(start -0.7874 0.4064)
			(end -0.7874 -0.4064)
			(stroke
				(width 0.1524)
				(type default)
			)
			(layer "F.SilkS")
		)
		(fp_line
			(start 0.7874 0.4064)
			(end -0.7874 0.4064)
			(stroke
				(width 0.1524)
				(type default)
			)
			(layer "F.SilkS")
		)
		(fp_line
			(start -0.7874 -0.4064)
			(end 0.7874 -0.4064)
			(stroke
				(width 0.1524)
				(type default)
			)
			(layer "F.SilkS")
		)
		(fp_line
			(start 0.7874 -0.4064)
			(end 0.7874 0.4064)
			(stroke
				(width 0.1524)
				(type default)
			)
			(layer "F.SilkS")
		)
		(fp_line
			(start -0.67945 0.3048)
			(end -0.67945 -0.305054)
			(stroke
				(width 0.1)
				(type default)
			)
			(layer "F.Fab")
		)
		(fp_line
			(start -0.12065 0.3048)
			(end -0.67945 0.3048)
			(stroke
				(width 0.1)
				(type default)
			)
			(layer "F.Fab")
		)
		(fp_line
			(start 0.120396 0.3048)
			(end 0.120396 0.2794)
			(stroke
				(width 0.1)
				(type default)
			)
			(layer "F.Fab")
		)
		(fp_line
			(start 0.67945 0.3048)
			(end 0.120396 0.3048)
			(stroke
				(width 0.1)
				(type default)
			)
			(layer "F.Fab")
		)
		(fp_line
			(start -0.12065 0.2794)
			(end -0.12065 0.3048)
			(stroke
				(width 0.1)
				(type default)
			)
			(layer "F.Fab")
		)
		(fp_line
			(start 0.120396 0.2794)
			(end -0.12065 0.2794)
			(stroke
				(width 0.1)
				(type default)
			)
			(layer "F.Fab")
		)
		(fp_line
			(start -0.12065 -0.2794)
			(end 0.12065 -0.2794)
			(stroke
				(width 0.1)
				(type default)
			)
			(layer "F.Fab")
		)
		(fp_line
			(start 0.12065 -0.2794)
			(end 0.12065 -0.3048)
			(stroke
				(width 0.1)
				(type default)
			)
			(layer "F.Fab")
		)
		(fp_line
			(start 0.12065 -0.3048)
			(end 0.67945 -0.3048)
			(stroke
				(width 0.1)
				(type default)
			)
			(layer "F.Fab")
		)
		(fp_line
			(start 0.67945 -0.3048)
			(end 0.67945 0.3048)
			(stroke
				(width 0.1)
				(type default)
			)
			(layer "F.Fab")
		)
		(fp_line
			(start -0.67945 -0.305054)
			(end -0.12065 -0.305054)
			(stroke
				(width 0.1)
				(type default)
			)
			(layer "F.Fab")
		)
		(fp_line
			(start -0.12065 -0.305054)
			(end -0.12065 -0.2794)
			(stroke
				(width 0.1)
				(type default)
			)
			(layer "F.Fab")
		)
		(pad "1" smd circle
			(at -0.40005 0 270)
			(size 0 0)
			(layers "F.Cu" "F.Mask" "F.Paste")
			(net "P1V8_PEX_VCC")
		)
		(pad "2" smd circle
			(at 0.40005 0 270)
			(size 0 0)
			(layers "F.Cu" "F.Mask" "F.Paste")
			(net "GND")
		)
	)
	(footprint ""
		(layer "F.Cu")
		(at 458.935836 -111.896906 90)
		(property "Reference" "PR7060"
			(at 0 0 90)
			(layer "F.SilkS")
			(hide yes)
			(effects
				(font
					(size 1.27 1.27)
				)
			)
		)
		(property "Value" ""
			(at 0 0 90)
			(layer "F.Fab")
			(effects
				(font
					(size 1.27 1.27)
				)
			)
		)
		(duplicate_pad_numbers_are_jumpers no)
		(fp_line
			(start 0.7874 -0.4064)
			(end 0.7874 0.4064)
			(stroke
				(width 0.1524)
				(type default)
			)
			(layer "F.SilkS")
		)
		(fp_line
			(start -0.7874 -0.4064)
			(end 0.7874 -0.4064)
			(stroke
				(width 0.1524)
				(type default)
			)
			(layer "F.SilkS")
		)
		(fp_line
			(start 0.7874 0.4064)
			(end -0.7874 0.4064)
			(stroke
				(width 0.1524)
				(type default)
			)
			(layer "F.SilkS")
		)
		(fp_line
			(start -0.7874 0.4064)
			(end -0.7874 -0.4064)
			(stroke
				(width 0.1524)
				(type default)
			)
			(layer "F.SilkS")
		)
		(fp_line
			(start -0.12065 -0.305054)
			(end -0.12065 -0.2794)
			(stroke
				(width 0.1)
				(type default)
			)
			(layer "F.Fab")
		)
		(fp_line
			(start -0.67945 -0.305054)
			(end -0.12065 -0.305054)
			(stroke
				(width 0.1)
				(type default)
			)
			(layer "F.Fab")
		)
		(fp_line
			(start 0.67945 -0.3048)
			(end 0.67945 0.3048)
			(stroke
				(width 0.1)
				(type default)
			)
			(layer "F.Fab")
		)
		(fp_line
			(start 0.12065 -0.3048)
			(end 0.67945 -0.3048)
			(stroke
				(width 0.1)
				(type default)
			)
			(layer "F.Fab")
		)
		(fp_line
			(start 0.12065 -0.2794)
			(end 0.12065 -0.3048)
			(stroke
				(width 0.1)
				(type default)
			)
			(layer "F.Fab")
		)
		(fp_line
			(start -0.12065 -0.2794)
			(end 0.12065 -0.2794)
			(stroke
				(width 0.1)
				(type default)
			)
			(layer "F.Fab")
		)
		(fp_line
			(start 0.120396 0.2794)
			(end -0.12065 0.2794)
			(stroke
				(width 0.1)
				(type default)
			)
			(layer "F.Fab")
		)
		(fp_line
			(start -0.12065 0.2794)
			(end -0.12065 0.3048)
			(stroke
				(width 0.1)
				(type default)
			)
			(layer "F.Fab")
		)
		(fp_line
			(start 0.67945 0.3048)
			(end 0.120396 0.3048)
			(stroke
				(width 0.1)
				(type default)
			)
			(layer "F.Fab")
		)
		(fp_line
			(start 0.120396 0.3048)
			(end 0.120396 0.2794)
			(stroke
				(width 0.1)
				(type default)
			)
			(layer "F.Fab")
		)
		(fp_line
			(start -0.12065 0.3048)
			(end -0.67945 0.3048)
			(stroke
				(width 0.1)
				(type default)
			)
			(layer "F.Fab")
		)
		(fp_line
			(start -0.67945 0.3048)
			(end -0.67945 -0.305054)
			(stroke
				(width 0.1)
				(type default)
			)
			(layer "F.Fab")
		)
		(pad "1" smd circle
			(at -0.40005 0 90)
			(size 0 0)
			(layers "F.Cu" "F.Mask" "F.Paste")
			(net "P12V_NIC7_CO_ISET")
		)
		(pad "2" smd circle
			(at 0.40005 0 90)
			(size 0 0)
			(layers "F.Cu" "F.Mask" "F.Paste")
			(net "P12V_NIC7_CO_ISET_R")
		)
	)
	(footprint ""
		(layer "F.Cu")
		(at 61.173868 -388.33679 -90)
		(property "Reference" "C4041"
			(at 0 0 270)
			(layer "F.SilkS")
			(hide yes)
			(effects
				(font
					(size 1.27 1.27)
				)
			)
		)
		(property "Value" ""
			(at 0 0 270)
			(layer "F.Fab")
			(effects
				(font
					(size 1.27 1.27)
				)
			)
		)
		(duplicate_pad_numbers_are_jumpers no)
		(fp_line
			(start -0.7874 0.4064)
			(end -0.7874 -0.4064)
			(stroke
				(width 0.1524)
				(type default)
			)
			(layer "F.SilkS")
		)
		(fp_line
			(start 0.7874 0.4064)
			(end -0.7874 0.4064)
			(stroke
				(width 0.1524)
				(type default)
			)
			(layer "F.SilkS")
		)
		(fp_line
			(start -0.7874 -0.4064)
			(end 0.7874 -0.4064)
			(stroke
				(width 0.1524)
				(type default)
			)
			(layer "F.SilkS")
		)
		(fp_line
			(start 0.7874 -0.4064)
			(end 0.7874 0.4064)
			(stroke
				(width 0.1524)
				(type default)
			)
			(layer "F.SilkS")
		)
		(fp_line
			(start -0.67945 0.3048)
			(end -0.67945 -0.305054)
			(stroke
				(width 0.1)
				(type default)
			)
			(layer "F.Fab")
		)
		(fp_line
			(start -0.12065 0.3048)
			(end -0.67945 0.3048)
			(stroke
				(width 0.1)
				(type default)
			)
			(layer "F.Fab")
		)
		(fp_line
			(start 0.120396 0.3048)
			(end 0.120396 0.2794)
			(stroke
				(width 0.1)
				(type default)
			)
			(layer "F.Fab")
		)
		(fp_line
			(start 0.67945 0.3048)
			(end 0.120396 0.3048)
			(stroke
				(width 0.1)
				(type default)
			)
			(layer "F.Fab")
		)
		(fp_line
			(start -0.12065 0.2794)
			(end -0.12065 0.3048)
			(stroke
				(width 0.1)
				(type default)
			)
			(layer "F.Fab")
		)
		(fp_line
			(start 0.120396 0.2794)
			(end -0.12065 0.2794)
			(stroke
				(width 0.1)
				(type default)
			)
			(layer "F.Fab")
		)
		(fp_line
			(start -0.12065 -0.2794)
			(end 0.12065 -0.2794)
			(stroke
				(width 0.1)
				(type default)
			)
			(layer "F.Fab")
		)
		(fp_line
			(start 0.12065 -0.2794)
			(end 0.12065 -0.3048)
			(stroke
				(width 0.1)
				(type default)
			)
			(layer "F.Fab")
		)
		(fp_line
			(start 0.12065 -0.3048)
			(end 0.67945 -0.3048)
			(stroke
				(width 0.1)
				(type default)
			)
			(layer "F.Fab")
		)
		(fp_line
			(start 0.67945 -0.3048)
			(end 0.67945 0.3048)
			(stroke
				(width 0.1)
				(type default)
			)
			(layer "F.Fab")
		)
		(fp_line
			(start -0.67945 -0.305054)
			(end -0.12065 -0.305054)
			(stroke
				(width 0.1)
				(type default)
			)
			(layer "F.Fab")
		)
		(fp_line
			(start -0.12065 -0.305054)
			(end -0.12065 -0.2794)
			(stroke
				(width 0.1)
				(type default)
			)
			(layer "F.Fab")
		)
		(pad "1" smd circle
			(at -0.40005 0 270)
			(size 0 0)
			(layers "F.Cu" "F.Mask" "F.Paste")
			(net "GND")
		)
		(pad "2" smd circle
			(at 0.40005 0 270)
			(size 0 0)
			(layers "F.Cu" "F.Mask" "F.Paste")
			(net "GPU_PWR_BRAKE_N")
		)
	)
	(footprint ""
		(layer "F.Cu")
		(at 226.377754 -239.93729)
		(property "Reference" "U418"
			(at -2.032 -2.377948 0)
			(unlocked yes)
			(layer "F.SilkS")
			(effects
				(font
					(size 0.7874 0.5842)
					(thickness 0.1524)
				)
				(justify left)
			)
		)
		(property "Value" ""
			(at 0 0 0)
			(layer "F.Fab")
			(effects
				(font
					(size 1.27 1.27)
				)
			)
		)
		(duplicate_pad_numbers_are_jumpers no)
		(fp_line
			(start -2.0574 -1.651)
			(end -0.381 -1.651)
			(stroke
				(width 0.1524)
				(type default)
			)
			(layer "F.SilkS")
		)
		(fp_line
			(start -2.0574 1.651)
			(end -2.0574 -1.651)
			(stroke
				(width 0.1524)
				(type default)
			)
			(layer "F.SilkS")
		)
		(fp_line
			(start -0.381 -1.651)
			(end 0 -1.016)
			(stroke
				(width 0.1524)
				(type default)
			)
			(layer "F.SilkS")
		)
		(fp_line
			(start 0 -1.016)
			(end 0.381 -1.651)
			(stroke
				(width 0.1524)
				(type default)
			)
			(layer "F.SilkS")
		)
		(fp_line
			(start 0.381 -1.651)
			(end 2.0574 -1.651)
			(stroke
				(width 0.1524)
				(type default)
			)
			(layer "F.SilkS")
		)
		(fp_line
			(start 2.0574 -1.651)
			(end 2.0574 1.651)
			(stroke
				(width 0.1524)
				(type default)
			)
			(layer "F.SilkS")
		)
		(fp_line
			(start 2.0574 1.651)
			(end -2.0574 1.651)
			(stroke
				(width 0.1524)
				(type default)
			)
			(layer "F.SilkS")
		)
		(fp_poly
			(pts
				(xy -2.71272 -0.719328) (xy -2.71272 -1.344168) (xy -2.159 -1.016)
			)
			(stroke
				(width 0)
				(type default)
			)
			(fill yes)
			(layer "F.SilkS")
		)
		(fp_line
			(start -1.599946 -1.199896)
			(end -0.899922 -1.199896)
			(stroke
				(width 0.1)
				(type default)
			)
			(layer "F.Fab")
		)
		(fp_line
			(start -1.599946 1.199896)
			(end -1.599946 -1.199896)
			(stroke
				(width 0.1)
				(type default)
			)
			(layer "F.Fab")
		)
		(fp_line
			(start -0.899922 -1.549908)
			(end 0.899922 -1.549908)
			(stroke
				(width 0.1)
				(type default)
			)
			(layer "F.Fab")
		)
		(fp_line
			(start -0.899922 -1.199896)
			(end -0.899922 -1.549908)
			(stroke
				(width 0.1)
				(type default)
			)
			(layer "F.Fab")
		)
		(fp_line
			(start -0.899922 1.199896)
			(end -1.599946 1.199896)
			(stroke
				(width 0.1)
				(type default)
			)
			(layer "F.Fab")
		)
		(fp_line
			(start -0.899922 1.549908)
			(end -0.899922 1.199896)
			(stroke
				(width 0.1)
				(type default)
			)
			(layer "F.Fab")
		)
		(fp_line
			(start 0.899922 -1.549908)
			(end 0.899922 -1.199896)
			(stroke
				(width 0.1)
				(type default)
			)
			(layer "F.Fab")
		)
		(fp_line
			(start 0.899922 -1.199896)
			(end 1.599946 -1.199896)
			(stroke
				(width 0.1)
				(type default)
			)
			(layer "F.Fab")
		)
		(fp_line
			(start 0.899922 1.199896)
			(end 0.899922 1.549908)
			(stroke
				(width 0.1)
				(type default)
			)
			(layer "F.Fab")
		)
		(fp_line
			(start 0.899922 1.549908)
			(end -0.899922 1.549908)
			(stroke
				(width 0.1)
				(type default)
			)
			(layer "F.Fab")
		)
		(fp_line
			(start 1.599946 -1.199896)
			(end 1.599946 1.199896)
			(stroke
				(width 0.1)
				(type default)
			)
			(layer "F.Fab")
		)
		(fp_line
			(start 1.599946 1.199896)
			(end 0.899922 1.199896)
			(stroke
				(width 0.1)
				(type default)
			)
			(layer "F.Fab")
		)
		(fp_poly
			(pts
				(xy -2.71272 -0.719328) (xy -2.71272 -1.344168) (xy -2.159 -1.016)
			)
			(stroke
				(width 0)
				(type default)
			)
			(fill yes)
			(layer "F.Fab")
		)
		(pad "1" smd rect
			(at -1.225042 -0.94996 270)
			(size 0.5588 1.3462)
			(layers "F.Cu" "F.Mask" "F.Paste")
			(net "BIC_UART_BMC_SEL_R")
		)
		(pad "2" smd rect
			(at -1.225042 0 270)
			(size 0.5588 1.3462)
			(layers "F.Cu" "F.Mask" "F.Paste")
			(net "BIC_UART_BIC_SEL_R")
		)
		(pad "3" smd rect
			(at -1.225042 0.94996 270)
			(size 0.5588 1.3462)
			(layers "F.Cu" "F.Mask" "F.Paste")
			(net "GND")
		)
		(pad "4" smd rect
			(at 1.225042 0.94996 270)
			(size 0.5588 1.3462)
			(layers "F.Cu" "F.Mask" "F.Paste")
			(net "BIC_UART_SW_SEL1")
		)
		(pad "5" smd rect
			(at 1.225042 -0.94996 270)
			(size 0.5588 1.3462)
			(layers "F.Cu" "F.Mask" "F.Paste")
			(net "P3V3_AUX")
		)
	)
	(footprint ""
		(layer "F.Cu")
		(at 430.961546 -148.91131 180)
		(property "Reference" "C642"
			(at 0 0 180)
			(layer "F.SilkS")
			(hide yes)
			(effects
				(font
					(size 1.27 1.27)
				)
			)
		)
		(property "Value" ""
			(at 0 0 180)
			(layer "F.Fab")
			(effects
				(font
					(size 1.27 1.27)
				)
			)
		)
		(duplicate_pad_numbers_are_jumpers no)
		(fp_line
			(start 0.299974 0.150114)
			(end -0.299974 0.150114)
			(stroke
				(width 0.1)
				(type default)
			)
			(layer "F.Fab")
		)
		(fp_line
			(start 0.299974 -0.150114)
			(end 0.299974 0.150114)
			(stroke
				(width 0.1)
				(type default)
			)
			(layer "F.Fab")
		)
		(fp_line
			(start -0.299974 0.150114)
			(end -0.299974 -0.150114)
			(stroke
				(width 0.1)
				(type default)
			)
			(layer "F.Fab")
		)
		(fp_line
			(start -0.299974 -0.150114)
			(end 0.299974 -0.150114)
			(stroke
				(width 0.1)
				(type default)
			)
			(layer "F.Fab")
		)
		(pad "1" smd rect
			(at -0.2667 0 180)
			(size 0.3048 0.381)
			(layers "F.Cu" "F.Mask" "F.Paste")
			(net "P5E_PEX3_STN0_TX_DP<11>")
		)
		(pad "2" smd rect
			(at 0.2667 0 180)
			(size 0.3048 0.381)
			(layers "F.Cu" "F.Mask" "F.Paste")
			(net "P5E_PEX3_STN0_TX_C_DP<11>")
		)
	)
	(footprint ""
		(layer "F.Cu")
		(at 320.451988 -228.604318 -90)
		(property "Reference" "R2988"
			(at 0 0 270)
			(layer "F.SilkS")
			(hide yes)
			(effects
				(font
					(size 1.27 1.27)
				)
			)
		)
		(property "Value" ""
			(at 0 0 270)
			(layer "F.Fab")
			(effects
				(font
					(size 1.27 1.27)
				)
			)
		)
		(duplicate_pad_numbers_are_jumpers no)
		(fp_line
			(start -0.7874 0.4064)
			(end -0.7874 -0.4064)
			(stroke
				(width 0.1524)
				(type default)
			)
			(layer "F.SilkS")
		)
		(fp_line
			(start 0.7874 0.4064)
			(end -0.7874 0.4064)
			(stroke
				(width 0.1524)
				(type default)
			)
			(layer "F.SilkS")
		)
		(fp_line
			(start -0.7874 -0.4064)
			(end 0.7874 -0.4064)
			(stroke
				(width 0.1524)
				(type default)
			)
			(layer "F.SilkS")
		)
		(fp_line
			(start 0.7874 -0.4064)
			(end 0.7874 0.4064)
			(stroke
				(width 0.1524)
				(type default)
			)
			(layer "F.SilkS")
		)
		(fp_line
			(start -0.67945 0.3048)
			(end -0.67945 -0.305054)
			(stroke
				(width 0.1)
				(type default)
			)
			(layer "F.Fab")
		)
		(fp_line
			(start -0.12065 0.3048)
			(end -0.67945 0.3048)
			(stroke
				(width 0.1)
				(type default)
			)
			(layer "F.Fab")
		)
		(fp_line
			(start 0.120396 0.3048)
			(end 0.120396 0.2794)
			(stroke
				(width 0.1)
				(type default)
			)
			(layer "F.Fab")
		)
		(fp_line
			(start 0.67945 0.3048)
			(end 0.120396 0.3048)
			(stroke
				(width 0.1)
				(type default)
			)
			(layer "F.Fab")
		)
		(fp_line
			(start -0.12065 0.2794)
			(end -0.12065 0.3048)
			(stroke
				(width 0.1)
				(type default)
			)
			(layer "F.Fab")
		)
		(fp_line
			(start 0.120396 0.2794)
			(end -0.12065 0.2794)
			(stroke
				(width 0.1)
				(type default)
			)
			(layer "F.Fab")
		)
		(fp_line
			(start -0.12065 -0.2794)
			(end 0.12065 -0.2794)
			(stroke
				(width 0.1)
				(type default)
			)
			(layer "F.Fab")
		)
		(fp_line
			(start 0.12065 -0.2794)
			(end 0.12065 -0.3048)
			(stroke
				(width 0.1)
				(type default)
			)
			(layer "F.Fab")
		)
		(fp_line
			(start 0.12065 -0.3048)
			(end 0.67945 -0.3048)
			(stroke
				(width 0.1)
				(type default)
			)
			(layer "F.Fab")
		)
		(fp_line
			(start 0.67945 -0.3048)
			(end 0.67945 0.3048)
			(stroke
				(width 0.1)
				(type default)
			)
			(layer "F.Fab")
		)
		(fp_line
			(start -0.67945 -0.305054)
			(end -0.12065 -0.305054)
			(stroke
				(width 0.1)
				(type default)
			)
			(layer "F.Fab")
		)
		(fp_line
			(start -0.12065 -0.305054)
			(end -0.12065 -0.2794)
			(stroke
				(width 0.1)
				(type default)
			)
			(layer "F.Fab")
		)
		(pad "1" smd circle
			(at -0.40005 0 270)
			(size 0 0)
			(layers "F.Cu" "F.Mask" "F.Paste")
			(net "FPGA_DEBUG_LED_N")
		)
		(pad "2" smd circle
			(at 0.40005 0 270)
			(size 0 0)
			(layers "F.Cu" "F.Mask" "F.Paste")
			(net "FPGA_DEBUG_LED_R_N")
		)
	)
	(footprint ""
		(layer "F.Cu")
		(at 352.639884 -235.11383 -90)
		(property "Reference" "R5912"
			(at 0 0 270)
			(layer "F.SilkS")
			(hide yes)
			(effects
				(font
					(size 1.27 1.27)
				)
			)
		)
		(property "Value" ""
			(at 0 0 270)
			(layer "F.Fab")
			(effects
				(font
					(size 1.27 1.27)
				)
			)
		)
		(duplicate_pad_numbers_are_jumpers no)
		(fp_line
			(start -0.7874 0.4064)
			(end -0.7874 -0.4064)
			(stroke
				(width 0.1524)
				(type default)
			)
			(layer "F.SilkS")
		)
		(fp_line
			(start 0.7874 0.4064)
			(end -0.7874 0.4064)
			(stroke
				(width 0.1524)
				(type default)
			)
			(layer "F.SilkS")
		)
		(fp_line
			(start -0.7874 -0.4064)
			(end 0.7874 -0.4064)
			(stroke
				(width 0.1524)
				(type default)
			)
			(layer "F.SilkS")
		)
		(fp_line
			(start 0.7874 -0.4064)
			(end 0.7874 0.4064)
			(stroke
				(width 0.1524)
				(type default)
			)
			(layer "F.SilkS")
		)
		(fp_line
			(start -0.67945 0.3048)
			(end -0.67945 -0.305054)
			(stroke
				(width 0.1)
				(type default)
			)
			(layer "F.Fab")
		)
		(fp_line
			(start -0.12065 0.3048)
			(end -0.67945 0.3048)
			(stroke
				(width 0.1)
				(type default)
			)
			(layer "F.Fab")
		)
		(fp_line
			(start 0.120396 0.3048)
			(end 0.120396 0.2794)
			(stroke
				(width 0.1)
				(type default)
			)
			(layer "F.Fab")
		)
		(fp_line
			(start 0.67945 0.3048)
			(end 0.120396 0.3048)
			(stroke
				(width 0.1)
				(type default)
			)
			(layer "F.Fab")
		)
		(fp_line
			(start -0.12065 0.2794)
			(end -0.12065 0.3048)
			(stroke
				(width 0.1)
				(type default)
			)
			(layer "F.Fab")
		)
		(fp_line
			(start 0.120396 0.2794)
			(end -0.12065 0.2794)
			(stroke
				(width 0.1)
				(type default)
			)
			(layer "F.Fab")
		)
		(fp_line
			(start -0.12065 -0.2794)
			(end 0.12065 -0.2794)
			(stroke
				(width 0.1)
				(type default)
			)
			(layer "F.Fab")
		)
		(fp_line
			(start 0.12065 -0.2794)
			(end 0.12065 -0.3048)
			(stroke
				(width 0.1)
				(type default)
			)
			(layer "F.Fab")
		)
		(fp_line
			(start 0.12065 -0.3048)
			(end 0.67945 -0.3048)
			(stroke
				(width 0.1)
				(type default)
			)
			(layer "F.Fab")
		)
		(fp_line
			(start 0.67945 -0.3048)
			(end 0.67945 0.3048)
			(stroke
				(width 0.1)
				(type default)
			)
			(layer "F.Fab")
		)
		(fp_line
			(start -0.67945 -0.305054)
			(end -0.12065 -0.305054)
			(stroke
				(width 0.1)
				(type default)
			)
			(layer "F.Fab")
		)
		(fp_line
			(start -0.12065 -0.305054)
			(end -0.12065 -0.2794)
			(stroke
				(width 0.1)
				(type default)
			)
			(layer "F.Fab")
		)
		(pad "1" smd circle
			(at -0.40005 0 270)
			(size 0 0)
			(layers "F.Cu" "F.Mask" "F.Paste")
			(net "BIC_FORCE_THROTTLE_R_N")
		)
		(pad "2" smd circle
			(at 0.40005 0 270)
			(size 0 0)
			(layers "F.Cu" "F.Mask" "F.Paste")
			(net "P3V3_AUX")
		)
	)
	(footprint ""
		(layer "F.Cu")
		(at 347.559122 -264.95756 180)
		(property "Reference" "PR7137"
			(at 0 0 180)
			(layer "F.SilkS")
			(hide yes)
			(effects
				(font
					(size 1.27 1.27)
				)
			)
		)
		(property "Value" ""
			(at 0 0 180)
			(layer "F.Fab")
			(effects
				(font
					(size 1.27 1.27)
				)
			)
		)
		(duplicate_pad_numbers_are_jumpers no)
		(fp_line
			(start 0.7874 0.4064)
			(end -0.7874 0.4064)
			(stroke
				(width 0.1524)
				(type default)
			)
			(layer "F.SilkS")
		)
		(fp_line
			(start 0.7874 -0.4064)
			(end 0.7874 0.4064)
			(stroke
				(width 0.1524)
				(type default)
			)
			(layer "F.SilkS")
		)
		(fp_line
			(start -0.7874 0.4064)
			(end -0.7874 -0.4064)
			(stroke
				(width 0.1524)
				(type default)
			)
			(layer "F.SilkS")
		)
		(fp_line
			(start -0.7874 -0.4064)
			(end 0.7874 -0.4064)
			(stroke
				(width 0.1524)
				(type default)
			)
			(layer "F.SilkS")
		)
		(fp_line
			(start 0.67945 0.3048)
			(end 0.120396 0.3048)
			(stroke
				(width 0.1)
				(type default)
			)
			(layer "F.Fab")
		)
		(fp_line
			(start 0.67945 -0.3048)
			(end 0.67945 0.3048)
			(stroke
				(width 0.1)
				(type default)
			)
			(layer "F.Fab")
		)
		(fp_line
			(start 0.12065 -0.2794)
			(end 0.12065 -0.3048)
			(stroke
				(width 0.1)
				(type default)
			)
			(layer "F.Fab")
		)
		(fp_line
			(start 0.12065 -0.3048)
			(end 0.67945 -0.3048)
			(stroke
				(width 0.1)
				(type default)
			)
			(layer "F.Fab")
		)
		(fp_line
			(start 0.120396 0.3048)
			(end 0.120396 0.2794)
			(stroke
				(width 0.1)
				(type default)
			)
			(layer "F.Fab")
		)
		(fp_line
			(start 0.120396 0.2794)
			(end -0.12065 0.2794)
			(stroke
				(width 0.1)
				(type default)
			)
			(layer "F.Fab")
		)
		(fp_line
			(start -0.12065 0.3048)
			(end -0.67945 0.3048)
			(stroke
				(width 0.1)
				(type default)
			)
			(layer "F.Fab")
		)
		(fp_line
			(start -0.12065 0.2794)
			(end -0.12065 0.3048)
			(stroke
				(width 0.1)
				(type default)
			)
			(layer "F.Fab")
		)
		(fp_line
			(start -0.12065 -0.2794)
			(end 0.12065 -0.2794)
			(stroke
				(width 0.1)
				(type default)
			)
			(layer "F.Fab")
		)
		(fp_line
			(start -0.12065 -0.305054)
			(end -0.12065 -0.2794)
			(stroke
				(width 0.1)
				(type default)
			)
			(layer "F.Fab")
		)
		(fp_line
			(start -0.67945 0.3048)
			(end -0.67945 -0.305054)
			(stroke
				(width 0.1)
				(type default)
			)
			(layer "F.Fab")
		)
		(fp_line
			(start -0.67945 -0.305054)
			(end -0.12065 -0.305054)
			(stroke
				(width 0.1)
				(type default)
			)
			(layer "F.Fab")
		)
		(pad "1" smd circle
			(at -0.40005 0 180)
			(size 0 0)
			(layers "F.Cu" "F.Mask" "F.Paste")
			(net "NC_P0V8_PEX2_ISEN5")
		)
		(pad "2" smd circle
			(at 0.40005 0 180)
			(size 0 0)
			(layers "F.Cu" "F.Mask" "F.Paste")
			(net "GND")
		)
	)
	(footprint ""
		(layer "F.Cu")
		(at 166.330884 -199.932798)
		(property "Reference" "R3406"
			(at 0 0 0)
			(layer "F.SilkS")
			(hide yes)
			(effects
				(font
					(size 1.27 1.27)
				)
			)
		)
		(property "Value" ""
			(at 0 0 0)
			(layer "F.Fab")
			(effects
				(font
					(size 1.27 1.27)
				)
			)
		)
		(duplicate_pad_numbers_are_jumpers no)
		(fp_line
			(start -0.7874 -0.4064)
			(end 0.7874 -0.4064)
			(stroke
				(width 0.1524)
				(type default)
			)
			(layer "F.SilkS")
		)
		(fp_line
			(start -0.7874 0.4064)
			(end -0.7874 -0.4064)
			(stroke
				(width 0.1524)
				(type default)
			)
			(layer "F.SilkS")
		)
		(fp_line
			(start 0.7874 -0.4064)
			(end 0.7874 0.4064)
			(stroke
				(width 0.1524)
				(type default)
			)
			(layer "F.SilkS")
		)
		(fp_line
			(start 0.7874 0.4064)
			(end -0.7874 0.4064)
			(stroke
				(width 0.1524)
				(type default)
			)
			(layer "F.SilkS")
		)
		(fp_line
			(start -0.67945 -0.305054)
			(end -0.12065 -0.305054)
			(stroke
				(width 0.1)
				(type default)
			)
			(layer "F.Fab")
		)
		(fp_line
			(start -0.67945 0.3048)
			(end -0.67945 -0.305054)
			(stroke
				(width 0.1)
				(type default)
			)
			(layer "F.Fab")
		)
		(fp_line
			(start -0.12065 -0.305054)
			(end -0.12065 -0.2794)
			(stroke
				(width 0.1)
				(type default)
			)
			(layer "F.Fab")
		)
		(fp_line
			(start -0.12065 -0.2794)
			(end 0.12065 -0.2794)
			(stroke
				(width 0.1)
				(type default)
			)
			(layer "F.Fab")
		)
		(fp_line
			(start -0.12065 0.2794)
			(end -0.12065 0.3048)
			(stroke
				(width 0.1)
				(type default)
			)
			(layer "F.Fab")
		)
		(fp_line
			(start -0.12065 0.3048)
			(end -0.67945 0.3048)
			(stroke
				(width 0.1)
				(type default)
			)
			(layer "F.Fab")
		)
		(fp_line
			(start 0.120396 0.2794)
			(end -0.12065 0.2794)
			(stroke
				(width 0.1)
				(type default)
			)
			(layer "F.Fab")
		)
		(fp_line
			(start 0.120396 0.3048)
			(end 0.120396 0.2794)
			(stroke
				(width 0.1)
				(type default)
			)
			(layer "F.Fab")
		)
		(fp_line
			(start 0.12065 -0.3048)
			(end 0.67945 -0.3048)
			(stroke
				(width 0.1)
				(type default)
			)
			(layer "F.Fab")
		)
		(fp_line
			(start 0.12065 -0.2794)
			(end 0.12065 -0.3048)
			(stroke
				(width 0.1)
				(type default)
			)
			(layer "F.Fab")
		)
		(fp_line
			(start 0.67945 -0.3048)
			(end 0.67945 0.3048)
			(stroke
				(width 0.1)
				(type default)
			)
			(layer "F.Fab")
		)
		(fp_line
			(start 0.67945 0.3048)
			(end 0.120396 0.3048)
			(stroke
				(width 0.1)
				(type default)
			)
			(layer "F.Fab")
		)
		(pad "1" smd circle
			(at -0.40005 0)
			(size 0 0)
			(layers "F.Cu" "F.Mask" "F.Paste")
			(net "SPI_BIC1_CS0_LS01_R2_N")
		)
		(pad "2" smd circle
			(at 0.40005 0)
			(size 0 0)
			(layers "F.Cu" "F.Mask" "F.Paste")
			(net "SPI_BIC1_CS0_LS01_R_N")
		)
	)
	(footprint ""
		(layer "F.Cu")
		(at 390.73074 -343.952322 90)
		(property "Reference" "C745"
			(at 0 0 90)
			(layer "F.SilkS")
			(hide yes)
			(effects
				(font
					(size 1.27 1.27)
				)
			)
		)
		(property "Value" ""
			(at 0 0 90)
			(layer "F.Fab")
			(effects
				(font
					(size 1.27 1.27)
				)
			)
		)
		(duplicate_pad_numbers_are_jumpers no)
		(fp_line
			(start 0.299974 -0.150114)
			(end 0.299974 0.150114)
			(stroke
				(width 0.1)
				(type default)
			)
			(layer "F.Fab")
		)
		(fp_line
			(start -0.299974 -0.150114)
			(end 0.299974 -0.150114)
			(stroke
				(width 0.1)
				(type default)
			)
			(layer "F.Fab")
		)
		(fp_line
			(start 0.299974 0.150114)
			(end -0.299974 0.150114)
			(stroke
				(width 0.1)
				(type default)
			)
			(layer "F.Fab")
		)
		(fp_line
			(start -0.299974 0.150114)
			(end -0.299974 -0.150114)
			(stroke
				(width 0.1)
				(type default)
			)
			(layer "F.Fab")
		)
		(pad "1" smd rect
			(at -0.2667 0 90)
			(size 0.3048 0.381)
			(layers "F.Cu" "F.Mask" "F.Paste")
			(net "P5E_PEX3_STN5_TX_DN<88>")
		)
		(pad "2" smd rect
			(at 0.2667 0 90)
			(size 0.3048 0.381)
			(layers "F.Cu" "F.Mask" "F.Paste")
			(net "P5E_PEX3_STN5_TX_C_DN<88>")
		)
	)
	(footprint ""
		(layer "F.Cu")
		(at 33.11144 -258.234434)
		(property "Reference" "L93"
			(at 0 0 0)
			(layer "F.SilkS")
			(hide yes)
			(effects
				(font
					(size 1.27 1.27)
				)
			)
		)
		(property "Value" ""
			(at 0 0 0)
			(layer "F.Fab")
			(effects
				(font
					(size 1.27 1.27)
				)
			)
		)
		(duplicate_pad_numbers_are_jumpers no)
		(fp_line
			(start -1.63576 -0.8128)
			(end -1.63576 0.8128)
			(stroke
				(width 0.1524)
				(type default)
			)
			(layer "F.SilkS")
		)
		(fp_line
			(start -1.63576 -0.8128)
			(end 1.63576 -0.8128)
			(stroke
				(width 0.1524)
				(type default)
			)
			(layer "F.SilkS")
		)
		(fp_line
			(start 1.63576 -0.8128)
			(end 1.63576 0.8128)
			(stroke
				(width 0.1524)
				(type default)
			)
			(layer "F.SilkS")
		)
		(fp_line
			(start 1.63576 0.8128)
			(end -1.63576 0.8128)
			(stroke
				(width 0.1524)
				(type default)
			)
			(layer "F.SilkS")
		)
		(fp_line
			(start -1.56083 -0.738632)
			(end -1.56083 0.7366)
			(stroke
				(width 0.1)
				(type default)
			)
			(layer "F.Fab")
		)
		(fp_line
			(start -1.56083 0.7366)
			(end -1.524 0.7366)
			(stroke
				(width 0.1)
				(type default)
			)
			(layer "F.Fab")
		)
		(fp_line
			(start -1.524 0.7366)
			(end 1.524 0.7366)
			(stroke
				(width 0.1)
				(type default)
			)
			(layer "F.Fab")
		)
		(fp_line
			(start 1.524 0.7366)
			(end 1.560576 0.7366)
			(stroke
				(width 0.1)
				(type default)
			)
			(layer "F.Fab")
		)
		(fp_line
			(start 1.560576 -0.738632)
			(end -1.56083 -0.738632)
			(stroke
				(width 0.1)
				(type default)
			)
			(layer "F.Fab")
		)
		(fp_line
			(start 1.560576 0.7366)
			(end 1.560576 -0.738632)
			(stroke
				(width 0.1)
				(type default)
			)
			(layer "F.Fab")
		)
		(pad "1" smd rect
			(at -0.94996 0 180)
			(size 1.1176 1.3716)
			(layers "F.Cu" "F.Mask" "F.Paste")
			(net "P1V8_PLL0_PEX0")
		)
		(pad "2" smd rect
			(at 0.94996 0 180)
			(size 1.1176 1.3716)
			(layers "F.Cu" "F.Mask" "F.Paste")
			(net "PCEPLL5_VDDA18_PEX0")
		)
	)
	(footprint ""
		(layer "F.Cu")
		(at 384.834384 -252.356874 -90)
		(property "Reference" "R1431"
			(at 0 0 270)
			(layer "F.SilkS")
			(hide yes)
			(effects
				(font
					(size 1.27 1.27)
				)
			)
		)
		(property "Value" ""
			(at 0 0 270)
			(layer "F.Fab")
			(effects
				(font
					(size 1.27 1.27)
				)
			)
		)
		(duplicate_pad_numbers_are_jumpers no)
		(fp_line
			(start -0.7874 0.4064)
			(end -0.7874 -0.4064)
			(stroke
				(width 0.1524)
				(type default)
			)
			(layer "F.SilkS")
		)
		(fp_line
			(start 0.7874 0.4064)
			(end -0.7874 0.4064)
			(stroke
				(width 0.1524)
				(type default)
			)
			(layer "F.SilkS")
		)
		(fp_line
			(start -0.7874 -0.4064)
			(end 0.7874 -0.4064)
			(stroke
				(width 0.1524)
				(type default)
			)
			(layer "F.SilkS")
		)
		(fp_line
			(start 0.7874 -0.4064)
			(end 0.7874 0.4064)
			(stroke
				(width 0.1524)
				(type default)
			)
			(layer "F.SilkS")
		)
		(fp_line
			(start -0.67945 0.3048)
			(end -0.67945 -0.305054)
			(stroke
				(width 0.1)
				(type default)
			)
			(layer "F.Fab")
		)
		(fp_line
			(start -0.12065 0.3048)
			(end -0.67945 0.3048)
			(stroke
				(width 0.1)
				(type default)
			)
			(layer "F.Fab")
		)
		(fp_line
			(start 0.120396 0.3048)
			(end 0.120396 0.2794)
			(stroke
				(width 0.1)
				(type default)
			)
			(layer "F.Fab")
		)
		(fp_line
			(start 0.67945 0.3048)
			(end 0.120396 0.3048)
			(stroke
				(width 0.1)
				(type default)
			)
			(layer "F.Fab")
		)
		(fp_line
			(start -0.12065 0.2794)
			(end -0.12065 0.3048)
			(stroke
				(width 0.1)
				(type default)
			)
			(layer "F.Fab")
		)
		(fp_line
			(start 0.120396 0.2794)
			(end -0.12065 0.2794)
			(stroke
				(width 0.1)
				(type default)
			)
			(layer "F.Fab")
		)
		(fp_line
			(start -0.12065 -0.2794)
			(end 0.12065 -0.2794)
			(stroke
				(width 0.1)
				(type default)
			)
			(layer "F.Fab")
		)
		(fp_line
			(start 0.12065 -0.2794)
			(end 0.12065 -0.3048)
			(stroke
				(width 0.1)
				(type default)
			)
			(layer "F.Fab")
		)
		(fp_line
			(start 0.12065 -0.3048)
			(end 0.67945 -0.3048)
			(stroke
				(width 0.1)
				(type default)
			)
			(layer "F.Fab")
		)
		(fp_line
			(start 0.67945 -0.3048)
			(end 0.67945 0.3048)
			(stroke
				(width 0.1)
				(type default)
			)
			(layer "F.Fab")
		)
		(fp_line
			(start -0.67945 -0.305054)
			(end -0.12065 -0.305054)
			(stroke
				(width 0.1)
				(type default)
			)
			(layer "F.Fab")
		)
		(fp_line
			(start -0.12065 -0.305054)
			(end -0.12065 -0.2794)
			(stroke
				(width 0.1)
				(type default)
			)
			(layer "F.Fab")
		)
		(pad "1" smd circle
			(at -0.40005 0 270)
			(size 0 0)
			(layers "F.Cu" "F.Mask" "F.Paste")
			(net "GND")
		)
		(pad "2" smd circle
			(at 0.40005 0 270)
			(size 0 0)
			(layers "F.Cu" "F.Mask" "F.Paste")
			(net "PEX3_MODE_SEL6")
		)
	)
	(footprint ""
		(layer "F.Cu")
		(at 315.586364 -343.952322 90)
		(property "Reference" "C547"
			(at 0 0 90)
			(layer "F.SilkS")
			(hide yes)
			(effects
				(font
					(size 1.27 1.27)
				)
			)
		)
		(property "Value" ""
			(at 0 0 90)
			(layer "F.Fab")
			(effects
				(font
					(size 1.27 1.27)
				)
			)
		)
		(duplicate_pad_numbers_are_jumpers no)
		(fp_line
			(start 0.299974 -0.150114)
			(end 0.299974 0.150114)
			(stroke
				(width 0.1)
				(type default)
			)
			(layer "F.Fab")
		)
		(fp_line
			(start -0.299974 -0.150114)
			(end 0.299974 -0.150114)
			(stroke
				(width 0.1)
				(type default)
			)
			(layer "F.Fab")
		)
		(fp_line
			(start 0.299974 0.150114)
			(end -0.299974 0.150114)
			(stroke
				(width 0.1)
				(type default)
			)
			(layer "F.Fab")
		)
		(fp_line
			(start -0.299974 0.150114)
			(end -0.299974 -0.150114)
			(stroke
				(width 0.1)
				(type default)
			)
			(layer "F.Fab")
		)
		(pad "1" smd rect
			(at -0.2667 0 90)
			(size 0.3048 0.381)
			(layers "F.Cu" "F.Mask" "F.Paste")
			(net "P5E_PEX2_STN5_TX_DP<81>")
		)
		(pad "2" smd rect
			(at 0.2667 0 90)
			(size 0.3048 0.381)
			(layers "F.Cu" "F.Mask" "F.Paste")
			(net "P5E_PEX2_STN5_TX_C_DP<81>")
		)
	)
	(footprint ""
		(layer "F.Cu")
		(at 200.691496 -112.39754)
		(property "Reference" "R182"
			(at 0 0 0)
			(layer "F.SilkS")
			(hide yes)
			(effects
				(font
					(size 1.27 1.27)
				)
			)
		)
		(property "Value" ""
			(at 0 0 0)
			(layer "F.Fab")
			(effects
				(font
					(size 1.27 1.27)
				)
			)
		)
		(duplicate_pad_numbers_are_jumpers no)
		(fp_line
			(start -0.7874 -0.4064)
			(end 0.7874 -0.4064)
			(stroke
				(width 0.1524)
				(type default)
			)
			(layer "F.SilkS")
		)
		(fp_line
			(start -0.7874 0.4064)
			(end -0.7874 -0.4064)
			(stroke
				(width 0.1524)
				(type default)
			)
			(layer "F.SilkS")
		)
		(fp_line
			(start 0.7874 -0.4064)
			(end 0.7874 0.4064)
			(stroke
				(width 0.1524)
				(type default)
			)
			(layer "F.SilkS")
		)
		(fp_line
			(start 0.7874 0.4064)
			(end -0.7874 0.4064)
			(stroke
				(width 0.1524)
				(type default)
			)
			(layer "F.SilkS")
		)
		(fp_line
			(start -0.67945 -0.305054)
			(end -0.12065 -0.305054)
			(stroke
				(width 0.1)
				(type default)
			)
			(layer "F.Fab")
		)
		(fp_line
			(start -0.67945 0.3048)
			(end -0.67945 -0.305054)
			(stroke
				(width 0.1)
				(type default)
			)
			(layer "F.Fab")
		)
		(fp_line
			(start -0.12065 -0.305054)
			(end -0.12065 -0.2794)
			(stroke
				(width 0.1)
				(type default)
			)
			(layer "F.Fab")
		)
		(fp_line
			(start -0.12065 -0.2794)
			(end 0.12065 -0.2794)
			(stroke
				(width 0.1)
				(type default)
			)
			(layer "F.Fab")
		)
		(fp_line
			(start -0.12065 0.2794)
			(end -0.12065 0.3048)
			(stroke
				(width 0.1)
				(type default)
			)
			(layer "F.Fab")
		)
		(fp_line
			(start -0.12065 0.3048)
			(end -0.67945 0.3048)
			(stroke
				(width 0.1)
				(type default)
			)
			(layer "F.Fab")
		)
		(fp_line
			(start 0.120396 0.2794)
			(end -0.12065 0.2794)
			(stroke
				(width 0.1)
				(type default)
			)
			(layer "F.Fab")
		)
		(fp_line
			(start 0.120396 0.3048)
			(end 0.120396 0.2794)
			(stroke
				(width 0.1)
				(type default)
			)
			(layer "F.Fab")
		)
		(fp_line
			(start 0.12065 -0.3048)
			(end 0.67945 -0.3048)
			(stroke
				(width 0.1)
				(type default)
			)
			(layer "F.Fab")
		)
		(fp_line
			(start 0.12065 -0.2794)
			(end 0.12065 -0.3048)
			(stroke
				(width 0.1)
				(type default)
			)
			(layer "F.Fab")
		)
		(fp_line
			(start 0.67945 -0.3048)
			(end 0.67945 0.3048)
			(stroke
				(width 0.1)
				(type default)
			)
			(layer "F.Fab")
		)
		(fp_line
			(start 0.67945 0.3048)
			(end 0.120396 0.3048)
			(stroke
				(width 0.1)
				(type default)
			)
			(layer "F.Fab")
		)
		(pad "1" smd circle
			(at -0.40005 0)
			(size 0 0)
			(layers "F.Cu" "F.Mask" "F.Paste")
			(net "NIC3_BIF0_N")
		)
		(pad "2" smd circle
			(at 0.40005 0)
			(size 0 0)
			(layers "F.Cu" "F.Mask" "F.Paste")
			(net "P3V3_AUX")
		)
	)
	(footprint ""
		(layer "F.Cu")
		(at 308.681882 -37.025072)
		(property "Reference" "R5689"
			(at 0 0 0)
			(layer "F.SilkS")
			(hide yes)
			(effects
				(font
					(size 1.27 1.27)
				)
			)
		)
		(property "Value" ""
			(at 0 0 0)
			(layer "F.Fab")
			(effects
				(font
					(size 1.27 1.27)
				)
			)
		)
		(duplicate_pad_numbers_are_jumpers no)
		(fp_line
			(start -0.7874 -0.4064)
			(end 0.7874 -0.4064)
			(stroke
				(width 0.1524)
				(type default)
			)
			(layer "F.SilkS")
		)
		(fp_line
			(start -0.7874 0.4064)
			(end -0.7874 -0.4064)
			(stroke
				(width 0.1524)
				(type default)
			)
			(layer "F.SilkS")
		)
		(fp_line
			(start 0.7874 -0.4064)
			(end 0.7874 0.4064)
			(stroke
				(width 0.1524)
				(type default)
			)
			(layer "F.SilkS")
		)
		(fp_line
			(start 0.7874 0.4064)
			(end -0.7874 0.4064)
			(stroke
				(width 0.1524)
				(type default)
			)
			(layer "F.SilkS")
		)
		(fp_line
			(start -0.67945 -0.305054)
			(end -0.12065 -0.305054)
			(stroke
				(width 0.1)
				(type default)
			)
			(layer "F.Fab")
		)
		(fp_line
			(start -0.67945 0.3048)
			(end -0.67945 -0.305054)
			(stroke
				(width 0.1)
				(type default)
			)
			(layer "F.Fab")
		)
		(fp_line
			(start -0.12065 -0.305054)
			(end -0.12065 -0.2794)
			(stroke
				(width 0.1)
				(type default)
			)
			(layer "F.Fab")
		)
		(fp_line
			(start -0.12065 -0.2794)
			(end 0.12065 -0.2794)
			(stroke
				(width 0.1)
				(type default)
			)
			(layer "F.Fab")
		)
		(fp_line
			(start -0.12065 0.2794)
			(end -0.12065 0.3048)
			(stroke
				(width 0.1)
				(type default)
			)
			(layer "F.Fab")
		)
		(fp_line
			(start -0.12065 0.3048)
			(end -0.67945 0.3048)
			(stroke
				(width 0.1)
				(type default)
			)
			(layer "F.Fab")
		)
		(fp_line
			(start 0.120396 0.2794)
			(end -0.12065 0.2794)
			(stroke
				(width 0.1)
				(type default)
			)
			(layer "F.Fab")
		)
		(fp_line
			(start 0.120396 0.3048)
			(end 0.120396 0.2794)
			(stroke
				(width 0.1)
				(type default)
			)
			(layer "F.Fab")
		)
		(fp_line
			(start 0.12065 -0.3048)
			(end 0.67945 -0.3048)
			(stroke
				(width 0.1)
				(type default)
			)
			(layer "F.Fab")
		)
		(fp_line
			(start 0.12065 -0.2794)
			(end 0.12065 -0.3048)
			(stroke
				(width 0.1)
				(type default)
			)
			(layer "F.Fab")
		)
		(fp_line
			(start 0.67945 -0.3048)
			(end 0.67945 0.3048)
			(stroke
				(width 0.1)
				(type default)
			)
			(layer "F.Fab")
		)
		(fp_line
			(start 0.67945 0.3048)
			(end 0.120396 0.3048)
			(stroke
				(width 0.1)
				(type default)
			)
			(layer "F.Fab")
		)
		(pad "1" smd circle
			(at -0.40005 0)
			(size 0 0)
			(layers "F.Cu" "F.Mask" "F.Paste")
			(net "RST_SMB_SSD_R_N")
		)
		(pad "2" smd circle
			(at 0.40005 0)
			(size 0 0)
			(layers "F.Cu" "F.Mask" "F.Paste")
			(net "RST_SMB_SSD11_N")
		)
	)
	(footprint ""
		(layer "F.Cu")
		(at 460.611982 -114.960654)
		(property "Reference" "PR7062"
			(at 0 0 0)
			(layer "F.SilkS")
			(hide yes)
			(effects
				(font
					(size 1.27 1.27)
				)
			)
		)
		(property "Value" ""
			(at 0 0 0)
			(layer "F.Fab")
			(effects
				(font
					(size 1.27 1.27)
				)
			)
		)
		(duplicate_pad_numbers_are_jumpers no)
		(fp_line
			(start -0.7874 -0.4064)
			(end 0.7874 -0.4064)
			(stroke
				(width 0.1524)
				(type default)
			)
			(layer "F.SilkS")
		)
		(fp_line
			(start -0.7874 0.4064)
			(end -0.7874 -0.4064)
			(stroke
				(width 0.1524)
				(type default)
			)
			(layer "F.SilkS")
		)
		(fp_line
			(start 0.7874 -0.4064)
			(end 0.7874 0.4064)
			(stroke
				(width 0.1524)
				(type default)
			)
			(layer "F.SilkS")
		)
		(fp_line
			(start 0.7874 0.4064)
			(end -0.7874 0.4064)
			(stroke
				(width 0.1524)
				(type default)
			)
			(layer "F.SilkS")
		)
		(fp_line
			(start -0.67945 -0.305054)
			(end -0.12065 -0.305054)
			(stroke
				(width 0.1)
				(type default)
			)
			(layer "F.Fab")
		)
		(fp_line
			(start -0.67945 0.3048)
			(end -0.67945 -0.305054)
			(stroke
				(width 0.1)
				(type default)
			)
			(layer "F.Fab")
		)
		(fp_line
			(start -0.12065 -0.305054)
			(end -0.12065 -0.2794)
			(stroke
				(width 0.1)
				(type default)
			)
			(layer "F.Fab")
		)
		(fp_line
			(start -0.12065 -0.2794)
			(end 0.12065 -0.2794)
			(stroke
				(width 0.1)
				(type default)
			)
			(layer "F.Fab")
		)
		(fp_line
			(start -0.12065 0.2794)
			(end -0.12065 0.3048)
			(stroke
				(width 0.1)
				(type default)
			)
			(layer "F.Fab")
		)
		(fp_line
			(start -0.12065 0.3048)
			(end -0.67945 0.3048)
			(stroke
				(width 0.1)
				(type default)
			)
			(layer "F.Fab")
		)
		(fp_line
			(start 0.120396 0.2794)
			(end -0.12065 0.2794)
			(stroke
				(width 0.1)
				(type default)
			)
			(layer "F.Fab")
		)
		(fp_line
			(start 0.120396 0.3048)
			(end 0.120396 0.2794)
			(stroke
				(width 0.1)
				(type default)
			)
			(layer "F.Fab")
		)
		(fp_line
			(start 0.12065 -0.3048)
			(end 0.67945 -0.3048)
			(stroke
				(width 0.1)
				(type default)
			)
			(layer "F.Fab")
		)
		(fp_line
			(start 0.12065 -0.2794)
			(end 0.12065 -0.3048)
			(stroke
				(width 0.1)
				(type default)
			)
			(layer "F.Fab")
		)
		(fp_line
			(start 0.67945 -0.3048)
			(end 0.67945 0.3048)
			(stroke
				(width 0.1)
				(type default)
			)
			(layer "F.Fab")
		)
		(fp_line
			(start 0.67945 0.3048)
			(end 0.120396 0.3048)
			(stroke
				(width 0.1)
				(type default)
			)
			(layer "F.Fab")
		)
		(pad "1" smd circle
			(at -0.40005 0)
			(size 0 0)
			(layers "F.Cu" "F.Mask" "F.Paste")
			(net "P12V_NIC7_CO_IMON_VR")
		)
		(pad "2" smd circle
			(at 0.40005 0)
			(size 0 0)
			(layers "F.Cu" "F.Mask" "F.Paste")
			(net "GND")
		)
	)
	(footprint ""
		(layer "F.Cu")
		(at 212.822536 -44.341542 90)
		(property "Reference" "R591"
			(at 0 0 90)
			(layer "F.SilkS")
			(hide yes)
			(effects
				(font
					(size 1.27 1.27)
				)
			)
		)
		(property "Value" ""
			(at 0 0 90)
			(layer "F.Fab")
			(effects
				(font
					(size 1.27 1.27)
				)
			)
		)
		(duplicate_pad_numbers_are_jumpers no)
		(fp_line
			(start 0.7874 -0.4064)
			(end 0.7874 0.4064)
			(stroke
				(width 0.1524)
				(type default)
			)
			(layer "F.SilkS")
		)
		(fp_line
			(start -0.7874 -0.4064)
			(end 0.7874 -0.4064)
			(stroke
				(width 0.1524)
				(type default)
			)
			(layer "F.SilkS")
		)
		(fp_line
			(start 0.7874 0.4064)
			(end -0.7874 0.4064)
			(stroke
				(width 0.1524)
				(type default)
			)
			(layer "F.SilkS")
		)
		(fp_line
			(start -0.7874 0.4064)
			(end -0.7874 -0.4064)
			(stroke
				(width 0.1524)
				(type default)
			)
			(layer "F.SilkS")
		)
		(fp_line
			(start -0.12065 -0.305054)
			(end -0.12065 -0.2794)
			(stroke
				(width 0.1)
				(type default)
			)
			(layer "F.Fab")
		)
		(fp_line
			(start -0.67945 -0.305054)
			(end -0.12065 -0.305054)
			(stroke
				(width 0.1)
				(type default)
			)
			(layer "F.Fab")
		)
		(fp_line
			(start 0.67945 -0.3048)
			(end 0.67945 0.3048)
			(stroke
				(width 0.1)
				(type default)
			)
			(layer "F.Fab")
		)
		(fp_line
			(start 0.12065 -0.3048)
			(end 0.67945 -0.3048)
			(stroke
				(width 0.1)
				(type default)
			)
			(layer "F.Fab")
		)
		(fp_line
			(start 0.12065 -0.2794)
			(end 0.12065 -0.3048)
			(stroke
				(width 0.1)
				(type default)
			)
			(layer "F.Fab")
		)
		(fp_line
			(start -0.12065 -0.2794)
			(end 0.12065 -0.2794)
			(stroke
				(width 0.1)
				(type default)
			)
			(layer "F.Fab")
		)
		(fp_line
			(start 0.120396 0.2794)
			(end -0.12065 0.2794)
			(stroke
				(width 0.1)
				(type default)
			)
			(layer "F.Fab")
		)
		(fp_line
			(start -0.12065 0.2794)
			(end -0.12065 0.3048)
			(stroke
				(width 0.1)
				(type default)
			)
			(layer "F.Fab")
		)
		(fp_line
			(start 0.67945 0.3048)
			(end 0.120396 0.3048)
			(stroke
				(width 0.1)
				(type default)
			)
			(layer "F.Fab")
		)
		(fp_line
			(start 0.120396 0.3048)
			(end 0.120396 0.2794)
			(stroke
				(width 0.1)
				(type default)
			)
			(layer "F.Fab")
		)
		(fp_line
			(start -0.12065 0.3048)
			(end -0.67945 0.3048)
			(stroke
				(width 0.1)
				(type default)
			)
			(layer "F.Fab")
		)
		(fp_line
			(start -0.67945 0.3048)
			(end -0.67945 -0.305054)
			(stroke
				(width 0.1)
				(type default)
			)
			(layer "F.Fab")
		)
		(pad "1" smd circle
			(at -0.40005 0 90)
			(size 0 0)
			(layers "F.Cu" "F.Mask" "F.Paste")
			(net "P12V_SSD7")
		)
		(pad "2" smd circle
			(at 0.40005 0 90)
			(size 0 0)
			(layers "F.Cu" "F.Mask" "F.Paste")
			(net "P12V_SSD7_VIN_N")
		)
	)
	(footprint ""
		(layer "F.Cu")
		(at 41.987978 -45.704252 90)
		(property "Reference" "R516"
			(at 0 0 90)
			(layer "F.SilkS")
			(hide yes)
			(effects
				(font
					(size 1.27 1.27)
				)
			)
		)
		(property "Value" ""
			(at 0 0 90)
			(layer "F.Fab")
			(effects
				(font
					(size 1.27 1.27)
				)
			)
		)
		(duplicate_pad_numbers_are_jumpers no)
		(fp_line
			(start 3.937508 -1.8796)
			(end -3.937508 -1.8796)
			(stroke
				(width 0.1524)
				(type default)
			)
			(layer "F.SilkS")
		)
		(fp_line
			(start -3.937508 -1.8796)
			(end -3.937508 1.8796)
			(stroke
				(width 0.1524)
				(type default)
			)
			(layer "F.SilkS")
		)
		(fp_line
			(start 3.937508 1.8796)
			(end 3.937508 -1.8796)
			(stroke
				(width 0.1524)
				(type default)
			)
			(layer "F.SilkS")
		)
		(fp_line
			(start -3.937508 1.8796)
			(end 3.937508 1.8796)
			(stroke
				(width 0.1524)
				(type default)
			)
			(layer "F.SilkS")
		)
		(fp_line
			(start 3.275076 -1.674876)
			(end -3.275076 -1.674876)
			(stroke
				(width 0.1)
				(type default)
			)
			(layer "F.Fab")
		)
		(fp_line
			(start -3.275076 -1.674876)
			(end -3.275076 1.674876)
			(stroke
				(width 0.1)
				(type default)
			)
			(layer "F.Fab")
		)
		(fp_line
			(start 3.275076 1.674876)
			(end 3.275076 -1.674876)
			(stroke
				(width 0.1)
				(type default)
			)
			(layer "F.Fab")
		)
		(fp_line
			(start -3.275076 1.674876)
			(end 3.275076 1.674876)
			(stroke
				(width 0.1)
				(type default)
			)
			(layer "F.Fab")
		)
		(pad "1" smd rect
			(at -2.350008 0 90)
			(size 2.921 3.5052)
			(layers "F.Cu" "F.Mask" "F.Paste")
			(net "P12V_SSD1")
		)
		(pad "2" smd rect
			(at 2.350008 0 90)
			(size 2.921 3.5052)
			(layers "F.Cu" "F.Mask" "F.Paste")
			(net "P12V_SSD1_R")
		)
	)
	(footprint ""
		(layer "F.Cu")
		(at 104.267762 -56.353456)
		(property "Reference" "C2867"
			(at 0 0 0)
			(layer "F.SilkS")
			(hide yes)
			(effects
				(font
					(size 1.27 1.27)
				)
			)
		)
		(property "Value" ""
			(at 0 0 0)
			(layer "F.Fab")
			(effects
				(font
					(size 1.27 1.27)
				)
			)
		)
		(duplicate_pad_numbers_are_jumpers no)
		(fp_line
			(start -0.7874 -0.4064)
			(end 0.7874 -0.4064)
			(stroke
				(width 0.1524)
				(type default)
			)
			(layer "F.SilkS")
		)
		(fp_line
			(start -0.7874 0.4064)
			(end -0.7874 -0.4064)
			(stroke
				(width 0.1524)
				(type default)
			)
			(layer "F.SilkS")
		)
		(fp_line
			(start 0.7874 -0.4064)
			(end 0.7874 0.4064)
			(stroke
				(width 0.1524)
				(type default)
			)
			(layer "F.SilkS")
		)
		(fp_line
			(start 0.7874 0.4064)
			(end -0.7874 0.4064)
			(stroke
				(width 0.1524)
				(type default)
			)
			(layer "F.SilkS")
		)
		(fp_line
			(start -0.67945 -0.305054)
			(end -0.12065 -0.305054)
			(stroke
				(width 0.1)
				(type default)
			)
			(layer "F.Fab")
		)
		(fp_line
			(start -0.67945 0.3048)
			(end -0.67945 -0.305054)
			(stroke
				(width 0.1)
				(type default)
			)
			(layer "F.Fab")
		)
		(fp_line
			(start -0.12065 -0.305054)
			(end -0.12065 -0.2794)
			(stroke
				(width 0.1)
				(type default)
			)
			(layer "F.Fab")
		)
		(fp_line
			(start -0.12065 -0.2794)
			(end 0.12065 -0.2794)
			(stroke
				(width 0.1)
				(type default)
			)
			(layer "F.Fab")
		)
		(fp_line
			(start -0.12065 0.2794)
			(end -0.12065 0.3048)
			(stroke
				(width 0.1)
				(type default)
			)
			(layer "F.Fab")
		)
		(fp_line
			(start -0.12065 0.3048)
			(end -0.67945 0.3048)
			(stroke
				(width 0.1)
				(type default)
			)
			(layer "F.Fab")
		)
		(fp_line
			(start 0.120396 0.2794)
			(end -0.12065 0.2794)
			(stroke
				(width 0.1)
				(type default)
			)
			(layer "F.Fab")
		)
		(fp_line
			(start 0.120396 0.3048)
			(end 0.120396 0.2794)
			(stroke
				(width 0.1)
				(type default)
			)
			(layer "F.Fab")
		)
		(fp_line
			(start 0.12065 -0.3048)
			(end 0.67945 -0.3048)
			(stroke
				(width 0.1)
				(type default)
			)
			(layer "F.Fab")
		)
		(fp_line
			(start 0.12065 -0.2794)
			(end 0.12065 -0.3048)
			(stroke
				(width 0.1)
				(type default)
			)
			(layer "F.Fab")
		)
		(fp_line
			(start 0.67945 -0.3048)
			(end 0.67945 0.3048)
			(stroke
				(width 0.1)
				(type default)
			)
			(layer "F.Fab")
		)
		(fp_line
			(start 0.67945 0.3048)
			(end 0.120396 0.3048)
			(stroke
				(width 0.1)
				(type default)
			)
			(layer "F.Fab")
		)
		(pad "1" smd circle
			(at -0.40005 0)
			(size 0 0)
			(layers "F.Cu" "F.Mask" "F.Paste")
			(net "SSD3_PWR_EN_R")
		)
		(pad "2" smd circle
			(at 0.40005 0)
			(size 0 0)
			(layers "F.Cu" "F.Mask" "F.Paste")
			(net "GND")
		)
	)
	(footprint ""
		(layer "F.Cu")
		(at 104.243632 -42.84091)
		(property "Reference" "R539"
			(at 0 0 0)
			(layer "F.SilkS")
			(hide yes)
			(effects
				(font
					(size 1.27 1.27)
				)
			)
		)
		(property "Value" ""
			(at 0 0 0)
			(layer "F.Fab")
			(effects
				(font
					(size 1.27 1.27)
				)
			)
		)
		(duplicate_pad_numbers_are_jumpers no)
		(fp_line
			(start -0.7874 -0.4064)
			(end 0.7874 -0.4064)
			(stroke
				(width 0.1524)
				(type default)
			)
			(layer "F.SilkS")
		)
		(fp_line
			(start -0.7874 0.4064)
			(end -0.7874 -0.4064)
			(stroke
				(width 0.1524)
				(type default)
			)
			(layer "F.SilkS")
		)
		(fp_line
			(start 0.7874 -0.4064)
			(end 0.7874 0.4064)
			(stroke
				(width 0.1524)
				(type default)
			)
			(layer "F.SilkS")
		)
		(fp_line
			(start 0.7874 0.4064)
			(end -0.7874 0.4064)
			(stroke
				(width 0.1524)
				(type default)
			)
			(layer "F.SilkS")
		)
		(fp_line
			(start -0.67945 -0.305054)
			(end -0.12065 -0.305054)
			(stroke
				(width 0.1)
				(type default)
			)
			(layer "F.Fab")
		)
		(fp_line
			(start -0.67945 0.3048)
			(end -0.67945 -0.305054)
			(stroke
				(width 0.1)
				(type default)
			)
			(layer "F.Fab")
		)
		(fp_line
			(start -0.12065 -0.305054)
			(end -0.12065 -0.2794)
			(stroke
				(width 0.1)
				(type default)
			)
			(layer "F.Fab")
		)
		(fp_line
			(start -0.12065 -0.2794)
			(end 0.12065 -0.2794)
			(stroke
				(width 0.1)
				(type default)
			)
			(layer "F.Fab")
		)
		(fp_line
			(start -0.12065 0.2794)
			(end -0.12065 0.3048)
			(stroke
				(width 0.1)
				(type default)
			)
			(layer "F.Fab")
		)
		(fp_line
			(start -0.12065 0.3048)
			(end -0.67945 0.3048)
			(stroke
				(width 0.1)
				(type default)
			)
			(layer "F.Fab")
		)
		(fp_line
			(start 0.120396 0.2794)
			(end -0.12065 0.2794)
			(stroke
				(width 0.1)
				(type default)
			)
			(layer "F.Fab")
		)
		(fp_line
			(start 0.120396 0.3048)
			(end 0.120396 0.2794)
			(stroke
				(width 0.1)
				(type default)
			)
			(layer "F.Fab")
		)
		(fp_line
			(start 0.12065 -0.3048)
			(end 0.67945 -0.3048)
			(stroke
				(width 0.1)
				(type default)
			)
			(layer "F.Fab")
		)
		(fp_line
			(start 0.12065 -0.2794)
			(end 0.12065 -0.3048)
			(stroke
				(width 0.1)
				(type default)
			)
			(layer "F.Fab")
		)
		(fp_line
			(start 0.67945 -0.3048)
			(end 0.67945 0.3048)
			(stroke
				(width 0.1)
				(type default)
			)
			(layer "F.Fab")
		)
		(fp_line
			(start 0.67945 0.3048)
			(end 0.120396 0.3048)
			(stroke
				(width 0.1)
				(type default)
			)
			(layer "F.Fab")
		)
		(pad "1" smd circle
			(at -0.40005 0)
			(size 0 0)
			(layers "F.Cu" "F.Mask" "F.Paste")
			(net "SSD3_ADC_A1")
		)
		(pad "2" smd circle
			(at 0.40005 0)
			(size 0 0)
			(layers "F.Cu" "F.Mask" "F.Paste")
			(net "P3V3_AUX")
		)
	)
	(footprint ""
		(layer "F.Cu")
		(at 95.622618 -22.867366 90)
		(property "Reference" "C3894"
			(at 0 0 90)
			(layer "F.SilkS")
			(hide yes)
			(effects
				(font
					(size 1.27 1.27)
				)
			)
		)
		(property "Value" ""
			(at 0 0 90)
			(layer "F.Fab")
			(effects
				(font
					(size 1.27 1.27)
				)
			)
		)
		(duplicate_pad_numbers_are_jumpers no)
		(fp_line
			(start 0.7874 -0.4064)
			(end 0.7874 0.4064)
			(stroke
				(width 0.1524)
				(type default)
			)
			(layer "F.SilkS")
		)
		(fp_line
			(start -0.7874 -0.4064)
			(end 0.7874 -0.4064)
			(stroke
				(width 0.1524)
				(type default)
			)
			(layer "F.SilkS")
		)
		(fp_line
			(start 0.7874 0.4064)
			(end -0.7874 0.4064)
			(stroke
				(width 0.1524)
				(type default)
			)
			(layer "F.SilkS")
		)
		(fp_line
			(start -0.7874 0.4064)
			(end -0.7874 -0.4064)
			(stroke
				(width 0.1524)
				(type default)
			)
			(layer "F.SilkS")
		)
		(fp_line
			(start -0.12065 -0.305054)
			(end -0.12065 -0.2794)
			(stroke
				(width 0.1)
				(type default)
			)
			(layer "F.Fab")
		)
		(fp_line
			(start -0.67945 -0.305054)
			(end -0.12065 -0.305054)
			(stroke
				(width 0.1)
				(type default)
			)
			(layer "F.Fab")
		)
		(fp_line
			(start 0.67945 -0.3048)
			(end 0.67945 0.3048)
			(stroke
				(width 0.1)
				(type default)
			)
			(layer "F.Fab")
		)
		(fp_line
			(start 0.12065 -0.3048)
			(end 0.67945 -0.3048)
			(stroke
				(width 0.1)
				(type default)
			)
			(layer "F.Fab")
		)
		(fp_line
			(start 0.12065 -0.2794)
			(end 0.12065 -0.3048)
			(stroke
				(width 0.1)
				(type default)
			)
			(layer "F.Fab")
		)
		(fp_line
			(start -0.12065 -0.2794)
			(end 0.12065 -0.2794)
			(stroke
				(width 0.1)
				(type default)
			)
			(layer "F.Fab")
		)
		(fp_line
			(start 0.120396 0.2794)
			(end -0.12065 0.2794)
			(stroke
				(width 0.1)
				(type default)
			)
			(layer "F.Fab")
		)
		(fp_line
			(start -0.12065 0.2794)
			(end -0.12065 0.3048)
			(stroke
				(width 0.1)
				(type default)
			)
			(layer "F.Fab")
		)
		(fp_line
			(start 0.67945 0.3048)
			(end 0.120396 0.3048)
			(stroke
				(width 0.1)
				(type default)
			)
			(layer "F.Fab")
		)
		(fp_line
			(start 0.120396 0.3048)
			(end 0.120396 0.2794)
			(stroke
				(width 0.1)
				(type default)
			)
			(layer "F.Fab")
		)
		(fp_line
			(start -0.12065 0.3048)
			(end -0.67945 0.3048)
			(stroke
				(width 0.1)
				(type default)
			)
			(layer "F.Fab")
		)
		(fp_line
			(start -0.67945 0.3048)
			(end -0.67945 -0.305054)
			(stroke
				(width 0.1)
				(type default)
			)
			(layer "F.Fab")
		)
		(pad "1" smd circle
			(at -0.40005 0 90)
			(size 0 0)
			(layers "F.Cu" "F.Mask" "F.Paste")
			(net "P12V_SSD3")
		)
		(pad "2" smd circle
			(at 0.40005 0 90)
			(size 0 0)
			(layers "F.Cu" "F.Mask" "F.Paste")
			(net "GND")
		)
	)
	(footprint ""
		(layer "F.Cu")
		(at 436.307484 -96.811592 -90)
		(property "Reference" "R762"
			(at 0 0 270)
			(layer "F.SilkS")
			(hide yes)
			(effects
				(font
					(size 1.27 1.27)
				)
			)
		)
		(property "Value" ""
			(at 0 0 270)
			(layer "F.Fab")
			(effects
				(font
					(size 1.27 1.27)
				)
			)
		)
		(duplicate_pad_numbers_are_jumpers no)
		(fp_line
			(start -0.7874 0.4064)
			(end -0.7874 -0.4064)
			(stroke
				(width 0.1524)
				(type default)
			)
			(layer "F.SilkS")
		)
		(fp_line
			(start 0.7874 0.4064)
			(end -0.7874 0.4064)
			(stroke
				(width 0.1524)
				(type default)
			)
			(layer "F.SilkS")
		)
		(fp_line
			(start -0.7874 -0.4064)
			(end 0.7874 -0.4064)
			(stroke
				(width 0.1524)
				(type default)
			)
			(layer "F.SilkS")
		)
		(fp_line
			(start 0.7874 -0.4064)
			(end 0.7874 0.4064)
			(stroke
				(width 0.1524)
				(type default)
			)
			(layer "F.SilkS")
		)
		(fp_line
			(start -0.67945 0.3048)
			(end -0.67945 -0.305054)
			(stroke
				(width 0.1)
				(type default)
			)
			(layer "F.Fab")
		)
		(fp_line
			(start -0.12065 0.3048)
			(end -0.67945 0.3048)
			(stroke
				(width 0.1)
				(type default)
			)
			(layer "F.Fab")
		)
		(fp_line
			(start 0.120396 0.3048)
			(end 0.120396 0.2794)
			(stroke
				(width 0.1)
				(type default)
			)
			(layer "F.Fab")
		)
		(fp_line
			(start 0.67945 0.3048)
			(end 0.120396 0.3048)
			(stroke
				(width 0.1)
				(type default)
			)
			(layer "F.Fab")
		)
		(fp_line
			(start -0.12065 0.2794)
			(end -0.12065 0.3048)
			(stroke
				(width 0.1)
				(type default)
			)
			(layer "F.Fab")
		)
		(fp_line
			(start 0.120396 0.2794)
			(end -0.12065 0.2794)
			(stroke
				(width 0.1)
				(type default)
			)
			(layer "F.Fab")
		)
		(fp_line
			(start -0.12065 -0.2794)
			(end 0.12065 -0.2794)
			(stroke
				(width 0.1)
				(type default)
			)
			(layer "F.Fab")
		)
		(fp_line
			(start 0.12065 -0.2794)
			(end 0.12065 -0.3048)
			(stroke
				(width 0.1)
				(type default)
			)
			(layer "F.Fab")
		)
		(fp_line
			(start 0.12065 -0.3048)
			(end 0.67945 -0.3048)
			(stroke
				(width 0.1)
				(type default)
			)
			(layer "F.Fab")
		)
		(fp_line
			(start 0.67945 -0.3048)
			(end 0.67945 0.3048)
			(stroke
				(width 0.1)
				(type default)
			)
			(layer "F.Fab")
		)
		(fp_line
			(start -0.67945 -0.305054)
			(end -0.12065 -0.305054)
			(stroke
				(width 0.1)
				(type default)
			)
			(layer "F.Fab")
		)
		(fp_line
			(start -0.12065 -0.305054)
			(end -0.12065 -0.2794)
			(stroke
				(width 0.1)
				(type default)
			)
			(layer "F.Fab")
		)
		(pad "1" smd circle
			(at -0.40005 0 270)
			(size 0 0)
			(layers "F.Cu" "F.Mask" "F.Paste")
			(net "NIC7_ADC_A1")
		)
		(pad "2" smd circle
			(at 0.40005 0 270)
			(size 0 0)
			(layers "F.Cu" "F.Mask" "F.Paste")
			(net "GND")
		)
	)
	(footprint ""
		(layer "F.Cu")
		(at 377.3805 -343.952322 90)
		(property "Reference" "C766"
			(at 0 0 90)
			(layer "F.SilkS")
			(hide yes)
			(effects
				(font
					(size 1.27 1.27)
				)
			)
		)
		(property "Value" ""
			(at 0 0 90)
			(layer "F.Fab")
			(effects
				(font
					(size 1.27 1.27)
				)
			)
		)
		(duplicate_pad_numbers_are_jumpers no)
		(fp_line
			(start 0.299974 -0.150114)
			(end 0.299974 0.150114)
			(stroke
				(width 0.1)
				(type default)
			)
			(layer "F.Fab")
		)
		(fp_line
			(start -0.299974 -0.150114)
			(end 0.299974 -0.150114)
			(stroke
				(width 0.1)
				(type default)
			)
			(layer "F.Fab")
		)
		(fp_line
			(start 0.299974 0.150114)
			(end -0.299974 0.150114)
			(stroke
				(width 0.1)
				(type default)
			)
			(layer "F.Fab")
		)
		(fp_line
			(start -0.299974 0.150114)
			(end -0.299974 -0.150114)
			(stroke
				(width 0.1)
				(type default)
			)
			(layer "F.Fab")
		)
		(pad "1" smd rect
			(at -0.2667 0 90)
			(size 0.3048 0.381)
			(layers "F.Cu" "F.Mask" "F.Paste")
			(net "P5E_PEX3_STN6_TX_DP<109>")
		)
		(pad "2" smd rect
			(at 0.2667 0 90)
			(size 0.3048 0.381)
			(layers "F.Cu" "F.Mask" "F.Paste")
			(net "P5E_PEX3_STN6_TX_C_DP<109>")
		)
	)
	(footprint ""
		(layer "F.Cu")
		(at 136.534652 -30.94609 180)
		(property "Reference" "C280"
			(at 0 0 180)
			(layer "F.SilkS")
			(hide yes)
			(effects
				(font
					(size 1.27 1.27)
				)
			)
		)
		(property "Value" ""
			(at 0 0 180)
			(layer "F.Fab")
			(effects
				(font
					(size 1.27 1.27)
				)
			)
		)
		(duplicate_pad_numbers_are_jumpers no)
		(fp_line
			(start 0.299974 0.150114)
			(end -0.299974 0.150114)
			(stroke
				(width 0.1)
				(type default)
			)
			(layer "F.Fab")
		)
		(fp_line
			(start 0.299974 -0.150114)
			(end 0.299974 0.150114)
			(stroke
				(width 0.1)
				(type default)
			)
			(layer "F.Fab")
		)
		(fp_line
			(start -0.299974 0.150114)
			(end -0.299974 -0.150114)
			(stroke
				(width 0.1)
				(type default)
			)
			(layer "F.Fab")
		)
		(fp_line
			(start -0.299974 -0.150114)
			(end 0.299974 -0.150114)
			(stroke
				(width 0.1)
				(type default)
			)
			(layer "F.Fab")
		)
		(pad "1" smd rect
			(at -0.2667 0 180)
			(size 0.3048 0.381)
			(layers "F.Cu" "F.Mask" "F.Paste")
			(net "P5E_PEX1_STN2_TX_DP<45>")
		)
		(pad "2" smd rect
			(at 0.2667 0 180)
			(size 0.3048 0.381)
			(layers "F.Cu" "F.Mask" "F.Paste")
			(net "P5E_PEX1_STN2_TX_C_DP<45>")
		)
	)
	(footprint ""
		(layer "F.Cu")
		(at 243.93271 -162.003994 90)
		(property "Reference" "PC814"
			(at 0 0 90)
			(layer "F.SilkS")
			(hide yes)
			(effects
				(font
					(size 1.27 1.27)
				)
			)
		)
		(property "Value" ""
			(at 0 0 90)
			(layer "F.Fab")
			(effects
				(font
					(size 1.27 1.27)
				)
			)
		)
		(duplicate_pad_numbers_are_jumpers no)
		(fp_line
			(start 0.7874 -0.4064)
			(end 0.7874 0.4064)
			(stroke
				(width 0.1524)
				(type default)
			)
			(layer "F.SilkS")
		)
		(fp_line
			(start -0.7874 -0.4064)
			(end 0.7874 -0.4064)
			(stroke
				(width 0.1524)
				(type default)
			)
			(layer "F.SilkS")
		)
		(fp_line
			(start 0.7874 0.4064)
			(end -0.7874 0.4064)
			(stroke
				(width 0.1524)
				(type default)
			)
			(layer "F.SilkS")
		)
		(fp_line
			(start -0.7874 0.4064)
			(end -0.7874 -0.4064)
			(stroke
				(width 0.1524)
				(type default)
			)
			(layer "F.SilkS")
		)
		(fp_line
			(start -0.12065 -0.305054)
			(end -0.12065 -0.2794)
			(stroke
				(width 0.1)
				(type default)
			)
			(layer "F.Fab")
		)
		(fp_line
			(start -0.67945 -0.305054)
			(end -0.12065 -0.305054)
			(stroke
				(width 0.1)
				(type default)
			)
			(layer "F.Fab")
		)
		(fp_line
			(start 0.67945 -0.3048)
			(end 0.67945 0.3048)
			(stroke
				(width 0.1)
				(type default)
			)
			(layer "F.Fab")
		)
		(fp_line
			(start 0.12065 -0.3048)
			(end 0.67945 -0.3048)
			(stroke
				(width 0.1)
				(type default)
			)
			(layer "F.Fab")
		)
		(fp_line
			(start 0.12065 -0.2794)
			(end 0.12065 -0.3048)
			(stroke
				(width 0.1)
				(type default)
			)
			(layer "F.Fab")
		)
		(fp_line
			(start -0.12065 -0.2794)
			(end 0.12065 -0.2794)
			(stroke
				(width 0.1)
				(type default)
			)
			(layer "F.Fab")
		)
		(fp_line
			(start 0.120396 0.2794)
			(end -0.12065 0.2794)
			(stroke
				(width 0.1)
				(type default)
			)
			(layer "F.Fab")
		)
		(fp_line
			(start -0.12065 0.2794)
			(end -0.12065 0.3048)
			(stroke
				(width 0.1)
				(type default)
			)
			(layer "F.Fab")
		)
		(fp_line
			(start 0.67945 0.3048)
			(end 0.120396 0.3048)
			(stroke
				(width 0.1)
				(type default)
			)
			(layer "F.Fab")
		)
		(fp_line
			(start 0.120396 0.3048)
			(end 0.120396 0.2794)
			(stroke
				(width 0.1)
				(type default)
			)
			(layer "F.Fab")
		)
		(fp_line
			(start -0.12065 0.3048)
			(end -0.67945 0.3048)
			(stroke
				(width 0.1)
				(type default)
			)
			(layer "F.Fab")
		)
		(fp_line
			(start -0.67945 0.3048)
			(end -0.67945 -0.305054)
			(stroke
				(width 0.1)
				(type default)
			)
			(layer "F.Fab")
		)
		(pad "1" smd circle
			(at -0.40005 0 90)
			(size 0 0)
			(layers "F.Cu" "F.Mask" "F.Paste")
			(net "P12V_NIC4_CO_ISET_R")
		)
		(pad "2" smd circle
			(at 0.40005 0 90)
			(size 0 0)
			(layers "F.Cu" "F.Mask" "F.Paste")
			(net "GND")
		)
	)
	(footprint ""
		(layer "F.Cu")
		(at 240.76914 -308.568598 180)
		(property "Reference" "PU18"
			(at 3.535426 -3.834638 0)
			(unlocked yes)
			(layer "F.SilkS")
			(effects
				(font
					(size 0.7874 0.5842)
					(thickness 0.1524)
				)
				(justify left)
			)
		)
		(property "Value" ""
			(at 0 0 180)
			(layer "F.Fab")
			(effects
				(font
					(size 1.27 1.27)
				)
			)
		)
		(duplicate_pad_numbers_are_jumpers no)
		(fp_line
			(start 1.549908 2.050034)
			(end 1.549908 1.9304)
			(stroke
				(width 0.1524)
				(type default)
			)
			(layer "F.SilkS")
		)
		(fp_line
			(start 1.549908 -1.9812)
			(end 1.549908 -2.050034)
			(stroke
				(width 0.1524)
				(type default)
			)
			(layer "F.SilkS")
		)
		(fp_line
			(start 1.549908 -2.050034)
			(end 0.5842 -2.050034)
			(stroke
				(width 0.1524)
				(type default)
			)
			(layer "F.SilkS")
		)
		(fp_line
			(start 0.3048 -2.4638)
			(end 0.3048 -3.2258)
			(stroke
				(width 0.1524)
				(type default)
			)
			(layer "F.SilkS")
		)
		(fp_line
			(start 0 2.050034)
			(end 1.549908 2.050034)
			(stroke
				(width 0.1524)
				(type default)
			)
			(layer "F.SilkS")
		)
		(fp_line
			(start -0.3048 2.4638)
			(end -0.3048 3.2258)
			(stroke
				(width 0.1524)
				(type default)
			)
			(layer "F.SilkS")
		)
		(fp_line
			(start -0.5842 -2.050034)
			(end -1.549908 -2.050034)
			(stroke
				(width 0.1524)
				(type default)
			)
			(layer "F.SilkS")
		)
		(fp_line
			(start -1.549908 2.050034)
			(end -0.5842 2.050034)
			(stroke
				(width 0.1524)
				(type default)
			)
			(layer "F.SilkS")
		)
		(fp_line
			(start -1.549908 1.9812)
			(end -1.549908 2.050034)
			(stroke
				(width 0.1524)
				(type default)
			)
			(layer "F.SilkS")
		)
		(fp_line
			(start -1.549908 -2.050034)
			(end -1.549908 -1.9812)
			(stroke
				(width 0.1524)
				(type default)
			)
			(layer "F.SilkS")
		)
		(fp_line
			(start -1.9812 0)
			(end -2.3622 0)
			(stroke
				(width 0.1524)
				(type default)
			)
			(layer "F.SilkS")
		)
		(fp_poly
			(pts
				(xy -2.9464 -2.208022) (xy -2.9464 -1.192022) (xy -1.9304 -1.700022)
			)
			(stroke
				(width 0)
				(type default)
			)
			(fill yes)
			(layer "F.SilkS")
		)
		(fp_line
			(start 1.549908 2.050034)
			(end 1.549908 -2.050034)
			(stroke
				(width 0.1)
				(type default)
			)
			(layer "F.Fab")
		)
		(fp_line
			(start 1.549908 -2.050034)
			(end -1.549908 -2.050034)
			(stroke
				(width 0.1)
				(type default)
			)
			(layer "F.Fab")
		)
		(fp_line
			(start 0.3048 -2.4638)
			(end 0.3048 -3.2258)
			(stroke
				(width 0.1)
				(type default)
			)
			(layer "F.Fab")
		)
		(fp_line
			(start -0.3048 2.4638)
			(end -0.3048 3.2258)
			(stroke
				(width 0.1)
				(type default)
			)
			(layer "F.Fab")
		)
		(fp_line
			(start -1.549908 2.050034)
			(end 1.549908 2.050034)
			(stroke
				(width 0.1)
				(type default)
			)
			(layer "F.Fab")
		)
		(fp_line
			(start -1.549908 -2.050034)
			(end -1.549908 2.050034)
			(stroke
				(width 0.1)
				(type default)
			)
			(layer "F.Fab")
		)
		(fp_line
			(start -1.9812 0)
			(end -2.3622 0)
			(stroke
				(width 0.1)
				(type default)
			)
			(layer "F.Fab")
		)
		(fp_poly
			(pts
				(xy -2.9464 -2.208022) (xy -2.9464 -1.192022) (xy -1.9304 -1.700022)
			)
			(stroke
				(width 0)
				(type default)
			)
			(fill yes)
			(layer "F.Fab")
		)
		(fp_text user "11_18"
			(at 2.512568 0.9906 90)
			(unlocked yes)
			(layer "F.SilkS")
			(effects
				(font
					(size 0.635 0.4064)
					(thickness 0.1524)
				)
			)
		)
		(fp_text user "19"
			(at 1.88849 -2.600198 90)
			(unlocked yes)
			(layer "F.SilkS")
			(effects
				(font
					(size 0.635 0.4064)
					(thickness 0.1524)
				)
			)
		)
		(fp_text user "9"
			(at -1.81991 2.378202 90)
			(unlocked yes)
			(layer "F.SilkS")
			(effects
				(font
					(size 0.635 0.4064)
					(thickness 0.1524)
				)
			)
		)
		(fp_text user "11_18"
			(at 2.512568 0.9906 90)
			(unlocked yes)
			(layer "F.Fab")
			(effects
				(font
					(size 0.635 0.4064)
					(thickness 0.1524)
				)
			)
		)
		(fp_text user "19"
			(at 2.410968 -2.159 90)
			(unlocked yes)
			(layer "F.Fab")
			(effects
				(font
					(size 0.635 0.4064)
					(thickness 0.1524)
				)
			)
		)
		(fp_text user "9"
			(at -2.338832 2.0574 90)
			(unlocked yes)
			(layer "F.Fab")
			(effects
				(font
					(size 0.635 0.4064)
					(thickness 0.1524)
				)
			)
		)
		(pad "1" smd rect
			(at -1.35001 -1.700022 270)
			(size 0.3048 0.9144)
			(layers "F.Cu" "F.Mask" "F.Paste")
			(net "SW_P1V25_PEX2_BT")
		)
		(pad "2" smd rect
			(at -1.400048 -1.199896 270)
			(size 0.1778 0.8128)
			(layers "F.Cu" "F.Mask" "F.Paste")
			(net "GND")
		)
		(pad "3" smd rect
			(at -1.400048 -0.8001 270)
			(size 0.1778 0.8128)
			(layers "F.Cu" "F.Mask" "F.Paste")
			(net "P1V25_PEX2_CS")
		)
		(pad "4" smd rect
			(at -1.400048 -0.40005 270)
			(size 0.1778 0.8128)
			(layers "F.Cu" "F.Mask" "F.Paste")
			(net "GND")
		)
		(pad "5" smd rect
			(at -1.400048 0 270)
			(size 0.1778 0.8128)
			(layers "F.Cu" "F.Mask" "F.Paste")
			(net "P1V25_PEX2_REF")
		)
		(pad "6" smd rect
			(at -1.400048 0.40005 270)
			(size 0.1778 0.8128)
			(layers "F.Cu" "F.Mask" "F.Paste")
			(net "SH_P1V25_PEX2_FB_N")
		)
		(pad "7" smd rect
			(at -1.400048 0.8001 270)
			(size 0.1778 0.8128)
			(layers "F.Cu" "F.Mask" "F.Paste")
			(net "P1V25_PEX2_FB")
		)
		(pad "8" smd rect
			(at -1.400048 1.199896 270)
			(size 0.1778 0.8128)
			(layers "F.Cu" "F.Mask" "F.Paste")
			(net "P1V25_PEX2_EN")
		)
		(pad "9" smd rect
			(at -1.400048 1.700022 270)
			(size 0.3048 0.8128)
			(layers "F.Cu" "F.Mask" "F.Paste")
			(net "PWRGD_P1V25_PEX2")
		)
		(pad "10" smd rect
			(at -0.299974 1.299972 180)
			(size 0.3048 2.0066)
			(layers "F.Cu" "F.Mask" "F.Paste")
			(net "SW_P12V_P1V25_PEX2_FLT")
		)
		(pad "11_18" smd circle
			(at 1.175004 0.275082 180)
			(size 0 0)
			(layers "F.Cu" "F.Mask" "F.Paste")
			(net "GND")
		)
		(pad "19" smd rect
			(at 1.400048 -1.700022 90)
			(size 0.3048 0.8128)
			(layers "F.Cu" "F.Mask" "F.Paste")
			(net "P1V25_PEX2_VCC")
		)
		(pad "20" smd rect
			(at 0.299974 -1.299972 180)
			(size 0.3048 2.0066)
			(layers "F.Cu" "F.Mask" "F.Paste")
			(net "SW_P1V25_PEX2_PH")
		)
		(pad "21" smd rect
			(at -0.299974 -1.299972 180)
			(size 0.3048 2.0066)
			(layers "F.Cu" "F.Mask" "F.Paste")
			(net "SW_P12V_P1V25_PEX2_FLT")
		)
	)
	(footprint ""
		(layer "F.Cu")
		(at 314.861448 -124.991114 180)
		(property "Reference" "C447"
			(at 0 0 180)
			(layer "F.SilkS")
			(hide yes)
			(effects
				(font
					(size 1.27 1.27)
				)
			)
		)
		(property "Value" ""
			(at 0 0 180)
			(layer "F.Fab")
			(effects
				(font
					(size 1.27 1.27)
				)
			)
		)
		(duplicate_pad_numbers_are_jumpers no)
		(fp_line
			(start 0.299974 0.150114)
			(end -0.299974 0.150114)
			(stroke
				(width 0.1)
				(type default)
			)
			(layer "F.Fab")
		)
		(fp_line
			(start 0.299974 -0.150114)
			(end 0.299974 0.150114)
			(stroke
				(width 0.1)
				(type default)
			)
			(layer "F.Fab")
		)
		(fp_line
			(start -0.299974 0.150114)
			(end -0.299974 -0.150114)
			(stroke
				(width 0.1)
				(type default)
			)
			(layer "F.Fab")
		)
		(fp_line
			(start -0.299974 -0.150114)
			(end 0.299974 -0.150114)
			(stroke
				(width 0.1)
				(type default)
			)
			(layer "F.Fab")
		)
		(pad "1" smd rect
			(at -0.2667 0 180)
			(size 0.3048 0.381)
			(layers "F.Cu" "F.Mask" "F.Paste")
			(net "P5E_PEX2_STN0_TX_DP<3>")
		)
		(pad "2" smd rect
			(at 0.2667 0 180)
			(size 0.3048 0.381)
			(layers "F.Cu" "F.Mask" "F.Paste")
			(net "P5E_PEX2_STN0_TX_C_DP<3>")
		)
	)
	(footprint ""
		(layer "F.Cu")
		(at 257.177032 -343.843356 180)
		(property "Reference" "C4492"
			(at 0 0 180)
			(layer "F.SilkS")
			(hide yes)
			(effects
				(font
					(size 1.27 1.27)
				)
			)
		)
		(property "Value" ""
			(at 0 0 180)
			(layer "F.Fab")
			(effects
				(font
					(size 1.27 1.27)
				)
			)
		)
		(duplicate_pad_numbers_are_jumpers no)
		(fp_line
			(start 0.7874 0.4064)
			(end -0.7874 0.4064)
			(stroke
				(width 0.1524)
				(type default)
			)
			(layer "F.SilkS")
		)
		(fp_line
			(start 0.7874 -0.4064)
			(end 0.7874 0.4064)
			(stroke
				(width 0.1524)
				(type default)
			)
			(layer "F.SilkS")
		)
		(fp_line
			(start -0.7874 0.4064)
			(end -0.7874 -0.4064)
			(stroke
				(width 0.1524)
				(type default)
			)
			(layer "F.SilkS")
		)
		(fp_line
			(start -0.7874 -0.4064)
			(end 0.7874 -0.4064)
			(stroke
				(width 0.1524)
				(type default)
			)
			(layer "F.SilkS")
		)
		(fp_line
			(start 0.67945 0.3048)
			(end 0.120396 0.3048)
			(stroke
				(width 0.1)
				(type default)
			)
			(layer "F.Fab")
		)
		(fp_line
			(start 0.67945 -0.3048)
			(end 0.67945 0.3048)
			(stroke
				(width 0.1)
				(type default)
			)
			(layer "F.Fab")
		)
		(fp_line
			(start 0.12065 -0.2794)
			(end 0.12065 -0.3048)
			(stroke
				(width 0.1)
				(type default)
			)
			(layer "F.Fab")
		)
		(fp_line
			(start 0.12065 -0.3048)
			(end 0.67945 -0.3048)
			(stroke
				(width 0.1)
				(type default)
			)
			(layer "F.Fab")
		)
		(fp_line
			(start 0.120396 0.3048)
			(end 0.120396 0.2794)
			(stroke
				(width 0.1)
				(type default)
			)
			(layer "F.Fab")
		)
		(fp_line
			(start 0.120396 0.2794)
			(end -0.12065 0.2794)
			(stroke
				(width 0.1)
				(type default)
			)
			(layer "F.Fab")
		)
		(fp_line
			(start -0.12065 0.3048)
			(end -0.67945 0.3048)
			(stroke
				(width 0.1)
				(type default)
			)
			(layer "F.Fab")
		)
		(fp_line
			(start -0.12065 0.2794)
			(end -0.12065 0.3048)
			(stroke
				(width 0.1)
				(type default)
			)
			(layer "F.Fab")
		)
		(fp_line
			(start -0.12065 -0.2794)
			(end 0.12065 -0.2794)
			(stroke
				(width 0.1)
				(type default)
			)
			(layer "F.Fab")
		)
		(fp_line
			(start -0.12065 -0.305054)
			(end -0.12065 -0.2794)
			(stroke
				(width 0.1)
				(type default)
			)
			(layer "F.Fab")
		)
		(fp_line
			(start -0.67945 0.3048)
			(end -0.67945 -0.305054)
			(stroke
				(width 0.1)
				(type default)
			)
			(layer "F.Fab")
		)
		(fp_line
			(start -0.67945 -0.305054)
			(end -0.12065 -0.305054)
			(stroke
				(width 0.1)
				(type default)
			)
			(layer "F.Fab")
		)
		(pad "1" smd circle
			(at -0.40005 0 180)
			(size 0 0)
			(layers "F.Cu" "F.Mask" "F.Paste")
			(net "HSC_OC_LT6700_VS")
		)
		(pad "2" smd circle
			(at 0.40005 0 180)
			(size 0 0)
			(layers "F.Cu" "F.Mask" "F.Paste")
			(net "GND")
		)
	)
	(footprint ""
		(layer "F.Cu")
		(at 47.530512 -66.32194 -90)
		(property "Reference" "PC647"
			(at 0 0 270)
			(layer "F.SilkS")
			(hide yes)
			(effects
				(font
					(size 1.27 1.27)
				)
			)
		)
		(property "Value" ""
			(at 0 0 270)
			(layer "F.Fab")
			(effects
				(font
					(size 1.27 1.27)
				)
			)
		)
		(duplicate_pad_numbers_are_jumpers no)
		(fp_line
			(start -0.7874 0.4064)
			(end -0.7874 -0.4064)
			(stroke
				(width 0.1524)
				(type default)
			)
			(layer "F.SilkS")
		)
		(fp_line
			(start 0.7874 0.4064)
			(end -0.7874 0.4064)
			(stroke
				(width 0.1524)
				(type default)
			)
			(layer "F.SilkS")
		)
		(fp_line
			(start -0.7874 -0.4064)
			(end 0.7874 -0.4064)
			(stroke
				(width 0.1524)
				(type default)
			)
			(layer "F.SilkS")
		)
		(fp_line
			(start 0.7874 -0.4064)
			(end 0.7874 0.4064)
			(stroke
				(width 0.1524)
				(type default)
			)
			(layer "F.SilkS")
		)
		(fp_line
			(start -0.67945 0.3048)
			(end -0.67945 -0.305054)
			(stroke
				(width 0.1)
				(type default)
			)
			(layer "F.Fab")
		)
		(fp_line
			(start -0.12065 0.3048)
			(end -0.67945 0.3048)
			(stroke
				(width 0.1)
				(type default)
			)
			(layer "F.Fab")
		)
		(fp_line
			(start 0.120396 0.3048)
			(end 0.120396 0.2794)
			(stroke
				(width 0.1)
				(type default)
			)
			(layer "F.Fab")
		)
		(fp_line
			(start 0.67945 0.3048)
			(end 0.120396 0.3048)
			(stroke
				(width 0.1)
				(type default)
			)
			(layer "F.Fab")
		)
		(fp_line
			(start -0.12065 0.2794)
			(end -0.12065 0.3048)
			(stroke
				(width 0.1)
				(type default)
			)
			(layer "F.Fab")
		)
		(fp_line
			(start 0.120396 0.2794)
			(end -0.12065 0.2794)
			(stroke
				(width 0.1)
				(type default)
			)
			(layer "F.Fab")
		)
		(fp_line
			(start -0.12065 -0.2794)
			(end 0.12065 -0.2794)
			(stroke
				(width 0.1)
				(type default)
			)
			(layer "F.Fab")
		)
		(fp_line
			(start 0.12065 -0.2794)
			(end 0.12065 -0.3048)
			(stroke
				(width 0.1)
				(type default)
			)
			(layer "F.Fab")
		)
		(fp_line
			(start 0.12065 -0.3048)
			(end 0.67945 -0.3048)
			(stroke
				(width 0.1)
				(type default)
			)
			(layer "F.Fab")
		)
		(fp_line
			(start 0.67945 -0.3048)
			(end 0.67945 0.3048)
			(stroke
				(width 0.1)
				(type default)
			)
			(layer "F.Fab")
		)
		(fp_line
			(start -0.67945 -0.305054)
			(end -0.12065 -0.305054)
			(stroke
				(width 0.1)
				(type default)
			)
			(layer "F.Fab")
		)
		(fp_line
			(start -0.12065 -0.305054)
			(end -0.12065 -0.2794)
			(stroke
				(width 0.1)
				(type default)
			)
			(layer "F.Fab")
		)
		(pad "1" smd circle
			(at -0.40005 0 270)
			(size 0 0)
			(layers "F.Cu" "F.Mask" "F.Paste")
			(net "P12V_SSD1_CO_DV_DT")
		)
		(pad "2" smd circle
			(at 0.40005 0 270)
			(size 0 0)
			(layers "F.Cu" "F.Mask" "F.Paste")
			(net "GND")
		)
	)
	(footprint ""
		(layer "F.Cu")
		(at 112.311942 -111.531654)
		(property "Reference" "PR6876"
			(at 0 0 0)
			(layer "F.SilkS")
			(hide yes)
			(effects
				(font
					(size 1.27 1.27)
				)
			)
		)
		(property "Value" ""
			(at 0 0 0)
			(layer "F.Fab")
			(effects
				(font
					(size 1.27 1.27)
				)
			)
		)
		(duplicate_pad_numbers_are_jumpers no)
		(fp_line
			(start -0.7874 -0.4064)
			(end 0.7874 -0.4064)
			(stroke
				(width 0.1524)
				(type default)
			)
			(layer "F.SilkS")
		)
		(fp_line
			(start -0.7874 0.4064)
			(end -0.7874 -0.4064)
			(stroke
				(width 0.1524)
				(type default)
			)
			(layer "F.SilkS")
		)
		(fp_line
			(start 0.7874 -0.4064)
			(end 0.7874 0.4064)
			(stroke
				(width 0.1524)
				(type default)
			)
			(layer "F.SilkS")
		)
		(fp_line
			(start 0.7874 0.4064)
			(end -0.7874 0.4064)
			(stroke
				(width 0.1524)
				(type default)
			)
			(layer "F.SilkS")
		)
		(fp_line
			(start -0.67945 -0.305054)
			(end -0.12065 -0.305054)
			(stroke
				(width 0.1)
				(type default)
			)
			(layer "F.Fab")
		)
		(fp_line
			(start -0.67945 0.3048)
			(end -0.67945 -0.305054)
			(stroke
				(width 0.1)
				(type default)
			)
			(layer "F.Fab")
		)
		(fp_line
			(start -0.12065 -0.305054)
			(end -0.12065 -0.2794)
			(stroke
				(width 0.1)
				(type default)
			)
			(layer "F.Fab")
		)
		(fp_line
			(start -0.12065 -0.2794)
			(end 0.12065 -0.2794)
			(stroke
				(width 0.1)
				(type default)
			)
			(layer "F.Fab")
		)
		(fp_line
			(start -0.12065 0.2794)
			(end -0.12065 0.3048)
			(stroke
				(width 0.1)
				(type default)
			)
			(layer "F.Fab")
		)
		(fp_line
			(start -0.12065 0.3048)
			(end -0.67945 0.3048)
			(stroke
				(width 0.1)
				(type default)
			)
			(layer "F.Fab")
		)
		(fp_line
			(start 0.120396 0.2794)
			(end -0.12065 0.2794)
			(stroke
				(width 0.1)
				(type default)
			)
			(layer "F.Fab")
		)
		(fp_line
			(start 0.120396 0.3048)
			(end 0.120396 0.2794)
			(stroke
				(width 0.1)
				(type default)
			)
			(layer "F.Fab")
		)
		(fp_line
			(start 0.12065 -0.3048)
			(end 0.67945 -0.3048)
			(stroke
				(width 0.1)
				(type default)
			)
			(layer "F.Fab")
		)
		(fp_line
			(start 0.12065 -0.2794)
			(end 0.12065 -0.3048)
			(stroke
				(width 0.1)
				(type default)
			)
			(layer "F.Fab")
		)
		(fp_line
			(start 0.67945 -0.3048)
			(end 0.67945 0.3048)
			(stroke
				(width 0.1)
				(type default)
			)
			(layer "F.Fab")
		)
		(fp_line
			(start 0.67945 0.3048)
			(end 0.120396 0.3048)
			(stroke
				(width 0.1)
				(type default)
			)
			(layer "F.Fab")
		)
		(pad "1" smd circle
			(at -0.40005 0)
			(size 0 0)
			(layers "F.Cu" "F.Mask" "F.Paste")
			(net "P12V_NIC1_CO_ISET")
		)
		(pad "2" smd circle
			(at 0.40005 0)
			(size 0 0)
			(layers "F.Cu" "F.Mask" "F.Paste")
			(net "GND")
		)
	)
	(footprint ""
		(layer "F.Cu")
		(at 334.838548 -80.607662 90)
		(property "Reference" "R1170"
			(at 0 0 90)
			(layer "F.SilkS")
			(hide yes)
			(effects
				(font
					(size 1.27 1.27)
				)
			)
		)
		(property "Value" ""
			(at 0 0 90)
			(layer "F.Fab")
			(effects
				(font
					(size 1.27 1.27)
				)
			)
		)
		(duplicate_pad_numbers_are_jumpers no)
		(fp_line
			(start -0.7874 -0.4064)
			(end 0.7874 -0.4064)
			(stroke
				(width 0.1524)
				(type default)
			)
			(layer "F.SilkS")
		)
		(fp_line
			(start -0.12065 -0.305054)
			(end -0.12065 -0.2794)
			(stroke
				(width 0.1)
				(type default)
			)
			(layer "F.Fab")
		)
		(fp_line
			(start -0.67945 -0.305054)
			(end -0.12065 -0.305054)
			(stroke
				(width 0.1)
				(type default)
			)
			(layer "F.Fab")
		)
		(fp_line
			(start 0.67945 -0.3048)
			(end 0.67945 0.3048)
			(stroke
				(width 0.1)
				(type default)
			)
			(layer "F.Fab")
		)
		(fp_line
			(start 0.12065 -0.3048)
			(end 0.67945 -0.3048)
			(stroke
				(width 0.1)
				(type default)
			)
			(layer "F.Fab")
		)
		(fp_line
			(start 0.12065 -0.2794)
			(end 0.12065 -0.3048)
			(stroke
				(width 0.1)
				(type default)
			)
			(layer "F.Fab")
		)
		(fp_line
			(start -0.12065 -0.2794)
			(end 0.12065 -0.2794)
			(stroke
				(width 0.1)
				(type default)
			)
			(layer "F.Fab")
		)
		(fp_line
			(start 0.120396 0.2794)
			(end -0.12065 0.2794)
			(stroke
				(width 0.1)
				(type default)
			)
			(layer "F.Fab")
		)
		(fp_line
			(start -0.12065 0.2794)
			(end -0.12065 0.3048)
			(stroke
				(width 0.1)
				(type default)
			)
			(layer "F.Fab")
		)
		(fp_line
			(start 0.67945 0.3048)
			(end 0.120396 0.3048)
			(stroke
				(width 0.1)
				(type default)
			)
			(layer "F.Fab")
		)
		(fp_line
			(start 0.120396 0.3048)
			(end 0.120396 0.2794)
			(stroke
				(width 0.1)
				(type default)
			)
			(layer "F.Fab")
		)
		(fp_line
			(start -0.12065 0.3048)
			(end -0.67945 0.3048)
			(stroke
				(width 0.1)
				(type default)
			)
			(layer "F.Fab")
		)
		(fp_line
			(start -0.67945 0.3048)
			(end -0.67945 -0.305054)
			(stroke
				(width 0.1)
				(type default)
			)
			(layer "F.Fab")
		)
		(pad "1" smd circle
			(at -0.40005 0 90)
			(size 0 0)
			(layers "F.Cu" "F.Mask" "F.Paste")
			(net "CLK_100M_DB800ZL_SSD8_R_DP")
		)
		(pad "2" smd circle
			(at 0.40005 0 90)
			(size 0 0)
			(layers "F.Cu" "F.Mask" "F.Paste")
			(net "CLK_100M_DB800ZL_SSD8_DP")
		)
	)
	(footprint ""
		(layer "F.Cu")
		(at 52.267104 -57.332626)
		(property "Reference" "R6840"
			(at 0 0 0)
			(layer "F.SilkS")
			(hide yes)
			(effects
				(font
					(size 1.27 1.27)
				)
			)
		)
		(property "Value" ""
			(at 0 0 0)
			(layer "F.Fab")
			(effects
				(font
					(size 1.27 1.27)
				)
			)
		)
		(duplicate_pad_numbers_are_jumpers no)
		(fp_line
			(start -0.7874 -0.4064)
			(end 0.7874 -0.4064)
			(stroke
				(width 0.1524)
				(type default)
			)
			(layer "F.SilkS")
		)
		(fp_line
			(start -0.7874 0.4064)
			(end -0.7874 -0.4064)
			(stroke
				(width 0.1524)
				(type default)
			)
			(layer "F.SilkS")
		)
		(fp_line
			(start 0.7874 -0.4064)
			(end 0.7874 0.4064)
			(stroke
				(width 0.1524)
				(type default)
			)
			(layer "F.SilkS")
		)
		(fp_line
			(start 0.7874 0.4064)
			(end -0.7874 0.4064)
			(stroke
				(width 0.1524)
				(type default)
			)
			(layer "F.SilkS")
		)
		(fp_line
			(start -0.67945 -0.305054)
			(end -0.12065 -0.305054)
			(stroke
				(width 0.1)
				(type default)
			)
			(layer "F.Fab")
		)
		(fp_line
			(start -0.67945 0.3048)
			(end -0.67945 -0.305054)
			(stroke
				(width 0.1)
				(type default)
			)
			(layer "F.Fab")
		)
		(fp_line
			(start -0.12065 -0.305054)
			(end -0.12065 -0.2794)
			(stroke
				(width 0.1)
				(type default)
			)
			(layer "F.Fab")
		)
		(fp_line
			(start -0.12065 -0.2794)
			(end 0.12065 -0.2794)
			(stroke
				(width 0.1)
				(type default)
			)
			(layer "F.Fab")
		)
		(fp_line
			(start -0.12065 0.2794)
			(end -0.12065 0.3048)
			(stroke
				(width 0.1)
				(type default)
			)
			(layer "F.Fab")
		)
		(fp_line
			(start -0.12065 0.3048)
			(end -0.67945 0.3048)
			(stroke
				(width 0.1)
				(type default)
			)
			(layer "F.Fab")
		)
		(fp_line
			(start 0.120396 0.2794)
			(end -0.12065 0.2794)
			(stroke
				(width 0.1)
				(type default)
			)
			(layer "F.Fab")
		)
		(fp_line
			(start 0.120396 0.3048)
			(end 0.120396 0.2794)
			(stroke
				(width 0.1)
				(type default)
			)
			(layer "F.Fab")
		)
		(fp_line
			(start 0.12065 -0.3048)
			(end 0.67945 -0.3048)
			(stroke
				(width 0.1)
				(type default)
			)
			(layer "F.Fab")
		)
		(fp_line
			(start 0.12065 -0.2794)
			(end 0.12065 -0.3048)
			(stroke
				(width 0.1)
				(type default)
			)
			(layer "F.Fab")
		)
		(fp_line
			(start 0.67945 -0.3048)
			(end 0.67945 0.3048)
			(stroke
				(width 0.1)
				(type default)
			)
			(layer "F.Fab")
		)
		(fp_line
			(start 0.67945 0.3048)
			(end 0.120396 0.3048)
			(stroke
				(width 0.1)
				(type default)
			)
			(layer "F.Fab")
		)
		(pad "1" smd circle
			(at -0.40005 0)
			(size 0 0)
			(layers "F.Cu" "F.Mask" "F.Paste")
			(net "SSD1_PWR_EN_R")
		)
		(pad "2" smd circle
			(at 0.40005 0)
			(size 0 0)
			(layers "F.Cu" "F.Mask" "F.Paste")
			(net "GND")
		)
	)
	(footprint ""
		(layer "F.Cu")
		(at 452.277734 -286.034988 180)
		(property "Reference" "PC278"
			(at 0 0 180)
			(layer "F.SilkS")
			(hide yes)
			(effects
				(font
					(size 1.27 1.27)
				)
			)
		)
		(property "Value" ""
			(at 0 0 180)
			(layer "F.Fab")
			(effects
				(font
					(size 1.27 1.27)
				)
			)
		)
		(duplicate_pad_numbers_are_jumpers no)
		(fp_line
			(start 2.750058 2.750058)
			(end 2.750058 0.9398)
			(stroke
				(width 0.1524)
				(type default)
			)
			(layer "F.SilkS")
		)
		(fp_line
			(start 2.750058 -0.9398)
			(end 2.750058 -2.750058)
			(stroke
				(width 0.1524)
				(type default)
			)
			(layer "F.SilkS")
		)
		(fp_line
			(start 2.750058 -2.750058)
			(end -1.988058 -2.750058)
			(stroke
				(width 0.1524)
				(type default)
			)
			(layer "F.SilkS")
		)
		(fp_line
			(start -1.988058 2.750058)
			(end 2.750058 2.750058)
			(stroke
				(width 0.1524)
				(type default)
			)
			(layer "F.SilkS")
		)
		(fp_line
			(start -1.988058 -2.750058)
			(end -2.750058 -1.988058)
			(stroke
				(width 0.1524)
				(type default)
			)
			(layer "F.SilkS")
		)
		(fp_line
			(start -2.750058 1.988058)
			(end -1.988058 2.750058)
			(stroke
				(width 0.1524)
				(type default)
			)
			(layer "F.SilkS")
		)
		(fp_line
			(start -2.750058 0.9398)
			(end -2.750058 1.988058)
			(stroke
				(width 0.1524)
				(type default)
			)
			(layer "F.SilkS")
		)
		(fp_line
			(start -2.750058 -1.988058)
			(end -2.750058 -0.9398)
			(stroke
				(width 0.1524)
				(type default)
			)
			(layer "F.SilkS")
		)
		(fp_line
			(start 2.750058 2.750058)
			(end 2.750058 -2.750058)
			(stroke
				(width 0.1)
				(type default)
			)
			(layer "F.Fab")
		)
		(fp_line
			(start 2.750058 -2.750058)
			(end -2.750058 -2.750058)
			(stroke
				(width 0.1)
				(type default)
			)
			(layer "F.Fab")
		)
		(fp_line
			(start -2.750058 2.750058)
			(end 2.750058 2.750058)
			(stroke
				(width 0.1)
				(type default)
			)
			(layer "F.Fab")
		)
		(fp_line
			(start -2.750058 -2.750058)
			(end -2.750058 2.750058)
			(stroke
				(width 0.1)
				(type default)
			)
			(layer "F.Fab")
		)
		(pad "1" smd rect
			(at -2.199894 0 270)
			(size 1.6002 3.0226)
			(layers "F.Cu" "F.Mask" "F.Paste")
			(net "P1V25_PEX3_R")
		)
		(pad "2" smd rect
			(at 2.199894 0 270)
			(size 1.6002 3.0226)
			(layers "F.Cu" "F.Mask" "F.Paste")
			(net "GND")
		)
	)
	(footprint ""
		(layer "F.Cu")
		(at 343.662 -205.232 -90)
		(property "Reference" "R4139"
			(at 0 0 270)
			(layer "F.SilkS")
			(hide yes)
			(effects
				(font
					(size 1.27 1.27)
				)
			)
		)
		(property "Value" ""
			(at 0 0 270)
			(layer "F.Fab")
			(effects
				(font
					(size 1.27 1.27)
				)
			)
		)
		(duplicate_pad_numbers_are_jumpers no)
		(fp_line
			(start -0.7874 0.4064)
			(end -0.7874 -0.4064)
			(stroke
				(width 0.1524)
				(type default)
			)
			(layer "F.SilkS")
		)
		(fp_line
			(start 0.7874 0.4064)
			(end -0.7874 0.4064)
			(stroke
				(width 0.1524)
				(type default)
			)
			(layer "F.SilkS")
		)
		(fp_line
			(start -0.7874 -0.4064)
			(end 0.7874 -0.4064)
			(stroke
				(width 0.1524)
				(type default)
			)
			(layer "F.SilkS")
		)
		(fp_line
			(start 0.7874 -0.4064)
			(end 0.7874 0.4064)
			(stroke
				(width 0.1524)
				(type default)
			)
			(layer "F.SilkS")
		)
		(fp_line
			(start -0.67945 0.3048)
			(end -0.67945 -0.305054)
			(stroke
				(width 0.1)
				(type default)
			)
			(layer "F.Fab")
		)
		(fp_line
			(start -0.12065 0.3048)
			(end -0.67945 0.3048)
			(stroke
				(width 0.1)
				(type default)
			)
			(layer "F.Fab")
		)
		(fp_line
			(start 0.120396 0.3048)
			(end 0.120396 0.2794)
			(stroke
				(width 0.1)
				(type default)
			)
			(layer "F.Fab")
		)
		(fp_line
			(start 0.67945 0.3048)
			(end 0.120396 0.3048)
			(stroke
				(width 0.1)
				(type default)
			)
			(layer "F.Fab")
		)
		(fp_line
			(start -0.12065 0.2794)
			(end -0.12065 0.3048)
			(stroke
				(width 0.1)
				(type default)
			)
			(layer "F.Fab")
		)
		(fp_line
			(start 0.120396 0.2794)
			(end -0.12065 0.2794)
			(stroke
				(width 0.1)
				(type default)
			)
			(layer "F.Fab")
		)
		(fp_line
			(start -0.12065 -0.2794)
			(end 0.12065 -0.2794)
			(stroke
				(width 0.1)
				(type default)
			)
			(layer "F.Fab")
		)
		(fp_line
			(start 0.12065 -0.2794)
			(end 0.12065 -0.3048)
			(stroke
				(width 0.1)
				(type default)
			)
			(layer "F.Fab")
		)
		(fp_line
			(start 0.12065 -0.3048)
			(end 0.67945 -0.3048)
			(stroke
				(width 0.1)
				(type default)
			)
			(layer "F.Fab")
		)
		(fp_line
			(start 0.67945 -0.3048)
			(end 0.67945 0.3048)
			(stroke
				(width 0.1)
				(type default)
			)
			(layer "F.Fab")
		)
		(fp_line
			(start -0.67945 -0.305054)
			(end -0.12065 -0.305054)
			(stroke
				(width 0.1)
				(type default)
			)
			(layer "F.Fab")
		)
		(fp_line
			(start -0.12065 -0.305054)
			(end -0.12065 -0.2794)
			(stroke
				(width 0.1)
				(type default)
			)
			(layer "F.Fab")
		)
		(pad "1" smd circle
			(at -0.40005 0 270)
			(size 0 0)
			(layers "F.Cu" "F.Mask" "F.Paste")
			(net "SSD14_PWR_EN")
		)
		(pad "2" smd circle
			(at 0.40005 0 270)
			(size 0 0)
			(layers "F.Cu" "F.Mask" "F.Paste")
			(net "SSD14_PWR_EN_R")
		)
	)
	(footprint ""
		(layer "F.Cu")
		(at 135.571738 -25.342342 -90)
		(property "Reference" "R421"
			(at 0 0 270)
			(layer "F.SilkS")
			(hide yes)
			(effects
				(font
					(size 1.27 1.27)
				)
			)
		)
		(property "Value" ""
			(at 0 0 270)
			(layer "F.Fab")
			(effects
				(font
					(size 1.27 1.27)
				)
			)
		)
		(duplicate_pad_numbers_are_jumpers no)
		(fp_line
			(start -0.7874 0.4064)
			(end -0.7874 -0.4064)
			(stroke
				(width 0.1524)
				(type default)
			)
			(layer "F.SilkS")
		)
		(fp_line
			(start 0.7874 0.4064)
			(end -0.7874 0.4064)
			(stroke
				(width 0.1524)
				(type default)
			)
			(layer "F.SilkS")
		)
		(fp_line
			(start -0.7874 -0.4064)
			(end 0.7874 -0.4064)
			(stroke
				(width 0.1524)
				(type default)
			)
			(layer "F.SilkS")
		)
		(fp_line
			(start 0.7874 -0.4064)
			(end 0.7874 0.4064)
			(stroke
				(width 0.1524)
				(type default)
			)
			(layer "F.SilkS")
		)
		(fp_line
			(start -0.67945 0.3048)
			(end -0.67945 -0.305054)
			(stroke
				(width 0.1)
				(type default)
			)
			(layer "F.Fab")
		)
		(fp_line
			(start -0.12065 0.3048)
			(end -0.67945 0.3048)
			(stroke
				(width 0.1)
				(type default)
			)
			(layer "F.Fab")
		)
		(fp_line
			(start 0.120396 0.3048)
			(end 0.120396 0.2794)
			(stroke
				(width 0.1)
				(type default)
			)
			(layer "F.Fab")
		)
		(fp_line
			(start 0.67945 0.3048)
			(end 0.120396 0.3048)
			(stroke
				(width 0.1)
				(type default)
			)
			(layer "F.Fab")
		)
		(fp_line
			(start -0.12065 0.2794)
			(end -0.12065 0.3048)
			(stroke
				(width 0.1)
				(type default)
			)
			(layer "F.Fab")
		)
		(fp_line
			(start 0.120396 0.2794)
			(end -0.12065 0.2794)
			(stroke
				(width 0.1)
				(type default)
			)
			(layer "F.Fab")
		)
		(fp_line
			(start -0.12065 -0.2794)
			(end 0.12065 -0.2794)
			(stroke
				(width 0.1)
				(type default)
			)
			(layer "F.Fab")
		)
		(fp_line
			(start 0.12065 -0.2794)
			(end 0.12065 -0.3048)
			(stroke
				(width 0.1)
				(type default)
			)
			(layer "F.Fab")
		)
		(fp_line
			(start 0.12065 -0.3048)
			(end 0.67945 -0.3048)
			(stroke
				(width 0.1)
				(type default)
			)
			(layer "F.Fab")
		)
		(fp_line
			(start 0.67945 -0.3048)
			(end 0.67945 0.3048)
			(stroke
				(width 0.1)
				(type default)
			)
			(layer "F.Fab")
		)
		(fp_line
			(start -0.67945 -0.305054)
			(end -0.12065 -0.305054)
			(stroke
				(width 0.1)
				(type default)
			)
			(layer "F.Fab")
		)
		(fp_line
			(start -0.12065 -0.305054)
			(end -0.12065 -0.2794)
			(stroke
				(width 0.1)
				(type default)
			)
			(layer "F.Fab")
		)
		(pad "1" smd circle
			(at -0.40005 0 270)
			(size 0 0)
			(layers "F.Cu" "F.Mask" "F.Paste")
			(net "P3V3_SSD4")
		)
		(pad "2" smd circle
			(at 0.40005 0 270)
			(size 0 0)
			(layers "F.Cu" "F.Mask" "F.Paste")
			(net "DUALPORT_N_SSD4")
		)
	)
	(footprint ""
		(layer "F.Cu")
		(at 320.354452 -217.039698 180)
		(property "Reference" "D20"
			(at 3.743452 -0.023368 0)
			(unlocked yes)
			(layer "F.SilkS")
			(effects
				(font
					(size 0.7874 0.5842)
					(thickness 0.1524)
				)
				(justify left)
			)
		)
		(property "Value" ""
			(at 0 0 180)
			(layer "F.Fab")
			(effects
				(font
					(size 1.27 1.27)
				)
			)
		)
		(duplicate_pad_numbers_are_jumpers no)
		(fp_line
			(start 1.16078 0.4826)
			(end -0.64008 0.4826)
			(stroke
				(width 0.1524)
				(type default)
			)
			(layer "F.SilkS")
		)
		(fp_line
			(start 1.16078 -0.4826)
			(end 1.16078 0.4826)
			(stroke
				(width 0.1524)
				(type default)
			)
			(layer "F.SilkS")
		)
		(fp_line
			(start 1.03378 0.4826)
			(end -0.79248 0.4826)
			(stroke
				(width 0.1524)
				(type default)
			)
			(layer "F.SilkS")
		)
		(fp_line
			(start 1.03378 -0.4826)
			(end 1.03378 0.4826)
			(stroke
				(width 0.1524)
				(type default)
			)
			(layer "F.SilkS")
		)
		(fp_line
			(start 0.90678 0.4826)
			(end -0.90678 0.4826)
			(stroke
				(width 0.1524)
				(type default)
			)
			(layer "F.SilkS")
		)
		(fp_line
			(start 0.90678 -0.4826)
			(end 0.90678 0.4826)
			(stroke
				(width 0.1524)
				(type default)
			)
			(layer "F.SilkS")
		)
		(fp_line
			(start -0.64008 -0.4826)
			(end 1.16078 -0.4826)
			(stroke
				(width 0.1524)
				(type default)
			)
			(layer "F.SilkS")
		)
		(fp_line
			(start -0.79248 -0.4826)
			(end 1.03378 -0.4826)
			(stroke
				(width 0.1524)
				(type default)
			)
			(layer "F.SilkS")
		)
		(fp_line
			(start -0.89408 -0.4826)
			(end 0.90678 -0.4826)
			(stroke
				(width 0.1524)
				(type default)
			)
			(layer "F.SilkS")
		)
		(fp_line
			(start -0.90678 0.4826)
			(end -0.90678 -0.4699)
			(stroke
				(width 0.1524)
				(type default)
			)
			(layer "F.SilkS")
		)
		(fp_line
			(start 0.499872 0.249936)
			(end -0.499872 0.249936)
			(stroke
				(width 0.1)
				(type default)
			)
			(layer "F.Fab")
		)
		(fp_line
			(start 0.499872 -0.249936)
			(end 0.499872 0.249936)
			(stroke
				(width 0.1)
				(type default)
			)
			(layer "F.Fab")
		)
		(fp_line
			(start -0.499872 0.249936)
			(end -0.499872 -0.249936)
			(stroke
				(width 0.1)
				(type default)
			)
			(layer "F.Fab")
		)
		(fp_line
			(start -0.499872 -0.249936)
			(end 0.499872 -0.249936)
			(stroke
				(width 0.1)
				(type default)
			)
			(layer "F.Fab")
		)
		(pad "A" smd rect
			(at -0.47498 0 180)
			(size 0.6096 0.7112)
			(layers "F.Cu" "F.Mask" "F.Paste")
			(net "LED_POSTCODE_R_7")
		)
		(pad "C" smd rect
			(at 0.47498 0 180)
			(size 0.6096 0.7112)
			(layers "F.Cu" "F.Mask" "F.Paste")
			(net "FPGA_DEBUG_LED_R_N")
		)
	)
	(footprint ""
		(layer "F.Cu")
		(at 78.584044 -29.222954 -90)
		(property "Reference" "PC679"
			(at 0 0 270)
			(layer "F.SilkS")
			(hide yes)
			(effects
				(font
					(size 1.27 1.27)
				)
			)
		)
		(property "Value" ""
			(at 0 0 270)
			(layer "F.Fab")
			(effects
				(font
					(size 1.27 1.27)
				)
			)
		)
		(duplicate_pad_numbers_are_jumpers no)
		(fp_line
			(start -0.7874 0.4064)
			(end -0.7874 -0.4064)
			(stroke
				(width 0.1524)
				(type default)
			)
			(layer "F.SilkS")
		)
		(fp_line
			(start 0.7874 0.4064)
			(end -0.7874 0.4064)
			(stroke
				(width 0.1524)
				(type default)
			)
			(layer "F.SilkS")
		)
		(fp_line
			(start -0.7874 -0.4064)
			(end 0.7874 -0.4064)
			(stroke
				(width 0.1524)
				(type default)
			)
			(layer "F.SilkS")
		)
		(fp_line
			(start 0.7874 -0.4064)
			(end 0.7874 0.4064)
			(stroke
				(width 0.1524)
				(type default)
			)
			(layer "F.SilkS")
		)
		(fp_line
			(start -0.67945 0.3048)
			(end -0.67945 -0.305054)
			(stroke
				(width 0.1)
				(type default)
			)
			(layer "F.Fab")
		)
		(fp_line
			(start -0.12065 0.3048)
			(end -0.67945 0.3048)
			(stroke
				(width 0.1)
				(type default)
			)
			(layer "F.Fab")
		)
		(fp_line
			(start 0.120396 0.3048)
			(end 0.120396 0.2794)
			(stroke
				(width 0.1)
				(type default)
			)
			(layer "F.Fab")
		)
		(fp_line
			(start 0.67945 0.3048)
			(end 0.120396 0.3048)
			(stroke
				(width 0.1)
				(type default)
			)
			(layer "F.Fab")
		)
		(fp_line
			(start -0.12065 0.2794)
			(end -0.12065 0.3048)
			(stroke
				(width 0.1)
				(type default)
			)
			(layer "F.Fab")
		)
		(fp_line
			(start 0.120396 0.2794)
			(end -0.12065 0.2794)
			(stroke
				(width 0.1)
				(type default)
			)
			(layer "F.Fab")
		)
		(fp_line
			(start -0.12065 -0.2794)
			(end 0.12065 -0.2794)
			(stroke
				(width 0.1)
				(type default)
			)
			(layer "F.Fab")
		)
		(fp_line
			(start 0.12065 -0.2794)
			(end 0.12065 -0.3048)
			(stroke
				(width 0.1)
				(type default)
			)
			(layer "F.Fab")
		)
		(fp_line
			(start 0.12065 -0.3048)
			(end 0.67945 -0.3048)
			(stroke
				(width 0.1)
				(type default)
			)
			(layer "F.Fab")
		)
		(fp_line
			(start 0.67945 -0.3048)
			(end 0.67945 0.3048)
			(stroke
				(width 0.1)
				(type default)
			)
			(layer "F.Fab")
		)
		(fp_line
			(start -0.67945 -0.305054)
			(end -0.12065 -0.305054)
			(stroke
				(width 0.1)
				(type default)
			)
			(layer "F.Fab")
		)
		(fp_line
			(start -0.12065 -0.305054)
			(end -0.12065 -0.2794)
			(stroke
				(width 0.1)
				(type default)
			)
			(layer "F.Fab")
		)
		(pad "1" smd circle
			(at -0.40005 0 270)
			(size 0 0)
			(layers "F.Cu" "F.Mask" "F.Paste")
			(net "P3V3_AUX")
		)
		(pad "2" smd circle
			(at 0.40005 0 270)
			(size 0 0)
			(layers "F.Cu" "F.Mask" "F.Paste")
			(net "GND")
		)
	)
	(footprint ""
		(layer "F.Cu")
		(at 447.275712 -123.795028)
		(property "Reference" "C2884"
			(at 0 0 0)
			(layer "F.SilkS")
			(hide yes)
			(effects
				(font
					(size 1.27 1.27)
				)
			)
		)
		(property "Value" ""
			(at 0 0 0)
			(layer "F.Fab")
			(effects
				(font
					(size 1.27 1.27)
				)
			)
		)
		(duplicate_pad_numbers_are_jumpers no)
		(fp_line
			(start -0.7874 -0.4064)
			(end 0.7874 -0.4064)
			(stroke
				(width 0.1524)
				(type default)
			)
			(layer "F.SilkS")
		)
		(fp_line
			(start -0.7874 0.4064)
			(end -0.7874 -0.4064)
			(stroke
				(width 0.1524)
				(type default)
			)
			(layer "F.SilkS")
		)
		(fp_line
			(start 0.7874 -0.4064)
			(end 0.7874 0.4064)
			(stroke
				(width 0.1524)
				(type default)
			)
			(layer "F.SilkS")
		)
		(fp_line
			(start 0.7874 0.4064)
			(end -0.7874 0.4064)
			(stroke
				(width 0.1524)
				(type default)
			)
			(layer "F.SilkS")
		)
		(fp_line
			(start -0.67945 -0.305054)
			(end -0.12065 -0.305054)
			(stroke
				(width 0.1)
				(type default)
			)
			(layer "F.Fab")
		)
		(fp_line
			(start -0.67945 0.3048)
			(end -0.67945 -0.305054)
			(stroke
				(width 0.1)
				(type default)
			)
			(layer "F.Fab")
		)
		(fp_line
			(start -0.12065 -0.305054)
			(end -0.12065 -0.2794)
			(stroke
				(width 0.1)
				(type default)
			)
			(layer "F.Fab")
		)
		(fp_line
			(start -0.12065 -0.2794)
			(end 0.12065 -0.2794)
			(stroke
				(width 0.1)
				(type default)
			)
			(layer "F.Fab")
		)
		(fp_line
			(start -0.12065 0.2794)
			(end -0.12065 0.3048)
			(stroke
				(width 0.1)
				(type default)
			)
			(layer "F.Fab")
		)
		(fp_line
			(start -0.12065 0.3048)
			(end -0.67945 0.3048)
			(stroke
				(width 0.1)
				(type default)
			)
			(layer "F.Fab")
		)
		(fp_line
			(start 0.120396 0.2794)
			(end -0.12065 0.2794)
			(stroke
				(width 0.1)
				(type default)
			)
			(layer "F.Fab")
		)
		(fp_line
			(start 0.120396 0.3048)
			(end 0.120396 0.2794)
			(stroke
				(width 0.1)
				(type default)
			)
			(layer "F.Fab")
		)
		(fp_line
			(start 0.12065 -0.3048)
			(end 0.67945 -0.3048)
			(stroke
				(width 0.1)
				(type default)
			)
			(layer "F.Fab")
		)
		(fp_line
			(start 0.12065 -0.2794)
			(end 0.12065 -0.3048)
			(stroke
				(width 0.1)
				(type default)
			)
			(layer "F.Fab")
		)
		(fp_line
			(start 0.67945 -0.3048)
			(end 0.67945 0.3048)
			(stroke
				(width 0.1)
				(type default)
			)
			(layer "F.Fab")
		)
		(fp_line
			(start 0.67945 0.3048)
			(end 0.120396 0.3048)
			(stroke
				(width 0.1)
				(type default)
			)
			(layer "F.Fab")
		)
		(pad "1" smd circle
			(at -0.40005 0)
			(size 0 0)
			(layers "F.Cu" "F.Mask" "F.Paste")
			(net "HP_NIC7_EN")
		)
		(pad "2" smd circle
			(at 0.40005 0)
			(size 0 0)
			(layers "F.Cu" "F.Mask" "F.Paste")
			(net "GND")
		)
	)
	(footprint ""
		(layer "F.Cu")
		(at 238.85271 -156.288994 -90)
		(property "Reference" "PR7021"
			(at 0 0 270)
			(layer "F.SilkS")
			(hide yes)
			(effects
				(font
					(size 1.27 1.27)
				)
			)
		)
		(property "Value" ""
			(at 0 0 270)
			(layer "F.Fab")
			(effects
				(font
					(size 1.27 1.27)
				)
			)
		)
		(duplicate_pad_numbers_are_jumpers no)
		(fp_line
			(start -0.7874 0.4064)
			(end -0.7874 -0.4064)
			(stroke
				(width 0.1524)
				(type default)
			)
			(layer "F.SilkS")
		)
		(fp_line
			(start 0.7874 0.4064)
			(end -0.7874 0.4064)
			(stroke
				(width 0.1524)
				(type default)
			)
			(layer "F.SilkS")
		)
		(fp_line
			(start -0.7874 -0.4064)
			(end 0.7874 -0.4064)
			(stroke
				(width 0.1524)
				(type default)
			)
			(layer "F.SilkS")
		)
		(fp_line
			(start 0.7874 -0.4064)
			(end 0.7874 0.4064)
			(stroke
				(width 0.1524)
				(type default)
			)
			(layer "F.SilkS")
		)
		(fp_line
			(start -0.67945 0.3048)
			(end -0.67945 -0.305054)
			(stroke
				(width 0.1)
				(type default)
			)
			(layer "F.Fab")
		)
		(fp_line
			(start -0.12065 0.3048)
			(end -0.67945 0.3048)
			(stroke
				(width 0.1)
				(type default)
			)
			(layer "F.Fab")
		)
		(fp_line
			(start 0.120396 0.3048)
			(end 0.120396 0.2794)
			(stroke
				(width 0.1)
				(type default)
			)
			(layer "F.Fab")
		)
		(fp_line
			(start 0.67945 0.3048)
			(end 0.120396 0.3048)
			(stroke
				(width 0.1)
				(type default)
			)
			(layer "F.Fab")
		)
		(fp_line
			(start -0.12065 0.2794)
			(end -0.12065 0.3048)
			(stroke
				(width 0.1)
				(type default)
			)
			(layer "F.Fab")
		)
		(fp_line
			(start 0.120396 0.2794)
			(end -0.12065 0.2794)
			(stroke
				(width 0.1)
				(type default)
			)
			(layer "F.Fab")
		)
		(fp_line
			(start -0.12065 -0.2794)
			(end 0.12065 -0.2794)
			(stroke
				(width 0.1)
				(type default)
			)
			(layer "F.Fab")
		)
		(fp_line
			(start 0.12065 -0.2794)
			(end 0.12065 -0.3048)
			(stroke
				(width 0.1)
				(type default)
			)
			(layer "F.Fab")
		)
		(fp_line
			(start 0.12065 -0.3048)
			(end 0.67945 -0.3048)
			(stroke
				(width 0.1)
				(type default)
			)
			(layer "F.Fab")
		)
		(fp_line
			(start 0.67945 -0.3048)
			(end 0.67945 0.3048)
			(stroke
				(width 0.1)
				(type default)
			)
			(layer "F.Fab")
		)
		(fp_line
			(start -0.67945 -0.305054)
			(end -0.12065 -0.305054)
			(stroke
				(width 0.1)
				(type default)
			)
			(layer "F.Fab")
		)
		(fp_line
			(start -0.12065 -0.305054)
			(end -0.12065 -0.2794)
			(stroke
				(width 0.1)
				(type default)
			)
			(layer "F.Fab")
		)
		(pad "1" smd circle
			(at -0.40005 0 270)
			(size 0 0)
			(layers "F.Cu" "F.Mask" "F.Paste")
			(net "P12V_NIC4_CO_OV_FB")
		)
		(pad "2" smd circle
			(at 0.40005 0 270)
			(size 0 0)
			(layers "F.Cu" "F.Mask" "F.Paste")
			(net "P12V_NIC4_R")
		)
	)
	(footprint ""
		(layer "F.Cu")
		(at 234.982512 -29.875734)
		(property "Reference" "PU127"
			(at -3.115564 -1.472438 90)
			(unlocked yes)
			(layer "F.SilkS")
			(effects
				(font
					(size 0.7874 0.5842)
					(thickness 0.1524)
				)
			)
		)
		(property "Value" ""
			(at 0 0 0)
			(layer "F.Fab")
			(effects
				(font
					(size 1.27 1.27)
				)
			)
		)
		(duplicate_pad_numbers_are_jumpers no)
		(fp_line
			(start -1.239774 -1.495298)
			(end 1.239774 -1.495298)
			(stroke
				(width 0.1524)
				(type default)
			)
			(layer "F.SilkS")
		)
		(fp_line
			(start -1.239774 1.495298)
			(end -1.239774 -1.495298)
			(stroke
				(width 0.1524)
				(type default)
			)
			(layer "F.SilkS")
		)
		(fp_line
			(start 1.239774 -1.495298)
			(end 1.239774 1.495298)
			(stroke
				(width 0.1524)
				(type default)
			)
			(layer "F.SilkS")
		)
		(fp_line
			(start 1.239774 1.495298)
			(end -1.239774 1.495298)
			(stroke
				(width 0.1524)
				(type default)
			)
			(layer "F.SilkS")
		)
		(fp_poly
			(pts
				(xy -1.93167 -1.763014) (xy -2.649982 -1.044702) (xy -1.57226 -0.685292)
			)
			(stroke
				(width 0)
				(type default)
			)
			(fill yes)
			(layer "F.SilkS")
		)
		(fp_line
			(start -0.8001 -1.050036)
			(end 0.8001 -1.050036)
			(stroke
				(width 0.1)
				(type default)
			)
			(layer "F.Fab")
		)
		(fp_line
			(start -0.8001 1.050036)
			(end -0.8001 -1.050036)
			(stroke
				(width 0.1)
				(type default)
			)
			(layer "F.Fab")
		)
		(fp_line
			(start 0.8001 -1.050036)
			(end 0.8001 1.050036)
			(stroke
				(width 0.1)
				(type default)
			)
			(layer "F.Fab")
		)
		(fp_line
			(start 0.8001 1.050036)
			(end -0.8001 1.050036)
			(stroke
				(width 0.1)
				(type default)
			)
			(layer "F.Fab")
		)
		(fp_poly
			(pts
				(xy -2.458974 -0.508) (xy -2.458974 0.508) (xy -1.442974 0)
			)
			(stroke
				(width 0)
				(type default)
			)
			(fill yes)
			(layer "F.Fab")
		)
		(pad "1_2" smd circle
			(at -0.374904 0 90)
			(size 0 0)
			(layers "F.Cu" "F.Mask" "F.Paste")
			(net "P3V3_AUX")
		)
		(pad "3" smd rect
			(at -0.499872 0.999998)
			(size 0.254 0.7112)
			(layers "F.Cu" "F.Mask" "F.Paste")
			(net "GND")
		)
		(pad "4" smd rect
			(at 0 0.999998)
			(size 0.254 0.7112)
			(layers "F.Cu" "F.Mask" "F.Paste")
			(net "P3V3_SSD8_CO_ILIMIT")
		)
		(pad "5" smd rect
			(at 0.499872 0.999998)
			(size 0.254 0.7112)
			(layers "F.Cu" "F.Mask" "F.Paste")
			(net "P3V3_SSD8_CO_MODE")
		)
		(pad "6_7" smd circle
			(at 0.374904 0 270)
			(size 0 0)
			(layers "F.Cu" "F.Mask" "F.Paste")
			(net "P3V3_SSD8")
		)
		(pad "8" smd rect
			(at 0.499872 -0.999998)
			(size 0.254 0.7112)
			(layers "F.Cu" "F.Mask" "F.Paste")
			(net "P3V3_SSD8_CO_GATE")
		)
		(pad "9" smd rect
			(at 0 -0.999998)
			(size 0.254 0.7112)
			(layers "F.Cu" "F.Mask" "F.Paste")
			(net "P3V3_SSD8_CO_EN")
		)
		(pad "10" smd rect
			(at -0.499872 -0.999998)
			(size 0.254 0.7112)
			(layers "F.Cu" "F.Mask" "F.Paste")
			(net "P3V3_SSD8_CO_DV_DT")
		)
	)
	(footprint ""
		(layer "F.Cu")
		(at 241.02949 -211.266278 90)
		(property "Reference" "C196"
			(at 0 0 90)
			(layer "F.SilkS")
			(hide yes)
			(effects
				(font
					(size 1.27 1.27)
				)
			)
		)
		(property "Value" ""
			(at 0 0 90)
			(layer "F.Fab")
			(effects
				(font
					(size 1.27 1.27)
				)
			)
		)
		(duplicate_pad_numbers_are_jumpers no)
		(fp_line
			(start 0.7874 -0.4064)
			(end 0.7874 0.4064)
			(stroke
				(width 0.1524)
				(type default)
			)
			(layer "F.SilkS")
		)
		(fp_line
			(start -0.7874 -0.4064)
			(end 0.7874 -0.4064)
			(stroke
				(width 0.1524)
				(type default)
			)
			(layer "F.SilkS")
		)
		(fp_line
			(start 0.7874 0.4064)
			(end -0.7874 0.4064)
			(stroke
				(width 0.1524)
				(type default)
			)
			(layer "F.SilkS")
		)
		(fp_line
			(start -0.7874 0.4064)
			(end -0.7874 -0.4064)
			(stroke
				(width 0.1524)
				(type default)
			)
			(layer "F.SilkS")
		)
		(fp_line
			(start -0.12065 -0.305054)
			(end -0.12065 -0.2794)
			(stroke
				(width 0.1)
				(type default)
			)
			(layer "F.Fab")
		)
		(fp_line
			(start -0.67945 -0.305054)
			(end -0.12065 -0.305054)
			(stroke
				(width 0.1)
				(type default)
			)
			(layer "F.Fab")
		)
		(fp_line
			(start 0.67945 -0.3048)
			(end 0.67945 0.3048)
			(stroke
				(width 0.1)
				(type default)
			)
			(layer "F.Fab")
		)
		(fp_line
			(start 0.12065 -0.3048)
			(end 0.67945 -0.3048)
			(stroke
				(width 0.1)
				(type default)
			)
			(layer "F.Fab")
		)
		(fp_line
			(start 0.12065 -0.2794)
			(end 0.12065 -0.3048)
			(stroke
				(width 0.1)
				(type default)
			)
			(layer "F.Fab")
		)
		(fp_line
			(start -0.12065 -0.2794)
			(end 0.12065 -0.2794)
			(stroke
				(width 0.1)
				(type default)
			)
			(layer "F.Fab")
		)
		(fp_line
			(start 0.120396 0.2794)
			(end -0.12065 0.2794)
			(stroke
				(width 0.1)
				(type default)
			)
			(layer "F.Fab")
		)
		(fp_line
			(start -0.12065 0.2794)
			(end -0.12065 0.3048)
			(stroke
				(width 0.1)
				(type default)
			)
			(layer "F.Fab")
		)
		(fp_line
			(start 0.67945 0.3048)
			(end 0.120396 0.3048)
			(stroke
				(width 0.1)
				(type default)
			)
			(layer "F.Fab")
		)
		(fp_line
			(start 0.120396 0.3048)
			(end 0.120396 0.2794)
			(stroke
				(width 0.1)
				(type default)
			)
			(layer "F.Fab")
		)
		(fp_line
			(start -0.12065 0.3048)
			(end -0.67945 0.3048)
			(stroke
				(width 0.1)
				(type default)
			)
			(layer "F.Fab")
		)
		(fp_line
			(start -0.67945 0.3048)
			(end -0.67945 -0.305054)
			(stroke
				(width 0.1)
				(type default)
			)
			(layer "F.Fab")
		)
		(pad "1" smd circle
			(at -0.40005 0 90)
			(size 0 0)
			(layers "F.Cu" "F.Mask" "F.Paste")
			(net "P3V3_SCALED")
		)
		(pad "2" smd circle
			(at 0.40005 0 90)
			(size 0 0)
			(layers "F.Cu" "F.Mask" "F.Paste")
			(net "GND")
		)
	)
	(footprint ""
		(layer "F.Cu")
		(at 336.042 -155.702 180)
		(property "Reference" "R4801"
			(at 0 0 180)
			(layer "F.SilkS")
			(hide yes)
			(effects
				(font
					(size 1.27 1.27)
				)
			)
		)
		(property "Value" ""
			(at 0 0 180)
			(layer "F.Fab")
			(effects
				(font
					(size 1.27 1.27)
				)
			)
		)
		(duplicate_pad_numbers_are_jumpers no)
		(fp_line
			(start 0.7874 0.4064)
			(end -0.7874 0.4064)
			(stroke
				(width 0.1524)
				(type default)
			)
			(layer "F.SilkS")
		)
		(fp_line
			(start 0.7874 -0.4064)
			(end 0.7874 0.4064)
			(stroke
				(width 0.1524)
				(type default)
			)
			(layer "F.SilkS")
		)
		(fp_line
			(start -0.7874 0.4064)
			(end -0.7874 -0.4064)
			(stroke
				(width 0.1524)
				(type default)
			)
			(layer "F.SilkS")
		)
		(fp_line
			(start -0.7874 -0.4064)
			(end 0.7874 -0.4064)
			(stroke
				(width 0.1524)
				(type default)
			)
			(layer "F.SilkS")
		)
		(fp_line
			(start 0.67945 0.3048)
			(end 0.120396 0.3048)
			(stroke
				(width 0.1)
				(type default)
			)
			(layer "F.Fab")
		)
		(fp_line
			(start 0.67945 -0.3048)
			(end 0.67945 0.3048)
			(stroke
				(width 0.1)
				(type default)
			)
			(layer "F.Fab")
		)
		(fp_line
			(start 0.12065 -0.2794)
			(end 0.12065 -0.3048)
			(stroke
				(width 0.1)
				(type default)
			)
			(layer "F.Fab")
		)
		(fp_line
			(start 0.12065 -0.3048)
			(end 0.67945 -0.3048)
			(stroke
				(width 0.1)
				(type default)
			)
			(layer "F.Fab")
		)
		(fp_line
			(start 0.120396 0.3048)
			(end 0.120396 0.2794)
			(stroke
				(width 0.1)
				(type default)
			)
			(layer "F.Fab")
		)
		(fp_line
			(start 0.120396 0.2794)
			(end -0.12065 0.2794)
			(stroke
				(width 0.1)
				(type default)
			)
			(layer "F.Fab")
		)
		(fp_line
			(start -0.12065 0.3048)
			(end -0.67945 0.3048)
			(stroke
				(width 0.1)
				(type default)
			)
			(layer "F.Fab")
		)
		(fp_line
			(start -0.12065 0.2794)
			(end -0.12065 0.3048)
			(stroke
				(width 0.1)
				(type default)
			)
			(layer "F.Fab")
		)
		(fp_line
			(start -0.12065 -0.2794)
			(end 0.12065 -0.2794)
			(stroke
				(width 0.1)
				(type default)
			)
			(layer "F.Fab")
		)
		(fp_line
			(start -0.12065 -0.305054)
			(end -0.12065 -0.2794)
			(stroke
				(width 0.1)
				(type default)
			)
			(layer "F.Fab")
		)
		(fp_line
			(start -0.67945 0.3048)
			(end -0.67945 -0.305054)
			(stroke
				(width 0.1)
				(type default)
			)
			(layer "F.Fab")
		)
		(fp_line
			(start -0.67945 -0.305054)
			(end -0.12065 -0.305054)
			(stroke
				(width 0.1)
				(type default)
			)
			(layer "F.Fab")
		)
		(pad "1" smd circle
			(at -0.40005 0 180)
			(size 0 0)
			(layers "F.Cu" "F.Mask" "F.Paste")
			(net "SSD13_PEX_PWR_EN_R")
		)
		(pad "2" smd circle
			(at 0.40005 0 180)
			(size 0 0)
			(layers "F.Cu" "F.Mask" "F.Paste")
			(net "GND")
		)
	)
	(footprint ""
		(layer "F.Cu")
		(at 295.852342 -356.244906 90)
		(property "Reference" "C585"
			(at 0 0 90)
			(layer "F.SilkS")
			(hide yes)
			(effects
				(font
					(size 1.27 1.27)
				)
			)
		)
		(property "Value" ""
			(at 0 0 90)
			(layer "F.Fab")
			(effects
				(font
					(size 1.27 1.27)
				)
			)
		)
		(duplicate_pad_numbers_are_jumpers no)
		(fp_line
			(start 0.299974 -0.150114)
			(end 0.299974 0.150114)
			(stroke
				(width 0.1)
				(type default)
			)
			(layer "F.Fab")
		)
		(fp_line
			(start -0.299974 -0.150114)
			(end 0.299974 -0.150114)
			(stroke
				(width 0.1)
				(type default)
			)
			(layer "F.Fab")
		)
		(fp_line
			(start 0.299974 0.150114)
			(end -0.299974 0.150114)
			(stroke
				(width 0.1)
				(type default)
			)
			(layer "F.Fab")
		)
		(fp_line
			(start -0.299974 0.150114)
			(end -0.299974 -0.150114)
			(stroke
				(width 0.1)
				(type default)
			)
			(layer "F.Fab")
		)
		(pad "1" smd rect
			(at -0.2667 0 90)
			(size 0.3048 0.381)
			(layers "F.Cu" "F.Mask" "F.Paste")
			(net "P5E_PEX2_STN7_TX_DP<126>")
		)
		(pad "2" smd rect
			(at 0.2667 0 90)
			(size 0.3048 0.381)
			(layers "F.Cu" "F.Mask" "F.Paste")
			(net "P5E_PEX2_STN7_TX_C_DP<126>")
		)
	)
	(footprint ""
		(layer "F.Cu")
		(at 445.771524 -25.342342 -90)
		(property "Reference" "R454"
			(at 0 0 270)
			(layer "F.SilkS")
			(hide yes)
			(effects
				(font
					(size 1.27 1.27)
				)
			)
		)
		(property "Value" ""
			(at 0 0 270)
			(layer "F.Fab")
			(effects
				(font
					(size 1.27 1.27)
				)
			)
		)
		(duplicate_pad_numbers_are_jumpers no)
		(fp_line
			(start -0.7874 0.4064)
			(end -0.7874 -0.4064)
			(stroke
				(width 0.1524)
				(type default)
			)
			(layer "F.SilkS")
		)
		(fp_line
			(start 0.7874 0.4064)
			(end -0.7874 0.4064)
			(stroke
				(width 0.1524)
				(type default)
			)
			(layer "F.SilkS")
		)
		(fp_line
			(start -0.7874 -0.4064)
			(end 0.7874 -0.4064)
			(stroke
				(width 0.1524)
				(type default)
			)
			(layer "F.SilkS")
		)
		(fp_line
			(start 0.7874 -0.4064)
			(end 0.7874 0.4064)
			(stroke
				(width 0.1524)
				(type default)
			)
			(layer "F.SilkS")
		)
		(fp_line
			(start -0.67945 0.3048)
			(end -0.67945 -0.305054)
			(stroke
				(width 0.1)
				(type default)
			)
			(layer "F.Fab")
		)
		(fp_line
			(start -0.12065 0.3048)
			(end -0.67945 0.3048)
			(stroke
				(width 0.1)
				(type default)
			)
			(layer "F.Fab")
		)
		(fp_line
			(start 0.120396 0.3048)
			(end 0.120396 0.2794)
			(stroke
				(width 0.1)
				(type default)
			)
			(layer "F.Fab")
		)
		(fp_line
			(start 0.67945 0.3048)
			(end 0.120396 0.3048)
			(stroke
				(width 0.1)
				(type default)
			)
			(layer "F.Fab")
		)
		(fp_line
			(start -0.12065 0.2794)
			(end -0.12065 0.3048)
			(stroke
				(width 0.1)
				(type default)
			)
			(layer "F.Fab")
		)
		(fp_line
			(start 0.120396 0.2794)
			(end -0.12065 0.2794)
			(stroke
				(width 0.1)
				(type default)
			)
			(layer "F.Fab")
		)
		(fp_line
			(start -0.12065 -0.2794)
			(end 0.12065 -0.2794)
			(stroke
				(width 0.1)
				(type default)
			)
			(layer "F.Fab")
		)
		(fp_line
			(start 0.12065 -0.2794)
			(end 0.12065 -0.3048)
			(stroke
				(width 0.1)
				(type default)
			)
			(layer "F.Fab")
		)
		(fp_line
			(start 0.12065 -0.3048)
			(end 0.67945 -0.3048)
			(stroke
				(width 0.1)
				(type default)
			)
			(layer "F.Fab")
		)
		(fp_line
			(start 0.67945 -0.3048)
			(end 0.67945 0.3048)
			(stroke
				(width 0.1)
				(type default)
			)
			(layer "F.Fab")
		)
		(fp_line
			(start -0.67945 -0.305054)
			(end -0.12065 -0.305054)
			(stroke
				(width 0.1)
				(type default)
			)
			(layer "F.Fab")
		)
		(fp_line
			(start -0.12065 -0.305054)
			(end -0.12065 -0.2794)
			(stroke
				(width 0.1)
				(type default)
			)
			(layer "F.Fab")
		)
		(pad "1" smd circle
			(at -0.40005 0 270)
			(size 0 0)
			(layers "F.Cu" "F.Mask" "F.Paste")
			(net "P3V3_SSD15")
		)
		(pad "2" smd circle
			(at 0.40005 0 270)
			(size 0 0)
			(layers "F.Cu" "F.Mask" "F.Paste")
			(net "DUALPORT_N_SSD15")
		)
	)
	(footprint ""
		(layer "F.Cu")
		(at 58.405268 -393.16279 -90)
		(property "Reference" "C4017"
			(at 0 0 270)
			(layer "F.SilkS")
			(hide yes)
			(effects
				(font
					(size 1.27 1.27)
				)
			)
		)
		(property "Value" ""
			(at 0 0 270)
			(layer "F.Fab")
			(effects
				(font
					(size 1.27 1.27)
				)
			)
		)
		(duplicate_pad_numbers_are_jumpers no)
		(fp_line
			(start -0.7874 0.4064)
			(end -0.7874 -0.4064)
			(stroke
				(width 0.1524)
				(type default)
			)
			(layer "F.SilkS")
		)
		(fp_line
			(start 0.7874 0.4064)
			(end -0.7874 0.4064)
			(stroke
				(width 0.1524)
				(type default)
			)
			(layer "F.SilkS")
		)
		(fp_line
			(start -0.7874 -0.4064)
			(end 0.7874 -0.4064)
			(stroke
				(width 0.1524)
				(type default)
			)
			(layer "F.SilkS")
		)
		(fp_line
			(start 0.7874 -0.4064)
			(end 0.7874 0.4064)
			(stroke
				(width 0.1524)
				(type default)
			)
			(layer "F.SilkS")
		)
		(fp_line
			(start -0.67945 0.3048)
			(end -0.67945 -0.305054)
			(stroke
				(width 0.1)
				(type default)
			)
			(layer "F.Fab")
		)
		(fp_line
			(start -0.12065 0.3048)
			(end -0.67945 0.3048)
			(stroke
				(width 0.1)
				(type default)
			)
			(layer "F.Fab")
		)
		(fp_line
			(start 0.120396 0.3048)
			(end 0.120396 0.2794)
			(stroke
				(width 0.1)
				(type default)
			)
			(layer "F.Fab")
		)
		(fp_line
			(start 0.67945 0.3048)
			(end 0.120396 0.3048)
			(stroke
				(width 0.1)
				(type default)
			)
			(layer "F.Fab")
		)
		(fp_line
			(start -0.12065 0.2794)
			(end -0.12065 0.3048)
			(stroke
				(width 0.1)
				(type default)
			)
			(layer "F.Fab")
		)
		(fp_line
			(start 0.120396 0.2794)
			(end -0.12065 0.2794)
			(stroke
				(width 0.1)
				(type default)
			)
			(layer "F.Fab")
		)
		(fp_line
			(start -0.12065 -0.2794)
			(end 0.12065 -0.2794)
			(stroke
				(width 0.1)
				(type default)
			)
			(layer "F.Fab")
		)
		(fp_line
			(start 0.12065 -0.2794)
			(end 0.12065 -0.3048)
			(stroke
				(width 0.1)
				(type default)
			)
			(layer "F.Fab")
		)
		(fp_line
			(start 0.12065 -0.3048)
			(end 0.67945 -0.3048)
			(stroke
				(width 0.1)
				(type default)
			)
			(layer "F.Fab")
		)
		(fp_line
			(start 0.67945 -0.3048)
			(end 0.67945 0.3048)
			(stroke
				(width 0.1)
				(type default)
			)
			(layer "F.Fab")
		)
		(fp_line
			(start -0.67945 -0.305054)
			(end -0.12065 -0.305054)
			(stroke
				(width 0.1)
				(type default)
			)
			(layer "F.Fab")
		)
		(fp_line
			(start -0.12065 -0.305054)
			(end -0.12065 -0.2794)
			(stroke
				(width 0.1)
				(type default)
			)
			(layer "F.Fab")
		)
		(pad "1" smd circle
			(at -0.40005 0 270)
			(size 0 0)
			(layers "F.Cu" "F.Mask" "F.Paste")
			(net "GND")
		)
		(pad "2" smd circle
			(at 0.40005 0 270)
			(size 0 0)
			(layers "F.Cu" "F.Mask" "F.Paste")
			(net "GPU_THERM_OVERT_N")
		)
	)
	(footprint ""
		(layer "F.Cu")
		(at 49.667922 -18.437098)
		(property "Reference" "R1638"
			(at 0 0 0)
			(layer "F.SilkS")
			(hide yes)
			(effects
				(font
					(size 1.27 1.27)
				)
			)
		)
		(property "Value" ""
			(at 0 0 0)
			(layer "F.Fab")
			(effects
				(font
					(size 1.27 1.27)
				)
			)
		)
		(duplicate_pad_numbers_are_jumpers no)
		(fp_line
			(start -0.7874 -0.4064)
			(end 0.7874 -0.4064)
			(stroke
				(width 0.1524)
				(type default)
			)
			(layer "F.SilkS")
		)
		(fp_line
			(start -0.7874 0.4064)
			(end -0.7874 -0.4064)
			(stroke
				(width 0.1524)
				(type default)
			)
			(layer "F.SilkS")
		)
		(fp_line
			(start 0.7874 -0.4064)
			(end 0.7874 0.4064)
			(stroke
				(width 0.1524)
				(type default)
			)
			(layer "F.SilkS")
		)
		(fp_line
			(start 0.7874 0.4064)
			(end -0.7874 0.4064)
			(stroke
				(width 0.1524)
				(type default)
			)
			(layer "F.SilkS")
		)
		(fp_line
			(start -0.67945 -0.305054)
			(end -0.12065 -0.305054)
			(stroke
				(width 0.1)
				(type default)
			)
			(layer "F.Fab")
		)
		(fp_line
			(start -0.67945 0.3048)
			(end -0.67945 -0.305054)
			(stroke
				(width 0.1)
				(type default)
			)
			(layer "F.Fab")
		)
		(fp_line
			(start -0.12065 -0.305054)
			(end -0.12065 -0.2794)
			(stroke
				(width 0.1)
				(type default)
			)
			(layer "F.Fab")
		)
		(fp_line
			(start -0.12065 -0.2794)
			(end 0.12065 -0.2794)
			(stroke
				(width 0.1)
				(type default)
			)
			(layer "F.Fab")
		)
		(fp_line
			(start -0.12065 0.2794)
			(end -0.12065 0.3048)
			(stroke
				(width 0.1)
				(type default)
			)
			(layer "F.Fab")
		)
		(fp_line
			(start -0.12065 0.3048)
			(end -0.67945 0.3048)
			(stroke
				(width 0.1)
				(type default)
			)
			(layer "F.Fab")
		)
		(fp_line
			(start 0.120396 0.2794)
			(end -0.12065 0.2794)
			(stroke
				(width 0.1)
				(type default)
			)
			(layer "F.Fab")
		)
		(fp_line
			(start 0.120396 0.3048)
			(end 0.120396 0.2794)
			(stroke
				(width 0.1)
				(type default)
			)
			(layer "F.Fab")
		)
		(fp_line
			(start 0.12065 -0.3048)
			(end 0.67945 -0.3048)
			(stroke
				(width 0.1)
				(type default)
			)
			(layer "F.Fab")
		)
		(fp_line
			(start 0.12065 -0.2794)
			(end 0.12065 -0.3048)
			(stroke
				(width 0.1)
				(type default)
			)
			(layer "F.Fab")
		)
		(fp_line
			(start 0.67945 -0.3048)
			(end 0.67945 0.3048)
			(stroke
				(width 0.1)
				(type default)
			)
			(layer "F.Fab")
		)
		(fp_line
			(start 0.67945 0.3048)
			(end 0.120396 0.3048)
			(stroke
				(width 0.1)
				(type default)
			)
			(layer "F.Fab")
		)
		(pad "1" smd circle
			(at -0.40005 0)
			(size 0 0)
			(layers "F.Cu" "F.Mask" "F.Paste")
			(net "SMB_ISO_SSD1_R_SCL")
		)
		(pad "2" smd circle
			(at 0.40005 0)
			(size 0 0)
			(layers "F.Cu" "F.Mask" "F.Paste")
			(net "SMB_ISO_SSD1_SCL")
		)
	)
	(footprint ""
		(layer "F.Cu")
		(at 126.249684 -148.872702)
		(property "Reference" "PD82"
			(at -3.4544 -2.225548 0)
			(unlocked yes)
			(layer "F.SilkS")
			(effects
				(font
					(size 0.7874 0.5842)
					(thickness 0.1524)
				)
				(justify left)
			)
		)
		(property "Value" ""
			(at 0 0 0)
			(layer "F.Fab")
			(effects
				(font
					(size 1.27 1.27)
				)
			)
		)
		(duplicate_pad_numbers_are_jumpers no)
		(fp_line
			(start -3.400044 -1.459992)
			(end 4.107942 -1.459992)
			(stroke
				(width 0.1524)
				(type default)
			)
			(layer "F.SilkS")
		)
		(fp_line
			(start -3.400044 1.459992)
			(end -3.400044 -1.459992)
			(stroke
				(width 0.1524)
				(type default)
			)
			(layer "F.SilkS")
		)
		(fp_line
			(start 4.107942 -1.459992)
			(end 4.107942 1.459992)
			(stroke
				(width 0.1524)
				(type default)
			)
			(layer "F.SilkS")
		)
		(fp_line
			(start 4.107942 1.459992)
			(end -3.400044 1.459992)
			(stroke
				(width 0.1524)
				(type default)
			)
			(layer "F.SilkS")
		)
		(fp_poly
			(pts
				(xy 4.107942 -1.459992) (xy 4.107942 1.459992) (xy 3.308096 1.459992) (xy 3.308096 -1.459992)
			)
			(stroke
				(width 0)
				(type default)
			)
			(fill yes)
			(layer "F.SilkS")
		)
		(fp_line
			(start -2.29997 -1.459992)
			(end 2.29997 -1.459992)
			(stroke
				(width 0.1)
				(type default)
			)
			(layer "F.Fab")
		)
		(fp_line
			(start -2.29997 1.459992)
			(end -2.29997 -1.459992)
			(stroke
				(width 0.1)
				(type default)
			)
			(layer "F.Fab")
		)
		(fp_line
			(start 2.29997 -1.459992)
			(end 2.29997 1.459992)
			(stroke
				(width 0.1)
				(type default)
			)
			(layer "F.Fab")
		)
		(fp_line
			(start 2.29997 1.459992)
			(end -2.29997 1.459992)
			(stroke
				(width 0.1)
				(type default)
			)
			(layer "F.Fab")
		)
		(fp_text user "+"
			(at -4.7752 -0.12065 0)
			(unlocked yes)
			(layer "F.SilkS")
			(effects
				(font
					(size 1.905 1.4224)
					(thickness 0.1524)
				)
				(justify left)
			)
		)
		(fp_text user "-"
			(at 5.4102 0.29845 180)
			(unlocked yes)
			(layer "F.SilkS")
			(effects
				(font
					(size 1.905 1.4224)
					(thickness 0.1524)
				)
				(justify left)
			)
		)
		(fp_text user "+"
			(at -4.7752 -0.12065 0)
			(unlocked yes)
			(layer "F.Fab")
			(effects
				(font
					(size 1.905 1.4224)
					(thickness 0.1524)
				)
				(justify left)
			)
		)
		(fp_text user "-"
			(at 5.4102 0.29845 180)
			(unlocked yes)
			(layer "F.Fab")
			(effects
				(font
					(size 1.905 1.4224)
					(thickness 0.1524)
				)
				(justify left)
			)
		)
		(pad "A" smd rect
			(at -1.999996 0 90)
			(size 1.7018 2.5146)
			(layers "F.Cu" "F.Mask" "F.Paste")
			(net "GND")
		)
		(pad "C" smd rect
			(at 1.999996 0 90)
			(size 1.7018 2.5146)
			(layers "F.Cu" "F.Mask" "F.Paste")
			(net "P12V_NIC2_R")
		)
	)
	(footprint ""
		(layer "F.Cu")
		(at 410.91739 -390.996932 180)
		(property "Reference" "C4158"
			(at 0 0 180)
			(layer "F.SilkS")
			(hide yes)
			(effects
				(font
					(size 1.27 1.27)
				)
			)
		)
		(property "Value" ""
			(at 0 0 180)
			(layer "F.Fab")
			(effects
				(font
					(size 1.27 1.27)
				)
			)
		)
		(duplicate_pad_numbers_are_jumpers no)
		(fp_line
			(start 0.7874 0.4064)
			(end -0.7874 0.4064)
			(stroke
				(width 0.1524)
				(type default)
			)
			(layer "F.SilkS")
		)
		(fp_line
			(start 0.7874 -0.4064)
			(end 0.7874 0.4064)
			(stroke
				(width 0.1524)
				(type default)
			)
			(layer "F.SilkS")
		)
		(fp_line
			(start -0.7874 0.4064)
			(end -0.7874 -0.4064)
			(stroke
				(width 0.1524)
				(type default)
			)
			(layer "F.SilkS")
		)
		(fp_line
			(start -0.7874 -0.4064)
			(end 0.7874 -0.4064)
			(stroke
				(width 0.1524)
				(type default)
			)
			(layer "F.SilkS")
		)
		(fp_line
			(start 0.67945 0.3048)
			(end 0.120396 0.3048)
			(stroke
				(width 0.1)
				(type default)
			)
			(layer "F.Fab")
		)
		(fp_line
			(start 0.67945 -0.3048)
			(end 0.67945 0.3048)
			(stroke
				(width 0.1)
				(type default)
			)
			(layer "F.Fab")
		)
		(fp_line
			(start 0.12065 -0.2794)
			(end 0.12065 -0.3048)
			(stroke
				(width 0.1)
				(type default)
			)
			(layer "F.Fab")
		)
		(fp_line
			(start 0.12065 -0.3048)
			(end 0.67945 -0.3048)
			(stroke
				(width 0.1)
				(type default)
			)
			(layer "F.Fab")
		)
		(fp_line
			(start 0.120396 0.3048)
			(end 0.120396 0.2794)
			(stroke
				(width 0.1)
				(type default)
			)
			(layer "F.Fab")
		)
		(fp_line
			(start 0.120396 0.2794)
			(end -0.12065 0.2794)
			(stroke
				(width 0.1)
				(type default)
			)
			(layer "F.Fab")
		)
		(fp_line
			(start -0.12065 0.3048)
			(end -0.67945 0.3048)
			(stroke
				(width 0.1)
				(type default)
			)
			(layer "F.Fab")
		)
		(fp_line
			(start -0.12065 0.2794)
			(end -0.12065 0.3048)
			(stroke
				(width 0.1)
				(type default)
			)
			(layer "F.Fab")
		)
		(fp_line
			(start -0.12065 -0.2794)
			(end 0.12065 -0.2794)
			(stroke
				(width 0.1)
				(type default)
			)
			(layer "F.Fab")
		)
		(fp_line
			(start -0.12065 -0.305054)
			(end -0.12065 -0.2794)
			(stroke
				(width 0.1)
				(type default)
			)
			(layer "F.Fab")
		)
		(fp_line
			(start -0.67945 0.3048)
			(end -0.67945 -0.305054)
			(stroke
				(width 0.1)
				(type default)
			)
			(layer "F.Fab")
		)
		(fp_line
			(start -0.67945 -0.305054)
			(end -0.12065 -0.305054)
			(stroke
				(width 0.1)
				(type default)
			)
			(layer "F.Fab")
		)
		(pad "1" smd circle
			(at -0.40005 0 180)
			(size 0 0)
			(layers "F.Cu" "F.Mask" "F.Paste")
			(net "GND")
		)
		(pad "2" smd circle
			(at 0.40005 0 180)
			(size 0 0)
			(layers "F.Cu" "F.Mask" "F.Paste")
			(net "GPU_BB_RSVD_1")
		)
	)
	(footprint ""
		(layer "F.Cu")
		(at 376.795284 -35.48253)
		(property "Reference" "U394"
			(at -2.550414 0.83693 90)
			(unlocked yes)
			(layer "F.SilkS")
			(effects
				(font
					(size 0.7874 0.5842)
					(thickness 0.1524)
				)
				(justify left)
			)
		)
		(property "Value" ""
			(at 0 0 0)
			(layer "F.Fab")
			(effects
				(font
					(size 1.27 1.27)
				)
			)
		)
		(duplicate_pad_numbers_are_jumpers no)
		(fp_line
			(start -1.3462 -1.1938)
			(end -1.3462 1.1684)
			(stroke
				(width 0.1524)
				(type default)
			)
			(layer "F.SilkS")
		)
		(fp_line
			(start -1.3462 1.1938)
			(end 1.3462 1.1938)
			(stroke
				(width 0.1524)
				(type default)
			)
			(layer "F.SilkS")
		)
		(fp_line
			(start 1.3462 -1.1938)
			(end -1.3462 -1.1938)
			(stroke
				(width 0.1524)
				(type default)
			)
			(layer "F.SilkS")
		)
		(fp_line
			(start 1.3462 1.1938)
			(end 1.3462 -1.1938)
			(stroke
				(width 0.1524)
				(type default)
			)
			(layer "F.SilkS")
		)
		(fp_poly
			(pts
				(xy -1.447038 -0.760476) (xy -2.052066 -0.457962) (xy -2.052066 -1.06299)
			)
			(stroke
				(width 0)
				(type default)
			)
			(fill yes)
			(layer "F.SilkS")
		)
		(fp_line
			(start -0.674878 -1.124966)
			(end -0.674878 1.124966)
			(stroke
				(width 0.1)
				(type default)
			)
			(layer "F.Fab")
		)
		(fp_line
			(start -0.674878 1.124966)
			(end 0.674878 1.124966)
			(stroke
				(width 0.1)
				(type default)
			)
			(layer "F.Fab")
		)
		(fp_line
			(start 0.674878 -1.124966)
			(end -0.674878 -1.124966)
			(stroke
				(width 0.1)
				(type default)
			)
			(layer "F.Fab")
		)
		(fp_line
			(start 0.674878 1.124966)
			(end 0.674878 -1.124966)
			(stroke
				(width 0.1)
				(type default)
			)
			(layer "F.Fab")
		)
		(fp_poly
			(pts
				(xy -1.447038 -0.760476) (xy -2.052066 -0.457962) (xy -2.052066 -1.06299)
			)
			(stroke
				(width 0)
				(type default)
			)
			(fill yes)
			(layer "F.Fab")
		)
		(pad "1" smd rect
			(at -0.899922 -0.750062)
			(size 0.6096 0.6096)
			(layers "F.Cu" "F.Mask" "F.Paste")
			(net "PWRGD_P3V3_SSD13_R")
		)
		(pad "2" smd rect
			(at -0.899922 0 90)
			(size 0.4064 0.6096)
			(layers "F.Cu" "F.Mask" "F.Paste")
			(net "RST_SMB_SSD13_N")
		)
		(pad "3" smd rect
			(at -0.899922 0.750062)
			(size 0.6096 0.6096)
			(layers "F.Cu" "F.Mask" "F.Paste")
			(net "GND")
		)
		(pad "4" smd rect
			(at 0.899922 0.750062)
			(size 0.6096 0.6096)
			(layers "F.Cu" "F.Mask" "F.Paste")
			(net "RST_SMB_SSD13_ISO_N")
		)
		(pad "5" smd rect
			(at 0.899922 -0.750062)
			(size 0.6096 0.6096)
			(layers "F.Cu" "F.Mask" "F.Paste")
			(net "P3V3_AUX")
		)
	)
	(footprint ""
		(layer "F.Cu")
		(at 376.312684 -84.2518)
		(property "Reference" "R1747"
			(at 0 0 0)
			(layer "F.SilkS")
			(hide yes)
			(effects
				(font
					(size 1.27 1.27)
				)
			)
		)
		(property "Value" ""
			(at 0 0 0)
			(layer "F.Fab")
			(effects
				(font
					(size 1.27 1.27)
				)
			)
		)
		(duplicate_pad_numbers_are_jumpers no)
		(fp_line
			(start -0.7874 -0.4064)
			(end 0.7874 -0.4064)
			(stroke
				(width 0.1524)
				(type default)
			)
			(layer "F.SilkS")
		)
		(fp_line
			(start -0.7874 0.4064)
			(end -0.7874 -0.4064)
			(stroke
				(width 0.1524)
				(type default)
			)
			(layer "F.SilkS")
		)
		(fp_line
			(start 0.7874 -0.4064)
			(end 0.7874 0.4064)
			(stroke
				(width 0.1524)
				(type default)
			)
			(layer "F.SilkS")
		)
		(fp_line
			(start 0.7874 0.4064)
			(end -0.7874 0.4064)
			(stroke
				(width 0.1524)
				(type default)
			)
			(layer "F.SilkS")
		)
		(fp_line
			(start -0.67945 -0.305054)
			(end -0.12065 -0.305054)
			(stroke
				(width 0.1)
				(type default)
			)
			(layer "F.Fab")
		)
		(fp_line
			(start -0.67945 0.3048)
			(end -0.67945 -0.305054)
			(stroke
				(width 0.1)
				(type default)
			)
			(layer "F.Fab")
		)
		(fp_line
			(start -0.12065 -0.305054)
			(end -0.12065 -0.2794)
			(stroke
				(width 0.1)
				(type default)
			)
			(layer "F.Fab")
		)
		(fp_line
			(start -0.12065 -0.2794)
			(end 0.12065 -0.2794)
			(stroke
				(width 0.1)
				(type default)
			)
			(layer "F.Fab")
		)
		(fp_line
			(start -0.12065 0.2794)
			(end -0.12065 0.3048)
			(stroke
				(width 0.1)
				(type default)
			)
			(layer "F.Fab")
		)
		(fp_line
			(start -0.12065 0.3048)
			(end -0.67945 0.3048)
			(stroke
				(width 0.1)
				(type default)
			)
			(layer "F.Fab")
		)
		(fp_line
			(start 0.120396 0.2794)
			(end -0.12065 0.2794)
			(stroke
				(width 0.1)
				(type default)
			)
			(layer "F.Fab")
		)
		(fp_line
			(start 0.120396 0.3048)
			(end 0.120396 0.2794)
			(stroke
				(width 0.1)
				(type default)
			)
			(layer "F.Fab")
		)
		(fp_line
			(start 0.12065 -0.3048)
			(end 0.67945 -0.3048)
			(stroke
				(width 0.1)
				(type default)
			)
			(layer "F.Fab")
		)
		(fp_line
			(start 0.12065 -0.2794)
			(end 0.12065 -0.3048)
			(stroke
				(width 0.1)
				(type default)
			)
			(layer "F.Fab")
		)
		(fp_line
			(start 0.67945 -0.3048)
			(end 0.67945 0.3048)
			(stroke
				(width 0.1)
				(type default)
			)
			(layer "F.Fab")
		)
		(fp_line
			(start 0.67945 0.3048)
			(end 0.120396 0.3048)
			(stroke
				(width 0.1)
				(type default)
			)
			(layer "F.Fab")
		)
		(pad "1" smd circle
			(at -0.40005 0)
			(size 0 0)
			(layers "F.Cu" "F.Mask" "F.Paste")
			(net "P3V3_AUX")
		)
		(pad "2" smd circle
			(at 0.40005 0)
			(size 0 0)
			(layers "F.Cu" "F.Mask" "F.Paste")
			(net "SMB_BIC_I2C6_MUX_THERMAL_R_SDA")
		)
	)
	(footprint ""
		(layer "F.Cu")
		(at 251.472954 -207.097122 90)
		(property "Reference" "C2494"
			(at 0 0 90)
			(layer "F.SilkS")
			(hide yes)
			(effects
				(font
					(size 1.27 1.27)
				)
			)
		)
		(property "Value" ""
			(at 0 0 90)
			(layer "F.Fab")
			(effects
				(font
					(size 1.27 1.27)
				)
			)
		)
		(duplicate_pad_numbers_are_jumpers no)
		(fp_line
			(start 0.7874 -0.4064)
			(end 0.7874 0.4064)
			(stroke
				(width 0.1524)
				(type default)
			)
			(layer "F.SilkS")
		)
		(fp_line
			(start -0.7874 -0.4064)
			(end 0.7874 -0.4064)
			(stroke
				(width 0.1524)
				(type default)
			)
			(layer "F.SilkS")
		)
		(fp_line
			(start 0.7874 0.4064)
			(end -0.7874 0.4064)
			(stroke
				(width 0.1524)
				(type default)
			)
			(layer "F.SilkS")
		)
		(fp_line
			(start -0.7874 0.4064)
			(end -0.7874 -0.4064)
			(stroke
				(width 0.1524)
				(type default)
			)
			(layer "F.SilkS")
		)
		(fp_line
			(start -0.12065 -0.305054)
			(end -0.12065 -0.2794)
			(stroke
				(width 0.1)
				(type default)
			)
			(layer "F.Fab")
		)
		(fp_line
			(start -0.67945 -0.305054)
			(end -0.12065 -0.305054)
			(stroke
				(width 0.1)
				(type default)
			)
			(layer "F.Fab")
		)
		(fp_line
			(start 0.67945 -0.3048)
			(end 0.67945 0.3048)
			(stroke
				(width 0.1)
				(type default)
			)
			(layer "F.Fab")
		)
		(fp_line
			(start 0.12065 -0.3048)
			(end 0.67945 -0.3048)
			(stroke
				(width 0.1)
				(type default)
			)
			(layer "F.Fab")
		)
		(fp_line
			(start 0.12065 -0.2794)
			(end 0.12065 -0.3048)
			(stroke
				(width 0.1)
				(type default)
			)
			(layer "F.Fab")
		)
		(fp_line
			(start -0.12065 -0.2794)
			(end 0.12065 -0.2794)
			(stroke
				(width 0.1)
				(type default)
			)
			(layer "F.Fab")
		)
		(fp_line
			(start 0.120396 0.2794)
			(end -0.12065 0.2794)
			(stroke
				(width 0.1)
				(type default)
			)
			(layer "F.Fab")
		)
		(fp_line
			(start -0.12065 0.2794)
			(end -0.12065 0.3048)
			(stroke
				(width 0.1)
				(type default)
			)
			(layer "F.Fab")
		)
		(fp_line
			(start 0.67945 0.3048)
			(end 0.120396 0.3048)
			(stroke
				(width 0.1)
				(type default)
			)
			(layer "F.Fab")
		)
		(fp_line
			(start 0.120396 0.3048)
			(end 0.120396 0.2794)
			(stroke
				(width 0.1)
				(type default)
			)
			(layer "F.Fab")
		)
		(fp_line
			(start -0.12065 0.3048)
			(end -0.67945 0.3048)
			(stroke
				(width 0.1)
				(type default)
			)
			(layer "F.Fab")
		)
		(fp_line
			(start -0.67945 0.3048)
			(end -0.67945 -0.305054)
			(stroke
				(width 0.1)
				(type default)
			)
			(layer "F.Fab")
		)
		(pad "1" smd circle
			(at -0.40005 0 90)
			(size 0 0)
			(layers "F.Cu" "F.Mask" "F.Paste")
			(net "P3V3_AUX")
		)
		(pad "2" smd circle
			(at 0.40005 0 90)
			(size 0 0)
			(layers "F.Cu" "F.Mask" "F.Paste")
			(net "GND")
		)
	)
	(footprint ""
		(layer "F.Cu")
		(at 32.411416 -290.044632 -90)
		(property "Reference" "R4562"
			(at 0 0 270)
			(layer "F.SilkS")
			(hide yes)
			(effects
				(font
					(size 1.27 1.27)
				)
			)
		)
		(property "Value" ""
			(at 0 0 270)
			(layer "F.Fab")
			(effects
				(font
					(size 1.27 1.27)
				)
			)
		)
		(duplicate_pad_numbers_are_jumpers no)
		(fp_line
			(start -0.7874 0.4064)
			(end -0.7874 -0.4064)
			(stroke
				(width 0.1524)
				(type default)
			)
			(layer "F.SilkS")
		)
		(fp_line
			(start 0.7874 0.4064)
			(end -0.7874 0.4064)
			(stroke
				(width 0.1524)
				(type default)
			)
			(layer "F.SilkS")
		)
		(fp_line
			(start -0.7874 -0.4064)
			(end 0.7874 -0.4064)
			(stroke
				(width 0.1524)
				(type default)
			)
			(layer "F.SilkS")
		)
		(fp_line
			(start 0.7874 -0.4064)
			(end 0.7874 0.4064)
			(stroke
				(width 0.1524)
				(type default)
			)
			(layer "F.SilkS")
		)
		(fp_line
			(start -0.67945 0.3048)
			(end -0.67945 -0.305054)
			(stroke
				(width 0.1)
				(type default)
			)
			(layer "F.Fab")
		)
		(fp_line
			(start -0.12065 0.3048)
			(end -0.67945 0.3048)
			(stroke
				(width 0.1)
				(type default)
			)
			(layer "F.Fab")
		)
		(fp_line
			(start 0.120396 0.3048)
			(end 0.120396 0.2794)
			(stroke
				(width 0.1)
				(type default)
			)
			(layer "F.Fab")
		)
		(fp_line
			(start 0.67945 0.3048)
			(end 0.120396 0.3048)
			(stroke
				(width 0.1)
				(type default)
			)
			(layer "F.Fab")
		)
		(fp_line
			(start -0.12065 0.2794)
			(end -0.12065 0.3048)
			(stroke
				(width 0.1)
				(type default)
			)
			(layer "F.Fab")
		)
		(fp_line
			(start 0.120396 0.2794)
			(end -0.12065 0.2794)
			(stroke
				(width 0.1)
				(type default)
			)
			(layer "F.Fab")
		)
		(fp_line
			(start -0.12065 -0.2794)
			(end 0.12065 -0.2794)
			(stroke
				(width 0.1)
				(type default)
			)
			(layer "F.Fab")
		)
		(fp_line
			(start 0.12065 -0.2794)
			(end 0.12065 -0.3048)
			(stroke
				(width 0.1)
				(type default)
			)
			(layer "F.Fab")
		)
		(fp_line
			(start 0.12065 -0.3048)
			(end 0.67945 -0.3048)
			(stroke
				(width 0.1)
				(type default)
			)
			(layer "F.Fab")
		)
		(fp_line
			(start 0.67945 -0.3048)
			(end 0.67945 0.3048)
			(stroke
				(width 0.1)
				(type default)
			)
			(layer "F.Fab")
		)
		(fp_line
			(start -0.67945 -0.305054)
			(end -0.12065 -0.305054)
			(stroke
				(width 0.1)
				(type default)
			)
			(layer "F.Fab")
		)
		(fp_line
			(start -0.12065 -0.305054)
			(end -0.12065 -0.2794)
			(stroke
				(width 0.1)
				(type default)
			)
			(layer "F.Fab")
		)
		(pad "1" smd circle
			(at -0.40005 0 270)
			(size 0 0)
			(layers "F.Cu" "F.Mask" "F.Paste")
			(net "PCEPLL4_VDDA18_PEX0")
		)
		(pad "2" smd circle
			(at 0.40005 0 270)
			(size 0 0)
			(layers "F.Cu" "F.Mask" "F.Paste")
			(net "PCEPLL4_VDDA18_PEX0_R")
		)
	)
	(footprint ""
		(layer "F.Cu")
		(at 398.782032 -38.041072 180)
		(property "Reference" "R6120"
			(at 0 0 180)
			(layer "F.SilkS")
			(hide yes)
			(effects
				(font
					(size 1.27 1.27)
				)
			)
		)
		(property "Value" ""
			(at 0 0 180)
			(layer "F.Fab")
			(effects
				(font
					(size 1.27 1.27)
				)
			)
		)
		(duplicate_pad_numbers_are_jumpers no)
		(fp_line
			(start 0.7874 0.4064)
			(end -0.7874 0.4064)
			(stroke
				(width 0.1524)
				(type default)
			)
			(layer "F.SilkS")
		)
		(fp_line
			(start 0.7874 -0.4064)
			(end 0.7874 0.4064)
			(stroke
				(width 0.1524)
				(type default)
			)
			(layer "F.SilkS")
		)
		(fp_line
			(start -0.7874 0.4064)
			(end -0.7874 -0.4064)
			(stroke
				(width 0.1524)
				(type default)
			)
			(layer "F.SilkS")
		)
		(fp_line
			(start -0.7874 -0.4064)
			(end 0.7874 -0.4064)
			(stroke
				(width 0.1524)
				(type default)
			)
			(layer "F.SilkS")
		)
		(fp_line
			(start 0.67945 0.3048)
			(end 0.120396 0.3048)
			(stroke
				(width 0.1)
				(type default)
			)
			(layer "F.Fab")
		)
		(fp_line
			(start 0.67945 -0.3048)
			(end 0.67945 0.3048)
			(stroke
				(width 0.1)
				(type default)
			)
			(layer "F.Fab")
		)
		(fp_line
			(start 0.12065 -0.2794)
			(end 0.12065 -0.3048)
			(stroke
				(width 0.1)
				(type default)
			)
			(layer "F.Fab")
		)
		(fp_line
			(start 0.12065 -0.3048)
			(end 0.67945 -0.3048)
			(stroke
				(width 0.1)
				(type default)
			)
			(layer "F.Fab")
		)
		(fp_line
			(start 0.120396 0.3048)
			(end 0.120396 0.2794)
			(stroke
				(width 0.1)
				(type default)
			)
			(layer "F.Fab")
		)
		(fp_line
			(start 0.120396 0.2794)
			(end -0.12065 0.2794)
			(stroke
				(width 0.1)
				(type default)
			)
			(layer "F.Fab")
		)
		(fp_line
			(start -0.12065 0.3048)
			(end -0.67945 0.3048)
			(stroke
				(width 0.1)
				(type default)
			)
			(layer "F.Fab")
		)
		(fp_line
			(start -0.12065 0.2794)
			(end -0.12065 0.3048)
			(stroke
				(width 0.1)
				(type default)
			)
			(layer "F.Fab")
		)
		(fp_line
			(start -0.12065 -0.2794)
			(end 0.12065 -0.2794)
			(stroke
				(width 0.1)
				(type default)
			)
			(layer "F.Fab")
		)
		(fp_line
			(start -0.12065 -0.305054)
			(end -0.12065 -0.2794)
			(stroke
				(width 0.1)
				(type default)
			)
			(layer "F.Fab")
		)
		(fp_line
			(start -0.67945 0.3048)
			(end -0.67945 -0.305054)
			(stroke
				(width 0.1)
				(type default)
			)
			(layer "F.Fab")
		)
		(fp_line
			(start -0.67945 -0.305054)
			(end -0.12065 -0.305054)
			(stroke
				(width 0.1)
				(type default)
			)
			(layer "F.Fab")
		)
		(pad "1" smd circle
			(at -0.40005 0 180)
			(size 0 0)
			(layers "F.Cu" "F.Mask" "F.Paste")
			(net "P5V_AUX")
		)
		(pad "2" smd circle
			(at 0.40005 0 180)
			(size 0 0)
			(layers "F.Cu" "F.Mask" "F.Paste")
			(net "P3V3_SSD14_PG_G2")
		)
	)
	(footprint ""
		(layer "F.Cu")
		(at 54.875176 -63.086234)
		(property "Reference" "R5852"
			(at 0 0 0)
			(layer "F.SilkS")
			(hide yes)
			(effects
				(font
					(size 1.27 1.27)
				)
			)
		)
		(property "Value" ""
			(at 0 0 0)
			(layer "F.Fab")
			(effects
				(font
					(size 1.27 1.27)
				)
			)
		)
		(duplicate_pad_numbers_are_jumpers no)
		(fp_line
			(start -0.7874 -0.4064)
			(end 0.7874 -0.4064)
			(stroke
				(width 0.1524)
				(type default)
			)
			(layer "F.SilkS")
		)
		(fp_line
			(start -0.7874 0.4064)
			(end -0.7874 -0.4064)
			(stroke
				(width 0.1524)
				(type default)
			)
			(layer "F.SilkS")
		)
		(fp_line
			(start 0.7874 -0.4064)
			(end 0.7874 0.4064)
			(stroke
				(width 0.1524)
				(type default)
			)
			(layer "F.SilkS")
		)
		(fp_line
			(start 0.7874 0.4064)
			(end -0.7874 0.4064)
			(stroke
				(width 0.1524)
				(type default)
			)
			(layer "F.SilkS")
		)
		(fp_line
			(start -0.67945 -0.305054)
			(end -0.12065 -0.305054)
			(stroke
				(width 0.1)
				(type default)
			)
			(layer "F.Fab")
		)
		(fp_line
			(start -0.67945 0.3048)
			(end -0.67945 -0.305054)
			(stroke
				(width 0.1)
				(type default)
			)
			(layer "F.Fab")
		)
		(fp_line
			(start -0.12065 -0.305054)
			(end -0.12065 -0.2794)
			(stroke
				(width 0.1)
				(type default)
			)
			(layer "F.Fab")
		)
		(fp_line
			(start -0.12065 -0.2794)
			(end 0.12065 -0.2794)
			(stroke
				(width 0.1)
				(type default)
			)
			(layer "F.Fab")
		)
		(fp_line
			(start -0.12065 0.2794)
			(end -0.12065 0.3048)
			(stroke
				(width 0.1)
				(type default)
			)
			(layer "F.Fab")
		)
		(fp_line
			(start -0.12065 0.3048)
			(end -0.67945 0.3048)
			(stroke
				(width 0.1)
				(type default)
			)
			(layer "F.Fab")
		)
		(fp_line
			(start 0.120396 0.2794)
			(end -0.12065 0.2794)
			(stroke
				(width 0.1)
				(type default)
			)
			(layer "F.Fab")
		)
		(fp_line
			(start 0.120396 0.3048)
			(end 0.120396 0.2794)
			(stroke
				(width 0.1)
				(type default)
			)
			(layer "F.Fab")
		)
		(fp_line
			(start 0.12065 -0.3048)
			(end 0.67945 -0.3048)
			(stroke
				(width 0.1)
				(type default)
			)
			(layer "F.Fab")
		)
		(fp_line
			(start 0.12065 -0.2794)
			(end 0.12065 -0.3048)
			(stroke
				(width 0.1)
				(type default)
			)
			(layer "F.Fab")
		)
		(fp_line
			(start 0.67945 -0.3048)
			(end 0.67945 0.3048)
			(stroke
				(width 0.1)
				(type default)
			)
			(layer "F.Fab")
		)
		(fp_line
			(start 0.67945 0.3048)
			(end 0.120396 0.3048)
			(stroke
				(width 0.1)
				(type default)
			)
			(layer "F.Fab")
		)
		(pad "1" smd circle
			(at -0.40005 0)
			(size 0 0)
			(layers "F.Cu" "F.Mask" "F.Paste")
			(net "P12V_SSD2_R")
		)
		(pad "2" smd circle
			(at 0.40005 0)
			(size 0 0)
			(layers "F.Cu" "F.Mask" "F.Paste")
			(net "P12V_SSD2_PG_G1")
		)
	)
	(footprint ""
		(layer "F.Cu")
		(at 161.358072 -72.766682 90)
		(property "Reference" "PC842"
			(at 0 0 90)
			(layer "F.SilkS")
			(hide yes)
			(effects
				(font
					(size 1.27 1.27)
				)
			)
		)
		(property "Value" ""
			(at 0 0 90)
			(layer "F.Fab")
			(effects
				(font
					(size 1.27 1.27)
				)
			)
		)
		(duplicate_pad_numbers_are_jumpers no)
		(fp_line
			(start 0.7874 -0.4064)
			(end 0.7874 0.4064)
			(stroke
				(width 0.1524)
				(type default)
			)
			(layer "F.SilkS")
		)
		(fp_line
			(start -0.7874 -0.4064)
			(end 0.7874 -0.4064)
			(stroke
				(width 0.1524)
				(type default)
			)
			(layer "F.SilkS")
		)
		(fp_line
			(start 0.7874 0.4064)
			(end -0.7874 0.4064)
			(stroke
				(width 0.1524)
				(type default)
			)
			(layer "F.SilkS")
		)
		(fp_line
			(start -0.7874 0.4064)
			(end -0.7874 -0.4064)
			(stroke
				(width 0.1524)
				(type default)
			)
			(layer "F.SilkS")
		)
		(fp_line
			(start -0.12065 -0.305054)
			(end -0.12065 -0.2794)
			(stroke
				(width 0.1)
				(type default)
			)
			(layer "F.Fab")
		)
		(fp_line
			(start -0.67945 -0.305054)
			(end -0.12065 -0.305054)
			(stroke
				(width 0.1)
				(type default)
			)
			(layer "F.Fab")
		)
		(fp_line
			(start 0.67945 -0.3048)
			(end 0.67945 0.3048)
			(stroke
				(width 0.1)
				(type default)
			)
			(layer "F.Fab")
		)
		(fp_line
			(start 0.12065 -0.3048)
			(end 0.67945 -0.3048)
			(stroke
				(width 0.1)
				(type default)
			)
			(layer "F.Fab")
		)
		(fp_line
			(start 0.12065 -0.2794)
			(end 0.12065 -0.3048)
			(stroke
				(width 0.1)
				(type default)
			)
			(layer "F.Fab")
		)
		(fp_line
			(start -0.12065 -0.2794)
			(end 0.12065 -0.2794)
			(stroke
				(width 0.1)
				(type default)
			)
			(layer "F.Fab")
		)
		(fp_line
			(start 0.120396 0.2794)
			(end -0.12065 0.2794)
			(stroke
				(width 0.1)
				(type default)
			)
			(layer "F.Fab")
		)
		(fp_line
			(start -0.12065 0.2794)
			(end -0.12065 0.3048)
			(stroke
				(width 0.1)
				(type default)
			)
			(layer "F.Fab")
		)
		(fp_line
			(start 0.67945 0.3048)
			(end 0.120396 0.3048)
			(stroke
				(width 0.1)
				(type default)
			)
			(layer "F.Fab")
		)
		(fp_line
			(start 0.120396 0.3048)
			(end 0.120396 0.2794)
			(stroke
				(width 0.1)
				(type default)
			)
			(layer "F.Fab")
		)
		(fp_line
			(start -0.12065 0.3048)
			(end -0.67945 0.3048)
			(stroke
				(width 0.1)
				(type default)
			)
			(layer "F.Fab")
		)
		(fp_line
			(start -0.67945 0.3048)
			(end -0.67945 -0.305054)
			(stroke
				(width 0.1)
				(type default)
			)
			(layer "F.Fab")
		)
		(pad "1" smd circle
			(at -0.40005 0 90)
			(size 0 0)
			(layers "F.Cu" "F.Mask" "F.Paste")
			(net "P12V_SSD5_CO_MODE")
		)
		(pad "2" smd circle
			(at 0.40005 0 90)
			(size 0 0)
			(layers "F.Cu" "F.Mask" "F.Paste")
			(net "GND")
		)
	)
	(footprint ""
		(layer "F.Cu")
		(at 152.738328 -105.609898)
		(property "Reference" "C269"
			(at 0 0 0)
			(layer "F.SilkS")
			(hide yes)
			(effects
				(font
					(size 1.27 1.27)
				)
			)
		)
		(property "Value" ""
			(at 0 0 0)
			(layer "F.Fab")
			(effects
				(font
					(size 1.27 1.27)
				)
			)
		)
		(duplicate_pad_numbers_are_jumpers no)
		(fp_line
			(start -0.299974 -0.150114)
			(end 0.299974 -0.150114)
			(stroke
				(width 0.1)
				(type default)
			)
			(layer "F.Fab")
		)
		(fp_line
			(start -0.299974 0.150114)
			(end -0.299974 -0.150114)
			(stroke
				(width 0.1)
				(type default)
			)
			(layer "F.Fab")
		)
		(fp_line
			(start 0.299974 -0.150114)
			(end 0.299974 0.150114)
			(stroke
				(width 0.1)
				(type default)
			)
			(layer "F.Fab")
		)
		(fp_line
			(start 0.299974 0.150114)
			(end -0.299974 0.150114)
			(stroke
				(width 0.1)
				(type default)
			)
			(layer "F.Fab")
		)
		(pad "1" smd rect
			(at -0.2667 0)
			(size 0.3048 0.381)
			(layers "F.Cu" "F.Mask" "F.Paste")
			(net "P5E_PEX1_STN1_TX_DP<19>")
		)
		(pad "2" smd rect
			(at 0.2667 0)
			(size 0.3048 0.381)
			(layers "F.Cu" "F.Mask" "F.Paste")
			(net "P5E_PEX1_STN1_TX_C_DP<19>")
		)
	)
	(footprint ""
		(layer "F.Cu")
		(at 113.561114 -260.671564)
		(property "Reference" "PR91"
			(at 0 0 0)
			(layer "F.SilkS")
			(hide yes)
			(effects
				(font
					(size 1.27 1.27)
				)
			)
		)
		(property "Value" ""
			(at 0 0 0)
			(layer "F.Fab")
			(effects
				(font
					(size 1.27 1.27)
				)
			)
		)
		(duplicate_pad_numbers_are_jumpers no)
		(fp_line
			(start -0.7874 -0.4064)
			(end 0.7874 -0.4064)
			(stroke
				(width 0.1524)
				(type default)
			)
			(layer "F.SilkS")
		)
		(fp_line
			(start -0.7874 0.4064)
			(end -0.7874 -0.4064)
			(stroke
				(width 0.1524)
				(type default)
			)
			(layer "F.SilkS")
		)
		(fp_line
			(start 0.7874 -0.4064)
			(end 0.7874 0.4064)
			(stroke
				(width 0.1524)
				(type default)
			)
			(layer "F.SilkS")
		)
		(fp_line
			(start 0.7874 0.4064)
			(end -0.7874 0.4064)
			(stroke
				(width 0.1524)
				(type default)
			)
			(layer "F.SilkS")
		)
		(fp_line
			(start -0.67945 -0.305054)
			(end -0.12065 -0.305054)
			(stroke
				(width 0.1)
				(type default)
			)
			(layer "F.Fab")
		)
		(fp_line
			(start -0.67945 0.3048)
			(end -0.67945 -0.305054)
			(stroke
				(width 0.1)
				(type default)
			)
			(layer "F.Fab")
		)
		(fp_line
			(start -0.12065 -0.305054)
			(end -0.12065 -0.2794)
			(stroke
				(width 0.1)
				(type default)
			)
			(layer "F.Fab")
		)
		(fp_line
			(start -0.12065 -0.2794)
			(end 0.12065 -0.2794)
			(stroke
				(width 0.1)
				(type default)
			)
			(layer "F.Fab")
		)
		(fp_line
			(start -0.12065 0.2794)
			(end -0.12065 0.3048)
			(stroke
				(width 0.1)
				(type default)
			)
			(layer "F.Fab")
		)
		(fp_line
			(start -0.12065 0.3048)
			(end -0.67945 0.3048)
			(stroke
				(width 0.1)
				(type default)
			)
			(layer "F.Fab")
		)
		(fp_line
			(start 0.120396 0.2794)
			(end -0.12065 0.2794)
			(stroke
				(width 0.1)
				(type default)
			)
			(layer "F.Fab")
		)
		(fp_line
			(start 0.120396 0.3048)
			(end 0.120396 0.2794)
			(stroke
				(width 0.1)
				(type default)
			)
			(layer "F.Fab")
		)
		(fp_line
			(start 0.12065 -0.3048)
			(end 0.67945 -0.3048)
			(stroke
				(width 0.1)
				(type default)
			)
			(layer "F.Fab")
		)
		(fp_line
			(start 0.12065 -0.2794)
			(end 0.12065 -0.3048)
			(stroke
				(width 0.1)
				(type default)
			)
			(layer "F.Fab")
		)
		(fp_line
			(start 0.67945 -0.3048)
			(end 0.67945 0.3048)
			(stroke
				(width 0.1)
				(type default)
			)
			(layer "F.Fab")
		)
		(fp_line
			(start 0.67945 0.3048)
			(end 0.120396 0.3048)
			(stroke
				(width 0.1)
				(type default)
			)
			(layer "F.Fab")
		)
		(pad "1" smd circle
			(at -0.40005 0)
			(size 0 0)
			(layers "F.Cu" "F.Mask" "F.Paste")
			(net "P0V8_PEX0_VREF")
		)
		(pad "2" smd circle
			(at 0.40005 0)
			(size 0 0)
			(layers "F.Cu" "F.Mask" "F.Paste")
			(net "P0V8_PEX0_ADDR")
		)
	)
	(footprint ""
		(layer "F.Cu")
		(at 152.738328 -104.695498)
		(property "Reference" "C268"
			(at 0 0 0)
			(layer "F.SilkS")
			(hide yes)
			(effects
				(font
					(size 1.27 1.27)
				)
			)
		)
		(property "Value" ""
			(at 0 0 0)
			(layer "F.Fab")
			(effects
				(font
					(size 1.27 1.27)
				)
			)
		)
		(duplicate_pad_numbers_are_jumpers no)
		(fp_line
			(start -0.299974 -0.150114)
			(end 0.299974 -0.150114)
			(stroke
				(width 0.1)
				(type default)
			)
			(layer "F.Fab")
		)
		(fp_line
			(start -0.299974 0.150114)
			(end -0.299974 -0.150114)
			(stroke
				(width 0.1)
				(type default)
			)
			(layer "F.Fab")
		)
		(fp_line
			(start 0.299974 -0.150114)
			(end 0.299974 0.150114)
			(stroke
				(width 0.1)
				(type default)
			)
			(layer "F.Fab")
		)
		(fp_line
			(start 0.299974 0.150114)
			(end -0.299974 0.150114)
			(stroke
				(width 0.1)
				(type default)
			)
			(layer "F.Fab")
		)
		(pad "1" smd rect
			(at -0.2667 0)
			(size 0.3048 0.381)
			(layers "F.Cu" "F.Mask" "F.Paste")
			(net "P5E_PEX1_STN1_TX_DN<19>")
		)
		(pad "2" smd rect
			(at 0.2667 0)
			(size 0.3048 0.381)
			(layers "F.Cu" "F.Mask" "F.Paste")
			(net "P5E_PEX1_STN1_TX_C_DN<19>")
		)
	)
	(footprint ""
		(layer "F.Cu")
		(at 312.21934 -122.270266 180)
		(property "Reference" "C450"
			(at 0 0 180)
			(layer "F.SilkS")
			(hide yes)
			(effects
				(font
					(size 1.27 1.27)
				)
			)
		)
		(property "Value" ""
			(at 0 0 180)
			(layer "F.Fab")
			(effects
				(font
					(size 1.27 1.27)
				)
			)
		)
		(duplicate_pad_numbers_are_jumpers no)
		(fp_line
			(start 0.299974 0.150114)
			(end -0.299974 0.150114)
			(stroke
				(width 0.1)
				(type default)
			)
			(layer "F.Fab")
		)
		(fp_line
			(start 0.299974 -0.150114)
			(end 0.299974 0.150114)
			(stroke
				(width 0.1)
				(type default)
			)
			(layer "F.Fab")
		)
		(fp_line
			(start -0.299974 0.150114)
			(end -0.299974 -0.150114)
			(stroke
				(width 0.1)
				(type default)
			)
			(layer "F.Fab")
		)
		(fp_line
			(start -0.299974 -0.150114)
			(end 0.299974 -0.150114)
			(stroke
				(width 0.1)
				(type default)
			)
			(layer "F.Fab")
		)
		(pad "1" smd rect
			(at -0.2667 0 180)
			(size 0.3048 0.381)
			(layers "F.Cu" "F.Mask" "F.Paste")
			(net "P5E_PEX2_STN0_TX_DN<2>")
		)
		(pad "2" smd rect
			(at 0.2667 0 180)
			(size 0.3048 0.381)
			(layers "F.Cu" "F.Mask" "F.Paste")
			(net "P5E_PEX2_STN0_TX_C_DN<2>")
		)
	)
	(footprint ""
		(layer "F.Cu")
		(at 263.494012 -35.264852)
		(property "Reference" "R5684"
			(at 0 0 0)
			(layer "F.SilkS")
			(hide yes)
			(effects
				(font
					(size 1.27 1.27)
				)
			)
		)
		(property "Value" ""
			(at 0 0 0)
			(layer "F.Fab")
			(effects
				(font
					(size 1.27 1.27)
				)
			)
		)
		(duplicate_pad_numbers_are_jumpers no)
		(fp_line
			(start -0.7874 -0.4064)
			(end 0.7874 -0.4064)
			(stroke
				(width 0.1524)
				(type default)
			)
			(layer "F.SilkS")
		)
		(fp_line
			(start -0.7874 0.4064)
			(end -0.7874 -0.4064)
			(stroke
				(width 0.1524)
				(type default)
			)
			(layer "F.SilkS")
		)
		(fp_line
			(start 0.7874 -0.4064)
			(end 0.7874 0.4064)
			(stroke
				(width 0.1524)
				(type default)
			)
			(layer "F.SilkS")
		)
		(fp_line
			(start 0.7874 0.4064)
			(end -0.7874 0.4064)
			(stroke
				(width 0.1524)
				(type default)
			)
			(layer "F.SilkS")
		)
		(fp_line
			(start -0.67945 -0.305054)
			(end -0.12065 -0.305054)
			(stroke
				(width 0.1)
				(type default)
			)
			(layer "F.Fab")
		)
		(fp_line
			(start -0.67945 0.3048)
			(end -0.67945 -0.305054)
			(stroke
				(width 0.1)
				(type default)
			)
			(layer "F.Fab")
		)
		(fp_line
			(start -0.12065 -0.305054)
			(end -0.12065 -0.2794)
			(stroke
				(width 0.1)
				(type default)
			)
			(layer "F.Fab")
		)
		(fp_line
			(start -0.12065 -0.2794)
			(end 0.12065 -0.2794)
			(stroke
				(width 0.1)
				(type default)
			)
			(layer "F.Fab")
		)
		(fp_line
			(start -0.12065 0.2794)
			(end -0.12065 0.3048)
			(stroke
				(width 0.1)
				(type default)
			)
			(layer "F.Fab")
		)
		(fp_line
			(start -0.12065 0.3048)
			(end -0.67945 0.3048)
			(stroke
				(width 0.1)
				(type default)
			)
			(layer "F.Fab")
		)
		(fp_line
			(start 0.120396 0.2794)
			(end -0.12065 0.2794)
			(stroke
				(width 0.1)
				(type default)
			)
			(layer "F.Fab")
		)
		(fp_line
			(start 0.120396 0.3048)
			(end 0.120396 0.2794)
			(stroke
				(width 0.1)
				(type default)
			)
			(layer "F.Fab")
		)
		(fp_line
			(start 0.12065 -0.3048)
			(end 0.67945 -0.3048)
			(stroke
				(width 0.1)
				(type default)
			)
			(layer "F.Fab")
		)
		(fp_line
			(start 0.12065 -0.2794)
			(end 0.12065 -0.3048)
			(stroke
				(width 0.1)
				(type default)
			)
			(layer "F.Fab")
		)
		(fp_line
			(start 0.67945 -0.3048)
			(end 0.67945 0.3048)
			(stroke
				(width 0.1)
				(type default)
			)
			(layer "F.Fab")
		)
		(fp_line
			(start 0.67945 0.3048)
			(end 0.120396 0.3048)
			(stroke
				(width 0.1)
				(type default)
			)
			(layer "F.Fab")
		)
		(pad "1" smd circle
			(at -0.40005 0)
			(size 0 0)
			(layers "F.Cu" "F.Mask" "F.Paste")
			(net "RST_SMB_SSD9_ISO_N")
		)
		(pad "2" smd circle
			(at 0.40005 0)
			(size 0 0)
			(layers "F.Cu" "F.Mask" "F.Paste")
			(net "GND")
		)
	)
	(footprint ""
		(layer "F.Cu")
		(at 446.957196 -102.088442)
		(property "Reference" "PC346"
			(at 0 0 0)
			(layer "F.SilkS")
			(hide yes)
			(effects
				(font
					(size 1.27 1.27)
				)
			)
		)
		(property "Value" ""
			(at 0 0 0)
			(layer "F.Fab")
			(effects
				(font
					(size 1.27 1.27)
				)
			)
		)
		(duplicate_pad_numbers_are_jumpers no)
		(fp_line
			(start -0.7874 -0.4064)
			(end 0.7874 -0.4064)
			(stroke
				(width 0.1524)
				(type default)
			)
			(layer "F.SilkS")
		)
		(fp_line
			(start -0.7874 0.4064)
			(end -0.7874 -0.4064)
			(stroke
				(width 0.1524)
				(type default)
			)
			(layer "F.SilkS")
		)
		(fp_line
			(start 0.7874 -0.4064)
			(end 0.7874 0.4064)
			(stroke
				(width 0.1524)
				(type default)
			)
			(layer "F.SilkS")
		)
		(fp_line
			(start 0.7874 0.4064)
			(end -0.7874 0.4064)
			(stroke
				(width 0.1524)
				(type default)
			)
			(layer "F.SilkS")
		)
		(fp_line
			(start -0.67945 -0.305054)
			(end -0.12065 -0.305054)
			(stroke
				(width 0.1)
				(type default)
			)
			(layer "F.Fab")
		)
		(fp_line
			(start -0.67945 0.3048)
			(end -0.67945 -0.305054)
			(stroke
				(width 0.1)
				(type default)
			)
			(layer "F.Fab")
		)
		(fp_line
			(start -0.12065 -0.305054)
			(end -0.12065 -0.2794)
			(stroke
				(width 0.1)
				(type default)
			)
			(layer "F.Fab")
		)
		(fp_line
			(start -0.12065 -0.2794)
			(end 0.12065 -0.2794)
			(stroke
				(width 0.1)
				(type default)
			)
			(layer "F.Fab")
		)
		(fp_line
			(start -0.12065 0.2794)
			(end -0.12065 0.3048)
			(stroke
				(width 0.1)
				(type default)
			)
			(layer "F.Fab")
		)
		(fp_line
			(start -0.12065 0.3048)
			(end -0.67945 0.3048)
			(stroke
				(width 0.1)
				(type default)
			)
			(layer "F.Fab")
		)
		(fp_line
			(start 0.120396 0.2794)
			(end -0.12065 0.2794)
			(stroke
				(width 0.1)
				(type default)
			)
			(layer "F.Fab")
		)
		(fp_line
			(start 0.120396 0.3048)
			(end 0.120396 0.2794)
			(stroke
				(width 0.1)
				(type default)
			)
			(layer "F.Fab")
		)
		(fp_line
			(start 0.12065 -0.3048)
			(end 0.67945 -0.3048)
			(stroke
				(width 0.1)
				(type default)
			)
			(layer "F.Fab")
		)
		(fp_line
			(start 0.12065 -0.2794)
			(end 0.12065 -0.3048)
			(stroke
				(width 0.1)
				(type default)
			)
			(layer "F.Fab")
		)
		(fp_line
			(start 0.67945 -0.3048)
			(end 0.67945 0.3048)
			(stroke
				(width 0.1)
				(type default)
			)
			(layer "F.Fab")
		)
		(fp_line
			(start 0.67945 0.3048)
			(end 0.120396 0.3048)
			(stroke
				(width 0.1)
				(type default)
			)
			(layer "F.Fab")
		)
		(pad "1" smd circle
			(at -0.40005 0)
			(size 0 0)
			(layers "F.Cu" "F.Mask" "F.Paste")
			(net "P12V_NIC7_R")
		)
		(pad "2" smd circle
			(at 0.40005 0)
			(size 0 0)
			(layers "F.Cu" "F.Mask" "F.Paste")
			(net "GND")
		)
	)
	(footprint ""
		(layer "F.Cu")
		(at 358.41051 -126.995428 180)
		(property "Reference" "PC483"
			(at 0 0 180)
			(layer "F.SilkS")
			(hide yes)
			(effects
				(font
					(size 1.27 1.27)
				)
			)
		)
		(property "Value" ""
			(at 0 0 180)
			(layer "F.Fab")
			(effects
				(font
					(size 1.27 1.27)
				)
			)
		)
		(duplicate_pad_numbers_are_jumpers no)
		(fp_line
			(start 0.7874 0.4064)
			(end -0.7874 0.4064)
			(stroke
				(width 0.1524)
				(type default)
			)
			(layer "F.SilkS")
		)
		(fp_line
			(start 0.7874 -0.4064)
			(end 0.7874 0.4064)
			(stroke
				(width 0.1524)
				(type default)
			)
			(layer "F.SilkS")
		)
		(fp_line
			(start -0.7874 0.4064)
			(end -0.7874 -0.4064)
			(stroke
				(width 0.1524)
				(type default)
			)
			(layer "F.SilkS")
		)
		(fp_line
			(start -0.7874 -0.4064)
			(end 0.7874 -0.4064)
			(stroke
				(width 0.1524)
				(type default)
			)
			(layer "F.SilkS")
		)
		(fp_line
			(start 0.67945 0.3048)
			(end 0.120396 0.3048)
			(stroke
				(width 0.1)
				(type default)
			)
			(layer "F.Fab")
		)
		(fp_line
			(start 0.67945 -0.3048)
			(end 0.67945 0.3048)
			(stroke
				(width 0.1)
				(type default)
			)
			(layer "F.Fab")
		)
		(fp_line
			(start 0.12065 -0.2794)
			(end 0.12065 -0.3048)
			(stroke
				(width 0.1)
				(type default)
			)
			(layer "F.Fab")
		)
		(fp_line
			(start 0.12065 -0.3048)
			(end 0.67945 -0.3048)
			(stroke
				(width 0.1)
				(type default)
			)
			(layer "F.Fab")
		)
		(fp_line
			(start 0.120396 0.3048)
			(end 0.120396 0.2794)
			(stroke
				(width 0.1)
				(type default)
			)
			(layer "F.Fab")
		)
		(fp_line
			(start 0.120396 0.2794)
			(end -0.12065 0.2794)
			(stroke
				(width 0.1)
				(type default)
			)
			(layer "F.Fab")
		)
		(fp_line
			(start -0.12065 0.3048)
			(end -0.67945 0.3048)
			(stroke
				(width 0.1)
				(type default)
			)
			(layer "F.Fab")
		)
		(fp_line
			(start -0.12065 0.2794)
			(end -0.12065 0.3048)
			(stroke
				(width 0.1)
				(type default)
			)
			(layer "F.Fab")
		)
		(fp_line
			(start -0.12065 -0.2794)
			(end 0.12065 -0.2794)
			(stroke
				(width 0.1)
				(type default)
			)
			(layer "F.Fab")
		)
		(fp_line
			(start -0.12065 -0.305054)
			(end -0.12065 -0.2794)
			(stroke
				(width 0.1)
				(type default)
			)
			(layer "F.Fab")
		)
		(fp_line
			(start -0.67945 0.3048)
			(end -0.67945 -0.305054)
			(stroke
				(width 0.1)
				(type default)
			)
			(layer "F.Fab")
		)
		(fp_line
			(start -0.67945 -0.305054)
			(end -0.12065 -0.305054)
			(stroke
				(width 0.1)
				(type default)
			)
			(layer "F.Fab")
		)
		(pad "1" smd circle
			(at -0.40005 0 180)
			(size 0 0)
			(layers "F.Cu" "F.Mask" "F.Paste")
			(net "P3V3_NIC6_SS")
		)
		(pad "2" smd circle
			(at 0.40005 0 180)
			(size 0 0)
			(layers "F.Cu" "F.Mask" "F.Paste")
			(net "GND")
		)
	)
	(footprint ""
		(layer "F.Cu")
		(at 298.961302 -350.098614 90)
		(property "Reference" "C583"
			(at 0 0 90)
			(layer "F.SilkS")
			(hide yes)
			(effects
				(font
					(size 1.27 1.27)
				)
			)
		)
		(property "Value" ""
			(at 0 0 90)
			(layer "F.Fab")
			(effects
				(font
					(size 1.27 1.27)
				)
			)
		)
		(duplicate_pad_numbers_are_jumpers no)
		(fp_line
			(start 0.299974 -0.150114)
			(end 0.299974 0.150114)
			(stroke
				(width 0.1)
				(type default)
			)
			(layer "F.Fab")
		)
		(fp_line
			(start -0.299974 -0.150114)
			(end 0.299974 -0.150114)
			(stroke
				(width 0.1)
				(type default)
			)
			(layer "F.Fab")
		)
		(fp_line
			(start 0.299974 0.150114)
			(end -0.299974 0.150114)
			(stroke
				(width 0.1)
				(type default)
			)
			(layer "F.Fab")
		)
		(fp_line
			(start -0.299974 0.150114)
			(end -0.299974 -0.150114)
			(stroke
				(width 0.1)
				(type default)
			)
			(layer "F.Fab")
		)
		(pad "1" smd rect
			(at -0.2667 0 90)
			(size 0.3048 0.381)
			(layers "F.Cu" "F.Mask" "F.Paste")
			(net "P5E_PEX2_STN7_TX_DP<127>")
		)
		(pad "2" smd rect
			(at 0.2667 0 90)
			(size 0.3048 0.381)
			(layers "F.Cu" "F.Mask" "F.Paste")
			(net "P5E_PEX2_STN7_TX_C_DP<127>")
		)
	)
	(footprint ""
		(layer "F.Cu")
		(at 6.363716 -74.322432 180)
		(property "Reference" "C3667"
			(at 0 0 180)
			(layer "F.SilkS")
			(hide yes)
			(effects
				(font
					(size 1.27 1.27)
				)
			)
		)
		(property "Value" ""
			(at 0 0 180)
			(layer "F.Fab")
			(effects
				(font
					(size 1.27 1.27)
				)
			)
		)
		(duplicate_pad_numbers_are_jumpers no)
		(fp_line
			(start 0.7874 0.4064)
			(end -0.7874 0.4064)
			(stroke
				(width 0.1524)
				(type default)
			)
			(layer "F.SilkS")
		)
		(fp_line
			(start 0.7874 -0.4064)
			(end 0.7874 0.4064)
			(stroke
				(width 0.1524)
				(type default)
			)
			(layer "F.SilkS")
		)
		(fp_line
			(start -0.7874 0.4064)
			(end -0.7874 -0.4064)
			(stroke
				(width 0.1524)
				(type default)
			)
			(layer "F.SilkS")
		)
		(fp_line
			(start -0.7874 -0.4064)
			(end 0.7874 -0.4064)
			(stroke
				(width 0.1524)
				(type default)
			)
			(layer "F.SilkS")
		)
		(fp_line
			(start 0.67945 0.3048)
			(end 0.120396 0.3048)
			(stroke
				(width 0.1)
				(type default)
			)
			(layer "F.Fab")
		)
		(fp_line
			(start 0.67945 -0.3048)
			(end 0.67945 0.3048)
			(stroke
				(width 0.1)
				(type default)
			)
			(layer "F.Fab")
		)
		(fp_line
			(start 0.12065 -0.2794)
			(end 0.12065 -0.3048)
			(stroke
				(width 0.1)
				(type default)
			)
			(layer "F.Fab")
		)
		(fp_line
			(start 0.12065 -0.3048)
			(end 0.67945 -0.3048)
			(stroke
				(width 0.1)
				(type default)
			)
			(layer "F.Fab")
		)
		(fp_line
			(start 0.120396 0.3048)
			(end 0.120396 0.2794)
			(stroke
				(width 0.1)
				(type default)
			)
			(layer "F.Fab")
		)
		(fp_line
			(start 0.120396 0.2794)
			(end -0.12065 0.2794)
			(stroke
				(width 0.1)
				(type default)
			)
			(layer "F.Fab")
		)
		(fp_line
			(start -0.12065 0.3048)
			(end -0.67945 0.3048)
			(stroke
				(width 0.1)
				(type default)
			)
			(layer "F.Fab")
		)
		(fp_line
			(start -0.12065 0.2794)
			(end -0.12065 0.3048)
			(stroke
				(width 0.1)
				(type default)
			)
			(layer "F.Fab")
		)
		(fp_line
			(start -0.12065 -0.2794)
			(end 0.12065 -0.2794)
			(stroke
				(width 0.1)
				(type default)
			)
			(layer "F.Fab")
		)
		(fp_line
			(start -0.12065 -0.305054)
			(end -0.12065 -0.2794)
			(stroke
				(width 0.1)
				(type default)
			)
			(layer "F.Fab")
		)
		(fp_line
			(start -0.67945 0.3048)
			(end -0.67945 -0.305054)
			(stroke
				(width 0.1)
				(type default)
			)
			(layer "F.Fab")
		)
		(fp_line
			(start -0.67945 -0.305054)
			(end -0.12065 -0.305054)
			(stroke
				(width 0.1)
				(type default)
			)
			(layer "F.Fab")
		)
		(pad "1" smd circle
			(at -0.40005 0 180)
			(size 0 0)
			(layers "F.Cu" "F.Mask" "F.Paste")
			(net "P3V3_AUX")
		)
		(pad "2" smd circle
			(at 0.40005 0 180)
			(size 0 0)
			(layers "F.Cu" "F.Mask" "F.Paste")
			(net "GND")
		)
	)
	(footprint ""
		(layer "F.Cu")
		(at 140.074142 -176.913286 180)
		(property "Reference" "R1101"
			(at 0 0 180)
			(layer "F.SilkS")
			(hide yes)
			(effects
				(font
					(size 1.27 1.27)
				)
			)
		)
		(property "Value" ""
			(at 0 0 180)
			(layer "F.Fab")
			(effects
				(font
					(size 1.27 1.27)
				)
			)
		)
		(duplicate_pad_numbers_are_jumpers no)
		(fp_line
			(start 0.7874 0.4064)
			(end -0.7874 0.4064)
			(stroke
				(width 0.1524)
				(type default)
			)
			(layer "F.SilkS")
		)
		(fp_line
			(start 0.67945 0.3048)
			(end 0.120396 0.3048)
			(stroke
				(width 0.1)
				(type default)
			)
			(layer "F.Fab")
		)
		(fp_line
			(start 0.67945 -0.3048)
			(end 0.67945 0.3048)
			(stroke
				(width 0.1)
				(type default)
			)
			(layer "F.Fab")
		)
		(fp_line
			(start 0.12065 -0.2794)
			(end 0.12065 -0.3048)
			(stroke
				(width 0.1)
				(type default)
			)
			(layer "F.Fab")
		)
		(fp_line
			(start 0.12065 -0.3048)
			(end 0.67945 -0.3048)
			(stroke
				(width 0.1)
				(type default)
			)
			(layer "F.Fab")
		)
		(fp_line
			(start 0.120396 0.3048)
			(end 0.120396 0.2794)
			(stroke
				(width 0.1)
				(type default)
			)
			(layer "F.Fab")
		)
		(fp_line
			(start 0.120396 0.2794)
			(end -0.12065 0.2794)
			(stroke
				(width 0.1)
				(type default)
			)
			(layer "F.Fab")
		)
		(fp_line
			(start -0.12065 0.3048)
			(end -0.67945 0.3048)
			(stroke
				(width 0.1)
				(type default)
			)
			(layer "F.Fab")
		)
		(fp_line
			(start -0.12065 0.2794)
			(end -0.12065 0.3048)
			(stroke
				(width 0.1)
				(type default)
			)
			(layer "F.Fab")
		)
		(fp_line
			(start -0.12065 -0.2794)
			(end 0.12065 -0.2794)
			(stroke
				(width 0.1)
				(type default)
			)
			(layer "F.Fab")
		)
		(fp_line
			(start -0.12065 -0.305054)
			(end -0.12065 -0.2794)
			(stroke
				(width 0.1)
				(type default)
			)
			(layer "F.Fab")
		)
		(fp_line
			(start -0.67945 0.3048)
			(end -0.67945 -0.305054)
			(stroke
				(width 0.1)
				(type default)
			)
			(layer "F.Fab")
		)
		(fp_line
			(start -0.67945 -0.305054)
			(end -0.12065 -0.305054)
			(stroke
				(width 0.1)
				(type default)
			)
			(layer "F.Fab")
		)
		(pad "1" smd circle
			(at -0.40005 0 180)
			(size 0 0)
			(layers "F.Cu" "F.Mask" "F.Paste")
			(net "CLK_100M_DB2000QL_NIC3_R_DN")
		)
		(pad "2" smd circle
			(at 0.40005 0 180)
			(size 0 0)
			(layers "F.Cu" "F.Mask" "F.Paste")
			(net "CLK_100M_DB2000QL_NIC3_DN")
		)
	)
	(footprint ""
		(layer "F.Cu")
		(at 168.065196 -5.999988 90)
		(property "Reference" "H52"
			(at 5.34289 -4.22529 0)
			(unlocked yes)
			(layer "F.SilkS")
			(effects
				(font
					(size 0.7874 0.5842)
					(thickness 0.1524)
				)
				(justify left)
			)
		)
		(property "Value" ""
			(at 0 0 90)
			(layer "F.Fab")
			(effects
				(font
					(size 1.27 1.27)
				)
			)
		)
		(duplicate_pad_numbers_are_jumpers no)
		(pad "1" thru_hole circle
			(at 0 0 90)
			(size 10.0076 10.0076)
			(drill 5.6134)
			(layers "*.Cu" "*.Mask")
			(remove_unused_layers no)
			(net "GND")
			(clearance -1.9431)
		)
	)
	(footprint ""
		(layer "F.Cu")
		(at 114.582194 -38.041072 180)
		(property "Reference" "R6060"
			(at 0 0 180)
			(layer "F.SilkS")
			(hide yes)
			(effects
				(font
					(size 1.27 1.27)
				)
			)
		)
		(property "Value" ""
			(at 0 0 180)
			(layer "F.Fab")
			(effects
				(font
					(size 1.27 1.27)
				)
			)
		)
		(duplicate_pad_numbers_are_jumpers no)
		(fp_line
			(start 0.7874 0.4064)
			(end -0.7874 0.4064)
			(stroke
				(width 0.1524)
				(type default)
			)
			(layer "F.SilkS")
		)
		(fp_line
			(start 0.7874 -0.4064)
			(end 0.7874 0.4064)
			(stroke
				(width 0.1524)
				(type default)
			)
			(layer "F.SilkS")
		)
		(fp_line
			(start -0.7874 0.4064)
			(end -0.7874 -0.4064)
			(stroke
				(width 0.1524)
				(type default)
			)
			(layer "F.SilkS")
		)
		(fp_line
			(start -0.7874 -0.4064)
			(end 0.7874 -0.4064)
			(stroke
				(width 0.1524)
				(type default)
			)
			(layer "F.SilkS")
		)
		(fp_line
			(start 0.67945 0.3048)
			(end 0.120396 0.3048)
			(stroke
				(width 0.1)
				(type default)
			)
			(layer "F.Fab")
		)
		(fp_line
			(start 0.67945 -0.3048)
			(end 0.67945 0.3048)
			(stroke
				(width 0.1)
				(type default)
			)
			(layer "F.Fab")
		)
		(fp_line
			(start 0.12065 -0.2794)
			(end 0.12065 -0.3048)
			(stroke
				(width 0.1)
				(type default)
			)
			(layer "F.Fab")
		)
		(fp_line
			(start 0.12065 -0.3048)
			(end 0.67945 -0.3048)
			(stroke
				(width 0.1)
				(type default)
			)
			(layer "F.Fab")
		)
		(fp_line
			(start 0.120396 0.3048)
			(end 0.120396 0.2794)
			(stroke
				(width 0.1)
				(type default)
			)
			(layer "F.Fab")
		)
		(fp_line
			(start 0.120396 0.2794)
			(end -0.12065 0.2794)
			(stroke
				(width 0.1)
				(type default)
			)
			(layer "F.Fab")
		)
		(fp_line
			(start -0.12065 0.3048)
			(end -0.67945 0.3048)
			(stroke
				(width 0.1)
				(type default)
			)
			(layer "F.Fab")
		)
		(fp_line
			(start -0.12065 0.2794)
			(end -0.12065 0.3048)
			(stroke
				(width 0.1)
				(type default)
			)
			(layer "F.Fab")
		)
		(fp_line
			(start -0.12065 -0.2794)
			(end 0.12065 -0.2794)
			(stroke
				(width 0.1)
				(type default)
			)
			(layer "F.Fab")
		)
		(fp_line
			(start -0.12065 -0.305054)
			(end -0.12065 -0.2794)
			(stroke
				(width 0.1)
				(type default)
			)
			(layer "F.Fab")
		)
		(fp_line
			(start -0.67945 0.3048)
			(end -0.67945 -0.305054)
			(stroke
				(width 0.1)
				(type default)
			)
			(layer "F.Fab")
		)
		(fp_line
			(start -0.67945 -0.305054)
			(end -0.12065 -0.305054)
			(stroke
				(width 0.1)
				(type default)
			)
			(layer "F.Fab")
		)
		(pad "1" smd circle
			(at -0.40005 0 180)
			(size 0 0)
			(layers "F.Cu" "F.Mask" "F.Paste")
			(net "P5V_AUX")
		)
		(pad "2" smd circle
			(at 0.40005 0 180)
			(size 0 0)
			(layers "F.Cu" "F.Mask" "F.Paste")
			(net "P3V3_SSD4_PG_G2")
		)
	)
	(footprint ""
		(layer "F.Cu")
		(at 230.952294 -182.61838)
		(property "Reference" "R5493"
			(at 0 0 0)
			(layer "F.SilkS")
			(hide yes)
			(effects
				(font
					(size 1.27 1.27)
				)
			)
		)
		(property "Value" ""
			(at 0 0 0)
			(layer "F.Fab")
			(effects
				(font
					(size 1.27 1.27)
				)
			)
		)
		(duplicate_pad_numbers_are_jumpers no)
		(fp_line
			(start -0.7874 -0.4064)
			(end 0.7874 -0.4064)
			(stroke
				(width 0.1524)
				(type default)
			)
			(layer "F.SilkS")
		)
		(fp_line
			(start -0.7874 0.4064)
			(end -0.7874 -0.4064)
			(stroke
				(width 0.1524)
				(type default)
			)
			(layer "F.SilkS")
		)
		(fp_line
			(start 0.7874 -0.4064)
			(end 0.7874 0.4064)
			(stroke
				(width 0.1524)
				(type default)
			)
			(layer "F.SilkS")
		)
		(fp_line
			(start 0.7874 0.4064)
			(end -0.7874 0.4064)
			(stroke
				(width 0.1524)
				(type default)
			)
			(layer "F.SilkS")
		)
		(fp_line
			(start -0.67945 -0.305054)
			(end -0.12065 -0.305054)
			(stroke
				(width 0.1)
				(type default)
			)
			(layer "F.Fab")
		)
		(fp_line
			(start -0.67945 0.3048)
			(end -0.67945 -0.305054)
			(stroke
				(width 0.1)
				(type default)
			)
			(layer "F.Fab")
		)
		(fp_line
			(start -0.12065 -0.305054)
			(end -0.12065 -0.2794)
			(stroke
				(width 0.1)
				(type default)
			)
			(layer "F.Fab")
		)
		(fp_line
			(start -0.12065 -0.2794)
			(end 0.12065 -0.2794)
			(stroke
				(width 0.1)
				(type default)
			)
			(layer "F.Fab")
		)
		(fp_line
			(start -0.12065 0.2794)
			(end -0.12065 0.3048)
			(stroke
				(width 0.1)
				(type default)
			)
			(layer "F.Fab")
		)
		(fp_line
			(start -0.12065 0.3048)
			(end -0.67945 0.3048)
			(stroke
				(width 0.1)
				(type default)
			)
			(layer "F.Fab")
		)
		(fp_line
			(start 0.120396 0.2794)
			(end -0.12065 0.2794)
			(stroke
				(width 0.1)
				(type default)
			)
			(layer "F.Fab")
		)
		(fp_line
			(start 0.120396 0.3048)
			(end 0.120396 0.2794)
			(stroke
				(width 0.1)
				(type default)
			)
			(layer "F.Fab")
		)
		(fp_line
			(start 0.12065 -0.3048)
			(end 0.67945 -0.3048)
			(stroke
				(width 0.1)
				(type default)
			)
			(layer "F.Fab")
		)
		(fp_line
			(start 0.12065 -0.2794)
			(end 0.12065 -0.3048)
			(stroke
				(width 0.1)
				(type default)
			)
			(layer "F.Fab")
		)
		(fp_line
			(start 0.67945 -0.3048)
			(end 0.67945 0.3048)
			(stroke
				(width 0.1)
				(type default)
			)
			(layer "F.Fab")
		)
		(fp_line
			(start 0.67945 0.3048)
			(end 0.120396 0.3048)
			(stroke
				(width 0.1)
				(type default)
			)
			(layer "F.Fab")
		)
		(pad "1" smd circle
			(at -0.40005 0)
			(size 0 0)
			(layers "F.Cu" "F.Mask" "F.Paste")
			(net "RST_BJT_Q15_C")
		)
		(pad "2" smd circle
			(at 0.40005 0)
			(size 0 0)
			(layers "F.Cu" "F.Mask" "F.Paste")
			(net "P3V3_AUX")
		)
	)
	(footprint ""
		(layer "F.Cu")
		(at 43.622722 -22.867366 90)
		(property "Reference" "C3884"
			(at 0 0 90)
			(layer "F.SilkS")
			(hide yes)
			(effects
				(font
					(size 1.27 1.27)
				)
			)
		)
		(property "Value" ""
			(at 0 0 90)
			(layer "F.Fab")
			(effects
				(font
					(size 1.27 1.27)
				)
			)
		)
		(duplicate_pad_numbers_are_jumpers no)
		(fp_line
			(start 0.7874 -0.4064)
			(end 0.7874 0.4064)
			(stroke
				(width 0.1524)
				(type default)
			)
			(layer "F.SilkS")
		)
		(fp_line
			(start -0.7874 -0.4064)
			(end 0.7874 -0.4064)
			(stroke
				(width 0.1524)
				(type default)
			)
			(layer "F.SilkS")
		)
		(fp_line
			(start 0.7874 0.4064)
			(end -0.7874 0.4064)
			(stroke
				(width 0.1524)
				(type default)
			)
			(layer "F.SilkS")
		)
		(fp_line
			(start -0.7874 0.4064)
			(end -0.7874 -0.4064)
			(stroke
				(width 0.1524)
				(type default)
			)
			(layer "F.SilkS")
		)
		(fp_line
			(start -0.12065 -0.305054)
			(end -0.12065 -0.2794)
			(stroke
				(width 0.1)
				(type default)
			)
			(layer "F.Fab")
		)
		(fp_line
			(start -0.67945 -0.305054)
			(end -0.12065 -0.305054)
			(stroke
				(width 0.1)
				(type default)
			)
			(layer "F.Fab")
		)
		(fp_line
			(start 0.67945 -0.3048)
			(end 0.67945 0.3048)
			(stroke
				(width 0.1)
				(type default)
			)
			(layer "F.Fab")
		)
		(fp_line
			(start 0.12065 -0.3048)
			(end 0.67945 -0.3048)
			(stroke
				(width 0.1)
				(type default)
			)
			(layer "F.Fab")
		)
		(fp_line
			(start 0.12065 -0.2794)
			(end 0.12065 -0.3048)
			(stroke
				(width 0.1)
				(type default)
			)
			(layer "F.Fab")
		)
		(fp_line
			(start -0.12065 -0.2794)
			(end 0.12065 -0.2794)
			(stroke
				(width 0.1)
				(type default)
			)
			(layer "F.Fab")
		)
		(fp_line
			(start 0.120396 0.2794)
			(end -0.12065 0.2794)
			(stroke
				(width 0.1)
				(type default)
			)
			(layer "F.Fab")
		)
		(fp_line
			(start -0.12065 0.2794)
			(end -0.12065 0.3048)
			(stroke
				(width 0.1)
				(type default)
			)
			(layer "F.Fab")
		)
		(fp_line
			(start 0.67945 0.3048)
			(end 0.120396 0.3048)
			(stroke
				(width 0.1)
				(type default)
			)
			(layer "F.Fab")
		)
		(fp_line
			(start 0.120396 0.3048)
			(end 0.120396 0.2794)
			(stroke
				(width 0.1)
				(type default)
			)
			(layer "F.Fab")
		)
		(fp_line
			(start -0.12065 0.3048)
			(end -0.67945 0.3048)
			(stroke
				(width 0.1)
				(type default)
			)
			(layer "F.Fab")
		)
		(fp_line
			(start -0.67945 0.3048)
			(end -0.67945 -0.305054)
			(stroke
				(width 0.1)
				(type default)
			)
			(layer "F.Fab")
		)
		(pad "1" smd circle
			(at -0.40005 0 90)
			(size 0 0)
			(layers "F.Cu" "F.Mask" "F.Paste")
			(net "P12V_SSD1")
		)
		(pad "2" smd circle
			(at 0.40005 0 90)
			(size 0 0)
			(layers "F.Cu" "F.Mask" "F.Paste")
			(net "GND")
		)
	)
	(footprint ""
		(layer "F.Cu")
		(at 200.675748 -36.915598 -90)
		(property "Reference" "R5562"
			(at 0 0 270)
			(layer "F.SilkS")
			(hide yes)
			(effects
				(font
					(size 1.27 1.27)
				)
			)
		)
		(property "Value" ""
			(at 0 0 270)
			(layer "F.Fab")
			(effects
				(font
					(size 1.27 1.27)
				)
			)
		)
		(duplicate_pad_numbers_are_jumpers no)
		(fp_line
			(start -0.7874 0.4064)
			(end -0.7874 -0.4064)
			(stroke
				(width 0.1524)
				(type default)
			)
			(layer "F.SilkS")
		)
		(fp_line
			(start 0.7874 0.4064)
			(end -0.7874 0.4064)
			(stroke
				(width 0.1524)
				(type default)
			)
			(layer "F.SilkS")
		)
		(fp_line
			(start -0.7874 -0.4064)
			(end 0.7874 -0.4064)
			(stroke
				(width 0.1524)
				(type default)
			)
			(layer "F.SilkS")
		)
		(fp_line
			(start 0.7874 -0.4064)
			(end 0.7874 0.4064)
			(stroke
				(width 0.1524)
				(type default)
			)
			(layer "F.SilkS")
		)
		(fp_line
			(start -0.67945 0.3048)
			(end -0.67945 -0.305054)
			(stroke
				(width 0.1)
				(type default)
			)
			(layer "F.Fab")
		)
		(fp_line
			(start -0.12065 0.3048)
			(end -0.67945 0.3048)
			(stroke
				(width 0.1)
				(type default)
			)
			(layer "F.Fab")
		)
		(fp_line
			(start 0.120396 0.3048)
			(end 0.120396 0.2794)
			(stroke
				(width 0.1)
				(type default)
			)
			(layer "F.Fab")
		)
		(fp_line
			(start 0.67945 0.3048)
			(end 0.120396 0.3048)
			(stroke
				(width 0.1)
				(type default)
			)
			(layer "F.Fab")
		)
		(fp_line
			(start -0.12065 0.2794)
			(end -0.12065 0.3048)
			(stroke
				(width 0.1)
				(type default)
			)
			(layer "F.Fab")
		)
		(fp_line
			(start 0.120396 0.2794)
			(end -0.12065 0.2794)
			(stroke
				(width 0.1)
				(type default)
			)
			(layer "F.Fab")
		)
		(fp_line
			(start -0.12065 -0.2794)
			(end 0.12065 -0.2794)
			(stroke
				(width 0.1)
				(type default)
			)
			(layer "F.Fab")
		)
		(fp_line
			(start 0.12065 -0.2794)
			(end 0.12065 -0.3048)
			(stroke
				(width 0.1)
				(type default)
			)
			(layer "F.Fab")
		)
		(fp_line
			(start 0.12065 -0.3048)
			(end 0.67945 -0.3048)
			(stroke
				(width 0.1)
				(type default)
			)
			(layer "F.Fab")
		)
		(fp_line
			(start 0.67945 -0.3048)
			(end 0.67945 0.3048)
			(stroke
				(width 0.1)
				(type default)
			)
			(layer "F.Fab")
		)
		(fp_line
			(start -0.67945 -0.305054)
			(end -0.12065 -0.305054)
			(stroke
				(width 0.1)
				(type default)
			)
			(layer "F.Fab")
		)
		(fp_line
			(start -0.12065 -0.305054)
			(end -0.12065 -0.2794)
			(stroke
				(width 0.1)
				(type default)
			)
			(layer "F.Fab")
		)
		(pad "1" smd circle
			(at -0.40005 0 270)
			(size 0 0)
			(layers "F.Cu" "F.Mask" "F.Paste")
			(net "PRSNT_SSD7_R1_N")
		)
		(pad "2" smd circle
			(at 0.40005 0 270)
			(size 0 0)
			(layers "F.Cu" "F.Mask" "F.Paste")
			(net "PRSNT_SSD7_R_N")
		)
	)
	(footprint ""
		(layer "F.Cu")
		(at 378.172218 -32.848042 90)
		(property "Reference" "PC965"
			(at 0 0 90)
			(layer "F.SilkS")
			(hide yes)
			(effects
				(font
					(size 1.27 1.27)
				)
			)
		)
		(property "Value" ""
			(at 0 0 90)
			(layer "F.Fab")
			(effects
				(font
					(size 1.27 1.27)
				)
			)
		)
		(duplicate_pad_numbers_are_jumpers no)
		(fp_line
			(start 0.7874 -0.4064)
			(end 0.7874 0.4064)
			(stroke
				(width 0.1524)
				(type default)
			)
			(layer "F.SilkS")
		)
		(fp_line
			(start -0.7874 -0.4064)
			(end 0.7874 -0.4064)
			(stroke
				(width 0.1524)
				(type default)
			)
			(layer "F.SilkS")
		)
		(fp_line
			(start 0.7874 0.4064)
			(end -0.7874 0.4064)
			(stroke
				(width 0.1524)
				(type default)
			)
			(layer "F.SilkS")
		)
		(fp_line
			(start -0.7874 0.4064)
			(end -0.7874 -0.4064)
			(stroke
				(width 0.1524)
				(type default)
			)
			(layer "F.SilkS")
		)
		(fp_line
			(start -0.12065 -0.305054)
			(end -0.12065 -0.2794)
			(stroke
				(width 0.1)
				(type default)
			)
			(layer "F.Fab")
		)
		(fp_line
			(start -0.67945 -0.305054)
			(end -0.12065 -0.305054)
			(stroke
				(width 0.1)
				(type default)
			)
			(layer "F.Fab")
		)
		(fp_line
			(start 0.67945 -0.3048)
			(end 0.67945 0.3048)
			(stroke
				(width 0.1)
				(type default)
			)
			(layer "F.Fab")
		)
		(fp_line
			(start 0.12065 -0.3048)
			(end 0.67945 -0.3048)
			(stroke
				(width 0.1)
				(type default)
			)
			(layer "F.Fab")
		)
		(fp_line
			(start 0.12065 -0.2794)
			(end 0.12065 -0.3048)
			(stroke
				(width 0.1)
				(type default)
			)
			(layer "F.Fab")
		)
		(fp_line
			(start -0.12065 -0.2794)
			(end 0.12065 -0.2794)
			(stroke
				(width 0.1)
				(type default)
			)
			(layer "F.Fab")
		)
		(fp_line
			(start 0.120396 0.2794)
			(end -0.12065 0.2794)
			(stroke
				(width 0.1)
				(type default)
			)
			(layer "F.Fab")
		)
		(fp_line
			(start -0.12065 0.2794)
			(end -0.12065 0.3048)
			(stroke
				(width 0.1)
				(type default)
			)
			(layer "F.Fab")
		)
		(fp_line
			(start 0.67945 0.3048)
			(end 0.120396 0.3048)
			(stroke
				(width 0.1)
				(type default)
			)
			(layer "F.Fab")
		)
		(fp_line
			(start 0.120396 0.3048)
			(end 0.120396 0.2794)
			(stroke
				(width 0.1)
				(type default)
			)
			(layer "F.Fab")
		)
		(fp_line
			(start -0.12065 0.3048)
			(end -0.67945 0.3048)
			(stroke
				(width 0.1)
				(type default)
			)
			(layer "F.Fab")
		)
		(fp_line
			(start -0.67945 0.3048)
			(end -0.67945 -0.305054)
			(stroke
				(width 0.1)
				(type default)
			)
			(layer "F.Fab")
		)
		(pad "1" smd circle
			(at -0.40005 0 90)
			(size 0 0)
			(layers "F.Cu" "F.Mask" "F.Paste")
			(net "P3V3_SSD13_CO_GATE")
		)
		(pad "2" smd circle
			(at 0.40005 0 90)
			(size 0 0)
			(layers "F.Cu" "F.Mask" "F.Paste")
			(net "GND")
		)
	)
	(footprint ""
		(layer "F.Cu")
		(at 265.686286 -252.356874 -90)
		(property "Reference" "R1353"
			(at 0 0 270)
			(layer "F.SilkS")
			(hide yes)
			(effects
				(font
					(size 1.27 1.27)
				)
			)
		)
		(property "Value" ""
			(at 0 0 270)
			(layer "F.Fab")
			(effects
				(font
					(size 1.27 1.27)
				)
			)
		)
		(duplicate_pad_numbers_are_jumpers no)
		(fp_line
			(start -0.7874 0.4064)
			(end -0.7874 -0.4064)
			(stroke
				(width 0.1524)
				(type default)
			)
			(layer "F.SilkS")
		)
		(fp_line
			(start 0.7874 0.4064)
			(end -0.7874 0.4064)
			(stroke
				(width 0.1524)
				(type default)
			)
			(layer "F.SilkS")
		)
		(fp_line
			(start -0.7874 -0.4064)
			(end 0.7874 -0.4064)
			(stroke
				(width 0.1524)
				(type default)
			)
			(layer "F.SilkS")
		)
		(fp_line
			(start 0.7874 -0.4064)
			(end 0.7874 0.4064)
			(stroke
				(width 0.1524)
				(type default)
			)
			(layer "F.SilkS")
		)
		(fp_line
			(start -0.67945 0.3048)
			(end -0.67945 -0.305054)
			(stroke
				(width 0.1)
				(type default)
			)
			(layer "F.Fab")
		)
		(fp_line
			(start -0.12065 0.3048)
			(end -0.67945 0.3048)
			(stroke
				(width 0.1)
				(type default)
			)
			(layer "F.Fab")
		)
		(fp_line
			(start 0.120396 0.3048)
			(end 0.120396 0.2794)
			(stroke
				(width 0.1)
				(type default)
			)
			(layer "F.Fab")
		)
		(fp_line
			(start 0.67945 0.3048)
			(end 0.120396 0.3048)
			(stroke
				(width 0.1)
				(type default)
			)
			(layer "F.Fab")
		)
		(fp_line
			(start -0.12065 0.2794)
			(end -0.12065 0.3048)
			(stroke
				(width 0.1)
				(type default)
			)
			(layer "F.Fab")
		)
		(fp_line
			(start 0.120396 0.2794)
			(end -0.12065 0.2794)
			(stroke
				(width 0.1)
				(type default)
			)
			(layer "F.Fab")
		)
		(fp_line
			(start -0.12065 -0.2794)
			(end 0.12065 -0.2794)
			(stroke
				(width 0.1)
				(type default)
			)
			(layer "F.Fab")
		)
		(fp_line
			(start 0.12065 -0.2794)
			(end 0.12065 -0.3048)
			(stroke
				(width 0.1)
				(type default)
			)
			(layer "F.Fab")
		)
		(fp_line
			(start 0.12065 -0.3048)
			(end 0.67945 -0.3048)
			(stroke
				(width 0.1)
				(type default)
			)
			(layer "F.Fab")
		)
		(fp_line
			(start 0.67945 -0.3048)
			(end 0.67945 0.3048)
			(stroke
				(width 0.1)
				(type default)
			)
			(layer "F.Fab")
		)
		(fp_line
			(start -0.67945 -0.305054)
			(end -0.12065 -0.305054)
			(stroke
				(width 0.1)
				(type default)
			)
			(layer "F.Fab")
		)
		(fp_line
			(start -0.12065 -0.305054)
			(end -0.12065 -0.2794)
			(stroke
				(width 0.1)
				(type default)
			)
			(layer "F.Fab")
		)
		(pad "1" smd circle
			(at -0.40005 0 270)
			(size 0 0)
			(layers "F.Cu" "F.Mask" "F.Paste")
			(net "GND")
		)
		(pad "2" smd circle
			(at 0.40005 0 270)
			(size 0 0)
			(layers "F.Cu" "F.Mask" "F.Paste")
			(net "PEX2_DBG_MODE2")
		)
	)
	(footprint ""
		(layer "F.Cu")
		(at 446.131188 -415.621216 90)
		(property "Reference" "R5605"
			(at 0 0 90)
			(layer "F.SilkS")
			(hide yes)
			(effects
				(font
					(size 1.27 1.27)
				)
			)
		)
		(property "Value" ""
			(at 0 0 90)
			(layer "F.Fab")
			(effects
				(font
					(size 1.27 1.27)
				)
			)
		)
		(duplicate_pad_numbers_are_jumpers no)
		(fp_line
			(start 0.7874 -0.4064)
			(end 0.7874 0.4064)
			(stroke
				(width 0.1524)
				(type default)
			)
			(layer "F.SilkS")
		)
		(fp_line
			(start -0.7874 -0.4064)
			(end 0.7874 -0.4064)
			(stroke
				(width 0.1524)
				(type default)
			)
			(layer "F.SilkS")
		)
		(fp_line
			(start 0.7874 0.4064)
			(end -0.7874 0.4064)
			(stroke
				(width 0.1524)
				(type default)
			)
			(layer "F.SilkS")
		)
		(fp_line
			(start -0.7874 0.4064)
			(end -0.7874 -0.4064)
			(stroke
				(width 0.1524)
				(type default)
			)
			(layer "F.SilkS")
		)
		(fp_line
			(start -0.12065 -0.305054)
			(end -0.12065 -0.2794)
			(stroke
				(width 0.1)
				(type default)
			)
			(layer "F.Fab")
		)
		(fp_line
			(start -0.67945 -0.305054)
			(end -0.12065 -0.305054)
			(stroke
				(width 0.1)
				(type default)
			)
			(layer "F.Fab")
		)
		(fp_line
			(start 0.67945 -0.3048)
			(end 0.67945 0.3048)
			(stroke
				(width 0.1)
				(type default)
			)
			(layer "F.Fab")
		)
		(fp_line
			(start 0.12065 -0.3048)
			(end 0.67945 -0.3048)
			(stroke
				(width 0.1)
				(type default)
			)
			(layer "F.Fab")
		)
		(fp_line
			(start 0.12065 -0.2794)
			(end 0.12065 -0.3048)
			(stroke
				(width 0.1)
				(type default)
			)
			(layer "F.Fab")
		)
		(fp_line
			(start -0.12065 -0.2794)
			(end 0.12065 -0.2794)
			(stroke
				(width 0.1)
				(type default)
			)
			(layer "F.Fab")
		)
		(fp_line
			(start 0.120396 0.2794)
			(end -0.12065 0.2794)
			(stroke
				(width 0.1)
				(type default)
			)
			(layer "F.Fab")
		)
		(fp_line
			(start -0.12065 0.2794)
			(end -0.12065 0.3048)
			(stroke
				(width 0.1)
				(type default)
			)
			(layer "F.Fab")
		)
		(fp_line
			(start 0.67945 0.3048)
			(end 0.120396 0.3048)
			(stroke
				(width 0.1)
				(type default)
			)
			(layer "F.Fab")
		)
		(fp_line
			(start 0.120396 0.3048)
			(end 0.120396 0.2794)
			(stroke
				(width 0.1)
				(type default)
			)
			(layer "F.Fab")
		)
		(fp_line
			(start -0.12065 0.3048)
			(end -0.67945 0.3048)
			(stroke
				(width 0.1)
				(type default)
			)
			(layer "F.Fab")
		)
		(fp_line
			(start -0.67945 0.3048)
			(end -0.67945 -0.305054)
			(stroke
				(width 0.1)
				(type default)
			)
			(layer "F.Fab")
		)
		(pad "1" smd circle
			(at -0.40005 0 90)
			(size 0 0)
			(layers "F.Cu" "F.Mask" "F.Paste")
			(net "LM75_1_A0")
		)
		(pad "2" smd circle
			(at 0.40005 0 90)
			(size 0 0)
			(layers "F.Cu" "F.Mask" "F.Paste")
			(net "GND")
		)
	)
	(footprint ""
		(layer "F.Cu")
		(at 214.534496 -30.94609 180)
		(property "Reference" "C304"
			(at 0 0 180)
			(layer "F.SilkS")
			(hide yes)
			(effects
				(font
					(size 1.27 1.27)
				)
			)
		)
		(property "Value" ""
			(at 0 0 180)
			(layer "F.Fab")
			(effects
				(font
					(size 1.27 1.27)
				)
			)
		)
		(duplicate_pad_numbers_are_jumpers no)
		(fp_line
			(start 0.299974 0.150114)
			(end -0.299974 0.150114)
			(stroke
				(width 0.1)
				(type default)
			)
			(layer "F.Fab")
		)
		(fp_line
			(start 0.299974 -0.150114)
			(end 0.299974 0.150114)
			(stroke
				(width 0.1)
				(type default)
			)
			(layer "F.Fab")
		)
		(fp_line
			(start -0.299974 0.150114)
			(end -0.299974 -0.150114)
			(stroke
				(width 0.1)
				(type default)
			)
			(layer "F.Fab")
		)
		(fp_line
			(start -0.299974 -0.150114)
			(end 0.299974 -0.150114)
			(stroke
				(width 0.1)
				(type default)
			)
			(layer "F.Fab")
		)
		(pad "1" smd rect
			(at -0.2667 0 180)
			(size 0.3048 0.381)
			(layers "F.Cu" "F.Mask" "F.Paste")
			(net "P5E_PEX1_STN2_TX_DP<33>")
		)
		(pad "2" smd rect
			(at 0.2667 0 180)
			(size 0.3048 0.381)
			(layers "F.Cu" "F.Mask" "F.Paste")
			(net "P5E_PEX1_STN2_TX_C_DP<33>")
		)
	)
	(footprint ""
		(layer "F.Cu")
		(at 6.709156 -26.03373)
		(property "Reference" "R4055"
			(at 0 0 0)
			(layer "F.SilkS")
			(hide yes)
			(effects
				(font
					(size 1.27 1.27)
				)
			)
		)
		(property "Value" ""
			(at 0 0 0)
			(layer "F.Fab")
			(effects
				(font
					(size 1.27 1.27)
				)
			)
		)
		(duplicate_pad_numbers_are_jumpers no)
		(fp_line
			(start -0.7874 -0.4064)
			(end 0.7874 -0.4064)
			(stroke
				(width 0.1524)
				(type default)
			)
			(layer "F.SilkS")
		)
		(fp_line
			(start -0.7874 0.4064)
			(end -0.7874 -0.4064)
			(stroke
				(width 0.1524)
				(type default)
			)
			(layer "F.SilkS")
		)
		(fp_line
			(start 0.7874 -0.4064)
			(end 0.7874 0.4064)
			(stroke
				(width 0.1524)
				(type default)
			)
			(layer "F.SilkS")
		)
		(fp_line
			(start 0.7874 0.4064)
			(end -0.7874 0.4064)
			(stroke
				(width 0.1524)
				(type default)
			)
			(layer "F.SilkS")
		)
		(fp_line
			(start -0.67945 -0.305054)
			(end -0.12065 -0.305054)
			(stroke
				(width 0.1)
				(type default)
			)
			(layer "F.Fab")
		)
		(fp_line
			(start -0.67945 0.3048)
			(end -0.67945 -0.305054)
			(stroke
				(width 0.1)
				(type default)
			)
			(layer "F.Fab")
		)
		(fp_line
			(start -0.12065 -0.305054)
			(end -0.12065 -0.2794)
			(stroke
				(width 0.1)
				(type default)
			)
			(layer "F.Fab")
		)
		(fp_line
			(start -0.12065 -0.2794)
			(end 0.12065 -0.2794)
			(stroke
				(width 0.1)
				(type default)
			)
			(layer "F.Fab")
		)
		(fp_line
			(start -0.12065 0.2794)
			(end -0.12065 0.3048)
			(stroke
				(width 0.1)
				(type default)
			)
			(layer "F.Fab")
		)
		(fp_line
			(start -0.12065 0.3048)
			(end -0.67945 0.3048)
			(stroke
				(width 0.1)
				(type default)
			)
			(layer "F.Fab")
		)
		(fp_line
			(start 0.120396 0.2794)
			(end -0.12065 0.2794)
			(stroke
				(width 0.1)
				(type default)
			)
			(layer "F.Fab")
		)
		(fp_line
			(start 0.120396 0.3048)
			(end 0.120396 0.2794)
			(stroke
				(width 0.1)
				(type default)
			)
			(layer "F.Fab")
		)
		(fp_line
			(start 0.12065 -0.3048)
			(end 0.67945 -0.3048)
			(stroke
				(width 0.1)
				(type default)
			)
			(layer "F.Fab")
		)
		(fp_line
			(start 0.12065 -0.2794)
			(end 0.12065 -0.3048)
			(stroke
				(width 0.1)
				(type default)
			)
			(layer "F.Fab")
		)
		(fp_line
			(start 0.67945 -0.3048)
			(end 0.67945 0.3048)
			(stroke
				(width 0.1)
				(type default)
			)
			(layer "F.Fab")
		)
		(fp_line
			(start 0.67945 0.3048)
			(end 0.120396 0.3048)
			(stroke
				(width 0.1)
				(type default)
			)
			(layer "F.Fab")
		)
		(pad "1" smd circle
			(at -0.40005 0)
			(size 0 0)
			(layers "F.Cu" "F.Mask" "F.Paste")
			(net "P3V3_AUX")
		)
		(pad "2" smd circle
			(at 0.40005 0)
			(size 0 0)
			(layers "F.Cu" "F.Mask" "F.Paste")
			(net "PRSNT_SSD0_R_N")
		)
	)
	(footprint ""
		(layer "F.Cu")
		(at 372.642384 -252.356874 -90)
		(property "Reference" "R1434"
			(at 0 0 270)
			(layer "F.SilkS")
			(hide yes)
			(effects
				(font
					(size 1.27 1.27)
				)
			)
		)
		(property "Value" ""
			(at 0 0 270)
			(layer "F.Fab")
			(effects
				(font
					(size 1.27 1.27)
				)
			)
		)
		(duplicate_pad_numbers_are_jumpers no)
		(fp_line
			(start -0.7874 0.4064)
			(end -0.7874 -0.4064)
			(stroke
				(width 0.1524)
				(type default)
			)
			(layer "F.SilkS")
		)
		(fp_line
			(start 0.7874 0.4064)
			(end -0.7874 0.4064)
			(stroke
				(width 0.1524)
				(type default)
			)
			(layer "F.SilkS")
		)
		(fp_line
			(start -0.7874 -0.4064)
			(end 0.7874 -0.4064)
			(stroke
				(width 0.1524)
				(type default)
			)
			(layer "F.SilkS")
		)
		(fp_line
			(start 0.7874 -0.4064)
			(end 0.7874 0.4064)
			(stroke
				(width 0.1524)
				(type default)
			)
			(layer "F.SilkS")
		)
		(fp_line
			(start -0.67945 0.3048)
			(end -0.67945 -0.305054)
			(stroke
				(width 0.1)
				(type default)
			)
			(layer "F.Fab")
		)
		(fp_line
			(start -0.12065 0.3048)
			(end -0.67945 0.3048)
			(stroke
				(width 0.1)
				(type default)
			)
			(layer "F.Fab")
		)
		(fp_line
			(start 0.120396 0.3048)
			(end 0.120396 0.2794)
			(stroke
				(width 0.1)
				(type default)
			)
			(layer "F.Fab")
		)
		(fp_line
			(start 0.67945 0.3048)
			(end 0.120396 0.3048)
			(stroke
				(width 0.1)
				(type default)
			)
			(layer "F.Fab")
		)
		(fp_line
			(start -0.12065 0.2794)
			(end -0.12065 0.3048)
			(stroke
				(width 0.1)
				(type default)
			)
			(layer "F.Fab")
		)
		(fp_line
			(start 0.120396 0.2794)
			(end -0.12065 0.2794)
			(stroke
				(width 0.1)
				(type default)
			)
			(layer "F.Fab")
		)
		(fp_line
			(start -0.12065 -0.2794)
			(end 0.12065 -0.2794)
			(stroke
				(width 0.1)
				(type default)
			)
			(layer "F.Fab")
		)
		(fp_line
			(start 0.12065 -0.2794)
			(end 0.12065 -0.3048)
			(stroke
				(width 0.1)
				(type default)
			)
			(layer "F.Fab")
		)
		(fp_line
			(start 0.12065 -0.3048)
			(end 0.67945 -0.3048)
			(stroke
				(width 0.1)
				(type default)
			)
			(layer "F.Fab")
		)
		(fp_line
			(start 0.67945 -0.3048)
			(end 0.67945 0.3048)
			(stroke
				(width 0.1)
				(type default)
			)
			(layer "F.Fab")
		)
		(fp_line
			(start -0.67945 -0.305054)
			(end -0.12065 -0.305054)
			(stroke
				(width 0.1)
				(type default)
			)
			(layer "F.Fab")
		)
		(fp_line
			(start -0.12065 -0.305054)
			(end -0.12065 -0.2794)
			(stroke
				(width 0.1)
				(type default)
			)
			(layer "F.Fab")
		)
		(pad "1" smd circle
			(at -0.40005 0 270)
			(size 0 0)
			(layers "F.Cu" "F.Mask" "F.Paste")
			(net "GND")
		)
		(pad "2" smd circle
			(at 0.40005 0 270)
			(size 0 0)
			(layers "F.Cu" "F.Mask" "F.Paste")
			(net "PEX3_MODE_SEL9")
		)
	)
	(footprint ""
		(layer "F.Cu")
		(at 476.12427 -528.059142 180)
		(property "Reference" "SCREW_SSD2_2"
			(at -5.207 -1.402334 0)
			(unlocked yes)
			(layer "B.SilkS")
			(effects
				(font
					(size 0.7874 0.5842)
					(thickness 0.1524)
				)
				(justify mirror)
			)
		)
		(property "Value" ""
			(at 0 0 180)
			(layer "F.Fab")
			(effects
				(font
					(size 1.27 1.27)
				)
			)
		)
		(duplicate_pad_numbers_are_jumpers no)
		(pad "1" thru_hole circle
			(at 0 0 180)
			(size 0.4572 0.4572)
			(drill 0.2032)
			(layers "*.Cu" "*.Mask")
			(remove_unused_layers no)
			(net "Net_9139")
			(clearance 0.127)
			(thermal_gap 0.127)
			(padstack
				(mode front_inner_back)
				(layer "Inner"
					(shape circle)
					(size 0.4572 0.4572)
					(clearance 0.127)
				)
				(layer "B.Cu"
					(shape circle)
					(size 0.508 0.508)
					(clearance 0.1016)
				)
			)
		)
	)
	(footprint ""
		(layer "F.Cu")
		(at 29.543756 -311.725564 45)
		(property "Reference" "R1168"
			(at 0 0 45)
			(layer "F.SilkS")
			(hide yes)
			(effects
				(font
					(size 1.27 1.27)
				)
			)
		)
		(property "Value" ""
			(at 0 0 45)
			(layer "F.Fab")
			(effects
				(font
					(size 1.27 1.27)
				)
			)
		)
		(duplicate_pad_numbers_are_jumpers no)
		(fp_line
			(start -0.787389 -0.406267)
			(end 0.787389 -0.406267)
			(stroke
				(width 0.1524)
				(type default)
			)
			(layer "F.SilkS")
		)
		(fp_line
			(start -0.787389 0.406267)
			(end -0.787389 -0.406267)
			(stroke
				(width 0.1524)
				(type default)
			)
			(layer "F.SilkS")
		)
		(fp_line
			(start 0.787389 -0.406267)
			(end 0.787389 0.406267)
			(stroke
				(width 0.1524)
				(type default)
			)
			(layer "F.SilkS")
		)
		(fp_line
			(start 0.787389 0.406267)
			(end -0.787389 0.406267)
			(stroke
				(width 0.1524)
				(type default)
			)
			(layer "F.SilkS")
		)
		(fp_line
			(start -0.679446 -0.305149)
			(end -0.120695 -0.304969)
			(stroke
				(width 0.1)
				(type default)
			)
			(layer "F.Fab")
		)
		(fp_line
			(start -0.120695 -0.304969)
			(end -0.120695 -0.279466)
			(stroke
				(width 0.1)
				(type default)
			)
			(layer "F.Fab")
		)
		(fp_line
			(start -0.120695 -0.279466)
			(end 0.120695 -0.279466)
			(stroke
				(width 0.1)
				(type default)
			)
			(layer "F.Fab")
		)
		(fp_line
			(start -0.679446 0.30479)
			(end -0.679446 -0.305149)
			(stroke
				(width 0.1)
				(type default)
			)
			(layer "F.Fab")
		)
		(fp_line
			(start 0.120515 -0.30479)
			(end 0.679446 -0.30479)
			(stroke
				(width 0.1)
				(type default)
			)
			(layer "F.Fab")
		)
		(fp_line
			(start 0.120695 -0.279466)
			(end 0.120515 -0.30479)
			(stroke
				(width 0.1)
				(type default)
			)
			(layer "F.Fab")
		)
		(fp_line
			(start -0.120695 0.279466)
			(end -0.120515 0.30479)
			(stroke
				(width 0.1)
				(type default)
			)
			(layer "F.Fab")
		)
		(fp_line
			(start -0.120515 0.30479)
			(end -0.679446 0.30479)
			(stroke
				(width 0.1)
				(type default)
			)
			(layer "F.Fab")
		)
		(fp_line
			(start 0.679446 -0.30479)
			(end 0.679446 0.30479)
			(stroke
				(width 0.1)
				(type default)
			)
			(layer "F.Fab")
		)
		(fp_line
			(start 0.120335 0.279466)
			(end -0.120695 0.279466)
			(stroke
				(width 0.1)
				(type default)
			)
			(layer "F.Fab")
		)
		(fp_line
			(start 0.120515 0.30479)
			(end 0.120335 0.279466)
			(stroke
				(width 0.1)
				(type default)
			)
			(layer "F.Fab")
		)
		(fp_line
			(start 0.679446 0.30479)
			(end 0.120515 0.30479)
			(stroke
				(width 0.1)
				(type default)
			)
			(layer "F.Fab")
		)
		(pad "1" smd circle
			(at -0.40005 0 45)
			(size 0 0)
			(layers "F.Cu" "F.Mask" "F.Paste")
			(net "GND")
		)
		(pad "2" smd circle
			(at 0.40005 0 45)
			(size 0 0)
			(layers "F.Cu" "F.Mask" "F.Paste")
			(net "PEX0_DBG_SEL1")
		)
	)
	(footprint ""
		(layer "F.Cu")
		(at 92.071444 -96.811592 -90)
		(property "Reference" "R691"
			(at 0 0 270)
			(layer "F.SilkS")
			(hide yes)
			(effects
				(font
					(size 1.27 1.27)
				)
			)
		)
		(property "Value" ""
			(at 0 0 270)
			(layer "F.Fab")
			(effects
				(font
					(size 1.27 1.27)
				)
			)
		)
		(duplicate_pad_numbers_are_jumpers no)
		(fp_line
			(start -0.7874 0.4064)
			(end -0.7874 -0.4064)
			(stroke
				(width 0.1524)
				(type default)
			)
			(layer "F.SilkS")
		)
		(fp_line
			(start 0.7874 0.4064)
			(end -0.7874 0.4064)
			(stroke
				(width 0.1524)
				(type default)
			)
			(layer "F.SilkS")
		)
		(fp_line
			(start -0.7874 -0.4064)
			(end 0.7874 -0.4064)
			(stroke
				(width 0.1524)
				(type default)
			)
			(layer "F.SilkS")
		)
		(fp_line
			(start 0.7874 -0.4064)
			(end 0.7874 0.4064)
			(stroke
				(width 0.1524)
				(type default)
			)
			(layer "F.SilkS")
		)
		(fp_line
			(start -0.67945 0.3048)
			(end -0.67945 -0.305054)
			(stroke
				(width 0.1)
				(type default)
			)
			(layer "F.Fab")
		)
		(fp_line
			(start -0.12065 0.3048)
			(end -0.67945 0.3048)
			(stroke
				(width 0.1)
				(type default)
			)
			(layer "F.Fab")
		)
		(fp_line
			(start 0.120396 0.3048)
			(end 0.120396 0.2794)
			(stroke
				(width 0.1)
				(type default)
			)
			(layer "F.Fab")
		)
		(fp_line
			(start 0.67945 0.3048)
			(end 0.120396 0.3048)
			(stroke
				(width 0.1)
				(type default)
			)
			(layer "F.Fab")
		)
		(fp_line
			(start -0.12065 0.2794)
			(end -0.12065 0.3048)
			(stroke
				(width 0.1)
				(type default)
			)
			(layer "F.Fab")
		)
		(fp_line
			(start 0.120396 0.2794)
			(end -0.12065 0.2794)
			(stroke
				(width 0.1)
				(type default)
			)
			(layer "F.Fab")
		)
		(fp_line
			(start -0.12065 -0.2794)
			(end 0.12065 -0.2794)
			(stroke
				(width 0.1)
				(type default)
			)
			(layer "F.Fab")
		)
		(fp_line
			(start 0.12065 -0.2794)
			(end 0.12065 -0.3048)
			(stroke
				(width 0.1)
				(type default)
			)
			(layer "F.Fab")
		)
		(fp_line
			(start 0.12065 -0.3048)
			(end 0.67945 -0.3048)
			(stroke
				(width 0.1)
				(type default)
			)
			(layer "F.Fab")
		)
		(fp_line
			(start 0.67945 -0.3048)
			(end 0.67945 0.3048)
			(stroke
				(width 0.1)
				(type default)
			)
			(layer "F.Fab")
		)
		(fp_line
			(start -0.67945 -0.305054)
			(end -0.12065 -0.305054)
			(stroke
				(width 0.1)
				(type default)
			)
			(layer "F.Fab")
		)
		(fp_line
			(start -0.12065 -0.305054)
			(end -0.12065 -0.2794)
			(stroke
				(width 0.1)
				(type default)
			)
			(layer "F.Fab")
		)
		(pad "1" smd circle
			(at -0.40005 0 270)
			(size 0 0)
			(layers "F.Cu" "F.Mask" "F.Paste")
			(net "P3V3_AUX")
		)
		(pad "2" smd circle
			(at 0.40005 0 270)
			(size 0 0)
			(layers "F.Cu" "F.Mask" "F.Paste")
			(net "NIC_ADC_ALERT_N")
		)
	)
	(footprint ""
		(layer "F.Cu")
		(at 338.074 -177.927 180)
		(property "Reference" "R4754"
			(at 0 0 180)
			(layer "F.SilkS")
			(hide yes)
			(effects
				(font
					(size 1.27 1.27)
				)
			)
		)
		(property "Value" ""
			(at 0 0 180)
			(layer "F.Fab")
			(effects
				(font
					(size 1.27 1.27)
				)
			)
		)
		(duplicate_pad_numbers_are_jumpers no)
		(fp_line
			(start 0.7874 0.4064)
			(end -0.7874 0.4064)
			(stroke
				(width 0.1524)
				(type default)
			)
			(layer "F.SilkS")
		)
		(fp_line
			(start 0.7874 -0.4064)
			(end 0.7874 0.4064)
			(stroke
				(width 0.1524)
				(type default)
			)
			(layer "F.SilkS")
		)
		(fp_line
			(start -0.7874 0.4064)
			(end -0.7874 -0.4064)
			(stroke
				(width 0.1524)
				(type default)
			)
			(layer "F.SilkS")
		)
		(fp_line
			(start -0.7874 -0.4064)
			(end 0.7874 -0.4064)
			(stroke
				(width 0.1524)
				(type default)
			)
			(layer "F.SilkS")
		)
		(fp_line
			(start 0.67945 0.3048)
			(end 0.120396 0.3048)
			(stroke
				(width 0.1)
				(type default)
			)
			(layer "F.Fab")
		)
		(fp_line
			(start 0.67945 -0.3048)
			(end 0.67945 0.3048)
			(stroke
				(width 0.1)
				(type default)
			)
			(layer "F.Fab")
		)
		(fp_line
			(start 0.12065 -0.2794)
			(end 0.12065 -0.3048)
			(stroke
				(width 0.1)
				(type default)
			)
			(layer "F.Fab")
		)
		(fp_line
			(start 0.12065 -0.3048)
			(end 0.67945 -0.3048)
			(stroke
				(width 0.1)
				(type default)
			)
			(layer "F.Fab")
		)
		(fp_line
			(start 0.120396 0.3048)
			(end 0.120396 0.2794)
			(stroke
				(width 0.1)
				(type default)
			)
			(layer "F.Fab")
		)
		(fp_line
			(start 0.120396 0.2794)
			(end -0.12065 0.2794)
			(stroke
				(width 0.1)
				(type default)
			)
			(layer "F.Fab")
		)
		(fp_line
			(start -0.12065 0.3048)
			(end -0.67945 0.3048)
			(stroke
				(width 0.1)
				(type default)
			)
			(layer "F.Fab")
		)
		(fp_line
			(start -0.12065 0.2794)
			(end -0.12065 0.3048)
			(stroke
				(width 0.1)
				(type default)
			)
			(layer "F.Fab")
		)
		(fp_line
			(start -0.12065 -0.2794)
			(end 0.12065 -0.2794)
			(stroke
				(width 0.1)
				(type default)
			)
			(layer "F.Fab")
		)
		(fp_line
			(start -0.12065 -0.305054)
			(end -0.12065 -0.2794)
			(stroke
				(width 0.1)
				(type default)
			)
			(layer "F.Fab")
		)
		(fp_line
			(start -0.67945 0.3048)
			(end -0.67945 -0.305054)
			(stroke
				(width 0.1)
				(type default)
			)
			(layer "F.Fab")
		)
		(fp_line
			(start -0.67945 -0.305054)
			(end -0.12065 -0.305054)
			(stroke
				(width 0.1)
				(type default)
			)
			(layer "F.Fab")
		)
		(pad "1" smd circle
			(at -0.40005 0 180)
			(size 0 0)
			(layers "F.Cu" "F.Mask" "F.Paste")
			(net "SSD9_PEX_PWR_EN")
		)
		(pad "2" smd circle
			(at 0.40005 0 180)
			(size 0 0)
			(layers "F.Cu" "F.Mask" "F.Paste")
			(net "SSD9_PEX_PWR_EN_R")
		)
	)
	(footprint ""
		(layer "F.Cu")
		(at 303.446688 -37.47516)
		(property "Reference" "R6099"
			(at 0 0 0)
			(layer "F.SilkS")
			(hide yes)
			(effects
				(font
					(size 1.27 1.27)
				)
			)
		)
		(property "Value" ""
			(at 0 0 0)
			(layer "F.Fab")
			(effects
				(font
					(size 1.27 1.27)
				)
			)
		)
		(duplicate_pad_numbers_are_jumpers no)
		(fp_line
			(start -0.7874 -0.4064)
			(end 0.7874 -0.4064)
			(stroke
				(width 0.1524)
				(type default)
			)
			(layer "F.SilkS")
		)
		(fp_line
			(start -0.7874 0.4064)
			(end -0.7874 -0.4064)
			(stroke
				(width 0.1524)
				(type default)
			)
			(layer "F.SilkS")
		)
		(fp_line
			(start 0.7874 -0.4064)
			(end 0.7874 0.4064)
			(stroke
				(width 0.1524)
				(type default)
			)
			(layer "F.SilkS")
		)
		(fp_line
			(start 0.7874 0.4064)
			(end -0.7874 0.4064)
			(stroke
				(width 0.1524)
				(type default)
			)
			(layer "F.SilkS")
		)
		(fp_line
			(start -0.67945 -0.305054)
			(end -0.12065 -0.305054)
			(stroke
				(width 0.1)
				(type default)
			)
			(layer "F.Fab")
		)
		(fp_line
			(start -0.67945 0.3048)
			(end -0.67945 -0.305054)
			(stroke
				(width 0.1)
				(type default)
			)
			(layer "F.Fab")
		)
		(fp_line
			(start -0.12065 -0.305054)
			(end -0.12065 -0.2794)
			(stroke
				(width 0.1)
				(type default)
			)
			(layer "F.Fab")
		)
		(fp_line
			(start -0.12065 -0.2794)
			(end 0.12065 -0.2794)
			(stroke
				(width 0.1)
				(type default)
			)
			(layer "F.Fab")
		)
		(fp_line
			(start -0.12065 0.2794)
			(end -0.12065 0.3048)
			(stroke
				(width 0.1)
				(type default)
			)
			(layer "F.Fab")
		)
		(fp_line
			(start -0.12065 0.3048)
			(end -0.67945 0.3048)
			(stroke
				(width 0.1)
				(type default)
			)
			(layer "F.Fab")
		)
		(fp_line
			(start 0.120396 0.2794)
			(end -0.12065 0.2794)
			(stroke
				(width 0.1)
				(type default)
			)
			(layer "F.Fab")
		)
		(fp_line
			(start 0.120396 0.3048)
			(end 0.120396 0.2794)
			(stroke
				(width 0.1)
				(type default)
			)
			(layer "F.Fab")
		)
		(fp_line
			(start 0.12065 -0.3048)
			(end 0.67945 -0.3048)
			(stroke
				(width 0.1)
				(type default)
			)
			(layer "F.Fab")
		)
		(fp_line
			(start 0.12065 -0.2794)
			(end 0.12065 -0.3048)
			(stroke
				(width 0.1)
				(type default)
			)
			(layer "F.Fab")
		)
		(fp_line
			(start 0.67945 -0.3048)
			(end 0.67945 0.3048)
			(stroke
				(width 0.1)
				(type default)
			)
			(layer "F.Fab")
		)
		(fp_line
			(start 0.67945 0.3048)
			(end 0.120396 0.3048)
			(stroke
				(width 0.1)
				(type default)
			)
			(layer "F.Fab")
		)
		(pad "1" smd circle
			(at -0.40005 0)
			(size 0 0)
			(layers "F.Cu" "F.Mask" "F.Paste")
			(net "P3V3_SSD11")
		)
		(pad "2" smd circle
			(at 0.40005 0)
			(size 0 0)
			(layers "F.Cu" "F.Mask" "F.Paste")
			(net "P3V3_SSD11_PG_G1")
		)
	)
	(footprint ""
		(layer "F.Cu")
		(at 4.050792 -34.872168 90)
		(property "Reference" "R1641"
			(at 0 0 90)
			(layer "F.SilkS")
			(hide yes)
			(effects
				(font
					(size 1.27 1.27)
				)
			)
		)
		(property "Value" ""
			(at 0 0 90)
			(layer "F.Fab")
			(effects
				(font
					(size 1.27 1.27)
				)
			)
		)
		(duplicate_pad_numbers_are_jumpers no)
		(fp_line
			(start 0.7874 -0.4064)
			(end 0.7874 0.4064)
			(stroke
				(width 0.1524)
				(type default)
			)
			(layer "F.SilkS")
		)
		(fp_line
			(start -0.7874 -0.4064)
			(end 0.7874 -0.4064)
			(stroke
				(width 0.1524)
				(type default)
			)
			(layer "F.SilkS")
		)
		(fp_line
			(start 0.7874 0.4064)
			(end -0.7874 0.4064)
			(stroke
				(width 0.1524)
				(type default)
			)
			(layer "F.SilkS")
		)
		(fp_line
			(start -0.7874 0.4064)
			(end -0.7874 -0.4064)
			(stroke
				(width 0.1524)
				(type default)
			)
			(layer "F.SilkS")
		)
		(fp_line
			(start -0.12065 -0.305054)
			(end -0.12065 -0.2794)
			(stroke
				(width 0.1)
				(type default)
			)
			(layer "F.Fab")
		)
		(fp_line
			(start -0.67945 -0.305054)
			(end -0.12065 -0.305054)
			(stroke
				(width 0.1)
				(type default)
			)
			(layer "F.Fab")
		)
		(fp_line
			(start 0.67945 -0.3048)
			(end 0.67945 0.3048)
			(stroke
				(width 0.1)
				(type default)
			)
			(layer "F.Fab")
		)
		(fp_line
			(start 0.12065 -0.3048)
			(end 0.67945 -0.3048)
			(stroke
				(width 0.1)
				(type default)
			)
			(layer "F.Fab")
		)
		(fp_line
			(start 0.12065 -0.2794)
			(end 0.12065 -0.3048)
			(stroke
				(width 0.1)
				(type default)
			)
			(layer "F.Fab")
		)
		(fp_line
			(start -0.12065 -0.2794)
			(end 0.12065 -0.2794)
			(stroke
				(width 0.1)
				(type default)
			)
			(layer "F.Fab")
		)
		(fp_line
			(start 0.120396 0.2794)
			(end -0.12065 0.2794)
			(stroke
				(width 0.1)
				(type default)
			)
			(layer "F.Fab")
		)
		(fp_line
			(start -0.12065 0.2794)
			(end -0.12065 0.3048)
			(stroke
				(width 0.1)
				(type default)
			)
			(layer "F.Fab")
		)
		(fp_line
			(start 0.67945 0.3048)
			(end 0.120396 0.3048)
			(stroke
				(width 0.1)
				(type default)
			)
			(layer "F.Fab")
		)
		(fp_line
			(start 0.120396 0.3048)
			(end 0.120396 0.2794)
			(stroke
				(width 0.1)
				(type default)
			)
			(layer "F.Fab")
		)
		(fp_line
			(start -0.12065 0.3048)
			(end -0.67945 0.3048)
			(stroke
				(width 0.1)
				(type default)
			)
			(layer "F.Fab")
		)
		(fp_line
			(start -0.67945 0.3048)
			(end -0.67945 -0.305054)
			(stroke
				(width 0.1)
				(type default)
			)
			(layer "F.Fab")
		)
		(pad "1" smd circle
			(at -0.40005 0 90)
			(size 0 0)
			(layers "F.Cu" "F.Mask" "F.Paste")
			(net "SMB_BIC_I2C9_MUX0_SSD0_R_SDA")
		)
		(pad "2" smd circle
			(at 0.40005 0 90)
			(size 0 0)
			(layers "F.Cu" "F.Mask" "F.Paste")
			(net "SMB_ISO_SSD0_SDA")
		)
	)
	(footprint ""
		(layer "F.Cu")
		(at 336.443574 -45.88891)
		(property "Reference" "R631"
			(at 0 0 0)
			(layer "F.SilkS")
			(hide yes)
			(effects
				(font
					(size 1.27 1.27)
				)
			)
		)
		(property "Value" ""
			(at 0 0 0)
			(layer "F.Fab")
			(effects
				(font
					(size 1.27 1.27)
				)
			)
		)
		(duplicate_pad_numbers_are_jumpers no)
		(fp_line
			(start -0.7874 -0.4064)
			(end 0.7874 -0.4064)
			(stroke
				(width 0.1524)
				(type default)
			)
			(layer "F.SilkS")
		)
		(fp_line
			(start -0.7874 0.4064)
			(end -0.7874 -0.4064)
			(stroke
				(width 0.1524)
				(type default)
			)
			(layer "F.SilkS")
		)
		(fp_line
			(start 0.7874 -0.4064)
			(end 0.7874 0.4064)
			(stroke
				(width 0.1524)
				(type default)
			)
			(layer "F.SilkS")
		)
		(fp_line
			(start 0.7874 0.4064)
			(end -0.7874 0.4064)
			(stroke
				(width 0.1524)
				(type default)
			)
			(layer "F.SilkS")
		)
		(fp_line
			(start -0.67945 -0.305054)
			(end -0.12065 -0.305054)
			(stroke
				(width 0.1)
				(type default)
			)
			(layer "F.Fab")
		)
		(fp_line
			(start -0.67945 0.3048)
			(end -0.67945 -0.305054)
			(stroke
				(width 0.1)
				(type default)
			)
			(layer "F.Fab")
		)
		(fp_line
			(start -0.12065 -0.305054)
			(end -0.12065 -0.2794)
			(stroke
				(width 0.1)
				(type default)
			)
			(layer "F.Fab")
		)
		(fp_line
			(start -0.12065 -0.2794)
			(end 0.12065 -0.2794)
			(stroke
				(width 0.1)
				(type default)
			)
			(layer "F.Fab")
		)
		(fp_line
			(start -0.12065 0.2794)
			(end -0.12065 0.3048)
			(stroke
				(width 0.1)
				(type default)
			)
			(layer "F.Fab")
		)
		(fp_line
			(start -0.12065 0.3048)
			(end -0.67945 0.3048)
			(stroke
				(width 0.1)
				(type default)
			)
			(layer "F.Fab")
		)
		(fp_line
			(start 0.120396 0.2794)
			(end -0.12065 0.2794)
			(stroke
				(width 0.1)
				(type default)
			)
			(layer "F.Fab")
		)
		(fp_line
			(start 0.120396 0.3048)
			(end 0.120396 0.2794)
			(stroke
				(width 0.1)
				(type default)
			)
			(layer "F.Fab")
		)
		(fp_line
			(start 0.12065 -0.3048)
			(end 0.67945 -0.3048)
			(stroke
				(width 0.1)
				(type default)
			)
			(layer "F.Fab")
		)
		(fp_line
			(start 0.12065 -0.2794)
			(end 0.12065 -0.3048)
			(stroke
				(width 0.1)
				(type default)
			)
			(layer "F.Fab")
		)
		(fp_line
			(start 0.67945 -0.3048)
			(end 0.67945 0.3048)
			(stroke
				(width 0.1)
				(type default)
			)
			(layer "F.Fab")
		)
		(fp_line
			(start 0.67945 0.3048)
			(end 0.120396 0.3048)
			(stroke
				(width 0.1)
				(type default)
			)
			(layer "F.Fab")
		)
		(pad "1" smd circle
			(at -0.40005 0)
			(size 0 0)
			(layers "F.Cu" "F.Mask" "F.Paste")
			(net "SSD11_ADC_A0")
		)
		(pad "2" smd circle
			(at 0.40005 0)
			(size 0 0)
			(layers "F.Cu" "F.Mask" "F.Paste")
			(net "GND")
		)
	)
	(footprint ""
		(layer "F.Cu")
		(at 224.851976 -368.010186 180)
		(property "Reference" "PR42"
			(at 0 0 180)
			(layer "F.SilkS")
			(hide yes)
			(effects
				(font
					(size 1.27 1.27)
				)
			)
		)
		(property "Value" ""
			(at 0 0 180)
			(layer "F.Fab")
			(effects
				(font
					(size 1.27 1.27)
				)
			)
		)
		(duplicate_pad_numbers_are_jumpers no)
		(fp_line
			(start 0.7874 0.4064)
			(end -0.7874 0.4064)
			(stroke
				(width 0.1524)
				(type default)
			)
			(layer "F.SilkS")
		)
		(fp_line
			(start 0.7874 -0.4064)
			(end 0.7874 0.4064)
			(stroke
				(width 0.1524)
				(type default)
			)
			(layer "F.SilkS")
		)
		(fp_line
			(start -0.7874 0.4064)
			(end -0.7874 -0.4064)
			(stroke
				(width 0.1524)
				(type default)
			)
			(layer "F.SilkS")
		)
		(fp_line
			(start -0.7874 -0.4064)
			(end 0.7874 -0.4064)
			(stroke
				(width 0.1524)
				(type default)
			)
			(layer "F.SilkS")
		)
		(fp_line
			(start 0.67945 0.3048)
			(end 0.120396 0.3048)
			(stroke
				(width 0.1)
				(type default)
			)
			(layer "F.Fab")
		)
		(fp_line
			(start 0.67945 -0.3048)
			(end 0.67945 0.3048)
			(stroke
				(width 0.1)
				(type default)
			)
			(layer "F.Fab")
		)
		(fp_line
			(start 0.12065 -0.2794)
			(end 0.12065 -0.3048)
			(stroke
				(width 0.1)
				(type default)
			)
			(layer "F.Fab")
		)
		(fp_line
			(start 0.12065 -0.3048)
			(end 0.67945 -0.3048)
			(stroke
				(width 0.1)
				(type default)
			)
			(layer "F.Fab")
		)
		(fp_line
			(start 0.120396 0.3048)
			(end 0.120396 0.2794)
			(stroke
				(width 0.1)
				(type default)
			)
			(layer "F.Fab")
		)
		(fp_line
			(start 0.120396 0.2794)
			(end -0.12065 0.2794)
			(stroke
				(width 0.1)
				(type default)
			)
			(layer "F.Fab")
		)
		(fp_line
			(start -0.12065 0.3048)
			(end -0.67945 0.3048)
			(stroke
				(width 0.1)
				(type default)
			)
			(layer "F.Fab")
		)
		(fp_line
			(start -0.12065 0.2794)
			(end -0.12065 0.3048)
			(stroke
				(width 0.1)
				(type default)
			)
			(layer "F.Fab")
		)
		(fp_line
			(start -0.12065 -0.2794)
			(end 0.12065 -0.2794)
			(stroke
				(width 0.1)
				(type default)
			)
			(layer "F.Fab")
		)
		(fp_line
			(start -0.12065 -0.305054)
			(end -0.12065 -0.2794)
			(stroke
				(width 0.1)
				(type default)
			)
			(layer "F.Fab")
		)
		(fp_line
			(start -0.67945 0.3048)
			(end -0.67945 -0.305054)
			(stroke
				(width 0.1)
				(type default)
			)
			(layer "F.Fab")
		)
		(fp_line
			(start -0.67945 -0.305054)
			(end -0.12065 -0.305054)
			(stroke
				(width 0.1)
				(type default)
			)
			(layer "F.Fab")
		)
		(pad "1" smd circle
			(at -0.40005 0 180)
			(size 0 0)
			(layers "F.Cu" "F.Mask" "F.Paste")
			(net "HSC_CS_2")
		)
		(pad "2" smd circle
			(at 0.40005 0 180)
			(size 0 0)
			(layers "F.Cu" "F.Mask" "F.Paste")
			(net "AGND_HSC")
		)
	)
	(footprint ""
		(layer "F.Cu")
		(at 376.706384 -252.356874 -90)
		(property "Reference" "R1423"
			(at 0 0 270)
			(layer "F.SilkS")
			(hide yes)
			(effects
				(font
					(size 1.27 1.27)
				)
			)
		)
		(property "Value" ""
			(at 0 0 270)
			(layer "F.Fab")
			(effects
				(font
					(size 1.27 1.27)
				)
			)
		)
		(duplicate_pad_numbers_are_jumpers no)
		(fp_line
			(start -0.7874 0.4064)
			(end -0.7874 -0.4064)
			(stroke
				(width 0.1524)
				(type default)
			)
			(layer "F.SilkS")
		)
		(fp_line
			(start 0.7874 0.4064)
			(end -0.7874 0.4064)
			(stroke
				(width 0.1524)
				(type default)
			)
			(layer "F.SilkS")
		)
		(fp_line
			(start -0.7874 -0.4064)
			(end 0.7874 -0.4064)
			(stroke
				(width 0.1524)
				(type default)
			)
			(layer "F.SilkS")
		)
		(fp_line
			(start 0.7874 -0.4064)
			(end 0.7874 0.4064)
			(stroke
				(width 0.1524)
				(type default)
			)
			(layer "F.SilkS")
		)
		(fp_line
			(start -0.67945 0.3048)
			(end -0.67945 -0.305054)
			(stroke
				(width 0.1)
				(type default)
			)
			(layer "F.Fab")
		)
		(fp_line
			(start -0.12065 0.3048)
			(end -0.67945 0.3048)
			(stroke
				(width 0.1)
				(type default)
			)
			(layer "F.Fab")
		)
		(fp_line
			(start 0.120396 0.3048)
			(end 0.120396 0.2794)
			(stroke
				(width 0.1)
				(type default)
			)
			(layer "F.Fab")
		)
		(fp_line
			(start 0.67945 0.3048)
			(end 0.120396 0.3048)
			(stroke
				(width 0.1)
				(type default)
			)
			(layer "F.Fab")
		)
		(fp_line
			(start -0.12065 0.2794)
			(end -0.12065 0.3048)
			(stroke
				(width 0.1)
				(type default)
			)
			(layer "F.Fab")
		)
		(fp_line
			(start 0.120396 0.2794)
			(end -0.12065 0.2794)
			(stroke
				(width 0.1)
				(type default)
			)
			(layer "F.Fab")
		)
		(fp_line
			(start -0.12065 -0.2794)
			(end 0.12065 -0.2794)
			(stroke
				(width 0.1)
				(type default)
			)
			(layer "F.Fab")
		)
		(fp_line
			(start 0.12065 -0.2794)
			(end 0.12065 -0.3048)
			(stroke
				(width 0.1)
				(type default)
			)
			(layer "F.Fab")
		)
		(fp_line
			(start 0.12065 -0.3048)
			(end 0.67945 -0.3048)
			(stroke
				(width 0.1)
				(type default)
			)
			(layer "F.Fab")
		)
		(fp_line
			(start 0.67945 -0.3048)
			(end 0.67945 0.3048)
			(stroke
				(width 0.1)
				(type default)
			)
			(layer "F.Fab")
		)
		(fp_line
			(start -0.67945 -0.305054)
			(end -0.12065 -0.305054)
			(stroke
				(width 0.1)
				(type default)
			)
			(layer "F.Fab")
		)
		(fp_line
			(start -0.12065 -0.305054)
			(end -0.12065 -0.2794)
			(stroke
				(width 0.1)
				(type default)
			)
			(layer "F.Fab")
		)
		(pad "1" smd circle
			(at -0.40005 0 270)
			(size 0 0)
			(layers "F.Cu" "F.Mask" "F.Paste")
			(net "GND")
		)
		(pad "2" smd circle
			(at 0.40005 0 270)
			(size 0 0)
			(layers "F.Cu" "F.Mask" "F.Paste")
			(net "PEX3_DBG_MODE3")
		)
	)
	(footprint ""
		(layer "F.Cu")
		(at 379.147832 -40.037258 90)
		(property "Reference" "U374"
			(at 0.196342 2.310638 90)
			(unlocked yes)
			(layer "F.SilkS")
			(effects
				(font
					(size 0.7874 0.5842)
					(thickness 0.1524)
				)
			)
		)
		(property "Value" ""
			(at 0 0 90)
			(layer "F.Fab")
			(effects
				(font
					(size 1.27 1.27)
				)
			)
		)
		(duplicate_pad_numbers_are_jumpers no)
		(fp_line
			(start -1.949958 -1.610106)
			(end 1.949958 -1.610106)
			(stroke
				(width 0.1524)
				(type default)
			)
			(layer "F.SilkS")
		)
		(fp_line
			(start 1.949958 -1.560068)
			(end 1.949958 1.610106)
			(stroke
				(width 0.1524)
				(type default)
			)
			(layer "F.SilkS")
		)
		(fp_line
			(start 1.949958 1.610106)
			(end -1.949958 1.610106)
			(stroke
				(width 0.1524)
				(type default)
			)
			(layer "F.SilkS")
		)
		(fp_line
			(start -1.949958 1.610106)
			(end -1.949958 -1.610106)
			(stroke
				(width 0.1524)
				(type default)
			)
			(layer "F.SilkS")
		)
		(fp_line
			(start 0.750062 -1.560068)
			(end 0.750062 1.560068)
			(stroke
				(width 0.1)
				(type default)
			)
			(layer "F.Fab")
		)
		(fp_line
			(start -0.750062 -1.560068)
			(end 0.750062 -1.560068)
			(stroke
				(width 0.1)
				(type default)
			)
			(layer "F.Fab")
		)
		(fp_line
			(start 0.750062 1.560068)
			(end -0.750062 1.560068)
			(stroke
				(width 0.1)
				(type default)
			)
			(layer "F.Fab")
		)
		(fp_line
			(start -0.750062 1.560068)
			(end -0.750062 -1.560068)
			(stroke
				(width 0.1)
				(type default)
			)
			(layer "F.Fab")
		)
		(pad "D" smd rect
			(at 1.100074 0)
			(size 1.016 1.4224)
			(layers "F.Cu" "F.Mask" "F.Paste")
			(net "SSD13_AUX_P3V3_EN")
		)
		(pad "G" smd rect
			(at -1.100074 -0.94996)
			(size 1.016 1.4224)
			(layers "F.Cu" "F.Mask" "F.Paste")
			(net "PRSNT_SSD13_R1_N")
		)
		(pad "S" smd rect
			(at -1.100074 0.94996)
			(size 1.016 1.4224)
			(layers "F.Cu" "F.Mask" "F.Paste")
			(net "GND")
		)
	)
	(footprint ""
		(layer "F.Cu")
		(at 332.045564 -356.244906 90)
		(property "Reference" "C570"
			(at 0 0 90)
			(layer "F.SilkS")
			(hide yes)
			(effects
				(font
					(size 1.27 1.27)
				)
			)
		)
		(property "Value" ""
			(at 0 0 90)
			(layer "F.Fab")
			(effects
				(font
					(size 1.27 1.27)
				)
			)
		)
		(duplicate_pad_numbers_are_jumpers no)
		(fp_line
			(start 0.299974 -0.150114)
			(end 0.299974 0.150114)
			(stroke
				(width 0.1)
				(type default)
			)
			(layer "F.Fab")
		)
		(fp_line
			(start -0.299974 -0.150114)
			(end 0.299974 -0.150114)
			(stroke
				(width 0.1)
				(type default)
			)
			(layer "F.Fab")
		)
		(fp_line
			(start 0.299974 0.150114)
			(end -0.299974 0.150114)
			(stroke
				(width 0.1)
				(type default)
			)
			(layer "F.Fab")
		)
		(fp_line
			(start -0.299974 0.150114)
			(end -0.299974 -0.150114)
			(stroke
				(width 0.1)
				(type default)
			)
			(layer "F.Fab")
		)
		(pad "1" smd rect
			(at -0.2667 0 90)
			(size 0.3048 0.381)
			(layers "F.Cu" "F.Mask" "F.Paste")
			(net "P5E_PEX2_STN6_TX_DN<102>")
		)
		(pad "2" smd rect
			(at 0.2667 0 90)
			(size 0.3048 0.381)
			(layers "F.Cu" "F.Mask" "F.Paste")
			(net "P5E_PEX2_STN6_TX_C_DN<102>")
		)
	)
	(footprint ""
		(layer "F.Cu")
		(at 404.439628 -367.407952)
		(property "Reference" "R6678"
			(at 0 0 0)
			(layer "F.SilkS")
			(hide yes)
			(effects
				(font
					(size 1.27 1.27)
				)
			)
		)
		(property "Value" ""
			(at 0 0 0)
			(layer "F.Fab")
			(effects
				(font
					(size 1.27 1.27)
				)
			)
		)
		(duplicate_pad_numbers_are_jumpers no)
		(fp_line
			(start -0.7874 -0.4064)
			(end 0.7874 -0.4064)
			(stroke
				(width 0.1524)
				(type default)
			)
			(layer "F.SilkS")
		)
		(fp_line
			(start -0.7874 0.4064)
			(end -0.7874 -0.4064)
			(stroke
				(width 0.1524)
				(type default)
			)
			(layer "F.SilkS")
		)
		(fp_line
			(start 0.7874 -0.4064)
			(end 0.7874 0.4064)
			(stroke
				(width 0.1524)
				(type default)
			)
			(layer "F.SilkS")
		)
		(fp_line
			(start 0.7874 0.4064)
			(end -0.7874 0.4064)
			(stroke
				(width 0.1524)
				(type default)
			)
			(layer "F.SilkS")
		)
		(fp_line
			(start -0.67945 -0.305054)
			(end -0.12065 -0.305054)
			(stroke
				(width 0.1)
				(type default)
			)
			(layer "F.Fab")
		)
		(fp_line
			(start -0.67945 0.3048)
			(end -0.67945 -0.305054)
			(stroke
				(width 0.1)
				(type default)
			)
			(layer "F.Fab")
		)
		(fp_line
			(start -0.12065 -0.305054)
			(end -0.12065 -0.2794)
			(stroke
				(width 0.1)
				(type default)
			)
			(layer "F.Fab")
		)
		(fp_line
			(start -0.12065 -0.2794)
			(end 0.12065 -0.2794)
			(stroke
				(width 0.1)
				(type default)
			)
			(layer "F.Fab")
		)
		(fp_line
			(start -0.12065 0.2794)
			(end -0.12065 0.3048)
			(stroke
				(width 0.1)
				(type default)
			)
			(layer "F.Fab")
		)
		(fp_line
			(start -0.12065 0.3048)
			(end -0.67945 0.3048)
			(stroke
				(width 0.1)
				(type default)
			)
			(layer "F.Fab")
		)
		(fp_line
			(start 0.120396 0.2794)
			(end -0.12065 0.2794)
			(stroke
				(width 0.1)
				(type default)
			)
			(layer "F.Fab")
		)
		(fp_line
			(start 0.120396 0.3048)
			(end 0.120396 0.2794)
			(stroke
				(width 0.1)
				(type default)
			)
			(layer "F.Fab")
		)
		(fp_line
			(start 0.12065 -0.3048)
			(end 0.67945 -0.3048)
			(stroke
				(width 0.1)
				(type default)
			)
			(layer "F.Fab")
		)
		(fp_line
			(start 0.12065 -0.2794)
			(end 0.12065 -0.3048)
			(stroke
				(width 0.1)
				(type default)
			)
			(layer "F.Fab")
		)
		(fp_line
			(start 0.67945 -0.3048)
			(end 0.67945 0.3048)
			(stroke
				(width 0.1)
				(type default)
			)
			(layer "F.Fab")
		)
		(fp_line
			(start 0.67945 0.3048)
			(end 0.120396 0.3048)
			(stroke
				(width 0.1)
				(type default)
			)
			(layer "F.Fab")
		)
		(pad "1" smd circle
			(at -0.40005 0)
			(size 0 0)
			(layers "F.Cu" "F.Mask" "F.Paste")
			(net "GPU_3V3IO_RSVD1_ISO")
		)
		(pad "2" smd circle
			(at 0.40005 0)
			(size 0 0)
			(layers "F.Cu" "F.Mask" "F.Paste")
			(net "P3V3_AUX")
		)
	)
	(footprint ""
		(layer "F.Cu")
		(at 150.319486 -390.398254 -90)
		(property "Reference" "R1839"
			(at 0 0 270)
			(layer "F.SilkS")
			(hide yes)
			(effects
				(font
					(size 1.27 1.27)
				)
			)
		)
		(property "Value" ""
			(at 0 0 270)
			(layer "F.Fab")
			(effects
				(font
					(size 1.27 1.27)
				)
			)
		)
		(duplicate_pad_numbers_are_jumpers no)
		(fp_line
			(start -0.7874 0.4064)
			(end -0.7874 -0.4064)
			(stroke
				(width 0.1524)
				(type default)
			)
			(layer "F.SilkS")
		)
		(fp_line
			(start 0.7874 0.4064)
			(end -0.7874 0.4064)
			(stroke
				(width 0.1524)
				(type default)
			)
			(layer "F.SilkS")
		)
		(fp_line
			(start -0.7874 -0.4064)
			(end 0.7874 -0.4064)
			(stroke
				(width 0.1524)
				(type default)
			)
			(layer "F.SilkS")
		)
		(fp_line
			(start 0.7874 -0.4064)
			(end 0.7874 0.4064)
			(stroke
				(width 0.1524)
				(type default)
			)
			(layer "F.SilkS")
		)
		(fp_line
			(start -0.67945 0.3048)
			(end -0.67945 -0.305054)
			(stroke
				(width 0.1)
				(type default)
			)
			(layer "F.Fab")
		)
		(fp_line
			(start -0.12065 0.3048)
			(end -0.67945 0.3048)
			(stroke
				(width 0.1)
				(type default)
			)
			(layer "F.Fab")
		)
		(fp_line
			(start 0.120396 0.3048)
			(end 0.120396 0.2794)
			(stroke
				(width 0.1)
				(type default)
			)
			(layer "F.Fab")
		)
		(fp_line
			(start 0.67945 0.3048)
			(end 0.120396 0.3048)
			(stroke
				(width 0.1)
				(type default)
			)
			(layer "F.Fab")
		)
		(fp_line
			(start -0.12065 0.2794)
			(end -0.12065 0.3048)
			(stroke
				(width 0.1)
				(type default)
			)
			(layer "F.Fab")
		)
		(fp_line
			(start 0.120396 0.2794)
			(end -0.12065 0.2794)
			(stroke
				(width 0.1)
				(type default)
			)
			(layer "F.Fab")
		)
		(fp_line
			(start -0.12065 -0.2794)
			(end 0.12065 -0.2794)
			(stroke
				(width 0.1)
				(type default)
			)
			(layer "F.Fab")
		)
		(fp_line
			(start 0.12065 -0.2794)
			(end 0.12065 -0.3048)
			(stroke
				(width 0.1)
				(type default)
			)
			(layer "F.Fab")
		)
		(fp_line
			(start 0.12065 -0.3048)
			(end 0.67945 -0.3048)
			(stroke
				(width 0.1)
				(type default)
			)
			(layer "F.Fab")
		)
		(fp_line
			(start 0.67945 -0.3048)
			(end 0.67945 0.3048)
			(stroke
				(width 0.1)
				(type default)
			)
			(layer "F.Fab")
		)
		(fp_line
			(start -0.67945 -0.305054)
			(end -0.12065 -0.305054)
			(stroke
				(width 0.1)
				(type default)
			)
			(layer "F.Fab")
		)
		(fp_line
			(start -0.12065 -0.305054)
			(end -0.12065 -0.2794)
			(stroke
				(width 0.1)
				(type default)
			)
			(layer "F.Fab")
		)
		(pad "1" smd circle
			(at -0.40005 0 270)
			(size 0 0)
			(layers "F.Cu" "F.Mask" "F.Paste")
			(net "PRSNT_GPU_HMC_R_N")
		)
		(pad "2" smd circle
			(at 0.40005 0 270)
			(size 0 0)
			(layers "F.Cu" "F.Mask" "F.Paste")
			(net "PRSNT_GPU_HMC_N")
		)
	)
	(footprint ""
		(layer "F.Cu")
		(at 9.62914 -310.00827 180)
		(property "Reference" "PC204"
			(at 0 0 180)
			(layer "F.SilkS")
			(hide yes)
			(effects
				(font
					(size 1.27 1.27)
				)
			)
		)
		(property "Value" ""
			(at 0 0 180)
			(layer "F.Fab")
			(effects
				(font
					(size 1.27 1.27)
				)
			)
		)
		(duplicate_pad_numbers_are_jumpers no)
		(fp_line
			(start 1.524 0.762)
			(end -1.524 0.762)
			(stroke
				(width 0.1524)
				(type default)
			)
			(layer "F.SilkS")
		)
		(fp_line
			(start 1.524 -0.762)
			(end 1.524 0.762)
			(stroke
				(width 0.1524)
				(type default)
			)
			(layer "F.SilkS")
		)
		(fp_line
			(start -1.524 0.762)
			(end -1.524 -0.762)
			(stroke
				(width 0.1524)
				(type default)
			)
			(layer "F.SilkS")
		)
		(fp_line
			(start -1.524 -0.762)
			(end 1.524 -0.762)
			(stroke
				(width 0.1524)
				(type default)
			)
			(layer "F.SilkS")
		)
		(fp_line
			(start 1.1049 0.724916)
			(end 1.1049 -0.724916)
			(stroke
				(width 0.1)
				(type default)
			)
			(layer "F.Fab")
		)
		(fp_line
			(start 1.1049 -0.724916)
			(end -1.1049 -0.724916)
			(stroke
				(width 0.1)
				(type default)
			)
			(layer "F.Fab")
		)
		(fp_line
			(start -1.1049 0.724916)
			(end 1.1049 0.724916)
			(stroke
				(width 0.1)
				(type default)
			)
			(layer "F.Fab")
		)
		(fp_line
			(start -1.1049 -0.724916)
			(end -1.1049 0.724916)
			(stroke
				(width 0.1)
				(type default)
			)
			(layer "F.Fab")
		)
		(pad "1" smd rect
			(at -0.889 0)
			(size 1.016 1.27)
			(layers "F.Cu" "F.Mask" "F.Paste")
			(net "SW_P12V_P1V25_PEX0_FLT")
		)
		(pad "2" smd rect
			(at 0.889 0)
			(size 1.016 1.27)
			(layers "F.Cu" "F.Mask" "F.Paste")
			(net "GND")
		)
	)
	(footprint ""
		(layer "F.Cu")
		(at 342.646 -205.232 -90)
		(property "Reference" "R4138"
			(at 0 0 270)
			(layer "F.SilkS")
			(hide yes)
			(effects
				(font
					(size 1.27 1.27)
				)
			)
		)
		(property "Value" ""
			(at 0 0 270)
			(layer "F.Fab")
			(effects
				(font
					(size 1.27 1.27)
				)
			)
		)
		(duplicate_pad_numbers_are_jumpers no)
		(fp_line
			(start -0.7874 0.4064)
			(end -0.7874 -0.4064)
			(stroke
				(width 0.1524)
				(type default)
			)
			(layer "F.SilkS")
		)
		(fp_line
			(start 0.7874 0.4064)
			(end -0.7874 0.4064)
			(stroke
				(width 0.1524)
				(type default)
			)
			(layer "F.SilkS")
		)
		(fp_line
			(start -0.7874 -0.4064)
			(end 0.7874 -0.4064)
			(stroke
				(width 0.1524)
				(type default)
			)
			(layer "F.SilkS")
		)
		(fp_line
			(start 0.7874 -0.4064)
			(end 0.7874 0.4064)
			(stroke
				(width 0.1524)
				(type default)
			)
			(layer "F.SilkS")
		)
		(fp_line
			(start -0.67945 0.3048)
			(end -0.67945 -0.305054)
			(stroke
				(width 0.1)
				(type default)
			)
			(layer "F.Fab")
		)
		(fp_line
			(start -0.12065 0.3048)
			(end -0.67945 0.3048)
			(stroke
				(width 0.1)
				(type default)
			)
			(layer "F.Fab")
		)
		(fp_line
			(start 0.120396 0.3048)
			(end 0.120396 0.2794)
			(stroke
				(width 0.1)
				(type default)
			)
			(layer "F.Fab")
		)
		(fp_line
			(start 0.67945 0.3048)
			(end 0.120396 0.3048)
			(stroke
				(width 0.1)
				(type default)
			)
			(layer "F.Fab")
		)
		(fp_line
			(start -0.12065 0.2794)
			(end -0.12065 0.3048)
			(stroke
				(width 0.1)
				(type default)
			)
			(layer "F.Fab")
		)
		(fp_line
			(start 0.120396 0.2794)
			(end -0.12065 0.2794)
			(stroke
				(width 0.1)
				(type default)
			)
			(layer "F.Fab")
		)
		(fp_line
			(start -0.12065 -0.2794)
			(end 0.12065 -0.2794)
			(stroke
				(width 0.1)
				(type default)
			)
			(layer "F.Fab")
		)
		(fp_line
			(start 0.12065 -0.2794)
			(end 0.12065 -0.3048)
			(stroke
				(width 0.1)
				(type default)
			)
			(layer "F.Fab")
		)
		(fp_line
			(start 0.12065 -0.3048)
			(end 0.67945 -0.3048)
			(stroke
				(width 0.1)
				(type default)
			)
			(layer "F.Fab")
		)
		(fp_line
			(start 0.67945 -0.3048)
			(end 0.67945 0.3048)
			(stroke
				(width 0.1)
				(type default)
			)
			(layer "F.Fab")
		)
		(fp_line
			(start -0.67945 -0.305054)
			(end -0.12065 -0.305054)
			(stroke
				(width 0.1)
				(type default)
			)
			(layer "F.Fab")
		)
		(fp_line
			(start -0.12065 -0.305054)
			(end -0.12065 -0.2794)
			(stroke
				(width 0.1)
				(type default)
			)
			(layer "F.Fab")
		)
		(pad "1" smd circle
			(at -0.40005 0 270)
			(size 0 0)
			(layers "F.Cu" "F.Mask" "F.Paste")
			(net "SSD13_CLK_EN_N")
		)
		(pad "2" smd circle
			(at 0.40005 0 270)
			(size 0 0)
			(layers "F.Cu" "F.Mask" "F.Paste")
			(net "SSD13_CLK_EN_R_N")
		)
	)
	(footprint ""
		(layer "F.Cu")
		(at 93.066108 -306.074572 90)
		(property "Reference" "R4179"
			(at 0 0 90)
			(layer "F.SilkS")
			(hide yes)
			(effects
				(font
					(size 1.27 1.27)
				)
			)
		)
		(property "Value" ""
			(at 0 0 90)
			(layer "F.Fab")
			(effects
				(font
					(size 1.27 1.27)
				)
			)
		)
		(duplicate_pad_numbers_are_jumpers no)
		(fp_line
			(start 0.7874 -0.4064)
			(end 0.7874 0.4064)
			(stroke
				(width 0.1524)
				(type default)
			)
			(layer "F.SilkS")
		)
		(fp_line
			(start -0.7874 -0.4064)
			(end 0.7874 -0.4064)
			(stroke
				(width 0.1524)
				(type default)
			)
			(layer "F.SilkS")
		)
		(fp_line
			(start 0.7874 0.4064)
			(end -0.7874 0.4064)
			(stroke
				(width 0.1524)
				(type default)
			)
			(layer "F.SilkS")
		)
		(fp_line
			(start -0.7874 0.4064)
			(end -0.7874 -0.4064)
			(stroke
				(width 0.1524)
				(type default)
			)
			(layer "F.SilkS")
		)
		(fp_line
			(start -0.12065 -0.305054)
			(end -0.12065 -0.2794)
			(stroke
				(width 0.1)
				(type default)
			)
			(layer "F.Fab")
		)
		(fp_line
			(start -0.67945 -0.305054)
			(end -0.12065 -0.305054)
			(stroke
				(width 0.1)
				(type default)
			)
			(layer "F.Fab")
		)
		(fp_line
			(start 0.67945 -0.3048)
			(end 0.67945 0.3048)
			(stroke
				(width 0.1)
				(type default)
			)
			(layer "F.Fab")
		)
		(fp_line
			(start 0.12065 -0.3048)
			(end 0.67945 -0.3048)
			(stroke
				(width 0.1)
				(type default)
			)
			(layer "F.Fab")
		)
		(fp_line
			(start 0.12065 -0.2794)
			(end 0.12065 -0.3048)
			(stroke
				(width 0.1)
				(type default)
			)
			(layer "F.Fab")
		)
		(fp_line
			(start -0.12065 -0.2794)
			(end 0.12065 -0.2794)
			(stroke
				(width 0.1)
				(type default)
			)
			(layer "F.Fab")
		)
		(fp_line
			(start 0.120396 0.2794)
			(end -0.12065 0.2794)
			(stroke
				(width 0.1)
				(type default)
			)
			(layer "F.Fab")
		)
		(fp_line
			(start -0.12065 0.2794)
			(end -0.12065 0.3048)
			(stroke
				(width 0.1)
				(type default)
			)
			(layer "F.Fab")
		)
		(fp_line
			(start 0.67945 0.3048)
			(end 0.120396 0.3048)
			(stroke
				(width 0.1)
				(type default)
			)
			(layer "F.Fab")
		)
		(fp_line
			(start 0.120396 0.3048)
			(end 0.120396 0.2794)
			(stroke
				(width 0.1)
				(type default)
			)
			(layer "F.Fab")
		)
		(fp_line
			(start -0.12065 0.3048)
			(end -0.67945 0.3048)
			(stroke
				(width 0.1)
				(type default)
			)
			(layer "F.Fab")
		)
		(fp_line
			(start -0.67945 0.3048)
			(end -0.67945 -0.305054)
			(stroke
				(width 0.1)
				(type default)
			)
			(layer "F.Fab")
		)
		(pad "1" smd circle
			(at -0.40005 0 90)
			(size 0 0)
			(layers "F.Cu" "F.Mask" "F.Paste")
			(net "PEX0_EXT_GPIO_LATCH_N")
		)
		(pad "2" smd circle
			(at 0.40005 0 90)
			(size 0 0)
			(layers "F.Cu" "F.Mask" "F.Paste")
			(net "P1V8_PEX")
		)
	)
	(footprint ""
		(layer "F.Cu")
		(at 436.588154 -100.459032 90)
		(property "Reference" "R766"
			(at 0 0 90)
			(layer "F.SilkS")
			(hide yes)
			(effects
				(font
					(size 1.27 1.27)
				)
			)
		)
		(property "Value" ""
			(at 0 0 90)
			(layer "F.Fab")
			(effects
				(font
					(size 1.27 1.27)
				)
			)
		)
		(duplicate_pad_numbers_are_jumpers no)
		(fp_line
			(start 0.7874 -0.4064)
			(end 0.7874 0.4064)
			(stroke
				(width 0.1524)
				(type default)
			)
			(layer "F.SilkS")
		)
		(fp_line
			(start -0.7874 -0.4064)
			(end 0.7874 -0.4064)
			(stroke
				(width 0.1524)
				(type default)
			)
			(layer "F.SilkS")
		)
		(fp_line
			(start 0.7874 0.4064)
			(end -0.7874 0.4064)
			(stroke
				(width 0.1524)
				(type default)
			)
			(layer "F.SilkS")
		)
		(fp_line
			(start -0.7874 0.4064)
			(end -0.7874 -0.4064)
			(stroke
				(width 0.1524)
				(type default)
			)
			(layer "F.SilkS")
		)
		(fp_line
			(start -0.12065 -0.305054)
			(end -0.12065 -0.2794)
			(stroke
				(width 0.1)
				(type default)
			)
			(layer "F.Fab")
		)
		(fp_line
			(start -0.67945 -0.305054)
			(end -0.12065 -0.305054)
			(stroke
				(width 0.1)
				(type default)
			)
			(layer "F.Fab")
		)
		(fp_line
			(start 0.67945 -0.3048)
			(end 0.67945 0.3048)
			(stroke
				(width 0.1)
				(type default)
			)
			(layer "F.Fab")
		)
		(fp_line
			(start 0.12065 -0.3048)
			(end 0.67945 -0.3048)
			(stroke
				(width 0.1)
				(type default)
			)
			(layer "F.Fab")
		)
		(fp_line
			(start 0.12065 -0.2794)
			(end 0.12065 -0.3048)
			(stroke
				(width 0.1)
				(type default)
			)
			(layer "F.Fab")
		)
		(fp_line
			(start -0.12065 -0.2794)
			(end 0.12065 -0.2794)
			(stroke
				(width 0.1)
				(type default)
			)
			(layer "F.Fab")
		)
		(fp_line
			(start 0.120396 0.2794)
			(end -0.12065 0.2794)
			(stroke
				(width 0.1)
				(type default)
			)
			(layer "F.Fab")
		)
		(fp_line
			(start -0.12065 0.2794)
			(end -0.12065 0.3048)
			(stroke
				(width 0.1)
				(type default)
			)
			(layer "F.Fab")
		)
		(fp_line
			(start 0.67945 0.3048)
			(end 0.120396 0.3048)
			(stroke
				(width 0.1)
				(type default)
			)
			(layer "F.Fab")
		)
		(fp_line
			(start 0.120396 0.3048)
			(end 0.120396 0.2794)
			(stroke
				(width 0.1)
				(type default)
			)
			(layer "F.Fab")
		)
		(fp_line
			(start -0.12065 0.3048)
			(end -0.67945 0.3048)
			(stroke
				(width 0.1)
				(type default)
			)
			(layer "F.Fab")
		)
		(fp_line
			(start -0.67945 0.3048)
			(end -0.67945 -0.305054)
			(stroke
				(width 0.1)
				(type default)
			)
			(layer "F.Fab")
		)
		(pad "1" smd circle
			(at -0.40005 0 90)
			(size 0 0)
			(layers "F.Cu" "F.Mask" "F.Paste")
			(net "P12V_NIC7_R")
		)
		(pad "2" smd circle
			(at 0.40005 0 90)
			(size 0 0)
			(layers "F.Cu" "F.Mask" "F.Paste")
			(net "P12V_NIC7_VIN_P")
		)
	)
	(footprint ""
		(layer "F.Cu")
		(at 338.074 -145.923 180)
		(property "Reference" "R4833"
			(at 0 0 180)
			(layer "F.SilkS")
			(hide yes)
			(effects
				(font
					(size 1.27 1.27)
				)
			)
		)
		(property "Value" ""
			(at 0 0 180)
			(layer "F.Fab")
			(effects
				(font
					(size 1.27 1.27)
				)
			)
		)
		(duplicate_pad_numbers_are_jumpers no)
		(fp_line
			(start 0.7874 0.4064)
			(end -0.7874 0.4064)
			(stroke
				(width 0.1524)
				(type default)
			)
			(layer "F.SilkS")
		)
		(fp_line
			(start 0.7874 -0.4064)
			(end 0.7874 0.4064)
			(stroke
				(width 0.1524)
				(type default)
			)
			(layer "F.SilkS")
		)
		(fp_line
			(start -0.7874 0.4064)
			(end -0.7874 -0.4064)
			(stroke
				(width 0.1524)
				(type default)
			)
			(layer "F.SilkS")
		)
		(fp_line
			(start -0.7874 -0.4064)
			(end 0.7874 -0.4064)
			(stroke
				(width 0.1524)
				(type default)
			)
			(layer "F.SilkS")
		)
		(fp_line
			(start 0.67945 0.3048)
			(end 0.120396 0.3048)
			(stroke
				(width 0.1)
				(type default)
			)
			(layer "F.Fab")
		)
		(fp_line
			(start 0.67945 -0.3048)
			(end 0.67945 0.3048)
			(stroke
				(width 0.1)
				(type default)
			)
			(layer "F.Fab")
		)
		(fp_line
			(start 0.12065 -0.2794)
			(end 0.12065 -0.3048)
			(stroke
				(width 0.1)
				(type default)
			)
			(layer "F.Fab")
		)
		(fp_line
			(start 0.12065 -0.3048)
			(end 0.67945 -0.3048)
			(stroke
				(width 0.1)
				(type default)
			)
			(layer "F.Fab")
		)
		(fp_line
			(start 0.120396 0.3048)
			(end 0.120396 0.2794)
			(stroke
				(width 0.1)
				(type default)
			)
			(layer "F.Fab")
		)
		(fp_line
			(start 0.120396 0.2794)
			(end -0.12065 0.2794)
			(stroke
				(width 0.1)
				(type default)
			)
			(layer "F.Fab")
		)
		(fp_line
			(start -0.12065 0.3048)
			(end -0.67945 0.3048)
			(stroke
				(width 0.1)
				(type default)
			)
			(layer "F.Fab")
		)
		(fp_line
			(start -0.12065 0.2794)
			(end -0.12065 0.3048)
			(stroke
				(width 0.1)
				(type default)
			)
			(layer "F.Fab")
		)
		(fp_line
			(start -0.12065 -0.2794)
			(end 0.12065 -0.2794)
			(stroke
				(width 0.1)
				(type default)
			)
			(layer "F.Fab")
		)
		(fp_line
			(start -0.12065 -0.305054)
			(end -0.12065 -0.2794)
			(stroke
				(width 0.1)
				(type default)
			)
			(layer "F.Fab")
		)
		(fp_line
			(start -0.67945 0.3048)
			(end -0.67945 -0.305054)
			(stroke
				(width 0.1)
				(type default)
			)
			(layer "F.Fab")
		)
		(fp_line
			(start -0.67945 -0.305054)
			(end -0.12065 -0.305054)
			(stroke
				(width 0.1)
				(type default)
			)
			(layer "F.Fab")
		)
		(pad "1" smd circle
			(at -0.40005 0 180)
			(size 0 0)
			(layers "F.Cu" "F.Mask" "F.Paste")
			(net "RST_PEX_SSD14_PERST_N")
		)
		(pad "2" smd circle
			(at 0.40005 0 180)
			(size 0 0)
			(layers "F.Cu" "F.Mask" "F.Paste")
			(net "RST_PEX_SSD14_PERST_R_N")
		)
	)
	(footprint ""
		(layer "F.Cu")
		(at 239.378998 -93.01607 -90)
		(property "Reference" "C2623"
			(at 0 0 270)
			(layer "F.SilkS")
			(hide yes)
			(effects
				(font
					(size 1.27 1.27)
				)
			)
		)
		(property "Value" ""
			(at 0 0 270)
			(layer "F.Fab")
			(effects
				(font
					(size 1.27 1.27)
				)
			)
		)
		(duplicate_pad_numbers_are_jumpers no)
		(fp_line
			(start -0.7874 0.4064)
			(end -0.7874 -0.4064)
			(stroke
				(width 0.1524)
				(type default)
			)
			(layer "F.SilkS")
		)
		(fp_line
			(start 0.7874 0.4064)
			(end -0.7874 0.4064)
			(stroke
				(width 0.1524)
				(type default)
			)
			(layer "F.SilkS")
		)
		(fp_line
			(start -0.7874 -0.4064)
			(end 0.7874 -0.4064)
			(stroke
				(width 0.1524)
				(type default)
			)
			(layer "F.SilkS")
		)
		(fp_line
			(start 0.7874 -0.4064)
			(end 0.7874 0.4064)
			(stroke
				(width 0.1524)
				(type default)
			)
			(layer "F.SilkS")
		)
		(fp_line
			(start -0.67945 0.3048)
			(end -0.67945 -0.305054)
			(stroke
				(width 0.1)
				(type default)
			)
			(layer "F.Fab")
		)
		(fp_line
			(start -0.12065 0.3048)
			(end -0.67945 0.3048)
			(stroke
				(width 0.1)
				(type default)
			)
			(layer "F.Fab")
		)
		(fp_line
			(start 0.120396 0.3048)
			(end 0.120396 0.2794)
			(stroke
				(width 0.1)
				(type default)
			)
			(layer "F.Fab")
		)
		(fp_line
			(start 0.67945 0.3048)
			(end 0.120396 0.3048)
			(stroke
				(width 0.1)
				(type default)
			)
			(layer "F.Fab")
		)
		(fp_line
			(start -0.12065 0.2794)
			(end -0.12065 0.3048)
			(stroke
				(width 0.1)
				(type default)
			)
			(layer "F.Fab")
		)
		(fp_line
			(start 0.120396 0.2794)
			(end -0.12065 0.2794)
			(stroke
				(width 0.1)
				(type default)
			)
			(layer "F.Fab")
		)
		(fp_line
			(start -0.12065 -0.2794)
			(end 0.12065 -0.2794)
			(stroke
				(width 0.1)
				(type default)
			)
			(layer "F.Fab")
		)
		(fp_line
			(start 0.12065 -0.2794)
			(end 0.12065 -0.3048)
			(stroke
				(width 0.1)
				(type default)
			)
			(layer "F.Fab")
		)
		(fp_line
			(start 0.12065 -0.3048)
			(end 0.67945 -0.3048)
			(stroke
				(width 0.1)
				(type default)
			)
			(layer "F.Fab")
		)
		(fp_line
			(start 0.67945 -0.3048)
			(end 0.67945 0.3048)
			(stroke
				(width 0.1)
				(type default)
			)
			(layer "F.Fab")
		)
		(fp_line
			(start -0.67945 -0.305054)
			(end -0.12065 -0.305054)
			(stroke
				(width 0.1)
				(type default)
			)
			(layer "F.Fab")
		)
		(fp_line
			(start -0.12065 -0.305054)
			(end -0.12065 -0.2794)
			(stroke
				(width 0.1)
				(type default)
			)
			(layer "F.Fab")
		)
		(pad "1" smd circle
			(at -0.40005 0 270)
			(size 0 0)
			(layers "F.Cu" "F.Mask" "F.Paste")
			(net "PEX_USB_HUB_XOUT_R")
		)
		(pad "2" smd circle
			(at 0.40005 0 270)
			(size 0 0)
			(layers "F.Cu" "F.Mask" "F.Paste")
			(net "GND")
		)
	)
	(footprint ""
		(layer "F.Cu")
		(at 108.120942 -116.230654 -90)
		(property "Reference" "R904"
			(at 0 0 270)
			(layer "F.SilkS")
			(hide yes)
			(effects
				(font
					(size 1.27 1.27)
				)
			)
		)
		(property "Value" ""
			(at 0 0 270)
			(layer "F.Fab")
			(effects
				(font
					(size 1.27 1.27)
				)
			)
		)
		(duplicate_pad_numbers_are_jumpers no)
		(fp_line
			(start -0.7874 0.4064)
			(end -0.7874 -0.4064)
			(stroke
				(width 0.1524)
				(type default)
			)
			(layer "F.SilkS")
		)
		(fp_line
			(start 0.7874 0.4064)
			(end -0.7874 0.4064)
			(stroke
				(width 0.1524)
				(type default)
			)
			(layer "F.SilkS")
		)
		(fp_line
			(start -0.7874 -0.4064)
			(end 0.7874 -0.4064)
			(stroke
				(width 0.1524)
				(type default)
			)
			(layer "F.SilkS")
		)
		(fp_line
			(start 0.7874 -0.4064)
			(end 0.7874 0.4064)
			(stroke
				(width 0.1524)
				(type default)
			)
			(layer "F.SilkS")
		)
		(fp_line
			(start -0.67945 0.3048)
			(end -0.67945 -0.305054)
			(stroke
				(width 0.1)
				(type default)
			)
			(layer "F.Fab")
		)
		(fp_line
			(start -0.12065 0.3048)
			(end -0.67945 0.3048)
			(stroke
				(width 0.1)
				(type default)
			)
			(layer "F.Fab")
		)
		(fp_line
			(start 0.120396 0.3048)
			(end 0.120396 0.2794)
			(stroke
				(width 0.1)
				(type default)
			)
			(layer "F.Fab")
		)
		(fp_line
			(start 0.67945 0.3048)
			(end 0.120396 0.3048)
			(stroke
				(width 0.1)
				(type default)
			)
			(layer "F.Fab")
		)
		(fp_line
			(start -0.12065 0.2794)
			(end -0.12065 0.3048)
			(stroke
				(width 0.1)
				(type default)
			)
			(layer "F.Fab")
		)
		(fp_line
			(start 0.120396 0.2794)
			(end -0.12065 0.2794)
			(stroke
				(width 0.1)
				(type default)
			)
			(layer "F.Fab")
		)
		(fp_line
			(start -0.12065 -0.2794)
			(end 0.12065 -0.2794)
			(stroke
				(width 0.1)
				(type default)
			)
			(layer "F.Fab")
		)
		(fp_line
			(start 0.12065 -0.2794)
			(end 0.12065 -0.3048)
			(stroke
				(width 0.1)
				(type default)
			)
			(layer "F.Fab")
		)
		(fp_line
			(start 0.12065 -0.3048)
			(end 0.67945 -0.3048)
			(stroke
				(width 0.1)
				(type default)
			)
			(layer "F.Fab")
		)
		(fp_line
			(start 0.67945 -0.3048)
			(end 0.67945 0.3048)
			(stroke
				(width 0.1)
				(type default)
			)
			(layer "F.Fab")
		)
		(fp_line
			(start -0.67945 -0.305054)
			(end -0.12065 -0.305054)
			(stroke
				(width 0.1)
				(type default)
			)
			(layer "F.Fab")
		)
		(fp_line
			(start -0.12065 -0.305054)
			(end -0.12065 -0.2794)
			(stroke
				(width 0.1)
				(type default)
			)
			(layer "F.Fab")
		)
		(pad "1" smd circle
			(at -0.40005 0 270)
			(size 0 0)
			(layers "F.Cu" "F.Mask" "F.Paste")
			(net "P3V3_AUX")
		)
		(pad "2" smd circle
			(at 0.40005 0 270)
			(size 0 0)
			(layers "F.Cu" "F.Mask" "F.Paste")
			(net "PWRGD_P12V_NIC1_CO")
		)
	)
	(footprint ""
		(layer "F.Cu")
		(at 330.71435 -66.32194 90)
		(property "Reference" "R6001"
			(at 0 0 90)
			(layer "F.SilkS")
			(hide yes)
			(effects
				(font
					(size 1.27 1.27)
				)
			)
		)
		(property "Value" ""
			(at 0 0 90)
			(layer "F.Fab")
			(effects
				(font
					(size 1.27 1.27)
				)
			)
		)
		(duplicate_pad_numbers_are_jumpers no)
		(fp_line
			(start 0.7874 -0.4064)
			(end 0.7874 0.4064)
			(stroke
				(width 0.1524)
				(type default)
			)
			(layer "F.SilkS")
		)
		(fp_line
			(start -0.7874 -0.4064)
			(end 0.7874 -0.4064)
			(stroke
				(width 0.1524)
				(type default)
			)
			(layer "F.SilkS")
		)
		(fp_line
			(start 0.7874 0.4064)
			(end -0.7874 0.4064)
			(stroke
				(width 0.1524)
				(type default)
			)
			(layer "F.SilkS")
		)
		(fp_line
			(start -0.7874 0.4064)
			(end -0.7874 -0.4064)
			(stroke
				(width 0.1524)
				(type default)
			)
			(layer "F.SilkS")
		)
		(fp_line
			(start -0.12065 -0.305054)
			(end -0.12065 -0.2794)
			(stroke
				(width 0.1)
				(type default)
			)
			(layer "F.Fab")
		)
		(fp_line
			(start -0.67945 -0.305054)
			(end -0.12065 -0.305054)
			(stroke
				(width 0.1)
				(type default)
			)
			(layer "F.Fab")
		)
		(fp_line
			(start 0.67945 -0.3048)
			(end 0.67945 0.3048)
			(stroke
				(width 0.1)
				(type default)
			)
			(layer "F.Fab")
		)
		(fp_line
			(start 0.12065 -0.3048)
			(end 0.67945 -0.3048)
			(stroke
				(width 0.1)
				(type default)
			)
			(layer "F.Fab")
		)
		(fp_line
			(start 0.12065 -0.2794)
			(end 0.12065 -0.3048)
			(stroke
				(width 0.1)
				(type default)
			)
			(layer "F.Fab")
		)
		(fp_line
			(start -0.12065 -0.2794)
			(end 0.12065 -0.2794)
			(stroke
				(width 0.1)
				(type default)
			)
			(layer "F.Fab")
		)
		(fp_line
			(start 0.120396 0.2794)
			(end -0.12065 0.2794)
			(stroke
				(width 0.1)
				(type default)
			)
			(layer "F.Fab")
		)
		(fp_line
			(start -0.12065 0.2794)
			(end -0.12065 0.3048)
			(stroke
				(width 0.1)
				(type default)
			)
			(layer "F.Fab")
		)
		(fp_line
			(start 0.67945 0.3048)
			(end 0.120396 0.3048)
			(stroke
				(width 0.1)
				(type default)
			)
			(layer "F.Fab")
		)
		(fp_line
			(start 0.120396 0.3048)
			(end 0.120396 0.2794)
			(stroke
				(width 0.1)
				(type default)
			)
			(layer "F.Fab")
		)
		(fp_line
			(start -0.12065 0.3048)
			(end -0.67945 0.3048)
			(stroke
				(width 0.1)
				(type default)
			)
			(layer "F.Fab")
		)
		(fp_line
			(start -0.67945 0.3048)
			(end -0.67945 -0.305054)
			(stroke
				(width 0.1)
				(type default)
			)
			(layer "F.Fab")
		)
		(pad "1" smd circle
			(at -0.40005 0 90)
			(size 0 0)
			(layers "F.Cu" "F.Mask" "F.Paste")
			(net "SSD11_PWR_EN_R")
		)
		(pad "2" smd circle
			(at 0.40005 0 90)
			(size 0 0)
			(layers "F.Cu" "F.Mask" "F.Paste")
			(net "P12V_SSD11_CO_EN")
		)
	)
	(footprint ""
		(layer "F.Cu")
		(at 11.997436 -251.312426 -90)
		(property "Reference" "C4229"
			(at 0 0 270)
			(layer "F.SilkS")
			(hide yes)
			(effects
				(font
					(size 1.27 1.27)
				)
			)
		)
		(property "Value" ""
			(at 0 0 270)
			(layer "F.Fab")
			(effects
				(font
					(size 1.27 1.27)
				)
			)
		)
		(duplicate_pad_numbers_are_jumpers no)
		(fp_line
			(start -1.2954 0.5842)
			(end -1.2954 -0.5842)
			(stroke
				(width 0.1524)
				(type default)
			)
			(layer "F.SilkS")
		)
		(fp_line
			(start 1.2954 0.5842)
			(end -1.2954 0.5842)
			(stroke
				(width 0.1524)
				(type default)
			)
			(layer "F.SilkS")
		)
		(fp_line
			(start -1.2954 -0.5842)
			(end 1.2954 -0.5842)
			(stroke
				(width 0.1524)
				(type default)
			)
			(layer "F.SilkS")
		)
		(fp_line
			(start 1.2954 -0.5842)
			(end 1.2954 0.5842)
			(stroke
				(width 0.1524)
				(type default)
			)
			(layer "F.SilkS")
		)
		(fp_line
			(start -0.8636 0.4572)
			(end -0.8636 0.4064)
			(stroke
				(width 0.1)
				(type default)
			)
			(layer "F.Fab")
		)
		(fp_line
			(start 0.8636 0.4572)
			(end -0.8636 0.4572)
			(stroke
				(width 0.1)
				(type default)
			)
			(layer "F.Fab")
		)
		(fp_line
			(start -1.1938 0.4064)
			(end -1.1938 -0.4064)
			(stroke
				(width 0.1)
				(type default)
			)
			(layer "F.Fab")
		)
		(fp_line
			(start -0.8636 0.4064)
			(end -1.1938 0.4064)
			(stroke
				(width 0.1)
				(type default)
			)
			(layer "F.Fab")
		)
		(fp_line
			(start 0.8636 0.4064)
			(end 0.8636 0.4572)
			(stroke
				(width 0.1)
				(type default)
			)
			(layer "F.Fab")
		)
		(fp_line
			(start 1.1938 0.4064)
			(end 0.8636 0.4064)
			(stroke
				(width 0.1)
				(type default)
			)
			(layer "F.Fab")
		)
		(fp_line
			(start -1.1938 -0.4064)
			(end -0.8636 -0.4064)
			(stroke
				(width 0.1)
				(type default)
			)
			(layer "F.Fab")
		)
		(fp_line
			(start -0.8636 -0.4064)
			(end -0.8636 -0.4572)
			(stroke
				(width 0.1)
				(type default)
			)
			(layer "F.Fab")
		)
		(fp_line
			(start 0.8636 -0.4064)
			(end 1.1938 -0.4064)
			(stroke
				(width 0.1)
				(type default)
			)
			(layer "F.Fab")
		)
		(fp_line
			(start 1.1938 -0.4064)
			(end 1.1938 0.4064)
			(stroke
				(width 0.1)
				(type default)
			)
			(layer "F.Fab")
		)
		(fp_line
			(start -0.8636 -0.4572)
			(end 0.8636 -0.4572)
			(stroke
				(width 0.1)
				(type default)
			)
			(layer "F.Fab")
		)
		(fp_line
			(start 0.8636 -0.4572)
			(end 0.8636 -0.4064)
			(stroke
				(width 0.1)
				(type default)
			)
			(layer "F.Fab")
		)
		(pad "1" smd rect
			(at -0.7366 0 180)
			(size 0.7112 0.8128)
			(layers "F.Cu" "F.Mask" "F.Paste")
			(net "P1V25_SERDES_VDDPLL_PEX0_C3")
		)
		(pad "2" smd rect
			(at 0.7366 0 180)
			(size 0.7112 0.8128)
			(layers "F.Cu" "F.Mask" "F.Paste")
			(net "GND")
		)
	)
	(footprint ""
		(layer "F.Cu")
		(at 57.58942 -63.56223)
		(property "Reference" "Q129"
			(at -0.13462 -1.8669 0)
			(unlocked yes)
			(layer "F.SilkS")
			(effects
				(font
					(size 0.7874 0.5842)
					(thickness 0.1524)
				)
			)
		)
		(property "Value" ""
			(at 0 0 0)
			(layer "F.Fab")
			(effects
				(font
					(size 1.27 1.27)
				)
			)
		)
		(duplicate_pad_numbers_are_jumpers no)
		(fp_line
			(start -1.376172 -1.199896)
			(end -0.508 -1.199896)
			(stroke
				(width 0.1524)
				(type default)
			)
			(layer "F.SilkS")
		)
		(fp_line
			(start -1.376172 1.199896)
			(end -1.376172 -1.199896)
			(stroke
				(width 0.1524)
				(type default)
			)
			(layer "F.SilkS")
		)
		(fp_line
			(start -0.508 -1.199896)
			(end 0 -0.762)
			(stroke
				(width 0.1524)
				(type default)
			)
			(layer "F.SilkS")
		)
		(fp_line
			(start 0 -0.762)
			(end 0.508 -1.199896)
			(stroke
				(width 0.1524)
				(type default)
			)
			(layer "F.SilkS")
		)
		(fp_line
			(start 0.508 -1.199896)
			(end 1.376172 -1.199896)
			(stroke
				(width 0.1524)
				(type default)
			)
			(layer "F.SilkS")
		)
		(fp_line
			(start 1.376172 -1.199896)
			(end 1.376172 1.199896)
			(stroke
				(width 0.1524)
				(type default)
			)
			(layer "F.SilkS")
		)
		(fp_line
			(start 1.376172 1.199896)
			(end -1.376172 1.199896)
			(stroke
				(width 0.1524)
				(type default)
			)
			(layer "F.SilkS")
		)
		(fp_poly
			(pts
				(xy -1.64973 -1.121156) (xy -1.919224 -1.929384) (xy -2.457958 -1.390396)
			)
			(stroke
				(width 0)
				(type default)
			)
			(fill yes)
			(layer "F.SilkS")
		)
		(fp_line
			(start -0.674878 -1.100074)
			(end 0.674878 -1.100074)
			(stroke
				(width 0.1)
				(type default)
			)
			(layer "F.Fab")
		)
		(fp_line
			(start -0.674878 1.100074)
			(end -0.674878 -1.100074)
			(stroke
				(width 0.1)
				(type default)
			)
			(layer "F.Fab")
		)
		(fp_line
			(start 0.674878 -1.100074)
			(end 0.674878 1.100074)
			(stroke
				(width 0.1)
				(type default)
			)
			(layer "F.Fab")
		)
		(fp_line
			(start 0.674878 1.100074)
			(end -0.674878 1.100074)
			(stroke
				(width 0.1)
				(type default)
			)
			(layer "F.Fab")
		)
		(fp_poly
			(pts
				(xy -1.4605 -0.7493) (xy -2.2225 -1.1303) (xy -2.2225 -0.3683)
			)
			(stroke
				(width 0)
				(type default)
			)
			(fill yes)
			(layer "F.Fab")
		)
		(pad "1" smd rect
			(at -0.899922 -0.750062 270)
			(size 0.6096 0.6096)
			(layers "F.Cu" "F.Mask" "F.Paste")
			(net "GND")
		)
		(pad "2" smd rect
			(at -0.899922 0 270)
			(size 0.4064 0.6096)
			(layers "F.Cu" "F.Mask" "F.Paste")
			(net "P12V_SSD2_PG_G1")
		)
		(pad "3" smd rect
			(at -0.899922 0.750062 270)
			(size 0.6096 0.6096)
			(layers "F.Cu" "F.Mask" "F.Paste")
			(net "PWRGD_P12V_SSD2_D")
		)
		(pad "4" smd rect
			(at 0.899922 0.750062 270)
			(size 0.6096 0.6096)
			(layers "F.Cu" "F.Mask" "F.Paste")
			(net "GND")
		)
		(pad "5" smd rect
			(at 0.899922 0 270)
			(size 0.4064 0.6096)
			(layers "F.Cu" "F.Mask" "F.Paste")
			(net "P12V_SSD2_PG_G2")
		)
		(pad "6" smd rect
			(at 0.899922 -0.750062 270)
			(size 0.6096 0.6096)
			(layers "F.Cu" "F.Mask" "F.Paste")
			(net "P12V_SSD2_PG_G2")
		)
	)
	(footprint ""
		(layer "F.Cu")
		(at 298.74718 -196.706236 180)
		(property "Reference" "C2109"
			(at 0 0 180)
			(layer "F.SilkS")
			(hide yes)
			(effects
				(font
					(size 1.27 1.27)
				)
			)
		)
		(property "Value" ""
			(at 0 0 180)
			(layer "F.Fab")
			(effects
				(font
					(size 1.27 1.27)
				)
			)
		)
		(duplicate_pad_numbers_are_jumpers no)
		(fp_line
			(start 0.7874 0.4064)
			(end -0.7874 0.4064)
			(stroke
				(width 0.1524)
				(type default)
			)
			(layer "F.SilkS")
		)
		(fp_line
			(start 0.7874 -0.4064)
			(end 0.7874 0.4064)
			(stroke
				(width 0.1524)
				(type default)
			)
			(layer "F.SilkS")
		)
		(fp_line
			(start -0.7874 0.4064)
			(end -0.7874 -0.4064)
			(stroke
				(width 0.1524)
				(type default)
			)
			(layer "F.SilkS")
		)
		(fp_line
			(start -0.7874 -0.4064)
			(end 0.7874 -0.4064)
			(stroke
				(width 0.1524)
				(type default)
			)
			(layer "F.SilkS")
		)
		(fp_line
			(start 0.67945 0.3048)
			(end 0.120396 0.3048)
			(stroke
				(width 0.1)
				(type default)
			)
			(layer "F.Fab")
		)
		(fp_line
			(start 0.67945 -0.3048)
			(end 0.67945 0.3048)
			(stroke
				(width 0.1)
				(type default)
			)
			(layer "F.Fab")
		)
		(fp_line
			(start 0.12065 -0.2794)
			(end 0.12065 -0.3048)
			(stroke
				(width 0.1)
				(type default)
			)
			(layer "F.Fab")
		)
		(fp_line
			(start 0.12065 -0.3048)
			(end 0.67945 -0.3048)
			(stroke
				(width 0.1)
				(type default)
			)
			(layer "F.Fab")
		)
		(fp_line
			(start 0.120396 0.3048)
			(end 0.120396 0.2794)
			(stroke
				(width 0.1)
				(type default)
			)
			(layer "F.Fab")
		)
		(fp_line
			(start 0.120396 0.2794)
			(end -0.12065 0.2794)
			(stroke
				(width 0.1)
				(type default)
			)
			(layer "F.Fab")
		)
		(fp_line
			(start -0.12065 0.3048)
			(end -0.67945 0.3048)
			(stroke
				(width 0.1)
				(type default)
			)
			(layer "F.Fab")
		)
		(fp_line
			(start -0.12065 0.2794)
			(end -0.12065 0.3048)
			(stroke
				(width 0.1)
				(type default)
			)
			(layer "F.Fab")
		)
		(fp_line
			(start -0.12065 -0.2794)
			(end 0.12065 -0.2794)
			(stroke
				(width 0.1)
				(type default)
			)
			(layer "F.Fab")
		)
		(fp_line
			(start -0.12065 -0.305054)
			(end -0.12065 -0.2794)
			(stroke
				(width 0.1)
				(type default)
			)
			(layer "F.Fab")
		)
		(fp_line
			(start -0.67945 0.3048)
			(end -0.67945 -0.305054)
			(stroke
				(width 0.1)
				(type default)
			)
			(layer "F.Fab")
		)
		(fp_line
			(start -0.67945 -0.305054)
			(end -0.12065 -0.305054)
			(stroke
				(width 0.1)
				(type default)
			)
			(layer "F.Fab")
		)
		(pad "1" smd circle
			(at -0.40005 0 180)
			(size 0 0)
			(layers "F.Cu" "F.Mask" "F.Paste")
			(net "GND")
		)
		(pad "2" smd circle
			(at 0.40005 0 180)
			(size 0 0)
			(layers "F.Cu" "F.Mask" "F.Paste")
			(net "P3V3_AUX")
		)
	)
	(footprint ""
		(layer "F.Cu")
		(at 442.287914 -45.704252 90)
		(property "Reference" "R670"
			(at 0 0 90)
			(layer "F.SilkS")
			(hide yes)
			(effects
				(font
					(size 1.27 1.27)
				)
			)
		)
		(property "Value" ""
			(at 0 0 90)
			(layer "F.Fab")
			(effects
				(font
					(size 1.27 1.27)
				)
			)
		)
		(duplicate_pad_numbers_are_jumpers no)
		(fp_line
			(start 3.937508 -1.8796)
			(end -3.937508 -1.8796)
			(stroke
				(width 0.1524)
				(type default)
			)
			(layer "F.SilkS")
		)
		(fp_line
			(start -3.937508 -1.8796)
			(end -3.937508 1.8796)
			(stroke
				(width 0.1524)
				(type default)
			)
			(layer "F.SilkS")
		)
		(fp_line
			(start 3.937508 1.8796)
			(end 3.937508 -1.8796)
			(stroke
				(width 0.1524)
				(type default)
			)
			(layer "F.SilkS")
		)
		(fp_line
			(start -3.937508 1.8796)
			(end 3.937508 1.8796)
			(stroke
				(width 0.1524)
				(type default)
			)
			(layer "F.SilkS")
		)
		(fp_line
			(start 3.275076 -1.674876)
			(end -3.275076 -1.674876)
			(stroke
				(width 0.1)
				(type default)
			)
			(layer "F.Fab")
		)
		(fp_line
			(start -3.275076 -1.674876)
			(end -3.275076 1.674876)
			(stroke
				(width 0.1)
				(type default)
			)
			(layer "F.Fab")
		)
		(fp_line
			(start 3.275076 1.674876)
			(end 3.275076 -1.674876)
			(stroke
				(width 0.1)
				(type default)
			)
			(layer "F.Fab")
		)
		(fp_line
			(start -3.275076 1.674876)
			(end 3.275076 1.674876)
			(stroke
				(width 0.1)
				(type default)
			)
			(layer "F.Fab")
		)
		(pad "1" smd rect
			(at -2.350008 0 90)
			(size 2.921 3.5052)
			(layers "F.Cu" "F.Mask" "F.Paste")
			(net "P12V_SSD15")
		)
		(pad "2" smd rect
			(at 2.350008 0 90)
			(size 2.921 3.5052)
			(layers "F.Cu" "F.Mask" "F.Paste")
			(net "P12V_SSD15_R")
		)
	)
	(footprint ""
		(layer "F.Cu")
		(at 422.619932 -343.952322 90)
		(property "Reference" "C815"
			(at 0 0 90)
			(layer "F.SilkS")
			(hide yes)
			(effects
				(font
					(size 1.27 1.27)
				)
			)
		)
		(property "Value" ""
			(at 0 0 90)
			(layer "F.Fab")
			(effects
				(font
					(size 1.27 1.27)
				)
			)
		)
		(duplicate_pad_numbers_are_jumpers no)
		(fp_line
			(start 0.299974 -0.150114)
			(end 0.299974 0.150114)
			(stroke
				(width 0.1)
				(type default)
			)
			(layer "F.Fab")
		)
		(fp_line
			(start -0.299974 -0.150114)
			(end 0.299974 -0.150114)
			(stroke
				(width 0.1)
				(type default)
			)
			(layer "F.Fab")
		)
		(fp_line
			(start 0.299974 0.150114)
			(end -0.299974 0.150114)
			(stroke
				(width 0.1)
				(type default)
			)
			(layer "F.Fab")
		)
		(fp_line
			(start -0.299974 0.150114)
			(end -0.299974 -0.150114)
			(stroke
				(width 0.1)
				(type default)
			)
			(layer "F.Fab")
		)
		(pad "1" smd rect
			(at -0.2667 0 90)
			(size 0.3048 0.381)
			(layers "F.Cu" "F.Mask" "F.Paste")
			(net "P5E_PEX3_STN7_TX_DN<117>")
		)
		(pad "2" smd rect
			(at 0.2667 0 90)
			(size 0.3048 0.381)
			(layers "F.Cu" "F.Mask" "F.Paste")
			(net "P5E_PEX3_STN7_TX_C_DN<117>")
		)
	)
	(footprint ""
		(layer "F.Cu")
		(at 312.739532 -138.661648 180)
		(property "Reference" "R294"
			(at 0 0 180)
			(layer "F.SilkS")
			(hide yes)
			(effects
				(font
					(size 1.27 1.27)
				)
			)
		)
		(property "Value" ""
			(at 0 0 180)
			(layer "F.Fab")
			(effects
				(font
					(size 1.27 1.27)
				)
			)
		)
		(duplicate_pad_numbers_are_jumpers no)
		(fp_line
			(start 0.7874 0.4064)
			(end -0.7874 0.4064)
			(stroke
				(width 0.1524)
				(type default)
			)
			(layer "F.SilkS")
		)
		(fp_line
			(start 0.7874 -0.4064)
			(end 0.7874 0.4064)
			(stroke
				(width 0.1524)
				(type default)
			)
			(layer "F.SilkS")
		)
		(fp_line
			(start -0.7874 0.4064)
			(end -0.7874 -0.4064)
			(stroke
				(width 0.1524)
				(type default)
			)
			(layer "F.SilkS")
		)
		(fp_line
			(start -0.7874 -0.4064)
			(end 0.7874 -0.4064)
			(stroke
				(width 0.1524)
				(type default)
			)
			(layer "F.SilkS")
		)
		(fp_line
			(start 0.67945 0.3048)
			(end 0.120396 0.3048)
			(stroke
				(width 0.1)
				(type default)
			)
			(layer "F.Fab")
		)
		(fp_line
			(start 0.67945 -0.3048)
			(end 0.67945 0.3048)
			(stroke
				(width 0.1)
				(type default)
			)
			(layer "F.Fab")
		)
		(fp_line
			(start 0.12065 -0.2794)
			(end 0.12065 -0.3048)
			(stroke
				(width 0.1)
				(type default)
			)
			(layer "F.Fab")
		)
		(fp_line
			(start 0.12065 -0.3048)
			(end 0.67945 -0.3048)
			(stroke
				(width 0.1)
				(type default)
			)
			(layer "F.Fab")
		)
		(fp_line
			(start 0.120396 0.3048)
			(end 0.120396 0.2794)
			(stroke
				(width 0.1)
				(type default)
			)
			(layer "F.Fab")
		)
		(fp_line
			(start 0.120396 0.2794)
			(end -0.12065 0.2794)
			(stroke
				(width 0.1)
				(type default)
			)
			(layer "F.Fab")
		)
		(fp_line
			(start -0.12065 0.3048)
			(end -0.67945 0.3048)
			(stroke
				(width 0.1)
				(type default)
			)
			(layer "F.Fab")
		)
		(fp_line
			(start -0.12065 0.2794)
			(end -0.12065 0.3048)
			(stroke
				(width 0.1)
				(type default)
			)
			(layer "F.Fab")
		)
		(fp_line
			(start -0.12065 -0.2794)
			(end 0.12065 -0.2794)
			(stroke
				(width 0.1)
				(type default)
			)
			(layer "F.Fab")
		)
		(fp_line
			(start -0.12065 -0.305054)
			(end -0.12065 -0.2794)
			(stroke
				(width 0.1)
				(type default)
			)
			(layer "F.Fab")
		)
		(fp_line
			(start -0.67945 0.3048)
			(end -0.67945 -0.305054)
			(stroke
				(width 0.1)
				(type default)
			)
			(layer "F.Fab")
		)
		(fp_line
			(start -0.67945 -0.305054)
			(end -0.12065 -0.305054)
			(stroke
				(width 0.1)
				(type default)
			)
			(layer "F.Fab")
		)
		(pad "1" smd circle
			(at -0.40005 0 180)
			(size 0 0)
			(layers "F.Cu" "F.Mask" "F.Paste")
			(net "PRSNT_NIC5_N")
		)
		(pad "2" smd circle
			(at 0.40005 0 180)
			(size 0 0)
			(layers "F.Cu" "F.Mask" "F.Paste")
			(net "PRSNTB0_NIC5_N")
		)
	)
	(footprint ""
		(layer "F.Cu")
		(at 343.567004 -356.244906 90)
		(property "Reference" "C581"
			(at 0 0 90)
			(layer "F.SilkS")
			(hide yes)
			(effects
				(font
					(size 1.27 1.27)
				)
			)
		)
		(property "Value" ""
			(at 0 0 90)
			(layer "F.Fab")
			(effects
				(font
					(size 1.27 1.27)
				)
			)
		)
		(duplicate_pad_numbers_are_jumpers no)
		(fp_line
			(start 0.299974 -0.150114)
			(end 0.299974 0.150114)
			(stroke
				(width 0.1)
				(type default)
			)
			(layer "F.Fab")
		)
		(fp_line
			(start -0.299974 -0.150114)
			(end 0.299974 -0.150114)
			(stroke
				(width 0.1)
				(type default)
			)
			(layer "F.Fab")
		)
		(fp_line
			(start 0.299974 0.150114)
			(end -0.299974 0.150114)
			(stroke
				(width 0.1)
				(type default)
			)
			(layer "F.Fab")
		)
		(fp_line
			(start -0.299974 0.150114)
			(end -0.299974 -0.150114)
			(stroke
				(width 0.1)
				(type default)
			)
			(layer "F.Fab")
		)
		(pad "1" smd rect
			(at -0.2667 0 90)
			(size 0.3048 0.381)
			(layers "F.Cu" "F.Mask" "F.Paste")
			(net "P5E_PEX2_STN6_TX_DP<96>")
		)
		(pad "2" smd rect
			(at 0.2667 0 90)
			(size 0.3048 0.381)
			(layers "F.Cu" "F.Mask" "F.Paste")
			(net "P5E_PEX2_STN6_TX_C_DP<96>")
		)
	)
	(footprint ""
		(layer "F.Cu")
		(at 172.401992 -343.952322 90)
		(property "Reference" "C2521"
			(at 0 0 90)
			(layer "F.SilkS")
			(hide yes)
			(effects
				(font
					(size 1.27 1.27)
				)
			)
		)
		(property "Value" ""
			(at 0 0 90)
			(layer "F.Fab")
			(effects
				(font
					(size 1.27 1.27)
				)
			)
		)
		(duplicate_pad_numbers_are_jumpers no)
		(fp_line
			(start 0.299974 -0.150114)
			(end 0.299974 0.150114)
			(stroke
				(width 0.1)
				(type default)
			)
			(layer "F.Fab")
		)
		(fp_line
			(start -0.299974 -0.150114)
			(end 0.299974 -0.150114)
			(stroke
				(width 0.1)
				(type default)
			)
			(layer "F.Fab")
		)
		(fp_line
			(start 0.299974 0.150114)
			(end -0.299974 0.150114)
			(stroke
				(width 0.1)
				(type default)
			)
			(layer "F.Fab")
		)
		(fp_line
			(start -0.299974 0.150114)
			(end -0.299974 -0.150114)
			(stroke
				(width 0.1)
				(type default)
			)
			(layer "F.Fab")
		)
		(pad "1" smd rect
			(at -0.2667 0 90)
			(size 0.3048 0.381)
			(layers "F.Cu" "F.Mask" "F.Paste")
			(net "P5E_PEX1_STN4_TX_DN<75>")
		)
		(pad "2" smd rect
			(at 0.2667 0 90)
			(size 0.3048 0.381)
			(layers "F.Cu" "F.Mask" "F.Paste")
			(net "P5E_PEX1_STN4_TX_C_DN<75>")
		)
	)
	(footprint ""
		(layer "F.Cu")
		(at 425.364402 -29.079952 180)
		(property "Reference" "R6212"
			(at 0 0 180)
			(layer "F.SilkS")
			(hide yes)
			(effects
				(font
					(size 1.27 1.27)
				)
			)
		)
		(property "Value" ""
			(at 0 0 180)
			(layer "F.Fab")
			(effects
				(font
					(size 1.27 1.27)
				)
			)
		)
		(duplicate_pad_numbers_are_jumpers no)
		(fp_line
			(start 0.7874 0.4064)
			(end -0.7874 0.4064)
			(stroke
				(width 0.1524)
				(type default)
			)
			(layer "F.SilkS")
		)
		(fp_line
			(start 0.7874 -0.4064)
			(end 0.7874 0.4064)
			(stroke
				(width 0.1524)
				(type default)
			)
			(layer "F.SilkS")
		)
		(fp_line
			(start -0.7874 0.4064)
			(end -0.7874 -0.4064)
			(stroke
				(width 0.1524)
				(type default)
			)
			(layer "F.SilkS")
		)
		(fp_line
			(start -0.7874 -0.4064)
			(end 0.7874 -0.4064)
			(stroke
				(width 0.1524)
				(type default)
			)
			(layer "F.SilkS")
		)
		(fp_line
			(start 0.67945 0.3048)
			(end 0.120396 0.3048)
			(stroke
				(width 0.1)
				(type default)
			)
			(layer "F.Fab")
		)
		(fp_line
			(start 0.67945 -0.3048)
			(end 0.67945 0.3048)
			(stroke
				(width 0.1)
				(type default)
			)
			(layer "F.Fab")
		)
		(fp_line
			(start 0.12065 -0.2794)
			(end 0.12065 -0.3048)
			(stroke
				(width 0.1)
				(type default)
			)
			(layer "F.Fab")
		)
		(fp_line
			(start 0.12065 -0.3048)
			(end 0.67945 -0.3048)
			(stroke
				(width 0.1)
				(type default)
			)
			(layer "F.Fab")
		)
		(fp_line
			(start 0.120396 0.3048)
			(end 0.120396 0.2794)
			(stroke
				(width 0.1)
				(type default)
			)
			(layer "F.Fab")
		)
		(fp_line
			(start 0.120396 0.2794)
			(end -0.12065 0.2794)
			(stroke
				(width 0.1)
				(type default)
			)
			(layer "F.Fab")
		)
		(fp_line
			(start -0.12065 0.3048)
			(end -0.67945 0.3048)
			(stroke
				(width 0.1)
				(type default)
			)
			(layer "F.Fab")
		)
		(fp_line
			(start -0.12065 0.2794)
			(end -0.12065 0.3048)
			(stroke
				(width 0.1)
				(type default)
			)
			(layer "F.Fab")
		)
		(fp_line
			(start -0.12065 -0.2794)
			(end 0.12065 -0.2794)
			(stroke
				(width 0.1)
				(type default)
			)
			(layer "F.Fab")
		)
		(fp_line
			(start -0.12065 -0.305054)
			(end -0.12065 -0.2794)
			(stroke
				(width 0.1)
				(type default)
			)
			(layer "F.Fab")
		)
		(fp_line
			(start -0.67945 0.3048)
			(end -0.67945 -0.305054)
			(stroke
				(width 0.1)
				(type default)
			)
			(layer "F.Fab")
		)
		(fp_line
			(start -0.67945 -0.305054)
			(end -0.12065 -0.305054)
			(stroke
				(width 0.1)
				(type default)
			)
			(layer "F.Fab")
		)
		(pad "1" smd circle
			(at -0.40005 0 180)
			(size 0 0)
			(layers "F.Cu" "F.Mask" "F.Paste")
			(net "GND")
		)
		(pad "2" smd circle
			(at 0.40005 0 180)
			(size 0 0)
			(layers "F.Cu" "F.Mask" "F.Paste")
			(net "SSD14_PWRDIS_R")
		)
	)
	(footprint ""
		(layer "F.Cu")
		(at 323.975222 -235.075222 90)
		(property "Reference" "R4387"
			(at 0 0 90)
			(layer "F.SilkS")
			(hide yes)
			(effects
				(font
					(size 1.27 1.27)
				)
			)
		)
		(property "Value" ""
			(at 0 0 90)
			(layer "F.Fab")
			(effects
				(font
					(size 1.27 1.27)
				)
			)
		)
		(duplicate_pad_numbers_are_jumpers no)
		(fp_line
			(start 0.7874 -0.4064)
			(end 0.7874 0.4064)
			(stroke
				(width 0.1524)
				(type default)
			)
			(layer "F.SilkS")
		)
		(fp_line
			(start -0.7874 -0.4064)
			(end 0.7874 -0.4064)
			(stroke
				(width 0.1524)
				(type default)
			)
			(layer "F.SilkS")
		)
		(fp_line
			(start 0.7874 0.4064)
			(end -0.7874 0.4064)
			(stroke
				(width 0.1524)
				(type default)
			)
			(layer "F.SilkS")
		)
		(fp_line
			(start -0.7874 0.4064)
			(end -0.7874 -0.4064)
			(stroke
				(width 0.1524)
				(type default)
			)
			(layer "F.SilkS")
		)
		(fp_line
			(start -0.12065 -0.305054)
			(end -0.12065 -0.2794)
			(stroke
				(width 0.1)
				(type default)
			)
			(layer "F.Fab")
		)
		(fp_line
			(start -0.67945 -0.305054)
			(end -0.12065 -0.305054)
			(stroke
				(width 0.1)
				(type default)
			)
			(layer "F.Fab")
		)
		(fp_line
			(start 0.67945 -0.3048)
			(end 0.67945 0.3048)
			(stroke
				(width 0.1)
				(type default)
			)
			(layer "F.Fab")
		)
		(fp_line
			(start 0.12065 -0.3048)
			(end 0.67945 -0.3048)
			(stroke
				(width 0.1)
				(type default)
			)
			(layer "F.Fab")
		)
		(fp_line
			(start 0.12065 -0.2794)
			(end 0.12065 -0.3048)
			(stroke
				(width 0.1)
				(type default)
			)
			(layer "F.Fab")
		)
		(fp_line
			(start -0.12065 -0.2794)
			(end 0.12065 -0.2794)
			(stroke
				(width 0.1)
				(type default)
			)
			(layer "F.Fab")
		)
		(fp_line
			(start 0.120396 0.2794)
			(end -0.12065 0.2794)
			(stroke
				(width 0.1)
				(type default)
			)
			(layer "F.Fab")
		)
		(fp_line
			(start -0.12065 0.2794)
			(end -0.12065 0.3048)
			(stroke
				(width 0.1)
				(type default)
			)
			(layer "F.Fab")
		)
		(fp_line
			(start 0.67945 0.3048)
			(end 0.120396 0.3048)
			(stroke
				(width 0.1)
				(type default)
			)
			(layer "F.Fab")
		)
		(fp_line
			(start 0.120396 0.3048)
			(end 0.120396 0.2794)
			(stroke
				(width 0.1)
				(type default)
			)
			(layer "F.Fab")
		)
		(fp_line
			(start -0.12065 0.3048)
			(end -0.67945 0.3048)
			(stroke
				(width 0.1)
				(type default)
			)
			(layer "F.Fab")
		)
		(fp_line
			(start -0.67945 0.3048)
			(end -0.67945 -0.305054)
			(stroke
				(width 0.1)
				(type default)
			)
			(layer "F.Fab")
		)
		(pad "1" smd circle
			(at -0.40005 0 90)
			(size 0 0)
			(layers "F.Cu" "F.Mask" "F.Paste")
			(net "RST_PEX_SYS_BUF_R_N")
		)
		(pad "2" smd circle
			(at 0.40005 0 90)
			(size 0 0)
			(layers "F.Cu" "F.Mask" "F.Paste")
			(net "RST_PEX0_SYS_N")
		)
	)
	(footprint ""
		(layer "F.Cu")
		(at 15.691866 -255.046734 -90)
		(property "Reference" "R6466"
			(at 0 0 270)
			(layer "F.SilkS")
			(hide yes)
			(effects
				(font
					(size 1.27 1.27)
				)
			)
		)
		(property "Value" ""
			(at 0 0 270)
			(layer "F.Fab")
			(effects
				(font
					(size 1.27 1.27)
				)
			)
		)
		(duplicate_pad_numbers_are_jumpers no)
		(fp_line
			(start -0.7874 0.4064)
			(end -0.7874 -0.4064)
			(stroke
				(width 0.1524)
				(type default)
			)
			(layer "F.SilkS")
		)
		(fp_line
			(start 0.7874 0.4064)
			(end -0.7874 0.4064)
			(stroke
				(width 0.1524)
				(type default)
			)
			(layer "F.SilkS")
		)
		(fp_line
			(start -0.7874 -0.4064)
			(end 0.7874 -0.4064)
			(stroke
				(width 0.1524)
				(type default)
			)
			(layer "F.SilkS")
		)
		(fp_line
			(start 0.7874 -0.4064)
			(end 0.7874 0.4064)
			(stroke
				(width 0.1524)
				(type default)
			)
			(layer "F.SilkS")
		)
		(fp_line
			(start -0.67945 0.3048)
			(end -0.67945 -0.305054)
			(stroke
				(width 0.1)
				(type default)
			)
			(layer "F.Fab")
		)
		(fp_line
			(start -0.12065 0.3048)
			(end -0.67945 0.3048)
			(stroke
				(width 0.1)
				(type default)
			)
			(layer "F.Fab")
		)
		(fp_line
			(start 0.120396 0.3048)
			(end 0.120396 0.2794)
			(stroke
				(width 0.1)
				(type default)
			)
			(layer "F.Fab")
		)
		(fp_line
			(start 0.67945 0.3048)
			(end 0.120396 0.3048)
			(stroke
				(width 0.1)
				(type default)
			)
			(layer "F.Fab")
		)
		(fp_line
			(start -0.12065 0.2794)
			(end -0.12065 0.3048)
			(stroke
				(width 0.1)
				(type default)
			)
			(layer "F.Fab")
		)
		(fp_line
			(start 0.120396 0.2794)
			(end -0.12065 0.2794)
			(stroke
				(width 0.1)
				(type default)
			)
			(layer "F.Fab")
		)
		(fp_line
			(start -0.12065 -0.2794)
			(end 0.12065 -0.2794)
			(stroke
				(width 0.1)
				(type default)
			)
			(layer "F.Fab")
		)
		(fp_line
			(start 0.12065 -0.2794)
			(end 0.12065 -0.3048)
			(stroke
				(width 0.1)
				(type default)
			)
			(layer "F.Fab")
		)
		(fp_line
			(start 0.12065 -0.3048)
			(end 0.67945 -0.3048)
			(stroke
				(width 0.1)
				(type default)
			)
			(layer "F.Fab")
		)
		(fp_line
			(start 0.67945 -0.3048)
			(end 0.67945 0.3048)
			(stroke
				(width 0.1)
				(type default)
			)
			(layer "F.Fab")
		)
		(fp_line
			(start -0.67945 -0.305054)
			(end -0.12065 -0.305054)
			(stroke
				(width 0.1)
				(type default)
			)
			(layer "F.Fab")
		)
		(fp_line
			(start -0.12065 -0.305054)
			(end -0.12065 -0.2794)
			(stroke
				(width 0.1)
				(type default)
			)
			(layer "F.Fab")
		)
		(pad "1" smd circle
			(at -0.40005 0 270)
			(size 0 0)
			(layers "F.Cu" "F.Mask" "F.Paste")
			(net "P1V25_SERDES_VDDPLL_PEX0")
		)
		(pad "2" smd circle
			(at 0.40005 0 270)
			(size 0 0)
			(layers "F.Cu" "F.Mask" "F.Paste")
			(net "P1V25_SERDES_VDDPLL_PEX0_C5")
		)
	)
	(footprint ""
		(layer "F.Cu")
		(at 285.66237 -22.937216 90)
		(property "Reference" "R1698"
			(at 0 0 90)
			(layer "F.SilkS")
			(hide yes)
			(effects
				(font
					(size 1.27 1.27)
				)
			)
		)
		(property "Value" ""
			(at 0 0 90)
			(layer "F.Fab")
			(effects
				(font
					(size 1.27 1.27)
				)
			)
		)
		(duplicate_pad_numbers_are_jumpers no)
		(fp_line
			(start 0.7874 -0.4064)
			(end 0.7874 0.4064)
			(stroke
				(width 0.1524)
				(type default)
			)
			(layer "F.SilkS")
		)
		(fp_line
			(start -0.7874 -0.4064)
			(end 0.7874 -0.4064)
			(stroke
				(width 0.1524)
				(type default)
			)
			(layer "F.SilkS")
		)
		(fp_line
			(start 0.7874 0.4064)
			(end -0.7874 0.4064)
			(stroke
				(width 0.1524)
				(type default)
			)
			(layer "F.SilkS")
		)
		(fp_line
			(start -0.7874 0.4064)
			(end -0.7874 -0.4064)
			(stroke
				(width 0.1524)
				(type default)
			)
			(layer "F.SilkS")
		)
		(fp_line
			(start -0.12065 -0.305054)
			(end -0.12065 -0.2794)
			(stroke
				(width 0.1)
				(type default)
			)
			(layer "F.Fab")
		)
		(fp_line
			(start -0.67945 -0.305054)
			(end -0.12065 -0.305054)
			(stroke
				(width 0.1)
				(type default)
			)
			(layer "F.Fab")
		)
		(fp_line
			(start 0.67945 -0.3048)
			(end 0.67945 0.3048)
			(stroke
				(width 0.1)
				(type default)
			)
			(layer "F.Fab")
		)
		(fp_line
			(start 0.12065 -0.3048)
			(end 0.67945 -0.3048)
			(stroke
				(width 0.1)
				(type default)
			)
			(layer "F.Fab")
		)
		(fp_line
			(start 0.12065 -0.2794)
			(end 0.12065 -0.3048)
			(stroke
				(width 0.1)
				(type default)
			)
			(layer "F.Fab")
		)
		(fp_line
			(start -0.12065 -0.2794)
			(end 0.12065 -0.2794)
			(stroke
				(width 0.1)
				(type default)
			)
			(layer "F.Fab")
		)
		(fp_line
			(start 0.120396 0.2794)
			(end -0.12065 0.2794)
			(stroke
				(width 0.1)
				(type default)
			)
			(layer "F.Fab")
		)
		(fp_line
			(start -0.12065 0.2794)
			(end -0.12065 0.3048)
			(stroke
				(width 0.1)
				(type default)
			)
			(layer "F.Fab")
		)
		(fp_line
			(start 0.67945 0.3048)
			(end 0.120396 0.3048)
			(stroke
				(width 0.1)
				(type default)
			)
			(layer "F.Fab")
		)
		(fp_line
			(start 0.120396 0.3048)
			(end 0.120396 0.2794)
			(stroke
				(width 0.1)
				(type default)
			)
			(layer "F.Fab")
		)
		(fp_line
			(start -0.12065 0.3048)
			(end -0.67945 0.3048)
			(stroke
				(width 0.1)
				(type default)
			)
			(layer "F.Fab")
		)
		(fp_line
			(start -0.67945 0.3048)
			(end -0.67945 -0.305054)
			(stroke
				(width 0.1)
				(type default)
			)
			(layer "F.Fab")
		)
		(pad "1" smd circle
			(at -0.40005 0 90)
			(size 0 0)
			(layers "F.Cu" "F.Mask" "F.Paste")
			(net "SMB_BIC_I2C9_MUX1_SSD9_R_SDA")
		)
		(pad "2" smd circle
			(at 0.40005 0 90)
			(size 0 0)
			(layers "F.Cu" "F.Mask" "F.Paste")
			(net "SMB_ISO_SSD9_SDA")
		)
	)
	(footprint ""
		(layer "F.Cu")
		(at 263.95426 -48.21809)
		(property "Reference" "PD70"
			(at -3.35026 2.24536 0)
			(unlocked yes)
			(layer "F.SilkS")
			(effects
				(font
					(size 0.7874 0.5842)
					(thickness 0.1524)
				)
				(justify left)
			)
		)
		(property "Value" ""
			(at 0 0 0)
			(layer "F.Fab")
			(effects
				(font
					(size 1.27 1.27)
				)
			)
		)
		(duplicate_pad_numbers_are_jumpers no)
		(fp_line
			(start -3.400044 -1.459992)
			(end 4.107942 -1.459992)
			(stroke
				(width 0.1524)
				(type default)
			)
			(layer "F.SilkS")
		)
		(fp_line
			(start -3.400044 1.459992)
			(end -3.400044 -1.459992)
			(stroke
				(width 0.1524)
				(type default)
			)
			(layer "F.SilkS")
		)
		(fp_line
			(start 4.107942 -1.459992)
			(end 4.107942 1.459992)
			(stroke
				(width 0.1524)
				(type default)
			)
			(layer "F.SilkS")
		)
		(fp_line
			(start 4.107942 1.459992)
			(end -3.400044 1.459992)
			(stroke
				(width 0.1524)
				(type default)
			)
			(layer "F.SilkS")
		)
		(fp_poly
			(pts
				(xy 4.107942 -1.459992) (xy 4.107942 1.459992) (xy 3.308096 1.459992) (xy 3.308096 -1.459992)
			)
			(stroke
				(width 0)
				(type default)
			)
			(fill yes)
			(layer "F.SilkS")
		)
		(fp_line
			(start -2.29997 -1.459992)
			(end 2.29997 -1.459992)
			(stroke
				(width 0.1)
				(type default)
			)
			(layer "F.Fab")
		)
		(fp_line
			(start -2.29997 1.459992)
			(end -2.29997 -1.459992)
			(stroke
				(width 0.1)
				(type default)
			)
			(layer "F.Fab")
		)
		(fp_line
			(start 2.29997 -1.459992)
			(end 2.29997 1.459992)
			(stroke
				(width 0.1)
				(type default)
			)
			(layer "F.Fab")
		)
		(fp_line
			(start 2.29997 1.459992)
			(end -2.29997 1.459992)
			(stroke
				(width 0.1)
				(type default)
			)
			(layer "F.Fab")
		)
		(fp_text user "+"
			(at -4.7752 -0.12065 0)
			(unlocked yes)
			(layer "F.SilkS")
			(effects
				(font
					(size 1.905 1.4224)
					(thickness 0.1524)
				)
				(justify left)
			)
		)
		(fp_text user "-"
			(at 5.4102 0.29845 180)
			(unlocked yes)
			(layer "F.SilkS")
			(effects
				(font
					(size 1.905 1.4224)
					(thickness 0.1524)
				)
				(justify left)
			)
		)
		(fp_text user "+"
			(at -4.7752 -0.12065 0)
			(unlocked yes)
			(layer "F.Fab")
			(effects
				(font
					(size 1.905 1.4224)
					(thickness 0.1524)
				)
				(justify left)
			)
		)
		(fp_text user "-"
			(at 5.4102 0.29845 180)
			(unlocked yes)
			(layer "F.Fab")
			(effects
				(font
					(size 1.905 1.4224)
					(thickness 0.1524)
				)
				(justify left)
			)
		)
		(pad "A" smd rect
			(at -1.999996 0 90)
			(size 1.7018 2.5146)
			(layers "F.Cu" "F.Mask" "F.Paste")
			(net "GND")
		)
		(pad "C" smd rect
			(at 1.999996 0 90)
			(size 1.7018 2.5146)
			(layers "F.Cu" "F.Mask" "F.Paste")
			(net "P3V3_SSD9")
		)
	)
	(footprint ""
		(layer "F.Cu")
		(at 338.074 -174.117)
		(property "Reference" "R4767"
			(at 0 0 0)
			(layer "F.SilkS")
			(hide yes)
			(effects
				(font
					(size 1.27 1.27)
				)
			)
		)
		(property "Value" ""
			(at 0 0 0)
			(layer "F.Fab")
			(effects
				(font
					(size 1.27 1.27)
				)
			)
		)
		(duplicate_pad_numbers_are_jumpers no)
		(fp_line
			(start -0.7874 -0.4064)
			(end 0.7874 -0.4064)
			(stroke
				(width 0.1524)
				(type default)
			)
			(layer "F.SilkS")
		)
		(fp_line
			(start -0.7874 0.4064)
			(end -0.7874 -0.4064)
			(stroke
				(width 0.1524)
				(type default)
			)
			(layer "F.SilkS")
		)
		(fp_line
			(start 0.7874 -0.4064)
			(end 0.7874 0.4064)
			(stroke
				(width 0.1524)
				(type default)
			)
			(layer "F.SilkS")
		)
		(fp_line
			(start 0.7874 0.4064)
			(end -0.7874 0.4064)
			(stroke
				(width 0.1524)
				(type default)
			)
			(layer "F.SilkS")
		)
		(fp_line
			(start -0.67945 -0.305054)
			(end -0.12065 -0.305054)
			(stroke
				(width 0.1)
				(type default)
			)
			(layer "F.Fab")
		)
		(fp_line
			(start -0.67945 0.3048)
			(end -0.67945 -0.305054)
			(stroke
				(width 0.1)
				(type default)
			)
			(layer "F.Fab")
		)
		(fp_line
			(start -0.12065 -0.305054)
			(end -0.12065 -0.2794)
			(stroke
				(width 0.1)
				(type default)
			)
			(layer "F.Fab")
		)
		(fp_line
			(start -0.12065 -0.2794)
			(end 0.12065 -0.2794)
			(stroke
				(width 0.1)
				(type default)
			)
			(layer "F.Fab")
		)
		(fp_line
			(start -0.12065 0.2794)
			(end -0.12065 0.3048)
			(stroke
				(width 0.1)
				(type default)
			)
			(layer "F.Fab")
		)
		(fp_line
			(start -0.12065 0.3048)
			(end -0.67945 0.3048)
			(stroke
				(width 0.1)
				(type default)
			)
			(layer "F.Fab")
		)
		(fp_line
			(start 0.120396 0.2794)
			(end -0.12065 0.2794)
			(stroke
				(width 0.1)
				(type default)
			)
			(layer "F.Fab")
		)
		(fp_line
			(start 0.120396 0.3048)
			(end 0.120396 0.2794)
			(stroke
				(width 0.1)
				(type default)
			)
			(layer "F.Fab")
		)
		(fp_line
			(start 0.12065 -0.3048)
			(end 0.67945 -0.3048)
			(stroke
				(width 0.1)
				(type default)
			)
			(layer "F.Fab")
		)
		(fp_line
			(start 0.12065 -0.2794)
			(end 0.12065 -0.3048)
			(stroke
				(width 0.1)
				(type default)
			)
			(layer "F.Fab")
		)
		(fp_line
			(start 0.67945 -0.3048)
			(end 0.67945 0.3048)
			(stroke
				(width 0.1)
				(type default)
			)
			(layer "F.Fab")
		)
		(fp_line
			(start 0.67945 0.3048)
			(end 0.120396 0.3048)
			(stroke
				(width 0.1)
				(type default)
			)
			(layer "F.Fab")
		)
		(pad "1" smd circle
			(at -0.40005 0)
			(size 0 0)
			(layers "F.Cu" "F.Mask" "F.Paste")
			(net "PEX2_PCA9555_1_INT_N")
		)
		(pad "2" smd circle
			(at 0.40005 0)
			(size 0 0)
			(layers "F.Cu" "F.Mask" "F.Paste")
			(net "P1V8_PEX")
		)
	)
	(footprint ""
		(layer "F.Cu")
		(at 83.034124 -4.014724)
		(property "Reference" "R5807"
			(at 0 0 0)
			(layer "F.SilkS")
			(hide yes)
			(effects
				(font
					(size 1.27 1.27)
				)
			)
		)
		(property "Value" ""
			(at 0 0 0)
			(layer "F.Fab")
			(effects
				(font
					(size 1.27 1.27)
				)
			)
		)
		(duplicate_pad_numbers_are_jumpers no)
		(fp_line
			(start -0.7874 -0.4064)
			(end 0.7874 -0.4064)
			(stroke
				(width 0.1524)
				(type default)
			)
			(layer "F.SilkS")
		)
		(fp_line
			(start -0.7874 0.4064)
			(end -0.7874 -0.4064)
			(stroke
				(width 0.1524)
				(type default)
			)
			(layer "F.SilkS")
		)
		(fp_line
			(start 0.7874 -0.4064)
			(end 0.7874 0.4064)
			(stroke
				(width 0.1524)
				(type default)
			)
			(layer "F.SilkS")
		)
		(fp_line
			(start 0.7874 0.4064)
			(end -0.7874 0.4064)
			(stroke
				(width 0.1524)
				(type default)
			)
			(layer "F.SilkS")
		)
		(fp_line
			(start -0.67945 -0.305054)
			(end -0.12065 -0.305054)
			(stroke
				(width 0.1)
				(type default)
			)
			(layer "F.Fab")
		)
		(fp_line
			(start -0.67945 0.3048)
			(end -0.67945 -0.305054)
			(stroke
				(width 0.1)
				(type default)
			)
			(layer "F.Fab")
		)
		(fp_line
			(start -0.12065 -0.305054)
			(end -0.12065 -0.2794)
			(stroke
				(width 0.1)
				(type default)
			)
			(layer "F.Fab")
		)
		(fp_line
			(start -0.12065 -0.2794)
			(end 0.12065 -0.2794)
			(stroke
				(width 0.1)
				(type default)
			)
			(layer "F.Fab")
		)
		(fp_line
			(start -0.12065 0.2794)
			(end -0.12065 0.3048)
			(stroke
				(width 0.1)
				(type default)
			)
			(layer "F.Fab")
		)
		(fp_line
			(start -0.12065 0.3048)
			(end -0.67945 0.3048)
			(stroke
				(width 0.1)
				(type default)
			)
			(layer "F.Fab")
		)
		(fp_line
			(start 0.120396 0.2794)
			(end -0.12065 0.2794)
			(stroke
				(width 0.1)
				(type default)
			)
			(layer "F.Fab")
		)
		(fp_line
			(start 0.120396 0.3048)
			(end 0.120396 0.2794)
			(stroke
				(width 0.1)
				(type default)
			)
			(layer "F.Fab")
		)
		(fp_line
			(start 0.12065 -0.3048)
			(end 0.67945 -0.3048)
			(stroke
				(width 0.1)
				(type default)
			)
			(layer "F.Fab")
		)
		(fp_line
			(start 0.12065 -0.2794)
			(end 0.12065 -0.3048)
			(stroke
				(width 0.1)
				(type default)
			)
			(layer "F.Fab")
		)
		(fp_line
			(start 0.67945 -0.3048)
			(end 0.67945 0.3048)
			(stroke
				(width 0.1)
				(type default)
			)
			(layer "F.Fab")
		)
		(fp_line
			(start 0.67945 0.3048)
			(end 0.120396 0.3048)
			(stroke
				(width 0.1)
				(type default)
			)
			(layer "F.Fab")
		)
		(pad "1" smd circle
			(at -0.40005 0)
			(size 0 0)
			(layers "F.Cu" "F.Mask" "F.Paste")
			(net "LM75_2_A2")
		)
		(pad "2" smd circle
			(at 0.40005 0)
			(size 0 0)
			(layers "F.Cu" "F.Mask" "F.Paste")
			(net "P3V3_AUX")
		)
	)
	(footprint ""
		(layer "F.Cu")
		(at 237.147354 -36.686998 90)
		(property "Reference" "C3675"
			(at 0 0 90)
			(layer "F.SilkS")
			(hide yes)
			(effects
				(font
					(size 1.27 1.27)
				)
			)
		)
		(property "Value" ""
			(at 0 0 90)
			(layer "F.Fab")
			(effects
				(font
					(size 1.27 1.27)
				)
			)
		)
		(duplicate_pad_numbers_are_jumpers no)
		(fp_line
			(start 0.7874 -0.4064)
			(end 0.7874 0.4064)
			(stroke
				(width 0.1524)
				(type default)
			)
			(layer "F.SilkS")
		)
		(fp_line
			(start -0.7874 -0.4064)
			(end 0.7874 -0.4064)
			(stroke
				(width 0.1524)
				(type default)
			)
			(layer "F.SilkS")
		)
		(fp_line
			(start 0.7874 0.4064)
			(end -0.7874 0.4064)
			(stroke
				(width 0.1524)
				(type default)
			)
			(layer "F.SilkS")
		)
		(fp_line
			(start -0.7874 0.4064)
			(end -0.7874 -0.4064)
			(stroke
				(width 0.1524)
				(type default)
			)
			(layer "F.SilkS")
		)
		(fp_line
			(start -0.12065 -0.305054)
			(end -0.12065 -0.2794)
			(stroke
				(width 0.1)
				(type default)
			)
			(layer "F.Fab")
		)
		(fp_line
			(start -0.67945 -0.305054)
			(end -0.12065 -0.305054)
			(stroke
				(width 0.1)
				(type default)
			)
			(layer "F.Fab")
		)
		(fp_line
			(start 0.67945 -0.3048)
			(end 0.67945 0.3048)
			(stroke
				(width 0.1)
				(type default)
			)
			(layer "F.Fab")
		)
		(fp_line
			(start 0.12065 -0.3048)
			(end 0.67945 -0.3048)
			(stroke
				(width 0.1)
				(type default)
			)
			(layer "F.Fab")
		)
		(fp_line
			(start 0.12065 -0.2794)
			(end 0.12065 -0.3048)
			(stroke
				(width 0.1)
				(type default)
			)
			(layer "F.Fab")
		)
		(fp_line
			(start -0.12065 -0.2794)
			(end 0.12065 -0.2794)
			(stroke
				(width 0.1)
				(type default)
			)
			(layer "F.Fab")
		)
		(fp_line
			(start 0.120396 0.2794)
			(end -0.12065 0.2794)
			(stroke
				(width 0.1)
				(type default)
			)
			(layer "F.Fab")
		)
		(fp_line
			(start -0.12065 0.2794)
			(end -0.12065 0.3048)
			(stroke
				(width 0.1)
				(type default)
			)
			(layer "F.Fab")
		)
		(fp_line
			(start 0.67945 0.3048)
			(end 0.120396 0.3048)
			(stroke
				(width 0.1)
				(type default)
			)
			(layer "F.Fab")
		)
		(fp_line
			(start 0.120396 0.3048)
			(end 0.120396 0.2794)
			(stroke
				(width 0.1)
				(type default)
			)
			(layer "F.Fab")
		)
		(fp_line
			(start -0.12065 0.3048)
			(end -0.67945 0.3048)
			(stroke
				(width 0.1)
				(type default)
			)
			(layer "F.Fab")
		)
		(fp_line
			(start -0.67945 0.3048)
			(end -0.67945 -0.305054)
			(stroke
				(width 0.1)
				(type default)
			)
			(layer "F.Fab")
		)
		(pad "1" smd circle
			(at -0.40005 0 90)
			(size 0 0)
			(layers "F.Cu" "F.Mask" "F.Paste")
			(net "P3V3_AUX")
		)
		(pad "2" smd circle
			(at 0.40005 0 90)
			(size 0 0)
			(layers "F.Cu" "F.Mask" "F.Paste")
			(net "GND")
		)
	)
	(footprint ""
		(layer "F.Cu")
		(at 98.975672 -120.493028)
		(property "Reference" "R4476"
			(at 0 0 0)
			(layer "F.SilkS")
			(hide yes)
			(effects
				(font
					(size 1.27 1.27)
				)
			)
		)
		(property "Value" ""
			(at 0 0 0)
			(layer "F.Fab")
			(effects
				(font
					(size 1.27 1.27)
				)
			)
		)
		(duplicate_pad_numbers_are_jumpers no)
		(fp_line
			(start -0.7874 -0.4064)
			(end 0.7874 -0.4064)
			(stroke
				(width 0.1524)
				(type default)
			)
			(layer "F.SilkS")
		)
		(fp_line
			(start -0.7874 0.4064)
			(end -0.7874 -0.4064)
			(stroke
				(width 0.1524)
				(type default)
			)
			(layer "F.SilkS")
		)
		(fp_line
			(start 0.7874 -0.4064)
			(end 0.7874 0.4064)
			(stroke
				(width 0.1524)
				(type default)
			)
			(layer "F.SilkS")
		)
		(fp_line
			(start 0.7874 0.4064)
			(end -0.7874 0.4064)
			(stroke
				(width 0.1524)
				(type default)
			)
			(layer "F.SilkS")
		)
		(fp_line
			(start -0.67945 -0.305054)
			(end -0.12065 -0.305054)
			(stroke
				(width 0.1)
				(type default)
			)
			(layer "F.Fab")
		)
		(fp_line
			(start -0.67945 0.3048)
			(end -0.67945 -0.305054)
			(stroke
				(width 0.1)
				(type default)
			)
			(layer "F.Fab")
		)
		(fp_line
			(start -0.12065 -0.305054)
			(end -0.12065 -0.2794)
			(stroke
				(width 0.1)
				(type default)
			)
			(layer "F.Fab")
		)
		(fp_line
			(start -0.12065 -0.2794)
			(end 0.12065 -0.2794)
			(stroke
				(width 0.1)
				(type default)
			)
			(layer "F.Fab")
		)
		(fp_line
			(start -0.12065 0.2794)
			(end -0.12065 0.3048)
			(stroke
				(width 0.1)
				(type default)
			)
			(layer "F.Fab")
		)
		(fp_line
			(start -0.12065 0.3048)
			(end -0.67945 0.3048)
			(stroke
				(width 0.1)
				(type default)
			)
			(layer "F.Fab")
		)
		(fp_line
			(start 0.120396 0.2794)
			(end -0.12065 0.2794)
			(stroke
				(width 0.1)
				(type default)
			)
			(layer "F.Fab")
		)
		(fp_line
			(start 0.120396 0.3048)
			(end 0.120396 0.2794)
			(stroke
				(width 0.1)
				(type default)
			)
			(layer "F.Fab")
		)
		(fp_line
			(start 0.12065 -0.3048)
			(end 0.67945 -0.3048)
			(stroke
				(width 0.1)
				(type default)
			)
			(layer "F.Fab")
		)
		(fp_line
			(start 0.12065 -0.2794)
			(end 0.12065 -0.3048)
			(stroke
				(width 0.1)
				(type default)
			)
			(layer "F.Fab")
		)
		(fp_line
			(start 0.67945 -0.3048)
			(end 0.67945 0.3048)
			(stroke
				(width 0.1)
				(type default)
			)
			(layer "F.Fab")
		)
		(fp_line
			(start 0.67945 0.3048)
			(end 0.120396 0.3048)
			(stroke
				(width 0.1)
				(type default)
			)
			(layer "F.Fab")
		)
		(pad "1" smd circle
			(at -0.40005 0)
			(size 0 0)
			(layers "F.Cu" "F.Mask" "F.Paste")
			(net "PWRGD_P3V3_NIC1")
		)
		(pad "2" smd circle
			(at 0.40005 0)
			(size 0 0)
			(layers "F.Cu" "F.Mask" "F.Paste")
			(net "PWRGD_P3V3_NIC1_R")
		)
	)
	(footprint ""
		(layer "F.Cu")
		(at 162.5346 -30.94609 180)
		(property "Reference" "C288"
			(at 0 0 180)
			(layer "F.SilkS")
			(hide yes)
			(effects
				(font
					(size 1.27 1.27)
				)
			)
		)
		(property "Value" ""
			(at 0 0 180)
			(layer "F.Fab")
			(effects
				(font
					(size 1.27 1.27)
				)
			)
		)
		(duplicate_pad_numbers_are_jumpers no)
		(fp_line
			(start 0.299974 0.150114)
			(end -0.299974 0.150114)
			(stroke
				(width 0.1)
				(type default)
			)
			(layer "F.Fab")
		)
		(fp_line
			(start 0.299974 -0.150114)
			(end 0.299974 0.150114)
			(stroke
				(width 0.1)
				(type default)
			)
			(layer "F.Fab")
		)
		(fp_line
			(start -0.299974 0.150114)
			(end -0.299974 -0.150114)
			(stroke
				(width 0.1)
				(type default)
			)
			(layer "F.Fab")
		)
		(fp_line
			(start -0.299974 -0.150114)
			(end 0.299974 -0.150114)
			(stroke
				(width 0.1)
				(type default)
			)
			(layer "F.Fab")
		)
		(pad "1" smd rect
			(at -0.2667 0 180)
			(size 0.3048 0.381)
			(layers "F.Cu" "F.Mask" "F.Paste")
			(net "P5E_PEX1_STN2_TX_DP<41>")
		)
		(pad "2" smd rect
			(at 0.2667 0 180)
			(size 0.3048 0.381)
			(layers "F.Cu" "F.Mask" "F.Paste")
			(net "P5E_PEX1_STN2_TX_C_DP<41>")
		)
	)
	(footprint ""
		(layer "F.Cu")
		(at 311.326022 -37.929566 90)
		(property "Reference" "R5582"
			(at 0 0 90)
			(layer "F.SilkS")
			(hide yes)
			(effects
				(font
					(size 1.27 1.27)
				)
			)
		)
		(property "Value" ""
			(at 0 0 90)
			(layer "F.Fab")
			(effects
				(font
					(size 1.27 1.27)
				)
			)
		)
		(duplicate_pad_numbers_are_jumpers no)
		(fp_line
			(start 0.7874 -0.4064)
			(end 0.7874 0.4064)
			(stroke
				(width 0.1524)
				(type default)
			)
			(layer "F.SilkS")
		)
		(fp_line
			(start -0.7874 -0.4064)
			(end 0.7874 -0.4064)
			(stroke
				(width 0.1524)
				(type default)
			)
			(layer "F.SilkS")
		)
		(fp_line
			(start 0.7874 0.4064)
			(end -0.7874 0.4064)
			(stroke
				(width 0.1524)
				(type default)
			)
			(layer "F.SilkS")
		)
		(fp_line
			(start -0.7874 0.4064)
			(end -0.7874 -0.4064)
			(stroke
				(width 0.1524)
				(type default)
			)
			(layer "F.SilkS")
		)
		(fp_line
			(start -0.12065 -0.305054)
			(end -0.12065 -0.2794)
			(stroke
				(width 0.1)
				(type default)
			)
			(layer "F.Fab")
		)
		(fp_line
			(start -0.67945 -0.305054)
			(end -0.12065 -0.305054)
			(stroke
				(width 0.1)
				(type default)
			)
			(layer "F.Fab")
		)
		(fp_line
			(start 0.67945 -0.3048)
			(end 0.67945 0.3048)
			(stroke
				(width 0.1)
				(type default)
			)
			(layer "F.Fab")
		)
		(fp_line
			(start 0.12065 -0.3048)
			(end 0.67945 -0.3048)
			(stroke
				(width 0.1)
				(type default)
			)
			(layer "F.Fab")
		)
		(fp_line
			(start 0.12065 -0.2794)
			(end 0.12065 -0.3048)
			(stroke
				(width 0.1)
				(type default)
			)
			(layer "F.Fab")
		)
		(fp_line
			(start -0.12065 -0.2794)
			(end 0.12065 -0.2794)
			(stroke
				(width 0.1)
				(type default)
			)
			(layer "F.Fab")
		)
		(fp_line
			(start 0.120396 0.2794)
			(end -0.12065 0.2794)
			(stroke
				(width 0.1)
				(type default)
			)
			(layer "F.Fab")
		)
		(fp_line
			(start -0.12065 0.2794)
			(end -0.12065 0.3048)
			(stroke
				(width 0.1)
				(type default)
			)
			(layer "F.Fab")
		)
		(fp_line
			(start 0.67945 0.3048)
			(end 0.120396 0.3048)
			(stroke
				(width 0.1)
				(type default)
			)
			(layer "F.Fab")
		)
		(fp_line
			(start 0.120396 0.3048)
			(end 0.120396 0.2794)
			(stroke
				(width 0.1)
				(type default)
			)
			(layer "F.Fab")
		)
		(fp_line
			(start -0.12065 0.3048)
			(end -0.67945 0.3048)
			(stroke
				(width 0.1)
				(type default)
			)
			(layer "F.Fab")
		)
		(fp_line
			(start -0.67945 0.3048)
			(end -0.67945 -0.305054)
			(stroke
				(width 0.1)
				(type default)
			)
			(layer "F.Fab")
		)
		(pad "1" smd circle
			(at -0.40005 0 90)
			(size 0 0)
			(layers "F.Cu" "F.Mask" "F.Paste")
			(net "SSD11_AUX_P3V3_EN_R")
		)
		(pad "2" smd circle
			(at 0.40005 0 90)
			(size 0 0)
			(layers "F.Cu" "F.Mask" "F.Paste")
			(net "SSD11_AUX_P3V3_EN")
		)
	)
	(footprint ""
		(layer "F.Cu")
		(at 46.434502 -33.631886 180)
		(property "Reference" "C74"
			(at 0 0 180)
			(layer "F.SilkS")
			(hide yes)
			(effects
				(font
					(size 1.27 1.27)
				)
			)
		)
		(property "Value" ""
			(at 0 0 180)
			(layer "F.Fab")
			(effects
				(font
					(size 1.27 1.27)
				)
			)
		)
		(duplicate_pad_numbers_are_jumpers no)
		(fp_line
			(start 0.299974 0.150114)
			(end -0.299974 0.150114)
			(stroke
				(width 0.1)
				(type default)
			)
			(layer "F.Fab")
		)
		(fp_line
			(start 0.299974 -0.150114)
			(end 0.299974 0.150114)
			(stroke
				(width 0.1)
				(type default)
			)
			(layer "F.Fab")
		)
		(fp_line
			(start -0.299974 0.150114)
			(end -0.299974 -0.150114)
			(stroke
				(width 0.1)
				(type default)
			)
			(layer "F.Fab")
		)
		(fp_line
			(start -0.299974 -0.150114)
			(end 0.299974 -0.150114)
			(stroke
				(width 0.1)
				(type default)
			)
			(layer "F.Fab")
		)
		(pad "1" smd rect
			(at -0.2667 0 180)
			(size 0.3048 0.381)
			(layers "F.Cu" "F.Mask" "F.Paste")
			(net "P5E_PEX0_STN2_TX_DN<43>")
		)
		(pad "2" smd rect
			(at 0.2667 0 180)
			(size 0.3048 0.381)
			(layers "F.Cu" "F.Mask" "F.Paste")
			(net "P5E_PEX0_STN2_TX_C_DN<43>")
		)
	)
	(footprint ""
		(layer "F.Cu")
		(at 187.571634 -25.342342 -90)
		(property "Reference" "R427"
			(at 0 0 270)
			(layer "F.SilkS")
			(hide yes)
			(effects
				(font
					(size 1.27 1.27)
				)
			)
		)
		(property "Value" ""
			(at 0 0 270)
			(layer "F.Fab")
			(effects
				(font
					(size 1.27 1.27)
				)
			)
		)
		(duplicate_pad_numbers_are_jumpers no)
		(fp_line
			(start -0.7874 0.4064)
			(end -0.7874 -0.4064)
			(stroke
				(width 0.1524)
				(type default)
			)
			(layer "F.SilkS")
		)
		(fp_line
			(start 0.7874 0.4064)
			(end -0.7874 0.4064)
			(stroke
				(width 0.1524)
				(type default)
			)
			(layer "F.SilkS")
		)
		(fp_line
			(start -0.7874 -0.4064)
			(end 0.7874 -0.4064)
			(stroke
				(width 0.1524)
				(type default)
			)
			(layer "F.SilkS")
		)
		(fp_line
			(start 0.7874 -0.4064)
			(end 0.7874 0.4064)
			(stroke
				(width 0.1524)
				(type default)
			)
			(layer "F.SilkS")
		)
		(fp_line
			(start -0.67945 0.3048)
			(end -0.67945 -0.305054)
			(stroke
				(width 0.1)
				(type default)
			)
			(layer "F.Fab")
		)
		(fp_line
			(start -0.12065 0.3048)
			(end -0.67945 0.3048)
			(stroke
				(width 0.1)
				(type default)
			)
			(layer "F.Fab")
		)
		(fp_line
			(start 0.120396 0.3048)
			(end 0.120396 0.2794)
			(stroke
				(width 0.1)
				(type default)
			)
			(layer "F.Fab")
		)
		(fp_line
			(start 0.67945 0.3048)
			(end 0.120396 0.3048)
			(stroke
				(width 0.1)
				(type default)
			)
			(layer "F.Fab")
		)
		(fp_line
			(start -0.12065 0.2794)
			(end -0.12065 0.3048)
			(stroke
				(width 0.1)
				(type default)
			)
			(layer "F.Fab")
		)
		(fp_line
			(start 0.120396 0.2794)
			(end -0.12065 0.2794)
			(stroke
				(width 0.1)
				(type default)
			)
			(layer "F.Fab")
		)
		(fp_line
			(start -0.12065 -0.2794)
			(end 0.12065 -0.2794)
			(stroke
				(width 0.1)
				(type default)
			)
			(layer "F.Fab")
		)
		(fp_line
			(start 0.12065 -0.2794)
			(end 0.12065 -0.3048)
			(stroke
				(width 0.1)
				(type default)
			)
			(layer "F.Fab")
		)
		(fp_line
			(start 0.12065 -0.3048)
			(end 0.67945 -0.3048)
			(stroke
				(width 0.1)
				(type default)
			)
			(layer "F.Fab")
		)
		(fp_line
			(start 0.67945 -0.3048)
			(end 0.67945 0.3048)
			(stroke
				(width 0.1)
				(type default)
			)
			(layer "F.Fab")
		)
		(fp_line
			(start -0.67945 -0.305054)
			(end -0.12065 -0.305054)
			(stroke
				(width 0.1)
				(type default)
			)
			(layer "F.Fab")
		)
		(fp_line
			(start -0.12065 -0.305054)
			(end -0.12065 -0.2794)
			(stroke
				(width 0.1)
				(type default)
			)
			(layer "F.Fab")
		)
		(pad "1" smd circle
			(at -0.40005 0 270)
			(size 0 0)
			(layers "F.Cu" "F.Mask" "F.Paste")
			(net "P3V3_SSD6")
		)
		(pad "2" smd circle
			(at 0.40005 0 270)
			(size 0 0)
			(layers "F.Cu" "F.Mask" "F.Paste")
			(net "DUALPORT_N_SSD6")
		)
	)
	(footprint ""
		(layer "F.Cu")
		(at 235.056172 -172.55998 -90)
		(property "Reference" "R4258"
			(at 0 0 270)
			(layer "F.SilkS")
			(hide yes)
			(effects
				(font
					(size 1.27 1.27)
				)
			)
		)
		(property "Value" ""
			(at 0 0 270)
			(layer "F.Fab")
			(effects
				(font
					(size 1.27 1.27)
				)
			)
		)
		(duplicate_pad_numbers_are_jumpers no)
		(fp_line
			(start -0.7874 0.4064)
			(end -0.7874 -0.4064)
			(stroke
				(width 0.1524)
				(type default)
			)
			(layer "F.SilkS")
		)
		(fp_line
			(start 0.7874 0.4064)
			(end -0.7874 0.4064)
			(stroke
				(width 0.1524)
				(type default)
			)
			(layer "F.SilkS")
		)
		(fp_line
			(start -0.7874 -0.4064)
			(end 0.7874 -0.4064)
			(stroke
				(width 0.1524)
				(type default)
			)
			(layer "F.SilkS")
		)
		(fp_line
			(start 0.7874 -0.4064)
			(end 0.7874 0.4064)
			(stroke
				(width 0.1524)
				(type default)
			)
			(layer "F.SilkS")
		)
		(fp_line
			(start -0.67945 0.3048)
			(end -0.67945 -0.305054)
			(stroke
				(width 0.1)
				(type default)
			)
			(layer "F.Fab")
		)
		(fp_line
			(start -0.12065 0.3048)
			(end -0.67945 0.3048)
			(stroke
				(width 0.1)
				(type default)
			)
			(layer "F.Fab")
		)
		(fp_line
			(start 0.120396 0.3048)
			(end 0.120396 0.2794)
			(stroke
				(width 0.1)
				(type default)
			)
			(layer "F.Fab")
		)
		(fp_line
			(start 0.67945 0.3048)
			(end 0.120396 0.3048)
			(stroke
				(width 0.1)
				(type default)
			)
			(layer "F.Fab")
		)
		(fp_line
			(start -0.12065 0.2794)
			(end -0.12065 0.3048)
			(stroke
				(width 0.1)
				(type default)
			)
			(layer "F.Fab")
		)
		(fp_line
			(start 0.120396 0.2794)
			(end -0.12065 0.2794)
			(stroke
				(width 0.1)
				(type default)
			)
			(layer "F.Fab")
		)
		(fp_line
			(start -0.12065 -0.2794)
			(end 0.12065 -0.2794)
			(stroke
				(width 0.1)
				(type default)
			)
			(layer "F.Fab")
		)
		(fp_line
			(start 0.12065 -0.2794)
			(end 0.12065 -0.3048)
			(stroke
				(width 0.1)
				(type default)
			)
			(layer "F.Fab")
		)
		(fp_line
			(start 0.12065 -0.3048)
			(end 0.67945 -0.3048)
			(stroke
				(width 0.1)
				(type default)
			)
			(layer "F.Fab")
		)
		(fp_line
			(start 0.67945 -0.3048)
			(end 0.67945 0.3048)
			(stroke
				(width 0.1)
				(type default)
			)
			(layer "F.Fab")
		)
		(fp_line
			(start -0.67945 -0.305054)
			(end -0.12065 -0.305054)
			(stroke
				(width 0.1)
				(type default)
			)
			(layer "F.Fab")
		)
		(fp_line
			(start -0.12065 -0.305054)
			(end -0.12065 -0.2794)
			(stroke
				(width 0.1)
				(type default)
			)
			(layer "F.Fab")
		)
		(pad "1" smd circle
			(at -0.40005 0 270)
			(size 0 0)
			(layers "F.Cu" "F.Mask" "F.Paste")
			(net "RST_BIC_SRST_N")
		)
		(pad "2" smd circle
			(at 0.40005 0 270)
			(size 0 0)
			(layers "F.Cu" "F.Mask" "F.Paste")
			(net "GND")
		)
	)
	(footprint ""
		(layer "F.Cu")
		(at 189.39002 -72.766682 90)
		(property "Reference" "PR7071"
			(at 0 0 90)
			(layer "F.SilkS")
			(hide yes)
			(effects
				(font
					(size 1.27 1.27)
				)
			)
		)
		(property "Value" ""
			(at 0 0 90)
			(layer "F.Fab")
			(effects
				(font
					(size 1.27 1.27)
				)
			)
		)
		(duplicate_pad_numbers_are_jumpers no)
		(fp_line
			(start 0.7874 -0.4064)
			(end 0.7874 0.4064)
			(stroke
				(width 0.1524)
				(type default)
			)
			(layer "F.SilkS")
		)
		(fp_line
			(start -0.7874 -0.4064)
			(end 0.7874 -0.4064)
			(stroke
				(width 0.1524)
				(type default)
			)
			(layer "F.SilkS")
		)
		(fp_line
			(start 0.7874 0.4064)
			(end -0.7874 0.4064)
			(stroke
				(width 0.1524)
				(type default)
			)
			(layer "F.SilkS")
		)
		(fp_line
			(start -0.7874 0.4064)
			(end -0.7874 -0.4064)
			(stroke
				(width 0.1524)
				(type default)
			)
			(layer "F.SilkS")
		)
		(fp_line
			(start -0.12065 -0.305054)
			(end -0.12065 -0.2794)
			(stroke
				(width 0.1)
				(type default)
			)
			(layer "F.Fab")
		)
		(fp_line
			(start -0.67945 -0.305054)
			(end -0.12065 -0.305054)
			(stroke
				(width 0.1)
				(type default)
			)
			(layer "F.Fab")
		)
		(fp_line
			(start 0.67945 -0.3048)
			(end 0.67945 0.3048)
			(stroke
				(width 0.1)
				(type default)
			)
			(layer "F.Fab")
		)
		(fp_line
			(start 0.12065 -0.3048)
			(end 0.67945 -0.3048)
			(stroke
				(width 0.1)
				(type default)
			)
			(layer "F.Fab")
		)
		(fp_line
			(start 0.12065 -0.2794)
			(end 0.12065 -0.3048)
			(stroke
				(width 0.1)
				(type default)
			)
			(layer "F.Fab")
		)
		(fp_line
			(start -0.12065 -0.2794)
			(end 0.12065 -0.2794)
			(stroke
				(width 0.1)
				(type default)
			)
			(layer "F.Fab")
		)
		(fp_line
			(start 0.120396 0.2794)
			(end -0.12065 0.2794)
			(stroke
				(width 0.1)
				(type default)
			)
			(layer "F.Fab")
		)
		(fp_line
			(start -0.12065 0.2794)
			(end -0.12065 0.3048)
			(stroke
				(width 0.1)
				(type default)
			)
			(layer "F.Fab")
		)
		(fp_line
			(start 0.67945 0.3048)
			(end 0.120396 0.3048)
			(stroke
				(width 0.1)
				(type default)
			)
			(layer "F.Fab")
		)
		(fp_line
			(start 0.120396 0.3048)
			(end 0.120396 0.2794)
			(stroke
				(width 0.1)
				(type default)
			)
			(layer "F.Fab")
		)
		(fp_line
			(start -0.12065 0.3048)
			(end -0.67945 0.3048)
			(stroke
				(width 0.1)
				(type default)
			)
			(layer "F.Fab")
		)
		(fp_line
			(start -0.67945 0.3048)
			(end -0.67945 -0.305054)
			(stroke
				(width 0.1)
				(type default)
			)
			(layer "F.Fab")
		)
		(pad "1" smd circle
			(at -0.40005 0 90)
			(size 0 0)
			(layers "F.Cu" "F.Mask" "F.Paste")
			(net "P12V_SSD6_CO_ILIMIT")
		)
		(pad "2" smd circle
			(at 0.40005 0 90)
			(size 0 0)
			(layers "F.Cu" "F.Mask" "F.Paste")
			(net "GND")
		)
	)
	(footprint ""
		(layer "F.Cu")
		(at 151.2951 -59.577986 90)
		(property "Reference" "PC519"
			(at 0 0 90)
			(layer "F.SilkS")
			(hide yes)
			(effects
				(font
					(size 1.27 1.27)
				)
			)
		)
		(property "Value" ""
			(at 0 0 90)
			(layer "F.Fab")
			(effects
				(font
					(size 1.27 1.27)
				)
			)
		)
		(duplicate_pad_numbers_are_jumpers no)
		(fp_line
			(start 0.7874 -0.4064)
			(end 0.7874 0.4064)
			(stroke
				(width 0.1524)
				(type default)
			)
			(layer "F.SilkS")
		)
		(fp_line
			(start -0.7874 -0.4064)
			(end 0.7874 -0.4064)
			(stroke
				(width 0.1524)
				(type default)
			)
			(layer "F.SilkS")
		)
		(fp_line
			(start 0.7874 0.4064)
			(end -0.7874 0.4064)
			(stroke
				(width 0.1524)
				(type default)
			)
			(layer "F.SilkS")
		)
		(fp_line
			(start -0.7874 0.4064)
			(end -0.7874 -0.4064)
			(stroke
				(width 0.1524)
				(type default)
			)
			(layer "F.SilkS")
		)
		(fp_line
			(start -0.12065 -0.305054)
			(end -0.12065 -0.2794)
			(stroke
				(width 0.1)
				(type default)
			)
			(layer "F.Fab")
		)
		(fp_line
			(start -0.67945 -0.305054)
			(end -0.12065 -0.305054)
			(stroke
				(width 0.1)
				(type default)
			)
			(layer "F.Fab")
		)
		(fp_line
			(start 0.67945 -0.3048)
			(end 0.67945 0.3048)
			(stroke
				(width 0.1)
				(type default)
			)
			(layer "F.Fab")
		)
		(fp_line
			(start 0.12065 -0.3048)
			(end 0.67945 -0.3048)
			(stroke
				(width 0.1)
				(type default)
			)
			(layer "F.Fab")
		)
		(fp_line
			(start 0.12065 -0.2794)
			(end 0.12065 -0.3048)
			(stroke
				(width 0.1)
				(type default)
			)
			(layer "F.Fab")
		)
		(fp_line
			(start -0.12065 -0.2794)
			(end 0.12065 -0.2794)
			(stroke
				(width 0.1)
				(type default)
			)
			(layer "F.Fab")
		)
		(fp_line
			(start 0.120396 0.2794)
			(end -0.12065 0.2794)
			(stroke
				(width 0.1)
				(type default)
			)
			(layer "F.Fab")
		)
		(fp_line
			(start -0.12065 0.2794)
			(end -0.12065 0.3048)
			(stroke
				(width 0.1)
				(type default)
			)
			(layer "F.Fab")
		)
		(fp_line
			(start 0.67945 0.3048)
			(end 0.120396 0.3048)
			(stroke
				(width 0.1)
				(type default)
			)
			(layer "F.Fab")
		)
		(fp_line
			(start 0.120396 0.3048)
			(end 0.120396 0.2794)
			(stroke
				(width 0.1)
				(type default)
			)
			(layer "F.Fab")
		)
		(fp_line
			(start -0.12065 0.3048)
			(end -0.67945 0.3048)
			(stroke
				(width 0.1)
				(type default)
			)
			(layer "F.Fab")
		)
		(fp_line
			(start -0.67945 0.3048)
			(end -0.67945 -0.305054)
			(stroke
				(width 0.1)
				(type default)
			)
			(layer "F.Fab")
		)
		(pad "1" smd circle
			(at -0.40005 0 90)
			(size 0 0)
			(layers "F.Cu" "F.Mask" "F.Paste")
			(net "P3V3_SSD5_SS")
		)
		(pad "2" smd circle
			(at 0.40005 0 90)
			(size 0 0)
			(layers "F.Cu" "F.Mask" "F.Paste")
			(net "GND")
		)
	)
	(footprint ""
		(layer "F.Cu")
		(at 364.724188 -247.92305)
		(property "Reference" "J57"
			(at -1.4224 -4.562348 0)
			(unlocked yes)
			(layer "F.SilkS")
			(effects
				(font
					(size 0.7874 0.5842)
					(thickness 0.1524)
				)
				(justify left)
			)
		)
		(property "Value" ""
			(at 0 0 0)
			(layer "F.Fab")
			(effects
				(font
					(size 1.27 1.27)
				)
			)
		)
		(duplicate_pad_numbers_are_jumpers no)
		(fp_line
			(start -1.27 -3.81)
			(end 1.27 -3.81)
			(stroke
				(width 0.1524)
				(type default)
			)
			(layer "F.SilkS")
		)
		(fp_line
			(start -1.27 -0.7747)
			(end -1.27 -3.81)
			(stroke
				(width 0.1524)
				(type default)
			)
			(layer "F.SilkS")
		)
		(fp_line
			(start -1.27 3.81)
			(end -1.27 0.7747)
			(stroke
				(width 0.1524)
				(type default)
			)
			(layer "F.SilkS")
		)
		(fp_line
			(start 1.27 -3.81)
			(end 1.27 -3.3147)
			(stroke
				(width 0.1524)
				(type default)
			)
			(layer "F.SilkS")
		)
		(fp_line
			(start 1.27 -1.7653)
			(end 1.27 1.7653)
			(stroke
				(width 0.1524)
				(type default)
			)
			(layer "F.SilkS")
		)
		(fp_line
			(start 1.27 3.3147)
			(end 1.27 3.81)
			(stroke
				(width 0.1524)
				(type default)
			)
			(layer "F.SilkS")
		)
		(fp_line
			(start 1.27 3.81)
			(end -1.27 3.81)
			(stroke
				(width 0.1524)
				(type default)
			)
			(layer "F.SilkS")
		)
		(fp_poly
			(pts
				(xy 4.3942 -3.048) (xy 4.3942 -2.032) (xy 3.3782 -2.54)
			)
			(stroke
				(width 0)
				(type default)
			)
			(fill yes)
			(layer "F.SilkS")
		)
		(fp_line
			(start -1.27 -3.81)
			(end -1.27 3.81)
			(stroke
				(width 0.1)
				(type default)
			)
			(layer "F.Fab")
		)
		(fp_line
			(start -1.27 3.81)
			(end 1.27 3.81)
			(stroke
				(width 0.1)
				(type default)
			)
			(layer "F.Fab")
		)
		(fp_line
			(start 1.27 -3.81)
			(end -1.27 -3.81)
			(stroke
				(width 0.1)
				(type default)
			)
			(layer "F.Fab")
		)
		(fp_line
			(start 1.27 3.81)
			(end 1.27 -3.81)
			(stroke
				(width 0.1)
				(type default)
			)
			(layer "F.Fab")
		)
		(fp_poly
			(pts
				(xy 4.3942 -3.048) (xy 4.3942 -2.032) (xy 3.3782 -2.54)
			)
			(stroke
				(width 0)
				(type default)
			)
			(fill yes)
			(layer "F.Fab")
		)
		(fp_text user "3"
			(at 3.921252 2.54 90)
			(unlocked yes)
			(layer "F.SilkS")
			(effects
				(font
					(size 0.7874 0.5842)
					(thickness 0.1524)
				)
			)
		)
		(fp_text user "3"
			(at 3.921252 2.54 90)
			(unlocked yes)
			(layer "F.Fab")
			(effects
				(font
					(size 0.7874 0.5842)
					(thickness 0.1524)
				)
			)
		)
		(pad "1" smd rect
			(at 1.459992 -2.54 90)
			(size 1.27 3.429)
			(layers "F.Cu" "F.Mask" "F.Paste")
			(net "P3V3_AUX")
		)
		(pad "2" smd rect
			(at -1.459992 0 90)
			(size 1.27 3.429)
			(layers "F.Cu" "F.Mask" "F.Paste")
			(net "P3V3_LED")
		)
		(pad "3" smd rect
			(at 1.459992 2.54 90)
			(size 1.27 3.429)
			(layers "F.Cu" "F.Mask" "F.Paste")
			(net "Net_987")
		)
	)
	(footprint ""
		(layer "F.Cu")
		(at 429.156114 -32.848042 -90)
		(property "Reference" "R6115"
			(at 0 0 270)
			(layer "F.SilkS")
			(hide yes)
			(effects
				(font
					(size 1.27 1.27)
				)
			)
		)
		(property "Value" ""
			(at 0 0 270)
			(layer "F.Fab")
			(effects
				(font
					(size 1.27 1.27)
				)
			)
		)
		(duplicate_pad_numbers_are_jumpers no)
		(fp_line
			(start -0.7874 0.4064)
			(end -0.7874 -0.4064)
			(stroke
				(width 0.1524)
				(type default)
			)
			(layer "F.SilkS")
		)
		(fp_line
			(start 0.7874 0.4064)
			(end -0.7874 0.4064)
			(stroke
				(width 0.1524)
				(type default)
			)
			(layer "F.SilkS")
		)
		(fp_line
			(start -0.7874 -0.4064)
			(end 0.7874 -0.4064)
			(stroke
				(width 0.1524)
				(type default)
			)
			(layer "F.SilkS")
		)
		(fp_line
			(start 0.7874 -0.4064)
			(end 0.7874 0.4064)
			(stroke
				(width 0.1524)
				(type default)
			)
			(layer "F.SilkS")
		)
		(fp_line
			(start -0.67945 0.3048)
			(end -0.67945 -0.305054)
			(stroke
				(width 0.1)
				(type default)
			)
			(layer "F.Fab")
		)
		(fp_line
			(start -0.12065 0.3048)
			(end -0.67945 0.3048)
			(stroke
				(width 0.1)
				(type default)
			)
			(layer "F.Fab")
		)
		(fp_line
			(start 0.120396 0.3048)
			(end 0.120396 0.2794)
			(stroke
				(width 0.1)
				(type default)
			)
			(layer "F.Fab")
		)
		(fp_line
			(start 0.67945 0.3048)
			(end 0.120396 0.3048)
			(stroke
				(width 0.1)
				(type default)
			)
			(layer "F.Fab")
		)
		(fp_line
			(start -0.12065 0.2794)
			(end -0.12065 0.3048)
			(stroke
				(width 0.1)
				(type default)
			)
			(layer "F.Fab")
		)
		(fp_line
			(start 0.120396 0.2794)
			(end -0.12065 0.2794)
			(stroke
				(width 0.1)
				(type default)
			)
			(layer "F.Fab")
		)
		(fp_line
			(start -0.12065 -0.2794)
			(end 0.12065 -0.2794)
			(stroke
				(width 0.1)
				(type default)
			)
			(layer "F.Fab")
		)
		(fp_line
			(start 0.12065 -0.2794)
			(end 0.12065 -0.3048)
			(stroke
				(width 0.1)
				(type default)
			)
			(layer "F.Fab")
		)
		(fp_line
			(start 0.12065 -0.3048)
			(end 0.67945 -0.3048)
			(stroke
				(width 0.1)
				(type default)
			)
			(layer "F.Fab")
		)
		(fp_line
			(start 0.67945 -0.3048)
			(end 0.67945 0.3048)
			(stroke
				(width 0.1)
				(type default)
			)
			(layer "F.Fab")
		)
		(fp_line
			(start -0.67945 -0.305054)
			(end -0.12065 -0.305054)
			(stroke
				(width 0.1)
				(type default)
			)
			(layer "F.Fab")
		)
		(fp_line
			(start -0.12065 -0.305054)
			(end -0.12065 -0.2794)
			(stroke
				(width 0.1)
				(type default)
			)
			(layer "F.Fab")
		)
		(pad "1" smd circle
			(at -0.40005 0 270)
			(size 0 0)
			(layers "F.Cu" "F.Mask" "F.Paste")
			(net "SSD15_AUX_P3V3_EN_R")
		)
		(pad "2" smd circle
			(at 0.40005 0 270)
			(size 0 0)
			(layers "F.Cu" "F.Mask" "F.Paste")
			(net "P3V3_SSD15_CO_EN")
		)
	)
	(footprint ""
		(layer "F.Cu")
		(at 208.999074 -212.913214 90)
		(property "Reference" "C2570"
			(at 0 0 90)
			(layer "F.SilkS")
			(hide yes)
			(effects
				(font
					(size 1.27 1.27)
				)
			)
		)
		(property "Value" ""
			(at 0 0 90)
			(layer "F.Fab")
			(effects
				(font
					(size 1.27 1.27)
				)
			)
		)
		(duplicate_pad_numbers_are_jumpers no)
		(fp_line
			(start 0.7874 -0.4064)
			(end 0.7874 0.4064)
			(stroke
				(width 0.1524)
				(type default)
			)
			(layer "F.SilkS")
		)
		(fp_line
			(start -0.7874 -0.4064)
			(end 0.7874 -0.4064)
			(stroke
				(width 0.1524)
				(type default)
			)
			(layer "F.SilkS")
		)
		(fp_line
			(start 0.7874 0.4064)
			(end -0.7874 0.4064)
			(stroke
				(width 0.1524)
				(type default)
			)
			(layer "F.SilkS")
		)
		(fp_line
			(start -0.7874 0.4064)
			(end -0.7874 -0.4064)
			(stroke
				(width 0.1524)
				(type default)
			)
			(layer "F.SilkS")
		)
		(fp_line
			(start -0.12065 -0.305054)
			(end -0.12065 -0.2794)
			(stroke
				(width 0.1)
				(type default)
			)
			(layer "F.Fab")
		)
		(fp_line
			(start -0.67945 -0.305054)
			(end -0.12065 -0.305054)
			(stroke
				(width 0.1)
				(type default)
			)
			(layer "F.Fab")
		)
		(fp_line
			(start 0.67945 -0.3048)
			(end 0.67945 0.3048)
			(stroke
				(width 0.1)
				(type default)
			)
			(layer "F.Fab")
		)
		(fp_line
			(start 0.12065 -0.3048)
			(end 0.67945 -0.3048)
			(stroke
				(width 0.1)
				(type default)
			)
			(layer "F.Fab")
		)
		(fp_line
			(start 0.12065 -0.2794)
			(end 0.12065 -0.3048)
			(stroke
				(width 0.1)
				(type default)
			)
			(layer "F.Fab")
		)
		(fp_line
			(start -0.12065 -0.2794)
			(end 0.12065 -0.2794)
			(stroke
				(width 0.1)
				(type default)
			)
			(layer "F.Fab")
		)
		(fp_line
			(start 0.120396 0.2794)
			(end -0.12065 0.2794)
			(stroke
				(width 0.1)
				(type default)
			)
			(layer "F.Fab")
		)
		(fp_line
			(start -0.12065 0.2794)
			(end -0.12065 0.3048)
			(stroke
				(width 0.1)
				(type default)
			)
			(layer "F.Fab")
		)
		(fp_line
			(start 0.67945 0.3048)
			(end 0.120396 0.3048)
			(stroke
				(width 0.1)
				(type default)
			)
			(layer "F.Fab")
		)
		(fp_line
			(start 0.120396 0.3048)
			(end 0.120396 0.2794)
			(stroke
				(width 0.1)
				(type default)
			)
			(layer "F.Fab")
		)
		(fp_line
			(start -0.12065 0.3048)
			(end -0.67945 0.3048)
			(stroke
				(width 0.1)
				(type default)
			)
			(layer "F.Fab")
		)
		(fp_line
			(start -0.67945 0.3048)
			(end -0.67945 -0.305054)
			(stroke
				(width 0.1)
				(type default)
			)
			(layer "F.Fab")
		)
		(pad "1" smd circle
			(at -0.40005 0 90)
			(size 0 0)
			(layers "F.Cu" "F.Mask" "F.Paste")
			(net "GND")
		)
		(pad "2" smd circle
			(at 0.40005 0 90)
			(size 0 0)
			(layers "F.Cu" "F.Mask" "F.Paste")
			(net "P3V3_AUX")
		)
	)
	(footprint ""
		(layer "F.Cu")
		(at 256.583434 -49.94148 180)
		(property "Reference" "R600"
			(at 0 0 180)
			(layer "F.SilkS")
			(hide yes)
			(effects
				(font
					(size 1.27 1.27)
				)
			)
		)
		(property "Value" ""
			(at 0 0 180)
			(layer "F.Fab")
			(effects
				(font
					(size 1.27 1.27)
				)
			)
		)
		(duplicate_pad_numbers_are_jumpers no)
		(fp_line
			(start 0.7874 0.4064)
			(end -0.7874 0.4064)
			(stroke
				(width 0.1524)
				(type default)
			)
			(layer "F.SilkS")
		)
		(fp_line
			(start 0.7874 -0.4064)
			(end 0.7874 0.4064)
			(stroke
				(width 0.1524)
				(type default)
			)
			(layer "F.SilkS")
		)
		(fp_line
			(start -0.7874 0.4064)
			(end -0.7874 -0.4064)
			(stroke
				(width 0.1524)
				(type default)
			)
			(layer "F.SilkS")
		)
		(fp_line
			(start -0.7874 -0.4064)
			(end 0.7874 -0.4064)
			(stroke
				(width 0.1524)
				(type default)
			)
			(layer "F.SilkS")
		)
		(fp_line
			(start 0.67945 0.3048)
			(end 0.120396 0.3048)
			(stroke
				(width 0.1)
				(type default)
			)
			(layer "F.Fab")
		)
		(fp_line
			(start 0.67945 -0.3048)
			(end 0.67945 0.3048)
			(stroke
				(width 0.1)
				(type default)
			)
			(layer "F.Fab")
		)
		(fp_line
			(start 0.12065 -0.2794)
			(end 0.12065 -0.3048)
			(stroke
				(width 0.1)
				(type default)
			)
			(layer "F.Fab")
		)
		(fp_line
			(start 0.12065 -0.3048)
			(end 0.67945 -0.3048)
			(stroke
				(width 0.1)
				(type default)
			)
			(layer "F.Fab")
		)
		(fp_line
			(start 0.120396 0.3048)
			(end 0.120396 0.2794)
			(stroke
				(width 0.1)
				(type default)
			)
			(layer "F.Fab")
		)
		(fp_line
			(start 0.120396 0.2794)
			(end -0.12065 0.2794)
			(stroke
				(width 0.1)
				(type default)
			)
			(layer "F.Fab")
		)
		(fp_line
			(start -0.12065 0.3048)
			(end -0.67945 0.3048)
			(stroke
				(width 0.1)
				(type default)
			)
			(layer "F.Fab")
		)
		(fp_line
			(start -0.12065 0.2794)
			(end -0.12065 0.3048)
			(stroke
				(width 0.1)
				(type default)
			)
			(layer "F.Fab")
		)
		(fp_line
			(start -0.12065 -0.2794)
			(end 0.12065 -0.2794)
			(stroke
				(width 0.1)
				(type default)
			)
			(layer "F.Fab")
		)
		(fp_line
			(start -0.12065 -0.305054)
			(end -0.12065 -0.2794)
			(stroke
				(width 0.1)
				(type default)
			)
			(layer "F.Fab")
		)
		(fp_line
			(start -0.67945 0.3048)
			(end -0.67945 -0.305054)
			(stroke
				(width 0.1)
				(type default)
			)
			(layer "F.Fab")
		)
		(fp_line
			(start -0.67945 -0.305054)
			(end -0.12065 -0.305054)
			(stroke
				(width 0.1)
				(type default)
			)
			(layer "F.Fab")
		)
		(pad "1" smd circle
			(at -0.40005 0 180)
			(size 0 0)
			(layers "F.Cu" "F.Mask" "F.Paste")
			(net "SMB_BIC_I2C6_MUX_SSD_8_15_ADC_R_SDA")
		)
		(pad "2" smd circle
			(at 0.40005 0 180)
			(size 0 0)
			(layers "F.Cu" "F.Mask" "F.Paste")
			(net "SMB_SSD8_ADC_SDA")
		)
	)
	(footprint ""
		(layer "F.Cu")
		(at 360.147362 -112.755426 90)
		(property "Reference" "R6048"
			(at 0 0 90)
			(layer "F.SilkS")
			(hide yes)
			(effects
				(font
					(size 1.27 1.27)
				)
			)
		)
		(property "Value" ""
			(at 0 0 90)
			(layer "F.Fab")
			(effects
				(font
					(size 1.27 1.27)
				)
			)
		)
		(duplicate_pad_numbers_are_jumpers no)
		(fp_line
			(start 0.7874 -0.4064)
			(end 0.7874 0.4064)
			(stroke
				(width 0.1524)
				(type default)
			)
			(layer "F.SilkS")
		)
		(fp_line
			(start -0.7874 -0.4064)
			(end 0.7874 -0.4064)
			(stroke
				(width 0.1524)
				(type default)
			)
			(layer "F.SilkS")
		)
		(fp_line
			(start 0.7874 0.4064)
			(end -0.7874 0.4064)
			(stroke
				(width 0.1524)
				(type default)
			)
			(layer "F.SilkS")
		)
		(fp_line
			(start -0.7874 0.4064)
			(end -0.7874 -0.4064)
			(stroke
				(width 0.1524)
				(type default)
			)
			(layer "F.SilkS")
		)
		(fp_line
			(start -0.12065 -0.305054)
			(end -0.12065 -0.2794)
			(stroke
				(width 0.1)
				(type default)
			)
			(layer "F.Fab")
		)
		(fp_line
			(start -0.67945 -0.305054)
			(end -0.12065 -0.305054)
			(stroke
				(width 0.1)
				(type default)
			)
			(layer "F.Fab")
		)
		(fp_line
			(start 0.67945 -0.3048)
			(end 0.67945 0.3048)
			(stroke
				(width 0.1)
				(type default)
			)
			(layer "F.Fab")
		)
		(fp_line
			(start 0.12065 -0.3048)
			(end 0.67945 -0.3048)
			(stroke
				(width 0.1)
				(type default)
			)
			(layer "F.Fab")
		)
		(fp_line
			(start 0.12065 -0.2794)
			(end 0.12065 -0.3048)
			(stroke
				(width 0.1)
				(type default)
			)
			(layer "F.Fab")
		)
		(fp_line
			(start -0.12065 -0.2794)
			(end 0.12065 -0.2794)
			(stroke
				(width 0.1)
				(type default)
			)
			(layer "F.Fab")
		)
		(fp_line
			(start 0.120396 0.2794)
			(end -0.12065 0.2794)
			(stroke
				(width 0.1)
				(type default)
			)
			(layer "F.Fab")
		)
		(fp_line
			(start -0.12065 0.2794)
			(end -0.12065 0.3048)
			(stroke
				(width 0.1)
				(type default)
			)
			(layer "F.Fab")
		)
		(fp_line
			(start 0.67945 0.3048)
			(end 0.120396 0.3048)
			(stroke
				(width 0.1)
				(type default)
			)
			(layer "F.Fab")
		)
		(fp_line
			(start 0.120396 0.3048)
			(end 0.120396 0.2794)
			(stroke
				(width 0.1)
				(type default)
			)
			(layer "F.Fab")
		)
		(fp_line
			(start -0.12065 0.3048)
			(end -0.67945 0.3048)
			(stroke
				(width 0.1)
				(type default)
			)
			(layer "F.Fab")
		)
		(fp_line
			(start -0.67945 0.3048)
			(end -0.67945 -0.305054)
			(stroke
				(width 0.1)
				(type default)
			)
			(layer "F.Fab")
		)
		(pad "1" smd circle
			(at -0.40005 0 90)
			(size 0 0)
			(layers "F.Cu" "F.Mask" "F.Paste")
			(net "P5V_AUX")
		)
		(pad "2" smd circle
			(at 0.40005 0 90)
			(size 0 0)
			(layers "F.Cu" "F.Mask" "F.Paste")
			(net "P3V3_NIC6_PG_G2")
		)
	)
	(footprint ""
		(layer "F.Cu")
		(at 336.838544 -80.607662 90)
		(property "Reference" "R1172"
			(at 0 0 90)
			(layer "F.SilkS")
			(hide yes)
			(effects
				(font
					(size 1.27 1.27)
				)
			)
		)
		(property "Value" ""
			(at 0 0 90)
			(layer "F.Fab")
			(effects
				(font
					(size 1.27 1.27)
				)
			)
		)
		(duplicate_pad_numbers_are_jumpers no)
		(fp_line
			(start -0.7874 -0.4064)
			(end 0.7874 -0.4064)
			(stroke
				(width 0.1524)
				(type default)
			)
			(layer "F.SilkS")
		)
		(fp_line
			(start -0.12065 -0.305054)
			(end -0.12065 -0.2794)
			(stroke
				(width 0.1)
				(type default)
			)
			(layer "F.Fab")
		)
		(fp_line
			(start -0.67945 -0.305054)
			(end -0.12065 -0.305054)
			(stroke
				(width 0.1)
				(type default)
			)
			(layer "F.Fab")
		)
		(fp_line
			(start 0.67945 -0.3048)
			(end 0.67945 0.3048)
			(stroke
				(width 0.1)
				(type default)
			)
			(layer "F.Fab")
		)
		(fp_line
			(start 0.12065 -0.3048)
			(end 0.67945 -0.3048)
			(stroke
				(width 0.1)
				(type default)
			)
			(layer "F.Fab")
		)
		(fp_line
			(start 0.12065 -0.2794)
			(end 0.12065 -0.3048)
			(stroke
				(width 0.1)
				(type default)
			)
			(layer "F.Fab")
		)
		(fp_line
			(start -0.12065 -0.2794)
			(end 0.12065 -0.2794)
			(stroke
				(width 0.1)
				(type default)
			)
			(layer "F.Fab")
		)
		(fp_line
			(start 0.120396 0.2794)
			(end -0.12065 0.2794)
			(stroke
				(width 0.1)
				(type default)
			)
			(layer "F.Fab")
		)
		(fp_line
			(start -0.12065 0.2794)
			(end -0.12065 0.3048)
			(stroke
				(width 0.1)
				(type default)
			)
			(layer "F.Fab")
		)
		(fp_line
			(start 0.67945 0.3048)
			(end 0.120396 0.3048)
			(stroke
				(width 0.1)
				(type default)
			)
			(layer "F.Fab")
		)
		(fp_line
			(start 0.120396 0.3048)
			(end 0.120396 0.2794)
			(stroke
				(width 0.1)
				(type default)
			)
			(layer "F.Fab")
		)
		(fp_line
			(start -0.12065 0.3048)
			(end -0.67945 0.3048)
			(stroke
				(width 0.1)
				(type default)
			)
			(layer "F.Fab")
		)
		(fp_line
			(start -0.67945 0.3048)
			(end -0.67945 -0.305054)
			(stroke
				(width 0.1)
				(type default)
			)
			(layer "F.Fab")
		)
		(pad "1" smd circle
			(at -0.40005 0 90)
			(size 0 0)
			(layers "F.Cu" "F.Mask" "F.Paste")
			(net "CLK_100M_DB800ZL_SSD9_R_DP")
		)
		(pad "2" smd circle
			(at 0.40005 0 90)
			(size 0 0)
			(layers "F.Cu" "F.Mask" "F.Paste")
			(net "CLK_100M_DB800ZL_SSD9_DP")
		)
	)
	(footprint ""
		(layer "F.Cu")
		(at 337.582256 -93.154246 90)
		(property "Reference" "R3512"
			(at 0 0 90)
			(layer "F.SilkS")
			(hide yes)
			(effects
				(font
					(size 1.27 1.27)
				)
			)
		)
		(property "Value" ""
			(at 0 0 90)
			(layer "F.Fab")
			(effects
				(font
					(size 1.27 1.27)
				)
			)
		)
		(duplicate_pad_numbers_are_jumpers no)
		(fp_line
			(start 0.7874 -0.4064)
			(end 0.7874 0.4064)
			(stroke
				(width 0.1524)
				(type default)
			)
			(layer "F.SilkS")
		)
		(fp_line
			(start -0.7874 -0.4064)
			(end 0.7874 -0.4064)
			(stroke
				(width 0.1524)
				(type default)
			)
			(layer "F.SilkS")
		)
		(fp_line
			(start 0.7874 0.4064)
			(end -0.7874 0.4064)
			(stroke
				(width 0.1524)
				(type default)
			)
			(layer "F.SilkS")
		)
		(fp_line
			(start -0.7874 0.4064)
			(end -0.7874 -0.4064)
			(stroke
				(width 0.1524)
				(type default)
			)
			(layer "F.SilkS")
		)
		(fp_line
			(start -0.12065 -0.305054)
			(end -0.12065 -0.2794)
			(stroke
				(width 0.1)
				(type default)
			)
			(layer "F.Fab")
		)
		(fp_line
			(start -0.67945 -0.305054)
			(end -0.12065 -0.305054)
			(stroke
				(width 0.1)
				(type default)
			)
			(layer "F.Fab")
		)
		(fp_line
			(start 0.67945 -0.3048)
			(end 0.67945 0.3048)
			(stroke
				(width 0.1)
				(type default)
			)
			(layer "F.Fab")
		)
		(fp_line
			(start 0.12065 -0.3048)
			(end 0.67945 -0.3048)
			(stroke
				(width 0.1)
				(type default)
			)
			(layer "F.Fab")
		)
		(fp_line
			(start 0.12065 -0.2794)
			(end 0.12065 -0.3048)
			(stroke
				(width 0.1)
				(type default)
			)
			(layer "F.Fab")
		)
		(fp_line
			(start -0.12065 -0.2794)
			(end 0.12065 -0.2794)
			(stroke
				(width 0.1)
				(type default)
			)
			(layer "F.Fab")
		)
		(fp_line
			(start 0.120396 0.2794)
			(end -0.12065 0.2794)
			(stroke
				(width 0.1)
				(type default)
			)
			(layer "F.Fab")
		)
		(fp_line
			(start -0.12065 0.2794)
			(end -0.12065 0.3048)
			(stroke
				(width 0.1)
				(type default)
			)
			(layer "F.Fab")
		)
		(fp_line
			(start 0.67945 0.3048)
			(end 0.120396 0.3048)
			(stroke
				(width 0.1)
				(type default)
			)
			(layer "F.Fab")
		)
		(fp_line
			(start 0.120396 0.3048)
			(end 0.120396 0.2794)
			(stroke
				(width 0.1)
				(type default)
			)
			(layer "F.Fab")
		)
		(fp_line
			(start -0.12065 0.3048)
			(end -0.67945 0.3048)
			(stroke
				(width 0.1)
				(type default)
			)
			(layer "F.Fab")
		)
		(fp_line
			(start -0.67945 0.3048)
			(end -0.67945 -0.305054)
			(stroke
				(width 0.1)
				(type default)
			)
			(layer "F.Fab")
		)
		(pad "1" smd circle
			(at -0.40005 0 90)
			(size 0 0)
			(layers "F.Cu" "F.Mask" "F.Paste")
			(net "PU_9ZXL0851_8_15_100M")
		)
		(pad "2" smd circle
			(at 0.40005 0 90)
			(size 0 0)
			(layers "F.Cu" "F.Mask" "F.Paste")
			(net "GND")
		)
	)
	(footprint ""
		(layer "F.Cu")
		(at 361.942634 -379.655324 180)
		(property "Reference" "R6707"
			(at 0 0 180)
			(layer "F.SilkS")
			(hide yes)
			(effects
				(font
					(size 1.27 1.27)
				)
			)
		)
		(property "Value" ""
			(at 0 0 180)
			(layer "F.Fab")
			(effects
				(font
					(size 1.27 1.27)
				)
			)
		)
		(duplicate_pad_numbers_are_jumpers no)
		(fp_line
			(start 0.7874 0.4064)
			(end -0.7874 0.4064)
			(stroke
				(width 0.1524)
				(type default)
			)
			(layer "F.SilkS")
		)
		(fp_line
			(start 0.7874 -0.4064)
			(end 0.7874 0.4064)
			(stroke
				(width 0.1524)
				(type default)
			)
			(layer "F.SilkS")
		)
		(fp_line
			(start -0.7874 0.4064)
			(end -0.7874 -0.4064)
			(stroke
				(width 0.1524)
				(type default)
			)
			(layer "F.SilkS")
		)
		(fp_line
			(start -0.7874 -0.4064)
			(end 0.7874 -0.4064)
			(stroke
				(width 0.1524)
				(type default)
			)
			(layer "F.SilkS")
		)
		(fp_line
			(start 0.67945 0.3048)
			(end 0.120396 0.3048)
			(stroke
				(width 0.1)
				(type default)
			)
			(layer "F.Fab")
		)
		(fp_line
			(start 0.67945 -0.3048)
			(end 0.67945 0.3048)
			(stroke
				(width 0.1)
				(type default)
			)
			(layer "F.Fab")
		)
		(fp_line
			(start 0.12065 -0.2794)
			(end 0.12065 -0.3048)
			(stroke
				(width 0.1)
				(type default)
			)
			(layer "F.Fab")
		)
		(fp_line
			(start 0.12065 -0.3048)
			(end 0.67945 -0.3048)
			(stroke
				(width 0.1)
				(type default)
			)
			(layer "F.Fab")
		)
		(fp_line
			(start 0.120396 0.3048)
			(end 0.120396 0.2794)
			(stroke
				(width 0.1)
				(type default)
			)
			(layer "F.Fab")
		)
		(fp_line
			(start 0.120396 0.2794)
			(end -0.12065 0.2794)
			(stroke
				(width 0.1)
				(type default)
			)
			(layer "F.Fab")
		)
		(fp_line
			(start -0.12065 0.3048)
			(end -0.67945 0.3048)
			(stroke
				(width 0.1)
				(type default)
			)
			(layer "F.Fab")
		)
		(fp_line
			(start -0.12065 0.2794)
			(end -0.12065 0.3048)
			(stroke
				(width 0.1)
				(type default)
			)
			(layer "F.Fab")
		)
		(fp_line
			(start -0.12065 -0.2794)
			(end 0.12065 -0.2794)
			(stroke
				(width 0.1)
				(type default)
			)
			(layer "F.Fab")
		)
		(fp_line
			(start -0.12065 -0.305054)
			(end -0.12065 -0.2794)
			(stroke
				(width 0.1)
				(type default)
			)
			(layer "F.Fab")
		)
		(fp_line
			(start -0.67945 0.3048)
			(end -0.67945 -0.305054)
			(stroke
				(width 0.1)
				(type default)
			)
			(layer "F.Fab")
		)
		(fp_line
			(start -0.67945 -0.305054)
			(end -0.12065 -0.305054)
			(stroke
				(width 0.1)
				(type default)
			)
			(layer "F.Fab")
		)
		(pad "1" smd circle
			(at -0.40005 0 180)
			(size 0 0)
			(layers "F.Cu" "F.Mask" "F.Paste")
			(net "MB_3V3IO_RSVD4_ISO")
		)
		(pad "2" smd circle
			(at 0.40005 0 180)
			(size 0 0)
			(layers "F.Cu" "F.Mask" "F.Paste")
			(net "P3V3_AUX")
		)
	)
	(footprint ""
		(layer "F.Cu")
		(at 80.000602 -350.098614 90)
		(property "Reference" "C109"
			(at 0 0 90)
			(layer "F.SilkS")
			(hide yes)
			(effects
				(font
					(size 1.27 1.27)
				)
			)
		)
		(property "Value" ""
			(at 0 0 90)
			(layer "F.Fab")
			(effects
				(font
					(size 1.27 1.27)
				)
			)
		)
		(duplicate_pad_numbers_are_jumpers no)
		(fp_line
			(start 0.299974 -0.150114)
			(end 0.299974 0.150114)
			(stroke
				(width 0.1)
				(type default)
			)
			(layer "F.Fab")
		)
		(fp_line
			(start -0.299974 -0.150114)
			(end 0.299974 -0.150114)
			(stroke
				(width 0.1)
				(type default)
			)
			(layer "F.Fab")
		)
		(fp_line
			(start 0.299974 0.150114)
			(end -0.299974 0.150114)
			(stroke
				(width 0.1)
				(type default)
			)
			(layer "F.Fab")
		)
		(fp_line
			(start -0.299974 0.150114)
			(end -0.299974 -0.150114)
			(stroke
				(width 0.1)
				(type default)
			)
			(layer "F.Fab")
		)
		(pad "1" smd rect
			(at -0.2667 0 90)
			(size 0.3048 0.381)
			(layers "F.Cu" "F.Mask" "F.Paste")
			(net "P5E_PEX0_STN5_TX_DP<89>")
		)
		(pad "2" smd rect
			(at 0.2667 0 90)
			(size 0.3048 0.381)
			(layers "F.Cu" "F.Mask" "F.Paste")
			(net "P5E_PEX0_STN5_TX_C_DP<89>")
		)
	)
	(footprint ""
		(layer "F.Cu")
		(at 43.839892 -70.52437 90)
		(property "Reference" "PC369"
			(at 0 0 90)
			(layer "F.SilkS")
			(hide yes)
			(effects
				(font
					(size 1.27 1.27)
				)
			)
		)
		(property "Value" ""
			(at 0 0 90)
			(layer "F.Fab")
			(effects
				(font
					(size 1.27 1.27)
				)
			)
		)
		(duplicate_pad_numbers_are_jumpers no)
		(fp_line
			(start 1.524 -0.762)
			(end 1.524 0.762)
			(stroke
				(width 0.1524)
				(type default)
			)
			(layer "F.SilkS")
		)
		(fp_line
			(start -1.524 -0.762)
			(end 1.524 -0.762)
			(stroke
				(width 0.1524)
				(type default)
			)
			(layer "F.SilkS")
		)
		(fp_line
			(start 1.524 0.762)
			(end -1.524 0.762)
			(stroke
				(width 0.1524)
				(type default)
			)
			(layer "F.SilkS")
		)
		(fp_line
			(start -1.524 0.762)
			(end -1.524 -0.762)
			(stroke
				(width 0.1524)
				(type default)
			)
			(layer "F.SilkS")
		)
		(fp_line
			(start 1.1049 -0.724916)
			(end -1.1049 -0.724916)
			(stroke
				(width 0.1)
				(type default)
			)
			(layer "F.Fab")
		)
		(fp_line
			(start -1.1049 -0.724916)
			(end -1.1049 0.724916)
			(stroke
				(width 0.1)
				(type default)
			)
			(layer "F.Fab")
		)
		(fp_line
			(start 1.1049 0.724916)
			(end 1.1049 -0.724916)
			(stroke
				(width 0.1)
				(type default)
			)
			(layer "F.Fab")
		)
		(fp_line
			(start -1.1049 0.724916)
			(end 1.1049 0.724916)
			(stroke
				(width 0.1)
				(type default)
			)
			(layer "F.Fab")
		)
		(pad "1" smd rect
			(at -0.889 0 270)
			(size 1.016 1.27)
			(layers "F.Cu" "F.Mask" "F.Paste")
			(net "P12V_SSD1_R")
		)
		(pad "2" smd rect
			(at 0.889 0 270)
			(size 1.016 1.27)
			(layers "F.Cu" "F.Mask" "F.Paste")
			(net "GND")
		)
	)
	(footprint ""
		(layer "F.Cu")
		(at 170.975274 -63.086234)
		(property "Reference" "R5988"
			(at 0 0 0)
			(layer "F.SilkS")
			(hide yes)
			(effects
				(font
					(size 1.27 1.27)
				)
			)
		)
		(property "Value" ""
			(at 0 0 0)
			(layer "F.Fab")
			(effects
				(font
					(size 1.27 1.27)
				)
			)
		)
		(duplicate_pad_numbers_are_jumpers no)
		(fp_line
			(start -0.7874 -0.4064)
			(end 0.7874 -0.4064)
			(stroke
				(width 0.1524)
				(type default)
			)
			(layer "F.SilkS")
		)
		(fp_line
			(start -0.7874 0.4064)
			(end -0.7874 -0.4064)
			(stroke
				(width 0.1524)
				(type default)
			)
			(layer "F.SilkS")
		)
		(fp_line
			(start 0.7874 -0.4064)
			(end 0.7874 0.4064)
			(stroke
				(width 0.1524)
				(type default)
			)
			(layer "F.SilkS")
		)
		(fp_line
			(start 0.7874 0.4064)
			(end -0.7874 0.4064)
			(stroke
				(width 0.1524)
				(type default)
			)
			(layer "F.SilkS")
		)
		(fp_line
			(start -0.67945 -0.305054)
			(end -0.12065 -0.305054)
			(stroke
				(width 0.1)
				(type default)
			)
			(layer "F.Fab")
		)
		(fp_line
			(start -0.67945 0.3048)
			(end -0.67945 -0.305054)
			(stroke
				(width 0.1)
				(type default)
			)
			(layer "F.Fab")
		)
		(fp_line
			(start -0.12065 -0.305054)
			(end -0.12065 -0.2794)
			(stroke
				(width 0.1)
				(type default)
			)
			(layer "F.Fab")
		)
		(fp_line
			(start -0.12065 -0.2794)
			(end 0.12065 -0.2794)
			(stroke
				(width 0.1)
				(type default)
			)
			(layer "F.Fab")
		)
		(fp_line
			(start -0.12065 0.2794)
			(end -0.12065 0.3048)
			(stroke
				(width 0.1)
				(type default)
			)
			(layer "F.Fab")
		)
		(fp_line
			(start -0.12065 0.3048)
			(end -0.67945 0.3048)
			(stroke
				(width 0.1)
				(type default)
			)
			(layer "F.Fab")
		)
		(fp_line
			(start 0.120396 0.2794)
			(end -0.12065 0.2794)
			(stroke
				(width 0.1)
				(type default)
			)
			(layer "F.Fab")
		)
		(fp_line
			(start 0.120396 0.3048)
			(end 0.120396 0.2794)
			(stroke
				(width 0.1)
				(type default)
			)
			(layer "F.Fab")
		)
		(fp_line
			(start 0.12065 -0.3048)
			(end 0.67945 -0.3048)
			(stroke
				(width 0.1)
				(type default)
			)
			(layer "F.Fab")
		)
		(fp_line
			(start 0.12065 -0.2794)
			(end 0.12065 -0.3048)
			(stroke
				(width 0.1)
				(type default)
			)
			(layer "F.Fab")
		)
		(fp_line
			(start 0.67945 -0.3048)
			(end 0.67945 0.3048)
			(stroke
				(width 0.1)
				(type default)
			)
			(layer "F.Fab")
		)
		(fp_line
			(start 0.67945 0.3048)
			(end 0.120396 0.3048)
			(stroke
				(width 0.1)
				(type default)
			)
			(layer "F.Fab")
		)
		(pad "1" smd circle
			(at -0.40005 0)
			(size 0 0)
			(layers "F.Cu" "F.Mask" "F.Paste")
			(net "P12V_SSD6_R")
		)
		(pad "2" smd circle
			(at 0.40005 0)
			(size 0 0)
			(layers "F.Cu" "F.Mask" "F.Paste")
			(net "P12V_SSD6_PG_G1")
		)
	)
	(footprint ""
		(layer "F.Cu")
		(at 375.230136 -281.203908 -90)
		(property "Reference" "C3585"
			(at 0 0 270)
			(layer "F.SilkS")
			(hide yes)
			(effects
				(font
					(size 1.27 1.27)
				)
			)
		)
		(property "Value" ""
			(at 0 0 270)
			(layer "F.Fab")
			(effects
				(font
					(size 1.27 1.27)
				)
			)
		)
		(duplicate_pad_numbers_are_jumpers no)
		(fp_line
			(start -1.2954 0.5842)
			(end -1.2954 -0.5842)
			(stroke
				(width 0.1524)
				(type default)
			)
			(layer "F.SilkS")
		)
		(fp_line
			(start 1.2954 0.5842)
			(end -1.2954 0.5842)
			(stroke
				(width 0.1524)
				(type default)
			)
			(layer "F.SilkS")
		)
		(fp_line
			(start -1.2954 -0.5842)
			(end 1.2954 -0.5842)
			(stroke
				(width 0.1524)
				(type default)
			)
			(layer "F.SilkS")
		)
		(fp_line
			(start 1.2954 -0.5842)
			(end 1.2954 0.5842)
			(stroke
				(width 0.1524)
				(type default)
			)
			(layer "F.SilkS")
		)
		(fp_line
			(start -0.8636 0.4572)
			(end -0.8636 0.4064)
			(stroke
				(width 0.1)
				(type default)
			)
			(layer "F.Fab")
		)
		(fp_line
			(start 0.8636 0.4572)
			(end -0.8636 0.4572)
			(stroke
				(width 0.1)
				(type default)
			)
			(layer "F.Fab")
		)
		(fp_line
			(start -1.1938 0.4064)
			(end -1.1938 -0.4064)
			(stroke
				(width 0.1)
				(type default)
			)
			(layer "F.Fab")
		)
		(fp_line
			(start -0.8636 0.4064)
			(end -1.1938 0.4064)
			(stroke
				(width 0.1)
				(type default)
			)
			(layer "F.Fab")
		)
		(fp_line
			(start 0.8636 0.4064)
			(end 0.8636 0.4572)
			(stroke
				(width 0.1)
				(type default)
			)
			(layer "F.Fab")
		)
		(fp_line
			(start 1.1938 0.4064)
			(end 0.8636 0.4064)
			(stroke
				(width 0.1)
				(type default)
			)
			(layer "F.Fab")
		)
		(fp_line
			(start -1.1938 -0.4064)
			(end -0.8636 -0.4064)
			(stroke
				(width 0.1)
				(type default)
			)
			(layer "F.Fab")
		)
		(fp_line
			(start -0.8636 -0.4064)
			(end -0.8636 -0.4572)
			(stroke
				(width 0.1)
				(type default)
			)
			(layer "F.Fab")
		)
		(fp_line
			(start 0.8636 -0.4064)
			(end 1.1938 -0.4064)
			(stroke
				(width 0.1)
				(type default)
			)
			(layer "F.Fab")
		)
		(fp_line
			(start 1.1938 -0.4064)
			(end 1.1938 0.4064)
			(stroke
				(width 0.1)
				(type default)
			)
			(layer "F.Fab")
		)
		(fp_line
			(start -0.8636 -0.4572)
			(end 0.8636 -0.4572)
			(stroke
				(width 0.1)
				(type default)
			)
			(layer "F.Fab")
		)
		(fp_line
			(start 0.8636 -0.4572)
			(end 0.8636 -0.4064)
			(stroke
				(width 0.1)
				(type default)
			)
			(layer "F.Fab")
		)
		(pad "1" smd rect
			(at -0.7366 0 180)
			(size 0.7112 0.8128)
			(layers "F.Cu" "F.Mask" "F.Paste")
			(net "P1V8_PLL0_PEX3")
		)
		(pad "2" smd rect
			(at 0.7366 0 180)
			(size 0.7112 0.8128)
			(layers "F.Cu" "F.Mask" "F.Paste")
			(net "GND")
		)
	)
	(footprint ""
		(layer "F.Cu")
		(at 117.958362 -128.947926)
		(property "Reference" "PC302"
			(at 0 0 0)
			(layer "F.SilkS")
			(hide yes)
			(effects
				(font
					(size 1.27 1.27)
				)
			)
		)
		(property "Value" ""
			(at 0 0 0)
			(layer "F.Fab")
			(effects
				(font
					(size 1.27 1.27)
				)
			)
		)
		(duplicate_pad_numbers_are_jumpers no)
		(fp_line
			(start -0.7874 -0.4064)
			(end 0.7874 -0.4064)
			(stroke
				(width 0.1524)
				(type default)
			)
			(layer "F.SilkS")
		)
		(fp_line
			(start -0.7874 0.4064)
			(end -0.7874 -0.4064)
			(stroke
				(width 0.1524)
				(type default)
			)
			(layer "F.SilkS")
		)
		(fp_line
			(start 0.7874 -0.4064)
			(end 0.7874 0.4064)
			(stroke
				(width 0.1524)
				(type default)
			)
			(layer "F.SilkS")
		)
		(fp_line
			(start 0.7874 0.4064)
			(end -0.7874 0.4064)
			(stroke
				(width 0.1524)
				(type default)
			)
			(layer "F.SilkS")
		)
		(fp_line
			(start -0.67945 -0.305054)
			(end -0.12065 -0.305054)
			(stroke
				(width 0.1)
				(type default)
			)
			(layer "F.Fab")
		)
		(fp_line
			(start -0.67945 0.3048)
			(end -0.67945 -0.305054)
			(stroke
				(width 0.1)
				(type default)
			)
			(layer "F.Fab")
		)
		(fp_line
			(start -0.12065 -0.305054)
			(end -0.12065 -0.2794)
			(stroke
				(width 0.1)
				(type default)
			)
			(layer "F.Fab")
		)
		(fp_line
			(start -0.12065 -0.2794)
			(end 0.12065 -0.2794)
			(stroke
				(width 0.1)
				(type default)
			)
			(layer "F.Fab")
		)
		(fp_line
			(start -0.12065 0.2794)
			(end -0.12065 0.3048)
			(stroke
				(width 0.1)
				(type default)
			)
			(layer "F.Fab")
		)
		(fp_line
			(start -0.12065 0.3048)
			(end -0.67945 0.3048)
			(stroke
				(width 0.1)
				(type default)
			)
			(layer "F.Fab")
		)
		(fp_line
			(start 0.120396 0.2794)
			(end -0.12065 0.2794)
			(stroke
				(width 0.1)
				(type default)
			)
			(layer "F.Fab")
		)
		(fp_line
			(start 0.120396 0.3048)
			(end 0.120396 0.2794)
			(stroke
				(width 0.1)
				(type default)
			)
			(layer "F.Fab")
		)
		(fp_line
			(start 0.12065 -0.3048)
			(end 0.67945 -0.3048)
			(stroke
				(width 0.1)
				(type default)
			)
			(layer "F.Fab")
		)
		(fp_line
			(start 0.12065 -0.2794)
			(end 0.12065 -0.3048)
			(stroke
				(width 0.1)
				(type default)
			)
			(layer "F.Fab")
		)
		(fp_line
			(start 0.67945 -0.3048)
			(end 0.67945 0.3048)
			(stroke
				(width 0.1)
				(type default)
			)
			(layer "F.Fab")
		)
		(fp_line
			(start 0.67945 0.3048)
			(end 0.120396 0.3048)
			(stroke
				(width 0.1)
				(type default)
			)
			(layer "F.Fab")
		)
		(pad "1" smd circle
			(at -0.40005 0)
			(size 0 0)
			(layers "F.Cu" "F.Mask" "F.Paste")
			(net "P5V_AUX")
		)
		(pad "2" smd circle
			(at 0.40005 0)
			(size 0 0)
			(layers "F.Cu" "F.Mask" "F.Paste")
			(net "GND")
		)
	)
	(footprint ""
		(layer "F.Cu")
		(at 304.374804 -48.753014 180)
		(property "Reference" "C324"
			(at 0 0 180)
			(layer "F.SilkS")
			(hide yes)
			(effects
				(font
					(size 1.27 1.27)
				)
			)
		)
		(property "Value" ""
			(at 0 0 180)
			(layer "F.Fab")
			(effects
				(font
					(size 1.27 1.27)
				)
			)
		)
		(duplicate_pad_numbers_are_jumpers no)
		(fp_line
			(start 0.7874 0.4064)
			(end -0.7874 0.4064)
			(stroke
				(width 0.1524)
				(type default)
			)
			(layer "F.SilkS")
		)
		(fp_line
			(start 0.7874 -0.4064)
			(end 0.7874 0.4064)
			(stroke
				(width 0.1524)
				(type default)
			)
			(layer "F.SilkS")
		)
		(fp_line
			(start -0.7874 0.4064)
			(end -0.7874 -0.4064)
			(stroke
				(width 0.1524)
				(type default)
			)
			(layer "F.SilkS")
		)
		(fp_line
			(start -0.7874 -0.4064)
			(end 0.7874 -0.4064)
			(stroke
				(width 0.1524)
				(type default)
			)
			(layer "F.SilkS")
		)
		(fp_line
			(start 0.67945 0.3048)
			(end 0.120396 0.3048)
			(stroke
				(width 0.1)
				(type default)
			)
			(layer "F.Fab")
		)
		(fp_line
			(start 0.67945 -0.3048)
			(end 0.67945 0.3048)
			(stroke
				(width 0.1)
				(type default)
			)
			(layer "F.Fab")
		)
		(fp_line
			(start 0.12065 -0.2794)
			(end 0.12065 -0.3048)
			(stroke
				(width 0.1)
				(type default)
			)
			(layer "F.Fab")
		)
		(fp_line
			(start 0.12065 -0.3048)
			(end 0.67945 -0.3048)
			(stroke
				(width 0.1)
				(type default)
			)
			(layer "F.Fab")
		)
		(fp_line
			(start 0.120396 0.3048)
			(end 0.120396 0.2794)
			(stroke
				(width 0.1)
				(type default)
			)
			(layer "F.Fab")
		)
		(fp_line
			(start 0.120396 0.2794)
			(end -0.12065 0.2794)
			(stroke
				(width 0.1)
				(type default)
			)
			(layer "F.Fab")
		)
		(fp_line
			(start -0.12065 0.3048)
			(end -0.67945 0.3048)
			(stroke
				(width 0.1)
				(type default)
			)
			(layer "F.Fab")
		)
		(fp_line
			(start -0.12065 0.2794)
			(end -0.12065 0.3048)
			(stroke
				(width 0.1)
				(type default)
			)
			(layer "F.Fab")
		)
		(fp_line
			(start -0.12065 -0.2794)
			(end 0.12065 -0.2794)
			(stroke
				(width 0.1)
				(type default)
			)
			(layer "F.Fab")
		)
		(fp_line
			(start -0.12065 -0.305054)
			(end -0.12065 -0.2794)
			(stroke
				(width 0.1)
				(type default)
			)
			(layer "F.Fab")
		)
		(fp_line
			(start -0.67945 0.3048)
			(end -0.67945 -0.305054)
			(stroke
				(width 0.1)
				(type default)
			)
			(layer "F.Fab")
		)
		(fp_line
			(start -0.67945 -0.305054)
			(end -0.12065 -0.305054)
			(stroke
				(width 0.1)
				(type default)
			)
			(layer "F.Fab")
		)
		(pad "1" smd circle
			(at -0.40005 0 180)
			(size 0 0)
			(layers "F.Cu" "F.Mask" "F.Paste")
			(net "P3V3_AUX")
		)
		(pad "2" smd circle
			(at 0.40005 0 180)
			(size 0 0)
			(layers "F.Cu" "F.Mask" "F.Paste")
			(net "GND")
		)
	)
	(footprint ""
		(layer "F.Cu")
		(at 289.49396 -34.248852)
		(property "Reference" "R5691"
			(at 0 0 0)
			(layer "F.SilkS")
			(hide yes)
			(effects
				(font
					(size 1.27 1.27)
				)
			)
		)
		(property "Value" ""
			(at 0 0 0)
			(layer "F.Fab")
			(effects
				(font
					(size 1.27 1.27)
				)
			)
		)
		(duplicate_pad_numbers_are_jumpers no)
		(fp_line
			(start -0.7874 -0.4064)
			(end 0.7874 -0.4064)
			(stroke
				(width 0.1524)
				(type default)
			)
			(layer "F.SilkS")
		)
		(fp_line
			(start -0.7874 0.4064)
			(end -0.7874 -0.4064)
			(stroke
				(width 0.1524)
				(type default)
			)
			(layer "F.SilkS")
		)
		(fp_line
			(start 0.7874 -0.4064)
			(end 0.7874 0.4064)
			(stroke
				(width 0.1524)
				(type default)
			)
			(layer "F.SilkS")
		)
		(fp_line
			(start 0.7874 0.4064)
			(end -0.7874 0.4064)
			(stroke
				(width 0.1524)
				(type default)
			)
			(layer "F.SilkS")
		)
		(fp_line
			(start -0.67945 -0.305054)
			(end -0.12065 -0.305054)
			(stroke
				(width 0.1)
				(type default)
			)
			(layer "F.Fab")
		)
		(fp_line
			(start -0.67945 0.3048)
			(end -0.67945 -0.305054)
			(stroke
				(width 0.1)
				(type default)
			)
			(layer "F.Fab")
		)
		(fp_line
			(start -0.12065 -0.305054)
			(end -0.12065 -0.2794)
			(stroke
				(width 0.1)
				(type default)
			)
			(layer "F.Fab")
		)
		(fp_line
			(start -0.12065 -0.2794)
			(end 0.12065 -0.2794)
			(stroke
				(width 0.1)
				(type default)
			)
			(layer "F.Fab")
		)
		(fp_line
			(start -0.12065 0.2794)
			(end -0.12065 0.3048)
			(stroke
				(width 0.1)
				(type default)
			)
			(layer "F.Fab")
		)
		(fp_line
			(start -0.12065 0.3048)
			(end -0.67945 0.3048)
			(stroke
				(width 0.1)
				(type default)
			)
			(layer "F.Fab")
		)
		(fp_line
			(start 0.120396 0.2794)
			(end -0.12065 0.2794)
			(stroke
				(width 0.1)
				(type default)
			)
			(layer "F.Fab")
		)
		(fp_line
			(start 0.120396 0.3048)
			(end 0.120396 0.2794)
			(stroke
				(width 0.1)
				(type default)
			)
			(layer "F.Fab")
		)
		(fp_line
			(start 0.12065 -0.3048)
			(end 0.67945 -0.3048)
			(stroke
				(width 0.1)
				(type default)
			)
			(layer "F.Fab")
		)
		(fp_line
			(start 0.12065 -0.2794)
			(end 0.12065 -0.3048)
			(stroke
				(width 0.1)
				(type default)
			)
			(layer "F.Fab")
		)
		(fp_line
			(start 0.67945 -0.3048)
			(end 0.67945 0.3048)
			(stroke
				(width 0.1)
				(type default)
			)
			(layer "F.Fab")
		)
		(fp_line
			(start 0.67945 0.3048)
			(end 0.120396 0.3048)
			(stroke
				(width 0.1)
				(type default)
			)
			(layer "F.Fab")
		)
		(pad "1" smd circle
			(at -0.40005 0)
			(size 0 0)
			(layers "F.Cu" "F.Mask" "F.Paste")
			(net "RST_SMB_SSD10_ISO_N")
		)
		(pad "2" smd circle
			(at 0.40005 0)
			(size 0 0)
			(layers "F.Cu" "F.Mask" "F.Paste")
			(net "P3V3_SSD10")
		)
	)
	(footprint ""
		(layer "F.Cu")
		(at 114.945668 -350.098614 90)
		(property "Reference" "C342"
			(at 0 0 90)
			(layer "F.SilkS")
			(hide yes)
			(effects
				(font
					(size 1.27 1.27)
				)
			)
		)
		(property "Value" ""
			(at 0 0 90)
			(layer "F.Fab")
			(effects
				(font
					(size 1.27 1.27)
				)
			)
		)
		(duplicate_pad_numbers_are_jumpers no)
		(fp_line
			(start 0.299974 -0.150114)
			(end 0.299974 0.150114)
			(stroke
				(width 0.1)
				(type default)
			)
			(layer "F.Fab")
		)
		(fp_line
			(start -0.299974 -0.150114)
			(end 0.299974 -0.150114)
			(stroke
				(width 0.1)
				(type default)
			)
			(layer "F.Fab")
		)
		(fp_line
			(start 0.299974 0.150114)
			(end -0.299974 0.150114)
			(stroke
				(width 0.1)
				(type default)
			)
			(layer "F.Fab")
		)
		(fp_line
			(start -0.299974 0.150114)
			(end -0.299974 -0.150114)
			(stroke
				(width 0.1)
				(type default)
			)
			(layer "F.Fab")
		)
		(pad "1" smd rect
			(at -0.2667 0 90)
			(size 0.3048 0.381)
			(layers "F.Cu" "F.Mask" "F.Paste")
			(net "P5E_PEX1_STN6_TX_DP<110>")
		)
		(pad "2" smd rect
			(at 0.2667 0 90)
			(size 0.3048 0.381)
			(layers "F.Cu" "F.Mask" "F.Paste")
			(net "P5E_PEX1_STN6_TX_C_DP<110>")
		)
	)
	(footprint ""
		(layer "F.Cu")
		(at 368.734594 -33.631886 180)
		(property "Reference" "C699"
			(at 0 0 180)
			(layer "F.SilkS")
			(hide yes)
			(effects
				(font
					(size 1.27 1.27)
				)
			)
		)
		(property "Value" ""
			(at 0 0 180)
			(layer "F.Fab")
			(effects
				(font
					(size 1.27 1.27)
				)
			)
		)
		(duplicate_pad_numbers_are_jumpers no)
		(fp_line
			(start 0.299974 0.150114)
			(end -0.299974 0.150114)
			(stroke
				(width 0.1)
				(type default)
			)
			(layer "F.Fab")
		)
		(fp_line
			(start 0.299974 -0.150114)
			(end 0.299974 0.150114)
			(stroke
				(width 0.1)
				(type default)
			)
			(layer "F.Fab")
		)
		(fp_line
			(start -0.299974 0.150114)
			(end -0.299974 -0.150114)
			(stroke
				(width 0.1)
				(type default)
			)
			(layer "F.Fab")
		)
		(fp_line
			(start -0.299974 -0.150114)
			(end 0.299974 -0.150114)
			(stroke
				(width 0.1)
				(type default)
			)
			(layer "F.Fab")
		)
		(pad "1" smd rect
			(at -0.2667 0 180)
			(size 0.3048 0.381)
			(layers "F.Cu" "F.Mask" "F.Paste")
			(net "P5E_PEX3_STN2_TX_DN<47>")
		)
		(pad "2" smd rect
			(at 0.2667 0 180)
			(size 0.3048 0.381)
			(layers "F.Cu" "F.Mask" "F.Paste")
			(net "P5E_PEX3_STN2_TX_C_DN<47>")
		)
	)
	(footprint ""
		(layer "F.Cu")
		(at 232.613962 -136.361424 -90)
		(property "Reference" "Y7"
			(at 2.250694 0.915162 0)
			(unlocked yes)
			(layer "F.SilkS")
			(effects
				(font
					(size 0.7874 0.5842)
					(thickness 0.1524)
				)
				(justify left)
			)
		)
		(property "Value" ""
			(at 0 0 270)
			(layer "F.Fab")
			(effects
				(font
					(size 1.27 1.27)
				)
			)
		)
		(duplicate_pad_numbers_are_jumpers no)
		(fp_line
			(start -1.538732 1.937004)
			(end -1.538732 -1.937004)
			(stroke
				(width 0.1524)
				(type default)
			)
			(layer "F.SilkS")
		)
		(fp_line
			(start 1.538732 1.937004)
			(end -1.538732 1.937004)
			(stroke
				(width 0.1524)
				(type default)
			)
			(layer "F.SilkS")
		)
		(fp_line
			(start -1.538732 -1.937004)
			(end 1.538732 -1.937004)
			(stroke
				(width 0.1524)
				(type default)
			)
			(layer "F.SilkS")
		)
		(fp_line
			(start 1.538732 -1.937004)
			(end 1.538732 1.937004)
			(stroke
				(width 0.1524)
				(type default)
			)
			(layer "F.SilkS")
		)
		(fp_poly
			(pts
				(xy -2.758694 -2.478532) (xy -2.146046 -3.09118) (xy -1.839722 -2.172208)
			)
			(stroke
				(width 0)
				(type default)
			)
			(fill yes)
			(layer "F.SilkS")
		)
		(fp_line
			(start -1.299972 1.649984)
			(end -1.299972 -1.649984)
			(stroke
				(width 0.1)
				(type default)
			)
			(layer "F.Fab")
		)
		(fp_line
			(start 1.299972 1.649984)
			(end -1.299972 1.649984)
			(stroke
				(width 0.1)
				(type default)
			)
			(layer "F.Fab")
		)
		(fp_line
			(start -1.299972 -1.649984)
			(end 1.299972 -1.649984)
			(stroke
				(width 0.1)
				(type default)
			)
			(layer "F.Fab")
		)
		(fp_line
			(start 1.299972 -1.649984)
			(end 1.299972 1.649984)
			(stroke
				(width 0.1)
				(type default)
			)
			(layer "F.Fab")
		)
		(fp_poly
			(pts
				(xy -2.5908 -0.626872) (xy -2.5908 -1.493266) (xy -1.724406 -1.059942)
			)
			(stroke
				(width 0)
				(type default)
			)
			(fill yes)
			(layer "F.Fab")
		)
		(pad "1" smd rect
			(at -0.8001 -1.059942 270)
			(size 1.2192 1.4986)
			(layers "F.Cu" "F.Mask" "F.Paste")
			(net "XTAL_CK440_PEX_25M_R_XIN")
		)
		(pad "2" smd rect
			(at -0.8001 1.059942 270)
			(size 1.2192 1.4986)
			(layers "F.Cu" "F.Mask" "F.Paste")
			(net "GND")
		)
		(pad "3" smd rect
			(at 0.8001 1.059942 270)
			(size 1.2192 1.4986)
			(layers "F.Cu" "F.Mask" "F.Paste")
			(net "XTAL_CK440_PEX_25M_XOUT")
		)
		(pad "4" smd rect
			(at 0.8001 -1.059942 270)
			(size 1.2192 1.4986)
			(layers "F.Cu" "F.Mask" "F.Paste")
			(net "GND")
		)
	)
	(footprint ""
		(layer "F.Cu")
		(at 369.071144 -146.205956 180)
		(property "Reference" "C621"
			(at 0 0 180)
			(layer "F.SilkS")
			(hide yes)
			(effects
				(font
					(size 1.27 1.27)
				)
			)
		)
		(property "Value" ""
			(at 0 0 180)
			(layer "F.Fab")
			(effects
				(font
					(size 1.27 1.27)
				)
			)
		)
		(duplicate_pad_numbers_are_jumpers no)
		(fp_line
			(start 0.7874 0.4064)
			(end -0.7874 0.4064)
			(stroke
				(width 0.1524)
				(type default)
			)
			(layer "F.SilkS")
		)
		(fp_line
			(start 0.7874 -0.4064)
			(end 0.7874 0.4064)
			(stroke
				(width 0.1524)
				(type default)
			)
			(layer "F.SilkS")
		)
		(fp_line
			(start -0.7874 0.4064)
			(end -0.7874 -0.4064)
			(stroke
				(width 0.1524)
				(type default)
			)
			(layer "F.SilkS")
		)
		(fp_line
			(start -0.7874 -0.4064)
			(end 0.7874 -0.4064)
			(stroke
				(width 0.1524)
				(type default)
			)
			(layer "F.SilkS")
		)
		(fp_line
			(start 0.67945 0.3048)
			(end 0.120396 0.3048)
			(stroke
				(width 0.1)
				(type default)
			)
			(layer "F.Fab")
		)
		(fp_line
			(start 0.67945 -0.3048)
			(end 0.67945 0.3048)
			(stroke
				(width 0.1)
				(type default)
			)
			(layer "F.Fab")
		)
		(fp_line
			(start 0.12065 -0.2794)
			(end 0.12065 -0.3048)
			(stroke
				(width 0.1)
				(type default)
			)
			(layer "F.Fab")
		)
		(fp_line
			(start 0.12065 -0.3048)
			(end 0.67945 -0.3048)
			(stroke
				(width 0.1)
				(type default)
			)
			(layer "F.Fab")
		)
		(fp_line
			(start 0.120396 0.3048)
			(end 0.120396 0.2794)
			(stroke
				(width 0.1)
				(type default)
			)
			(layer "F.Fab")
		)
		(fp_line
			(start 0.120396 0.2794)
			(end -0.12065 0.2794)
			(stroke
				(width 0.1)
				(type default)
			)
			(layer "F.Fab")
		)
		(fp_line
			(start -0.12065 0.3048)
			(end -0.67945 0.3048)
			(stroke
				(width 0.1)
				(type default)
			)
			(layer "F.Fab")
		)
		(fp_line
			(start -0.12065 0.2794)
			(end -0.12065 0.3048)
			(stroke
				(width 0.1)
				(type default)
			)
			(layer "F.Fab")
		)
		(fp_line
			(start -0.12065 -0.2794)
			(end 0.12065 -0.2794)
			(stroke
				(width 0.1)
				(type default)
			)
			(layer "F.Fab")
		)
		(fp_line
			(start -0.12065 -0.305054)
			(end -0.12065 -0.2794)
			(stroke
				(width 0.1)
				(type default)
			)
			(layer "F.Fab")
		)
		(fp_line
			(start -0.67945 0.3048)
			(end -0.67945 -0.305054)
			(stroke
				(width 0.1)
				(type default)
			)
			(layer "F.Fab")
		)
		(fp_line
			(start -0.67945 -0.305054)
			(end -0.12065 -0.305054)
			(stroke
				(width 0.1)
				(type default)
			)
			(layer "F.Fab")
		)
		(pad "1" smd circle
			(at -0.40005 0 180)
			(size 0 0)
			(layers "F.Cu" "F.Mask" "F.Paste")
			(net "P12V_NIC6_VIN_P")
		)
		(pad "2" smd circle
			(at 0.40005 0 180)
			(size 0 0)
			(layers "F.Cu" "F.Mask" "F.Paste")
			(net "P12V_NIC6_VIN_N")
		)
	)
	(footprint ""
		(layer "F.Cu")
		(at 338.074 -165.989 180)
		(property "Reference" "R4773"
			(at 0 0 180)
			(layer "F.SilkS")
			(hide yes)
			(effects
				(font
					(size 1.27 1.27)
				)
			)
		)
		(property "Value" ""
			(at 0 0 180)
			(layer "F.Fab")
			(effects
				(font
					(size 1.27 1.27)
				)
			)
		)
		(duplicate_pad_numbers_are_jumpers no)
		(fp_line
			(start 0.7874 0.4064)
			(end -0.7874 0.4064)
			(stroke
				(width 0.1524)
				(type default)
			)
			(layer "F.SilkS")
		)
		(fp_line
			(start 0.7874 -0.4064)
			(end 0.7874 0.4064)
			(stroke
				(width 0.1524)
				(type default)
			)
			(layer "F.SilkS")
		)
		(fp_line
			(start -0.7874 0.4064)
			(end -0.7874 -0.4064)
			(stroke
				(width 0.1524)
				(type default)
			)
			(layer "F.SilkS")
		)
		(fp_line
			(start -0.7874 -0.4064)
			(end 0.7874 -0.4064)
			(stroke
				(width 0.1524)
				(type default)
			)
			(layer "F.SilkS")
		)
		(fp_line
			(start 0.67945 0.3048)
			(end 0.120396 0.3048)
			(stroke
				(width 0.1)
				(type default)
			)
			(layer "F.Fab")
		)
		(fp_line
			(start 0.67945 -0.3048)
			(end 0.67945 0.3048)
			(stroke
				(width 0.1)
				(type default)
			)
			(layer "F.Fab")
		)
		(fp_line
			(start 0.12065 -0.2794)
			(end 0.12065 -0.3048)
			(stroke
				(width 0.1)
				(type default)
			)
			(layer "F.Fab")
		)
		(fp_line
			(start 0.12065 -0.3048)
			(end 0.67945 -0.3048)
			(stroke
				(width 0.1)
				(type default)
			)
			(layer "F.Fab")
		)
		(fp_line
			(start 0.120396 0.3048)
			(end 0.120396 0.2794)
			(stroke
				(width 0.1)
				(type default)
			)
			(layer "F.Fab")
		)
		(fp_line
			(start 0.120396 0.2794)
			(end -0.12065 0.2794)
			(stroke
				(width 0.1)
				(type default)
			)
			(layer "F.Fab")
		)
		(fp_line
			(start -0.12065 0.3048)
			(end -0.67945 0.3048)
			(stroke
				(width 0.1)
				(type default)
			)
			(layer "F.Fab")
		)
		(fp_line
			(start -0.12065 0.2794)
			(end -0.12065 0.3048)
			(stroke
				(width 0.1)
				(type default)
			)
			(layer "F.Fab")
		)
		(fp_line
			(start -0.12065 -0.2794)
			(end 0.12065 -0.2794)
			(stroke
				(width 0.1)
				(type default)
			)
			(layer "F.Fab")
		)
		(fp_line
			(start -0.12065 -0.305054)
			(end -0.12065 -0.2794)
			(stroke
				(width 0.1)
				(type default)
			)
			(layer "F.Fab")
		)
		(fp_line
			(start -0.67945 0.3048)
			(end -0.67945 -0.305054)
			(stroke
				(width 0.1)
				(type default)
			)
			(layer "F.Fab")
		)
		(fp_line
			(start -0.67945 -0.305054)
			(end -0.12065 -0.305054)
			(stroke
				(width 0.1)
				(type default)
			)
			(layer "F.Fab")
		)
		(pad "1" smd circle
			(at -0.40005 0 180)
			(size 0 0)
			(layers "F.Cu" "F.Mask" "F.Paste")
			(net "SSD11_PEX_PWR_EN")
		)
		(pad "2" smd circle
			(at 0.40005 0 180)
			(size 0 0)
			(layers "F.Cu" "F.Mask" "F.Paste")
			(net "SSD11_PEX_PWR_EN_R")
		)
	)
	(footprint ""
		(layer "F.Cu")
		(at 211.400136 -185.702956 -90)
		(property "Reference" "U352"
			(at -0.072644 -1.910334 90)
			(unlocked yes)
			(layer "F.SilkS")
			(effects
				(font
					(size 0.7874 0.5842)
					(thickness 0.1524)
				)
			)
		)
		(property "Value" ""
			(at 0 0 270)
			(layer "F.Fab")
			(effects
				(font
					(size 1.27 1.27)
				)
			)
		)
		(duplicate_pad_numbers_are_jumpers no)
		(fp_line
			(start -1.7272 1.1176)
			(end -1.7272 -1.1176)
			(stroke
				(width 0.1524)
				(type default)
			)
			(layer "F.SilkS")
		)
		(fp_line
			(start 1.7272 1.1176)
			(end -1.7272 1.1176)
			(stroke
				(width 0.1524)
				(type default)
			)
			(layer "F.SilkS")
		)
		(fp_line
			(start 0 -0.7366)
			(end -0.254 -1.1176)
			(stroke
				(width 0.1524)
				(type default)
			)
			(layer "F.SilkS")
		)
		(fp_line
			(start -0.254 -1.1176)
			(end -1.7272 -1.1176)
			(stroke
				(width 0.1524)
				(type default)
			)
			(layer "F.SilkS")
		)
		(fp_line
			(start 0.254 -1.1176)
			(end 0 -0.7366)
			(stroke
				(width 0.1524)
				(type default)
			)
			(layer "F.SilkS")
		)
		(fp_line
			(start 1.7272 -1.1176)
			(end 1.7272 1.1176)
			(stroke
				(width 0.1524)
				(type default)
			)
			(layer "F.SilkS")
		)
		(fp_line
			(start 1.7272 -1.1176)
			(end 0.254 -1.1176)
			(stroke
				(width 0.1524)
				(type default)
			)
			(layer "F.SilkS")
		)
		(fp_poly
			(pts
				(xy -1.70942 -1.378204) (xy -2.09042 -2.140204) (xy -1.32842 -2.140204)
			)
			(stroke
				(width 0)
				(type default)
			)
			(fill yes)
			(layer "F.SilkS")
		)
		(fp_line
			(start -1.5748 1.1176)
			(end 1.5748 1.1176)
			(stroke
				(width 0.1)
				(type default)
			)
			(layer "F.Fab")
		)
		(fp_line
			(start 1.5748 1.1176)
			(end 1.5748 -1.1176)
			(stroke
				(width 0.1)
				(type default)
			)
			(layer "F.Fab")
		)
		(fp_line
			(start -1.5748 -1.1176)
			(end -1.5748 1.1176)
			(stroke
				(width 0.1)
				(type default)
			)
			(layer "F.Fab")
		)
		(fp_line
			(start 1.5748 -1.1176)
			(end -1.5748 -1.1176)
			(stroke
				(width 0.1)
				(type default)
			)
			(layer "F.Fab")
		)
		(fp_poly
			(pts
				(xy -1.9558 -0.649986) (xy -2.7178 -0.268986) (xy -2.7178 -1.030986)
			)
			(stroke
				(width 0)
				(type default)
			)
			(fill yes)
			(layer "F.Fab")
		)
		(pad "1" smd rect
			(at -0.999998 -0.649986 180)
			(size 0.3556 1.1176)
			(layers "F.Cu" "F.Mask" "F.Paste")
			(net "BIC_SEL_FLASH_SW2_R")
		)
		(pad "2" smd rect
			(at -0.999998 0 180)
			(size 0.3556 1.1176)
			(layers "F.Cu" "F.Mask" "F.Paste")
			(net "GND")
		)
		(pad "3" smd rect
			(at -0.999998 0.649986 180)
			(size 0.3556 1.1176)
			(layers "F.Cu" "F.Mask" "F.Paste")
			(net "BIC_SEL_FLASH_SW3_R")
		)
		(pad "4" smd rect
			(at 0.999998 0.649986 180)
			(size 0.3556 1.1176)
			(layers "F.Cu" "F.Mask" "F.Paste")
			(net "SEL_FLASH_PEX3_BUF")
		)
		(pad "5" smd rect
			(at 0.999998 0 180)
			(size 0.3556 1.1176)
			(layers "F.Cu" "F.Mask" "F.Paste")
			(net "P3V3_AUX")
		)
		(pad "6" smd rect
			(at 0.999998 -0.649986 180)
			(size 0.3556 1.1176)
			(layers "F.Cu" "F.Mask" "F.Paste")
			(net "SEL_FLASH_PEX2_BUF")
		)
	)
	(footprint ""
		(layer "F.Cu")
		(at 361.927394 -391.25779 180)
		(property "Reference" "Q245"
			(at -1.302512 -2.186686 0)
			(unlocked yes)
			(layer "F.SilkS")
			(effects
				(font
					(size 0.7874 0.5842)
					(thickness 0.1524)
				)
			)
		)
		(property "Value" ""
			(at 0 0 180)
			(layer "F.Fab")
			(effects
				(font
					(size 1.27 1.27)
				)
			)
		)
		(duplicate_pad_numbers_are_jumpers no)
		(fp_line
			(start 1.376172 1.199896)
			(end -1.376172 1.199896)
			(stroke
				(width 0.1524)
				(type default)
			)
			(layer "F.SilkS")
		)
		(fp_line
			(start 1.376172 -1.199896)
			(end 1.376172 1.199896)
			(stroke
				(width 0.1524)
				(type default)
			)
			(layer "F.SilkS")
		)
		(fp_line
			(start 0.508 -1.199896)
			(end 1.376172 -1.199896)
			(stroke
				(width 0.1524)
				(type default)
			)
			(layer "F.SilkS")
		)
		(fp_line
			(start 0 -0.762)
			(end 0.508 -1.199896)
			(stroke
				(width 0.1524)
				(type default)
			)
			(layer "F.SilkS")
		)
		(fp_line
			(start -0.508 -1.199896)
			(end 0 -0.762)
			(stroke
				(width 0.1524)
				(type default)
			)
			(layer "F.SilkS")
		)
		(fp_line
			(start -1.376172 1.199896)
			(end -1.376172 -1.199896)
			(stroke
				(width 0.1524)
				(type default)
			)
			(layer "F.SilkS")
		)
		(fp_line
			(start -1.376172 -1.199896)
			(end -0.508 -1.199896)
			(stroke
				(width 0.1524)
				(type default)
			)
			(layer "F.SilkS")
		)
		(fp_poly
			(pts
				(xy -1.4605 -0.7493) (xy -2.2225 -1.1303) (xy -2.2225 -0.3683)
			)
			(stroke
				(width 0)
				(type default)
			)
			(fill yes)
			(layer "F.SilkS")
		)
		(fp_line
			(start 0.674878 1.100074)
			(end -0.674878 1.100074)
			(stroke
				(width 0.1)
				(type default)
			)
			(layer "F.Fab")
		)
		(fp_line
			(start 0.674878 -1.100074)
			(end 0.674878 1.100074)
			(stroke
				(width 0.1)
				(type default)
			)
			(layer "F.Fab")
		)
		(fp_line
			(start -0.674878 1.100074)
			(end -0.674878 -1.100074)
			(stroke
				(width 0.1)
				(type default)
			)
			(layer "F.Fab")
		)
		(fp_line
			(start -0.674878 -1.100074)
			(end 0.674878 -1.100074)
			(stroke
				(width 0.1)
				(type default)
			)
			(layer "F.Fab")
		)
		(fp_poly
			(pts
				(xy -1.4605 -0.7493) (xy -2.2225 -1.1303) (xy -2.2225 -0.3683)
			)
			(stroke
				(width 0)
				(type default)
			)
			(fill yes)
			(layer "F.Fab")
		)
		(pad "1" smd rect
			(at -0.899922 -0.750062 90)
			(size 0.6096 0.6096)
			(layers "F.Cu" "F.Mask" "F.Paste")
			(net "GND")
		)
		(pad "2" smd rect
			(at -0.899922 0 90)
			(size 0.4064 0.6096)
			(layers "F.Cu" "F.Mask" "F.Paste")
			(net "MB_3V3IO_RSVD1")
		)
		(pad "3" smd rect
			(at -0.899922 0.750062 90)
			(size 0.6096 0.6096)
			(layers "F.Cu" "F.Mask" "F.Paste")
			(net "MB_3V3IO_RSVD1_ISO")
		)
		(pad "4" smd rect
			(at 0.899922 0.750062 90)
			(size 0.6096 0.6096)
			(layers "F.Cu" "F.Mask" "F.Paste")
			(net "GND")
		)
		(pad "5" smd rect
			(at 0.899922 0 90)
			(size 0.4064 0.6096)
			(layers "F.Cu" "F.Mask" "F.Paste")
			(net "MB_3V3IO_RSVD1_N")
		)
		(pad "6" smd rect
			(at 0.899922 -0.750062 90)
			(size 0.6096 0.6096)
			(layers "F.Cu" "F.Mask" "F.Paste")
			(net "MB_3V3IO_RSVD1_N")
		)
	)
	(footprint ""
		(layer "F.Cu")
		(at 317.735712 -289.230816 -90)
		(property "Reference" "R6397"
			(at 0 0 270)
			(layer "F.SilkS")
			(hide yes)
			(effects
				(font
					(size 1.27 1.27)
				)
			)
		)
		(property "Value" ""
			(at 0 0 270)
			(layer "F.Fab")
			(effects
				(font
					(size 1.27 1.27)
				)
			)
		)
		(duplicate_pad_numbers_are_jumpers no)
		(fp_line
			(start -0.7874 0.4064)
			(end -0.7874 -0.4064)
			(stroke
				(width 0.1524)
				(type default)
			)
			(layer "F.SilkS")
		)
		(fp_line
			(start 0.7874 0.4064)
			(end -0.7874 0.4064)
			(stroke
				(width 0.1524)
				(type default)
			)
			(layer "F.SilkS")
		)
		(fp_line
			(start -0.7874 -0.4064)
			(end 0.7874 -0.4064)
			(stroke
				(width 0.1524)
				(type default)
			)
			(layer "F.SilkS")
		)
		(fp_line
			(start 0.7874 -0.4064)
			(end 0.7874 0.4064)
			(stroke
				(width 0.1524)
				(type default)
			)
			(layer "F.SilkS")
		)
		(fp_line
			(start -0.67945 0.3048)
			(end -0.67945 -0.305054)
			(stroke
				(width 0.1)
				(type default)
			)
			(layer "F.Fab")
		)
		(fp_line
			(start -0.12065 0.3048)
			(end -0.67945 0.3048)
			(stroke
				(width 0.1)
				(type default)
			)
			(layer "F.Fab")
		)
		(fp_line
			(start 0.120396 0.3048)
			(end 0.120396 0.2794)
			(stroke
				(width 0.1)
				(type default)
			)
			(layer "F.Fab")
		)
		(fp_line
			(start 0.67945 0.3048)
			(end 0.120396 0.3048)
			(stroke
				(width 0.1)
				(type default)
			)
			(layer "F.Fab")
		)
		(fp_line
			(start -0.12065 0.2794)
			(end -0.12065 0.3048)
			(stroke
				(width 0.1)
				(type default)
			)
			(layer "F.Fab")
		)
		(fp_line
			(start 0.120396 0.2794)
			(end -0.12065 0.2794)
			(stroke
				(width 0.1)
				(type default)
			)
			(layer "F.Fab")
		)
		(fp_line
			(start -0.12065 -0.2794)
			(end 0.12065 -0.2794)
			(stroke
				(width 0.1)
				(type default)
			)
			(layer "F.Fab")
		)
		(fp_line
			(start 0.12065 -0.2794)
			(end 0.12065 -0.3048)
			(stroke
				(width 0.1)
				(type default)
			)
			(layer "F.Fab")
		)
		(fp_line
			(start 0.12065 -0.3048)
			(end 0.67945 -0.3048)
			(stroke
				(width 0.1)
				(type default)
			)
			(layer "F.Fab")
		)
		(fp_line
			(start 0.67945 -0.3048)
			(end 0.67945 0.3048)
			(stroke
				(width 0.1)
				(type default)
			)
			(layer "F.Fab")
		)
		(fp_line
			(start -0.67945 -0.305054)
			(end -0.12065 -0.305054)
			(stroke
				(width 0.1)
				(type default)
			)
			(layer "F.Fab")
		)
		(fp_line
			(start -0.12065 -0.305054)
			(end -0.12065 -0.2794)
			(stroke
				(width 0.1)
				(type default)
			)
			(layer "F.Fab")
		)
		(pad "1" smd circle
			(at -0.40005 0 270)
			(size 0 0)
			(layers "F.Cu" "F.Mask" "F.Paste")
			(net "RST_PEX2_S0_PERST_N")
		)
		(pad "2" smd circle
			(at 0.40005 0 270)
			(size 0 0)
			(layers "F.Cu" "F.Mask" "F.Paste")
			(net "RST_PEX2_S0_PERST_R_N")
		)
	)
	(footprint ""
		(layer "F.Cu")
		(at 333.883 -234.061 90)
		(property "Reference" "R3521"
			(at 0 0 90)
			(layer "F.SilkS")
			(hide yes)
			(effects
				(font
					(size 1.27 1.27)
				)
			)
		)
		(property "Value" ""
			(at 0 0 90)
			(layer "F.Fab")
			(effects
				(font
					(size 1.27 1.27)
				)
			)
		)
		(duplicate_pad_numbers_are_jumpers no)
		(fp_line
			(start 0.7874 -0.4064)
			(end 0.7874 0.4064)
			(stroke
				(width 0.1524)
				(type default)
			)
			(layer "F.SilkS")
		)
		(fp_line
			(start -0.7874 -0.4064)
			(end 0.7874 -0.4064)
			(stroke
				(width 0.1524)
				(type default)
			)
			(layer "F.SilkS")
		)
		(fp_line
			(start 0.7874 0.4064)
			(end -0.7874 0.4064)
			(stroke
				(width 0.1524)
				(type default)
			)
			(layer "F.SilkS")
		)
		(fp_line
			(start -0.7874 0.4064)
			(end -0.7874 -0.4064)
			(stroke
				(width 0.1524)
				(type default)
			)
			(layer "F.SilkS")
		)
		(fp_line
			(start -0.12065 -0.305054)
			(end -0.12065 -0.2794)
			(stroke
				(width 0.1)
				(type default)
			)
			(layer "F.Fab")
		)
		(fp_line
			(start -0.67945 -0.305054)
			(end -0.12065 -0.305054)
			(stroke
				(width 0.1)
				(type default)
			)
			(layer "F.Fab")
		)
		(fp_line
			(start 0.67945 -0.3048)
			(end 0.67945 0.3048)
			(stroke
				(width 0.1)
				(type default)
			)
			(layer "F.Fab")
		)
		(fp_line
			(start 0.12065 -0.3048)
			(end 0.67945 -0.3048)
			(stroke
				(width 0.1)
				(type default)
			)
			(layer "F.Fab")
		)
		(fp_line
			(start 0.12065 -0.2794)
			(end 0.12065 -0.3048)
			(stroke
				(width 0.1)
				(type default)
			)
			(layer "F.Fab")
		)
		(fp_line
			(start -0.12065 -0.2794)
			(end 0.12065 -0.2794)
			(stroke
				(width 0.1)
				(type default)
			)
			(layer "F.Fab")
		)
		(fp_line
			(start 0.120396 0.2794)
			(end -0.12065 0.2794)
			(stroke
				(width 0.1)
				(type default)
			)
			(layer "F.Fab")
		)
		(fp_line
			(start -0.12065 0.2794)
			(end -0.12065 0.3048)
			(stroke
				(width 0.1)
				(type default)
			)
			(layer "F.Fab")
		)
		(fp_line
			(start 0.67945 0.3048)
			(end 0.120396 0.3048)
			(stroke
				(width 0.1)
				(type default)
			)
			(layer "F.Fab")
		)
		(fp_line
			(start 0.120396 0.3048)
			(end 0.120396 0.2794)
			(stroke
				(width 0.1)
				(type default)
			)
			(layer "F.Fab")
		)
		(fp_line
			(start -0.12065 0.3048)
			(end -0.67945 0.3048)
			(stroke
				(width 0.1)
				(type default)
			)
			(layer "F.Fab")
		)
		(fp_line
			(start -0.67945 0.3048)
			(end -0.67945 -0.305054)
			(stroke
				(width 0.1)
				(type default)
			)
			(layer "F.Fab")
		)
		(pad "1" smd circle
			(at -0.40005 0 90)
			(size 0 0)
			(layers "F.Cu" "F.Mask" "F.Paste")
			(net "SSD2_PWR_EN")
		)
		(pad "2" smd circle
			(at 0.40005 0 90)
			(size 0 0)
			(layers "F.Cu" "F.Mask" "F.Paste")
			(net "SSD2_PWR_EN_R")
		)
	)
	(footprint ""
		(layer "F.Cu")
		(at 61.493908 -165.670484 -90)
		(property "Reference" "R2463"
			(at 0 0 270)
			(layer "F.SilkS")
			(hide yes)
			(effects
				(font
					(size 1.27 1.27)
				)
			)
		)
		(property "Value" ""
			(at 0 0 270)
			(layer "F.Fab")
			(effects
				(font
					(size 1.27 1.27)
				)
			)
		)
		(duplicate_pad_numbers_are_jumpers no)
		(fp_line
			(start -0.7874 0.4064)
			(end -0.7874 -0.4064)
			(stroke
				(width 0.1524)
				(type default)
			)
			(layer "F.SilkS")
		)
		(fp_line
			(start 0.7874 0.4064)
			(end -0.7874 0.4064)
			(stroke
				(width 0.1524)
				(type default)
			)
			(layer "F.SilkS")
		)
		(fp_line
			(start -0.7874 -0.4064)
			(end 0.7874 -0.4064)
			(stroke
				(width 0.1524)
				(type default)
			)
			(layer "F.SilkS")
		)
		(fp_line
			(start 0.7874 -0.4064)
			(end 0.7874 0.4064)
			(stroke
				(width 0.1524)
				(type default)
			)
			(layer "F.SilkS")
		)
		(fp_line
			(start -0.67945 0.3048)
			(end -0.67945 -0.305054)
			(stroke
				(width 0.1)
				(type default)
			)
			(layer "F.Fab")
		)
		(fp_line
			(start -0.12065 0.3048)
			(end -0.67945 0.3048)
			(stroke
				(width 0.1)
				(type default)
			)
			(layer "F.Fab")
		)
		(fp_line
			(start 0.120396 0.3048)
			(end 0.120396 0.2794)
			(stroke
				(width 0.1)
				(type default)
			)
			(layer "F.Fab")
		)
		(fp_line
			(start 0.67945 0.3048)
			(end 0.120396 0.3048)
			(stroke
				(width 0.1)
				(type default)
			)
			(layer "F.Fab")
		)
		(fp_line
			(start -0.12065 0.2794)
			(end -0.12065 0.3048)
			(stroke
				(width 0.1)
				(type default)
			)
			(layer "F.Fab")
		)
		(fp_line
			(start 0.120396 0.2794)
			(end -0.12065 0.2794)
			(stroke
				(width 0.1)
				(type default)
			)
			(layer "F.Fab")
		)
		(fp_line
			(start -0.12065 -0.2794)
			(end 0.12065 -0.2794)
			(stroke
				(width 0.1)
				(type default)
			)
			(layer "F.Fab")
		)
		(fp_line
			(start 0.12065 -0.2794)
			(end 0.12065 -0.3048)
			(stroke
				(width 0.1)
				(type default)
			)
			(layer "F.Fab")
		)
		(fp_line
			(start 0.12065 -0.3048)
			(end 0.67945 -0.3048)
			(stroke
				(width 0.1)
				(type default)
			)
			(layer "F.Fab")
		)
		(fp_line
			(start 0.67945 -0.3048)
			(end 0.67945 0.3048)
			(stroke
				(width 0.1)
				(type default)
			)
			(layer "F.Fab")
		)
		(fp_line
			(start -0.67945 -0.305054)
			(end -0.12065 -0.305054)
			(stroke
				(width 0.1)
				(type default)
			)
			(layer "F.Fab")
		)
		(fp_line
			(start -0.12065 -0.305054)
			(end -0.12065 -0.2794)
			(stroke
				(width 0.1)
				(type default)
			)
			(layer "F.Fab")
		)
		(pad "1" smd circle
			(at -0.40005 0 270)
			(size 0 0)
			(layers "F.Cu" "F.Mask" "F.Paste")
			(net "P3V3_NIC0")
		)
		(pad "2" smd circle
			(at 0.40005 0 270)
			(size 0 0)
			(layers "F.Cu" "F.Mask" "F.Paste")
			(net "NIC0_PWRBRK_N")
		)
	)
	(footprint ""
		(layer "F.Cu")
		(at 144.506442 -250.070874 -90)
		(property "Reference" "R1267"
			(at 0 0 270)
			(layer "F.SilkS")
			(hide yes)
			(effects
				(font
					(size 1.27 1.27)
				)
			)
		)
		(property "Value" ""
			(at 0 0 270)
			(layer "F.Fab")
			(effects
				(font
					(size 1.27 1.27)
				)
			)
		)
		(duplicate_pad_numbers_are_jumpers no)
		(fp_line
			(start -0.7874 0.4064)
			(end -0.7874 -0.4064)
			(stroke
				(width 0.1524)
				(type default)
			)
			(layer "F.SilkS")
		)
		(fp_line
			(start 0.7874 0.4064)
			(end -0.7874 0.4064)
			(stroke
				(width 0.1524)
				(type default)
			)
			(layer "F.SilkS")
		)
		(fp_line
			(start -0.7874 -0.4064)
			(end 0.7874 -0.4064)
			(stroke
				(width 0.1524)
				(type default)
			)
			(layer "F.SilkS")
		)
		(fp_line
			(start 0.7874 -0.4064)
			(end 0.7874 0.4064)
			(stroke
				(width 0.1524)
				(type default)
			)
			(layer "F.SilkS")
		)
		(fp_line
			(start -0.67945 0.3048)
			(end -0.67945 -0.305054)
			(stroke
				(width 0.1)
				(type default)
			)
			(layer "F.Fab")
		)
		(fp_line
			(start -0.12065 0.3048)
			(end -0.67945 0.3048)
			(stroke
				(width 0.1)
				(type default)
			)
			(layer "F.Fab")
		)
		(fp_line
			(start 0.120396 0.3048)
			(end 0.120396 0.2794)
			(stroke
				(width 0.1)
				(type default)
			)
			(layer "F.Fab")
		)
		(fp_line
			(start 0.67945 0.3048)
			(end 0.120396 0.3048)
			(stroke
				(width 0.1)
				(type default)
			)
			(layer "F.Fab")
		)
		(fp_line
			(start -0.12065 0.2794)
			(end -0.12065 0.3048)
			(stroke
				(width 0.1)
				(type default)
			)
			(layer "F.Fab")
		)
		(fp_line
			(start 0.120396 0.2794)
			(end -0.12065 0.2794)
			(stroke
				(width 0.1)
				(type default)
			)
			(layer "F.Fab")
		)
		(fp_line
			(start -0.12065 -0.2794)
			(end 0.12065 -0.2794)
			(stroke
				(width 0.1)
				(type default)
			)
			(layer "F.Fab")
		)
		(fp_line
			(start 0.12065 -0.2794)
			(end 0.12065 -0.3048)
			(stroke
				(width 0.1)
				(type default)
			)
			(layer "F.Fab")
		)
		(fp_line
			(start 0.12065 -0.3048)
			(end 0.67945 -0.3048)
			(stroke
				(width 0.1)
				(type default)
			)
			(layer "F.Fab")
		)
		(fp_line
			(start 0.67945 -0.3048)
			(end 0.67945 0.3048)
			(stroke
				(width 0.1)
				(type default)
			)
			(layer "F.Fab")
		)
		(fp_line
			(start -0.67945 -0.305054)
			(end -0.12065 -0.305054)
			(stroke
				(width 0.1)
				(type default)
			)
			(layer "F.Fab")
		)
		(fp_line
			(start -0.12065 -0.305054)
			(end -0.12065 -0.2794)
			(stroke
				(width 0.1)
				(type default)
			)
			(layer "F.Fab")
		)
		(pad "1" smd circle
			(at -0.40005 0 270)
			(size 0 0)
			(layers "F.Cu" "F.Mask" "F.Paste")
			(net "PEX1_DBG_MODE3")
		)
		(pad "2" smd circle
			(at 0.40005 0 270)
			(size 0 0)
			(layers "F.Cu" "F.Mask" "F.Paste")
			(net "P1V8_PEX")
		)
	)
	(footprint ""
		(layer "F.Cu")
		(at 10.401554 -394.13942 -90)
		(property "Reference" "R6742"
			(at 0 0 270)
			(layer "F.SilkS")
			(hide yes)
			(effects
				(font
					(size 1.27 1.27)
				)
			)
		)
		(property "Value" ""
			(at 0 0 270)
			(layer "F.Fab")
			(effects
				(font
					(size 1.27 1.27)
				)
			)
		)
		(duplicate_pad_numbers_are_jumpers no)
		(fp_line
			(start -0.7874 0.4064)
			(end -0.7874 -0.4064)
			(stroke
				(width 0.1524)
				(type default)
			)
			(layer "F.SilkS")
		)
		(fp_line
			(start 0.7874 0.4064)
			(end -0.7874 0.4064)
			(stroke
				(width 0.1524)
				(type default)
			)
			(layer "F.SilkS")
		)
		(fp_line
			(start -0.7874 -0.4064)
			(end 0.7874 -0.4064)
			(stroke
				(width 0.1524)
				(type default)
			)
			(layer "F.SilkS")
		)
		(fp_line
			(start 0.7874 -0.4064)
			(end 0.7874 0.4064)
			(stroke
				(width 0.1524)
				(type default)
			)
			(layer "F.SilkS")
		)
		(fp_line
			(start -0.67945 0.3048)
			(end -0.67945 -0.305054)
			(stroke
				(width 0.1)
				(type default)
			)
			(layer "F.Fab")
		)
		(fp_line
			(start -0.12065 0.3048)
			(end -0.67945 0.3048)
			(stroke
				(width 0.1)
				(type default)
			)
			(layer "F.Fab")
		)
		(fp_line
			(start 0.120396 0.3048)
			(end 0.120396 0.2794)
			(stroke
				(width 0.1)
				(type default)
			)
			(layer "F.Fab")
		)
		(fp_line
			(start 0.67945 0.3048)
			(end 0.120396 0.3048)
			(stroke
				(width 0.1)
				(type default)
			)
			(layer "F.Fab")
		)
		(fp_line
			(start -0.12065 0.2794)
			(end -0.12065 0.3048)
			(stroke
				(width 0.1)
				(type default)
			)
			(layer "F.Fab")
		)
		(fp_line
			(start 0.120396 0.2794)
			(end -0.12065 0.2794)
			(stroke
				(width 0.1)
				(type default)
			)
			(layer "F.Fab")
		)
		(fp_line
			(start -0.12065 -0.2794)
			(end 0.12065 -0.2794)
			(stroke
				(width 0.1)
				(type default)
			)
			(layer "F.Fab")
		)
		(fp_line
			(start 0.12065 -0.2794)
			(end 0.12065 -0.3048)
			(stroke
				(width 0.1)
				(type default)
			)
			(layer "F.Fab")
		)
		(fp_line
			(start 0.12065 -0.3048)
			(end 0.67945 -0.3048)
			(stroke
				(width 0.1)
				(type default)
			)
			(layer "F.Fab")
		)
		(fp_line
			(start 0.67945 -0.3048)
			(end 0.67945 0.3048)
			(stroke
				(width 0.1)
				(type default)
			)
			(layer "F.Fab")
		)
		(fp_line
			(start -0.67945 -0.305054)
			(end -0.12065 -0.305054)
			(stroke
				(width 0.1)
				(type default)
			)
			(layer "F.Fab")
		)
		(fp_line
			(start -0.12065 -0.305054)
			(end -0.12065 -0.2794)
			(stroke
				(width 0.1)
				(type default)
			)
			(layer "F.Fab")
		)
		(pad "1" smd circle
			(at -0.40005 0 270)
			(size 0 0)
			(layers "F.Cu" "F.Mask" "F.Paste")
			(net "P3V3_USB_8042")
		)
		(pad "2" smd circle
			(at 0.40005 0 270)
			(size 0 0)
			(layers "F.Cu" "F.Mask" "F.Paste")
			(net "BIC_USB_8042_HUB_OVCUR3")
		)
	)
	(footprint ""
		(layer "F.Cu")
		(at 229.954836 -240.946178)
		(property "Reference" "C3988"
			(at 0 0 0)
			(layer "F.SilkS")
			(hide yes)
			(effects
				(font
					(size 1.27 1.27)
				)
			)
		)
		(property "Value" ""
			(at 0 0 0)
			(layer "F.Fab")
			(effects
				(font
					(size 1.27 1.27)
				)
			)
		)
		(duplicate_pad_numbers_are_jumpers no)
		(fp_line
			(start -0.7874 -0.4064)
			(end 0.7874 -0.4064)
			(stroke
				(width 0.1524)
				(type default)
			)
			(layer "F.SilkS")
		)
		(fp_line
			(start -0.7874 0.4064)
			(end -0.7874 -0.4064)
			(stroke
				(width 0.1524)
				(type default)
			)
			(layer "F.SilkS")
		)
		(fp_line
			(start 0.7874 -0.4064)
			(end 0.7874 0.4064)
			(stroke
				(width 0.1524)
				(type default)
			)
			(layer "F.SilkS")
		)
		(fp_line
			(start 0.7874 0.4064)
			(end -0.7874 0.4064)
			(stroke
				(width 0.1524)
				(type default)
			)
			(layer "F.SilkS")
		)
		(fp_line
			(start -0.67945 -0.305054)
			(end -0.12065 -0.305054)
			(stroke
				(width 0.1)
				(type default)
			)
			(layer "F.Fab")
		)
		(fp_line
			(start -0.67945 0.3048)
			(end -0.67945 -0.305054)
			(stroke
				(width 0.1)
				(type default)
			)
			(layer "F.Fab")
		)
		(fp_line
			(start -0.12065 -0.305054)
			(end -0.12065 -0.2794)
			(stroke
				(width 0.1)
				(type default)
			)
			(layer "F.Fab")
		)
		(fp_line
			(start -0.12065 -0.2794)
			(end 0.12065 -0.2794)
			(stroke
				(width 0.1)
				(type default)
			)
			(layer "F.Fab")
		)
		(fp_line
			(start -0.12065 0.2794)
			(end -0.12065 0.3048)
			(stroke
				(width 0.1)
				(type default)
			)
			(layer "F.Fab")
		)
		(fp_line
			(start -0.12065 0.3048)
			(end -0.67945 0.3048)
			(stroke
				(width 0.1)
				(type default)
			)
			(layer "F.Fab")
		)
		(fp_line
			(start 0.120396 0.2794)
			(end -0.12065 0.2794)
			(stroke
				(width 0.1)
				(type default)
			)
			(layer "F.Fab")
		)
		(fp_line
			(start 0.120396 0.3048)
			(end 0.120396 0.2794)
			(stroke
				(width 0.1)
				(type default)
			)
			(layer "F.Fab")
		)
		(fp_line
			(start 0.12065 -0.3048)
			(end 0.67945 -0.3048)
			(stroke
				(width 0.1)
				(type default)
			)
			(layer "F.Fab")
		)
		(fp_line
			(start 0.12065 -0.2794)
			(end 0.12065 -0.3048)
			(stroke
				(width 0.1)
				(type default)
			)
			(layer "F.Fab")
		)
		(fp_line
			(start 0.67945 -0.3048)
			(end 0.67945 0.3048)
			(stroke
				(width 0.1)
				(type default)
			)
			(layer "F.Fab")
		)
		(fp_line
			(start 0.67945 0.3048)
			(end 0.120396 0.3048)
			(stroke
				(width 0.1)
				(type default)
			)
			(layer "F.Fab")
		)
		(pad "1" smd circle
			(at -0.40005 0)
			(size 0 0)
			(layers "F.Cu" "F.Mask" "F.Paste")
			(net "P3V3_AUX")
		)
		(pad "2" smd circle
			(at 0.40005 0)
			(size 0 0)
			(layers "F.Cu" "F.Mask" "F.Paste")
			(net "GND")
		)
	)
	(footprint ""
		(layer "F.Cu")
		(at 387.62178 -356.244906 90)
		(property "Reference" "C761"
			(at 0 0 90)
			(layer "F.SilkS")
			(hide yes)
			(effects
				(font
					(size 1.27 1.27)
				)
			)
		)
		(property "Value" ""
			(at 0 0 90)
			(layer "F.Fab")
			(effects
				(font
					(size 1.27 1.27)
				)
			)
		)
		(duplicate_pad_numbers_are_jumpers no)
		(fp_line
			(start 0.299974 -0.150114)
			(end 0.299974 0.150114)
			(stroke
				(width 0.1)
				(type default)
			)
			(layer "F.Fab")
		)
		(fp_line
			(start -0.299974 -0.150114)
			(end 0.299974 -0.150114)
			(stroke
				(width 0.1)
				(type default)
			)
			(layer "F.Fab")
		)
		(fp_line
			(start 0.299974 0.150114)
			(end -0.299974 0.150114)
			(stroke
				(width 0.1)
				(type default)
			)
			(layer "F.Fab")
		)
		(fp_line
			(start -0.299974 0.150114)
			(end -0.299974 -0.150114)
			(stroke
				(width 0.1)
				(type default)
			)
			(layer "F.Fab")
		)
		(pad "1" smd rect
			(at -0.2667 0 90)
			(size 0.3048 0.381)
			(layers "F.Cu" "F.Mask" "F.Paste")
			(net "P5E_PEX3_STN5_TX_DN<80>")
		)
		(pad "2" smd rect
			(at 0.2667 0 90)
			(size 0.3048 0.381)
			(layers "F.Cu" "F.Mask" "F.Paste")
			(net "P5E_PEX3_STN5_TX_C_DN<80>")
		)
	)
	(footprint ""
		(layer "F.Cu")
		(at 420.096188 -47.20082 90)
		(property "Reference" "C404"
			(at 0 0 90)
			(layer "F.SilkS")
			(hide yes)
			(effects
				(font
					(size 1.27 1.27)
				)
			)
		)
		(property "Value" ""
			(at 0 0 90)
			(layer "F.Fab")
			(effects
				(font
					(size 1.27 1.27)
				)
			)
		)
		(duplicate_pad_numbers_are_jumpers no)
		(fp_line
			(start 0.7874 -0.4064)
			(end 0.7874 0.4064)
			(stroke
				(width 0.1524)
				(type default)
			)
			(layer "F.SilkS")
		)
		(fp_line
			(start -0.7874 -0.4064)
			(end 0.7874 -0.4064)
			(stroke
				(width 0.1524)
				(type default)
			)
			(layer "F.SilkS")
		)
		(fp_line
			(start 0.7874 0.4064)
			(end -0.7874 0.4064)
			(stroke
				(width 0.1524)
				(type default)
			)
			(layer "F.SilkS")
		)
		(fp_line
			(start -0.7874 0.4064)
			(end -0.7874 -0.4064)
			(stroke
				(width 0.1524)
				(type default)
			)
			(layer "F.SilkS")
		)
		(fp_line
			(start -0.12065 -0.305054)
			(end -0.12065 -0.2794)
			(stroke
				(width 0.1)
				(type default)
			)
			(layer "F.Fab")
		)
		(fp_line
			(start -0.67945 -0.305054)
			(end -0.12065 -0.305054)
			(stroke
				(width 0.1)
				(type default)
			)
			(layer "F.Fab")
		)
		(fp_line
			(start 0.67945 -0.3048)
			(end 0.67945 0.3048)
			(stroke
				(width 0.1)
				(type default)
			)
			(layer "F.Fab")
		)
		(fp_line
			(start 0.12065 -0.3048)
			(end 0.67945 -0.3048)
			(stroke
				(width 0.1)
				(type default)
			)
			(layer "F.Fab")
		)
		(fp_line
			(start 0.12065 -0.2794)
			(end 0.12065 -0.3048)
			(stroke
				(width 0.1)
				(type default)
			)
			(layer "F.Fab")
		)
		(fp_line
			(start -0.12065 -0.2794)
			(end 0.12065 -0.2794)
			(stroke
				(width 0.1)
				(type default)
			)
			(layer "F.Fab")
		)
		(fp_line
			(start 0.120396 0.2794)
			(end -0.12065 0.2794)
			(stroke
				(width 0.1)
				(type default)
			)
			(layer "F.Fab")
		)
		(fp_line
			(start -0.12065 0.2794)
			(end -0.12065 0.3048)
			(stroke
				(width 0.1)
				(type default)
			)
			(layer "F.Fab")
		)
		(fp_line
			(start 0.67945 0.3048)
			(end 0.120396 0.3048)
			(stroke
				(width 0.1)
				(type default)
			)
			(layer "F.Fab")
		)
		(fp_line
			(start 0.120396 0.3048)
			(end 0.120396 0.2794)
			(stroke
				(width 0.1)
				(type default)
			)
			(layer "F.Fab")
		)
		(fp_line
			(start -0.12065 0.3048)
			(end -0.67945 0.3048)
			(stroke
				(width 0.1)
				(type default)
			)
			(layer "F.Fab")
		)
		(fp_line
			(start -0.67945 0.3048)
			(end -0.67945 -0.305054)
			(stroke
				(width 0.1)
				(type default)
			)
			(layer "F.Fab")
		)
		(pad "1" smd circle
			(at -0.40005 0 90)
			(size 0 0)
			(layers "F.Cu" "F.Mask" "F.Paste")
			(net "P12V_SSD14_R")
		)
		(pad "2" smd circle
			(at 0.40005 0 90)
			(size 0 0)
			(layers "F.Cu" "F.Mask" "F.Paste")
			(net "GND")
		)
	)
	(footprint ""
		(layer "F.Cu")
		(at 16.175736 -152.71115 -90)
		(property "Reference" "R688"
			(at 0 0 270)
			(layer "F.SilkS")
			(hide yes)
			(effects
				(font
					(size 1.27 1.27)
				)
			)
		)
		(property "Value" ""
			(at 0 0 270)
			(layer "F.Fab")
			(effects
				(font
					(size 1.27 1.27)
				)
			)
		)
		(duplicate_pad_numbers_are_jumpers no)
		(fp_line
			(start -0.7874 0.4064)
			(end -0.7874 -0.4064)
			(stroke
				(width 0.1524)
				(type default)
			)
			(layer "F.SilkS")
		)
		(fp_line
			(start 0.7874 0.4064)
			(end -0.7874 0.4064)
			(stroke
				(width 0.1524)
				(type default)
			)
			(layer "F.SilkS")
		)
		(fp_line
			(start -0.7874 -0.4064)
			(end 0.7874 -0.4064)
			(stroke
				(width 0.1524)
				(type default)
			)
			(layer "F.SilkS")
		)
		(fp_line
			(start 0.7874 -0.4064)
			(end 0.7874 0.4064)
			(stroke
				(width 0.1524)
				(type default)
			)
			(layer "F.SilkS")
		)
		(fp_line
			(start -0.67945 0.3048)
			(end -0.67945 -0.305054)
			(stroke
				(width 0.1)
				(type default)
			)
			(layer "F.Fab")
		)
		(fp_line
			(start -0.12065 0.3048)
			(end -0.67945 0.3048)
			(stroke
				(width 0.1)
				(type default)
			)
			(layer "F.Fab")
		)
		(fp_line
			(start 0.120396 0.3048)
			(end 0.120396 0.2794)
			(stroke
				(width 0.1)
				(type default)
			)
			(layer "F.Fab")
		)
		(fp_line
			(start 0.67945 0.3048)
			(end 0.120396 0.3048)
			(stroke
				(width 0.1)
				(type default)
			)
			(layer "F.Fab")
		)
		(fp_line
			(start -0.12065 0.2794)
			(end -0.12065 0.3048)
			(stroke
				(width 0.1)
				(type default)
			)
			(layer "F.Fab")
		)
		(fp_line
			(start 0.120396 0.2794)
			(end -0.12065 0.2794)
			(stroke
				(width 0.1)
				(type default)
			)
			(layer "F.Fab")
		)
		(fp_line
			(start -0.12065 -0.2794)
			(end 0.12065 -0.2794)
			(stroke
				(width 0.1)
				(type default)
			)
			(layer "F.Fab")
		)
		(fp_line
			(start 0.12065 -0.2794)
			(end 0.12065 -0.3048)
			(stroke
				(width 0.1)
				(type default)
			)
			(layer "F.Fab")
		)
		(fp_line
			(start 0.12065 -0.3048)
			(end 0.67945 -0.3048)
			(stroke
				(width 0.1)
				(type default)
			)
			(layer "F.Fab")
		)
		(fp_line
			(start 0.67945 -0.3048)
			(end 0.67945 0.3048)
			(stroke
				(width 0.1)
				(type default)
			)
			(layer "F.Fab")
		)
		(fp_line
			(start -0.67945 -0.305054)
			(end -0.12065 -0.305054)
			(stroke
				(width 0.1)
				(type default)
			)
			(layer "F.Fab")
		)
		(fp_line
			(start -0.12065 -0.305054)
			(end -0.12065 -0.2794)
			(stroke
				(width 0.1)
				(type default)
			)
			(layer "F.Fab")
		)
		(pad "1" smd circle
			(at -0.40005 0 270)
			(size 0 0)
			(layers "F.Cu" "F.Mask" "F.Paste")
			(net "SMB_BIC_I2C6_MUX_NIC_ADC_R_SDA")
		)
		(pad "2" smd circle
			(at 0.40005 0 270)
			(size 0 0)
			(layers "F.Cu" "F.Mask" "F.Paste")
			(net "SMB_NIC0_ADC_SDA")
		)
	)
	(footprint ""
		(layer "F.Cu")
		(at 137.420096 -198.091806)
		(property "Reference" "C2598"
			(at 0 0 0)
			(layer "F.SilkS")
			(hide yes)
			(effects
				(font
					(size 1.27 1.27)
				)
			)
		)
		(property "Value" ""
			(at 0 0 0)
			(layer "F.Fab")
			(effects
				(font
					(size 1.27 1.27)
				)
			)
		)
		(duplicate_pad_numbers_are_jumpers no)
		(fp_line
			(start -0.7874 -0.4064)
			(end 0.7874 -0.4064)
			(stroke
				(width 0.1524)
				(type default)
			)
			(layer "F.SilkS")
		)
		(fp_line
			(start -0.7874 0.4064)
			(end -0.7874 -0.4064)
			(stroke
				(width 0.1524)
				(type default)
			)
			(layer "F.SilkS")
		)
		(fp_line
			(start 0.7874 -0.4064)
			(end 0.7874 0.4064)
			(stroke
				(width 0.1524)
				(type default)
			)
			(layer "F.SilkS")
		)
		(fp_line
			(start 0.7874 0.4064)
			(end -0.7874 0.4064)
			(stroke
				(width 0.1524)
				(type default)
			)
			(layer "F.SilkS")
		)
		(fp_line
			(start -0.67945 -0.305054)
			(end -0.12065 -0.305054)
			(stroke
				(width 0.1)
				(type default)
			)
			(layer "F.Fab")
		)
		(fp_line
			(start -0.67945 0.3048)
			(end -0.67945 -0.305054)
			(stroke
				(width 0.1)
				(type default)
			)
			(layer "F.Fab")
		)
		(fp_line
			(start -0.12065 -0.305054)
			(end -0.12065 -0.2794)
			(stroke
				(width 0.1)
				(type default)
			)
			(layer "F.Fab")
		)
		(fp_line
			(start -0.12065 -0.2794)
			(end 0.12065 -0.2794)
			(stroke
				(width 0.1)
				(type default)
			)
			(layer "F.Fab")
		)
		(fp_line
			(start -0.12065 0.2794)
			(end -0.12065 0.3048)
			(stroke
				(width 0.1)
				(type default)
			)
			(layer "F.Fab")
		)
		(fp_line
			(start -0.12065 0.3048)
			(end -0.67945 0.3048)
			(stroke
				(width 0.1)
				(type default)
			)
			(layer "F.Fab")
		)
		(fp_line
			(start 0.120396 0.2794)
			(end -0.12065 0.2794)
			(stroke
				(width 0.1)
				(type default)
			)
			(layer "F.Fab")
		)
		(fp_line
			(start 0.120396 0.3048)
			(end 0.120396 0.2794)
			(stroke
				(width 0.1)
				(type default)
			)
			(layer "F.Fab")
		)
		(fp_line
			(start 0.12065 -0.3048)
			(end 0.67945 -0.3048)
			(stroke
				(width 0.1)
				(type default)
			)
			(layer "F.Fab")
		)
		(fp_line
			(start 0.12065 -0.2794)
			(end 0.12065 -0.3048)
			(stroke
				(width 0.1)
				(type default)
			)
			(layer "F.Fab")
		)
		(fp_line
			(start 0.67945 -0.3048)
			(end 0.67945 0.3048)
			(stroke
				(width 0.1)
				(type default)
			)
			(layer "F.Fab")
		)
		(fp_line
			(start 0.67945 0.3048)
			(end 0.120396 0.3048)
			(stroke
				(width 0.1)
				(type default)
			)
			(layer "F.Fab")
		)
		(pad "1" smd circle
			(at -0.40005 0)
			(size 0 0)
			(layers "F.Cu" "F.Mask" "F.Paste")
			(net "OSC_CLI_OUT")
		)
		(pad "2" smd circle
			(at 0.40005 0)
			(size 0 0)
			(layers "F.Cu" "F.Mask" "F.Paste")
			(net "GND")
		)
	)
	(footprint ""
		(layer "F.Cu")
		(at 376.809 -177.19802)
		(property "Reference" "R4715"
			(at 0 0 0)
			(layer "F.SilkS")
			(hide yes)
			(effects
				(font
					(size 1.27 1.27)
				)
			)
		)
		(property "Value" ""
			(at 0 0 0)
			(layer "F.Fab")
			(effects
				(font
					(size 1.27 1.27)
				)
			)
		)
		(duplicate_pad_numbers_are_jumpers no)
		(fp_line
			(start -0.7874 -0.4064)
			(end 0.7874 -0.4064)
			(stroke
				(width 0.1524)
				(type default)
			)
			(layer "F.SilkS")
		)
		(fp_line
			(start -0.7874 0.4064)
			(end -0.7874 -0.4064)
			(stroke
				(width 0.1524)
				(type default)
			)
			(layer "F.SilkS")
		)
		(fp_line
			(start 0.7874 -0.4064)
			(end 0.7874 0.4064)
			(stroke
				(width 0.1524)
				(type default)
			)
			(layer "F.SilkS")
		)
		(fp_line
			(start 0.7874 0.4064)
			(end -0.7874 0.4064)
			(stroke
				(width 0.1524)
				(type default)
			)
			(layer "F.SilkS")
		)
		(fp_line
			(start -0.67945 -0.305054)
			(end -0.12065 -0.305054)
			(stroke
				(width 0.1)
				(type default)
			)
			(layer "F.Fab")
		)
		(fp_line
			(start -0.67945 0.3048)
			(end -0.67945 -0.305054)
			(stroke
				(width 0.1)
				(type default)
			)
			(layer "F.Fab")
		)
		(fp_line
			(start -0.12065 -0.305054)
			(end -0.12065 -0.2794)
			(stroke
				(width 0.1)
				(type default)
			)
			(layer "F.Fab")
		)
		(fp_line
			(start -0.12065 -0.2794)
			(end 0.12065 -0.2794)
			(stroke
				(width 0.1)
				(type default)
			)
			(layer "F.Fab")
		)
		(fp_line
			(start -0.12065 0.2794)
			(end -0.12065 0.3048)
			(stroke
				(width 0.1)
				(type default)
			)
			(layer "F.Fab")
		)
		(fp_line
			(start -0.12065 0.3048)
			(end -0.67945 0.3048)
			(stroke
				(width 0.1)
				(type default)
			)
			(layer "F.Fab")
		)
		(fp_line
			(start 0.120396 0.2794)
			(end -0.12065 0.2794)
			(stroke
				(width 0.1)
				(type default)
			)
			(layer "F.Fab")
		)
		(fp_line
			(start 0.120396 0.3048)
			(end 0.120396 0.2794)
			(stroke
				(width 0.1)
				(type default)
			)
			(layer "F.Fab")
		)
		(fp_line
			(start 0.12065 -0.3048)
			(end 0.67945 -0.3048)
			(stroke
				(width 0.1)
				(type default)
			)
			(layer "F.Fab")
		)
		(fp_line
			(start 0.12065 -0.2794)
			(end 0.12065 -0.3048)
			(stroke
				(width 0.1)
				(type default)
			)
			(layer "F.Fab")
		)
		(fp_line
			(start 0.67945 -0.3048)
			(end 0.67945 0.3048)
			(stroke
				(width 0.1)
				(type default)
			)
			(layer "F.Fab")
		)
		(fp_line
			(start 0.67945 0.3048)
			(end 0.120396 0.3048)
			(stroke
				(width 0.1)
				(type default)
			)
			(layer "F.Fab")
		)
		(pad "1" smd circle
			(at -0.40005 0)
			(size 0 0)
			(layers "F.Cu" "F.Mask" "F.Paste")
			(net "RST_PEX_NIC3_PERST_N")
		)
		(pad "2" smd circle
			(at 0.40005 0)
			(size 0 0)
			(layers "F.Cu" "F.Mask" "F.Paste")
			(net "RST_PEX_NIC3_PERST_R_N")
		)
	)
	(footprint ""
		(layer "F.Cu")
		(at 194.343782 -43.85691)
		(property "Reference" "R574"
			(at 0 0 0)
			(layer "F.SilkS")
			(hide yes)
			(effects
				(font
					(size 1.27 1.27)
				)
			)
		)
		(property "Value" ""
			(at 0 0 0)
			(layer "F.Fab")
			(effects
				(font
					(size 1.27 1.27)
				)
			)
		)
		(duplicate_pad_numbers_are_jumpers no)
		(fp_line
			(start -0.7874 -0.4064)
			(end 0.7874 -0.4064)
			(stroke
				(width 0.1524)
				(type default)
			)
			(layer "F.SilkS")
		)
		(fp_line
			(start -0.7874 0.4064)
			(end -0.7874 -0.4064)
			(stroke
				(width 0.1524)
				(type default)
			)
			(layer "F.SilkS")
		)
		(fp_line
			(start 0.7874 -0.4064)
			(end 0.7874 0.4064)
			(stroke
				(width 0.1524)
				(type default)
			)
			(layer "F.SilkS")
		)
		(fp_line
			(start 0.7874 0.4064)
			(end -0.7874 0.4064)
			(stroke
				(width 0.1524)
				(type default)
			)
			(layer "F.SilkS")
		)
		(fp_line
			(start -0.67945 -0.305054)
			(end -0.12065 -0.305054)
			(stroke
				(width 0.1)
				(type default)
			)
			(layer "F.Fab")
		)
		(fp_line
			(start -0.67945 0.3048)
			(end -0.67945 -0.305054)
			(stroke
				(width 0.1)
				(type default)
			)
			(layer "F.Fab")
		)
		(fp_line
			(start -0.12065 -0.305054)
			(end -0.12065 -0.2794)
			(stroke
				(width 0.1)
				(type default)
			)
			(layer "F.Fab")
		)
		(fp_line
			(start -0.12065 -0.2794)
			(end 0.12065 -0.2794)
			(stroke
				(width 0.1)
				(type default)
			)
			(layer "F.Fab")
		)
		(fp_line
			(start -0.12065 0.2794)
			(end -0.12065 0.3048)
			(stroke
				(width 0.1)
				(type default)
			)
			(layer "F.Fab")
		)
		(fp_line
			(start -0.12065 0.3048)
			(end -0.67945 0.3048)
			(stroke
				(width 0.1)
				(type default)
			)
			(layer "F.Fab")
		)
		(fp_line
			(start 0.120396 0.2794)
			(end -0.12065 0.2794)
			(stroke
				(width 0.1)
				(type default)
			)
			(layer "F.Fab")
		)
		(fp_line
			(start 0.120396 0.3048)
			(end 0.120396 0.2794)
			(stroke
				(width 0.1)
				(type default)
			)
			(layer "F.Fab")
		)
		(fp_line
			(start 0.12065 -0.3048)
			(end 0.67945 -0.3048)
			(stroke
				(width 0.1)
				(type default)
			)
			(layer "F.Fab")
		)
		(fp_line
			(start 0.12065 -0.2794)
			(end 0.12065 -0.3048)
			(stroke
				(width 0.1)
				(type default)
			)
			(layer "F.Fab")
		)
		(fp_line
			(start 0.67945 -0.3048)
			(end 0.67945 0.3048)
			(stroke
				(width 0.1)
				(type default)
			)
			(layer "F.Fab")
		)
		(fp_line
			(start 0.67945 0.3048)
			(end 0.120396 0.3048)
			(stroke
				(width 0.1)
				(type default)
			)
			(layer "F.Fab")
		)
		(pad "1" smd circle
			(at -0.40005 0)
			(size 0 0)
			(layers "F.Cu" "F.Mask" "F.Paste")
			(net "SSD6_ADC_A1")
		)
		(pad "2" smd circle
			(at 0.40005 0)
			(size 0 0)
			(layers "F.Cu" "F.Mask" "F.Paste")
			(net "GND")
		)
	)
	(footprint ""
		(layer "F.Cu")
		(at 385.850384 -252.356874 -90)
		(property "Reference" "R1435"
			(at 0 0 270)
			(layer "F.SilkS")
			(hide yes)
			(effects
				(font
					(size 1.27 1.27)
				)
			)
		)
		(property "Value" ""
			(at 0 0 270)
			(layer "F.Fab")
			(effects
				(font
					(size 1.27 1.27)
				)
			)
		)
		(duplicate_pad_numbers_are_jumpers no)
		(fp_line
			(start -0.7874 0.4064)
			(end -0.7874 -0.4064)
			(stroke
				(width 0.1524)
				(type default)
			)
			(layer "F.SilkS")
		)
		(fp_line
			(start 0.7874 0.4064)
			(end -0.7874 0.4064)
			(stroke
				(width 0.1524)
				(type default)
			)
			(layer "F.SilkS")
		)
		(fp_line
			(start -0.7874 -0.4064)
			(end 0.7874 -0.4064)
			(stroke
				(width 0.1524)
				(type default)
			)
			(layer "F.SilkS")
		)
		(fp_line
			(start 0.7874 -0.4064)
			(end 0.7874 0.4064)
			(stroke
				(width 0.1524)
				(type default)
			)
			(layer "F.SilkS")
		)
		(fp_line
			(start -0.67945 0.3048)
			(end -0.67945 -0.305054)
			(stroke
				(width 0.1)
				(type default)
			)
			(layer "F.Fab")
		)
		(fp_line
			(start -0.12065 0.3048)
			(end -0.67945 0.3048)
			(stroke
				(width 0.1)
				(type default)
			)
			(layer "F.Fab")
		)
		(fp_line
			(start 0.120396 0.3048)
			(end 0.120396 0.2794)
			(stroke
				(width 0.1)
				(type default)
			)
			(layer "F.Fab")
		)
		(fp_line
			(start 0.67945 0.3048)
			(end 0.120396 0.3048)
			(stroke
				(width 0.1)
				(type default)
			)
			(layer "F.Fab")
		)
		(fp_line
			(start -0.12065 0.2794)
			(end -0.12065 0.3048)
			(stroke
				(width 0.1)
				(type default)
			)
			(layer "F.Fab")
		)
		(fp_line
			(start 0.120396 0.2794)
			(end -0.12065 0.2794)
			(stroke
				(width 0.1)
				(type default)
			)
			(layer "F.Fab")
		)
		(fp_line
			(start -0.12065 -0.2794)
			(end 0.12065 -0.2794)
			(stroke
				(width 0.1)
				(type default)
			)
			(layer "F.Fab")
		)
		(fp_line
			(start 0.12065 -0.2794)
			(end 0.12065 -0.3048)
			(stroke
				(width 0.1)
				(type default)
			)
			(layer "F.Fab")
		)
		(fp_line
			(start 0.12065 -0.3048)
			(end 0.67945 -0.3048)
			(stroke
				(width 0.1)
				(type default)
			)
			(layer "F.Fab")
		)
		(fp_line
			(start 0.67945 -0.3048)
			(end 0.67945 0.3048)
			(stroke
				(width 0.1)
				(type default)
			)
			(layer "F.Fab")
		)
		(fp_line
			(start -0.67945 -0.305054)
			(end -0.12065 -0.305054)
			(stroke
				(width 0.1)
				(type default)
			)
			(layer "F.Fab")
		)
		(fp_line
			(start -0.12065 -0.305054)
			(end -0.12065 -0.2794)
			(stroke
				(width 0.1)
				(type default)
			)
			(layer "F.Fab")
		)
		(pad "1" smd circle
			(at -0.40005 0 270)
			(size 0 0)
			(layers "F.Cu" "F.Mask" "F.Paste")
			(net "GND")
		)
		(pad "2" smd circle
			(at 0.40005 0 270)
			(size 0 0)
			(layers "F.Cu" "F.Mask" "F.Paste")
			(net "PEX3_MODE_SEL10")
		)
	)
	(footprint ""
		(layer "F.Cu")
		(at 270.807942 -158.3944 180)
		(property "Reference" "R215"
			(at 0 0 180)
			(layer "F.SilkS")
			(hide yes)
			(effects
				(font
					(size 1.27 1.27)
				)
			)
		)
		(property "Value" ""
			(at 0 0 180)
			(layer "F.Fab")
			(effects
				(font
					(size 1.27 1.27)
				)
			)
		)
		(duplicate_pad_numbers_are_jumpers no)
		(fp_line
			(start 0.7874 0.4064)
			(end -0.7874 0.4064)
			(stroke
				(width 0.1524)
				(type default)
			)
			(layer "F.SilkS")
		)
		(fp_line
			(start 0.7874 -0.4064)
			(end 0.7874 0.4064)
			(stroke
				(width 0.1524)
				(type default)
			)
			(layer "F.SilkS")
		)
		(fp_line
			(start -0.7874 0.4064)
			(end -0.7874 -0.4064)
			(stroke
				(width 0.1524)
				(type default)
			)
			(layer "F.SilkS")
		)
		(fp_line
			(start -0.7874 -0.4064)
			(end 0.7874 -0.4064)
			(stroke
				(width 0.1524)
				(type default)
			)
			(layer "F.SilkS")
		)
		(fp_line
			(start 0.67945 0.3048)
			(end 0.120396 0.3048)
			(stroke
				(width 0.1)
				(type default)
			)
			(layer "F.Fab")
		)
		(fp_line
			(start 0.67945 -0.3048)
			(end 0.67945 0.3048)
			(stroke
				(width 0.1)
				(type default)
			)
			(layer "F.Fab")
		)
		(fp_line
			(start 0.12065 -0.2794)
			(end 0.12065 -0.3048)
			(stroke
				(width 0.1)
				(type default)
			)
			(layer "F.Fab")
		)
		(fp_line
			(start 0.12065 -0.3048)
			(end 0.67945 -0.3048)
			(stroke
				(width 0.1)
				(type default)
			)
			(layer "F.Fab")
		)
		(fp_line
			(start 0.120396 0.3048)
			(end 0.120396 0.2794)
			(stroke
				(width 0.1)
				(type default)
			)
			(layer "F.Fab")
		)
		(fp_line
			(start 0.120396 0.2794)
			(end -0.12065 0.2794)
			(stroke
				(width 0.1)
				(type default)
			)
			(layer "F.Fab")
		)
		(fp_line
			(start -0.12065 0.3048)
			(end -0.67945 0.3048)
			(stroke
				(width 0.1)
				(type default)
			)
			(layer "F.Fab")
		)
		(fp_line
			(start -0.12065 0.2794)
			(end -0.12065 0.3048)
			(stroke
				(width 0.1)
				(type default)
			)
			(layer "F.Fab")
		)
		(fp_line
			(start -0.12065 -0.2794)
			(end 0.12065 -0.2794)
			(stroke
				(width 0.1)
				(type default)
			)
			(layer "F.Fab")
		)
		(fp_line
			(start -0.12065 -0.305054)
			(end -0.12065 -0.2794)
			(stroke
				(width 0.1)
				(type default)
			)
			(layer "F.Fab")
		)
		(fp_line
			(start -0.67945 0.3048)
			(end -0.67945 -0.305054)
			(stroke
				(width 0.1)
				(type default)
			)
			(layer "F.Fab")
		)
		(fp_line
			(start -0.67945 -0.305054)
			(end -0.12065 -0.305054)
			(stroke
				(width 0.1)
				(type default)
			)
			(layer "F.Fab")
		)
		(pad "1" smd circle
			(at -0.40005 0 180)
			(size 0 0)
			(layers "F.Cu" "F.Mask" "F.Paste")
			(net "NIC4_LD_N")
		)
		(pad "2" smd circle
			(at 0.40005 0 180)
			(size 0 0)
			(layers "F.Cu" "F.Mask" "F.Paste")
			(net "P3V3_NIC4")
		)
	)
	(footprint ""
		(layer "F.Cu")
		(at 219.202 -206.756)
		(property "Reference" "R1509"
			(at 0 0 0)
			(layer "F.SilkS")
			(hide yes)
			(effects
				(font
					(size 1.27 1.27)
				)
			)
		)
		(property "Value" ""
			(at 0 0 0)
			(layer "F.Fab")
			(effects
				(font
					(size 1.27 1.27)
				)
			)
		)
		(duplicate_pad_numbers_are_jumpers no)
		(fp_line
			(start -0.7874 -0.4064)
			(end 0.7874 -0.4064)
			(stroke
				(width 0.1524)
				(type default)
			)
			(layer "F.SilkS")
		)
		(fp_line
			(start -0.7874 0.4064)
			(end -0.7874 -0.4064)
			(stroke
				(width 0.1524)
				(type default)
			)
			(layer "F.SilkS")
		)
		(fp_line
			(start 0.7874 -0.4064)
			(end 0.7874 0.4064)
			(stroke
				(width 0.1524)
				(type default)
			)
			(layer "F.SilkS")
		)
		(fp_line
			(start 0.7874 0.4064)
			(end -0.7874 0.4064)
			(stroke
				(width 0.1524)
				(type default)
			)
			(layer "F.SilkS")
		)
		(fp_line
			(start -0.67945 -0.305054)
			(end -0.12065 -0.305054)
			(stroke
				(width 0.1)
				(type default)
			)
			(layer "F.Fab")
		)
		(fp_line
			(start -0.67945 0.3048)
			(end -0.67945 -0.305054)
			(stroke
				(width 0.1)
				(type default)
			)
			(layer "F.Fab")
		)
		(fp_line
			(start -0.12065 -0.305054)
			(end -0.12065 -0.2794)
			(stroke
				(width 0.1)
				(type default)
			)
			(layer "F.Fab")
		)
		(fp_line
			(start -0.12065 -0.2794)
			(end 0.12065 -0.2794)
			(stroke
				(width 0.1)
				(type default)
			)
			(layer "F.Fab")
		)
		(fp_line
			(start -0.12065 0.2794)
			(end -0.12065 0.3048)
			(stroke
				(width 0.1)
				(type default)
			)
			(layer "F.Fab")
		)
		(fp_line
			(start -0.12065 0.3048)
			(end -0.67945 0.3048)
			(stroke
				(width 0.1)
				(type default)
			)
			(layer "F.Fab")
		)
		(fp_line
			(start 0.120396 0.2794)
			(end -0.12065 0.2794)
			(stroke
				(width 0.1)
				(type default)
			)
			(layer "F.Fab")
		)
		(fp_line
			(start 0.120396 0.3048)
			(end 0.120396 0.2794)
			(stroke
				(width 0.1)
				(type default)
			)
			(layer "F.Fab")
		)
		(fp_line
			(start 0.12065 -0.3048)
			(end 0.67945 -0.3048)
			(stroke
				(width 0.1)
				(type default)
			)
			(layer "F.Fab")
		)
		(fp_line
			(start 0.12065 -0.2794)
			(end 0.12065 -0.3048)
			(stroke
				(width 0.1)
				(type default)
			)
			(layer "F.Fab")
		)
		(fp_line
			(start 0.67945 -0.3048)
			(end 0.67945 0.3048)
			(stroke
				(width 0.1)
				(type default)
			)
			(layer "F.Fab")
		)
		(fp_line
			(start 0.67945 0.3048)
			(end 0.120396 0.3048)
			(stroke
				(width 0.1)
				(type default)
			)
			(layer "F.Fab")
		)
		(pad "1" smd circle
			(at -0.40005 0)
			(size 0 0)
			(layers "F.Cu" "F.Mask" "F.Paste")
			(net "SMB_NIC4_LS_R_SCL")
		)
		(pad "2" smd circle
			(at 0.40005 0)
			(size 0 0)
			(layers "F.Cu" "F.Mask" "F.Paste")
			(net "P3V3_NIC4")
		)
	)
	(footprint ""
		(layer "F.Cu")
		(at 430.961546 -136.20115 180)
		(property "Reference" "C650"
			(at 0 0 180)
			(layer "F.SilkS")
			(hide yes)
			(effects
				(font
					(size 1.27 1.27)
				)
			)
		)
		(property "Value" ""
			(at 0 0 180)
			(layer "F.Fab")
			(effects
				(font
					(size 1.27 1.27)
				)
			)
		)
		(duplicate_pad_numbers_are_jumpers no)
		(fp_line
			(start 0.299974 0.150114)
			(end -0.299974 0.150114)
			(stroke
				(width 0.1)
				(type default)
			)
			(layer "F.Fab")
		)
		(fp_line
			(start 0.299974 -0.150114)
			(end 0.299974 0.150114)
			(stroke
				(width 0.1)
				(type default)
			)
			(layer "F.Fab")
		)
		(fp_line
			(start -0.299974 0.150114)
			(end -0.299974 -0.150114)
			(stroke
				(width 0.1)
				(type default)
			)
			(layer "F.Fab")
		)
		(fp_line
			(start -0.299974 -0.150114)
			(end 0.299974 -0.150114)
			(stroke
				(width 0.1)
				(type default)
			)
			(layer "F.Fab")
		)
		(pad "1" smd rect
			(at -0.2667 0 180)
			(size 0.3048 0.381)
			(layers "F.Cu" "F.Mask" "F.Paste")
			(net "P5E_PEX3_STN0_TX_DP<7>")
		)
		(pad "2" smd rect
			(at 0.2667 0 180)
			(size 0.3048 0.381)
			(layers "F.Cu" "F.Mask" "F.Paste")
			(net "P5E_PEX3_STN0_TX_C_DP<7>")
		)
	)
	(footprint ""
		(layer "F.Cu")
		(at 143.030194 -300.406308 -90)
		(property "Reference" "C3191"
			(at 0 0 270)
			(layer "F.SilkS")
			(hide yes)
			(effects
				(font
					(size 1.27 1.27)
				)
			)
		)
		(property "Value" ""
			(at 0 0 270)
			(layer "F.Fab")
			(effects
				(font
					(size 1.27 1.27)
				)
			)
		)
		(duplicate_pad_numbers_are_jumpers no)
		(fp_line
			(start -1.2954 0.5842)
			(end -1.2954 -0.5842)
			(stroke
				(width 0.1524)
				(type default)
			)
			(layer "F.SilkS")
		)
		(fp_line
			(start 1.2954 0.5842)
			(end -1.2954 0.5842)
			(stroke
				(width 0.1524)
				(type default)
			)
			(layer "F.SilkS")
		)
		(fp_line
			(start -1.2954 -0.5842)
			(end 1.2954 -0.5842)
			(stroke
				(width 0.1524)
				(type default)
			)
			(layer "F.SilkS")
		)
		(fp_line
			(start 1.2954 -0.5842)
			(end 1.2954 0.5842)
			(stroke
				(width 0.1524)
				(type default)
			)
			(layer "F.SilkS")
		)
		(fp_line
			(start -0.8636 0.4572)
			(end -0.8636 0.4064)
			(stroke
				(width 0.1)
				(type default)
			)
			(layer "F.Fab")
		)
		(fp_line
			(start 0.8636 0.4572)
			(end -0.8636 0.4572)
			(stroke
				(width 0.1)
				(type default)
			)
			(layer "F.Fab")
		)
		(fp_line
			(start -1.1938 0.4064)
			(end -1.1938 -0.4064)
			(stroke
				(width 0.1)
				(type default)
			)
			(layer "F.Fab")
		)
		(fp_line
			(start -0.8636 0.4064)
			(end -1.1938 0.4064)
			(stroke
				(width 0.1)
				(type default)
			)
			(layer "F.Fab")
		)
		(fp_line
			(start 0.8636 0.4064)
			(end 0.8636 0.4572)
			(stroke
				(width 0.1)
				(type default)
			)
			(layer "F.Fab")
		)
		(fp_line
			(start 1.1938 0.4064)
			(end 0.8636 0.4064)
			(stroke
				(width 0.1)
				(type default)
			)
			(layer "F.Fab")
		)
		(fp_line
			(start -1.1938 -0.4064)
			(end -0.8636 -0.4064)
			(stroke
				(width 0.1)
				(type default)
			)
			(layer "F.Fab")
		)
		(fp_line
			(start -0.8636 -0.4064)
			(end -0.8636 -0.4572)
			(stroke
				(width 0.1)
				(type default)
			)
			(layer "F.Fab")
		)
		(fp_line
			(start 0.8636 -0.4064)
			(end 1.1938 -0.4064)
			(stroke
				(width 0.1)
				(type default)
			)
			(layer "F.Fab")
		)
		(fp_line
			(start 1.1938 -0.4064)
			(end 1.1938 0.4064)
			(stroke
				(width 0.1)
				(type default)
			)
			(layer "F.Fab")
		)
		(fp_line
			(start -0.8636 -0.4572)
			(end 0.8636 -0.4572)
			(stroke
				(width 0.1)
				(type default)
			)
			(layer "F.Fab")
		)
		(fp_line
			(start 0.8636 -0.4572)
			(end 0.8636 -0.4064)
			(stroke
				(width 0.1)
				(type default)
			)
			(layer "F.Fab")
		)
		(pad "1" smd rect
			(at -0.7366 0 180)
			(size 0.7112 0.8128)
			(layers "F.Cu" "F.Mask" "F.Paste")
			(net "P1V8_PLL0_PEX1")
		)
		(pad "2" smd rect
			(at 0.7366 0 180)
			(size 0.7112 0.8128)
			(layers "F.Cu" "F.Mask" "F.Paste")
			(net "GND")
		)
	)
	(footprint ""
		(layer "F.Cu")
		(at 73.782682 -350.098614 90)
		(property "Reference" "C115"
			(at 0 0 90)
			(layer "F.SilkS")
			(hide yes)
			(effects
				(font
					(size 1.27 1.27)
				)
			)
		)
		(property "Value" ""
			(at 0 0 90)
			(layer "F.Fab")
			(effects
				(font
					(size 1.27 1.27)
				)
			)
		)
		(duplicate_pad_numbers_are_jumpers no)
		(fp_line
			(start 0.299974 -0.150114)
			(end 0.299974 0.150114)
			(stroke
				(width 0.1)
				(type default)
			)
			(layer "F.Fab")
		)
		(fp_line
			(start -0.299974 -0.150114)
			(end 0.299974 -0.150114)
			(stroke
				(width 0.1)
				(type default)
			)
			(layer "F.Fab")
		)
		(fp_line
			(start 0.299974 0.150114)
			(end -0.299974 0.150114)
			(stroke
				(width 0.1)
				(type default)
			)
			(layer "F.Fab")
		)
		(fp_line
			(start -0.299974 0.150114)
			(end -0.299974 -0.150114)
			(stroke
				(width 0.1)
				(type default)
			)
			(layer "F.Fab")
		)
		(pad "1" smd rect
			(at -0.2667 0 90)
			(size 0.3048 0.381)
			(layers "F.Cu" "F.Mask" "F.Paste")
			(net "P5E_PEX0_STN5_TX_DP<86>")
		)
		(pad "2" smd rect
			(at 0.2667 0 90)
			(size 0.3048 0.381)
			(layers "F.Cu" "F.Mask" "F.Paste")
			(net "P5E_PEX0_STN5_TX_C_DP<86>")
		)
	)
	(footprint ""
		(layer "F.Cu")
		(at 244.221762 -178.519328 -90)
		(property "Reference" "C2147"
			(at 0 0 270)
			(layer "F.SilkS")
			(hide yes)
			(effects
				(font
					(size 1.27 1.27)
				)
			)
		)
		(property "Value" ""
			(at 0 0 270)
			(layer "F.Fab")
			(effects
				(font
					(size 1.27 1.27)
				)
			)
		)
		(duplicate_pad_numbers_are_jumpers no)
		(fp_line
			(start -0.7874 0.4064)
			(end -0.7874 -0.4064)
			(stroke
				(width 0.1524)
				(type default)
			)
			(layer "F.SilkS")
		)
		(fp_line
			(start 0.7874 0.4064)
			(end -0.7874 0.4064)
			(stroke
				(width 0.1524)
				(type default)
			)
			(layer "F.SilkS")
		)
		(fp_line
			(start -0.7874 -0.4064)
			(end 0.7874 -0.4064)
			(stroke
				(width 0.1524)
				(type default)
			)
			(layer "F.SilkS")
		)
		(fp_line
			(start 0.7874 -0.4064)
			(end 0.7874 0.4064)
			(stroke
				(width 0.1524)
				(type default)
			)
			(layer "F.SilkS")
		)
		(fp_line
			(start -0.67945 0.3048)
			(end -0.67945 -0.305054)
			(stroke
				(width 0.1)
				(type default)
			)
			(layer "F.Fab")
		)
		(fp_line
			(start -0.12065 0.3048)
			(end -0.67945 0.3048)
			(stroke
				(width 0.1)
				(type default)
			)
			(layer "F.Fab")
		)
		(fp_line
			(start 0.120396 0.3048)
			(end 0.120396 0.2794)
			(stroke
				(width 0.1)
				(type default)
			)
			(layer "F.Fab")
		)
		(fp_line
			(start 0.67945 0.3048)
			(end 0.120396 0.3048)
			(stroke
				(width 0.1)
				(type default)
			)
			(layer "F.Fab")
		)
		(fp_line
			(start -0.12065 0.2794)
			(end -0.12065 0.3048)
			(stroke
				(width 0.1)
				(type default)
			)
			(layer "F.Fab")
		)
		(fp_line
			(start 0.120396 0.2794)
			(end -0.12065 0.2794)
			(stroke
				(width 0.1)
				(type default)
			)
			(layer "F.Fab")
		)
		(fp_line
			(start -0.12065 -0.2794)
			(end 0.12065 -0.2794)
			(stroke
				(width 0.1)
				(type default)
			)
			(layer "F.Fab")
		)
		(fp_line
			(start 0.12065 -0.2794)
			(end 0.12065 -0.3048)
			(stroke
				(width 0.1)
				(type default)
			)
			(layer "F.Fab")
		)
		(fp_line
			(start 0.12065 -0.3048)
			(end 0.67945 -0.3048)
			(stroke
				(width 0.1)
				(type default)
			)
			(layer "F.Fab")
		)
		(fp_line
			(start 0.67945 -0.3048)
			(end 0.67945 0.3048)
			(stroke
				(width 0.1)
				(type default)
			)
			(layer "F.Fab")
		)
		(fp_line
			(start -0.67945 -0.305054)
			(end -0.12065 -0.305054)
			(stroke
				(width 0.1)
				(type default)
			)
			(layer "F.Fab")
		)
		(fp_line
			(start -0.12065 -0.305054)
			(end -0.12065 -0.2794)
			(stroke
				(width 0.1)
				(type default)
			)
			(layer "F.Fab")
		)
		(pad "1" smd circle
			(at -0.40005 0 270)
			(size 0 0)
			(layers "F.Cu" "F.Mask" "F.Paste")
			(net "P3V3_AUX")
		)
		(pad "2" smd circle
			(at 0.40005 0 270)
			(size 0 0)
			(layers "F.Cu" "F.Mask" "F.Paste")
			(net "GND")
		)
	)
	(footprint ""
		(layer "F.Cu")
		(at 252.634496 -34.546286 180)
		(property "Reference" "C487"
			(at 0 0 180)
			(layer "F.SilkS")
			(hide yes)
			(effects
				(font
					(size 1.27 1.27)
				)
			)
		)
		(property "Value" ""
			(at 0 0 180)
			(layer "F.Fab")
			(effects
				(font
					(size 1.27 1.27)
				)
			)
		)
		(duplicate_pad_numbers_are_jumpers no)
		(fp_line
			(start 0.299974 0.150114)
			(end -0.299974 0.150114)
			(stroke
				(width 0.1)
				(type default)
			)
			(layer "F.Fab")
		)
		(fp_line
			(start 0.299974 -0.150114)
			(end 0.299974 0.150114)
			(stroke
				(width 0.1)
				(type default)
			)
			(layer "F.Fab")
		)
		(fp_line
			(start -0.299974 0.150114)
			(end -0.299974 -0.150114)
			(stroke
				(width 0.1)
				(type default)
			)
			(layer "F.Fab")
		)
		(fp_line
			(start -0.299974 -0.150114)
			(end 0.299974 -0.150114)
			(stroke
				(width 0.1)
				(type default)
			)
			(layer "F.Fab")
		)
		(pad "1" smd rect
			(at -0.2667 0 180)
			(size 0.3048 0.381)
			(layers "F.Cu" "F.Mask" "F.Paste")
			(net "P5E_PEX2_STN2_TX_DP<47>")
		)
		(pad "2" smd rect
			(at 0.2667 0 180)
			(size 0.3048 0.381)
			(layers "F.Cu" "F.Mask" "F.Paste")
			(net "P5E_PEX2_STN2_TX_C_DP<47>")
		)
	)
	(footprint ""
		(layer "F.Cu")
		(at 316.500764 -356.244906 90)
		(property "Reference" "C546"
			(at 0 0 90)
			(layer "F.SilkS")
			(hide yes)
			(effects
				(font
					(size 1.27 1.27)
				)
			)
		)
		(property "Value" ""
			(at 0 0 90)
			(layer "F.Fab")
			(effects
				(font
					(size 1.27 1.27)
				)
			)
		)
		(duplicate_pad_numbers_are_jumpers no)
		(fp_line
			(start 0.299974 -0.150114)
			(end 0.299974 0.150114)
			(stroke
				(width 0.1)
				(type default)
			)
			(layer "F.Fab")
		)
		(fp_line
			(start -0.299974 -0.150114)
			(end 0.299974 -0.150114)
			(stroke
				(width 0.1)
				(type default)
			)
			(layer "F.Fab")
		)
		(fp_line
			(start 0.299974 0.150114)
			(end -0.299974 0.150114)
			(stroke
				(width 0.1)
				(type default)
			)
			(layer "F.Fab")
		)
		(fp_line
			(start -0.299974 0.150114)
			(end -0.299974 -0.150114)
			(stroke
				(width 0.1)
				(type default)
			)
			(layer "F.Fab")
		)
		(pad "1" smd rect
			(at -0.2667 0 90)
			(size 0.3048 0.381)
			(layers "F.Cu" "F.Mask" "F.Paste")
			(net "P5E_PEX2_STN5_TX_DN<82>")
		)
		(pad "2" smd rect
			(at 0.2667 0 90)
			(size 0.3048 0.381)
			(layers "F.Cu" "F.Mask" "F.Paste")
			(net "P5E_PEX2_STN5_TX_C_DN<82>")
		)
	)
	(footprint ""
		(layer "F.Cu")
		(at 39.280592 -106.488738)
		(property "Reference" "C55"
			(at 0 0 0)
			(layer "F.SilkS")
			(hide yes)
			(effects
				(font
					(size 1.27 1.27)
				)
			)
		)
		(property "Value" ""
			(at 0 0 0)
			(layer "F.Fab")
			(effects
				(font
					(size 1.27 1.27)
				)
			)
		)
		(duplicate_pad_numbers_are_jumpers no)
		(fp_line
			(start -0.299974 -0.150114)
			(end 0.299974 -0.150114)
			(stroke
				(width 0.1)
				(type default)
			)
			(layer "F.Fab")
		)
		(fp_line
			(start -0.299974 0.150114)
			(end -0.299974 -0.150114)
			(stroke
				(width 0.1)
				(type default)
			)
			(layer "F.Fab")
		)
		(fp_line
			(start 0.299974 -0.150114)
			(end 0.299974 0.150114)
			(stroke
				(width 0.1)
				(type default)
			)
			(layer "F.Fab")
		)
		(fp_line
			(start 0.299974 0.150114)
			(end -0.299974 0.150114)
			(stroke
				(width 0.1)
				(type default)
			)
			(layer "F.Fab")
		)
		(pad "1" smd rect
			(at -0.2667 0)
			(size 0.3048 0.381)
			(layers "F.Cu" "F.Mask" "F.Paste")
			(net "P5E_PEX0_STN1_TX_DP<20>")
		)
		(pad "2" smd rect
			(at 0.2667 0)
			(size 0.3048 0.381)
			(layers "F.Cu" "F.Mask" "F.Paste")
			(net "P5E_PEX0_STN1_TX_C_DP<20>")
		)
	)
	(footprint ""
		(layer "F.Cu")
		(at 19.796252 -47.20082 90)
		(property "Reference" "C202"
			(at 0 0 90)
			(layer "F.SilkS")
			(hide yes)
			(effects
				(font
					(size 1.27 1.27)
				)
			)
		)
		(property "Value" ""
			(at 0 0 90)
			(layer "F.Fab")
			(effects
				(font
					(size 1.27 1.27)
				)
			)
		)
		(duplicate_pad_numbers_are_jumpers no)
		(fp_line
			(start 0.7874 -0.4064)
			(end 0.7874 0.4064)
			(stroke
				(width 0.1524)
				(type default)
			)
			(layer "F.SilkS")
		)
		(fp_line
			(start -0.7874 -0.4064)
			(end 0.7874 -0.4064)
			(stroke
				(width 0.1524)
				(type default)
			)
			(layer "F.SilkS")
		)
		(fp_line
			(start 0.7874 0.4064)
			(end -0.7874 0.4064)
			(stroke
				(width 0.1524)
				(type default)
			)
			(layer "F.SilkS")
		)
		(fp_line
			(start -0.7874 0.4064)
			(end -0.7874 -0.4064)
			(stroke
				(width 0.1524)
				(type default)
			)
			(layer "F.SilkS")
		)
		(fp_line
			(start -0.12065 -0.305054)
			(end -0.12065 -0.2794)
			(stroke
				(width 0.1)
				(type default)
			)
			(layer "F.Fab")
		)
		(fp_line
			(start -0.67945 -0.305054)
			(end -0.12065 -0.305054)
			(stroke
				(width 0.1)
				(type default)
			)
			(layer "F.Fab")
		)
		(fp_line
			(start 0.67945 -0.3048)
			(end 0.67945 0.3048)
			(stroke
				(width 0.1)
				(type default)
			)
			(layer "F.Fab")
		)
		(fp_line
			(start 0.12065 -0.3048)
			(end 0.67945 -0.3048)
			(stroke
				(width 0.1)
				(type default)
			)
			(layer "F.Fab")
		)
		(fp_line
			(start 0.12065 -0.2794)
			(end 0.12065 -0.3048)
			(stroke
				(width 0.1)
				(type default)
			)
			(layer "F.Fab")
		)
		(fp_line
			(start -0.12065 -0.2794)
			(end 0.12065 -0.2794)
			(stroke
				(width 0.1)
				(type default)
			)
			(layer "F.Fab")
		)
		(fp_line
			(start 0.120396 0.2794)
			(end -0.12065 0.2794)
			(stroke
				(width 0.1)
				(type default)
			)
			(layer "F.Fab")
		)
		(fp_line
			(start -0.12065 0.2794)
			(end -0.12065 0.3048)
			(stroke
				(width 0.1)
				(type default)
			)
			(layer "F.Fab")
		)
		(fp_line
			(start 0.67945 0.3048)
			(end 0.120396 0.3048)
			(stroke
				(width 0.1)
				(type default)
			)
			(layer "F.Fab")
		)
		(fp_line
			(start 0.120396 0.3048)
			(end 0.120396 0.2794)
			(stroke
				(width 0.1)
				(type default)
			)
			(layer "F.Fab")
		)
		(fp_line
			(start -0.12065 0.3048)
			(end -0.67945 0.3048)
			(stroke
				(width 0.1)
				(type default)
			)
			(layer "F.Fab")
		)
		(fp_line
			(start -0.67945 0.3048)
			(end -0.67945 -0.305054)
			(stroke
				(width 0.1)
				(type default)
			)
			(layer "F.Fab")
		)
		(pad "1" smd circle
			(at -0.40005 0 90)
			(size 0 0)
			(layers "F.Cu" "F.Mask" "F.Paste")
			(net "P12V_SSD0_R")
		)
		(pad "2" smd circle
			(at 0.40005 0 90)
			(size 0 0)
			(layers "F.Cu" "F.Mask" "F.Paste")
			(net "GND")
		)
	)
	(footprint ""
		(layer "F.Cu")
		(at 244.809264 -119.105426 -90)
		(property "Reference" "R6038"
			(at 0 0 270)
			(layer "F.SilkS")
			(hide yes)
			(effects
				(font
					(size 1.27 1.27)
				)
			)
		)
		(property "Value" ""
			(at 0 0 270)
			(layer "F.Fab")
			(effects
				(font
					(size 1.27 1.27)
				)
			)
		)
		(duplicate_pad_numbers_are_jumpers no)
		(fp_line
			(start -0.7874 0.4064)
			(end -0.7874 -0.4064)
			(stroke
				(width 0.1524)
				(type default)
			)
			(layer "F.SilkS")
		)
		(fp_line
			(start 0.7874 0.4064)
			(end -0.7874 0.4064)
			(stroke
				(width 0.1524)
				(type default)
			)
			(layer "F.SilkS")
		)
		(fp_line
			(start -0.7874 -0.4064)
			(end 0.7874 -0.4064)
			(stroke
				(width 0.1524)
				(type default)
			)
			(layer "F.SilkS")
		)
		(fp_line
			(start 0.7874 -0.4064)
			(end 0.7874 0.4064)
			(stroke
				(width 0.1524)
				(type default)
			)
			(layer "F.SilkS")
		)
		(fp_line
			(start -0.67945 0.3048)
			(end -0.67945 -0.305054)
			(stroke
				(width 0.1)
				(type default)
			)
			(layer "F.Fab")
		)
		(fp_line
			(start -0.12065 0.3048)
			(end -0.67945 0.3048)
			(stroke
				(width 0.1)
				(type default)
			)
			(layer "F.Fab")
		)
		(fp_line
			(start 0.120396 0.3048)
			(end 0.120396 0.2794)
			(stroke
				(width 0.1)
				(type default)
			)
			(layer "F.Fab")
		)
		(fp_line
			(start 0.67945 0.3048)
			(end 0.120396 0.3048)
			(stroke
				(width 0.1)
				(type default)
			)
			(layer "F.Fab")
		)
		(fp_line
			(start -0.12065 0.2794)
			(end -0.12065 0.3048)
			(stroke
				(width 0.1)
				(type default)
			)
			(layer "F.Fab")
		)
		(fp_line
			(start 0.120396 0.2794)
			(end -0.12065 0.2794)
			(stroke
				(width 0.1)
				(type default)
			)
			(layer "F.Fab")
		)
		(fp_line
			(start -0.12065 -0.2794)
			(end 0.12065 -0.2794)
			(stroke
				(width 0.1)
				(type default)
			)
			(layer "F.Fab")
		)
		(fp_line
			(start 0.12065 -0.2794)
			(end 0.12065 -0.3048)
			(stroke
				(width 0.1)
				(type default)
			)
			(layer "F.Fab")
		)
		(fp_line
			(start 0.12065 -0.3048)
			(end 0.67945 -0.3048)
			(stroke
				(width 0.1)
				(type default)
			)
			(layer "F.Fab")
		)
		(fp_line
			(start 0.67945 -0.3048)
			(end 0.67945 0.3048)
			(stroke
				(width 0.1)
				(type default)
			)
			(layer "F.Fab")
		)
		(fp_line
			(start -0.67945 -0.305054)
			(end -0.12065 -0.305054)
			(stroke
				(width 0.1)
				(type default)
			)
			(layer "F.Fab")
		)
		(fp_line
			(start -0.12065 -0.305054)
			(end -0.12065 -0.2794)
			(stroke
				(width 0.1)
				(type default)
			)
			(layer "F.Fab")
		)
		(pad "1" smd circle
			(at -0.40005 0 270)
			(size 0 0)
			(layers "F.Cu" "F.Mask" "F.Paste")
			(net "P3V3_NIC4")
		)
		(pad "2" smd circle
			(at 0.40005 0 270)
			(size 0 0)
			(layers "F.Cu" "F.Mask" "F.Paste")
			(net "P3V3_NIC4_PG_G1")
		)
	)
	(footprint ""
		(layer "F.Cu")
		(at 151.50719 -379.389132 180)
		(property "Reference" "C4096"
			(at 0 0 180)
			(layer "F.SilkS")
			(hide yes)
			(effects
				(font
					(size 1.27 1.27)
				)
			)
		)
		(property "Value" ""
			(at 0 0 180)
			(layer "F.Fab")
			(effects
				(font
					(size 1.27 1.27)
				)
			)
		)
		(duplicate_pad_numbers_are_jumpers no)
		(fp_line
			(start 0.7874 0.4064)
			(end -0.7874 0.4064)
			(stroke
				(width 0.1524)
				(type default)
			)
			(layer "F.SilkS")
		)
		(fp_line
			(start 0.7874 -0.4064)
			(end 0.7874 0.4064)
			(stroke
				(width 0.1524)
				(type default)
			)
			(layer "F.SilkS")
		)
		(fp_line
			(start -0.7874 0.4064)
			(end -0.7874 -0.4064)
			(stroke
				(width 0.1524)
				(type default)
			)
			(layer "F.SilkS")
		)
		(fp_line
			(start -0.7874 -0.4064)
			(end 0.7874 -0.4064)
			(stroke
				(width 0.1524)
				(type default)
			)
			(layer "F.SilkS")
		)
		(fp_line
			(start 0.67945 0.3048)
			(end 0.120396 0.3048)
			(stroke
				(width 0.1)
				(type default)
			)
			(layer "F.Fab")
		)
		(fp_line
			(start 0.67945 -0.3048)
			(end 0.67945 0.3048)
			(stroke
				(width 0.1)
				(type default)
			)
			(layer "F.Fab")
		)
		(fp_line
			(start 0.12065 -0.2794)
			(end 0.12065 -0.3048)
			(stroke
				(width 0.1)
				(type default)
			)
			(layer "F.Fab")
		)
		(fp_line
			(start 0.12065 -0.3048)
			(end 0.67945 -0.3048)
			(stroke
				(width 0.1)
				(type default)
			)
			(layer "F.Fab")
		)
		(fp_line
			(start 0.120396 0.3048)
			(end 0.120396 0.2794)
			(stroke
				(width 0.1)
				(type default)
			)
			(layer "F.Fab")
		)
		(fp_line
			(start 0.120396 0.2794)
			(end -0.12065 0.2794)
			(stroke
				(width 0.1)
				(type default)
			)
			(layer "F.Fab")
		)
		(fp_line
			(start -0.12065 0.3048)
			(end -0.67945 0.3048)
			(stroke
				(width 0.1)
				(type default)
			)
			(layer "F.Fab")
		)
		(fp_line
			(start -0.12065 0.2794)
			(end -0.12065 0.3048)
			(stroke
				(width 0.1)
				(type default)
			)
			(layer "F.Fab")
		)
		(fp_line
			(start -0.12065 -0.2794)
			(end 0.12065 -0.2794)
			(stroke
				(width 0.1)
				(type default)
			)
			(layer "F.Fab")
		)
		(fp_line
			(start -0.12065 -0.305054)
			(end -0.12065 -0.2794)
			(stroke
				(width 0.1)
				(type default)
			)
			(layer "F.Fab")
		)
		(fp_line
			(start -0.67945 0.3048)
			(end -0.67945 -0.305054)
			(stroke
				(width 0.1)
				(type default)
			)
			(layer "F.Fab")
		)
		(fp_line
			(start -0.67945 -0.305054)
			(end -0.12065 -0.305054)
			(stroke
				(width 0.1)
				(type default)
			)
			(layer "F.Fab")
		)
		(pad "1" smd circle
			(at -0.40005 0 180)
			(size 0 0)
			(layers "F.Cu" "F.Mask" "F.Paste")
			(net "GND")
		)
		(pad "2" smd circle
			(at 0.40005 0 180)
			(size 0 0)
			(layers "F.Cu" "F.Mask" "F.Paste")
			(net "GPU_FPGA_EROT_FATALERR_N")
		)
	)
	(footprint ""
		(layer "F.Cu")
		(at 328.03973 -70.52437 90)
		(property "Reference" "PC876"
			(at 0 0 90)
			(layer "F.SilkS")
			(hide yes)
			(effects
				(font
					(size 1.27 1.27)
				)
			)
		)
		(property "Value" ""
			(at 0 0 90)
			(layer "F.Fab")
			(effects
				(font
					(size 1.27 1.27)
				)
			)
		)
		(duplicate_pad_numbers_are_jumpers no)
		(fp_line
			(start 1.524 -0.762)
			(end 1.524 0.762)
			(stroke
				(width 0.1524)
				(type default)
			)
			(layer "F.SilkS")
		)
		(fp_line
			(start -1.524 -0.762)
			(end 1.524 -0.762)
			(stroke
				(width 0.1524)
				(type default)
			)
			(layer "F.SilkS")
		)
		(fp_line
			(start 1.524 0.762)
			(end -1.524 0.762)
			(stroke
				(width 0.1524)
				(type default)
			)
			(layer "F.SilkS")
		)
		(fp_line
			(start -1.524 0.762)
			(end -1.524 -0.762)
			(stroke
				(width 0.1524)
				(type default)
			)
			(layer "F.SilkS")
		)
		(fp_line
			(start 1.1049 -0.724916)
			(end -1.1049 -0.724916)
			(stroke
				(width 0.1)
				(type default)
			)
			(layer "F.Fab")
		)
		(fp_line
			(start -1.1049 -0.724916)
			(end -1.1049 0.724916)
			(stroke
				(width 0.1)
				(type default)
			)
			(layer "F.Fab")
		)
		(fp_line
			(start 1.1049 0.724916)
			(end 1.1049 -0.724916)
			(stroke
				(width 0.1)
				(type default)
			)
			(layer "F.Fab")
		)
		(fp_line
			(start -1.1049 0.724916)
			(end 1.1049 0.724916)
			(stroke
				(width 0.1)
				(type default)
			)
			(layer "F.Fab")
		)
		(pad "1" smd rect
			(at -0.889 0 270)
			(size 1.016 1.27)
			(layers "F.Cu" "F.Mask" "F.Paste")
			(net "P12V_SSD11_R")
		)
		(pad "2" smd rect
			(at 0.889 0 270)
			(size 1.016 1.27)
			(layers "F.Cu" "F.Mask" "F.Paste")
			(net "GND")
		)
	)
	(footprint ""
		(layer "F.Cu")
		(at 358.792272 -251.054362)
		(property "Reference" "R1776"
			(at 0 0 0)
			(layer "F.SilkS")
			(hide yes)
			(effects
				(font
					(size 1.27 1.27)
				)
			)
		)
		(property "Value" ""
			(at 0 0 0)
			(layer "F.Fab")
			(effects
				(font
					(size 1.27 1.27)
				)
			)
		)
		(duplicate_pad_numbers_are_jumpers no)
		(fp_line
			(start -0.7874 -0.4064)
			(end 0.7874 -0.4064)
			(stroke
				(width 0.1524)
				(type default)
			)
			(layer "F.SilkS")
		)
		(fp_line
			(start -0.7874 0.4064)
			(end -0.7874 -0.4064)
			(stroke
				(width 0.1524)
				(type default)
			)
			(layer "F.SilkS")
		)
		(fp_line
			(start 0.7874 -0.4064)
			(end 0.7874 0.4064)
			(stroke
				(width 0.1524)
				(type default)
			)
			(layer "F.SilkS")
		)
		(fp_line
			(start 0.7874 0.4064)
			(end -0.7874 0.4064)
			(stroke
				(width 0.1524)
				(type default)
			)
			(layer "F.SilkS")
		)
		(fp_line
			(start -0.67945 -0.305054)
			(end -0.12065 -0.305054)
			(stroke
				(width 0.1)
				(type default)
			)
			(layer "F.Fab")
		)
		(fp_line
			(start -0.67945 0.3048)
			(end -0.67945 -0.305054)
			(stroke
				(width 0.1)
				(type default)
			)
			(layer "F.Fab")
		)
		(fp_line
			(start -0.12065 -0.305054)
			(end -0.12065 -0.2794)
			(stroke
				(width 0.1)
				(type default)
			)
			(layer "F.Fab")
		)
		(fp_line
			(start -0.12065 -0.2794)
			(end 0.12065 -0.2794)
			(stroke
				(width 0.1)
				(type default)
			)
			(layer "F.Fab")
		)
		(fp_line
			(start -0.12065 0.2794)
			(end -0.12065 0.3048)
			(stroke
				(width 0.1)
				(type default)
			)
			(layer "F.Fab")
		)
		(fp_line
			(start -0.12065 0.3048)
			(end -0.67945 0.3048)
			(stroke
				(width 0.1)
				(type default)
			)
			(layer "F.Fab")
		)
		(fp_line
			(start 0.120396 0.2794)
			(end -0.12065 0.2794)
			(stroke
				(width 0.1)
				(type default)
			)
			(layer "F.Fab")
		)
		(fp_line
			(start 0.120396 0.3048)
			(end 0.120396 0.2794)
			(stroke
				(width 0.1)
				(type default)
			)
			(layer "F.Fab")
		)
		(fp_line
			(start 0.12065 -0.3048)
			(end 0.67945 -0.3048)
			(stroke
				(width 0.1)
				(type default)
			)
			(layer "F.Fab")
		)
		(fp_line
			(start 0.12065 -0.2794)
			(end 0.12065 -0.3048)
			(stroke
				(width 0.1)
				(type default)
			)
			(layer "F.Fab")
		)
		(fp_line
			(start 0.67945 -0.3048)
			(end 0.67945 0.3048)
			(stroke
				(width 0.1)
				(type default)
			)
			(layer "F.Fab")
		)
		(fp_line
			(start 0.67945 0.3048)
			(end 0.120396 0.3048)
			(stroke
				(width 0.1)
				(type default)
			)
			(layer "F.Fab")
		)
		(pad "1" smd circle
			(at -0.40005 0)
			(size 0 0)
			(layers "F.Cu" "F.Mask" "F.Paste")
			(net "SMB_BIC_I2C6_MUX_VR_R_SCL")
		)
		(pad "2" smd circle
			(at 0.40005 0)
			(size 0 0)
			(layers "F.Cu" "F.Mask" "F.Paste")
			(net "SMB_BIC_I2C6_MUX_VR_SCL")
		)
	)
	(footprint ""
		(layer "F.Cu")
		(at 336.042 -165.989)
		(property "Reference" "R4727"
			(at 0 0 0)
			(layer "F.SilkS")
			(hide yes)
			(effects
				(font
					(size 1.27 1.27)
				)
			)
		)
		(property "Value" ""
			(at 0 0 0)
			(layer "F.Fab")
			(effects
				(font
					(size 1.27 1.27)
				)
			)
		)
		(duplicate_pad_numbers_are_jumpers no)
		(fp_line
			(start -0.7874 -0.4064)
			(end 0.7874 -0.4064)
			(stroke
				(width 0.1524)
				(type default)
			)
			(layer "F.SilkS")
		)
		(fp_line
			(start -0.7874 0.4064)
			(end -0.7874 -0.4064)
			(stroke
				(width 0.1524)
				(type default)
			)
			(layer "F.SilkS")
		)
		(fp_line
			(start 0.7874 -0.4064)
			(end 0.7874 0.4064)
			(stroke
				(width 0.1524)
				(type default)
			)
			(layer "F.SilkS")
		)
		(fp_line
			(start 0.7874 0.4064)
			(end -0.7874 0.4064)
			(stroke
				(width 0.1524)
				(type default)
			)
			(layer "F.SilkS")
		)
		(fp_line
			(start -0.67945 -0.305054)
			(end -0.12065 -0.305054)
			(stroke
				(width 0.1)
				(type default)
			)
			(layer "F.Fab")
		)
		(fp_line
			(start -0.67945 0.3048)
			(end -0.67945 -0.305054)
			(stroke
				(width 0.1)
				(type default)
			)
			(layer "F.Fab")
		)
		(fp_line
			(start -0.12065 -0.305054)
			(end -0.12065 -0.2794)
			(stroke
				(width 0.1)
				(type default)
			)
			(layer "F.Fab")
		)
		(fp_line
			(start -0.12065 -0.2794)
			(end 0.12065 -0.2794)
			(stroke
				(width 0.1)
				(type default)
			)
			(layer "F.Fab")
		)
		(fp_line
			(start -0.12065 0.2794)
			(end -0.12065 0.3048)
			(stroke
				(width 0.1)
				(type default)
			)
			(layer "F.Fab")
		)
		(fp_line
			(start -0.12065 0.3048)
			(end -0.67945 0.3048)
			(stroke
				(width 0.1)
				(type default)
			)
			(layer "F.Fab")
		)
		(fp_line
			(start 0.120396 0.2794)
			(end -0.12065 0.2794)
			(stroke
				(width 0.1)
				(type default)
			)
			(layer "F.Fab")
		)
		(fp_line
			(start 0.120396 0.3048)
			(end 0.120396 0.2794)
			(stroke
				(width 0.1)
				(type default)
			)
			(layer "F.Fab")
		)
		(fp_line
			(start 0.12065 -0.3048)
			(end 0.67945 -0.3048)
			(stroke
				(width 0.1)
				(type default)
			)
			(layer "F.Fab")
		)
		(fp_line
			(start 0.12065 -0.2794)
			(end 0.12065 -0.3048)
			(stroke
				(width 0.1)
				(type default)
			)
			(layer "F.Fab")
		)
		(fp_line
			(start 0.67945 -0.3048)
			(end 0.67945 0.3048)
			(stroke
				(width 0.1)
				(type default)
			)
			(layer "F.Fab")
		)
		(fp_line
			(start 0.67945 0.3048)
			(end 0.120396 0.3048)
			(stroke
				(width 0.1)
				(type default)
			)
			(layer "F.Fab")
		)
		(pad "1" smd circle
			(at -0.40005 0)
			(size 0 0)
			(layers "F.Cu" "F.Mask" "F.Paste")
			(net "P3V3_AUX")
		)
		(pad "2" smd circle
			(at 0.40005 0)
			(size 0 0)
			(layers "F.Cu" "F.Mask" "F.Paste")
			(net "SSD11_PEX_PWR_EN_R")
		)
	)
	(footprint ""
		(layer "F.Cu")
		(at 171.979844 -138.6332 180)
		(property "Reference" "R143"
			(at 0 0 180)
			(layer "F.SilkS")
			(hide yes)
			(effects
				(font
					(size 1.27 1.27)
				)
			)
		)
		(property "Value" ""
			(at 0 0 180)
			(layer "F.Fab")
			(effects
				(font
					(size 1.27 1.27)
				)
			)
		)
		(duplicate_pad_numbers_are_jumpers no)
		(fp_line
			(start 0.7874 0.4064)
			(end -0.7874 0.4064)
			(stroke
				(width 0.1524)
				(type default)
			)
			(layer "F.SilkS")
		)
		(fp_line
			(start 0.7874 -0.4064)
			(end 0.7874 0.4064)
			(stroke
				(width 0.1524)
				(type default)
			)
			(layer "F.SilkS")
		)
		(fp_line
			(start -0.7874 0.4064)
			(end -0.7874 -0.4064)
			(stroke
				(width 0.1524)
				(type default)
			)
			(layer "F.SilkS")
		)
		(fp_line
			(start -0.7874 -0.4064)
			(end 0.7874 -0.4064)
			(stroke
				(width 0.1524)
				(type default)
			)
			(layer "F.SilkS")
		)
		(fp_line
			(start 0.67945 0.3048)
			(end 0.120396 0.3048)
			(stroke
				(width 0.1)
				(type default)
			)
			(layer "F.Fab")
		)
		(fp_line
			(start 0.67945 -0.3048)
			(end 0.67945 0.3048)
			(stroke
				(width 0.1)
				(type default)
			)
			(layer "F.Fab")
		)
		(fp_line
			(start 0.12065 -0.2794)
			(end 0.12065 -0.3048)
			(stroke
				(width 0.1)
				(type default)
			)
			(layer "F.Fab")
		)
		(fp_line
			(start 0.12065 -0.3048)
			(end 0.67945 -0.3048)
			(stroke
				(width 0.1)
				(type default)
			)
			(layer "F.Fab")
		)
		(fp_line
			(start 0.120396 0.3048)
			(end 0.120396 0.2794)
			(stroke
				(width 0.1)
				(type default)
			)
			(layer "F.Fab")
		)
		(fp_line
			(start 0.120396 0.2794)
			(end -0.12065 0.2794)
			(stroke
				(width 0.1)
				(type default)
			)
			(layer "F.Fab")
		)
		(fp_line
			(start -0.12065 0.3048)
			(end -0.67945 0.3048)
			(stroke
				(width 0.1)
				(type default)
			)
			(layer "F.Fab")
		)
		(fp_line
			(start -0.12065 0.2794)
			(end -0.12065 0.3048)
			(stroke
				(width 0.1)
				(type default)
			)
			(layer "F.Fab")
		)
		(fp_line
			(start -0.12065 -0.2794)
			(end 0.12065 -0.2794)
			(stroke
				(width 0.1)
				(type default)
			)
			(layer "F.Fab")
		)
		(fp_line
			(start -0.12065 -0.305054)
			(end -0.12065 -0.2794)
			(stroke
				(width 0.1)
				(type default)
			)
			(layer "F.Fab")
		)
		(fp_line
			(start -0.67945 0.3048)
			(end -0.67945 -0.305054)
			(stroke
				(width 0.1)
				(type default)
			)
			(layer "F.Fab")
		)
		(fp_line
			(start -0.67945 -0.305054)
			(end -0.12065 -0.305054)
			(stroke
				(width 0.1)
				(type default)
			)
			(layer "F.Fab")
		)
		(pad "1" smd circle
			(at -0.40005 0 180)
			(size 0 0)
			(layers "F.Cu" "F.Mask" "F.Paste")
			(net "PRSNT_NIC2_N")
		)
		(pad "2" smd circle
			(at 0.40005 0 180)
			(size 0 0)
			(layers "F.Cu" "F.Mask" "F.Paste")
			(net "PRSNTB2_NIC2_N")
		)
	)
	(footprint ""
		(layer "F.Cu")
		(at 295.852342 -343.952322 90)
		(property "Reference" "C587"
			(at 0 0 90)
			(layer "F.SilkS")
			(hide yes)
			(effects
				(font
					(size 1.27 1.27)
				)
			)
		)
		(property "Value" ""
			(at 0 0 90)
			(layer "F.Fab")
			(effects
				(font
					(size 1.27 1.27)
				)
			)
		)
		(duplicate_pad_numbers_are_jumpers no)
		(fp_line
			(start 0.299974 -0.150114)
			(end 0.299974 0.150114)
			(stroke
				(width 0.1)
				(type default)
			)
			(layer "F.Fab")
		)
		(fp_line
			(start -0.299974 -0.150114)
			(end 0.299974 -0.150114)
			(stroke
				(width 0.1)
				(type default)
			)
			(layer "F.Fab")
		)
		(fp_line
			(start 0.299974 0.150114)
			(end -0.299974 0.150114)
			(stroke
				(width 0.1)
				(type default)
			)
			(layer "F.Fab")
		)
		(fp_line
			(start -0.299974 0.150114)
			(end -0.299974 -0.150114)
			(stroke
				(width 0.1)
				(type default)
			)
			(layer "F.Fab")
		)
		(pad "1" smd rect
			(at -0.2667 0 90)
			(size 0.3048 0.381)
			(layers "F.Cu" "F.Mask" "F.Paste")
			(net "P5E_PEX2_STN7_TX_DP<125>")
		)
		(pad "2" smd rect
			(at 0.2667 0 90)
			(size 0.3048 0.381)
			(layers "F.Cu" "F.Mask" "F.Paste")
			(net "P5E_PEX2_STN7_TX_C_DP<125>")
		)
	)
	(footprint ""
		(layer "F.Cu")
		(at 166.184072 -356.244906 90)
		(property "Reference" "C2517"
			(at 0 0 90)
			(layer "F.SilkS")
			(hide yes)
			(effects
				(font
					(size 1.27 1.27)
				)
			)
		)
		(property "Value" ""
			(at 0 0 90)
			(layer "F.Fab")
			(effects
				(font
					(size 1.27 1.27)
				)
			)
		)
		(duplicate_pad_numbers_are_jumpers no)
		(fp_line
			(start 0.299974 -0.150114)
			(end 0.299974 0.150114)
			(stroke
				(width 0.1)
				(type default)
			)
			(layer "F.Fab")
		)
		(fp_line
			(start -0.299974 -0.150114)
			(end 0.299974 -0.150114)
			(stroke
				(width 0.1)
				(type default)
			)
			(layer "F.Fab")
		)
		(fp_line
			(start 0.299974 0.150114)
			(end -0.299974 0.150114)
			(stroke
				(width 0.1)
				(type default)
			)
			(layer "F.Fab")
		)
		(fp_line
			(start -0.299974 0.150114)
			(end -0.299974 -0.150114)
			(stroke
				(width 0.1)
				(type default)
			)
			(layer "F.Fab")
		)
		(pad "1" smd rect
			(at -0.2667 0 90)
			(size 0.3048 0.381)
			(layers "F.Cu" "F.Mask" "F.Paste")
			(net "P5E_PEX1_STN4_TX_DN<77>")
		)
		(pad "2" smd rect
			(at 0.2667 0 90)
			(size 0.3048 0.381)
			(layers "F.Cu" "F.Mask" "F.Paste")
			(net "P5E_PEX1_STN4_TX_C_DN<77>")
		)
	)
	(footprint ""
		(layer "F.Cu")
		(at 235.623608 -147.720812)
		(property "Reference" "R4221"
			(at 0 0 0)
			(layer "F.SilkS")
			(hide yes)
			(effects
				(font
					(size 1.27 1.27)
				)
			)
		)
		(property "Value" ""
			(at 0 0 0)
			(layer "F.Fab")
			(effects
				(font
					(size 1.27 1.27)
				)
			)
		)
		(duplicate_pad_numbers_are_jumpers no)
		(fp_line
			(start -0.7874 -0.4064)
			(end 0.7874 -0.4064)
			(stroke
				(width 0.1524)
				(type default)
			)
			(layer "F.SilkS")
		)
		(fp_line
			(start -0.7874 0.4064)
			(end -0.7874 -0.4064)
			(stroke
				(width 0.1524)
				(type default)
			)
			(layer "F.SilkS")
		)
		(fp_line
			(start 0.7874 -0.4064)
			(end 0.7874 0.4064)
			(stroke
				(width 0.1524)
				(type default)
			)
			(layer "F.SilkS")
		)
		(fp_line
			(start 0.7874 0.4064)
			(end -0.7874 0.4064)
			(stroke
				(width 0.1524)
				(type default)
			)
			(layer "F.SilkS")
		)
		(fp_line
			(start -0.67945 -0.305054)
			(end -0.12065 -0.305054)
			(stroke
				(width 0.1)
				(type default)
			)
			(layer "F.Fab")
		)
		(fp_line
			(start -0.67945 0.3048)
			(end -0.67945 -0.305054)
			(stroke
				(width 0.1)
				(type default)
			)
			(layer "F.Fab")
		)
		(fp_line
			(start -0.12065 -0.305054)
			(end -0.12065 -0.2794)
			(stroke
				(width 0.1)
				(type default)
			)
			(layer "F.Fab")
		)
		(fp_line
			(start -0.12065 -0.2794)
			(end 0.12065 -0.2794)
			(stroke
				(width 0.1)
				(type default)
			)
			(layer "F.Fab")
		)
		(fp_line
			(start -0.12065 0.2794)
			(end -0.12065 0.3048)
			(stroke
				(width 0.1)
				(type default)
			)
			(layer "F.Fab")
		)
		(fp_line
			(start -0.12065 0.3048)
			(end -0.67945 0.3048)
			(stroke
				(width 0.1)
				(type default)
			)
			(layer "F.Fab")
		)
		(fp_line
			(start 0.120396 0.2794)
			(end -0.12065 0.2794)
			(stroke
				(width 0.1)
				(type default)
			)
			(layer "F.Fab")
		)
		(fp_line
			(start 0.120396 0.3048)
			(end 0.120396 0.2794)
			(stroke
				(width 0.1)
				(type default)
			)
			(layer "F.Fab")
		)
		(fp_line
			(start 0.12065 -0.3048)
			(end 0.67945 -0.3048)
			(stroke
				(width 0.1)
				(type default)
			)
			(layer "F.Fab")
		)
		(fp_line
			(start 0.12065 -0.2794)
			(end 0.12065 -0.3048)
			(stroke
				(width 0.1)
				(type default)
			)
			(layer "F.Fab")
		)
		(fp_line
			(start 0.67945 -0.3048)
			(end 0.67945 0.3048)
			(stroke
				(width 0.1)
				(type default)
			)
			(layer "F.Fab")
		)
		(fp_line
			(start 0.67945 0.3048)
			(end 0.120396 0.3048)
			(stroke
				(width 0.1)
				(type default)
			)
			(layer "F.Fab")
		)
		(pad "1" smd circle
			(at -0.40005 0)
			(size 0 0)
			(layers "F.Cu" "F.Mask" "F.Paste")
			(net "CLK_GEN_CK440_PEX_OE4_N")
		)
		(pad "2" smd circle
			(at 0.40005 0)
			(size 0 0)
			(layers "F.Cu" "F.Mask" "F.Paste")
			(net "P3V3")
		)
	)
	(footprint ""
		(layer "F.Cu")
		(at 236.492288 -97.258378 -90)
		(property "Reference" "R1009"
			(at 0 0 270)
			(layer "F.SilkS")
			(hide yes)
			(effects
				(font
					(size 1.27 1.27)
				)
			)
		)
		(property "Value" ""
			(at 0 0 270)
			(layer "F.Fab")
			(effects
				(font
					(size 1.27 1.27)
				)
			)
		)
		(duplicate_pad_numbers_are_jumpers no)
		(fp_line
			(start -0.7874 0.4064)
			(end -0.7874 -0.4064)
			(stroke
				(width 0.1524)
				(type default)
			)
			(layer "F.SilkS")
		)
		(fp_line
			(start 0.7874 0.4064)
			(end -0.7874 0.4064)
			(stroke
				(width 0.1524)
				(type default)
			)
			(layer "F.SilkS")
		)
		(fp_line
			(start -0.7874 -0.4064)
			(end 0.7874 -0.4064)
			(stroke
				(width 0.1524)
				(type default)
			)
			(layer "F.SilkS")
		)
		(fp_line
			(start 0.7874 -0.4064)
			(end 0.7874 0.4064)
			(stroke
				(width 0.1524)
				(type default)
			)
			(layer "F.SilkS")
		)
		(fp_line
			(start -0.67945 0.3048)
			(end -0.67945 -0.305054)
			(stroke
				(width 0.1)
				(type default)
			)
			(layer "F.Fab")
		)
		(fp_line
			(start -0.12065 0.3048)
			(end -0.67945 0.3048)
			(stroke
				(width 0.1)
				(type default)
			)
			(layer "F.Fab")
		)
		(fp_line
			(start 0.120396 0.3048)
			(end 0.120396 0.2794)
			(stroke
				(width 0.1)
				(type default)
			)
			(layer "F.Fab")
		)
		(fp_line
			(start 0.67945 0.3048)
			(end 0.120396 0.3048)
			(stroke
				(width 0.1)
				(type default)
			)
			(layer "F.Fab")
		)
		(fp_line
			(start -0.12065 0.2794)
			(end -0.12065 0.3048)
			(stroke
				(width 0.1)
				(type default)
			)
			(layer "F.Fab")
		)
		(fp_line
			(start 0.120396 0.2794)
			(end -0.12065 0.2794)
			(stroke
				(width 0.1)
				(type default)
			)
			(layer "F.Fab")
		)
		(fp_line
			(start -0.12065 -0.2794)
			(end 0.12065 -0.2794)
			(stroke
				(width 0.1)
				(type default)
			)
			(layer "F.Fab")
		)
		(fp_line
			(start 0.12065 -0.2794)
			(end 0.12065 -0.3048)
			(stroke
				(width 0.1)
				(type default)
			)
			(layer "F.Fab")
		)
		(fp_line
			(start 0.12065 -0.3048)
			(end 0.67945 -0.3048)
			(stroke
				(width 0.1)
				(type default)
			)
			(layer "F.Fab")
		)
		(fp_line
			(start 0.67945 -0.3048)
			(end 0.67945 0.3048)
			(stroke
				(width 0.1)
				(type default)
			)
			(layer "F.Fab")
		)
		(fp_line
			(start -0.67945 -0.305054)
			(end -0.12065 -0.305054)
			(stroke
				(width 0.1)
				(type default)
			)
			(layer "F.Fab")
		)
		(fp_line
			(start -0.12065 -0.305054)
			(end -0.12065 -0.2794)
			(stroke
				(width 0.1)
				(type default)
			)
			(layer "F.Fab")
		)
		(pad "1" smd circle
			(at -0.40005 0 270)
			(size 0 0)
			(layers "F.Cu" "F.Mask" "F.Paste")
			(net "P3V3_AUX")
		)
		(pad "2" smd circle
			(at 0.40005 0 270)
			(size 0 0)
			(layers "F.Cu" "F.Mask" "F.Paste")
			(net "RST_PEX_USB_HUB_R_N")
		)
	)
	(footprint ""
		(layer "F.Cu")
		(at 456.271376 -258.331208 -90)
		(property "Reference" "R6554"
			(at 0 0 270)
			(layer "F.SilkS")
			(hide yes)
			(effects
				(font
					(size 1.27 1.27)
				)
			)
		)
		(property "Value" ""
			(at 0 0 270)
			(layer "F.Fab")
			(effects
				(font
					(size 1.27 1.27)
				)
			)
		)
		(duplicate_pad_numbers_are_jumpers no)
		(fp_line
			(start -0.7874 0.4064)
			(end -0.7874 -0.4064)
			(stroke
				(width 0.1524)
				(type default)
			)
			(layer "F.SilkS")
		)
		(fp_line
			(start 0.7874 0.4064)
			(end -0.7874 0.4064)
			(stroke
				(width 0.1524)
				(type default)
			)
			(layer "F.SilkS")
		)
		(fp_line
			(start -0.7874 -0.4064)
			(end 0.7874 -0.4064)
			(stroke
				(width 0.1524)
				(type default)
			)
			(layer "F.SilkS")
		)
		(fp_line
			(start 0.7874 -0.4064)
			(end 0.7874 0.4064)
			(stroke
				(width 0.1524)
				(type default)
			)
			(layer "F.SilkS")
		)
		(fp_line
			(start -0.67945 0.3048)
			(end -0.67945 -0.305054)
			(stroke
				(width 0.1)
				(type default)
			)
			(layer "F.Fab")
		)
		(fp_line
			(start -0.12065 0.3048)
			(end -0.67945 0.3048)
			(stroke
				(width 0.1)
				(type default)
			)
			(layer "F.Fab")
		)
		(fp_line
			(start 0.120396 0.3048)
			(end 0.120396 0.2794)
			(stroke
				(width 0.1)
				(type default)
			)
			(layer "F.Fab")
		)
		(fp_line
			(start 0.67945 0.3048)
			(end 0.120396 0.3048)
			(stroke
				(width 0.1)
				(type default)
			)
			(layer "F.Fab")
		)
		(fp_line
			(start -0.12065 0.2794)
			(end -0.12065 0.3048)
			(stroke
				(width 0.1)
				(type default)
			)
			(layer "F.Fab")
		)
		(fp_line
			(start 0.120396 0.2794)
			(end -0.12065 0.2794)
			(stroke
				(width 0.1)
				(type default)
			)
			(layer "F.Fab")
		)
		(fp_line
			(start -0.12065 -0.2794)
			(end 0.12065 -0.2794)
			(stroke
				(width 0.1)
				(type default)
			)
			(layer "F.Fab")
		)
		(fp_line
			(start 0.12065 -0.2794)
			(end 0.12065 -0.3048)
			(stroke
				(width 0.1)
				(type default)
			)
			(layer "F.Fab")
		)
		(fp_line
			(start 0.12065 -0.3048)
			(end 0.67945 -0.3048)
			(stroke
				(width 0.1)
				(type default)
			)
			(layer "F.Fab")
		)
		(fp_line
			(start 0.67945 -0.3048)
			(end 0.67945 0.3048)
			(stroke
				(width 0.1)
				(type default)
			)
			(layer "F.Fab")
		)
		(fp_line
			(start -0.67945 -0.305054)
			(end -0.12065 -0.305054)
			(stroke
				(width 0.1)
				(type default)
			)
			(layer "F.Fab")
		)
		(fp_line
			(start -0.12065 -0.305054)
			(end -0.12065 -0.2794)
			(stroke
				(width 0.1)
				(type default)
			)
			(layer "F.Fab")
		)
		(pad "1" smd circle
			(at -0.40005 0 270)
			(size 0 0)
			(layers "F.Cu" "F.Mask" "F.Paste")
			(net "P1V25_SERDES_VDDPLL_PEX3")
		)
		(pad "2" smd circle
			(at 0.40005 0 270)
			(size 0 0)
			(layers "F.Cu" "F.Mask" "F.Paste")
			(net "P1V25_SERDES_VDDPLL_PEX3_C3")
		)
	)
	(footprint ""
		(layer "F.Cu")
		(at 442.794136 -117.426486)
		(property "Reference" "PC916"
			(at 0 0 0)
			(layer "F.SilkS")
			(hide yes)
			(effects
				(font
					(size 1.27 1.27)
				)
			)
		)
		(property "Value" ""
			(at 0 0 0)
			(layer "F.Fab")
			(effects
				(font
					(size 1.27 1.27)
				)
			)
		)
		(duplicate_pad_numbers_are_jumpers no)
		(fp_line
			(start -0.7874 -0.4064)
			(end 0.7874 -0.4064)
			(stroke
				(width 0.1524)
				(type default)
			)
			(layer "F.SilkS")
		)
		(fp_line
			(start -0.7874 0.4064)
			(end -0.7874 -0.4064)
			(stroke
				(width 0.1524)
				(type default)
			)
			(layer "F.SilkS")
		)
		(fp_line
			(start 0.7874 -0.4064)
			(end 0.7874 0.4064)
			(stroke
				(width 0.1524)
				(type default)
			)
			(layer "F.SilkS")
		)
		(fp_line
			(start 0.7874 0.4064)
			(end -0.7874 0.4064)
			(stroke
				(width 0.1524)
				(type default)
			)
			(layer "F.SilkS")
		)
		(fp_line
			(start -0.67945 -0.305054)
			(end -0.12065 -0.305054)
			(stroke
				(width 0.1)
				(type default)
			)
			(layer "F.Fab")
		)
		(fp_line
			(start -0.67945 0.3048)
			(end -0.67945 -0.305054)
			(stroke
				(width 0.1)
				(type default)
			)
			(layer "F.Fab")
		)
		(fp_line
			(start -0.12065 -0.305054)
			(end -0.12065 -0.2794)
			(stroke
				(width 0.1)
				(type default)
			)
			(layer "F.Fab")
		)
		(fp_line
			(start -0.12065 -0.2794)
			(end 0.12065 -0.2794)
			(stroke
				(width 0.1)
				(type default)
			)
			(layer "F.Fab")
		)
		(fp_line
			(start -0.12065 0.2794)
			(end -0.12065 0.3048)
			(stroke
				(width 0.1)
				(type default)
			)
			(layer "F.Fab")
		)
		(fp_line
			(start -0.12065 0.3048)
			(end -0.67945 0.3048)
			(stroke
				(width 0.1)
				(type default)
			)
			(layer "F.Fab")
		)
		(fp_line
			(start 0.120396 0.2794)
			(end -0.12065 0.2794)
			(stroke
				(width 0.1)
				(type default)
			)
			(layer "F.Fab")
		)
		(fp_line
			(start 0.120396 0.3048)
			(end 0.120396 0.2794)
			(stroke
				(width 0.1)
				(type default)
			)
			(layer "F.Fab")
		)
		(fp_line
			(start 0.12065 -0.3048)
			(end 0.67945 -0.3048)
			(stroke
				(width 0.1)
				(type default)
			)
			(layer "F.Fab")
		)
		(fp_line
			(start 0.12065 -0.2794)
			(end 0.12065 -0.3048)
			(stroke
				(width 0.1)
				(type default)
			)
			(layer "F.Fab")
		)
		(fp_line
			(start 0.67945 -0.3048)
			(end 0.67945 0.3048)
			(stroke
				(width 0.1)
				(type default)
			)
			(layer "F.Fab")
		)
		(fp_line
			(start 0.67945 0.3048)
			(end 0.120396 0.3048)
			(stroke
				(width 0.1)
				(type default)
			)
			(layer "F.Fab")
		)
		(pad "1" smd circle
			(at -0.40005 0)
			(size 0 0)
			(layers "F.Cu" "F.Mask" "F.Paste")
			(net "P3V3_NIC7_CO_MODE")
		)
		(pad "2" smd circle
			(at 0.40005 0)
			(size 0 0)
			(layers "F.Cu" "F.Mask" "F.Paste")
			(net "GND")
		)
	)
	(footprint ""
		(layer "F.Cu")
		(at 330.835 -239.395 180)
		(property "Reference" "C2744"
			(at 0 0 180)
			(layer "F.SilkS")
			(hide yes)
			(effects
				(font
					(size 1.27 1.27)
				)
			)
		)
		(property "Value" ""
			(at 0 0 180)
			(layer "F.Fab")
			(effects
				(font
					(size 1.27 1.27)
				)
			)
		)
		(duplicate_pad_numbers_are_jumpers no)
		(fp_line
			(start 0.7874 0.4064)
			(end -0.7874 0.4064)
			(stroke
				(width 0.1524)
				(type default)
			)
			(layer "F.SilkS")
		)
		(fp_line
			(start 0.7874 -0.4064)
			(end 0.7874 0.4064)
			(stroke
				(width 0.1524)
				(type default)
			)
			(layer "F.SilkS")
		)
		(fp_line
			(start -0.7874 0.4064)
			(end -0.7874 -0.4064)
			(stroke
				(width 0.1524)
				(type default)
			)
			(layer "F.SilkS")
		)
		(fp_line
			(start -0.7874 -0.4064)
			(end 0.7874 -0.4064)
			(stroke
				(width 0.1524)
				(type default)
			)
			(layer "F.SilkS")
		)
		(fp_line
			(start 0.67945 0.3048)
			(end 0.120396 0.3048)
			(stroke
				(width 0.1)
				(type default)
			)
			(layer "F.Fab")
		)
		(fp_line
			(start 0.67945 -0.3048)
			(end 0.67945 0.3048)
			(stroke
				(width 0.1)
				(type default)
			)
			(layer "F.Fab")
		)
		(fp_line
			(start 0.12065 -0.2794)
			(end 0.12065 -0.3048)
			(stroke
				(width 0.1)
				(type default)
			)
			(layer "F.Fab")
		)
		(fp_line
			(start 0.12065 -0.3048)
			(end 0.67945 -0.3048)
			(stroke
				(width 0.1)
				(type default)
			)
			(layer "F.Fab")
		)
		(fp_line
			(start 0.120396 0.3048)
			(end 0.120396 0.2794)
			(stroke
				(width 0.1)
				(type default)
			)
			(layer "F.Fab")
		)
		(fp_line
			(start 0.120396 0.2794)
			(end -0.12065 0.2794)
			(stroke
				(width 0.1)
				(type default)
			)
			(layer "F.Fab")
		)
		(fp_line
			(start -0.12065 0.3048)
			(end -0.67945 0.3048)
			(stroke
				(width 0.1)
				(type default)
			)
			(layer "F.Fab")
		)
		(fp_line
			(start -0.12065 0.2794)
			(end -0.12065 0.3048)
			(stroke
				(width 0.1)
				(type default)
			)
			(layer "F.Fab")
		)
		(fp_line
			(start -0.12065 -0.2794)
			(end 0.12065 -0.2794)
			(stroke
				(width 0.1)
				(type default)
			)
			(layer "F.Fab")
		)
		(fp_line
			(start -0.12065 -0.305054)
			(end -0.12065 -0.2794)
			(stroke
				(width 0.1)
				(type default)
			)
			(layer "F.Fab")
		)
		(fp_line
			(start -0.67945 0.3048)
			(end -0.67945 -0.305054)
			(stroke
				(width 0.1)
				(type default)
			)
			(layer "F.Fab")
		)
		(fp_line
			(start -0.67945 -0.305054)
			(end -0.12065 -0.305054)
			(stroke
				(width 0.1)
				(type default)
			)
			(layer "F.Fab")
		)
		(pad "1" smd circle
			(at -0.40005 0 180)
			(size 0 0)
			(layers "F.Cu" "F.Mask" "F.Paste")
			(net "P3V3_AUX")
		)
		(pad "2" smd circle
			(at 0.40005 0 180)
			(size 0 0)
			(layers "F.Cu" "F.Mask" "F.Paste")
			(net "GND")
		)
	)
	(footprint ""
		(layer "F.Cu")
		(at 245.553484 -236.675168 -90)
		(property "Reference" "C3989"
			(at 0 0 270)
			(layer "F.SilkS")
			(hide yes)
			(effects
				(font
					(size 1.27 1.27)
				)
			)
		)
		(property "Value" ""
			(at 0 0 270)
			(layer "F.Fab")
			(effects
				(font
					(size 1.27 1.27)
				)
			)
		)
		(duplicate_pad_numbers_are_jumpers no)
		(fp_line
			(start -0.7874 0.4064)
			(end -0.7874 -0.4064)
			(stroke
				(width 0.1524)
				(type default)
			)
			(layer "F.SilkS")
		)
		(fp_line
			(start 0.7874 0.4064)
			(end -0.7874 0.4064)
			(stroke
				(width 0.1524)
				(type default)
			)
			(layer "F.SilkS")
		)
		(fp_line
			(start -0.7874 -0.4064)
			(end 0.7874 -0.4064)
			(stroke
				(width 0.1524)
				(type default)
			)
			(layer "F.SilkS")
		)
		(fp_line
			(start 0.7874 -0.4064)
			(end 0.7874 0.4064)
			(stroke
				(width 0.1524)
				(type default)
			)
			(layer "F.SilkS")
		)
		(fp_line
			(start -0.67945 0.3048)
			(end -0.67945 -0.305054)
			(stroke
				(width 0.1)
				(type default)
			)
			(layer "F.Fab")
		)
		(fp_line
			(start -0.12065 0.3048)
			(end -0.67945 0.3048)
			(stroke
				(width 0.1)
				(type default)
			)
			(layer "F.Fab")
		)
		(fp_line
			(start 0.120396 0.3048)
			(end 0.120396 0.2794)
			(stroke
				(width 0.1)
				(type default)
			)
			(layer "F.Fab")
		)
		(fp_line
			(start 0.67945 0.3048)
			(end 0.120396 0.3048)
			(stroke
				(width 0.1)
				(type default)
			)
			(layer "F.Fab")
		)
		(fp_line
			(start -0.12065 0.2794)
			(end -0.12065 0.3048)
			(stroke
				(width 0.1)
				(type default)
			)
			(layer "F.Fab")
		)
		(fp_line
			(start 0.120396 0.2794)
			(end -0.12065 0.2794)
			(stroke
				(width 0.1)
				(type default)
			)
			(layer "F.Fab")
		)
		(fp_line
			(start -0.12065 -0.2794)
			(end 0.12065 -0.2794)
			(stroke
				(width 0.1)
				(type default)
			)
			(layer "F.Fab")
		)
		(fp_line
			(start 0.12065 -0.2794)
			(end 0.12065 -0.3048)
			(stroke
				(width 0.1)
				(type default)
			)
			(layer "F.Fab")
		)
		(fp_line
			(start 0.12065 -0.3048)
			(end 0.67945 -0.3048)
			(stroke
				(width 0.1)
				(type default)
			)
			(layer "F.Fab")
		)
		(fp_line
			(start 0.67945 -0.3048)
			(end 0.67945 0.3048)
			(stroke
				(width 0.1)
				(type default)
			)
			(layer "F.Fab")
		)
		(fp_line
			(start -0.67945 -0.305054)
			(end -0.12065 -0.305054)
			(stroke
				(width 0.1)
				(type default)
			)
			(layer "F.Fab")
		)
		(fp_line
			(start -0.12065 -0.305054)
			(end -0.12065 -0.2794)
			(stroke
				(width 0.1)
				(type default)
			)
			(layer "F.Fab")
		)
		(pad "1" smd circle
			(at -0.40005 0 270)
			(size 0 0)
			(layers "F.Cu" "F.Mask" "F.Paste")
			(net "P3V3_AUX")
		)
		(pad "2" smd circle
			(at 0.40005 0 270)
			(size 0 0)
			(layers "F.Cu" "F.Mask" "F.Paste")
			(net "GND")
		)
	)
	(footprint ""
		(layer "F.Cu")
		(at 214.534496 -34.546286 180)
		(property "Reference" "C300"
			(at 0 0 180)
			(layer "F.SilkS")
			(hide yes)
			(effects
				(font
					(size 1.27 1.27)
				)
			)
		)
		(property "Value" ""
			(at 0 0 180)
			(layer "F.Fab")
			(effects
				(font
					(size 1.27 1.27)
				)
			)
		)
		(duplicate_pad_numbers_are_jumpers no)
		(fp_line
			(start 0.299974 0.150114)
			(end -0.299974 0.150114)
			(stroke
				(width 0.1)
				(type default)
			)
			(layer "F.Fab")
		)
		(fp_line
			(start 0.299974 -0.150114)
			(end 0.299974 0.150114)
			(stroke
				(width 0.1)
				(type default)
			)
			(layer "F.Fab")
		)
		(fp_line
			(start -0.299974 0.150114)
			(end -0.299974 -0.150114)
			(stroke
				(width 0.1)
				(type default)
			)
			(layer "F.Fab")
		)
		(fp_line
			(start -0.299974 -0.150114)
			(end 0.299974 -0.150114)
			(stroke
				(width 0.1)
				(type default)
			)
			(layer "F.Fab")
		)
		(pad "1" smd rect
			(at -0.2667 0 180)
			(size 0.3048 0.381)
			(layers "F.Cu" "F.Mask" "F.Paste")
			(net "P5E_PEX1_STN2_TX_DP<35>")
		)
		(pad "2" smd rect
			(at 0.2667 0 180)
			(size 0.3048 0.381)
			(layers "F.Cu" "F.Mask" "F.Paste")
			(net "P5E_PEX1_STN2_TX_C_DP<35>")
		)
	)
	(footprint ""
		(layer "F.Cu")
		(at 383.159 -212.344)
		(property "Reference" "R4622"
			(at 0 0 0)
			(layer "F.SilkS")
			(hide yes)
			(effects
				(font
					(size 1.27 1.27)
				)
			)
		)
		(property "Value" ""
			(at 0 0 0)
			(layer "F.Fab")
			(effects
				(font
					(size 1.27 1.27)
				)
			)
		)
		(duplicate_pad_numbers_are_jumpers no)
		(fp_line
			(start -0.7874 -0.4064)
			(end 0.7874 -0.4064)
			(stroke
				(width 0.1524)
				(type default)
			)
			(layer "F.SilkS")
		)
		(fp_line
			(start -0.7874 0.4064)
			(end -0.7874 -0.4064)
			(stroke
				(width 0.1524)
				(type default)
			)
			(layer "F.SilkS")
		)
		(fp_line
			(start 0.7874 -0.4064)
			(end 0.7874 0.4064)
			(stroke
				(width 0.1524)
				(type default)
			)
			(layer "F.SilkS")
		)
		(fp_line
			(start 0.7874 0.4064)
			(end -0.7874 0.4064)
			(stroke
				(width 0.1524)
				(type default)
			)
			(layer "F.SilkS")
		)
		(fp_line
			(start -0.67945 -0.305054)
			(end -0.12065 -0.305054)
			(stroke
				(width 0.1)
				(type default)
			)
			(layer "F.Fab")
		)
		(fp_line
			(start -0.67945 0.3048)
			(end -0.67945 -0.305054)
			(stroke
				(width 0.1)
				(type default)
			)
			(layer "F.Fab")
		)
		(fp_line
			(start -0.12065 -0.305054)
			(end -0.12065 -0.2794)
			(stroke
				(width 0.1)
				(type default)
			)
			(layer "F.Fab")
		)
		(fp_line
			(start -0.12065 -0.2794)
			(end 0.12065 -0.2794)
			(stroke
				(width 0.1)
				(type default)
			)
			(layer "F.Fab")
		)
		(fp_line
			(start -0.12065 0.2794)
			(end -0.12065 0.3048)
			(stroke
				(width 0.1)
				(type default)
			)
			(layer "F.Fab")
		)
		(fp_line
			(start -0.12065 0.3048)
			(end -0.67945 0.3048)
			(stroke
				(width 0.1)
				(type default)
			)
			(layer "F.Fab")
		)
		(fp_line
			(start 0.120396 0.2794)
			(end -0.12065 0.2794)
			(stroke
				(width 0.1)
				(type default)
			)
			(layer "F.Fab")
		)
		(fp_line
			(start 0.120396 0.3048)
			(end 0.120396 0.2794)
			(stroke
				(width 0.1)
				(type default)
			)
			(layer "F.Fab")
		)
		(fp_line
			(start 0.12065 -0.3048)
			(end 0.67945 -0.3048)
			(stroke
				(width 0.1)
				(type default)
			)
			(layer "F.Fab")
		)
		(fp_line
			(start 0.12065 -0.2794)
			(end 0.12065 -0.3048)
			(stroke
				(width 0.1)
				(type default)
			)
			(layer "F.Fab")
		)
		(fp_line
			(start 0.67945 -0.3048)
			(end 0.67945 0.3048)
			(stroke
				(width 0.1)
				(type default)
			)
			(layer "F.Fab")
		)
		(fp_line
			(start 0.67945 0.3048)
			(end 0.120396 0.3048)
			(stroke
				(width 0.1)
				(type default)
			)
			(layer "F.Fab")
		)
		(pad "1" smd circle
			(at -0.40005 0)
			(size 0 0)
			(layers "F.Cu" "F.Mask" "F.Paste")
			(net "PCA9555_0_PEX0_A0")
		)
		(pad "2" smd circle
			(at 0.40005 0)
			(size 0 0)
			(layers "F.Cu" "F.Mask" "F.Paste")
			(net "P3V3_AUX")
		)
	)
	(footprint ""
		(layer "F.Cu")
		(at 224.993454 -117.265196 -90)
		(property "Reference" "PD18"
			(at 4.031996 -2.236216 90)
			(unlocked yes)
			(layer "F.SilkS")
			(effects
				(font
					(size 0.7874 0.5842)
					(thickness 0.1524)
				)
				(justify left)
			)
		)
		(property "Value" ""
			(at 0 0 270)
			(layer "F.Fab")
			(effects
				(font
					(size 1.27 1.27)
				)
			)
		)
		(duplicate_pad_numbers_are_jumpers no)
		(fp_line
			(start -3.400044 1.459992)
			(end -3.400044 -1.459992)
			(stroke
				(width 0.1524)
				(type default)
			)
			(layer "F.SilkS")
		)
		(fp_line
			(start 4.107942 1.459992)
			(end -3.400044 1.459992)
			(stroke
				(width 0.1524)
				(type default)
			)
			(layer "F.SilkS")
		)
		(fp_line
			(start -3.400044 -1.459992)
			(end 4.107942 -1.459992)
			(stroke
				(width 0.1524)
				(type default)
			)
			(layer "F.SilkS")
		)
		(fp_line
			(start 4.107942 -1.459992)
			(end 4.107942 1.459992)
			(stroke
				(width 0.1524)
				(type default)
			)
			(layer "F.SilkS")
		)
		(fp_poly
			(pts
				(xy 4.107942 -1.459992) (xy 4.107942 1.459992) (xy 3.308096 1.459992) (xy 3.308096 -1.459992)
			)
			(stroke
				(width 0)
				(type default)
			)
			(fill yes)
			(layer "F.SilkS")
		)
		(fp_line
			(start -2.29997 1.459992)
			(end -2.29997 -1.459992)
			(stroke
				(width 0.1)
				(type default)
			)
			(layer "F.Fab")
		)
		(fp_line
			(start 2.29997 1.459992)
			(end -2.29997 1.459992)
			(stroke
				(width 0.1)
				(type default)
			)
			(layer "F.Fab")
		)
		(fp_line
			(start -2.29997 -1.459992)
			(end 2.29997 -1.459992)
			(stroke
				(width 0.1)
				(type default)
			)
			(layer "F.Fab")
		)
		(fp_line
			(start 2.29997 -1.459992)
			(end 2.29997 1.459992)
			(stroke
				(width 0.1)
				(type default)
			)
			(layer "F.Fab")
		)
		(fp_text user "-"
			(at 5.4102 0.29845 90)
			(unlocked yes)
			(layer "F.SilkS")
			(effects
				(font
					(size 1.905 1.4224)
					(thickness 0.1524)
				)
				(justify left)
			)
		)
		(fp_text user "+"
			(at -4.7752 -0.12065 270)
			(unlocked yes)
			(layer "F.SilkS")
			(effects
				(font
					(size 1.905 1.4224)
					(thickness 0.1524)
				)
				(justify left)
			)
		)
		(fp_text user "-"
			(at 5.4102 0.29845 90)
			(unlocked yes)
			(layer "F.Fab")
			(effects
				(font
					(size 1.905 1.4224)
					(thickness 0.1524)
				)
				(justify left)
			)
		)
		(fp_text user "+"
			(at -4.7752 -0.12065 270)
			(unlocked yes)
			(layer "F.Fab")
			(effects
				(font
					(size 1.905 1.4224)
					(thickness 0.1524)
				)
				(justify left)
			)
		)
		(pad "A" smd rect
			(at -1.999996 0)
			(size 1.7018 2.5146)
			(layers "F.Cu" "F.Mask" "F.Paste")
			(net "GND")
		)
		(pad "C" smd rect
			(at 1.999996 0)
			(size 1.7018 2.5146)
			(layers "F.Cu" "F.Mask" "F.Paste")
			(net "P12V_NIC3_R")
		)
	)
	(footprint ""
		(layer "F.Cu")
		(at 50.396648 -356.244906 90)
		(property "Reference" "C2182"
			(at 0 0 90)
			(layer "F.SilkS")
			(hide yes)
			(effects
				(font
					(size 1.27 1.27)
				)
			)
		)
		(property "Value" ""
			(at 0 0 90)
			(layer "F.Fab")
			(effects
				(font
					(size 1.27 1.27)
				)
			)
		)
		(duplicate_pad_numbers_are_jumpers no)
		(fp_line
			(start 0.299974 -0.150114)
			(end 0.299974 0.150114)
			(stroke
				(width 0.1)
				(type default)
			)
			(layer "F.Fab")
		)
		(fp_line
			(start -0.299974 -0.150114)
			(end 0.299974 -0.150114)
			(stroke
				(width 0.1)
				(type default)
			)
			(layer "F.Fab")
		)
		(fp_line
			(start 0.299974 0.150114)
			(end -0.299974 0.150114)
			(stroke
				(width 0.1)
				(type default)
			)
			(layer "F.Fab")
		)
		(fp_line
			(start -0.299974 0.150114)
			(end -0.299974 -0.150114)
			(stroke
				(width 0.1)
				(type default)
			)
			(layer "F.Fab")
		)
		(pad "1" smd rect
			(at -0.2667 0 90)
			(size 0.3048 0.381)
			(layers "F.Cu" "F.Mask" "F.Paste")
			(net "P5E_PEX0_STN4_TX_DP<64>")
		)
		(pad "2" smd rect
			(at 0.2667 0 90)
			(size 0.3048 0.381)
			(layers "F.Cu" "F.Mask" "F.Paste")
			(net "P5E_PEX0_STN4_TX_C_DP<64>")
		)
	)
	(footprint ""
		(layer "F.Cu")
		(at 12.748768 -162.003994 90)
		(property "Reference" "PR6875"
			(at 0 0 90)
			(layer "F.SilkS")
			(hide yes)
			(effects
				(font
					(size 1.27 1.27)
				)
			)
		)
		(property "Value" ""
			(at 0 0 90)
			(layer "F.Fab")
			(effects
				(font
					(size 1.27 1.27)
				)
			)
		)
		(duplicate_pad_numbers_are_jumpers no)
		(fp_line
			(start 0.7874 -0.4064)
			(end 0.7874 0.4064)
			(stroke
				(width 0.1524)
				(type default)
			)
			(layer "F.SilkS")
		)
		(fp_line
			(start -0.7874 -0.4064)
			(end 0.7874 -0.4064)
			(stroke
				(width 0.1524)
				(type default)
			)
			(layer "F.SilkS")
		)
		(fp_line
			(start 0.7874 0.4064)
			(end -0.7874 0.4064)
			(stroke
				(width 0.1524)
				(type default)
			)
			(layer "F.SilkS")
		)
		(fp_line
			(start -0.7874 0.4064)
			(end -0.7874 -0.4064)
			(stroke
				(width 0.1524)
				(type default)
			)
			(layer "F.SilkS")
		)
		(fp_line
			(start -0.12065 -0.305054)
			(end -0.12065 -0.2794)
			(stroke
				(width 0.1)
				(type default)
			)
			(layer "F.Fab")
		)
		(fp_line
			(start -0.67945 -0.305054)
			(end -0.12065 -0.305054)
			(stroke
				(width 0.1)
				(type default)
			)
			(layer "F.Fab")
		)
		(fp_line
			(start 0.67945 -0.3048)
			(end 0.67945 0.3048)
			(stroke
				(width 0.1)
				(type default)
			)
			(layer "F.Fab")
		)
		(fp_line
			(start 0.12065 -0.3048)
			(end 0.67945 -0.3048)
			(stroke
				(width 0.1)
				(type default)
			)
			(layer "F.Fab")
		)
		(fp_line
			(start 0.12065 -0.2794)
			(end 0.12065 -0.3048)
			(stroke
				(width 0.1)
				(type default)
			)
			(layer "F.Fab")
		)
		(fp_line
			(start -0.12065 -0.2794)
			(end 0.12065 -0.2794)
			(stroke
				(width 0.1)
				(type default)
			)
			(layer "F.Fab")
		)
		(fp_line
			(start 0.120396 0.2794)
			(end -0.12065 0.2794)
			(stroke
				(width 0.1)
				(type default)
			)
			(layer "F.Fab")
		)
		(fp_line
			(start -0.12065 0.2794)
			(end -0.12065 0.3048)
			(stroke
				(width 0.1)
				(type default)
			)
			(layer "F.Fab")
		)
		(fp_line
			(start 0.67945 0.3048)
			(end 0.120396 0.3048)
			(stroke
				(width 0.1)
				(type default)
			)
			(layer "F.Fab")
		)
		(fp_line
			(start 0.120396 0.3048)
			(end 0.120396 0.2794)
			(stroke
				(width 0.1)
				(type default)
			)
			(layer "F.Fab")
		)
		(fp_line
			(start -0.12065 0.3048)
			(end -0.67945 0.3048)
			(stroke
				(width 0.1)
				(type default)
			)
			(layer "F.Fab")
		)
		(fp_line
			(start -0.67945 0.3048)
			(end -0.67945 -0.305054)
			(stroke
				(width 0.1)
				(type default)
			)
			(layer "F.Fab")
		)
		(pad "1" smd circle
			(at -0.40005 0 90)
			(size 0 0)
			(layers "F.Cu" "F.Mask" "F.Paste")
			(net "P12V_NIC0_CO_ISET")
		)
		(pad "2" smd circle
			(at 0.40005 0 90)
			(size 0 0)
			(layers "F.Cu" "F.Mask" "F.Paste")
			(net "GND")
		)
	)
	(footprint ""
		(layer "F.Cu")
		(at 366.092486 -31.825184 180)
		(property "Reference" "C701"
			(at 0 0 180)
			(layer "F.SilkS")
			(hide yes)
			(effects
				(font
					(size 1.27 1.27)
				)
			)
		)
		(property "Value" ""
			(at 0 0 180)
			(layer "F.Fab")
			(effects
				(font
					(size 1.27 1.27)
				)
			)
		)
		(duplicate_pad_numbers_are_jumpers no)
		(fp_line
			(start 0.299974 0.150114)
			(end -0.299974 0.150114)
			(stroke
				(width 0.1)
				(type default)
			)
			(layer "F.Fab")
		)
		(fp_line
			(start 0.299974 -0.150114)
			(end 0.299974 0.150114)
			(stroke
				(width 0.1)
				(type default)
			)
			(layer "F.Fab")
		)
		(fp_line
			(start -0.299974 0.150114)
			(end -0.299974 -0.150114)
			(stroke
				(width 0.1)
				(type default)
			)
			(layer "F.Fab")
		)
		(fp_line
			(start -0.299974 -0.150114)
			(end 0.299974 -0.150114)
			(stroke
				(width 0.1)
				(type default)
			)
			(layer "F.Fab")
		)
		(pad "1" smd rect
			(at -0.2667 0 180)
			(size 0.3048 0.381)
			(layers "F.Cu" "F.Mask" "F.Paste")
			(net "P5E_PEX3_STN2_TX_DN<46>")
		)
		(pad "2" smd rect
			(at 0.2667 0 180)
			(size 0.3048 0.381)
			(layers "F.Cu" "F.Mask" "F.Paste")
			(net "P5E_PEX3_STN2_TX_C_DN<46>")
		)
	)
	(footprint ""
		(layer "F.Cu")
		(at 137.630662 -66.32194 -90)
		(property "Reference" "PC846"
			(at 0 0 270)
			(layer "F.SilkS")
			(hide yes)
			(effects
				(font
					(size 1.27 1.27)
				)
			)
		)
		(property "Value" ""
			(at 0 0 270)
			(layer "F.Fab")
			(effects
				(font
					(size 1.27 1.27)
				)
			)
		)
		(duplicate_pad_numbers_are_jumpers no)
		(fp_line
			(start -0.7874 0.4064)
			(end -0.7874 -0.4064)
			(stroke
				(width 0.1524)
				(type default)
			)
			(layer "F.SilkS")
		)
		(fp_line
			(start 0.7874 0.4064)
			(end -0.7874 0.4064)
			(stroke
				(width 0.1524)
				(type default)
			)
			(layer "F.SilkS")
		)
		(fp_line
			(start -0.7874 -0.4064)
			(end 0.7874 -0.4064)
			(stroke
				(width 0.1524)
				(type default)
			)
			(layer "F.SilkS")
		)
		(fp_line
			(start 0.7874 -0.4064)
			(end 0.7874 0.4064)
			(stroke
				(width 0.1524)
				(type default)
			)
			(layer "F.SilkS")
		)
		(fp_line
			(start -0.67945 0.3048)
			(end -0.67945 -0.305054)
			(stroke
				(width 0.1)
				(type default)
			)
			(layer "F.Fab")
		)
		(fp_line
			(start -0.12065 0.3048)
			(end -0.67945 0.3048)
			(stroke
				(width 0.1)
				(type default)
			)
			(layer "F.Fab")
		)
		(fp_line
			(start 0.120396 0.3048)
			(end 0.120396 0.2794)
			(stroke
				(width 0.1)
				(type default)
			)
			(layer "F.Fab")
		)
		(fp_line
			(start 0.67945 0.3048)
			(end 0.120396 0.3048)
			(stroke
				(width 0.1)
				(type default)
			)
			(layer "F.Fab")
		)
		(fp_line
			(start -0.12065 0.2794)
			(end -0.12065 0.3048)
			(stroke
				(width 0.1)
				(type default)
			)
			(layer "F.Fab")
		)
		(fp_line
			(start 0.120396 0.2794)
			(end -0.12065 0.2794)
			(stroke
				(width 0.1)
				(type default)
			)
			(layer "F.Fab")
		)
		(fp_line
			(start -0.12065 -0.2794)
			(end 0.12065 -0.2794)
			(stroke
				(width 0.1)
				(type default)
			)
			(layer "F.Fab")
		)
		(fp_line
			(start 0.12065 -0.2794)
			(end 0.12065 -0.3048)
			(stroke
				(width 0.1)
				(type default)
			)
			(layer "F.Fab")
		)
		(fp_line
			(start 0.12065 -0.3048)
			(end 0.67945 -0.3048)
			(stroke
				(width 0.1)
				(type default)
			)
			(layer "F.Fab")
		)
		(fp_line
			(start 0.67945 -0.3048)
			(end 0.67945 0.3048)
			(stroke
				(width 0.1)
				(type default)
			)
			(layer "F.Fab")
		)
		(fp_line
			(start -0.67945 -0.305054)
			(end -0.12065 -0.305054)
			(stroke
				(width 0.1)
				(type default)
			)
			(layer "F.Fab")
		)
		(fp_line
			(start -0.12065 -0.305054)
			(end -0.12065 -0.2794)
			(stroke
				(width 0.1)
				(type default)
			)
			(layer "F.Fab")
		)
		(pad "1" smd circle
			(at -0.40005 0 270)
			(size 0 0)
			(layers "F.Cu" "F.Mask" "F.Paste")
			(net "P12V_SSD4_CO_DV_DT")
		)
		(pad "2" smd circle
			(at 0.40005 0 270)
			(size 0 0)
			(layers "F.Cu" "F.Mask" "F.Paste")
			(net "GND")
		)
	)
	(footprint ""
		(layer "F.Cu")
		(at 207.133698 -304.036476 90)
		(property "Reference" "R1317"
			(at 0 0 90)
			(layer "F.SilkS")
			(hide yes)
			(effects
				(font
					(size 1.27 1.27)
				)
			)
		)
		(property "Value" ""
			(at 0 0 90)
			(layer "F.Fab")
			(effects
				(font
					(size 1.27 1.27)
				)
			)
		)
		(duplicate_pad_numbers_are_jumpers no)
		(fp_line
			(start 0.7874 -0.4064)
			(end 0.7874 0.4064)
			(stroke
				(width 0.1524)
				(type default)
			)
			(layer "F.SilkS")
		)
		(fp_line
			(start -0.7874 -0.4064)
			(end 0.7874 -0.4064)
			(stroke
				(width 0.1524)
				(type default)
			)
			(layer "F.SilkS")
		)
		(fp_line
			(start 0.7874 0.4064)
			(end -0.7874 0.4064)
			(stroke
				(width 0.1524)
				(type default)
			)
			(layer "F.SilkS")
		)
		(fp_line
			(start -0.7874 0.4064)
			(end -0.7874 -0.4064)
			(stroke
				(width 0.1524)
				(type default)
			)
			(layer "F.SilkS")
		)
		(fp_line
			(start -0.12065 -0.305054)
			(end -0.12065 -0.2794)
			(stroke
				(width 0.1)
				(type default)
			)
			(layer "F.Fab")
		)
		(fp_line
			(start -0.67945 -0.305054)
			(end -0.12065 -0.305054)
			(stroke
				(width 0.1)
				(type default)
			)
			(layer "F.Fab")
		)
		(fp_line
			(start 0.67945 -0.3048)
			(end 0.67945 0.3048)
			(stroke
				(width 0.1)
				(type default)
			)
			(layer "F.Fab")
		)
		(fp_line
			(start 0.12065 -0.3048)
			(end 0.67945 -0.3048)
			(stroke
				(width 0.1)
				(type default)
			)
			(layer "F.Fab")
		)
		(fp_line
			(start 0.12065 -0.2794)
			(end 0.12065 -0.3048)
			(stroke
				(width 0.1)
				(type default)
			)
			(layer "F.Fab")
		)
		(fp_line
			(start -0.12065 -0.2794)
			(end 0.12065 -0.2794)
			(stroke
				(width 0.1)
				(type default)
			)
			(layer "F.Fab")
		)
		(fp_line
			(start 0.120396 0.2794)
			(end -0.12065 0.2794)
			(stroke
				(width 0.1)
				(type default)
			)
			(layer "F.Fab")
		)
		(fp_line
			(start -0.12065 0.2794)
			(end -0.12065 0.3048)
			(stroke
				(width 0.1)
				(type default)
			)
			(layer "F.Fab")
		)
		(fp_line
			(start 0.67945 0.3048)
			(end 0.120396 0.3048)
			(stroke
				(width 0.1)
				(type default)
			)
			(layer "F.Fab")
		)
		(fp_line
			(start 0.120396 0.3048)
			(end 0.120396 0.2794)
			(stroke
				(width 0.1)
				(type default)
			)
			(layer "F.Fab")
		)
		(fp_line
			(start -0.12065 0.3048)
			(end -0.67945 0.3048)
			(stroke
				(width 0.1)
				(type default)
			)
			(layer "F.Fab")
		)
		(fp_line
			(start -0.67945 0.3048)
			(end -0.67945 -0.305054)
			(stroke
				(width 0.1)
				(type default)
			)
			(layer "F.Fab")
		)
		(pad "1" smd circle
			(at -0.40005 0 90)
			(size 0 0)
			(layers "F.Cu" "F.Mask" "F.Paste")
			(net "GND")
		)
		(pad "2" smd circle
			(at 0.40005 0 90)
			(size 0 0)
			(layers "F.Cu" "F.Mask" "F.Paste")
			(net "PEX1_SPARE1")
		)
	)
	(footprint ""
		(layer "F.Cu")
		(at 192.483486 -49.94148)
		(property "Reference" "R577"
			(at 0 0 0)
			(layer "F.SilkS")
			(hide yes)
			(effects
				(font
					(size 1.27 1.27)
				)
			)
		)
		(property "Value" ""
			(at 0 0 0)
			(layer "F.Fab")
			(effects
				(font
					(size 1.27 1.27)
				)
			)
		)
		(duplicate_pad_numbers_are_jumpers no)
		(fp_line
			(start -0.7874 -0.4064)
			(end 0.7874 -0.4064)
			(stroke
				(width 0.1524)
				(type default)
			)
			(layer "F.SilkS")
		)
		(fp_line
			(start -0.7874 0.4064)
			(end -0.7874 -0.4064)
			(stroke
				(width 0.1524)
				(type default)
			)
			(layer "F.SilkS")
		)
		(fp_line
			(start 0.7874 -0.4064)
			(end 0.7874 0.4064)
			(stroke
				(width 0.1524)
				(type default)
			)
			(layer "F.SilkS")
		)
		(fp_line
			(start 0.7874 0.4064)
			(end -0.7874 0.4064)
			(stroke
				(width 0.1524)
				(type default)
			)
			(layer "F.SilkS")
		)
		(fp_line
			(start -0.67945 -0.305054)
			(end -0.12065 -0.305054)
			(stroke
				(width 0.1)
				(type default)
			)
			(layer "F.Fab")
		)
		(fp_line
			(start -0.67945 0.3048)
			(end -0.67945 -0.305054)
			(stroke
				(width 0.1)
				(type default)
			)
			(layer "F.Fab")
		)
		(fp_line
			(start -0.12065 -0.305054)
			(end -0.12065 -0.2794)
			(stroke
				(width 0.1)
				(type default)
			)
			(layer "F.Fab")
		)
		(fp_line
			(start -0.12065 -0.2794)
			(end 0.12065 -0.2794)
			(stroke
				(width 0.1)
				(type default)
			)
			(layer "F.Fab")
		)
		(fp_line
			(start -0.12065 0.2794)
			(end -0.12065 0.3048)
			(stroke
				(width 0.1)
				(type default)
			)
			(layer "F.Fab")
		)
		(fp_line
			(start -0.12065 0.3048)
			(end -0.67945 0.3048)
			(stroke
				(width 0.1)
				(type default)
			)
			(layer "F.Fab")
		)
		(fp_line
			(start 0.120396 0.2794)
			(end -0.12065 0.2794)
			(stroke
				(width 0.1)
				(type default)
			)
			(layer "F.Fab")
		)
		(fp_line
			(start 0.120396 0.3048)
			(end 0.120396 0.2794)
			(stroke
				(width 0.1)
				(type default)
			)
			(layer "F.Fab")
		)
		(fp_line
			(start 0.12065 -0.3048)
			(end 0.67945 -0.3048)
			(stroke
				(width 0.1)
				(type default)
			)
			(layer "F.Fab")
		)
		(fp_line
			(start 0.12065 -0.2794)
			(end 0.12065 -0.3048)
			(stroke
				(width 0.1)
				(type default)
			)
			(layer "F.Fab")
		)
		(fp_line
			(start 0.67945 -0.3048)
			(end 0.67945 0.3048)
			(stroke
				(width 0.1)
				(type default)
			)
			(layer "F.Fab")
		)
		(fp_line
			(start 0.67945 0.3048)
			(end 0.120396 0.3048)
			(stroke
				(width 0.1)
				(type default)
			)
			(layer "F.Fab")
		)
		(pad "1" smd circle
			(at -0.40005 0)
			(size 0 0)
			(layers "F.Cu" "F.Mask" "F.Paste")
			(net "SMB_BIC_I2C6_MUX_SSD_0_7_ADC_R_SCL")
		)
		(pad "2" smd circle
			(at 0.40005 0)
			(size 0 0)
			(layers "F.Cu" "F.Mask" "F.Paste")
			(net "SMB_SSD6_ADC_SCL")
		)
	)
	(footprint ""
		(layer "F.Cu")
		(at 443.551818 -230.203756 90)
		(property "Reference" "C4442"
			(at 0 0 90)
			(layer "F.SilkS")
			(hide yes)
			(effects
				(font
					(size 1.27 1.27)
				)
			)
		)
		(property "Value" ""
			(at 0 0 90)
			(layer "F.Fab")
			(effects
				(font
					(size 1.27 1.27)
				)
			)
		)
		(duplicate_pad_numbers_are_jumpers no)
		(fp_line
			(start 1.2954 -0.5842)
			(end 1.2954 0.5842)
			(stroke
				(width 0.1524)
				(type default)
			)
			(layer "F.SilkS")
		)
		(fp_line
			(start -1.2954 -0.5842)
			(end 1.2954 -0.5842)
			(stroke
				(width 0.1524)
				(type default)
			)
			(layer "F.SilkS")
		)
		(fp_line
			(start 1.2954 0.5842)
			(end -1.2954 0.5842)
			(stroke
				(width 0.1524)
				(type default)
			)
			(layer "F.SilkS")
		)
		(fp_line
			(start -1.2954 0.5842)
			(end -1.2954 -0.5842)
			(stroke
				(width 0.1524)
				(type default)
			)
			(layer "F.SilkS")
		)
		(fp_line
			(start 0.8636 -0.4572)
			(end 0.8636 -0.4064)
			(stroke
				(width 0.1)
				(type default)
			)
			(layer "F.Fab")
		)
		(fp_line
			(start -0.8636 -0.4572)
			(end 0.8636 -0.4572)
			(stroke
				(width 0.1)
				(type default)
			)
			(layer "F.Fab")
		)
		(fp_line
			(start 1.1938 -0.4064)
			(end 1.1938 0.4064)
			(stroke
				(width 0.1)
				(type default)
			)
			(layer "F.Fab")
		)
		(fp_line
			(start 0.8636 -0.4064)
			(end 1.1938 -0.4064)
			(stroke
				(width 0.1)
				(type default)
			)
			(layer "F.Fab")
		)
		(fp_line
			(start -0.8636 -0.4064)
			(end -0.8636 -0.4572)
			(stroke
				(width 0.1)
				(type default)
			)
			(layer "F.Fab")
		)
		(fp_line
			(start -1.1938 -0.4064)
			(end -0.8636 -0.4064)
			(stroke
				(width 0.1)
				(type default)
			)
			(layer "F.Fab")
		)
		(fp_line
			(start 1.1938 0.4064)
			(end 0.8636 0.4064)
			(stroke
				(width 0.1)
				(type default)
			)
			(layer "F.Fab")
		)
		(fp_line
			(start 0.8636 0.4064)
			(end 0.8636 0.4572)
			(stroke
				(width 0.1)
				(type default)
			)
			(layer "F.Fab")
		)
		(fp_line
			(start -0.8636 0.4064)
			(end -1.1938 0.4064)
			(stroke
				(width 0.1)
				(type default)
			)
			(layer "F.Fab")
		)
		(fp_line
			(start -1.1938 0.4064)
			(end -1.1938 -0.4064)
			(stroke
				(width 0.1)
				(type default)
			)
			(layer "F.Fab")
		)
		(fp_line
			(start 0.8636 0.4572)
			(end -0.8636 0.4572)
			(stroke
				(width 0.1)
				(type default)
			)
			(layer "F.Fab")
		)
		(fp_line
			(start -0.8636 0.4572)
			(end -0.8636 0.4064)
			(stroke
				(width 0.1)
				(type default)
			)
			(layer "F.Fab")
		)
		(pad "1" smd rect
			(at -0.7366 0)
			(size 0.7112 0.8128)
			(layers "F.Cu" "F.Mask" "F.Paste")
			(net "P3V3_AUX")
		)
		(pad "2" smd rect
			(at 0.7366 0)
			(size 0.7112 0.8128)
			(layers "F.Cu" "F.Mask" "F.Paste")
			(net "GND")
		)
	)
	(footprint ""
		(layer "F.Cu")
		(at 441.303918 -291.722048 90)
		(property "Reference" "C2760"
			(at 0 0 90)
			(layer "F.SilkS")
			(hide yes)
			(effects
				(font
					(size 1.27 1.27)
				)
			)
		)
		(property "Value" ""
			(at 0 0 90)
			(layer "F.Fab")
			(effects
				(font
					(size 1.27 1.27)
				)
			)
		)
		(duplicate_pad_numbers_are_jumpers no)
		(fp_line
			(start 0.7874 -0.4064)
			(end 0.7874 0.4064)
			(stroke
				(width 0.1524)
				(type default)
			)
			(layer "F.SilkS")
		)
		(fp_line
			(start -0.7874 -0.4064)
			(end 0.7874 -0.4064)
			(stroke
				(width 0.1524)
				(type default)
			)
			(layer "F.SilkS")
		)
		(fp_line
			(start 0.7874 0.4064)
			(end -0.7874 0.4064)
			(stroke
				(width 0.1524)
				(type default)
			)
			(layer "F.SilkS")
		)
		(fp_line
			(start -0.7874 0.4064)
			(end -0.7874 -0.4064)
			(stroke
				(width 0.1524)
				(type default)
			)
			(layer "F.SilkS")
		)
		(fp_line
			(start -0.12065 -0.305054)
			(end -0.12065 -0.2794)
			(stroke
				(width 0.1)
				(type default)
			)
			(layer "F.Fab")
		)
		(fp_line
			(start -0.67945 -0.305054)
			(end -0.12065 -0.305054)
			(stroke
				(width 0.1)
				(type default)
			)
			(layer "F.Fab")
		)
		(fp_line
			(start 0.67945 -0.3048)
			(end 0.67945 0.3048)
			(stroke
				(width 0.1)
				(type default)
			)
			(layer "F.Fab")
		)
		(fp_line
			(start 0.12065 -0.3048)
			(end 0.67945 -0.3048)
			(stroke
				(width 0.1)
				(type default)
			)
			(layer "F.Fab")
		)
		(fp_line
			(start 0.12065 -0.2794)
			(end 0.12065 -0.3048)
			(stroke
				(width 0.1)
				(type default)
			)
			(layer "F.Fab")
		)
		(fp_line
			(start -0.12065 -0.2794)
			(end 0.12065 -0.2794)
			(stroke
				(width 0.1)
				(type default)
			)
			(layer "F.Fab")
		)
		(fp_line
			(start 0.120396 0.2794)
			(end -0.12065 0.2794)
			(stroke
				(width 0.1)
				(type default)
			)
			(layer "F.Fab")
		)
		(fp_line
			(start -0.12065 0.2794)
			(end -0.12065 0.3048)
			(stroke
				(width 0.1)
				(type default)
			)
			(layer "F.Fab")
		)
		(fp_line
			(start 0.67945 0.3048)
			(end 0.120396 0.3048)
			(stroke
				(width 0.1)
				(type default)
			)
			(layer "F.Fab")
		)
		(fp_line
			(start 0.120396 0.3048)
			(end 0.120396 0.2794)
			(stroke
				(width 0.1)
				(type default)
			)
			(layer "F.Fab")
		)
		(fp_line
			(start -0.12065 0.3048)
			(end -0.67945 0.3048)
			(stroke
				(width 0.1)
				(type default)
			)
			(layer "F.Fab")
		)
		(fp_line
			(start -0.67945 0.3048)
			(end -0.67945 -0.305054)
			(stroke
				(width 0.1)
				(type default)
			)
			(layer "F.Fab")
		)
		(pad "1" smd circle
			(at -0.40005 0 90)
			(size 0 0)
			(layers "F.Cu" "F.Mask" "F.Paste")
			(net "GND")
		)
		(pad "2" smd circle
			(at 0.40005 0 90)
			(size 0 0)
			(layers "F.Cu" "F.Mask" "F.Paste")
			(net "P3V3_AUX")
		)
	)
	(footprint ""
		(layer "F.Cu")
		(at 383.495042 -59.577986 90)
		(property "Reference" "PC567"
			(at 0 0 90)
			(layer "F.SilkS")
			(hide yes)
			(effects
				(font
					(size 1.27 1.27)
				)
			)
		)
		(property "Value" ""
			(at 0 0 90)
			(layer "F.Fab")
			(effects
				(font
					(size 1.27 1.27)
				)
			)
		)
		(duplicate_pad_numbers_are_jumpers no)
		(fp_line
			(start 0.7874 -0.4064)
			(end 0.7874 0.4064)
			(stroke
				(width 0.1524)
				(type default)
			)
			(layer "F.SilkS")
		)
		(fp_line
			(start -0.7874 -0.4064)
			(end 0.7874 -0.4064)
			(stroke
				(width 0.1524)
				(type default)
			)
			(layer "F.SilkS")
		)
		(fp_line
			(start 0.7874 0.4064)
			(end -0.7874 0.4064)
			(stroke
				(width 0.1524)
				(type default)
			)
			(layer "F.SilkS")
		)
		(fp_line
			(start -0.7874 0.4064)
			(end -0.7874 -0.4064)
			(stroke
				(width 0.1524)
				(type default)
			)
			(layer "F.SilkS")
		)
		(fp_line
			(start -0.12065 -0.305054)
			(end -0.12065 -0.2794)
			(stroke
				(width 0.1)
				(type default)
			)
			(layer "F.Fab")
		)
		(fp_line
			(start -0.67945 -0.305054)
			(end -0.12065 -0.305054)
			(stroke
				(width 0.1)
				(type default)
			)
			(layer "F.Fab")
		)
		(fp_line
			(start 0.67945 -0.3048)
			(end 0.67945 0.3048)
			(stroke
				(width 0.1)
				(type default)
			)
			(layer "F.Fab")
		)
		(fp_line
			(start 0.12065 -0.3048)
			(end 0.67945 -0.3048)
			(stroke
				(width 0.1)
				(type default)
			)
			(layer "F.Fab")
		)
		(fp_line
			(start 0.12065 -0.2794)
			(end 0.12065 -0.3048)
			(stroke
				(width 0.1)
				(type default)
			)
			(layer "F.Fab")
		)
		(fp_line
			(start -0.12065 -0.2794)
			(end 0.12065 -0.2794)
			(stroke
				(width 0.1)
				(type default)
			)
			(layer "F.Fab")
		)
		(fp_line
			(start 0.120396 0.2794)
			(end -0.12065 0.2794)
			(stroke
				(width 0.1)
				(type default)
			)
			(layer "F.Fab")
		)
		(fp_line
			(start -0.12065 0.2794)
			(end -0.12065 0.3048)
			(stroke
				(width 0.1)
				(type default)
			)
			(layer "F.Fab")
		)
		(fp_line
			(start 0.67945 0.3048)
			(end 0.120396 0.3048)
			(stroke
				(width 0.1)
				(type default)
			)
			(layer "F.Fab")
		)
		(fp_line
			(start 0.120396 0.3048)
			(end 0.120396 0.2794)
			(stroke
				(width 0.1)
				(type default)
			)
			(layer "F.Fab")
		)
		(fp_line
			(start -0.12065 0.3048)
			(end -0.67945 0.3048)
			(stroke
				(width 0.1)
				(type default)
			)
			(layer "F.Fab")
		)
		(fp_line
			(start -0.67945 0.3048)
			(end -0.67945 -0.305054)
			(stroke
				(width 0.1)
				(type default)
			)
			(layer "F.Fab")
		)
		(pad "1" smd circle
			(at -0.40005 0 90)
			(size 0 0)
			(layers "F.Cu" "F.Mask" "F.Paste")
			(net "P3V3_SSD13_SS")
		)
		(pad "2" smd circle
			(at 0.40005 0 90)
			(size 0 0)
			(layers "F.Cu" "F.Mask" "F.Paste")
			(net "GND")
		)
	)
	(footprint ""
		(layer "F.Cu")
		(at 313.056016 -32.848042 -90)
		(property "Reference" "R6091"
			(at 0 0 270)
			(layer "F.SilkS")
			(hide yes)
			(effects
				(font
					(size 1.27 1.27)
				)
			)
		)
		(property "Value" ""
			(at 0 0 270)
			(layer "F.Fab")
			(effects
				(font
					(size 1.27 1.27)
				)
			)
		)
		(duplicate_pad_numbers_are_jumpers no)
		(fp_line
			(start -0.7874 0.4064)
			(end -0.7874 -0.4064)
			(stroke
				(width 0.1524)
				(type default)
			)
			(layer "F.SilkS")
		)
		(fp_line
			(start 0.7874 0.4064)
			(end -0.7874 0.4064)
			(stroke
				(width 0.1524)
				(type default)
			)
			(layer "F.SilkS")
		)
		(fp_line
			(start -0.7874 -0.4064)
			(end 0.7874 -0.4064)
			(stroke
				(width 0.1524)
				(type default)
			)
			(layer "F.SilkS")
		)
		(fp_line
			(start 0.7874 -0.4064)
			(end 0.7874 0.4064)
			(stroke
				(width 0.1524)
				(type default)
			)
			(layer "F.SilkS")
		)
		(fp_line
			(start -0.67945 0.3048)
			(end -0.67945 -0.305054)
			(stroke
				(width 0.1)
				(type default)
			)
			(layer "F.Fab")
		)
		(fp_line
			(start -0.12065 0.3048)
			(end -0.67945 0.3048)
			(stroke
				(width 0.1)
				(type default)
			)
			(layer "F.Fab")
		)
		(fp_line
			(start 0.120396 0.3048)
			(end 0.120396 0.2794)
			(stroke
				(width 0.1)
				(type default)
			)
			(layer "F.Fab")
		)
		(fp_line
			(start 0.67945 0.3048)
			(end 0.120396 0.3048)
			(stroke
				(width 0.1)
				(type default)
			)
			(layer "F.Fab")
		)
		(fp_line
			(start -0.12065 0.2794)
			(end -0.12065 0.3048)
			(stroke
				(width 0.1)
				(type default)
			)
			(layer "F.Fab")
		)
		(fp_line
			(start 0.120396 0.2794)
			(end -0.12065 0.2794)
			(stroke
				(width 0.1)
				(type default)
			)
			(layer "F.Fab")
		)
		(fp_line
			(start -0.12065 -0.2794)
			(end 0.12065 -0.2794)
			(stroke
				(width 0.1)
				(type default)
			)
			(layer "F.Fab")
		)
		(fp_line
			(start 0.12065 -0.2794)
			(end 0.12065 -0.3048)
			(stroke
				(width 0.1)
				(type default)
			)
			(layer "F.Fab")
		)
		(fp_line
			(start 0.12065 -0.3048)
			(end 0.67945 -0.3048)
			(stroke
				(width 0.1)
				(type default)
			)
			(layer "F.Fab")
		)
		(fp_line
			(start 0.67945 -0.3048)
			(end 0.67945 0.3048)
			(stroke
				(width 0.1)
				(type default)
			)
			(layer "F.Fab")
		)
		(fp_line
			(start -0.67945 -0.305054)
			(end -0.12065 -0.305054)
			(stroke
				(width 0.1)
				(type default)
			)
			(layer "F.Fab")
		)
		(fp_line
			(start -0.12065 -0.305054)
			(end -0.12065 -0.2794)
			(stroke
				(width 0.1)
				(type default)
			)
			(layer "F.Fab")
		)
		(pad "1" smd circle
			(at -0.40005 0 270)
			(size 0 0)
			(layers "F.Cu" "F.Mask" "F.Paste")
			(net "SSD11_AUX_P3V3_EN_R")
		)
		(pad "2" smd circle
			(at 0.40005 0 270)
			(size 0 0)
			(layers "F.Cu" "F.Mask" "F.Paste")
			(net "P3V3_SSD11_CO_EN")
		)
	)
	(footprint ""
		(layer "F.Cu")
		(at 196.554852 -22.961346 90)
		(property "Reference" "R1673"
			(at 0 0 90)
			(layer "F.SilkS")
			(hide yes)
			(effects
				(font
					(size 1.27 1.27)
				)
			)
		)
		(property "Value" ""
			(at 0 0 90)
			(layer "F.Fab")
			(effects
				(font
					(size 1.27 1.27)
				)
			)
		)
		(duplicate_pad_numbers_are_jumpers no)
		(fp_line
			(start 0.7874 -0.4064)
			(end 0.7874 0.4064)
			(stroke
				(width 0.1524)
				(type default)
			)
			(layer "F.SilkS")
		)
		(fp_line
			(start -0.7874 -0.4064)
			(end 0.7874 -0.4064)
			(stroke
				(width 0.1524)
				(type default)
			)
			(layer "F.SilkS")
		)
		(fp_line
			(start 0.7874 0.4064)
			(end -0.7874 0.4064)
			(stroke
				(width 0.1524)
				(type default)
			)
			(layer "F.SilkS")
		)
		(fp_line
			(start -0.7874 0.4064)
			(end -0.7874 -0.4064)
			(stroke
				(width 0.1524)
				(type default)
			)
			(layer "F.SilkS")
		)
		(fp_line
			(start -0.12065 -0.305054)
			(end -0.12065 -0.2794)
			(stroke
				(width 0.1)
				(type default)
			)
			(layer "F.Fab")
		)
		(fp_line
			(start -0.67945 -0.305054)
			(end -0.12065 -0.305054)
			(stroke
				(width 0.1)
				(type default)
			)
			(layer "F.Fab")
		)
		(fp_line
			(start 0.67945 -0.3048)
			(end 0.67945 0.3048)
			(stroke
				(width 0.1)
				(type default)
			)
			(layer "F.Fab")
		)
		(fp_line
			(start 0.12065 -0.3048)
			(end 0.67945 -0.3048)
			(stroke
				(width 0.1)
				(type default)
			)
			(layer "F.Fab")
		)
		(fp_line
			(start 0.12065 -0.2794)
			(end 0.12065 -0.3048)
			(stroke
				(width 0.1)
				(type default)
			)
			(layer "F.Fab")
		)
		(fp_line
			(start -0.12065 -0.2794)
			(end 0.12065 -0.2794)
			(stroke
				(width 0.1)
				(type default)
			)
			(layer "F.Fab")
		)
		(fp_line
			(start 0.120396 0.2794)
			(end -0.12065 0.2794)
			(stroke
				(width 0.1)
				(type default)
			)
			(layer "F.Fab")
		)
		(fp_line
			(start -0.12065 0.2794)
			(end -0.12065 0.3048)
			(stroke
				(width 0.1)
				(type default)
			)
			(layer "F.Fab")
		)
		(fp_line
			(start 0.67945 0.3048)
			(end 0.120396 0.3048)
			(stroke
				(width 0.1)
				(type default)
			)
			(layer "F.Fab")
		)
		(fp_line
			(start 0.120396 0.3048)
			(end 0.120396 0.2794)
			(stroke
				(width 0.1)
				(type default)
			)
			(layer "F.Fab")
		)
		(fp_line
			(start -0.12065 0.3048)
			(end -0.67945 0.3048)
			(stroke
				(width 0.1)
				(type default)
			)
			(layer "F.Fab")
		)
		(fp_line
			(start -0.67945 0.3048)
			(end -0.67945 -0.305054)
			(stroke
				(width 0.1)
				(type default)
			)
			(layer "F.Fab")
		)
		(pad "1" smd circle
			(at -0.40005 0 90)
			(size 0 0)
			(layers "F.Cu" "F.Mask" "F.Paste")
			(net "SMB_SSD6_ISO_EN")
		)
		(pad "2" smd circle
			(at 0.40005 0 90)
			(size 0 0)
			(layers "F.Cu" "F.Mask" "F.Paste")
			(net "P3V3_AUX")
		)
	)
	(footprint ""
		(layer "F.Cu")
		(at 378.453396 -294.591232)
		(property "Reference" "L138"
			(at 0 0 0)
			(layer "F.SilkS")
			(hide yes)
			(effects
				(font
					(size 1.27 1.27)
				)
			)
		)
		(property "Value" ""
			(at 0 0 0)
			(layer "F.Fab")
			(effects
				(font
					(size 1.27 1.27)
				)
			)
		)
		(duplicate_pad_numbers_are_jumpers no)
		(fp_line
			(start -1.63576 -0.8128)
			(end -1.63576 0.8128)
			(stroke
				(width 0.1524)
				(type default)
			)
			(layer "F.SilkS")
		)
		(fp_line
			(start -1.63576 -0.8128)
			(end 1.63576 -0.8128)
			(stroke
				(width 0.1524)
				(type default)
			)
			(layer "F.SilkS")
		)
		(fp_line
			(start 1.63576 -0.8128)
			(end 1.63576 0.8128)
			(stroke
				(width 0.1524)
				(type default)
			)
			(layer "F.SilkS")
		)
		(fp_line
			(start 1.63576 0.8128)
			(end -1.63576 0.8128)
			(stroke
				(width 0.1524)
				(type default)
			)
			(layer "F.SilkS")
		)
		(fp_line
			(start -1.56083 -0.738632)
			(end -1.56083 0.7366)
			(stroke
				(width 0.1)
				(type default)
			)
			(layer "F.Fab")
		)
		(fp_line
			(start -1.56083 0.7366)
			(end -1.524 0.7366)
			(stroke
				(width 0.1)
				(type default)
			)
			(layer "F.Fab")
		)
		(fp_line
			(start -1.524 0.7366)
			(end 1.524 0.7366)
			(stroke
				(width 0.1)
				(type default)
			)
			(layer "F.Fab")
		)
		(fp_line
			(start 1.524 0.7366)
			(end 1.560576 0.7366)
			(stroke
				(width 0.1)
				(type default)
			)
			(layer "F.Fab")
		)
		(fp_line
			(start 1.560576 -0.738632)
			(end -1.56083 -0.738632)
			(stroke
				(width 0.1)
				(type default)
			)
			(layer "F.Fab")
		)
		(fp_line
			(start 1.560576 0.7366)
			(end 1.560576 -0.738632)
			(stroke
				(width 0.1)
				(type default)
			)
			(layer "F.Fab")
		)
		(pad "1" smd rect
			(at -0.94996 0 180)
			(size 1.1176 1.3716)
			(layers "F.Cu" "F.Mask" "F.Paste")
			(net "P1V8_PLL0_PEX3")
		)
		(pad "2" smd rect
			(at 0.94996 0 180)
			(size 1.1176 1.3716)
			(layers "F.Cu" "F.Mask" "F.Paste")
			(net "PCEPLL2_VDDA18_PEX3")
		)
	)
	(footprint ""
		(layer "F.Cu")
		(at 22.416008 -356.244906 90)
		(property "Reference" "C187"
			(at 0 0 90)
			(layer "F.SilkS")
			(hide yes)
			(effects
				(font
					(size 1.27 1.27)
				)
			)
		)
		(property "Value" ""
			(at 0 0 90)
			(layer "F.Fab")
			(effects
				(font
					(size 1.27 1.27)
				)
			)
		)
		(duplicate_pad_numbers_are_jumpers no)
		(fp_line
			(start 0.299974 -0.150114)
			(end 0.299974 0.150114)
			(stroke
				(width 0.1)
				(type default)
			)
			(layer "F.Fab")
		)
		(fp_line
			(start -0.299974 -0.150114)
			(end 0.299974 -0.150114)
			(stroke
				(width 0.1)
				(type default)
			)
			(layer "F.Fab")
		)
		(fp_line
			(start 0.299974 0.150114)
			(end -0.299974 0.150114)
			(stroke
				(width 0.1)
				(type default)
			)
			(layer "F.Fab")
		)
		(fp_line
			(start -0.299974 0.150114)
			(end -0.299974 -0.150114)
			(stroke
				(width 0.1)
				(type default)
			)
			(layer "F.Fab")
		)
		(pad "1" smd rect
			(at -0.2667 0 90)
			(size 0.3048 0.381)
			(layers "F.Cu" "F.Mask" "F.Paste")
			(net "P5E_PEX0_STN7_TX_DP<114>")
		)
		(pad "2" smd rect
			(at 0.2667 0 90)
			(size 0.3048 0.381)
			(layers "F.Cu" "F.Mask" "F.Paste")
			(net "P5E_PEX0_STN7_TX_C_DP<114>")
		)
	)
	(footprint ""
		(layer "F.Cu")
		(at 56.373268 -390.11479 -90)
		(property "Reference" "C4040"
			(at 0 0 270)
			(layer "F.SilkS")
			(hide yes)
			(effects
				(font
					(size 1.27 1.27)
				)
			)
		)
		(property "Value" ""
			(at 0 0 270)
			(layer "F.Fab")
			(effects
				(font
					(size 1.27 1.27)
				)
			)
		)
		(duplicate_pad_numbers_are_jumpers no)
		(fp_line
			(start -0.7874 0.4064)
			(end -0.7874 -0.4064)
			(stroke
				(width 0.1524)
				(type default)
			)
			(layer "F.SilkS")
		)
		(fp_line
			(start 0.7874 0.4064)
			(end -0.7874 0.4064)
			(stroke
				(width 0.1524)
				(type default)
			)
			(layer "F.SilkS")
		)
		(fp_line
			(start -0.7874 -0.4064)
			(end 0.7874 -0.4064)
			(stroke
				(width 0.1524)
				(type default)
			)
			(layer "F.SilkS")
		)
		(fp_line
			(start 0.7874 -0.4064)
			(end 0.7874 0.4064)
			(stroke
				(width 0.1524)
				(type default)
			)
			(layer "F.SilkS")
		)
		(fp_line
			(start -0.67945 0.3048)
			(end -0.67945 -0.305054)
			(stroke
				(width 0.1)
				(type default)
			)
			(layer "F.Fab")
		)
		(fp_line
			(start -0.12065 0.3048)
			(end -0.67945 0.3048)
			(stroke
				(width 0.1)
				(type default)
			)
			(layer "F.Fab")
		)
		(fp_line
			(start 0.120396 0.3048)
			(end 0.120396 0.2794)
			(stroke
				(width 0.1)
				(type default)
			)
			(layer "F.Fab")
		)
		(fp_line
			(start 0.67945 0.3048)
			(end 0.120396 0.3048)
			(stroke
				(width 0.1)
				(type default)
			)
			(layer "F.Fab")
		)
		(fp_line
			(start -0.12065 0.2794)
			(end -0.12065 0.3048)
			(stroke
				(width 0.1)
				(type default)
			)
			(layer "F.Fab")
		)
		(fp_line
			(start 0.120396 0.2794)
			(end -0.12065 0.2794)
			(stroke
				(width 0.1)
				(type default)
			)
			(layer "F.Fab")
		)
		(fp_line
			(start -0.12065 -0.2794)
			(end 0.12065 -0.2794)
			(stroke
				(width 0.1)
				(type default)
			)
			(layer "F.Fab")
		)
		(fp_line
			(start 0.12065 -0.2794)
			(end 0.12065 -0.3048)
			(stroke
				(width 0.1)
				(type default)
			)
			(layer "F.Fab")
		)
		(fp_line
			(start 0.12065 -0.3048)
			(end 0.67945 -0.3048)
			(stroke
				(width 0.1)
				(type default)
			)
			(layer "F.Fab")
		)
		(fp_line
			(start 0.67945 -0.3048)
			(end 0.67945 0.3048)
			(stroke
				(width 0.1)
				(type default)
			)
			(layer "F.Fab")
		)
		(fp_line
			(start -0.67945 -0.305054)
			(end -0.12065 -0.305054)
			(stroke
				(width 0.1)
				(type default)
			)
			(layer "F.Fab")
		)
		(fp_line
			(start -0.12065 -0.305054)
			(end -0.12065 -0.2794)
			(stroke
				(width 0.1)
				(type default)
			)
			(layer "F.Fab")
		)
		(pad "1" smd circle
			(at -0.40005 0 270)
			(size 0 0)
			(layers "F.Cu" "F.Mask" "F.Paste")
			(net "GND")
		)
		(pad "2" smd circle
			(at 0.40005 0 270)
			(size 0 0)
			(layers "F.Cu" "F.Mask" "F.Paste")
			(net "GPU_PEX_STRAP0")
		)
	)
	(footprint ""
		(layer "F.Cu")
		(at 258.170426 -242.372388)
		(property "Reference" "C4428"
			(at 0 0 0)
			(layer "F.SilkS")
			(hide yes)
			(effects
				(font
					(size 1.27 1.27)
				)
			)
		)
		(property "Value" ""
			(at 0 0 0)
			(layer "F.Fab")
			(effects
				(font
					(size 1.27 1.27)
				)
			)
		)
		(duplicate_pad_numbers_are_jumpers no)
		(fp_line
			(start -0.7874 -0.4064)
			(end 0.7874 -0.4064)
			(stroke
				(width 0.1524)
				(type default)
			)
			(layer "F.SilkS")
		)
		(fp_line
			(start -0.7874 0.4064)
			(end -0.7874 -0.4064)
			(stroke
				(width 0.1524)
				(type default)
			)
			(layer "F.SilkS")
		)
		(fp_line
			(start 0.7874 -0.4064)
			(end 0.7874 0.4064)
			(stroke
				(width 0.1524)
				(type default)
			)
			(layer "F.SilkS")
		)
		(fp_line
			(start 0.7874 0.4064)
			(end -0.7874 0.4064)
			(stroke
				(width 0.1524)
				(type default)
			)
			(layer "F.SilkS")
		)
		(fp_line
			(start -0.67945 -0.305054)
			(end -0.12065 -0.305054)
			(stroke
				(width 0.1)
				(type default)
			)
			(layer "F.Fab")
		)
		(fp_line
			(start -0.67945 0.3048)
			(end -0.67945 -0.305054)
			(stroke
				(width 0.1)
				(type default)
			)
			(layer "F.Fab")
		)
		(fp_line
			(start -0.12065 -0.305054)
			(end -0.12065 -0.2794)
			(stroke
				(width 0.1)
				(type default)
			)
			(layer "F.Fab")
		)
		(fp_line
			(start -0.12065 -0.2794)
			(end 0.12065 -0.2794)
			(stroke
				(width 0.1)
				(type default)
			)
			(layer "F.Fab")
		)
		(fp_line
			(start -0.12065 0.2794)
			(end -0.12065 0.3048)
			(stroke
				(width 0.1)
				(type default)
			)
			(layer "F.Fab")
		)
		(fp_line
			(start -0.12065 0.3048)
			(end -0.67945 0.3048)
			(stroke
				(width 0.1)
				(type default)
			)
			(layer "F.Fab")
		)
		(fp_line
			(start 0.120396 0.2794)
			(end -0.12065 0.2794)
			(stroke
				(width 0.1)
				(type default)
			)
			(layer "F.Fab")
		)
		(fp_line
			(start 0.120396 0.3048)
			(end 0.120396 0.2794)
			(stroke
				(width 0.1)
				(type default)
			)
			(layer "F.Fab")
		)
		(fp_line
			(start 0.12065 -0.3048)
			(end 0.67945 -0.3048)
			(stroke
				(width 0.1)
				(type default)
			)
			(layer "F.Fab")
		)
		(fp_line
			(start 0.12065 -0.2794)
			(end 0.12065 -0.3048)
			(stroke
				(width 0.1)
				(type default)
			)
			(layer "F.Fab")
		)
		(fp_line
			(start 0.67945 -0.3048)
			(end 0.67945 0.3048)
			(stroke
				(width 0.1)
				(type default)
			)
			(layer "F.Fab")
		)
		(fp_line
			(start 0.67945 0.3048)
			(end 0.120396 0.3048)
			(stroke
				(width 0.1)
				(type default)
			)
			(layer "F.Fab")
		)
		(pad "1" smd circle
			(at -0.40005 0)
			(size 0 0)
			(layers "F.Cu" "F.Mask" "F.Paste")
			(net "PEX2_P1V8_PLL_EN")
		)
		(pad "2" smd circle
			(at 0.40005 0)
			(size 0 0)
			(layers "F.Cu" "F.Mask" "F.Paste")
			(net "GND")
		)
	)
	(footprint ""
		(layer "F.Cu")
		(at 265.303254 -59.571636 90)
		(property "Reference" "PR277"
			(at 0 0 90)
			(layer "F.SilkS")
			(hide yes)
			(effects
				(font
					(size 1.27 1.27)
				)
			)
		)
		(property "Value" ""
			(at 0 0 90)
			(layer "F.Fab")
			(effects
				(font
					(size 1.27 1.27)
				)
			)
		)
		(duplicate_pad_numbers_are_jumpers no)
		(fp_line
			(start 0.7874 -0.4064)
			(end 0.7874 0.4064)
			(stroke
				(width 0.1524)
				(type default)
			)
			(layer "F.SilkS")
		)
		(fp_line
			(start -0.7874 -0.4064)
			(end 0.7874 -0.4064)
			(stroke
				(width 0.1524)
				(type default)
			)
			(layer "F.SilkS")
		)
		(fp_line
			(start 0.7874 0.4064)
			(end -0.7874 0.4064)
			(stroke
				(width 0.1524)
				(type default)
			)
			(layer "F.SilkS")
		)
		(fp_line
			(start -0.7874 0.4064)
			(end -0.7874 -0.4064)
			(stroke
				(width 0.1524)
				(type default)
			)
			(layer "F.SilkS")
		)
		(fp_line
			(start -0.12065 -0.305054)
			(end -0.12065 -0.2794)
			(stroke
				(width 0.1)
				(type default)
			)
			(layer "F.Fab")
		)
		(fp_line
			(start -0.67945 -0.305054)
			(end -0.12065 -0.305054)
			(stroke
				(width 0.1)
				(type default)
			)
			(layer "F.Fab")
		)
		(fp_line
			(start 0.67945 -0.3048)
			(end 0.67945 0.3048)
			(stroke
				(width 0.1)
				(type default)
			)
			(layer "F.Fab")
		)
		(fp_line
			(start 0.12065 -0.3048)
			(end 0.67945 -0.3048)
			(stroke
				(width 0.1)
				(type default)
			)
			(layer "F.Fab")
		)
		(fp_line
			(start 0.12065 -0.2794)
			(end 0.12065 -0.3048)
			(stroke
				(width 0.1)
				(type default)
			)
			(layer "F.Fab")
		)
		(fp_line
			(start -0.12065 -0.2794)
			(end 0.12065 -0.2794)
			(stroke
				(width 0.1)
				(type default)
			)
			(layer "F.Fab")
		)
		(fp_line
			(start 0.120396 0.2794)
			(end -0.12065 0.2794)
			(stroke
				(width 0.1)
				(type default)
			)
			(layer "F.Fab")
		)
		(fp_line
			(start -0.12065 0.2794)
			(end -0.12065 0.3048)
			(stroke
				(width 0.1)
				(type default)
			)
			(layer "F.Fab")
		)
		(fp_line
			(start 0.67945 0.3048)
			(end 0.120396 0.3048)
			(stroke
				(width 0.1)
				(type default)
			)
			(layer "F.Fab")
		)
		(fp_line
			(start 0.120396 0.3048)
			(end 0.120396 0.2794)
			(stroke
				(width 0.1)
				(type default)
			)
			(layer "F.Fab")
		)
		(fp_line
			(start -0.12065 0.3048)
			(end -0.67945 0.3048)
			(stroke
				(width 0.1)
				(type default)
			)
			(layer "F.Fab")
		)
		(fp_line
			(start -0.67945 0.3048)
			(end -0.67945 -0.305054)
			(stroke
				(width 0.1)
				(type default)
			)
			(layer "F.Fab")
		)
		(pad "1" smd circle
			(at -0.40005 0 90)
			(size 0 0)
			(layers "F.Cu" "F.Mask" "F.Paste")
			(net "P3V3_SSD9_OCP")
		)
		(pad "2" smd circle
			(at 0.40005 0 90)
			(size 0 0)
			(layers "F.Cu" "F.Mask" "F.Paste")
			(net "GND")
		)
	)
	(footprint ""
		(layer "F.Cu")
		(at 439.57621 -297.46448 180)
		(property "Reference" "R4007"
			(at 0 0 180)
			(layer "F.SilkS")
			(hide yes)
			(effects
				(font
					(size 1.27 1.27)
				)
			)
		)
		(property "Value" ""
			(at 0 0 180)
			(layer "F.Fab")
			(effects
				(font
					(size 1.27 1.27)
				)
			)
		)
		(duplicate_pad_numbers_are_jumpers no)
		(fp_line
			(start 0.7874 0.4064)
			(end -0.7874 0.4064)
			(stroke
				(width 0.1524)
				(type default)
			)
			(layer "F.SilkS")
		)
		(fp_line
			(start 0.7874 -0.4064)
			(end 0.7874 0.4064)
			(stroke
				(width 0.1524)
				(type default)
			)
			(layer "F.SilkS")
		)
		(fp_line
			(start -0.7874 0.4064)
			(end -0.7874 -0.4064)
			(stroke
				(width 0.1524)
				(type default)
			)
			(layer "F.SilkS")
		)
		(fp_line
			(start -0.7874 -0.4064)
			(end 0.7874 -0.4064)
			(stroke
				(width 0.1524)
				(type default)
			)
			(layer "F.SilkS")
		)
		(fp_line
			(start 0.67945 0.3048)
			(end 0.120396 0.3048)
			(stroke
				(width 0.1)
				(type default)
			)
			(layer "F.Fab")
		)
		(fp_line
			(start 0.67945 -0.3048)
			(end 0.67945 0.3048)
			(stroke
				(width 0.1)
				(type default)
			)
			(layer "F.Fab")
		)
		(fp_line
			(start 0.12065 -0.2794)
			(end 0.12065 -0.3048)
			(stroke
				(width 0.1)
				(type default)
			)
			(layer "F.Fab")
		)
		(fp_line
			(start 0.12065 -0.3048)
			(end 0.67945 -0.3048)
			(stroke
				(width 0.1)
				(type default)
			)
			(layer "F.Fab")
		)
		(fp_line
			(start 0.120396 0.3048)
			(end 0.120396 0.2794)
			(stroke
				(width 0.1)
				(type default)
			)
			(layer "F.Fab")
		)
		(fp_line
			(start 0.120396 0.2794)
			(end -0.12065 0.2794)
			(stroke
				(width 0.1)
				(type default)
			)
			(layer "F.Fab")
		)
		(fp_line
			(start -0.12065 0.3048)
			(end -0.67945 0.3048)
			(stroke
				(width 0.1)
				(type default)
			)
			(layer "F.Fab")
		)
		(fp_line
			(start -0.12065 0.2794)
			(end -0.12065 0.3048)
			(stroke
				(width 0.1)
				(type default)
			)
			(layer "F.Fab")
		)
		(fp_line
			(start -0.12065 -0.2794)
			(end 0.12065 -0.2794)
			(stroke
				(width 0.1)
				(type default)
			)
			(layer "F.Fab")
		)
		(fp_line
			(start -0.12065 -0.305054)
			(end -0.12065 -0.2794)
			(stroke
				(width 0.1)
				(type default)
			)
			(layer "F.Fab")
		)
		(fp_line
			(start -0.67945 0.3048)
			(end -0.67945 -0.305054)
			(stroke
				(width 0.1)
				(type default)
			)
			(layer "F.Fab")
		)
		(fp_line
			(start -0.67945 -0.305054)
			(end -0.12065 -0.305054)
			(stroke
				(width 0.1)
				(type default)
			)
			(layer "F.Fab")
		)
		(pad "1" smd circle
			(at -0.40005 0 180)
			(size 0 0)
			(layers "F.Cu" "F.Mask" "F.Paste")
			(net "SMB_PEX3_HOST_LS_SCL")
		)
		(pad "2" smd circle
			(at 0.40005 0 180)
			(size 0 0)
			(layers "F.Cu" "F.Mask" "F.Paste")
			(net "I2C_PEX3_HOST_R_SCL")
		)
	)
	(footprint ""
		(layer "F.Cu")
		(at 386.899912 -150.263352 180)
		(property "Reference" "R321"
			(at 0 0 180)
			(layer "F.SilkS")
			(hide yes)
			(effects
				(font
					(size 1.27 1.27)
				)
			)
		)
		(property "Value" ""
			(at 0 0 180)
			(layer "F.Fab")
			(effects
				(font
					(size 1.27 1.27)
				)
			)
		)
		(duplicate_pad_numbers_are_jumpers no)
		(fp_line
			(start 0.7874 0.4064)
			(end -0.7874 0.4064)
			(stroke
				(width 0.1524)
				(type default)
			)
			(layer "F.SilkS")
		)
		(fp_line
			(start 0.7874 -0.4064)
			(end 0.7874 0.4064)
			(stroke
				(width 0.1524)
				(type default)
			)
			(layer "F.SilkS")
		)
		(fp_line
			(start -0.7874 0.4064)
			(end -0.7874 -0.4064)
			(stroke
				(width 0.1524)
				(type default)
			)
			(layer "F.SilkS")
		)
		(fp_line
			(start -0.7874 -0.4064)
			(end 0.7874 -0.4064)
			(stroke
				(width 0.1524)
				(type default)
			)
			(layer "F.SilkS")
		)
		(fp_line
			(start 0.67945 0.3048)
			(end 0.120396 0.3048)
			(stroke
				(width 0.1)
				(type default)
			)
			(layer "F.Fab")
		)
		(fp_line
			(start 0.67945 -0.3048)
			(end 0.67945 0.3048)
			(stroke
				(width 0.1)
				(type default)
			)
			(layer "F.Fab")
		)
		(fp_line
			(start 0.12065 -0.2794)
			(end 0.12065 -0.3048)
			(stroke
				(width 0.1)
				(type default)
			)
			(layer "F.Fab")
		)
		(fp_line
			(start 0.12065 -0.3048)
			(end 0.67945 -0.3048)
			(stroke
				(width 0.1)
				(type default)
			)
			(layer "F.Fab")
		)
		(fp_line
			(start 0.120396 0.3048)
			(end 0.120396 0.2794)
			(stroke
				(width 0.1)
				(type default)
			)
			(layer "F.Fab")
		)
		(fp_line
			(start 0.120396 0.2794)
			(end -0.12065 0.2794)
			(stroke
				(width 0.1)
				(type default)
			)
			(layer "F.Fab")
		)
		(fp_line
			(start -0.12065 0.3048)
			(end -0.67945 0.3048)
			(stroke
				(width 0.1)
				(type default)
			)
			(layer "F.Fab")
		)
		(fp_line
			(start -0.12065 0.2794)
			(end -0.12065 0.3048)
			(stroke
				(width 0.1)
				(type default)
			)
			(layer "F.Fab")
		)
		(fp_line
			(start -0.12065 -0.2794)
			(end 0.12065 -0.2794)
			(stroke
				(width 0.1)
				(type default)
			)
			(layer "F.Fab")
		)
		(fp_line
			(start -0.12065 -0.305054)
			(end -0.12065 -0.2794)
			(stroke
				(width 0.1)
				(type default)
			)
			(layer "F.Fab")
		)
		(fp_line
			(start -0.67945 0.3048)
			(end -0.67945 -0.305054)
			(stroke
				(width 0.1)
				(type default)
			)
			(layer "F.Fab")
		)
		(fp_line
			(start -0.67945 -0.305054)
			(end -0.12065 -0.305054)
			(stroke
				(width 0.1)
				(type default)
			)
			(layer "F.Fab")
		)
		(pad "1" smd circle
			(at -0.40005 0 180)
			(size 0 0)
			(layers "F.Cu" "F.Mask" "F.Paste")
			(net "NCSI_NIC6_CRS_DV")
		)
		(pad "2" smd circle
			(at 0.40005 0 180)
			(size 0 0)
			(layers "F.Cu" "F.Mask" "F.Paste")
			(net "GND")
		)
	)
	(footprint ""
		(layer "F.Cu")
		(at 29.548328 -343.952322 90)
		(property "Reference" "C184"
			(at 0 0 90)
			(layer "F.SilkS")
			(hide yes)
			(effects
				(font
					(size 1.27 1.27)
				)
			)
		)
		(property "Value" ""
			(at 0 0 90)
			(layer "F.Fab")
			(effects
				(font
					(size 1.27 1.27)
				)
			)
		)
		(duplicate_pad_numbers_are_jumpers no)
		(fp_line
			(start 0.299974 -0.150114)
			(end 0.299974 0.150114)
			(stroke
				(width 0.1)
				(type default)
			)
			(layer "F.Fab")
		)
		(fp_line
			(start -0.299974 -0.150114)
			(end 0.299974 -0.150114)
			(stroke
				(width 0.1)
				(type default)
			)
			(layer "F.Fab")
		)
		(fp_line
			(start 0.299974 0.150114)
			(end -0.299974 0.150114)
			(stroke
				(width 0.1)
				(type default)
			)
			(layer "F.Fab")
		)
		(fp_line
			(start -0.299974 0.150114)
			(end -0.299974 -0.150114)
			(stroke
				(width 0.1)
				(type default)
			)
			(layer "F.Fab")
		)
		(pad "1" smd rect
			(at -0.2667 0 90)
			(size 0.3048 0.381)
			(layers "F.Cu" "F.Mask" "F.Paste")
			(net "P5E_PEX0_STN7_TX_DN<116>")
		)
		(pad "2" smd rect
			(at 0.2667 0 90)
			(size 0.3048 0.381)
			(layers "F.Cu" "F.Mask" "F.Paste")
			(net "P5E_PEX0_STN7_TX_C_DN<116>")
		)
	)
	(footprint ""
		(layer "F.Cu")
		(at 428.923704 -87.349076 -90)
		(property "Reference" "R403"
			(at 0 0 270)
			(layer "F.SilkS")
			(hide yes)
			(effects
				(font
					(size 1.27 1.27)
				)
			)
		)
		(property "Value" ""
			(at 0 0 270)
			(layer "F.Fab")
			(effects
				(font
					(size 1.27 1.27)
				)
			)
		)
		(duplicate_pad_numbers_are_jumpers no)
		(fp_line
			(start -0.7874 0.4064)
			(end -0.7874 -0.4064)
			(stroke
				(width 0.1524)
				(type default)
			)
			(layer "F.SilkS")
		)
		(fp_line
			(start 0.7874 0.4064)
			(end -0.7874 0.4064)
			(stroke
				(width 0.1524)
				(type default)
			)
			(layer "F.SilkS")
		)
		(fp_line
			(start -0.7874 -0.4064)
			(end 0.7874 -0.4064)
			(stroke
				(width 0.1524)
				(type default)
			)
			(layer "F.SilkS")
		)
		(fp_line
			(start 0.7874 -0.4064)
			(end 0.7874 0.4064)
			(stroke
				(width 0.1524)
				(type default)
			)
			(layer "F.SilkS")
		)
		(fp_line
			(start -0.67945 0.3048)
			(end -0.67945 -0.305054)
			(stroke
				(width 0.1)
				(type default)
			)
			(layer "F.Fab")
		)
		(fp_line
			(start -0.12065 0.3048)
			(end -0.67945 0.3048)
			(stroke
				(width 0.1)
				(type default)
			)
			(layer "F.Fab")
		)
		(fp_line
			(start 0.120396 0.3048)
			(end 0.120396 0.2794)
			(stroke
				(width 0.1)
				(type default)
			)
			(layer "F.Fab")
		)
		(fp_line
			(start 0.67945 0.3048)
			(end 0.120396 0.3048)
			(stroke
				(width 0.1)
				(type default)
			)
			(layer "F.Fab")
		)
		(fp_line
			(start -0.12065 0.2794)
			(end -0.12065 0.3048)
			(stroke
				(width 0.1)
				(type default)
			)
			(layer "F.Fab")
		)
		(fp_line
			(start 0.120396 0.2794)
			(end -0.12065 0.2794)
			(stroke
				(width 0.1)
				(type default)
			)
			(layer "F.Fab")
		)
		(fp_line
			(start -0.12065 -0.2794)
			(end 0.12065 -0.2794)
			(stroke
				(width 0.1)
				(type default)
			)
			(layer "F.Fab")
		)
		(fp_line
			(start 0.12065 -0.2794)
			(end 0.12065 -0.3048)
			(stroke
				(width 0.1)
				(type default)
			)
			(layer "F.Fab")
		)
		(fp_line
			(start 0.12065 -0.3048)
			(end 0.67945 -0.3048)
			(stroke
				(width 0.1)
				(type default)
			)
			(layer "F.Fab")
		)
		(fp_line
			(start 0.67945 -0.3048)
			(end 0.67945 0.3048)
			(stroke
				(width 0.1)
				(type default)
			)
			(layer "F.Fab")
		)
		(fp_line
			(start -0.67945 -0.305054)
			(end -0.12065 -0.305054)
			(stroke
				(width 0.1)
				(type default)
			)
			(layer "F.Fab")
		)
		(fp_line
			(start -0.12065 -0.305054)
			(end -0.12065 -0.2794)
			(stroke
				(width 0.1)
				(type default)
			)
			(layer "F.Fab")
		)
		(pad "1" smd circle
			(at -0.40005 0 270)
			(size 0 0)
			(layers "F.Cu" "F.Mask" "F.Paste")
			(net "RST_NIC7_PERST1_R_N")
		)
		(pad "2" smd circle
			(at 0.40005 0 270)
			(size 0 0)
			(layers "F.Cu" "F.Mask" "F.Paste")
			(net "RST_HP_NIC7_BUF_N")
		)
	)
	(footprint ""
		(layer "F.Cu")
		(at 138.985244 -88.956642 180)
		(property "Reference" "R1563"
			(at 0 0 180)
			(layer "F.SilkS")
			(hide yes)
			(effects
				(font
					(size 1.27 1.27)
				)
			)
		)
		(property "Value" ""
			(at 0 0 180)
			(layer "F.Fab")
			(effects
				(font
					(size 1.27 1.27)
				)
			)
		)
		(duplicate_pad_numbers_are_jumpers no)
		(fp_line
			(start 0.7874 0.4064)
			(end -0.7874 0.4064)
			(stroke
				(width 0.1524)
				(type default)
			)
			(layer "F.SilkS")
		)
		(fp_line
			(start 0.7874 -0.4064)
			(end 0.7874 0.4064)
			(stroke
				(width 0.1524)
				(type default)
			)
			(layer "F.SilkS")
		)
		(fp_line
			(start -0.7874 0.4064)
			(end -0.7874 -0.4064)
			(stroke
				(width 0.1524)
				(type default)
			)
			(layer "F.SilkS")
		)
		(fp_line
			(start -0.7874 -0.4064)
			(end 0.7874 -0.4064)
			(stroke
				(width 0.1524)
				(type default)
			)
			(layer "F.SilkS")
		)
		(fp_line
			(start 0.67945 0.3048)
			(end 0.120396 0.3048)
			(stroke
				(width 0.1)
				(type default)
			)
			(layer "F.Fab")
		)
		(fp_line
			(start 0.67945 -0.3048)
			(end 0.67945 0.3048)
			(stroke
				(width 0.1)
				(type default)
			)
			(layer "F.Fab")
		)
		(fp_line
			(start 0.12065 -0.2794)
			(end 0.12065 -0.3048)
			(stroke
				(width 0.1)
				(type default)
			)
			(layer "F.Fab")
		)
		(fp_line
			(start 0.12065 -0.3048)
			(end 0.67945 -0.3048)
			(stroke
				(width 0.1)
				(type default)
			)
			(layer "F.Fab")
		)
		(fp_line
			(start 0.120396 0.3048)
			(end 0.120396 0.2794)
			(stroke
				(width 0.1)
				(type default)
			)
			(layer "F.Fab")
		)
		(fp_line
			(start 0.120396 0.2794)
			(end -0.12065 0.2794)
			(stroke
				(width 0.1)
				(type default)
			)
			(layer "F.Fab")
		)
		(fp_line
			(start -0.12065 0.3048)
			(end -0.67945 0.3048)
			(stroke
				(width 0.1)
				(type default)
			)
			(layer "F.Fab")
		)
		(fp_line
			(start -0.12065 0.2794)
			(end -0.12065 0.3048)
			(stroke
				(width 0.1)
				(type default)
			)
			(layer "F.Fab")
		)
		(fp_line
			(start -0.12065 -0.2794)
			(end 0.12065 -0.2794)
			(stroke
				(width 0.1)
				(type default)
			)
			(layer "F.Fab")
		)
		(fp_line
			(start -0.12065 -0.305054)
			(end -0.12065 -0.2794)
			(stroke
				(width 0.1)
				(type default)
			)
			(layer "F.Fab")
		)
		(fp_line
			(start -0.67945 0.3048)
			(end -0.67945 -0.305054)
			(stroke
				(width 0.1)
				(type default)
			)
			(layer "F.Fab")
		)
		(fp_line
			(start -0.67945 -0.305054)
			(end -0.12065 -0.305054)
			(stroke
				(width 0.1)
				(type default)
			)
			(layer "F.Fab")
		)
		(pad "1" smd circle
			(at -0.40005 0 180)
			(size 0 0)
			(layers "F.Cu" "F.Mask" "F.Paste")
			(net "P3V3_AUX")
		)
		(pad "2" smd circle
			(at 0.40005 0 180)
			(size 0 0)
			(layers "F.Cu" "F.Mask" "F.Paste")
			(net "SMB_BIC_I2C9_MUX0_SSD4_R_SCL")
		)
	)
	(footprint ""
		(layer "F.Cu")
		(at 336.042 -169.037)
		(property "Reference" "R4732"
			(at 0 0 0)
			(layer "F.SilkS")
			(hide yes)
			(effects
				(font
					(size 1.27 1.27)
				)
			)
		)
		(property "Value" ""
			(at 0 0 0)
			(layer "F.Fab")
			(effects
				(font
					(size 1.27 1.27)
				)
			)
		)
		(duplicate_pad_numbers_are_jumpers no)
		(fp_line
			(start -0.7874 -0.4064)
			(end 0.7874 -0.4064)
			(stroke
				(width 0.1524)
				(type default)
			)
			(layer "F.SilkS")
		)
		(fp_line
			(start -0.7874 0.4064)
			(end -0.7874 -0.4064)
			(stroke
				(width 0.1524)
				(type default)
			)
			(layer "F.SilkS")
		)
		(fp_line
			(start 0.7874 -0.4064)
			(end 0.7874 0.4064)
			(stroke
				(width 0.1524)
				(type default)
			)
			(layer "F.SilkS")
		)
		(fp_line
			(start 0.7874 0.4064)
			(end -0.7874 0.4064)
			(stroke
				(width 0.1524)
				(type default)
			)
			(layer "F.SilkS")
		)
		(fp_line
			(start -0.67945 -0.305054)
			(end -0.12065 -0.305054)
			(stroke
				(width 0.1)
				(type default)
			)
			(layer "F.Fab")
		)
		(fp_line
			(start -0.67945 0.3048)
			(end -0.67945 -0.305054)
			(stroke
				(width 0.1)
				(type default)
			)
			(layer "F.Fab")
		)
		(fp_line
			(start -0.12065 -0.305054)
			(end -0.12065 -0.2794)
			(stroke
				(width 0.1)
				(type default)
			)
			(layer "F.Fab")
		)
		(fp_line
			(start -0.12065 -0.2794)
			(end 0.12065 -0.2794)
			(stroke
				(width 0.1)
				(type default)
			)
			(layer "F.Fab")
		)
		(fp_line
			(start -0.12065 0.2794)
			(end -0.12065 0.3048)
			(stroke
				(width 0.1)
				(type default)
			)
			(layer "F.Fab")
		)
		(fp_line
			(start -0.12065 0.3048)
			(end -0.67945 0.3048)
			(stroke
				(width 0.1)
				(type default)
			)
			(layer "F.Fab")
		)
		(fp_line
			(start 0.120396 0.2794)
			(end -0.12065 0.2794)
			(stroke
				(width 0.1)
				(type default)
			)
			(layer "F.Fab")
		)
		(fp_line
			(start 0.120396 0.3048)
			(end 0.120396 0.2794)
			(stroke
				(width 0.1)
				(type default)
			)
			(layer "F.Fab")
		)
		(fp_line
			(start 0.12065 -0.3048)
			(end 0.67945 -0.3048)
			(stroke
				(width 0.1)
				(type default)
			)
			(layer "F.Fab")
		)
		(fp_line
			(start 0.12065 -0.2794)
			(end 0.12065 -0.3048)
			(stroke
				(width 0.1)
				(type default)
			)
			(layer "F.Fab")
		)
		(fp_line
			(start 0.67945 -0.3048)
			(end 0.67945 0.3048)
			(stroke
				(width 0.1)
				(type default)
			)
			(layer "F.Fab")
		)
		(fp_line
			(start 0.67945 0.3048)
			(end 0.120396 0.3048)
			(stroke
				(width 0.1)
				(type default)
			)
			(layer "F.Fab")
		)
		(pad "1" smd circle
			(at -0.40005 0)
			(size 0 0)
			(layers "F.Cu" "F.Mask" "F.Paste")
			(net "P3V3_AUX")
		)
		(pad "2" smd circle
			(at 0.40005 0)
			(size 0 0)
			(layers "F.Cu" "F.Mask" "F.Paste")
			(net "RST_PEX_SSD10_PERST_R_N")
		)
	)
	(footprint ""
		(layer "F.Cu")
		(at 13.221716 -129.799334 180)
		(property "Reference" "PD24"
			(at 7.532116 -0.311404 0)
			(unlocked yes)
			(layer "F.SilkS")
			(effects
				(font
					(size 0.7874 0.5842)
					(thickness 0.1524)
				)
				(justify left)
			)
		)
		(property "Value" ""
			(at 0 0 180)
			(layer "F.Fab")
			(effects
				(font
					(size 1.27 1.27)
				)
			)
		)
		(duplicate_pad_numbers_are_jumpers no)
		(fp_line
			(start 4.240784 1.970024)
			(end 4.240784 -1.970024)
			(stroke
				(width 0.1524)
				(type default)
			)
			(layer "F.SilkS")
		)
		(fp_line
			(start 4.240784 -1.970024)
			(end -3.656584 -1.970024)
			(stroke
				(width 0.1524)
				(type default)
			)
			(layer "F.SilkS")
		)
		(fp_line
			(start -3.656584 1.970024)
			(end 4.240784 1.970024)
			(stroke
				(width 0.1524)
				(type default)
			)
			(layer "F.SilkS")
		)
		(fp_line
			(start -3.656584 -1.970024)
			(end -3.656584 1.970024)
			(stroke
				(width 0.1524)
				(type default)
			)
			(layer "F.SilkS")
		)
		(fp_poly
			(pts
				(xy 3.580384 1.970024) (xy 3.580384 -1.970024) (xy 4.240784 -1.970024) (xy 4.240784 1.970024)
			)
			(stroke
				(width 0)
				(type default)
			)
			(fill yes)
			(layer "F.SilkS")
		)
		(fp_line
			(start 2.3749 1.970024)
			(end 2.3749 -1.970024)
			(stroke
				(width 0.1)
				(type default)
			)
			(layer "F.Fab")
		)
		(fp_line
			(start 2.3749 -1.970024)
			(end -2.3749 -1.970024)
			(stroke
				(width 0.1)
				(type default)
			)
			(layer "F.Fab")
		)
		(fp_line
			(start -2.3749 1.970024)
			(end 2.3749 1.970024)
			(stroke
				(width 0.1)
				(type default)
			)
			(layer "F.Fab")
		)
		(fp_line
			(start -2.3749 -1.970024)
			(end -2.3749 1.970024)
			(stroke
				(width 0.1)
				(type default)
			)
			(layer "F.Fab")
		)
		(fp_text user "-"
			(at 4.1656 -0.23495 180)
			(unlocked yes)
			(layer "F.Fab")
			(effects
				(font
					(size 1.905 1.4224)
					(thickness 0.1524)
				)
				(justify left)
			)
		)
		(fp_text user "+"
			(at -4.9784 -0.23495 180)
			(unlocked yes)
			(layer "F.Fab")
			(effects
				(font
					(size 1.905 1.4224)
					(thickness 0.1524)
				)
				(justify left)
			)
		)
		(pad "A" smd rect
			(at -2.450084 0 180)
			(size 2.159 2.2606)
			(layers "F.Cu" "F.Mask" "F.Paste")
			(net "GND")
		)
		(pad "C" smd rect
			(at 2.450084 0 180)
			(size 2.159 2.2606)
			(layers "F.Cu" "F.Mask" "F.Paste")
			(net "P12V_AUX")
		)
	)
	(footprint ""
		(layer "F.Cu")
		(at 63.6778 -114.267742)
		(property "Reference" "R89"
			(at 0 0 0)
			(layer "F.SilkS")
			(hide yes)
			(effects
				(font
					(size 1.27 1.27)
				)
			)
		)
		(property "Value" ""
			(at 0 0 0)
			(layer "F.Fab")
			(effects
				(font
					(size 1.27 1.27)
				)
			)
		)
		(duplicate_pad_numbers_are_jumpers no)
		(fp_line
			(start -0.7874 -0.4064)
			(end 0.7874 -0.4064)
			(stroke
				(width 0.1524)
				(type default)
			)
			(layer "F.SilkS")
		)
		(fp_line
			(start -0.7874 0.4064)
			(end -0.7874 -0.4064)
			(stroke
				(width 0.1524)
				(type default)
			)
			(layer "F.SilkS")
		)
		(fp_line
			(start 0.7874 -0.4064)
			(end 0.7874 0.4064)
			(stroke
				(width 0.1524)
				(type default)
			)
			(layer "F.SilkS")
		)
		(fp_line
			(start 0.7874 0.4064)
			(end -0.7874 0.4064)
			(stroke
				(width 0.1524)
				(type default)
			)
			(layer "F.SilkS")
		)
		(fp_line
			(start -0.67945 -0.305054)
			(end -0.12065 -0.305054)
			(stroke
				(width 0.1)
				(type default)
			)
			(layer "F.Fab")
		)
		(fp_line
			(start -0.67945 0.3048)
			(end -0.67945 -0.305054)
			(stroke
				(width 0.1)
				(type default)
			)
			(layer "F.Fab")
		)
		(fp_line
			(start -0.12065 -0.305054)
			(end -0.12065 -0.2794)
			(stroke
				(width 0.1)
				(type default)
			)
			(layer "F.Fab")
		)
		(fp_line
			(start -0.12065 -0.2794)
			(end 0.12065 -0.2794)
			(stroke
				(width 0.1)
				(type default)
			)
			(layer "F.Fab")
		)
		(fp_line
			(start -0.12065 0.2794)
			(end -0.12065 0.3048)
			(stroke
				(width 0.1)
				(type default)
			)
			(layer "F.Fab")
		)
		(fp_line
			(start -0.12065 0.3048)
			(end -0.67945 0.3048)
			(stroke
				(width 0.1)
				(type default)
			)
			(layer "F.Fab")
		)
		(fp_line
			(start 0.120396 0.2794)
			(end -0.12065 0.2794)
			(stroke
				(width 0.1)
				(type default)
			)
			(layer "F.Fab")
		)
		(fp_line
			(start 0.120396 0.3048)
			(end 0.120396 0.2794)
			(stroke
				(width 0.1)
				(type default)
			)
			(layer "F.Fab")
		)
		(fp_line
			(start 0.12065 -0.3048)
			(end 0.67945 -0.3048)
			(stroke
				(width 0.1)
				(type default)
			)
			(layer "F.Fab")
		)
		(fp_line
			(start 0.12065 -0.2794)
			(end 0.12065 -0.3048)
			(stroke
				(width 0.1)
				(type default)
			)
			(layer "F.Fab")
		)
		(fp_line
			(start 0.67945 -0.3048)
			(end 0.67945 0.3048)
			(stroke
				(width 0.1)
				(type default)
			)
			(layer "F.Fab")
		)
		(fp_line
			(start 0.67945 0.3048)
			(end 0.120396 0.3048)
			(stroke
				(width 0.1)
				(type default)
			)
			(layer "F.Fab")
		)
		(pad "1" smd circle
			(at -0.40005 0)
			(size 0 0)
			(layers "F.Cu" "F.Mask" "F.Paste")
			(net "RST_SMB_NIC1_MUX_ISO_N")
		)
		(pad "2" smd circle
			(at 0.40005 0)
			(size 0 0)
			(layers "F.Cu" "F.Mask" "F.Paste")
			(net "GND")
		)
	)
	(footprint ""
		(layer "F.Cu")
		(at 242.593368 -318.648588 -90)
		(property "Reference" "PL21"
			(at 0 0 270)
			(layer "F.SilkS")
			(hide yes)
			(effects
				(font
					(size 1.27 1.27)
				)
			)
		)
		(property "Value" ""
			(at 0 0 270)
			(layer "F.Fab")
			(effects
				(font
					(size 1.27 1.27)
				)
			)
		)
		(duplicate_pad_numbers_are_jumpers no)
		(fp_line
			(start -1.27 0.5842)
			(end -1.27 -0.5842)
			(stroke
				(width 0.1524)
				(type default)
			)
			(layer "F.SilkS")
		)
		(fp_line
			(start 1.27 0.5842)
			(end -1.27 0.5842)
			(stroke
				(width 0.1524)
				(type default)
			)
			(layer "F.SilkS")
		)
		(fp_line
			(start 1.27 0.5842)
			(end 1.27 -0.5842)
			(stroke
				(width 0.1524)
				(type default)
			)
			(layer "F.SilkS")
		)
		(fp_line
			(start -1.27 -0.5588)
			(end -1.27 -0.5842)
			(stroke
				(width 0.1524)
				(type default)
			)
			(layer "F.SilkS")
		)
		(fp_line
			(start -1.27 -0.5842)
			(end 1.27 -0.5842)
			(stroke
				(width 0.1524)
				(type default)
			)
			(layer "F.SilkS")
		)
		(fp_line
			(start -0.9144 0.508)
			(end -0.9144 0.406654)
			(stroke
				(width 0.1)
				(type default)
			)
			(layer "F.Fab")
		)
		(fp_line
			(start 0.9144 0.508)
			(end -0.9144 0.508)
			(stroke
				(width 0.1)
				(type default)
			)
			(layer "F.Fab")
		)
		(fp_line
			(start -1.194308 0.406654)
			(end -1.194308 -0.406654)
			(stroke
				(width 0.1)
				(type default)
			)
			(layer "F.Fab")
		)
		(fp_line
			(start -0.9144 0.406654)
			(end -1.194308 0.406654)
			(stroke
				(width 0.1)
				(type default)
			)
			(layer "F.Fab")
		)
		(fp_line
			(start 0.9144 0.4064)
			(end 0.9144 0.508)
			(stroke
				(width 0.1)
				(type default)
			)
			(layer "F.Fab")
		)
		(fp_line
			(start 1.1938 0.4064)
			(end 0.9144 0.4064)
			(stroke
				(width 0.1)
				(type default)
			)
			(layer "F.Fab")
		)
		(fp_line
			(start -1.194308 -0.406654)
			(end -0.9144 -0.406654)
			(stroke
				(width 0.1)
				(type default)
			)
			(layer "F.Fab")
		)
		(fp_line
			(start -0.9144 -0.406654)
			(end -0.9144 -0.508)
			(stroke
				(width 0.1)
				(type default)
			)
			(layer "F.Fab")
		)
		(fp_line
			(start 0.9144 -0.406654)
			(end 1.1938 -0.406654)
			(stroke
				(width 0.1)
				(type default)
			)
			(layer "F.Fab")
		)
		(fp_line
			(start 1.1938 -0.406654)
			(end 1.1938 0.4064)
			(stroke
				(width 0.1)
				(type default)
			)
			(layer "F.Fab")
		)
		(fp_line
			(start -0.9144 -0.508)
			(end 0.9144 -0.508)
			(stroke
				(width 0.1)
				(type default)
			)
			(layer "F.Fab")
		)
		(fp_line
			(start 0.9144 -0.508)
			(end 0.9144 -0.406654)
			(stroke
				(width 0.1)
				(type default)
			)
			(layer "F.Fab")
		)
		(pad "1" smd rect
			(at -0.7366 0 180)
			(size 0.7112 0.8128)
			(layers "F.Cu" "F.Mask" "F.Paste")
			(net "P12V_AUX")
		)
		(pad "2" smd rect
			(at 0.7366 0 180)
			(size 0.7112 0.8128)
			(layers "F.Cu" "F.Mask" "F.Paste")
			(net "SW_P12V_P1V25_PEX2_FLT")
		)
	)
	(footprint ""
		(layer "F.Cu")
		(at 129.690114 -259.147564 180)
		(property "Reference" "R832"
			(at 0 0 180)
			(layer "F.SilkS")
			(hide yes)
			(effects
				(font
					(size 1.27 1.27)
				)
			)
		)
		(property "Value" ""
			(at 0 0 180)
			(layer "F.Fab")
			(effects
				(font
					(size 1.27 1.27)
				)
			)
		)
		(duplicate_pad_numbers_are_jumpers no)
		(fp_line
			(start 0.7874 0.4064)
			(end -0.7874 0.4064)
			(stroke
				(width 0.1524)
				(type default)
			)
			(layer "F.SilkS")
		)
		(fp_line
			(start 0.7874 -0.4064)
			(end 0.7874 0.4064)
			(stroke
				(width 0.1524)
				(type default)
			)
			(layer "F.SilkS")
		)
		(fp_line
			(start -0.7874 0.4064)
			(end -0.7874 -0.4064)
			(stroke
				(width 0.1524)
				(type default)
			)
			(layer "F.SilkS")
		)
		(fp_line
			(start -0.7874 -0.4064)
			(end 0.7874 -0.4064)
			(stroke
				(width 0.1524)
				(type default)
			)
			(layer "F.SilkS")
		)
		(fp_line
			(start 0.67945 0.3048)
			(end 0.120396 0.3048)
			(stroke
				(width 0.1)
				(type default)
			)
			(layer "F.Fab")
		)
		(fp_line
			(start 0.67945 -0.3048)
			(end 0.67945 0.3048)
			(stroke
				(width 0.1)
				(type default)
			)
			(layer "F.Fab")
		)
		(fp_line
			(start 0.12065 -0.2794)
			(end 0.12065 -0.3048)
			(stroke
				(width 0.1)
				(type default)
			)
			(layer "F.Fab")
		)
		(fp_line
			(start 0.12065 -0.3048)
			(end 0.67945 -0.3048)
			(stroke
				(width 0.1)
				(type default)
			)
			(layer "F.Fab")
		)
		(fp_line
			(start 0.120396 0.3048)
			(end 0.120396 0.2794)
			(stroke
				(width 0.1)
				(type default)
			)
			(layer "F.Fab")
		)
		(fp_line
			(start 0.120396 0.2794)
			(end -0.12065 0.2794)
			(stroke
				(width 0.1)
				(type default)
			)
			(layer "F.Fab")
		)
		(fp_line
			(start -0.12065 0.3048)
			(end -0.67945 0.3048)
			(stroke
				(width 0.1)
				(type default)
			)
			(layer "F.Fab")
		)
		(fp_line
			(start -0.12065 0.2794)
			(end -0.12065 0.3048)
			(stroke
				(width 0.1)
				(type default)
			)
			(layer "F.Fab")
		)
		(fp_line
			(start -0.12065 -0.2794)
			(end 0.12065 -0.2794)
			(stroke
				(width 0.1)
				(type default)
			)
			(layer "F.Fab")
		)
		(fp_line
			(start -0.12065 -0.305054)
			(end -0.12065 -0.2794)
			(stroke
				(width 0.1)
				(type default)
			)
			(layer "F.Fab")
		)
		(fp_line
			(start -0.67945 0.3048)
			(end -0.67945 -0.305054)
			(stroke
				(width 0.1)
				(type default)
			)
			(layer "F.Fab")
		)
		(fp_line
			(start -0.67945 -0.305054)
			(end -0.12065 -0.305054)
			(stroke
				(width 0.1)
				(type default)
			)
			(layer "F.Fab")
		)
		(pad "1" smd circle
			(at -0.40005 0 180)
			(size 0 0)
			(layers "F.Cu" "F.Mask" "F.Paste")
			(net "PWRGD_P0V8_PEX1_R")
		)
		(pad "2" smd circle
			(at 0.40005 0 180)
			(size 0 0)
			(layers "F.Cu" "F.Mask" "F.Paste")
			(net "P0V8_PEX1_BVRRDY")
		)
	)
	(footprint ""
		(layer "F.Cu")
		(at 424.814492 -343.952322 90)
		(property "Reference" "C2453"
			(at 0 0 90)
			(layer "F.SilkS")
			(hide yes)
			(effects
				(font
					(size 1.27 1.27)
				)
			)
		)
		(property "Value" ""
			(at 0 0 90)
			(layer "F.Fab")
			(effects
				(font
					(size 1.27 1.27)
				)
			)
		)
		(duplicate_pad_numbers_are_jumpers no)
		(fp_line
			(start 0.299974 -0.150114)
			(end 0.299974 0.150114)
			(stroke
				(width 0.1)
				(type default)
			)
			(layer "F.Fab")
		)
		(fp_line
			(start -0.299974 -0.150114)
			(end 0.299974 -0.150114)
			(stroke
				(width 0.1)
				(type default)
			)
			(layer "F.Fab")
		)
		(fp_line
			(start 0.299974 0.150114)
			(end -0.299974 0.150114)
			(stroke
				(width 0.1)
				(type default)
			)
			(layer "F.Fab")
		)
		(fp_line
			(start -0.299974 0.150114)
			(end -0.299974 -0.150114)
			(stroke
				(width 0.1)
				(type default)
			)
			(layer "F.Fab")
		)
		(pad "1" smd rect
			(at -0.2667 0 90)
			(size 0.3048 0.381)
			(layers "F.Cu" "F.Mask" "F.Paste")
			(net "P5E_PEX3_STN4_TX_DP<72>")
		)
		(pad "2" smd rect
			(at 0.2667 0 90)
			(size 0.3048 0.381)
			(layers "F.Cu" "F.Mask" "F.Paste")
			(net "P5E_PEX3_STN4_TX_C_DP<72>")
		)
	)
	(footprint ""
		(layer "F.Cu")
		(at 353.594162 -35.264852)
		(property "Reference" "R5703"
			(at 0 0 0)
			(layer "F.SilkS")
			(hide yes)
			(effects
				(font
					(size 1.27 1.27)
				)
			)
		)
		(property "Value" ""
			(at 0 0 0)
			(layer "F.Fab")
			(effects
				(font
					(size 1.27 1.27)
				)
			)
		)
		(duplicate_pad_numbers_are_jumpers no)
		(fp_line
			(start -0.7874 -0.4064)
			(end 0.7874 -0.4064)
			(stroke
				(width 0.1524)
				(type default)
			)
			(layer "F.SilkS")
		)
		(fp_line
			(start -0.7874 0.4064)
			(end -0.7874 -0.4064)
			(stroke
				(width 0.1524)
				(type default)
			)
			(layer "F.SilkS")
		)
		(fp_line
			(start 0.7874 -0.4064)
			(end 0.7874 0.4064)
			(stroke
				(width 0.1524)
				(type default)
			)
			(layer "F.SilkS")
		)
		(fp_line
			(start 0.7874 0.4064)
			(end -0.7874 0.4064)
			(stroke
				(width 0.1524)
				(type default)
			)
			(layer "F.SilkS")
		)
		(fp_line
			(start -0.67945 -0.305054)
			(end -0.12065 -0.305054)
			(stroke
				(width 0.1)
				(type default)
			)
			(layer "F.Fab")
		)
		(fp_line
			(start -0.67945 0.3048)
			(end -0.67945 -0.305054)
			(stroke
				(width 0.1)
				(type default)
			)
			(layer "F.Fab")
		)
		(fp_line
			(start -0.12065 -0.305054)
			(end -0.12065 -0.2794)
			(stroke
				(width 0.1)
				(type default)
			)
			(layer "F.Fab")
		)
		(fp_line
			(start -0.12065 -0.2794)
			(end 0.12065 -0.2794)
			(stroke
				(width 0.1)
				(type default)
			)
			(layer "F.Fab")
		)
		(fp_line
			(start -0.12065 0.2794)
			(end -0.12065 0.3048)
			(stroke
				(width 0.1)
				(type default)
			)
			(layer "F.Fab")
		)
		(fp_line
			(start -0.12065 0.3048)
			(end -0.67945 0.3048)
			(stroke
				(width 0.1)
				(type default)
			)
			(layer "F.Fab")
		)
		(fp_line
			(start 0.120396 0.2794)
			(end -0.12065 0.2794)
			(stroke
				(width 0.1)
				(type default)
			)
			(layer "F.Fab")
		)
		(fp_line
			(start 0.120396 0.3048)
			(end 0.120396 0.2794)
			(stroke
				(width 0.1)
				(type default)
			)
			(layer "F.Fab")
		)
		(fp_line
			(start 0.12065 -0.3048)
			(end 0.67945 -0.3048)
			(stroke
				(width 0.1)
				(type default)
			)
			(layer "F.Fab")
		)
		(fp_line
			(start 0.12065 -0.2794)
			(end 0.12065 -0.3048)
			(stroke
				(width 0.1)
				(type default)
			)
			(layer "F.Fab")
		)
		(fp_line
			(start 0.67945 -0.3048)
			(end 0.67945 0.3048)
			(stroke
				(width 0.1)
				(type default)
			)
			(layer "F.Fab")
		)
		(fp_line
			(start 0.67945 0.3048)
			(end 0.120396 0.3048)
			(stroke
				(width 0.1)
				(type default)
			)
			(layer "F.Fab")
		)
		(pad "1" smd circle
			(at -0.40005 0)
			(size 0 0)
			(layers "F.Cu" "F.Mask" "F.Paste")
			(net "RST_SMB_SSD12_ISO_N")
		)
		(pad "2" smd circle
			(at 0.40005 0)
			(size 0 0)
			(layers "F.Cu" "F.Mask" "F.Paste")
			(net "GND")
		)
	)
	(footprint ""
		(layer "F.Cu")
		(at 264.909046 -26.03373)
		(property "Reference" "R4070"
			(at 0 0 0)
			(layer "F.SilkS")
			(hide yes)
			(effects
				(font
					(size 1.27 1.27)
				)
			)
		)
		(property "Value" ""
			(at 0 0 0)
			(layer "F.Fab")
			(effects
				(font
					(size 1.27 1.27)
				)
			)
		)
		(duplicate_pad_numbers_are_jumpers no)
		(fp_line
			(start -0.7874 -0.4064)
			(end 0.7874 -0.4064)
			(stroke
				(width 0.1524)
				(type default)
			)
			(layer "F.SilkS")
		)
		(fp_line
			(start -0.7874 0.4064)
			(end -0.7874 -0.4064)
			(stroke
				(width 0.1524)
				(type default)
			)
			(layer "F.SilkS")
		)
		(fp_line
			(start 0.7874 -0.4064)
			(end 0.7874 0.4064)
			(stroke
				(width 0.1524)
				(type default)
			)
			(layer "F.SilkS")
		)
		(fp_line
			(start 0.7874 0.4064)
			(end -0.7874 0.4064)
			(stroke
				(width 0.1524)
				(type default)
			)
			(layer "F.SilkS")
		)
		(fp_line
			(start -0.67945 -0.305054)
			(end -0.12065 -0.305054)
			(stroke
				(width 0.1)
				(type default)
			)
			(layer "F.Fab")
		)
		(fp_line
			(start -0.67945 0.3048)
			(end -0.67945 -0.305054)
			(stroke
				(width 0.1)
				(type default)
			)
			(layer "F.Fab")
		)
		(fp_line
			(start -0.12065 -0.305054)
			(end -0.12065 -0.2794)
			(stroke
				(width 0.1)
				(type default)
			)
			(layer "F.Fab")
		)
		(fp_line
			(start -0.12065 -0.2794)
			(end 0.12065 -0.2794)
			(stroke
				(width 0.1)
				(type default)
			)
			(layer "F.Fab")
		)
		(fp_line
			(start -0.12065 0.2794)
			(end -0.12065 0.3048)
			(stroke
				(width 0.1)
				(type default)
			)
			(layer "F.Fab")
		)
		(fp_line
			(start -0.12065 0.3048)
			(end -0.67945 0.3048)
			(stroke
				(width 0.1)
				(type default)
			)
			(layer "F.Fab")
		)
		(fp_line
			(start 0.120396 0.2794)
			(end -0.12065 0.2794)
			(stroke
				(width 0.1)
				(type default)
			)
			(layer "F.Fab")
		)
		(fp_line
			(start 0.120396 0.3048)
			(end 0.120396 0.2794)
			(stroke
				(width 0.1)
				(type default)
			)
			(layer "F.Fab")
		)
		(fp_line
			(start 0.12065 -0.3048)
			(end 0.67945 -0.3048)
			(stroke
				(width 0.1)
				(type default)
			)
			(layer "F.Fab")
		)
		(fp_line
			(start 0.12065 -0.2794)
			(end 0.12065 -0.3048)
			(stroke
				(width 0.1)
				(type default)
			)
			(layer "F.Fab")
		)
		(fp_line
			(start 0.67945 -0.3048)
			(end 0.67945 0.3048)
			(stroke
				(width 0.1)
				(type default)
			)
			(layer "F.Fab")
		)
		(fp_line
			(start 0.67945 0.3048)
			(end 0.120396 0.3048)
			(stroke
				(width 0.1)
				(type default)
			)
			(layer "F.Fab")
		)
		(pad "1" smd circle
			(at -0.40005 0)
			(size 0 0)
			(layers "F.Cu" "F.Mask" "F.Paste")
			(net "P3V3_AUX")
		)
		(pad "2" smd circle
			(at 0.40005 0)
			(size 0 0)
			(layers "F.Cu" "F.Mask" "F.Paste")
			(net "PRSNT_SSD9_R_N")
		)
	)
	(footprint ""
		(layer "F.Cu")
		(at 149.387814 -285.218632)
		(property "Reference" "C3232"
			(at 0 0 0)
			(layer "F.SilkS")
			(hide yes)
			(effects
				(font
					(size 1.27 1.27)
				)
			)
		)
		(property "Value" ""
			(at 0 0 0)
			(layer "F.Fab")
			(effects
				(font
					(size 1.27 1.27)
				)
			)
		)
		(duplicate_pad_numbers_are_jumpers no)
		(fp_line
			(start -1.2954 -0.5842)
			(end 1.2954 -0.5842)
			(stroke
				(width 0.1524)
				(type default)
			)
			(layer "F.SilkS")
		)
		(fp_line
			(start -1.2954 0.5842)
			(end -1.2954 -0.5842)
			(stroke
				(width 0.1524)
				(type default)
			)
			(layer "F.SilkS")
		)
		(fp_line
			(start 1.2954 -0.5842)
			(end 1.2954 0.5842)
			(stroke
				(width 0.1524)
				(type default)
			)
			(layer "F.SilkS")
		)
		(fp_line
			(start 1.2954 0.5842)
			(end -1.2954 0.5842)
			(stroke
				(width 0.1524)
				(type default)
			)
			(layer "F.SilkS")
		)
		(fp_line
			(start -1.1938 -0.4064)
			(end -0.8636 -0.4064)
			(stroke
				(width 0.1)
				(type default)
			)
			(layer "F.Fab")
		)
		(fp_line
			(start -1.1938 0.4064)
			(end -1.1938 -0.4064)
			(stroke
				(width 0.1)
				(type default)
			)
			(layer "F.Fab")
		)
		(fp_line
			(start -0.8636 -0.4572)
			(end 0.8636 -0.4572)
			(stroke
				(width 0.1)
				(type default)
			)
			(layer "F.Fab")
		)
		(fp_line
			(start -0.8636 -0.4064)
			(end -0.8636 -0.4572)
			(stroke
				(width 0.1)
				(type default)
			)
			(layer "F.Fab")
		)
		(fp_line
			(start -0.8636 0.4064)
			(end -1.1938 0.4064)
			(stroke
				(width 0.1)
				(type default)
			)
			(layer "F.Fab")
		)
		(fp_line
			(start -0.8636 0.4572)
			(end -0.8636 0.4064)
			(stroke
				(width 0.1)
				(type default)
			)
			(layer "F.Fab")
		)
		(fp_line
			(start 0.8636 -0.4572)
			(end 0.8636 -0.4064)
			(stroke
				(width 0.1)
				(type default)
			)
			(layer "F.Fab")
		)
		(fp_line
			(start 0.8636 -0.4064)
			(end 1.1938 -0.4064)
			(stroke
				(width 0.1)
				(type default)
			)
			(layer "F.Fab")
		)
		(fp_line
			(start 0.8636 0.4064)
			(end 0.8636 0.4572)
			(stroke
				(width 0.1)
				(type default)
			)
			(layer "F.Fab")
		)
		(fp_line
			(start 0.8636 0.4572)
			(end -0.8636 0.4572)
			(stroke
				(width 0.1)
				(type default)
			)
			(layer "F.Fab")
		)
		(fp_line
			(start 1.1938 -0.4064)
			(end 1.1938 0.4064)
			(stroke
				(width 0.1)
				(type default)
			)
			(layer "F.Fab")
		)
		(fp_line
			(start 1.1938 0.4064)
			(end 0.8636 0.4064)
			(stroke
				(width 0.1)
				(type default)
			)
			(layer "F.Fab")
		)
		(pad "1" smd rect
			(at -0.7366 0 270)
			(size 0.7112 0.8128)
			(layers "F.Cu" "F.Mask" "F.Paste")
			(net "PCEPLL7_VDDA18_PEX1")
		)
		(pad "2" smd rect
			(at 0.7366 0 270)
			(size 0.7112 0.8128)
			(layers "F.Cu" "F.Mask" "F.Paste")
			(net "GND")
		)
	)
	(footprint ""
		(layer "F.Cu")
		(at 121.04751 -36.686998 90)
		(property "Reference" "C3663"
			(at 0 0 90)
			(layer "F.SilkS")
			(hide yes)
			(effects
				(font
					(size 1.27 1.27)
				)
			)
		)
		(property "Value" ""
			(at 0 0 90)
			(layer "F.Fab")
			(effects
				(font
					(size 1.27 1.27)
				)
			)
		)
		(duplicate_pad_numbers_are_jumpers no)
		(fp_line
			(start 0.7874 -0.4064)
			(end 0.7874 0.4064)
			(stroke
				(width 0.1524)
				(type default)
			)
			(layer "F.SilkS")
		)
		(fp_line
			(start -0.7874 -0.4064)
			(end 0.7874 -0.4064)
			(stroke
				(width 0.1524)
				(type default)
			)
			(layer "F.SilkS")
		)
		(fp_line
			(start 0.7874 0.4064)
			(end -0.7874 0.4064)
			(stroke
				(width 0.1524)
				(type default)
			)
			(layer "F.SilkS")
		)
		(fp_line
			(start -0.7874 0.4064)
			(end -0.7874 -0.4064)
			(stroke
				(width 0.1524)
				(type default)
			)
			(layer "F.SilkS")
		)
		(fp_line
			(start -0.12065 -0.305054)
			(end -0.12065 -0.2794)
			(stroke
				(width 0.1)
				(type default)
			)
			(layer "F.Fab")
		)
		(fp_line
			(start -0.67945 -0.305054)
			(end -0.12065 -0.305054)
			(stroke
				(width 0.1)
				(type default)
			)
			(layer "F.Fab")
		)
		(fp_line
			(start 0.67945 -0.3048)
			(end 0.67945 0.3048)
			(stroke
				(width 0.1)
				(type default)
			)
			(layer "F.Fab")
		)
		(fp_line
			(start 0.12065 -0.3048)
			(end 0.67945 -0.3048)
			(stroke
				(width 0.1)
				(type default)
			)
			(layer "F.Fab")
		)
		(fp_line
			(start 0.12065 -0.2794)
			(end 0.12065 -0.3048)
			(stroke
				(width 0.1)
				(type default)
			)
			(layer "F.Fab")
		)
		(fp_line
			(start -0.12065 -0.2794)
			(end 0.12065 -0.2794)
			(stroke
				(width 0.1)
				(type default)
			)
			(layer "F.Fab")
		)
		(fp_line
			(start 0.120396 0.2794)
			(end -0.12065 0.2794)
			(stroke
				(width 0.1)
				(type default)
			)
			(layer "F.Fab")
		)
		(fp_line
			(start -0.12065 0.2794)
			(end -0.12065 0.3048)
			(stroke
				(width 0.1)
				(type default)
			)
			(layer "F.Fab")
		)
		(fp_line
			(start 0.67945 0.3048)
			(end 0.120396 0.3048)
			(stroke
				(width 0.1)
				(type default)
			)
			(layer "F.Fab")
		)
		(fp_line
			(start 0.120396 0.3048)
			(end 0.120396 0.2794)
			(stroke
				(width 0.1)
				(type default)
			)
			(layer "F.Fab")
		)
		(fp_line
			(start -0.12065 0.3048)
			(end -0.67945 0.3048)
			(stroke
				(width 0.1)
				(type default)
			)
			(layer "F.Fab")
		)
		(fp_line
			(start -0.67945 0.3048)
			(end -0.67945 -0.305054)
			(stroke
				(width 0.1)
				(type default)
			)
			(layer "F.Fab")
		)
		(pad "1" smd circle
			(at -0.40005 0 90)
			(size 0 0)
			(layers "F.Cu" "F.Mask" "F.Paste")
			(net "P3V3_AUX")
		)
		(pad "2" smd circle
			(at 0.40005 0 90)
			(size 0 0)
			(layers "F.Cu" "F.Mask" "F.Paste")
			(net "GND")
		)
	)
	(footprint ""
		(layer "F.Cu")
		(at 89.649808 -320.900044)
		(property "Reference" "H88"
			(at -6.698234 -7.580884 0)
			(unlocked yes)
			(layer "F.SilkS")
			(effects
				(font
					(size 0.7874 0.5842)
					(thickness 0.1524)
				)
				(justify left)
			)
		)
		(property "Value" ""
			(at 0 0 0)
			(layer "F.Fab")
			(effects
				(font
					(size 1.27 1.27)
				)
			)
		)
		(duplicate_pad_numbers_are_jumpers no)
		(fp_arc
			(start -7.997444 -0.2032)
			(mid 0.10159 -7.999338)
			(end 7.999984 0)
			(stroke
				(width 0.1524)
				(type default)
			)
			(layer "F.SilkS")
		)
		(fp_arc
			(start 7.999984 0)
			(mid 3.104805 7.372968)
			(end -5.590032 5.722874)
			(stroke
				(width 0.1524)
				(type default)
			)
			(layer "F.SilkS")
		)
		(fp_arc
			(start -7.9756 0.623062)
			(mid -7.040405 -3.7988)
			(end -3.858006 -7.008114)
			(stroke
				(width 0.1524)
				(type default)
			)
			(layer "B.SilkS")
		)
		(fp_arc
			(start -1.80848 -7.79272)
			(mid 0.009393 -7.999763)
			(end 1.826768 -7.788402)
			(stroke
				(width 0.1524)
				(type default)
			)
			(layer "B.SilkS")
		)
		(fp_arc
			(start 4.00304 -6.926326)
			(mid 6.929054 -3.998416)
			(end 7.999984 0)
			(stroke
				(width 0.1524)
				(type default)
			)
			(layer "B.SilkS")
		)
		(fp_arc
			(start 7.999984 0)
			(mid 3.342574 7.268164)
			(end -5.206746 6.073648)
			(stroke
				(width 0.1524)
				(type default)
			)
			(layer "B.SilkS")
		)
		(fp_circle
			(center 0 0)
			(end 7.999984 0)
			(stroke
				(width 0.1)
				(type default)
			)
			(fill no)
			(layer "B.Fab")
		)
		(fp_circle
			(center 0 0)
			(end 7.999984 0)
			(stroke
				(width 0.1)
				(type default)
			)
			(fill no)
			(layer "F.Fab")
		)
		(pad "" np_thru_hole circle
			(at 0 0)
			(size 4.5212 4.5212)
			(drill 4.5212)
			(layers "*.Cu" "*.Mask")
			(clearance 0.381)
			(thermal_gap 0.381)
		)
		(pad "2" thru_hole circle
			(at 3.6322 0)
			(size 0.762 0.762)
			(drill 0.5588)
			(layers "*.Cu" "*.Mask")
			(remove_unused_layers no)
			(net "GND")
			(clearance 0.1524)
			(thermal_gap 0.1524)
		)
		(pad "3" thru_hole circle
			(at 2.568448 -2.568448)
			(size 0.762 0.762)
			(drill 0.5588)
			(layers "*.Cu" "*.Mask")
			(remove_unused_layers no)
			(net "GND")
			(clearance 0.1524)
			(thermal_gap 0.1524)
		)
		(pad "4" thru_hole circle
			(at 0 -3.6322)
			(size 0.762 0.762)
			(drill 0.5588)
			(layers "*.Cu" "*.Mask")
			(remove_unused_layers no)
			(net "GND")
			(clearance 0.1524)
			(thermal_gap 0.1524)
		)
		(pad "5" thru_hole circle
			(at -2.568448 -2.568448)
			(size 0.762 0.762)
			(drill 0.5588)
			(layers "*.Cu" "*.Mask")
			(remove_unused_layers no)
			(net "GND")
			(clearance 0.1524)
			(thermal_gap 0.1524)
		)
		(pad "6" thru_hole circle
			(at -3.6322 0)
			(size 0.762 0.762)
			(drill 0.5588)
			(layers "*.Cu" "*.Mask")
			(remove_unused_layers no)
			(net "GND")
			(clearance 0.1524)
			(thermal_gap 0.1524)
		)
		(pad "7" thru_hole circle
			(at -2.568448 2.568448)
			(size 0.762 0.762)
			(drill 0.5588)
			(layers "*.Cu" "*.Mask")
			(remove_unused_layers no)
			(net "GND")
			(clearance 0.1524)
			(thermal_gap 0.1524)
		)
		(pad "8" thru_hole circle
			(at 0 3.6322)
			(size 0.762 0.762)
			(drill 0.5588)
			(layers "*.Cu" "*.Mask")
			(remove_unused_layers no)
			(net "GND")
			(clearance 0.1524)
			(thermal_gap 0.1524)
		)
		(pad "9" thru_hole circle
			(at 2.568448 2.568448)
			(size 0.762 0.762)
			(drill 0.5588)
			(layers "*.Cu" "*.Mask")
			(remove_unused_layers no)
			(net "GND")
			(clearance 0.1524)
			(thermal_gap 0.1524)
		)
		(zone
			(layer "F.Cu")
			(hatch none 0.5)
			(connect_pads
				(clearance 0)
			)
			(min_thickness 0.25)
			(keepout
				(tracks not_allowed)
				(vias allowed)
				(pads allowed)
				(copperpour not_allowed)
				(footprints allowed)
			)
			(placement
				(enabled no)
				(sheetname "")
			)
			(fill
				(thermal_gap 0.5)
				(thermal_bridge_width 0.5)
				(island_removal_mode 0)
			)
			(polygon
				(pts
					(arc
						(start 89.649808 -312.90006)
						(mid 81.649824 -320.900044)
						(end 89.649808 -328.900028)
					)
					(arc
						(start 89.649808 -325.649844)
						(mid 84.900008 -320.900044)
						(end 89.649808 -316.150244)
					)
				)
			)
		)
		(zone
			(layer "F.Cu")
			(hatch none 0.5)
			(connect_pads
				(clearance 0)
			)
			(min_thickness 0.25)
			(keepout
				(tracks not_allowed)
				(vias allowed)
				(pads allowed)
				(copperpour not_allowed)
				(footprints allowed)
			)
			(placement
				(enabled no)
				(sheetname "")
			)
			(fill
				(thermal_gap 0.5)
				(thermal_bridge_width 0.5)
				(island_removal_mode 0)
			)
			(polygon
				(pts
					(arc
						(start 89.649808 -312.90006)
						(mid 97.649792 -320.900044)
						(end 89.649808 -328.900028)
					)
					(arc
						(start 89.649808 -325.649844)
						(mid 94.399608 -320.900044)
						(end 89.649808 -316.150244)
					)
				)
			)
		)
		(zone
			(layers "F.Cu" "B.Cu" "In1.Cu" "In2.Cu" "In3.Cu" "In4.Cu" "In5.Cu" "In6.Cu"
				"In7.Cu" "In8.Cu" "In9.Cu" "In10.Cu" "In11.Cu" "In12.Cu" "In13.Cu" "In14.Cu"
				"In15.Cu" "In16.Cu"
			)
			(hatch none 0.5)
			(connect_pads
				(clearance 0)
			)
			(min_thickness 0.25)
			(keepout
				(tracks not_allowed)
				(vias allowed)
				(pads allowed)
				(copperpour not_allowed)
				(footprints allowed)
			)
			(placement
				(enabled no)
				(sheetname "")
			)
			(fill
				(thermal_gap 0.5)
				(thermal_bridge_width 0.5)
				(island_removal_mode 0)
			)
			(polygon
				(pts
					(arc
						(start 92.415868 -320.900044)
						(mid 86.883748 -320.900044)
						(end 92.415868 -320.900044)
					)
				)
			)
		)
		(zone
			(layer "B.Cu")
			(hatch none 0.5)
			(connect_pads
				(clearance 0)
			)
			(min_thickness 0.25)
			(keepout
				(tracks not_allowed)
				(vias allowed)
				(pads allowed)
				(copperpour not_allowed)
				(footprints allowed)
			)
			(placement
				(enabled no)
				(sheetname "")
			)
			(fill
				(thermal_gap 0.5)
				(thermal_bridge_width 0.5)
				(island_removal_mode 0)
			)
			(polygon
				(pts
					(arc
						(start 89.649808 -315.896244)
						(mid 84.646008 -320.900044)
						(end 89.649808 -325.903844)
					)
					(arc
						(start 89.649808 -325.421244)
						(mid 85.128608 -320.900044)
						(end 89.649808 -316.378844)
					)
				)
			)
		)
		(zone
			(layer "B.Cu")
			(hatch none 0.5)
			(connect_pads
				(clearance 0)
			)
			(min_thickness 0.25)
			(keepout
				(tracks not_allowed)
				(vias allowed)
				(pads allowed)
				(copperpour not_allowed)
				(footprints allowed)
			)
			(placement
				(enabled no)
				(sheetname "")
			)
			(fill
				(thermal_gap 0.5)
				(thermal_bridge_width 0.5)
				(island_removal_mode 0)
			)
			(polygon
				(pts
					(arc
						(start 89.649808 -315.896244)
						(mid 94.653608 -320.900044)
						(end 89.649808 -325.903844)
					)
					(arc
						(start 89.649808 -325.421244)
						(mid 94.171008 -320.900044)
						(end 89.649808 -316.378844)
					)
				)
			)
		)
	)
	(footprint ""
		(layer "F.Cu")
		(at 338.074 -143.891 180)
		(property "Reference" "R4835"
			(at 0 0 180)
			(layer "F.SilkS")
			(hide yes)
			(effects
				(font
					(size 1.27 1.27)
				)
			)
		)
		(property "Value" ""
			(at 0 0 180)
			(layer "F.Fab")
			(effects
				(font
					(size 1.27 1.27)
				)
			)
		)
		(duplicate_pad_numbers_are_jumpers no)
		(fp_line
			(start 0.7874 0.4064)
			(end -0.7874 0.4064)
			(stroke
				(width 0.1524)
				(type default)
			)
			(layer "F.SilkS")
		)
		(fp_line
			(start 0.7874 -0.4064)
			(end 0.7874 0.4064)
			(stroke
				(width 0.1524)
				(type default)
			)
			(layer "F.SilkS")
		)
		(fp_line
			(start -0.7874 0.4064)
			(end -0.7874 -0.4064)
			(stroke
				(width 0.1524)
				(type default)
			)
			(layer "F.SilkS")
		)
		(fp_line
			(start -0.7874 -0.4064)
			(end 0.7874 -0.4064)
			(stroke
				(width 0.1524)
				(type default)
			)
			(layer "F.SilkS")
		)
		(fp_line
			(start 0.67945 0.3048)
			(end 0.120396 0.3048)
			(stroke
				(width 0.1)
				(type default)
			)
			(layer "F.Fab")
		)
		(fp_line
			(start 0.67945 -0.3048)
			(end 0.67945 0.3048)
			(stroke
				(width 0.1)
				(type default)
			)
			(layer "F.Fab")
		)
		(fp_line
			(start 0.12065 -0.2794)
			(end 0.12065 -0.3048)
			(stroke
				(width 0.1)
				(type default)
			)
			(layer "F.Fab")
		)
		(fp_line
			(start 0.12065 -0.3048)
			(end 0.67945 -0.3048)
			(stroke
				(width 0.1)
				(type default)
			)
			(layer "F.Fab")
		)
		(fp_line
			(start 0.120396 0.3048)
			(end 0.120396 0.2794)
			(stroke
				(width 0.1)
				(type default)
			)
			(layer "F.Fab")
		)
		(fp_line
			(start 0.120396 0.2794)
			(end -0.12065 0.2794)
			(stroke
				(width 0.1)
				(type default)
			)
			(layer "F.Fab")
		)
		(fp_line
			(start -0.12065 0.3048)
			(end -0.67945 0.3048)
			(stroke
				(width 0.1)
				(type default)
			)
			(layer "F.Fab")
		)
		(fp_line
			(start -0.12065 0.2794)
			(end -0.12065 0.3048)
			(stroke
				(width 0.1)
				(type default)
			)
			(layer "F.Fab")
		)
		(fp_line
			(start -0.12065 -0.2794)
			(end 0.12065 -0.2794)
			(stroke
				(width 0.1)
				(type default)
			)
			(layer "F.Fab")
		)
		(fp_line
			(start -0.12065 -0.305054)
			(end -0.12065 -0.2794)
			(stroke
				(width 0.1)
				(type default)
			)
			(layer "F.Fab")
		)
		(fp_line
			(start -0.67945 0.3048)
			(end -0.67945 -0.305054)
			(stroke
				(width 0.1)
				(type default)
			)
			(layer "F.Fab")
		)
		(fp_line
			(start -0.67945 -0.305054)
			(end -0.12065 -0.305054)
			(stroke
				(width 0.1)
				(type default)
			)
			(layer "F.Fab")
		)
		(pad "1" smd circle
			(at -0.40005 0 180)
			(size 0 0)
			(layers "F.Cu" "F.Mask" "F.Paste")
			(net "PRSNT_SSD15_FPGA_PCA9555_N")
		)
		(pad "2" smd circle
			(at 0.40005 0 180)
			(size 0 0)
			(layers "F.Cu" "F.Mask" "F.Paste")
			(net "PRSNT_SSD15_FPGA_R_N")
		)
	)
	(footprint ""
		(layer "F.Cu")
		(at 446.096136 -47.20082 90)
		(property "Reference" "C407"
			(at 0 0 90)
			(layer "F.SilkS")
			(hide yes)
			(effects
				(font
					(size 1.27 1.27)
				)
			)
		)
		(property "Value" ""
			(at 0 0 90)
			(layer "F.Fab")
			(effects
				(font
					(size 1.27 1.27)
				)
			)
		)
		(duplicate_pad_numbers_are_jumpers no)
		(fp_line
			(start 0.7874 -0.4064)
			(end 0.7874 0.4064)
			(stroke
				(width 0.1524)
				(type default)
			)
			(layer "F.SilkS")
		)
		(fp_line
			(start -0.7874 -0.4064)
			(end 0.7874 -0.4064)
			(stroke
				(width 0.1524)
				(type default)
			)
			(layer "F.SilkS")
		)
		(fp_line
			(start 0.7874 0.4064)
			(end -0.7874 0.4064)
			(stroke
				(width 0.1524)
				(type default)
			)
			(layer "F.SilkS")
		)
		(fp_line
			(start -0.7874 0.4064)
			(end -0.7874 -0.4064)
			(stroke
				(width 0.1524)
				(type default)
			)
			(layer "F.SilkS")
		)
		(fp_line
			(start -0.12065 -0.305054)
			(end -0.12065 -0.2794)
			(stroke
				(width 0.1)
				(type default)
			)
			(layer "F.Fab")
		)
		(fp_line
			(start -0.67945 -0.305054)
			(end -0.12065 -0.305054)
			(stroke
				(width 0.1)
				(type default)
			)
			(layer "F.Fab")
		)
		(fp_line
			(start 0.67945 -0.3048)
			(end 0.67945 0.3048)
			(stroke
				(width 0.1)
				(type default)
			)
			(layer "F.Fab")
		)
		(fp_line
			(start 0.12065 -0.3048)
			(end 0.67945 -0.3048)
			(stroke
				(width 0.1)
				(type default)
			)
			(layer "F.Fab")
		)
		(fp_line
			(start 0.12065 -0.2794)
			(end 0.12065 -0.3048)
			(stroke
				(width 0.1)
				(type default)
			)
			(layer "F.Fab")
		)
		(fp_line
			(start -0.12065 -0.2794)
			(end 0.12065 -0.2794)
			(stroke
				(width 0.1)
				(type default)
			)
			(layer "F.Fab")
		)
		(fp_line
			(start 0.120396 0.2794)
			(end -0.12065 0.2794)
			(stroke
				(width 0.1)
				(type default)
			)
			(layer "F.Fab")
		)
		(fp_line
			(start -0.12065 0.2794)
			(end -0.12065 0.3048)
			(stroke
				(width 0.1)
				(type default)
			)
			(layer "F.Fab")
		)
		(fp_line
			(start 0.67945 0.3048)
			(end 0.120396 0.3048)
			(stroke
				(width 0.1)
				(type default)
			)
			(layer "F.Fab")
		)
		(fp_line
			(start 0.120396 0.3048)
			(end 0.120396 0.2794)
			(stroke
				(width 0.1)
				(type default)
			)
			(layer "F.Fab")
		)
		(fp_line
			(start -0.12065 0.3048)
			(end -0.67945 0.3048)
			(stroke
				(width 0.1)
				(type default)
			)
			(layer "F.Fab")
		)
		(fp_line
			(start -0.67945 0.3048)
			(end -0.67945 -0.305054)
			(stroke
				(width 0.1)
				(type default)
			)
			(layer "F.Fab")
		)
		(pad "1" smd circle
			(at -0.40005 0 90)
			(size 0 0)
			(layers "F.Cu" "F.Mask" "F.Paste")
			(net "P12V_SSD15_R")
		)
		(pad "2" smd circle
			(at 0.40005 0 90)
			(size 0 0)
			(layers "F.Cu" "F.Mask" "F.Paste")
			(net "GND")
		)
	)
	(footprint ""
		(layer "F.Cu")
		(at 153.104596 -140.85697 180)
		(property "Reference" "R135"
			(at 0 0 180)
			(layer "F.SilkS")
			(hide yes)
			(effects
				(font
					(size 1.27 1.27)
				)
			)
		)
		(property "Value" ""
			(at 0 0 180)
			(layer "F.Fab")
			(effects
				(font
					(size 1.27 1.27)
				)
			)
		)
		(duplicate_pad_numbers_are_jumpers no)
		(fp_line
			(start 0.7874 0.4064)
			(end -0.7874 0.4064)
			(stroke
				(width 0.1524)
				(type default)
			)
			(layer "F.SilkS")
		)
		(fp_line
			(start 0.7874 -0.4064)
			(end 0.7874 0.4064)
			(stroke
				(width 0.1524)
				(type default)
			)
			(layer "F.SilkS")
		)
		(fp_line
			(start -0.7874 0.4064)
			(end -0.7874 -0.4064)
			(stroke
				(width 0.1524)
				(type default)
			)
			(layer "F.SilkS")
		)
		(fp_line
			(start -0.7874 -0.4064)
			(end 0.7874 -0.4064)
			(stroke
				(width 0.1524)
				(type default)
			)
			(layer "F.SilkS")
		)
		(fp_line
			(start 0.67945 0.3048)
			(end 0.120396 0.3048)
			(stroke
				(width 0.1)
				(type default)
			)
			(layer "F.Fab")
		)
		(fp_line
			(start 0.67945 -0.3048)
			(end 0.67945 0.3048)
			(stroke
				(width 0.1)
				(type default)
			)
			(layer "F.Fab")
		)
		(fp_line
			(start 0.12065 -0.2794)
			(end 0.12065 -0.3048)
			(stroke
				(width 0.1)
				(type default)
			)
			(layer "F.Fab")
		)
		(fp_line
			(start 0.12065 -0.3048)
			(end 0.67945 -0.3048)
			(stroke
				(width 0.1)
				(type default)
			)
			(layer "F.Fab")
		)
		(fp_line
			(start 0.120396 0.3048)
			(end 0.120396 0.2794)
			(stroke
				(width 0.1)
				(type default)
			)
			(layer "F.Fab")
		)
		(fp_line
			(start 0.120396 0.2794)
			(end -0.12065 0.2794)
			(stroke
				(width 0.1)
				(type default)
			)
			(layer "F.Fab")
		)
		(fp_line
			(start -0.12065 0.3048)
			(end -0.67945 0.3048)
			(stroke
				(width 0.1)
				(type default)
			)
			(layer "F.Fab")
		)
		(fp_line
			(start -0.12065 0.2794)
			(end -0.12065 0.3048)
			(stroke
				(width 0.1)
				(type default)
			)
			(layer "F.Fab")
		)
		(fp_line
			(start -0.12065 -0.2794)
			(end 0.12065 -0.2794)
			(stroke
				(width 0.1)
				(type default)
			)
			(layer "F.Fab")
		)
		(fp_line
			(start -0.12065 -0.305054)
			(end -0.12065 -0.2794)
			(stroke
				(width 0.1)
				(type default)
			)
			(layer "F.Fab")
		)
		(fp_line
			(start -0.67945 0.3048)
			(end -0.67945 -0.305054)
			(stroke
				(width 0.1)
				(type default)
			)
			(layer "F.Fab")
		)
		(fp_line
			(start -0.67945 -0.305054)
			(end -0.12065 -0.305054)
			(stroke
				(width 0.1)
				(type default)
			)
			(layer "F.Fab")
		)
		(pad "1" smd circle
			(at -0.40005 0 180)
			(size 0 0)
			(layers "F.Cu" "F.Mask" "F.Paste")
			(net "NIC2_BIF2_N")
		)
		(pad "2" smd circle
			(at 0.40005 0 180)
			(size 0 0)
			(layers "F.Cu" "F.Mask" "F.Paste")
			(net "P3V3_AUX")
		)
	)
	(footprint ""
		(layer "F.Cu")
		(at 216.531952 -257.975862 -90)
		(property "Reference" "R6496"
			(at 0 0 270)
			(layer "F.SilkS")
			(hide yes)
			(effects
				(font
					(size 1.27 1.27)
				)
			)
		)
		(property "Value" ""
			(at 0 0 270)
			(layer "F.Fab")
			(effects
				(font
					(size 1.27 1.27)
				)
			)
		)
		(duplicate_pad_numbers_are_jumpers no)
		(fp_line
			(start -0.7874 0.4064)
			(end -0.7874 -0.4064)
			(stroke
				(width 0.1524)
				(type default)
			)
			(layer "F.SilkS")
		)
		(fp_line
			(start 0.7874 0.4064)
			(end -0.7874 0.4064)
			(stroke
				(width 0.1524)
				(type default)
			)
			(layer "F.SilkS")
		)
		(fp_line
			(start -0.7874 -0.4064)
			(end 0.7874 -0.4064)
			(stroke
				(width 0.1524)
				(type default)
			)
			(layer "F.SilkS")
		)
		(fp_line
			(start 0.7874 -0.4064)
			(end 0.7874 0.4064)
			(stroke
				(width 0.1524)
				(type default)
			)
			(layer "F.SilkS")
		)
		(fp_line
			(start -0.67945 0.3048)
			(end -0.67945 -0.305054)
			(stroke
				(width 0.1)
				(type default)
			)
			(layer "F.Fab")
		)
		(fp_line
			(start -0.12065 0.3048)
			(end -0.67945 0.3048)
			(stroke
				(width 0.1)
				(type default)
			)
			(layer "F.Fab")
		)
		(fp_line
			(start 0.120396 0.3048)
			(end 0.120396 0.2794)
			(stroke
				(width 0.1)
				(type default)
			)
			(layer "F.Fab")
		)
		(fp_line
			(start 0.67945 0.3048)
			(end 0.120396 0.3048)
			(stroke
				(width 0.1)
				(type default)
			)
			(layer "F.Fab")
		)
		(fp_line
			(start -0.12065 0.2794)
			(end -0.12065 0.3048)
			(stroke
				(width 0.1)
				(type default)
			)
			(layer "F.Fab")
		)
		(fp_line
			(start 0.120396 0.2794)
			(end -0.12065 0.2794)
			(stroke
				(width 0.1)
				(type default)
			)
			(layer "F.Fab")
		)
		(fp_line
			(start -0.12065 -0.2794)
			(end 0.12065 -0.2794)
			(stroke
				(width 0.1)
				(type default)
			)
			(layer "F.Fab")
		)
		(fp_line
			(start 0.12065 -0.2794)
			(end 0.12065 -0.3048)
			(stroke
				(width 0.1)
				(type default)
			)
			(layer "F.Fab")
		)
		(fp_line
			(start 0.12065 -0.3048)
			(end 0.67945 -0.3048)
			(stroke
				(width 0.1)
				(type default)
			)
			(layer "F.Fab")
		)
		(fp_line
			(start 0.67945 -0.3048)
			(end 0.67945 0.3048)
			(stroke
				(width 0.1)
				(type default)
			)
			(layer "F.Fab")
		)
		(fp_line
			(start -0.67945 -0.305054)
			(end -0.12065 -0.305054)
			(stroke
				(width 0.1)
				(type default)
			)
			(layer "F.Fab")
		)
		(fp_line
			(start -0.12065 -0.305054)
			(end -0.12065 -0.2794)
			(stroke
				(width 0.1)
				(type default)
			)
			(layer "F.Fab")
		)
		(pad "1" smd circle
			(at -0.40005 0 270)
			(size 0 0)
			(layers "F.Cu" "F.Mask" "F.Paste")
			(net "P1V25_SERDES_VDDPLL_PEX1")
		)
		(pad "2" smd circle
			(at 0.40005 0 270)
			(size 0 0)
			(layers "F.Cu" "F.Mask" "F.Paste")
			(net "P1V25_SERDES_VDDPLL_PEX1_C5")
		)
	)
	(footprint ""
		(layer "F.Cu")
		(at 279.459182 -402.338032 90)
		(property "Reference" "R1808"
			(at 0 0 90)
			(layer "F.SilkS")
			(hide yes)
			(effects
				(font
					(size 1.27 1.27)
				)
			)
		)
		(property "Value" ""
			(at 0 0 90)
			(layer "F.Fab")
			(effects
				(font
					(size 1.27 1.27)
				)
			)
		)
		(duplicate_pad_numbers_are_jumpers no)
		(fp_line
			(start 0.7874 -0.4064)
			(end 0.7874 0.4064)
			(stroke
				(width 0.1524)
				(type default)
			)
			(layer "F.SilkS")
		)
		(fp_line
			(start -0.7874 -0.4064)
			(end 0.7874 -0.4064)
			(stroke
				(width 0.1524)
				(type default)
			)
			(layer "F.SilkS")
		)
		(fp_line
			(start 0.7874 0.4064)
			(end -0.7874 0.4064)
			(stroke
				(width 0.1524)
				(type default)
			)
			(layer "F.SilkS")
		)
		(fp_line
			(start -0.7874 0.4064)
			(end -0.7874 -0.4064)
			(stroke
				(width 0.1524)
				(type default)
			)
			(layer "F.SilkS")
		)
		(fp_line
			(start -0.12065 -0.305054)
			(end -0.12065 -0.2794)
			(stroke
				(width 0.1)
				(type default)
			)
			(layer "F.Fab")
		)
		(fp_line
			(start -0.67945 -0.305054)
			(end -0.12065 -0.305054)
			(stroke
				(width 0.1)
				(type default)
			)
			(layer "F.Fab")
		)
		(fp_line
			(start 0.67945 -0.3048)
			(end 0.67945 0.3048)
			(stroke
				(width 0.1)
				(type default)
			)
			(layer "F.Fab")
		)
		(fp_line
			(start 0.12065 -0.3048)
			(end 0.67945 -0.3048)
			(stroke
				(width 0.1)
				(type default)
			)
			(layer "F.Fab")
		)
		(fp_line
			(start 0.12065 -0.2794)
			(end 0.12065 -0.3048)
			(stroke
				(width 0.1)
				(type default)
			)
			(layer "F.Fab")
		)
		(fp_line
			(start -0.12065 -0.2794)
			(end 0.12065 -0.2794)
			(stroke
				(width 0.1)
				(type default)
			)
			(layer "F.Fab")
		)
		(fp_line
			(start 0.120396 0.2794)
			(end -0.12065 0.2794)
			(stroke
				(width 0.1)
				(type default)
			)
			(layer "F.Fab")
		)
		(fp_line
			(start -0.12065 0.2794)
			(end -0.12065 0.3048)
			(stroke
				(width 0.1)
				(type default)
			)
			(layer "F.Fab")
		)
		(fp_line
			(start 0.67945 0.3048)
			(end 0.120396 0.3048)
			(stroke
				(width 0.1)
				(type default)
			)
			(layer "F.Fab")
		)
		(fp_line
			(start 0.120396 0.3048)
			(end 0.120396 0.2794)
			(stroke
				(width 0.1)
				(type default)
			)
			(layer "F.Fab")
		)
		(fp_line
			(start -0.12065 0.3048)
			(end -0.67945 0.3048)
			(stroke
				(width 0.1)
				(type default)
			)
			(layer "F.Fab")
		)
		(fp_line
			(start -0.67945 0.3048)
			(end -0.67945 -0.305054)
			(stroke
				(width 0.1)
				(type default)
			)
			(layer "F.Fab")
		)
		(pad "1" smd circle
			(at -0.40005 0 90)
			(size 0 0)
			(layers "F.Cu" "F.Mask" "F.Paste")
			(net "RST_MB_BIC_ISO_N")
		)
		(pad "2" smd circle
			(at 0.40005 0 90)
			(size 0 0)
			(layers "F.Cu" "F.Mask" "F.Paste")
			(net "RST_MB_BIC_ISO_R_N")
		)
	)
	(footprint ""
		(layer "F.Cu")
		(at 191.756538 -20.467574 180)
		(property "Reference" "R1675"
			(at 0 0 180)
			(layer "F.SilkS")
			(hide yes)
			(effects
				(font
					(size 1.27 1.27)
				)
			)
		)
		(property "Value" ""
			(at 0 0 180)
			(layer "F.Fab")
			(effects
				(font
					(size 1.27 1.27)
				)
			)
		)
		(duplicate_pad_numbers_are_jumpers no)
		(fp_line
			(start 0.7874 0.4064)
			(end -0.7874 0.4064)
			(stroke
				(width 0.1524)
				(type default)
			)
			(layer "F.SilkS")
		)
		(fp_line
			(start 0.7874 -0.4064)
			(end 0.7874 0.4064)
			(stroke
				(width 0.1524)
				(type default)
			)
			(layer "F.SilkS")
		)
		(fp_line
			(start -0.7874 0.4064)
			(end -0.7874 -0.4064)
			(stroke
				(width 0.1524)
				(type default)
			)
			(layer "F.SilkS")
		)
		(fp_line
			(start -0.7874 -0.4064)
			(end 0.7874 -0.4064)
			(stroke
				(width 0.1524)
				(type default)
			)
			(layer "F.SilkS")
		)
		(fp_line
			(start 0.67945 0.3048)
			(end 0.120396 0.3048)
			(stroke
				(width 0.1)
				(type default)
			)
			(layer "F.Fab")
		)
		(fp_line
			(start 0.67945 -0.3048)
			(end 0.67945 0.3048)
			(stroke
				(width 0.1)
				(type default)
			)
			(layer "F.Fab")
		)
		(fp_line
			(start 0.12065 -0.2794)
			(end 0.12065 -0.3048)
			(stroke
				(width 0.1)
				(type default)
			)
			(layer "F.Fab")
		)
		(fp_line
			(start 0.12065 -0.3048)
			(end 0.67945 -0.3048)
			(stroke
				(width 0.1)
				(type default)
			)
			(layer "F.Fab")
		)
		(fp_line
			(start 0.120396 0.3048)
			(end 0.120396 0.2794)
			(stroke
				(width 0.1)
				(type default)
			)
			(layer "F.Fab")
		)
		(fp_line
			(start 0.120396 0.2794)
			(end -0.12065 0.2794)
			(stroke
				(width 0.1)
				(type default)
			)
			(layer "F.Fab")
		)
		(fp_line
			(start -0.12065 0.3048)
			(end -0.67945 0.3048)
			(stroke
				(width 0.1)
				(type default)
			)
			(layer "F.Fab")
		)
		(fp_line
			(start -0.12065 0.2794)
			(end -0.12065 0.3048)
			(stroke
				(width 0.1)
				(type default)
			)
			(layer "F.Fab")
		)
		(fp_line
			(start -0.12065 -0.2794)
			(end 0.12065 -0.2794)
			(stroke
				(width 0.1)
				(type default)
			)
			(layer "F.Fab")
		)
		(fp_line
			(start -0.12065 -0.305054)
			(end -0.12065 -0.2794)
			(stroke
				(width 0.1)
				(type default)
			)
			(layer "F.Fab")
		)
		(fp_line
			(start -0.67945 0.3048)
			(end -0.67945 -0.305054)
			(stroke
				(width 0.1)
				(type default)
			)
			(layer "F.Fab")
		)
		(fp_line
			(start -0.67945 -0.305054)
			(end -0.12065 -0.305054)
			(stroke
				(width 0.1)
				(type default)
			)
			(layer "F.Fab")
		)
		(pad "1" smd circle
			(at -0.40005 0 180)
			(size 0 0)
			(layers "F.Cu" "F.Mask" "F.Paste")
			(net "P3V3_SSD6")
		)
		(pad "2" smd circle
			(at 0.40005 0 180)
			(size 0 0)
			(layers "F.Cu" "F.Mask" "F.Paste")
			(net "SMB_ISO_SSD6_SDA")
		)
	)
	(footprint ""
		(layer "F.Cu")
		(at 329.93838 -44.341542 90)
		(property "Reference" "C332"
			(at 0 0 90)
			(layer "F.SilkS")
			(hide yes)
			(effects
				(font
					(size 1.27 1.27)
				)
			)
		)
		(property "Value" ""
			(at 0 0 90)
			(layer "F.Fab")
			(effects
				(font
					(size 1.27 1.27)
				)
			)
		)
		(duplicate_pad_numbers_are_jumpers no)
		(fp_line
			(start 0.7874 -0.4064)
			(end 0.7874 0.4064)
			(stroke
				(width 0.1524)
				(type default)
			)
			(layer "F.SilkS")
		)
		(fp_line
			(start -0.7874 -0.4064)
			(end 0.7874 -0.4064)
			(stroke
				(width 0.1524)
				(type default)
			)
			(layer "F.SilkS")
		)
		(fp_line
			(start 0.7874 0.4064)
			(end -0.7874 0.4064)
			(stroke
				(width 0.1524)
				(type default)
			)
			(layer "F.SilkS")
		)
		(fp_line
			(start -0.7874 0.4064)
			(end -0.7874 -0.4064)
			(stroke
				(width 0.1524)
				(type default)
			)
			(layer "F.SilkS")
		)
		(fp_line
			(start -0.12065 -0.305054)
			(end -0.12065 -0.2794)
			(stroke
				(width 0.1)
				(type default)
			)
			(layer "F.Fab")
		)
		(fp_line
			(start -0.67945 -0.305054)
			(end -0.12065 -0.305054)
			(stroke
				(width 0.1)
				(type default)
			)
			(layer "F.Fab")
		)
		(fp_line
			(start 0.67945 -0.3048)
			(end 0.67945 0.3048)
			(stroke
				(width 0.1)
				(type default)
			)
			(layer "F.Fab")
		)
		(fp_line
			(start 0.12065 -0.3048)
			(end 0.67945 -0.3048)
			(stroke
				(width 0.1)
				(type default)
			)
			(layer "F.Fab")
		)
		(fp_line
			(start 0.12065 -0.2794)
			(end 0.12065 -0.3048)
			(stroke
				(width 0.1)
				(type default)
			)
			(layer "F.Fab")
		)
		(fp_line
			(start -0.12065 -0.2794)
			(end 0.12065 -0.2794)
			(stroke
				(width 0.1)
				(type default)
			)
			(layer "F.Fab")
		)
		(fp_line
			(start 0.120396 0.2794)
			(end -0.12065 0.2794)
			(stroke
				(width 0.1)
				(type default)
			)
			(layer "F.Fab")
		)
		(fp_line
			(start -0.12065 0.2794)
			(end -0.12065 0.3048)
			(stroke
				(width 0.1)
				(type default)
			)
			(layer "F.Fab")
		)
		(fp_line
			(start 0.67945 0.3048)
			(end 0.120396 0.3048)
			(stroke
				(width 0.1)
				(type default)
			)
			(layer "F.Fab")
		)
		(fp_line
			(start 0.120396 0.3048)
			(end 0.120396 0.2794)
			(stroke
				(width 0.1)
				(type default)
			)
			(layer "F.Fab")
		)
		(fp_line
			(start -0.12065 0.3048)
			(end -0.67945 0.3048)
			(stroke
				(width 0.1)
				(type default)
			)
			(layer "F.Fab")
		)
		(fp_line
			(start -0.67945 0.3048)
			(end -0.67945 -0.305054)
			(stroke
				(width 0.1)
				(type default)
			)
			(layer "F.Fab")
		)
		(pad "1" smd circle
			(at -0.40005 0 90)
			(size 0 0)
			(layers "F.Cu" "F.Mask" "F.Paste")
			(net "P12V_SSD11_VIN_P")
		)
		(pad "2" smd circle
			(at 0.40005 0 90)
			(size 0 0)
			(layers "F.Cu" "F.Mask" "F.Paste")
			(net "P12V_SSD11_VIN_N")
		)
	)
	(footprint ""
		(layer "F.Cu")
		(at 90.018108 -306.074572 90)
		(property "Reference" "R1237"
			(at 0 0 90)
			(layer "F.SilkS")
			(hide yes)
			(effects
				(font
					(size 1.27 1.27)
				)
			)
		)
		(property "Value" ""
			(at 0 0 90)
			(layer "F.Fab")
			(effects
				(font
					(size 1.27 1.27)
				)
			)
		)
		(duplicate_pad_numbers_are_jumpers no)
		(fp_line
			(start 0.7874 -0.4064)
			(end 0.7874 0.4064)
			(stroke
				(width 0.1524)
				(type default)
			)
			(layer "F.SilkS")
		)
		(fp_line
			(start -0.7874 -0.4064)
			(end 0.7874 -0.4064)
			(stroke
				(width 0.1524)
				(type default)
			)
			(layer "F.SilkS")
		)
		(fp_line
			(start 0.7874 0.4064)
			(end -0.7874 0.4064)
			(stroke
				(width 0.1524)
				(type default)
			)
			(layer "F.SilkS")
		)
		(fp_line
			(start -0.7874 0.4064)
			(end -0.7874 -0.4064)
			(stroke
				(width 0.1524)
				(type default)
			)
			(layer "F.SilkS")
		)
		(fp_line
			(start -0.12065 -0.305054)
			(end -0.12065 -0.2794)
			(stroke
				(width 0.1)
				(type default)
			)
			(layer "F.Fab")
		)
		(fp_line
			(start -0.67945 -0.305054)
			(end -0.12065 -0.305054)
			(stroke
				(width 0.1)
				(type default)
			)
			(layer "F.Fab")
		)
		(fp_line
			(start 0.67945 -0.3048)
			(end 0.67945 0.3048)
			(stroke
				(width 0.1)
				(type default)
			)
			(layer "F.Fab")
		)
		(fp_line
			(start 0.12065 -0.3048)
			(end 0.67945 -0.3048)
			(stroke
				(width 0.1)
				(type default)
			)
			(layer "F.Fab")
		)
		(fp_line
			(start 0.12065 -0.2794)
			(end 0.12065 -0.3048)
			(stroke
				(width 0.1)
				(type default)
			)
			(layer "F.Fab")
		)
		(fp_line
			(start -0.12065 -0.2794)
			(end 0.12065 -0.2794)
			(stroke
				(width 0.1)
				(type default)
			)
			(layer "F.Fab")
		)
		(fp_line
			(start 0.120396 0.2794)
			(end -0.12065 0.2794)
			(stroke
				(width 0.1)
				(type default)
			)
			(layer "F.Fab")
		)
		(fp_line
			(start -0.12065 0.2794)
			(end -0.12065 0.3048)
			(stroke
				(width 0.1)
				(type default)
			)
			(layer "F.Fab")
		)
		(fp_line
			(start 0.67945 0.3048)
			(end 0.120396 0.3048)
			(stroke
				(width 0.1)
				(type default)
			)
			(layer "F.Fab")
		)
		(fp_line
			(start 0.120396 0.3048)
			(end 0.120396 0.2794)
			(stroke
				(width 0.1)
				(type default)
			)
			(layer "F.Fab")
		)
		(fp_line
			(start -0.12065 0.3048)
			(end -0.67945 0.3048)
			(stroke
				(width 0.1)
				(type default)
			)
			(layer "F.Fab")
		)
		(fp_line
			(start -0.67945 0.3048)
			(end -0.67945 -0.305054)
			(stroke
				(width 0.1)
				(type default)
			)
			(layer "F.Fab")
		)
		(pad "1" smd circle
			(at -0.40005 0 90)
			(size 0 0)
			(layers "F.Cu" "F.Mask" "F.Paste")
			(net "PEX0_SPARE3")
		)
		(pad "2" smd circle
			(at 0.40005 0 90)
			(size 0 0)
			(layers "F.Cu" "F.Mask" "F.Paste")
			(net "P1V8_PEX")
		)
	)
	(footprint ""
		(layer "F.Cu")
		(at 82.7151 -59.546236 90)
		(property "Reference" "C2892"
			(at 0 0 90)
			(layer "F.SilkS")
			(hide yes)
			(effects
				(font
					(size 1.27 1.27)
				)
			)
		)
		(property "Value" ""
			(at 0 0 90)
			(layer "F.Fab")
			(effects
				(font
					(size 1.27 1.27)
				)
			)
		)
		(duplicate_pad_numbers_are_jumpers no)
		(fp_line
			(start 0.7874 -0.4064)
			(end 0.7874 0.4064)
			(stroke
				(width 0.1524)
				(type default)
			)
			(layer "F.SilkS")
		)
		(fp_line
			(start -0.7874 -0.4064)
			(end 0.7874 -0.4064)
			(stroke
				(width 0.1524)
				(type default)
			)
			(layer "F.SilkS")
		)
		(fp_line
			(start 0.7874 0.4064)
			(end -0.7874 0.4064)
			(stroke
				(width 0.1524)
				(type default)
			)
			(layer "F.SilkS")
		)
		(fp_line
			(start -0.7874 0.4064)
			(end -0.7874 -0.4064)
			(stroke
				(width 0.1524)
				(type default)
			)
			(layer "F.SilkS")
		)
		(fp_line
			(start -0.12065 -0.305054)
			(end -0.12065 -0.2794)
			(stroke
				(width 0.1)
				(type default)
			)
			(layer "F.Fab")
		)
		(fp_line
			(start -0.67945 -0.305054)
			(end -0.12065 -0.305054)
			(stroke
				(width 0.1)
				(type default)
			)
			(layer "F.Fab")
		)
		(fp_line
			(start 0.67945 -0.3048)
			(end 0.67945 0.3048)
			(stroke
				(width 0.1)
				(type default)
			)
			(layer "F.Fab")
		)
		(fp_line
			(start 0.12065 -0.3048)
			(end 0.67945 -0.3048)
			(stroke
				(width 0.1)
				(type default)
			)
			(layer "F.Fab")
		)
		(fp_line
			(start 0.12065 -0.2794)
			(end 0.12065 -0.3048)
			(stroke
				(width 0.1)
				(type default)
			)
			(layer "F.Fab")
		)
		(fp_line
			(start -0.12065 -0.2794)
			(end 0.12065 -0.2794)
			(stroke
				(width 0.1)
				(type default)
			)
			(layer "F.Fab")
		)
		(fp_line
			(start 0.120396 0.2794)
			(end -0.12065 0.2794)
			(stroke
				(width 0.1)
				(type default)
			)
			(layer "F.Fab")
		)
		(fp_line
			(start -0.12065 0.2794)
			(end -0.12065 0.3048)
			(stroke
				(width 0.1)
				(type default)
			)
			(layer "F.Fab")
		)
		(fp_line
			(start 0.67945 0.3048)
			(end 0.120396 0.3048)
			(stroke
				(width 0.1)
				(type default)
			)
			(layer "F.Fab")
		)
		(fp_line
			(start 0.120396 0.3048)
			(end 0.120396 0.2794)
			(stroke
				(width 0.1)
				(type default)
			)
			(layer "F.Fab")
		)
		(fp_line
			(start -0.12065 0.3048)
			(end -0.67945 0.3048)
			(stroke
				(width 0.1)
				(type default)
			)
			(layer "F.Fab")
		)
		(fp_line
			(start -0.67945 0.3048)
			(end -0.67945 -0.305054)
			(stroke
				(width 0.1)
				(type default)
			)
			(layer "F.Fab")
		)
		(pad "1" smd circle
			(at -0.40005 0 90)
			(size 0 0)
			(layers "F.Cu" "F.Mask" "F.Paste")
			(net "SSD3_AUX_P3V3_EN_R")
		)
		(pad "2" smd circle
			(at 0.40005 0 90)
			(size 0 0)
			(layers "F.Cu" "F.Mask" "F.Paste")
			(net "GND")
		)
	)
	(footprint ""
		(layer "F.Cu")
		(at 374.543828 -46.90491)
		(property "Reference" "R642"
			(at 0 0 0)
			(layer "F.SilkS")
			(hide yes)
			(effects
				(font
					(size 1.27 1.27)
				)
			)
		)
		(property "Value" ""
			(at 0 0 0)
			(layer "F.Fab")
			(effects
				(font
					(size 1.27 1.27)
				)
			)
		)
		(duplicate_pad_numbers_are_jumpers no)
		(fp_line
			(start -0.7874 -0.4064)
			(end 0.7874 -0.4064)
			(stroke
				(width 0.1524)
				(type default)
			)
			(layer "F.SilkS")
		)
		(fp_line
			(start -0.7874 0.4064)
			(end -0.7874 -0.4064)
			(stroke
				(width 0.1524)
				(type default)
			)
			(layer "F.SilkS")
		)
		(fp_line
			(start 0.7874 -0.4064)
			(end 0.7874 0.4064)
			(stroke
				(width 0.1524)
				(type default)
			)
			(layer "F.SilkS")
		)
		(fp_line
			(start 0.7874 0.4064)
			(end -0.7874 0.4064)
			(stroke
				(width 0.1524)
				(type default)
			)
			(layer "F.SilkS")
		)
		(fp_line
			(start -0.67945 -0.305054)
			(end -0.12065 -0.305054)
			(stroke
				(width 0.1)
				(type default)
			)
			(layer "F.Fab")
		)
		(fp_line
			(start -0.67945 0.3048)
			(end -0.67945 -0.305054)
			(stroke
				(width 0.1)
				(type default)
			)
			(layer "F.Fab")
		)
		(fp_line
			(start -0.12065 -0.305054)
			(end -0.12065 -0.2794)
			(stroke
				(width 0.1)
				(type default)
			)
			(layer "F.Fab")
		)
		(fp_line
			(start -0.12065 -0.2794)
			(end 0.12065 -0.2794)
			(stroke
				(width 0.1)
				(type default)
			)
			(layer "F.Fab")
		)
		(fp_line
			(start -0.12065 0.2794)
			(end -0.12065 0.3048)
			(stroke
				(width 0.1)
				(type default)
			)
			(layer "F.Fab")
		)
		(fp_line
			(start -0.12065 0.3048)
			(end -0.67945 0.3048)
			(stroke
				(width 0.1)
				(type default)
			)
			(layer "F.Fab")
		)
		(fp_line
			(start 0.120396 0.2794)
			(end -0.12065 0.2794)
			(stroke
				(width 0.1)
				(type default)
			)
			(layer "F.Fab")
		)
		(fp_line
			(start 0.120396 0.3048)
			(end 0.120396 0.2794)
			(stroke
				(width 0.1)
				(type default)
			)
			(layer "F.Fab")
		)
		(fp_line
			(start 0.12065 -0.3048)
			(end 0.67945 -0.3048)
			(stroke
				(width 0.1)
				(type default)
			)
			(layer "F.Fab")
		)
		(fp_line
			(start 0.12065 -0.2794)
			(end 0.12065 -0.3048)
			(stroke
				(width 0.1)
				(type default)
			)
			(layer "F.Fab")
		)
		(fp_line
			(start 0.67945 -0.3048)
			(end 0.67945 0.3048)
			(stroke
				(width 0.1)
				(type default)
			)
			(layer "F.Fab")
		)
		(fp_line
			(start 0.67945 0.3048)
			(end 0.120396 0.3048)
			(stroke
				(width 0.1)
				(type default)
			)
			(layer "F.Fab")
		)
		(pad "1" smd circle
			(at -0.40005 0)
			(size 0 0)
			(layers "F.Cu" "F.Mask" "F.Paste")
			(net "SSD12_ADC_ALERT_N")
		)
		(pad "2" smd circle
			(at 0.40005 0)
			(size 0 0)
			(layers "F.Cu" "F.Mask" "F.Paste")
			(net "SSD_8_15_ADC_ALERT_N")
		)
	)
	(footprint ""
		(layer "F.Cu")
		(at 104.243632 -49.95291 180)
		(property "Reference" "R544"
			(at 0 0 180)
			(layer "F.SilkS")
			(hide yes)
			(effects
				(font
					(size 1.27 1.27)
				)
			)
		)
		(property "Value" ""
			(at 0 0 180)
			(layer "F.Fab")
			(effects
				(font
					(size 1.27 1.27)
				)
			)
		)
		(duplicate_pad_numbers_are_jumpers no)
		(fp_line
			(start 0.7874 0.4064)
			(end -0.7874 0.4064)
			(stroke
				(width 0.1524)
				(type default)
			)
			(layer "F.SilkS")
		)
		(fp_line
			(start 0.7874 -0.4064)
			(end 0.7874 0.4064)
			(stroke
				(width 0.1524)
				(type default)
			)
			(layer "F.SilkS")
		)
		(fp_line
			(start -0.7874 0.4064)
			(end -0.7874 -0.4064)
			(stroke
				(width 0.1524)
				(type default)
			)
			(layer "F.SilkS")
		)
		(fp_line
			(start -0.7874 -0.4064)
			(end 0.7874 -0.4064)
			(stroke
				(width 0.1524)
				(type default)
			)
			(layer "F.SilkS")
		)
		(fp_line
			(start 0.67945 0.3048)
			(end 0.120396 0.3048)
			(stroke
				(width 0.1)
				(type default)
			)
			(layer "F.Fab")
		)
		(fp_line
			(start 0.67945 -0.3048)
			(end 0.67945 0.3048)
			(stroke
				(width 0.1)
				(type default)
			)
			(layer "F.Fab")
		)
		(fp_line
			(start 0.12065 -0.2794)
			(end 0.12065 -0.3048)
			(stroke
				(width 0.1)
				(type default)
			)
			(layer "F.Fab")
		)
		(fp_line
			(start 0.12065 -0.3048)
			(end 0.67945 -0.3048)
			(stroke
				(width 0.1)
				(type default)
			)
			(layer "F.Fab")
		)
		(fp_line
			(start 0.120396 0.3048)
			(end 0.120396 0.2794)
			(stroke
				(width 0.1)
				(type default)
			)
			(layer "F.Fab")
		)
		(fp_line
			(start 0.120396 0.2794)
			(end -0.12065 0.2794)
			(stroke
				(width 0.1)
				(type default)
			)
			(layer "F.Fab")
		)
		(fp_line
			(start -0.12065 0.3048)
			(end -0.67945 0.3048)
			(stroke
				(width 0.1)
				(type default)
			)
			(layer "F.Fab")
		)
		(fp_line
			(start -0.12065 0.2794)
			(end -0.12065 0.3048)
			(stroke
				(width 0.1)
				(type default)
			)
			(layer "F.Fab")
		)
		(fp_line
			(start -0.12065 -0.2794)
			(end 0.12065 -0.2794)
			(stroke
				(width 0.1)
				(type default)
			)
			(layer "F.Fab")
		)
		(fp_line
			(start -0.12065 -0.305054)
			(end -0.12065 -0.2794)
			(stroke
				(width 0.1)
				(type default)
			)
			(layer "F.Fab")
		)
		(fp_line
			(start -0.67945 0.3048)
			(end -0.67945 -0.305054)
			(stroke
				(width 0.1)
				(type default)
			)
			(layer "F.Fab")
		)
		(fp_line
			(start -0.67945 -0.305054)
			(end -0.12065 -0.305054)
			(stroke
				(width 0.1)
				(type default)
			)
			(layer "F.Fab")
		)
		(pad "1" smd circle
			(at -0.40005 0 180)
			(size 0 0)
			(layers "F.Cu" "F.Mask" "F.Paste")
			(net "SMB_BIC_I2C6_MUX_SSD_0_7_ADC_R_SCL")
		)
		(pad "2" smd circle
			(at 0.40005 0 180)
			(size 0 0)
			(layers "F.Cu" "F.Mask" "F.Paste")
			(net "SMB_SSD3_ADC_SCL")
		)
	)
	(footprint ""
		(layer "F.Cu")
		(at 339.979 -234.061 90)
		(property "Reference" "R3596"
			(at 0 0 90)
			(layer "F.SilkS")
			(hide yes)
			(effects
				(font
					(size 1.27 1.27)
				)
			)
		)
		(property "Value" ""
			(at 0 0 90)
			(layer "F.Fab")
			(effects
				(font
					(size 1.27 1.27)
				)
			)
		)
		(duplicate_pad_numbers_are_jumpers no)
		(fp_line
			(start 0.7874 -0.4064)
			(end 0.7874 0.4064)
			(stroke
				(width 0.1524)
				(type default)
			)
			(layer "F.SilkS")
		)
		(fp_line
			(start -0.7874 -0.4064)
			(end 0.7874 -0.4064)
			(stroke
				(width 0.1524)
				(type default)
			)
			(layer "F.SilkS")
		)
		(fp_line
			(start 0.7874 0.4064)
			(end -0.7874 0.4064)
			(stroke
				(width 0.1524)
				(type default)
			)
			(layer "F.SilkS")
		)
		(fp_line
			(start -0.7874 0.4064)
			(end -0.7874 -0.4064)
			(stroke
				(width 0.1524)
				(type default)
			)
			(layer "F.SilkS")
		)
		(fp_line
			(start -0.12065 -0.305054)
			(end -0.12065 -0.2794)
			(stroke
				(width 0.1)
				(type default)
			)
			(layer "F.Fab")
		)
		(fp_line
			(start -0.67945 -0.305054)
			(end -0.12065 -0.305054)
			(stroke
				(width 0.1)
				(type default)
			)
			(layer "F.Fab")
		)
		(fp_line
			(start 0.67945 -0.3048)
			(end 0.67945 0.3048)
			(stroke
				(width 0.1)
				(type default)
			)
			(layer "F.Fab")
		)
		(fp_line
			(start 0.12065 -0.3048)
			(end 0.67945 -0.3048)
			(stroke
				(width 0.1)
				(type default)
			)
			(layer "F.Fab")
		)
		(fp_line
			(start 0.12065 -0.2794)
			(end 0.12065 -0.3048)
			(stroke
				(width 0.1)
				(type default)
			)
			(layer "F.Fab")
		)
		(fp_line
			(start -0.12065 -0.2794)
			(end 0.12065 -0.2794)
			(stroke
				(width 0.1)
				(type default)
			)
			(layer "F.Fab")
		)
		(fp_line
			(start 0.120396 0.2794)
			(end -0.12065 0.2794)
			(stroke
				(width 0.1)
				(type default)
			)
			(layer "F.Fab")
		)
		(fp_line
			(start -0.12065 0.2794)
			(end -0.12065 0.3048)
			(stroke
				(width 0.1)
				(type default)
			)
			(layer "F.Fab")
		)
		(fp_line
			(start 0.67945 0.3048)
			(end 0.120396 0.3048)
			(stroke
				(width 0.1)
				(type default)
			)
			(layer "F.Fab")
		)
		(fp_line
			(start 0.120396 0.3048)
			(end 0.120396 0.2794)
			(stroke
				(width 0.1)
				(type default)
			)
			(layer "F.Fab")
		)
		(fp_line
			(start -0.12065 0.3048)
			(end -0.67945 0.3048)
			(stroke
				(width 0.1)
				(type default)
			)
			(layer "F.Fab")
		)
		(fp_line
			(start -0.67945 0.3048)
			(end -0.67945 -0.305054)
			(stroke
				(width 0.1)
				(type default)
			)
			(layer "F.Fab")
		)
		(pad "1" smd circle
			(at -0.40005 0 90)
			(size 0 0)
			(layers "F.Cu" "F.Mask" "F.Paste")
			(net "SSD1_PWRDIS")
		)
		(pad "2" smd circle
			(at 0.40005 0 90)
			(size 0 0)
			(layers "F.Cu" "F.Mask" "F.Paste")
			(net "SSD1_PWRDIS_R")
		)
	)
	(footprint ""
		(layer "F.Cu")
		(at 361.89031 -259.147564 180)
		(property "Reference" "R840"
			(at 0 0 180)
			(layer "F.SilkS")
			(hide yes)
			(effects
				(font
					(size 1.27 1.27)
				)
			)
		)
		(property "Value" ""
			(at 0 0 180)
			(layer "F.Fab")
			(effects
				(font
					(size 1.27 1.27)
				)
			)
		)
		(duplicate_pad_numbers_are_jumpers no)
		(fp_line
			(start 0.7874 0.4064)
			(end -0.7874 0.4064)
			(stroke
				(width 0.1524)
				(type default)
			)
			(layer "F.SilkS")
		)
		(fp_line
			(start 0.7874 -0.4064)
			(end 0.7874 0.4064)
			(stroke
				(width 0.1524)
				(type default)
			)
			(layer "F.SilkS")
		)
		(fp_line
			(start -0.7874 0.4064)
			(end -0.7874 -0.4064)
			(stroke
				(width 0.1524)
				(type default)
			)
			(layer "F.SilkS")
		)
		(fp_line
			(start -0.7874 -0.4064)
			(end 0.7874 -0.4064)
			(stroke
				(width 0.1524)
				(type default)
			)
			(layer "F.SilkS")
		)
		(fp_line
			(start 0.67945 0.3048)
			(end 0.120396 0.3048)
			(stroke
				(width 0.1)
				(type default)
			)
			(layer "F.Fab")
		)
		(fp_line
			(start 0.67945 -0.3048)
			(end 0.67945 0.3048)
			(stroke
				(width 0.1)
				(type default)
			)
			(layer "F.Fab")
		)
		(fp_line
			(start 0.12065 -0.2794)
			(end 0.12065 -0.3048)
			(stroke
				(width 0.1)
				(type default)
			)
			(layer "F.Fab")
		)
		(fp_line
			(start 0.12065 -0.3048)
			(end 0.67945 -0.3048)
			(stroke
				(width 0.1)
				(type default)
			)
			(layer "F.Fab")
		)
		(fp_line
			(start 0.120396 0.3048)
			(end 0.120396 0.2794)
			(stroke
				(width 0.1)
				(type default)
			)
			(layer "F.Fab")
		)
		(fp_line
			(start 0.120396 0.2794)
			(end -0.12065 0.2794)
			(stroke
				(width 0.1)
				(type default)
			)
			(layer "F.Fab")
		)
		(fp_line
			(start -0.12065 0.3048)
			(end -0.67945 0.3048)
			(stroke
				(width 0.1)
				(type default)
			)
			(layer "F.Fab")
		)
		(fp_line
			(start -0.12065 0.2794)
			(end -0.12065 0.3048)
			(stroke
				(width 0.1)
				(type default)
			)
			(layer "F.Fab")
		)
		(fp_line
			(start -0.12065 -0.2794)
			(end 0.12065 -0.2794)
			(stroke
				(width 0.1)
				(type default)
			)
			(layer "F.Fab")
		)
		(fp_line
			(start -0.12065 -0.305054)
			(end -0.12065 -0.2794)
			(stroke
				(width 0.1)
				(type default)
			)
			(layer "F.Fab")
		)
		(fp_line
			(start -0.67945 0.3048)
			(end -0.67945 -0.305054)
			(stroke
				(width 0.1)
				(type default)
			)
			(layer "F.Fab")
		)
		(fp_line
			(start -0.67945 -0.305054)
			(end -0.12065 -0.305054)
			(stroke
				(width 0.1)
				(type default)
			)
			(layer "F.Fab")
		)
		(pad "1" smd circle
			(at -0.40005 0 180)
			(size 0 0)
			(layers "F.Cu" "F.Mask" "F.Paste")
			(net "PWRGD_P0V8_PEX3_R")
		)
		(pad "2" smd circle
			(at 0.40005 0 180)
			(size 0 0)
			(layers "F.Cu" "F.Mask" "F.Paste")
			(net "P0V8_PEX3_BVRRDY")
		)
	)
	(footprint ""
		(layer "F.Cu")
		(at 121.441972 -119.071136)
		(property "Reference" "PR6854"
			(at 0 0 0)
			(layer "F.SilkS")
			(hide yes)
			(effects
				(font
					(size 1.27 1.27)
				)
			)
		)
		(property "Value" ""
			(at 0 0 0)
			(layer "F.Fab")
			(effects
				(font
					(size 1.27 1.27)
				)
			)
		)
		(duplicate_pad_numbers_are_jumpers no)
		(fp_line
			(start -0.7874 -0.4064)
			(end 0.7874 -0.4064)
			(stroke
				(width 0.1524)
				(type default)
			)
			(layer "F.SilkS")
		)
		(fp_line
			(start -0.7874 0.4064)
			(end -0.7874 -0.4064)
			(stroke
				(width 0.1524)
				(type default)
			)
			(layer "F.SilkS")
		)
		(fp_line
			(start 0.7874 -0.4064)
			(end 0.7874 0.4064)
			(stroke
				(width 0.1524)
				(type default)
			)
			(layer "F.SilkS")
		)
		(fp_line
			(start 0.7874 0.4064)
			(end -0.7874 0.4064)
			(stroke
				(width 0.1524)
				(type default)
			)
			(layer "F.SilkS")
		)
		(fp_line
			(start -0.67945 -0.305054)
			(end -0.12065 -0.305054)
			(stroke
				(width 0.1)
				(type default)
			)
			(layer "F.Fab")
		)
		(fp_line
			(start -0.67945 0.3048)
			(end -0.67945 -0.305054)
			(stroke
				(width 0.1)
				(type default)
			)
			(layer "F.Fab")
		)
		(fp_line
			(start -0.12065 -0.305054)
			(end -0.12065 -0.2794)
			(stroke
				(width 0.1)
				(type default)
			)
			(layer "F.Fab")
		)
		(fp_line
			(start -0.12065 -0.2794)
			(end 0.12065 -0.2794)
			(stroke
				(width 0.1)
				(type default)
			)
			(layer "F.Fab")
		)
		(fp_line
			(start -0.12065 0.2794)
			(end -0.12065 0.3048)
			(stroke
				(width 0.1)
				(type default)
			)
			(layer "F.Fab")
		)
		(fp_line
			(start -0.12065 0.3048)
			(end -0.67945 0.3048)
			(stroke
				(width 0.1)
				(type default)
			)
			(layer "F.Fab")
		)
		(fp_line
			(start 0.120396 0.2794)
			(end -0.12065 0.2794)
			(stroke
				(width 0.1)
				(type default)
			)
			(layer "F.Fab")
		)
		(fp_line
			(start 0.120396 0.3048)
			(end 0.120396 0.2794)
			(stroke
				(width 0.1)
				(type default)
			)
			(layer "F.Fab")
		)
		(fp_line
			(start 0.12065 -0.3048)
			(end 0.67945 -0.3048)
			(stroke
				(width 0.1)
				(type default)
			)
			(layer "F.Fab")
		)
		(fp_line
			(start 0.12065 -0.2794)
			(end 0.12065 -0.3048)
			(stroke
				(width 0.1)
				(type default)
			)
			(layer "F.Fab")
		)
		(fp_line
			(start 0.67945 -0.3048)
			(end 0.67945 0.3048)
			(stroke
				(width 0.1)
				(type default)
			)
			(layer "F.Fab")
		)
		(fp_line
			(start 0.67945 0.3048)
			(end 0.120396 0.3048)
			(stroke
				(width 0.1)
				(type default)
			)
			(layer "F.Fab")
		)
		(pad "1" smd circle
			(at -0.40005 0)
			(size 0 0)
			(layers "F.Cu" "F.Mask" "F.Paste")
			(net "P3V3_CO_ILIMIT")
		)
		(pad "2" smd circle
			(at 0.40005 0)
			(size 0 0)
			(layers "F.Cu" "F.Mask" "F.Paste")
			(net "GND")
		)
	)
	(footprint ""
		(layer "F.Cu")
		(at 320.695828 -310.509412 135)
		(property "Reference" "R1372"
			(at 0 0 135)
			(layer "F.SilkS")
			(hide yes)
			(effects
				(font
					(size 1.27 1.27)
				)
			)
		)
		(property "Value" ""
			(at 0 0 135)
			(layer "F.Fab")
			(effects
				(font
					(size 1.27 1.27)
				)
			)
		)
		(duplicate_pad_numbers_are_jumpers no)
		(fp_line
			(start 0.787389 -0.406267)
			(end 0.787389 0.406267)
			(stroke
				(width 0.1524)
				(type default)
			)
			(layer "F.SilkS")
		)
		(fp_line
			(start 0.787389 0.406267)
			(end -0.787389 0.406267)
			(stroke
				(width 0.1524)
				(type default)
			)
			(layer "F.SilkS")
		)
		(fp_line
			(start -0.787389 -0.406267)
			(end 0.787389 -0.406267)
			(stroke
				(width 0.1524)
				(type default)
			)
			(layer "F.SilkS")
		)
		(fp_line
			(start -0.787389 0.406267)
			(end -0.787389 -0.406267)
			(stroke
				(width 0.1524)
				(type default)
			)
			(layer "F.SilkS")
		)
		(fp_line
			(start 0.679446 -0.30479)
			(end 0.679446 0.30479)
			(stroke
				(width 0.1)
				(type default)
			)
			(layer "F.Fab")
		)
		(fp_line
			(start 0.120515 -0.30479)
			(end 0.679446 -0.30479)
			(stroke
				(width 0.1)
				(type default)
			)
			(layer "F.Fab")
		)
		(fp_line
			(start 0.120695 -0.279466)
			(end 0.120515 -0.30479)
			(stroke
				(width 0.1)
				(type default)
			)
			(layer "F.Fab")
		)
		(fp_line
			(start 0.679446 0.30479)
			(end 0.120515 0.30479)
			(stroke
				(width 0.1)
				(type default)
			)
			(layer "F.Fab")
		)
		(fp_line
			(start -0.120695 -0.304969)
			(end -0.120695 -0.279466)
			(stroke
				(width 0.1)
				(type default)
			)
			(layer "F.Fab")
		)
		(fp_line
			(start -0.120695 -0.279466)
			(end 0.120695 -0.279466)
			(stroke
				(width 0.1)
				(type default)
			)
			(layer "F.Fab")
		)
		(fp_line
			(start 0.120335 0.279466)
			(end -0.120695 0.279466)
			(stroke
				(width 0.1)
				(type default)
			)
			(layer "F.Fab")
		)
		(fp_line
			(start 0.120515 0.30479)
			(end 0.120335 0.279466)
			(stroke
				(width 0.1)
				(type default)
			)
			(layer "F.Fab")
		)
		(fp_line
			(start -0.679446 -0.305149)
			(end -0.120695 -0.304969)
			(stroke
				(width 0.1)
				(type default)
			)
			(layer "F.Fab")
		)
		(fp_line
			(start -0.120695 0.279466)
			(end -0.120515 0.30479)
			(stroke
				(width 0.1)
				(type default)
			)
			(layer "F.Fab")
		)
		(fp_line
			(start -0.120515 0.30479)
			(end -0.679446 0.30479)
			(stroke
				(width 0.1)
				(type default)
			)
			(layer "F.Fab")
		)
		(fp_line
			(start -0.679446 0.30479)
			(end -0.679446 -0.305149)
			(stroke
				(width 0.1)
				(type default)
			)
			(layer "F.Fab")
		)
		(pad "1" smd circle
			(at -0.40005 0 135)
			(size 0 0)
			(layers "F.Cu" "F.Mask" "F.Paste")
			(net "PEX2_SPARE2")
		)
		(pad "2" smd circle
			(at 0.40005 0 135)
			(size 0 0)
			(layers "F.Cu" "F.Mask" "F.Paste")
			(net "P1V8_PEX")
		)
	)
	(footprint ""
		(layer "F.Cu")
		(at 224.518982 -308.568598 180)
		(property "Reference" "PU17"
			(at 3.716782 -4.150868 0)
			(unlocked yes)
			(layer "F.SilkS")
			(effects
				(font
					(size 0.7874 0.5842)
					(thickness 0.1524)
				)
				(justify left)
			)
		)
		(property "Value" ""
			(at 0 0 180)
			(layer "F.Fab")
			(effects
				(font
					(size 1.27 1.27)
				)
			)
		)
		(duplicate_pad_numbers_are_jumpers no)
		(fp_line
			(start 1.549908 2.050034)
			(end 1.549908 1.9304)
			(stroke
				(width 0.1524)
				(type default)
			)
			(layer "F.SilkS")
		)
		(fp_line
			(start 1.549908 -1.9812)
			(end 1.549908 -2.050034)
			(stroke
				(width 0.1524)
				(type default)
			)
			(layer "F.SilkS")
		)
		(fp_line
			(start 1.549908 -2.050034)
			(end 0.5842 -2.050034)
			(stroke
				(width 0.1524)
				(type default)
			)
			(layer "F.SilkS")
		)
		(fp_line
			(start 0.3048 -2.4638)
			(end 0.3048 -3.2258)
			(stroke
				(width 0.1524)
				(type default)
			)
			(layer "F.SilkS")
		)
		(fp_line
			(start 0 2.050034)
			(end 1.549908 2.050034)
			(stroke
				(width 0.1524)
				(type default)
			)
			(layer "F.SilkS")
		)
		(fp_line
			(start -0.3048 2.4638)
			(end -0.3048 3.2258)
			(stroke
				(width 0.1524)
				(type default)
			)
			(layer "F.SilkS")
		)
		(fp_line
			(start -0.5842 -2.050034)
			(end -1.549908 -2.050034)
			(stroke
				(width 0.1524)
				(type default)
			)
			(layer "F.SilkS")
		)
		(fp_line
			(start -1.549908 2.050034)
			(end -0.5842 2.050034)
			(stroke
				(width 0.1524)
				(type default)
			)
			(layer "F.SilkS")
		)
		(fp_line
			(start -1.549908 1.9812)
			(end -1.549908 2.050034)
			(stroke
				(width 0.1524)
				(type default)
			)
			(layer "F.SilkS")
		)
		(fp_line
			(start -1.549908 -2.050034)
			(end -1.549908 -1.9812)
			(stroke
				(width 0.1524)
				(type default)
			)
			(layer "F.SilkS")
		)
		(fp_line
			(start -1.9812 0)
			(end -2.3622 0)
			(stroke
				(width 0.1524)
				(type default)
			)
			(layer "F.SilkS")
		)
		(fp_poly
			(pts
				(xy -2.9464 -2.208022) (xy -2.9464 -1.192022) (xy -1.9304 -1.700022)
			)
			(stroke
				(width 0)
				(type default)
			)
			(fill yes)
			(layer "F.SilkS")
		)
		(fp_line
			(start 1.549908 2.050034)
			(end 1.549908 -2.050034)
			(stroke
				(width 0.1)
				(type default)
			)
			(layer "F.Fab")
		)
		(fp_line
			(start 1.549908 -2.050034)
			(end -1.549908 -2.050034)
			(stroke
				(width 0.1)
				(type default)
			)
			(layer "F.Fab")
		)
		(fp_line
			(start 0.3048 -2.4638)
			(end 0.3048 -3.2258)
			(stroke
				(width 0.1)
				(type default)
			)
			(layer "F.Fab")
		)
		(fp_line
			(start -0.3048 2.4638)
			(end -0.3048 3.2258)
			(stroke
				(width 0.1)
				(type default)
			)
			(layer "F.Fab")
		)
		(fp_line
			(start -1.549908 2.050034)
			(end 1.549908 2.050034)
			(stroke
				(width 0.1)
				(type default)
			)
			(layer "F.Fab")
		)
		(fp_line
			(start -1.549908 -2.050034)
			(end -1.549908 2.050034)
			(stroke
				(width 0.1)
				(type default)
			)
			(layer "F.Fab")
		)
		(fp_line
			(start -1.9812 0)
			(end -2.3622 0)
			(stroke
				(width 0.1)
				(type default)
			)
			(layer "F.Fab")
		)
		(fp_poly
			(pts
				(xy -2.9464 -2.208022) (xy -2.9464 -1.192022) (xy -1.9304 -1.700022)
			)
			(stroke
				(width 0)
				(type default)
			)
			(fill yes)
			(layer "F.Fab")
		)
		(fp_text user "11_18"
			(at 2.512568 0.9906 90)
			(unlocked yes)
			(layer "F.SilkS")
			(effects
				(font
					(size 0.635 0.4064)
					(thickness 0.1524)
				)
			)
		)
		(fp_text user "19"
			(at 1.919732 -2.676398 90)
			(unlocked yes)
			(layer "F.SilkS")
			(effects
				(font
					(size 0.635 0.4064)
					(thickness 0.1524)
				)
			)
		)
		(fp_text user "9"
			(at -1.814068 2.429002 90)
			(unlocked yes)
			(layer "F.SilkS")
			(effects
				(font
					(size 0.635 0.4064)
					(thickness 0.1524)
				)
			)
		)
		(fp_text user "11_18"
			(at 2.512568 0.9906 90)
			(unlocked yes)
			(layer "F.Fab")
			(effects
				(font
					(size 0.635 0.4064)
					(thickness 0.1524)
				)
			)
		)
		(fp_text user "19"
			(at 2.410968 -2.159 90)
			(unlocked yes)
			(layer "F.Fab")
			(effects
				(font
					(size 0.635 0.4064)
					(thickness 0.1524)
				)
			)
		)
		(fp_text user "9"
			(at -2.338832 2.0574 90)
			(unlocked yes)
			(layer "F.Fab")
			(effects
				(font
					(size 0.635 0.4064)
					(thickness 0.1524)
				)
			)
		)
		(pad "1" smd rect
			(at -1.35001 -1.700022 270)
			(size 0.3048 0.9144)
			(layers "F.Cu" "F.Mask" "F.Paste")
			(net "SW_P1V25_PEX1_BT")
		)
		(pad "2" smd rect
			(at -1.400048 -1.199896 270)
			(size 0.1778 0.8128)
			(layers "F.Cu" "F.Mask" "F.Paste")
			(net "GND")
		)
		(pad "3" smd rect
			(at -1.400048 -0.8001 270)
			(size 0.1778 0.8128)
			(layers "F.Cu" "F.Mask" "F.Paste")
			(net "P1V25_PEX1_CS")
		)
		(pad "4" smd rect
			(at -1.400048 -0.40005 270)
			(size 0.1778 0.8128)
			(layers "F.Cu" "F.Mask" "F.Paste")
			(net "GND")
		)
		(pad "5" smd rect
			(at -1.400048 0 270)
			(size 0.1778 0.8128)
			(layers "F.Cu" "F.Mask" "F.Paste")
			(net "P1V25_PEX1_REF")
		)
		(pad "6" smd rect
			(at -1.400048 0.40005 270)
			(size 0.1778 0.8128)
			(layers "F.Cu" "F.Mask" "F.Paste")
			(net "SH_P1V25_PEX1_FB_N")
		)
		(pad "7" smd rect
			(at -1.400048 0.8001 270)
			(size 0.1778 0.8128)
			(layers "F.Cu" "F.Mask" "F.Paste")
			(net "P1V25_PEX1_FB")
		)
		(pad "8" smd rect
			(at -1.400048 1.199896 270)
			(size 0.1778 0.8128)
			(layers "F.Cu" "F.Mask" "F.Paste")
			(net "P1V25_PEX1_EN")
		)
		(pad "9" smd rect
			(at -1.400048 1.700022 270)
			(size 0.3048 0.8128)
			(layers "F.Cu" "F.Mask" "F.Paste")
			(net "PWRGD_P1V25_PEX1")
		)
		(pad "10" smd rect
			(at -0.299974 1.299972 180)
			(size 0.3048 2.0066)
			(layers "F.Cu" "F.Mask" "F.Paste")
			(net "SW_P12V_P1V25_PEX1_FLT")
		)
		(pad "11_18" smd circle
			(at 1.175004 0.275082 180)
			(size 0 0)
			(layers "F.Cu" "F.Mask" "F.Paste")
			(net "GND")
		)
		(pad "19" smd rect
			(at 1.400048 -1.700022 90)
			(size 0.3048 0.8128)
			(layers "F.Cu" "F.Mask" "F.Paste")
			(net "P1V25_PEX1_VCC")
		)
		(pad "20" smd rect
			(at 0.299974 -1.299972 180)
			(size 0.3048 2.0066)
			(layers "F.Cu" "F.Mask" "F.Paste")
			(net "SW_P1V25_PEX1_PH")
		)
		(pad "21" smd rect
			(at -0.299974 -1.299972 180)
			(size 0.3048 2.0066)
			(layers "F.Cu" "F.Mask" "F.Paste")
			(net "SW_P12V_P1V25_PEX1_FLT")
		)
	)
	(footprint ""
		(layer "F.Cu")
		(at 144.506442 -252.356874 -90)
		(property "Reference" "R1287"
			(at 0 0 270)
			(layer "F.SilkS")
			(hide yes)
			(effects
				(font
					(size 1.27 1.27)
				)
			)
		)
		(property "Value" ""
			(at 0 0 270)
			(layer "F.Fab")
			(effects
				(font
					(size 1.27 1.27)
				)
			)
		)
		(duplicate_pad_numbers_are_jumpers no)
		(fp_line
			(start -0.7874 0.4064)
			(end -0.7874 -0.4064)
			(stroke
				(width 0.1524)
				(type default)
			)
			(layer "F.SilkS")
		)
		(fp_line
			(start 0.7874 0.4064)
			(end -0.7874 0.4064)
			(stroke
				(width 0.1524)
				(type default)
			)
			(layer "F.SilkS")
		)
		(fp_line
			(start -0.7874 -0.4064)
			(end 0.7874 -0.4064)
			(stroke
				(width 0.1524)
				(type default)
			)
			(layer "F.SilkS")
		)
		(fp_line
			(start 0.7874 -0.4064)
			(end 0.7874 0.4064)
			(stroke
				(width 0.1524)
				(type default)
			)
			(layer "F.SilkS")
		)
		(fp_line
			(start -0.67945 0.3048)
			(end -0.67945 -0.305054)
			(stroke
				(width 0.1)
				(type default)
			)
			(layer "F.Fab")
		)
		(fp_line
			(start -0.12065 0.3048)
			(end -0.67945 0.3048)
			(stroke
				(width 0.1)
				(type default)
			)
			(layer "F.Fab")
		)
		(fp_line
			(start 0.120396 0.3048)
			(end 0.120396 0.2794)
			(stroke
				(width 0.1)
				(type default)
			)
			(layer "F.Fab")
		)
		(fp_line
			(start 0.67945 0.3048)
			(end 0.120396 0.3048)
			(stroke
				(width 0.1)
				(type default)
			)
			(layer "F.Fab")
		)
		(fp_line
			(start -0.12065 0.2794)
			(end -0.12065 0.3048)
			(stroke
				(width 0.1)
				(type default)
			)
			(layer "F.Fab")
		)
		(fp_line
			(start 0.120396 0.2794)
			(end -0.12065 0.2794)
			(stroke
				(width 0.1)
				(type default)
			)
			(layer "F.Fab")
		)
		(fp_line
			(start -0.12065 -0.2794)
			(end 0.12065 -0.2794)
			(stroke
				(width 0.1)
				(type default)
			)
			(layer "F.Fab")
		)
		(fp_line
			(start 0.12065 -0.2794)
			(end 0.12065 -0.3048)
			(stroke
				(width 0.1)
				(type default)
			)
			(layer "F.Fab")
		)
		(fp_line
			(start 0.12065 -0.3048)
			(end 0.67945 -0.3048)
			(stroke
				(width 0.1)
				(type default)
			)
			(layer "F.Fab")
		)
		(fp_line
			(start 0.67945 -0.3048)
			(end 0.67945 0.3048)
			(stroke
				(width 0.1)
				(type default)
			)
			(layer "F.Fab")
		)
		(fp_line
			(start -0.67945 -0.305054)
			(end -0.12065 -0.305054)
			(stroke
				(width 0.1)
				(type default)
			)
			(layer "F.Fab")
		)
		(fp_line
			(start -0.12065 -0.305054)
			(end -0.12065 -0.2794)
			(stroke
				(width 0.1)
				(type default)
			)
			(layer "F.Fab")
		)
		(pad "1" smd circle
			(at -0.40005 0 270)
			(size 0 0)
			(layers "F.Cu" "F.Mask" "F.Paste")
			(net "GND")
		)
		(pad "2" smd circle
			(at 0.40005 0 270)
			(size 0 0)
			(layers "F.Cu" "F.Mask" "F.Paste")
			(net "PEX1_DBG_MODE3")
		)
	)
	(footprint ""
		(layer "F.Cu")
		(at 344.511884 -109.626654 180)
		(property "Reference" "R956"
			(at 0 0 180)
			(layer "F.SilkS")
			(hide yes)
			(effects
				(font
					(size 1.27 1.27)
				)
			)
		)
		(property "Value" ""
			(at 0 0 180)
			(layer "F.Fab")
			(effects
				(font
					(size 1.27 1.27)
				)
			)
		)
		(duplicate_pad_numbers_are_jumpers no)
		(fp_line
			(start 0.7874 0.4064)
			(end -0.7874 0.4064)
			(stroke
				(width 0.1524)
				(type default)
			)
			(layer "F.SilkS")
		)
		(fp_line
			(start 0.7874 -0.4064)
			(end 0.7874 0.4064)
			(stroke
				(width 0.1524)
				(type default)
			)
			(layer "F.SilkS")
		)
		(fp_line
			(start -0.7874 0.4064)
			(end -0.7874 -0.4064)
			(stroke
				(width 0.1524)
				(type default)
			)
			(layer "F.SilkS")
		)
		(fp_line
			(start -0.7874 -0.4064)
			(end 0.7874 -0.4064)
			(stroke
				(width 0.1524)
				(type default)
			)
			(layer "F.SilkS")
		)
		(fp_line
			(start 0.67945 0.3048)
			(end 0.120396 0.3048)
			(stroke
				(width 0.1)
				(type default)
			)
			(layer "F.Fab")
		)
		(fp_line
			(start 0.67945 -0.3048)
			(end 0.67945 0.3048)
			(stroke
				(width 0.1)
				(type default)
			)
			(layer "F.Fab")
		)
		(fp_line
			(start 0.12065 -0.2794)
			(end 0.12065 -0.3048)
			(stroke
				(width 0.1)
				(type default)
			)
			(layer "F.Fab")
		)
		(fp_line
			(start 0.12065 -0.3048)
			(end 0.67945 -0.3048)
			(stroke
				(width 0.1)
				(type default)
			)
			(layer "F.Fab")
		)
		(fp_line
			(start 0.120396 0.3048)
			(end 0.120396 0.2794)
			(stroke
				(width 0.1)
				(type default)
			)
			(layer "F.Fab")
		)
		(fp_line
			(start 0.120396 0.2794)
			(end -0.12065 0.2794)
			(stroke
				(width 0.1)
				(type default)
			)
			(layer "F.Fab")
		)
		(fp_line
			(start -0.12065 0.3048)
			(end -0.67945 0.3048)
			(stroke
				(width 0.1)
				(type default)
			)
			(layer "F.Fab")
		)
		(fp_line
			(start -0.12065 0.2794)
			(end -0.12065 0.3048)
			(stroke
				(width 0.1)
				(type default)
			)
			(layer "F.Fab")
		)
		(fp_line
			(start -0.12065 -0.2794)
			(end 0.12065 -0.2794)
			(stroke
				(width 0.1)
				(type default)
			)
			(layer "F.Fab")
		)
		(fp_line
			(start -0.12065 -0.305054)
			(end -0.12065 -0.2794)
			(stroke
				(width 0.1)
				(type default)
			)
			(layer "F.Fab")
		)
		(fp_line
			(start -0.67945 0.3048)
			(end -0.67945 -0.305054)
			(stroke
				(width 0.1)
				(type default)
			)
			(layer "F.Fab")
		)
		(fp_line
			(start -0.67945 -0.305054)
			(end -0.12065 -0.305054)
			(stroke
				(width 0.1)
				(type default)
			)
			(layer "F.Fab")
		)
		(pad "1" smd circle
			(at -0.40005 0 180)
			(size 0 0)
			(layers "F.Cu" "F.Mask" "F.Paste")
			(net "GND")
		)
		(pad "2" smd circle
			(at 0.40005 0 180)
			(size 0 0)
			(layers "F.Cu" "F.Mask" "F.Paste")
			(net "P12V_NIC5_CO_EN")
		)
	)
	(footprint ""
		(layer "F.Cu")
		(at 18.800064 -84.699856)
		(property "Reference" "H47"
			(at -4.464812 -5.279136 0)
			(unlocked yes)
			(layer "F.SilkS")
			(effects
				(font
					(size 0.7874 0.5842)
					(thickness 0.1524)
				)
				(justify left)
			)
		)
		(property "Value" ""
			(at 0 0 0)
			(layer "F.Fab")
			(effects
				(font
					(size 1.27 1.27)
				)
			)
		)
		(duplicate_pad_numbers_are_jumpers no)
		(pad "1" thru_hole circle
			(at 0 0)
			(size 10.0076 10.0076)
			(drill 5.6134)
			(layers "*.Cu" "*.Mask")
			(remove_unused_layers no)
			(net "GND")
			(clearance -1.9431)
		)
	)
	(footprint ""
		(layer "F.Cu")
		(at 381.587756 -282.018232)
		(property "Reference" "C3589"
			(at 0 0 0)
			(layer "F.SilkS")
			(hide yes)
			(effects
				(font
					(size 1.27 1.27)
				)
			)
		)
		(property "Value" ""
			(at 0 0 0)
			(layer "F.Fab")
			(effects
				(font
					(size 1.27 1.27)
				)
			)
		)
		(duplicate_pad_numbers_are_jumpers no)
		(fp_line
			(start -1.2954 -0.5842)
			(end 1.2954 -0.5842)
			(stroke
				(width 0.1524)
				(type default)
			)
			(layer "F.SilkS")
		)
		(fp_line
			(start -1.2954 0.5842)
			(end -1.2954 -0.5842)
			(stroke
				(width 0.1524)
				(type default)
			)
			(layer "F.SilkS")
		)
		(fp_line
			(start 1.2954 -0.5842)
			(end 1.2954 0.5842)
			(stroke
				(width 0.1524)
				(type default)
			)
			(layer "F.SilkS")
		)
		(fp_line
			(start 1.2954 0.5842)
			(end -1.2954 0.5842)
			(stroke
				(width 0.1524)
				(type default)
			)
			(layer "F.SilkS")
		)
		(fp_line
			(start -1.1938 -0.4064)
			(end -0.8636 -0.4064)
			(stroke
				(width 0.1)
				(type default)
			)
			(layer "F.Fab")
		)
		(fp_line
			(start -1.1938 0.4064)
			(end -1.1938 -0.4064)
			(stroke
				(width 0.1)
				(type default)
			)
			(layer "F.Fab")
		)
		(fp_line
			(start -0.8636 -0.4572)
			(end 0.8636 -0.4572)
			(stroke
				(width 0.1)
				(type default)
			)
			(layer "F.Fab")
		)
		(fp_line
			(start -0.8636 -0.4064)
			(end -0.8636 -0.4572)
			(stroke
				(width 0.1)
				(type default)
			)
			(layer "F.Fab")
		)
		(fp_line
			(start -0.8636 0.4064)
			(end -1.1938 0.4064)
			(stroke
				(width 0.1)
				(type default)
			)
			(layer "F.Fab")
		)
		(fp_line
			(start -0.8636 0.4572)
			(end -0.8636 0.4064)
			(stroke
				(width 0.1)
				(type default)
			)
			(layer "F.Fab")
		)
		(fp_line
			(start 0.8636 -0.4572)
			(end 0.8636 -0.4064)
			(stroke
				(width 0.1)
				(type default)
			)
			(layer "F.Fab")
		)
		(fp_line
			(start 0.8636 -0.4064)
			(end 1.1938 -0.4064)
			(stroke
				(width 0.1)
				(type default)
			)
			(layer "F.Fab")
		)
		(fp_line
			(start 0.8636 0.4064)
			(end 0.8636 0.4572)
			(stroke
				(width 0.1)
				(type default)
			)
			(layer "F.Fab")
		)
		(fp_line
			(start 0.8636 0.4572)
			(end -0.8636 0.4572)
			(stroke
				(width 0.1)
				(type default)
			)
			(layer "F.Fab")
		)
		(fp_line
			(start 1.1938 -0.4064)
			(end 1.1938 0.4064)
			(stroke
				(width 0.1)
				(type default)
			)
			(layer "F.Fab")
		)
		(fp_line
			(start 1.1938 0.4064)
			(end 0.8636 0.4064)
			(stroke
				(width 0.1)
				(type default)
			)
			(layer "F.Fab")
		)
		(pad "1" smd rect
			(at -0.7366 0 270)
			(size 0.7112 0.8128)
			(layers "F.Cu" "F.Mask" "F.Paste")
			(net "SYSPLL_VDDA18_PEX3")
		)
		(pad "2" smd rect
			(at 0.7366 0 270)
			(size 0.7112 0.8128)
			(layers "F.Cu" "F.Mask" "F.Paste")
			(net "GND")
		)
	)
	(footprint ""
		(layer "F.Cu")
		(at 387.62178 -350.098614 90)
		(property "Reference" "C777"
			(at 0 0 90)
			(layer "F.SilkS")
			(hide yes)
			(effects
				(font
					(size 1.27 1.27)
				)
			)
		)
		(property "Value" ""
			(at 0 0 90)
			(layer "F.Fab")
			(effects
				(font
					(size 1.27 1.27)
				)
			)
		)
		(duplicate_pad_numbers_are_jumpers no)
		(fp_line
			(start 0.299974 -0.150114)
			(end 0.299974 0.150114)
			(stroke
				(width 0.1)
				(type default)
			)
			(layer "F.Fab")
		)
		(fp_line
			(start -0.299974 -0.150114)
			(end 0.299974 -0.150114)
			(stroke
				(width 0.1)
				(type default)
			)
			(layer "F.Fab")
		)
		(fp_line
			(start 0.299974 0.150114)
			(end -0.299974 0.150114)
			(stroke
				(width 0.1)
				(type default)
			)
			(layer "F.Fab")
		)
		(fp_line
			(start -0.299974 0.150114)
			(end -0.299974 -0.150114)
			(stroke
				(width 0.1)
				(type default)
			)
			(layer "F.Fab")
		)
		(pad "1" smd rect
			(at -0.2667 0 90)
			(size 0.3048 0.381)
			(layers "F.Cu" "F.Mask" "F.Paste")
			(net "P5E_PEX3_STN6_TX_DN<104>")
		)
		(pad "2" smd rect
			(at 0.2667 0 90)
			(size 0.3048 0.381)
			(layers "F.Cu" "F.Mask" "F.Paste")
			(net "P5E_PEX3_STN6_TX_C_DN<104>")
		)
	)
	(footprint ""
		(layer "F.Cu")
		(at 425.728892 -350.098614 90)
		(property "Reference" "C811"
			(at 0 0 90)
			(layer "F.SilkS")
			(hide yes)
			(effects
				(font
					(size 1.27 1.27)
				)
			)
		)
		(property "Value" ""
			(at 0 0 90)
			(layer "F.Fab")
			(effects
				(font
					(size 1.27 1.27)
				)
			)
		)
		(duplicate_pad_numbers_are_jumpers no)
		(fp_line
			(start 0.299974 -0.150114)
			(end 0.299974 0.150114)
			(stroke
				(width 0.1)
				(type default)
			)
			(layer "F.Fab")
		)
		(fp_line
			(start -0.299974 -0.150114)
			(end 0.299974 -0.150114)
			(stroke
				(width 0.1)
				(type default)
			)
			(layer "F.Fab")
		)
		(fp_line
			(start 0.299974 0.150114)
			(end -0.299974 0.150114)
			(stroke
				(width 0.1)
				(type default)
			)
			(layer "F.Fab")
		)
		(fp_line
			(start -0.299974 0.150114)
			(end -0.299974 -0.150114)
			(stroke
				(width 0.1)
				(type default)
			)
			(layer "F.Fab")
		)
		(pad "1" smd rect
			(at -0.2667 0 90)
			(size 0.3048 0.381)
			(layers "F.Cu" "F.Mask" "F.Paste")
			(net "P5E_PEX3_STN7_TX_DN<119>")
		)
		(pad "2" smd rect
			(at 0.2667 0 90)
			(size 0.3048 0.381)
			(layers "F.Cu" "F.Mask" "F.Paste")
			(net "P5E_PEX3_STN7_TX_C_DN<119>")
		)
	)
	(footprint ""
		(layer "F.Cu")
		(at 295.008554 -158.080202 90)
		(property "Reference" "R2475"
			(at 0 0 90)
			(layer "F.SilkS")
			(hide yes)
			(effects
				(font
					(size 1.27 1.27)
				)
			)
		)
		(property "Value" ""
			(at 0 0 90)
			(layer "F.Fab")
			(effects
				(font
					(size 1.27 1.27)
				)
			)
		)
		(duplicate_pad_numbers_are_jumpers no)
		(fp_line
			(start 0.7874 -0.4064)
			(end 0.7874 0.4064)
			(stroke
				(width 0.1524)
				(type default)
			)
			(layer "F.SilkS")
		)
		(fp_line
			(start -0.7874 -0.4064)
			(end 0.7874 -0.4064)
			(stroke
				(width 0.1524)
				(type default)
			)
			(layer "F.SilkS")
		)
		(fp_line
			(start 0.7874 0.4064)
			(end -0.7874 0.4064)
			(stroke
				(width 0.1524)
				(type default)
			)
			(layer "F.SilkS")
		)
		(fp_line
			(start -0.7874 0.4064)
			(end -0.7874 -0.4064)
			(stroke
				(width 0.1524)
				(type default)
			)
			(layer "F.SilkS")
		)
		(fp_line
			(start -0.12065 -0.305054)
			(end -0.12065 -0.2794)
			(stroke
				(width 0.1)
				(type default)
			)
			(layer "F.Fab")
		)
		(fp_line
			(start -0.67945 -0.305054)
			(end -0.12065 -0.305054)
			(stroke
				(width 0.1)
				(type default)
			)
			(layer "F.Fab")
		)
		(fp_line
			(start 0.67945 -0.3048)
			(end 0.67945 0.3048)
			(stroke
				(width 0.1)
				(type default)
			)
			(layer "F.Fab")
		)
		(fp_line
			(start 0.12065 -0.3048)
			(end 0.67945 -0.3048)
			(stroke
				(width 0.1)
				(type default)
			)
			(layer "F.Fab")
		)
		(fp_line
			(start 0.12065 -0.2794)
			(end 0.12065 -0.3048)
			(stroke
				(width 0.1)
				(type default)
			)
			(layer "F.Fab")
		)
		(fp_line
			(start -0.12065 -0.2794)
			(end 0.12065 -0.2794)
			(stroke
				(width 0.1)
				(type default)
			)
			(layer "F.Fab")
		)
		(fp_line
			(start 0.120396 0.2794)
			(end -0.12065 0.2794)
			(stroke
				(width 0.1)
				(type default)
			)
			(layer "F.Fab")
		)
		(fp_line
			(start -0.12065 0.2794)
			(end -0.12065 0.3048)
			(stroke
				(width 0.1)
				(type default)
			)
			(layer "F.Fab")
		)
		(fp_line
			(start 0.67945 0.3048)
			(end 0.120396 0.3048)
			(stroke
				(width 0.1)
				(type default)
			)
			(layer "F.Fab")
		)
		(fp_line
			(start 0.120396 0.3048)
			(end 0.120396 0.2794)
			(stroke
				(width 0.1)
				(type default)
			)
			(layer "F.Fab")
		)
		(fp_line
			(start -0.12065 0.3048)
			(end -0.67945 0.3048)
			(stroke
				(width 0.1)
				(type default)
			)
			(layer "F.Fab")
		)
		(fp_line
			(start -0.67945 0.3048)
			(end -0.67945 -0.305054)
			(stroke
				(width 0.1)
				(type default)
			)
			(layer "F.Fab")
		)
		(pad "1" smd circle
			(at -0.40005 0 90)
			(size 0 0)
			(layers "F.Cu" "F.Mask" "F.Paste")
			(net "P3V3_NIC5")
		)
		(pad "2" smd circle
			(at 0.40005 0 90)
			(size 0 0)
			(layers "F.Cu" "F.Mask" "F.Paste")
			(net "NIC5_PWRBRK_N")
		)
	)
	(footprint ""
		(layer "F.Cu")
		(at 129.690114 -254.194564 180)
		(property "Reference" "R825"
			(at 0 0 180)
			(layer "F.SilkS")
			(hide yes)
			(effects
				(font
					(size 1.27 1.27)
				)
			)
		)
		(property "Value" ""
			(at 0 0 180)
			(layer "F.Fab")
			(effects
				(font
					(size 1.27 1.27)
				)
			)
		)
		(duplicate_pad_numbers_are_jumpers no)
		(fp_line
			(start 0.7874 0.4064)
			(end -0.7874 0.4064)
			(stroke
				(width 0.1524)
				(type default)
			)
			(layer "F.SilkS")
		)
		(fp_line
			(start 0.7874 -0.4064)
			(end 0.7874 0.4064)
			(stroke
				(width 0.1524)
				(type default)
			)
			(layer "F.SilkS")
		)
		(fp_line
			(start -0.7874 0.4064)
			(end -0.7874 -0.4064)
			(stroke
				(width 0.1524)
				(type default)
			)
			(layer "F.SilkS")
		)
		(fp_line
			(start -0.7874 -0.4064)
			(end 0.7874 -0.4064)
			(stroke
				(width 0.1524)
				(type default)
			)
			(layer "F.SilkS")
		)
		(fp_line
			(start 0.67945 0.3048)
			(end 0.120396 0.3048)
			(stroke
				(width 0.1)
				(type default)
			)
			(layer "F.Fab")
		)
		(fp_line
			(start 0.67945 -0.3048)
			(end 0.67945 0.3048)
			(stroke
				(width 0.1)
				(type default)
			)
			(layer "F.Fab")
		)
		(fp_line
			(start 0.12065 -0.2794)
			(end 0.12065 -0.3048)
			(stroke
				(width 0.1)
				(type default)
			)
			(layer "F.Fab")
		)
		(fp_line
			(start 0.12065 -0.3048)
			(end 0.67945 -0.3048)
			(stroke
				(width 0.1)
				(type default)
			)
			(layer "F.Fab")
		)
		(fp_line
			(start 0.120396 0.3048)
			(end 0.120396 0.2794)
			(stroke
				(width 0.1)
				(type default)
			)
			(layer "F.Fab")
		)
		(fp_line
			(start 0.120396 0.2794)
			(end -0.12065 0.2794)
			(stroke
				(width 0.1)
				(type default)
			)
			(layer "F.Fab")
		)
		(fp_line
			(start -0.12065 0.3048)
			(end -0.67945 0.3048)
			(stroke
				(width 0.1)
				(type default)
			)
			(layer "F.Fab")
		)
		(fp_line
			(start -0.12065 0.2794)
			(end -0.12065 0.3048)
			(stroke
				(width 0.1)
				(type default)
			)
			(layer "F.Fab")
		)
		(fp_line
			(start -0.12065 -0.2794)
			(end 0.12065 -0.2794)
			(stroke
				(width 0.1)
				(type default)
			)
			(layer "F.Fab")
		)
		(fp_line
			(start -0.12065 -0.305054)
			(end -0.12065 -0.2794)
			(stroke
				(width 0.1)
				(type default)
			)
			(layer "F.Fab")
		)
		(fp_line
			(start -0.67945 0.3048)
			(end -0.67945 -0.305054)
			(stroke
				(width 0.1)
				(type default)
			)
			(layer "F.Fab")
		)
		(fp_line
			(start -0.67945 -0.305054)
			(end -0.12065 -0.305054)
			(stroke
				(width 0.1)
				(type default)
			)
			(layer "F.Fab")
		)
		(pad "1" smd circle
			(at -0.40005 0 180)
			(size 0 0)
			(layers "F.Cu" "F.Mask" "F.Paste")
			(net "P3V3_AUX")
		)
		(pad "2" smd circle
			(at 0.40005 0 180)
			(size 0 0)
			(layers "F.Cu" "F.Mask" "F.Paste")
			(net "P0V8_PEX0_AVRRDY")
		)
	)
	(footprint ""
		(layer "F.Cu")
		(at 112.470184 -280.44902 -90)
		(property "Reference" "PC82"
			(at 0 0 270)
			(layer "F.SilkS")
			(hide yes)
			(effects
				(font
					(size 1.27 1.27)
				)
			)
		)
		(property "Value" ""
			(at 0 0 270)
			(layer "F.Fab")
			(effects
				(font
					(size 1.27 1.27)
				)
			)
		)
		(duplicate_pad_numbers_are_jumpers no)
		(fp_line
			(start -0.7874 0.4064)
			(end -0.7874 -0.4064)
			(stroke
				(width 0.1524)
				(type default)
			)
			(layer "F.SilkS")
		)
		(fp_line
			(start 0.7874 0.4064)
			(end -0.7874 0.4064)
			(stroke
				(width 0.1524)
				(type default)
			)
			(layer "F.SilkS")
		)
		(fp_line
			(start -0.7874 -0.4064)
			(end 0.7874 -0.4064)
			(stroke
				(width 0.1524)
				(type default)
			)
			(layer "F.SilkS")
		)
		(fp_line
			(start 0.7874 -0.4064)
			(end 0.7874 0.4064)
			(stroke
				(width 0.1524)
				(type default)
			)
			(layer "F.SilkS")
		)
		(fp_line
			(start -0.67945 0.3048)
			(end -0.67945 -0.305054)
			(stroke
				(width 0.1)
				(type default)
			)
			(layer "F.Fab")
		)
		(fp_line
			(start -0.12065 0.3048)
			(end -0.67945 0.3048)
			(stroke
				(width 0.1)
				(type default)
			)
			(layer "F.Fab")
		)
		(fp_line
			(start 0.120396 0.3048)
			(end 0.120396 0.2794)
			(stroke
				(width 0.1)
				(type default)
			)
			(layer "F.Fab")
		)
		(fp_line
			(start 0.67945 0.3048)
			(end 0.120396 0.3048)
			(stroke
				(width 0.1)
				(type default)
			)
			(layer "F.Fab")
		)
		(fp_line
			(start -0.12065 0.2794)
			(end -0.12065 0.3048)
			(stroke
				(width 0.1)
				(type default)
			)
			(layer "F.Fab")
		)
		(fp_line
			(start 0.120396 0.2794)
			(end -0.12065 0.2794)
			(stroke
				(width 0.1)
				(type default)
			)
			(layer "F.Fab")
		)
		(fp_line
			(start -0.12065 -0.2794)
			(end 0.12065 -0.2794)
			(stroke
				(width 0.1)
				(type default)
			)
			(layer "F.Fab")
		)
		(fp_line
			(start 0.12065 -0.2794)
			(end 0.12065 -0.3048)
			(stroke
				(width 0.1)
				(type default)
			)
			(layer "F.Fab")
		)
		(fp_line
			(start 0.12065 -0.3048)
			(end 0.67945 -0.3048)
			(stroke
				(width 0.1)
				(type default)
			)
			(layer "F.Fab")
		)
		(fp_line
			(start 0.67945 -0.3048)
			(end 0.67945 0.3048)
			(stroke
				(width 0.1)
				(type default)
			)
			(layer "F.Fab")
		)
		(fp_line
			(start -0.67945 -0.305054)
			(end -0.12065 -0.305054)
			(stroke
				(width 0.1)
				(type default)
			)
			(layer "F.Fab")
		)
		(fp_line
			(start -0.12065 -0.305054)
			(end -0.12065 -0.2794)
			(stroke
				(width 0.1)
				(type default)
			)
			(layer "F.Fab")
		)
		(pad "1" smd circle
			(at -0.40005 0 270)
			(size 0 0)
			(layers "F.Cu" "F.Mask" "F.Paste")
			(net "SW_P0V8_PEX0_PHASE2")
		)
		(pad "2" smd circle
			(at 0.40005 0 270)
			(size 0 0)
			(layers "F.Cu" "F.Mask" "F.Paste")
			(net "SW_P0V8_PEX0_BOOT2_R")
		)
	)
	(footprint ""
		(layer "F.Cu")
		(at 218.963494 -183.55818)
		(property "Reference" "R5500"
			(at 0 0 0)
			(layer "F.SilkS")
			(hide yes)
			(effects
				(font
					(size 1.27 1.27)
				)
			)
		)
		(property "Value" ""
			(at 0 0 0)
			(layer "F.Fab")
			(effects
				(font
					(size 1.27 1.27)
				)
			)
		)
		(duplicate_pad_numbers_are_jumpers no)
		(fp_line
			(start -0.7874 -0.4064)
			(end 0.7874 -0.4064)
			(stroke
				(width 0.1524)
				(type default)
			)
			(layer "F.SilkS")
		)
		(fp_line
			(start -0.7874 0.4064)
			(end -0.7874 -0.4064)
			(stroke
				(width 0.1524)
				(type default)
			)
			(layer "F.SilkS")
		)
		(fp_line
			(start 0.7874 -0.4064)
			(end 0.7874 0.4064)
			(stroke
				(width 0.1524)
				(type default)
			)
			(layer "F.SilkS")
		)
		(fp_line
			(start 0.7874 0.4064)
			(end -0.7874 0.4064)
			(stroke
				(width 0.1524)
				(type default)
			)
			(layer "F.SilkS")
		)
		(fp_line
			(start -0.67945 -0.305054)
			(end -0.12065 -0.305054)
			(stroke
				(width 0.1)
				(type default)
			)
			(layer "F.Fab")
		)
		(fp_line
			(start -0.67945 0.3048)
			(end -0.67945 -0.305054)
			(stroke
				(width 0.1)
				(type default)
			)
			(layer "F.Fab")
		)
		(fp_line
			(start -0.12065 -0.305054)
			(end -0.12065 -0.2794)
			(stroke
				(width 0.1)
				(type default)
			)
			(layer "F.Fab")
		)
		(fp_line
			(start -0.12065 -0.2794)
			(end 0.12065 -0.2794)
			(stroke
				(width 0.1)
				(type default)
			)
			(layer "F.Fab")
		)
		(fp_line
			(start -0.12065 0.2794)
			(end -0.12065 0.3048)
			(stroke
				(width 0.1)
				(type default)
			)
			(layer "F.Fab")
		)
		(fp_line
			(start -0.12065 0.3048)
			(end -0.67945 0.3048)
			(stroke
				(width 0.1)
				(type default)
			)
			(layer "F.Fab")
		)
		(fp_line
			(start 0.120396 0.2794)
			(end -0.12065 0.2794)
			(stroke
				(width 0.1)
				(type default)
			)
			(layer "F.Fab")
		)
		(fp_line
			(start 0.120396 0.3048)
			(end 0.120396 0.2794)
			(stroke
				(width 0.1)
				(type default)
			)
			(layer "F.Fab")
		)
		(fp_line
			(start 0.12065 -0.3048)
			(end 0.67945 -0.3048)
			(stroke
				(width 0.1)
				(type default)
			)
			(layer "F.Fab")
		)
		(fp_line
			(start 0.12065 -0.2794)
			(end 0.12065 -0.3048)
			(stroke
				(width 0.1)
				(type default)
			)
			(layer "F.Fab")
		)
		(fp_line
			(start 0.67945 -0.3048)
			(end 0.67945 0.3048)
			(stroke
				(width 0.1)
				(type default)
			)
			(layer "F.Fab")
		)
		(fp_line
			(start 0.67945 0.3048)
			(end 0.120396 0.3048)
			(stroke
				(width 0.1)
				(type default)
			)
			(layer "F.Fab")
		)
		(pad "1" smd circle
			(at -0.40005 0)
			(size 0 0)
			(layers "F.Cu" "F.Mask" "F.Paste")
			(net "RST_BIC_SRST_R_N")
		)
		(pad "2" smd circle
			(at 0.40005 0)
			(size 0 0)
			(layers "F.Cu" "F.Mask" "F.Paste")
			(net "RST_BIC_BUF_RSMRST_N")
		)
	)
	(footprint ""
		(layer "F.Cu")
		(at 16.02486 -409.848558 -90)
		(property "Reference" "C3652"
			(at 0 0 270)
			(layer "F.SilkS")
			(hide yes)
			(effects
				(font
					(size 1.27 1.27)
				)
			)
		)
		(property "Value" ""
			(at 0 0 270)
			(layer "F.Fab")
			(effects
				(font
					(size 1.27 1.27)
				)
			)
		)
		(duplicate_pad_numbers_are_jumpers no)
		(fp_line
			(start -0.7874 0.4064)
			(end -0.7874 -0.4064)
			(stroke
				(width 0.1524)
				(type default)
			)
			(layer "F.SilkS")
		)
		(fp_line
			(start 0.7874 0.4064)
			(end -0.7874 0.4064)
			(stroke
				(width 0.1524)
				(type default)
			)
			(layer "F.SilkS")
		)
		(fp_line
			(start -0.7874 -0.4064)
			(end 0.7874 -0.4064)
			(stroke
				(width 0.1524)
				(type default)
			)
			(layer "F.SilkS")
		)
		(fp_line
			(start 0.7874 -0.4064)
			(end 0.7874 0.4064)
			(stroke
				(width 0.1524)
				(type default)
			)
			(layer "F.SilkS")
		)
		(fp_line
			(start -0.67945 0.3048)
			(end -0.67945 -0.305054)
			(stroke
				(width 0.1)
				(type default)
			)
			(layer "F.Fab")
		)
		(fp_line
			(start -0.12065 0.3048)
			(end -0.67945 0.3048)
			(stroke
				(width 0.1)
				(type default)
			)
			(layer "F.Fab")
		)
		(fp_line
			(start 0.120396 0.3048)
			(end 0.120396 0.2794)
			(stroke
				(width 0.1)
				(type default)
			)
			(layer "F.Fab")
		)
		(fp_line
			(start 0.67945 0.3048)
			(end 0.120396 0.3048)
			(stroke
				(width 0.1)
				(type default)
			)
			(layer "F.Fab")
		)
		(fp_line
			(start -0.12065 0.2794)
			(end -0.12065 0.3048)
			(stroke
				(width 0.1)
				(type default)
			)
			(layer "F.Fab")
		)
		(fp_line
			(start 0.120396 0.2794)
			(end -0.12065 0.2794)
			(stroke
				(width 0.1)
				(type default)
			)
			(layer "F.Fab")
		)
		(fp_line
			(start -0.12065 -0.2794)
			(end 0.12065 -0.2794)
			(stroke
				(width 0.1)
				(type default)
			)
			(layer "F.Fab")
		)
		(fp_line
			(start 0.12065 -0.2794)
			(end 0.12065 -0.3048)
			(stroke
				(width 0.1)
				(type default)
			)
			(layer "F.Fab")
		)
		(fp_line
			(start 0.12065 -0.3048)
			(end 0.67945 -0.3048)
			(stroke
				(width 0.1)
				(type default)
			)
			(layer "F.Fab")
		)
		(fp_line
			(start 0.67945 -0.3048)
			(end 0.67945 0.3048)
			(stroke
				(width 0.1)
				(type default)
			)
			(layer "F.Fab")
		)
		(fp_line
			(start -0.67945 -0.305054)
			(end -0.12065 -0.305054)
			(stroke
				(width 0.1)
				(type default)
			)
			(layer "F.Fab")
		)
		(fp_line
			(start -0.12065 -0.305054)
			(end -0.12065 -0.2794)
			(stroke
				(width 0.1)
				(type default)
			)
			(layer "F.Fab")
		)
		(pad "1" smd circle
			(at -0.40005 0 270)
			(size 0 0)
			(layers "F.Cu" "F.Mask" "F.Paste")
			(net "P3V3_AUX")
		)
		(pad "2" smd circle
			(at 0.40005 0 270)
			(size 0 0)
			(layers "F.Cu" "F.Mask" "F.Paste")
			(net "GND")
		)
	)
	(footprint ""
		(layer "F.Cu")
		(at 95.105728 -246.840248 180)
		(property "Reference" "R813"
			(at 0 0 180)
			(layer "F.SilkS")
			(hide yes)
			(effects
				(font
					(size 1.27 1.27)
				)
			)
		)
		(property "Value" ""
			(at 0 0 180)
			(layer "F.Fab")
			(effects
				(font
					(size 1.27 1.27)
				)
			)
		)
		(duplicate_pad_numbers_are_jumpers no)
		(fp_line
			(start 0.7874 0.4064)
			(end -0.7874 0.4064)
			(stroke
				(width 0.1524)
				(type default)
			)
			(layer "F.SilkS")
		)
		(fp_line
			(start 0.7874 -0.4064)
			(end 0.7874 0.4064)
			(stroke
				(width 0.1524)
				(type default)
			)
			(layer "F.SilkS")
		)
		(fp_line
			(start -0.7874 0.4064)
			(end -0.7874 -0.4064)
			(stroke
				(width 0.1524)
				(type default)
			)
			(layer "F.SilkS")
		)
		(fp_line
			(start -0.7874 -0.4064)
			(end 0.7874 -0.4064)
			(stroke
				(width 0.1524)
				(type default)
			)
			(layer "F.SilkS")
		)
		(fp_line
			(start 0.67945 0.3048)
			(end 0.120396 0.3048)
			(stroke
				(width 0.1)
				(type default)
			)
			(layer "F.Fab")
		)
		(fp_line
			(start 0.67945 -0.3048)
			(end 0.67945 0.3048)
			(stroke
				(width 0.1)
				(type default)
			)
			(layer "F.Fab")
		)
		(fp_line
			(start 0.12065 -0.2794)
			(end 0.12065 -0.3048)
			(stroke
				(width 0.1)
				(type default)
			)
			(layer "F.Fab")
		)
		(fp_line
			(start 0.12065 -0.3048)
			(end 0.67945 -0.3048)
			(stroke
				(width 0.1)
				(type default)
			)
			(layer "F.Fab")
		)
		(fp_line
			(start 0.120396 0.3048)
			(end 0.120396 0.2794)
			(stroke
				(width 0.1)
				(type default)
			)
			(layer "F.Fab")
		)
		(fp_line
			(start 0.120396 0.2794)
			(end -0.12065 0.2794)
			(stroke
				(width 0.1)
				(type default)
			)
			(layer "F.Fab")
		)
		(fp_line
			(start -0.12065 0.3048)
			(end -0.67945 0.3048)
			(stroke
				(width 0.1)
				(type default)
			)
			(layer "F.Fab")
		)
		(fp_line
			(start -0.12065 0.2794)
			(end -0.12065 0.3048)
			(stroke
				(width 0.1)
				(type default)
			)
			(layer "F.Fab")
		)
		(fp_line
			(start -0.12065 -0.2794)
			(end 0.12065 -0.2794)
			(stroke
				(width 0.1)
				(type default)
			)
			(layer "F.Fab")
		)
		(fp_line
			(start -0.12065 -0.305054)
			(end -0.12065 -0.2794)
			(stroke
				(width 0.1)
				(type default)
			)
			(layer "F.Fab")
		)
		(fp_line
			(start -0.67945 0.3048)
			(end -0.67945 -0.305054)
			(stroke
				(width 0.1)
				(type default)
			)
			(layer "F.Fab")
		)
		(fp_line
			(start -0.67945 -0.305054)
			(end -0.12065 -0.305054)
			(stroke
				(width 0.1)
				(type default)
			)
			(layer "F.Fab")
		)
		(pad "1" smd circle
			(at -0.40005 0 180)
			(size 0 0)
			(layers "F.Cu" "F.Mask" "F.Paste")
			(net "PEX_P1V8_ADC_A1")
		)
		(pad "2" smd circle
			(at 0.40005 0 180)
			(size 0 0)
			(layers "F.Cu" "F.Mask" "F.Paste")
			(net "P3V3_AUX")
		)
	)
	(footprint ""
		(layer "F.Cu")
		(at 286.654748 -22.961346 90)
		(property "Reference" "R1690"
			(at 0 0 90)
			(layer "F.SilkS")
			(hide yes)
			(effects
				(font
					(size 1.27 1.27)
				)
			)
		)
		(property "Value" ""
			(at 0 0 90)
			(layer "F.Fab")
			(effects
				(font
					(size 1.27 1.27)
				)
			)
		)
		(duplicate_pad_numbers_are_jumpers no)
		(fp_line
			(start 0.7874 -0.4064)
			(end 0.7874 0.4064)
			(stroke
				(width 0.1524)
				(type default)
			)
			(layer "F.SilkS")
		)
		(fp_line
			(start -0.7874 -0.4064)
			(end 0.7874 -0.4064)
			(stroke
				(width 0.1524)
				(type default)
			)
			(layer "F.SilkS")
		)
		(fp_line
			(start 0.7874 0.4064)
			(end -0.7874 0.4064)
			(stroke
				(width 0.1524)
				(type default)
			)
			(layer "F.SilkS")
		)
		(fp_line
			(start -0.7874 0.4064)
			(end -0.7874 -0.4064)
			(stroke
				(width 0.1524)
				(type default)
			)
			(layer "F.SilkS")
		)
		(fp_line
			(start -0.12065 -0.305054)
			(end -0.12065 -0.2794)
			(stroke
				(width 0.1)
				(type default)
			)
			(layer "F.Fab")
		)
		(fp_line
			(start -0.67945 -0.305054)
			(end -0.12065 -0.305054)
			(stroke
				(width 0.1)
				(type default)
			)
			(layer "F.Fab")
		)
		(fp_line
			(start 0.67945 -0.3048)
			(end 0.67945 0.3048)
			(stroke
				(width 0.1)
				(type default)
			)
			(layer "F.Fab")
		)
		(fp_line
			(start 0.12065 -0.3048)
			(end 0.67945 -0.3048)
			(stroke
				(width 0.1)
				(type default)
			)
			(layer "F.Fab")
		)
		(fp_line
			(start 0.12065 -0.2794)
			(end 0.12065 -0.3048)
			(stroke
				(width 0.1)
				(type default)
			)
			(layer "F.Fab")
		)
		(fp_line
			(start -0.12065 -0.2794)
			(end 0.12065 -0.2794)
			(stroke
				(width 0.1)
				(type default)
			)
			(layer "F.Fab")
		)
		(fp_line
			(start 0.120396 0.2794)
			(end -0.12065 0.2794)
			(stroke
				(width 0.1)
				(type default)
			)
			(layer "F.Fab")
		)
		(fp_line
			(start -0.12065 0.2794)
			(end -0.12065 0.3048)
			(stroke
				(width 0.1)
				(type default)
			)
			(layer "F.Fab")
		)
		(fp_line
			(start 0.67945 0.3048)
			(end 0.120396 0.3048)
			(stroke
				(width 0.1)
				(type default)
			)
			(layer "F.Fab")
		)
		(fp_line
			(start 0.120396 0.3048)
			(end 0.120396 0.2794)
			(stroke
				(width 0.1)
				(type default)
			)
			(layer "F.Fab")
		)
		(fp_line
			(start -0.12065 0.3048)
			(end -0.67945 0.3048)
			(stroke
				(width 0.1)
				(type default)
			)
			(layer "F.Fab")
		)
		(fp_line
			(start -0.67945 0.3048)
			(end -0.67945 -0.305054)
			(stroke
				(width 0.1)
				(type default)
			)
			(layer "F.Fab")
		)
		(pad "1" smd circle
			(at -0.40005 0 90)
			(size 0 0)
			(layers "F.Cu" "F.Mask" "F.Paste")
			(net "SMB_SSD9_ISO_EN")
		)
		(pad "2" smd circle
			(at 0.40005 0 90)
			(size 0 0)
			(layers "F.Cu" "F.Mask" "F.Paste")
			(net "P3V3_AUX")
		)
	)
	(footprint ""
		(layer "F.Cu")
		(at 336.03438 -187.061856 180)
		(property "Reference" "R4737"
			(at 0 0 180)
			(layer "F.SilkS")
			(hide yes)
			(effects
				(font
					(size 1.27 1.27)
				)
			)
		)
		(property "Value" ""
			(at 0 0 180)
			(layer "F.Fab")
			(effects
				(font
					(size 1.27 1.27)
				)
			)
		)
		(duplicate_pad_numbers_are_jumpers no)
		(fp_line
			(start 0.7874 0.4064)
			(end -0.7874 0.4064)
			(stroke
				(width 0.1524)
				(type default)
			)
			(layer "F.SilkS")
		)
		(fp_line
			(start 0.7874 -0.4064)
			(end 0.7874 0.4064)
			(stroke
				(width 0.1524)
				(type default)
			)
			(layer "F.SilkS")
		)
		(fp_line
			(start -0.7874 0.4064)
			(end -0.7874 -0.4064)
			(stroke
				(width 0.1524)
				(type default)
			)
			(layer "F.SilkS")
		)
		(fp_line
			(start -0.7874 -0.4064)
			(end 0.7874 -0.4064)
			(stroke
				(width 0.1524)
				(type default)
			)
			(layer "F.SilkS")
		)
		(fp_line
			(start 0.67945 0.3048)
			(end 0.120396 0.3048)
			(stroke
				(width 0.1)
				(type default)
			)
			(layer "F.Fab")
		)
		(fp_line
			(start 0.67945 -0.3048)
			(end 0.67945 0.3048)
			(stroke
				(width 0.1)
				(type default)
			)
			(layer "F.Fab")
		)
		(fp_line
			(start 0.12065 -0.2794)
			(end 0.12065 -0.3048)
			(stroke
				(width 0.1)
				(type default)
			)
			(layer "F.Fab")
		)
		(fp_line
			(start 0.12065 -0.3048)
			(end 0.67945 -0.3048)
			(stroke
				(width 0.1)
				(type default)
			)
			(layer "F.Fab")
		)
		(fp_line
			(start 0.120396 0.3048)
			(end 0.120396 0.2794)
			(stroke
				(width 0.1)
				(type default)
			)
			(layer "F.Fab")
		)
		(fp_line
			(start 0.120396 0.2794)
			(end -0.12065 0.2794)
			(stroke
				(width 0.1)
				(type default)
			)
			(layer "F.Fab")
		)
		(fp_line
			(start -0.12065 0.3048)
			(end -0.67945 0.3048)
			(stroke
				(width 0.1)
				(type default)
			)
			(layer "F.Fab")
		)
		(fp_line
			(start -0.12065 0.2794)
			(end -0.12065 0.3048)
			(stroke
				(width 0.1)
				(type default)
			)
			(layer "F.Fab")
		)
		(fp_line
			(start -0.12065 -0.2794)
			(end 0.12065 -0.2794)
			(stroke
				(width 0.1)
				(type default)
			)
			(layer "F.Fab")
		)
		(fp_line
			(start -0.12065 -0.305054)
			(end -0.12065 -0.2794)
			(stroke
				(width 0.1)
				(type default)
			)
			(layer "F.Fab")
		)
		(fp_line
			(start -0.67945 0.3048)
			(end -0.67945 -0.305054)
			(stroke
				(width 0.1)
				(type default)
			)
			(layer "F.Fab")
		)
		(fp_line
			(start -0.67945 -0.305054)
			(end -0.12065 -0.305054)
			(stroke
				(width 0.1)
				(type default)
			)
			(layer "F.Fab")
		)
		(pad "1" smd circle
			(at -0.40005 0 180)
			(size 0 0)
			(layers "F.Cu" "F.Mask" "F.Paste")
			(net "PEX2_PCA9555_INT_R_N")
		)
		(pad "2" smd circle
			(at 0.40005 0 180)
			(size 0 0)
			(layers "F.Cu" "F.Mask" "F.Paste")
			(net "PEX2_PCA9555_INT_N")
		)
	)
	(footprint ""
		(layer "F.Cu")
		(at 38.875208 -356.244906 90)
		(property "Reference" "C2171"
			(at 0 0 90)
			(layer "F.SilkS")
			(hide yes)
			(effects
				(font
					(size 1.27 1.27)
				)
			)
		)
		(property "Value" ""
			(at 0 0 90)
			(layer "F.Fab")
			(effects
				(font
					(size 1.27 1.27)
				)
			)
		)
		(duplicate_pad_numbers_are_jumpers no)
		(fp_line
			(start 0.299974 -0.150114)
			(end 0.299974 0.150114)
			(stroke
				(width 0.1)
				(type default)
			)
			(layer "F.Fab")
		)
		(fp_line
			(start -0.299974 -0.150114)
			(end 0.299974 -0.150114)
			(stroke
				(width 0.1)
				(type default)
			)
			(layer "F.Fab")
		)
		(fp_line
			(start 0.299974 0.150114)
			(end -0.299974 0.150114)
			(stroke
				(width 0.1)
				(type default)
			)
			(layer "F.Fab")
		)
		(fp_line
			(start -0.299974 0.150114)
			(end -0.299974 -0.150114)
			(stroke
				(width 0.1)
				(type default)
			)
			(layer "F.Fab")
		)
		(pad "1" smd rect
			(at -0.2667 0 90)
			(size 0.3048 0.381)
			(layers "F.Cu" "F.Mask" "F.Paste")
			(net "P5E_PEX0_STN4_TX_DN<70>")
		)
		(pad "2" smd rect
			(at 0.2667 0 90)
			(size 0.3048 0.381)
			(layers "F.Cu" "F.Mask" "F.Paste")
			(net "P5E_PEX0_STN4_TX_C_DN<70>")
		)
	)
	(footprint ""
		(layer "F.Cu")
		(at 310.466994 -57.332626)
		(property "Reference" "R6831"
			(at 0 0 0)
			(layer "F.SilkS")
			(hide yes)
			(effects
				(font
					(size 1.27 1.27)
				)
			)
		)
		(property "Value" ""
			(at 0 0 0)
			(layer "F.Fab")
			(effects
				(font
					(size 1.27 1.27)
				)
			)
		)
		(duplicate_pad_numbers_are_jumpers no)
		(fp_line
			(start -0.7874 -0.4064)
			(end 0.7874 -0.4064)
			(stroke
				(width 0.1524)
				(type default)
			)
			(layer "F.SilkS")
		)
		(fp_line
			(start -0.7874 0.4064)
			(end -0.7874 -0.4064)
			(stroke
				(width 0.1524)
				(type default)
			)
			(layer "F.SilkS")
		)
		(fp_line
			(start 0.7874 -0.4064)
			(end 0.7874 0.4064)
			(stroke
				(width 0.1524)
				(type default)
			)
			(layer "F.SilkS")
		)
		(fp_line
			(start 0.7874 0.4064)
			(end -0.7874 0.4064)
			(stroke
				(width 0.1524)
				(type default)
			)
			(layer "F.SilkS")
		)
		(fp_line
			(start -0.67945 -0.305054)
			(end -0.12065 -0.305054)
			(stroke
				(width 0.1)
				(type default)
			)
			(layer "F.Fab")
		)
		(fp_line
			(start -0.67945 0.3048)
			(end -0.67945 -0.305054)
			(stroke
				(width 0.1)
				(type default)
			)
			(layer "F.Fab")
		)
		(fp_line
			(start -0.12065 -0.305054)
			(end -0.12065 -0.2794)
			(stroke
				(width 0.1)
				(type default)
			)
			(layer "F.Fab")
		)
		(fp_line
			(start -0.12065 -0.2794)
			(end 0.12065 -0.2794)
			(stroke
				(width 0.1)
				(type default)
			)
			(layer "F.Fab")
		)
		(fp_line
			(start -0.12065 0.2794)
			(end -0.12065 0.3048)
			(stroke
				(width 0.1)
				(type default)
			)
			(layer "F.Fab")
		)
		(fp_line
			(start -0.12065 0.3048)
			(end -0.67945 0.3048)
			(stroke
				(width 0.1)
				(type default)
			)
			(layer "F.Fab")
		)
		(fp_line
			(start 0.120396 0.2794)
			(end -0.12065 0.2794)
			(stroke
				(width 0.1)
				(type default)
			)
			(layer "F.Fab")
		)
		(fp_line
			(start 0.120396 0.3048)
			(end 0.120396 0.2794)
			(stroke
				(width 0.1)
				(type default)
			)
			(layer "F.Fab")
		)
		(fp_line
			(start 0.12065 -0.3048)
			(end 0.67945 -0.3048)
			(stroke
				(width 0.1)
				(type default)
			)
			(layer "F.Fab")
		)
		(fp_line
			(start 0.12065 -0.2794)
			(end 0.12065 -0.3048)
			(stroke
				(width 0.1)
				(type default)
			)
			(layer "F.Fab")
		)
		(fp_line
			(start 0.67945 -0.3048)
			(end 0.67945 0.3048)
			(stroke
				(width 0.1)
				(type default)
			)
			(layer "F.Fab")
		)
		(fp_line
			(start 0.67945 0.3048)
			(end 0.120396 0.3048)
			(stroke
				(width 0.1)
				(type default)
			)
			(layer "F.Fab")
		)
		(pad "1" smd circle
			(at -0.40005 0)
			(size 0 0)
			(layers "F.Cu" "F.Mask" "F.Paste")
			(net "SSD10_PWR_EN_R")
		)
		(pad "2" smd circle
			(at 0.40005 0)
			(size 0 0)
			(layers "F.Cu" "F.Mask" "F.Paste")
			(net "GND")
		)
	)
	(footprint ""
		(layer "F.Cu")
		(at 59.319922 -20.72005)
		(property "Reference" "H117"
			(at -0.930148 -2.659634 0)
			(unlocked yes)
			(layer "B.SilkS")
			(effects
				(font
					(size 0.7874 0.5842)
					(thickness 0.1524)
				)
				(justify left mirror)
			)
		)
		(property "Value" ""
			(at 0 0 0)
			(layer "F.Fab")
			(effects
				(font
					(size 1.27 1.27)
				)
			)
		)
		(duplicate_pad_numbers_are_jumpers no)
		(pad "1" thru_hole rect
			(at 0 0)
			(size 4.2164 5.0038)
			(drill 2.0066
				(offset 0.099822 0)
			)
			(layers "*.Cu" "*.Mask")
			(remove_unused_layers no)
			(net "Net_8546")
			(clearance -0.8509)
			(padstack
				(mode front_inner_back)
				(layer "Inner"
					(shape circle)
					(size 4.0132 4.0132)
					(clearance -0.7493)
				)
				(layer "B.Cu"
					(shape circle)
					(size 4.0132 4.0132)
					(clearance -0.7493)
				)
			)
		)
	)
	(footprint ""
		(layer "F.Cu")
		(at 338.074 -161.798 180)
		(property "Reference" "R4825"
			(at 0 0 180)
			(layer "F.SilkS")
			(hide yes)
			(effects
				(font
					(size 1.27 1.27)
				)
			)
		)
		(property "Value" ""
			(at 0 0 180)
			(layer "F.Fab")
			(effects
				(font
					(size 1.27 1.27)
				)
			)
		)
		(duplicate_pad_numbers_are_jumpers no)
		(fp_line
			(start 0.7874 0.4064)
			(end -0.7874 0.4064)
			(stroke
				(width 0.1524)
				(type default)
			)
			(layer "F.SilkS")
		)
		(fp_line
			(start 0.7874 -0.4064)
			(end 0.7874 0.4064)
			(stroke
				(width 0.1524)
				(type default)
			)
			(layer "F.SilkS")
		)
		(fp_line
			(start -0.7874 0.4064)
			(end -0.7874 -0.4064)
			(stroke
				(width 0.1524)
				(type default)
			)
			(layer "F.SilkS")
		)
		(fp_line
			(start -0.7874 -0.4064)
			(end 0.7874 -0.4064)
			(stroke
				(width 0.1524)
				(type default)
			)
			(layer "F.SilkS")
		)
		(fp_line
			(start 0.67945 0.3048)
			(end 0.120396 0.3048)
			(stroke
				(width 0.1)
				(type default)
			)
			(layer "F.Fab")
		)
		(fp_line
			(start 0.67945 -0.3048)
			(end 0.67945 0.3048)
			(stroke
				(width 0.1)
				(type default)
			)
			(layer "F.Fab")
		)
		(fp_line
			(start 0.12065 -0.2794)
			(end 0.12065 -0.3048)
			(stroke
				(width 0.1)
				(type default)
			)
			(layer "F.Fab")
		)
		(fp_line
			(start 0.12065 -0.3048)
			(end 0.67945 -0.3048)
			(stroke
				(width 0.1)
				(type default)
			)
			(layer "F.Fab")
		)
		(fp_line
			(start 0.120396 0.3048)
			(end 0.120396 0.2794)
			(stroke
				(width 0.1)
				(type default)
			)
			(layer "F.Fab")
		)
		(fp_line
			(start 0.120396 0.2794)
			(end -0.12065 0.2794)
			(stroke
				(width 0.1)
				(type default)
			)
			(layer "F.Fab")
		)
		(fp_line
			(start -0.12065 0.3048)
			(end -0.67945 0.3048)
			(stroke
				(width 0.1)
				(type default)
			)
			(layer "F.Fab")
		)
		(fp_line
			(start -0.12065 0.2794)
			(end -0.12065 0.3048)
			(stroke
				(width 0.1)
				(type default)
			)
			(layer "F.Fab")
		)
		(fp_line
			(start -0.12065 -0.2794)
			(end 0.12065 -0.2794)
			(stroke
				(width 0.1)
				(type default)
			)
			(layer "F.Fab")
		)
		(fp_line
			(start -0.12065 -0.305054)
			(end -0.12065 -0.2794)
			(stroke
				(width 0.1)
				(type default)
			)
			(layer "F.Fab")
		)
		(fp_line
			(start -0.67945 0.3048)
			(end -0.67945 -0.305054)
			(stroke
				(width 0.1)
				(type default)
			)
			(layer "F.Fab")
		)
		(fp_line
			(start -0.67945 -0.305054)
			(end -0.12065 -0.305054)
			(stroke
				(width 0.1)
				(type default)
			)
			(layer "F.Fab")
		)
		(pad "1" smd circle
			(at -0.40005 0 180)
			(size 0 0)
			(layers "F.Cu" "F.Mask" "F.Paste")
			(net "GND")
		)
		(pad "2" smd circle
			(at 0.40005 0 180)
			(size 0 0)
			(layers "F.Cu" "F.Mask" "F.Paste")
			(net "PCA9555_0_PEX3_A1")
		)
	)
	(footprint ""
		(layer "F.Cu")
		(at 159.93999 -70.52437 90)
		(property "Reference" "PC844"
			(at 0 0 90)
			(layer "F.SilkS")
			(hide yes)
			(effects
				(font
					(size 1.27 1.27)
				)
			)
		)
		(property "Value" ""
			(at 0 0 90)
			(layer "F.Fab")
			(effects
				(font
					(size 1.27 1.27)
				)
			)
		)
		(duplicate_pad_numbers_are_jumpers no)
		(fp_line
			(start 1.524 -0.762)
			(end 1.524 0.762)
			(stroke
				(width 0.1524)
				(type default)
			)
			(layer "F.SilkS")
		)
		(fp_line
			(start -1.524 -0.762)
			(end 1.524 -0.762)
			(stroke
				(width 0.1524)
				(type default)
			)
			(layer "F.SilkS")
		)
		(fp_line
			(start 1.524 0.762)
			(end -1.524 0.762)
			(stroke
				(width 0.1524)
				(type default)
			)
			(layer "F.SilkS")
		)
		(fp_line
			(start -1.524 0.762)
			(end -1.524 -0.762)
			(stroke
				(width 0.1524)
				(type default)
			)
			(layer "F.SilkS")
		)
		(fp_line
			(start 1.1049 -0.724916)
			(end -1.1049 -0.724916)
			(stroke
				(width 0.1)
				(type default)
			)
			(layer "F.Fab")
		)
		(fp_line
			(start -1.1049 -0.724916)
			(end -1.1049 0.724916)
			(stroke
				(width 0.1)
				(type default)
			)
			(layer "F.Fab")
		)
		(fp_line
			(start 1.1049 0.724916)
			(end 1.1049 -0.724916)
			(stroke
				(width 0.1)
				(type default)
			)
			(layer "F.Fab")
		)
		(fp_line
			(start -1.1049 0.724916)
			(end 1.1049 0.724916)
			(stroke
				(width 0.1)
				(type default)
			)
			(layer "F.Fab")
		)
		(pad "1" smd rect
			(at -0.889 0 270)
			(size 1.016 1.27)
			(layers "F.Cu" "F.Mask" "F.Paste")
			(net "P12V_SSD5_R")
		)
		(pad "2" smd rect
			(at 0.889 0 270)
			(size 1.016 1.27)
			(layers "F.Cu" "F.Mask" "F.Paste")
			(net "GND")
		)
	)
	(footprint ""
		(layer "F.Cu")
		(at 238.124746 -113.777268 180)
		(property "Reference" "R950"
			(at 0 0 180)
			(layer "F.SilkS")
			(hide yes)
			(effects
				(font
					(size 1.27 1.27)
				)
			)
		)
		(property "Value" ""
			(at 0 0 180)
			(layer "F.Fab")
			(effects
				(font
					(size 1.27 1.27)
				)
			)
		)
		(duplicate_pad_numbers_are_jumpers no)
		(fp_line
			(start 0.7874 0.4064)
			(end -0.7874 0.4064)
			(stroke
				(width 0.1524)
				(type default)
			)
			(layer "F.SilkS")
		)
		(fp_line
			(start 0.7874 -0.4064)
			(end 0.7874 0.4064)
			(stroke
				(width 0.1524)
				(type default)
			)
			(layer "F.SilkS")
		)
		(fp_line
			(start -0.7874 0.4064)
			(end -0.7874 -0.4064)
			(stroke
				(width 0.1524)
				(type default)
			)
			(layer "F.SilkS")
		)
		(fp_line
			(start -0.7874 -0.4064)
			(end 0.7874 -0.4064)
			(stroke
				(width 0.1524)
				(type default)
			)
			(layer "F.SilkS")
		)
		(fp_line
			(start 0.67945 0.3048)
			(end 0.120396 0.3048)
			(stroke
				(width 0.1)
				(type default)
			)
			(layer "F.Fab")
		)
		(fp_line
			(start 0.67945 -0.3048)
			(end 0.67945 0.3048)
			(stroke
				(width 0.1)
				(type default)
			)
			(layer "F.Fab")
		)
		(fp_line
			(start 0.12065 -0.2794)
			(end 0.12065 -0.3048)
			(stroke
				(width 0.1)
				(type default)
			)
			(layer "F.Fab")
		)
		(fp_line
			(start 0.12065 -0.3048)
			(end 0.67945 -0.3048)
			(stroke
				(width 0.1)
				(type default)
			)
			(layer "F.Fab")
		)
		(fp_line
			(start 0.120396 0.3048)
			(end 0.120396 0.2794)
			(stroke
				(width 0.1)
				(type default)
			)
			(layer "F.Fab")
		)
		(fp_line
			(start 0.120396 0.2794)
			(end -0.12065 0.2794)
			(stroke
				(width 0.1)
				(type default)
			)
			(layer "F.Fab")
		)
		(fp_line
			(start -0.12065 0.3048)
			(end -0.67945 0.3048)
			(stroke
				(width 0.1)
				(type default)
			)
			(layer "F.Fab")
		)
		(fp_line
			(start -0.12065 0.2794)
			(end -0.12065 0.3048)
			(stroke
				(width 0.1)
				(type default)
			)
			(layer "F.Fab")
		)
		(fp_line
			(start -0.12065 -0.2794)
			(end 0.12065 -0.2794)
			(stroke
				(width 0.1)
				(type default)
			)
			(layer "F.Fab")
		)
		(fp_line
			(start -0.12065 -0.305054)
			(end -0.12065 -0.2794)
			(stroke
				(width 0.1)
				(type default)
			)
			(layer "F.Fab")
		)
		(fp_line
			(start -0.67945 0.3048)
			(end -0.67945 -0.305054)
			(stroke
				(width 0.1)
				(type default)
			)
			(layer "F.Fab")
		)
		(fp_line
			(start -0.67945 -0.305054)
			(end -0.12065 -0.305054)
			(stroke
				(width 0.1)
				(type default)
			)
			(layer "F.Fab")
		)
		(pad "1" smd circle
			(at -0.40005 0 180)
			(size 0 0)
			(layers "F.Cu" "F.Mask" "F.Paste")
			(net "GND")
		)
		(pad "2" smd circle
			(at 0.40005 0 180)
			(size 0 0)
			(layers "F.Cu" "F.Mask" "F.Paste")
			(net "P12V_NIC3_CO_EN")
		)
	)
	(footprint ""
		(layer "F.Cu")
		(at 214.307674 -365.978186 180)
		(property "Reference" "PR32"
			(at 0 0 180)
			(layer "F.SilkS")
			(hide yes)
			(effects
				(font
					(size 1.27 1.27)
				)
			)
		)
		(property "Value" ""
			(at 0 0 180)
			(layer "F.Fab")
			(effects
				(font
					(size 1.27 1.27)
				)
			)
		)
		(duplicate_pad_numbers_are_jumpers no)
		(fp_line
			(start 0.7874 0.4064)
			(end -0.7874 0.4064)
			(stroke
				(width 0.1524)
				(type default)
			)
			(layer "F.SilkS")
		)
		(fp_line
			(start 0.7874 -0.4064)
			(end 0.7874 0.4064)
			(stroke
				(width 0.1524)
				(type default)
			)
			(layer "F.SilkS")
		)
		(fp_line
			(start -0.7874 0.4064)
			(end -0.7874 -0.4064)
			(stroke
				(width 0.1524)
				(type default)
			)
			(layer "F.SilkS")
		)
		(fp_line
			(start -0.7874 -0.4064)
			(end 0.7874 -0.4064)
			(stroke
				(width 0.1524)
				(type default)
			)
			(layer "F.SilkS")
		)
		(fp_line
			(start 0.67945 0.3048)
			(end 0.120396 0.3048)
			(stroke
				(width 0.1)
				(type default)
			)
			(layer "F.Fab")
		)
		(fp_line
			(start 0.67945 -0.3048)
			(end 0.67945 0.3048)
			(stroke
				(width 0.1)
				(type default)
			)
			(layer "F.Fab")
		)
		(fp_line
			(start 0.12065 -0.2794)
			(end 0.12065 -0.3048)
			(stroke
				(width 0.1)
				(type default)
			)
			(layer "F.Fab")
		)
		(fp_line
			(start 0.12065 -0.3048)
			(end 0.67945 -0.3048)
			(stroke
				(width 0.1)
				(type default)
			)
			(layer "F.Fab")
		)
		(fp_line
			(start 0.120396 0.3048)
			(end 0.120396 0.2794)
			(stroke
				(width 0.1)
				(type default)
			)
			(layer "F.Fab")
		)
		(fp_line
			(start 0.120396 0.2794)
			(end -0.12065 0.2794)
			(stroke
				(width 0.1)
				(type default)
			)
			(layer "F.Fab")
		)
		(fp_line
			(start -0.12065 0.3048)
			(end -0.67945 0.3048)
			(stroke
				(width 0.1)
				(type default)
			)
			(layer "F.Fab")
		)
		(fp_line
			(start -0.12065 0.2794)
			(end -0.12065 0.3048)
			(stroke
				(width 0.1)
				(type default)
			)
			(layer "F.Fab")
		)
		(fp_line
			(start -0.12065 -0.2794)
			(end 0.12065 -0.2794)
			(stroke
				(width 0.1)
				(type default)
			)
			(layer "F.Fab")
		)
		(fp_line
			(start -0.12065 -0.305054)
			(end -0.12065 -0.2794)
			(stroke
				(width 0.1)
				(type default)
			)
			(layer "F.Fab")
		)
		(fp_line
			(start -0.67945 0.3048)
			(end -0.67945 -0.305054)
			(stroke
				(width 0.1)
				(type default)
			)
			(layer "F.Fab")
		)
		(fp_line
			(start -0.67945 -0.305054)
			(end -0.12065 -0.305054)
			(stroke
				(width 0.1)
				(type default)
			)
			(layer "F.Fab")
		)
		(pad "1" smd circle
			(at -0.40005 0 180)
			(size 0 0)
			(layers "F.Cu" "F.Mask" "F.Paste")
			(net "HSC_OCREF")
		)
		(pad "2" smd circle
			(at 0.40005 0 180)
			(size 0 0)
			(layers "F.Cu" "F.Mask" "F.Paste")
			(net "AGND_HSC")
		)
	)
	(footprint ""
		(layer "F.Cu")
		(at 437.312308 -300.64202 -90)
		(property "Reference" "R3995"
			(at 0 0 270)
			(layer "F.SilkS")
			(hide yes)
			(effects
				(font
					(size 1.27 1.27)
				)
			)
		)
		(property "Value" ""
			(at 0 0 270)
			(layer "F.Fab")
			(effects
				(font
					(size 1.27 1.27)
				)
			)
		)
		(duplicate_pad_numbers_are_jumpers no)
		(fp_line
			(start -0.7874 0.4064)
			(end -0.7874 -0.4064)
			(stroke
				(width 0.1524)
				(type default)
			)
			(layer "F.SilkS")
		)
		(fp_line
			(start 0.7874 0.4064)
			(end -0.7874 0.4064)
			(stroke
				(width 0.1524)
				(type default)
			)
			(layer "F.SilkS")
		)
		(fp_line
			(start -0.7874 -0.4064)
			(end 0.7874 -0.4064)
			(stroke
				(width 0.1524)
				(type default)
			)
			(layer "F.SilkS")
		)
		(fp_line
			(start 0.7874 -0.4064)
			(end 0.7874 0.4064)
			(stroke
				(width 0.1524)
				(type default)
			)
			(layer "F.SilkS")
		)
		(fp_line
			(start -0.67945 0.3048)
			(end -0.67945 -0.305054)
			(stroke
				(width 0.1)
				(type default)
			)
			(layer "F.Fab")
		)
		(fp_line
			(start -0.12065 0.3048)
			(end -0.67945 0.3048)
			(stroke
				(width 0.1)
				(type default)
			)
			(layer "F.Fab")
		)
		(fp_line
			(start 0.120396 0.3048)
			(end 0.120396 0.2794)
			(stroke
				(width 0.1)
				(type default)
			)
			(layer "F.Fab")
		)
		(fp_line
			(start 0.67945 0.3048)
			(end 0.120396 0.3048)
			(stroke
				(width 0.1)
				(type default)
			)
			(layer "F.Fab")
		)
		(fp_line
			(start -0.12065 0.2794)
			(end -0.12065 0.3048)
			(stroke
				(width 0.1)
				(type default)
			)
			(layer "F.Fab")
		)
		(fp_line
			(start 0.120396 0.2794)
			(end -0.12065 0.2794)
			(stroke
				(width 0.1)
				(type default)
			)
			(layer "F.Fab")
		)
		(fp_line
			(start -0.12065 -0.2794)
			(end 0.12065 -0.2794)
			(stroke
				(width 0.1)
				(type default)
			)
			(layer "F.Fab")
		)
		(fp_line
			(start 0.12065 -0.2794)
			(end 0.12065 -0.3048)
			(stroke
				(width 0.1)
				(type default)
			)
			(layer "F.Fab")
		)
		(fp_line
			(start 0.12065 -0.3048)
			(end 0.67945 -0.3048)
			(stroke
				(width 0.1)
				(type default)
			)
			(layer "F.Fab")
		)
		(fp_line
			(start 0.67945 -0.3048)
			(end 0.67945 0.3048)
			(stroke
				(width 0.1)
				(type default)
			)
			(layer "F.Fab")
		)
		(fp_line
			(start -0.67945 -0.305054)
			(end -0.12065 -0.305054)
			(stroke
				(width 0.1)
				(type default)
			)
			(layer "F.Fab")
		)
		(fp_line
			(start -0.12065 -0.305054)
			(end -0.12065 -0.2794)
			(stroke
				(width 0.1)
				(type default)
			)
			(layer "F.Fab")
		)
		(pad "1" smd circle
			(at -0.40005 0 270)
			(size 0 0)
			(layers "F.Cu" "F.Mask" "F.Paste")
			(net "I2C0_PEX3_SHPC_SDA")
		)
		(pad "2" smd circle
			(at 0.40005 0 270)
			(size 0 0)
			(layers "F.Cu" "F.Mask" "F.Paste")
			(net "I2C_PEX3_HOST_SDA")
		)
	)
	(footprint ""
		(layer "F.Cu")
		(at 195.226178 -39.73576 -90)
		(property "Reference" "R5560"
			(at 0 0 270)
			(layer "F.SilkS")
			(hide yes)
			(effects
				(font
					(size 1.27 1.27)
				)
			)
		)
		(property "Value" ""
			(at 0 0 270)
			(layer "F.Fab")
			(effects
				(font
					(size 1.27 1.27)
				)
			)
		)
		(duplicate_pad_numbers_are_jumpers no)
		(fp_line
			(start -0.7874 0.4064)
			(end -0.7874 -0.4064)
			(stroke
				(width 0.1524)
				(type default)
			)
			(layer "F.SilkS")
		)
		(fp_line
			(start 0.7874 0.4064)
			(end -0.7874 0.4064)
			(stroke
				(width 0.1524)
				(type default)
			)
			(layer "F.SilkS")
		)
		(fp_line
			(start -0.7874 -0.4064)
			(end 0.7874 -0.4064)
			(stroke
				(width 0.1524)
				(type default)
			)
			(layer "F.SilkS")
		)
		(fp_line
			(start 0.7874 -0.4064)
			(end 0.7874 0.4064)
			(stroke
				(width 0.1524)
				(type default)
			)
			(layer "F.SilkS")
		)
		(fp_line
			(start -0.67945 0.3048)
			(end -0.67945 -0.305054)
			(stroke
				(width 0.1)
				(type default)
			)
			(layer "F.Fab")
		)
		(fp_line
			(start -0.12065 0.3048)
			(end -0.67945 0.3048)
			(stroke
				(width 0.1)
				(type default)
			)
			(layer "F.Fab")
		)
		(fp_line
			(start 0.120396 0.3048)
			(end 0.120396 0.2794)
			(stroke
				(width 0.1)
				(type default)
			)
			(layer "F.Fab")
		)
		(fp_line
			(start 0.67945 0.3048)
			(end 0.120396 0.3048)
			(stroke
				(width 0.1)
				(type default)
			)
			(layer "F.Fab")
		)
		(fp_line
			(start -0.12065 0.2794)
			(end -0.12065 0.3048)
			(stroke
				(width 0.1)
				(type default)
			)
			(layer "F.Fab")
		)
		(fp_line
			(start 0.120396 0.2794)
			(end -0.12065 0.2794)
			(stroke
				(width 0.1)
				(type default)
			)
			(layer "F.Fab")
		)
		(fp_line
			(start -0.12065 -0.2794)
			(end 0.12065 -0.2794)
			(stroke
				(width 0.1)
				(type default)
			)
			(layer "F.Fab")
		)
		(fp_line
			(start 0.12065 -0.2794)
			(end 0.12065 -0.3048)
			(stroke
				(width 0.1)
				(type default)
			)
			(layer "F.Fab")
		)
		(fp_line
			(start 0.12065 -0.3048)
			(end 0.67945 -0.3048)
			(stroke
				(width 0.1)
				(type default)
			)
			(layer "F.Fab")
		)
		(fp_line
			(start 0.67945 -0.3048)
			(end 0.67945 0.3048)
			(stroke
				(width 0.1)
				(type default)
			)
			(layer "F.Fab")
		)
		(fp_line
			(start -0.67945 -0.305054)
			(end -0.12065 -0.305054)
			(stroke
				(width 0.1)
				(type default)
			)
			(layer "F.Fab")
		)
		(fp_line
			(start -0.12065 -0.305054)
			(end -0.12065 -0.2794)
			(stroke
				(width 0.1)
				(type default)
			)
			(layer "F.Fab")
		)
		(pad "1" smd circle
			(at -0.40005 0 270)
			(size 0 0)
			(layers "F.Cu" "F.Mask" "F.Paste")
			(net "P3V3_AUX")
		)
		(pad "2" smd circle
			(at 0.40005 0 270)
			(size 0 0)
			(layers "F.Cu" "F.Mask" "F.Paste")
			(net "SSD7_AUX_P3V3_EN")
		)
	)
	(footprint ""
		(layer "F.Cu")
		(at 3.88366 -66.567812 180)
		(property "Reference" "R5870"
			(at 0 0 180)
			(layer "F.SilkS")
			(hide yes)
			(effects
				(font
					(size 1.27 1.27)
				)
			)
		)
		(property "Value" ""
			(at 0 0 180)
			(layer "F.Fab")
			(effects
				(font
					(size 1.27 1.27)
				)
			)
		)
		(duplicate_pad_numbers_are_jumpers no)
		(fp_line
			(start 0.7874 0.4064)
			(end -0.7874 0.4064)
			(stroke
				(width 0.1524)
				(type default)
			)
			(layer "F.SilkS")
		)
		(fp_line
			(start 0.7874 -0.4064)
			(end 0.7874 0.4064)
			(stroke
				(width 0.1524)
				(type default)
			)
			(layer "F.SilkS")
		)
		(fp_line
			(start -0.7874 0.4064)
			(end -0.7874 -0.4064)
			(stroke
				(width 0.1524)
				(type default)
			)
			(layer "F.SilkS")
		)
		(fp_line
			(start -0.7874 -0.4064)
			(end 0.7874 -0.4064)
			(stroke
				(width 0.1524)
				(type default)
			)
			(layer "F.SilkS")
		)
		(fp_line
			(start 0.67945 0.3048)
			(end 0.120396 0.3048)
			(stroke
				(width 0.1)
				(type default)
			)
			(layer "F.Fab")
		)
		(fp_line
			(start 0.67945 -0.3048)
			(end 0.67945 0.3048)
			(stroke
				(width 0.1)
				(type default)
			)
			(layer "F.Fab")
		)
		(fp_line
			(start 0.12065 -0.2794)
			(end 0.12065 -0.3048)
			(stroke
				(width 0.1)
				(type default)
			)
			(layer "F.Fab")
		)
		(fp_line
			(start 0.12065 -0.3048)
			(end 0.67945 -0.3048)
			(stroke
				(width 0.1)
				(type default)
			)
			(layer "F.Fab")
		)
		(fp_line
			(start 0.120396 0.3048)
			(end 0.120396 0.2794)
			(stroke
				(width 0.1)
				(type default)
			)
			(layer "F.Fab")
		)
		(fp_line
			(start 0.120396 0.2794)
			(end -0.12065 0.2794)
			(stroke
				(width 0.1)
				(type default)
			)
			(layer "F.Fab")
		)
		(fp_line
			(start -0.12065 0.3048)
			(end -0.67945 0.3048)
			(stroke
				(width 0.1)
				(type default)
			)
			(layer "F.Fab")
		)
		(fp_line
			(start -0.12065 0.2794)
			(end -0.12065 0.3048)
			(stroke
				(width 0.1)
				(type default)
			)
			(layer "F.Fab")
		)
		(fp_line
			(start -0.12065 -0.2794)
			(end 0.12065 -0.2794)
			(stroke
				(width 0.1)
				(type default)
			)
			(layer "F.Fab")
		)
		(fp_line
			(start -0.12065 -0.305054)
			(end -0.12065 -0.2794)
			(stroke
				(width 0.1)
				(type default)
			)
			(layer "F.Fab")
		)
		(fp_line
			(start -0.67945 0.3048)
			(end -0.67945 -0.305054)
			(stroke
				(width 0.1)
				(type default)
			)
			(layer "F.Fab")
		)
		(fp_line
			(start -0.67945 -0.305054)
			(end -0.12065 -0.305054)
			(stroke
				(width 0.1)
				(type default)
			)
			(layer "F.Fab")
		)
		(pad "1" smd circle
			(at -0.40005 0 180)
			(size 0 0)
			(layers "F.Cu" "F.Mask" "F.Paste")
			(net "PWRGD_P3V3_SSD0_D")
		)
		(pad "2" smd circle
			(at 0.40005 0 180)
			(size 0 0)
			(layers "F.Cu" "F.Mask" "F.Paste")
			(net "PWRGD_P3V3_SSD0_R")
		)
	)
	(footprint ""
		(layer "F.Cu")
		(at 71.526654 -55.418228 90)
		(property "Reference" "PC380"
			(at 0 0 90)
			(layer "F.SilkS")
			(hide yes)
			(effects
				(font
					(size 1.27 1.27)
				)
			)
		)
		(property "Value" ""
			(at 0 0 90)
			(layer "F.Fab")
			(effects
				(font
					(size 1.27 1.27)
				)
			)
		)
		(duplicate_pad_numbers_are_jumpers no)
		(fp_line
			(start 0.7874 -0.4064)
			(end 0.7874 0.4064)
			(stroke
				(width 0.1524)
				(type default)
			)
			(layer "F.SilkS")
		)
		(fp_line
			(start -0.7874 -0.4064)
			(end 0.7874 -0.4064)
			(stroke
				(width 0.1524)
				(type default)
			)
			(layer "F.SilkS")
		)
		(fp_line
			(start 0.7874 0.4064)
			(end -0.7874 0.4064)
			(stroke
				(width 0.1524)
				(type default)
			)
			(layer "F.SilkS")
		)
		(fp_line
			(start -0.7874 0.4064)
			(end -0.7874 -0.4064)
			(stroke
				(width 0.1524)
				(type default)
			)
			(layer "F.SilkS")
		)
		(fp_line
			(start -0.12065 -0.305054)
			(end -0.12065 -0.2794)
			(stroke
				(width 0.1)
				(type default)
			)
			(layer "F.Fab")
		)
		(fp_line
			(start -0.67945 -0.305054)
			(end -0.12065 -0.305054)
			(stroke
				(width 0.1)
				(type default)
			)
			(layer "F.Fab")
		)
		(fp_line
			(start 0.67945 -0.3048)
			(end 0.67945 0.3048)
			(stroke
				(width 0.1)
				(type default)
			)
			(layer "F.Fab")
		)
		(fp_line
			(start 0.12065 -0.3048)
			(end 0.67945 -0.3048)
			(stroke
				(width 0.1)
				(type default)
			)
			(layer "F.Fab")
		)
		(fp_line
			(start 0.12065 -0.2794)
			(end 0.12065 -0.3048)
			(stroke
				(width 0.1)
				(type default)
			)
			(layer "F.Fab")
		)
		(fp_line
			(start -0.12065 -0.2794)
			(end 0.12065 -0.2794)
			(stroke
				(width 0.1)
				(type default)
			)
			(layer "F.Fab")
		)
		(fp_line
			(start 0.120396 0.2794)
			(end -0.12065 0.2794)
			(stroke
				(width 0.1)
				(type default)
			)
			(layer "F.Fab")
		)
		(fp_line
			(start -0.12065 0.2794)
			(end -0.12065 0.3048)
			(stroke
				(width 0.1)
				(type default)
			)
			(layer "F.Fab")
		)
		(fp_line
			(start 0.67945 0.3048)
			(end 0.120396 0.3048)
			(stroke
				(width 0.1)
				(type default)
			)
			(layer "F.Fab")
		)
		(fp_line
			(start 0.120396 0.3048)
			(end 0.120396 0.2794)
			(stroke
				(width 0.1)
				(type default)
			)
			(layer "F.Fab")
		)
		(fp_line
			(start -0.12065 0.3048)
			(end -0.67945 0.3048)
			(stroke
				(width 0.1)
				(type default)
			)
			(layer "F.Fab")
		)
		(fp_line
			(start -0.67945 0.3048)
			(end -0.67945 -0.305054)
			(stroke
				(width 0.1)
				(type default)
			)
			(layer "F.Fab")
		)
		(pad "1" smd circle
			(at -0.40005 0 90)
			(size 0 0)
			(layers "F.Cu" "F.Mask" "F.Paste")
			(net "P12V_SSD2_R")
		)
		(pad "2" smd circle
			(at 0.40005 0 90)
			(size 0 0)
			(layers "F.Cu" "F.Mask" "F.Paste")
			(net "GND")
		)
	)
	(footprint ""
		(layer "F.Cu")
		(at 198.76135 -120.476772 180)
		(property "Reference" "C241"
			(at 0 0 180)
			(layer "F.SilkS")
			(hide yes)
			(effects
				(font
					(size 1.27 1.27)
				)
			)
		)
		(property "Value" ""
			(at 0 0 180)
			(layer "F.Fab")
			(effects
				(font
					(size 1.27 1.27)
				)
			)
		)
		(duplicate_pad_numbers_are_jumpers no)
		(fp_line
			(start 0.299974 0.150114)
			(end -0.299974 0.150114)
			(stroke
				(width 0.1)
				(type default)
			)
			(layer "F.Fab")
		)
		(fp_line
			(start 0.299974 -0.150114)
			(end 0.299974 0.150114)
			(stroke
				(width 0.1)
				(type default)
			)
			(layer "F.Fab")
		)
		(fp_line
			(start -0.299974 0.150114)
			(end -0.299974 -0.150114)
			(stroke
				(width 0.1)
				(type default)
			)
			(layer "F.Fab")
		)
		(fp_line
			(start -0.299974 -0.150114)
			(end 0.299974 -0.150114)
			(stroke
				(width 0.1)
				(type default)
			)
			(layer "F.Fab")
		)
		(pad "1" smd rect
			(at -0.2667 0 180)
			(size 0.3048 0.381)
			(layers "F.Cu" "F.Mask" "F.Paste")
			(net "P5E_PEX1_STN0_TX_DN<1>")
		)
		(pad "2" smd rect
			(at 0.2667 0 180)
			(size 0.3048 0.381)
			(layers "F.Cu" "F.Mask" "F.Paste")
			(net "P5E_PEX1_STN0_TX_C_DN<1>")
		)
	)
	(footprint ""
		(layer "F.Cu")
		(at 220.34373 -47.92091)
		(property "Reference" "R581"
			(at 0 0 0)
			(layer "F.SilkS")
			(hide yes)
			(effects
				(font
					(size 1.27 1.27)
				)
			)
		)
		(property "Value" ""
			(at 0 0 0)
			(layer "F.Fab")
			(effects
				(font
					(size 1.27 1.27)
				)
			)
		)
		(duplicate_pad_numbers_are_jumpers no)
		(fp_line
			(start -0.7874 -0.4064)
			(end 0.7874 -0.4064)
			(stroke
				(width 0.1524)
				(type default)
			)
			(layer "F.SilkS")
		)
		(fp_line
			(start -0.7874 0.4064)
			(end -0.7874 -0.4064)
			(stroke
				(width 0.1524)
				(type default)
			)
			(layer "F.SilkS")
		)
		(fp_line
			(start 0.7874 -0.4064)
			(end 0.7874 0.4064)
			(stroke
				(width 0.1524)
				(type default)
			)
			(layer "F.SilkS")
		)
		(fp_line
			(start 0.7874 0.4064)
			(end -0.7874 0.4064)
			(stroke
				(width 0.1524)
				(type default)
			)
			(layer "F.SilkS")
		)
		(fp_line
			(start -0.67945 -0.305054)
			(end -0.12065 -0.305054)
			(stroke
				(width 0.1)
				(type default)
			)
			(layer "F.Fab")
		)
		(fp_line
			(start -0.67945 0.3048)
			(end -0.67945 -0.305054)
			(stroke
				(width 0.1)
				(type default)
			)
			(layer "F.Fab")
		)
		(fp_line
			(start -0.12065 -0.305054)
			(end -0.12065 -0.2794)
			(stroke
				(width 0.1)
				(type default)
			)
			(layer "F.Fab")
		)
		(fp_line
			(start -0.12065 -0.2794)
			(end 0.12065 -0.2794)
			(stroke
				(width 0.1)
				(type default)
			)
			(layer "F.Fab")
		)
		(fp_line
			(start -0.12065 0.2794)
			(end -0.12065 0.3048)
			(stroke
				(width 0.1)
				(type default)
			)
			(layer "F.Fab")
		)
		(fp_line
			(start -0.12065 0.3048)
			(end -0.67945 0.3048)
			(stroke
				(width 0.1)
				(type default)
			)
			(layer "F.Fab")
		)
		(fp_line
			(start 0.120396 0.2794)
			(end -0.12065 0.2794)
			(stroke
				(width 0.1)
				(type default)
			)
			(layer "F.Fab")
		)
		(fp_line
			(start 0.120396 0.3048)
			(end 0.120396 0.2794)
			(stroke
				(width 0.1)
				(type default)
			)
			(layer "F.Fab")
		)
		(fp_line
			(start 0.12065 -0.3048)
			(end 0.67945 -0.3048)
			(stroke
				(width 0.1)
				(type default)
			)
			(layer "F.Fab")
		)
		(fp_line
			(start 0.12065 -0.2794)
			(end 0.12065 -0.3048)
			(stroke
				(width 0.1)
				(type default)
			)
			(layer "F.Fab")
		)
		(fp_line
			(start 0.67945 -0.3048)
			(end 0.67945 0.3048)
			(stroke
				(width 0.1)
				(type default)
			)
			(layer "F.Fab")
		)
		(fp_line
			(start 0.67945 0.3048)
			(end 0.120396 0.3048)
			(stroke
				(width 0.1)
				(type default)
			)
			(layer "F.Fab")
		)
		(pad "1" smd circle
			(at -0.40005 0)
			(size 0 0)
			(layers "F.Cu" "F.Mask" "F.Paste")
			(net "P3V3_AUX")
		)
		(pad "2" smd circle
			(at 0.40005 0)
			(size 0 0)
			(layers "F.Cu" "F.Mask" "F.Paste")
			(net "SSD_0_7_ADC_ALERT_N")
		)
	)
	(footprint ""
		(layer "F.Cu")
		(at 360.607356 -238.580168 180)
		(property "Reference" "R6407"
			(at 0 0 180)
			(layer "F.SilkS")
			(hide yes)
			(effects
				(font
					(size 1.27 1.27)
				)
			)
		)
		(property "Value" ""
			(at 0 0 180)
			(layer "F.Fab")
			(effects
				(font
					(size 1.27 1.27)
				)
			)
		)
		(duplicate_pad_numbers_are_jumpers no)
		(fp_line
			(start 0.7874 0.4064)
			(end -0.7874 0.4064)
			(stroke
				(width 0.1524)
				(type default)
			)
			(layer "F.SilkS")
		)
		(fp_line
			(start 0.7874 -0.4064)
			(end 0.7874 0.4064)
			(stroke
				(width 0.1524)
				(type default)
			)
			(layer "F.SilkS")
		)
		(fp_line
			(start -0.7874 0.4064)
			(end -0.7874 -0.4064)
			(stroke
				(width 0.1524)
				(type default)
			)
			(layer "F.SilkS")
		)
		(fp_line
			(start -0.7874 -0.4064)
			(end 0.7874 -0.4064)
			(stroke
				(width 0.1524)
				(type default)
			)
			(layer "F.SilkS")
		)
		(fp_line
			(start 0.67945 0.3048)
			(end 0.120396 0.3048)
			(stroke
				(width 0.1)
				(type default)
			)
			(layer "F.Fab")
		)
		(fp_line
			(start 0.67945 -0.3048)
			(end 0.67945 0.3048)
			(stroke
				(width 0.1)
				(type default)
			)
			(layer "F.Fab")
		)
		(fp_line
			(start 0.12065 -0.2794)
			(end 0.12065 -0.3048)
			(stroke
				(width 0.1)
				(type default)
			)
			(layer "F.Fab")
		)
		(fp_line
			(start 0.12065 -0.3048)
			(end 0.67945 -0.3048)
			(stroke
				(width 0.1)
				(type default)
			)
			(layer "F.Fab")
		)
		(fp_line
			(start 0.120396 0.3048)
			(end 0.120396 0.2794)
			(stroke
				(width 0.1)
				(type default)
			)
			(layer "F.Fab")
		)
		(fp_line
			(start 0.120396 0.2794)
			(end -0.12065 0.2794)
			(stroke
				(width 0.1)
				(type default)
			)
			(layer "F.Fab")
		)
		(fp_line
			(start -0.12065 0.3048)
			(end -0.67945 0.3048)
			(stroke
				(width 0.1)
				(type default)
			)
			(layer "F.Fab")
		)
		(fp_line
			(start -0.12065 0.2794)
			(end -0.12065 0.3048)
			(stroke
				(width 0.1)
				(type default)
			)
			(layer "F.Fab")
		)
		(fp_line
			(start -0.12065 -0.2794)
			(end 0.12065 -0.2794)
			(stroke
				(width 0.1)
				(type default)
			)
			(layer "F.Fab")
		)
		(fp_line
			(start -0.12065 -0.305054)
			(end -0.12065 -0.2794)
			(stroke
				(width 0.1)
				(type default)
			)
			(layer "F.Fab")
		)
		(fp_line
			(start -0.67945 0.3048)
			(end -0.67945 -0.305054)
			(stroke
				(width 0.1)
				(type default)
			)
			(layer "F.Fab")
		)
		(fp_line
			(start -0.67945 -0.305054)
			(end -0.12065 -0.305054)
			(stroke
				(width 0.1)
				(type default)
			)
			(layer "F.Fab")
		)
		(pad "1" smd circle
			(at -0.40005 0 180)
			(size 0 0)
			(layers "F.Cu" "F.Mask" "F.Paste")
			(net "PWRGD_P5V_AUX_R2")
		)
		(pad "2" smd circle
			(at 0.40005 0 180)
			(size 0 0)
			(layers "F.Cu" "F.Mask" "F.Paste")
			(net "PWRGD_P5V_AUX_R")
		)
	)
	(footprint ""
		(layer "F.Cu")
		(at 83.589368 -63.56223)
		(property "Reference" "Q130"
			(at -0.224028 -2.570734 0)
			(unlocked yes)
			(layer "F.SilkS")
			(effects
				(font
					(size 0.7874 0.5842)
					(thickness 0.1524)
				)
			)
		)
		(property "Value" ""
			(at 0 0 0)
			(layer "F.Fab")
			(effects
				(font
					(size 1.27 1.27)
				)
			)
		)
		(duplicate_pad_numbers_are_jumpers no)
		(fp_line
			(start -1.376172 -1.199896)
			(end -0.508 -1.199896)
			(stroke
				(width 0.1524)
				(type default)
			)
			(layer "F.SilkS")
		)
		(fp_line
			(start -1.376172 1.199896)
			(end -1.376172 -1.199896)
			(stroke
				(width 0.1524)
				(type default)
			)
			(layer "F.SilkS")
		)
		(fp_line
			(start -0.508 -1.199896)
			(end 0 -0.762)
			(stroke
				(width 0.1524)
				(type default)
			)
			(layer "F.SilkS")
		)
		(fp_line
			(start 0 -0.762)
			(end 0.508 -1.199896)
			(stroke
				(width 0.1524)
				(type default)
			)
			(layer "F.SilkS")
		)
		(fp_line
			(start 0.508 -1.199896)
			(end 1.376172 -1.199896)
			(stroke
				(width 0.1524)
				(type default)
			)
			(layer "F.SilkS")
		)
		(fp_line
			(start 1.376172 -1.199896)
			(end 1.376172 1.199896)
			(stroke
				(width 0.1524)
				(type default)
			)
			(layer "F.SilkS")
		)
		(fp_line
			(start 1.376172 1.199896)
			(end -1.376172 1.199896)
			(stroke
				(width 0.1524)
				(type default)
			)
			(layer "F.SilkS")
		)
		(fp_poly
			(pts
				(xy -1.586738 -0.940308) (xy -1.856232 -1.748536) (xy -2.394966 -1.209802)
			)
			(stroke
				(width 0)
				(type default)
			)
			(fill yes)
			(layer "F.SilkS")
		)
		(fp_line
			(start -0.674878 -1.100074)
			(end 0.674878 -1.100074)
			(stroke
				(width 0.1)
				(type default)
			)
			(layer "F.Fab")
		)
		(fp_line
			(start -0.674878 1.100074)
			(end -0.674878 -1.100074)
			(stroke
				(width 0.1)
				(type default)
			)
			(layer "F.Fab")
		)
		(fp_line
			(start 0.674878 -1.100074)
			(end 0.674878 1.100074)
			(stroke
				(width 0.1)
				(type default)
			)
			(layer "F.Fab")
		)
		(fp_line
			(start 0.674878 1.100074)
			(end -0.674878 1.100074)
			(stroke
				(width 0.1)
				(type default)
			)
			(layer "F.Fab")
		)
		(fp_poly
			(pts
				(xy -1.4605 -0.7493) (xy -2.2225 -1.1303) (xy -2.2225 -0.3683)
			)
			(stroke
				(width 0)
				(type default)
			)
			(fill yes)
			(layer "F.Fab")
		)
		(pad "1" smd rect
			(at -0.899922 -0.750062 270)
			(size 0.6096 0.6096)
			(layers "F.Cu" "F.Mask" "F.Paste")
			(net "GND")
		)
		(pad "2" smd rect
			(at -0.899922 0 270)
			(size 0.4064 0.6096)
			(layers "F.Cu" "F.Mask" "F.Paste")
			(net "P12V_SSD3_PG_G1")
		)
		(pad "3" smd rect
			(at -0.899922 0.750062 270)
			(size 0.6096 0.6096)
			(layers "F.Cu" "F.Mask" "F.Paste")
			(net "PWRGD_P12V_SSD3_D")
		)
		(pad "4" smd rect
			(at 0.899922 0.750062 270)
			(size 0.6096 0.6096)
			(layers "F.Cu" "F.Mask" "F.Paste")
			(net "GND")
		)
		(pad "5" smd rect
			(at 0.899922 0 270)
			(size 0.4064 0.6096)
			(layers "F.Cu" "F.Mask" "F.Paste")
			(net "P12V_SSD3_PG_G2")
		)
		(pad "6" smd rect
			(at 0.899922 -0.750062 270)
			(size 0.6096 0.6096)
			(layers "F.Cu" "F.Mask" "F.Paste")
			(net "P12V_SSD3_PG_G2")
		)
	)
	(footprint ""
		(layer "F.Cu")
		(at 171.457874 -27.006296 -90)
		(property "Reference" "PR7111"
			(at 0 0 270)
			(layer "F.SilkS")
			(hide yes)
			(effects
				(font
					(size 1.27 1.27)
				)
			)
		)
		(property "Value" ""
			(at 0 0 270)
			(layer "F.Fab")
			(effects
				(font
					(size 1.27 1.27)
				)
			)
		)
		(duplicate_pad_numbers_are_jumpers no)
		(fp_line
			(start -0.7874 0.4064)
			(end -0.7874 -0.4064)
			(stroke
				(width 0.1524)
				(type default)
			)
			(layer "F.SilkS")
		)
		(fp_line
			(start 0.7874 0.4064)
			(end -0.7874 0.4064)
			(stroke
				(width 0.1524)
				(type default)
			)
			(layer "F.SilkS")
		)
		(fp_line
			(start -0.7874 -0.4064)
			(end 0.7874 -0.4064)
			(stroke
				(width 0.1524)
				(type default)
			)
			(layer "F.SilkS")
		)
		(fp_line
			(start 0.7874 -0.4064)
			(end 0.7874 0.4064)
			(stroke
				(width 0.1524)
				(type default)
			)
			(layer "F.SilkS")
		)
		(fp_line
			(start -0.67945 0.3048)
			(end -0.67945 -0.305054)
			(stroke
				(width 0.1)
				(type default)
			)
			(layer "F.Fab")
		)
		(fp_line
			(start -0.12065 0.3048)
			(end -0.67945 0.3048)
			(stroke
				(width 0.1)
				(type default)
			)
			(layer "F.Fab")
		)
		(fp_line
			(start 0.120396 0.3048)
			(end 0.120396 0.2794)
			(stroke
				(width 0.1)
				(type default)
			)
			(layer "F.Fab")
		)
		(fp_line
			(start 0.67945 0.3048)
			(end 0.120396 0.3048)
			(stroke
				(width 0.1)
				(type default)
			)
			(layer "F.Fab")
		)
		(fp_line
			(start -0.12065 0.2794)
			(end -0.12065 0.3048)
			(stroke
				(width 0.1)
				(type default)
			)
			(layer "F.Fab")
		)
		(fp_line
			(start 0.120396 0.2794)
			(end -0.12065 0.2794)
			(stroke
				(width 0.1)
				(type default)
			)
			(layer "F.Fab")
		)
		(fp_line
			(start -0.12065 -0.2794)
			(end 0.12065 -0.2794)
			(stroke
				(width 0.1)
				(type default)
			)
			(layer "F.Fab")
		)
		(fp_line
			(start 0.12065 -0.2794)
			(end 0.12065 -0.3048)
			(stroke
				(width 0.1)
				(type default)
			)
			(layer "F.Fab")
		)
		(fp_line
			(start 0.12065 -0.3048)
			(end 0.67945 -0.3048)
			(stroke
				(width 0.1)
				(type default)
			)
			(layer "F.Fab")
		)
		(fp_line
			(start 0.67945 -0.3048)
			(end 0.67945 0.3048)
			(stroke
				(width 0.1)
				(type default)
			)
			(layer "F.Fab")
		)
		(fp_line
			(start -0.67945 -0.305054)
			(end -0.12065 -0.305054)
			(stroke
				(width 0.1)
				(type default)
			)
			(layer "F.Fab")
		)
		(fp_line
			(start -0.12065 -0.305054)
			(end -0.12065 -0.2794)
			(stroke
				(width 0.1)
				(type default)
			)
			(layer "F.Fab")
		)
		(pad "1" smd circle
			(at -0.40005 0 270)
			(size 0 0)
			(layers "F.Cu" "F.Mask" "F.Paste")
			(net "P3V3_SSD6_CO_MODE")
		)
		(pad "2" smd circle
			(at 0.40005 0 270)
			(size 0 0)
			(layers "F.Cu" "F.Mask" "F.Paste")
			(net "GND")
		)
	)
	(footprint ""
		(layer "F.Cu")
		(at 144.956276 -32.848042 -90)
		(property "Reference" "R6055"
			(at 0 0 270)
			(layer "F.SilkS")
			(hide yes)
			(effects
				(font
					(size 1.27 1.27)
				)
			)
		)
		(property "Value" ""
			(at 0 0 270)
			(layer "F.Fab")
			(effects
				(font
					(size 1.27 1.27)
				)
			)
		)
		(duplicate_pad_numbers_are_jumpers no)
		(fp_line
			(start -0.7874 0.4064)
			(end -0.7874 -0.4064)
			(stroke
				(width 0.1524)
				(type default)
			)
			(layer "F.SilkS")
		)
		(fp_line
			(start 0.7874 0.4064)
			(end -0.7874 0.4064)
			(stroke
				(width 0.1524)
				(type default)
			)
			(layer "F.SilkS")
		)
		(fp_line
			(start -0.7874 -0.4064)
			(end 0.7874 -0.4064)
			(stroke
				(width 0.1524)
				(type default)
			)
			(layer "F.SilkS")
		)
		(fp_line
			(start 0.7874 -0.4064)
			(end 0.7874 0.4064)
			(stroke
				(width 0.1524)
				(type default)
			)
			(layer "F.SilkS")
		)
		(fp_line
			(start -0.67945 0.3048)
			(end -0.67945 -0.305054)
			(stroke
				(width 0.1)
				(type default)
			)
			(layer "F.Fab")
		)
		(fp_line
			(start -0.12065 0.3048)
			(end -0.67945 0.3048)
			(stroke
				(width 0.1)
				(type default)
			)
			(layer "F.Fab")
		)
		(fp_line
			(start 0.120396 0.3048)
			(end 0.120396 0.2794)
			(stroke
				(width 0.1)
				(type default)
			)
			(layer "F.Fab")
		)
		(fp_line
			(start 0.67945 0.3048)
			(end 0.120396 0.3048)
			(stroke
				(width 0.1)
				(type default)
			)
			(layer "F.Fab")
		)
		(fp_line
			(start -0.12065 0.2794)
			(end -0.12065 0.3048)
			(stroke
				(width 0.1)
				(type default)
			)
			(layer "F.Fab")
		)
		(fp_line
			(start 0.120396 0.2794)
			(end -0.12065 0.2794)
			(stroke
				(width 0.1)
				(type default)
			)
			(layer "F.Fab")
		)
		(fp_line
			(start -0.12065 -0.2794)
			(end 0.12065 -0.2794)
			(stroke
				(width 0.1)
				(type default)
			)
			(layer "F.Fab")
		)
		(fp_line
			(start 0.12065 -0.2794)
			(end 0.12065 -0.3048)
			(stroke
				(width 0.1)
				(type default)
			)
			(layer "F.Fab")
		)
		(fp_line
			(start 0.12065 -0.3048)
			(end 0.67945 -0.3048)
			(stroke
				(width 0.1)
				(type default)
			)
			(layer "F.Fab")
		)
		(fp_line
			(start 0.67945 -0.3048)
			(end 0.67945 0.3048)
			(stroke
				(width 0.1)
				(type default)
			)
			(layer "F.Fab")
		)
		(fp_line
			(start -0.67945 -0.305054)
			(end -0.12065 -0.305054)
			(stroke
				(width 0.1)
				(type default)
			)
			(layer "F.Fab")
		)
		(fp_line
			(start -0.12065 -0.305054)
			(end -0.12065 -0.2794)
			(stroke
				(width 0.1)
				(type default)
			)
			(layer "F.Fab")
		)
		(pad "1" smd circle
			(at -0.40005 0 270)
			(size 0 0)
			(layers "F.Cu" "F.Mask" "F.Paste")
			(net "SSD5_AUX_P3V3_EN_R")
		)
		(pad "2" smd circle
			(at 0.40005 0 270)
			(size 0 0)
			(layers "F.Cu" "F.Mask" "F.Paste")
			(net "P3V3_SSD5_CO_EN")
		)
	)
	(footprint ""
		(layer "F.Cu")
		(at 252.374908 -48.753014 180)
		(property "Reference" "C321"
			(at 0 0 180)
			(layer "F.SilkS")
			(hide yes)
			(effects
				(font
					(size 1.27 1.27)
				)
			)
		)
		(property "Value" ""
			(at 0 0 180)
			(layer "F.Fab")
			(effects
				(font
					(size 1.27 1.27)
				)
			)
		)
		(duplicate_pad_numbers_are_jumpers no)
		(fp_line
			(start 0.7874 0.4064)
			(end -0.7874 0.4064)
			(stroke
				(width 0.1524)
				(type default)
			)
			(layer "F.SilkS")
		)
		(fp_line
			(start 0.7874 -0.4064)
			(end 0.7874 0.4064)
			(stroke
				(width 0.1524)
				(type default)
			)
			(layer "F.SilkS")
		)
		(fp_line
			(start -0.7874 0.4064)
			(end -0.7874 -0.4064)
			(stroke
				(width 0.1524)
				(type default)
			)
			(layer "F.SilkS")
		)
		(fp_line
			(start -0.7874 -0.4064)
			(end 0.7874 -0.4064)
			(stroke
				(width 0.1524)
				(type default)
			)
			(layer "F.SilkS")
		)
		(fp_line
			(start 0.67945 0.3048)
			(end 0.120396 0.3048)
			(stroke
				(width 0.1)
				(type default)
			)
			(layer "F.Fab")
		)
		(fp_line
			(start 0.67945 -0.3048)
			(end 0.67945 0.3048)
			(stroke
				(width 0.1)
				(type default)
			)
			(layer "F.Fab")
		)
		(fp_line
			(start 0.12065 -0.2794)
			(end 0.12065 -0.3048)
			(stroke
				(width 0.1)
				(type default)
			)
			(layer "F.Fab")
		)
		(fp_line
			(start 0.12065 -0.3048)
			(end 0.67945 -0.3048)
			(stroke
				(width 0.1)
				(type default)
			)
			(layer "F.Fab")
		)
		(fp_line
			(start 0.120396 0.3048)
			(end 0.120396 0.2794)
			(stroke
				(width 0.1)
				(type default)
			)
			(layer "F.Fab")
		)
		(fp_line
			(start 0.120396 0.2794)
			(end -0.12065 0.2794)
			(stroke
				(width 0.1)
				(type default)
			)
			(layer "F.Fab")
		)
		(fp_line
			(start -0.12065 0.3048)
			(end -0.67945 0.3048)
			(stroke
				(width 0.1)
				(type default)
			)
			(layer "F.Fab")
		)
		(fp_line
			(start -0.12065 0.2794)
			(end -0.12065 0.3048)
			(stroke
				(width 0.1)
				(type default)
			)
			(layer "F.Fab")
		)
		(fp_line
			(start -0.12065 -0.2794)
			(end 0.12065 -0.2794)
			(stroke
				(width 0.1)
				(type default)
			)
			(layer "F.Fab")
		)
		(fp_line
			(start -0.12065 -0.305054)
			(end -0.12065 -0.2794)
			(stroke
				(width 0.1)
				(type default)
			)
			(layer "F.Fab")
		)
		(fp_line
			(start -0.67945 0.3048)
			(end -0.67945 -0.305054)
			(stroke
				(width 0.1)
				(type default)
			)
			(layer "F.Fab")
		)
		(fp_line
			(start -0.67945 -0.305054)
			(end -0.12065 -0.305054)
			(stroke
				(width 0.1)
				(type default)
			)
			(layer "F.Fab")
		)
		(pad "1" smd circle
			(at -0.40005 0 180)
			(size 0 0)
			(layers "F.Cu" "F.Mask" "F.Paste")
			(net "P3V3_AUX")
		)
		(pad "2" smd circle
			(at 0.40005 0 180)
			(size 0 0)
			(layers "F.Cu" "F.Mask" "F.Paste")
			(net "GND")
		)
	)
	(footprint ""
		(layer "F.Cu")
		(at 82.373724 -27.006296 -90)
		(property "Reference" "PC686"
			(at 0 0 270)
			(layer "F.SilkS")
			(hide yes)
			(effects
				(font
					(size 1.27 1.27)
				)
			)
		)
		(property "Value" ""
			(at 0 0 270)
			(layer "F.Fab")
			(effects
				(font
					(size 1.27 1.27)
				)
			)
		)
		(duplicate_pad_numbers_are_jumpers no)
		(fp_line
			(start -0.7874 0.4064)
			(end -0.7874 -0.4064)
			(stroke
				(width 0.1524)
				(type default)
			)
			(layer "F.SilkS")
		)
		(fp_line
			(start 0.7874 0.4064)
			(end -0.7874 0.4064)
			(stroke
				(width 0.1524)
				(type default)
			)
			(layer "F.SilkS")
		)
		(fp_line
			(start -0.7874 -0.4064)
			(end 0.7874 -0.4064)
			(stroke
				(width 0.1524)
				(type default)
			)
			(layer "F.SilkS")
		)
		(fp_line
			(start 0.7874 -0.4064)
			(end 0.7874 0.4064)
			(stroke
				(width 0.1524)
				(type default)
			)
			(layer "F.SilkS")
		)
		(fp_line
			(start -0.67945 0.3048)
			(end -0.67945 -0.305054)
			(stroke
				(width 0.1)
				(type default)
			)
			(layer "F.Fab")
		)
		(fp_line
			(start -0.12065 0.3048)
			(end -0.67945 0.3048)
			(stroke
				(width 0.1)
				(type default)
			)
			(layer "F.Fab")
		)
		(fp_line
			(start 0.120396 0.3048)
			(end 0.120396 0.2794)
			(stroke
				(width 0.1)
				(type default)
			)
			(layer "F.Fab")
		)
		(fp_line
			(start 0.67945 0.3048)
			(end 0.120396 0.3048)
			(stroke
				(width 0.1)
				(type default)
			)
			(layer "F.Fab")
		)
		(fp_line
			(start -0.12065 0.2794)
			(end -0.12065 0.3048)
			(stroke
				(width 0.1)
				(type default)
			)
			(layer "F.Fab")
		)
		(fp_line
			(start 0.120396 0.2794)
			(end -0.12065 0.2794)
			(stroke
				(width 0.1)
				(type default)
			)
			(layer "F.Fab")
		)
		(fp_line
			(start -0.12065 -0.2794)
			(end 0.12065 -0.2794)
			(stroke
				(width 0.1)
				(type default)
			)
			(layer "F.Fab")
		)
		(fp_line
			(start 0.12065 -0.2794)
			(end 0.12065 -0.3048)
			(stroke
				(width 0.1)
				(type default)
			)
			(layer "F.Fab")
		)
		(fp_line
			(start 0.12065 -0.3048)
			(end 0.67945 -0.3048)
			(stroke
				(width 0.1)
				(type default)
			)
			(layer "F.Fab")
		)
		(fp_line
			(start 0.67945 -0.3048)
			(end 0.67945 0.3048)
			(stroke
				(width 0.1)
				(type default)
			)
			(layer "F.Fab")
		)
		(fp_line
			(start -0.67945 -0.305054)
			(end -0.12065 -0.305054)
			(stroke
				(width 0.1)
				(type default)
			)
			(layer "F.Fab")
		)
		(fp_line
			(start -0.12065 -0.305054)
			(end -0.12065 -0.2794)
			(stroke
				(width 0.1)
				(type default)
			)
			(layer "F.Fab")
		)
		(pad "1" smd circle
			(at -0.40005 0 270)
			(size 0 0)
			(layers "F.Cu" "F.Mask" "F.Paste")
			(net "P3V3_SSD3_CO_MODE")
		)
		(pad "2" smd circle
			(at 0.40005 0 270)
			(size 0 0)
			(layers "F.Cu" "F.Mask" "F.Paste")
			(net "GND")
		)
	)
	(footprint ""
		(layer "F.Cu")
		(at 360.713528 -268.352524 -90)
		(property "Reference" "PC985"
			(at 0 0 270)
			(layer "F.SilkS")
			(hide yes)
			(effects
				(font
					(size 1.27 1.27)
				)
			)
		)
		(property "Value" ""
			(at 0 0 270)
			(layer "F.Fab")
			(effects
				(font
					(size 1.27 1.27)
				)
			)
		)
		(duplicate_pad_numbers_are_jumpers no)
		(fp_line
			(start -0.7874 0.4064)
			(end -0.7874 -0.4064)
			(stroke
				(width 0.1524)
				(type default)
			)
			(layer "F.SilkS")
		)
		(fp_line
			(start 0.7874 0.4064)
			(end -0.7874 0.4064)
			(stroke
				(width 0.1524)
				(type default)
			)
			(layer "F.SilkS")
		)
		(fp_line
			(start -0.7874 -0.4064)
			(end 0.7874 -0.4064)
			(stroke
				(width 0.1524)
				(type default)
			)
			(layer "F.SilkS")
		)
		(fp_line
			(start 0.7874 -0.4064)
			(end 0.7874 0.4064)
			(stroke
				(width 0.1524)
				(type default)
			)
			(layer "F.SilkS")
		)
		(fp_line
			(start -0.67945 0.3048)
			(end -0.67945 -0.305054)
			(stroke
				(width 0.1)
				(type default)
			)
			(layer "F.Fab")
		)
		(fp_line
			(start -0.12065 0.3048)
			(end -0.67945 0.3048)
			(stroke
				(width 0.1)
				(type default)
			)
			(layer "F.Fab")
		)
		(fp_line
			(start 0.120396 0.3048)
			(end 0.120396 0.2794)
			(stroke
				(width 0.1)
				(type default)
			)
			(layer "F.Fab")
		)
		(fp_line
			(start 0.67945 0.3048)
			(end 0.120396 0.3048)
			(stroke
				(width 0.1)
				(type default)
			)
			(layer "F.Fab")
		)
		(fp_line
			(start -0.12065 0.2794)
			(end -0.12065 0.3048)
			(stroke
				(width 0.1)
				(type default)
			)
			(layer "F.Fab")
		)
		(fp_line
			(start 0.120396 0.2794)
			(end -0.12065 0.2794)
			(stroke
				(width 0.1)
				(type default)
			)
			(layer "F.Fab")
		)
		(fp_line
			(start -0.12065 -0.2794)
			(end 0.12065 -0.2794)
			(stroke
				(width 0.1)
				(type default)
			)
			(layer "F.Fab")
		)
		(fp_line
			(start 0.12065 -0.2794)
			(end 0.12065 -0.3048)
			(stroke
				(width 0.1)
				(type default)
			)
			(layer "F.Fab")
		)
		(fp_line
			(start 0.12065 -0.3048)
			(end 0.67945 -0.3048)
			(stroke
				(width 0.1)
				(type default)
			)
			(layer "F.Fab")
		)
		(fp_line
			(start 0.67945 -0.3048)
			(end 0.67945 0.3048)
			(stroke
				(width 0.1)
				(type default)
			)
			(layer "F.Fab")
		)
		(fp_line
			(start -0.67945 -0.305054)
			(end -0.12065 -0.305054)
			(stroke
				(width 0.1)
				(type default)
			)
			(layer "F.Fab")
		)
		(fp_line
			(start -0.12065 -0.305054)
			(end -0.12065 -0.2794)
			(stroke
				(width 0.1)
				(type default)
			)
			(layer "F.Fab")
		)
		(pad "1" smd circle
			(at -0.40005 0 270)
			(size 0 0)
			(layers "F.Cu" "F.Mask" "F.Paste")
			(net "P12V_AUX")
		)
		(pad "2" smd circle
			(at 0.40005 0 270)
			(size 0 0)
			(layers "F.Cu" "F.Mask" "F.Paste")
			(net "GND")
		)
	)
	(footprint ""
		(layer "F.Cu")
		(at 353.694238 -29.507688 -90)
		(property "Reference" "PC962"
			(at 0 0 270)
			(layer "F.SilkS")
			(hide yes)
			(effects
				(font
					(size 1.27 1.27)
				)
			)
		)
		(property "Value" ""
			(at 0 0 270)
			(layer "F.Fab")
			(effects
				(font
					(size 1.27 1.27)
				)
			)
		)
		(duplicate_pad_numbers_are_jumpers no)
		(fp_line
			(start -1.524 0.762)
			(end -1.524 -0.762)
			(stroke
				(width 0.1524)
				(type default)
			)
			(layer "F.SilkS")
		)
		(fp_line
			(start 1.524 0.762)
			(end -1.524 0.762)
			(stroke
				(width 0.1524)
				(type default)
			)
			(layer "F.SilkS")
		)
		(fp_line
			(start -1.524 -0.762)
			(end 1.524 -0.762)
			(stroke
				(width 0.1524)
				(type default)
			)
			(layer "F.SilkS")
		)
		(fp_line
			(start 1.524 -0.762)
			(end 1.524 0.762)
			(stroke
				(width 0.1524)
				(type default)
			)
			(layer "F.SilkS")
		)
		(fp_line
			(start -1.1049 0.724916)
			(end 1.1049 0.724916)
			(stroke
				(width 0.1)
				(type default)
			)
			(layer "F.Fab")
		)
		(fp_line
			(start 1.1049 0.724916)
			(end 1.1049 -0.724916)
			(stroke
				(width 0.1)
				(type default)
			)
			(layer "F.Fab")
		)
		(fp_line
			(start -1.1049 -0.724916)
			(end -1.1049 0.724916)
			(stroke
				(width 0.1)
				(type default)
			)
			(layer "F.Fab")
		)
		(fp_line
			(start 1.1049 -0.724916)
			(end -1.1049 -0.724916)
			(stroke
				(width 0.1)
				(type default)
			)
			(layer "F.Fab")
		)
		(pad "1" smd rect
			(at -0.889 0 90)
			(size 1.016 1.27)
			(layers "F.Cu" "F.Mask" "F.Paste")
			(net "P3V3_SSD12")
		)
		(pad "2" smd rect
			(at 0.889 0 90)
			(size 1.016 1.27)
			(layers "F.Cu" "F.Mask" "F.Paste")
			(net "GND")
		)
	)
	(footprint ""
		(layer "F.Cu")
		(at 6.909054 -40.297354 -90)
		(property "Reference" "PC671"
			(at 0 0 270)
			(layer "F.SilkS")
			(hide yes)
			(effects
				(font
					(size 1.27 1.27)
				)
			)
		)
		(property "Value" ""
			(at 0 0 270)
			(layer "F.Fab")
			(effects
				(font
					(size 1.27 1.27)
				)
			)
		)
		(duplicate_pad_numbers_are_jumpers no)
		(fp_line
			(start -1.524 0.762)
			(end -1.524 -0.762)
			(stroke
				(width 0.1524)
				(type default)
			)
			(layer "F.SilkS")
		)
		(fp_line
			(start 1.524 0.762)
			(end -1.524 0.762)
			(stroke
				(width 0.1524)
				(type default)
			)
			(layer "F.SilkS")
		)
		(fp_line
			(start -1.524 -0.762)
			(end 1.524 -0.762)
			(stroke
				(width 0.1524)
				(type default)
			)
			(layer "F.SilkS")
		)
		(fp_line
			(start 1.524 -0.762)
			(end 1.524 0.762)
			(stroke
				(width 0.1524)
				(type default)
			)
			(layer "F.SilkS")
		)
		(fp_line
			(start -1.1049 0.724916)
			(end 1.1049 0.724916)
			(stroke
				(width 0.1)
				(type default)
			)
			(layer "F.Fab")
		)
		(fp_line
			(start 1.1049 0.724916)
			(end 1.1049 -0.724916)
			(stroke
				(width 0.1)
				(type default)
			)
			(layer "F.Fab")
		)
		(fp_line
			(start -1.1049 -0.724916)
			(end -1.1049 0.724916)
			(stroke
				(width 0.1)
				(type default)
			)
			(layer "F.Fab")
		)
		(fp_line
			(start 1.1049 -0.724916)
			(end -1.1049 -0.724916)
			(stroke
				(width 0.1)
				(type default)
			)
			(layer "F.Fab")
		)
		(pad "1" smd rect
			(at -0.889 0 90)
			(size 1.016 1.27)
			(layers "F.Cu" "F.Mask" "F.Paste")
			(net "P3V3_SSD0")
		)
		(pad "2" smd rect
			(at 0.889 0 90)
			(size 1.016 1.27)
			(layers "F.Cu" "F.Mask" "F.Paste")
			(net "GND")
		)
	)
	(footprint ""
		(layer "F.Cu")
		(at 54.404514 -363.380782 -90)
		(property "Reference" "R5453"
			(at 0 0 270)
			(layer "F.SilkS")
			(hide yes)
			(effects
				(font
					(size 1.27 1.27)
				)
			)
		)
		(property "Value" ""
			(at 0 0 270)
			(layer "F.Fab")
			(effects
				(font
					(size 1.27 1.27)
				)
			)
		)
		(duplicate_pad_numbers_are_jumpers no)
		(fp_line
			(start 0.7874 0.4064)
			(end -0.7874 0.4064)
			(stroke
				(width 0.1524)
				(type default)
			)
			(layer "F.SilkS")
		)
		(fp_line
			(start -0.7874 -0.4064)
			(end -0.041656 -0.4064)
			(stroke
				(width 0.1524)
				(type default)
			)
			(layer "F.SilkS")
		)
		(fp_line
			(start 0.7874 -0.4064)
			(end 0.7874 0.4064)
			(stroke
				(width 0.1524)
				(type default)
			)
			(layer "F.SilkS")
		)
		(fp_line
			(start -0.67945 0.3048)
			(end -0.67945 -0.305054)
			(stroke
				(width 0.1)
				(type default)
			)
			(layer "F.Fab")
		)
		(fp_line
			(start -0.12065 0.3048)
			(end -0.67945 0.3048)
			(stroke
				(width 0.1)
				(type default)
			)
			(layer "F.Fab")
		)
		(fp_line
			(start 0.120396 0.3048)
			(end 0.120396 0.2794)
			(stroke
				(width 0.1)
				(type default)
			)
			(layer "F.Fab")
		)
		(fp_line
			(start 0.67945 0.3048)
			(end 0.120396 0.3048)
			(stroke
				(width 0.1)
				(type default)
			)
			(layer "F.Fab")
		)
		(fp_line
			(start -0.12065 0.2794)
			(end -0.12065 0.3048)
			(stroke
				(width 0.1)
				(type default)
			)
			(layer "F.Fab")
		)
		(fp_line
			(start 0.120396 0.2794)
			(end -0.12065 0.2794)
			(stroke
				(width 0.1)
				(type default)
			)
			(layer "F.Fab")
		)
		(fp_line
			(start -0.12065 -0.2794)
			(end 0.12065 -0.2794)
			(stroke
				(width 0.1)
				(type default)
			)
			(layer "F.Fab")
		)
		(fp_line
			(start 0.12065 -0.2794)
			(end 0.12065 -0.3048)
			(stroke
				(width 0.1)
				(type default)
			)
			(layer "F.Fab")
		)
		(fp_line
			(start 0.12065 -0.3048)
			(end 0.67945 -0.3048)
			(stroke
				(width 0.1)
				(type default)
			)
			(layer "F.Fab")
		)
		(fp_line
			(start 0.67945 -0.3048)
			(end 0.67945 0.3048)
			(stroke
				(width 0.1)
				(type default)
			)
			(layer "F.Fab")
		)
		(fp_line
			(start -0.67945 -0.305054)
			(end -0.12065 -0.305054)
			(stroke
				(width 0.1)
				(type default)
			)
			(layer "F.Fab")
		)
		(fp_line
			(start -0.12065 -0.305054)
			(end -0.12065 -0.2794)
			(stroke
				(width 0.1)
				(type default)
			)
			(layer "F.Fab")
		)
		(pad "1" smd rect
			(at -0.40005 0 90)
			(size 0.4572 0.508)
			(layers "F.Cu" "F.Mask" "F.Paste")
			(net "USB2_GPU_HMC_R_DN")
		)
		(pad "2" smd rect
			(at 0.40005 0 90)
			(size 0.4572 0.508)
			(layers "F.Cu" "F.Mask" "F.Paste")
			(net "USB2_GPU_HMC_DN")
		)
	)
	(footprint ""
		(layer "F.Cu")
		(at 340.890098 -279.486868 -90)
		(property "Reference" "PC153"
			(at 0 0 270)
			(layer "F.SilkS")
			(hide yes)
			(effects
				(font
					(size 1.27 1.27)
				)
			)
		)
		(property "Value" ""
			(at 0 0 270)
			(layer "F.Fab")
			(effects
				(font
					(size 1.27 1.27)
				)
			)
		)
		(duplicate_pad_numbers_are_jumpers no)
		(fp_line
			(start -0.7874 0.4064)
			(end -0.7874 -0.4064)
			(stroke
				(width 0.1524)
				(type default)
			)
			(layer "F.SilkS")
		)
		(fp_line
			(start 0.7874 0.4064)
			(end -0.7874 0.4064)
			(stroke
				(width 0.1524)
				(type default)
			)
			(layer "F.SilkS")
		)
		(fp_line
			(start -0.7874 -0.4064)
			(end 0.7874 -0.4064)
			(stroke
				(width 0.1524)
				(type default)
			)
			(layer "F.SilkS")
		)
		(fp_line
			(start 0.7874 -0.4064)
			(end 0.7874 0.4064)
			(stroke
				(width 0.1524)
				(type default)
			)
			(layer "F.SilkS")
		)
		(fp_line
			(start -0.67945 0.3048)
			(end -0.67945 -0.305054)
			(stroke
				(width 0.1)
				(type default)
			)
			(layer "F.Fab")
		)
		(fp_line
			(start -0.12065 0.3048)
			(end -0.67945 0.3048)
			(stroke
				(width 0.1)
				(type default)
			)
			(layer "F.Fab")
		)
		(fp_line
			(start 0.120396 0.3048)
			(end 0.120396 0.2794)
			(stroke
				(width 0.1)
				(type default)
			)
			(layer "F.Fab")
		)
		(fp_line
			(start 0.67945 0.3048)
			(end 0.120396 0.3048)
			(stroke
				(width 0.1)
				(type default)
			)
			(layer "F.Fab")
		)
		(fp_line
			(start -0.12065 0.2794)
			(end -0.12065 0.3048)
			(stroke
				(width 0.1)
				(type default)
			)
			(layer "F.Fab")
		)
		(fp_line
			(start 0.120396 0.2794)
			(end -0.12065 0.2794)
			(stroke
				(width 0.1)
				(type default)
			)
			(layer "F.Fab")
		)
		(fp_line
			(start -0.12065 -0.2794)
			(end 0.12065 -0.2794)
			(stroke
				(width 0.1)
				(type default)
			)
			(layer "F.Fab")
		)
		(fp_line
			(start 0.12065 -0.2794)
			(end 0.12065 -0.3048)
			(stroke
				(width 0.1)
				(type default)
			)
			(layer "F.Fab")
		)
		(fp_line
			(start 0.12065 -0.3048)
			(end 0.67945 -0.3048)
			(stroke
				(width 0.1)
				(type default)
			)
			(layer "F.Fab")
		)
		(fp_line
			(start 0.67945 -0.3048)
			(end 0.67945 0.3048)
			(stroke
				(width 0.1)
				(type default)
			)
			(layer "F.Fab")
		)
		(fp_line
			(start -0.67945 -0.305054)
			(end -0.12065 -0.305054)
			(stroke
				(width 0.1)
				(type default)
			)
			(layer "F.Fab")
		)
		(fp_line
			(start -0.12065 -0.305054)
			(end -0.12065 -0.2794)
			(stroke
				(width 0.1)
				(type default)
			)
			(layer "F.Fab")
		)
		(pad "1" smd circle
			(at -0.40005 0 270)
			(size 0 0)
			(layers "F.Cu" "F.Mask" "F.Paste")
			(net "P0V8_PEX2_VREF")
		)
		(pad "2" smd circle
			(at 0.40005 0 270)
			(size 0 0)
			(layers "F.Cu" "F.Mask" "F.Paste")
			(net "GND")
		)
	)
	(footprint ""
		(layer "F.Cu")
		(at 166.330884 -194.852798)
		(property "Reference" "R3408"
			(at 0 0 0)
			(layer "F.SilkS")
			(hide yes)
			(effects
				(font
					(size 1.27 1.27)
				)
			)
		)
		(property "Value" ""
			(at 0 0 0)
			(layer "F.Fab")
			(effects
				(font
					(size 1.27 1.27)
				)
			)
		)
		(duplicate_pad_numbers_are_jumpers no)
		(fp_line
			(start -0.7874 -0.4064)
			(end 0.7874 -0.4064)
			(stroke
				(width 0.1524)
				(type default)
			)
			(layer "F.SilkS")
		)
		(fp_line
			(start -0.7874 0.4064)
			(end -0.7874 -0.4064)
			(stroke
				(width 0.1524)
				(type default)
			)
			(layer "F.SilkS")
		)
		(fp_line
			(start 0.7874 -0.4064)
			(end 0.7874 0.4064)
			(stroke
				(width 0.1524)
				(type default)
			)
			(layer "F.SilkS")
		)
		(fp_line
			(start 0.7874 0.4064)
			(end -0.7874 0.4064)
			(stroke
				(width 0.1524)
				(type default)
			)
			(layer "F.SilkS")
		)
		(fp_line
			(start -0.67945 -0.305054)
			(end -0.12065 -0.305054)
			(stroke
				(width 0.1)
				(type default)
			)
			(layer "F.Fab")
		)
		(fp_line
			(start -0.67945 0.3048)
			(end -0.67945 -0.305054)
			(stroke
				(width 0.1)
				(type default)
			)
			(layer "F.Fab")
		)
		(fp_line
			(start -0.12065 -0.305054)
			(end -0.12065 -0.2794)
			(stroke
				(width 0.1)
				(type default)
			)
			(layer "F.Fab")
		)
		(fp_line
			(start -0.12065 -0.2794)
			(end 0.12065 -0.2794)
			(stroke
				(width 0.1)
				(type default)
			)
			(layer "F.Fab")
		)
		(fp_line
			(start -0.12065 0.2794)
			(end -0.12065 0.3048)
			(stroke
				(width 0.1)
				(type default)
			)
			(layer "F.Fab")
		)
		(fp_line
			(start -0.12065 0.3048)
			(end -0.67945 0.3048)
			(stroke
				(width 0.1)
				(type default)
			)
			(layer "F.Fab")
		)
		(fp_line
			(start 0.120396 0.2794)
			(end -0.12065 0.2794)
			(stroke
				(width 0.1)
				(type default)
			)
			(layer "F.Fab")
		)
		(fp_line
			(start 0.120396 0.3048)
			(end 0.120396 0.2794)
			(stroke
				(width 0.1)
				(type default)
			)
			(layer "F.Fab")
		)
		(fp_line
			(start 0.12065 -0.3048)
			(end 0.67945 -0.3048)
			(stroke
				(width 0.1)
				(type default)
			)
			(layer "F.Fab")
		)
		(fp_line
			(start 0.12065 -0.2794)
			(end 0.12065 -0.3048)
			(stroke
				(width 0.1)
				(type default)
			)
			(layer "F.Fab")
		)
		(fp_line
			(start 0.67945 -0.3048)
			(end 0.67945 0.3048)
			(stroke
				(width 0.1)
				(type default)
			)
			(layer "F.Fab")
		)
		(fp_line
			(start 0.67945 0.3048)
			(end 0.120396 0.3048)
			(stroke
				(width 0.1)
				(type default)
			)
			(layer "F.Fab")
		)
		(pad "1" smd circle
			(at -0.40005 0)
			(size 0 0)
			(layers "F.Cu" "F.Mask" "F.Paste")
			(net "SPI_BIC1_MOSI_LS01_R2")
		)
		(pad "2" smd circle
			(at 0.40005 0)
			(size 0 0)
			(layers "F.Cu" "F.Mask" "F.Paste")
			(net "SPI_BIC1_MOSI_LS01_R")
		)
	)
	(footprint ""
		(layer "F.Cu")
		(at 289.047682 -40.037258 90)
		(property "Reference" "U375"
			(at 0.145542 2.342388 90)
			(unlocked yes)
			(layer "F.SilkS")
			(effects
				(font
					(size 0.7874 0.5842)
					(thickness 0.1524)
				)
			)
		)
		(property "Value" ""
			(at 0 0 90)
			(layer "F.Fab")
			(effects
				(font
					(size 1.27 1.27)
				)
			)
		)
		(duplicate_pad_numbers_are_jumpers no)
		(fp_line
			(start -1.949958 -1.610106)
			(end 1.949958 -1.610106)
			(stroke
				(width 0.1524)
				(type default)
			)
			(layer "F.SilkS")
		)
		(fp_line
			(start 1.949958 -1.560068)
			(end 1.949958 1.610106)
			(stroke
				(width 0.1524)
				(type default)
			)
			(layer "F.SilkS")
		)
		(fp_line
			(start 1.949958 1.610106)
			(end -1.949958 1.610106)
			(stroke
				(width 0.1524)
				(type default)
			)
			(layer "F.SilkS")
		)
		(fp_line
			(start -1.949958 1.610106)
			(end -1.949958 -1.610106)
			(stroke
				(width 0.1524)
				(type default)
			)
			(layer "F.SilkS")
		)
		(fp_line
			(start 0.750062 -1.560068)
			(end 0.750062 1.560068)
			(stroke
				(width 0.1)
				(type default)
			)
			(layer "F.Fab")
		)
		(fp_line
			(start -0.750062 -1.560068)
			(end 0.750062 -1.560068)
			(stroke
				(width 0.1)
				(type default)
			)
			(layer "F.Fab")
		)
		(fp_line
			(start 0.750062 1.560068)
			(end -0.750062 1.560068)
			(stroke
				(width 0.1)
				(type default)
			)
			(layer "F.Fab")
		)
		(fp_line
			(start -0.750062 1.560068)
			(end -0.750062 -1.560068)
			(stroke
				(width 0.1)
				(type default)
			)
			(layer "F.Fab")
		)
		(pad "D" smd rect
			(at 1.100074 0)
			(size 1.016 1.4224)
			(layers "F.Cu" "F.Mask" "F.Paste")
			(net "SSD10_AUX_P3V3_EN")
		)
		(pad "G" smd rect
			(at -1.100074 -0.94996)
			(size 1.016 1.4224)
			(layers "F.Cu" "F.Mask" "F.Paste")
			(net "PRSNT_SSD10_R1_N")
		)
		(pad "S" smd rect
			(at -1.100074 0.94996)
			(size 1.016 1.4224)
			(layers "F.Cu" "F.Mask" "F.Paste")
			(net "GND")
		)
	)
	(footprint ""
		(layer "F.Cu")
		(at 86.94039 -143.182848 90)
		(property "Reference" "C3999"
			(at 0 0 90)
			(layer "F.SilkS")
			(hide yes)
			(effects
				(font
					(size 1.27 1.27)
				)
			)
		)
		(property "Value" ""
			(at 0 0 90)
			(layer "F.Fab")
			(effects
				(font
					(size 1.27 1.27)
				)
			)
		)
		(duplicate_pad_numbers_are_jumpers no)
		(fp_line
			(start 0.7874 -0.4064)
			(end 0.7874 0.4064)
			(stroke
				(width 0.1524)
				(type default)
			)
			(layer "F.SilkS")
		)
		(fp_line
			(start -0.7874 -0.4064)
			(end 0.7874 -0.4064)
			(stroke
				(width 0.1524)
				(type default)
			)
			(layer "F.SilkS")
		)
		(fp_line
			(start 0.7874 0.4064)
			(end -0.7874 0.4064)
			(stroke
				(width 0.1524)
				(type default)
			)
			(layer "F.SilkS")
		)
		(fp_line
			(start -0.7874 0.4064)
			(end -0.7874 -0.4064)
			(stroke
				(width 0.1524)
				(type default)
			)
			(layer "F.SilkS")
		)
		(fp_line
			(start -0.12065 -0.305054)
			(end -0.12065 -0.2794)
			(stroke
				(width 0.1)
				(type default)
			)
			(layer "F.Fab")
		)
		(fp_line
			(start -0.67945 -0.305054)
			(end -0.12065 -0.305054)
			(stroke
				(width 0.1)
				(type default)
			)
			(layer "F.Fab")
		)
		(fp_line
			(start 0.67945 -0.3048)
			(end 0.67945 0.3048)
			(stroke
				(width 0.1)
				(type default)
			)
			(layer "F.Fab")
		)
		(fp_line
			(start 0.12065 -0.3048)
			(end 0.67945 -0.3048)
			(stroke
				(width 0.1)
				(type default)
			)
			(layer "F.Fab")
		)
		(fp_line
			(start 0.12065 -0.2794)
			(end 0.12065 -0.3048)
			(stroke
				(width 0.1)
				(type default)
			)
			(layer "F.Fab")
		)
		(fp_line
			(start -0.12065 -0.2794)
			(end 0.12065 -0.2794)
			(stroke
				(width 0.1)
				(type default)
			)
			(layer "F.Fab")
		)
		(fp_line
			(start 0.120396 0.2794)
			(end -0.12065 0.2794)
			(stroke
				(width 0.1)
				(type default)
			)
			(layer "F.Fab")
		)
		(fp_line
			(start -0.12065 0.2794)
			(end -0.12065 0.3048)
			(stroke
				(width 0.1)
				(type default)
			)
			(layer "F.Fab")
		)
		(fp_line
			(start 0.67945 0.3048)
			(end 0.120396 0.3048)
			(stroke
				(width 0.1)
				(type default)
			)
			(layer "F.Fab")
		)
		(fp_line
			(start 0.120396 0.3048)
			(end 0.120396 0.2794)
			(stroke
				(width 0.1)
				(type default)
			)
			(layer "F.Fab")
		)
		(fp_line
			(start -0.12065 0.3048)
			(end -0.67945 0.3048)
			(stroke
				(width 0.1)
				(type default)
			)
			(layer "F.Fab")
		)
		(fp_line
			(start -0.67945 0.3048)
			(end -0.67945 -0.305054)
			(stroke
				(width 0.1)
				(type default)
			)
			(layer "F.Fab")
		)
		(pad "1" smd circle
			(at -0.40005 0 90)
			(size 0 0)
			(layers "F.Cu" "F.Mask" "F.Paste")
			(net "PRSNT_NIC1_R_N")
		)
		(pad "2" smd circle
			(at 0.40005 0 90)
			(size 0 0)
			(layers "F.Cu" "F.Mask" "F.Paste")
			(net "GND")
		)
	)
	(footprint ""
		(layer "F.Cu")
		(at 223.139 -50.52695 90)
		(property "Reference" "R1779"
			(at 0 0 90)
			(layer "F.SilkS")
			(hide yes)
			(effects
				(font
					(size 1.27 1.27)
				)
			)
		)
		(property "Value" ""
			(at 0 0 90)
			(layer "F.Fab")
			(effects
				(font
					(size 1.27 1.27)
				)
			)
		)
		(duplicate_pad_numbers_are_jumpers no)
		(fp_line
			(start 0.7874 -0.4064)
			(end 0.7874 0.4064)
			(stroke
				(width 0.1524)
				(type default)
			)
			(layer "F.SilkS")
		)
		(fp_line
			(start -0.7874 -0.4064)
			(end 0.7874 -0.4064)
			(stroke
				(width 0.1524)
				(type default)
			)
			(layer "F.SilkS")
		)
		(fp_line
			(start 0.7874 0.4064)
			(end -0.7874 0.4064)
			(stroke
				(width 0.1524)
				(type default)
			)
			(layer "F.SilkS")
		)
		(fp_line
			(start -0.7874 0.4064)
			(end -0.7874 -0.4064)
			(stroke
				(width 0.1524)
				(type default)
			)
			(layer "F.SilkS")
		)
		(fp_line
			(start -0.12065 -0.305054)
			(end -0.12065 -0.2794)
			(stroke
				(width 0.1)
				(type default)
			)
			(layer "F.Fab")
		)
		(fp_line
			(start -0.67945 -0.305054)
			(end -0.12065 -0.305054)
			(stroke
				(width 0.1)
				(type default)
			)
			(layer "F.Fab")
		)
		(fp_line
			(start 0.67945 -0.3048)
			(end 0.67945 0.3048)
			(stroke
				(width 0.1)
				(type default)
			)
			(layer "F.Fab")
		)
		(fp_line
			(start 0.12065 -0.3048)
			(end 0.67945 -0.3048)
			(stroke
				(width 0.1)
				(type default)
			)
			(layer "F.Fab")
		)
		(fp_line
			(start 0.12065 -0.2794)
			(end 0.12065 -0.3048)
			(stroke
				(width 0.1)
				(type default)
			)
			(layer "F.Fab")
		)
		(fp_line
			(start -0.12065 -0.2794)
			(end 0.12065 -0.2794)
			(stroke
				(width 0.1)
				(type default)
			)
			(layer "F.Fab")
		)
		(fp_line
			(start 0.120396 0.2794)
			(end -0.12065 0.2794)
			(stroke
				(width 0.1)
				(type default)
			)
			(layer "F.Fab")
		)
		(fp_line
			(start -0.12065 0.2794)
			(end -0.12065 0.3048)
			(stroke
				(width 0.1)
				(type default)
			)
			(layer "F.Fab")
		)
		(fp_line
			(start 0.67945 0.3048)
			(end 0.120396 0.3048)
			(stroke
				(width 0.1)
				(type default)
			)
			(layer "F.Fab")
		)
		(fp_line
			(start 0.120396 0.3048)
			(end 0.120396 0.2794)
			(stroke
				(width 0.1)
				(type default)
			)
			(layer "F.Fab")
		)
		(fp_line
			(start -0.12065 0.3048)
			(end -0.67945 0.3048)
			(stroke
				(width 0.1)
				(type default)
			)
			(layer "F.Fab")
		)
		(fp_line
			(start -0.67945 0.3048)
			(end -0.67945 -0.305054)
			(stroke
				(width 0.1)
				(type default)
			)
			(layer "F.Fab")
		)
		(pad "1" smd circle
			(at -0.40005 0 90)
			(size 0 0)
			(layers "F.Cu" "F.Mask" "F.Paste")
			(net "SMB_BIC_I2C6_MUX_SSD_0_7_ADC_R_SCL")
		)
		(pad "2" smd circle
			(at 0.40005 0 90)
			(size 0 0)
			(layers "F.Cu" "F.Mask" "F.Paste")
			(net "SMB_BIC_I2C6_MUX_SSD_0_7_ADC_SCL")
		)
	)
	(footprint ""
		(layer "F.Cu")
		(at 268.19987 -393.099798)
		(property "Reference" "H46"
			(at -4.758182 -5.132324 0)
			(unlocked yes)
			(layer "F.SilkS")
			(effects
				(font
					(size 0.7874 0.5842)
					(thickness 0.1524)
				)
				(justify left)
			)
		)
		(property "Value" ""
			(at 0 0 0)
			(layer "F.Fab")
			(effects
				(font
					(size 1.27 1.27)
				)
			)
		)
		(duplicate_pad_numbers_are_jumpers no)
		(pad "1" thru_hole circle
			(at 0 0)
			(size 10.0076 10.0076)
			(drill 5.6134)
			(layers "*.Cu" "*.Mask")
			(remove_unused_layers no)
			(net "GND")
			(clearance -1.9431)
		)
	)
	(footprint ""
		(layer "F.Cu")
		(at 376.936 -188.849)
		(property "Reference" "R4609"
			(at 0 0 0)
			(layer "F.SilkS")
			(hide yes)
			(effects
				(font
					(size 1.27 1.27)
				)
			)
		)
		(property "Value" ""
			(at 0 0 0)
			(layer "F.Fab")
			(effects
				(font
					(size 1.27 1.27)
				)
			)
		)
		(duplicate_pad_numbers_are_jumpers no)
		(fp_line
			(start -0.7874 -0.4064)
			(end 0.7874 -0.4064)
			(stroke
				(width 0.1524)
				(type default)
			)
			(layer "F.SilkS")
		)
		(fp_line
			(start -0.7874 0.4064)
			(end -0.7874 -0.4064)
			(stroke
				(width 0.1524)
				(type default)
			)
			(layer "F.SilkS")
		)
		(fp_line
			(start 0.7874 -0.4064)
			(end 0.7874 0.4064)
			(stroke
				(width 0.1524)
				(type default)
			)
			(layer "F.SilkS")
		)
		(fp_line
			(start 0.7874 0.4064)
			(end -0.7874 0.4064)
			(stroke
				(width 0.1524)
				(type default)
			)
			(layer "F.SilkS")
		)
		(fp_line
			(start -0.67945 -0.305054)
			(end -0.12065 -0.305054)
			(stroke
				(width 0.1)
				(type default)
			)
			(layer "F.Fab")
		)
		(fp_line
			(start -0.67945 0.3048)
			(end -0.67945 -0.305054)
			(stroke
				(width 0.1)
				(type default)
			)
			(layer "F.Fab")
		)
		(fp_line
			(start -0.12065 -0.305054)
			(end -0.12065 -0.2794)
			(stroke
				(width 0.1)
				(type default)
			)
			(layer "F.Fab")
		)
		(fp_line
			(start -0.12065 -0.2794)
			(end 0.12065 -0.2794)
			(stroke
				(width 0.1)
				(type default)
			)
			(layer "F.Fab")
		)
		(fp_line
			(start -0.12065 0.2794)
			(end -0.12065 0.3048)
			(stroke
				(width 0.1)
				(type default)
			)
			(layer "F.Fab")
		)
		(fp_line
			(start -0.12065 0.3048)
			(end -0.67945 0.3048)
			(stroke
				(width 0.1)
				(type default)
			)
			(layer "F.Fab")
		)
		(fp_line
			(start 0.120396 0.2794)
			(end -0.12065 0.2794)
			(stroke
				(width 0.1)
				(type default)
			)
			(layer "F.Fab")
		)
		(fp_line
			(start 0.120396 0.3048)
			(end 0.120396 0.2794)
			(stroke
				(width 0.1)
				(type default)
			)
			(layer "F.Fab")
		)
		(fp_line
			(start 0.12065 -0.3048)
			(end 0.67945 -0.3048)
			(stroke
				(width 0.1)
				(type default)
			)
			(layer "F.Fab")
		)
		(fp_line
			(start 0.12065 -0.2794)
			(end 0.12065 -0.3048)
			(stroke
				(width 0.1)
				(type default)
			)
			(layer "F.Fab")
		)
		(fp_line
			(start 0.67945 -0.3048)
			(end 0.67945 0.3048)
			(stroke
				(width 0.1)
				(type default)
			)
			(layer "F.Fab")
		)
		(fp_line
			(start 0.67945 0.3048)
			(end 0.120396 0.3048)
			(stroke
				(width 0.1)
				(type default)
			)
			(layer "F.Fab")
		)
		(pad "1" smd circle
			(at -0.40005 0)
			(size 0 0)
			(layers "F.Cu" "F.Mask" "F.Paste")
			(net "P3V3_AUX")
		)
		(pad "2" smd circle
			(at 0.40005 0)
			(size 0 0)
			(layers "F.Cu" "F.Mask" "F.Paste")
			(net "RST_PEX_NIC1_PERST_R_N")
		)
	)
	(footprint ""
		(layer "F.Cu")
		(at 284.330902 -356.244906 90)
		(property "Reference" "C598"
			(at 0 0 90)
			(layer "F.SilkS")
			(hide yes)
			(effects
				(font
					(size 1.27 1.27)
				)
			)
		)
		(property "Value" ""
			(at 0 0 90)
			(layer "F.Fab")
			(effects
				(font
					(size 1.27 1.27)
				)
			)
		)
		(duplicate_pad_numbers_are_jumpers no)
		(fp_line
			(start 0.299974 -0.150114)
			(end 0.299974 0.150114)
			(stroke
				(width 0.1)
				(type default)
			)
			(layer "F.Fab")
		)
		(fp_line
			(start -0.299974 -0.150114)
			(end 0.299974 -0.150114)
			(stroke
				(width 0.1)
				(type default)
			)
			(layer "F.Fab")
		)
		(fp_line
			(start 0.299974 0.150114)
			(end -0.299974 0.150114)
			(stroke
				(width 0.1)
				(type default)
			)
			(layer "F.Fab")
		)
		(fp_line
			(start -0.299974 0.150114)
			(end -0.299974 -0.150114)
			(stroke
				(width 0.1)
				(type default)
			)
			(layer "F.Fab")
		)
		(pad "1" smd rect
			(at -0.2667 0 90)
			(size 0.3048 0.381)
			(layers "F.Cu" "F.Mask" "F.Paste")
			(net "P5E_PEX2_STN7_TX_DN<120>")
		)
		(pad "2" smd rect
			(at 0.2667 0 90)
			(size 0.3048 0.381)
			(layers "F.Cu" "F.Mask" "F.Paste")
			(net "P5E_PEX2_STN7_TX_C_DN<120>")
		)
	)
	(footprint ""
		(layer "F.Cu")
		(at 191.767968 -18.430748)
		(property "Reference" "R1679"
			(at 0 0 0)
			(layer "F.SilkS")
			(hide yes)
			(effects
				(font
					(size 1.27 1.27)
				)
			)
		)
		(property "Value" ""
			(at 0 0 0)
			(layer "F.Fab")
			(effects
				(font
					(size 1.27 1.27)
				)
			)
		)
		(duplicate_pad_numbers_are_jumpers no)
		(fp_line
			(start -0.7874 -0.4064)
			(end 0.7874 -0.4064)
			(stroke
				(width 0.1524)
				(type default)
			)
			(layer "F.SilkS")
		)
		(fp_line
			(start -0.7874 0.4064)
			(end -0.7874 -0.4064)
			(stroke
				(width 0.1524)
				(type default)
			)
			(layer "F.SilkS")
		)
		(fp_line
			(start 0.7874 -0.4064)
			(end 0.7874 0.4064)
			(stroke
				(width 0.1524)
				(type default)
			)
			(layer "F.SilkS")
		)
		(fp_line
			(start 0.7874 0.4064)
			(end -0.7874 0.4064)
			(stroke
				(width 0.1524)
				(type default)
			)
			(layer "F.SilkS")
		)
		(fp_line
			(start -0.67945 -0.305054)
			(end -0.12065 -0.305054)
			(stroke
				(width 0.1)
				(type default)
			)
			(layer "F.Fab")
		)
		(fp_line
			(start -0.67945 0.3048)
			(end -0.67945 -0.305054)
			(stroke
				(width 0.1)
				(type default)
			)
			(layer "F.Fab")
		)
		(fp_line
			(start -0.12065 -0.305054)
			(end -0.12065 -0.2794)
			(stroke
				(width 0.1)
				(type default)
			)
			(layer "F.Fab")
		)
		(fp_line
			(start -0.12065 -0.2794)
			(end 0.12065 -0.2794)
			(stroke
				(width 0.1)
				(type default)
			)
			(layer "F.Fab")
		)
		(fp_line
			(start -0.12065 0.2794)
			(end -0.12065 0.3048)
			(stroke
				(width 0.1)
				(type default)
			)
			(layer "F.Fab")
		)
		(fp_line
			(start -0.12065 0.3048)
			(end -0.67945 0.3048)
			(stroke
				(width 0.1)
				(type default)
			)
			(layer "F.Fab")
		)
		(fp_line
			(start 0.120396 0.2794)
			(end -0.12065 0.2794)
			(stroke
				(width 0.1)
				(type default)
			)
			(layer "F.Fab")
		)
		(fp_line
			(start 0.120396 0.3048)
			(end 0.120396 0.2794)
			(stroke
				(width 0.1)
				(type default)
			)
			(layer "F.Fab")
		)
		(fp_line
			(start 0.12065 -0.3048)
			(end 0.67945 -0.3048)
			(stroke
				(width 0.1)
				(type default)
			)
			(layer "F.Fab")
		)
		(fp_line
			(start 0.12065 -0.2794)
			(end 0.12065 -0.3048)
			(stroke
				(width 0.1)
				(type default)
			)
			(layer "F.Fab")
		)
		(fp_line
			(start 0.67945 -0.3048)
			(end 0.67945 0.3048)
			(stroke
				(width 0.1)
				(type default)
			)
			(layer "F.Fab")
		)
		(fp_line
			(start 0.67945 0.3048)
			(end 0.120396 0.3048)
			(stroke
				(width 0.1)
				(type default)
			)
			(layer "F.Fab")
		)
		(pad "1" smd circle
			(at -0.40005 0)
			(size 0 0)
			(layers "F.Cu" "F.Mask" "F.Paste")
			(net "SMB_ISO_SSD6_R_SCL")
		)
		(pad "2" smd circle
			(at 0.40005 0)
			(size 0 0)
			(layers "F.Cu" "F.Mask" "F.Paste")
			(net "SMB_ISO_SSD6_SCL")
		)
	)
	(footprint ""
		(layer "F.Cu")
		(at 318.695324 -343.952322 90)
		(property "Reference" "C555"
			(at 0 0 90)
			(layer "F.SilkS")
			(hide yes)
			(effects
				(font
					(size 1.27 1.27)
				)
			)
		)
		(property "Value" ""
			(at 0 0 90)
			(layer "F.Fab")
			(effects
				(font
					(size 1.27 1.27)
				)
			)
		)
		(duplicate_pad_numbers_are_jumpers no)
		(fp_line
			(start 0.299974 -0.150114)
			(end 0.299974 0.150114)
			(stroke
				(width 0.1)
				(type default)
			)
			(layer "F.Fab")
		)
		(fp_line
			(start -0.299974 -0.150114)
			(end 0.299974 -0.150114)
			(stroke
				(width 0.1)
				(type default)
			)
			(layer "F.Fab")
		)
		(fp_line
			(start 0.299974 0.150114)
			(end -0.299974 0.150114)
			(stroke
				(width 0.1)
				(type default)
			)
			(layer "F.Fab")
		)
		(fp_line
			(start -0.299974 0.150114)
			(end -0.299974 -0.150114)
			(stroke
				(width 0.1)
				(type default)
			)
			(layer "F.Fab")
		)
		(pad "1" smd rect
			(at -0.2667 0 90)
			(size 0.3048 0.381)
			(layers "F.Cu" "F.Mask" "F.Paste")
			(net "P5E_PEX2_STN6_TX_DP<109>")
		)
		(pad "2" smd rect
			(at 0.2667 0 90)
			(size 0.3048 0.381)
			(layers "F.Cu" "F.Mask" "F.Paste")
			(net "P5E_PEX2_STN6_TX_C_DP<109>")
		)
	)
	(footprint ""
		(layer "F.Cu")
		(at 344.043 -234.061 -90)
		(property "Reference" "R3541"
			(at 0 0 270)
			(layer "F.SilkS")
			(hide yes)
			(effects
				(font
					(size 1.27 1.27)
				)
			)
		)
		(property "Value" ""
			(at 0 0 270)
			(layer "F.Fab")
			(effects
				(font
					(size 1.27 1.27)
				)
			)
		)
		(duplicate_pad_numbers_are_jumpers no)
		(fp_line
			(start -0.7874 0.4064)
			(end -0.7874 -0.4064)
			(stroke
				(width 0.1524)
				(type default)
			)
			(layer "F.SilkS")
		)
		(fp_line
			(start 0.7874 0.4064)
			(end -0.7874 0.4064)
			(stroke
				(width 0.1524)
				(type default)
			)
			(layer "F.SilkS")
		)
		(fp_line
			(start -0.7874 -0.4064)
			(end 0.7874 -0.4064)
			(stroke
				(width 0.1524)
				(type default)
			)
			(layer "F.SilkS")
		)
		(fp_line
			(start 0.7874 -0.4064)
			(end 0.7874 0.4064)
			(stroke
				(width 0.1524)
				(type default)
			)
			(layer "F.SilkS")
		)
		(fp_line
			(start -0.67945 0.3048)
			(end -0.67945 -0.305054)
			(stroke
				(width 0.1)
				(type default)
			)
			(layer "F.Fab")
		)
		(fp_line
			(start -0.12065 0.3048)
			(end -0.67945 0.3048)
			(stroke
				(width 0.1)
				(type default)
			)
			(layer "F.Fab")
		)
		(fp_line
			(start 0.120396 0.3048)
			(end 0.120396 0.2794)
			(stroke
				(width 0.1)
				(type default)
			)
			(layer "F.Fab")
		)
		(fp_line
			(start 0.67945 0.3048)
			(end 0.120396 0.3048)
			(stroke
				(width 0.1)
				(type default)
			)
			(layer "F.Fab")
		)
		(fp_line
			(start -0.12065 0.2794)
			(end -0.12065 0.3048)
			(stroke
				(width 0.1)
				(type default)
			)
			(layer "F.Fab")
		)
		(fp_line
			(start 0.120396 0.2794)
			(end -0.12065 0.2794)
			(stroke
				(width 0.1)
				(type default)
			)
			(layer "F.Fab")
		)
		(fp_line
			(start -0.12065 -0.2794)
			(end 0.12065 -0.2794)
			(stroke
				(width 0.1)
				(type default)
			)
			(layer "F.Fab")
		)
		(fp_line
			(start 0.12065 -0.2794)
			(end 0.12065 -0.3048)
			(stroke
				(width 0.1)
				(type default)
			)
			(layer "F.Fab")
		)
		(fp_line
			(start 0.12065 -0.3048)
			(end 0.67945 -0.3048)
			(stroke
				(width 0.1)
				(type default)
			)
			(layer "F.Fab")
		)
		(fp_line
			(start 0.67945 -0.3048)
			(end 0.67945 0.3048)
			(stroke
				(width 0.1)
				(type default)
			)
			(layer "F.Fab")
		)
		(fp_line
			(start -0.67945 -0.305054)
			(end -0.12065 -0.305054)
			(stroke
				(width 0.1)
				(type default)
			)
			(layer "F.Fab")
		)
		(fp_line
			(start -0.12065 -0.305054)
			(end -0.12065 -0.2794)
			(stroke
				(width 0.1)
				(type default)
			)
			(layer "F.Fab")
		)
		(pad "1" smd circle
			(at -0.40005 0 270)
			(size 0 0)
			(layers "F.Cu" "F.Mask" "F.Paste")
			(net "SSD3_CLK_EN_R_N")
		)
		(pad "2" smd circle
			(at 0.40005 0 270)
			(size 0 0)
			(layers "F.Cu" "F.Mask" "F.Paste")
			(net "SSD3_CLK_EN_N")
		)
	)
	(footprint ""
		(layer "F.Cu")
		(at 72.125332 -42.849038 180)
		(property "Reference" "R535"
			(at 0 0 180)
			(layer "F.SilkS")
			(hide yes)
			(effects
				(font
					(size 1.27 1.27)
				)
			)
		)
		(property "Value" ""
			(at 0 0 180)
			(layer "F.Fab")
			(effects
				(font
					(size 1.27 1.27)
				)
			)
		)
		(duplicate_pad_numbers_are_jumpers no)
		(fp_line
			(start 0.7874 0.4064)
			(end -0.7874 0.4064)
			(stroke
				(width 0.1524)
				(type default)
			)
			(layer "F.SilkS")
		)
		(fp_line
			(start 0.7874 -0.4064)
			(end 0.7874 0.4064)
			(stroke
				(width 0.1524)
				(type default)
			)
			(layer "F.SilkS")
		)
		(fp_line
			(start -0.7874 0.4064)
			(end -0.7874 -0.4064)
			(stroke
				(width 0.1524)
				(type default)
			)
			(layer "F.SilkS")
		)
		(fp_line
			(start -0.7874 -0.4064)
			(end 0.7874 -0.4064)
			(stroke
				(width 0.1524)
				(type default)
			)
			(layer "F.SilkS")
		)
		(fp_line
			(start 0.67945 0.3048)
			(end 0.120396 0.3048)
			(stroke
				(width 0.1)
				(type default)
			)
			(layer "F.Fab")
		)
		(fp_line
			(start 0.67945 -0.3048)
			(end 0.67945 0.3048)
			(stroke
				(width 0.1)
				(type default)
			)
			(layer "F.Fab")
		)
		(fp_line
			(start 0.12065 -0.2794)
			(end 0.12065 -0.3048)
			(stroke
				(width 0.1)
				(type default)
			)
			(layer "F.Fab")
		)
		(fp_line
			(start 0.12065 -0.3048)
			(end 0.67945 -0.3048)
			(stroke
				(width 0.1)
				(type default)
			)
			(layer "F.Fab")
		)
		(fp_line
			(start 0.120396 0.3048)
			(end 0.120396 0.2794)
			(stroke
				(width 0.1)
				(type default)
			)
			(layer "F.Fab")
		)
		(fp_line
			(start 0.120396 0.2794)
			(end -0.12065 0.2794)
			(stroke
				(width 0.1)
				(type default)
			)
			(layer "F.Fab")
		)
		(fp_line
			(start -0.12065 0.3048)
			(end -0.67945 0.3048)
			(stroke
				(width 0.1)
				(type default)
			)
			(layer "F.Fab")
		)
		(fp_line
			(start -0.12065 0.2794)
			(end -0.12065 0.3048)
			(stroke
				(width 0.1)
				(type default)
			)
			(layer "F.Fab")
		)
		(fp_line
			(start -0.12065 -0.2794)
			(end 0.12065 -0.2794)
			(stroke
				(width 0.1)
				(type default)
			)
			(layer "F.Fab")
		)
		(fp_line
			(start -0.12065 -0.305054)
			(end -0.12065 -0.2794)
			(stroke
				(width 0.1)
				(type default)
			)
			(layer "F.Fab")
		)
		(fp_line
			(start -0.67945 0.3048)
			(end -0.67945 -0.305054)
			(stroke
				(width 0.1)
				(type default)
			)
			(layer "F.Fab")
		)
		(fp_line
			(start -0.67945 -0.305054)
			(end -0.12065 -0.305054)
			(stroke
				(width 0.1)
				(type default)
			)
			(layer "F.Fab")
		)
		(pad "1" smd circle
			(at -0.40005 0 180)
			(size 0 0)
			(layers "F.Cu" "F.Mask" "F.Paste")
			(net "P12V_SSD2_R")
		)
		(pad "2" smd circle
			(at 0.40005 0 180)
			(size 0 0)
			(layers "F.Cu" "F.Mask" "F.Paste")
			(net "P12V_SSD2_VIN_P")
		)
	)
	(footprint ""
		(layer "F.Cu")
		(at 128.513332 -268.352524 -90)
		(property "Reference" "PC983"
			(at 0 0 270)
			(layer "F.SilkS")
			(hide yes)
			(effects
				(font
					(size 1.27 1.27)
				)
			)
		)
		(property "Value" ""
			(at 0 0 270)
			(layer "F.Fab")
			(effects
				(font
					(size 1.27 1.27)
				)
			)
		)
		(duplicate_pad_numbers_are_jumpers no)
		(fp_line
			(start -0.7874 0.4064)
			(end -0.7874 -0.4064)
			(stroke
				(width 0.1524)
				(type default)
			)
			(layer "F.SilkS")
		)
		(fp_line
			(start 0.7874 0.4064)
			(end -0.7874 0.4064)
			(stroke
				(width 0.1524)
				(type default)
			)
			(layer "F.SilkS")
		)
		(fp_line
			(start -0.7874 -0.4064)
			(end 0.7874 -0.4064)
			(stroke
				(width 0.1524)
				(type default)
			)
			(layer "F.SilkS")
		)
		(fp_line
			(start 0.7874 -0.4064)
			(end 0.7874 0.4064)
			(stroke
				(width 0.1524)
				(type default)
			)
			(layer "F.SilkS")
		)
		(fp_line
			(start -0.67945 0.3048)
			(end -0.67945 -0.305054)
			(stroke
				(width 0.1)
				(type default)
			)
			(layer "F.Fab")
		)
		(fp_line
			(start -0.12065 0.3048)
			(end -0.67945 0.3048)
			(stroke
				(width 0.1)
				(type default)
			)
			(layer "F.Fab")
		)
		(fp_line
			(start 0.120396 0.3048)
			(end 0.120396 0.2794)
			(stroke
				(width 0.1)
				(type default)
			)
			(layer "F.Fab")
		)
		(fp_line
			(start 0.67945 0.3048)
			(end 0.120396 0.3048)
			(stroke
				(width 0.1)
				(type default)
			)
			(layer "F.Fab")
		)
		(fp_line
			(start -0.12065 0.2794)
			(end -0.12065 0.3048)
			(stroke
				(width 0.1)
				(type default)
			)
			(layer "F.Fab")
		)
		(fp_line
			(start 0.120396 0.2794)
			(end -0.12065 0.2794)
			(stroke
				(width 0.1)
				(type default)
			)
			(layer "F.Fab")
		)
		(fp_line
			(start -0.12065 -0.2794)
			(end 0.12065 -0.2794)
			(stroke
				(width 0.1)
				(type default)
			)
			(layer "F.Fab")
		)
		(fp_line
			(start 0.12065 -0.2794)
			(end 0.12065 -0.3048)
			(stroke
				(width 0.1)
				(type default)
			)
			(layer "F.Fab")
		)
		(fp_line
			(start 0.12065 -0.3048)
			(end 0.67945 -0.3048)
			(stroke
				(width 0.1)
				(type default)
			)
			(layer "F.Fab")
		)
		(fp_line
			(start 0.67945 -0.3048)
			(end 0.67945 0.3048)
			(stroke
				(width 0.1)
				(type default)
			)
			(layer "F.Fab")
		)
		(fp_line
			(start -0.67945 -0.305054)
			(end -0.12065 -0.305054)
			(stroke
				(width 0.1)
				(type default)
			)
			(layer "F.Fab")
		)
		(fp_line
			(start -0.12065 -0.305054)
			(end -0.12065 -0.2794)
			(stroke
				(width 0.1)
				(type default)
			)
			(layer "F.Fab")
		)
		(pad "1" smd circle
			(at -0.40005 0 270)
			(size 0 0)
			(layers "F.Cu" "F.Mask" "F.Paste")
			(net "P12V_AUX")
		)
		(pad "2" smd circle
			(at 0.40005 0 270)
			(size 0 0)
			(layers "F.Cu" "F.Mask" "F.Paste")
			(net "GND")
		)
	)
	(footprint ""
		(layer "F.Cu")
		(at 192.828926 -402.67509 -90)
		(property "Reference" "C4493"
			(at 0 0 270)
			(layer "F.SilkS")
			(hide yes)
			(effects
				(font
					(size 1.27 1.27)
				)
			)
		)
		(property "Value" ""
			(at 0 0 270)
			(layer "F.Fab")
			(effects
				(font
					(size 1.27 1.27)
				)
			)
		)
		(duplicate_pad_numbers_are_jumpers no)
		(fp_line
			(start -0.7874 0.4064)
			(end -0.7874 -0.4064)
			(stroke
				(width 0.1524)
				(type default)
			)
			(layer "F.SilkS")
		)
		(fp_line
			(start 0.7874 0.4064)
			(end -0.7874 0.4064)
			(stroke
				(width 0.1524)
				(type default)
			)
			(layer "F.SilkS")
		)
		(fp_line
			(start -0.7874 -0.4064)
			(end 0.7874 -0.4064)
			(stroke
				(width 0.1524)
				(type default)
			)
			(layer "F.SilkS")
		)
		(fp_line
			(start 0.7874 -0.4064)
			(end 0.7874 0.4064)
			(stroke
				(width 0.1524)
				(type default)
			)
			(layer "F.SilkS")
		)
		(fp_line
			(start -0.67945 0.3048)
			(end -0.67945 -0.305054)
			(stroke
				(width 0.1)
				(type default)
			)
			(layer "F.Fab")
		)
		(fp_line
			(start -0.12065 0.3048)
			(end -0.67945 0.3048)
			(stroke
				(width 0.1)
				(type default)
			)
			(layer "F.Fab")
		)
		(fp_line
			(start 0.120396 0.3048)
			(end 0.120396 0.2794)
			(stroke
				(width 0.1)
				(type default)
			)
			(layer "F.Fab")
		)
		(fp_line
			(start 0.67945 0.3048)
			(end 0.120396 0.3048)
			(stroke
				(width 0.1)
				(type default)
			)
			(layer "F.Fab")
		)
		(fp_line
			(start -0.12065 0.2794)
			(end -0.12065 0.3048)
			(stroke
				(width 0.1)
				(type default)
			)
			(layer "F.Fab")
		)
		(fp_line
			(start 0.120396 0.2794)
			(end -0.12065 0.2794)
			(stroke
				(width 0.1)
				(type default)
			)
			(layer "F.Fab")
		)
		(fp_line
			(start -0.12065 -0.2794)
			(end 0.12065 -0.2794)
			(stroke
				(width 0.1)
				(type default)
			)
			(layer "F.Fab")
		)
		(fp_line
			(start 0.12065 -0.2794)
			(end 0.12065 -0.3048)
			(stroke
				(width 0.1)
				(type default)
			)
			(layer "F.Fab")
		)
		(fp_line
			(start 0.12065 -0.3048)
			(end 0.67945 -0.3048)
			(stroke
				(width 0.1)
				(type default)
			)
			(layer "F.Fab")
		)
		(fp_line
			(start 0.67945 -0.3048)
			(end 0.67945 0.3048)
			(stroke
				(width 0.1)
				(type default)
			)
			(layer "F.Fab")
		)
		(fp_line
			(start -0.67945 -0.305054)
			(end -0.12065 -0.305054)
			(stroke
				(width 0.1)
				(type default)
			)
			(layer "F.Fab")
		)
		(fp_line
			(start -0.12065 -0.305054)
			(end -0.12065 -0.2794)
			(stroke
				(width 0.1)
				(type default)
			)
			(layer "F.Fab")
		)
		(pad "1" smd circle
			(at -0.40005 0 270)
			(size 0 0)
			(layers "F.Cu" "F.Mask" "F.Paste")
			(net "FM_UV_LT6700_VS")
		)
		(pad "2" smd circle
			(at 0.40005 0 270)
			(size 0 0)
			(layers "F.Cu" "F.Mask" "F.Paste")
			(net "GND")
		)
	)
	(footprint ""
		(layer "F.Cu")
		(at 270.799814 -152.295352 180)
		(property "Reference" "R221"
			(at 0 0 180)
			(layer "F.SilkS")
			(hide yes)
			(effects
				(font
					(size 1.27 1.27)
				)
			)
		)
		(property "Value" ""
			(at 0 0 180)
			(layer "F.Fab")
			(effects
				(font
					(size 1.27 1.27)
				)
			)
		)
		(duplicate_pad_numbers_are_jumpers no)
		(fp_line
			(start 0.7874 0.4064)
			(end -0.7874 0.4064)
			(stroke
				(width 0.1524)
				(type default)
			)
			(layer "F.SilkS")
		)
		(fp_line
			(start 0.7874 -0.4064)
			(end 0.7874 0.4064)
			(stroke
				(width 0.1524)
				(type default)
			)
			(layer "F.SilkS")
		)
		(fp_line
			(start -0.7874 0.4064)
			(end -0.7874 -0.4064)
			(stroke
				(width 0.1524)
				(type default)
			)
			(layer "F.SilkS")
		)
		(fp_line
			(start -0.7874 -0.4064)
			(end 0.7874 -0.4064)
			(stroke
				(width 0.1524)
				(type default)
			)
			(layer "F.SilkS")
		)
		(fp_line
			(start 0.67945 0.3048)
			(end 0.120396 0.3048)
			(stroke
				(width 0.1)
				(type default)
			)
			(layer "F.Fab")
		)
		(fp_line
			(start 0.67945 -0.3048)
			(end 0.67945 0.3048)
			(stroke
				(width 0.1)
				(type default)
			)
			(layer "F.Fab")
		)
		(fp_line
			(start 0.12065 -0.2794)
			(end 0.12065 -0.3048)
			(stroke
				(width 0.1)
				(type default)
			)
			(layer "F.Fab")
		)
		(fp_line
			(start 0.12065 -0.3048)
			(end 0.67945 -0.3048)
			(stroke
				(width 0.1)
				(type default)
			)
			(layer "F.Fab")
		)
		(fp_line
			(start 0.120396 0.3048)
			(end 0.120396 0.2794)
			(stroke
				(width 0.1)
				(type default)
			)
			(layer "F.Fab")
		)
		(fp_line
			(start 0.120396 0.2794)
			(end -0.12065 0.2794)
			(stroke
				(width 0.1)
				(type default)
			)
			(layer "F.Fab")
		)
		(fp_line
			(start -0.12065 0.3048)
			(end -0.67945 0.3048)
			(stroke
				(width 0.1)
				(type default)
			)
			(layer "F.Fab")
		)
		(fp_line
			(start -0.12065 0.2794)
			(end -0.12065 0.3048)
			(stroke
				(width 0.1)
				(type default)
			)
			(layer "F.Fab")
		)
		(fp_line
			(start -0.12065 -0.2794)
			(end 0.12065 -0.2794)
			(stroke
				(width 0.1)
				(type default)
			)
			(layer "F.Fab")
		)
		(fp_line
			(start -0.12065 -0.305054)
			(end -0.12065 -0.2794)
			(stroke
				(width 0.1)
				(type default)
			)
			(layer "F.Fab")
		)
		(fp_line
			(start -0.67945 0.3048)
			(end -0.67945 -0.305054)
			(stroke
				(width 0.1)
				(type default)
			)
			(layer "F.Fab")
		)
		(fp_line
			(start -0.67945 -0.305054)
			(end -0.12065 -0.305054)
			(stroke
				(width 0.1)
				(type default)
			)
			(layer "F.Fab")
		)
		(pad "1" smd circle
			(at -0.40005 0 180)
			(size 0 0)
			(layers "F.Cu" "F.Mask" "F.Paste")
			(net "NCSI_NIC4_RXD1")
		)
		(pad "2" smd circle
			(at 0.40005 0 180)
			(size 0 0)
			(layers "F.Cu" "F.Mask" "F.Paste")
			(net "GND")
		)
	)
	(footprint ""
		(layer "F.Cu")
		(at 290.264342 -140.6398 180)
		(property "Reference" "R242"
			(at 0 0 180)
			(layer "F.SilkS")
			(hide yes)
			(effects
				(font
					(size 1.27 1.27)
				)
			)
		)
		(property "Value" ""
			(at 0 0 180)
			(layer "F.Fab")
			(effects
				(font
					(size 1.27 1.27)
				)
			)
		)
		(duplicate_pad_numbers_are_jumpers no)
		(fp_line
			(start 0.7874 0.4064)
			(end -0.7874 0.4064)
			(stroke
				(width 0.1524)
				(type default)
			)
			(layer "F.SilkS")
		)
		(fp_line
			(start 0.7874 -0.4064)
			(end 0.7874 0.4064)
			(stroke
				(width 0.1524)
				(type default)
			)
			(layer "F.SilkS")
		)
		(fp_line
			(start -0.7874 0.4064)
			(end -0.7874 -0.4064)
			(stroke
				(width 0.1524)
				(type default)
			)
			(layer "F.SilkS")
		)
		(fp_line
			(start -0.7874 -0.4064)
			(end 0.7874 -0.4064)
			(stroke
				(width 0.1524)
				(type default)
			)
			(layer "F.SilkS")
		)
		(fp_line
			(start 0.67945 0.3048)
			(end 0.120396 0.3048)
			(stroke
				(width 0.1)
				(type default)
			)
			(layer "F.Fab")
		)
		(fp_line
			(start 0.67945 -0.3048)
			(end 0.67945 0.3048)
			(stroke
				(width 0.1)
				(type default)
			)
			(layer "F.Fab")
		)
		(fp_line
			(start 0.12065 -0.2794)
			(end 0.12065 -0.3048)
			(stroke
				(width 0.1)
				(type default)
			)
			(layer "F.Fab")
		)
		(fp_line
			(start 0.12065 -0.3048)
			(end 0.67945 -0.3048)
			(stroke
				(width 0.1)
				(type default)
			)
			(layer "F.Fab")
		)
		(fp_line
			(start 0.120396 0.3048)
			(end 0.120396 0.2794)
			(stroke
				(width 0.1)
				(type default)
			)
			(layer "F.Fab")
		)
		(fp_line
			(start 0.120396 0.2794)
			(end -0.12065 0.2794)
			(stroke
				(width 0.1)
				(type default)
			)
			(layer "F.Fab")
		)
		(fp_line
			(start -0.12065 0.3048)
			(end -0.67945 0.3048)
			(stroke
				(width 0.1)
				(type default)
			)
			(layer "F.Fab")
		)
		(fp_line
			(start -0.12065 0.2794)
			(end -0.12065 0.3048)
			(stroke
				(width 0.1)
				(type default)
			)
			(layer "F.Fab")
		)
		(fp_line
			(start -0.12065 -0.2794)
			(end 0.12065 -0.2794)
			(stroke
				(width 0.1)
				(type default)
			)
			(layer "F.Fab")
		)
		(fp_line
			(start -0.12065 -0.305054)
			(end -0.12065 -0.2794)
			(stroke
				(width 0.1)
				(type default)
			)
			(layer "F.Fab")
		)
		(fp_line
			(start -0.67945 0.3048)
			(end -0.67945 -0.305054)
			(stroke
				(width 0.1)
				(type default)
			)
			(layer "F.Fab")
		)
		(fp_line
			(start -0.67945 -0.305054)
			(end -0.12065 -0.305054)
			(stroke
				(width 0.1)
				(type default)
			)
			(layer "F.Fab")
		)
		(pad "1" smd circle
			(at -0.40005 0 180)
			(size 0 0)
			(layers "F.Cu" "F.Mask" "F.Paste")
			(net "RST_SMB_NIC4_MUX_ISO_N")
		)
		(pad "2" smd circle
			(at 0.40005 0 180)
			(size 0 0)
			(layers "F.Cu" "F.Mask" "F.Paste")
			(net "GND")
		)
	)
	(footprint ""
		(layer "F.Cu")
		(at 184.837832 -356.22103 90)
		(property "Reference" "C2535"
			(at 0 0 90)
			(layer "F.SilkS")
			(hide yes)
			(effects
				(font
					(size 1.27 1.27)
				)
			)
		)
		(property "Value" ""
			(at 0 0 90)
			(layer "F.Fab")
			(effects
				(font
					(size 1.27 1.27)
				)
			)
		)
		(duplicate_pad_numbers_are_jumpers no)
		(fp_line
			(start 0.299974 -0.150114)
			(end 0.299974 0.150114)
			(stroke
				(width 0.1)
				(type default)
			)
			(layer "F.Fab")
		)
		(fp_line
			(start -0.299974 -0.150114)
			(end 0.299974 -0.150114)
			(stroke
				(width 0.1)
				(type default)
			)
			(layer "F.Fab")
		)
		(fp_line
			(start 0.299974 0.150114)
			(end -0.299974 0.150114)
			(stroke
				(width 0.1)
				(type default)
			)
			(layer "F.Fab")
		)
		(fp_line
			(start -0.299974 0.150114)
			(end -0.299974 -0.150114)
			(stroke
				(width 0.1)
				(type default)
			)
			(layer "F.Fab")
		)
		(pad "1" smd rect
			(at -0.2667 0 90)
			(size 0.3048 0.381)
			(layers "F.Cu" "F.Mask" "F.Paste")
			(net "P5E_PEX1_STN4_TX_DN<68>")
		)
		(pad "2" smd rect
			(at 0.2667 0 90)
			(size 0.3048 0.381)
			(layers "F.Cu" "F.Mask" "F.Paste")
			(net "P5E_PEX1_STN4_TX_C_DN<68>")
		)
	)
	(footprint ""
		(layer "F.Cu")
		(at 155.380436 -103.803196)
		(property "Reference" "C271"
			(at 0 0 0)
			(layer "F.SilkS")
			(hide yes)
			(effects
				(font
					(size 1.27 1.27)
				)
			)
		)
		(property "Value" ""
			(at 0 0 0)
			(layer "F.Fab")
			(effects
				(font
					(size 1.27 1.27)
				)
			)
		)
		(duplicate_pad_numbers_are_jumpers no)
		(fp_line
			(start -0.299974 -0.150114)
			(end 0.299974 -0.150114)
			(stroke
				(width 0.1)
				(type default)
			)
			(layer "F.Fab")
		)
		(fp_line
			(start -0.299974 0.150114)
			(end -0.299974 -0.150114)
			(stroke
				(width 0.1)
				(type default)
			)
			(layer "F.Fab")
		)
		(fp_line
			(start 0.299974 -0.150114)
			(end 0.299974 0.150114)
			(stroke
				(width 0.1)
				(type default)
			)
			(layer "F.Fab")
		)
		(fp_line
			(start 0.299974 0.150114)
			(end -0.299974 0.150114)
			(stroke
				(width 0.1)
				(type default)
			)
			(layer "F.Fab")
		)
		(pad "1" smd rect
			(at -0.2667 0)
			(size 0.3048 0.381)
			(layers "F.Cu" "F.Mask" "F.Paste")
			(net "P5E_PEX1_STN1_TX_DN<18>")
		)
		(pad "2" smd rect
			(at 0.2667 0)
			(size 0.3048 0.381)
			(layers "F.Cu" "F.Mask" "F.Paste")
			(net "P5E_PEX1_STN1_TX_C_DN<18>")
		)
	)
	(footprint ""
		(layer "F.Cu")
		(at 233.594656 -204.44206 90)
		(property "Reference" "R5535"
			(at 0 0 90)
			(layer "F.SilkS")
			(hide yes)
			(effects
				(font
					(size 1.27 1.27)
				)
			)
		)
		(property "Value" ""
			(at 0 0 90)
			(layer "F.Fab")
			(effects
				(font
					(size 1.27 1.27)
				)
			)
		)
		(duplicate_pad_numbers_are_jumpers no)
		(fp_line
			(start 0.7874 -0.4064)
			(end 0.7874 0.4064)
			(stroke
				(width 0.1524)
				(type default)
			)
			(layer "F.SilkS")
		)
		(fp_line
			(start -0.7874 -0.4064)
			(end 0.7874 -0.4064)
			(stroke
				(width 0.1524)
				(type default)
			)
			(layer "F.SilkS")
		)
		(fp_line
			(start 0.7874 0.4064)
			(end -0.7874 0.4064)
			(stroke
				(width 0.1524)
				(type default)
			)
			(layer "F.SilkS")
		)
		(fp_line
			(start -0.7874 0.4064)
			(end -0.7874 -0.4064)
			(stroke
				(width 0.1524)
				(type default)
			)
			(layer "F.SilkS")
		)
		(fp_line
			(start -0.12065 -0.305054)
			(end -0.12065 -0.2794)
			(stroke
				(width 0.1)
				(type default)
			)
			(layer "F.Fab")
		)
		(fp_line
			(start -0.67945 -0.305054)
			(end -0.12065 -0.305054)
			(stroke
				(width 0.1)
				(type default)
			)
			(layer "F.Fab")
		)
		(fp_line
			(start 0.67945 -0.3048)
			(end 0.67945 0.3048)
			(stroke
				(width 0.1)
				(type default)
			)
			(layer "F.Fab")
		)
		(fp_line
			(start 0.12065 -0.3048)
			(end 0.67945 -0.3048)
			(stroke
				(width 0.1)
				(type default)
			)
			(layer "F.Fab")
		)
		(fp_line
			(start 0.12065 -0.2794)
			(end 0.12065 -0.3048)
			(stroke
				(width 0.1)
				(type default)
			)
			(layer "F.Fab")
		)
		(fp_line
			(start -0.12065 -0.2794)
			(end 0.12065 -0.2794)
			(stroke
				(width 0.1)
				(type default)
			)
			(layer "F.Fab")
		)
		(fp_line
			(start 0.120396 0.2794)
			(end -0.12065 0.2794)
			(stroke
				(width 0.1)
				(type default)
			)
			(layer "F.Fab")
		)
		(fp_line
			(start -0.12065 0.2794)
			(end -0.12065 0.3048)
			(stroke
				(width 0.1)
				(type default)
			)
			(layer "F.Fab")
		)
		(fp_line
			(start 0.67945 0.3048)
			(end 0.120396 0.3048)
			(stroke
				(width 0.1)
				(type default)
			)
			(layer "F.Fab")
		)
		(fp_line
			(start 0.120396 0.3048)
			(end 0.120396 0.2794)
			(stroke
				(width 0.1)
				(type default)
			)
			(layer "F.Fab")
		)
		(fp_line
			(start -0.12065 0.3048)
			(end -0.67945 0.3048)
			(stroke
				(width 0.1)
				(type default)
			)
			(layer "F.Fab")
		)
		(fp_line
			(start -0.67945 0.3048)
			(end -0.67945 -0.305054)
			(stroke
				(width 0.1)
				(type default)
			)
			(layer "F.Fab")
		)
		(pad "1" smd circle
			(at -0.40005 0 90)
			(size 0 0)
			(layers "F.Cu" "F.Mask" "F.Paste")
			(net "GND")
		)
		(pad "2" smd circle
			(at 0.40005 0 90)
			(size 0 0)
			(layers "F.Cu" "F.Mask" "F.Paste")
			(net "SPI_BIC1_MISO")
		)
	)
	(footprint ""
		(layer "F.Cu")
		(at 30.94736 -36.686998 90)
		(property "Reference" "C3661"
			(at 0 0 90)
			(layer "F.SilkS")
			(hide yes)
			(effects
				(font
					(size 1.27 1.27)
				)
			)
		)
		(property "Value" ""
			(at 0 0 90)
			(layer "F.Fab")
			(effects
				(font
					(size 1.27 1.27)
				)
			)
		)
		(duplicate_pad_numbers_are_jumpers no)
		(fp_line
			(start 0.7874 -0.4064)
			(end 0.7874 0.4064)
			(stroke
				(width 0.1524)
				(type default)
			)
			(layer "F.SilkS")
		)
		(fp_line
			(start -0.7874 -0.4064)
			(end 0.7874 -0.4064)
			(stroke
				(width 0.1524)
				(type default)
			)
			(layer "F.SilkS")
		)
		(fp_line
			(start 0.7874 0.4064)
			(end -0.7874 0.4064)
			(stroke
				(width 0.1524)
				(type default)
			)
			(layer "F.SilkS")
		)
		(fp_line
			(start -0.7874 0.4064)
			(end -0.7874 -0.4064)
			(stroke
				(width 0.1524)
				(type default)
			)
			(layer "F.SilkS")
		)
		(fp_line
			(start -0.12065 -0.305054)
			(end -0.12065 -0.2794)
			(stroke
				(width 0.1)
				(type default)
			)
			(layer "F.Fab")
		)
		(fp_line
			(start -0.67945 -0.305054)
			(end -0.12065 -0.305054)
			(stroke
				(width 0.1)
				(type default)
			)
			(layer "F.Fab")
		)
		(fp_line
			(start 0.67945 -0.3048)
			(end 0.67945 0.3048)
			(stroke
				(width 0.1)
				(type default)
			)
			(layer "F.Fab")
		)
		(fp_line
			(start 0.12065 -0.3048)
			(end 0.67945 -0.3048)
			(stroke
				(width 0.1)
				(type default)
			)
			(layer "F.Fab")
		)
		(fp_line
			(start 0.12065 -0.2794)
			(end 0.12065 -0.3048)
			(stroke
				(width 0.1)
				(type default)
			)
			(layer "F.Fab")
		)
		(fp_line
			(start -0.12065 -0.2794)
			(end 0.12065 -0.2794)
			(stroke
				(width 0.1)
				(type default)
			)
			(layer "F.Fab")
		)
		(fp_line
			(start 0.120396 0.2794)
			(end -0.12065 0.2794)
			(stroke
				(width 0.1)
				(type default)
			)
			(layer "F.Fab")
		)
		(fp_line
			(start -0.12065 0.2794)
			(end -0.12065 0.3048)
			(stroke
				(width 0.1)
				(type default)
			)
			(layer "F.Fab")
		)
		(fp_line
			(start 0.67945 0.3048)
			(end 0.120396 0.3048)
			(stroke
				(width 0.1)
				(type default)
			)
			(layer "F.Fab")
		)
		(fp_line
			(start 0.120396 0.3048)
			(end 0.120396 0.2794)
			(stroke
				(width 0.1)
				(type default)
			)
			(layer "F.Fab")
		)
		(fp_line
			(start -0.12065 0.3048)
			(end -0.67945 0.3048)
			(stroke
				(width 0.1)
				(type default)
			)
			(layer "F.Fab")
		)
		(fp_line
			(start -0.67945 0.3048)
			(end -0.67945 -0.305054)
			(stroke
				(width 0.1)
				(type default)
			)
			(layer "F.Fab")
		)
		(pad "1" smd circle
			(at -0.40005 0 90)
			(size 0 0)
			(layers "F.Cu" "F.Mask" "F.Paste")
			(net "P3V3_AUX")
		)
		(pad "2" smd circle
			(at 0.40005 0 90)
			(size 0 0)
			(layers "F.Cu" "F.Mask" "F.Paste")
			(net "GND")
		)
	)
	(footprint ""
		(layer "F.Cu")
		(at 12.494768 -157.304994 -90)
		(property "Reference" "PU71"
			(at -3.272536 -1.526032 0)
			(unlocked yes)
			(layer "F.SilkS")
			(effects
				(font
					(size 0.7874 0.5842)
					(thickness 0.1524)
				)
				(justify left)
			)
		)
		(property "Value" ""
			(at 0 0 270)
			(layer "F.Fab")
			(effects
				(font
					(size 1.27 1.27)
				)
			)
		)
		(duplicate_pad_numbers_are_jumpers no)
		(fp_line
			(start -1.549908 2.549906)
			(end -0.753872 2.549906)
			(stroke
				(width 0.1524)
				(type default)
			)
			(layer "F.SilkS")
		)
		(fp_line
			(start -0.245872 2.549906)
			(end 0.245872 2.549906)
			(stroke
				(width 0.1524)
				(type default)
			)
			(layer "F.SilkS")
		)
		(fp_line
			(start 0.753872 2.549906)
			(end 1.549908 2.549906)
			(stroke
				(width 0.1524)
				(type default)
			)
			(layer "F.SilkS")
		)
		(fp_line
			(start 1.549908 2.549906)
			(end 1.549908 2.253996)
			(stroke
				(width 0.1524)
				(type default)
			)
			(layer "F.SilkS")
		)
		(fp_line
			(start -1.549908 2.253996)
			(end -1.549908 2.549906)
			(stroke
				(width 0.1524)
				(type default)
			)
			(layer "F.SilkS")
		)
		(fp_line
			(start 1.549908 -2.253996)
			(end 1.549908 -2.549906)
			(stroke
				(width 0.1524)
				(type default)
			)
			(layer "F.SilkS")
		)
		(fp_line
			(start -1.549908 -2.549906)
			(end -1.549908 -2.251964)
			(stroke
				(width 0.1524)
				(type default)
			)
			(layer "F.SilkS")
		)
		(fp_line
			(start -0.752094 -2.549906)
			(end -1.549908 -2.549906)
			(stroke
				(width 0.1524)
				(type default)
			)
			(layer "F.SilkS")
		)
		(fp_line
			(start 0.2413 -2.549906)
			(end -0.2413 -2.549906)
			(stroke
				(width 0.1524)
				(type default)
			)
			(layer "F.SilkS")
		)
		(fp_line
			(start 1.549908 -2.549906)
			(end 0.752094 -2.549906)
			(stroke
				(width 0.1524)
				(type default)
			)
			(layer "F.SilkS")
		)
		(fp_poly
			(pts
				(xy -1.702054 -2.417064) (xy -2.605278 -2.718054) (xy -2.003298 -3.320288)
			)
			(stroke
				(width 0)
				(type default)
			)
			(fill yes)
			(layer "F.SilkS")
		)
		(fp_line
			(start -1.549908 2.549906)
			(end 1.549908 2.549906)
			(stroke
				(width 0.1)
				(type default)
			)
			(layer "F.Fab")
		)
		(fp_line
			(start 1.549908 2.549906)
			(end 1.549908 -2.549906)
			(stroke
				(width 0.1)
				(type default)
			)
			(layer "F.Fab")
		)
		(fp_line
			(start -1.549908 -2.549906)
			(end -1.549908 2.549906)
			(stroke
				(width 0.1)
				(type default)
			)
			(layer "F.Fab")
		)
		(fp_line
			(start 1.549908 -2.549906)
			(end -1.549908 -2.549906)
			(stroke
				(width 0.1)
				(type default)
			)
			(layer "F.Fab")
		)
		(fp_poly
			(pts
				(xy -1.891538 -1.999996) (xy -2.7432 -1.574292) (xy -2.7432 -2.4257)
			)
			(stroke
				(width 0)
				(type default)
			)
			(fill yes)
			(layer "F.Fab")
		)
		(fp_text user "10"
			(at -1.4224 3.044444 270)
			(unlocked yes)
			(layer "F.SilkS")
			(effects
				(font
					(size 0.635 0.4064)
					(thickness 0.1524)
				)
			)
		)
		(fp_text user "11"
			(at 1.182878 2.989072 270)
			(unlocked yes)
			(layer "F.SilkS")
			(effects
				(font
					(size 0.635 0.4064)
					(thickness 0.1524)
				)
			)
		)
		(fp_text user "9"
			(at -2.338832 2.5908 180)
			(unlocked yes)
			(layer "F.SilkS")
			(effects
				(font
					(size 0.635 0.4064)
					(thickness 0.1524)
				)
			)
		)
		(fp_text user "12"
			(at 2.482088 1.070864 180)
			(unlocked yes)
			(layer "F.SilkS")
			(effects
				(font
					(size 0.635 0.4064)
					(thickness 0.1524)
				)
			)
		)
		(fp_text user "21_22"
			(at 0.395986 -3.379724 270)
			(unlocked yes)
			(layer "F.SilkS")
			(effects
				(font
					(size 0.635 0.4064)
					(thickness 0.1524)
				)
			)
		)
		(fp_text user "20"
			(at 2.143252 -3.877564 180)
			(unlocked yes)
			(layer "F.SilkS")
			(effects
				(font
					(size 0.635 0.4064)
					(thickness 0.1524)
				)
			)
		)
		(fp_text user "11"
			(at 1.1938 3.329432 270)
			(unlocked yes)
			(layer "F.Fab")
			(effects
				(font
					(size 0.635 0.4064)
					(thickness 0.1524)
				)
			)
		)
		(fp_text user "10"
			(at -1.4224 3.253232 270)
			(unlocked yes)
			(layer "F.Fab")
			(effects
				(font
					(size 0.635 0.4064)
					(thickness 0.1524)
				)
			)
		)
		(fp_text user "12"
			(at 2.207768 2.7178 180)
			(unlocked yes)
			(layer "F.Fab")
			(effects
				(font
					(size 0.635 0.4064)
					(thickness 0.1524)
				)
			)
		)
		(fp_text user "9"
			(at -2.338832 2.5908 180)
			(unlocked yes)
			(layer "F.Fab")
			(effects
				(font
					(size 0.635 0.4064)
					(thickness 0.1524)
				)
			)
		)
		(fp_text user "20"
			(at 2.055368 -2.7686 180)
			(unlocked yes)
			(layer "F.Fab")
			(effects
				(font
					(size 0.635 0.4064)
					(thickness 0.1524)
				)
			)
		)
		(fp_text user "21_22"
			(at -0.0762 -3.401568 270)
			(unlocked yes)
			(layer "F.Fab")
			(effects
				(font
					(size 0.635 0.4064)
					(thickness 0.1524)
				)
			)
		)
		(pad "1" smd circle
			(at -1.374902 -1.999996 180)
			(size 0 0)
			(layers "F.Cu" "F.Mask" "F.Paste")
			(net "P12V_NIC0_CO_EN")
		)
		(pad "2" smd rect
			(at -1.400048 -1.500124 180)
			(size 0.254 0.8128)
			(layers "F.Cu" "F.Mask" "F.Paste")
			(net "GND")
		)
		(pad "3" smd rect
			(at -1.400048 -0.999998 180)
			(size 0.254 0.8128)
			(layers "F.Cu" "F.Mask" "F.Paste")
			(net "GND")
		)
		(pad "4" smd rect
			(at -1.400048 -0.499872 180)
			(size 0.254 0.8128)
			(layers "F.Cu" "F.Mask" "F.Paste")
			(net "P12V_NIC0_CO_TIMER")
		)
		(pad "5" smd rect
			(at -1.400048 0 180)
			(size 0.254 0.8128)
			(layers "F.Cu" "F.Mask" "F.Paste")
			(net "P12V_NIC0_CO_ISET")
		)
		(pad "6" smd rect
			(at -1.400048 0.499872 180)
			(size 0.254 0.8128)
			(layers "F.Cu" "F.Mask" "F.Paste")
			(net "P12V_NIC0_CO_SS")
		)
		(pad "7" smd rect
			(at -1.400048 0.999998 180)
			(size 0.254 0.8128)
			(layers "F.Cu" "F.Mask" "F.Paste")
			(net "GND")
		)
		(pad "8" smd rect
			(at -1.400048 1.500124 180)
			(size 0.254 0.8128)
			(layers "F.Cu" "F.Mask" "F.Paste")
			(net "P12V_NIC0_CO_IMON_VR")
		)
		(pad "9" smd rect
			(at -1.400048 1.999996 180)
			(size 0.254 0.8128)
			(layers "F.Cu" "F.Mask" "F.Paste")
			(net "P12V_NIC0_CO_FLTB")
		)
		(pad "10" smd rect
			(at -0.499872 2.400046 270)
			(size 0.254 0.8128)
			(layers "F.Cu" "F.Mask" "F.Paste")
			(net "PWRGD_P12V_NIC0_CO")
		)
		(pad "11" smd rect
			(at 0.499872 2.400046 270)
			(size 0.254 0.8128)
			(layers "F.Cu" "F.Mask" "F.Paste")
			(net "P12V_NIC0_CO_OV_FB")
		)
		(pad "12" smd rect
			(at 1.400048 1.999996 180)
			(size 0.254 0.8128)
			(layers "F.Cu" "F.Mask" "F.Paste")
			(net "P12V_NIC0_CO_AVIN_PD")
		)
		(pad "13" smd rect
			(at 1.400048 1.500124 180)
			(size 0.254 0.8128)
			(layers "F.Cu" "F.Mask" "F.Paste")
			(net "P12V_NIC0_R")
		)
		(pad "14" smd rect
			(at 1.400048 0.999998 180)
			(size 0.254 0.8128)
			(layers "F.Cu" "F.Mask" "F.Paste")
			(net "P12V_NIC0_R")
		)
		(pad "15" smd rect
			(at 1.400048 0.499872 180)
			(size 0.254 0.8128)
			(layers "F.Cu" "F.Mask" "F.Paste")
			(net "P12V_NIC0_R")
		)
		(pad "16" smd rect
			(at 1.400048 0 180)
			(size 0.254 0.8128)
			(layers "F.Cu" "F.Mask" "F.Paste")
			(net "P12V_NIC0_R")
		)
		(pad "17" smd rect
			(at 1.400048 -0.499872 180)
			(size 0.254 0.8128)
			(layers "F.Cu" "F.Mask" "F.Paste")
			(net "P12V_NIC0_R")
		)
		(pad "18" smd rect
			(at 1.400048 -0.999998 180)
			(size 0.254 0.8128)
			(layers "F.Cu" "F.Mask" "F.Paste")
			(net "P12V_NIC0_R")
		)
		(pad "19" smd rect
			(at 1.400048 -1.500124 180)
			(size 0.254 0.8128)
			(layers "F.Cu" "F.Mask" "F.Paste")
			(net "P12V_NIC0_R")
		)
		(pad "20" smd rect
			(at 1.400048 -1.999996 180)
			(size 0.254 0.8128)
			(layers "F.Cu" "F.Mask" "F.Paste")
			(net "P12V_NIC0_R")
		)
		(pad "21_22" smd circle
			(at 0.499872 -2.337562 180)
			(size 0 0)
			(layers "F.Cu" "F.Mask" "F.Paste")
			(net "P12V_AUX")
		)
		(pad "23" smd rect
			(at 0 -1.100074 180)
			(size 0.254 1.27)
			(layers "F.Cu" "F.Mask" "F.Paste")
			(net "P12V_AUX")
		)
		(pad "24" smd rect
			(at 0 -0.199898 180)
			(size 0.254 1.27)
			(layers "F.Cu" "F.Mask" "F.Paste")
			(net "P12V_AUX")
		)
		(pad "25" smd rect
			(at 0 0.700024 180)
			(size 0.254 1.27)
			(layers "F.Cu" "F.Mask" "F.Paste")
			(net "P12V_AUX")
		)
		(pad "26" smd rect
			(at 0 1.599946 180)
			(size 0.254 1.27)
			(layers "F.Cu" "F.Mask" "F.Paste")
			(net "P12V_AUX")
		)
	)
	(footprint ""
		(layer "F.Cu")
		(at 431.247296 -36.686998 90)
		(property "Reference" "C3673"
			(at 0 0 90)
			(layer "F.SilkS")
			(hide yes)
			(effects
				(font
					(size 1.27 1.27)
				)
			)
		)
		(property "Value" ""
			(at 0 0 90)
			(layer "F.Fab")
			(effects
				(font
					(size 1.27 1.27)
				)
			)
		)
		(duplicate_pad_numbers_are_jumpers no)
		(fp_line
			(start 0.7874 -0.4064)
			(end 0.7874 0.4064)
			(stroke
				(width 0.1524)
				(type default)
			)
			(layer "F.SilkS")
		)
		(fp_line
			(start -0.7874 -0.4064)
			(end 0.7874 -0.4064)
			(stroke
				(width 0.1524)
				(type default)
			)
			(layer "F.SilkS")
		)
		(fp_line
			(start 0.7874 0.4064)
			(end -0.7874 0.4064)
			(stroke
				(width 0.1524)
				(type default)
			)
			(layer "F.SilkS")
		)
		(fp_line
			(start -0.7874 0.4064)
			(end -0.7874 -0.4064)
			(stroke
				(width 0.1524)
				(type default)
			)
			(layer "F.SilkS")
		)
		(fp_line
			(start -0.12065 -0.305054)
			(end -0.12065 -0.2794)
			(stroke
				(width 0.1)
				(type default)
			)
			(layer "F.Fab")
		)
		(fp_line
			(start -0.67945 -0.305054)
			(end -0.12065 -0.305054)
			(stroke
				(width 0.1)
				(type default)
			)
			(layer "F.Fab")
		)
		(fp_line
			(start 0.67945 -0.3048)
			(end 0.67945 0.3048)
			(stroke
				(width 0.1)
				(type default)
			)
			(layer "F.Fab")
		)
		(fp_line
			(start 0.12065 -0.3048)
			(end 0.67945 -0.3048)
			(stroke
				(width 0.1)
				(type default)
			)
			(layer "F.Fab")
		)
		(fp_line
			(start 0.12065 -0.2794)
			(end 0.12065 -0.3048)
			(stroke
				(width 0.1)
				(type default)
			)
			(layer "F.Fab")
		)
		(fp_line
			(start -0.12065 -0.2794)
			(end 0.12065 -0.2794)
			(stroke
				(width 0.1)
				(type default)
			)
			(layer "F.Fab")
		)
		(fp_line
			(start 0.120396 0.2794)
			(end -0.12065 0.2794)
			(stroke
				(width 0.1)
				(type default)
			)
			(layer "F.Fab")
		)
		(fp_line
			(start -0.12065 0.2794)
			(end -0.12065 0.3048)
			(stroke
				(width 0.1)
				(type default)
			)
			(layer "F.Fab")
		)
		(fp_line
			(start 0.67945 0.3048)
			(end 0.120396 0.3048)
			(stroke
				(width 0.1)
				(type default)
			)
			(layer "F.Fab")
		)
		(fp_line
			(start 0.120396 0.3048)
			(end 0.120396 0.2794)
			(stroke
				(width 0.1)
				(type default)
			)
			(layer "F.Fab")
		)
		(fp_line
			(start -0.12065 0.3048)
			(end -0.67945 0.3048)
			(stroke
				(width 0.1)
				(type default)
			)
			(layer "F.Fab")
		)
		(fp_line
			(start -0.67945 0.3048)
			(end -0.67945 -0.305054)
			(stroke
				(width 0.1)
				(type default)
			)
			(layer "F.Fab")
		)
		(pad "1" smd circle
			(at -0.40005 0 90)
			(size 0 0)
			(layers "F.Cu" "F.Mask" "F.Paste")
			(net "P3V3_AUX")
		)
		(pad "2" smd circle
			(at 0.40005 0 90)
			(size 0 0)
			(layers "F.Cu" "F.Mask" "F.Paste")
			(net "GND")
		)
	)
	(footprint ""
		(layer "F.Cu")
		(at 383.05613 -115.590574 90)
		(property "Reference" "U39"
			(at 2.542286 -0.661416 0)
			(unlocked yes)
			(layer "F.SilkS")
			(effects
				(font
					(size 0.7874 0.5842)
					(thickness 0.1524)
				)
			)
		)
		(property "Value" ""
			(at 0 0 90)
			(layer "F.Fab")
			(effects
				(font
					(size 1.27 1.27)
				)
			)
		)
		(duplicate_pad_numbers_are_jumpers no)
		(fp_line
			(start -1.949958 -1.610106)
			(end 1.949958 -1.610106)
			(stroke
				(width 0.1524)
				(type default)
			)
			(layer "F.SilkS")
		)
		(fp_line
			(start 1.949958 -1.560068)
			(end 1.949958 1.610106)
			(stroke
				(width 0.1524)
				(type default)
			)
			(layer "F.SilkS")
		)
		(fp_line
			(start 1.949958 1.610106)
			(end -1.949958 1.610106)
			(stroke
				(width 0.1524)
				(type default)
			)
			(layer "F.SilkS")
		)
		(fp_line
			(start -1.949958 1.610106)
			(end -1.949958 -1.610106)
			(stroke
				(width 0.1524)
				(type default)
			)
			(layer "F.SilkS")
		)
		(fp_line
			(start 0.750062 -1.560068)
			(end 0.750062 1.560068)
			(stroke
				(width 0.1)
				(type default)
			)
			(layer "F.Fab")
		)
		(fp_line
			(start -0.750062 -1.560068)
			(end 0.750062 -1.560068)
			(stroke
				(width 0.1)
				(type default)
			)
			(layer "F.Fab")
		)
		(fp_line
			(start 0.750062 1.560068)
			(end -0.750062 1.560068)
			(stroke
				(width 0.1)
				(type default)
			)
			(layer "F.Fab")
		)
		(fp_line
			(start -0.750062 1.560068)
			(end -0.750062 -1.560068)
			(stroke
				(width 0.1)
				(type default)
			)
			(layer "F.Fab")
		)
		(pad "D" smd rect
			(at 1.100074 0)
			(size 1.016 1.4224)
			(layers "F.Cu" "F.Mask" "F.Paste")
			(net "HP_NIC6_EN")
		)
		(pad "G" smd rect
			(at -1.100074 -0.94996)
			(size 1.016 1.4224)
			(layers "F.Cu" "F.Mask" "F.Paste")
			(net "PRSNT_NIC6_R_N")
		)
		(pad "S" smd rect
			(at -1.100074 0.94996)
			(size 1.016 1.4224)
			(layers "F.Cu" "F.Mask" "F.Paste")
			(net "GND")
		)
	)
	(footprint ""
		(layer "F.Cu")
		(at 236.927136 -266.873228 180)
		(property "Reference" "R6137"
			(at 0 0 180)
			(layer "F.SilkS")
			(hide yes)
			(effects
				(font
					(size 1.27 1.27)
				)
			)
		)
		(property "Value" ""
			(at 0 0 180)
			(layer "F.Fab")
			(effects
				(font
					(size 1.27 1.27)
				)
			)
		)
		(duplicate_pad_numbers_are_jumpers no)
		(fp_line
			(start 2.576322 1.1303)
			(end -2.576322 1.1303)
			(stroke
				(width 0.1524)
				(type default)
			)
			(layer "F.SilkS")
		)
		(fp_line
			(start 2.576322 -1.1303)
			(end 2.576322 1.1303)
			(stroke
				(width 0.1524)
				(type default)
			)
			(layer "F.SilkS")
		)
		(fp_line
			(start -2.576322 1.1303)
			(end -2.576322 -1.1303)
			(stroke
				(width 0.1524)
				(type default)
			)
			(layer "F.SilkS")
		)
		(fp_line
			(start -2.576322 -1.1303)
			(end 2.576322 -1.1303)
			(stroke
				(width 0.1524)
				(type default)
			)
			(layer "F.SilkS")
		)
		(fp_line
			(start 1.649984 0.899922)
			(end 1.649984 -0.899922)
			(stroke
				(width 0.1)
				(type default)
			)
			(layer "F.Fab")
		)
		(fp_line
			(start 1.649984 -0.899922)
			(end -1.649984 -0.899922)
			(stroke
				(width 0.1)
				(type default)
			)
			(layer "F.Fab")
		)
		(fp_line
			(start -1.649984 0.899922)
			(end 1.649984 0.899922)
			(stroke
				(width 0.1)
				(type default)
			)
			(layer "F.Fab")
		)
		(fp_line
			(start -1.649984 -0.899922)
			(end -1.649984 0.899922)
			(stroke
				(width 0.1)
				(type default)
			)
			(layer "F.Fab")
		)
		(pad "1A" smd rect
			(at -1.700022 0 180)
			(size 1.4986 2.0066)
			(layers "F.Cu" "F.Mask" "F.Paste")
			(net "P1V25_PEX2")
		)
		(pad "1B" smd rect
			(at -1.077722 0 180)
			(size 0.254 0.508)
			(layers "F.Cu" "F.Mask" "F.Paste")
			(net "P1V25_PEX2")
		)
		(pad "2A" smd rect
			(at 1.700022 0 180)
			(size 1.4986 2.0066)
			(layers "F.Cu" "F.Mask" "F.Paste")
			(net "P1V25_SERDES_VDDPLL_PEX2")
		)
		(pad "2B" smd rect
			(at 1.077722 0 180)
			(size 0.254 0.508)
			(layers "F.Cu" "F.Mask" "F.Paste")
			(net "P1V25_SERDES_VDDPLL_PEX2")
		)
	)
	(footprint ""
		(layer "F.Cu")
		(at 80.000602 -356.244906 90)
		(property "Reference" "C147"
			(at 0 0 90)
			(layer "F.SilkS")
			(hide yes)
			(effects
				(font
					(size 1.27 1.27)
				)
			)
		)
		(property "Value" ""
			(at 0 0 90)
			(layer "F.Fab")
			(effects
				(font
					(size 1.27 1.27)
				)
			)
		)
		(duplicate_pad_numbers_are_jumpers no)
		(fp_line
			(start 0.299974 -0.150114)
			(end 0.299974 0.150114)
			(stroke
				(width 0.1)
				(type default)
			)
			(layer "F.Fab")
		)
		(fp_line
			(start -0.299974 -0.150114)
			(end 0.299974 -0.150114)
			(stroke
				(width 0.1)
				(type default)
			)
			(layer "F.Fab")
		)
		(fp_line
			(start 0.299974 0.150114)
			(end -0.299974 0.150114)
			(stroke
				(width 0.1)
				(type default)
			)
			(layer "F.Fab")
		)
		(fp_line
			(start -0.299974 0.150114)
			(end -0.299974 -0.150114)
			(stroke
				(width 0.1)
				(type default)
			)
			(layer "F.Fab")
		)
		(pad "1" smd rect
			(at -0.2667 0 90)
			(size 0.3048 0.381)
			(layers "F.Cu" "F.Mask" "F.Paste")
			(net "P5E_PEX0_STN6_TX_DP<102>")
		)
		(pad "2" smd rect
			(at 0.2667 0 90)
			(size 0.3048 0.381)
			(layers "F.Cu" "F.Mask" "F.Paste")
			(net "P5E_PEX0_STN6_TX_C_DP<102>")
		)
	)
	(footprint ""
		(layer "F.Cu")
		(at 43.792394 -28.225242 180)
		(property "Reference" "C80"
			(at 0 0 180)
			(layer "F.SilkS")
			(hide yes)
			(effects
				(font
					(size 1.27 1.27)
				)
			)
		)
		(property "Value" ""
			(at 0 0 180)
			(layer "F.Fab")
			(effects
				(font
					(size 1.27 1.27)
				)
			)
		)
		(duplicate_pad_numbers_are_jumpers no)
		(fp_line
			(start 0.299974 0.150114)
			(end -0.299974 0.150114)
			(stroke
				(width 0.1)
				(type default)
			)
			(layer "F.Fab")
		)
		(fp_line
			(start 0.299974 -0.150114)
			(end 0.299974 0.150114)
			(stroke
				(width 0.1)
				(type default)
			)
			(layer "F.Fab")
		)
		(fp_line
			(start -0.299974 0.150114)
			(end -0.299974 -0.150114)
			(stroke
				(width 0.1)
				(type default)
			)
			(layer "F.Fab")
		)
		(fp_line
			(start -0.299974 -0.150114)
			(end 0.299974 -0.150114)
			(stroke
				(width 0.1)
				(type default)
			)
			(layer "F.Fab")
		)
		(pad "1" smd rect
			(at -0.2667 0 180)
			(size 0.3048 0.381)
			(layers "F.Cu" "F.Mask" "F.Paste")
			(net "P5E_PEX0_STN2_TX_DN<40>")
		)
		(pad "2" smd rect
			(at 0.2667 0 180)
			(size 0.3048 0.381)
			(layers "F.Cu" "F.Mask" "F.Paste")
			(net "P5E_PEX0_STN2_TX_C_DN<40>")
		)
	)
	(footprint ""
		(layer "F.Cu")
		(at 23.326852 -172.974508 90)
		(property "Reference" "PJ2"
			(at 0 0 90)
			(layer "F.SilkS")
			(hide yes)
			(effects
				(font
					(size 1.27 1.27)
				)
			)
		)
		(property "Value" ""
			(at 0 0 90)
			(layer "F.Fab")
			(effects
				(font
					(size 1.27 1.27)
				)
			)
		)
		(duplicate_pad_numbers_are_jumpers no)
		(pad "1" smd circle
			(at -0.40005 0 180)
			(size 0 0)
			(layers "F.Cu" "F.Mask" "F.Paste")
			(net "SH_P5V_AUX_FB")
		)
		(pad "2" smd rect
			(at 0.40005 0 270)
			(size 0.4572 0.508)
			(layers "F.Cu" "F.Mask" "F.Paste")
			(net "P5V_AUX")
		)
		(zone
			(layer "F.Cu")
			(hatch none 0.5)
			(connect_pads
				(clearance 0)
			)
			(min_thickness 0.25)
			(keepout
				(tracks allowed)
				(vias not_allowed)
				(pads allowed)
				(copperpour not_allowed)
				(footprints allowed)
			)
			(placement
				(enabled no)
				(sheetname "")
			)
			(fill
				(thermal_gap 0.5)
				(thermal_bridge_width 0.5)
				(island_removal_mode 0)
			)
			(polygon
				(pts
					(xy 23.631652 -173.660308) (xy 23.022052 -173.660308) (xy 23.022052 -172.288708) (xy 23.631652 -172.288708)
				)
			)
		)
	)
	(footprint ""
		(layer "F.Cu")
		(at 494.303558 -549.60774 180)
		(property "Reference" "SCREW_1"
			(at -3.2385 -1.402334 0)
			(unlocked yes)
			(layer "B.SilkS")
			(effects
				(font
					(size 0.7874 0.5842)
					(thickness 0.1524)
				)
				(justify mirror)
			)
		)
		(property "Value" ""
			(at 0 0 180)
			(layer "F.Fab")
			(effects
				(font
					(size 1.27 1.27)
				)
			)
		)
		(duplicate_pad_numbers_are_jumpers no)
		(pad "1" thru_hole circle
			(at 0 0 180)
			(size 0.4572 0.4572)
			(drill 0.2032)
			(layers "*.Cu" "*.Mask")
			(remove_unused_layers no)
			(net "Net_9163")
			(clearance 0.127)
			(thermal_gap 0.127)
			(padstack
				(mode front_inner_back)
				(layer "Inner"
					(shape circle)
					(size 0.4572 0.4572)
					(clearance 0.127)
				)
				(layer "B.Cu"
					(shape circle)
					(size 0.508 0.508)
					(clearance 0.1016)
				)
			)
		)
	)
	(footprint ""
		(layer "F.Cu")
		(at 452.324978 -14.735302 180)
		(property "Reference" "C2742"
			(at 0 0 180)
			(layer "F.SilkS")
			(hide yes)
			(effects
				(font
					(size 1.27 1.27)
				)
			)
		)
		(property "Value" ""
			(at 0 0 180)
			(layer "F.Fab")
			(effects
				(font
					(size 1.27 1.27)
				)
			)
		)
		(duplicate_pad_numbers_are_jumpers no)
		(fp_line
			(start 0.7874 0.4064)
			(end -0.7874 0.4064)
			(stroke
				(width 0.1524)
				(type default)
			)
			(layer "F.SilkS")
		)
		(fp_line
			(start 0.7874 -0.4064)
			(end 0.7874 0.4064)
			(stroke
				(width 0.1524)
				(type default)
			)
			(layer "F.SilkS")
		)
		(fp_line
			(start -0.7874 0.4064)
			(end -0.7874 -0.4064)
			(stroke
				(width 0.1524)
				(type default)
			)
			(layer "F.SilkS")
		)
		(fp_line
			(start -0.7874 -0.4064)
			(end 0.7874 -0.4064)
			(stroke
				(width 0.1524)
				(type default)
			)
			(layer "F.SilkS")
		)
		(fp_line
			(start 0.67945 0.3048)
			(end 0.120396 0.3048)
			(stroke
				(width 0.1)
				(type default)
			)
			(layer "F.Fab")
		)
		(fp_line
			(start 0.67945 -0.3048)
			(end 0.67945 0.3048)
			(stroke
				(width 0.1)
				(type default)
			)
			(layer "F.Fab")
		)
		(fp_line
			(start 0.12065 -0.2794)
			(end 0.12065 -0.3048)
			(stroke
				(width 0.1)
				(type default)
			)
			(layer "F.Fab")
		)
		(fp_line
			(start 0.12065 -0.3048)
			(end 0.67945 -0.3048)
			(stroke
				(width 0.1)
				(type default)
			)
			(layer "F.Fab")
		)
		(fp_line
			(start 0.120396 0.3048)
			(end 0.120396 0.2794)
			(stroke
				(width 0.1)
				(type default)
			)
			(layer "F.Fab")
		)
		(fp_line
			(start 0.120396 0.2794)
			(end -0.12065 0.2794)
			(stroke
				(width 0.1)
				(type default)
			)
			(layer "F.Fab")
		)
		(fp_line
			(start -0.12065 0.3048)
			(end -0.67945 0.3048)
			(stroke
				(width 0.1)
				(type default)
			)
			(layer "F.Fab")
		)
		(fp_line
			(start -0.12065 0.2794)
			(end -0.12065 0.3048)
			(stroke
				(width 0.1)
				(type default)
			)
			(layer "F.Fab")
		)
		(fp_line
			(start -0.12065 -0.2794)
			(end 0.12065 -0.2794)
			(stroke
				(width 0.1)
				(type default)
			)
			(layer "F.Fab")
		)
		(fp_line
			(start -0.12065 -0.305054)
			(end -0.12065 -0.2794)
			(stroke
				(width 0.1)
				(type default)
			)
			(layer "F.Fab")
		)
		(fp_line
			(start -0.67945 0.3048)
			(end -0.67945 -0.305054)
			(stroke
				(width 0.1)
				(type default)
			)
			(layer "F.Fab")
		)
		(fp_line
			(start -0.67945 -0.305054)
			(end -0.12065 -0.305054)
			(stroke
				(width 0.1)
				(type default)
			)
			(layer "F.Fab")
		)
		(pad "1" smd circle
			(at -0.40005 0 180)
			(size 0 0)
			(layers "F.Cu" "F.Mask" "F.Paste")
			(net "GND")
		)
		(pad "2" smd circle
			(at 0.40005 0 180)
			(size 0 0)
			(layers "F.Cu" "F.Mask" "F.Paste")
			(net "P3V3_SSD15")
		)
	)
	(footprint ""
		(layer "F.Cu")
		(at 232.591864 -204.44206 90)
		(property "Reference" "R5529"
			(at 0 0 90)
			(layer "F.SilkS")
			(hide yes)
			(effects
				(font
					(size 1.27 1.27)
				)
			)
		)
		(property "Value" ""
			(at 0 0 90)
			(layer "F.Fab")
			(effects
				(font
					(size 1.27 1.27)
				)
			)
		)
		(duplicate_pad_numbers_are_jumpers no)
		(fp_line
			(start 0.7874 -0.4064)
			(end 0.7874 0.4064)
			(stroke
				(width 0.1524)
				(type default)
			)
			(layer "F.SilkS")
		)
		(fp_line
			(start -0.7874 -0.4064)
			(end 0.7874 -0.4064)
			(stroke
				(width 0.1524)
				(type default)
			)
			(layer "F.SilkS")
		)
		(fp_line
			(start 0.7874 0.4064)
			(end -0.7874 0.4064)
			(stroke
				(width 0.1524)
				(type default)
			)
			(layer "F.SilkS")
		)
		(fp_line
			(start -0.7874 0.4064)
			(end -0.7874 -0.4064)
			(stroke
				(width 0.1524)
				(type default)
			)
			(layer "F.SilkS")
		)
		(fp_line
			(start -0.12065 -0.305054)
			(end -0.12065 -0.2794)
			(stroke
				(width 0.1)
				(type default)
			)
			(layer "F.Fab")
		)
		(fp_line
			(start -0.67945 -0.305054)
			(end -0.12065 -0.305054)
			(stroke
				(width 0.1)
				(type default)
			)
			(layer "F.Fab")
		)
		(fp_line
			(start 0.67945 -0.3048)
			(end 0.67945 0.3048)
			(stroke
				(width 0.1)
				(type default)
			)
			(layer "F.Fab")
		)
		(fp_line
			(start 0.12065 -0.3048)
			(end 0.67945 -0.3048)
			(stroke
				(width 0.1)
				(type default)
			)
			(layer "F.Fab")
		)
		(fp_line
			(start 0.12065 -0.2794)
			(end 0.12065 -0.3048)
			(stroke
				(width 0.1)
				(type default)
			)
			(layer "F.Fab")
		)
		(fp_line
			(start -0.12065 -0.2794)
			(end 0.12065 -0.2794)
			(stroke
				(width 0.1)
				(type default)
			)
			(layer "F.Fab")
		)
		(fp_line
			(start 0.120396 0.2794)
			(end -0.12065 0.2794)
			(stroke
				(width 0.1)
				(type default)
			)
			(layer "F.Fab")
		)
		(fp_line
			(start -0.12065 0.2794)
			(end -0.12065 0.3048)
			(stroke
				(width 0.1)
				(type default)
			)
			(layer "F.Fab")
		)
		(fp_line
			(start 0.67945 0.3048)
			(end 0.120396 0.3048)
			(stroke
				(width 0.1)
				(type default)
			)
			(layer "F.Fab")
		)
		(fp_line
			(start 0.120396 0.3048)
			(end 0.120396 0.2794)
			(stroke
				(width 0.1)
				(type default)
			)
			(layer "F.Fab")
		)
		(fp_line
			(start -0.12065 0.3048)
			(end -0.67945 0.3048)
			(stroke
				(width 0.1)
				(type default)
			)
			(layer "F.Fab")
		)
		(fp_line
			(start -0.67945 0.3048)
			(end -0.67945 -0.305054)
			(stroke
				(width 0.1)
				(type default)
			)
			(layer "F.Fab")
		)
		(pad "1" smd circle
			(at -0.40005 0 90)
			(size 0 0)
			(layers "F.Cu" "F.Mask" "F.Paste")
			(net "GND")
		)
		(pad "2" smd circle
			(at 0.40005 0 90)
			(size 0 0)
			(layers "F.Cu" "F.Mask" "F.Paste")
			(net "SPI_BIC1_CLK")
		)
	)
	(footprint ""
		(layer "F.Cu")
		(at 223.50476 -315.821314 180)
		(property "Reference" "PC226"
			(at 0 0 180)
			(layer "F.SilkS")
			(hide yes)
			(effects
				(font
					(size 1.27 1.27)
				)
			)
		)
		(property "Value" ""
			(at 0 0 180)
			(layer "F.Fab")
			(effects
				(font
					(size 1.27 1.27)
				)
			)
		)
		(duplicate_pad_numbers_are_jumpers no)
		(fp_line
			(start 1.524 0.762)
			(end -1.524 0.762)
			(stroke
				(width 0.1524)
				(type default)
			)
			(layer "F.SilkS")
		)
		(fp_line
			(start 1.524 -0.762)
			(end 1.524 0.762)
			(stroke
				(width 0.1524)
				(type default)
			)
			(layer "F.SilkS")
		)
		(fp_line
			(start -1.524 0.762)
			(end -1.524 -0.762)
			(stroke
				(width 0.1524)
				(type default)
			)
			(layer "F.SilkS")
		)
		(fp_line
			(start -1.524 -0.762)
			(end 1.524 -0.762)
			(stroke
				(width 0.1524)
				(type default)
			)
			(layer "F.SilkS")
		)
		(fp_line
			(start 1.1049 0.724916)
			(end 1.1049 -0.724916)
			(stroke
				(width 0.1)
				(type default)
			)
			(layer "F.Fab")
		)
		(fp_line
			(start 1.1049 -0.724916)
			(end -1.1049 -0.724916)
			(stroke
				(width 0.1)
				(type default)
			)
			(layer "F.Fab")
		)
		(fp_line
			(start -1.1049 0.724916)
			(end 1.1049 0.724916)
			(stroke
				(width 0.1)
				(type default)
			)
			(layer "F.Fab")
		)
		(fp_line
			(start -1.1049 -0.724916)
			(end -1.1049 0.724916)
			(stroke
				(width 0.1)
				(type default)
			)
			(layer "F.Fab")
		)
		(pad "1" smd rect
			(at -0.889 0)
			(size 1.016 1.27)
			(layers "F.Cu" "F.Mask" "F.Paste")
			(net "SW_P12V_P1V25_PEX1_FLT")
		)
		(pad "2" smd rect
			(at 0.889 0)
			(size 1.016 1.27)
			(layers "F.Cu" "F.Mask" "F.Paste")
			(net "GND")
		)
	)
	(footprint ""
		(layer "F.Cu")
		(at 108.106464 -390.420352 180)
		(property "Reference" "R5455"
			(at 0 0 180)
			(layer "F.SilkS")
			(hide yes)
			(effects
				(font
					(size 1.27 1.27)
				)
			)
		)
		(property "Value" ""
			(at 0 0 180)
			(layer "F.Fab")
			(effects
				(font
					(size 1.27 1.27)
				)
			)
		)
		(duplicate_pad_numbers_are_jumpers no)
		(fp_line
			(start 0.7874 0.4064)
			(end -0.7874 0.4064)
			(stroke
				(width 0.1524)
				(type default)
			)
			(layer "F.SilkS")
		)
		(fp_line
			(start 0.7874 -0.4064)
			(end 0.7874 0.4064)
			(stroke
				(width 0.1524)
				(type default)
			)
			(layer "F.SilkS")
		)
		(fp_line
			(start -0.7874 0.4064)
			(end -0.7874 -0.4064)
			(stroke
				(width 0.1524)
				(type default)
			)
			(layer "F.SilkS")
		)
		(fp_line
			(start -0.7874 -0.4064)
			(end 0.7874 -0.4064)
			(stroke
				(width 0.1524)
				(type default)
			)
			(layer "F.SilkS")
		)
		(fp_line
			(start 0.67945 0.3048)
			(end 0.120396 0.3048)
			(stroke
				(width 0.1)
				(type default)
			)
			(layer "F.Fab")
		)
		(fp_line
			(start 0.67945 -0.3048)
			(end 0.67945 0.3048)
			(stroke
				(width 0.1)
				(type default)
			)
			(layer "F.Fab")
		)
		(fp_line
			(start 0.12065 -0.2794)
			(end 0.12065 -0.3048)
			(stroke
				(width 0.1)
				(type default)
			)
			(layer "F.Fab")
		)
		(fp_line
			(start 0.12065 -0.3048)
			(end 0.67945 -0.3048)
			(stroke
				(width 0.1)
				(type default)
			)
			(layer "F.Fab")
		)
		(fp_line
			(start 0.120396 0.3048)
			(end 0.120396 0.2794)
			(stroke
				(width 0.1)
				(type default)
			)
			(layer "F.Fab")
		)
		(fp_line
			(start 0.120396 0.2794)
			(end -0.12065 0.2794)
			(stroke
				(width 0.1)
				(type default)
			)
			(layer "F.Fab")
		)
		(fp_line
			(start -0.12065 0.3048)
			(end -0.67945 0.3048)
			(stroke
				(width 0.1)
				(type default)
			)
			(layer "F.Fab")
		)
		(fp_line
			(start -0.12065 0.2794)
			(end -0.12065 0.3048)
			(stroke
				(width 0.1)
				(type default)
			)
			(layer "F.Fab")
		)
		(fp_line
			(start -0.12065 -0.2794)
			(end 0.12065 -0.2794)
			(stroke
				(width 0.1)
				(type default)
			)
			(layer "F.Fab")
		)
		(fp_line
			(start -0.12065 -0.305054)
			(end -0.12065 -0.2794)
			(stroke
				(width 0.1)
				(type default)
			)
			(layer "F.Fab")
		)
		(fp_line
			(start -0.67945 0.3048)
			(end -0.67945 -0.305054)
			(stroke
				(width 0.1)
				(type default)
			)
			(layer "F.Fab")
		)
		(fp_line
			(start -0.67945 -0.305054)
			(end -0.12065 -0.305054)
			(stroke
				(width 0.1)
				(type default)
			)
			(layer "F.Fab")
		)
		(pad "1" smd circle
			(at -0.40005 0 180)
			(size 0 0)
			(layers "F.Cu" "F.Mask" "F.Paste")
			(net "GND")
		)
		(pad "2" smd circle
			(at 0.40005 0 180)
			(size 0 0)
			(layers "F.Cu" "F.Mask" "F.Paste")
			(net "BIC_USB_HUB_RREF")
		)
	)
	(footprint ""
		(layer "F.Cu")
		(at 400.325082 -14.735302 180)
		(property "Reference" "C2738"
			(at 0 0 180)
			(layer "F.SilkS")
			(hide yes)
			(effects
				(font
					(size 1.27 1.27)
				)
			)
		)
		(property "Value" ""
			(at 0 0 180)
			(layer "F.Fab")
			(effects
				(font
					(size 1.27 1.27)
				)
			)
		)
		(duplicate_pad_numbers_are_jumpers no)
		(fp_line
			(start 0.7874 0.4064)
			(end -0.7874 0.4064)
			(stroke
				(width 0.1524)
				(type default)
			)
			(layer "F.SilkS")
		)
		(fp_line
			(start 0.7874 -0.4064)
			(end 0.7874 0.4064)
			(stroke
				(width 0.1524)
				(type default)
			)
			(layer "F.SilkS")
		)
		(fp_line
			(start -0.7874 0.4064)
			(end -0.7874 -0.4064)
			(stroke
				(width 0.1524)
				(type default)
			)
			(layer "F.SilkS")
		)
		(fp_line
			(start -0.7874 -0.4064)
			(end 0.7874 -0.4064)
			(stroke
				(width 0.1524)
				(type default)
			)
			(layer "F.SilkS")
		)
		(fp_line
			(start 0.67945 0.3048)
			(end 0.120396 0.3048)
			(stroke
				(width 0.1)
				(type default)
			)
			(layer "F.Fab")
		)
		(fp_line
			(start 0.67945 -0.3048)
			(end 0.67945 0.3048)
			(stroke
				(width 0.1)
				(type default)
			)
			(layer "F.Fab")
		)
		(fp_line
			(start 0.12065 -0.2794)
			(end 0.12065 -0.3048)
			(stroke
				(width 0.1)
				(type default)
			)
			(layer "F.Fab")
		)
		(fp_line
			(start 0.12065 -0.3048)
			(end 0.67945 -0.3048)
			(stroke
				(width 0.1)
				(type default)
			)
			(layer "F.Fab")
		)
		(fp_line
			(start 0.120396 0.3048)
			(end 0.120396 0.2794)
			(stroke
				(width 0.1)
				(type default)
			)
			(layer "F.Fab")
		)
		(fp_line
			(start 0.120396 0.2794)
			(end -0.12065 0.2794)
			(stroke
				(width 0.1)
				(type default)
			)
			(layer "F.Fab")
		)
		(fp_line
			(start -0.12065 0.3048)
			(end -0.67945 0.3048)
			(stroke
				(width 0.1)
				(type default)
			)
			(layer "F.Fab")
		)
		(fp_line
			(start -0.12065 0.2794)
			(end -0.12065 0.3048)
			(stroke
				(width 0.1)
				(type default)
			)
			(layer "F.Fab")
		)
		(fp_line
			(start -0.12065 -0.2794)
			(end 0.12065 -0.2794)
			(stroke
				(width 0.1)
				(type default)
			)
			(layer "F.Fab")
		)
		(fp_line
			(start -0.12065 -0.305054)
			(end -0.12065 -0.2794)
			(stroke
				(width 0.1)
				(type default)
			)
			(layer "F.Fab")
		)
		(fp_line
			(start -0.67945 0.3048)
			(end -0.67945 -0.305054)
			(stroke
				(width 0.1)
				(type default)
			)
			(layer "F.Fab")
		)
		(fp_line
			(start -0.67945 -0.305054)
			(end -0.12065 -0.305054)
			(stroke
				(width 0.1)
				(type default)
			)
			(layer "F.Fab")
		)
		(pad "1" smd circle
			(at -0.40005 0 180)
			(size 0 0)
			(layers "F.Cu" "F.Mask" "F.Paste")
			(net "GND")
		)
		(pad "2" smd circle
			(at 0.40005 0 180)
			(size 0 0)
			(layers "F.Cu" "F.Mask" "F.Paste")
			(net "P3V3_SSD13")
		)
	)
	(footprint ""
		(layer "F.Cu")
		(at 369.495578 -89.499694 180)
		(property "Reference" "R1612"
			(at 0 0 180)
			(layer "F.SilkS")
			(hide yes)
			(effects
				(font
					(size 1.27 1.27)
				)
			)
		)
		(property "Value" ""
			(at 0 0 180)
			(layer "F.Fab")
			(effects
				(font
					(size 1.27 1.27)
				)
			)
		)
		(duplicate_pad_numbers_are_jumpers no)
		(fp_line
			(start 0.7874 0.4064)
			(end -0.7874 0.4064)
			(stroke
				(width 0.1524)
				(type default)
			)
			(layer "F.SilkS")
		)
		(fp_line
			(start 0.7874 -0.4064)
			(end 0.7874 0.4064)
			(stroke
				(width 0.1524)
				(type default)
			)
			(layer "F.SilkS")
		)
		(fp_line
			(start -0.7874 0.4064)
			(end -0.7874 -0.4064)
			(stroke
				(width 0.1524)
				(type default)
			)
			(layer "F.SilkS")
		)
		(fp_line
			(start -0.7874 -0.4064)
			(end 0.7874 -0.4064)
			(stroke
				(width 0.1524)
				(type default)
			)
			(layer "F.SilkS")
		)
		(fp_line
			(start 0.67945 0.3048)
			(end 0.120396 0.3048)
			(stroke
				(width 0.1)
				(type default)
			)
			(layer "F.Fab")
		)
		(fp_line
			(start 0.67945 -0.3048)
			(end 0.67945 0.3048)
			(stroke
				(width 0.1)
				(type default)
			)
			(layer "F.Fab")
		)
		(fp_line
			(start 0.12065 -0.2794)
			(end 0.12065 -0.3048)
			(stroke
				(width 0.1)
				(type default)
			)
			(layer "F.Fab")
		)
		(fp_line
			(start 0.12065 -0.3048)
			(end 0.67945 -0.3048)
			(stroke
				(width 0.1)
				(type default)
			)
			(layer "F.Fab")
		)
		(fp_line
			(start 0.120396 0.3048)
			(end 0.120396 0.2794)
			(stroke
				(width 0.1)
				(type default)
			)
			(layer "F.Fab")
		)
		(fp_line
			(start 0.120396 0.2794)
			(end -0.12065 0.2794)
			(stroke
				(width 0.1)
				(type default)
			)
			(layer "F.Fab")
		)
		(fp_line
			(start -0.12065 0.3048)
			(end -0.67945 0.3048)
			(stroke
				(width 0.1)
				(type default)
			)
			(layer "F.Fab")
		)
		(fp_line
			(start -0.12065 0.2794)
			(end -0.12065 0.3048)
			(stroke
				(width 0.1)
				(type default)
			)
			(layer "F.Fab")
		)
		(fp_line
			(start -0.12065 -0.2794)
			(end 0.12065 -0.2794)
			(stroke
				(width 0.1)
				(type default)
			)
			(layer "F.Fab")
		)
		(fp_line
			(start -0.12065 -0.305054)
			(end -0.12065 -0.2794)
			(stroke
				(width 0.1)
				(type default)
			)
			(layer "F.Fab")
		)
		(fp_line
			(start -0.67945 0.3048)
			(end -0.67945 -0.305054)
			(stroke
				(width 0.1)
				(type default)
			)
			(layer "F.Fab")
		)
		(fp_line
			(start -0.67945 -0.305054)
			(end -0.12065 -0.305054)
			(stroke
				(width 0.1)
				(type default)
			)
			(layer "F.Fab")
		)
		(pad "1" smd circle
			(at -0.40005 0 180)
			(size 0 0)
			(layers "F.Cu" "F.Mask" "F.Paste")
			(net "P3V3_AUX")
		)
		(pad "2" smd circle
			(at 0.40005 0 180)
			(size 0 0)
			(layers "F.Cu" "F.Mask" "F.Paste")
			(net "SMB_BIC_I2C9_MUX1_SSD15_R_SCL")
		)
	)
	(footprint ""
		(layer "F.Cu")
		(at 6.804406 -348.911926)
		(property "Reference" "H42"
			(at -2.808478 -3.424936 0)
			(unlocked yes)
			(layer "F.SilkS")
			(effects
				(font
					(size 0.7874 0.5842)
					(thickness 0.1524)
				)
				(justify left)
			)
		)
		(property "Value" ""
			(at 0 0 0)
			(layer "F.Fab")
			(effects
				(font
					(size 1.27 1.27)
				)
			)
		)
		(duplicate_pad_numbers_are_jumpers no)
		(fp_circle
			(center 0 0)
			(end 2.4003 0)
			(stroke
				(width 0.1524)
				(type default)
			)
			(fill no)
			(layer "F.SilkS")
		)
		(fp_circle
			(center 0 0)
			(end 6.5913 0)
			(stroke
				(width 0.1524)
				(type default)
			)
			(fill no)
			(layer "B.SilkS")
		)
		(fp_circle
			(center 0 0)
			(end 6.5913 0)
			(stroke
				(width 0.1)
				(type default)
			)
			(fill no)
			(layer "B.Fab")
		)
		(fp_circle
			(center 0 0)
			(end 2.4003 0)
			(stroke
				(width 0.1)
				(type default)
			)
			(fill no)
			(layer "F.Fab")
		)
		(pad "" np_thru_hole circle
			(at 0 0)
			(size 3.175 3.175)
			(drill 3.175)
			(layers "*.Cu" "*.Mask")
			(clearance 0.381)
			(thermal_gap 0.381)
		)
		(zone
			(layers "F.Cu" "B.Cu" "In1.Cu" "In2.Cu" "In3.Cu" "In4.Cu" "In5.Cu" "In6.Cu"
				"In7.Cu" "In8.Cu" "In9.Cu" "In10.Cu" "In11.Cu" "In12.Cu" "In13.Cu" "In14.Cu"
				"In15.Cu" "In16.Cu"
			)
			(hatch none 0.5)
			(connect_pads
				(clearance 0)
			)
			(min_thickness 0.25)
			(keepout
				(tracks not_allowed)
				(vias allowed)
				(pads allowed)
				(copperpour not_allowed)
				(footprints allowed)
			)
			(placement
				(enabled no)
				(sheetname "")
			)
			(fill
				(thermal_gap 0.5)
				(thermal_bridge_width 0.5)
				(island_removal_mode 0)
			)
			(polygon
				(pts
					(arc
						(start 8.899906 -348.911926)
						(mid 4.708906 -348.911926)
						(end 8.899906 -348.911926)
					)
				)
			)
		)
	)
	(footprint ""
		(layer "F.Cu")
		(at 303.457864 -72.766682 90)
		(property "Reference" "PC870"
			(at 0 0 90)
			(layer "F.SilkS")
			(hide yes)
			(effects
				(font
					(size 1.27 1.27)
				)
			)
		)
		(property "Value" ""
			(at 0 0 90)
			(layer "F.Fab")
			(effects
				(font
					(size 1.27 1.27)
				)
			)
		)
		(duplicate_pad_numbers_are_jumpers no)
		(fp_line
			(start 0.7874 -0.4064)
			(end 0.7874 0.4064)
			(stroke
				(width 0.1524)
				(type default)
			)
			(layer "F.SilkS")
		)
		(fp_line
			(start -0.7874 -0.4064)
			(end 0.7874 -0.4064)
			(stroke
				(width 0.1524)
				(type default)
			)
			(layer "F.SilkS")
		)
		(fp_line
			(start 0.7874 0.4064)
			(end -0.7874 0.4064)
			(stroke
				(width 0.1524)
				(type default)
			)
			(layer "F.SilkS")
		)
		(fp_line
			(start -0.7874 0.4064)
			(end -0.7874 -0.4064)
			(stroke
				(width 0.1524)
				(type default)
			)
			(layer "F.SilkS")
		)
		(fp_line
			(start -0.12065 -0.305054)
			(end -0.12065 -0.2794)
			(stroke
				(width 0.1)
				(type default)
			)
			(layer "F.Fab")
		)
		(fp_line
			(start -0.67945 -0.305054)
			(end -0.12065 -0.305054)
			(stroke
				(width 0.1)
				(type default)
			)
			(layer "F.Fab")
		)
		(fp_line
			(start 0.67945 -0.3048)
			(end 0.67945 0.3048)
			(stroke
				(width 0.1)
				(type default)
			)
			(layer "F.Fab")
		)
		(fp_line
			(start 0.12065 -0.3048)
			(end 0.67945 -0.3048)
			(stroke
				(width 0.1)
				(type default)
			)
			(layer "F.Fab")
		)
		(fp_line
			(start 0.12065 -0.2794)
			(end 0.12065 -0.3048)
			(stroke
				(width 0.1)
				(type default)
			)
			(layer "F.Fab")
		)
		(fp_line
			(start -0.12065 -0.2794)
			(end 0.12065 -0.2794)
			(stroke
				(width 0.1)
				(type default)
			)
			(layer "F.Fab")
		)
		(fp_line
			(start 0.120396 0.2794)
			(end -0.12065 0.2794)
			(stroke
				(width 0.1)
				(type default)
			)
			(layer "F.Fab")
		)
		(fp_line
			(start -0.12065 0.2794)
			(end -0.12065 0.3048)
			(stroke
				(width 0.1)
				(type default)
			)
			(layer "F.Fab")
		)
		(fp_line
			(start 0.67945 0.3048)
			(end 0.120396 0.3048)
			(stroke
				(width 0.1)
				(type default)
			)
			(layer "F.Fab")
		)
		(fp_line
			(start 0.120396 0.3048)
			(end 0.120396 0.2794)
			(stroke
				(width 0.1)
				(type default)
			)
			(layer "F.Fab")
		)
		(fp_line
			(start -0.12065 0.3048)
			(end -0.67945 0.3048)
			(stroke
				(width 0.1)
				(type default)
			)
			(layer "F.Fab")
		)
		(fp_line
			(start -0.67945 0.3048)
			(end -0.67945 -0.305054)
			(stroke
				(width 0.1)
				(type default)
			)
			(layer "F.Fab")
		)
		(pad "1" smd circle
			(at -0.40005 0 90)
			(size 0 0)
			(layers "F.Cu" "F.Mask" "F.Paste")
			(net "P12V_SSD10_CO_MODE")
		)
		(pad "2" smd circle
			(at 0.40005 0 90)
			(size 0 0)
			(layers "F.Cu" "F.Mask" "F.Paste")
			(net "GND")
		)
	)
	(footprint ""
		(layer "F.Cu")
		(at 62.632082 -169.040302 -90)
		(property "Reference" "U12"
			(at 0.50038 2.571242 90)
			(unlocked yes)
			(layer "F.SilkS")
			(effects
				(font
					(size 0.7874 0.5842)
					(thickness 0.1524)
				)
			)
		)
		(property "Value" ""
			(at 0 0 270)
			(layer "F.Fab")
			(effects
				(font
					(size 1.27 1.27)
				)
			)
		)
		(duplicate_pad_numbers_are_jumpers no)
		(fp_line
			(start -1.905 1.651)
			(end -1.905 -1.651)
			(stroke
				(width 0.1524)
				(type default)
			)
			(layer "F.SilkS")
		)
		(fp_line
			(start 1.905 1.651)
			(end -1.905 1.651)
			(stroke
				(width 0.1524)
				(type default)
			)
			(layer "F.SilkS")
		)
		(fp_line
			(start -1.905 -1.651)
			(end 1.905 -1.651)
			(stroke
				(width 0.1524)
				(type default)
			)
			(layer "F.SilkS")
		)
		(fp_line
			(start 1.905 -1.651)
			(end 1.905 1.651)
			(stroke
				(width 0.1524)
				(type default)
			)
			(layer "F.SilkS")
		)
		(fp_line
			(start -0.649986 1.524)
			(end -0.649986 1.169924)
			(stroke
				(width 0.1)
				(type default)
			)
			(layer "F.Fab")
		)
		(fp_line
			(start 0.6985 1.524)
			(end -0.649986 1.524)
			(stroke
				(width 0.1)
				(type default)
			)
			(layer "F.Fab")
		)
		(fp_line
			(start -1.249934 1.169924)
			(end -1.249934 0.729996)
			(stroke
				(width 0.1)
				(type default)
			)
			(layer "F.Fab")
		)
		(fp_line
			(start -0.649986 1.169924)
			(end -1.249934 1.169924)
			(stroke
				(width 0.1)
				(type default)
			)
			(layer "F.Fab")
		)
		(fp_line
			(start -1.249934 0.729996)
			(end -0.6985 0.729996)
			(stroke
				(width 0.1)
				(type default)
			)
			(layer "F.Fab")
		)
		(fp_line
			(start -0.6985 0.729996)
			(end -0.6985 -0.729996)
			(stroke
				(width 0.1)
				(type default)
			)
			(layer "F.Fab")
		)
		(fp_line
			(start 0.6985 0.219964)
			(end 0.6985 1.524)
			(stroke
				(width 0.1)
				(type default)
			)
			(layer "F.Fab")
		)
		(fp_line
			(start 1.249934 0.219964)
			(end 0.6985 0.219964)
			(stroke
				(width 0.1)
				(type default)
			)
			(layer "F.Fab")
		)
		(fp_line
			(start 0.6985 -0.219964)
			(end 1.249934 -0.219964)
			(stroke
				(width 0.1)
				(type default)
			)
			(layer "F.Fab")
		)
		(fp_line
			(start 1.249934 -0.219964)
			(end 1.249934 0.219964)
			(stroke
				(width 0.1)
				(type default)
			)
			(layer "F.Fab")
		)
		(fp_line
			(start -1.249934 -0.729996)
			(end -1.249934 -1.169924)
			(stroke
				(width 0.1)
				(type default)
			)
			(layer "F.Fab")
		)
		(fp_line
			(start -0.6985 -0.729996)
			(end -1.249934 -0.729996)
			(stroke
				(width 0.1)
				(type default)
			)
			(layer "F.Fab")
		)
		(fp_line
			(start -1.249934 -1.169924)
			(end -0.649986 -1.169924)
			(stroke
				(width 0.1)
				(type default)
			)
			(layer "F.Fab")
		)
		(fp_line
			(start -0.649986 -1.169924)
			(end -0.649986 -1.524)
			(stroke
				(width 0.1)
				(type default)
			)
			(layer "F.Fab")
		)
		(fp_line
			(start -0.649986 -1.524)
			(end 0.6985 -1.524)
			(stroke
				(width 0.1)
				(type default)
			)
			(layer "F.Fab")
		)
		(fp_line
			(start 0.6985 -1.524)
			(end 0.6985 -0.219964)
			(stroke
				(width 0.1)
				(type default)
			)
			(layer "F.Fab")
		)
		(pad "1" smd rect
			(at -1.1176 -1.016 180)
			(size 1.016 1.27)
			(layers "F.Cu" "F.Mask" "F.Paste")
			(net "HP_NIC0_PWRGD")
		)
		(pad "2" smd rect
			(at -1.1176 1.016 180)
			(size 1.016 1.27)
			(layers "F.Cu" "F.Mask" "F.Paste")
			(net "P3V3_NIC0")
		)
		(pad "3" smd rect
			(at 1.1176 0 180)
			(size 1.016 1.27)
			(layers "F.Cu" "F.Mask" "F.Paste")
			(net "GND")
		)
	)
	(footprint ""
		(layer "F.Cu")
		(at 382.07188 -24.807418)
		(property "Reference" "R450"
			(at 0 0 0)
			(layer "F.SilkS")
			(hide yes)
			(effects
				(font
					(size 1.27 1.27)
				)
			)
		)
		(property "Value" ""
			(at 0 0 0)
			(layer "F.Fab")
			(effects
				(font
					(size 1.27 1.27)
				)
			)
		)
		(duplicate_pad_numbers_are_jumpers no)
		(fp_line
			(start -0.7874 -0.4064)
			(end 0.7874 -0.4064)
			(stroke
				(width 0.1524)
				(type default)
			)
			(layer "F.SilkS")
		)
		(fp_line
			(start -0.7874 0.4064)
			(end -0.7874 -0.4064)
			(stroke
				(width 0.1524)
				(type default)
			)
			(layer "F.SilkS")
		)
		(fp_line
			(start 0.7874 -0.4064)
			(end 0.7874 0.4064)
			(stroke
				(width 0.1524)
				(type default)
			)
			(layer "F.SilkS")
		)
		(fp_line
			(start 0.7874 0.4064)
			(end -0.7874 0.4064)
			(stroke
				(width 0.1524)
				(type default)
			)
			(layer "F.SilkS")
		)
		(fp_line
			(start -0.67945 -0.305054)
			(end -0.12065 -0.305054)
			(stroke
				(width 0.1)
				(type default)
			)
			(layer "F.Fab")
		)
		(fp_line
			(start -0.67945 0.3048)
			(end -0.67945 -0.305054)
			(stroke
				(width 0.1)
				(type default)
			)
			(layer "F.Fab")
		)
		(fp_line
			(start -0.12065 -0.305054)
			(end -0.12065 -0.2794)
			(stroke
				(width 0.1)
				(type default)
			)
			(layer "F.Fab")
		)
		(fp_line
			(start -0.12065 -0.2794)
			(end 0.12065 -0.2794)
			(stroke
				(width 0.1)
				(type default)
			)
			(layer "F.Fab")
		)
		(fp_line
			(start -0.12065 0.2794)
			(end -0.12065 0.3048)
			(stroke
				(width 0.1)
				(type default)
			)
			(layer "F.Fab")
		)
		(fp_line
			(start -0.12065 0.3048)
			(end -0.67945 0.3048)
			(stroke
				(width 0.1)
				(type default)
			)
			(layer "F.Fab")
		)
		(fp_line
			(start 0.120396 0.2794)
			(end -0.12065 0.2794)
			(stroke
				(width 0.1)
				(type default)
			)
			(layer "F.Fab")
		)
		(fp_line
			(start 0.120396 0.3048)
			(end 0.120396 0.2794)
			(stroke
				(width 0.1)
				(type default)
			)
			(layer "F.Fab")
		)
		(fp_line
			(start 0.12065 -0.3048)
			(end 0.67945 -0.3048)
			(stroke
				(width 0.1)
				(type default)
			)
			(layer "F.Fab")
		)
		(fp_line
			(start 0.12065 -0.2794)
			(end 0.12065 -0.3048)
			(stroke
				(width 0.1)
				(type default)
			)
			(layer "F.Fab")
		)
		(fp_line
			(start 0.67945 -0.3048)
			(end 0.67945 0.3048)
			(stroke
				(width 0.1)
				(type default)
			)
			(layer "F.Fab")
		)
		(fp_line
			(start 0.67945 0.3048)
			(end 0.120396 0.3048)
			(stroke
				(width 0.1)
				(type default)
			)
			(layer "F.Fab")
		)
		(pad "1" smd circle
			(at -0.40005 0)
			(size 0 0)
			(layers "F.Cu" "F.Mask" "F.Paste")
			(net "P3V3_SSD13")
		)
		(pad "2" smd circle
			(at 0.40005 0)
			(size 0 0)
			(layers "F.Cu" "F.Mask" "F.Paste")
			(net "PU_CLKREQ13")
		)
	)
	(footprint ""
		(layer "F.Cu")
		(at 148.511514 -280.443432 -90)
		(property "Reference" "R4576"
			(at 0 0 270)
			(layer "F.SilkS")
			(hide yes)
			(effects
				(font
					(size 1.27 1.27)
				)
			)
		)
		(property "Value" ""
			(at 0 0 270)
			(layer "F.Fab")
			(effects
				(font
					(size 1.27 1.27)
				)
			)
		)
		(duplicate_pad_numbers_are_jumpers no)
		(fp_line
			(start -0.7874 0.4064)
			(end -0.7874 -0.4064)
			(stroke
				(width 0.1524)
				(type default)
			)
			(layer "F.SilkS")
		)
		(fp_line
			(start 0.7874 0.4064)
			(end -0.7874 0.4064)
			(stroke
				(width 0.1524)
				(type default)
			)
			(layer "F.SilkS")
		)
		(fp_line
			(start -0.7874 -0.4064)
			(end 0.7874 -0.4064)
			(stroke
				(width 0.1524)
				(type default)
			)
			(layer "F.SilkS")
		)
		(fp_line
			(start 0.7874 -0.4064)
			(end 0.7874 0.4064)
			(stroke
				(width 0.1524)
				(type default)
			)
			(layer "F.SilkS")
		)
		(fp_line
			(start -0.67945 0.3048)
			(end -0.67945 -0.305054)
			(stroke
				(width 0.1)
				(type default)
			)
			(layer "F.Fab")
		)
		(fp_line
			(start -0.12065 0.3048)
			(end -0.67945 0.3048)
			(stroke
				(width 0.1)
				(type default)
			)
			(layer "F.Fab")
		)
		(fp_line
			(start 0.120396 0.3048)
			(end 0.120396 0.2794)
			(stroke
				(width 0.1)
				(type default)
			)
			(layer "F.Fab")
		)
		(fp_line
			(start 0.67945 0.3048)
			(end 0.120396 0.3048)
			(stroke
				(width 0.1)
				(type default)
			)
			(layer "F.Fab")
		)
		(fp_line
			(start -0.12065 0.2794)
			(end -0.12065 0.3048)
			(stroke
				(width 0.1)
				(type default)
			)
			(layer "F.Fab")
		)
		(fp_line
			(start 0.120396 0.2794)
			(end -0.12065 0.2794)
			(stroke
				(width 0.1)
				(type default)
			)
			(layer "F.Fab")
		)
		(fp_line
			(start -0.12065 -0.2794)
			(end 0.12065 -0.2794)
			(stroke
				(width 0.1)
				(type default)
			)
			(layer "F.Fab")
		)
		(fp_line
			(start 0.12065 -0.2794)
			(end 0.12065 -0.3048)
			(stroke
				(width 0.1)
				(type default)
			)
			(layer "F.Fab")
		)
		(fp_line
			(start 0.12065 -0.3048)
			(end 0.67945 -0.3048)
			(stroke
				(width 0.1)
				(type default)
			)
			(layer "F.Fab")
		)
		(fp_line
			(start 0.67945 -0.3048)
			(end 0.67945 0.3048)
			(stroke
				(width 0.1)
				(type default)
			)
			(layer "F.Fab")
		)
		(fp_line
			(start -0.67945 -0.305054)
			(end -0.12065 -0.305054)
			(stroke
				(width 0.1)
				(type default)
			)
			(layer "F.Fab")
		)
		(fp_line
			(start -0.12065 -0.305054)
			(end -0.12065 -0.2794)
			(stroke
				(width 0.1)
				(type default)
			)
			(layer "F.Fab")
		)
		(pad "1" smd circle
			(at -0.40005 0 270)
			(size 0 0)
			(layers "F.Cu" "F.Mask" "F.Paste")
			(net "SYSPLL_VDDA18_PEX1")
		)
		(pad "2" smd circle
			(at 0.40005 0 270)
			(size 0 0)
			(layers "F.Cu" "F.Mask" "F.Paste")
			(net "SYSPLL_VDDA18_PEX1_R")
		)
	)
	(footprint ""
		(layer "F.Cu")
		(at 406.875742 -36.915598 -90)
		(property "Reference" "R5580"
			(at 0 0 270)
			(layer "F.SilkS")
			(hide yes)
			(effects
				(font
					(size 1.27 1.27)
				)
			)
		)
		(property "Value" ""
			(at 0 0 270)
			(layer "F.Fab")
			(effects
				(font
					(size 1.27 1.27)
				)
			)
		)
		(duplicate_pad_numbers_are_jumpers no)
		(fp_line
			(start -0.7874 0.4064)
			(end -0.7874 -0.4064)
			(stroke
				(width 0.1524)
				(type default)
			)
			(layer "F.SilkS")
		)
		(fp_line
			(start 0.7874 0.4064)
			(end -0.7874 0.4064)
			(stroke
				(width 0.1524)
				(type default)
			)
			(layer "F.SilkS")
		)
		(fp_line
			(start -0.7874 -0.4064)
			(end 0.7874 -0.4064)
			(stroke
				(width 0.1524)
				(type default)
			)
			(layer "F.SilkS")
		)
		(fp_line
			(start 0.7874 -0.4064)
			(end 0.7874 0.4064)
			(stroke
				(width 0.1524)
				(type default)
			)
			(layer "F.SilkS")
		)
		(fp_line
			(start -0.67945 0.3048)
			(end -0.67945 -0.305054)
			(stroke
				(width 0.1)
				(type default)
			)
			(layer "F.Fab")
		)
		(fp_line
			(start -0.12065 0.3048)
			(end -0.67945 0.3048)
			(stroke
				(width 0.1)
				(type default)
			)
			(layer "F.Fab")
		)
		(fp_line
			(start 0.120396 0.3048)
			(end 0.120396 0.2794)
			(stroke
				(width 0.1)
				(type default)
			)
			(layer "F.Fab")
		)
		(fp_line
			(start 0.67945 0.3048)
			(end 0.120396 0.3048)
			(stroke
				(width 0.1)
				(type default)
			)
			(layer "F.Fab")
		)
		(fp_line
			(start -0.12065 0.2794)
			(end -0.12065 0.3048)
			(stroke
				(width 0.1)
				(type default)
			)
			(layer "F.Fab")
		)
		(fp_line
			(start 0.120396 0.2794)
			(end -0.12065 0.2794)
			(stroke
				(width 0.1)
				(type default)
			)
			(layer "F.Fab")
		)
		(fp_line
			(start -0.12065 -0.2794)
			(end 0.12065 -0.2794)
			(stroke
				(width 0.1)
				(type default)
			)
			(layer "F.Fab")
		)
		(fp_line
			(start 0.12065 -0.2794)
			(end 0.12065 -0.3048)
			(stroke
				(width 0.1)
				(type default)
			)
			(layer "F.Fab")
		)
		(fp_line
			(start 0.12065 -0.3048)
			(end 0.67945 -0.3048)
			(stroke
				(width 0.1)
				(type default)
			)
			(layer "F.Fab")
		)
		(fp_line
			(start 0.67945 -0.3048)
			(end 0.67945 0.3048)
			(stroke
				(width 0.1)
				(type default)
			)
			(layer "F.Fab")
		)
		(fp_line
			(start -0.67945 -0.305054)
			(end -0.12065 -0.305054)
			(stroke
				(width 0.1)
				(type default)
			)
			(layer "F.Fab")
		)
		(fp_line
			(start -0.12065 -0.305054)
			(end -0.12065 -0.2794)
			(stroke
				(width 0.1)
				(type default)
			)
			(layer "F.Fab")
		)
		(pad "1" smd circle
			(at -0.40005 0 270)
			(size 0 0)
			(layers "F.Cu" "F.Mask" "F.Paste")
			(net "PRSNT_SSD14_R1_N")
		)
		(pad "2" smd circle
			(at 0.40005 0 270)
			(size 0 0)
			(layers "F.Cu" "F.Mask" "F.Paste")
			(net "PRSNT_SSD14_R_N")
		)
	)
	(footprint ""
		(layer "F.Cu")
		(at 439.264806 -26.785062 180)
		(property "Reference" "J45"
			(at 4.028186 -11.14044 90)
			(unlocked yes)
			(layer "F.SilkS")
			(effects
				(font
					(size 0.7874 0.5842)
					(thickness 0.1524)
				)
			)
		)
		(property "Value" ""
			(at 0 0 180)
			(layer "F.Fab")
			(effects
				(font
					(size 1.27 1.27)
				)
			)
		)
		(duplicate_pad_numbers_are_jumpers no)
		(fp_line
			(start 3.150108 12.115038)
			(end 1.529334 12.115038)
			(stroke
				(width 0.1524)
				(type default)
			)
			(layer "F.SilkS")
		)
		(fp_line
			(start 3.074924 12.014962)
			(end 1.632204 12.014962)
			(stroke
				(width 0.1524)
				(type default)
			)
			(layer "F.SilkS")
		)
		(fp_line
			(start 1.632204 -12.014962)
			(end 3.074924 -12.014962)
			(stroke
				(width 0.1524)
				(type default)
			)
			(layer "F.SilkS")
		)
		(fp_line
			(start 1.529334 -12.115038)
			(end 3.150108 -12.115038)
			(stroke
				(width 0.1524)
				(type default)
			)
			(layer "F.SilkS")
		)
		(fp_line
			(start -1.529334 12.115038)
			(end -3.150108 12.115038)
			(stroke
				(width 0.1524)
				(type default)
			)
			(layer "F.SilkS")
		)
		(fp_line
			(start -1.632204 12.014962)
			(end -3.074924 12.014962)
			(stroke
				(width 0.1524)
				(type default)
			)
			(layer "F.SilkS")
		)
		(fp_line
			(start -3.074924 -12.014962)
			(end -1.632204 -12.014962)
			(stroke
				(width 0.1524)
				(type default)
			)
			(layer "F.SilkS")
		)
		(fp_line
			(start -3.150108 -12.115038)
			(end -1.529334 -12.115038)
			(stroke
				(width 0.1524)
				(type default)
			)
			(layer "F.SilkS")
		)
		(fp_poly
			(pts
				(xy 3.344418 -8.619236) (xy 3.76682 -9.88695) (xy 4.611878 -9.041892)
			)
			(stroke
				(width 0)
				(type default)
			)
			(fill yes)
			(layer "F.SilkS")
		)
		(fp_line
			(start 3.074924 12.014962)
			(end -3.074924 12.014962)
			(stroke
				(width 0.1)
				(type default)
			)
			(layer "F.Fab")
		)
		(fp_line
			(start 3.074924 -12.014962)
			(end 3.074924 12.014962)
			(stroke
				(width 0.1)
				(type default)
			)
			(layer "F.Fab")
		)
		(fp_line
			(start -3.074924 12.014962)
			(end -3.074924 -12.014962)
			(stroke
				(width 0.1)
				(type default)
			)
			(layer "F.Fab")
		)
		(fp_line
			(start -3.074924 -12.014962)
			(end 3.074924 -12.014962)
			(stroke
				(width 0.1)
				(type default)
			)
			(layer "F.Fab")
		)
		(fp_poly
			(pts
				(xy 3.348736 -7.994904) (xy 4.543806 -8.592566) (xy 4.543806 -7.397496)
			)
			(stroke
				(width 0)
				(type default)
			)
			(fill yes)
			(layer "F.Fab")
		)
		(pad "" np_thru_hole circle
			(at -1.75006 -9.815068 90)
			(size 1.1176 1.1176)
			(drill 1.1176)
			(layers "*.Cu" "*.Mask")
			(clearance 0.381)
			(thermal_gap 0.381)
		)
		(pad "" np_thru_hole circle
			(at 0 9.815068 90)
			(size 1.1176 1.1176)
			(drill 1.1176)
			(layers "*.Cu" "*.Mask")
			(clearance 0.381)
			(thermal_gap 0.381)
		)
		(pad "A1" smd rect
			(at 2.29997 -7.994904 90)
			(size 0.381 1.27)
			(layers "F.Cu" "F.Mask" "F.Paste")
			(net "GND")
		)
		(pad "A2" smd rect
			(at 2.29997 -7.394956 90)
			(size 0.381 1.27)
			(layers "F.Cu" "F.Mask" "F.Paste")
			(net "GND")
		)
		(pad "A3" smd rect
			(at 2.29997 -6.795008 90)
			(size 0.381 1.27)
			(layers "F.Cu" "F.Mask" "F.Paste")
			(net "GND")
		)
		(pad "A4" smd rect
			(at 2.29997 -6.19506 90)
			(size 0.381 1.27)
			(layers "F.Cu" "F.Mask" "F.Paste")
			(net "GND")
		)
		(pad "A5" smd rect
			(at 2.29997 -5.595112 90)
			(size 0.381 1.27)
			(layers "F.Cu" "F.Mask" "F.Paste")
			(net "GND")
		)
		(pad "A6" smd rect
			(at 2.29997 -4.99491 90)
			(size 0.381 1.27)
			(layers "F.Cu" "F.Mask" "F.Paste")
			(net "GND")
		)
		(pad "A7" smd rect
			(at 2.29997 -4.394962 90)
			(size 0.381 1.27)
			(layers "F.Cu" "F.Mask" "F.Paste")
			(net "SMB_ISO_SSD15_R_SCL")
		)
		(pad "A8" smd rect
			(at 2.29997 -3.795014 90)
			(size 0.381 1.27)
			(layers "F.Cu" "F.Mask" "F.Paste")
			(net "SMB_ISO_SSD15_R_SDA")
		)
		(pad "A9" smd rect
			(at 2.29997 -3.195066 90)
			(size 0.381 1.27)
			(layers "F.Cu" "F.Mask" "F.Paste")
			(net "RST_SMB_SSD15_ISO_R_N")
		)
		(pad "A10" smd rect
			(at 2.29997 -2.595118 90)
			(size 0.381 1.27)
			(layers "F.Cu" "F.Mask" "F.Paste")
			(net "SSD15_LED_ISO_R_N")
		)
		(pad "A11" smd rect
			(at 2.29997 -1.994916 90)
			(size 0.381 1.27)
			(layers "F.Cu" "F.Mask" "F.Paste")
			(net "PU_CLKREQ15")
		)
		(pad "A12" smd rect
			(at 2.29997 -1.394968 90)
			(size 0.381 1.27)
			(layers "F.Cu" "F.Mask" "F.Paste")
			(net "PRSNT_SSD15_N")
		)
		(pad "A13" smd rect
			(at 2.29997 -0.79502 90)
			(size 0.381 1.27)
			(layers "F.Cu" "F.Mask" "F.Paste")
			(net "GND")
		)
		(pad "A14" smd rect
			(at 2.29997 -0.195072 90)
			(size 0.381 1.27)
			(layers "F.Cu" "F.Mask" "F.Paste")
			(net "Net_8459")
		)
		(pad "A15" smd rect
			(at 2.29997 0.404876 90)
			(size 0.381 1.27)
			(layers "F.Cu" "F.Mask" "F.Paste")
			(net "Net_8458")
		)
		(pad "A16" smd rect
			(at 2.29997 1.005078 90)
			(size 0.381 1.27)
			(layers "F.Cu" "F.Mask" "F.Paste")
			(net "GND")
		)
		(pad "A17" smd rect
			(at 2.29997 1.605026 90)
			(size 0.381 1.27)
			(layers "F.Cu" "F.Mask" "F.Paste")
			(net "P5E_PEX3_STN2_RX_DN<32>")
		)
		(pad "A18" smd rect
			(at 2.29997 2.204974 90)
			(size 0.381 1.27)
			(layers "F.Cu" "F.Mask" "F.Paste")
			(net "P5E_PEX3_STN2_RX_DP<32>")
		)
		(pad "A19" smd rect
			(at 2.29997 2.804922 90)
			(size 0.381 1.27)
			(layers "F.Cu" "F.Mask" "F.Paste")
			(net "GND")
		)
		(pad "A20" smd rect
			(at 2.29997 3.405124 90)
			(size 0.381 1.27)
			(layers "F.Cu" "F.Mask" "F.Paste")
			(net "P5E_PEX3_STN2_RX_DN<33>")
		)
		(pad "A21" smd rect
			(at 2.29997 4.005072 90)
			(size 0.381 1.27)
			(layers "F.Cu" "F.Mask" "F.Paste")
			(net "P5E_PEX3_STN2_RX_DP<33>")
		)
		(pad "A22" smd rect
			(at 2.29997 4.60502 90)
			(size 0.381 1.27)
			(layers "F.Cu" "F.Mask" "F.Paste")
			(net "GND")
		)
		(pad "A23" smd rect
			(at 2.29997 5.204968 90)
			(size 0.381 1.27)
			(layers "F.Cu" "F.Mask" "F.Paste")
			(net "P5E_PEX3_STN2_RX_DN<34>")
		)
		(pad "A24" smd rect
			(at 2.29997 5.804916 90)
			(size 0.381 1.27)
			(layers "F.Cu" "F.Mask" "F.Paste")
			(net "P5E_PEX3_STN2_RX_DP<34>")
		)
		(pad "A25" smd rect
			(at 2.29997 6.405118 90)
			(size 0.381 1.27)
			(layers "F.Cu" "F.Mask" "F.Paste")
			(net "GND")
		)
		(pad "A26" smd rect
			(at 2.29997 7.005066 90)
			(size 0.381 1.27)
			(layers "F.Cu" "F.Mask" "F.Paste")
			(net "P5E_PEX3_STN2_RX_DN<35>")
		)
		(pad "A27" smd rect
			(at 2.29997 7.605014 90)
			(size 0.381 1.27)
			(layers "F.Cu" "F.Mask" "F.Paste")
			(net "P5E_PEX3_STN2_RX_DP<35>")
		)
		(pad "A28" smd rect
			(at 2.29997 8.204962 90)
			(size 0.381 1.27)
			(layers "F.Cu" "F.Mask" "F.Paste")
			(net "GND")
		)
		(pad "B1" smd rect
			(at -2.29997 -7.994904 90)
			(size 0.381 1.27)
			(layers "F.Cu" "F.Mask" "F.Paste")
			(net "P12V_SSD15")
		)
		(pad "B2" smd rect
			(at -2.29997 -7.394956 90)
			(size 0.381 1.27)
			(layers "F.Cu" "F.Mask" "F.Paste")
			(net "P12V_SSD15")
		)
		(pad "B3" smd rect
			(at -2.29997 -6.795008 90)
			(size 0.381 1.27)
			(layers "F.Cu" "F.Mask" "F.Paste")
			(net "P12V_SSD15")
		)
		(pad "B4" smd rect
			(at -2.29997 -6.19506 90)
			(size 0.381 1.27)
			(layers "F.Cu" "F.Mask" "F.Paste")
			(net "P12V_SSD15")
		)
		(pad "B5" smd rect
			(at -2.29997 -5.595112 90)
			(size 0.381 1.27)
			(layers "F.Cu" "F.Mask" "F.Paste")
			(net "P12V_SSD15")
		)
		(pad "B6" smd rect
			(at -2.29997 -4.99491 90)
			(size 0.381 1.27)
			(layers "F.Cu" "F.Mask" "F.Paste")
			(net "P12V_SSD15")
		)
		(pad "B7" smd rect
			(at -2.29997 -4.394962 90)
			(size 0.381 1.27)
			(layers "F.Cu" "F.Mask" "F.Paste")
			(net "Net_8460")
		)
		(pad "B8" smd rect
			(at -2.29997 -3.795014 90)
			(size 0.381 1.27)
			(layers "F.Cu" "F.Mask" "F.Paste")
			(net "Net_8457")
		)
		(pad "B9" smd rect
			(at -2.29997 -3.195066 90)
			(size 0.381 1.27)
			(layers "F.Cu" "F.Mask" "F.Paste")
			(net "DUALPORT_N_SSD15")
		)
		(pad "B10" smd rect
			(at -2.29997 -2.595118 90)
			(size 0.381 1.27)
			(layers "F.Cu" "F.Mask" "F.Paste")
			(net "RST_SSD15_PERST_R_N")
		)
		(pad "B11" smd rect
			(at -2.29997 -1.994916 90)
			(size 0.381 1.27)
			(layers "F.Cu" "F.Mask" "F.Paste")
			(net "P3V3_SSD15")
		)
		(pad "B12" smd rect
			(at -2.29997 -1.394968 90)
			(size 0.381 1.27)
			(layers "F.Cu" "F.Mask" "F.Paste")
			(net "SSD15_PWRDIS_R")
		)
		(pad "B13" smd rect
			(at -2.29997 -0.79502 90)
			(size 0.381 1.27)
			(layers "F.Cu" "F.Mask" "F.Paste")
			(net "GND")
		)
		(pad "B14" smd rect
			(at -2.29997 -0.195072 90)
			(size 0.381 1.27)
			(layers "F.Cu" "F.Mask" "F.Paste")
			(net "CLK_100M_DB800ZL_SSD15_R_DN")
		)
		(pad "B15" smd rect
			(at -2.29997 0.404876 90)
			(size 0.381 1.27)
			(layers "F.Cu" "F.Mask" "F.Paste")
			(net "CLK_100M_DB800ZL_SSD15_R_DP")
		)
		(pad "B16" smd rect
			(at -2.29997 1.005078 90)
			(size 0.381 1.27)
			(layers "F.Cu" "F.Mask" "F.Paste")
			(net "GND")
		)
		(pad "B17" smd rect
			(at -2.29997 1.605026 90)
			(size 0.381 1.27)
			(layers "F.Cu" "F.Mask" "F.Paste")
			(net "P5E_PEX3_STN2_TX_C_DN<32>")
		)
		(pad "B18" smd rect
			(at -2.29997 2.204974 90)
			(size 0.381 1.27)
			(layers "F.Cu" "F.Mask" "F.Paste")
			(net "P5E_PEX3_STN2_TX_C_DP<32>")
		)
		(pad "B19" smd rect
			(at -2.29997 2.804922 90)
			(size 0.381 1.27)
			(layers "F.Cu" "F.Mask" "F.Paste")
			(net "GND")
		)
		(pad "B20" smd rect
			(at -2.29997 3.405124 90)
			(size 0.381 1.27)
			(layers "F.Cu" "F.Mask" "F.Paste")
			(net "P5E_PEX3_STN2_TX_C_DN<33>")
		)
		(pad "B21" smd rect
			(at -2.29997 4.005072 90)
			(size 0.381 1.27)
			(layers "F.Cu" "F.Mask" "F.Paste")
			(net "P5E_PEX3_STN2_TX_C_DP<33>")
		)
		(pad "B22" smd rect
			(at -2.29997 4.60502 90)
			(size 0.381 1.27)
			(layers "F.Cu" "F.Mask" "F.Paste")
			(net "GND")
		)
		(pad "B23" smd rect
			(at -2.29997 5.204968 90)
			(size 0.381 1.27)
			(layers "F.Cu" "F.Mask" "F.Paste")
			(net "P5E_PEX3_STN2_TX_C_DN<34>")
		)
		(pad "B24" smd rect
			(at -2.29997 5.804916 90)
			(size 0.381 1.27)
			(layers "F.Cu" "F.Mask" "F.Paste")
			(net "P5E_PEX3_STN2_TX_C_DP<34>")
		)
		(pad "B25" smd rect
			(at -2.29997 6.405118 90)
			(size 0.381 1.27)
			(layers "F.Cu" "F.Mask" "F.Paste")
			(net "GND")
		)
		(pad "B26" smd rect
			(at -2.29997 7.005066 90)
			(size 0.381 1.27)
			(layers "F.Cu" "F.Mask" "F.Paste")
			(net "P5E_PEX3_STN2_TX_C_DN<35>")
		)
		(pad "B27" smd rect
			(at -2.29997 7.605014 90)
			(size 0.381 1.27)
			(layers "F.Cu" "F.Mask" "F.Paste")
			(net "P5E_PEX3_STN2_TX_C_DP<35>")
		)
		(pad "B28" smd rect
			(at -2.29997 8.204962 90)
			(size 0.381 1.27)
			(layers "F.Cu" "F.Mask" "F.Paste")
			(net "GND")
		)
		(pad "G1" thru_hole oval
			(at 0 -11.364976 90)
			(size 1.6256 3.4798)
			(drill oval 1.1176 2.4638)
			(layers "*.Cu" "*.Mask")
			(remove_unused_layers no)
			(net "GND")
			(clearance 0.127)
			(thermal_gap 0.127)
		)
		(pad "G2" thru_hole oval
			(at 0 11.364976 90)
			(size 1.6256 3.4798)
			(drill oval 1.1176 2.4638)
			(layers "*.Cu" "*.Mask")
			(remove_unused_layers no)
			(net "GND")
			(clearance 0.127)
			(thermal_gap 0.127)
		)
		(zone
			(layer "F.Cu")
			(hatch none 0.5)
			(connect_pads
				(clearance 0)
			)
			(min_thickness 0.25)
			(keepout
				(tracks not_allowed)
				(vias allowed)
				(pads allowed)
				(copperpour not_allowed)
				(footprints allowed)
			)
			(placement
				(enabled no)
				(sheetname "")
			)
			(fill
				(thermal_gap 0.5)
				(thermal_bridge_width 0.5)
				(island_removal_mode 0)
			)
			(polygon
				(pts
					(xy 440.644788 -38.850062) (xy 437.89473 -38.850062) (xy 437.89473 -35.900106) (xy 440.644788 -35.900106)
				)
			)
		)
		(zone
			(layer "F.Cu")
			(hatch none 0.5)
			(connect_pads
				(clearance 0)
			)
			(min_thickness 0.25)
			(keepout
				(tracks not_allowed)
				(vias allowed)
				(pads allowed)
				(copperpour not_allowed)
				(footprints allowed)
			)
			(placement
				(enabled no)
				(sheetname "")
			)
			(fill
				(thermal_gap 0.5)
				(thermal_bridge_width 0.5)
				(island_removal_mode 0)
			)
			(polygon
				(pts
					(xy 441.71489 -17.670018) (xy 437.884824 -17.670018) (xy 437.884824 -14.720062) (xy 441.71489 -14.720062)
				)
			)
		)
		(zone
			(layers "F.Cu" "B.Cu" "In1.Cu" "In2.Cu" "In3.Cu" "In4.Cu" "In5.Cu" "In6.Cu"
				"In7.Cu" "In8.Cu" "In9.Cu" "In10.Cu" "In11.Cu" "In12.Cu" "In13.Cu" "In14.Cu"
				"In15.Cu" "In16.Cu"
			)
			(hatch none 0.5)
			(connect_pads
				(clearance 0)
			)
			(min_thickness 0.25)
			(keepout
				(tracks not_allowed)
				(vias allowed)
				(pads allowed)
				(copperpour not_allowed)
				(footprints allowed)
			)
			(placement
				(enabled no)
				(sheetname "")
			)
			(fill
				(thermal_gap 0.5)
				(thermal_bridge_width 0.5)
				(island_removal_mode 0)
			)
			(polygon
				(pts
					(arc
						(start 440.230006 -36.60013)
						(mid 438.299606 -36.60013)
						(end 440.230006 -36.60013)
					)
				)
			)
		)
		(zone
			(layers "F.Cu" "B.Cu" "In1.Cu" "In2.Cu" "In3.Cu" "In4.Cu" "In5.Cu" "In6.Cu"
				"In7.Cu" "In8.Cu" "In9.Cu" "In10.Cu" "In11.Cu" "In12.Cu" "In13.Cu" "In14.Cu"
				"In15.Cu" "In16.Cu"
			)
			(hatch none 0.5)
			(connect_pads
				(clearance 0)
			)
			(min_thickness 0.25)
			(keepout
				(tracks not_allowed)
				(vias allowed)
				(pads allowed)
				(copperpour not_allowed)
				(footprints allowed)
			)
			(placement
				(enabled no)
				(sheetname "")
			)
			(fill
				(thermal_gap 0.5)
				(thermal_bridge_width 0.5)
				(island_removal_mode 0)
			)
			(polygon
				(pts
					(arc
						(start 441.980066 -16.969994)
						(mid 440.049666 -16.969994)
						(end 441.980066 -16.969994)
					)
				)
			)
		)
	)
	(footprint ""
		(layer "F.Cu")
		(at 362.459016 -319.420494 90)
		(property "Reference" "R5798"
			(at 0 0 90)
			(layer "F.SilkS")
			(hide yes)
			(effects
				(font
					(size 1.27 1.27)
				)
			)
		)
		(property "Value" ""
			(at 0 0 90)
			(layer "F.Fab")
			(effects
				(font
					(size 1.27 1.27)
				)
			)
		)
		(duplicate_pad_numbers_are_jumpers no)
		(fp_line
			(start 2.576322 -1.1303)
			(end 2.576322 1.1303)
			(stroke
				(width 0.1524)
				(type default)
			)
			(layer "F.SilkS")
		)
		(fp_line
			(start -2.576322 -1.1303)
			(end 2.576322 -1.1303)
			(stroke
				(width 0.1524)
				(type default)
			)
			(layer "F.SilkS")
		)
		(fp_line
			(start 2.576322 1.1303)
			(end -2.576322 1.1303)
			(stroke
				(width 0.1524)
				(type default)
			)
			(layer "F.SilkS")
		)
		(fp_line
			(start -2.576322 1.1303)
			(end -2.576322 -1.1303)
			(stroke
				(width 0.1524)
				(type default)
			)
			(layer "F.SilkS")
		)
		(fp_line
			(start 1.649984 -0.899922)
			(end -1.649984 -0.899922)
			(stroke
				(width 0.1)
				(type default)
			)
			(layer "F.Fab")
		)
		(fp_line
			(start -1.649984 -0.899922)
			(end -1.649984 0.899922)
			(stroke
				(width 0.1)
				(type default)
			)
			(layer "F.Fab")
		)
		(fp_line
			(start 1.649984 0.899922)
			(end 1.649984 -0.899922)
			(stroke
				(width 0.1)
				(type default)
			)
			(layer "F.Fab")
		)
		(fp_line
			(start -1.649984 0.899922)
			(end 1.649984 0.899922)
			(stroke
				(width 0.1)
				(type default)
			)
			(layer "F.Fab")
		)
		(pad "1A" smd rect
			(at -1.700022 0 90)
			(size 1.4986 2.0066)
			(layers "F.Cu" "F.Mask" "F.Paste")
			(net "P0V8_PEX3")
		)
		(pad "1B" smd rect
			(at -1.077722 0 90)
			(size 0.254 0.508)
			(layers "F.Cu" "F.Mask" "F.Paste")
			(net "P0V8_PEX3")
		)
		(pad "2A" smd rect
			(at 1.700022 0 90)
			(size 1.4986 2.0066)
			(layers "F.Cu" "F.Mask" "F.Paste")
			(net "P0V8_SERDES_VDDA_PEX3")
		)
		(pad "2B" smd rect
			(at 1.077722 0 90)
			(size 0.254 0.508)
			(layers "F.Cu" "F.Mask" "F.Paste")
			(net "P0V8_SERDES_VDDA_PEX3")
		)
	)
	(footprint ""
		(layer "F.Cu")
		(at 140.731748 -343.952322 90)
		(property "Reference" "C2264"
			(at 0 0 90)
			(layer "F.SilkS")
			(hide yes)
			(effects
				(font
					(size 1.27 1.27)
				)
			)
		)
		(property "Value" ""
			(at 0 0 90)
			(layer "F.Fab")
			(effects
				(font
					(size 1.27 1.27)
				)
			)
		)
		(duplicate_pad_numbers_are_jumpers no)
		(fp_line
			(start 0.299974 -0.150114)
			(end 0.299974 0.150114)
			(stroke
				(width 0.1)
				(type default)
			)
			(layer "F.Fab")
		)
		(fp_line
			(start -0.299974 -0.150114)
			(end 0.299974 -0.150114)
			(stroke
				(width 0.1)
				(type default)
			)
			(layer "F.Fab")
		)
		(fp_line
			(start 0.299974 0.150114)
			(end -0.299974 0.150114)
			(stroke
				(width 0.1)
				(type default)
			)
			(layer "F.Fab")
		)
		(fp_line
			(start -0.299974 0.150114)
			(end -0.299974 -0.150114)
			(stroke
				(width 0.1)
				(type default)
			)
			(layer "F.Fab")
		)
		(pad "1" smd rect
			(at -0.2667 0 90)
			(size 0.3048 0.381)
			(layers "F.Cu" "F.Mask" "F.Paste")
			(net "P5E_PEX1_STN5_TX_DN<85>")
		)
		(pad "2" smd rect
			(at 0.2667 0 90)
			(size 0.3048 0.381)
			(layers "F.Cu" "F.Mask" "F.Paste")
			(net "P5E_PEX1_STN5_TX_C_DN<85>")
		)
	)
	(footprint ""
		(layer "F.Cu")
		(at 71.7296 -238.255556 90)
		(property "Reference" "R6640"
			(at 0 0 90)
			(layer "F.SilkS")
			(hide yes)
			(effects
				(font
					(size 1.27 1.27)
				)
			)
		)
		(property "Value" ""
			(at 0 0 90)
			(layer "F.Fab")
			(effects
				(font
					(size 1.27 1.27)
				)
			)
		)
		(duplicate_pad_numbers_are_jumpers no)
		(fp_line
			(start 0.7874 -0.4064)
			(end 0.7874 0.4064)
			(stroke
				(width 0.1524)
				(type default)
			)
			(layer "F.SilkS")
		)
		(fp_line
			(start -0.7874 -0.4064)
			(end 0.7874 -0.4064)
			(stroke
				(width 0.1524)
				(type default)
			)
			(layer "F.SilkS")
		)
		(fp_line
			(start 0.7874 0.4064)
			(end -0.7874 0.4064)
			(stroke
				(width 0.1524)
				(type default)
			)
			(layer "F.SilkS")
		)
		(fp_line
			(start -0.7874 0.4064)
			(end -0.7874 -0.4064)
			(stroke
				(width 0.1524)
				(type default)
			)
			(layer "F.SilkS")
		)
		(fp_line
			(start -0.12065 -0.305054)
			(end -0.12065 -0.2794)
			(stroke
				(width 0.1)
				(type default)
			)
			(layer "F.Fab")
		)
		(fp_line
			(start -0.67945 -0.305054)
			(end -0.12065 -0.305054)
			(stroke
				(width 0.1)
				(type default)
			)
			(layer "F.Fab")
		)
		(fp_line
			(start 0.67945 -0.3048)
			(end 0.67945 0.3048)
			(stroke
				(width 0.1)
				(type default)
			)
			(layer "F.Fab")
		)
		(fp_line
			(start 0.12065 -0.3048)
			(end 0.67945 -0.3048)
			(stroke
				(width 0.1)
				(type default)
			)
			(layer "F.Fab")
		)
		(fp_line
			(start 0.12065 -0.2794)
			(end 0.12065 -0.3048)
			(stroke
				(width 0.1)
				(type default)
			)
			(layer "F.Fab")
		)
		(fp_line
			(start -0.12065 -0.2794)
			(end 0.12065 -0.2794)
			(stroke
				(width 0.1)
				(type default)
			)
			(layer "F.Fab")
		)
		(fp_line
			(start 0.120396 0.2794)
			(end -0.12065 0.2794)
			(stroke
				(width 0.1)
				(type default)
			)
			(layer "F.Fab")
		)
		(fp_line
			(start -0.12065 0.2794)
			(end -0.12065 0.3048)
			(stroke
				(width 0.1)
				(type default)
			)
			(layer "F.Fab")
		)
		(fp_line
			(start 0.67945 0.3048)
			(end 0.120396 0.3048)
			(stroke
				(width 0.1)
				(type default)
			)
			(layer "F.Fab")
		)
		(fp_line
			(start 0.120396 0.3048)
			(end 0.120396 0.2794)
			(stroke
				(width 0.1)
				(type default)
			)
			(layer "F.Fab")
		)
		(fp_line
			(start -0.12065 0.3048)
			(end -0.67945 0.3048)
			(stroke
				(width 0.1)
				(type default)
			)
			(layer "F.Fab")
		)
		(fp_line
			(start -0.67945 0.3048)
			(end -0.67945 -0.305054)
			(stroke
				(width 0.1)
				(type default)
			)
			(layer "F.Fab")
		)
		(pad "1" smd circle
			(at -0.40005 0 90)
			(size 0 0)
			(layers "F.Cu" "F.Mask" "F.Paste")
			(net "UART_PEX0_CLI_BUF_R_TX")
		)
		(pad "2" smd circle
			(at 0.40005 0 90)
			(size 0 0)
			(layers "F.Cu" "F.Mask" "F.Paste")
			(net "UART_PEX0_CLI_BUF_R1_TX")
		)
	)
	(footprint ""
		(layer "F.Cu")
		(at 266.410948 -61.386974)
		(property "Reference" "R4502"
			(at 0 0 0)
			(layer "F.SilkS")
			(hide yes)
			(effects
				(font
					(size 1.27 1.27)
				)
			)
		)
		(property "Value" ""
			(at 0 0 0)
			(layer "F.Fab")
			(effects
				(font
					(size 1.27 1.27)
				)
			)
		)
		(duplicate_pad_numbers_are_jumpers no)
		(fp_line
			(start -0.7874 -0.4064)
			(end 0.7874 -0.4064)
			(stroke
				(width 0.1524)
				(type default)
			)
			(layer "F.SilkS")
		)
		(fp_line
			(start -0.7874 0.4064)
			(end -0.7874 -0.4064)
			(stroke
				(width 0.1524)
				(type default)
			)
			(layer "F.SilkS")
		)
		(fp_line
			(start 0.7874 -0.4064)
			(end 0.7874 0.4064)
			(stroke
				(width 0.1524)
				(type default)
			)
			(layer "F.SilkS")
		)
		(fp_line
			(start 0.7874 0.4064)
			(end -0.7874 0.4064)
			(stroke
				(width 0.1524)
				(type default)
			)
			(layer "F.SilkS")
		)
		(fp_line
			(start -0.67945 -0.305054)
			(end -0.12065 -0.305054)
			(stroke
				(width 0.1)
				(type default)
			)
			(layer "F.Fab")
		)
		(fp_line
			(start -0.67945 0.3048)
			(end -0.67945 -0.305054)
			(stroke
				(width 0.1)
				(type default)
			)
			(layer "F.Fab")
		)
		(fp_line
			(start -0.12065 -0.305054)
			(end -0.12065 -0.2794)
			(stroke
				(width 0.1)
				(type default)
			)
			(layer "F.Fab")
		)
		(fp_line
			(start -0.12065 -0.2794)
			(end 0.12065 -0.2794)
			(stroke
				(width 0.1)
				(type default)
			)
			(layer "F.Fab")
		)
		(fp_line
			(start -0.12065 0.2794)
			(end -0.12065 0.3048)
			(stroke
				(width 0.1)
				(type default)
			)
			(layer "F.Fab")
		)
		(fp_line
			(start -0.12065 0.3048)
			(end -0.67945 0.3048)
			(stroke
				(width 0.1)
				(type default)
			)
			(layer "F.Fab")
		)
		(fp_line
			(start 0.120396 0.2794)
			(end -0.12065 0.2794)
			(stroke
				(width 0.1)
				(type default)
			)
			(layer "F.Fab")
		)
		(fp_line
			(start 0.120396 0.3048)
			(end 0.120396 0.2794)
			(stroke
				(width 0.1)
				(type default)
			)
			(layer "F.Fab")
		)
		(fp_line
			(start 0.12065 -0.3048)
			(end 0.67945 -0.3048)
			(stroke
				(width 0.1)
				(type default)
			)
			(layer "F.Fab")
		)
		(fp_line
			(start 0.12065 -0.2794)
			(end 0.12065 -0.3048)
			(stroke
				(width 0.1)
				(type default)
			)
			(layer "F.Fab")
		)
		(fp_line
			(start 0.67945 -0.3048)
			(end 0.67945 0.3048)
			(stroke
				(width 0.1)
				(type default)
			)
			(layer "F.Fab")
		)
		(fp_line
			(start 0.67945 0.3048)
			(end 0.120396 0.3048)
			(stroke
				(width 0.1)
				(type default)
			)
			(layer "F.Fab")
		)
		(pad "1" smd circle
			(at -0.40005 0)
			(size 0 0)
			(layers "F.Cu" "F.Mask" "F.Paste")
			(net "PWRGD_P3V3_SSD9")
		)
		(pad "2" smd circle
			(at 0.40005 0)
			(size 0 0)
			(layers "F.Cu" "F.Mask" "F.Paste")
			(net "PWRGD_P3V3_SSD9_R")
		)
	)
	(footprint ""
		(layer "F.Cu")
		(at 147.07997 -310.28894 -135)
		(property "Reference" "R1264"
			(at 0 0 225)
			(layer "F.SilkS")
			(hide yes)
			(effects
				(font
					(size 1.27 1.27)
				)
			)
		)
		(property "Value" ""
			(at 0 0 225)
			(layer "F.Fab")
			(effects
				(font
					(size 1.27 1.27)
				)
			)
		)
		(duplicate_pad_numbers_are_jumpers no)
		(fp_line
			(start 0.787389 0.406267)
			(end -0.787389 0.406267)
			(stroke
				(width 0.1524)
				(type default)
			)
			(layer "F.SilkS")
		)
		(fp_line
			(start 0.787389 -0.406267)
			(end 0.787389 0.406267)
			(stroke
				(width 0.1524)
				(type default)
			)
			(layer "F.SilkS")
		)
		(fp_line
			(start -0.787389 0.406267)
			(end -0.787389 -0.406267)
			(stroke
				(width 0.1524)
				(type default)
			)
			(layer "F.SilkS")
		)
		(fp_line
			(start -0.787389 -0.406267)
			(end 0.787389 -0.406267)
			(stroke
				(width 0.1524)
				(type default)
			)
			(layer "F.SilkS")
		)
		(fp_line
			(start 0.679446 0.30479)
			(end 0.120515 0.30479)
			(stroke
				(width 0.1)
				(type default)
			)
			(layer "F.Fab")
		)
		(fp_line
			(start 0.120515 0.30479)
			(end 0.120335 0.279466)
			(stroke
				(width 0.1)
				(type default)
			)
			(layer "F.Fab")
		)
		(fp_line
			(start 0.120335 0.279466)
			(end -0.120695 0.279466)
			(stroke
				(width 0.1)
				(type default)
			)
			(layer "F.Fab")
		)
		(fp_line
			(start 0.679446 -0.30479)
			(end 0.679446 0.30479)
			(stroke
				(width 0.1)
				(type default)
			)
			(layer "F.Fab")
		)
		(fp_line
			(start -0.120515 0.30479)
			(end -0.679446 0.30479)
			(stroke
				(width 0.1)
				(type default)
			)
			(layer "F.Fab")
		)
		(fp_line
			(start -0.120695 0.279466)
			(end -0.120515 0.30479)
			(stroke
				(width 0.1)
				(type default)
			)
			(layer "F.Fab")
		)
		(fp_line
			(start 0.120695 -0.279466)
			(end 0.120515 -0.30479)
			(stroke
				(width 0.1)
				(type default)
			)
			(layer "F.Fab")
		)
		(fp_line
			(start 0.120515 -0.30479)
			(end 0.679446 -0.30479)
			(stroke
				(width 0.1)
				(type default)
			)
			(layer "F.Fab")
		)
		(fp_line
			(start -0.679446 0.30479)
			(end -0.679446 -0.305149)
			(stroke
				(width 0.1)
				(type default)
			)
			(layer "F.Fab")
		)
		(fp_line
			(start -0.120695 -0.279466)
			(end 0.120695 -0.279466)
			(stroke
				(width 0.1)
				(type default)
			)
			(layer "F.Fab")
		)
		(fp_line
			(start -0.120695 -0.304969)
			(end -0.120695 -0.279466)
			(stroke
				(width 0.1)
				(type default)
			)
			(layer "F.Fab")
		)
		(fp_line
			(start -0.679446 -0.305149)
			(end -0.120695 -0.304969)
			(stroke
				(width 0.1)
				(type default)
			)
			(layer "F.Fab")
		)
		(pad "1" smd circle
			(at -0.40005 0 225)
			(size 0 0)
			(layers "F.Cu" "F.Mask" "F.Paste")
			(net "PEX1_DBG_MODE0")
		)
		(pad "2" smd circle
			(at 0.40005 0 225)
			(size 0 0)
			(layers "F.Cu" "F.Mask" "F.Paste")
			(net "P1V8_PEX")
		)
	)
	(footprint ""
		(layer "F.Cu")
		(at 12.383516 -160.327848 180)
		(property "Reference" "PR6869"
			(at 0 0 180)
			(layer "F.SilkS")
			(hide yes)
			(effects
				(font
					(size 1.27 1.27)
				)
			)
		)
		(property "Value" ""
			(at 0 0 180)
			(layer "F.Fab")
			(effects
				(font
					(size 1.27 1.27)
				)
			)
		)
		(duplicate_pad_numbers_are_jumpers no)
		(fp_line
			(start 0.7874 0.4064)
			(end -0.7874 0.4064)
			(stroke
				(width 0.1524)
				(type default)
			)
			(layer "F.SilkS")
		)
		(fp_line
			(start 0.7874 -0.4064)
			(end 0.7874 0.4064)
			(stroke
				(width 0.1524)
				(type default)
			)
			(layer "F.SilkS")
		)
		(fp_line
			(start -0.7874 0.4064)
			(end -0.7874 -0.4064)
			(stroke
				(width 0.1524)
				(type default)
			)
			(layer "F.SilkS")
		)
		(fp_line
			(start -0.7874 -0.4064)
			(end 0.7874 -0.4064)
			(stroke
				(width 0.1524)
				(type default)
			)
			(layer "F.SilkS")
		)
		(fp_line
			(start 0.67945 0.3048)
			(end 0.120396 0.3048)
			(stroke
				(width 0.1)
				(type default)
			)
			(layer "F.Fab")
		)
		(fp_line
			(start 0.67945 -0.3048)
			(end 0.67945 0.3048)
			(stroke
				(width 0.1)
				(type default)
			)
			(layer "F.Fab")
		)
		(fp_line
			(start 0.12065 -0.2794)
			(end 0.12065 -0.3048)
			(stroke
				(width 0.1)
				(type default)
			)
			(layer "F.Fab")
		)
		(fp_line
			(start 0.12065 -0.3048)
			(end 0.67945 -0.3048)
			(stroke
				(width 0.1)
				(type default)
			)
			(layer "F.Fab")
		)
		(fp_line
			(start 0.120396 0.3048)
			(end 0.120396 0.2794)
			(stroke
				(width 0.1)
				(type default)
			)
			(layer "F.Fab")
		)
		(fp_line
			(start 0.120396 0.2794)
			(end -0.12065 0.2794)
			(stroke
				(width 0.1)
				(type default)
			)
			(layer "F.Fab")
		)
		(fp_line
			(start -0.12065 0.3048)
			(end -0.67945 0.3048)
			(stroke
				(width 0.1)
				(type default)
			)
			(layer "F.Fab")
		)
		(fp_line
			(start -0.12065 0.2794)
			(end -0.12065 0.3048)
			(stroke
				(width 0.1)
				(type default)
			)
			(layer "F.Fab")
		)
		(fp_line
			(start -0.12065 -0.2794)
			(end 0.12065 -0.2794)
			(stroke
				(width 0.1)
				(type default)
			)
			(layer "F.Fab")
		)
		(fp_line
			(start -0.12065 -0.305054)
			(end -0.12065 -0.2794)
			(stroke
				(width 0.1)
				(type default)
			)
			(layer "F.Fab")
		)
		(fp_line
			(start -0.67945 0.3048)
			(end -0.67945 -0.305054)
			(stroke
				(width 0.1)
				(type default)
			)
			(layer "F.Fab")
		)
		(fp_line
			(start -0.67945 -0.305054)
			(end -0.12065 -0.305054)
			(stroke
				(width 0.1)
				(type default)
			)
			(layer "F.Fab")
		)
		(pad "1" smd circle
			(at -0.40005 0 180)
			(size 0 0)
			(layers "F.Cu" "F.Mask" "F.Paste")
			(net "P12V_NIC0_CO_ISET")
		)
		(pad "2" smd circle
			(at 0.40005 0 180)
			(size 0 0)
			(layers "F.Cu" "F.Mask" "F.Paste")
			(net "P12V_NIC0_CO_ISET_R")
		)
	)
	(footprint ""
		(layer "F.Cu")
		(at 88.65235 -114.384836 180)
		(property "Reference" "PC667"
			(at 0 0 180)
			(layer "F.SilkS")
			(hide yes)
			(effects
				(font
					(size 1.27 1.27)
				)
			)
		)
		(property "Value" ""
			(at 0 0 180)
			(layer "F.Fab")
			(effects
				(font
					(size 1.27 1.27)
				)
			)
		)
		(duplicate_pad_numbers_are_jumpers no)
		(fp_line
			(start 0.7874 0.4064)
			(end -0.7874 0.4064)
			(stroke
				(width 0.1524)
				(type default)
			)
			(layer "F.SilkS")
		)
		(fp_line
			(start 0.7874 -0.4064)
			(end 0.7874 0.4064)
			(stroke
				(width 0.1524)
				(type default)
			)
			(layer "F.SilkS")
		)
		(fp_line
			(start -0.7874 0.4064)
			(end -0.7874 -0.4064)
			(stroke
				(width 0.1524)
				(type default)
			)
			(layer "F.SilkS")
		)
		(fp_line
			(start -0.7874 -0.4064)
			(end 0.7874 -0.4064)
			(stroke
				(width 0.1524)
				(type default)
			)
			(layer "F.SilkS")
		)
		(fp_line
			(start 0.67945 0.3048)
			(end 0.120396 0.3048)
			(stroke
				(width 0.1)
				(type default)
			)
			(layer "F.Fab")
		)
		(fp_line
			(start 0.67945 -0.3048)
			(end 0.67945 0.3048)
			(stroke
				(width 0.1)
				(type default)
			)
			(layer "F.Fab")
		)
		(fp_line
			(start 0.12065 -0.2794)
			(end 0.12065 -0.3048)
			(stroke
				(width 0.1)
				(type default)
			)
			(layer "F.Fab")
		)
		(fp_line
			(start 0.12065 -0.3048)
			(end 0.67945 -0.3048)
			(stroke
				(width 0.1)
				(type default)
			)
			(layer "F.Fab")
		)
		(fp_line
			(start 0.120396 0.3048)
			(end 0.120396 0.2794)
			(stroke
				(width 0.1)
				(type default)
			)
			(layer "F.Fab")
		)
		(fp_line
			(start 0.120396 0.2794)
			(end -0.12065 0.2794)
			(stroke
				(width 0.1)
				(type default)
			)
			(layer "F.Fab")
		)
		(fp_line
			(start -0.12065 0.3048)
			(end -0.67945 0.3048)
			(stroke
				(width 0.1)
				(type default)
			)
			(layer "F.Fab")
		)
		(fp_line
			(start -0.12065 0.2794)
			(end -0.12065 0.3048)
			(stroke
				(width 0.1)
				(type default)
			)
			(layer "F.Fab")
		)
		(fp_line
			(start -0.12065 -0.2794)
			(end 0.12065 -0.2794)
			(stroke
				(width 0.1)
				(type default)
			)
			(layer "F.Fab")
		)
		(fp_line
			(start -0.12065 -0.305054)
			(end -0.12065 -0.2794)
			(stroke
				(width 0.1)
				(type default)
			)
			(layer "F.Fab")
		)
		(fp_line
			(start -0.67945 0.3048)
			(end -0.67945 -0.305054)
			(stroke
				(width 0.1)
				(type default)
			)
			(layer "F.Fab")
		)
		(fp_line
			(start -0.67945 -0.305054)
			(end -0.12065 -0.305054)
			(stroke
				(width 0.1)
				(type default)
			)
			(layer "F.Fab")
		)
		(pad "1" smd circle
			(at -0.40005 0 180)
			(size 0 0)
			(layers "F.Cu" "F.Mask" "F.Paste")
			(net "P3V3_NIC1_CO_DV_DT")
		)
		(pad "2" smd circle
			(at 0.40005 0 180)
			(size 0 0)
			(layers "F.Cu" "F.Mask" "F.Paste")
			(net "GND")
		)
	)
	(footprint ""
		(layer "F.Cu")
		(at 224.022158 -79.595472 180)
		(property "Reference" "R4348"
			(at 0 0 180)
			(layer "F.SilkS")
			(hide yes)
			(effects
				(font
					(size 1.27 1.27)
				)
			)
		)
		(property "Value" ""
			(at 0 0 180)
			(layer "F.Fab")
			(effects
				(font
					(size 1.27 1.27)
				)
			)
		)
		(duplicate_pad_numbers_are_jumpers no)
		(fp_line
			(start 0.7874 0.4064)
			(end -0.7874 0.4064)
			(stroke
				(width 0.1524)
				(type default)
			)
			(layer "F.SilkS")
		)
		(fp_line
			(start 0.7874 -0.4064)
			(end 0.7874 0.4064)
			(stroke
				(width 0.1524)
				(type default)
			)
			(layer "F.SilkS")
		)
		(fp_line
			(start -0.7874 0.4064)
			(end -0.7874 -0.4064)
			(stroke
				(width 0.1524)
				(type default)
			)
			(layer "F.SilkS")
		)
		(fp_line
			(start -0.7874 -0.4064)
			(end 0.7874 -0.4064)
			(stroke
				(width 0.1524)
				(type default)
			)
			(layer "F.SilkS")
		)
		(fp_line
			(start 0.67945 0.3048)
			(end 0.120396 0.3048)
			(stroke
				(width 0.1)
				(type default)
			)
			(layer "F.Fab")
		)
		(fp_line
			(start 0.67945 -0.3048)
			(end 0.67945 0.3048)
			(stroke
				(width 0.1)
				(type default)
			)
			(layer "F.Fab")
		)
		(fp_line
			(start 0.12065 -0.2794)
			(end 0.12065 -0.3048)
			(stroke
				(width 0.1)
				(type default)
			)
			(layer "F.Fab")
		)
		(fp_line
			(start 0.12065 -0.3048)
			(end 0.67945 -0.3048)
			(stroke
				(width 0.1)
				(type default)
			)
			(layer "F.Fab")
		)
		(fp_line
			(start 0.120396 0.3048)
			(end 0.120396 0.2794)
			(stroke
				(width 0.1)
				(type default)
			)
			(layer "F.Fab")
		)
		(fp_line
			(start 0.120396 0.2794)
			(end -0.12065 0.2794)
			(stroke
				(width 0.1)
				(type default)
			)
			(layer "F.Fab")
		)
		(fp_line
			(start -0.12065 0.3048)
			(end -0.67945 0.3048)
			(stroke
				(width 0.1)
				(type default)
			)
			(layer "F.Fab")
		)
		(fp_line
			(start -0.12065 0.2794)
			(end -0.12065 0.3048)
			(stroke
				(width 0.1)
				(type default)
			)
			(layer "F.Fab")
		)
		(fp_line
			(start -0.12065 -0.2794)
			(end 0.12065 -0.2794)
			(stroke
				(width 0.1)
				(type default)
			)
			(layer "F.Fab")
		)
		(fp_line
			(start -0.12065 -0.305054)
			(end -0.12065 -0.2794)
			(stroke
				(width 0.1)
				(type default)
			)
			(layer "F.Fab")
		)
		(fp_line
			(start -0.67945 0.3048)
			(end -0.67945 -0.305054)
			(stroke
				(width 0.1)
				(type default)
			)
			(layer "F.Fab")
		)
		(fp_line
			(start -0.67945 -0.305054)
			(end -0.12065 -0.305054)
			(stroke
				(width 0.1)
				(type default)
			)
			(layer "F.Fab")
		)
		(pad "1" smd circle
			(at -0.40005 0 180)
			(size 0 0)
			(layers "F.Cu" "F.Mask" "F.Paste")
			(net "P3V3_AUX")
		)
		(pad "2" smd circle
			(at 0.40005 0 180)
			(size 0 0)
			(layers "F.Cu" "F.Mask" "F.Paste")
			(net "SSD10_LED_R")
		)
	)
	(footprint ""
		(layer "F.Cu")
		(at 2.796794 -18.037048 90)
		(property "Reference" "U398"
			(at -1.831848 2.335276 90)
			(unlocked yes)
			(layer "F.SilkS")
			(effects
				(font
					(size 0.7874 0.5842)
					(thickness 0.1524)
				)
			)
		)
		(property "Value" ""
			(at 0 0 90)
			(layer "F.Fab")
			(effects
				(font
					(size 1.27 1.27)
				)
			)
		)
		(duplicate_pad_numbers_are_jumpers no)
		(fp_line
			(start -1.949958 -1.610106)
			(end 1.949958 -1.610106)
			(stroke
				(width 0.1524)
				(type default)
			)
			(layer "F.SilkS")
		)
		(fp_line
			(start 1.949958 -1.560068)
			(end 1.949958 1.610106)
			(stroke
				(width 0.1524)
				(type default)
			)
			(layer "F.SilkS")
		)
		(fp_line
			(start 1.949958 1.610106)
			(end -1.949958 1.610106)
			(stroke
				(width 0.1524)
				(type default)
			)
			(layer "F.SilkS")
		)
		(fp_line
			(start -1.949958 1.610106)
			(end -1.949958 -1.610106)
			(stroke
				(width 0.1524)
				(type default)
			)
			(layer "F.SilkS")
		)
		(fp_line
			(start 0.750062 -1.560068)
			(end 0.750062 1.560068)
			(stroke
				(width 0.1)
				(type default)
			)
			(layer "F.Fab")
		)
		(fp_line
			(start -0.750062 -1.560068)
			(end 0.750062 -1.560068)
			(stroke
				(width 0.1)
				(type default)
			)
			(layer "F.Fab")
		)
		(fp_line
			(start 0.750062 1.560068)
			(end -0.750062 1.560068)
			(stroke
				(width 0.1)
				(type default)
			)
			(layer "F.Fab")
		)
		(fp_line
			(start -0.750062 1.560068)
			(end -0.750062 -1.560068)
			(stroke
				(width 0.1)
				(type default)
			)
			(layer "F.Fab")
		)
		(pad "D" smd rect
			(at 1.100074 0)
			(size 1.016 1.4224)
			(layers "F.Cu" "F.Mask" "F.Paste")
			(net "SSD0_LED_ISO_N")
		)
		(pad "G" smd rect
			(at -1.100074 -0.94996)
			(size 1.016 1.4224)
			(layers "F.Cu" "F.Mask" "F.Paste")
			(net "SSD0_LED_R")
		)
		(pad "S" smd rect
			(at -1.100074 0.94996)
			(size 1.016 1.4224)
			(layers "F.Cu" "F.Mask" "F.Paste")
			(net "GND")
		)
	)
	(footprint ""
		(layer "F.Cu")
		(at 101.562662 -100.406708 -90)
		(property "Reference" "PC307"
			(at 0 0 270)
			(layer "F.SilkS")
			(hide yes)
			(effects
				(font
					(size 1.27 1.27)
				)
			)
		)
		(property "Value" ""
			(at 0 0 270)
			(layer "F.Fab")
			(effects
				(font
					(size 1.27 1.27)
				)
			)
		)
		(duplicate_pad_numbers_are_jumpers no)
		(fp_line
			(start -1.524 0.762)
			(end -1.524 -0.762)
			(stroke
				(width 0.1524)
				(type default)
			)
			(layer "F.SilkS")
		)
		(fp_line
			(start 1.524 0.762)
			(end -1.524 0.762)
			(stroke
				(width 0.1524)
				(type default)
			)
			(layer "F.SilkS")
		)
		(fp_line
			(start -1.524 -0.762)
			(end 1.524 -0.762)
			(stroke
				(width 0.1524)
				(type default)
			)
			(layer "F.SilkS")
		)
		(fp_line
			(start 1.524 -0.762)
			(end 1.524 0.762)
			(stroke
				(width 0.1524)
				(type default)
			)
			(layer "F.SilkS")
		)
		(fp_line
			(start -1.1049 0.724916)
			(end 1.1049 0.724916)
			(stroke
				(width 0.1)
				(type default)
			)
			(layer "F.Fab")
		)
		(fp_line
			(start 1.1049 0.724916)
			(end 1.1049 -0.724916)
			(stroke
				(width 0.1)
				(type default)
			)
			(layer "F.Fab")
		)
		(fp_line
			(start -1.1049 -0.724916)
			(end -1.1049 0.724916)
			(stroke
				(width 0.1)
				(type default)
			)
			(layer "F.Fab")
		)
		(fp_line
			(start 1.1049 -0.724916)
			(end -1.1049 -0.724916)
			(stroke
				(width 0.1)
				(type default)
			)
			(layer "F.Fab")
		)
		(pad "1" smd rect
			(at -0.889 0 90)
			(size 1.016 1.27)
			(layers "F.Cu" "F.Mask" "F.Paste")
			(net "GND")
		)
		(pad "2" smd rect
			(at 0.889 0 90)
			(size 1.016 1.27)
			(layers "F.Cu" "F.Mask" "F.Paste")
			(net "P12V_AUX")
		)
	)
	(footprint ""
		(layer "F.Cu")
		(at 135.32358 -152.71115 90)
		(property "Reference" "R708"
			(at 0 0 90)
			(layer "F.SilkS")
			(hide yes)
			(effects
				(font
					(size 1.27 1.27)
				)
			)
		)
		(property "Value" ""
			(at 0 0 90)
			(layer "F.Fab")
			(effects
				(font
					(size 1.27 1.27)
				)
			)
		)
		(duplicate_pad_numbers_are_jumpers no)
		(fp_line
			(start 0.7874 -0.4064)
			(end 0.7874 0.4064)
			(stroke
				(width 0.1524)
				(type default)
			)
			(layer "F.SilkS")
		)
		(fp_line
			(start -0.7874 -0.4064)
			(end 0.7874 -0.4064)
			(stroke
				(width 0.1524)
				(type default)
			)
			(layer "F.SilkS")
		)
		(fp_line
			(start 0.7874 0.4064)
			(end -0.7874 0.4064)
			(stroke
				(width 0.1524)
				(type default)
			)
			(layer "F.SilkS")
		)
		(fp_line
			(start -0.7874 0.4064)
			(end -0.7874 -0.4064)
			(stroke
				(width 0.1524)
				(type default)
			)
			(layer "F.SilkS")
		)
		(fp_line
			(start -0.12065 -0.305054)
			(end -0.12065 -0.2794)
			(stroke
				(width 0.1)
				(type default)
			)
			(layer "F.Fab")
		)
		(fp_line
			(start -0.67945 -0.305054)
			(end -0.12065 -0.305054)
			(stroke
				(width 0.1)
				(type default)
			)
			(layer "F.Fab")
		)
		(fp_line
			(start 0.67945 -0.3048)
			(end 0.67945 0.3048)
			(stroke
				(width 0.1)
				(type default)
			)
			(layer "F.Fab")
		)
		(fp_line
			(start 0.12065 -0.3048)
			(end 0.67945 -0.3048)
			(stroke
				(width 0.1)
				(type default)
			)
			(layer "F.Fab")
		)
		(fp_line
			(start 0.12065 -0.2794)
			(end 0.12065 -0.3048)
			(stroke
				(width 0.1)
				(type default)
			)
			(layer "F.Fab")
		)
		(fp_line
			(start -0.12065 -0.2794)
			(end 0.12065 -0.2794)
			(stroke
				(width 0.1)
				(type default)
			)
			(layer "F.Fab")
		)
		(fp_line
			(start 0.120396 0.2794)
			(end -0.12065 0.2794)
			(stroke
				(width 0.1)
				(type default)
			)
			(layer "F.Fab")
		)
		(fp_line
			(start -0.12065 0.2794)
			(end -0.12065 0.3048)
			(stroke
				(width 0.1)
				(type default)
			)
			(layer "F.Fab")
		)
		(fp_line
			(start 0.67945 0.3048)
			(end 0.120396 0.3048)
			(stroke
				(width 0.1)
				(type default)
			)
			(layer "F.Fab")
		)
		(fp_line
			(start 0.120396 0.3048)
			(end 0.120396 0.2794)
			(stroke
				(width 0.1)
				(type default)
			)
			(layer "F.Fab")
		)
		(fp_line
			(start -0.12065 0.3048)
			(end -0.67945 0.3048)
			(stroke
				(width 0.1)
				(type default)
			)
			(layer "F.Fab")
		)
		(fp_line
			(start -0.67945 0.3048)
			(end -0.67945 -0.305054)
			(stroke
				(width 0.1)
				(type default)
			)
			(layer "F.Fab")
		)
		(pad "1" smd circle
			(at -0.40005 0 90)
			(size 0 0)
			(layers "F.Cu" "F.Mask" "F.Paste")
			(net "NIC2_ADC_A0")
		)
		(pad "2" smd circle
			(at 0.40005 0 90)
			(size 0 0)
			(layers "F.Cu" "F.Mask" "F.Paste")
			(net "GND")
		)
	)
	(footprint ""
		(layer "F.Cu")
		(at 338.074 -178.943 180)
		(property "Reference" "R4753"
			(at 0 0 180)
			(layer "F.SilkS")
			(hide yes)
			(effects
				(font
					(size 1.27 1.27)
				)
			)
		)
		(property "Value" ""
			(at 0 0 180)
			(layer "F.Fab")
			(effects
				(font
					(size 1.27 1.27)
				)
			)
		)
		(duplicate_pad_numbers_are_jumpers no)
		(fp_line
			(start 0.7874 0.4064)
			(end -0.7874 0.4064)
			(stroke
				(width 0.1524)
				(type default)
			)
			(layer "F.SilkS")
		)
		(fp_line
			(start 0.7874 -0.4064)
			(end 0.7874 0.4064)
			(stroke
				(width 0.1524)
				(type default)
			)
			(layer "F.SilkS")
		)
		(fp_line
			(start -0.7874 0.4064)
			(end -0.7874 -0.4064)
			(stroke
				(width 0.1524)
				(type default)
			)
			(layer "F.SilkS")
		)
		(fp_line
			(start -0.7874 -0.4064)
			(end 0.7874 -0.4064)
			(stroke
				(width 0.1524)
				(type default)
			)
			(layer "F.SilkS")
		)
		(fp_line
			(start 0.67945 0.3048)
			(end 0.120396 0.3048)
			(stroke
				(width 0.1)
				(type default)
			)
			(layer "F.Fab")
		)
		(fp_line
			(start 0.67945 -0.3048)
			(end 0.67945 0.3048)
			(stroke
				(width 0.1)
				(type default)
			)
			(layer "F.Fab")
		)
		(fp_line
			(start 0.12065 -0.2794)
			(end 0.12065 -0.3048)
			(stroke
				(width 0.1)
				(type default)
			)
			(layer "F.Fab")
		)
		(fp_line
			(start 0.12065 -0.3048)
			(end 0.67945 -0.3048)
			(stroke
				(width 0.1)
				(type default)
			)
			(layer "F.Fab")
		)
		(fp_line
			(start 0.120396 0.3048)
			(end 0.120396 0.2794)
			(stroke
				(width 0.1)
				(type default)
			)
			(layer "F.Fab")
		)
		(fp_line
			(start 0.120396 0.2794)
			(end -0.12065 0.2794)
			(stroke
				(width 0.1)
				(type default)
			)
			(layer "F.Fab")
		)
		(fp_line
			(start -0.12065 0.3048)
			(end -0.67945 0.3048)
			(stroke
				(width 0.1)
				(type default)
			)
			(layer "F.Fab")
		)
		(fp_line
			(start -0.12065 0.2794)
			(end -0.12065 0.3048)
			(stroke
				(width 0.1)
				(type default)
			)
			(layer "F.Fab")
		)
		(fp_line
			(start -0.12065 -0.2794)
			(end 0.12065 -0.2794)
			(stroke
				(width 0.1)
				(type default)
			)
			(layer "F.Fab")
		)
		(fp_line
			(start -0.12065 -0.305054)
			(end -0.12065 -0.2794)
			(stroke
				(width 0.1)
				(type default)
			)
			(layer "F.Fab")
		)
		(fp_line
			(start -0.67945 0.3048)
			(end -0.67945 -0.305054)
			(stroke
				(width 0.1)
				(type default)
			)
			(layer "F.Fab")
		)
		(fp_line
			(start -0.67945 -0.305054)
			(end -0.12065 -0.305054)
			(stroke
				(width 0.1)
				(type default)
			)
			(layer "F.Fab")
		)
		(pad "1" smd circle
			(at -0.40005 0 180)
			(size 0 0)
			(layers "F.Cu" "F.Mask" "F.Paste")
			(net "PRSNT_SSD9_FPGA_PCA9555_N")
		)
		(pad "2" smd circle
			(at 0.40005 0 180)
			(size 0 0)
			(layers "F.Cu" "F.Mask" "F.Paste")
			(net "PRSNT_SSD9_FPGA_R_N")
		)
	)
	(footprint ""
		(layer "F.Cu")
		(at 425.728892 -356.244906 90)
		(property "Reference" "C2456"
			(at 0 0 90)
			(layer "F.SilkS")
			(hide yes)
			(effects
				(font
					(size 1.27 1.27)
				)
			)
		)
		(property "Value" ""
			(at 0 0 90)
			(layer "F.Fab")
			(effects
				(font
					(size 1.27 1.27)
				)
			)
		)
		(duplicate_pad_numbers_are_jumpers no)
		(fp_line
			(start 0.299974 -0.150114)
			(end 0.299974 0.150114)
			(stroke
				(width 0.1)
				(type default)
			)
			(layer "F.Fab")
		)
		(fp_line
			(start -0.299974 -0.150114)
			(end 0.299974 -0.150114)
			(stroke
				(width 0.1)
				(type default)
			)
			(layer "F.Fab")
		)
		(fp_line
			(start 0.299974 0.150114)
			(end -0.299974 0.150114)
			(stroke
				(width 0.1)
				(type default)
			)
			(layer "F.Fab")
		)
		(fp_line
			(start -0.299974 0.150114)
			(end -0.299974 -0.150114)
			(stroke
				(width 0.1)
				(type default)
			)
			(layer "F.Fab")
		)
		(pad "1" smd rect
			(at -0.2667 0 90)
			(size 0.3048 0.381)
			(layers "F.Cu" "F.Mask" "F.Paste")
			(net "P5E_PEX3_STN4_TX_DN<71>")
		)
		(pad "2" smd rect
			(at 0.2667 0 90)
			(size 0.3048 0.381)
			(layers "F.Cu" "F.Mask" "F.Paste")
			(net "P5E_PEX3_STN4_TX_C_DN<71>")
		)
	)
	(footprint ""
		(layer "F.Cu")
		(at 56.034686 -368.542062 180)
		(property "Reference" "C3985"
			(at 0 0 180)
			(layer "F.SilkS")
			(hide yes)
			(effects
				(font
					(size 1.27 1.27)
				)
			)
		)
		(property "Value" ""
			(at 0 0 180)
			(layer "F.Fab")
			(effects
				(font
					(size 1.27 1.27)
				)
			)
		)
		(duplicate_pad_numbers_are_jumpers no)
		(fp_line
			(start 0.299974 0.150114)
			(end -0.299974 0.150114)
			(stroke
				(width 0.1)
				(type default)
			)
			(layer "F.Fab")
		)
		(fp_line
			(start 0.299974 -0.150114)
			(end 0.299974 0.150114)
			(stroke
				(width 0.1)
				(type default)
			)
			(layer "F.Fab")
		)
		(fp_line
			(start -0.299974 0.150114)
			(end -0.299974 -0.150114)
			(stroke
				(width 0.1)
				(type default)
			)
			(layer "F.Fab")
		)
		(fp_line
			(start -0.299974 -0.150114)
			(end 0.299974 -0.150114)
			(stroke
				(width 0.1)
				(type default)
			)
			(layer "F.Fab")
		)
		(pad "1" smd rect
			(at -0.2667 0 180)
			(size 0.3048 0.381)
			(layers "F.Cu" "F.Mask" "F.Paste")
			(net "P4E_PEX0_STN3_TX_DN<49>")
		)
		(pad "2" smd rect
			(at 0.2667 0 180)
			(size 0.3048 0.381)
			(layers "F.Cu" "F.Mask" "F.Paste")
			(net "P4E_PEX0_STN3_TX_C_DN<49>")
		)
	)
	(footprint ""
		(layer "F.Cu")
		(at 378.841 -190.627)
		(property "Reference" "R4641"
			(at 0 0 0)
			(layer "F.SilkS")
			(hide yes)
			(effects
				(font
					(size 1.27 1.27)
				)
			)
		)
		(property "Value" ""
			(at 0 0 0)
			(layer "F.Fab")
			(effects
				(font
					(size 1.27 1.27)
				)
			)
		)
		(duplicate_pad_numbers_are_jumpers no)
		(fp_line
			(start -0.7874 -0.4064)
			(end 0.7874 -0.4064)
			(stroke
				(width 0.1524)
				(type default)
			)
			(layer "F.SilkS")
		)
		(fp_line
			(start -0.7874 0.4064)
			(end -0.7874 -0.4064)
			(stroke
				(width 0.1524)
				(type default)
			)
			(layer "F.SilkS")
		)
		(fp_line
			(start 0.7874 -0.4064)
			(end 0.7874 0.4064)
			(stroke
				(width 0.1524)
				(type default)
			)
			(layer "F.SilkS")
		)
		(fp_line
			(start 0.7874 0.4064)
			(end -0.7874 0.4064)
			(stroke
				(width 0.1524)
				(type default)
			)
			(layer "F.SilkS")
		)
		(fp_line
			(start -0.67945 -0.305054)
			(end -0.12065 -0.305054)
			(stroke
				(width 0.1)
				(type default)
			)
			(layer "F.Fab")
		)
		(fp_line
			(start -0.67945 0.3048)
			(end -0.67945 -0.305054)
			(stroke
				(width 0.1)
				(type default)
			)
			(layer "F.Fab")
		)
		(fp_line
			(start -0.12065 -0.305054)
			(end -0.12065 -0.2794)
			(stroke
				(width 0.1)
				(type default)
			)
			(layer "F.Fab")
		)
		(fp_line
			(start -0.12065 -0.2794)
			(end 0.12065 -0.2794)
			(stroke
				(width 0.1)
				(type default)
			)
			(layer "F.Fab")
		)
		(fp_line
			(start -0.12065 0.2794)
			(end -0.12065 0.3048)
			(stroke
				(width 0.1)
				(type default)
			)
			(layer "F.Fab")
		)
		(fp_line
			(start -0.12065 0.3048)
			(end -0.67945 0.3048)
			(stroke
				(width 0.1)
				(type default)
			)
			(layer "F.Fab")
		)
		(fp_line
			(start 0.120396 0.2794)
			(end -0.12065 0.2794)
			(stroke
				(width 0.1)
				(type default)
			)
			(layer "F.Fab")
		)
		(fp_line
			(start 0.120396 0.3048)
			(end 0.120396 0.2794)
			(stroke
				(width 0.1)
				(type default)
			)
			(layer "F.Fab")
		)
		(fp_line
			(start 0.12065 -0.3048)
			(end 0.67945 -0.3048)
			(stroke
				(width 0.1)
				(type default)
			)
			(layer "F.Fab")
		)
		(fp_line
			(start 0.12065 -0.2794)
			(end 0.12065 -0.3048)
			(stroke
				(width 0.1)
				(type default)
			)
			(layer "F.Fab")
		)
		(fp_line
			(start 0.67945 -0.3048)
			(end 0.67945 0.3048)
			(stroke
				(width 0.1)
				(type default)
			)
			(layer "F.Fab")
		)
		(fp_line
			(start 0.67945 0.3048)
			(end 0.120396 0.3048)
			(stroke
				(width 0.1)
				(type default)
			)
			(layer "F.Fab")
		)
		(pad "1" smd circle
			(at -0.40005 0)
			(size 0 0)
			(layers "F.Cu" "F.Mask" "F.Paste")
			(net "PCA9555_1_PEX0_A0")
		)
		(pad "2" smd circle
			(at 0.40005 0)
			(size 0 0)
			(layers "F.Cu" "F.Mask" "F.Paste")
			(net "P3V3_AUX")
		)
	)
	(footprint ""
		(layer "F.Cu")
		(at 174.936912 -178.291236 -90)
		(property "Reference" "C4499"
			(at 0 0 270)
			(layer "F.SilkS")
			(hide yes)
			(effects
				(font
					(size 1.27 1.27)
				)
			)
		)
		(property "Value" ""
			(at 0 0 270)
			(layer "F.Fab")
			(effects
				(font
					(size 1.27 1.27)
				)
			)
		)
		(duplicate_pad_numbers_are_jumpers no)
		(fp_line
			(start -0.7874 0.4064)
			(end -0.7874 -0.4064)
			(stroke
				(width 0.1524)
				(type default)
			)
			(layer "F.SilkS")
		)
		(fp_line
			(start 0.7874 0.4064)
			(end -0.7874 0.4064)
			(stroke
				(width 0.1524)
				(type default)
			)
			(layer "F.SilkS")
		)
		(fp_line
			(start -0.7874 -0.4064)
			(end 0.7874 -0.4064)
			(stroke
				(width 0.1524)
				(type default)
			)
			(layer "F.SilkS")
		)
		(fp_line
			(start 0.7874 -0.4064)
			(end 0.7874 0.4064)
			(stroke
				(width 0.1524)
				(type default)
			)
			(layer "F.SilkS")
		)
		(fp_line
			(start -0.67945 0.3048)
			(end -0.67945 -0.305054)
			(stroke
				(width 0.1)
				(type default)
			)
			(layer "F.Fab")
		)
		(fp_line
			(start -0.12065 0.3048)
			(end -0.67945 0.3048)
			(stroke
				(width 0.1)
				(type default)
			)
			(layer "F.Fab")
		)
		(fp_line
			(start 0.120396 0.3048)
			(end 0.120396 0.2794)
			(stroke
				(width 0.1)
				(type default)
			)
			(layer "F.Fab")
		)
		(fp_line
			(start 0.67945 0.3048)
			(end 0.120396 0.3048)
			(stroke
				(width 0.1)
				(type default)
			)
			(layer "F.Fab")
		)
		(fp_line
			(start -0.12065 0.2794)
			(end -0.12065 0.3048)
			(stroke
				(width 0.1)
				(type default)
			)
			(layer "F.Fab")
		)
		(fp_line
			(start 0.120396 0.2794)
			(end -0.12065 0.2794)
			(stroke
				(width 0.1)
				(type default)
			)
			(layer "F.Fab")
		)
		(fp_line
			(start -0.12065 -0.2794)
			(end 0.12065 -0.2794)
			(stroke
				(width 0.1)
				(type default)
			)
			(layer "F.Fab")
		)
		(fp_line
			(start 0.12065 -0.2794)
			(end 0.12065 -0.3048)
			(stroke
				(width 0.1)
				(type default)
			)
			(layer "F.Fab")
		)
		(fp_line
			(start 0.12065 -0.3048)
			(end 0.67945 -0.3048)
			(stroke
				(width 0.1)
				(type default)
			)
			(layer "F.Fab")
		)
		(fp_line
			(start 0.67945 -0.3048)
			(end 0.67945 0.3048)
			(stroke
				(width 0.1)
				(type default)
			)
			(layer "F.Fab")
		)
		(fp_line
			(start -0.67945 -0.305054)
			(end -0.12065 -0.305054)
			(stroke
				(width 0.1)
				(type default)
			)
			(layer "F.Fab")
		)
		(fp_line
			(start -0.12065 -0.305054)
			(end -0.12065 -0.2794)
			(stroke
				(width 0.1)
				(type default)
			)
			(layer "F.Fab")
		)
		(pad "1" smd circle
			(at -0.40005 0 270)
			(size 0 0)
			(layers "F.Cu" "F.Mask" "F.Paste")
			(net "NIC2_CLK_EN_R_N")
		)
		(pad "2" smd circle
			(at 0.40005 0 270)
			(size 0 0)
			(layers "F.Cu" "F.Mask" "F.Paste")
			(net "GND")
		)
	)
	(footprint ""
		(layer "F.Cu")
		(at 383.59842 -356.244906 90)
		(property "Reference" "C774"
			(at 0 0 90)
			(layer "F.SilkS")
			(hide yes)
			(effects
				(font
					(size 1.27 1.27)
				)
			)
		)
		(property "Value" ""
			(at 0 0 90)
			(layer "F.Fab")
			(effects
				(font
					(size 1.27 1.27)
				)
			)
		)
		(duplicate_pad_numbers_are_jumpers no)
		(fp_line
			(start 0.299974 -0.150114)
			(end 0.299974 0.150114)
			(stroke
				(width 0.1)
				(type default)
			)
			(layer "F.Fab")
		)
		(fp_line
			(start -0.299974 -0.150114)
			(end 0.299974 -0.150114)
			(stroke
				(width 0.1)
				(type default)
			)
			(layer "F.Fab")
		)
		(fp_line
			(start 0.299974 0.150114)
			(end -0.299974 0.150114)
			(stroke
				(width 0.1)
				(type default)
			)
			(layer "F.Fab")
		)
		(fp_line
			(start -0.299974 0.150114)
			(end -0.299974 -0.150114)
			(stroke
				(width 0.1)
				(type default)
			)
			(layer "F.Fab")
		)
		(pad "1" smd rect
			(at -0.2667 0 90)
			(size 0.3048 0.381)
			(layers "F.Cu" "F.Mask" "F.Paste")
			(net "P5E_PEX3_STN6_TX_DP<105>")
		)
		(pad "2" smd rect
			(at 0.2667 0 90)
			(size 0.3048 0.381)
			(layers "F.Cu" "F.Mask" "F.Paste")
			(net "P5E_PEX3_STN6_TX_C_DP<105>")
		)
	)
	(footprint ""
		(layer "F.Cu")
		(at 299.90161 -198.238872 90)
		(property "Reference" "C2108"
			(at 0 0 90)
			(layer "F.SilkS")
			(hide yes)
			(effects
				(font
					(size 1.27 1.27)
				)
			)
		)
		(property "Value" ""
			(at 0 0 90)
			(layer "F.Fab")
			(effects
				(font
					(size 1.27 1.27)
				)
			)
		)
		(duplicate_pad_numbers_are_jumpers no)
		(fp_line
			(start 0.7874 -0.4064)
			(end 0.7874 0.4064)
			(stroke
				(width 0.1524)
				(type default)
			)
			(layer "F.SilkS")
		)
		(fp_line
			(start -0.7874 -0.4064)
			(end 0.7874 -0.4064)
			(stroke
				(width 0.1524)
				(type default)
			)
			(layer "F.SilkS")
		)
		(fp_line
			(start 0.7874 0.4064)
			(end -0.7874 0.4064)
			(stroke
				(width 0.1524)
				(type default)
			)
			(layer "F.SilkS")
		)
		(fp_line
			(start -0.7874 0.4064)
			(end -0.7874 -0.4064)
			(stroke
				(width 0.1524)
				(type default)
			)
			(layer "F.SilkS")
		)
		(fp_line
			(start -0.12065 -0.305054)
			(end -0.12065 -0.2794)
			(stroke
				(width 0.1)
				(type default)
			)
			(layer "F.Fab")
		)
		(fp_line
			(start -0.67945 -0.305054)
			(end -0.12065 -0.305054)
			(stroke
				(width 0.1)
				(type default)
			)
			(layer "F.Fab")
		)
		(fp_line
			(start 0.67945 -0.3048)
			(end 0.67945 0.3048)
			(stroke
				(width 0.1)
				(type default)
			)
			(layer "F.Fab")
		)
		(fp_line
			(start 0.12065 -0.3048)
			(end 0.67945 -0.3048)
			(stroke
				(width 0.1)
				(type default)
			)
			(layer "F.Fab")
		)
		(fp_line
			(start 0.12065 -0.2794)
			(end 0.12065 -0.3048)
			(stroke
				(width 0.1)
				(type default)
			)
			(layer "F.Fab")
		)
		(fp_line
			(start -0.12065 -0.2794)
			(end 0.12065 -0.2794)
			(stroke
				(width 0.1)
				(type default)
			)
			(layer "F.Fab")
		)
		(fp_line
			(start 0.120396 0.2794)
			(end -0.12065 0.2794)
			(stroke
				(width 0.1)
				(type default)
			)
			(layer "F.Fab")
		)
		(fp_line
			(start -0.12065 0.2794)
			(end -0.12065 0.3048)
			(stroke
				(width 0.1)
				(type default)
			)
			(layer "F.Fab")
		)
		(fp_line
			(start 0.67945 0.3048)
			(end 0.120396 0.3048)
			(stroke
				(width 0.1)
				(type default)
			)
			(layer "F.Fab")
		)
		(fp_line
			(start 0.120396 0.3048)
			(end 0.120396 0.2794)
			(stroke
				(width 0.1)
				(type default)
			)
			(layer "F.Fab")
		)
		(fp_line
			(start -0.12065 0.3048)
			(end -0.67945 0.3048)
			(stroke
				(width 0.1)
				(type default)
			)
			(layer "F.Fab")
		)
		(fp_line
			(start -0.67945 0.3048)
			(end -0.67945 -0.305054)
			(stroke
				(width 0.1)
				(type default)
			)
			(layer "F.Fab")
		)
		(pad "1" smd circle
			(at -0.40005 0 90)
			(size 0 0)
			(layers "F.Cu" "F.Mask" "F.Paste")
			(net "GND")
		)
		(pad "2" smd circle
			(at 0.40005 0 90)
			(size 0 0)
			(layers "F.Cu" "F.Mask" "F.Paste")
			(net "P1V8_PEX")
		)
	)
	(footprint ""
		(layer "F.Cu")
		(at 446.746376 -58.323734)
		(property "Reference" "PC403"
			(at 0 0 0)
			(layer "F.SilkS")
			(hide yes)
			(effects
				(font
					(size 1.27 1.27)
				)
			)
		)
		(property "Value" ""
			(at 0 0 0)
			(layer "F.Fab")
			(effects
				(font
					(size 1.27 1.27)
				)
			)
		)
		(duplicate_pad_numbers_are_jumpers no)
		(fp_line
			(start -1.524 -0.762)
			(end 1.524 -0.762)
			(stroke
				(width 0.1524)
				(type default)
			)
			(layer "F.SilkS")
		)
		(fp_line
			(start -1.524 0.762)
			(end -1.524 -0.762)
			(stroke
				(width 0.1524)
				(type default)
			)
			(layer "F.SilkS")
		)
		(fp_line
			(start 1.524 -0.762)
			(end 1.524 0.762)
			(stroke
				(width 0.1524)
				(type default)
			)
			(layer "F.SilkS")
		)
		(fp_line
			(start 1.524 0.762)
			(end -1.524 0.762)
			(stroke
				(width 0.1524)
				(type default)
			)
			(layer "F.SilkS")
		)
		(fp_line
			(start -1.1049 -0.724916)
			(end -1.1049 0.724916)
			(stroke
				(width 0.1)
				(type default)
			)
			(layer "F.Fab")
		)
		(fp_line
			(start -1.1049 0.724916)
			(end 1.1049 0.724916)
			(stroke
				(width 0.1)
				(type default)
			)
			(layer "F.Fab")
		)
		(fp_line
			(start 1.1049 -0.724916)
			(end -1.1049 -0.724916)
			(stroke
				(width 0.1)
				(type default)
			)
			(layer "F.Fab")
		)
		(fp_line
			(start 1.1049 0.724916)
			(end 1.1049 -0.724916)
			(stroke
				(width 0.1)
				(type default)
			)
			(layer "F.Fab")
		)
		(pad "1" smd rect
			(at -0.889 0 180)
			(size 1.016 1.27)
			(layers "F.Cu" "F.Mask" "F.Paste")
			(net "GND")
		)
		(pad "2" smd rect
			(at 0.889 0 180)
			(size 1.016 1.27)
			(layers "F.Cu" "F.Mask" "F.Paste")
			(net "P12V_AUX")
		)
	)
	(footprint ""
		(layer "F.Cu")
		(at 127.832612 -162.003994 90)
		(property "Reference" "PC635"
			(at 0 0 90)
			(layer "F.SilkS")
			(hide yes)
			(effects
				(font
					(size 1.27 1.27)
				)
			)
		)
		(property "Value" ""
			(at 0 0 90)
			(layer "F.Fab")
			(effects
				(font
					(size 1.27 1.27)
				)
			)
		)
		(duplicate_pad_numbers_are_jumpers no)
		(fp_line
			(start 0.7874 -0.4064)
			(end 0.7874 0.4064)
			(stroke
				(width 0.1524)
				(type default)
			)
			(layer "F.SilkS")
		)
		(fp_line
			(start -0.7874 -0.4064)
			(end 0.7874 -0.4064)
			(stroke
				(width 0.1524)
				(type default)
			)
			(layer "F.SilkS")
		)
		(fp_line
			(start 0.7874 0.4064)
			(end -0.7874 0.4064)
			(stroke
				(width 0.1524)
				(type default)
			)
			(layer "F.SilkS")
		)
		(fp_line
			(start -0.7874 0.4064)
			(end -0.7874 -0.4064)
			(stroke
				(width 0.1524)
				(type default)
			)
			(layer "F.SilkS")
		)
		(fp_line
			(start -0.12065 -0.305054)
			(end -0.12065 -0.2794)
			(stroke
				(width 0.1)
				(type default)
			)
			(layer "F.Fab")
		)
		(fp_line
			(start -0.67945 -0.305054)
			(end -0.12065 -0.305054)
			(stroke
				(width 0.1)
				(type default)
			)
			(layer "F.Fab")
		)
		(fp_line
			(start 0.67945 -0.3048)
			(end 0.67945 0.3048)
			(stroke
				(width 0.1)
				(type default)
			)
			(layer "F.Fab")
		)
		(fp_line
			(start 0.12065 -0.3048)
			(end 0.67945 -0.3048)
			(stroke
				(width 0.1)
				(type default)
			)
			(layer "F.Fab")
		)
		(fp_line
			(start 0.12065 -0.2794)
			(end 0.12065 -0.3048)
			(stroke
				(width 0.1)
				(type default)
			)
			(layer "F.Fab")
		)
		(fp_line
			(start -0.12065 -0.2794)
			(end 0.12065 -0.2794)
			(stroke
				(width 0.1)
				(type default)
			)
			(layer "F.Fab")
		)
		(fp_line
			(start 0.120396 0.2794)
			(end -0.12065 0.2794)
			(stroke
				(width 0.1)
				(type default)
			)
			(layer "F.Fab")
		)
		(fp_line
			(start -0.12065 0.2794)
			(end -0.12065 0.3048)
			(stroke
				(width 0.1)
				(type default)
			)
			(layer "F.Fab")
		)
		(fp_line
			(start 0.67945 0.3048)
			(end 0.120396 0.3048)
			(stroke
				(width 0.1)
				(type default)
			)
			(layer "F.Fab")
		)
		(fp_line
			(start 0.120396 0.3048)
			(end 0.120396 0.2794)
			(stroke
				(width 0.1)
				(type default)
			)
			(layer "F.Fab")
		)
		(fp_line
			(start -0.12065 0.3048)
			(end -0.67945 0.3048)
			(stroke
				(width 0.1)
				(type default)
			)
			(layer "F.Fab")
		)
		(fp_line
			(start -0.67945 0.3048)
			(end -0.67945 -0.305054)
			(stroke
				(width 0.1)
				(type default)
			)
			(layer "F.Fab")
		)
		(pad "1" smd circle
			(at -0.40005 0 90)
			(size 0 0)
			(layers "F.Cu" "F.Mask" "F.Paste")
			(net "P12V_NIC2_CO_ISET_R")
		)
		(pad "2" smd circle
			(at 0.40005 0 90)
			(size 0 0)
			(layers "F.Cu" "F.Mask" "F.Paste")
			(net "GND")
		)
	)
	(footprint ""
		(layer "F.Cu")
		(at 136.225534 -42.849038 180)
		(property "Reference" "R557"
			(at 0 0 180)
			(layer "F.SilkS")
			(hide yes)
			(effects
				(font
					(size 1.27 1.27)
				)
			)
		)
		(property "Value" ""
			(at 0 0 180)
			(layer "F.Fab")
			(effects
				(font
					(size 1.27 1.27)
				)
			)
		)
		(duplicate_pad_numbers_are_jumpers no)
		(fp_line
			(start 0.7874 0.4064)
			(end -0.7874 0.4064)
			(stroke
				(width 0.1524)
				(type default)
			)
			(layer "F.SilkS")
		)
		(fp_line
			(start 0.7874 -0.4064)
			(end 0.7874 0.4064)
			(stroke
				(width 0.1524)
				(type default)
			)
			(layer "F.SilkS")
		)
		(fp_line
			(start -0.7874 0.4064)
			(end -0.7874 -0.4064)
			(stroke
				(width 0.1524)
				(type default)
			)
			(layer "F.SilkS")
		)
		(fp_line
			(start -0.7874 -0.4064)
			(end 0.7874 -0.4064)
			(stroke
				(width 0.1524)
				(type default)
			)
			(layer "F.SilkS")
		)
		(fp_line
			(start 0.67945 0.3048)
			(end 0.120396 0.3048)
			(stroke
				(width 0.1)
				(type default)
			)
			(layer "F.Fab")
		)
		(fp_line
			(start 0.67945 -0.3048)
			(end 0.67945 0.3048)
			(stroke
				(width 0.1)
				(type default)
			)
			(layer "F.Fab")
		)
		(fp_line
			(start 0.12065 -0.2794)
			(end 0.12065 -0.3048)
			(stroke
				(width 0.1)
				(type default)
			)
			(layer "F.Fab")
		)
		(fp_line
			(start 0.12065 -0.3048)
			(end 0.67945 -0.3048)
			(stroke
				(width 0.1)
				(type default)
			)
			(layer "F.Fab")
		)
		(fp_line
			(start 0.120396 0.3048)
			(end 0.120396 0.2794)
			(stroke
				(width 0.1)
				(type default)
			)
			(layer "F.Fab")
		)
		(fp_line
			(start 0.120396 0.2794)
			(end -0.12065 0.2794)
			(stroke
				(width 0.1)
				(type default)
			)
			(layer "F.Fab")
		)
		(fp_line
			(start -0.12065 0.3048)
			(end -0.67945 0.3048)
			(stroke
				(width 0.1)
				(type default)
			)
			(layer "F.Fab")
		)
		(fp_line
			(start -0.12065 0.2794)
			(end -0.12065 0.3048)
			(stroke
				(width 0.1)
				(type default)
			)
			(layer "F.Fab")
		)
		(fp_line
			(start -0.12065 -0.2794)
			(end 0.12065 -0.2794)
			(stroke
				(width 0.1)
				(type default)
			)
			(layer "F.Fab")
		)
		(fp_line
			(start -0.12065 -0.305054)
			(end -0.12065 -0.2794)
			(stroke
				(width 0.1)
				(type default)
			)
			(layer "F.Fab")
		)
		(fp_line
			(start -0.67945 0.3048)
			(end -0.67945 -0.305054)
			(stroke
				(width 0.1)
				(type default)
			)
			(layer "F.Fab")
		)
		(fp_line
			(start -0.67945 -0.305054)
			(end -0.12065 -0.305054)
			(stroke
				(width 0.1)
				(type default)
			)
			(layer "F.Fab")
		)
		(pad "1" smd circle
			(at -0.40005 0 180)
			(size 0 0)
			(layers "F.Cu" "F.Mask" "F.Paste")
			(net "P12V_SSD4_R")
		)
		(pad "2" smd circle
			(at 0.40005 0 180)
			(size 0 0)
			(layers "F.Cu" "F.Mask" "F.Paste")
			(net "P12V_SSD4_VIN_P")
		)
	)
	(footprint ""
		(layer "F.Cu")
		(at 490.25937 -551.726608 180)
		(property "Reference" "SCREW_SSD0_1"
			(at -5.207 -1.402334 0)
			(unlocked yes)
			(layer "B.SilkS")
			(effects
				(font
					(size 0.7874 0.5842)
					(thickness 0.1524)
				)
				(justify mirror)
			)
		)
		(property "Value" ""
			(at 0 0 180)
			(layer "F.Fab")
			(effects
				(font
					(size 1.27 1.27)
				)
			)
		)
		(duplicate_pad_numbers_are_jumpers no)
		(pad "1" thru_hole circle
			(at 0 0 180)
			(size 0.4572 0.4572)
			(drill 0.2032)
			(layers "*.Cu" "*.Mask")
			(remove_unused_layers no)
			(net "Net_9156")
			(clearance 0.127)
			(thermal_gap 0.127)
			(padstack
				(mode front_inner_back)
				(layer "Inner"
					(shape circle)
					(size 0.4572 0.4572)
					(clearance 0.127)
				)
				(layer "B.Cu"
					(shape circle)
					(size 0.508 0.508)
					(clearance 0.1016)
				)
			)
		)
	)
	(footprint ""
		(layer "F.Cu")
		(at 359.85831 -258.131564)
		(property "Reference" "C837"
			(at 0 0 0)
			(layer "F.SilkS")
			(hide yes)
			(effects
				(font
					(size 1.27 1.27)
				)
			)
		)
		(property "Value" ""
			(at 0 0 0)
			(layer "F.Fab")
			(effects
				(font
					(size 1.27 1.27)
				)
			)
		)
		(duplicate_pad_numbers_are_jumpers no)
		(fp_line
			(start -0.7874 -0.4064)
			(end 0.7874 -0.4064)
			(stroke
				(width 0.1524)
				(type default)
			)
			(layer "F.SilkS")
		)
		(fp_line
			(start -0.7874 0.4064)
			(end -0.7874 -0.4064)
			(stroke
				(width 0.1524)
				(type default)
			)
			(layer "F.SilkS")
		)
		(fp_line
			(start 0.7874 -0.4064)
			(end 0.7874 0.4064)
			(stroke
				(width 0.1524)
				(type default)
			)
			(layer "F.SilkS")
		)
		(fp_line
			(start 0.7874 0.4064)
			(end -0.7874 0.4064)
			(stroke
				(width 0.1524)
				(type default)
			)
			(layer "F.SilkS")
		)
		(fp_line
			(start -0.67945 -0.305054)
			(end -0.12065 -0.305054)
			(stroke
				(width 0.1)
				(type default)
			)
			(layer "F.Fab")
		)
		(fp_line
			(start -0.67945 0.3048)
			(end -0.67945 -0.305054)
			(stroke
				(width 0.1)
				(type default)
			)
			(layer "F.Fab")
		)
		(fp_line
			(start -0.12065 -0.305054)
			(end -0.12065 -0.2794)
			(stroke
				(width 0.1)
				(type default)
			)
			(layer "F.Fab")
		)
		(fp_line
			(start -0.12065 -0.2794)
			(end 0.12065 -0.2794)
			(stroke
				(width 0.1)
				(type default)
			)
			(layer "F.Fab")
		)
		(fp_line
			(start -0.12065 0.2794)
			(end -0.12065 0.3048)
			(stroke
				(width 0.1)
				(type default)
			)
			(layer "F.Fab")
		)
		(fp_line
			(start -0.12065 0.3048)
			(end -0.67945 0.3048)
			(stroke
				(width 0.1)
				(type default)
			)
			(layer "F.Fab")
		)
		(fp_line
			(start 0.120396 0.2794)
			(end -0.12065 0.2794)
			(stroke
				(width 0.1)
				(type default)
			)
			(layer "F.Fab")
		)
		(fp_line
			(start 0.120396 0.3048)
			(end 0.120396 0.2794)
			(stroke
				(width 0.1)
				(type default)
			)
			(layer "F.Fab")
		)
		(fp_line
			(start 0.12065 -0.3048)
			(end 0.67945 -0.3048)
			(stroke
				(width 0.1)
				(type default)
			)
			(layer "F.Fab")
		)
		(fp_line
			(start 0.12065 -0.2794)
			(end 0.12065 -0.3048)
			(stroke
				(width 0.1)
				(type default)
			)
			(layer "F.Fab")
		)
		(fp_line
			(start 0.67945 -0.3048)
			(end 0.67945 0.3048)
			(stroke
				(width 0.1)
				(type default)
			)
			(layer "F.Fab")
		)
		(fp_line
			(start 0.67945 0.3048)
			(end 0.120396 0.3048)
			(stroke
				(width 0.1)
				(type default)
			)
			(layer "F.Fab")
		)
		(pad "1" smd circle
			(at -0.40005 0)
			(size 0 0)
			(layers "F.Cu" "F.Mask" "F.Paste")
			(net "P0V8_PEX3_BVRRDY")
		)
		(pad "2" smd circle
			(at 0.40005 0)
			(size 0 0)
			(layers "F.Cu" "F.Mask" "F.Paste")
			(net "GND")
		)
	)
	(footprint ""
		(layer "F.Cu")
		(at 161.346896 -37.47516)
		(property "Reference" "R6074"
			(at 0 0 0)
			(layer "F.SilkS")
			(hide yes)
			(effects
				(font
					(size 1.27 1.27)
				)
			)
		)
		(property "Value" ""
			(at 0 0 0)
			(layer "F.Fab")
			(effects
				(font
					(size 1.27 1.27)
				)
			)
		)
		(duplicate_pad_numbers_are_jumpers no)
		(fp_line
			(start -0.7874 -0.4064)
			(end 0.7874 -0.4064)
			(stroke
				(width 0.1524)
				(type default)
			)
			(layer "F.SilkS")
		)
		(fp_line
			(start -0.7874 0.4064)
			(end -0.7874 -0.4064)
			(stroke
				(width 0.1524)
				(type default)
			)
			(layer "F.SilkS")
		)
		(fp_line
			(start 0.7874 -0.4064)
			(end 0.7874 0.4064)
			(stroke
				(width 0.1524)
				(type default)
			)
			(layer "F.SilkS")
		)
		(fp_line
			(start 0.7874 0.4064)
			(end -0.7874 0.4064)
			(stroke
				(width 0.1524)
				(type default)
			)
			(layer "F.SilkS")
		)
		(fp_line
			(start -0.67945 -0.305054)
			(end -0.12065 -0.305054)
			(stroke
				(width 0.1)
				(type default)
			)
			(layer "F.Fab")
		)
		(fp_line
			(start -0.67945 0.3048)
			(end -0.67945 -0.305054)
			(stroke
				(width 0.1)
				(type default)
			)
			(layer "F.Fab")
		)
		(fp_line
			(start -0.12065 -0.305054)
			(end -0.12065 -0.2794)
			(stroke
				(width 0.1)
				(type default)
			)
			(layer "F.Fab")
		)
		(fp_line
			(start -0.12065 -0.2794)
			(end 0.12065 -0.2794)
			(stroke
				(width 0.1)
				(type default)
			)
			(layer "F.Fab")
		)
		(fp_line
			(start -0.12065 0.2794)
			(end -0.12065 0.3048)
			(stroke
				(width 0.1)
				(type default)
			)
			(layer "F.Fab")
		)
		(fp_line
			(start -0.12065 0.3048)
			(end -0.67945 0.3048)
			(stroke
				(width 0.1)
				(type default)
			)
			(layer "F.Fab")
		)
		(fp_line
			(start 0.120396 0.2794)
			(end -0.12065 0.2794)
			(stroke
				(width 0.1)
				(type default)
			)
			(layer "F.Fab")
		)
		(fp_line
			(start 0.120396 0.3048)
			(end 0.120396 0.2794)
			(stroke
				(width 0.1)
				(type default)
			)
			(layer "F.Fab")
		)
		(fp_line
			(start 0.12065 -0.3048)
			(end 0.67945 -0.3048)
			(stroke
				(width 0.1)
				(type default)
			)
			(layer "F.Fab")
		)
		(fp_line
			(start 0.12065 -0.2794)
			(end 0.12065 -0.3048)
			(stroke
				(width 0.1)
				(type default)
			)
			(layer "F.Fab")
		)
		(fp_line
			(start 0.67945 -0.3048)
			(end 0.67945 0.3048)
			(stroke
				(width 0.1)
				(type default)
			)
			(layer "F.Fab")
		)
		(fp_line
			(start 0.67945 0.3048)
			(end 0.120396 0.3048)
			(stroke
				(width 0.1)
				(type default)
			)
			(layer "F.Fab")
		)
		(pad "1" smd circle
			(at -0.40005 0)
			(size 0 0)
			(layers "F.Cu" "F.Mask" "F.Paste")
			(net "P3V3_SSD6")
		)
		(pad "2" smd circle
			(at 0.40005 0)
			(size 0 0)
			(layers "F.Cu" "F.Mask" "F.Paste")
			(net "P3V3_SSD6_PG_G1")
		)
	)
	(footprint ""
		(layer "F.Cu")
		(at 7.398258 -304.850546 90)
		(property "Reference" "PC220"
			(at 0 0 90)
			(layer "F.SilkS")
			(hide yes)
			(effects
				(font
					(size 1.27 1.27)
				)
			)
		)
		(property "Value" ""
			(at 0 0 90)
			(layer "F.Fab")
			(effects
				(font
					(size 1.27 1.27)
				)
			)
		)
		(duplicate_pad_numbers_are_jumpers no)
		(fp_line
			(start 0.7874 -0.4064)
			(end 0.7874 0.4064)
			(stroke
				(width 0.1524)
				(type default)
			)
			(layer "F.SilkS")
		)
		(fp_line
			(start -0.7874 -0.4064)
			(end 0.7874 -0.4064)
			(stroke
				(width 0.1524)
				(type default)
			)
			(layer "F.SilkS")
		)
		(fp_line
			(start 0.7874 0.4064)
			(end -0.7874 0.4064)
			(stroke
				(width 0.1524)
				(type default)
			)
			(layer "F.SilkS")
		)
		(fp_line
			(start -0.7874 0.4064)
			(end -0.7874 -0.4064)
			(stroke
				(width 0.1524)
				(type default)
			)
			(layer "F.SilkS")
		)
		(fp_line
			(start -0.12065 -0.305054)
			(end -0.12065 -0.2794)
			(stroke
				(width 0.1)
				(type default)
			)
			(layer "F.Fab")
		)
		(fp_line
			(start -0.67945 -0.305054)
			(end -0.12065 -0.305054)
			(stroke
				(width 0.1)
				(type default)
			)
			(layer "F.Fab")
		)
		(fp_line
			(start 0.67945 -0.3048)
			(end 0.67945 0.3048)
			(stroke
				(width 0.1)
				(type default)
			)
			(layer "F.Fab")
		)
		(fp_line
			(start 0.12065 -0.3048)
			(end 0.67945 -0.3048)
			(stroke
				(width 0.1)
				(type default)
			)
			(layer "F.Fab")
		)
		(fp_line
			(start 0.12065 -0.2794)
			(end 0.12065 -0.3048)
			(stroke
				(width 0.1)
				(type default)
			)
			(layer "F.Fab")
		)
		(fp_line
			(start -0.12065 -0.2794)
			(end 0.12065 -0.2794)
			(stroke
				(width 0.1)
				(type default)
			)
			(layer "F.Fab")
		)
		(fp_line
			(start 0.120396 0.2794)
			(end -0.12065 0.2794)
			(stroke
				(width 0.1)
				(type default)
			)
			(layer "F.Fab")
		)
		(fp_line
			(start -0.12065 0.2794)
			(end -0.12065 0.3048)
			(stroke
				(width 0.1)
				(type default)
			)
			(layer "F.Fab")
		)
		(fp_line
			(start 0.67945 0.3048)
			(end 0.120396 0.3048)
			(stroke
				(width 0.1)
				(type default)
			)
			(layer "F.Fab")
		)
		(fp_line
			(start 0.120396 0.3048)
			(end 0.120396 0.2794)
			(stroke
				(width 0.1)
				(type default)
			)
			(layer "F.Fab")
		)
		(fp_line
			(start -0.12065 0.3048)
			(end -0.67945 0.3048)
			(stroke
				(width 0.1)
				(type default)
			)
			(layer "F.Fab")
		)
		(fp_line
			(start -0.67945 0.3048)
			(end -0.67945 -0.305054)
			(stroke
				(width 0.1)
				(type default)
			)
			(layer "F.Fab")
		)
		(pad "1" smd circle
			(at -0.40005 0 90)
			(size 0 0)
			(layers "F.Cu" "F.Mask" "F.Paste")
			(net "P1V25_PEX0_VCC")
		)
		(pad "2" smd circle
			(at 0.40005 0 90)
			(size 0 0)
			(layers "F.Cu" "F.Mask" "F.Paste")
			(net "GND")
		)
	)
	(footprint ""
		(layer "F.Cu")
		(at 331.457046 -236.871256 -90)
		(property "Reference" "R1786"
			(at 0 0 270)
			(layer "F.SilkS")
			(hide yes)
			(effects
				(font
					(size 1.27 1.27)
				)
			)
		)
		(property "Value" ""
			(at 0 0 270)
			(layer "F.Fab")
			(effects
				(font
					(size 1.27 1.27)
				)
			)
		)
		(duplicate_pad_numbers_are_jumpers no)
		(fp_line
			(start -0.7874 0.4064)
			(end -0.7874 -0.4064)
			(stroke
				(width 0.1524)
				(type default)
			)
			(layer "F.SilkS")
		)
		(fp_line
			(start 0.7874 0.4064)
			(end -0.7874 0.4064)
			(stroke
				(width 0.1524)
				(type default)
			)
			(layer "F.SilkS")
		)
		(fp_line
			(start -0.7874 -0.4064)
			(end 0.7874 -0.4064)
			(stroke
				(width 0.1524)
				(type default)
			)
			(layer "F.SilkS")
		)
		(fp_line
			(start 0.7874 -0.4064)
			(end 0.7874 0.4064)
			(stroke
				(width 0.1524)
				(type default)
			)
			(layer "F.SilkS")
		)
		(fp_line
			(start -0.67945 0.3048)
			(end -0.67945 -0.305054)
			(stroke
				(width 0.1)
				(type default)
			)
			(layer "F.Fab")
		)
		(fp_line
			(start -0.12065 0.3048)
			(end -0.67945 0.3048)
			(stroke
				(width 0.1)
				(type default)
			)
			(layer "F.Fab")
		)
		(fp_line
			(start 0.120396 0.3048)
			(end 0.120396 0.2794)
			(stroke
				(width 0.1)
				(type default)
			)
			(layer "F.Fab")
		)
		(fp_line
			(start 0.67945 0.3048)
			(end 0.120396 0.3048)
			(stroke
				(width 0.1)
				(type default)
			)
			(layer "F.Fab")
		)
		(fp_line
			(start -0.12065 0.2794)
			(end -0.12065 0.3048)
			(stroke
				(width 0.1)
				(type default)
			)
			(layer "F.Fab")
		)
		(fp_line
			(start 0.120396 0.2794)
			(end -0.12065 0.2794)
			(stroke
				(width 0.1)
				(type default)
			)
			(layer "F.Fab")
		)
		(fp_line
			(start -0.12065 -0.2794)
			(end 0.12065 -0.2794)
			(stroke
				(width 0.1)
				(type default)
			)
			(layer "F.Fab")
		)
		(fp_line
			(start 0.12065 -0.2794)
			(end 0.12065 -0.3048)
			(stroke
				(width 0.1)
				(type default)
			)
			(layer "F.Fab")
		)
		(fp_line
			(start 0.12065 -0.3048)
			(end 0.67945 -0.3048)
			(stroke
				(width 0.1)
				(type default)
			)
			(layer "F.Fab")
		)
		(fp_line
			(start 0.67945 -0.3048)
			(end 0.67945 0.3048)
			(stroke
				(width 0.1)
				(type default)
			)
			(layer "F.Fab")
		)
		(fp_line
			(start -0.67945 -0.305054)
			(end -0.12065 -0.305054)
			(stroke
				(width 0.1)
				(type default)
			)
			(layer "F.Fab")
		)
		(fp_line
			(start -0.12065 -0.305054)
			(end -0.12065 -0.2794)
			(stroke
				(width 0.1)
				(type default)
			)
			(layer "F.Fab")
		)
		(pad "1" smd circle
			(at -0.40005 0 270)
			(size 0 0)
			(layers "F.Cu" "F.Mask" "F.Paste")
			(net "P3V3_AUX")
		)
		(pad "2" smd circle
			(at 0.40005 0 270)
			(size 0 0)
			(layers "F.Cu" "F.Mask" "F.Paste")
			(net "RST_MB_PERST_0_ISO_R_N")
		)
	)
	(footprint ""
		(layer "F.Cu")
		(at 281.856434 -20.467574 180)
		(property "Reference" "R1692"
			(at 0 0 180)
			(layer "F.SilkS")
			(hide yes)
			(effects
				(font
					(size 1.27 1.27)
				)
			)
		)
		(property "Value" ""
			(at 0 0 180)
			(layer "F.Fab")
			(effects
				(font
					(size 1.27 1.27)
				)
			)
		)
		(duplicate_pad_numbers_are_jumpers no)
		(fp_line
			(start 0.7874 0.4064)
			(end -0.7874 0.4064)
			(stroke
				(width 0.1524)
				(type default)
			)
			(layer "F.SilkS")
		)
		(fp_line
			(start 0.7874 -0.4064)
			(end 0.7874 0.4064)
			(stroke
				(width 0.1524)
				(type default)
			)
			(layer "F.SilkS")
		)
		(fp_line
			(start -0.7874 0.4064)
			(end -0.7874 -0.4064)
			(stroke
				(width 0.1524)
				(type default)
			)
			(layer "F.SilkS")
		)
		(fp_line
			(start -0.7874 -0.4064)
			(end 0.7874 -0.4064)
			(stroke
				(width 0.1524)
				(type default)
			)
			(layer "F.SilkS")
		)
		(fp_line
			(start 0.67945 0.3048)
			(end 0.120396 0.3048)
			(stroke
				(width 0.1)
				(type default)
			)
			(layer "F.Fab")
		)
		(fp_line
			(start 0.67945 -0.3048)
			(end 0.67945 0.3048)
			(stroke
				(width 0.1)
				(type default)
			)
			(layer "F.Fab")
		)
		(fp_line
			(start 0.12065 -0.2794)
			(end 0.12065 -0.3048)
			(stroke
				(width 0.1)
				(type default)
			)
			(layer "F.Fab")
		)
		(fp_line
			(start 0.12065 -0.3048)
			(end 0.67945 -0.3048)
			(stroke
				(width 0.1)
				(type default)
			)
			(layer "F.Fab")
		)
		(fp_line
			(start 0.120396 0.3048)
			(end 0.120396 0.2794)
			(stroke
				(width 0.1)
				(type default)
			)
			(layer "F.Fab")
		)
		(fp_line
			(start 0.120396 0.2794)
			(end -0.12065 0.2794)
			(stroke
				(width 0.1)
				(type default)
			)
			(layer "F.Fab")
		)
		(fp_line
			(start -0.12065 0.3048)
			(end -0.67945 0.3048)
			(stroke
				(width 0.1)
				(type default)
			)
			(layer "F.Fab")
		)
		(fp_line
			(start -0.12065 0.2794)
			(end -0.12065 0.3048)
			(stroke
				(width 0.1)
				(type default)
			)
			(layer "F.Fab")
		)
		(fp_line
			(start -0.12065 -0.2794)
			(end 0.12065 -0.2794)
			(stroke
				(width 0.1)
				(type default)
			)
			(layer "F.Fab")
		)
		(fp_line
			(start -0.12065 -0.305054)
			(end -0.12065 -0.2794)
			(stroke
				(width 0.1)
				(type default)
			)
			(layer "F.Fab")
		)
		(fp_line
			(start -0.67945 0.3048)
			(end -0.67945 -0.305054)
			(stroke
				(width 0.1)
				(type default)
			)
			(layer "F.Fab")
		)
		(fp_line
			(start -0.67945 -0.305054)
			(end -0.12065 -0.305054)
			(stroke
				(width 0.1)
				(type default)
			)
			(layer "F.Fab")
		)
		(pad "1" smd circle
			(at -0.40005 0 180)
			(size 0 0)
			(layers "F.Cu" "F.Mask" "F.Paste")
			(net "P3V3_SSD9")
		)
		(pad "2" smd circle
			(at 0.40005 0 180)
			(size 0 0)
			(layers "F.Cu" "F.Mask" "F.Paste")
			(net "SMB_ISO_SSD9_SDA")
		)
	)
	(footprint ""
		(layer "F.Cu")
		(at 18.431256 -123.903994 -90)
		(property "Reference" "PC453"
			(at 0 0 270)
			(layer "F.SilkS")
			(hide yes)
			(effects
				(font
					(size 1.27 1.27)
				)
			)
		)
		(property "Value" ""
			(at 0 0 270)
			(layer "F.Fab")
			(effects
				(font
					(size 1.27 1.27)
				)
			)
		)
		(duplicate_pad_numbers_are_jumpers no)
		(fp_line
			(start -1.524 0.762)
			(end -1.524 -0.762)
			(stroke
				(width 0.1524)
				(type default)
			)
			(layer "F.SilkS")
		)
		(fp_line
			(start 1.524 0.762)
			(end -1.524 0.762)
			(stroke
				(width 0.1524)
				(type default)
			)
			(layer "F.SilkS")
		)
		(fp_line
			(start -1.524 -0.762)
			(end 1.524 -0.762)
			(stroke
				(width 0.1524)
				(type default)
			)
			(layer "F.SilkS")
		)
		(fp_line
			(start 1.524 -0.762)
			(end 1.524 0.762)
			(stroke
				(width 0.1524)
				(type default)
			)
			(layer "F.SilkS")
		)
		(fp_line
			(start -1.1049 0.724916)
			(end 1.1049 0.724916)
			(stroke
				(width 0.1)
				(type default)
			)
			(layer "F.Fab")
		)
		(fp_line
			(start 1.1049 0.724916)
			(end 1.1049 -0.724916)
			(stroke
				(width 0.1)
				(type default)
			)
			(layer "F.Fab")
		)
		(fp_line
			(start -1.1049 -0.724916)
			(end -1.1049 0.724916)
			(stroke
				(width 0.1)
				(type default)
			)
			(layer "F.Fab")
		)
		(fp_line
			(start 1.1049 -0.724916)
			(end -1.1049 -0.724916)
			(stroke
				(width 0.1)
				(type default)
			)
			(layer "F.Fab")
		)
		(pad "1" smd rect
			(at -0.889 0 90)
			(size 1.016 1.27)
			(layers "F.Cu" "F.Mask" "F.Paste")
			(net "P3V3_NIC0")
		)
		(pad "2" smd rect
			(at 0.889 0 90)
			(size 1.016 1.27)
			(layers "F.Cu" "F.Mask" "F.Paste")
			(net "GND")
		)
	)
	(footprint ""
		(layer "F.Cu")
		(at 263.496044 -77.279754 90)
		(property "Reference" "R1075"
			(at 0 0 90)
			(layer "F.SilkS")
			(hide yes)
			(effects
				(font
					(size 1.27 1.27)
				)
			)
		)
		(property "Value" ""
			(at 0 0 90)
			(layer "F.Fab")
			(effects
				(font
					(size 1.27 1.27)
				)
			)
		)
		(duplicate_pad_numbers_are_jumpers no)
		(fp_line
			(start 0.7874 0.4064)
			(end -0.7874 0.4064)
			(stroke
				(width 0.1524)
				(type default)
			)
			(layer "F.SilkS")
		)
		(fp_line
			(start -0.12065 -0.305054)
			(end -0.12065 -0.2794)
			(stroke
				(width 0.1)
				(type default)
			)
			(layer "F.Fab")
		)
		(fp_line
			(start -0.67945 -0.305054)
			(end -0.12065 -0.305054)
			(stroke
				(width 0.1)
				(type default)
			)
			(layer "F.Fab")
		)
		(fp_line
			(start 0.67945 -0.3048)
			(end 0.67945 0.3048)
			(stroke
				(width 0.1)
				(type default)
			)
			(layer "F.Fab")
		)
		(fp_line
			(start 0.12065 -0.3048)
			(end 0.67945 -0.3048)
			(stroke
				(width 0.1)
				(type default)
			)
			(layer "F.Fab")
		)
		(fp_line
			(start 0.12065 -0.2794)
			(end 0.12065 -0.3048)
			(stroke
				(width 0.1)
				(type default)
			)
			(layer "F.Fab")
		)
		(fp_line
			(start -0.12065 -0.2794)
			(end 0.12065 -0.2794)
			(stroke
				(width 0.1)
				(type default)
			)
			(layer "F.Fab")
		)
		(fp_line
			(start 0.120396 0.2794)
			(end -0.12065 0.2794)
			(stroke
				(width 0.1)
				(type default)
			)
			(layer "F.Fab")
		)
		(fp_line
			(start -0.12065 0.2794)
			(end -0.12065 0.3048)
			(stroke
				(width 0.1)
				(type default)
			)
			(layer "F.Fab")
		)
		(fp_line
			(start 0.67945 0.3048)
			(end 0.120396 0.3048)
			(stroke
				(width 0.1)
				(type default)
			)
			(layer "F.Fab")
		)
		(fp_line
			(start 0.120396 0.3048)
			(end 0.120396 0.2794)
			(stroke
				(width 0.1)
				(type default)
			)
			(layer "F.Fab")
		)
		(fp_line
			(start -0.12065 0.3048)
			(end -0.67945 0.3048)
			(stroke
				(width 0.1)
				(type default)
			)
			(layer "F.Fab")
		)
		(fp_line
			(start -0.67945 0.3048)
			(end -0.67945 -0.305054)
			(stroke
				(width 0.1)
				(type default)
			)
			(layer "F.Fab")
		)
		(pad "1" smd circle
			(at -0.40005 0 90)
			(size 0 0)
			(layers "F.Cu" "F.Mask" "F.Paste")
			(net "CLK_100M_CK440Q_2_DB800ZL_R_DP")
		)
		(pad "2" smd circle
			(at 0.40005 0 90)
			(size 0 0)
			(layers "F.Cu" "F.Mask" "F.Paste")
			(net "CLK_100M_CK440Q_2_DB800ZL_DP")
		)
	)
	(footprint ""
		(layer "F.Cu")
		(at 4.297426 -40.6654)
		(property "Reference" "PU81"
			(at -2.242566 -2.831338 90)
			(unlocked yes)
			(layer "F.SilkS")
			(effects
				(font
					(size 0.7874 0.5842)
					(thickness 0.1524)
				)
			)
		)
		(property "Value" ""
			(at 0 0 0)
			(layer "F.Fab")
			(effects
				(font
					(size 1.27 1.27)
				)
			)
		)
		(duplicate_pad_numbers_are_jumpers no)
		(fp_line
			(start -1.239774 -1.495298)
			(end 1.239774 -1.495298)
			(stroke
				(width 0.1524)
				(type default)
			)
			(layer "F.SilkS")
		)
		(fp_line
			(start -1.239774 1.495298)
			(end -1.239774 -1.495298)
			(stroke
				(width 0.1524)
				(type default)
			)
			(layer "F.SilkS")
		)
		(fp_line
			(start 1.239774 -1.495298)
			(end 1.239774 1.495298)
			(stroke
				(width 0.1524)
				(type default)
			)
			(layer "F.SilkS")
		)
		(fp_line
			(start 1.239774 1.495298)
			(end -1.239774 1.495298)
			(stroke
				(width 0.1524)
				(type default)
			)
			(layer "F.SilkS")
		)
		(fp_poly
			(pts
				(xy -2.195576 -1.29921) (xy -2.914142 -0.580644) (xy -1.83642 -0.221488)
			)
			(stroke
				(width 0)
				(type default)
			)
			(fill yes)
			(layer "F.SilkS")
		)
		(fp_line
			(start -0.8001 -1.050036)
			(end 0.8001 -1.050036)
			(stroke
				(width 0.1)
				(type default)
			)
			(layer "F.Fab")
		)
		(fp_line
			(start -0.8001 1.050036)
			(end -0.8001 -1.050036)
			(stroke
				(width 0.1)
				(type default)
			)
			(layer "F.Fab")
		)
		(fp_line
			(start 0.8001 -1.050036)
			(end 0.8001 1.050036)
			(stroke
				(width 0.1)
				(type default)
			)
			(layer "F.Fab")
		)
		(fp_line
			(start 0.8001 1.050036)
			(end -0.8001 1.050036)
			(stroke
				(width 0.1)
				(type default)
			)
			(layer "F.Fab")
		)
		(fp_poly
			(pts
				(xy -2.458974 -0.508) (xy -2.458974 0.508) (xy -1.442974 0)
			)
			(stroke
				(width 0)
				(type default)
			)
			(fill yes)
			(layer "F.Fab")
		)
		(pad "1_2" smd circle
			(at -0.374904 0 90)
			(size 0 0)
			(layers "F.Cu" "F.Mask" "F.Paste")
			(net "P3V3_AUX")
		)
		(pad "3" smd rect
			(at -0.499872 0.999998)
			(size 0.254 0.7112)
			(layers "F.Cu" "F.Mask" "F.Paste")
			(net "GND")
		)
		(pad "4" smd rect
			(at 0 0.999998)
			(size 0.254 0.7112)
			(layers "F.Cu" "F.Mask" "F.Paste")
			(net "P3V3_SSD0_CO_ILIMIT")
		)
		(pad "5" smd rect
			(at 0.499872 0.999998)
			(size 0.254 0.7112)
			(layers "F.Cu" "F.Mask" "F.Paste")
			(net "P3V3_SSD0_CO_MODE")
		)
		(pad "6_7" smd circle
			(at 0.374904 0 270)
			(size 0 0)
			(layers "F.Cu" "F.Mask" "F.Paste")
			(net "P3V3_SSD0")
		)
		(pad "8" smd rect
			(at 0.499872 -0.999998)
			(size 0.254 0.7112)
			(layers "F.Cu" "F.Mask" "F.Paste")
			(net "P3V3_SSD0_CO_GATE")
		)
		(pad "9" smd rect
			(at 0 -0.999998)
			(size 0.254 0.7112)
			(layers "F.Cu" "F.Mask" "F.Paste")
			(net "P3V3_SSD0_CO_EN")
		)
		(pad "10" smd rect
			(at -0.499872 -0.999998)
			(size 0.254 0.7112)
			(layers "F.Cu" "F.Mask" "F.Paste")
			(net "P3V3_SSD0_CO_DV_DT")
		)
	)
	(footprint ""
		(layer "F.Cu")
		(at 91.992704 -118.446804)
		(property "Reference" "PC663"
			(at 0 0 0)
			(layer "F.SilkS")
			(hide yes)
			(effects
				(font
					(size 1.27 1.27)
				)
			)
		)
		(property "Value" ""
			(at 0 0 0)
			(layer "F.Fab")
			(effects
				(font
					(size 1.27 1.27)
				)
			)
		)
		(duplicate_pad_numbers_are_jumpers no)
		(fp_line
			(start -1.524 -0.762)
			(end 1.524 -0.762)
			(stroke
				(width 0.1524)
				(type default)
			)
			(layer "F.SilkS")
		)
		(fp_line
			(start -1.524 0.762)
			(end -1.524 -0.762)
			(stroke
				(width 0.1524)
				(type default)
			)
			(layer "F.SilkS")
		)
		(fp_line
			(start 1.524 -0.762)
			(end 1.524 0.762)
			(stroke
				(width 0.1524)
				(type default)
			)
			(layer "F.SilkS")
		)
		(fp_line
			(start 1.524 0.762)
			(end -1.524 0.762)
			(stroke
				(width 0.1524)
				(type default)
			)
			(layer "F.SilkS")
		)
		(fp_line
			(start -1.1049 -0.724916)
			(end -1.1049 0.724916)
			(stroke
				(width 0.1)
				(type default)
			)
			(layer "F.Fab")
		)
		(fp_line
			(start -1.1049 0.724916)
			(end 1.1049 0.724916)
			(stroke
				(width 0.1)
				(type default)
			)
			(layer "F.Fab")
		)
		(fp_line
			(start 1.1049 -0.724916)
			(end -1.1049 -0.724916)
			(stroke
				(width 0.1)
				(type default)
			)
			(layer "F.Fab")
		)
		(fp_line
			(start 1.1049 0.724916)
			(end 1.1049 -0.724916)
			(stroke
				(width 0.1)
				(type default)
			)
			(layer "F.Fab")
		)
		(pad "1" smd rect
			(at -0.889 0 180)
			(size 1.016 1.27)
			(layers "F.Cu" "F.Mask" "F.Paste")
			(net "P3V3_NIC1")
		)
		(pad "2" smd rect
			(at 0.889 0 180)
			(size 1.016 1.27)
			(layers "F.Cu" "F.Mask" "F.Paste")
			(net "GND")
		)
	)
	(footprint ""
		(layer "F.Cu")
		(at 102.1588 -200.406)
		(property "Reference" "C4446"
			(at 0 0 0)
			(layer "F.SilkS")
			(hide yes)
			(effects
				(font
					(size 1.27 1.27)
				)
			)
		)
		(property "Value" ""
			(at 0 0 0)
			(layer "F.Fab")
			(effects
				(font
					(size 1.27 1.27)
				)
			)
		)
		(duplicate_pad_numbers_are_jumpers no)
		(fp_line
			(start -0.7874 -0.4064)
			(end 0.7874 -0.4064)
			(stroke
				(width 0.1524)
				(type default)
			)
			(layer "F.SilkS")
		)
		(fp_line
			(start -0.7874 0.4064)
			(end -0.7874 -0.4064)
			(stroke
				(width 0.1524)
				(type default)
			)
			(layer "F.SilkS")
		)
		(fp_line
			(start 0.7874 -0.4064)
			(end 0.7874 0.4064)
			(stroke
				(width 0.1524)
				(type default)
			)
			(layer "F.SilkS")
		)
		(fp_line
			(start 0.7874 0.4064)
			(end -0.7874 0.4064)
			(stroke
				(width 0.1524)
				(type default)
			)
			(layer "F.SilkS")
		)
		(fp_line
			(start -0.67945 -0.305054)
			(end -0.12065 -0.305054)
			(stroke
				(width 0.1)
				(type default)
			)
			(layer "F.Fab")
		)
		(fp_line
			(start -0.67945 0.3048)
			(end -0.67945 -0.305054)
			(stroke
				(width 0.1)
				(type default)
			)
			(layer "F.Fab")
		)
		(fp_line
			(start -0.12065 -0.305054)
			(end -0.12065 -0.2794)
			(stroke
				(width 0.1)
				(type default)
			)
			(layer "F.Fab")
		)
		(fp_line
			(start -0.12065 -0.2794)
			(end 0.12065 -0.2794)
			(stroke
				(width 0.1)
				(type default)
			)
			(layer "F.Fab")
		)
		(fp_line
			(start -0.12065 0.2794)
			(end -0.12065 0.3048)
			(stroke
				(width 0.1)
				(type default)
			)
			(layer "F.Fab")
		)
		(fp_line
			(start -0.12065 0.3048)
			(end -0.67945 0.3048)
			(stroke
				(width 0.1)
				(type default)
			)
			(layer "F.Fab")
		)
		(fp_line
			(start 0.120396 0.2794)
			(end -0.12065 0.2794)
			(stroke
				(width 0.1)
				(type default)
			)
			(layer "F.Fab")
		)
		(fp_line
			(start 0.120396 0.3048)
			(end 0.120396 0.2794)
			(stroke
				(width 0.1)
				(type default)
			)
			(layer "F.Fab")
		)
		(fp_line
			(start 0.12065 -0.3048)
			(end 0.67945 -0.3048)
			(stroke
				(width 0.1)
				(type default)
			)
			(layer "F.Fab")
		)
		(fp_line
			(start 0.12065 -0.2794)
			(end 0.12065 -0.3048)
			(stroke
				(width 0.1)
				(type default)
			)
			(layer "F.Fab")
		)
		(fp_line
			(start 0.67945 -0.3048)
			(end 0.67945 0.3048)
			(stroke
				(width 0.1)
				(type default)
			)
			(layer "F.Fab")
		)
		(fp_line
			(start 0.67945 0.3048)
			(end 0.120396 0.3048)
			(stroke
				(width 0.1)
				(type default)
			)
			(layer "F.Fab")
		)
		(pad "1" smd circle
			(at -0.40005 0)
			(size 0 0)
			(layers "F.Cu" "F.Mask" "F.Paste")
			(net "P3V3_AUX")
		)
		(pad "2" smd circle
			(at 0.40005 0)
			(size 0 0)
			(layers "F.Cu" "F.Mask" "F.Paste")
			(net "GND")
		)
	)
	(footprint ""
		(layer "F.Cu")
		(at 323.164708 -26.785062 180)
		(property "Reference" "J41"
			(at 4.551934 -10.961116 90)
			(unlocked yes)
			(layer "F.SilkS")
			(effects
				(font
					(size 0.7874 0.5842)
					(thickness 0.1524)
				)
			)
		)
		(property "Value" ""
			(at 0 0 180)
			(layer "F.Fab")
			(effects
				(font
					(size 1.27 1.27)
				)
			)
		)
		(duplicate_pad_numbers_are_jumpers no)
		(fp_line
			(start 3.150108 12.115038)
			(end 1.529334 12.115038)
			(stroke
				(width 0.1524)
				(type default)
			)
			(layer "F.SilkS")
		)
		(fp_line
			(start 3.074924 12.014962)
			(end 1.632204 12.014962)
			(stroke
				(width 0.1524)
				(type default)
			)
			(layer "F.SilkS")
		)
		(fp_line
			(start 1.632204 -12.014962)
			(end 3.074924 -12.014962)
			(stroke
				(width 0.1524)
				(type default)
			)
			(layer "F.SilkS")
		)
		(fp_line
			(start 1.529334 -12.115038)
			(end 3.150108 -12.115038)
			(stroke
				(width 0.1524)
				(type default)
			)
			(layer "F.SilkS")
		)
		(fp_line
			(start -1.529334 12.115038)
			(end -3.150108 12.115038)
			(stroke
				(width 0.1524)
				(type default)
			)
			(layer "F.SilkS")
		)
		(fp_line
			(start -1.632204 12.014962)
			(end -3.074924 12.014962)
			(stroke
				(width 0.1524)
				(type default)
			)
			(layer "F.SilkS")
		)
		(fp_line
			(start -3.074924 -12.014962)
			(end -1.632204 -12.014962)
			(stroke
				(width 0.1524)
				(type default)
			)
			(layer "F.SilkS")
		)
		(fp_line
			(start -3.150108 -12.115038)
			(end -1.529334 -12.115038)
			(stroke
				(width 0.1524)
				(type default)
			)
			(layer "F.SilkS")
		)
		(fp_poly
			(pts
				(xy 3.360674 -8.78713) (xy 3.783076 -10.054844) (xy 4.628134 -9.209786)
			)
			(stroke
				(width 0)
				(type default)
			)
			(fill yes)
			(layer "F.SilkS")
		)
		(fp_line
			(start 3.074924 12.014962)
			(end -3.074924 12.014962)
			(stroke
				(width 0.1)
				(type default)
			)
			(layer "F.Fab")
		)
		(fp_line
			(start 3.074924 -12.014962)
			(end 3.074924 12.014962)
			(stroke
				(width 0.1)
				(type default)
			)
			(layer "F.Fab")
		)
		(fp_line
			(start -3.074924 12.014962)
			(end -3.074924 -12.014962)
			(stroke
				(width 0.1)
				(type default)
			)
			(layer "F.Fab")
		)
		(fp_line
			(start -3.074924 -12.014962)
			(end 3.074924 -12.014962)
			(stroke
				(width 0.1)
				(type default)
			)
			(layer "F.Fab")
		)
		(fp_poly
			(pts
				(xy 3.348736 -7.994904) (xy 4.543806 -8.592566) (xy 4.543806 -7.397496)
			)
			(stroke
				(width 0)
				(type default)
			)
			(fill yes)
			(layer "F.Fab")
		)
		(pad "" np_thru_hole circle
			(at -1.75006 -9.815068 90)
			(size 1.1176 1.1176)
			(drill 1.1176)
			(layers "*.Cu" "*.Mask")
			(clearance 0.381)
			(thermal_gap 0.381)
		)
		(pad "" np_thru_hole circle
			(at 0 9.815068 90)
			(size 1.1176 1.1176)
			(drill 1.1176)
			(layers "*.Cu" "*.Mask")
			(clearance 0.381)
			(thermal_gap 0.381)
		)
		(pad "A1" smd rect
			(at 2.29997 -7.994904 90)
			(size 0.381 1.27)
			(layers "F.Cu" "F.Mask" "F.Paste")
			(net "GND")
		)
		(pad "A2" smd rect
			(at 2.29997 -7.394956 90)
			(size 0.381 1.27)
			(layers "F.Cu" "F.Mask" "F.Paste")
			(net "GND")
		)
		(pad "A3" smd rect
			(at 2.29997 -6.795008 90)
			(size 0.381 1.27)
			(layers "F.Cu" "F.Mask" "F.Paste")
			(net "GND")
		)
		(pad "A4" smd rect
			(at 2.29997 -6.19506 90)
			(size 0.381 1.27)
			(layers "F.Cu" "F.Mask" "F.Paste")
			(net "GND")
		)
		(pad "A5" smd rect
			(at 2.29997 -5.595112 90)
			(size 0.381 1.27)
			(layers "F.Cu" "F.Mask" "F.Paste")
			(net "GND")
		)
		(pad "A6" smd rect
			(at 2.29997 -4.99491 90)
			(size 0.381 1.27)
			(layers "F.Cu" "F.Mask" "F.Paste")
			(net "GND")
		)
		(pad "A7" smd rect
			(at 2.29997 -4.394962 90)
			(size 0.381 1.27)
			(layers "F.Cu" "F.Mask" "F.Paste")
			(net "SMB_ISO_SSD11_R_SCL")
		)
		(pad "A8" smd rect
			(at 2.29997 -3.795014 90)
			(size 0.381 1.27)
			(layers "F.Cu" "F.Mask" "F.Paste")
			(net "SMB_ISO_SSD11_R_SDA")
		)
		(pad "A9" smd rect
			(at 2.29997 -3.195066 90)
			(size 0.381 1.27)
			(layers "F.Cu" "F.Mask" "F.Paste")
			(net "RST_SMB_SSD11_ISO_R_N")
		)
		(pad "A10" smd rect
			(at 2.29997 -2.595118 90)
			(size 0.381 1.27)
			(layers "F.Cu" "F.Mask" "F.Paste")
			(net "SSD11_LED_ISO_R_N")
		)
		(pad "A11" smd rect
			(at 2.29997 -1.994916 90)
			(size 0.381 1.27)
			(layers "F.Cu" "F.Mask" "F.Paste")
			(net "PU_CLKREQ11")
		)
		(pad "A12" smd rect
			(at 2.29997 -1.394968 90)
			(size 0.381 1.27)
			(layers "F.Cu" "F.Mask" "F.Paste")
			(net "PRSNT_SSD11_N")
		)
		(pad "A13" smd rect
			(at 2.29997 -0.79502 90)
			(size 0.381 1.27)
			(layers "F.Cu" "F.Mask" "F.Paste")
			(net "GND")
		)
		(pad "A14" smd rect
			(at 2.29997 -0.195072 90)
			(size 0.381 1.27)
			(layers "F.Cu" "F.Mask" "F.Paste")
			(net "Net_8483")
		)
		(pad "A15" smd rect
			(at 2.29997 0.404876 90)
			(size 0.381 1.27)
			(layers "F.Cu" "F.Mask" "F.Paste")
			(net "Net_8482")
		)
		(pad "A16" smd rect
			(at 2.29997 1.005078 90)
			(size 0.381 1.27)
			(layers "F.Cu" "F.Mask" "F.Paste")
			(net "GND")
		)
		(pad "A17" smd rect
			(at 2.29997 1.605026 90)
			(size 0.381 1.27)
			(layers "F.Cu" "F.Mask" "F.Paste")
			(net "P5E_PEX2_STN2_RX_DN<32>")
		)
		(pad "A18" smd rect
			(at 2.29997 2.204974 90)
			(size 0.381 1.27)
			(layers "F.Cu" "F.Mask" "F.Paste")
			(net "P5E_PEX2_STN2_RX_DP<32>")
		)
		(pad "A19" smd rect
			(at 2.29997 2.804922 90)
			(size 0.381 1.27)
			(layers "F.Cu" "F.Mask" "F.Paste")
			(net "GND")
		)
		(pad "A20" smd rect
			(at 2.29997 3.405124 90)
			(size 0.381 1.27)
			(layers "F.Cu" "F.Mask" "F.Paste")
			(net "P5E_PEX2_STN2_RX_DN<33>")
		)
		(pad "A21" smd rect
			(at 2.29997 4.005072 90)
			(size 0.381 1.27)
			(layers "F.Cu" "F.Mask" "F.Paste")
			(net "P5E_PEX2_STN2_RX_DP<33>")
		)
		(pad "A22" smd rect
			(at 2.29997 4.60502 90)
			(size 0.381 1.27)
			(layers "F.Cu" "F.Mask" "F.Paste")
			(net "GND")
		)
		(pad "A23" smd rect
			(at 2.29997 5.204968 90)
			(size 0.381 1.27)
			(layers "F.Cu" "F.Mask" "F.Paste")
			(net "P5E_PEX2_STN2_RX_DN<34>")
		)
		(pad "A24" smd rect
			(at 2.29997 5.804916 90)
			(size 0.381 1.27)
			(layers "F.Cu" "F.Mask" "F.Paste")
			(net "P5E_PEX2_STN2_RX_DP<34>")
		)
		(pad "A25" smd rect
			(at 2.29997 6.405118 90)
			(size 0.381 1.27)
			(layers "F.Cu" "F.Mask" "F.Paste")
			(net "GND")
		)
		(pad "A26" smd rect
			(at 2.29997 7.005066 90)
			(size 0.381 1.27)
			(layers "F.Cu" "F.Mask" "F.Paste")
			(net "P5E_PEX2_STN2_RX_DN<35>")
		)
		(pad "A27" smd rect
			(at 2.29997 7.605014 90)
			(size 0.381 1.27)
			(layers "F.Cu" "F.Mask" "F.Paste")
			(net "P5E_PEX2_STN2_RX_DP<35>")
		)
		(pad "A28" smd rect
			(at 2.29997 8.204962 90)
			(size 0.381 1.27)
			(layers "F.Cu" "F.Mask" "F.Paste")
			(net "GND")
		)
		(pad "B1" smd rect
			(at -2.29997 -7.994904 90)
			(size 0.381 1.27)
			(layers "F.Cu" "F.Mask" "F.Paste")
			(net "P12V_SSD11")
		)
		(pad "B2" smd rect
			(at -2.29997 -7.394956 90)
			(size 0.381 1.27)
			(layers "F.Cu" "F.Mask" "F.Paste")
			(net "P12V_SSD11")
		)
		(pad "B3" smd rect
			(at -2.29997 -6.795008 90)
			(size 0.381 1.27)
			(layers "F.Cu" "F.Mask" "F.Paste")
			(net "P12V_SSD11")
		)
		(pad "B4" smd rect
			(at -2.29997 -6.19506 90)
			(size 0.381 1.27)
			(layers "F.Cu" "F.Mask" "F.Paste")
			(net "P12V_SSD11")
		)
		(pad "B5" smd rect
			(at -2.29997 -5.595112 90)
			(size 0.381 1.27)
			(layers "F.Cu" "F.Mask" "F.Paste")
			(net "P12V_SSD11")
		)
		(pad "B6" smd rect
			(at -2.29997 -4.99491 90)
			(size 0.381 1.27)
			(layers "F.Cu" "F.Mask" "F.Paste")
			(net "P12V_SSD11")
		)
		(pad "B7" smd rect
			(at -2.29997 -4.394962 90)
			(size 0.381 1.27)
			(layers "F.Cu" "F.Mask" "F.Paste")
			(net "Net_8484")
		)
		(pad "B8" smd rect
			(at -2.29997 -3.795014 90)
			(size 0.381 1.27)
			(layers "F.Cu" "F.Mask" "F.Paste")
			(net "Net_8481")
		)
		(pad "B9" smd rect
			(at -2.29997 -3.195066 90)
			(size 0.381 1.27)
			(layers "F.Cu" "F.Mask" "F.Paste")
			(net "DUALPORT_N_SSD11")
		)
		(pad "B10" smd rect
			(at -2.29997 -2.595118 90)
			(size 0.381 1.27)
			(layers "F.Cu" "F.Mask" "F.Paste")
			(net "RST_SSD11_PERST_R_N")
		)
		(pad "B11" smd rect
			(at -2.29997 -1.994916 90)
			(size 0.381 1.27)
			(layers "F.Cu" "F.Mask" "F.Paste")
			(net "P3V3_SSD11")
		)
		(pad "B12" smd rect
			(at -2.29997 -1.394968 90)
			(size 0.381 1.27)
			(layers "F.Cu" "F.Mask" "F.Paste")
			(net "SSD11_PWRDIS_R")
		)
		(pad "B13" smd rect
			(at -2.29997 -0.79502 90)
			(size 0.381 1.27)
			(layers "F.Cu" "F.Mask" "F.Paste")
			(net "GND")
		)
		(pad "B14" smd rect
			(at -2.29997 -0.195072 90)
			(size 0.381 1.27)
			(layers "F.Cu" "F.Mask" "F.Paste")
			(net "CLK_100M_DB800ZL_SSD11_R_DN")
		)
		(pad "B15" smd rect
			(at -2.29997 0.404876 90)
			(size 0.381 1.27)
			(layers "F.Cu" "F.Mask" "F.Paste")
			(net "CLK_100M_DB800ZL_SSD11_R_DP")
		)
		(pad "B16" smd rect
			(at -2.29997 1.005078 90)
			(size 0.381 1.27)
			(layers "F.Cu" "F.Mask" "F.Paste")
			(net "GND")
		)
		(pad "B17" smd rect
			(at -2.29997 1.605026 90)
			(size 0.381 1.27)
			(layers "F.Cu" "F.Mask" "F.Paste")
			(net "P5E_PEX2_STN2_TX_C_DN<32>")
		)
		(pad "B18" smd rect
			(at -2.29997 2.204974 90)
			(size 0.381 1.27)
			(layers "F.Cu" "F.Mask" "F.Paste")
			(net "P5E_PEX2_STN2_TX_C_DP<32>")
		)
		(pad "B19" smd rect
			(at -2.29997 2.804922 90)
			(size 0.381 1.27)
			(layers "F.Cu" "F.Mask" "F.Paste")
			(net "GND")
		)
		(pad "B20" smd rect
			(at -2.29997 3.405124 90)
			(size 0.381 1.27)
			(layers "F.Cu" "F.Mask" "F.Paste")
			(net "P5E_PEX2_STN2_TX_C_DN<33>")
		)
		(pad "B21" smd rect
			(at -2.29997 4.005072 90)
			(size 0.381 1.27)
			(layers "F.Cu" "F.Mask" "F.Paste")
			(net "P5E_PEX2_STN2_TX_C_DP<33>")
		)
		(pad "B22" smd rect
			(at -2.29997 4.60502 90)
			(size 0.381 1.27)
			(layers "F.Cu" "F.Mask" "F.Paste")
			(net "GND")
		)
		(pad "B23" smd rect
			(at -2.29997 5.204968 90)
			(size 0.381 1.27)
			(layers "F.Cu" "F.Mask" "F.Paste")
			(net "P5E_PEX2_STN2_TX_C_DN<34>")
		)
		(pad "B24" smd rect
			(at -2.29997 5.804916 90)
			(size 0.381 1.27)
			(layers "F.Cu" "F.Mask" "F.Paste")
			(net "P5E_PEX2_STN2_TX_C_DP<34>")
		)
		(pad "B25" smd rect
			(at -2.29997 6.405118 90)
			(size 0.381 1.27)
			(layers "F.Cu" "F.Mask" "F.Paste")
			(net "GND")
		)
		(pad "B26" smd rect
			(at -2.29997 7.005066 90)
			(size 0.381 1.27)
			(layers "F.Cu" "F.Mask" "F.Paste")
			(net "P5E_PEX2_STN2_TX_C_DN<35>")
		)
		(pad "B27" smd rect
			(at -2.29997 7.605014 90)
			(size 0.381 1.27)
			(layers "F.Cu" "F.Mask" "F.Paste")
			(net "P5E_PEX2_STN2_TX_C_DP<35>")
		)
		(pad "B28" smd rect
			(at -2.29997 8.204962 90)
			(size 0.381 1.27)
			(layers "F.Cu" "F.Mask" "F.Paste")
			(net "GND")
		)
		(pad "G1" thru_hole oval
			(at 0 -11.364976 90)
			(size 1.6256 3.4798)
			(drill oval 1.1176 2.4638)
			(layers "*.Cu" "*.Mask")
			(remove_unused_layers no)
			(net "GND")
			(clearance 0.127)
			(thermal_gap 0.127)
		)
		(pad "G2" thru_hole oval
			(at 0 11.364976 90)
			(size 1.6256 3.4798)
			(drill oval 1.1176 2.4638)
			(layers "*.Cu" "*.Mask")
			(remove_unused_layers no)
			(net "GND")
			(clearance 0.127)
			(thermal_gap 0.127)
		)
		(zone
			(layer "F.Cu")
			(hatch none 0.5)
			(connect_pads
				(clearance 0)
			)
			(min_thickness 0.25)
			(keepout
				(tracks not_allowed)
				(vias allowed)
				(pads allowed)
				(copperpour not_allowed)
				(footprints allowed)
			)
			(placement
				(enabled no)
				(sheetname "")
			)
			(fill
				(thermal_gap 0.5)
				(thermal_bridge_width 0.5)
				(island_removal_mode 0)
			)
			(polygon
				(pts
					(xy 324.54469 -38.850062) (xy 321.794632 -38.850062) (xy 321.794632 -35.900106) (xy 324.54469 -35.900106)
				)
			)
		)
		(zone
			(layer "F.Cu")
			(hatch none 0.5)
			(connect_pads
				(clearance 0)
			)
			(min_thickness 0.25)
			(keepout
				(tracks not_allowed)
				(vias allowed)
				(pads allowed)
				(copperpour not_allowed)
				(footprints allowed)
			)
			(placement
				(enabled no)
				(sheetname "")
			)
			(fill
				(thermal_gap 0.5)
				(thermal_bridge_width 0.5)
				(island_removal_mode 0)
			)
			(polygon
				(pts
					(xy 325.614792 -17.670018) (xy 321.784726 -17.670018) (xy 321.784726 -14.720062) (xy 325.614792 -14.720062)
				)
			)
		)
		(zone
			(layers "F.Cu" "B.Cu" "In1.Cu" "In2.Cu" "In3.Cu" "In4.Cu" "In5.Cu" "In6.Cu"
				"In7.Cu" "In8.Cu" "In9.Cu" "In10.Cu" "In11.Cu" "In12.Cu" "In13.Cu" "In14.Cu"
				"In15.Cu" "In16.Cu"
			)
			(hatch none 0.5)
			(connect_pads
				(clearance 0)
			)
			(min_thickness 0.25)
			(keepout
				(tracks not_allowed)
				(vias allowed)
				(pads allowed)
				(copperpour not_allowed)
				(footprints allowed)
			)
			(placement
				(enabled no)
				(sheetname "")
			)
			(fill
				(thermal_gap 0.5)
				(thermal_bridge_width 0.5)
				(island_removal_mode 0)
			)
			(polygon
				(pts
					(arc
						(start 324.129908 -36.60013)
						(mid 322.199508 -36.60013)
						(end 324.129908 -36.60013)
					)
				)
			)
		)
		(zone
			(layers "F.Cu" "B.Cu" "In1.Cu" "In2.Cu" "In3.Cu" "In4.Cu" "In5.Cu" "In6.Cu"
				"In7.Cu" "In8.Cu" "In9.Cu" "In10.Cu" "In11.Cu" "In12.Cu" "In13.Cu" "In14.Cu"
				"In15.Cu" "In16.Cu"
			)
			(hatch none 0.5)
			(connect_pads
				(clearance 0)
			)
			(min_thickness 0.25)
			(keepout
				(tracks not_allowed)
				(vias allowed)
				(pads allowed)
				(copperpour not_allowed)
				(footprints allowed)
			)
			(placement
				(enabled no)
				(sheetname "")
			)
			(fill
				(thermal_gap 0.5)
				(thermal_bridge_width 0.5)
				(island_removal_mode 0)
			)
			(polygon
				(pts
					(arc
						(start 325.879968 -16.969994)
						(mid 323.949568 -16.969994)
						(end 325.879968 -16.969994)
					)
				)
			)
		)
	)
	(footprint ""
		(layer "F.Cu")
		(at 426.567854 -56.353456)
		(property "Reference" "C2874"
			(at 0 0 0)
			(layer "F.SilkS")
			(hide yes)
			(effects
				(font
					(size 1.27 1.27)
				)
			)
		)
		(property "Value" ""
			(at 0 0 0)
			(layer "F.Fab")
			(effects
				(font
					(size 1.27 1.27)
				)
			)
		)
		(duplicate_pad_numbers_are_jumpers no)
		(fp_line
			(start -0.7874 -0.4064)
			(end 0.7874 -0.4064)
			(stroke
				(width 0.1524)
				(type default)
			)
			(layer "F.SilkS")
		)
		(fp_line
			(start -0.7874 0.4064)
			(end -0.7874 -0.4064)
			(stroke
				(width 0.1524)
				(type default)
			)
			(layer "F.SilkS")
		)
		(fp_line
			(start 0.7874 -0.4064)
			(end 0.7874 0.4064)
			(stroke
				(width 0.1524)
				(type default)
			)
			(layer "F.SilkS")
		)
		(fp_line
			(start 0.7874 0.4064)
			(end -0.7874 0.4064)
			(stroke
				(width 0.1524)
				(type default)
			)
			(layer "F.SilkS")
		)
		(fp_line
			(start -0.67945 -0.305054)
			(end -0.12065 -0.305054)
			(stroke
				(width 0.1)
				(type default)
			)
			(layer "F.Fab")
		)
		(fp_line
			(start -0.67945 0.3048)
			(end -0.67945 -0.305054)
			(stroke
				(width 0.1)
				(type default)
			)
			(layer "F.Fab")
		)
		(fp_line
			(start -0.12065 -0.305054)
			(end -0.12065 -0.2794)
			(stroke
				(width 0.1)
				(type default)
			)
			(layer "F.Fab")
		)
		(fp_line
			(start -0.12065 -0.2794)
			(end 0.12065 -0.2794)
			(stroke
				(width 0.1)
				(type default)
			)
			(layer "F.Fab")
		)
		(fp_line
			(start -0.12065 0.2794)
			(end -0.12065 0.3048)
			(stroke
				(width 0.1)
				(type default)
			)
			(layer "F.Fab")
		)
		(fp_line
			(start -0.12065 0.3048)
			(end -0.67945 0.3048)
			(stroke
				(width 0.1)
				(type default)
			)
			(layer "F.Fab")
		)
		(fp_line
			(start 0.120396 0.2794)
			(end -0.12065 0.2794)
			(stroke
				(width 0.1)
				(type default)
			)
			(layer "F.Fab")
		)
		(fp_line
			(start 0.120396 0.3048)
			(end 0.120396 0.2794)
			(stroke
				(width 0.1)
				(type default)
			)
			(layer "F.Fab")
		)
		(fp_line
			(start 0.12065 -0.3048)
			(end 0.67945 -0.3048)
			(stroke
				(width 0.1)
				(type default)
			)
			(layer "F.Fab")
		)
		(fp_line
			(start 0.12065 -0.2794)
			(end 0.12065 -0.3048)
			(stroke
				(width 0.1)
				(type default)
			)
			(layer "F.Fab")
		)
		(fp_line
			(start 0.67945 -0.3048)
			(end 0.67945 0.3048)
			(stroke
				(width 0.1)
				(type default)
			)
			(layer "F.Fab")
		)
		(fp_line
			(start 0.67945 0.3048)
			(end 0.120396 0.3048)
			(stroke
				(width 0.1)
				(type default)
			)
			(layer "F.Fab")
		)
		(pad "1" smd circle
			(at -0.40005 0)
			(size 0 0)
			(layers "F.Cu" "F.Mask" "F.Paste")
			(net "SSD14_PWR_EN_R")
		)
		(pad "2" smd circle
			(at 0.40005 0)
			(size 0 0)
			(layers "F.Cu" "F.Mask" "F.Paste")
			(net "GND")
		)
	)
	(footprint ""
		(layer "F.Cu")
		(at 453.762364 -22.937216 90)
		(property "Reference" "R1740"
			(at 0 0 90)
			(layer "F.SilkS")
			(hide yes)
			(effects
				(font
					(size 1.27 1.27)
				)
			)
		)
		(property "Value" ""
			(at 0 0 90)
			(layer "F.Fab")
			(effects
				(font
					(size 1.27 1.27)
				)
			)
		)
		(duplicate_pad_numbers_are_jumpers no)
		(fp_line
			(start 0.7874 -0.4064)
			(end 0.7874 0.4064)
			(stroke
				(width 0.1524)
				(type default)
			)
			(layer "F.SilkS")
		)
		(fp_line
			(start -0.7874 -0.4064)
			(end 0.7874 -0.4064)
			(stroke
				(width 0.1524)
				(type default)
			)
			(layer "F.SilkS")
		)
		(fp_line
			(start 0.7874 0.4064)
			(end -0.7874 0.4064)
			(stroke
				(width 0.1524)
				(type default)
			)
			(layer "F.SilkS")
		)
		(fp_line
			(start -0.7874 0.4064)
			(end -0.7874 -0.4064)
			(stroke
				(width 0.1524)
				(type default)
			)
			(layer "F.SilkS")
		)
		(fp_line
			(start -0.12065 -0.305054)
			(end -0.12065 -0.2794)
			(stroke
				(width 0.1)
				(type default)
			)
			(layer "F.Fab")
		)
		(fp_line
			(start -0.67945 -0.305054)
			(end -0.12065 -0.305054)
			(stroke
				(width 0.1)
				(type default)
			)
			(layer "F.Fab")
		)
		(fp_line
			(start 0.67945 -0.3048)
			(end 0.67945 0.3048)
			(stroke
				(width 0.1)
				(type default)
			)
			(layer "F.Fab")
		)
		(fp_line
			(start 0.12065 -0.3048)
			(end 0.67945 -0.3048)
			(stroke
				(width 0.1)
				(type default)
			)
			(layer "F.Fab")
		)
		(fp_line
			(start 0.12065 -0.2794)
			(end 0.12065 -0.3048)
			(stroke
				(width 0.1)
				(type default)
			)
			(layer "F.Fab")
		)
		(fp_line
			(start -0.12065 -0.2794)
			(end 0.12065 -0.2794)
			(stroke
				(width 0.1)
				(type default)
			)
			(layer "F.Fab")
		)
		(fp_line
			(start 0.120396 0.2794)
			(end -0.12065 0.2794)
			(stroke
				(width 0.1)
				(type default)
			)
			(layer "F.Fab")
		)
		(fp_line
			(start -0.12065 0.2794)
			(end -0.12065 0.3048)
			(stroke
				(width 0.1)
				(type default)
			)
			(layer "F.Fab")
		)
		(fp_line
			(start 0.67945 0.3048)
			(end 0.120396 0.3048)
			(stroke
				(width 0.1)
				(type default)
			)
			(layer "F.Fab")
		)
		(fp_line
			(start 0.120396 0.3048)
			(end 0.120396 0.2794)
			(stroke
				(width 0.1)
				(type default)
			)
			(layer "F.Fab")
		)
		(fp_line
			(start -0.12065 0.3048)
			(end -0.67945 0.3048)
			(stroke
				(width 0.1)
				(type default)
			)
			(layer "F.Fab")
		)
		(fp_line
			(start -0.67945 0.3048)
			(end -0.67945 -0.305054)
			(stroke
				(width 0.1)
				(type default)
			)
			(layer "F.Fab")
		)
		(pad "1" smd circle
			(at -0.40005 0 90)
			(size 0 0)
			(layers "F.Cu" "F.Mask" "F.Paste")
			(net "SMB_BIC_I2C9_MUX1_SSD15_R_SDA")
		)
		(pad "2" smd circle
			(at 0.40005 0 90)
			(size 0 0)
			(layers "F.Cu" "F.Mask" "F.Paste")
			(net "SMB_ISO_SSD15_SDA")
		)
	)
	(footprint ""
		(layer "F.Cu")
		(at 10.221722 -306.281836 180)
		(property "Reference" "PU16"
			(at 4.075684 -3.873246 0)
			(unlocked yes)
			(layer "F.SilkS")
			(effects
				(font
					(size 0.7874 0.5842)
					(thickness 0.1524)
				)
				(justify left)
			)
		)
		(property "Value" ""
			(at 0 0 180)
			(layer "F.Fab")
			(effects
				(font
					(size 1.27 1.27)
				)
			)
		)
		(duplicate_pad_numbers_are_jumpers no)
		(fp_line
			(start 1.549908 2.050034)
			(end 1.549908 1.9304)
			(stroke
				(width 0.1524)
				(type default)
			)
			(layer "F.SilkS")
		)
		(fp_line
			(start 1.549908 -1.9812)
			(end 1.549908 -2.050034)
			(stroke
				(width 0.1524)
				(type default)
			)
			(layer "F.SilkS")
		)
		(fp_line
			(start 1.549908 -2.050034)
			(end 0.5842 -2.050034)
			(stroke
				(width 0.1524)
				(type default)
			)
			(layer "F.SilkS")
		)
		(fp_line
			(start 0.3048 -2.4638)
			(end 0.3048 -3.2258)
			(stroke
				(width 0.1524)
				(type default)
			)
			(layer "F.SilkS")
		)
		(fp_line
			(start 0 2.050034)
			(end 1.549908 2.050034)
			(stroke
				(width 0.1524)
				(type default)
			)
			(layer "F.SilkS")
		)
		(fp_line
			(start -0.3048 2.4638)
			(end -0.3048 3.2258)
			(stroke
				(width 0.1524)
				(type default)
			)
			(layer "F.SilkS")
		)
		(fp_line
			(start -0.5842 -2.050034)
			(end -1.549908 -2.050034)
			(stroke
				(width 0.1524)
				(type default)
			)
			(layer "F.SilkS")
		)
		(fp_line
			(start -1.549908 2.050034)
			(end -0.5842 2.050034)
			(stroke
				(width 0.1524)
				(type default)
			)
			(layer "F.SilkS")
		)
		(fp_line
			(start -1.549908 1.9812)
			(end -1.549908 2.050034)
			(stroke
				(width 0.1524)
				(type default)
			)
			(layer "F.SilkS")
		)
		(fp_line
			(start -1.549908 -2.050034)
			(end -1.549908 -1.9812)
			(stroke
				(width 0.1524)
				(type default)
			)
			(layer "F.SilkS")
		)
		(fp_line
			(start -1.9812 0)
			(end -2.3622 0)
			(stroke
				(width 0.1524)
				(type default)
			)
			(layer "F.SilkS")
		)
		(fp_poly
			(pts
				(xy -2.9464 -2.208022) (xy -2.9464 -1.192022) (xy -1.9304 -1.700022)
			)
			(stroke
				(width 0)
				(type default)
			)
			(fill yes)
			(layer "F.SilkS")
		)
		(fp_line
			(start 1.549908 2.050034)
			(end 1.549908 -2.050034)
			(stroke
				(width 0.1)
				(type default)
			)
			(layer "F.Fab")
		)
		(fp_line
			(start 1.549908 -2.050034)
			(end -1.549908 -2.050034)
			(stroke
				(width 0.1)
				(type default)
			)
			(layer "F.Fab")
		)
		(fp_line
			(start 0.3048 -2.4638)
			(end 0.3048 -3.2258)
			(stroke
				(width 0.1)
				(type default)
			)
			(layer "F.Fab")
		)
		(fp_line
			(start -0.3048 2.4638)
			(end -0.3048 3.2258)
			(stroke
				(width 0.1)
				(type default)
			)
			(layer "F.Fab")
		)
		(fp_line
			(start -1.549908 2.050034)
			(end 1.549908 2.050034)
			(stroke
				(width 0.1)
				(type default)
			)
			(layer "F.Fab")
		)
		(fp_line
			(start -1.549908 -2.050034)
			(end -1.549908 2.050034)
			(stroke
				(width 0.1)
				(type default)
			)
			(layer "F.Fab")
		)
		(fp_line
			(start -1.9812 0)
			(end -2.3622 0)
			(stroke
				(width 0.1)
				(type default)
			)
			(layer "F.Fab")
		)
		(fp_poly
			(pts
				(xy -2.9464 -2.208022) (xy -2.9464 -1.192022) (xy -1.9304 -1.700022)
			)
			(stroke
				(width 0)
				(type default)
			)
			(fill yes)
			(layer "F.Fab")
		)
		(fp_text user "11_18"
			(at 2.512568 0.9906 90)
			(unlocked yes)
			(layer "F.SilkS")
			(effects
				(font
					(size 0.635 0.4064)
					(thickness 0.1524)
				)
			)
		)
		(fp_text user "19"
			(at 1.823974 -2.636012 90)
			(unlocked yes)
			(layer "F.SilkS")
			(effects
				(font
					(size 0.635 0.4064)
					(thickness 0.1524)
				)
			)
		)
		(fp_text user "9"
			(at -1.913128 2.378964 90)
			(unlocked yes)
			(layer "F.SilkS")
			(effects
				(font
					(size 0.635 0.4064)
					(thickness 0.1524)
				)
			)
		)
		(fp_text user "11_18"
			(at 2.512568 0.9906 90)
			(unlocked yes)
			(layer "F.Fab")
			(effects
				(font
					(size 0.635 0.4064)
					(thickness 0.1524)
				)
			)
		)
		(fp_text user "19"
			(at 2.410968 -2.159 90)
			(unlocked yes)
			(layer "F.Fab")
			(effects
				(font
					(size 0.635 0.4064)
					(thickness 0.1524)
				)
			)
		)
		(fp_text user "9"
			(at -2.338832 2.0574 90)
			(unlocked yes)
			(layer "F.Fab")
			(effects
				(font
					(size 0.635 0.4064)
					(thickness 0.1524)
				)
			)
		)
		(pad "1" smd rect
			(at -1.35001 -1.700022 270)
			(size 0.3048 0.9144)
			(layers "F.Cu" "F.Mask" "F.Paste")
			(net "SW_P1V25_PEX0_BT")
		)
		(pad "2" smd rect
			(at -1.400048 -1.199896 270)
			(size 0.1778 0.8128)
			(layers "F.Cu" "F.Mask" "F.Paste")
			(net "GND")
		)
		(pad "3" smd rect
			(at -1.400048 -0.8001 270)
			(size 0.1778 0.8128)
			(layers "F.Cu" "F.Mask" "F.Paste")
			(net "P1V25_PEX0_CS")
		)
		(pad "4" smd rect
			(at -1.400048 -0.40005 270)
			(size 0.1778 0.8128)
			(layers "F.Cu" "F.Mask" "F.Paste")
			(net "GND")
		)
		(pad "5" smd rect
			(at -1.400048 0 270)
			(size 0.1778 0.8128)
			(layers "F.Cu" "F.Mask" "F.Paste")
			(net "P1V25_PEX0_REF")
		)
		(pad "6" smd rect
			(at -1.400048 0.40005 270)
			(size 0.1778 0.8128)
			(layers "F.Cu" "F.Mask" "F.Paste")
			(net "SH_P1V25_PEX0_FB_N")
		)
		(pad "7" smd rect
			(at -1.400048 0.8001 270)
			(size 0.1778 0.8128)
			(layers "F.Cu" "F.Mask" "F.Paste")
			(net "P1V25_PEX0_FB")
		)
		(pad "8" smd rect
			(at -1.400048 1.199896 270)
			(size 0.1778 0.8128)
			(layers "F.Cu" "F.Mask" "F.Paste")
			(net "P1V25_PEX0_EN")
		)
		(pad "9" smd rect
			(at -1.400048 1.700022 270)
			(size 0.3048 0.8128)
			(layers "F.Cu" "F.Mask" "F.Paste")
			(net "PWRGD_P1V25_PEX0")
		)
		(pad "10" smd rect
			(at -0.299974 1.299972 180)
			(size 0.3048 2.0066)
			(layers "F.Cu" "F.Mask" "F.Paste")
			(net "SW_P12V_P1V25_PEX0_FLT")
		)
		(pad "11_18" smd circle
			(at 1.175004 0.275082 180)
			(size 0 0)
			(layers "F.Cu" "F.Mask" "F.Paste")
			(net "GND")
		)
		(pad "19" smd rect
			(at 1.400048 -1.700022 90)
			(size 0.3048 0.8128)
			(layers "F.Cu" "F.Mask" "F.Paste")
			(net "P1V25_PEX0_VCC")
		)
		(pad "20" smd rect
			(at 0.299974 -1.299972 180)
			(size 0.3048 2.0066)
			(layers "F.Cu" "F.Mask" "F.Paste")
			(net "SW_P1V25_PEX0_PH")
		)
		(pad "21" smd rect
			(at -0.299974 -1.299972 180)
			(size 0.3048 2.0066)
			(layers "F.Cu" "F.Mask" "F.Paste")
			(net "SW_P12V_P1V25_PEX0_FLT")
		)
	)
	(footprint ""
		(layer "F.Cu")
		(at 122.689366 -313.620404 180)
		(property "Reference" "L28"
			(at 3.502914 -1.171448 90)
			(unlocked yes)
			(layer "F.SilkS")
			(effects
				(font
					(size 0.7874 0.5842)
					(thickness 0.1524)
				)
				(justify left)
			)
		)
		(property "Value" ""
			(at 0 0 180)
			(layer "F.Fab")
			(effects
				(font
					(size 1.27 1.27)
				)
			)
		)
		(duplicate_pad_numbers_are_jumpers no)
		(fp_line
			(start 2.248154 4.9911)
			(end 2.248154 1.556512)
			(stroke
				(width 0.1524)
				(type default)
			)
			(layer "F.SilkS")
		)
		(fp_line
			(start 2.248154 -1.660652)
			(end 2.248154 -4.9911)
			(stroke
				(width 0.1524)
				(type default)
			)
			(layer "F.SilkS")
		)
		(fp_line
			(start 2.248154 -4.9911)
			(end -2.248154 -4.9911)
			(stroke
				(width 0.1524)
				(type default)
			)
			(layer "F.SilkS")
		)
		(fp_line
			(start -2.248154 4.9911)
			(end 2.248154 4.9911)
			(stroke
				(width 0.1524)
				(type default)
			)
			(layer "F.SilkS")
		)
		(fp_line
			(start -2.248154 1.622552)
			(end -2.248154 4.9911)
			(stroke
				(width 0.1524)
				(type default)
			)
			(layer "F.SilkS")
		)
		(fp_line
			(start -2.248154 -4.9911)
			(end -2.248154 -1.693418)
			(stroke
				(width 0.1524)
				(type default)
			)
			(layer "F.SilkS")
		)
		(fp_line
			(start 1.700022 0.899922)
			(end 1.700022 -0.899922)
			(stroke
				(width 0.1)
				(type default)
			)
			(layer "F.Fab")
		)
		(fp_line
			(start 1.700022 -0.899922)
			(end -1.700022 -0.899922)
			(stroke
				(width 0.1)
				(type default)
			)
			(layer "F.Fab")
		)
		(fp_line
			(start -1.700022 0.899922)
			(end 1.700022 0.899922)
			(stroke
				(width 0.1)
				(type default)
			)
			(layer "F.Fab")
		)
		(fp_line
			(start -1.700022 -0.899922)
			(end -1.700022 0.899922)
			(stroke
				(width 0.1)
				(type default)
			)
			(layer "F.Fab")
		)
		(pad "1" smd rect
			(at -1.575054 0 180)
			(size 1.1684 9.8044)
			(layers "F.Cu" "F.Mask" "F.Paste")
			(net "P0V8_PEX1")
		)
		(pad "2" smd rect
			(at 1.575054 0 180)
			(size 1.1684 9.8044)
			(layers "F.Cu" "F.Mask" "F.Paste")
			(net "P0V8_SERDES_VDDA_PEX1")
		)
	)
	(footprint ""
		(layer "F.Cu")
		(at 213.357968 -72.766682 90)
		(property "Reference" "PC855"
			(at 0 0 90)
			(layer "F.SilkS")
			(hide yes)
			(effects
				(font
					(size 1.27 1.27)
				)
			)
		)
		(property "Value" ""
			(at 0 0 90)
			(layer "F.Fab")
			(effects
				(font
					(size 1.27 1.27)
				)
			)
		)
		(duplicate_pad_numbers_are_jumpers no)
		(fp_line
			(start 0.7874 -0.4064)
			(end 0.7874 0.4064)
			(stroke
				(width 0.1524)
				(type default)
			)
			(layer "F.SilkS")
		)
		(fp_line
			(start -0.7874 -0.4064)
			(end 0.7874 -0.4064)
			(stroke
				(width 0.1524)
				(type default)
			)
			(layer "F.SilkS")
		)
		(fp_line
			(start 0.7874 0.4064)
			(end -0.7874 0.4064)
			(stroke
				(width 0.1524)
				(type default)
			)
			(layer "F.SilkS")
		)
		(fp_line
			(start -0.7874 0.4064)
			(end -0.7874 -0.4064)
			(stroke
				(width 0.1524)
				(type default)
			)
			(layer "F.SilkS")
		)
		(fp_line
			(start -0.12065 -0.305054)
			(end -0.12065 -0.2794)
			(stroke
				(width 0.1)
				(type default)
			)
			(layer "F.Fab")
		)
		(fp_line
			(start -0.67945 -0.305054)
			(end -0.12065 -0.305054)
			(stroke
				(width 0.1)
				(type default)
			)
			(layer "F.Fab")
		)
		(fp_line
			(start 0.67945 -0.3048)
			(end 0.67945 0.3048)
			(stroke
				(width 0.1)
				(type default)
			)
			(layer "F.Fab")
		)
		(fp_line
			(start 0.12065 -0.3048)
			(end 0.67945 -0.3048)
			(stroke
				(width 0.1)
				(type default)
			)
			(layer "F.Fab")
		)
		(fp_line
			(start 0.12065 -0.2794)
			(end 0.12065 -0.3048)
			(stroke
				(width 0.1)
				(type default)
			)
			(layer "F.Fab")
		)
		(fp_line
			(start -0.12065 -0.2794)
			(end 0.12065 -0.2794)
			(stroke
				(width 0.1)
				(type default)
			)
			(layer "F.Fab")
		)
		(fp_line
			(start 0.120396 0.2794)
			(end -0.12065 0.2794)
			(stroke
				(width 0.1)
				(type default)
			)
			(layer "F.Fab")
		)
		(fp_line
			(start -0.12065 0.2794)
			(end -0.12065 0.3048)
			(stroke
				(width 0.1)
				(type default)
			)
			(layer "F.Fab")
		)
		(fp_line
			(start 0.67945 0.3048)
			(end 0.120396 0.3048)
			(stroke
				(width 0.1)
				(type default)
			)
			(layer "F.Fab")
		)
		(fp_line
			(start 0.120396 0.3048)
			(end 0.120396 0.2794)
			(stroke
				(width 0.1)
				(type default)
			)
			(layer "F.Fab")
		)
		(fp_line
			(start -0.12065 0.3048)
			(end -0.67945 0.3048)
			(stroke
				(width 0.1)
				(type default)
			)
			(layer "F.Fab")
		)
		(fp_line
			(start -0.67945 0.3048)
			(end -0.67945 -0.305054)
			(stroke
				(width 0.1)
				(type default)
			)
			(layer "F.Fab")
		)
		(pad "1" smd circle
			(at -0.40005 0 90)
			(size 0 0)
			(layers "F.Cu" "F.Mask" "F.Paste")
			(net "P12V_SSD7_CO_MODE")
		)
		(pad "2" smd circle
			(at 0.40005 0 90)
			(size 0 0)
			(layers "F.Cu" "F.Mask" "F.Paste")
			(net "GND")
		)
	)
	(footprint ""
		(layer "F.Cu")
		(at 240.200434 -250.759722 -90)
		(property "Reference" "R6244"
			(at 0 0 270)
			(layer "F.SilkS")
			(hide yes)
			(effects
				(font
					(size 1.27 1.27)
				)
			)
		)
		(property "Value" ""
			(at 0 0 270)
			(layer "F.Fab")
			(effects
				(font
					(size 1.27 1.27)
				)
			)
		)
		(duplicate_pad_numbers_are_jumpers no)
		(fp_line
			(start -0.7874 0.4064)
			(end -0.7874 -0.4064)
			(stroke
				(width 0.1524)
				(type default)
			)
			(layer "F.SilkS")
		)
		(fp_line
			(start 0.7874 0.4064)
			(end -0.7874 0.4064)
			(stroke
				(width 0.1524)
				(type default)
			)
			(layer "F.SilkS")
		)
		(fp_line
			(start -0.7874 -0.4064)
			(end 0.7874 -0.4064)
			(stroke
				(width 0.1524)
				(type default)
			)
			(layer "F.SilkS")
		)
		(fp_line
			(start 0.7874 -0.4064)
			(end 0.7874 0.4064)
			(stroke
				(width 0.1524)
				(type default)
			)
			(layer "F.SilkS")
		)
		(fp_line
			(start -0.67945 0.3048)
			(end -0.67945 -0.305054)
			(stroke
				(width 0.1)
				(type default)
			)
			(layer "F.Fab")
		)
		(fp_line
			(start -0.12065 0.3048)
			(end -0.67945 0.3048)
			(stroke
				(width 0.1)
				(type default)
			)
			(layer "F.Fab")
		)
		(fp_line
			(start 0.120396 0.3048)
			(end 0.120396 0.2794)
			(stroke
				(width 0.1)
				(type default)
			)
			(layer "F.Fab")
		)
		(fp_line
			(start 0.67945 0.3048)
			(end 0.120396 0.3048)
			(stroke
				(width 0.1)
				(type default)
			)
			(layer "F.Fab")
		)
		(fp_line
			(start -0.12065 0.2794)
			(end -0.12065 0.3048)
			(stroke
				(width 0.1)
				(type default)
			)
			(layer "F.Fab")
		)
		(fp_line
			(start 0.120396 0.2794)
			(end -0.12065 0.2794)
			(stroke
				(width 0.1)
				(type default)
			)
			(layer "F.Fab")
		)
		(fp_line
			(start -0.12065 -0.2794)
			(end 0.12065 -0.2794)
			(stroke
				(width 0.1)
				(type default)
			)
			(layer "F.Fab")
		)
		(fp_line
			(start 0.12065 -0.2794)
			(end 0.12065 -0.3048)
			(stroke
				(width 0.1)
				(type default)
			)
			(layer "F.Fab")
		)
		(fp_line
			(start 0.12065 -0.3048)
			(end 0.67945 -0.3048)
			(stroke
				(width 0.1)
				(type default)
			)
			(layer "F.Fab")
		)
		(fp_line
			(start 0.67945 -0.3048)
			(end 0.67945 0.3048)
			(stroke
				(width 0.1)
				(type default)
			)
			(layer "F.Fab")
		)
		(fp_line
			(start -0.67945 -0.305054)
			(end -0.12065 -0.305054)
			(stroke
				(width 0.1)
				(type default)
			)
			(layer "F.Fab")
		)
		(fp_line
			(start -0.12065 -0.305054)
			(end -0.12065 -0.2794)
			(stroke
				(width 0.1)
				(type default)
			)
			(layer "F.Fab")
		)
		(pad "1" smd circle
			(at -0.40005 0 270)
			(size 0 0)
			(layers "F.Cu" "F.Mask" "F.Paste")
			(net "BIC_UART_BMC_SEL_R")
		)
		(pad "2" smd circle
			(at 0.40005 0 270)
			(size 0 0)
			(layers "F.Cu" "F.Mask" "F.Paste")
			(net "BIC_UART_BMC_SEL")
		)
	)
	(footprint ""
		(layer "F.Cu")
		(at 211.435442 -244.016276 90)
		(property "Reference" "R1536"
			(at 0 0 90)
			(layer "F.SilkS")
			(hide yes)
			(effects
				(font
					(size 1.27 1.27)
				)
			)
		)
		(property "Value" ""
			(at 0 0 90)
			(layer "F.Fab")
			(effects
				(font
					(size 1.27 1.27)
				)
			)
		)
		(duplicate_pad_numbers_are_jumpers no)
		(fp_line
			(start 0.7874 -0.4064)
			(end 0.7874 0.4064)
			(stroke
				(width 0.1524)
				(type default)
			)
			(layer "F.SilkS")
		)
		(fp_line
			(start -0.7874 -0.4064)
			(end 0.7874 -0.4064)
			(stroke
				(width 0.1524)
				(type default)
			)
			(layer "F.SilkS")
		)
		(fp_line
			(start 0.7874 0.4064)
			(end -0.7874 0.4064)
			(stroke
				(width 0.1524)
				(type default)
			)
			(layer "F.SilkS")
		)
		(fp_line
			(start -0.7874 0.4064)
			(end -0.7874 -0.4064)
			(stroke
				(width 0.1524)
				(type default)
			)
			(layer "F.SilkS")
		)
		(fp_line
			(start -0.12065 -0.305054)
			(end -0.12065 -0.2794)
			(stroke
				(width 0.1)
				(type default)
			)
			(layer "F.Fab")
		)
		(fp_line
			(start -0.67945 -0.305054)
			(end -0.12065 -0.305054)
			(stroke
				(width 0.1)
				(type default)
			)
			(layer "F.Fab")
		)
		(fp_line
			(start 0.67945 -0.3048)
			(end 0.67945 0.3048)
			(stroke
				(width 0.1)
				(type default)
			)
			(layer "F.Fab")
		)
		(fp_line
			(start 0.12065 -0.3048)
			(end 0.67945 -0.3048)
			(stroke
				(width 0.1)
				(type default)
			)
			(layer "F.Fab")
		)
		(fp_line
			(start 0.12065 -0.2794)
			(end 0.12065 -0.3048)
			(stroke
				(width 0.1)
				(type default)
			)
			(layer "F.Fab")
		)
		(fp_line
			(start -0.12065 -0.2794)
			(end 0.12065 -0.2794)
			(stroke
				(width 0.1)
				(type default)
			)
			(layer "F.Fab")
		)
		(fp_line
			(start 0.120396 0.2794)
			(end -0.12065 0.2794)
			(stroke
				(width 0.1)
				(type default)
			)
			(layer "F.Fab")
		)
		(fp_line
			(start -0.12065 0.2794)
			(end -0.12065 0.3048)
			(stroke
				(width 0.1)
				(type default)
			)
			(layer "F.Fab")
		)
		(fp_line
			(start 0.67945 0.3048)
			(end 0.120396 0.3048)
			(stroke
				(width 0.1)
				(type default)
			)
			(layer "F.Fab")
		)
		(fp_line
			(start 0.120396 0.3048)
			(end 0.120396 0.2794)
			(stroke
				(width 0.1)
				(type default)
			)
			(layer "F.Fab")
		)
		(fp_line
			(start -0.12065 0.3048)
			(end -0.67945 0.3048)
			(stroke
				(width 0.1)
				(type default)
			)
			(layer "F.Fab")
		)
		(fp_line
			(start -0.67945 0.3048)
			(end -0.67945 -0.305054)
			(stroke
				(width 0.1)
				(type default)
			)
			(layer "F.Fab")
		)
		(pad "1" smd circle
			(at -0.40005 0 90)
			(size 0 0)
			(layers "F.Cu" "F.Mask" "F.Paste")
			(net "SMB_PEX_R_SCL")
		)
		(pad "2" smd circle
			(at 0.40005 0 90)
			(size 0 0)
			(layers "F.Cu" "F.Mask" "F.Paste")
			(net "P3V3_AUX")
		)
	)
	(footprint ""
		(layer "F.Cu")
		(at 454.125838 -312.439558 180)
		(property "Reference" "PC268"
			(at 0 0 180)
			(layer "F.SilkS")
			(hide yes)
			(effects
				(font
					(size 1.27 1.27)
				)
			)
		)
		(property "Value" ""
			(at 0 0 180)
			(layer "F.Fab")
			(effects
				(font
					(size 1.27 1.27)
				)
			)
		)
		(duplicate_pad_numbers_are_jumpers no)
		(fp_line
			(start 1.524 0.762)
			(end -1.524 0.762)
			(stroke
				(width 0.1524)
				(type default)
			)
			(layer "F.SilkS")
		)
		(fp_line
			(start 1.524 -0.762)
			(end 1.524 0.762)
			(stroke
				(width 0.1524)
				(type default)
			)
			(layer "F.SilkS")
		)
		(fp_line
			(start -1.524 0.762)
			(end -1.524 -0.762)
			(stroke
				(width 0.1524)
				(type default)
			)
			(layer "F.SilkS")
		)
		(fp_line
			(start -1.524 -0.762)
			(end 1.524 -0.762)
			(stroke
				(width 0.1524)
				(type default)
			)
			(layer "F.SilkS")
		)
		(fp_line
			(start 1.1049 0.724916)
			(end 1.1049 -0.724916)
			(stroke
				(width 0.1)
				(type default)
			)
			(layer "F.Fab")
		)
		(fp_line
			(start 1.1049 -0.724916)
			(end -1.1049 -0.724916)
			(stroke
				(width 0.1)
				(type default)
			)
			(layer "F.Fab")
		)
		(fp_line
			(start -1.1049 0.724916)
			(end 1.1049 0.724916)
			(stroke
				(width 0.1)
				(type default)
			)
			(layer "F.Fab")
		)
		(fp_line
			(start -1.1049 -0.724916)
			(end -1.1049 0.724916)
			(stroke
				(width 0.1)
				(type default)
			)
			(layer "F.Fab")
		)
		(pad "1" smd rect
			(at -0.889 0)
			(size 1.016 1.27)
			(layers "F.Cu" "F.Mask" "F.Paste")
			(net "SW_P12V_P1V25_PEX3_FLT")
		)
		(pad "2" smd rect
			(at 0.889 0)
			(size 1.016 1.27)
			(layers "F.Cu" "F.Mask" "F.Paste")
			(net "GND")
		)
	)
	(footprint ""
		(layer "F.Cu")
		(at 154.860244 -96.1644)
		(property "Reference" "R144"
			(at 0 0 0)
			(layer "F.SilkS")
			(hide yes)
			(effects
				(font
					(size 1.27 1.27)
				)
			)
		)
		(property "Value" ""
			(at 0 0 0)
			(layer "F.Fab")
			(effects
				(font
					(size 1.27 1.27)
				)
			)
		)
		(duplicate_pad_numbers_are_jumpers no)
		(fp_line
			(start -0.7874 -0.4064)
			(end 0.7874 -0.4064)
			(stroke
				(width 0.1524)
				(type default)
			)
			(layer "F.SilkS")
		)
		(fp_line
			(start -0.7874 0.4064)
			(end -0.7874 -0.4064)
			(stroke
				(width 0.1524)
				(type default)
			)
			(layer "F.SilkS")
		)
		(fp_line
			(start 0.7874 -0.4064)
			(end 0.7874 0.4064)
			(stroke
				(width 0.1524)
				(type default)
			)
			(layer "F.SilkS")
		)
		(fp_line
			(start 0.7874 0.4064)
			(end -0.7874 0.4064)
			(stroke
				(width 0.1524)
				(type default)
			)
			(layer "F.SilkS")
		)
		(fp_line
			(start -0.67945 -0.305054)
			(end -0.12065 -0.305054)
			(stroke
				(width 0.1)
				(type default)
			)
			(layer "F.Fab")
		)
		(fp_line
			(start -0.67945 0.3048)
			(end -0.67945 -0.305054)
			(stroke
				(width 0.1)
				(type default)
			)
			(layer "F.Fab")
		)
		(fp_line
			(start -0.12065 -0.305054)
			(end -0.12065 -0.2794)
			(stroke
				(width 0.1)
				(type default)
			)
			(layer "F.Fab")
		)
		(fp_line
			(start -0.12065 -0.2794)
			(end 0.12065 -0.2794)
			(stroke
				(width 0.1)
				(type default)
			)
			(layer "F.Fab")
		)
		(fp_line
			(start -0.12065 0.2794)
			(end -0.12065 0.3048)
			(stroke
				(width 0.1)
				(type default)
			)
			(layer "F.Fab")
		)
		(fp_line
			(start -0.12065 0.3048)
			(end -0.67945 0.3048)
			(stroke
				(width 0.1)
				(type default)
			)
			(layer "F.Fab")
		)
		(fp_line
			(start 0.120396 0.2794)
			(end -0.12065 0.2794)
			(stroke
				(width 0.1)
				(type default)
			)
			(layer "F.Fab")
		)
		(fp_line
			(start 0.120396 0.3048)
			(end 0.120396 0.2794)
			(stroke
				(width 0.1)
				(type default)
			)
			(layer "F.Fab")
		)
		(fp_line
			(start 0.12065 -0.3048)
			(end 0.67945 -0.3048)
			(stroke
				(width 0.1)
				(type default)
			)
			(layer "F.Fab")
		)
		(fp_line
			(start 0.12065 -0.2794)
			(end 0.12065 -0.3048)
			(stroke
				(width 0.1)
				(type default)
			)
			(layer "F.Fab")
		)
		(fp_line
			(start 0.67945 -0.3048)
			(end 0.67945 0.3048)
			(stroke
				(width 0.1)
				(type default)
			)
			(layer "F.Fab")
		)
		(fp_line
			(start 0.67945 0.3048)
			(end 0.120396 0.3048)
			(stroke
				(width 0.1)
				(type default)
			)
			(layer "F.Fab")
		)
		(pad "1" smd circle
			(at -0.40005 0)
			(size 0 0)
			(layers "F.Cu" "F.Mask" "F.Paste")
			(net "PRSNT_NIC2_N")
		)
		(pad "2" smd circle
			(at 0.40005 0)
			(size 0 0)
			(layers "F.Cu" "F.Mask" "F.Paste")
			(net "PRSNTB3_NIC2_N")
		)
	)
	(footprint ""
		(layer "F.Cu")
		(at 210.53552 -220.691456 -90)
		(property "Reference" "R2740"
			(at 0 0 270)
			(layer "F.SilkS")
			(hide yes)
			(effects
				(font
					(size 1.27 1.27)
				)
			)
		)
		(property "Value" ""
			(at 0 0 270)
			(layer "F.Fab")
			(effects
				(font
					(size 1.27 1.27)
				)
			)
		)
		(duplicate_pad_numbers_are_jumpers no)
		(fp_line
			(start -0.7874 0.4064)
			(end -0.7874 -0.4064)
			(stroke
				(width 0.1524)
				(type default)
			)
			(layer "F.SilkS")
		)
		(fp_line
			(start 0.7874 0.4064)
			(end -0.7874 0.4064)
			(stroke
				(width 0.1524)
				(type default)
			)
			(layer "F.SilkS")
		)
		(fp_line
			(start -0.7874 -0.4064)
			(end 0.7874 -0.4064)
			(stroke
				(width 0.1524)
				(type default)
			)
			(layer "F.SilkS")
		)
		(fp_line
			(start 0.7874 -0.4064)
			(end 0.7874 0.4064)
			(stroke
				(width 0.1524)
				(type default)
			)
			(layer "F.SilkS")
		)
		(fp_line
			(start -0.67945 0.3048)
			(end -0.67945 -0.305054)
			(stroke
				(width 0.1)
				(type default)
			)
			(layer "F.Fab")
		)
		(fp_line
			(start -0.12065 0.3048)
			(end -0.67945 0.3048)
			(stroke
				(width 0.1)
				(type default)
			)
			(layer "F.Fab")
		)
		(fp_line
			(start 0.120396 0.3048)
			(end 0.120396 0.2794)
			(stroke
				(width 0.1)
				(type default)
			)
			(layer "F.Fab")
		)
		(fp_line
			(start 0.67945 0.3048)
			(end 0.120396 0.3048)
			(stroke
				(width 0.1)
				(type default)
			)
			(layer "F.Fab")
		)
		(fp_line
			(start -0.12065 0.2794)
			(end -0.12065 0.3048)
			(stroke
				(width 0.1)
				(type default)
			)
			(layer "F.Fab")
		)
		(fp_line
			(start 0.120396 0.2794)
			(end -0.12065 0.2794)
			(stroke
				(width 0.1)
				(type default)
			)
			(layer "F.Fab")
		)
		(fp_line
			(start -0.12065 -0.2794)
			(end 0.12065 -0.2794)
			(stroke
				(width 0.1)
				(type default)
			)
			(layer "F.Fab")
		)
		(fp_line
			(start 0.12065 -0.2794)
			(end 0.12065 -0.3048)
			(stroke
				(width 0.1)
				(type default)
			)
			(layer "F.Fab")
		)
		(fp_line
			(start 0.12065 -0.3048)
			(end 0.67945 -0.3048)
			(stroke
				(width 0.1)
				(type default)
			)
			(layer "F.Fab")
		)
		(fp_line
			(start 0.67945 -0.3048)
			(end 0.67945 0.3048)
			(stroke
				(width 0.1)
				(type default)
			)
			(layer "F.Fab")
		)
		(fp_line
			(start -0.67945 -0.305054)
			(end -0.12065 -0.305054)
			(stroke
				(width 0.1)
				(type default)
			)
			(layer "F.Fab")
		)
		(fp_line
			(start -0.12065 -0.305054)
			(end -0.12065 -0.2794)
			(stroke
				(width 0.1)
				(type default)
			)
			(layer "F.Fab")
		)
		(pad "1" smd circle
			(at -0.40005 0 270)
			(size 0 0)
			(layers "F.Cu" "F.Mask" "F.Paste")
			(net "BUF_UART_MB_BIC_TX_EN")
		)
		(pad "2" smd circle
			(at 0.40005 0 270)
			(size 0 0)
			(layers "F.Cu" "F.Mask" "F.Paste")
			(net "P3V3_AUX")
		)
	)
	(footprint ""
		(layer "F.Cu")
		(at 115.64239 -258.14655 180)
		(property "Reference" "PR94"
			(at 0 0 180)
			(layer "F.SilkS")
			(hide yes)
			(effects
				(font
					(size 1.27 1.27)
				)
			)
		)
		(property "Value" ""
			(at 0 0 180)
			(layer "F.Fab")
			(effects
				(font
					(size 1.27 1.27)
				)
			)
		)
		(duplicate_pad_numbers_are_jumpers no)
		(fp_line
			(start 0.7874 0.4064)
			(end -0.7874 0.4064)
			(stroke
				(width 0.1524)
				(type default)
			)
			(layer "F.SilkS")
		)
		(fp_line
			(start 0.7874 -0.4064)
			(end 0.7874 0.4064)
			(stroke
				(width 0.1524)
				(type default)
			)
			(layer "F.SilkS")
		)
		(fp_line
			(start -0.7874 0.4064)
			(end -0.7874 -0.4064)
			(stroke
				(width 0.1524)
				(type default)
			)
			(layer "F.SilkS")
		)
		(fp_line
			(start -0.7874 -0.4064)
			(end 0.7874 -0.4064)
			(stroke
				(width 0.1524)
				(type default)
			)
			(layer "F.SilkS")
		)
		(fp_line
			(start 0.67945 0.3048)
			(end 0.120396 0.3048)
			(stroke
				(width 0.1)
				(type default)
			)
			(layer "F.Fab")
		)
		(fp_line
			(start 0.67945 -0.3048)
			(end 0.67945 0.3048)
			(stroke
				(width 0.1)
				(type default)
			)
			(layer "F.Fab")
		)
		(fp_line
			(start 0.12065 -0.2794)
			(end 0.12065 -0.3048)
			(stroke
				(width 0.1)
				(type default)
			)
			(layer "F.Fab")
		)
		(fp_line
			(start 0.12065 -0.3048)
			(end 0.67945 -0.3048)
			(stroke
				(width 0.1)
				(type default)
			)
			(layer "F.Fab")
		)
		(fp_line
			(start 0.120396 0.3048)
			(end 0.120396 0.2794)
			(stroke
				(width 0.1)
				(type default)
			)
			(layer "F.Fab")
		)
		(fp_line
			(start 0.120396 0.2794)
			(end -0.12065 0.2794)
			(stroke
				(width 0.1)
				(type default)
			)
			(layer "F.Fab")
		)
		(fp_line
			(start -0.12065 0.3048)
			(end -0.67945 0.3048)
			(stroke
				(width 0.1)
				(type default)
			)
			(layer "F.Fab")
		)
		(fp_line
			(start -0.12065 0.2794)
			(end -0.12065 0.3048)
			(stroke
				(width 0.1)
				(type default)
			)
			(layer "F.Fab")
		)
		(fp_line
			(start -0.12065 -0.2794)
			(end 0.12065 -0.2794)
			(stroke
				(width 0.1)
				(type default)
			)
			(layer "F.Fab")
		)
		(fp_line
			(start -0.12065 -0.305054)
			(end -0.12065 -0.2794)
			(stroke
				(width 0.1)
				(type default)
			)
			(layer "F.Fab")
		)
		(fp_line
			(start -0.67945 0.3048)
			(end -0.67945 -0.305054)
			(stroke
				(width 0.1)
				(type default)
			)
			(layer "F.Fab")
		)
		(fp_line
			(start -0.67945 -0.305054)
			(end -0.12065 -0.305054)
			(stroke
				(width 0.1)
				(type default)
			)
			(layer "F.Fab")
		)
		(pad "1" smd circle
			(at -0.40005 0 180)
			(size 0 0)
			(layers "F.Cu" "F.Mask" "F.Paste")
			(net "P0V8_PEX0_IINSEN")
		)
		(pad "2" smd circle
			(at 0.40005 0 180)
			(size 0 0)
			(layers "F.Cu" "F.Mask" "F.Paste")
			(net "GND")
		)
	)
	(footprint ""
		(layer "F.Cu")
		(at 125.34519 -110.722918 90)
		(property "Reference" "R5829"
			(at 0 0 90)
			(layer "F.SilkS")
			(hide yes)
			(effects
				(font
					(size 1.27 1.27)
				)
			)
		)
		(property "Value" ""
			(at 0 0 90)
			(layer "F.Fab")
			(effects
				(font
					(size 1.27 1.27)
				)
			)
		)
		(duplicate_pad_numbers_are_jumpers no)
		(fp_line
			(start 0.7874 -0.4064)
			(end 0.7874 0.4064)
			(stroke
				(width 0.1524)
				(type default)
			)
			(layer "F.SilkS")
		)
		(fp_line
			(start -0.7874 -0.4064)
			(end 0.7874 -0.4064)
			(stroke
				(width 0.1524)
				(type default)
			)
			(layer "F.SilkS")
		)
		(fp_line
			(start 0.7874 0.4064)
			(end -0.7874 0.4064)
			(stroke
				(width 0.1524)
				(type default)
			)
			(layer "F.SilkS")
		)
		(fp_line
			(start -0.7874 0.4064)
			(end -0.7874 -0.4064)
			(stroke
				(width 0.1524)
				(type default)
			)
			(layer "F.SilkS")
		)
		(fp_line
			(start -0.12065 -0.305054)
			(end -0.12065 -0.2794)
			(stroke
				(width 0.1)
				(type default)
			)
			(layer "F.Fab")
		)
		(fp_line
			(start -0.67945 -0.305054)
			(end -0.12065 -0.305054)
			(stroke
				(width 0.1)
				(type default)
			)
			(layer "F.Fab")
		)
		(fp_line
			(start 0.67945 -0.3048)
			(end 0.67945 0.3048)
			(stroke
				(width 0.1)
				(type default)
			)
			(layer "F.Fab")
		)
		(fp_line
			(start 0.12065 -0.3048)
			(end 0.67945 -0.3048)
			(stroke
				(width 0.1)
				(type default)
			)
			(layer "F.Fab")
		)
		(fp_line
			(start 0.12065 -0.2794)
			(end 0.12065 -0.3048)
			(stroke
				(width 0.1)
				(type default)
			)
			(layer "F.Fab")
		)
		(fp_line
			(start -0.12065 -0.2794)
			(end 0.12065 -0.2794)
			(stroke
				(width 0.1)
				(type default)
			)
			(layer "F.Fab")
		)
		(fp_line
			(start 0.120396 0.2794)
			(end -0.12065 0.2794)
			(stroke
				(width 0.1)
				(type default)
			)
			(layer "F.Fab")
		)
		(fp_line
			(start -0.12065 0.2794)
			(end -0.12065 0.3048)
			(stroke
				(width 0.1)
				(type default)
			)
			(layer "F.Fab")
		)
		(fp_line
			(start 0.67945 0.3048)
			(end 0.120396 0.3048)
			(stroke
				(width 0.1)
				(type default)
			)
			(layer "F.Fab")
		)
		(fp_line
			(start 0.120396 0.3048)
			(end 0.120396 0.2794)
			(stroke
				(width 0.1)
				(type default)
			)
			(layer "F.Fab")
		)
		(fp_line
			(start -0.12065 0.3048)
			(end -0.67945 0.3048)
			(stroke
				(width 0.1)
				(type default)
			)
			(layer "F.Fab")
		)
		(fp_line
			(start -0.67945 0.3048)
			(end -0.67945 -0.305054)
			(stroke
				(width 0.1)
				(type default)
			)
			(layer "F.Fab")
		)
		(pad "1" smd circle
			(at -0.40005 0 90)
			(size 0 0)
			(layers "F.Cu" "F.Mask" "F.Paste")
			(net "P3V3_PG_G1")
		)
		(pad "2" smd circle
			(at 0.40005 0 90)
			(size 0 0)
			(layers "F.Cu" "F.Mask" "F.Paste")
			(net "GND")
		)
	)
	(footprint ""
		(layer "F.Cu")
		(at 180.594 -187.495688 180)
		(property "Reference" "Q240"
			(at 5.220462 1.054862 0)
			(unlocked yes)
			(layer "F.SilkS")
			(effects
				(font
					(size 0.7874 0.5842)
					(thickness 0.1524)
				)
				(justify left)
			)
		)
		(property "Value" ""
			(at 0 0 180)
			(layer "F.Fab")
			(effects
				(font
					(size 1.27 1.27)
				)
			)
		)
		(duplicate_pad_numbers_are_jumpers no)
		(fp_line
			(start 1.603248 1.500124)
			(end -1.603248 1.500124)
			(stroke
				(width 0.1524)
				(type default)
			)
			(layer "F.SilkS")
		)
		(fp_line
			(start 1.603248 -1.500124)
			(end 1.603248 1.500124)
			(stroke
				(width 0.1524)
				(type default)
			)
			(layer "F.SilkS")
		)
		(fp_line
			(start -1.603248 1.500124)
			(end -1.603248 -1.500124)
			(stroke
				(width 0.1524)
				(type default)
			)
			(layer "F.SilkS")
		)
		(fp_line
			(start -1.603248 -1.500124)
			(end 1.603248 -1.500124)
			(stroke
				(width 0.1524)
				(type default)
			)
			(layer "F.SilkS")
		)
		(fp_line
			(start 1.249934 0.219964)
			(end 1.249934 -0.219964)
			(stroke
				(width 0.1)
				(type default)
			)
			(layer "F.Fab")
		)
		(fp_line
			(start 1.249934 -0.219964)
			(end 0.700024 -0.219964)
			(stroke
				(width 0.1)
				(type default)
			)
			(layer "F.Fab")
		)
		(fp_line
			(start 0.700024 1.500124)
			(end 0.700024 0.219964)
			(stroke
				(width 0.1)
				(type default)
			)
			(layer "F.Fab")
		)
		(fp_line
			(start 0.700024 0.219964)
			(end 1.249934 0.219964)
			(stroke
				(width 0.1)
				(type default)
			)
			(layer "F.Fab")
		)
		(fp_line
			(start 0.700024 -0.219964)
			(end 0.700024 -1.500124)
			(stroke
				(width 0.1)
				(type default)
			)
			(layer "F.Fab")
		)
		(fp_line
			(start 0.700024 -1.500124)
			(end -0.700024 -1.500124)
			(stroke
				(width 0.1)
				(type default)
			)
			(layer "F.Fab")
		)
		(fp_line
			(start -0.6985 0.729996)
			(end -1.249934 0.729996)
			(stroke
				(width 0.1)
				(type default)
			)
			(layer "F.Fab")
		)
		(fp_line
			(start -0.6985 -0.729996)
			(end -0.6985 0.729996)
			(stroke
				(width 0.1)
				(type default)
			)
			(layer "F.Fab")
		)
		(fp_line
			(start -0.700024 1.500124)
			(end 0.700024 1.500124)
			(stroke
				(width 0.1)
				(type default)
			)
			(layer "F.Fab")
		)
		(fp_line
			(start -0.700024 1.169924)
			(end -0.700024 1.500124)
			(stroke
				(width 0.1)
				(type default)
			)
			(layer "F.Fab")
		)
		(fp_line
			(start -0.700024 -1.169924)
			(end -1.249934 -1.169924)
			(stroke
				(width 0.1)
				(type default)
			)
			(layer "F.Fab")
		)
		(fp_line
			(start -0.700024 -1.500124)
			(end -0.700024 -1.169924)
			(stroke
				(width 0.1)
				(type default)
			)
			(layer "F.Fab")
		)
		(fp_line
			(start -1.249934 1.169924)
			(end -0.700024 1.169924)
			(stroke
				(width 0.1)
				(type default)
			)
			(layer "F.Fab")
		)
		(fp_line
			(start -1.249934 0.729996)
			(end -1.249934 1.169924)
			(stroke
				(width 0.1)
				(type default)
			)
			(layer "F.Fab")
		)
		(fp_line
			(start -1.249934 -0.729996)
			(end -0.6985 -0.729996)
			(stroke
				(width 0.1)
				(type default)
			)
			(layer "F.Fab")
		)
		(fp_line
			(start -1.249934 -1.169924)
			(end -1.249934 -0.729996)
			(stroke
				(width 0.1)
				(type default)
			)
			(layer "F.Fab")
		)
		(fp_rect
			(start -0.700024 1.500124)
			(end 0.700024 -1.500124)
			(stroke
				(width 0)
				(type default)
			)
			(fill no)
			(layer "F.Fab")
		)
		(pad "D" smd rect
			(at 0.999998 0 90)
			(size 0.8128 0.9144)
			(layers "F.Cu" "F.Mask" "F.Paste")
			(net "SPI_BIC1_LS01_EN_N")
		)
		(pad "G" smd rect
			(at -0.999998 -0.94996 90)
			(size 0.8128 0.9144)
			(layers "F.Cu" "F.Mask" "F.Paste")
			(net "SPI_BIC1_LS01_EN")
		)
		(pad "S" smd rect
			(at -0.999998 0.94996 90)
			(size 0.8128 0.9144)
			(layers "F.Cu" "F.Mask" "F.Paste")
			(net "GND")
		)
	)
	(footprint ""
		(layer "F.Cu")
		(at 93.726 -125.530864)
		(property "Reference" "PC461"
			(at 0 0 0)
			(layer "F.SilkS")
			(hide yes)
			(effects
				(font
					(size 1.27 1.27)
				)
			)
		)
		(property "Value" ""
			(at 0 0 0)
			(layer "F.Fab")
			(effects
				(font
					(size 1.27 1.27)
				)
			)
		)
		(duplicate_pad_numbers_are_jumpers no)
		(fp_line
			(start -1.524 -0.762)
			(end 1.524 -0.762)
			(stroke
				(width 0.1524)
				(type default)
			)
			(layer "F.SilkS")
		)
		(fp_line
			(start -1.524 0.762)
			(end -1.524 -0.762)
			(stroke
				(width 0.1524)
				(type default)
			)
			(layer "F.SilkS")
		)
		(fp_line
			(start 1.524 -0.762)
			(end 1.524 0.762)
			(stroke
				(width 0.1524)
				(type default)
			)
			(layer "F.SilkS")
		)
		(fp_line
			(start 1.524 0.762)
			(end -1.524 0.762)
			(stroke
				(width 0.1524)
				(type default)
			)
			(layer "F.SilkS")
		)
		(fp_line
			(start -1.1049 -0.724916)
			(end -1.1049 0.724916)
			(stroke
				(width 0.1)
				(type default)
			)
			(layer "F.Fab")
		)
		(fp_line
			(start -1.1049 0.724916)
			(end 1.1049 0.724916)
			(stroke
				(width 0.1)
				(type default)
			)
			(layer "F.Fab")
		)
		(fp_line
			(start 1.1049 -0.724916)
			(end -1.1049 -0.724916)
			(stroke
				(width 0.1)
				(type default)
			)
			(layer "F.Fab")
		)
		(fp_line
			(start 1.1049 0.724916)
			(end 1.1049 -0.724916)
			(stroke
				(width 0.1)
				(type default)
			)
			(layer "F.Fab")
		)
		(pad "1" smd rect
			(at -0.889 0 180)
			(size 1.016 1.27)
			(layers "F.Cu" "F.Mask" "F.Paste")
			(net "GND")
		)
		(pad "2" smd rect
			(at 0.889 0 180)
			(size 1.016 1.27)
			(layers "F.Cu" "F.Mask" "F.Paste")
			(net "P3V3_AUX")
		)
	)
	(footprint ""
		(layer "F.Cu")
		(at 39.280592 -99.288854)
		(property "Reference" "C63"
			(at 0 0 0)
			(layer "F.SilkS")
			(hide yes)
			(effects
				(font
					(size 1.27 1.27)
				)
			)
		)
		(property "Value" ""
			(at 0 0 0)
			(layer "F.Fab")
			(effects
				(font
					(size 1.27 1.27)
				)
			)
		)
		(duplicate_pad_numbers_are_jumpers no)
		(fp_line
			(start -0.299974 -0.150114)
			(end 0.299974 -0.150114)
			(stroke
				(width 0.1)
				(type default)
			)
			(layer "F.Fab")
		)
		(fp_line
			(start -0.299974 0.150114)
			(end -0.299974 -0.150114)
			(stroke
				(width 0.1)
				(type default)
			)
			(layer "F.Fab")
		)
		(fp_line
			(start 0.299974 -0.150114)
			(end 0.299974 0.150114)
			(stroke
				(width 0.1)
				(type default)
			)
			(layer "F.Fab")
		)
		(fp_line
			(start 0.299974 0.150114)
			(end -0.299974 0.150114)
			(stroke
				(width 0.1)
				(type default)
			)
			(layer "F.Fab")
		)
		(pad "1" smd rect
			(at -0.2667 0)
			(size 0.3048 0.381)
			(layers "F.Cu" "F.Mask" "F.Paste")
			(net "P5E_PEX0_STN1_TX_DP<16>")
		)
		(pad "2" smd rect
			(at 0.2667 0)
			(size 0.3048 0.381)
			(layers "F.Cu" "F.Mask" "F.Paste")
			(net "P5E_PEX0_STN1_TX_C_DP<16>")
		)
	)
	(footprint ""
		(layer "F.Cu")
		(at 196.975222 -64.102234 180)
		(property "Reference" "PR7074"
			(at 0 0 180)
			(layer "F.SilkS")
			(hide yes)
			(effects
				(font
					(size 1.27 1.27)
				)
			)
		)
		(property "Value" ""
			(at 0 0 180)
			(layer "F.Fab")
			(effects
				(font
					(size 1.27 1.27)
				)
			)
		)
		(duplicate_pad_numbers_are_jumpers no)
		(fp_line
			(start 0.7874 0.4064)
			(end -0.7874 0.4064)
			(stroke
				(width 0.1524)
				(type default)
			)
			(layer "F.SilkS")
		)
		(fp_line
			(start 0.7874 -0.4064)
			(end 0.7874 0.4064)
			(stroke
				(width 0.1524)
				(type default)
			)
			(layer "F.SilkS")
		)
		(fp_line
			(start -0.7874 0.4064)
			(end -0.7874 -0.4064)
			(stroke
				(width 0.1524)
				(type default)
			)
			(layer "F.SilkS")
		)
		(fp_line
			(start -0.7874 -0.4064)
			(end 0.7874 -0.4064)
			(stroke
				(width 0.1524)
				(type default)
			)
			(layer "F.SilkS")
		)
		(fp_line
			(start 0.67945 0.3048)
			(end 0.120396 0.3048)
			(stroke
				(width 0.1)
				(type default)
			)
			(layer "F.Fab")
		)
		(fp_line
			(start 0.67945 -0.3048)
			(end 0.67945 0.3048)
			(stroke
				(width 0.1)
				(type default)
			)
			(layer "F.Fab")
		)
		(fp_line
			(start 0.12065 -0.2794)
			(end 0.12065 -0.3048)
			(stroke
				(width 0.1)
				(type default)
			)
			(layer "F.Fab")
		)
		(fp_line
			(start 0.12065 -0.3048)
			(end 0.67945 -0.3048)
			(stroke
				(width 0.1)
				(type default)
			)
			(layer "F.Fab")
		)
		(fp_line
			(start 0.120396 0.3048)
			(end 0.120396 0.2794)
			(stroke
				(width 0.1)
				(type default)
			)
			(layer "F.Fab")
		)
		(fp_line
			(start 0.120396 0.2794)
			(end -0.12065 0.2794)
			(stroke
				(width 0.1)
				(type default)
			)
			(layer "F.Fab")
		)
		(fp_line
			(start -0.12065 0.3048)
			(end -0.67945 0.3048)
			(stroke
				(width 0.1)
				(type default)
			)
			(layer "F.Fab")
		)
		(fp_line
			(start -0.12065 0.2794)
			(end -0.12065 0.3048)
			(stroke
				(width 0.1)
				(type default)
			)
			(layer "F.Fab")
		)
		(fp_line
			(start -0.12065 -0.2794)
			(end 0.12065 -0.2794)
			(stroke
				(width 0.1)
				(type default)
			)
			(layer "F.Fab")
		)
		(fp_line
			(start -0.12065 -0.305054)
			(end -0.12065 -0.2794)
			(stroke
				(width 0.1)
				(type default)
			)
			(layer "F.Fab")
		)
		(fp_line
			(start -0.67945 0.3048)
			(end -0.67945 -0.305054)
			(stroke
				(width 0.1)
				(type default)
			)
			(layer "F.Fab")
		)
		(fp_line
			(start -0.67945 -0.305054)
			(end -0.12065 -0.305054)
			(stroke
				(width 0.1)
				(type default)
			)
			(layer "F.Fab")
		)
		(pad "1" smd circle
			(at -0.40005 0 180)
			(size 0 0)
			(layers "F.Cu" "F.Mask" "F.Paste")
			(net "P12V_SSD7_PG_G1")
		)
		(pad "2" smd circle
			(at 0.40005 0 180)
			(size 0 0)
			(layers "F.Cu" "F.Mask" "F.Paste")
			(net "GND")
		)
	)
	(footprint ""
		(layer "F.Cu")
		(at 344.511884 -110.515654)
		(property "Reference" "PC815"
			(at 0 0 0)
			(layer "F.SilkS")
			(hide yes)
			(effects
				(font
					(size 1.27 1.27)
				)
			)
		)
		(property "Value" ""
			(at 0 0 0)
			(layer "F.Fab")
			(effects
				(font
					(size 1.27 1.27)
				)
			)
		)
		(duplicate_pad_numbers_are_jumpers no)
		(fp_line
			(start -0.7874 -0.4064)
			(end 0.7874 -0.4064)
			(stroke
				(width 0.1524)
				(type default)
			)
			(layer "F.SilkS")
		)
		(fp_line
			(start -0.7874 0.4064)
			(end -0.7874 -0.4064)
			(stroke
				(width 0.1524)
				(type default)
			)
			(layer "F.SilkS")
		)
		(fp_line
			(start 0.7874 -0.4064)
			(end 0.7874 0.4064)
			(stroke
				(width 0.1524)
				(type default)
			)
			(layer "F.SilkS")
		)
		(fp_line
			(start 0.7874 0.4064)
			(end -0.7874 0.4064)
			(stroke
				(width 0.1524)
				(type default)
			)
			(layer "F.SilkS")
		)
		(fp_line
			(start -0.67945 -0.305054)
			(end -0.12065 -0.305054)
			(stroke
				(width 0.1)
				(type default)
			)
			(layer "F.Fab")
		)
		(fp_line
			(start -0.67945 0.3048)
			(end -0.67945 -0.305054)
			(stroke
				(width 0.1)
				(type default)
			)
			(layer "F.Fab")
		)
		(fp_line
			(start -0.12065 -0.305054)
			(end -0.12065 -0.2794)
			(stroke
				(width 0.1)
				(type default)
			)
			(layer "F.Fab")
		)
		(fp_line
			(start -0.12065 -0.2794)
			(end 0.12065 -0.2794)
			(stroke
				(width 0.1)
				(type default)
			)
			(layer "F.Fab")
		)
		(fp_line
			(start -0.12065 0.2794)
			(end -0.12065 0.3048)
			(stroke
				(width 0.1)
				(type default)
			)
			(layer "F.Fab")
		)
		(fp_line
			(start -0.12065 0.3048)
			(end -0.67945 0.3048)
			(stroke
				(width 0.1)
				(type default)
			)
			(layer "F.Fab")
		)
		(fp_line
			(start 0.120396 0.2794)
			(end -0.12065 0.2794)
			(stroke
				(width 0.1)
				(type default)
			)
			(layer "F.Fab")
		)
		(fp_line
			(start 0.120396 0.3048)
			(end 0.120396 0.2794)
			(stroke
				(width 0.1)
				(type default)
			)
			(layer "F.Fab")
		)
		(fp_line
			(start 0.12065 -0.3048)
			(end 0.67945 -0.3048)
			(stroke
				(width 0.1)
				(type default)
			)
			(layer "F.Fab")
		)
		(fp_line
			(start 0.12065 -0.2794)
			(end 0.12065 -0.3048)
			(stroke
				(width 0.1)
				(type default)
			)
			(layer "F.Fab")
		)
		(fp_line
			(start 0.67945 -0.3048)
			(end 0.67945 0.3048)
			(stroke
				(width 0.1)
				(type default)
			)
			(layer "F.Fab")
		)
		(fp_line
			(start 0.67945 0.3048)
			(end 0.120396 0.3048)
			(stroke
				(width 0.1)
				(type default)
			)
			(layer "F.Fab")
		)
		(pad "1" smd circle
			(at -0.40005 0)
			(size 0 0)
			(layers "F.Cu" "F.Mask" "F.Paste")
			(net "P12V_NIC5_CO_TIMER")
		)
		(pad "2" smd circle
			(at 0.40005 0)
			(size 0 0)
			(layers "F.Cu" "F.Mask" "F.Paste")
			(net "GND")
		)
	)
	(footprint ""
		(layer "F.Cu")
		(at 154.699716 -150.263352 180)
		(property "Reference" "R117"
			(at 0 0 180)
			(layer "F.SilkS")
			(hide yes)
			(effects
				(font
					(size 1.27 1.27)
				)
			)
		)
		(property "Value" ""
			(at 0 0 180)
			(layer "F.Fab")
			(effects
				(font
					(size 1.27 1.27)
				)
			)
		)
		(duplicate_pad_numbers_are_jumpers no)
		(fp_line
			(start 0.7874 0.4064)
			(end -0.7874 0.4064)
			(stroke
				(width 0.1524)
				(type default)
			)
			(layer "F.SilkS")
		)
		(fp_line
			(start 0.7874 -0.4064)
			(end 0.7874 0.4064)
			(stroke
				(width 0.1524)
				(type default)
			)
			(layer "F.SilkS")
		)
		(fp_line
			(start -0.7874 0.4064)
			(end -0.7874 -0.4064)
			(stroke
				(width 0.1524)
				(type default)
			)
			(layer "F.SilkS")
		)
		(fp_line
			(start -0.7874 -0.4064)
			(end 0.7874 -0.4064)
			(stroke
				(width 0.1524)
				(type default)
			)
			(layer "F.SilkS")
		)
		(fp_line
			(start 0.67945 0.3048)
			(end 0.120396 0.3048)
			(stroke
				(width 0.1)
				(type default)
			)
			(layer "F.Fab")
		)
		(fp_line
			(start 0.67945 -0.3048)
			(end 0.67945 0.3048)
			(stroke
				(width 0.1)
				(type default)
			)
			(layer "F.Fab")
		)
		(fp_line
			(start 0.12065 -0.2794)
			(end 0.12065 -0.3048)
			(stroke
				(width 0.1)
				(type default)
			)
			(layer "F.Fab")
		)
		(fp_line
			(start 0.12065 -0.3048)
			(end 0.67945 -0.3048)
			(stroke
				(width 0.1)
				(type default)
			)
			(layer "F.Fab")
		)
		(fp_line
			(start 0.120396 0.3048)
			(end 0.120396 0.2794)
			(stroke
				(width 0.1)
				(type default)
			)
			(layer "F.Fab")
		)
		(fp_line
			(start 0.120396 0.2794)
			(end -0.12065 0.2794)
			(stroke
				(width 0.1)
				(type default)
			)
			(layer "F.Fab")
		)
		(fp_line
			(start -0.12065 0.3048)
			(end -0.67945 0.3048)
			(stroke
				(width 0.1)
				(type default)
			)
			(layer "F.Fab")
		)
		(fp_line
			(start -0.12065 0.2794)
			(end -0.12065 0.3048)
			(stroke
				(width 0.1)
				(type default)
			)
			(layer "F.Fab")
		)
		(fp_line
			(start -0.12065 -0.2794)
			(end 0.12065 -0.2794)
			(stroke
				(width 0.1)
				(type default)
			)
			(layer "F.Fab")
		)
		(fp_line
			(start -0.12065 -0.305054)
			(end -0.12065 -0.2794)
			(stroke
				(width 0.1)
				(type default)
			)
			(layer "F.Fab")
		)
		(fp_line
			(start -0.67945 0.3048)
			(end -0.67945 -0.305054)
			(stroke
				(width 0.1)
				(type default)
			)
			(layer "F.Fab")
		)
		(fp_line
			(start -0.67945 -0.305054)
			(end -0.12065 -0.305054)
			(stroke
				(width 0.1)
				(type default)
			)
			(layer "F.Fab")
		)
		(pad "1" smd circle
			(at -0.40005 0 180)
			(size 0 0)
			(layers "F.Cu" "F.Mask" "F.Paste")
			(net "NCSI_NIC2_CRS_DV")
		)
		(pad "2" smd circle
			(at 0.40005 0 180)
			(size 0 0)
			(layers "F.Cu" "F.Mask" "F.Paste")
			(net "GND")
		)
	)
	(footprint ""
		(layer "F.Cu")
		(at 413.766508 -189.056518 180)
		(property "Reference" "R6425"
			(at 0 0 180)
			(layer "F.SilkS")
			(hide yes)
			(effects
				(font
					(size 1.27 1.27)
				)
			)
		)
		(property "Value" ""
			(at 0 0 180)
			(layer "F.Fab")
			(effects
				(font
					(size 1.27 1.27)
				)
			)
		)
		(duplicate_pad_numbers_are_jumpers no)
		(fp_line
			(start 0.7874 0.4064)
			(end -0.7874 0.4064)
			(stroke
				(width 0.1524)
				(type default)
			)
			(layer "F.SilkS")
		)
		(fp_line
			(start 0.7874 -0.4064)
			(end 0.7874 0.4064)
			(stroke
				(width 0.1524)
				(type default)
			)
			(layer "F.SilkS")
		)
		(fp_line
			(start -0.7874 0.4064)
			(end -0.7874 -0.4064)
			(stroke
				(width 0.1524)
				(type default)
			)
			(layer "F.SilkS")
		)
		(fp_line
			(start -0.7874 -0.4064)
			(end 0.7874 -0.4064)
			(stroke
				(width 0.1524)
				(type default)
			)
			(layer "F.SilkS")
		)
		(fp_line
			(start 0.67945 0.3048)
			(end 0.120396 0.3048)
			(stroke
				(width 0.1)
				(type default)
			)
			(layer "F.Fab")
		)
		(fp_line
			(start 0.67945 -0.3048)
			(end 0.67945 0.3048)
			(stroke
				(width 0.1)
				(type default)
			)
			(layer "F.Fab")
		)
		(fp_line
			(start 0.12065 -0.2794)
			(end 0.12065 -0.3048)
			(stroke
				(width 0.1)
				(type default)
			)
			(layer "F.Fab")
		)
		(fp_line
			(start 0.12065 -0.3048)
			(end 0.67945 -0.3048)
			(stroke
				(width 0.1)
				(type default)
			)
			(layer "F.Fab")
		)
		(fp_line
			(start 0.120396 0.3048)
			(end 0.120396 0.2794)
			(stroke
				(width 0.1)
				(type default)
			)
			(layer "F.Fab")
		)
		(fp_line
			(start 0.120396 0.2794)
			(end -0.12065 0.2794)
			(stroke
				(width 0.1)
				(type default)
			)
			(layer "F.Fab")
		)
		(fp_line
			(start -0.12065 0.3048)
			(end -0.67945 0.3048)
			(stroke
				(width 0.1)
				(type default)
			)
			(layer "F.Fab")
		)
		(fp_line
			(start -0.12065 0.2794)
			(end -0.12065 0.3048)
			(stroke
				(width 0.1)
				(type default)
			)
			(layer "F.Fab")
		)
		(fp_line
			(start -0.12065 -0.2794)
			(end 0.12065 -0.2794)
			(stroke
				(width 0.1)
				(type default)
			)
			(layer "F.Fab")
		)
		(fp_line
			(start -0.12065 -0.305054)
			(end -0.12065 -0.2794)
			(stroke
				(width 0.1)
				(type default)
			)
			(layer "F.Fab")
		)
		(fp_line
			(start -0.67945 0.3048)
			(end -0.67945 -0.305054)
			(stroke
				(width 0.1)
				(type default)
			)
			(layer "F.Fab")
		)
		(fp_line
			(start -0.67945 -0.305054)
			(end -0.12065 -0.305054)
			(stroke
				(width 0.1)
				(type default)
			)
			(layer "F.Fab")
		)
		(pad "1" smd circle
			(at -0.40005 0 180)
			(size 0 0)
			(layers "F.Cu" "F.Mask" "F.Paste")
			(net "FPGA_PEX0_MODE_SEL2_D_N")
		)
		(pad "2" smd circle
			(at 0.40005 0 180)
			(size 0 0)
			(layers "F.Cu" "F.Mask" "F.Paste")
			(net "P3V3_AUX")
		)
	)
	(footprint ""
		(layer "F.Cu")
		(at 110.635796 -111.896906 90)
		(property "Reference" "PR6872"
			(at 0 0 90)
			(layer "F.SilkS")
			(hide yes)
			(effects
				(font
					(size 1.27 1.27)
				)
			)
		)
		(property "Value" ""
			(at 0 0 90)
			(layer "F.Fab")
			(effects
				(font
					(size 1.27 1.27)
				)
			)
		)
		(duplicate_pad_numbers_are_jumpers no)
		(fp_line
			(start 0.7874 -0.4064)
			(end 0.7874 0.4064)
			(stroke
				(width 0.1524)
				(type default)
			)
			(layer "F.SilkS")
		)
		(fp_line
			(start -0.7874 -0.4064)
			(end 0.7874 -0.4064)
			(stroke
				(width 0.1524)
				(type default)
			)
			(layer "F.SilkS")
		)
		(fp_line
			(start 0.7874 0.4064)
			(end -0.7874 0.4064)
			(stroke
				(width 0.1524)
				(type default)
			)
			(layer "F.SilkS")
		)
		(fp_line
			(start -0.7874 0.4064)
			(end -0.7874 -0.4064)
			(stroke
				(width 0.1524)
				(type default)
			)
			(layer "F.SilkS")
		)
		(fp_line
			(start -0.12065 -0.305054)
			(end -0.12065 -0.2794)
			(stroke
				(width 0.1)
				(type default)
			)
			(layer "F.Fab")
		)
		(fp_line
			(start -0.67945 -0.305054)
			(end -0.12065 -0.305054)
			(stroke
				(width 0.1)
				(type default)
			)
			(layer "F.Fab")
		)
		(fp_line
			(start 0.67945 -0.3048)
			(end 0.67945 0.3048)
			(stroke
				(width 0.1)
				(type default)
			)
			(layer "F.Fab")
		)
		(fp_line
			(start 0.12065 -0.3048)
			(end 0.67945 -0.3048)
			(stroke
				(width 0.1)
				(type default)
			)
			(layer "F.Fab")
		)
		(fp_line
			(start 0.12065 -0.2794)
			(end 0.12065 -0.3048)
			(stroke
				(width 0.1)
				(type default)
			)
			(layer "F.Fab")
		)
		(fp_line
			(start -0.12065 -0.2794)
			(end 0.12065 -0.2794)
			(stroke
				(width 0.1)
				(type default)
			)
			(layer "F.Fab")
		)
		(fp_line
			(start 0.120396 0.2794)
			(end -0.12065 0.2794)
			(stroke
				(width 0.1)
				(type default)
			)
			(layer "F.Fab")
		)
		(fp_line
			(start -0.12065 0.2794)
			(end -0.12065 0.3048)
			(stroke
				(width 0.1)
				(type default)
			)
			(layer "F.Fab")
		)
		(fp_line
			(start 0.67945 0.3048)
			(end 0.120396 0.3048)
			(stroke
				(width 0.1)
				(type default)
			)
			(layer "F.Fab")
		)
		(fp_line
			(start 0.120396 0.3048)
			(end 0.120396 0.2794)
			(stroke
				(width 0.1)
				(type default)
			)
			(layer "F.Fab")
		)
		(fp_line
			(start -0.12065 0.3048)
			(end -0.67945 0.3048)
			(stroke
				(width 0.1)
				(type default)
			)
			(layer "F.Fab")
		)
		(fp_line
			(start -0.67945 0.3048)
			(end -0.67945 -0.305054)
			(stroke
				(width 0.1)
				(type default)
			)
			(layer "F.Fab")
		)
		(pad "1" smd circle
			(at -0.40005 0 90)
			(size 0 0)
			(layers "F.Cu" "F.Mask" "F.Paste")
			(net "P12V_NIC1_CO_ISET")
		)
		(pad "2" smd circle
			(at 0.40005 0 90)
			(size 0 0)
			(layers "F.Cu" "F.Mask" "F.Paste")
			(net "P12V_NIC1_CO_ISET_R")
		)
	)
	(footprint ""
		(layer "F.Cu")
		(at 402.641816 -27.006296 -90)
		(property "Reference" "PR7129"
			(at 0 0 270)
			(layer "F.SilkS")
			(hide yes)
			(effects
				(font
					(size 1.27 1.27)
				)
			)
		)
		(property "Value" ""
			(at 0 0 270)
			(layer "F.Fab")
			(effects
				(font
					(size 1.27 1.27)
				)
			)
		)
		(duplicate_pad_numbers_are_jumpers no)
		(fp_line
			(start -0.7874 0.4064)
			(end -0.7874 -0.4064)
			(stroke
				(width 0.1524)
				(type default)
			)
			(layer "F.SilkS")
		)
		(fp_line
			(start 0.7874 0.4064)
			(end -0.7874 0.4064)
			(stroke
				(width 0.1524)
				(type default)
			)
			(layer "F.SilkS")
		)
		(fp_line
			(start -0.7874 -0.4064)
			(end 0.7874 -0.4064)
			(stroke
				(width 0.1524)
				(type default)
			)
			(layer "F.SilkS")
		)
		(fp_line
			(start 0.7874 -0.4064)
			(end 0.7874 0.4064)
			(stroke
				(width 0.1524)
				(type default)
			)
			(layer "F.SilkS")
		)
		(fp_line
			(start -0.67945 0.3048)
			(end -0.67945 -0.305054)
			(stroke
				(width 0.1)
				(type default)
			)
			(layer "F.Fab")
		)
		(fp_line
			(start -0.12065 0.3048)
			(end -0.67945 0.3048)
			(stroke
				(width 0.1)
				(type default)
			)
			(layer "F.Fab")
		)
		(fp_line
			(start 0.120396 0.3048)
			(end 0.120396 0.2794)
			(stroke
				(width 0.1)
				(type default)
			)
			(layer "F.Fab")
		)
		(fp_line
			(start 0.67945 0.3048)
			(end 0.120396 0.3048)
			(stroke
				(width 0.1)
				(type default)
			)
			(layer "F.Fab")
		)
		(fp_line
			(start -0.12065 0.2794)
			(end -0.12065 0.3048)
			(stroke
				(width 0.1)
				(type default)
			)
			(layer "F.Fab")
		)
		(fp_line
			(start 0.120396 0.2794)
			(end -0.12065 0.2794)
			(stroke
				(width 0.1)
				(type default)
			)
			(layer "F.Fab")
		)
		(fp_line
			(start -0.12065 -0.2794)
			(end 0.12065 -0.2794)
			(stroke
				(width 0.1)
				(type default)
			)
			(layer "F.Fab")
		)
		(fp_line
			(start 0.12065 -0.2794)
			(end 0.12065 -0.3048)
			(stroke
				(width 0.1)
				(type default)
			)
			(layer "F.Fab")
		)
		(fp_line
			(start 0.12065 -0.3048)
			(end 0.67945 -0.3048)
			(stroke
				(width 0.1)
				(type default)
			)
			(layer "F.Fab")
		)
		(fp_line
			(start 0.67945 -0.3048)
			(end 0.67945 0.3048)
			(stroke
				(width 0.1)
				(type default)
			)
			(layer "F.Fab")
		)
		(fp_line
			(start -0.67945 -0.305054)
			(end -0.12065 -0.305054)
			(stroke
				(width 0.1)
				(type default)
			)
			(layer "F.Fab")
		)
		(fp_line
			(start -0.12065 -0.305054)
			(end -0.12065 -0.2794)
			(stroke
				(width 0.1)
				(type default)
			)
			(layer "F.Fab")
		)
		(pad "1" smd circle
			(at -0.40005 0 270)
			(size 0 0)
			(layers "F.Cu" "F.Mask" "F.Paste")
			(net "P3V3_SSD14_CO_ILIMIT")
		)
		(pad "2" smd circle
			(at 0.40005 0 270)
			(size 0 0)
			(layers "F.Cu" "F.Mask" "F.Paste")
			(net "GND")
		)
	)
	(footprint ""
		(layer "F.Cu")
		(at 396.209266 -84.928202 180)
		(property "Reference" "R1760"
			(at 0 0 180)
			(layer "F.SilkS")
			(hide yes)
			(effects
				(font
					(size 1.27 1.27)
				)
			)
		)
		(property "Value" ""
			(at 0 0 180)
			(layer "F.Fab")
			(effects
				(font
					(size 1.27 1.27)
				)
			)
		)
		(duplicate_pad_numbers_are_jumpers no)
		(fp_line
			(start 0.7874 0.4064)
			(end -0.7874 0.4064)
			(stroke
				(width 0.1524)
				(type default)
			)
			(layer "F.SilkS")
		)
		(fp_line
			(start 0.7874 -0.4064)
			(end 0.7874 0.4064)
			(stroke
				(width 0.1524)
				(type default)
			)
			(layer "F.SilkS")
		)
		(fp_line
			(start -0.7874 0.4064)
			(end -0.7874 -0.4064)
			(stroke
				(width 0.1524)
				(type default)
			)
			(layer "F.SilkS")
		)
		(fp_line
			(start -0.7874 -0.4064)
			(end 0.7874 -0.4064)
			(stroke
				(width 0.1524)
				(type default)
			)
			(layer "F.SilkS")
		)
		(fp_line
			(start 0.67945 0.3048)
			(end 0.120396 0.3048)
			(stroke
				(width 0.1)
				(type default)
			)
			(layer "F.Fab")
		)
		(fp_line
			(start 0.67945 -0.3048)
			(end 0.67945 0.3048)
			(stroke
				(width 0.1)
				(type default)
			)
			(layer "F.Fab")
		)
		(fp_line
			(start 0.12065 -0.2794)
			(end 0.12065 -0.3048)
			(stroke
				(width 0.1)
				(type default)
			)
			(layer "F.Fab")
		)
		(fp_line
			(start 0.12065 -0.3048)
			(end 0.67945 -0.3048)
			(stroke
				(width 0.1)
				(type default)
			)
			(layer "F.Fab")
		)
		(fp_line
			(start 0.120396 0.3048)
			(end 0.120396 0.2794)
			(stroke
				(width 0.1)
				(type default)
			)
			(layer "F.Fab")
		)
		(fp_line
			(start 0.120396 0.2794)
			(end -0.12065 0.2794)
			(stroke
				(width 0.1)
				(type default)
			)
			(layer "F.Fab")
		)
		(fp_line
			(start -0.12065 0.3048)
			(end -0.67945 0.3048)
			(stroke
				(width 0.1)
				(type default)
			)
			(layer "F.Fab")
		)
		(fp_line
			(start -0.12065 0.2794)
			(end -0.12065 0.3048)
			(stroke
				(width 0.1)
				(type default)
			)
			(layer "F.Fab")
		)
		(fp_line
			(start -0.12065 -0.2794)
			(end 0.12065 -0.2794)
			(stroke
				(width 0.1)
				(type default)
			)
			(layer "F.Fab")
		)
		(fp_line
			(start -0.12065 -0.305054)
			(end -0.12065 -0.2794)
			(stroke
				(width 0.1)
				(type default)
			)
			(layer "F.Fab")
		)
		(fp_line
			(start -0.67945 0.3048)
			(end -0.67945 -0.305054)
			(stroke
				(width 0.1)
				(type default)
			)
			(layer "F.Fab")
		)
		(fp_line
			(start -0.67945 -0.305054)
			(end -0.12065 -0.305054)
			(stroke
				(width 0.1)
				(type default)
			)
			(layer "F.Fab")
		)
		(pad "1" smd circle
			(at -0.40005 0 180)
			(size 0 0)
			(layers "F.Cu" "F.Mask" "F.Paste")
			(net "P3V3_AUX")
		)
		(pad "2" smd circle
			(at 0.40005 0 180)
			(size 0 0)
			(layers "F.Cu" "F.Mask" "F.Paste")
			(net "SMB_BIC_I2C6_MUX_VR_R_SDA")
		)
	)
	(footprint ""
		(layer "F.Cu")
		(at 239.289844 -201.25182)
		(property "Reference" "C3620"
			(at 0 0 0)
			(layer "F.SilkS")
			(hide yes)
			(effects
				(font
					(size 1.27 1.27)
				)
			)
		)
		(property "Value" ""
			(at 0 0 0)
			(layer "F.Fab")
			(effects
				(font
					(size 1.27 1.27)
				)
			)
		)
		(duplicate_pad_numbers_are_jumpers no)
		(fp_line
			(start -0.7874 -0.4064)
			(end 0.7874 -0.4064)
			(stroke
				(width 0.1524)
				(type default)
			)
			(layer "F.SilkS")
		)
		(fp_line
			(start -0.7874 0.4064)
			(end -0.7874 -0.4064)
			(stroke
				(width 0.1524)
				(type default)
			)
			(layer "F.SilkS")
		)
		(fp_line
			(start 0.7874 -0.4064)
			(end 0.7874 0.4064)
			(stroke
				(width 0.1524)
				(type default)
			)
			(layer "F.SilkS")
		)
		(fp_line
			(start 0.7874 0.4064)
			(end -0.7874 0.4064)
			(stroke
				(width 0.1524)
				(type default)
			)
			(layer "F.SilkS")
		)
		(fp_line
			(start -0.67945 -0.305054)
			(end -0.12065 -0.305054)
			(stroke
				(width 0.1)
				(type default)
			)
			(layer "F.Fab")
		)
		(fp_line
			(start -0.67945 0.3048)
			(end -0.67945 -0.305054)
			(stroke
				(width 0.1)
				(type default)
			)
			(layer "F.Fab")
		)
		(fp_line
			(start -0.12065 -0.305054)
			(end -0.12065 -0.2794)
			(stroke
				(width 0.1)
				(type default)
			)
			(layer "F.Fab")
		)
		(fp_line
			(start -0.12065 -0.2794)
			(end 0.12065 -0.2794)
			(stroke
				(width 0.1)
				(type default)
			)
			(layer "F.Fab")
		)
		(fp_line
			(start -0.12065 0.2794)
			(end -0.12065 0.3048)
			(stroke
				(width 0.1)
				(type default)
			)
			(layer "F.Fab")
		)
		(fp_line
			(start -0.12065 0.3048)
			(end -0.67945 0.3048)
			(stroke
				(width 0.1)
				(type default)
			)
			(layer "F.Fab")
		)
		(fp_line
			(start 0.120396 0.2794)
			(end -0.12065 0.2794)
			(stroke
				(width 0.1)
				(type default)
			)
			(layer "F.Fab")
		)
		(fp_line
			(start 0.120396 0.3048)
			(end 0.120396 0.2794)
			(stroke
				(width 0.1)
				(type default)
			)
			(layer "F.Fab")
		)
		(fp_line
			(start 0.12065 -0.3048)
			(end 0.67945 -0.3048)
			(stroke
				(width 0.1)
				(type default)
			)
			(layer "F.Fab")
		)
		(fp_line
			(start 0.12065 -0.2794)
			(end 0.12065 -0.3048)
			(stroke
				(width 0.1)
				(type default)
			)
			(layer "F.Fab")
		)
		(fp_line
			(start 0.67945 -0.3048)
			(end 0.67945 0.3048)
			(stroke
				(width 0.1)
				(type default)
			)
			(layer "F.Fab")
		)
		(fp_line
			(start 0.67945 0.3048)
			(end 0.120396 0.3048)
			(stroke
				(width 0.1)
				(type default)
			)
			(layer "F.Fab")
		)
		(pad "1" smd circle
			(at -0.40005 0)
			(size 0 0)
			(layers "F.Cu" "F.Mask" "F.Paste")
			(net "P3V3_AUX")
		)
		(pad "2" smd circle
			(at 0.40005 0)
			(size 0 0)
			(layers "F.Cu" "F.Mask" "F.Paste")
			(net "GND")
		)
	)
	(footprint ""
		(layer "F.Cu")
		(at 26.991056 -255.359662)
		(property "Reference" "C3065"
			(at 0 0 0)
			(layer "F.SilkS")
			(hide yes)
			(effects
				(font
					(size 1.27 1.27)
				)
			)
		)
		(property "Value" ""
			(at 0 0 0)
			(layer "F.Fab")
			(effects
				(font
					(size 1.27 1.27)
				)
			)
		)
		(duplicate_pad_numbers_are_jumpers no)
		(fp_line
			(start -1.2954 -0.5842)
			(end 1.2954 -0.5842)
			(stroke
				(width 0.1524)
				(type default)
			)
			(layer "F.SilkS")
		)
		(fp_line
			(start -1.2954 0.5842)
			(end -1.2954 -0.5842)
			(stroke
				(width 0.1524)
				(type default)
			)
			(layer "F.SilkS")
		)
		(fp_line
			(start 1.2954 -0.5842)
			(end 1.2954 0.5842)
			(stroke
				(width 0.1524)
				(type default)
			)
			(layer "F.SilkS")
		)
		(fp_line
			(start 1.2954 0.5842)
			(end -1.2954 0.5842)
			(stroke
				(width 0.1524)
				(type default)
			)
			(layer "F.SilkS")
		)
		(fp_line
			(start -1.1938 -0.4064)
			(end -0.8636 -0.4064)
			(stroke
				(width 0.1)
				(type default)
			)
			(layer "F.Fab")
		)
		(fp_line
			(start -1.1938 0.4064)
			(end -1.1938 -0.4064)
			(stroke
				(width 0.1)
				(type default)
			)
			(layer "F.Fab")
		)
		(fp_line
			(start -0.8636 -0.4572)
			(end 0.8636 -0.4572)
			(stroke
				(width 0.1)
				(type default)
			)
			(layer "F.Fab")
		)
		(fp_line
			(start -0.8636 -0.4064)
			(end -0.8636 -0.4572)
			(stroke
				(width 0.1)
				(type default)
			)
			(layer "F.Fab")
		)
		(fp_line
			(start -0.8636 0.4064)
			(end -1.1938 0.4064)
			(stroke
				(width 0.1)
				(type default)
			)
			(layer "F.Fab")
		)
		(fp_line
			(start -0.8636 0.4572)
			(end -0.8636 0.4064)
			(stroke
				(width 0.1)
				(type default)
			)
			(layer "F.Fab")
		)
		(fp_line
			(start 0.8636 -0.4572)
			(end 0.8636 -0.4064)
			(stroke
				(width 0.1)
				(type default)
			)
			(layer "F.Fab")
		)
		(fp_line
			(start 0.8636 -0.4064)
			(end 1.1938 -0.4064)
			(stroke
				(width 0.1)
				(type default)
			)
			(layer "F.Fab")
		)
		(fp_line
			(start 0.8636 0.4064)
			(end 0.8636 0.4572)
			(stroke
				(width 0.1)
				(type default)
			)
			(layer "F.Fab")
		)
		(fp_line
			(start 0.8636 0.4572)
			(end -0.8636 0.4572)
			(stroke
				(width 0.1)
				(type default)
			)
			(layer "F.Fab")
		)
		(fp_line
			(start 1.1938 -0.4064)
			(end 1.1938 0.4064)
			(stroke
				(width 0.1)
				(type default)
			)
			(layer "F.Fab")
		)
		(fp_line
			(start 1.1938 0.4064)
			(end 0.8636 0.4064)
			(stroke
				(width 0.1)
				(type default)
			)
			(layer "F.Fab")
		)
		(pad "1" smd rect
			(at -0.7366 0 270)
			(size 0.7112 0.8128)
			(layers "F.Cu" "F.Mask" "F.Paste")
			(net "P1V8_PLL0_PEX0")
		)
		(pad "2" smd rect
			(at 0.7366 0 270)
			(size 0.7112 0.8128)
			(layers "F.Cu" "F.Mask" "F.Paste")
			(net "GND")
		)
	)
	(footprint ""
		(layer "F.Cu")
		(at 304.775362 -69.47916 180)
		(property "Reference" "PU114"
			(at -1.956308 4.07924 90)
			(unlocked yes)
			(layer "F.SilkS")
			(effects
				(font
					(size 0.7874 0.5842)
					(thickness 0.1524)
				)
			)
		)
		(property "Value" ""
			(at 0 0 180)
			(layer "F.Fab")
			(effects
				(font
					(size 1.27 1.27)
				)
			)
		)
		(duplicate_pad_numbers_are_jumpers no)
		(fp_line
			(start 1.239774 1.495298)
			(end -1.239774 1.495298)
			(stroke
				(width 0.1524)
				(type default)
			)
			(layer "F.SilkS")
		)
		(fp_line
			(start 1.239774 -1.495298)
			(end 1.239774 1.495298)
			(stroke
				(width 0.1524)
				(type default)
			)
			(layer "F.SilkS")
		)
		(fp_line
			(start -1.239774 1.495298)
			(end -1.239774 -1.495298)
			(stroke
				(width 0.1524)
				(type default)
			)
			(layer "F.SilkS")
		)
		(fp_line
			(start -1.239774 -1.495298)
			(end 1.239774 -1.495298)
			(stroke
				(width 0.1524)
				(type default)
			)
			(layer "F.SilkS")
		)
		(fp_poly
			(pts
				(xy -1.684274 -1.175766) (xy -2.402586 -0.457454) (xy -1.324864 -0.098298)
			)
			(stroke
				(width 0)
				(type default)
			)
			(fill yes)
			(layer "F.SilkS")
		)
		(fp_line
			(start 0.8001 1.050036)
			(end -0.8001 1.050036)
			(stroke
				(width 0.1)
				(type default)
			)
			(layer "F.Fab")
		)
		(fp_line
			(start 0.8001 -1.050036)
			(end 0.8001 1.050036)
			(stroke
				(width 0.1)
				(type default)
			)
			(layer "F.Fab")
		)
		(fp_line
			(start -0.8001 1.050036)
			(end -0.8001 -1.050036)
			(stroke
				(width 0.1)
				(type default)
			)
			(layer "F.Fab")
		)
		(fp_line
			(start -0.8001 -1.050036)
			(end 0.8001 -1.050036)
			(stroke
				(width 0.1)
				(type default)
			)
			(layer "F.Fab")
		)
		(fp_poly
			(pts
				(xy -2.458974 -0.508) (xy -2.458974 0.508) (xy -1.442974 0)
			)
			(stroke
				(width 0)
				(type default)
			)
			(fill yes)
			(layer "F.Fab")
		)
		(pad "1_2" smd circle
			(at -0.374904 0 270)
			(size 0 0)
			(layers "F.Cu" "F.Mask" "F.Paste")
			(net "P12V_AUX")
		)
		(pad "3" smd rect
			(at -0.499872 0.999998 180)
			(size 0.254 0.7112)
			(layers "F.Cu" "F.Mask" "F.Paste")
			(net "GND")
		)
		(pad "4" smd rect
			(at 0 0.999998 180)
			(size 0.254 0.7112)
			(layers "F.Cu" "F.Mask" "F.Paste")
			(net "P12V_SSD10_CO_ILIMIT")
		)
		(pad "5" smd rect
			(at 0.499872 0.999998 180)
			(size 0.254 0.7112)
			(layers "F.Cu" "F.Mask" "F.Paste")
			(net "P12V_SSD10_CO_MODE")
		)
		(pad "6_7" smd circle
			(at 0.374904 0 90)
			(size 0 0)
			(layers "F.Cu" "F.Mask" "F.Paste")
			(net "P12V_SSD10_R")
		)
		(pad "8" smd rect
			(at 0.499872 -0.999998 180)
			(size 0.254 0.7112)
			(layers "F.Cu" "F.Mask" "F.Paste")
			(net "P12V_SSD10_CO_GATE")
		)
		(pad "9" smd rect
			(at 0 -0.999998 180)
			(size 0.254 0.7112)
			(layers "F.Cu" "F.Mask" "F.Paste")
			(net "P12V_SSD10_CO_EN")
		)
		(pad "10" smd rect
			(at -0.499872 -0.999998 180)
			(size 0.254 0.7112)
			(layers "F.Cu" "F.Mask" "F.Paste")
			(net "P12V_SSD10_CO_DV_DT")
		)
	)
	(footprint ""
		(layer "F.Cu")
		(at 118.975378 -63.086234)
		(property "Reference" "R5978"
			(at 0 0 0)
			(layer "F.SilkS")
			(hide yes)
			(effects
				(font
					(size 1.27 1.27)
				)
			)
		)
		(property "Value" ""
			(at 0 0 0)
			(layer "F.Fab")
			(effects
				(font
					(size 1.27 1.27)
				)
			)
		)
		(duplicate_pad_numbers_are_jumpers no)
		(fp_line
			(start -0.7874 -0.4064)
			(end 0.7874 -0.4064)
			(stroke
				(width 0.1524)
				(type default)
			)
			(layer "F.SilkS")
		)
		(fp_line
			(start -0.7874 0.4064)
			(end -0.7874 -0.4064)
			(stroke
				(width 0.1524)
				(type default)
			)
			(layer "F.SilkS")
		)
		(fp_line
			(start 0.7874 -0.4064)
			(end 0.7874 0.4064)
			(stroke
				(width 0.1524)
				(type default)
			)
			(layer "F.SilkS")
		)
		(fp_line
			(start 0.7874 0.4064)
			(end -0.7874 0.4064)
			(stroke
				(width 0.1524)
				(type default)
			)
			(layer "F.SilkS")
		)
		(fp_line
			(start -0.67945 -0.305054)
			(end -0.12065 -0.305054)
			(stroke
				(width 0.1)
				(type default)
			)
			(layer "F.Fab")
		)
		(fp_line
			(start -0.67945 0.3048)
			(end -0.67945 -0.305054)
			(stroke
				(width 0.1)
				(type default)
			)
			(layer "F.Fab")
		)
		(fp_line
			(start -0.12065 -0.305054)
			(end -0.12065 -0.2794)
			(stroke
				(width 0.1)
				(type default)
			)
			(layer "F.Fab")
		)
		(fp_line
			(start -0.12065 -0.2794)
			(end 0.12065 -0.2794)
			(stroke
				(width 0.1)
				(type default)
			)
			(layer "F.Fab")
		)
		(fp_line
			(start -0.12065 0.2794)
			(end -0.12065 0.3048)
			(stroke
				(width 0.1)
				(type default)
			)
			(layer "F.Fab")
		)
		(fp_line
			(start -0.12065 0.3048)
			(end -0.67945 0.3048)
			(stroke
				(width 0.1)
				(type default)
			)
			(layer "F.Fab")
		)
		(fp_line
			(start 0.120396 0.2794)
			(end -0.12065 0.2794)
			(stroke
				(width 0.1)
				(type default)
			)
			(layer "F.Fab")
		)
		(fp_line
			(start 0.120396 0.3048)
			(end 0.120396 0.2794)
			(stroke
				(width 0.1)
				(type default)
			)
			(layer "F.Fab")
		)
		(fp_line
			(start 0.12065 -0.3048)
			(end 0.67945 -0.3048)
			(stroke
				(width 0.1)
				(type default)
			)
			(layer "F.Fab")
		)
		(fp_line
			(start 0.12065 -0.2794)
			(end 0.12065 -0.3048)
			(stroke
				(width 0.1)
				(type default)
			)
			(layer "F.Fab")
		)
		(fp_line
			(start 0.67945 -0.3048)
			(end 0.67945 0.3048)
			(stroke
				(width 0.1)
				(type default)
			)
			(layer "F.Fab")
		)
		(fp_line
			(start 0.67945 0.3048)
			(end 0.120396 0.3048)
			(stroke
				(width 0.1)
				(type default)
			)
			(layer "F.Fab")
		)
		(pad "1" smd circle
			(at -0.40005 0)
			(size 0 0)
			(layers "F.Cu" "F.Mask" "F.Paste")
			(net "P12V_SSD4_R")
		)
		(pad "2" smd circle
			(at 0.40005 0)
			(size 0 0)
			(layers "F.Cu" "F.Mask" "F.Paste")
			(net "P12V_SSD4_PG_G1")
		)
	)
	(footprint ""
		(layer "F.Cu")
		(at 62.215268 -393.16279 -90)
		(property "Reference" "C4014"
			(at 0 0 270)
			(layer "F.SilkS")
			(hide yes)
			(effects
				(font
					(size 1.27 1.27)
				)
			)
		)
		(property "Value" ""
			(at 0 0 270)
			(layer "F.Fab")
			(effects
				(font
					(size 1.27 1.27)
				)
			)
		)
		(duplicate_pad_numbers_are_jumpers no)
		(fp_line
			(start -0.7874 0.4064)
			(end -0.7874 -0.4064)
			(stroke
				(width 0.1524)
				(type default)
			)
			(layer "F.SilkS")
		)
		(fp_line
			(start 0.7874 0.4064)
			(end -0.7874 0.4064)
			(stroke
				(width 0.1524)
				(type default)
			)
			(layer "F.SilkS")
		)
		(fp_line
			(start -0.7874 -0.4064)
			(end 0.7874 -0.4064)
			(stroke
				(width 0.1524)
				(type default)
			)
			(layer "F.SilkS")
		)
		(fp_line
			(start 0.7874 -0.4064)
			(end 0.7874 0.4064)
			(stroke
				(width 0.1524)
				(type default)
			)
			(layer "F.SilkS")
		)
		(fp_line
			(start -0.67945 0.3048)
			(end -0.67945 -0.305054)
			(stroke
				(width 0.1)
				(type default)
			)
			(layer "F.Fab")
		)
		(fp_line
			(start -0.12065 0.3048)
			(end -0.67945 0.3048)
			(stroke
				(width 0.1)
				(type default)
			)
			(layer "F.Fab")
		)
		(fp_line
			(start 0.120396 0.3048)
			(end 0.120396 0.2794)
			(stroke
				(width 0.1)
				(type default)
			)
			(layer "F.Fab")
		)
		(fp_line
			(start 0.67945 0.3048)
			(end 0.120396 0.3048)
			(stroke
				(width 0.1)
				(type default)
			)
			(layer "F.Fab")
		)
		(fp_line
			(start -0.12065 0.2794)
			(end -0.12065 0.3048)
			(stroke
				(width 0.1)
				(type default)
			)
			(layer "F.Fab")
		)
		(fp_line
			(start 0.120396 0.2794)
			(end -0.12065 0.2794)
			(stroke
				(width 0.1)
				(type default)
			)
			(layer "F.Fab")
		)
		(fp_line
			(start -0.12065 -0.2794)
			(end 0.12065 -0.2794)
			(stroke
				(width 0.1)
				(type default)
			)
			(layer "F.Fab")
		)
		(fp_line
			(start 0.12065 -0.2794)
			(end 0.12065 -0.3048)
			(stroke
				(width 0.1)
				(type default)
			)
			(layer "F.Fab")
		)
		(fp_line
			(start 0.12065 -0.3048)
			(end 0.67945 -0.3048)
			(stroke
				(width 0.1)
				(type default)
			)
			(layer "F.Fab")
		)
		(fp_line
			(start 0.67945 -0.3048)
			(end 0.67945 0.3048)
			(stroke
				(width 0.1)
				(type default)
			)
			(layer "F.Fab")
		)
		(fp_line
			(start -0.67945 -0.305054)
			(end -0.12065 -0.305054)
			(stroke
				(width 0.1)
				(type default)
			)
			(layer "F.Fab")
		)
		(fp_line
			(start -0.12065 -0.305054)
			(end -0.12065 -0.2794)
			(stroke
				(width 0.1)
				(type default)
			)
			(layer "F.Fab")
		)
		(pad "1" smd circle
			(at -0.40005 0 270)
			(size 0 0)
			(layers "F.Cu" "F.Mask" "F.Paste")
			(net "GND")
		)
		(pad "2" smd circle
			(at 0.40005 0 270)
			(size 0 0)
			(layers "F.Cu" "F.Mask" "F.Paste")
			(net "PRSNT_GPU_N")
		)
	)
	(footprint ""
		(layer "F.Cu")
		(at 242.447318 -266.873228)
		(property "Reference" "R6136"
			(at 0 0 0)
			(layer "F.SilkS")
			(hide yes)
			(effects
				(font
					(size 1.27 1.27)
				)
			)
		)
		(property "Value" ""
			(at 0 0 0)
			(layer "F.Fab")
			(effects
				(font
					(size 1.27 1.27)
				)
			)
		)
		(duplicate_pad_numbers_are_jumpers no)
		(fp_line
			(start -2.576322 -1.1303)
			(end 2.576322 -1.1303)
			(stroke
				(width 0.1524)
				(type default)
			)
			(layer "F.SilkS")
		)
		(fp_line
			(start -2.576322 1.1303)
			(end -2.576322 -1.1303)
			(stroke
				(width 0.1524)
				(type default)
			)
			(layer "F.SilkS")
		)
		(fp_line
			(start 2.576322 -1.1303)
			(end 2.576322 1.1303)
			(stroke
				(width 0.1524)
				(type default)
			)
			(layer "F.SilkS")
		)
		(fp_line
			(start 2.576322 1.1303)
			(end -2.576322 1.1303)
			(stroke
				(width 0.1524)
				(type default)
			)
			(layer "F.SilkS")
		)
		(fp_line
			(start -1.649984 -0.899922)
			(end -1.649984 0.899922)
			(stroke
				(width 0.1)
				(type default)
			)
			(layer "F.Fab")
		)
		(fp_line
			(start -1.649984 0.899922)
			(end 1.649984 0.899922)
			(stroke
				(width 0.1)
				(type default)
			)
			(layer "F.Fab")
		)
		(fp_line
			(start 1.649984 -0.899922)
			(end -1.649984 -0.899922)
			(stroke
				(width 0.1)
				(type default)
			)
			(layer "F.Fab")
		)
		(fp_line
			(start 1.649984 0.899922)
			(end 1.649984 -0.899922)
			(stroke
				(width 0.1)
				(type default)
			)
			(layer "F.Fab")
		)
		(pad "1A" smd rect
			(at -1.700022 0)
			(size 1.4986 2.0066)
			(layers "F.Cu" "F.Mask" "F.Paste")
			(net "P1V25_PEX2")
		)
		(pad "1B" smd rect
			(at -1.077722 0)
			(size 0.254 0.508)
			(layers "F.Cu" "F.Mask" "F.Paste")
			(net "P1V25_PEX2")
		)
		(pad "2A" smd rect
			(at 1.700022 0)
			(size 1.4986 2.0066)
			(layers "F.Cu" "F.Mask" "F.Paste")
			(net "P1V25_SERDES_VDDPLL_PEX2")
		)
		(pad "2B" smd rect
			(at 1.077722 0)
			(size 0.254 0.508)
			(layers "F.Cu" "F.Mask" "F.Paste")
			(net "P1V25_SERDES_VDDPLL_PEX2")
		)
	)
	(footprint ""
		(layer "F.Cu")
		(at 382.420622 -26.666444 -90)
		(property "Reference" "R4079"
			(at 0 0 270)
			(layer "F.SilkS")
			(hide yes)
			(effects
				(font
					(size 1.27 1.27)
				)
			)
		)
		(property "Value" ""
			(at 0 0 270)
			(layer "F.Fab")
			(effects
				(font
					(size 1.27 1.27)
				)
			)
		)
		(duplicate_pad_numbers_are_jumpers no)
		(fp_line
			(start -0.7874 0.4064)
			(end -0.7874 -0.4064)
			(stroke
				(width 0.1524)
				(type default)
			)
			(layer "F.SilkS")
		)
		(fp_line
			(start 0.7874 0.4064)
			(end -0.7874 0.4064)
			(stroke
				(width 0.1524)
				(type default)
			)
			(layer "F.SilkS")
		)
		(fp_line
			(start -0.7874 -0.4064)
			(end 0.7874 -0.4064)
			(stroke
				(width 0.1524)
				(type default)
			)
			(layer "F.SilkS")
		)
		(fp_line
			(start 0.7874 -0.4064)
			(end 0.7874 0.4064)
			(stroke
				(width 0.1524)
				(type default)
			)
			(layer "F.SilkS")
		)
		(fp_line
			(start -0.67945 0.3048)
			(end -0.67945 -0.305054)
			(stroke
				(width 0.1)
				(type default)
			)
			(layer "F.Fab")
		)
		(fp_line
			(start -0.12065 0.3048)
			(end -0.67945 0.3048)
			(stroke
				(width 0.1)
				(type default)
			)
			(layer "F.Fab")
		)
		(fp_line
			(start 0.120396 0.3048)
			(end 0.120396 0.2794)
			(stroke
				(width 0.1)
				(type default)
			)
			(layer "F.Fab")
		)
		(fp_line
			(start 0.67945 0.3048)
			(end 0.120396 0.3048)
			(stroke
				(width 0.1)
				(type default)
			)
			(layer "F.Fab")
		)
		(fp_line
			(start -0.12065 0.2794)
			(end -0.12065 0.3048)
			(stroke
				(width 0.1)
				(type default)
			)
			(layer "F.Fab")
		)
		(fp_line
			(start 0.120396 0.2794)
			(end -0.12065 0.2794)
			(stroke
				(width 0.1)
				(type default)
			)
			(layer "F.Fab")
		)
		(fp_line
			(start -0.12065 -0.2794)
			(end 0.12065 -0.2794)
			(stroke
				(width 0.1)
				(type default)
			)
			(layer "F.Fab")
		)
		(fp_line
			(start 0.12065 -0.2794)
			(end 0.12065 -0.3048)
			(stroke
				(width 0.1)
				(type default)
			)
			(layer "F.Fab")
		)
		(fp_line
			(start 0.12065 -0.3048)
			(end 0.67945 -0.3048)
			(stroke
				(width 0.1)
				(type default)
			)
			(layer "F.Fab")
		)
		(fp_line
			(start 0.67945 -0.3048)
			(end 0.67945 0.3048)
			(stroke
				(width 0.1)
				(type default)
			)
			(layer "F.Fab")
		)
		(fp_line
			(start -0.67945 -0.305054)
			(end -0.12065 -0.305054)
			(stroke
				(width 0.1)
				(type default)
			)
			(layer "F.Fab")
		)
		(fp_line
			(start -0.12065 -0.305054)
			(end -0.12065 -0.2794)
			(stroke
				(width 0.1)
				(type default)
			)
			(layer "F.Fab")
		)
		(pad "1" smd circle
			(at -0.40005 0 270)
			(size 0 0)
			(layers "F.Cu" "F.Mask" "F.Paste")
			(net "PRSNT_SSD13_R_N")
		)
		(pad "2" smd circle
			(at 0.40005 0 270)
			(size 0 0)
			(layers "F.Cu" "F.Mask" "F.Paste")
			(net "PRSNT_SSD13_N")
		)
	)
	(footprint ""
		(layer "F.Cu")
		(at 314.861448 -132.601208 180)
		(property "Reference" "C443"
			(at 0 0 180)
			(layer "F.SilkS")
			(hide yes)
			(effects
				(font
					(size 1.27 1.27)
				)
			)
		)
		(property "Value" ""
			(at 0 0 180)
			(layer "F.Fab")
			(effects
				(font
					(size 1.27 1.27)
				)
			)
		)
		(duplicate_pad_numbers_are_jumpers no)
		(fp_line
			(start 0.299974 0.150114)
			(end -0.299974 0.150114)
			(stroke
				(width 0.1)
				(type default)
			)
			(layer "F.Fab")
		)
		(fp_line
			(start 0.299974 -0.150114)
			(end 0.299974 0.150114)
			(stroke
				(width 0.1)
				(type default)
			)
			(layer "F.Fab")
		)
		(fp_line
			(start -0.299974 0.150114)
			(end -0.299974 -0.150114)
			(stroke
				(width 0.1)
				(type default)
			)
			(layer "F.Fab")
		)
		(fp_line
			(start -0.299974 -0.150114)
			(end 0.299974 -0.150114)
			(stroke
				(width 0.1)
				(type default)
			)
			(layer "F.Fab")
		)
		(pad "1" smd rect
			(at -0.2667 0 180)
			(size 0.3048 0.381)
			(layers "F.Cu" "F.Mask" "F.Paste")
			(net "P5E_PEX2_STN0_TX_DP<5>")
		)
		(pad "2" smd rect
			(at 0.2667 0 180)
			(size 0.3048 0.381)
			(layers "F.Cu" "F.Mask" "F.Paste")
			(net "P5E_PEX2_STN0_TX_C_DP<5>")
		)
	)
	(footprint ""
		(layer "F.Cu")
		(at 422.947084 -54.3941)
		(property "Reference" "PU43"
			(at -1.670812 2.828798 0)
			(unlocked yes)
			(layer "F.SilkS")
			(effects
				(font
					(size 0.7874 0.5842)
					(thickness 0.1524)
				)
				(justify left)
			)
		)
		(property "Value" ""
			(at 0 0 0)
			(layer "F.Fab")
			(effects
				(font
					(size 1.27 1.27)
				)
			)
		)
		(duplicate_pad_numbers_are_jumpers no)
		(fp_line
			(start -1.943608 -1.549908)
			(end 1.943608 -1.549908)
			(stroke
				(width 0.1524)
				(type default)
			)
			(layer "F.SilkS")
		)
		(fp_line
			(start -1.943608 1.549908)
			(end -1.943608 -1.549908)
			(stroke
				(width 0.1524)
				(type default)
			)
			(layer "F.SilkS")
		)
		(fp_line
			(start 1.943608 -1.549908)
			(end 1.943608 1.549908)
			(stroke
				(width 0.1524)
				(type default)
			)
			(layer "F.SilkS")
		)
		(fp_line
			(start 1.943608 1.549908)
			(end -1.943608 1.549908)
			(stroke
				(width 0.1524)
				(type default)
			)
			(layer "F.SilkS")
		)
		(fp_poly
			(pts
				(xy -2.019808 -1.549908) (xy -1.257808 -1.549908) (xy -1.257808 -1.880108) (xy -2.019808 -1.880108)
			)
			(stroke
				(width 0)
				(type default)
			)
			(fill yes)
			(layer "F.SilkS")
		)
		(fp_line
			(start -1.549908 -1.549908)
			(end 1.549908 -1.549908)
			(stroke
				(width 0.1)
				(type default)
			)
			(layer "F.Fab")
		)
		(fp_line
			(start -1.549908 1.549908)
			(end -1.549908 -1.549908)
			(stroke
				(width 0.1)
				(type default)
			)
			(layer "F.Fab")
		)
		(fp_line
			(start 1.549908 -1.549908)
			(end 1.549908 1.549908)
			(stroke
				(width 0.1)
				(type default)
			)
			(layer "F.Fab")
		)
		(fp_line
			(start 1.549908 1.549908)
			(end -1.549908 1.549908)
			(stroke
				(width 0.1)
				(type default)
			)
			(layer "F.Fab")
		)
		(fp_poly
			(pts
				(xy -2.019808 -1.549908) (xy -1.257808 -1.549908) (xy -1.257808 -1.880108) (xy -2.019808 -1.880108)
			)
			(stroke
				(width 0)
				(type default)
			)
			(fill yes)
			(layer "F.Fab")
		)
		(pad "1" smd rect
			(at -1.500124 -1.249934 270)
			(size 0.2794 0.6096)
			(layers "F.Cu" "F.Mask" "F.Paste")
			(net "P12V_SSD14_R")
		)
		(pad "2" smd rect
			(at -1.500124 -0.750062 270)
			(size 0.2794 0.6096)
			(layers "F.Cu" "F.Mask" "F.Paste")
			(net "P12V_SSD14_R")
		)
		(pad "3" smd rect
			(at -1.500124 -0.249936 270)
			(size 0.2794 0.6096)
			(layers "F.Cu" "F.Mask" "F.Paste")
			(net "P12V_SSD14_R")
		)
		(pad "4" smd rect
			(at -1.500124 0.249936 270)
			(size 0.2794 0.6096)
			(layers "F.Cu" "F.Mask" "F.Paste")
			(net "P12V_SSD14_R")
		)
		(pad "5" smd rect
			(at -1.500124 0.750062 270)
			(size 0.2794 0.6096)
			(layers "F.Cu" "F.Mask" "F.Paste")
			(net "P12V_SSD14_R")
		)
		(pad "6" smd rect
			(at -1.500124 1.249934 270)
			(size 0.2794 0.6096)
			(layers "F.Cu" "F.Mask" "F.Paste")
			(net "GND")
		)
		(pad "7" smd rect
			(at 1.500124 1.249934 270)
			(size 0.2794 0.6096)
			(layers "F.Cu" "F.Mask" "F.Paste")
			(net "P12V_SSD14_SS")
		)
		(pad "8" smd rect
			(at 1.500124 0.750062 270)
			(size 0.2794 0.6096)
			(layers "F.Cu" "F.Mask" "F.Paste")
			(net "PWRGD_P12V_SSD14")
		)
		(pad "9" smd rect
			(at 1.500124 0.249936 270)
			(size 0.2794 0.6096)
			(layers "F.Cu" "F.Mask" "F.Paste")
			(net "P12V_SSD14_OCP")
		)
		(pad "10" smd rect
			(at 1.500124 -0.249936 270)
			(size 0.2794 0.6096)
			(layers "F.Cu" "F.Mask" "F.Paste")
			(net "P5V_AUX")
		)
		(pad "11" smd rect
			(at 1.500124 -0.750062 270)
			(size 0.2794 0.6096)
			(layers "F.Cu" "F.Mask" "F.Paste")
			(net "SSD14_PWR_EN_R")
		)
		(pad "12" smd rect
			(at 1.500124 -1.249934 270)
			(size 0.2794 0.6096)
			(layers "F.Cu" "F.Mask" "F.Paste")
			(net "P12V_AUX")
		)
		(pad "13" smd rect
			(at 0 0)
			(size 1.9812 2.7178)
			(layers "F.Cu" "F.Mask" "F.Paste")
			(net "P12V_AUX")
		)
		(zone
			(layer "F.Cu")
			(hatch none 0.5)
			(connect_pads
				(clearance 0)
			)
			(min_thickness 0.25)
			(keepout
				(tracks not_allowed)
				(vias allowed)
				(pads allowed)
				(copperpour not_allowed)
				(footprints allowed)
			)
			(placement
				(enabled no)
				(sheetname "")
			)
			(fill
				(thermal_gap 0.5)
				(thermal_bridge_width 0.5)
				(island_removal_mode 0)
			)
			(polygon
				(pts
					(xy 424.090084 -55.9435) (xy 424.090084 -55.8165) (xy 424.090084 -52.8447) (xy 424.090084 -52.844192)
					(xy 421.804084 -52.844192) (xy 421.804084 -52.8447) (xy 421.804084 -52.9717) (xy 421.804084 -54.3941)
					(xy 421.905684 -54.3941) (xy 421.905684 -52.9717) (xy 423.988484 -52.9717) (xy 423.988484 -55.8165)
					(xy 421.905684 -55.8165) (xy 421.905684 -54.4195) (xy 421.804084 -54.4195) (xy 421.804084 -55.8165)
					(xy 421.804084 -55.9435) (xy 421.804084 -55.944008) (xy 424.090084 -55.944008)
				)
			)
		)
	)
	(footprint ""
		(layer "F.Cu")
		(at 133.874764 -303.649634 90)
		(property "Reference" "PC120"
			(at 0 0 90)
			(layer "F.SilkS")
			(hide yes)
			(effects
				(font
					(size 1.27 1.27)
				)
			)
		)
		(property "Value" ""
			(at 0 0 90)
			(layer "F.Fab")
			(effects
				(font
					(size 1.27 1.27)
				)
			)
		)
		(duplicate_pad_numbers_are_jumpers no)
		(fp_line
			(start 1.524 -0.762)
			(end 1.524 0.762)
			(stroke
				(width 0.1524)
				(type default)
			)
			(layer "F.SilkS")
		)
		(fp_line
			(start -1.524 -0.762)
			(end 1.524 -0.762)
			(stroke
				(width 0.1524)
				(type default)
			)
			(layer "F.SilkS")
		)
		(fp_line
			(start 1.524 0.762)
			(end -1.524 0.762)
			(stroke
				(width 0.1524)
				(type default)
			)
			(layer "F.SilkS")
		)
		(fp_line
			(start -1.524 0.762)
			(end -1.524 -0.762)
			(stroke
				(width 0.1524)
				(type default)
			)
			(layer "F.SilkS")
		)
		(fp_line
			(start 1.1049 -0.724916)
			(end -1.1049 -0.724916)
			(stroke
				(width 0.1)
				(type default)
			)
			(layer "F.Fab")
		)
		(fp_line
			(start -1.1049 -0.724916)
			(end -1.1049 0.724916)
			(stroke
				(width 0.1)
				(type default)
			)
			(layer "F.Fab")
		)
		(fp_line
			(start 1.1049 0.724916)
			(end 1.1049 -0.724916)
			(stroke
				(width 0.1)
				(type default)
			)
			(layer "F.Fab")
		)
		(fp_line
			(start -1.1049 0.724916)
			(end 1.1049 0.724916)
			(stroke
				(width 0.1)
				(type default)
			)
			(layer "F.Fab")
		)
		(pad "1" smd rect
			(at -0.889 0 270)
			(size 1.016 1.27)
			(layers "F.Cu" "F.Mask" "F.Paste")
			(net "P0V8_PEX1")
		)
		(pad "2" smd rect
			(at 0.889 0 270)
			(size 1.016 1.27)
			(layers "F.Cu" "F.Mask" "F.Paste")
			(net "GND")
		)
	)
	(footprint ""
		(layer "F.Cu")
		(at 338.074 -176.911 180)
		(property "Reference" "R4755"
			(at 0 0 180)
			(layer "F.SilkS")
			(hide yes)
			(effects
				(font
					(size 1.27 1.27)
				)
			)
		)
		(property "Value" ""
			(at 0 0 180)
			(layer "F.Fab")
			(effects
				(font
					(size 1.27 1.27)
				)
			)
		)
		(duplicate_pad_numbers_are_jumpers no)
		(fp_line
			(start 0.7874 0.4064)
			(end -0.7874 0.4064)
			(stroke
				(width 0.1524)
				(type default)
			)
			(layer "F.SilkS")
		)
		(fp_line
			(start 0.7874 -0.4064)
			(end 0.7874 0.4064)
			(stroke
				(width 0.1524)
				(type default)
			)
			(layer "F.SilkS")
		)
		(fp_line
			(start -0.7874 0.4064)
			(end -0.7874 -0.4064)
			(stroke
				(width 0.1524)
				(type default)
			)
			(layer "F.SilkS")
		)
		(fp_line
			(start -0.7874 -0.4064)
			(end 0.7874 -0.4064)
			(stroke
				(width 0.1524)
				(type default)
			)
			(layer "F.SilkS")
		)
		(fp_line
			(start 0.67945 0.3048)
			(end 0.120396 0.3048)
			(stroke
				(width 0.1)
				(type default)
			)
			(layer "F.Fab")
		)
		(fp_line
			(start 0.67945 -0.3048)
			(end 0.67945 0.3048)
			(stroke
				(width 0.1)
				(type default)
			)
			(layer "F.Fab")
		)
		(fp_line
			(start 0.12065 -0.2794)
			(end 0.12065 -0.3048)
			(stroke
				(width 0.1)
				(type default)
			)
			(layer "F.Fab")
		)
		(fp_line
			(start 0.12065 -0.3048)
			(end 0.67945 -0.3048)
			(stroke
				(width 0.1)
				(type default)
			)
			(layer "F.Fab")
		)
		(fp_line
			(start 0.120396 0.3048)
			(end 0.120396 0.2794)
			(stroke
				(width 0.1)
				(type default)
			)
			(layer "F.Fab")
		)
		(fp_line
			(start 0.120396 0.2794)
			(end -0.12065 0.2794)
			(stroke
				(width 0.1)
				(type default)
			)
			(layer "F.Fab")
		)
		(fp_line
			(start -0.12065 0.3048)
			(end -0.67945 0.3048)
			(stroke
				(width 0.1)
				(type default)
			)
			(layer "F.Fab")
		)
		(fp_line
			(start -0.12065 0.2794)
			(end -0.12065 0.3048)
			(stroke
				(width 0.1)
				(type default)
			)
			(layer "F.Fab")
		)
		(fp_line
			(start -0.12065 -0.2794)
			(end 0.12065 -0.2794)
			(stroke
				(width 0.1)
				(type default)
			)
			(layer "F.Fab")
		)
		(fp_line
			(start -0.12065 -0.305054)
			(end -0.12065 -0.2794)
			(stroke
				(width 0.1)
				(type default)
			)
			(layer "F.Fab")
		)
		(fp_line
			(start -0.67945 0.3048)
			(end -0.67945 -0.305054)
			(stroke
				(width 0.1)
				(type default)
			)
			(layer "F.Fab")
		)
		(fp_line
			(start -0.67945 -0.305054)
			(end -0.12065 -0.305054)
			(stroke
				(width 0.1)
				(type default)
			)
			(layer "F.Fab")
		)
		(pad "1" smd circle
			(at -0.40005 0 180)
			(size 0 0)
			(layers "F.Cu" "F.Mask" "F.Paste")
			(net "RST_PEX_SSD9_PERST_N")
		)
		(pad "2" smd circle
			(at 0.40005 0 180)
			(size 0 0)
			(layers "F.Cu" "F.Mask" "F.Paste")
			(net "RST_PEX_SSD9_PERST_R_N")
		)
	)
	(footprint ""
		(layer "F.Cu")
		(at 369.189 -177.292)
		(property "Reference" "U346"
			(at -1.3462 -4.613148 0)
			(unlocked yes)
			(layer "F.SilkS")
			(effects
				(font
					(size 0.7874 0.5842)
					(thickness 0.1524)
				)
				(justify left)
			)
		)
		(property "Value" ""
			(at 0 0 0)
			(layer "F.Fab")
			(effects
				(font
					(size 1.27 1.27)
				)
			)
		)
		(duplicate_pad_numbers_are_jumpers no)
		(fp_line
			(start -2.097532 -3.949954)
			(end -2.097532 3.949954)
			(stroke
				(width 0.1524)
				(type default)
			)
			(layer "F.SilkS")
		)
		(fp_line
			(start -2.097532 3.949954)
			(end 2.097532 3.949954)
			(stroke
				(width 0.1524)
				(type default)
			)
			(layer "F.SilkS")
		)
		(fp_line
			(start -1.409954 -3.949954)
			(end -2.097532 -3.949954)
			(stroke
				(width 0.1524)
				(type default)
			)
			(layer "F.SilkS")
		)
		(fp_line
			(start 0 -2.54)
			(end -1.409954 -3.949954)
			(stroke
				(width 0.1524)
				(type default)
			)
			(layer "F.SilkS")
		)
		(fp_line
			(start 1.409954 -3.949954)
			(end 0 -2.54)
			(stroke
				(width 0.1524)
				(type default)
			)
			(layer "F.SilkS")
		)
		(fp_line
			(start 2.097532 -3.949954)
			(end 1.409954 -3.949954)
			(stroke
				(width 0.1524)
				(type default)
			)
			(layer "F.SilkS")
		)
		(fp_line
			(start 2.097532 3.949954)
			(end 2.097532 -3.949954)
			(stroke
				(width 0.1524)
				(type default)
			)
			(layer "F.SilkS")
		)
		(fp_poly
			(pts
				(xy -4.7498 -4.182872) (xy -4.7498 -3.166872) (xy -3.7338 -3.674872)
			)
			(stroke
				(width 0)
				(type default)
			)
			(fill yes)
			(layer "F.SilkS")
		)
		(fp_line
			(start -2.249932 -3.949954)
			(end -2.249932 3.949954)
			(stroke
				(width 0.1)
				(type default)
			)
			(layer "F.Fab")
		)
		(fp_line
			(start -2.249932 3.949954)
			(end 2.249932 3.949954)
			(stroke
				(width 0.1)
				(type default)
			)
			(layer "F.Fab")
		)
		(fp_line
			(start 2.249932 -3.949954)
			(end -2.249932 -3.949954)
			(stroke
				(width 0.1)
				(type default)
			)
			(layer "F.Fab")
		)
		(fp_line
			(start 2.249932 3.949954)
			(end 2.249932 -3.949954)
			(stroke
				(width 0.1)
				(type default)
			)
			(layer "F.Fab")
		)
		(fp_poly
			(pts
				(xy -4.7498 -4.182872) (xy -4.7498 -3.166872) (xy -3.7338 -3.674872)
			)
			(stroke
				(width 0)
				(type default)
			)
			(fill yes)
			(layer "F.Fab")
		)
		(pad "1" smd rect
			(at -2.925064 -3.674872 270)
			(size 0.6096 1.3716)
			(layers "F.Cu" "F.Mask" "F.Paste")
			(net "PEX1_PCA9555_1_INT_N")
		)
		(pad "2" smd rect
			(at -2.925064 -2.925064 270)
			(size 0.4064 1.3716)
			(layers "F.Cu" "F.Mask" "F.Paste")
			(net "PCA9555_1_PEX1_A1")
		)
		(pad "3" smd rect
			(at -2.925064 -2.275078 270)
			(size 0.4064 1.3716)
			(layers "F.Cu" "F.Mask" "F.Paste")
			(net "PCA9555_1_PEX1_A2")
		)
		(pad "4" smd rect
			(at -2.925064 -1.625092 270)
			(size 0.4064 1.3716)
			(layers "F.Cu" "F.Mask" "F.Paste")
			(net "PRSNT_SSD6_FPGA_PCA9555_N")
		)
		(pad "5" smd rect
			(at -2.925064 -0.975106 270)
			(size 0.4064 1.3716)
			(layers "F.Cu" "F.Mask" "F.Paste")
			(net "SSD6_PEX_PWR_EN")
		)
		(pad "6" smd rect
			(at -2.925064 -0.32512 270)
			(size 0.4064 1.3716)
			(layers "F.Cu" "F.Mask" "F.Paste")
			(net "RST_PEX_SSD6_PERST_N")
		)
		(pad "7" smd rect
			(at -2.925064 0.32512 270)
			(size 0.4064 1.3716)
			(layers "F.Cu" "F.Mask" "F.Paste")
			(net "Net_1173")
		)
		(pad "8" smd rect
			(at -2.925064 0.975106 270)
			(size 0.4064 1.3716)
			(layers "F.Cu" "F.Mask" "F.Paste")
			(net "PRSNT_SSD7_FPGA_PCA9555_N")
		)
		(pad "9" smd rect
			(at -2.925064 1.625092 270)
			(size 0.4064 1.3716)
			(layers "F.Cu" "F.Mask" "F.Paste")
			(net "SSD7_PEX_PWR_EN")
		)
		(pad "10" smd rect
			(at -2.925064 2.275078 270)
			(size 0.4064 1.3716)
			(layers "F.Cu" "F.Mask" "F.Paste")
			(net "RST_PEX_SSD7_PERST_N")
		)
		(pad "11" smd rect
			(at -2.925064 2.925064 270)
			(size 0.4064 1.3716)
			(layers "F.Cu" "F.Mask" "F.Paste")
			(net "Net_1172")
		)
		(pad "12" smd rect
			(at -2.925064 3.674872 270)
			(size 0.6096 1.3716)
			(layers "F.Cu" "F.Mask" "F.Paste")
			(net "GND")
		)
		(pad "13" smd rect
			(at 2.925064 3.674872 270)
			(size 0.6096 1.3716)
			(layers "F.Cu" "F.Mask" "F.Paste")
			(net "PRSNT_NIC3_FPGA_PCA9555_N")
		)
		(pad "14" smd rect
			(at 2.925064 2.925064 270)
			(size 0.4064 1.3716)
			(layers "F.Cu" "F.Mask" "F.Paste")
			(net "NIC3_PEX_PWR_EN")
		)
		(pad "15" smd rect
			(at 2.925064 2.275078 270)
			(size 0.4064 1.3716)
			(layers "F.Cu" "F.Mask" "F.Paste")
			(net "RST_PEX_NIC3_PERST_N")
		)
		(pad "16" smd rect
			(at 2.925064 1.625092 270)
			(size 0.4064 1.3716)
			(layers "F.Cu" "F.Mask" "F.Paste")
			(net "Net_1174")
		)
		(pad "17" smd rect
			(at 2.925064 0.975106 270)
			(size 0.4064 1.3716)
			(layers "F.Cu" "F.Mask" "F.Paste")
			(net "Net_8980")
		)
		(pad "18" smd rect
			(at 2.925064 0.32512 270)
			(size 0.4064 1.3716)
			(layers "F.Cu" "F.Mask" "F.Paste")
			(net "Net_8979")
		)
		(pad "19" smd rect
			(at 2.925064 -0.32512 270)
			(size 0.4064 1.3716)
			(layers "F.Cu" "F.Mask" "F.Paste")
			(net "Net_8978")
		)
		(pad "20" smd rect
			(at 2.925064 -0.975106 270)
			(size 0.4064 1.3716)
			(layers "F.Cu" "F.Mask" "F.Paste")
			(net "Net_8977")
		)
		(pad "21" smd rect
			(at 2.925064 -1.625092 270)
			(size 0.4064 1.3716)
			(layers "F.Cu" "F.Mask" "F.Paste")
			(net "PCA9555_1_PEX1_A0")
		)
		(pad "22" smd rect
			(at 2.925064 -2.275078 270)
			(size 0.4064 1.3716)
			(layers "F.Cu" "F.Mask" "F.Paste")
			(net "SMB_PEX1_PCA9555_SCL")
		)
		(pad "23" smd rect
			(at 2.925064 -2.925064 270)
			(size 0.4064 1.3716)
			(layers "F.Cu" "F.Mask" "F.Paste")
			(net "SMB_PEX1_PCA9555_SDA")
		)
		(pad "24" smd rect
			(at 2.925064 -3.674872 270)
			(size 0.6096 1.3716)
			(layers "F.Cu" "F.Mask" "F.Paste")
			(net "P3V3_AUX")
		)
	)
	(footprint ""
		(layer "F.Cu")
		(at 430.961546 -147.99691 180)
		(property "Reference" "C643"
			(at 0 0 180)
			(layer "F.SilkS")
			(hide yes)
			(effects
				(font
					(size 1.27 1.27)
				)
			)
		)
		(property "Value" ""
			(at 0 0 180)
			(layer "F.Fab")
			(effects
				(font
					(size 1.27 1.27)
				)
			)
		)
		(duplicate_pad_numbers_are_jumpers no)
		(fp_line
			(start 0.299974 0.150114)
			(end -0.299974 0.150114)
			(stroke
				(width 0.1)
				(type default)
			)
			(layer "F.Fab")
		)
		(fp_line
			(start 0.299974 -0.150114)
			(end 0.299974 0.150114)
			(stroke
				(width 0.1)
				(type default)
			)
			(layer "F.Fab")
		)
		(fp_line
			(start -0.299974 0.150114)
			(end -0.299974 -0.150114)
			(stroke
				(width 0.1)
				(type default)
			)
			(layer "F.Fab")
		)
		(fp_line
			(start -0.299974 -0.150114)
			(end 0.299974 -0.150114)
			(stroke
				(width 0.1)
				(type default)
			)
			(layer "F.Fab")
		)
		(pad "1" smd rect
			(at -0.2667 0 180)
			(size 0.3048 0.381)
			(layers "F.Cu" "F.Mask" "F.Paste")
			(net "P5E_PEX3_STN0_TX_DN<11>")
		)
		(pad "2" smd rect
			(at 0.2667 0 180)
			(size 0.3048 0.381)
			(layers "F.Cu" "F.Mask" "F.Paste")
			(net "P5E_PEX3_STN0_TX_C_DN<11>")
		)
	)
	(footprint ""
		(layer "F.Cu")
		(at 350.380554 -87.216234)
		(property "Reference" "R1593"
			(at 0 0 0)
			(layer "F.SilkS")
			(hide yes)
			(effects
				(font
					(size 1.27 1.27)
				)
			)
		)
		(property "Value" ""
			(at 0 0 0)
			(layer "F.Fab")
			(effects
				(font
					(size 1.27 1.27)
				)
			)
		)
		(duplicate_pad_numbers_are_jumpers no)
		(fp_line
			(start -0.7874 -0.4064)
			(end 0.7874 -0.4064)
			(stroke
				(width 0.1524)
				(type default)
			)
			(layer "F.SilkS")
		)
		(fp_line
			(start -0.7874 0.4064)
			(end -0.7874 -0.4064)
			(stroke
				(width 0.1524)
				(type default)
			)
			(layer "F.SilkS")
		)
		(fp_line
			(start 0.7874 -0.4064)
			(end 0.7874 0.4064)
			(stroke
				(width 0.1524)
				(type default)
			)
			(layer "F.SilkS")
		)
		(fp_line
			(start 0.7874 0.4064)
			(end -0.7874 0.4064)
			(stroke
				(width 0.1524)
				(type default)
			)
			(layer "F.SilkS")
		)
		(fp_line
			(start -0.67945 -0.305054)
			(end -0.12065 -0.305054)
			(stroke
				(width 0.1)
				(type default)
			)
			(layer "F.Fab")
		)
		(fp_line
			(start -0.67945 0.3048)
			(end -0.67945 -0.305054)
			(stroke
				(width 0.1)
				(type default)
			)
			(layer "F.Fab")
		)
		(fp_line
			(start -0.12065 -0.305054)
			(end -0.12065 -0.2794)
			(stroke
				(width 0.1)
				(type default)
			)
			(layer "F.Fab")
		)
		(fp_line
			(start -0.12065 -0.2794)
			(end 0.12065 -0.2794)
			(stroke
				(width 0.1)
				(type default)
			)
			(layer "F.Fab")
		)
		(fp_line
			(start -0.12065 0.2794)
			(end -0.12065 0.3048)
			(stroke
				(width 0.1)
				(type default)
			)
			(layer "F.Fab")
		)
		(fp_line
			(start -0.12065 0.3048)
			(end -0.67945 0.3048)
			(stroke
				(width 0.1)
				(type default)
			)
			(layer "F.Fab")
		)
		(fp_line
			(start 0.120396 0.2794)
			(end -0.12065 0.2794)
			(stroke
				(width 0.1)
				(type default)
			)
			(layer "F.Fab")
		)
		(fp_line
			(start 0.120396 0.3048)
			(end 0.120396 0.2794)
			(stroke
				(width 0.1)
				(type default)
			)
			(layer "F.Fab")
		)
		(fp_line
			(start 0.12065 -0.3048)
			(end 0.67945 -0.3048)
			(stroke
				(width 0.1)
				(type default)
			)
			(layer "F.Fab")
		)
		(fp_line
			(start 0.12065 -0.2794)
			(end 0.12065 -0.3048)
			(stroke
				(width 0.1)
				(type default)
			)
			(layer "F.Fab")
		)
		(fp_line
			(start 0.67945 -0.3048)
			(end 0.67945 0.3048)
			(stroke
				(width 0.1)
				(type default)
			)
			(layer "F.Fab")
		)
		(fp_line
			(start 0.67945 0.3048)
			(end 0.120396 0.3048)
			(stroke
				(width 0.1)
				(type default)
			)
			(layer "F.Fab")
		)
		(pad "1" smd circle
			(at -0.40005 0)
			(size 0 0)
			(layers "F.Cu" "F.Mask" "F.Paste")
			(net "P3V3_AUX")
		)
		(pad "2" smd circle
			(at 0.40005 0)
			(size 0 0)
			(layers "F.Cu" "F.Mask" "F.Paste")
			(net "SMB_BIC_I2C9_MUX1_SSD9_R_SDA")
		)
	)
	(footprint ""
		(layer "F.Cu")
		(at 336.042 -143.891 180)
		(property "Reference" "R4803"
			(at 0 0 180)
			(layer "F.SilkS")
			(hide yes)
			(effects
				(font
					(size 1.27 1.27)
				)
			)
		)
		(property "Value" ""
			(at 0 0 180)
			(layer "F.Fab")
			(effects
				(font
					(size 1.27 1.27)
				)
			)
		)
		(duplicate_pad_numbers_are_jumpers no)
		(fp_line
			(start 0.7874 0.4064)
			(end -0.7874 0.4064)
			(stroke
				(width 0.1524)
				(type default)
			)
			(layer "F.SilkS")
		)
		(fp_line
			(start 0.7874 -0.4064)
			(end 0.7874 0.4064)
			(stroke
				(width 0.1524)
				(type default)
			)
			(layer "F.SilkS")
		)
		(fp_line
			(start -0.7874 0.4064)
			(end -0.7874 -0.4064)
			(stroke
				(width 0.1524)
				(type default)
			)
			(layer "F.SilkS")
		)
		(fp_line
			(start -0.7874 -0.4064)
			(end 0.7874 -0.4064)
			(stroke
				(width 0.1524)
				(type default)
			)
			(layer "F.SilkS")
		)
		(fp_line
			(start 0.67945 0.3048)
			(end 0.120396 0.3048)
			(stroke
				(width 0.1)
				(type default)
			)
			(layer "F.Fab")
		)
		(fp_line
			(start 0.67945 -0.3048)
			(end 0.67945 0.3048)
			(stroke
				(width 0.1)
				(type default)
			)
			(layer "F.Fab")
		)
		(fp_line
			(start 0.12065 -0.2794)
			(end 0.12065 -0.3048)
			(stroke
				(width 0.1)
				(type default)
			)
			(layer "F.Fab")
		)
		(fp_line
			(start 0.12065 -0.3048)
			(end 0.67945 -0.3048)
			(stroke
				(width 0.1)
				(type default)
			)
			(layer "F.Fab")
		)
		(fp_line
			(start 0.120396 0.3048)
			(end 0.120396 0.2794)
			(stroke
				(width 0.1)
				(type default)
			)
			(layer "F.Fab")
		)
		(fp_line
			(start 0.120396 0.2794)
			(end -0.12065 0.2794)
			(stroke
				(width 0.1)
				(type default)
			)
			(layer "F.Fab")
		)
		(fp_line
			(start -0.12065 0.3048)
			(end -0.67945 0.3048)
			(stroke
				(width 0.1)
				(type default)
			)
			(layer "F.Fab")
		)
		(fp_line
			(start -0.12065 0.2794)
			(end -0.12065 0.3048)
			(stroke
				(width 0.1)
				(type default)
			)
			(layer "F.Fab")
		)
		(fp_line
			(start -0.12065 -0.2794)
			(end 0.12065 -0.2794)
			(stroke
				(width 0.1)
				(type default)
			)
			(layer "F.Fab")
		)
		(fp_line
			(start -0.12065 -0.305054)
			(end -0.12065 -0.2794)
			(stroke
				(width 0.1)
				(type default)
			)
			(layer "F.Fab")
		)
		(fp_line
			(start -0.67945 0.3048)
			(end -0.67945 -0.305054)
			(stroke
				(width 0.1)
				(type default)
			)
			(layer "F.Fab")
		)
		(fp_line
			(start -0.67945 -0.305054)
			(end -0.12065 -0.305054)
			(stroke
				(width 0.1)
				(type default)
			)
			(layer "F.Fab")
		)
		(pad "1" smd circle
			(at -0.40005 0 180)
			(size 0 0)
			(layers "F.Cu" "F.Mask" "F.Paste")
			(net "SSD15_PEX_PWR_EN_R")
		)
		(pad "2" smd circle
			(at 0.40005 0 180)
			(size 0 0)
			(layers "F.Cu" "F.Mask" "F.Paste")
			(net "GND")
		)
	)
	(footprint ""
		(layer "F.Cu")
		(at 252.473968 -72.766682 90)
		(property "Reference" "PR7075"
			(at 0 0 90)
			(layer "F.SilkS")
			(hide yes)
			(effects
				(font
					(size 1.27 1.27)
				)
			)
		)
		(property "Value" ""
			(at 0 0 90)
			(layer "F.Fab")
			(effects
				(font
					(size 1.27 1.27)
				)
			)
		)
		(duplicate_pad_numbers_are_jumpers no)
		(fp_line
			(start 0.7874 -0.4064)
			(end 0.7874 0.4064)
			(stroke
				(width 0.1524)
				(type default)
			)
			(layer "F.SilkS")
		)
		(fp_line
			(start -0.7874 -0.4064)
			(end 0.7874 -0.4064)
			(stroke
				(width 0.1524)
				(type default)
			)
			(layer "F.SilkS")
		)
		(fp_line
			(start 0.7874 0.4064)
			(end -0.7874 0.4064)
			(stroke
				(width 0.1524)
				(type default)
			)
			(layer "F.SilkS")
		)
		(fp_line
			(start -0.7874 0.4064)
			(end -0.7874 -0.4064)
			(stroke
				(width 0.1524)
				(type default)
			)
			(layer "F.SilkS")
		)
		(fp_line
			(start -0.12065 -0.305054)
			(end -0.12065 -0.2794)
			(stroke
				(width 0.1)
				(type default)
			)
			(layer "F.Fab")
		)
		(fp_line
			(start -0.67945 -0.305054)
			(end -0.12065 -0.305054)
			(stroke
				(width 0.1)
				(type default)
			)
			(layer "F.Fab")
		)
		(fp_line
			(start 0.67945 -0.3048)
			(end 0.67945 0.3048)
			(stroke
				(width 0.1)
				(type default)
			)
			(layer "F.Fab")
		)
		(fp_line
			(start 0.12065 -0.3048)
			(end 0.67945 -0.3048)
			(stroke
				(width 0.1)
				(type default)
			)
			(layer "F.Fab")
		)
		(fp_line
			(start 0.12065 -0.2794)
			(end 0.12065 -0.3048)
			(stroke
				(width 0.1)
				(type default)
			)
			(layer "F.Fab")
		)
		(fp_line
			(start -0.12065 -0.2794)
			(end 0.12065 -0.2794)
			(stroke
				(width 0.1)
				(type default)
			)
			(layer "F.Fab")
		)
		(fp_line
			(start 0.120396 0.2794)
			(end -0.12065 0.2794)
			(stroke
				(width 0.1)
				(type default)
			)
			(layer "F.Fab")
		)
		(fp_line
			(start -0.12065 0.2794)
			(end -0.12065 0.3048)
			(stroke
				(width 0.1)
				(type default)
			)
			(layer "F.Fab")
		)
		(fp_line
			(start 0.67945 0.3048)
			(end 0.120396 0.3048)
			(stroke
				(width 0.1)
				(type default)
			)
			(layer "F.Fab")
		)
		(fp_line
			(start 0.120396 0.3048)
			(end 0.120396 0.2794)
			(stroke
				(width 0.1)
				(type default)
			)
			(layer "F.Fab")
		)
		(fp_line
			(start -0.12065 0.3048)
			(end -0.67945 0.3048)
			(stroke
				(width 0.1)
				(type default)
			)
			(layer "F.Fab")
		)
		(fp_line
			(start -0.67945 0.3048)
			(end -0.67945 -0.305054)
			(stroke
				(width 0.1)
				(type default)
			)
			(layer "F.Fab")
		)
		(pad "1" smd circle
			(at -0.40005 0 90)
			(size 0 0)
			(layers "F.Cu" "F.Mask" "F.Paste")
			(net "P12V_SSD8_CO_MODE")
		)
		(pad "2" smd circle
			(at 0.40005 0 90)
			(size 0 0)
			(layers "F.Cu" "F.Mask" "F.Paste")
			(net "GND")
		)
	)
	(footprint ""
		(layer "F.Cu")
		(at 368.814604 -66.32194 90)
		(property "Reference" "R6010"
			(at 0 0 90)
			(layer "F.SilkS")
			(hide yes)
			(effects
				(font
					(size 1.27 1.27)
				)
			)
		)
		(property "Value" ""
			(at 0 0 90)
			(layer "F.Fab")
			(effects
				(font
					(size 1.27 1.27)
				)
			)
		)
		(duplicate_pad_numbers_are_jumpers no)
		(fp_line
			(start 0.7874 -0.4064)
			(end 0.7874 0.4064)
			(stroke
				(width 0.1524)
				(type default)
			)
			(layer "F.SilkS")
		)
		(fp_line
			(start -0.7874 -0.4064)
			(end 0.7874 -0.4064)
			(stroke
				(width 0.1524)
				(type default)
			)
			(layer "F.SilkS")
		)
		(fp_line
			(start 0.7874 0.4064)
			(end -0.7874 0.4064)
			(stroke
				(width 0.1524)
				(type default)
			)
			(layer "F.SilkS")
		)
		(fp_line
			(start -0.7874 0.4064)
			(end -0.7874 -0.4064)
			(stroke
				(width 0.1524)
				(type default)
			)
			(layer "F.SilkS")
		)
		(fp_line
			(start -0.12065 -0.305054)
			(end -0.12065 -0.2794)
			(stroke
				(width 0.1)
				(type default)
			)
			(layer "F.Fab")
		)
		(fp_line
			(start -0.67945 -0.305054)
			(end -0.12065 -0.305054)
			(stroke
				(width 0.1)
				(type default)
			)
			(layer "F.Fab")
		)
		(fp_line
			(start 0.67945 -0.3048)
			(end 0.67945 0.3048)
			(stroke
				(width 0.1)
				(type default)
			)
			(layer "F.Fab")
		)
		(fp_line
			(start 0.12065 -0.3048)
			(end 0.67945 -0.3048)
			(stroke
				(width 0.1)
				(type default)
			)
			(layer "F.Fab")
		)
		(fp_line
			(start 0.12065 -0.2794)
			(end 0.12065 -0.3048)
			(stroke
				(width 0.1)
				(type default)
			)
			(layer "F.Fab")
		)
		(fp_line
			(start -0.12065 -0.2794)
			(end 0.12065 -0.2794)
			(stroke
				(width 0.1)
				(type default)
			)
			(layer "F.Fab")
		)
		(fp_line
			(start 0.120396 0.2794)
			(end -0.12065 0.2794)
			(stroke
				(width 0.1)
				(type default)
			)
			(layer "F.Fab")
		)
		(fp_line
			(start -0.12065 0.2794)
			(end -0.12065 0.3048)
			(stroke
				(width 0.1)
				(type default)
			)
			(layer "F.Fab")
		)
		(fp_line
			(start 0.67945 0.3048)
			(end 0.120396 0.3048)
			(stroke
				(width 0.1)
				(type default)
			)
			(layer "F.Fab")
		)
		(fp_line
			(start 0.120396 0.3048)
			(end 0.120396 0.2794)
			(stroke
				(width 0.1)
				(type default)
			)
			(layer "F.Fab")
		)
		(fp_line
			(start -0.12065 0.3048)
			(end -0.67945 0.3048)
			(stroke
				(width 0.1)
				(type default)
			)
			(layer "F.Fab")
		)
		(fp_line
			(start -0.67945 0.3048)
			(end -0.67945 -0.305054)
			(stroke
				(width 0.1)
				(type default)
			)
			(layer "F.Fab")
		)
		(pad "1" smd circle
			(at -0.40005 0 90)
			(size 0 0)
			(layers "F.Cu" "F.Mask" "F.Paste")
			(net "SSD12_PWR_EN_R")
		)
		(pad "2" smd circle
			(at 0.40005 0 90)
			(size 0 0)
			(layers "F.Cu" "F.Mask" "F.Paste")
			(net "P12V_SSD12_CO_EN")
		)
	)
	(footprint ""
		(layer "F.Cu")
		(at 288.079942 -142.9512 180)
		(property "Reference" "R213"
			(at 0 0 180)
			(layer "F.SilkS")
			(hide yes)
			(effects
				(font
					(size 1.27 1.27)
				)
			)
		)
		(property "Value" ""
			(at 0 0 180)
			(layer "F.Fab")
			(effects
				(font
					(size 1.27 1.27)
				)
			)
		)
		(duplicate_pad_numbers_are_jumpers no)
		(fp_line
			(start 0.7874 0.4064)
			(end -0.7874 0.4064)
			(stroke
				(width 0.1524)
				(type default)
			)
			(layer "F.SilkS")
		)
		(fp_line
			(start 0.7874 -0.4064)
			(end 0.7874 0.4064)
			(stroke
				(width 0.1524)
				(type default)
			)
			(layer "F.SilkS")
		)
		(fp_line
			(start -0.7874 0.4064)
			(end -0.7874 -0.4064)
			(stroke
				(width 0.1524)
				(type default)
			)
			(layer "F.SilkS")
		)
		(fp_line
			(start -0.7874 -0.4064)
			(end 0.7874 -0.4064)
			(stroke
				(width 0.1524)
				(type default)
			)
			(layer "F.SilkS")
		)
		(fp_line
			(start 0.67945 0.3048)
			(end 0.120396 0.3048)
			(stroke
				(width 0.1)
				(type default)
			)
			(layer "F.Fab")
		)
		(fp_line
			(start 0.67945 -0.3048)
			(end 0.67945 0.3048)
			(stroke
				(width 0.1)
				(type default)
			)
			(layer "F.Fab")
		)
		(fp_line
			(start 0.12065 -0.2794)
			(end 0.12065 -0.3048)
			(stroke
				(width 0.1)
				(type default)
			)
			(layer "F.Fab")
		)
		(fp_line
			(start 0.12065 -0.3048)
			(end 0.67945 -0.3048)
			(stroke
				(width 0.1)
				(type default)
			)
			(layer "F.Fab")
		)
		(fp_line
			(start 0.120396 0.3048)
			(end 0.120396 0.2794)
			(stroke
				(width 0.1)
				(type default)
			)
			(layer "F.Fab")
		)
		(fp_line
			(start 0.120396 0.2794)
			(end -0.12065 0.2794)
			(stroke
				(width 0.1)
				(type default)
			)
			(layer "F.Fab")
		)
		(fp_line
			(start -0.12065 0.3048)
			(end -0.67945 0.3048)
			(stroke
				(width 0.1)
				(type default)
			)
			(layer "F.Fab")
		)
		(fp_line
			(start -0.12065 0.2794)
			(end -0.12065 0.3048)
			(stroke
				(width 0.1)
				(type default)
			)
			(layer "F.Fab")
		)
		(fp_line
			(start -0.12065 -0.2794)
			(end 0.12065 -0.2794)
			(stroke
				(width 0.1)
				(type default)
			)
			(layer "F.Fab")
		)
		(fp_line
			(start -0.12065 -0.305054)
			(end -0.12065 -0.2794)
			(stroke
				(width 0.1)
				(type default)
			)
			(layer "F.Fab")
		)
		(fp_line
			(start -0.67945 0.3048)
			(end -0.67945 -0.305054)
			(stroke
				(width 0.1)
				(type default)
			)
			(layer "F.Fab")
		)
		(fp_line
			(start -0.67945 -0.305054)
			(end -0.12065 -0.305054)
			(stroke
				(width 0.1)
				(type default)
			)
			(layer "F.Fab")
		)
		(pad "1" smd circle
			(at -0.40005 0 180)
			(size 0 0)
			(layers "F.Cu" "F.Mask" "F.Paste")
			(net "P3V3_NIC4")
		)
		(pad "2" smd circle
			(at 0.40005 0 180)
			(size 0 0)
			(layers "F.Cu" "F.Mask" "F.Paste")
			(net "SMB_NIC4_LS_SCL")
		)
	)
	(footprint ""
		(layer "F.Cu")
		(at 259.400294 -256.478786)
		(property "Reference" "C3414"
			(at 0 0 0)
			(layer "F.SilkS")
			(hide yes)
			(effects
				(font
					(size 1.27 1.27)
				)
			)
		)
		(property "Value" ""
			(at 0 0 0)
			(layer "F.Fab")
			(effects
				(font
					(size 1.27 1.27)
				)
			)
		)
		(duplicate_pad_numbers_are_jumpers no)
		(fp_line
			(start -0.299974 -0.150114)
			(end 0.299974 -0.150114)
			(stroke
				(width 0.1)
				(type default)
			)
			(layer "F.Fab")
		)
		(fp_line
			(start -0.299974 0.150114)
			(end -0.299974 -0.150114)
			(stroke
				(width 0.1)
				(type default)
			)
			(layer "F.Fab")
		)
		(fp_line
			(start 0.299974 -0.150114)
			(end 0.299974 0.150114)
			(stroke
				(width 0.1)
				(type default)
			)
			(layer "F.Fab")
		)
		(fp_line
			(start 0.299974 0.150114)
			(end -0.299974 0.150114)
			(stroke
				(width 0.1)
				(type default)
			)
			(layer "F.Fab")
		)
		(pad "1" smd rect
			(at -0.2667 0)
			(size 0.3048 0.381)
			(layers "F.Cu" "F.Mask" "F.Paste")
			(net "P1V8_PLL0_PEX2")
		)
		(pad "2" smd rect
			(at 0.2667 0)
			(size 0.3048 0.381)
			(layers "F.Cu" "F.Mask" "F.Paste")
			(net "GND")
		)
	)
	(footprint ""
		(layer "F.Cu")
		(at 13.805154 -376.525282 -90)
		(property "Reference" "R6752"
			(at 0 0 270)
			(layer "F.SilkS")
			(hide yes)
			(effects
				(font
					(size 1.27 1.27)
				)
			)
		)
		(property "Value" ""
			(at 0 0 270)
			(layer "F.Fab")
			(effects
				(font
					(size 1.27 1.27)
				)
			)
		)
		(duplicate_pad_numbers_are_jumpers no)
		(fp_line
			(start 0.7874 0.4064)
			(end -0.454406 0.4064)
			(stroke
				(width 0.1524)
				(type default)
			)
			(layer "F.SilkS")
		)
		(fp_line
			(start -0.363982 -0.4064)
			(end 0.7874 -0.4064)
			(stroke
				(width 0.1524)
				(type default)
			)
			(layer "F.SilkS")
		)
		(fp_line
			(start 0.7874 -0.4064)
			(end 0.7874 0.4064)
			(stroke
				(width 0.1524)
				(type default)
			)
			(layer "F.SilkS")
		)
		(fp_line
			(start -0.67945 0.3048)
			(end -0.67945 -0.305054)
			(stroke
				(width 0.1)
				(type default)
			)
			(layer "F.Fab")
		)
		(fp_line
			(start -0.12065 0.3048)
			(end -0.67945 0.3048)
			(stroke
				(width 0.1)
				(type default)
			)
			(layer "F.Fab")
		)
		(fp_line
			(start 0.120396 0.3048)
			(end 0.120396 0.2794)
			(stroke
				(width 0.1)
				(type default)
			)
			(layer "F.Fab")
		)
		(fp_line
			(start 0.67945 0.3048)
			(end 0.120396 0.3048)
			(stroke
				(width 0.1)
				(type default)
			)
			(layer "F.Fab")
		)
		(fp_line
			(start -0.12065 0.2794)
			(end -0.12065 0.3048)
			(stroke
				(width 0.1)
				(type default)
			)
			(layer "F.Fab")
		)
		(fp_line
			(start 0.120396 0.2794)
			(end -0.12065 0.2794)
			(stroke
				(width 0.1)
				(type default)
			)
			(layer "F.Fab")
		)
		(fp_line
			(start -0.12065 -0.2794)
			(end 0.12065 -0.2794)
			(stroke
				(width 0.1)
				(type default)
			)
			(layer "F.Fab")
		)
		(fp_line
			(start 0.12065 -0.2794)
			(end 0.12065 -0.3048)
			(stroke
				(width 0.1)
				(type default)
			)
			(layer "F.Fab")
		)
		(fp_line
			(start 0.12065 -0.3048)
			(end 0.67945 -0.3048)
			(stroke
				(width 0.1)
				(type default)
			)
			(layer "F.Fab")
		)
		(fp_line
			(start 0.67945 -0.3048)
			(end 0.67945 0.3048)
			(stroke
				(width 0.1)
				(type default)
			)
			(layer "F.Fab")
		)
		(fp_line
			(start -0.67945 -0.305054)
			(end -0.12065 -0.305054)
			(stroke
				(width 0.1)
				(type default)
			)
			(layer "F.Fab")
		)
		(fp_line
			(start -0.12065 -0.305054)
			(end -0.12065 -0.2794)
			(stroke
				(width 0.1)
				(type default)
			)
			(layer "F.Fab")
		)
		(pad "1" smd circle
			(at -0.40005 0 270)
			(size 0 0)
			(layers "F.Cu" "F.Mask" "F.Paste")
			(net "USB2_GPU_HMC_USB8042_DP")
		)
		(pad "2" smd circle
			(at 0.40005 0 270)
			(size 0 0)
			(layers "F.Cu" "F.Mask" "F.Paste")
			(net "GND")
		)
	)
	(footprint ""
		(layer "F.Cu")
		(at 279.121616 -405.074374 90)
		(property "Reference" "R1812"
			(at 0 0 90)
			(layer "F.SilkS")
			(hide yes)
			(effects
				(font
					(size 1.27 1.27)
				)
			)
		)
		(property "Value" ""
			(at 0 0 90)
			(layer "F.Fab")
			(effects
				(font
					(size 1.27 1.27)
				)
			)
		)
		(duplicate_pad_numbers_are_jumpers no)
		(fp_line
			(start 0.7874 -0.4064)
			(end 0.7874 0.4064)
			(stroke
				(width 0.1524)
				(type default)
			)
			(layer "F.SilkS")
		)
		(fp_line
			(start -0.7874 -0.4064)
			(end 0.7874 -0.4064)
			(stroke
				(width 0.1524)
				(type default)
			)
			(layer "F.SilkS")
		)
		(fp_line
			(start 0.7874 0.4064)
			(end -0.7874 0.4064)
			(stroke
				(width 0.1524)
				(type default)
			)
			(layer "F.SilkS")
		)
		(fp_line
			(start -0.7874 0.4064)
			(end -0.7874 -0.4064)
			(stroke
				(width 0.1524)
				(type default)
			)
			(layer "F.SilkS")
		)
		(fp_line
			(start -0.12065 -0.305054)
			(end -0.12065 -0.2794)
			(stroke
				(width 0.1)
				(type default)
			)
			(layer "F.Fab")
		)
		(fp_line
			(start -0.67945 -0.305054)
			(end -0.12065 -0.305054)
			(stroke
				(width 0.1)
				(type default)
			)
			(layer "F.Fab")
		)
		(fp_line
			(start 0.67945 -0.3048)
			(end 0.67945 0.3048)
			(stroke
				(width 0.1)
				(type default)
			)
			(layer "F.Fab")
		)
		(fp_line
			(start 0.12065 -0.3048)
			(end 0.67945 -0.3048)
			(stroke
				(width 0.1)
				(type default)
			)
			(layer "F.Fab")
		)
		(fp_line
			(start 0.12065 -0.2794)
			(end 0.12065 -0.3048)
			(stroke
				(width 0.1)
				(type default)
			)
			(layer "F.Fab")
		)
		(fp_line
			(start -0.12065 -0.2794)
			(end 0.12065 -0.2794)
			(stroke
				(width 0.1)
				(type default)
			)
			(layer "F.Fab")
		)
		(fp_line
			(start 0.120396 0.2794)
			(end -0.12065 0.2794)
			(stroke
				(width 0.1)
				(type default)
			)
			(layer "F.Fab")
		)
		(fp_line
			(start -0.12065 0.2794)
			(end -0.12065 0.3048)
			(stroke
				(width 0.1)
				(type default)
			)
			(layer "F.Fab")
		)
		(fp_line
			(start 0.67945 0.3048)
			(end 0.120396 0.3048)
			(stroke
				(width 0.1)
				(type default)
			)
			(layer "F.Fab")
		)
		(fp_line
			(start 0.120396 0.3048)
			(end 0.120396 0.2794)
			(stroke
				(width 0.1)
				(type default)
			)
			(layer "F.Fab")
		)
		(fp_line
			(start -0.12065 0.3048)
			(end -0.67945 0.3048)
			(stroke
				(width 0.1)
				(type default)
			)
			(layer "F.Fab")
		)
		(fp_line
			(start -0.67945 0.3048)
			(end -0.67945 -0.305054)
			(stroke
				(width 0.1)
				(type default)
			)
			(layer "F.Fab")
		)
		(pad "1" smd circle
			(at -0.40005 0 90)
			(size 0 0)
			(layers "F.Cu" "F.Mask" "F.Paste")
			(net "P3V3_AUX")
		)
		(pad "2" smd circle
			(at 0.40005 0 90)
			(size 0 0)
			(layers "F.Cu" "F.Mask" "F.Paste")
			(net "MB_BIC_MON_BUF")
		)
	)
	(footprint ""
		(layer "F.Cu")
		(at 76.48194 -38.041072 180)
		(property "Reference" "R5885"
			(at 0 0 180)
			(layer "F.SilkS")
			(hide yes)
			(effects
				(font
					(size 1.27 1.27)
				)
			)
		)
		(property "Value" ""
			(at 0 0 180)
			(layer "F.Fab")
			(effects
				(font
					(size 1.27 1.27)
				)
			)
		)
		(duplicate_pad_numbers_are_jumpers no)
		(fp_line
			(start 0.7874 0.4064)
			(end -0.7874 0.4064)
			(stroke
				(width 0.1524)
				(type default)
			)
			(layer "F.SilkS")
		)
		(fp_line
			(start 0.7874 -0.4064)
			(end 0.7874 0.4064)
			(stroke
				(width 0.1524)
				(type default)
			)
			(layer "F.SilkS")
		)
		(fp_line
			(start -0.7874 0.4064)
			(end -0.7874 -0.4064)
			(stroke
				(width 0.1524)
				(type default)
			)
			(layer "F.SilkS")
		)
		(fp_line
			(start -0.7874 -0.4064)
			(end 0.7874 -0.4064)
			(stroke
				(width 0.1524)
				(type default)
			)
			(layer "F.SilkS")
		)
		(fp_line
			(start 0.67945 0.3048)
			(end 0.120396 0.3048)
			(stroke
				(width 0.1)
				(type default)
			)
			(layer "F.Fab")
		)
		(fp_line
			(start 0.67945 -0.3048)
			(end 0.67945 0.3048)
			(stroke
				(width 0.1)
				(type default)
			)
			(layer "F.Fab")
		)
		(fp_line
			(start 0.12065 -0.2794)
			(end 0.12065 -0.3048)
			(stroke
				(width 0.1)
				(type default)
			)
			(layer "F.Fab")
		)
		(fp_line
			(start 0.12065 -0.3048)
			(end 0.67945 -0.3048)
			(stroke
				(width 0.1)
				(type default)
			)
			(layer "F.Fab")
		)
		(fp_line
			(start 0.120396 0.3048)
			(end 0.120396 0.2794)
			(stroke
				(width 0.1)
				(type default)
			)
			(layer "F.Fab")
		)
		(fp_line
			(start 0.120396 0.2794)
			(end -0.12065 0.2794)
			(stroke
				(width 0.1)
				(type default)
			)
			(layer "F.Fab")
		)
		(fp_line
			(start -0.12065 0.3048)
			(end -0.67945 0.3048)
			(stroke
				(width 0.1)
				(type default)
			)
			(layer "F.Fab")
		)
		(fp_line
			(start -0.12065 0.2794)
			(end -0.12065 0.3048)
			(stroke
				(width 0.1)
				(type default)
			)
			(layer "F.Fab")
		)
		(fp_line
			(start -0.12065 -0.2794)
			(end 0.12065 -0.2794)
			(stroke
				(width 0.1)
				(type default)
			)
			(layer "F.Fab")
		)
		(fp_line
			(start -0.12065 -0.305054)
			(end -0.12065 -0.2794)
			(stroke
				(width 0.1)
				(type default)
			)
			(layer "F.Fab")
		)
		(fp_line
			(start -0.67945 0.3048)
			(end -0.67945 -0.305054)
			(stroke
				(width 0.1)
				(type default)
			)
			(layer "F.Fab")
		)
		(fp_line
			(start -0.67945 -0.305054)
			(end -0.12065 -0.305054)
			(stroke
				(width 0.1)
				(type default)
			)
			(layer "F.Fab")
		)
		(pad "1" smd circle
			(at -0.40005 0 180)
			(size 0 0)
			(layers "F.Cu" "F.Mask" "F.Paste")
			(net "P5V_AUX")
		)
		(pad "2" smd circle
			(at 0.40005 0 180)
			(size 0 0)
			(layers "F.Cu" "F.Mask" "F.Paste")
			(net "P3V3_SSD3_PG_G2")
		)
	)
	(footprint ""
		(layer "F.Cu")
		(at 26.439368 -350.098614 90)
		(property "Reference" "C186"
			(at 0 0 90)
			(layer "F.SilkS")
			(hide yes)
			(effects
				(font
					(size 1.27 1.27)
				)
			)
		)
		(property "Value" ""
			(at 0 0 90)
			(layer "F.Fab")
			(effects
				(font
					(size 1.27 1.27)
				)
			)
		)
		(duplicate_pad_numbers_are_jumpers no)
		(fp_line
			(start 0.299974 -0.150114)
			(end 0.299974 0.150114)
			(stroke
				(width 0.1)
				(type default)
			)
			(layer "F.Fab")
		)
		(fp_line
			(start -0.299974 -0.150114)
			(end 0.299974 -0.150114)
			(stroke
				(width 0.1)
				(type default)
			)
			(layer "F.Fab")
		)
		(fp_line
			(start 0.299974 0.150114)
			(end -0.299974 0.150114)
			(stroke
				(width 0.1)
				(type default)
			)
			(layer "F.Fab")
		)
		(fp_line
			(start -0.299974 0.150114)
			(end -0.299974 -0.150114)
			(stroke
				(width 0.1)
				(type default)
			)
			(layer "F.Fab")
		)
		(pad "1" smd rect
			(at -0.2667 0 90)
			(size 0.3048 0.381)
			(layers "F.Cu" "F.Mask" "F.Paste")
			(net "P5E_PEX0_STN7_TX_DN<115>")
		)
		(pad "2" smd rect
			(at 0.2667 0 90)
			(size 0.3048 0.381)
			(layers "F.Cu" "F.Mask" "F.Paste")
			(net "P5E_PEX0_STN7_TX_C_DN<115>")
		)
	)
	(footprint ""
		(layer "F.Cu")
		(at 299.342556 -70.844918 -90)
		(property "Reference" "PD46"
			(at 4.144518 2.161286 90)
			(unlocked yes)
			(layer "F.SilkS")
			(effects
				(font
					(size 0.7874 0.5842)
					(thickness 0.1524)
				)
				(justify left)
			)
		)
		(property "Value" ""
			(at 0 0 270)
			(layer "F.Fab")
			(effects
				(font
					(size 1.27 1.27)
				)
			)
		)
		(duplicate_pad_numbers_are_jumpers no)
		(fp_line
			(start -3.400044 1.459992)
			(end -3.400044 -1.459992)
			(stroke
				(width 0.1524)
				(type default)
			)
			(layer "F.SilkS")
		)
		(fp_line
			(start 4.107942 1.459992)
			(end -3.400044 1.459992)
			(stroke
				(width 0.1524)
				(type default)
			)
			(layer "F.SilkS")
		)
		(fp_line
			(start -3.400044 -1.459992)
			(end 4.107942 -1.459992)
			(stroke
				(width 0.1524)
				(type default)
			)
			(layer "F.SilkS")
		)
		(fp_line
			(start 4.107942 -1.459992)
			(end 4.107942 1.459992)
			(stroke
				(width 0.1524)
				(type default)
			)
			(layer "F.SilkS")
		)
		(fp_poly
			(pts
				(xy 4.107942 -1.459992) (xy 4.107942 1.459992) (xy 3.308096 1.459992) (xy 3.308096 -1.459992)
			)
			(stroke
				(width 0)
				(type default)
			)
			(fill yes)
			(layer "F.SilkS")
		)
		(fp_line
			(start -2.29997 1.459992)
			(end -2.29997 -1.459992)
			(stroke
				(width 0.1)
				(type default)
			)
			(layer "F.Fab")
		)
		(fp_line
			(start 2.29997 1.459992)
			(end -2.29997 1.459992)
			(stroke
				(width 0.1)
				(type default)
			)
			(layer "F.Fab")
		)
		(fp_line
			(start -2.29997 -1.459992)
			(end 2.29997 -1.459992)
			(stroke
				(width 0.1)
				(type default)
			)
			(layer "F.Fab")
		)
		(fp_line
			(start 2.29997 -1.459992)
			(end 2.29997 1.459992)
			(stroke
				(width 0.1)
				(type default)
			)
			(layer "F.Fab")
		)
		(fp_text user "-"
			(at 5.4102 0.29845 90)
			(unlocked yes)
			(layer "F.SilkS")
			(effects
				(font
					(size 1.905 1.4224)
					(thickness 0.1524)
				)
				(justify left)
			)
		)
		(fp_text user "+"
			(at -5.166868 -0.175006 270)
			(unlocked yes)
			(layer "F.SilkS")
			(effects
				(font
					(size 1.905 1.4224)
					(thickness 0.1524)
				)
				(justify left)
			)
		)
		(fp_text user "-"
			(at 5.4102 0.29845 90)
			(unlocked yes)
			(layer "F.Fab")
			(effects
				(font
					(size 1.905 1.4224)
					(thickness 0.1524)
				)
				(justify left)
			)
		)
		(fp_text user "+"
			(at -4.7752 -0.12065 270)
			(unlocked yes)
			(layer "F.Fab")
			(effects
				(font
					(size 1.905 1.4224)
					(thickness 0.1524)
				)
				(justify left)
			)
		)
		(pad "A" smd rect
			(at -1.999996 0)
			(size 1.7018 2.5146)
			(layers "F.Cu" "F.Mask" "F.Paste")
			(net "GND")
		)
		(pad "C" smd rect
			(at 1.999996 0)
			(size 1.7018 2.5146)
			(layers "F.Cu" "F.Mask" "F.Paste")
			(net "P12V_SSD10_R")
		)
	)
	(footprint ""
		(layer "F.Cu")
		(at 150.540974 -382.471676 180)
		(property "Reference" "R6773"
			(at 0 0 180)
			(layer "F.SilkS")
			(hide yes)
			(effects
				(font
					(size 1.27 1.27)
				)
			)
		)
		(property "Value" ""
			(at 0 0 180)
			(layer "F.Fab")
			(effects
				(font
					(size 1.27 1.27)
				)
			)
		)
		(duplicate_pad_numbers_are_jumpers no)
		(fp_line
			(start 0.7874 0.4064)
			(end -0.7874 0.4064)
			(stroke
				(width 0.1524)
				(type default)
			)
			(layer "F.SilkS")
		)
		(fp_line
			(start 0.7874 -0.4064)
			(end 0.7874 0.4064)
			(stroke
				(width 0.1524)
				(type default)
			)
			(layer "F.SilkS")
		)
		(fp_line
			(start -0.7874 0.4064)
			(end -0.7874 -0.4064)
			(stroke
				(width 0.1524)
				(type default)
			)
			(layer "F.SilkS")
		)
		(fp_line
			(start -0.7874 -0.4064)
			(end 0.7874 -0.4064)
			(stroke
				(width 0.1524)
				(type default)
			)
			(layer "F.SilkS")
		)
		(fp_line
			(start 0.67945 0.3048)
			(end 0.120396 0.3048)
			(stroke
				(width 0.1)
				(type default)
			)
			(layer "F.Fab")
		)
		(fp_line
			(start 0.67945 -0.3048)
			(end 0.67945 0.3048)
			(stroke
				(width 0.1)
				(type default)
			)
			(layer "F.Fab")
		)
		(fp_line
			(start 0.12065 -0.2794)
			(end 0.12065 -0.3048)
			(stroke
				(width 0.1)
				(type default)
			)
			(layer "F.Fab")
		)
		(fp_line
			(start 0.12065 -0.3048)
			(end 0.67945 -0.3048)
			(stroke
				(width 0.1)
				(type default)
			)
			(layer "F.Fab")
		)
		(fp_line
			(start 0.120396 0.3048)
			(end 0.120396 0.2794)
			(stroke
				(width 0.1)
				(type default)
			)
			(layer "F.Fab")
		)
		(fp_line
			(start 0.120396 0.2794)
			(end -0.12065 0.2794)
			(stroke
				(width 0.1)
				(type default)
			)
			(layer "F.Fab")
		)
		(fp_line
			(start -0.12065 0.3048)
			(end -0.67945 0.3048)
			(stroke
				(width 0.1)
				(type default)
			)
			(layer "F.Fab")
		)
		(fp_line
			(start -0.12065 0.2794)
			(end -0.12065 0.3048)
			(stroke
				(width 0.1)
				(type default)
			)
			(layer "F.Fab")
		)
		(fp_line
			(start -0.12065 -0.2794)
			(end 0.12065 -0.2794)
			(stroke
				(width 0.1)
				(type default)
			)
			(layer "F.Fab")
		)
		(fp_line
			(start -0.12065 -0.305054)
			(end -0.12065 -0.2794)
			(stroke
				(width 0.1)
				(type default)
			)
			(layer "F.Fab")
		)
		(fp_line
			(start -0.67945 0.3048)
			(end -0.67945 -0.305054)
			(stroke
				(width 0.1)
				(type default)
			)
			(layer "F.Fab")
		)
		(fp_line
			(start -0.67945 -0.305054)
			(end -0.12065 -0.305054)
			(stroke
				(width 0.1)
				(type default)
			)
			(layer "F.Fab")
		)
		(pad "1" smd circle
			(at -0.40005 0 180)
			(size 0 0)
			(layers "F.Cu" "F.Mask" "F.Paste")
			(net "PRSNT_GPU_A3_R_N")
		)
		(pad "2" smd circle
			(at 0.40005 0 180)
			(size 0 0)
			(layers "F.Cu" "F.Mask" "F.Paste")
			(net "PRSNT_GPU_A3_N")
		)
	)
	(footprint ""
		(layer "F.Cu")
		(at 241.561112 -198.746618)
		(property "Reference" "R6149"
			(at 0 0 0)
			(layer "F.SilkS")
			(hide yes)
			(effects
				(font
					(size 1.27 1.27)
				)
			)
		)
		(property "Value" ""
			(at 0 0 0)
			(layer "F.Fab")
			(effects
				(font
					(size 1.27 1.27)
				)
			)
		)
		(duplicate_pad_numbers_are_jumpers no)
		(fp_line
			(start -0.7874 -0.4064)
			(end 0.7874 -0.4064)
			(stroke
				(width 0.1524)
				(type default)
			)
			(layer "F.SilkS")
		)
		(fp_line
			(start -0.7874 0.4064)
			(end -0.7874 -0.4064)
			(stroke
				(width 0.1524)
				(type default)
			)
			(layer "F.SilkS")
		)
		(fp_line
			(start 0.7874 -0.4064)
			(end 0.7874 0.4064)
			(stroke
				(width 0.1524)
				(type default)
			)
			(layer "F.SilkS")
		)
		(fp_line
			(start 0.7874 0.4064)
			(end -0.7874 0.4064)
			(stroke
				(width 0.1524)
				(type default)
			)
			(layer "F.SilkS")
		)
		(fp_line
			(start -0.67945 -0.305054)
			(end -0.12065 -0.305054)
			(stroke
				(width 0.1)
				(type default)
			)
			(layer "F.Fab")
		)
		(fp_line
			(start -0.67945 0.3048)
			(end -0.67945 -0.305054)
			(stroke
				(width 0.1)
				(type default)
			)
			(layer "F.Fab")
		)
		(fp_line
			(start -0.12065 -0.305054)
			(end -0.12065 -0.2794)
			(stroke
				(width 0.1)
				(type default)
			)
			(layer "F.Fab")
		)
		(fp_line
			(start -0.12065 -0.2794)
			(end 0.12065 -0.2794)
			(stroke
				(width 0.1)
				(type default)
			)
			(layer "F.Fab")
		)
		(fp_line
			(start -0.12065 0.2794)
			(end -0.12065 0.3048)
			(stroke
				(width 0.1)
				(type default)
			)
			(layer "F.Fab")
		)
		(fp_line
			(start -0.12065 0.3048)
			(end -0.67945 0.3048)
			(stroke
				(width 0.1)
				(type default)
			)
			(layer "F.Fab")
		)
		(fp_line
			(start 0.120396 0.2794)
			(end -0.12065 0.2794)
			(stroke
				(width 0.1)
				(type default)
			)
			(layer "F.Fab")
		)
		(fp_line
			(start 0.120396 0.3048)
			(end 0.120396 0.2794)
			(stroke
				(width 0.1)
				(type default)
			)
			(layer "F.Fab")
		)
		(fp_line
			(start 0.12065 -0.3048)
			(end 0.67945 -0.3048)
			(stroke
				(width 0.1)
				(type default)
			)
			(layer "F.Fab")
		)
		(fp_line
			(start 0.12065 -0.2794)
			(end 0.12065 -0.3048)
			(stroke
				(width 0.1)
				(type default)
			)
			(layer "F.Fab")
		)
		(fp_line
			(start 0.67945 -0.3048)
			(end 0.67945 0.3048)
			(stroke
				(width 0.1)
				(type default)
			)
			(layer "F.Fab")
		)
		(fp_line
			(start 0.67945 0.3048)
			(end 0.120396 0.3048)
			(stroke
				(width 0.1)
				(type default)
			)
			(layer "F.Fab")
		)
		(pad "1" smd circle
			(at -0.40005 0)
			(size 0 0)
			(layers "F.Cu" "F.Mask" "F.Paste")
			(net "BIC_FWSPIDQ2")
		)
		(pad "2" smd circle
			(at 0.40005 0)
			(size 0 0)
			(layers "F.Cu" "F.Mask" "F.Paste")
			(net "P3V3_AUX")
		)
	)
	(footprint ""
		(layer "F.Cu")
		(at 149.871938 -24.807418)
		(property "Reference" "R426"
			(at 0 0 0)
			(layer "F.SilkS")
			(hide yes)
			(effects
				(font
					(size 1.27 1.27)
				)
			)
		)
		(property "Value" ""
			(at 0 0 0)
			(layer "F.Fab")
			(effects
				(font
					(size 1.27 1.27)
				)
			)
		)
		(duplicate_pad_numbers_are_jumpers no)
		(fp_line
			(start -0.7874 -0.4064)
			(end 0.7874 -0.4064)
			(stroke
				(width 0.1524)
				(type default)
			)
			(layer "F.SilkS")
		)
		(fp_line
			(start -0.7874 0.4064)
			(end -0.7874 -0.4064)
			(stroke
				(width 0.1524)
				(type default)
			)
			(layer "F.SilkS")
		)
		(fp_line
			(start 0.7874 -0.4064)
			(end 0.7874 0.4064)
			(stroke
				(width 0.1524)
				(type default)
			)
			(layer "F.SilkS")
		)
		(fp_line
			(start 0.7874 0.4064)
			(end -0.7874 0.4064)
			(stroke
				(width 0.1524)
				(type default)
			)
			(layer "F.SilkS")
		)
		(fp_line
			(start -0.67945 -0.305054)
			(end -0.12065 -0.305054)
			(stroke
				(width 0.1)
				(type default)
			)
			(layer "F.Fab")
		)
		(fp_line
			(start -0.67945 0.3048)
			(end -0.67945 -0.305054)
			(stroke
				(width 0.1)
				(type default)
			)
			(layer "F.Fab")
		)
		(fp_line
			(start -0.12065 -0.305054)
			(end -0.12065 -0.2794)
			(stroke
				(width 0.1)
				(type default)
			)
			(layer "F.Fab")
		)
		(fp_line
			(start -0.12065 -0.2794)
			(end 0.12065 -0.2794)
			(stroke
				(width 0.1)
				(type default)
			)
			(layer "F.Fab")
		)
		(fp_line
			(start -0.12065 0.2794)
			(end -0.12065 0.3048)
			(stroke
				(width 0.1)
				(type default)
			)
			(layer "F.Fab")
		)
		(fp_line
			(start -0.12065 0.3048)
			(end -0.67945 0.3048)
			(stroke
				(width 0.1)
				(type default)
			)
			(layer "F.Fab")
		)
		(fp_line
			(start 0.120396 0.2794)
			(end -0.12065 0.2794)
			(stroke
				(width 0.1)
				(type default)
			)
			(layer "F.Fab")
		)
		(fp_line
			(start 0.120396 0.3048)
			(end 0.120396 0.2794)
			(stroke
				(width 0.1)
				(type default)
			)
			(layer "F.Fab")
		)
		(fp_line
			(start 0.12065 -0.3048)
			(end 0.67945 -0.3048)
			(stroke
				(width 0.1)
				(type default)
			)
			(layer "F.Fab")
		)
		(fp_line
			(start 0.12065 -0.2794)
			(end 0.12065 -0.3048)
			(stroke
				(width 0.1)
				(type default)
			)
			(layer "F.Fab")
		)
		(fp_line
			(start 0.67945 -0.3048)
			(end 0.67945 0.3048)
			(stroke
				(width 0.1)
				(type default)
			)
			(layer "F.Fab")
		)
		(fp_line
			(start 0.67945 0.3048)
			(end 0.120396 0.3048)
			(stroke
				(width 0.1)
				(type default)
			)
			(layer "F.Fab")
		)
		(pad "1" smd circle
			(at -0.40005 0)
			(size 0 0)
			(layers "F.Cu" "F.Mask" "F.Paste")
			(net "P3V3_SSD5")
		)
		(pad "2" smd circle
			(at 0.40005 0)
			(size 0 0)
			(layers "F.Cu" "F.Mask" "F.Paste")
			(net "PU_CLKREQ5")
		)
	)
	(footprint ""
		(layer "F.Cu")
		(at 127.658114 -256.226564 180)
		(property "Reference" "PR85"
			(at 0 0 180)
			(layer "F.SilkS")
			(hide yes)
			(effects
				(font
					(size 1.27 1.27)
				)
			)
		)
		(property "Value" ""
			(at 0 0 180)
			(layer "F.Fab")
			(effects
				(font
					(size 1.27 1.27)
				)
			)
		)
		(duplicate_pad_numbers_are_jumpers no)
		(fp_line
			(start 0.7874 0.4064)
			(end -0.7874 0.4064)
			(stroke
				(width 0.1524)
				(type default)
			)
			(layer "F.SilkS")
		)
		(fp_line
			(start 0.7874 -0.4064)
			(end 0.7874 0.4064)
			(stroke
				(width 0.1524)
				(type default)
			)
			(layer "F.SilkS")
		)
		(fp_line
			(start -0.7874 0.4064)
			(end -0.7874 -0.4064)
			(stroke
				(width 0.1524)
				(type default)
			)
			(layer "F.SilkS")
		)
		(fp_line
			(start -0.7874 -0.4064)
			(end 0.7874 -0.4064)
			(stroke
				(width 0.1524)
				(type default)
			)
			(layer "F.SilkS")
		)
		(fp_line
			(start 0.67945 0.3048)
			(end 0.120396 0.3048)
			(stroke
				(width 0.1)
				(type default)
			)
			(layer "F.Fab")
		)
		(fp_line
			(start 0.67945 -0.3048)
			(end 0.67945 0.3048)
			(stroke
				(width 0.1)
				(type default)
			)
			(layer "F.Fab")
		)
		(fp_line
			(start 0.12065 -0.2794)
			(end 0.12065 -0.3048)
			(stroke
				(width 0.1)
				(type default)
			)
			(layer "F.Fab")
		)
		(fp_line
			(start 0.12065 -0.3048)
			(end 0.67945 -0.3048)
			(stroke
				(width 0.1)
				(type default)
			)
			(layer "F.Fab")
		)
		(fp_line
			(start 0.120396 0.3048)
			(end 0.120396 0.2794)
			(stroke
				(width 0.1)
				(type default)
			)
			(layer "F.Fab")
		)
		(fp_line
			(start 0.120396 0.2794)
			(end -0.12065 0.2794)
			(stroke
				(width 0.1)
				(type default)
			)
			(layer "F.Fab")
		)
		(fp_line
			(start -0.12065 0.3048)
			(end -0.67945 0.3048)
			(stroke
				(width 0.1)
				(type default)
			)
			(layer "F.Fab")
		)
		(fp_line
			(start -0.12065 0.2794)
			(end -0.12065 0.3048)
			(stroke
				(width 0.1)
				(type default)
			)
			(layer "F.Fab")
		)
		(fp_line
			(start -0.12065 -0.2794)
			(end 0.12065 -0.2794)
			(stroke
				(width 0.1)
				(type default)
			)
			(layer "F.Fab")
		)
		(fp_line
			(start -0.12065 -0.305054)
			(end -0.12065 -0.2794)
			(stroke
				(width 0.1)
				(type default)
			)
			(layer "F.Fab")
		)
		(fp_line
			(start -0.67945 0.3048)
			(end -0.67945 -0.305054)
			(stroke
				(width 0.1)
				(type default)
			)
			(layer "F.Fab")
		)
		(fp_line
			(start -0.67945 -0.305054)
			(end -0.12065 -0.305054)
			(stroke
				(width 0.1)
				(type default)
			)
			(layer "F.Fab")
		)
		(pad "1" smd circle
			(at -0.40005 0 180)
			(size 0 0)
			(layers "F.Cu" "F.Mask" "F.Paste")
			(net "P3V3_AUX")
		)
		(pad "2" smd circle
			(at 0.40005 0 180)
			(size 0 0)
			(layers "F.Cu" "F.Mask" "F.Paste")
			(net "P0V8_PEX0_VRHOT_R")
		)
	)
	(footprint ""
		(layer "F.Cu")
		(at 314.3504 -80.581246 90)
		(property "Reference" "U37"
			(at -0.571246 2.38887 90)
			(unlocked yes)
			(layer "F.SilkS")
			(effects
				(font
					(size 0.7874 0.5842)
					(thickness 0.1524)
				)
			)
		)
		(property "Value" ""
			(at 0 0 90)
			(layer "F.Fab")
			(effects
				(font
					(size 1.27 1.27)
				)
			)
		)
		(duplicate_pad_numbers_are_jumpers no)
		(fp_line
			(start 1.905 -1.651)
			(end 1.905 1.651)
			(stroke
				(width 0.1524)
				(type default)
			)
			(layer "F.SilkS")
		)
		(fp_line
			(start -1.905 -1.651)
			(end 1.905 -1.651)
			(stroke
				(width 0.1524)
				(type default)
			)
			(layer "F.SilkS")
		)
		(fp_line
			(start 1.905 1.651)
			(end -1.905 1.651)
			(stroke
				(width 0.1524)
				(type default)
			)
			(layer "F.SilkS")
		)
		(fp_line
			(start -1.905 1.651)
			(end -1.905 -1.651)
			(stroke
				(width 0.1524)
				(type default)
			)
			(layer "F.SilkS")
		)
		(fp_line
			(start 0.6985 -1.524)
			(end 0.6985 -0.219964)
			(stroke
				(width 0.1)
				(type default)
			)
			(layer "F.Fab")
		)
		(fp_line
			(start -0.649986 -1.524)
			(end 0.6985 -1.524)
			(stroke
				(width 0.1)
				(type default)
			)
			(layer "F.Fab")
		)
		(fp_line
			(start -0.649986 -1.169924)
			(end -0.649986 -1.524)
			(stroke
				(width 0.1)
				(type default)
			)
			(layer "F.Fab")
		)
		(fp_line
			(start -1.249934 -1.169924)
			(end -0.649986 -1.169924)
			(stroke
				(width 0.1)
				(type default)
			)
			(layer "F.Fab")
		)
		(fp_line
			(start -0.6985 -0.729996)
			(end -1.249934 -0.729996)
			(stroke
				(width 0.1)
				(type default)
			)
			(layer "F.Fab")
		)
		(fp_line
			(start -1.249934 -0.729996)
			(end -1.249934 -1.169924)
			(stroke
				(width 0.1)
				(type default)
			)
			(layer "F.Fab")
		)
		(fp_line
			(start 1.249934 -0.219964)
			(end 1.249934 0.219964)
			(stroke
				(width 0.1)
				(type default)
			)
			(layer "F.Fab")
		)
		(fp_line
			(start 0.6985 -0.219964)
			(end 1.249934 -0.219964)
			(stroke
				(width 0.1)
				(type default)
			)
			(layer "F.Fab")
		)
		(fp_line
			(start 1.249934 0.219964)
			(end 0.6985 0.219964)
			(stroke
				(width 0.1)
				(type default)
			)
			(layer "F.Fab")
		)
		(fp_line
			(start 0.6985 0.219964)
			(end 0.6985 1.524)
			(stroke
				(width 0.1)
				(type default)
			)
			(layer "F.Fab")
		)
		(fp_line
			(start -0.6985 0.729996)
			(end -0.6985 -0.729996)
			(stroke
				(width 0.1)
				(type default)
			)
			(layer "F.Fab")
		)
		(fp_line
			(start -1.249934 0.729996)
			(end -0.6985 0.729996)
			(stroke
				(width 0.1)
				(type default)
			)
			(layer "F.Fab")
		)
		(fp_line
			(start -0.649986 1.169924)
			(end -1.249934 1.169924)
			(stroke
				(width 0.1)
				(type default)
			)
			(layer "F.Fab")
		)
		(fp_line
			(start -1.249934 1.169924)
			(end -1.249934 0.729996)
			(stroke
				(width 0.1)
				(type default)
			)
			(layer "F.Fab")
		)
		(fp_line
			(start 0.6985 1.524)
			(end -0.649986 1.524)
			(stroke
				(width 0.1)
				(type default)
			)
			(layer "F.Fab")
		)
		(fp_line
			(start -0.649986 1.524)
			(end -0.649986 1.169924)
			(stroke
				(width 0.1)
				(type default)
			)
			(layer "F.Fab")
		)
		(pad "1" smd rect
			(at -1.1176 -1.016)
			(size 1.016 1.27)
			(layers "F.Cu" "F.Mask" "F.Paste")
			(net "HP_NIC5_PWRGD")
		)
		(pad "2" smd rect
			(at -1.1176 1.016)
			(size 1.016 1.27)
			(layers "F.Cu" "F.Mask" "F.Paste")
			(net "P3V3_NIC5")
		)
		(pad "3" smd rect
			(at 1.1176 0)
			(size 1.016 1.27)
			(layers "F.Cu" "F.Mask" "F.Paste")
			(net "GND")
		)
	)
	(footprint ""
		(layer "F.Cu")
		(at 345.632278 -280.44902 -90)
		(property "Reference" "PR153"
			(at 0 0 270)
			(layer "F.SilkS")
			(hide yes)
			(effects
				(font
					(size 1.27 1.27)
				)
			)
		)
		(property "Value" ""
			(at 0 0 270)
			(layer "F.Fab")
			(effects
				(font
					(size 1.27 1.27)
				)
			)
		)
		(duplicate_pad_numbers_are_jumpers no)
		(fp_line
			(start -0.7874 0.4064)
			(end -0.7874 -0.4064)
			(stroke
				(width 0.1524)
				(type default)
			)
			(layer "F.SilkS")
		)
		(fp_line
			(start 0.7874 0.4064)
			(end -0.7874 0.4064)
			(stroke
				(width 0.1524)
				(type default)
			)
			(layer "F.SilkS")
		)
		(fp_line
			(start -0.7874 -0.4064)
			(end 0.7874 -0.4064)
			(stroke
				(width 0.1524)
				(type default)
			)
			(layer "F.SilkS")
		)
		(fp_line
			(start 0.7874 -0.4064)
			(end 0.7874 0.4064)
			(stroke
				(width 0.1524)
				(type default)
			)
			(layer "F.SilkS")
		)
		(fp_line
			(start -0.67945 0.3048)
			(end -0.67945 -0.305054)
			(stroke
				(width 0.1)
				(type default)
			)
			(layer "F.Fab")
		)
		(fp_line
			(start -0.12065 0.3048)
			(end -0.67945 0.3048)
			(stroke
				(width 0.1)
				(type default)
			)
			(layer "F.Fab")
		)
		(fp_line
			(start 0.120396 0.3048)
			(end 0.120396 0.2794)
			(stroke
				(width 0.1)
				(type default)
			)
			(layer "F.Fab")
		)
		(fp_line
			(start 0.67945 0.3048)
			(end 0.120396 0.3048)
			(stroke
				(width 0.1)
				(type default)
			)
			(layer "F.Fab")
		)
		(fp_line
			(start -0.12065 0.2794)
			(end -0.12065 0.3048)
			(stroke
				(width 0.1)
				(type default)
			)
			(layer "F.Fab")
		)
		(fp_line
			(start 0.120396 0.2794)
			(end -0.12065 0.2794)
			(stroke
				(width 0.1)
				(type default)
			)
			(layer "F.Fab")
		)
		(fp_line
			(start -0.12065 -0.2794)
			(end 0.12065 -0.2794)
			(stroke
				(width 0.1)
				(type default)
			)
			(layer "F.Fab")
		)
		(fp_line
			(start 0.12065 -0.2794)
			(end 0.12065 -0.3048)
			(stroke
				(width 0.1)
				(type default)
			)
			(layer "F.Fab")
		)
		(fp_line
			(start 0.12065 -0.3048)
			(end 0.67945 -0.3048)
			(stroke
				(width 0.1)
				(type default)
			)
			(layer "F.Fab")
		)
		(fp_line
			(start 0.67945 -0.3048)
			(end 0.67945 0.3048)
			(stroke
				(width 0.1)
				(type default)
			)
			(layer "F.Fab")
		)
		(fp_line
			(start -0.67945 -0.305054)
			(end -0.12065 -0.305054)
			(stroke
				(width 0.1)
				(type default)
			)
			(layer "F.Fab")
		)
		(fp_line
			(start -0.12065 -0.305054)
			(end -0.12065 -0.2794)
			(stroke
				(width 0.1)
				(type default)
			)
			(layer "F.Fab")
		)
		(pad "1" smd circle
			(at -0.40005 0 270)
			(size 0 0)
			(layers "F.Cu" "F.Mask" "F.Paste")
			(net "SW_P0V8_PEX2_BOOT2")
		)
		(pad "2" smd circle
			(at 0.40005 0 270)
			(size 0 0)
			(layers "F.Cu" "F.Mask" "F.Paste")
			(net "SW_P0V8_PEX2_BOOT2_R")
		)
	)
	(footprint ""
		(layer "F.Cu")
		(at 438.164732 -356.244906 90)
		(property "Reference" "C2468"
			(at 0 0 90)
			(layer "F.SilkS")
			(hide yes)
			(effects
				(font
					(size 1.27 1.27)
				)
			)
		)
		(property "Value" ""
			(at 0 0 90)
			(layer "F.Fab")
			(effects
				(font
					(size 1.27 1.27)
				)
			)
		)
		(duplicate_pad_numbers_are_jumpers no)
		(fp_line
			(start 0.299974 -0.150114)
			(end 0.299974 0.150114)
			(stroke
				(width 0.1)
				(type default)
			)
			(layer "F.Fab")
		)
		(fp_line
			(start -0.299974 -0.150114)
			(end 0.299974 -0.150114)
			(stroke
				(width 0.1)
				(type default)
			)
			(layer "F.Fab")
		)
		(fp_line
			(start 0.299974 0.150114)
			(end -0.299974 0.150114)
			(stroke
				(width 0.1)
				(type default)
			)
			(layer "F.Fab")
		)
		(fp_line
			(start -0.299974 0.150114)
			(end -0.299974 -0.150114)
			(stroke
				(width 0.1)
				(type default)
			)
			(layer "F.Fab")
		)
		(pad "1" smd rect
			(at -0.2667 0 90)
			(size 0.3048 0.381)
			(layers "F.Cu" "F.Mask" "F.Paste")
			(net "P5E_PEX3_STN4_TX_DN<65>")
		)
		(pad "2" smd rect
			(at 0.2667 0 90)
			(size 0.3048 0.381)
			(layers "F.Cu" "F.Mask" "F.Paste")
			(net "P5E_PEX3_STN4_TX_C_DN<65>")
		)
	)
	(footprint ""
		(layer "F.Cu")
		(at 206.128366 -300.64202 -90)
		(property "Reference" "R3925"
			(at 0 0 270)
			(layer "F.SilkS")
			(hide yes)
			(effects
				(font
					(size 1.27 1.27)
				)
			)
		)
		(property "Value" ""
			(at 0 0 270)
			(layer "F.Fab")
			(effects
				(font
					(size 1.27 1.27)
				)
			)
		)
		(duplicate_pad_numbers_are_jumpers no)
		(fp_line
			(start -0.7874 0.4064)
			(end -0.7874 -0.4064)
			(stroke
				(width 0.1524)
				(type default)
			)
			(layer "F.SilkS")
		)
		(fp_line
			(start 0.7874 0.4064)
			(end -0.7874 0.4064)
			(stroke
				(width 0.1524)
				(type default)
			)
			(layer "F.SilkS")
		)
		(fp_line
			(start -0.7874 -0.4064)
			(end 0.7874 -0.4064)
			(stroke
				(width 0.1524)
				(type default)
			)
			(layer "F.SilkS")
		)
		(fp_line
			(start 0.7874 -0.4064)
			(end 0.7874 0.4064)
			(stroke
				(width 0.1524)
				(type default)
			)
			(layer "F.SilkS")
		)
		(fp_line
			(start -0.67945 0.3048)
			(end -0.67945 -0.305054)
			(stroke
				(width 0.1)
				(type default)
			)
			(layer "F.Fab")
		)
		(fp_line
			(start -0.12065 0.3048)
			(end -0.67945 0.3048)
			(stroke
				(width 0.1)
				(type default)
			)
			(layer "F.Fab")
		)
		(fp_line
			(start 0.120396 0.3048)
			(end 0.120396 0.2794)
			(stroke
				(width 0.1)
				(type default)
			)
			(layer "F.Fab")
		)
		(fp_line
			(start 0.67945 0.3048)
			(end 0.120396 0.3048)
			(stroke
				(width 0.1)
				(type default)
			)
			(layer "F.Fab")
		)
		(fp_line
			(start -0.12065 0.2794)
			(end -0.12065 0.3048)
			(stroke
				(width 0.1)
				(type default)
			)
			(layer "F.Fab")
		)
		(fp_line
			(start 0.120396 0.2794)
			(end -0.12065 0.2794)
			(stroke
				(width 0.1)
				(type default)
			)
			(layer "F.Fab")
		)
		(fp_line
			(start -0.12065 -0.2794)
			(end 0.12065 -0.2794)
			(stroke
				(width 0.1)
				(type default)
			)
			(layer "F.Fab")
		)
		(fp_line
			(start 0.12065 -0.2794)
			(end 0.12065 -0.3048)
			(stroke
				(width 0.1)
				(type default)
			)
			(layer "F.Fab")
		)
		(fp_line
			(start 0.12065 -0.3048)
			(end 0.67945 -0.3048)
			(stroke
				(width 0.1)
				(type default)
			)
			(layer "F.Fab")
		)
		(fp_line
			(start 0.67945 -0.3048)
			(end 0.67945 0.3048)
			(stroke
				(width 0.1)
				(type default)
			)
			(layer "F.Fab")
		)
		(fp_line
			(start -0.67945 -0.305054)
			(end -0.12065 -0.305054)
			(stroke
				(width 0.1)
				(type default)
			)
			(layer "F.Fab")
		)
		(fp_line
			(start -0.12065 -0.305054)
			(end -0.12065 -0.2794)
			(stroke
				(width 0.1)
				(type default)
			)
			(layer "F.Fab")
		)
		(pad "1" smd circle
			(at -0.40005 0 270)
			(size 0 0)
			(layers "F.Cu" "F.Mask" "F.Paste")
			(net "I2C0_PEX1_SDA")
		)
		(pad "2" smd circle
			(at 0.40005 0 270)
			(size 0 0)
			(layers "F.Cu" "F.Mask" "F.Paste")
			(net "I2C_PEX1_HOST_SDA")
		)
	)
	(footprint ""
		(layer "F.Cu")
		(at 21.74621 -166.87546 180)
		(property "Reference" "PL1"
			(at 0.10541 -1.31953 0)
			(unlocked yes)
			(layer "F.SilkS")
			(effects
				(font
					(size 0.7874 0.5842)
					(thickness 0.1524)
				)
			)
		)
		(property "Value" ""
			(at 0 0 180)
			(layer "F.Fab")
			(effects
				(font
					(size 1.27 1.27)
				)
			)
		)
		(duplicate_pad_numbers_are_jumpers no)
		(fp_line
			(start 1.27 0.5842)
			(end 1.27 -0.5842)
			(stroke
				(width 0.1524)
				(type default)
			)
			(layer "F.SilkS")
		)
		(fp_line
			(start 1.27 0.5842)
			(end -1.27 0.5842)
			(stroke
				(width 0.1524)
				(type default)
			)
			(layer "F.SilkS")
		)
		(fp_line
			(start -1.27 0.5842)
			(end -1.27 -0.5842)
			(stroke
				(width 0.1524)
				(type default)
			)
			(layer "F.SilkS")
		)
		(fp_line
			(start -1.27 -0.5588)
			(end -1.27 -0.5842)
			(stroke
				(width 0.1524)
				(type default)
			)
			(layer "F.SilkS")
		)
		(fp_line
			(start -1.27 -0.5842)
			(end 1.27 -0.5842)
			(stroke
				(width 0.1524)
				(type default)
			)
			(layer "F.SilkS")
		)
		(fp_line
			(start 1.1938 0.4064)
			(end 0.9144 0.4064)
			(stroke
				(width 0.1)
				(type default)
			)
			(layer "F.Fab")
		)
		(fp_line
			(start 1.1938 -0.406654)
			(end 1.1938 0.4064)
			(stroke
				(width 0.1)
				(type default)
			)
			(layer "F.Fab")
		)
		(fp_line
			(start 0.9144 0.508)
			(end -0.9144 0.508)
			(stroke
				(width 0.1)
				(type default)
			)
			(layer "F.Fab")
		)
		(fp_line
			(start 0.9144 0.4064)
			(end 0.9144 0.508)
			(stroke
				(width 0.1)
				(type default)
			)
			(layer "F.Fab")
		)
		(fp_line
			(start 0.9144 -0.406654)
			(end 1.1938 -0.406654)
			(stroke
				(width 0.1)
				(type default)
			)
			(layer "F.Fab")
		)
		(fp_line
			(start 0.9144 -0.508)
			(end 0.9144 -0.406654)
			(stroke
				(width 0.1)
				(type default)
			)
			(layer "F.Fab")
		)
		(fp_line
			(start -0.9144 0.508)
			(end -0.9144 0.406654)
			(stroke
				(width 0.1)
				(type default)
			)
			(layer "F.Fab")
		)
		(fp_line
			(start -0.9144 0.406654)
			(end -1.194308 0.406654)
			(stroke
				(width 0.1)
				(type default)
			)
			(layer "F.Fab")
		)
		(fp_line
			(start -0.9144 -0.406654)
			(end -0.9144 -0.508)
			(stroke
				(width 0.1)
				(type default)
			)
			(layer "F.Fab")
		)
		(fp_line
			(start -0.9144 -0.508)
			(end 0.9144 -0.508)
			(stroke
				(width 0.1)
				(type default)
			)
			(layer "F.Fab")
		)
		(fp_line
			(start -1.194308 0.406654)
			(end -1.194308 -0.406654)
			(stroke
				(width 0.1)
				(type default)
			)
			(layer "F.Fab")
		)
		(fp_line
			(start -1.194308 -0.406654)
			(end -0.9144 -0.406654)
			(stroke
				(width 0.1)
				(type default)
			)
			(layer "F.Fab")
		)
		(pad "1" smd rect
			(at -0.7366 0 90)
			(size 0.7112 0.8128)
			(layers "F.Cu" "F.Mask" "F.Paste")
			(net "P12V_AUX")
		)
		(pad "2" smd rect
			(at 0.7366 0 90)
			(size 0.7112 0.8128)
			(layers "F.Cu" "F.Mask" "F.Paste")
			(net "SW_P12V_P5V_AUX_FLT")
		)
	)
	(footprint ""
		(layer "F.Cu")
		(at 277.457916 -72.766682 90)
		(property "Reference" "PC862"
			(at 0 0 90)
			(layer "F.SilkS")
			(hide yes)
			(effects
				(font
					(size 1.27 1.27)
				)
			)
		)
		(property "Value" ""
			(at 0 0 90)
			(layer "F.Fab")
			(effects
				(font
					(size 1.27 1.27)
				)
			)
		)
		(duplicate_pad_numbers_are_jumpers no)
		(fp_line
			(start 0.7874 -0.4064)
			(end 0.7874 0.4064)
			(stroke
				(width 0.1524)
				(type default)
			)
			(layer "F.SilkS")
		)
		(fp_line
			(start -0.7874 -0.4064)
			(end 0.7874 -0.4064)
			(stroke
				(width 0.1524)
				(type default)
			)
			(layer "F.SilkS")
		)
		(fp_line
			(start 0.7874 0.4064)
			(end -0.7874 0.4064)
			(stroke
				(width 0.1524)
				(type default)
			)
			(layer "F.SilkS")
		)
		(fp_line
			(start -0.7874 0.4064)
			(end -0.7874 -0.4064)
			(stroke
				(width 0.1524)
				(type default)
			)
			(layer "F.SilkS")
		)
		(fp_line
			(start -0.12065 -0.305054)
			(end -0.12065 -0.2794)
			(stroke
				(width 0.1)
				(type default)
			)
			(layer "F.Fab")
		)
		(fp_line
			(start -0.67945 -0.305054)
			(end -0.12065 -0.305054)
			(stroke
				(width 0.1)
				(type default)
			)
			(layer "F.Fab")
		)
		(fp_line
			(start 0.67945 -0.3048)
			(end 0.67945 0.3048)
			(stroke
				(width 0.1)
				(type default)
			)
			(layer "F.Fab")
		)
		(fp_line
			(start 0.12065 -0.3048)
			(end 0.67945 -0.3048)
			(stroke
				(width 0.1)
				(type default)
			)
			(layer "F.Fab")
		)
		(fp_line
			(start 0.12065 -0.2794)
			(end 0.12065 -0.3048)
			(stroke
				(width 0.1)
				(type default)
			)
			(layer "F.Fab")
		)
		(fp_line
			(start -0.12065 -0.2794)
			(end 0.12065 -0.2794)
			(stroke
				(width 0.1)
				(type default)
			)
			(layer "F.Fab")
		)
		(fp_line
			(start 0.120396 0.2794)
			(end -0.12065 0.2794)
			(stroke
				(width 0.1)
				(type default)
			)
			(layer "F.Fab")
		)
		(fp_line
			(start -0.12065 0.2794)
			(end -0.12065 0.3048)
			(stroke
				(width 0.1)
				(type default)
			)
			(layer "F.Fab")
		)
		(fp_line
			(start 0.67945 0.3048)
			(end 0.120396 0.3048)
			(stroke
				(width 0.1)
				(type default)
			)
			(layer "F.Fab")
		)
		(fp_line
			(start 0.120396 0.3048)
			(end 0.120396 0.2794)
			(stroke
				(width 0.1)
				(type default)
			)
			(layer "F.Fab")
		)
		(fp_line
			(start -0.12065 0.3048)
			(end -0.67945 0.3048)
			(stroke
				(width 0.1)
				(type default)
			)
			(layer "F.Fab")
		)
		(fp_line
			(start -0.67945 0.3048)
			(end -0.67945 -0.305054)
			(stroke
				(width 0.1)
				(type default)
			)
			(layer "F.Fab")
		)
		(pad "1" smd circle
			(at -0.40005 0 90)
			(size 0 0)
			(layers "F.Cu" "F.Mask" "F.Paste")
			(net "P12V_SSD9_CO_MODE")
		)
		(pad "2" smd circle
			(at 0.40005 0 90)
			(size 0 0)
			(layers "F.Cu" "F.Mask" "F.Paste")
			(net "GND")
		)
	)
	(footprint ""
		(layer "F.Cu")
		(at 239.754918 -317.573914 180)
		(property "Reference" "PC1009"
			(at 0 0 180)
			(layer "F.SilkS")
			(hide yes)
			(effects
				(font
					(size 1.27 1.27)
				)
			)
		)
		(property "Value" ""
			(at 0 0 180)
			(layer "F.Fab")
			(effects
				(font
					(size 1.27 1.27)
				)
			)
		)
		(duplicate_pad_numbers_are_jumpers no)
		(fp_line
			(start 1.524 0.762)
			(end -1.524 0.762)
			(stroke
				(width 0.1524)
				(type default)
			)
			(layer "F.SilkS")
		)
		(fp_line
			(start 1.524 -0.762)
			(end 1.524 0.762)
			(stroke
				(width 0.1524)
				(type default)
			)
			(layer "F.SilkS")
		)
		(fp_line
			(start -1.524 0.762)
			(end -1.524 -0.762)
			(stroke
				(width 0.1524)
				(type default)
			)
			(layer "F.SilkS")
		)
		(fp_line
			(start -1.524 -0.762)
			(end 1.524 -0.762)
			(stroke
				(width 0.1524)
				(type default)
			)
			(layer "F.SilkS")
		)
		(fp_line
			(start 1.1049 0.724916)
			(end 1.1049 -0.724916)
			(stroke
				(width 0.1)
				(type default)
			)
			(layer "F.Fab")
		)
		(fp_line
			(start 1.1049 -0.724916)
			(end -1.1049 -0.724916)
			(stroke
				(width 0.1)
				(type default)
			)
			(layer "F.Fab")
		)
		(fp_line
			(start -1.1049 0.724916)
			(end 1.1049 0.724916)
			(stroke
				(width 0.1)
				(type default)
			)
			(layer "F.Fab")
		)
		(fp_line
			(start -1.1049 -0.724916)
			(end -1.1049 0.724916)
			(stroke
				(width 0.1)
				(type default)
			)
			(layer "F.Fab")
		)
		(pad "1" smd rect
			(at -0.889 0)
			(size 1.016 1.27)
			(layers "F.Cu" "F.Mask" "F.Paste")
			(net "SW_P12V_P1V25_PEX2_FLT")
		)
		(pad "2" smd rect
			(at 0.889 0)
			(size 1.016 1.27)
			(layers "F.Cu" "F.Mask" "F.Paste")
			(net "GND")
		)
	)
	(footprint ""
		(layer "F.Cu")
		(at 70.72249 -44.341542 90)
		(property "Reference" "R536"
			(at 0 0 90)
			(layer "F.SilkS")
			(hide yes)
			(effects
				(font
					(size 1.27 1.27)
				)
			)
		)
		(property "Value" ""
			(at 0 0 90)
			(layer "F.Fab")
			(effects
				(font
					(size 1.27 1.27)
				)
			)
		)
		(duplicate_pad_numbers_are_jumpers no)
		(fp_line
			(start 0.7874 -0.4064)
			(end 0.7874 0.4064)
			(stroke
				(width 0.1524)
				(type default)
			)
			(layer "F.SilkS")
		)
		(fp_line
			(start -0.7874 -0.4064)
			(end 0.7874 -0.4064)
			(stroke
				(width 0.1524)
				(type default)
			)
			(layer "F.SilkS")
		)
		(fp_line
			(start 0.7874 0.4064)
			(end -0.7874 0.4064)
			(stroke
				(width 0.1524)
				(type default)
			)
			(layer "F.SilkS")
		)
		(fp_line
			(start -0.7874 0.4064)
			(end -0.7874 -0.4064)
			(stroke
				(width 0.1524)
				(type default)
			)
			(layer "F.SilkS")
		)
		(fp_line
			(start -0.12065 -0.305054)
			(end -0.12065 -0.2794)
			(stroke
				(width 0.1)
				(type default)
			)
			(layer "F.Fab")
		)
		(fp_line
			(start -0.67945 -0.305054)
			(end -0.12065 -0.305054)
			(stroke
				(width 0.1)
				(type default)
			)
			(layer "F.Fab")
		)
		(fp_line
			(start 0.67945 -0.3048)
			(end 0.67945 0.3048)
			(stroke
				(width 0.1)
				(type default)
			)
			(layer "F.Fab")
		)
		(fp_line
			(start 0.12065 -0.3048)
			(end 0.67945 -0.3048)
			(stroke
				(width 0.1)
				(type default)
			)
			(layer "F.Fab")
		)
		(fp_line
			(start 0.12065 -0.2794)
			(end 0.12065 -0.3048)
			(stroke
				(width 0.1)
				(type default)
			)
			(layer "F.Fab")
		)
		(fp_line
			(start -0.12065 -0.2794)
			(end 0.12065 -0.2794)
			(stroke
				(width 0.1)
				(type default)
			)
			(layer "F.Fab")
		)
		(fp_line
			(start 0.120396 0.2794)
			(end -0.12065 0.2794)
			(stroke
				(width 0.1)
				(type default)
			)
			(layer "F.Fab")
		)
		(fp_line
			(start -0.12065 0.2794)
			(end -0.12065 0.3048)
			(stroke
				(width 0.1)
				(type default)
			)
			(layer "F.Fab")
		)
		(fp_line
			(start 0.67945 0.3048)
			(end 0.120396 0.3048)
			(stroke
				(width 0.1)
				(type default)
			)
			(layer "F.Fab")
		)
		(fp_line
			(start 0.120396 0.3048)
			(end 0.120396 0.2794)
			(stroke
				(width 0.1)
				(type default)
			)
			(layer "F.Fab")
		)
		(fp_line
			(start -0.12065 0.3048)
			(end -0.67945 0.3048)
			(stroke
				(width 0.1)
				(type default)
			)
			(layer "F.Fab")
		)
		(fp_line
			(start -0.67945 0.3048)
			(end -0.67945 -0.305054)
			(stroke
				(width 0.1)
				(type default)
			)
			(layer "F.Fab")
		)
		(pad "1" smd circle
			(at -0.40005 0 90)
			(size 0 0)
			(layers "F.Cu" "F.Mask" "F.Paste")
			(net "P12V_SSD2")
		)
		(pad "2" smd circle
			(at 0.40005 0 90)
			(size 0 0)
			(layers "F.Cu" "F.Mask" "F.Paste")
			(net "P12V_SSD2_VIN_N")
		)
	)
	(footprint ""
		(layer "F.Cu")
		(at 205.822296 -212.577426 180)
		(property "Reference" "R5918"
			(at 0 0 180)
			(layer "F.SilkS")
			(hide yes)
			(effects
				(font
					(size 1.27 1.27)
				)
			)
		)
		(property "Value" ""
			(at 0 0 180)
			(layer "F.Fab")
			(effects
				(font
					(size 1.27 1.27)
				)
			)
		)
		(duplicate_pad_numbers_are_jumpers no)
		(fp_line
			(start 0.7874 0.4064)
			(end -0.7874 0.4064)
			(stroke
				(width 0.1524)
				(type default)
			)
			(layer "F.SilkS")
		)
		(fp_line
			(start 0.7874 -0.4064)
			(end 0.7874 0.4064)
			(stroke
				(width 0.1524)
				(type default)
			)
			(layer "F.SilkS")
		)
		(fp_line
			(start -0.7874 0.4064)
			(end -0.7874 -0.4064)
			(stroke
				(width 0.1524)
				(type default)
			)
			(layer "F.SilkS")
		)
		(fp_line
			(start -0.7874 -0.4064)
			(end 0.7874 -0.4064)
			(stroke
				(width 0.1524)
				(type default)
			)
			(layer "F.SilkS")
		)
		(fp_line
			(start 0.67945 0.3048)
			(end 0.120396 0.3048)
			(stroke
				(width 0.1)
				(type default)
			)
			(layer "F.Fab")
		)
		(fp_line
			(start 0.67945 -0.3048)
			(end 0.67945 0.3048)
			(stroke
				(width 0.1)
				(type default)
			)
			(layer "F.Fab")
		)
		(fp_line
			(start 0.12065 -0.2794)
			(end 0.12065 -0.3048)
			(stroke
				(width 0.1)
				(type default)
			)
			(layer "F.Fab")
		)
		(fp_line
			(start 0.12065 -0.3048)
			(end 0.67945 -0.3048)
			(stroke
				(width 0.1)
				(type default)
			)
			(layer "F.Fab")
		)
		(fp_line
			(start 0.120396 0.3048)
			(end 0.120396 0.2794)
			(stroke
				(width 0.1)
				(type default)
			)
			(layer "F.Fab")
		)
		(fp_line
			(start 0.120396 0.2794)
			(end -0.12065 0.2794)
			(stroke
				(width 0.1)
				(type default)
			)
			(layer "F.Fab")
		)
		(fp_line
			(start -0.12065 0.3048)
			(end -0.67945 0.3048)
			(stroke
				(width 0.1)
				(type default)
			)
			(layer "F.Fab")
		)
		(fp_line
			(start -0.12065 0.2794)
			(end -0.12065 0.3048)
			(stroke
				(width 0.1)
				(type default)
			)
			(layer "F.Fab")
		)
		(fp_line
			(start -0.12065 -0.2794)
			(end 0.12065 -0.2794)
			(stroke
				(width 0.1)
				(type default)
			)
			(layer "F.Fab")
		)
		(fp_line
			(start -0.12065 -0.305054)
			(end -0.12065 -0.2794)
			(stroke
				(width 0.1)
				(type default)
			)
			(layer "F.Fab")
		)
		(fp_line
			(start -0.67945 0.3048)
			(end -0.67945 -0.305054)
			(stroke
				(width 0.1)
				(type default)
			)
			(layer "F.Fab")
		)
		(fp_line
			(start -0.67945 -0.305054)
			(end -0.12065 -0.305054)
			(stroke
				(width 0.1)
				(type default)
			)
			(layer "F.Fab")
		)
		(pad "1" smd circle
			(at -0.40005 0 180)
			(size 0 0)
			(layers "F.Cu" "F.Mask" "F.Paste")
			(net "BIC_UART_SEL2")
		)
		(pad "2" smd circle
			(at 0.40005 0 180)
			(size 0 0)
			(layers "F.Cu" "F.Mask" "F.Paste")
			(net "P3V3_AUX")
		)
	)
	(footprint ""
		(layer "F.Cu")
		(at 45.738542 -44.341542 90)
		(property "Reference" "C206"
			(at 0 0 90)
			(layer "F.SilkS")
			(hide yes)
			(effects
				(font
					(size 1.27 1.27)
				)
			)
		)
		(property "Value" ""
			(at 0 0 90)
			(layer "F.Fab")
			(effects
				(font
					(size 1.27 1.27)
				)
			)
		)
		(duplicate_pad_numbers_are_jumpers no)
		(fp_line
			(start 0.7874 -0.4064)
			(end 0.7874 0.4064)
			(stroke
				(width 0.1524)
				(type default)
			)
			(layer "F.SilkS")
		)
		(fp_line
			(start -0.7874 -0.4064)
			(end 0.7874 -0.4064)
			(stroke
				(width 0.1524)
				(type default)
			)
			(layer "F.SilkS")
		)
		(fp_line
			(start 0.7874 0.4064)
			(end -0.7874 0.4064)
			(stroke
				(width 0.1524)
				(type default)
			)
			(layer "F.SilkS")
		)
		(fp_line
			(start -0.7874 0.4064)
			(end -0.7874 -0.4064)
			(stroke
				(width 0.1524)
				(type default)
			)
			(layer "F.SilkS")
		)
		(fp_line
			(start -0.12065 -0.305054)
			(end -0.12065 -0.2794)
			(stroke
				(width 0.1)
				(type default)
			)
			(layer "F.Fab")
		)
		(fp_line
			(start -0.67945 -0.305054)
			(end -0.12065 -0.305054)
			(stroke
				(width 0.1)
				(type default)
			)
			(layer "F.Fab")
		)
		(fp_line
			(start 0.67945 -0.3048)
			(end 0.67945 0.3048)
			(stroke
				(width 0.1)
				(type default)
			)
			(layer "F.Fab")
		)
		(fp_line
			(start 0.12065 -0.3048)
			(end 0.67945 -0.3048)
			(stroke
				(width 0.1)
				(type default)
			)
			(layer "F.Fab")
		)
		(fp_line
			(start 0.12065 -0.2794)
			(end 0.12065 -0.3048)
			(stroke
				(width 0.1)
				(type default)
			)
			(layer "F.Fab")
		)
		(fp_line
			(start -0.12065 -0.2794)
			(end 0.12065 -0.2794)
			(stroke
				(width 0.1)
				(type default)
			)
			(layer "F.Fab")
		)
		(fp_line
			(start 0.120396 0.2794)
			(end -0.12065 0.2794)
			(stroke
				(width 0.1)
				(type default)
			)
			(layer "F.Fab")
		)
		(fp_line
			(start -0.12065 0.2794)
			(end -0.12065 0.3048)
			(stroke
				(width 0.1)
				(type default)
			)
			(layer "F.Fab")
		)
		(fp_line
			(start 0.67945 0.3048)
			(end 0.120396 0.3048)
			(stroke
				(width 0.1)
				(type default)
			)
			(layer "F.Fab")
		)
		(fp_line
			(start 0.120396 0.3048)
			(end 0.120396 0.2794)
			(stroke
				(width 0.1)
				(type default)
			)
			(layer "F.Fab")
		)
		(fp_line
			(start -0.12065 0.3048)
			(end -0.67945 0.3048)
			(stroke
				(width 0.1)
				(type default)
			)
			(layer "F.Fab")
		)
		(fp_line
			(start -0.67945 0.3048)
			(end -0.67945 -0.305054)
			(stroke
				(width 0.1)
				(type default)
			)
			(layer "F.Fab")
		)
		(pad "1" smd circle
			(at -0.40005 0 90)
			(size 0 0)
			(layers "F.Cu" "F.Mask" "F.Paste")
			(net "P12V_SSD1_VIN_P")
		)
		(pad "2" smd circle
			(at 0.40005 0 90)
			(size 0 0)
			(layers "F.Cu" "F.Mask" "F.Paste")
			(net "P12V_SSD1_VIN_N")
		)
	)
	(footprint ""
		(layer "F.Cu")
		(at 111.836708 -343.952322 90)
		(property "Reference" "C340"
			(at 0 0 90)
			(layer "F.SilkS")
			(hide yes)
			(effects
				(font
					(size 1.27 1.27)
				)
			)
		)
		(property "Value" ""
			(at 0 0 90)
			(layer "F.Fab")
			(effects
				(font
					(size 1.27 1.27)
				)
			)
		)
		(duplicate_pad_numbers_are_jumpers no)
		(fp_line
			(start 0.299974 -0.150114)
			(end 0.299974 0.150114)
			(stroke
				(width 0.1)
				(type default)
			)
			(layer "F.Fab")
		)
		(fp_line
			(start -0.299974 -0.150114)
			(end 0.299974 -0.150114)
			(stroke
				(width 0.1)
				(type default)
			)
			(layer "F.Fab")
		)
		(fp_line
			(start 0.299974 0.150114)
			(end -0.299974 0.150114)
			(stroke
				(width 0.1)
				(type default)
			)
			(layer "F.Fab")
		)
		(fp_line
			(start -0.299974 0.150114)
			(end -0.299974 -0.150114)
			(stroke
				(width 0.1)
				(type default)
			)
			(layer "F.Fab")
		)
		(pad "1" smd rect
			(at -0.2667 0 90)
			(size 0.3048 0.381)
			(layers "F.Cu" "F.Mask" "F.Paste")
			(net "P5E_PEX1_STN6_TX_DP<111>")
		)
		(pad "2" smd rect
			(at 0.2667 0 90)
			(size 0.3048 0.381)
			(layers "F.Cu" "F.Mask" "F.Paste")
			(net "P5E_PEX1_STN6_TX_C_DP<111>")
		)
	)
	(footprint ""
		(layer "F.Cu")
		(at 28.04922 -287.395412 -90)
		(property "Reference" "C3052"
			(at 0 0 270)
			(layer "F.SilkS")
			(hide yes)
			(effects
				(font
					(size 1.27 1.27)
				)
			)
		)
		(property "Value" ""
			(at 0 0 270)
			(layer "F.Fab")
			(effects
				(font
					(size 1.27 1.27)
				)
			)
		)
		(duplicate_pad_numbers_are_jumpers no)
		(fp_line
			(start -0.299974 0.150114)
			(end -0.299974 -0.150114)
			(stroke
				(width 0.1)
				(type default)
			)
			(layer "F.Fab")
		)
		(fp_line
			(start 0.299974 0.150114)
			(end -0.299974 0.150114)
			(stroke
				(width 0.1)
				(type default)
			)
			(layer "F.Fab")
		)
		(fp_line
			(start -0.299974 -0.150114)
			(end 0.299974 -0.150114)
			(stroke
				(width 0.1)
				(type default)
			)
			(layer "F.Fab")
		)
		(fp_line
			(start 0.299974 -0.150114)
			(end 0.299974 0.150114)
			(stroke
				(width 0.1)
				(type default)
			)
			(layer "F.Fab")
		)
		(pad "1" smd rect
			(at -0.2667 0 270)
			(size 0.3048 0.381)
			(layers "F.Cu" "F.Mask" "F.Paste")
			(net "P1V8_PLL0_PEX0")
		)
		(pad "2" smd rect
			(at 0.2667 0 270)
			(size 0.3048 0.381)
			(layers "F.Cu" "F.Mask" "F.Paste")
			(net "GND")
		)
	)
	(footprint ""
		(layer "F.Cu")
		(at 353.015296 -59.546236 90)
		(property "Reference" "C2894"
			(at 0 0 90)
			(layer "F.SilkS")
			(hide yes)
			(effects
				(font
					(size 1.27 1.27)
				)
			)
		)
		(property "Value" ""
			(at 0 0 90)
			(layer "F.Fab")
			(effects
				(font
					(size 1.27 1.27)
				)
			)
		)
		(duplicate_pad_numbers_are_jumpers no)
		(fp_line
			(start 0.7874 -0.4064)
			(end 0.7874 0.4064)
			(stroke
				(width 0.1524)
				(type default)
			)
			(layer "F.SilkS")
		)
		(fp_line
			(start -0.7874 -0.4064)
			(end 0.7874 -0.4064)
			(stroke
				(width 0.1524)
				(type default)
			)
			(layer "F.SilkS")
		)
		(fp_line
			(start 0.7874 0.4064)
			(end -0.7874 0.4064)
			(stroke
				(width 0.1524)
				(type default)
			)
			(layer "F.SilkS")
		)
		(fp_line
			(start -0.7874 0.4064)
			(end -0.7874 -0.4064)
			(stroke
				(width 0.1524)
				(type default)
			)
			(layer "F.SilkS")
		)
		(fp_line
			(start -0.12065 -0.305054)
			(end -0.12065 -0.2794)
			(stroke
				(width 0.1)
				(type default)
			)
			(layer "F.Fab")
		)
		(fp_line
			(start -0.67945 -0.305054)
			(end -0.12065 -0.305054)
			(stroke
				(width 0.1)
				(type default)
			)
			(layer "F.Fab")
		)
		(fp_line
			(start 0.67945 -0.3048)
			(end 0.67945 0.3048)
			(stroke
				(width 0.1)
				(type default)
			)
			(layer "F.Fab")
		)
		(fp_line
			(start 0.12065 -0.3048)
			(end 0.67945 -0.3048)
			(stroke
				(width 0.1)
				(type default)
			)
			(layer "F.Fab")
		)
		(fp_line
			(start 0.12065 -0.2794)
			(end 0.12065 -0.3048)
			(stroke
				(width 0.1)
				(type default)
			)
			(layer "F.Fab")
		)
		(fp_line
			(start -0.12065 -0.2794)
			(end 0.12065 -0.2794)
			(stroke
				(width 0.1)
				(type default)
			)
			(layer "F.Fab")
		)
		(fp_line
			(start 0.120396 0.2794)
			(end -0.12065 0.2794)
			(stroke
				(width 0.1)
				(type default)
			)
			(layer "F.Fab")
		)
		(fp_line
			(start -0.12065 0.2794)
			(end -0.12065 0.3048)
			(stroke
				(width 0.1)
				(type default)
			)
			(layer "F.Fab")
		)
		(fp_line
			(start 0.67945 0.3048)
			(end 0.120396 0.3048)
			(stroke
				(width 0.1)
				(type default)
			)
			(layer "F.Fab")
		)
		(fp_line
			(start 0.120396 0.3048)
			(end 0.120396 0.2794)
			(stroke
				(width 0.1)
				(type default)
			)
			(layer "F.Fab")
		)
		(fp_line
			(start -0.12065 0.3048)
			(end -0.67945 0.3048)
			(stroke
				(width 0.1)
				(type default)
			)
			(layer "F.Fab")
		)
		(fp_line
			(start -0.67945 0.3048)
			(end -0.67945 -0.305054)
			(stroke
				(width 0.1)
				(type default)
			)
			(layer "F.Fab")
		)
		(pad "1" smd circle
			(at -0.40005 0 90)
			(size 0 0)
			(layers "F.Cu" "F.Mask" "F.Paste")
			(net "SSD12_AUX_P3V3_EN_R")
		)
		(pad "2" smd circle
			(at 0.40005 0 90)
			(size 0 0)
			(layers "F.Cu" "F.Mask" "F.Paste")
			(net "GND")
		)
	)
	(footprint ""
		(layer "F.Cu")
		(at 177.705512 -356.244906 90)
		(property "Reference" "C2528"
			(at 0 0 90)
			(layer "F.SilkS")
			(hide yes)
			(effects
				(font
					(size 1.27 1.27)
				)
			)
		)
		(property "Value" ""
			(at 0 0 90)
			(layer "F.Fab")
			(effects
				(font
					(size 1.27 1.27)
				)
			)
		)
		(duplicate_pad_numbers_are_jumpers no)
		(fp_line
			(start 0.299974 -0.150114)
			(end 0.299974 0.150114)
			(stroke
				(width 0.1)
				(type default)
			)
			(layer "F.Fab")
		)
		(fp_line
			(start -0.299974 -0.150114)
			(end 0.299974 -0.150114)
			(stroke
				(width 0.1)
				(type default)
			)
			(layer "F.Fab")
		)
		(fp_line
			(start 0.299974 0.150114)
			(end -0.299974 0.150114)
			(stroke
				(width 0.1)
				(type default)
			)
			(layer "F.Fab")
		)
		(fp_line
			(start -0.299974 0.150114)
			(end -0.299974 -0.150114)
			(stroke
				(width 0.1)
				(type default)
			)
			(layer "F.Fab")
		)
		(pad "1" smd rect
			(at -0.2667 0 90)
			(size 0.3048 0.381)
			(layers "F.Cu" "F.Mask" "F.Paste")
			(net "P5E_PEX1_STN4_TX_DP<71>")
		)
		(pad "2" smd rect
			(at 0.2667 0 90)
			(size 0.3048 0.381)
			(layers "F.Cu" "F.Mask" "F.Paste")
			(net "P5E_PEX1_STN4_TX_C_DP<71>")
		)
	)
	(footprint ""
		(layer "F.Cu")
		(at 98.048318 -395.1478 180)
		(property "Reference" "R5460"
			(at 0 0 180)
			(layer "F.SilkS")
			(hide yes)
			(effects
				(font
					(size 1.27 1.27)
				)
			)
		)
		(property "Value" ""
			(at 0 0 180)
			(layer "F.Fab")
			(effects
				(font
					(size 1.27 1.27)
				)
			)
		)
		(duplicate_pad_numbers_are_jumpers no)
		(fp_line
			(start 0.7874 0.4064)
			(end -0.7874 0.4064)
			(stroke
				(width 0.1524)
				(type default)
			)
			(layer "F.SilkS")
		)
		(fp_line
			(start 0.7874 -0.4064)
			(end 0.7874 0.4064)
			(stroke
				(width 0.1524)
				(type default)
			)
			(layer "F.SilkS")
		)
		(fp_line
			(start -0.7874 0.4064)
			(end -0.7874 -0.4064)
			(stroke
				(width 0.1524)
				(type default)
			)
			(layer "F.SilkS")
		)
		(fp_line
			(start -0.7874 -0.4064)
			(end 0.7874 -0.4064)
			(stroke
				(width 0.1524)
				(type default)
			)
			(layer "F.SilkS")
		)
		(fp_line
			(start 0.67945 0.3048)
			(end 0.120396 0.3048)
			(stroke
				(width 0.1)
				(type default)
			)
			(layer "F.Fab")
		)
		(fp_line
			(start 0.67945 -0.3048)
			(end 0.67945 0.3048)
			(stroke
				(width 0.1)
				(type default)
			)
			(layer "F.Fab")
		)
		(fp_line
			(start 0.12065 -0.2794)
			(end 0.12065 -0.3048)
			(stroke
				(width 0.1)
				(type default)
			)
			(layer "F.Fab")
		)
		(fp_line
			(start 0.12065 -0.3048)
			(end 0.67945 -0.3048)
			(stroke
				(width 0.1)
				(type default)
			)
			(layer "F.Fab")
		)
		(fp_line
			(start 0.120396 0.3048)
			(end 0.120396 0.2794)
			(stroke
				(width 0.1)
				(type default)
			)
			(layer "F.Fab")
		)
		(fp_line
			(start 0.120396 0.2794)
			(end -0.12065 0.2794)
			(stroke
				(width 0.1)
				(type default)
			)
			(layer "F.Fab")
		)
		(fp_line
			(start -0.12065 0.3048)
			(end -0.67945 0.3048)
			(stroke
				(width 0.1)
				(type default)
			)
			(layer "F.Fab")
		)
		(fp_line
			(start -0.12065 0.2794)
			(end -0.12065 0.3048)
			(stroke
				(width 0.1)
				(type default)
			)
			(layer "F.Fab")
		)
		(fp_line
			(start -0.12065 -0.2794)
			(end 0.12065 -0.2794)
			(stroke
				(width 0.1)
				(type default)
			)
			(layer "F.Fab")
		)
		(fp_line
			(start -0.12065 -0.305054)
			(end -0.12065 -0.2794)
			(stroke
				(width 0.1)
				(type default)
			)
			(layer "F.Fab")
		)
		(fp_line
			(start -0.67945 0.3048)
			(end -0.67945 -0.305054)
			(stroke
				(width 0.1)
				(type default)
			)
			(layer "F.Fab")
		)
		(fp_line
			(start -0.67945 -0.305054)
			(end -0.12065 -0.305054)
			(stroke
				(width 0.1)
				(type default)
			)
			(layer "F.Fab")
		)
		(pad "1" smd circle
			(at -0.40005 0 180)
			(size 0 0)
			(layers "F.Cu" "F.Mask" "F.Paste")
			(net "BIC_USB_HUB_PSELF")
		)
		(pad "2" smd circle
			(at 0.40005 0 180)
			(size 0 0)
			(layers "F.Cu" "F.Mask" "F.Paste")
			(net "GND")
		)
	)
	(footprint ""
		(layer "F.Cu")
		(at 427.614842 -81.36001 -90)
		(property "Reference" "R408"
			(at 0 0 270)
			(layer "F.SilkS")
			(hide yes)
			(effects
				(font
					(size 1.27 1.27)
				)
			)
		)
		(property "Value" ""
			(at 0 0 270)
			(layer "F.Fab")
			(effects
				(font
					(size 1.27 1.27)
				)
			)
		)
		(duplicate_pad_numbers_are_jumpers no)
		(fp_line
			(start -0.7874 0.4064)
			(end -0.7874 -0.4064)
			(stroke
				(width 0.1524)
				(type default)
			)
			(layer "F.SilkS")
		)
		(fp_line
			(start 0.7874 0.4064)
			(end -0.7874 0.4064)
			(stroke
				(width 0.1524)
				(type default)
			)
			(layer "F.SilkS")
		)
		(fp_line
			(start -0.7874 -0.4064)
			(end 0.7874 -0.4064)
			(stroke
				(width 0.1524)
				(type default)
			)
			(layer "F.SilkS")
		)
		(fp_line
			(start 0.7874 -0.4064)
			(end 0.7874 0.4064)
			(stroke
				(width 0.1524)
				(type default)
			)
			(layer "F.SilkS")
		)
		(fp_line
			(start -0.67945 0.3048)
			(end -0.67945 -0.305054)
			(stroke
				(width 0.1)
				(type default)
			)
			(layer "F.Fab")
		)
		(fp_line
			(start -0.12065 0.3048)
			(end -0.67945 0.3048)
			(stroke
				(width 0.1)
				(type default)
			)
			(layer "F.Fab")
		)
		(fp_line
			(start 0.120396 0.3048)
			(end 0.120396 0.2794)
			(stroke
				(width 0.1)
				(type default)
			)
			(layer "F.Fab")
		)
		(fp_line
			(start 0.67945 0.3048)
			(end 0.120396 0.3048)
			(stroke
				(width 0.1)
				(type default)
			)
			(layer "F.Fab")
		)
		(fp_line
			(start -0.12065 0.2794)
			(end -0.12065 0.3048)
			(stroke
				(width 0.1)
				(type default)
			)
			(layer "F.Fab")
		)
		(fp_line
			(start 0.120396 0.2794)
			(end -0.12065 0.2794)
			(stroke
				(width 0.1)
				(type default)
			)
			(layer "F.Fab")
		)
		(fp_line
			(start -0.12065 -0.2794)
			(end 0.12065 -0.2794)
			(stroke
				(width 0.1)
				(type default)
			)
			(layer "F.Fab")
		)
		(fp_line
			(start 0.12065 -0.2794)
			(end 0.12065 -0.3048)
			(stroke
				(width 0.1)
				(type default)
			)
			(layer "F.Fab")
		)
		(fp_line
			(start 0.12065 -0.3048)
			(end 0.67945 -0.3048)
			(stroke
				(width 0.1)
				(type default)
			)
			(layer "F.Fab")
		)
		(fp_line
			(start 0.67945 -0.3048)
			(end 0.67945 0.3048)
			(stroke
				(width 0.1)
				(type default)
			)
			(layer "F.Fab")
		)
		(fp_line
			(start -0.67945 -0.305054)
			(end -0.12065 -0.305054)
			(stroke
				(width 0.1)
				(type default)
			)
			(layer "F.Fab")
		)
		(fp_line
			(start -0.12065 -0.305054)
			(end -0.12065 -0.2794)
			(stroke
				(width 0.1)
				(type default)
			)
			(layer "F.Fab")
		)
		(pad "1" smd circle
			(at -0.40005 0 270)
			(size 0 0)
			(layers "F.Cu" "F.Mask" "F.Paste")
			(net "HP_NIC7_PWRGD_R")
		)
		(pad "2" smd circle
			(at 0.40005 0 270)
			(size 0 0)
			(layers "F.Cu" "F.Mask" "F.Paste")
			(net "HP_NIC7_PWRGD")
		)
	)
	(footprint ""
		(layer "F.Cu")
		(at 375.690384 -252.356874 -90)
		(property "Reference" "R1430"
			(at 0 0 270)
			(layer "F.SilkS")
			(hide yes)
			(effects
				(font
					(size 1.27 1.27)
				)
			)
		)
		(property "Value" ""
			(at 0 0 270)
			(layer "F.Fab")
			(effects
				(font
					(size 1.27 1.27)
				)
			)
		)
		(duplicate_pad_numbers_are_jumpers no)
		(fp_line
			(start -0.7874 0.4064)
			(end -0.7874 -0.4064)
			(stroke
				(width 0.1524)
				(type default)
			)
			(layer "F.SilkS")
		)
		(fp_line
			(start 0.7874 0.4064)
			(end -0.7874 0.4064)
			(stroke
				(width 0.1524)
				(type default)
			)
			(layer "F.SilkS")
		)
		(fp_line
			(start -0.7874 -0.4064)
			(end 0.7874 -0.4064)
			(stroke
				(width 0.1524)
				(type default)
			)
			(layer "F.SilkS")
		)
		(fp_line
			(start 0.7874 -0.4064)
			(end 0.7874 0.4064)
			(stroke
				(width 0.1524)
				(type default)
			)
			(layer "F.SilkS")
		)
		(fp_line
			(start -0.67945 0.3048)
			(end -0.67945 -0.305054)
			(stroke
				(width 0.1)
				(type default)
			)
			(layer "F.Fab")
		)
		(fp_line
			(start -0.12065 0.3048)
			(end -0.67945 0.3048)
			(stroke
				(width 0.1)
				(type default)
			)
			(layer "F.Fab")
		)
		(fp_line
			(start 0.120396 0.3048)
			(end 0.120396 0.2794)
			(stroke
				(width 0.1)
				(type default)
			)
			(layer "F.Fab")
		)
		(fp_line
			(start 0.67945 0.3048)
			(end 0.120396 0.3048)
			(stroke
				(width 0.1)
				(type default)
			)
			(layer "F.Fab")
		)
		(fp_line
			(start -0.12065 0.2794)
			(end -0.12065 0.3048)
			(stroke
				(width 0.1)
				(type default)
			)
			(layer "F.Fab")
		)
		(fp_line
			(start 0.120396 0.2794)
			(end -0.12065 0.2794)
			(stroke
				(width 0.1)
				(type default)
			)
			(layer "F.Fab")
		)
		(fp_line
			(start -0.12065 -0.2794)
			(end 0.12065 -0.2794)
			(stroke
				(width 0.1)
				(type default)
			)
			(layer "F.Fab")
		)
		(fp_line
			(start 0.12065 -0.2794)
			(end 0.12065 -0.3048)
			(stroke
				(width 0.1)
				(type default)
			)
			(layer "F.Fab")
		)
		(fp_line
			(start 0.12065 -0.3048)
			(end 0.67945 -0.3048)
			(stroke
				(width 0.1)
				(type default)
			)
			(layer "F.Fab")
		)
		(fp_line
			(start 0.67945 -0.3048)
			(end 0.67945 0.3048)
			(stroke
				(width 0.1)
				(type default)
			)
			(layer "F.Fab")
		)
		(fp_line
			(start -0.67945 -0.305054)
			(end -0.12065 -0.305054)
			(stroke
				(width 0.1)
				(type default)
			)
			(layer "F.Fab")
		)
		(fp_line
			(start -0.12065 -0.305054)
			(end -0.12065 -0.2794)
			(stroke
				(width 0.1)
				(type default)
			)
			(layer "F.Fab")
		)
		(pad "1" smd circle
			(at -0.40005 0 270)
			(size 0 0)
			(layers "F.Cu" "F.Mask" "F.Paste")
			(net "GND")
		)
		(pad "2" smd circle
			(at 0.40005 0 270)
			(size 0 0)
			(layers "F.Cu" "F.Mask" "F.Paste")
			(net "PEX3_MODE_SEL5")
		)
	)
	(footprint ""
		(layer "F.Cu")
		(at 355.854 -178.562 180)
		(property "Reference" "R4728"
			(at 0 0 180)
			(layer "F.SilkS")
			(hide yes)
			(effects
				(font
					(size 1.27 1.27)
				)
			)
		)
		(property "Value" ""
			(at 0 0 180)
			(layer "F.Fab")
			(effects
				(font
					(size 1.27 1.27)
				)
			)
		)
		(duplicate_pad_numbers_are_jumpers no)
		(fp_line
			(start 0.7874 0.4064)
			(end -0.7874 0.4064)
			(stroke
				(width 0.1524)
				(type default)
			)
			(layer "F.SilkS")
		)
		(fp_line
			(start 0.7874 -0.4064)
			(end 0.7874 0.4064)
			(stroke
				(width 0.1524)
				(type default)
			)
			(layer "F.SilkS")
		)
		(fp_line
			(start -0.7874 0.4064)
			(end -0.7874 -0.4064)
			(stroke
				(width 0.1524)
				(type default)
			)
			(layer "F.SilkS")
		)
		(fp_line
			(start -0.7874 -0.4064)
			(end 0.7874 -0.4064)
			(stroke
				(width 0.1524)
				(type default)
			)
			(layer "F.SilkS")
		)
		(fp_line
			(start 0.67945 0.3048)
			(end 0.120396 0.3048)
			(stroke
				(width 0.1)
				(type default)
			)
			(layer "F.Fab")
		)
		(fp_line
			(start 0.67945 -0.3048)
			(end 0.67945 0.3048)
			(stroke
				(width 0.1)
				(type default)
			)
			(layer "F.Fab")
		)
		(fp_line
			(start 0.12065 -0.2794)
			(end 0.12065 -0.3048)
			(stroke
				(width 0.1)
				(type default)
			)
			(layer "F.Fab")
		)
		(fp_line
			(start 0.12065 -0.3048)
			(end 0.67945 -0.3048)
			(stroke
				(width 0.1)
				(type default)
			)
			(layer "F.Fab")
		)
		(fp_line
			(start 0.120396 0.3048)
			(end 0.120396 0.2794)
			(stroke
				(width 0.1)
				(type default)
			)
			(layer "F.Fab")
		)
		(fp_line
			(start 0.120396 0.2794)
			(end -0.12065 0.2794)
			(stroke
				(width 0.1)
				(type default)
			)
			(layer "F.Fab")
		)
		(fp_line
			(start -0.12065 0.3048)
			(end -0.67945 0.3048)
			(stroke
				(width 0.1)
				(type default)
			)
			(layer "F.Fab")
		)
		(fp_line
			(start -0.12065 0.2794)
			(end -0.12065 0.3048)
			(stroke
				(width 0.1)
				(type default)
			)
			(layer "F.Fab")
		)
		(fp_line
			(start -0.12065 -0.2794)
			(end 0.12065 -0.2794)
			(stroke
				(width 0.1)
				(type default)
			)
			(layer "F.Fab")
		)
		(fp_line
			(start -0.12065 -0.305054)
			(end -0.12065 -0.2794)
			(stroke
				(width 0.1)
				(type default)
			)
			(layer "F.Fab")
		)
		(fp_line
			(start -0.67945 0.3048)
			(end -0.67945 -0.305054)
			(stroke
				(width 0.1)
				(type default)
			)
			(layer "F.Fab")
		)
		(fp_line
			(start -0.67945 -0.305054)
			(end -0.12065 -0.305054)
			(stroke
				(width 0.1)
				(type default)
			)
			(layer "F.Fab")
		)
		(pad "1" smd circle
			(at -0.40005 0 180)
			(size 0 0)
			(layers "F.Cu" "F.Mask" "F.Paste")
			(net "P3V3_AUX")
		)
		(pad "2" smd circle
			(at 0.40005 0 180)
			(size 0 0)
			(layers "F.Cu" "F.Mask" "F.Paste")
			(net "NIC4_PEX_PWR_EN_R")
		)
	)
	(footprint ""
		(layer "F.Cu")
		(at 242.838478 -215.05291 180)
		(property "Reference" "R474"
			(at 0 0 180)
			(layer "F.SilkS")
			(hide yes)
			(effects
				(font
					(size 1.27 1.27)
				)
			)
		)
		(property "Value" ""
			(at 0 0 180)
			(layer "F.Fab")
			(effects
				(font
					(size 1.27 1.27)
				)
			)
		)
		(duplicate_pad_numbers_are_jumpers no)
		(fp_line
			(start 0.7874 0.4064)
			(end -0.7874 0.4064)
			(stroke
				(width 0.1524)
				(type default)
			)
			(layer "F.SilkS")
		)
		(fp_line
			(start 0.7874 -0.4064)
			(end 0.7874 0.4064)
			(stroke
				(width 0.1524)
				(type default)
			)
			(layer "F.SilkS")
		)
		(fp_line
			(start -0.7874 0.4064)
			(end -0.7874 -0.4064)
			(stroke
				(width 0.1524)
				(type default)
			)
			(layer "F.SilkS")
		)
		(fp_line
			(start -0.7874 -0.4064)
			(end 0.7874 -0.4064)
			(stroke
				(width 0.1524)
				(type default)
			)
			(layer "F.SilkS")
		)
		(fp_line
			(start 0.67945 0.3048)
			(end 0.120396 0.3048)
			(stroke
				(width 0.1)
				(type default)
			)
			(layer "F.Fab")
		)
		(fp_line
			(start 0.67945 -0.3048)
			(end 0.67945 0.3048)
			(stroke
				(width 0.1)
				(type default)
			)
			(layer "F.Fab")
		)
		(fp_line
			(start 0.12065 -0.2794)
			(end 0.12065 -0.3048)
			(stroke
				(width 0.1)
				(type default)
			)
			(layer "F.Fab")
		)
		(fp_line
			(start 0.12065 -0.3048)
			(end 0.67945 -0.3048)
			(stroke
				(width 0.1)
				(type default)
			)
			(layer "F.Fab")
		)
		(fp_line
			(start 0.120396 0.3048)
			(end 0.120396 0.2794)
			(stroke
				(width 0.1)
				(type default)
			)
			(layer "F.Fab")
		)
		(fp_line
			(start 0.120396 0.2794)
			(end -0.12065 0.2794)
			(stroke
				(width 0.1)
				(type default)
			)
			(layer "F.Fab")
		)
		(fp_line
			(start -0.12065 0.3048)
			(end -0.67945 0.3048)
			(stroke
				(width 0.1)
				(type default)
			)
			(layer "F.Fab")
		)
		(fp_line
			(start -0.12065 0.2794)
			(end -0.12065 0.3048)
			(stroke
				(width 0.1)
				(type default)
			)
			(layer "F.Fab")
		)
		(fp_line
			(start -0.12065 -0.2794)
			(end 0.12065 -0.2794)
			(stroke
				(width 0.1)
				(type default)
			)
			(layer "F.Fab")
		)
		(fp_line
			(start -0.12065 -0.305054)
			(end -0.12065 -0.2794)
			(stroke
				(width 0.1)
				(type default)
			)
			(layer "F.Fab")
		)
		(fp_line
			(start -0.67945 0.3048)
			(end -0.67945 -0.305054)
			(stroke
				(width 0.1)
				(type default)
			)
			(layer "F.Fab")
		)
		(fp_line
			(start -0.67945 -0.305054)
			(end -0.12065 -0.305054)
			(stroke
				(width 0.1)
				(type default)
			)
			(layer "F.Fab")
		)
		(pad "1" smd circle
			(at -0.40005 0 180)
			(size 0 0)
			(layers "F.Cu" "F.Mask" "F.Paste")
			(net "P3V3_AUX")
		)
		(pad "2" smd circle
			(at 0.40005 0 180)
			(size 0 0)
			(layers "F.Cu" "F.Mask" "F.Paste")
			(net "P3V3_AUX_SCALED")
		)
	)
	(footprint ""
		(layer "F.Cu")
		(at 353.201986 -32.849312 90)
		(property "Reference" "R5702"
			(at 0 0 90)
			(layer "F.SilkS")
			(hide yes)
			(effects
				(font
					(size 1.27 1.27)
				)
			)
		)
		(property "Value" ""
			(at 0 0 90)
			(layer "F.Fab")
			(effects
				(font
					(size 1.27 1.27)
				)
			)
		)
		(duplicate_pad_numbers_are_jumpers no)
		(fp_line
			(start 0.7874 -0.4064)
			(end 0.7874 0.4064)
			(stroke
				(width 0.1524)
				(type default)
			)
			(layer "F.SilkS")
		)
		(fp_line
			(start -0.7874 -0.4064)
			(end 0.7874 -0.4064)
			(stroke
				(width 0.1524)
				(type default)
			)
			(layer "F.SilkS")
		)
		(fp_line
			(start 0.7874 0.4064)
			(end -0.7874 0.4064)
			(stroke
				(width 0.1524)
				(type default)
			)
			(layer "F.SilkS")
		)
		(fp_line
			(start -0.7874 0.4064)
			(end -0.7874 -0.4064)
			(stroke
				(width 0.1524)
				(type default)
			)
			(layer "F.SilkS")
		)
		(fp_line
			(start -0.12065 -0.305054)
			(end -0.12065 -0.2794)
			(stroke
				(width 0.1)
				(type default)
			)
			(layer "F.Fab")
		)
		(fp_line
			(start -0.67945 -0.305054)
			(end -0.12065 -0.305054)
			(stroke
				(width 0.1)
				(type default)
			)
			(layer "F.Fab")
		)
		(fp_line
			(start 0.67945 -0.3048)
			(end 0.67945 0.3048)
			(stroke
				(width 0.1)
				(type default)
			)
			(layer "F.Fab")
		)
		(fp_line
			(start 0.12065 -0.3048)
			(end 0.67945 -0.3048)
			(stroke
				(width 0.1)
				(type default)
			)
			(layer "F.Fab")
		)
		(fp_line
			(start 0.12065 -0.2794)
			(end 0.12065 -0.3048)
			(stroke
				(width 0.1)
				(type default)
			)
			(layer "F.Fab")
		)
		(fp_line
			(start -0.12065 -0.2794)
			(end 0.12065 -0.2794)
			(stroke
				(width 0.1)
				(type default)
			)
			(layer "F.Fab")
		)
		(fp_line
			(start 0.120396 0.2794)
			(end -0.12065 0.2794)
			(stroke
				(width 0.1)
				(type default)
			)
			(layer "F.Fab")
		)
		(fp_line
			(start -0.12065 0.2794)
			(end -0.12065 0.3048)
			(stroke
				(width 0.1)
				(type default)
			)
			(layer "F.Fab")
		)
		(fp_line
			(start 0.67945 0.3048)
			(end 0.120396 0.3048)
			(stroke
				(width 0.1)
				(type default)
			)
			(layer "F.Fab")
		)
		(fp_line
			(start 0.120396 0.3048)
			(end 0.120396 0.2794)
			(stroke
				(width 0.1)
				(type default)
			)
			(layer "F.Fab")
		)
		(fp_line
			(start -0.12065 0.3048)
			(end -0.67945 0.3048)
			(stroke
				(width 0.1)
				(type default)
			)
			(layer "F.Fab")
		)
		(fp_line
			(start -0.67945 0.3048)
			(end -0.67945 -0.305054)
			(stroke
				(width 0.1)
				(type default)
			)
			(layer "F.Fab")
		)
		(pad "1" smd circle
			(at -0.40005 0 90)
			(size 0 0)
			(layers "F.Cu" "F.Mask" "F.Paste")
			(net "RST_SMB_SSD12_ISO_R_N")
		)
		(pad "2" smd circle
			(at 0.40005 0 90)
			(size 0 0)
			(layers "F.Cu" "F.Mask" "F.Paste")
			(net "RST_SMB_SSD12_ISO_N")
		)
	)
	(footprint ""
		(layer "F.Cu")
		(at 450.650864 -374.4722 -90)
		(property "Reference" "R6687"
			(at 0 0 270)
			(layer "F.SilkS")
			(hide yes)
			(effects
				(font
					(size 1.27 1.27)
				)
			)
		)
		(property "Value" ""
			(at 0 0 270)
			(layer "F.Fab")
			(effects
				(font
					(size 1.27 1.27)
				)
			)
		)
		(duplicate_pad_numbers_are_jumpers no)
		(fp_line
			(start -0.7874 0.4064)
			(end -0.7874 -0.4064)
			(stroke
				(width 0.1524)
				(type default)
			)
			(layer "F.SilkS")
		)
		(fp_line
			(start 0.7874 0.4064)
			(end -0.7874 0.4064)
			(stroke
				(width 0.1524)
				(type default)
			)
			(layer "F.SilkS")
		)
		(fp_line
			(start -0.7874 -0.4064)
			(end 0.7874 -0.4064)
			(stroke
				(width 0.1524)
				(type default)
			)
			(layer "F.SilkS")
		)
		(fp_line
			(start 0.7874 -0.4064)
			(end 0.7874 0.4064)
			(stroke
				(width 0.1524)
				(type default)
			)
			(layer "F.SilkS")
		)
		(fp_line
			(start -0.67945 0.3048)
			(end -0.67945 -0.305054)
			(stroke
				(width 0.1)
				(type default)
			)
			(layer "F.Fab")
		)
		(fp_line
			(start -0.12065 0.3048)
			(end -0.67945 0.3048)
			(stroke
				(width 0.1)
				(type default)
			)
			(layer "F.Fab")
		)
		(fp_line
			(start 0.120396 0.3048)
			(end 0.120396 0.2794)
			(stroke
				(width 0.1)
				(type default)
			)
			(layer "F.Fab")
		)
		(fp_line
			(start 0.67945 0.3048)
			(end 0.120396 0.3048)
			(stroke
				(width 0.1)
				(type default)
			)
			(layer "F.Fab")
		)
		(fp_line
			(start -0.12065 0.2794)
			(end -0.12065 0.3048)
			(stroke
				(width 0.1)
				(type default)
			)
			(layer "F.Fab")
		)
		(fp_line
			(start 0.120396 0.2794)
			(end -0.12065 0.2794)
			(stroke
				(width 0.1)
				(type default)
			)
			(layer "F.Fab")
		)
		(fp_line
			(start -0.12065 -0.2794)
			(end 0.12065 -0.2794)
			(stroke
				(width 0.1)
				(type default)
			)
			(layer "F.Fab")
		)
		(fp_line
			(start 0.12065 -0.2794)
			(end 0.12065 -0.3048)
			(stroke
				(width 0.1)
				(type default)
			)
			(layer "F.Fab")
		)
		(fp_line
			(start 0.12065 -0.3048)
			(end 0.67945 -0.3048)
			(stroke
				(width 0.1)
				(type default)
			)
			(layer "F.Fab")
		)
		(fp_line
			(start 0.67945 -0.3048)
			(end 0.67945 0.3048)
			(stroke
				(width 0.1)
				(type default)
			)
			(layer "F.Fab")
		)
		(fp_line
			(start -0.67945 -0.305054)
			(end -0.12065 -0.305054)
			(stroke
				(width 0.1)
				(type default)
			)
			(layer "F.Fab")
		)
		(fp_line
			(start -0.12065 -0.305054)
			(end -0.12065 -0.2794)
			(stroke
				(width 0.1)
				(type default)
			)
			(layer "F.Fab")
		)
		(pad "1" smd circle
			(at -0.40005 0 270)
			(size 0 0)
			(layers "F.Cu" "F.Mask" "F.Paste")
			(net "GPU_3V3IO_RSVD3")
		)
		(pad "2" smd circle
			(at 0.40005 0 270)
			(size 0 0)
			(layers "F.Cu" "F.Mask" "F.Paste")
			(net "GND")
		)
	)
	(footprint ""
		(layer "F.Cu")
		(at 336.443574 -48.93691 180)
		(property "Reference" "R633"
			(at 0 0 180)
			(layer "F.SilkS")
			(hide yes)
			(effects
				(font
					(size 1.27 1.27)
				)
			)
		)
		(property "Value" ""
			(at 0 0 180)
			(layer "F.Fab")
			(effects
				(font
					(size 1.27 1.27)
				)
			)
		)
		(duplicate_pad_numbers_are_jumpers no)
		(fp_line
			(start 0.7874 0.4064)
			(end -0.7874 0.4064)
			(stroke
				(width 0.1524)
				(type default)
			)
			(layer "F.SilkS")
		)
		(fp_line
			(start 0.7874 -0.4064)
			(end 0.7874 0.4064)
			(stroke
				(width 0.1524)
				(type default)
			)
			(layer "F.SilkS")
		)
		(fp_line
			(start -0.7874 0.4064)
			(end -0.7874 -0.4064)
			(stroke
				(width 0.1524)
				(type default)
			)
			(layer "F.SilkS")
		)
		(fp_line
			(start -0.7874 -0.4064)
			(end 0.7874 -0.4064)
			(stroke
				(width 0.1524)
				(type default)
			)
			(layer "F.SilkS")
		)
		(fp_line
			(start 0.67945 0.3048)
			(end 0.120396 0.3048)
			(stroke
				(width 0.1)
				(type default)
			)
			(layer "F.Fab")
		)
		(fp_line
			(start 0.67945 -0.3048)
			(end 0.67945 0.3048)
			(stroke
				(width 0.1)
				(type default)
			)
			(layer "F.Fab")
		)
		(fp_line
			(start 0.12065 -0.2794)
			(end 0.12065 -0.3048)
			(stroke
				(width 0.1)
				(type default)
			)
			(layer "F.Fab")
		)
		(fp_line
			(start 0.12065 -0.3048)
			(end 0.67945 -0.3048)
			(stroke
				(width 0.1)
				(type default)
			)
			(layer "F.Fab")
		)
		(fp_line
			(start 0.120396 0.3048)
			(end 0.120396 0.2794)
			(stroke
				(width 0.1)
				(type default)
			)
			(layer "F.Fab")
		)
		(fp_line
			(start 0.120396 0.2794)
			(end -0.12065 0.2794)
			(stroke
				(width 0.1)
				(type default)
			)
			(layer "F.Fab")
		)
		(fp_line
			(start -0.12065 0.3048)
			(end -0.67945 0.3048)
			(stroke
				(width 0.1)
				(type default)
			)
			(layer "F.Fab")
		)
		(fp_line
			(start -0.12065 0.2794)
			(end -0.12065 0.3048)
			(stroke
				(width 0.1)
				(type default)
			)
			(layer "F.Fab")
		)
		(fp_line
			(start -0.12065 -0.2794)
			(end 0.12065 -0.2794)
			(stroke
				(width 0.1)
				(type default)
			)
			(layer "F.Fab")
		)
		(fp_line
			(start -0.12065 -0.305054)
			(end -0.12065 -0.2794)
			(stroke
				(width 0.1)
				(type default)
			)
			(layer "F.Fab")
		)
		(fp_line
			(start -0.67945 0.3048)
			(end -0.67945 -0.305054)
			(stroke
				(width 0.1)
				(type default)
			)
			(layer "F.Fab")
		)
		(fp_line
			(start -0.67945 -0.305054)
			(end -0.12065 -0.305054)
			(stroke
				(width 0.1)
				(type default)
			)
			(layer "F.Fab")
		)
		(pad "1" smd circle
			(at -0.40005 0 180)
			(size 0 0)
			(layers "F.Cu" "F.Mask" "F.Paste")
			(net "SMB_BIC_I2C6_MUX_SSD_8_15_ADC_R_SDA")
		)
		(pad "2" smd circle
			(at 0.40005 0 180)
			(size 0 0)
			(layers "F.Cu" "F.Mask" "F.Paste")
			(net "SMB_SSD11_ADC_SDA")
		)
	)
	(footprint ""
		(layer "F.Cu")
		(at 444.799466 -112.903508 90)
		(property "Reference" "PC826"
			(at 0 0 90)
			(layer "F.SilkS")
			(hide yes)
			(effects
				(font
					(size 1.27 1.27)
				)
			)
		)
		(property "Value" ""
			(at 0 0 90)
			(layer "F.Fab")
			(effects
				(font
					(size 1.27 1.27)
				)
			)
		)
		(duplicate_pad_numbers_are_jumpers no)
		(fp_line
			(start 1.524 -0.762)
			(end 1.524 0.762)
			(stroke
				(width 0.1524)
				(type default)
			)
			(layer "F.SilkS")
		)
		(fp_line
			(start -1.524 -0.762)
			(end 1.524 -0.762)
			(stroke
				(width 0.1524)
				(type default)
			)
			(layer "F.SilkS")
		)
		(fp_line
			(start 1.524 0.762)
			(end -1.524 0.762)
			(stroke
				(width 0.1524)
				(type default)
			)
			(layer "F.SilkS")
		)
		(fp_line
			(start -1.524 0.762)
			(end -1.524 -0.762)
			(stroke
				(width 0.1524)
				(type default)
			)
			(layer "F.SilkS")
		)
		(fp_line
			(start 1.1049 -0.724916)
			(end -1.1049 -0.724916)
			(stroke
				(width 0.1)
				(type default)
			)
			(layer "F.Fab")
		)
		(fp_line
			(start -1.1049 -0.724916)
			(end -1.1049 0.724916)
			(stroke
				(width 0.1)
				(type default)
			)
			(layer "F.Fab")
		)
		(fp_line
			(start 1.1049 0.724916)
			(end 1.1049 -0.724916)
			(stroke
				(width 0.1)
				(type default)
			)
			(layer "F.Fab")
		)
		(fp_line
			(start -1.1049 0.724916)
			(end 1.1049 0.724916)
			(stroke
				(width 0.1)
				(type default)
			)
			(layer "F.Fab")
		)
		(pad "1" smd rect
			(at -0.889 0 270)
			(size 1.016 1.27)
			(layers "F.Cu" "F.Mask" "F.Paste")
			(net "P12V_NIC7_R")
		)
		(pad "2" smd rect
			(at 0.889 0 270)
			(size 1.016 1.27)
			(layers "F.Cu" "F.Mask" "F.Paste")
			(net "GND")
		)
	)
	(footprint ""
		(layer "F.Cu")
		(at 132.026406 -121.408952 180)
		(property "Reference" "PC463"
			(at 0 0 180)
			(layer "F.SilkS")
			(hide yes)
			(effects
				(font
					(size 1.27 1.27)
				)
			)
		)
		(property "Value" ""
			(at 0 0 180)
			(layer "F.Fab")
			(effects
				(font
					(size 1.27 1.27)
				)
			)
		)
		(duplicate_pad_numbers_are_jumpers no)
		(fp_line
			(start 1.524 0.762)
			(end -1.524 0.762)
			(stroke
				(width 0.1524)
				(type default)
			)
			(layer "F.SilkS")
		)
		(fp_line
			(start 1.524 -0.762)
			(end 1.524 0.762)
			(stroke
				(width 0.1524)
				(type default)
			)
			(layer "F.SilkS")
		)
		(fp_line
			(start -1.524 0.762)
			(end -1.524 -0.762)
			(stroke
				(width 0.1524)
				(type default)
			)
			(layer "F.SilkS")
		)
		(fp_line
			(start -1.524 -0.762)
			(end 1.524 -0.762)
			(stroke
				(width 0.1524)
				(type default)
			)
			(layer "F.SilkS")
		)
		(fp_line
			(start 1.1049 0.724916)
			(end 1.1049 -0.724916)
			(stroke
				(width 0.1)
				(type default)
			)
			(layer "F.Fab")
		)
		(fp_line
			(start 1.1049 -0.724916)
			(end -1.1049 -0.724916)
			(stroke
				(width 0.1)
				(type default)
			)
			(layer "F.Fab")
		)
		(fp_line
			(start -1.1049 0.724916)
			(end 1.1049 0.724916)
			(stroke
				(width 0.1)
				(type default)
			)
			(layer "F.Fab")
		)
		(fp_line
			(start -1.1049 -0.724916)
			(end -1.1049 0.724916)
			(stroke
				(width 0.1)
				(type default)
			)
			(layer "F.Fab")
		)
		(pad "1" smd rect
			(at -0.889 0)
			(size 1.016 1.27)
			(layers "F.Cu" "F.Mask" "F.Paste")
			(net "GND")
		)
		(pad "2" smd rect
			(at 0.889 0)
			(size 1.016 1.27)
			(layers "F.Cu" "F.Mask" "F.Paste")
			(net "P3V3_AUX")
		)
	)
	(footprint ""
		(layer "F.Cu")
		(at 226.752912 -200.984104 -90)
		(property "Reference" "R465"
			(at 0 0 270)
			(layer "F.SilkS")
			(hide yes)
			(effects
				(font
					(size 1.27 1.27)
				)
			)
		)
		(property "Value" ""
			(at 0 0 270)
			(layer "F.Fab")
			(effects
				(font
					(size 1.27 1.27)
				)
			)
		)
		(duplicate_pad_numbers_are_jumpers no)
		(fp_line
			(start -0.7874 0.4064)
			(end -0.7874 -0.4064)
			(stroke
				(width 0.1524)
				(type default)
			)
			(layer "F.SilkS")
		)
		(fp_line
			(start 0.7874 0.4064)
			(end -0.7874 0.4064)
			(stroke
				(width 0.1524)
				(type default)
			)
			(layer "F.SilkS")
		)
		(fp_line
			(start -0.7874 -0.4064)
			(end 0.7874 -0.4064)
			(stroke
				(width 0.1524)
				(type default)
			)
			(layer "F.SilkS")
		)
		(fp_line
			(start 0.7874 -0.4064)
			(end 0.7874 0.4064)
			(stroke
				(width 0.1524)
				(type default)
			)
			(layer "F.SilkS")
		)
		(fp_line
			(start -0.67945 0.3048)
			(end -0.67945 -0.305054)
			(stroke
				(width 0.1)
				(type default)
			)
			(layer "F.Fab")
		)
		(fp_line
			(start -0.12065 0.3048)
			(end -0.67945 0.3048)
			(stroke
				(width 0.1)
				(type default)
			)
			(layer "F.Fab")
		)
		(fp_line
			(start 0.120396 0.3048)
			(end 0.120396 0.2794)
			(stroke
				(width 0.1)
				(type default)
			)
			(layer "F.Fab")
		)
		(fp_line
			(start 0.67945 0.3048)
			(end 0.120396 0.3048)
			(stroke
				(width 0.1)
				(type default)
			)
			(layer "F.Fab")
		)
		(fp_line
			(start -0.12065 0.2794)
			(end -0.12065 0.3048)
			(stroke
				(width 0.1)
				(type default)
			)
			(layer "F.Fab")
		)
		(fp_line
			(start 0.120396 0.2794)
			(end -0.12065 0.2794)
			(stroke
				(width 0.1)
				(type default)
			)
			(layer "F.Fab")
		)
		(fp_line
			(start -0.12065 -0.2794)
			(end 0.12065 -0.2794)
			(stroke
				(width 0.1)
				(type default)
			)
			(layer "F.Fab")
		)
		(fp_line
			(start 0.12065 -0.2794)
			(end 0.12065 -0.3048)
			(stroke
				(width 0.1)
				(type default)
			)
			(layer "F.Fab")
		)
		(fp_line
			(start 0.12065 -0.3048)
			(end 0.67945 -0.3048)
			(stroke
				(width 0.1)
				(type default)
			)
			(layer "F.Fab")
		)
		(fp_line
			(start 0.67945 -0.3048)
			(end 0.67945 0.3048)
			(stroke
				(width 0.1)
				(type default)
			)
			(layer "F.Fab")
		)
		(fp_line
			(start -0.67945 -0.305054)
			(end -0.12065 -0.305054)
			(stroke
				(width 0.1)
				(type default)
			)
			(layer "F.Fab")
		)
		(fp_line
			(start -0.12065 -0.305054)
			(end -0.12065 -0.2794)
			(stroke
				(width 0.1)
				(type default)
			)
			(layer "F.Fab")
		)
		(pad "1" smd circle
			(at -0.40005 0 270)
			(size 0 0)
			(layers "F.Cu" "F.Mask" "F.Paste")
			(net "SPI_BIC1_CS0_R_N")
		)
		(pad "2" smd circle
			(at 0.40005 0 270)
			(size 0 0)
			(layers "F.Cu" "F.Mask" "F.Paste")
			(net "SPI_BIC1_CS0_R1_N")
		)
	)
	(footprint ""
		(layer "F.Cu")
		(at 89.327482 -350.098614 90)
		(property "Reference" "C155"
			(at 0 0 90)
			(layer "F.SilkS")
			(hide yes)
			(effects
				(font
					(size 1.27 1.27)
				)
			)
		)
		(property "Value" ""
			(at 0 0 90)
			(layer "F.Fab")
			(effects
				(font
					(size 1.27 1.27)
				)
			)
		)
		(duplicate_pad_numbers_are_jumpers no)
		(fp_line
			(start 0.299974 -0.150114)
			(end 0.299974 0.150114)
			(stroke
				(width 0.1)
				(type default)
			)
			(layer "F.Fab")
		)
		(fp_line
			(start -0.299974 -0.150114)
			(end 0.299974 -0.150114)
			(stroke
				(width 0.1)
				(type default)
			)
			(layer "F.Fab")
		)
		(fp_line
			(start 0.299974 0.150114)
			(end -0.299974 0.150114)
			(stroke
				(width 0.1)
				(type default)
			)
			(layer "F.Fab")
		)
		(fp_line
			(start -0.299974 0.150114)
			(end -0.299974 -0.150114)
			(stroke
				(width 0.1)
				(type default)
			)
			(layer "F.Fab")
		)
		(pad "1" smd rect
			(at -0.2667 0 90)
			(size 0.3048 0.381)
			(layers "F.Cu" "F.Mask" "F.Paste")
			(net "P5E_PEX0_STN6_TX_DP<98>")
		)
		(pad "2" smd rect
			(at 0.2667 0 90)
			(size 0.3048 0.381)
			(layers "F.Cu" "F.Mask" "F.Paste")
			(net "P5E_PEX0_STN6_TX_C_DP<98>")
		)
	)
	(footprint ""
		(layer "F.Cu")
		(at 262.564626 -238.968788 90)
		(property "Reference" "R6579"
			(at 0 0 90)
			(layer "F.SilkS")
			(hide yes)
			(effects
				(font
					(size 1.27 1.27)
				)
			)
		)
		(property "Value" ""
			(at 0 0 90)
			(layer "F.Fab")
			(effects
				(font
					(size 1.27 1.27)
				)
			)
		)
		(duplicate_pad_numbers_are_jumpers no)
		(fp_line
			(start 0.7874 -0.4064)
			(end 0.7874 0.4064)
			(stroke
				(width 0.1524)
				(type default)
			)
			(layer "F.SilkS")
		)
		(fp_line
			(start -0.7874 -0.4064)
			(end 0.7874 -0.4064)
			(stroke
				(width 0.1524)
				(type default)
			)
			(layer "F.SilkS")
		)
		(fp_line
			(start 0.7874 0.4064)
			(end -0.7874 0.4064)
			(stroke
				(width 0.1524)
				(type default)
			)
			(layer "F.SilkS")
		)
		(fp_line
			(start -0.7874 0.4064)
			(end -0.7874 -0.4064)
			(stroke
				(width 0.1524)
				(type default)
			)
			(layer "F.SilkS")
		)
		(fp_line
			(start -0.12065 -0.305054)
			(end -0.12065 -0.2794)
			(stroke
				(width 0.1)
				(type default)
			)
			(layer "F.Fab")
		)
		(fp_line
			(start -0.67945 -0.305054)
			(end -0.12065 -0.305054)
			(stroke
				(width 0.1)
				(type default)
			)
			(layer "F.Fab")
		)
		(fp_line
			(start 0.67945 -0.3048)
			(end 0.67945 0.3048)
			(stroke
				(width 0.1)
				(type default)
			)
			(layer "F.Fab")
		)
		(fp_line
			(start 0.12065 -0.3048)
			(end 0.67945 -0.3048)
			(stroke
				(width 0.1)
				(type default)
			)
			(layer "F.Fab")
		)
		(fp_line
			(start 0.12065 -0.2794)
			(end 0.12065 -0.3048)
			(stroke
				(width 0.1)
				(type default)
			)
			(layer "F.Fab")
		)
		(fp_line
			(start -0.12065 -0.2794)
			(end 0.12065 -0.2794)
			(stroke
				(width 0.1)
				(type default)
			)
			(layer "F.Fab")
		)
		(fp_line
			(start 0.120396 0.2794)
			(end -0.12065 0.2794)
			(stroke
				(width 0.1)
				(type default)
			)
			(layer "F.Fab")
		)
		(fp_line
			(start -0.12065 0.2794)
			(end -0.12065 0.3048)
			(stroke
				(width 0.1)
				(type default)
			)
			(layer "F.Fab")
		)
		(fp_line
			(start 0.67945 0.3048)
			(end 0.120396 0.3048)
			(stroke
				(width 0.1)
				(type default)
			)
			(layer "F.Fab")
		)
		(fp_line
			(start 0.120396 0.3048)
			(end 0.120396 0.2794)
			(stroke
				(width 0.1)
				(type default)
			)
			(layer "F.Fab")
		)
		(fp_line
			(start -0.12065 0.3048)
			(end -0.67945 0.3048)
			(stroke
				(width 0.1)
				(type default)
			)
			(layer "F.Fab")
		)
		(fp_line
			(start -0.67945 0.3048)
			(end -0.67945 -0.305054)
			(stroke
				(width 0.1)
				(type default)
			)
			(layer "F.Fab")
		)
		(pad "1" smd circle
			(at -0.40005 0 90)
			(size 0 0)
			(layers "F.Cu" "F.Mask" "F.Paste")
			(net "P1V8_PLL0_PEX2")
		)
		(pad "2" smd circle
			(at 0.40005 0 90)
			(size 0 0)
			(layers "F.Cu" "F.Mask" "F.Paste")
			(net "P1V8_PLL_PEX2_ADJ")
		)
	)
	(footprint ""
		(layer "F.Cu")
		(at 481.221288 -553.346874 180)
		(property "Reference" "SCREW_SSD12_2"
			(at -5.6007 -1.402334 0)
			(unlocked yes)
			(layer "B.SilkS")
			(effects
				(font
					(size 0.7874 0.5842)
					(thickness 0.1524)
				)
				(justify mirror)
			)
		)
		(property "Value" ""
			(at 0 0 180)
			(layer "F.Fab")
			(effects
				(font
					(size 1.27 1.27)
				)
			)
		)
		(duplicate_pad_numbers_are_jumpers no)
		(pad "1" thru_hole circle
			(at 0 0 180)
			(size 0.4572 0.4572)
			(drill 0.2032)
			(layers "*.Cu" "*.Mask")
			(remove_unused_layers no)
			(net "Net_9149")
			(clearance 0.127)
			(thermal_gap 0.127)
			(padstack
				(mode front_inner_back)
				(layer "Inner"
					(shape circle)
					(size 0.4572 0.4572)
					(clearance 0.127)
				)
				(layer "B.Cu"
					(shape circle)
					(size 0.508 0.508)
					(clearance 0.1016)
				)
			)
		)
	)
	(footprint ""
		(layer "F.Cu")
		(at 439.33364 -304.036476 90)
		(property "Reference" "R1453"
			(at 0 0 90)
			(layer "F.SilkS")
			(hide yes)
			(effects
				(font
					(size 1.27 1.27)
				)
			)
		)
		(property "Value" ""
			(at 0 0 90)
			(layer "F.Fab")
			(effects
				(font
					(size 1.27 1.27)
				)
			)
		)
		(duplicate_pad_numbers_are_jumpers no)
		(fp_line
			(start 0.7874 -0.4064)
			(end 0.7874 0.4064)
			(stroke
				(width 0.1524)
				(type default)
			)
			(layer "F.SilkS")
		)
		(fp_line
			(start -0.7874 -0.4064)
			(end 0.7874 -0.4064)
			(stroke
				(width 0.1524)
				(type default)
			)
			(layer "F.SilkS")
		)
		(fp_line
			(start 0.7874 0.4064)
			(end -0.7874 0.4064)
			(stroke
				(width 0.1524)
				(type default)
			)
			(layer "F.SilkS")
		)
		(fp_line
			(start -0.7874 0.4064)
			(end -0.7874 -0.4064)
			(stroke
				(width 0.1524)
				(type default)
			)
			(layer "F.SilkS")
		)
		(fp_line
			(start -0.12065 -0.305054)
			(end -0.12065 -0.2794)
			(stroke
				(width 0.1)
				(type default)
			)
			(layer "F.Fab")
		)
		(fp_line
			(start -0.67945 -0.305054)
			(end -0.12065 -0.305054)
			(stroke
				(width 0.1)
				(type default)
			)
			(layer "F.Fab")
		)
		(fp_line
			(start 0.67945 -0.3048)
			(end 0.67945 0.3048)
			(stroke
				(width 0.1)
				(type default)
			)
			(layer "F.Fab")
		)
		(fp_line
			(start 0.12065 -0.3048)
			(end 0.67945 -0.3048)
			(stroke
				(width 0.1)
				(type default)
			)
			(layer "F.Fab")
		)
		(fp_line
			(start 0.12065 -0.2794)
			(end 0.12065 -0.3048)
			(stroke
				(width 0.1)
				(type default)
			)
			(layer "F.Fab")
		)
		(fp_line
			(start -0.12065 -0.2794)
			(end 0.12065 -0.2794)
			(stroke
				(width 0.1)
				(type default)
			)
			(layer "F.Fab")
		)
		(fp_line
			(start 0.120396 0.2794)
			(end -0.12065 0.2794)
			(stroke
				(width 0.1)
				(type default)
			)
			(layer "F.Fab")
		)
		(fp_line
			(start -0.12065 0.2794)
			(end -0.12065 0.3048)
			(stroke
				(width 0.1)
				(type default)
			)
			(layer "F.Fab")
		)
		(fp_line
			(start 0.67945 0.3048)
			(end 0.120396 0.3048)
			(stroke
				(width 0.1)
				(type default)
			)
			(layer "F.Fab")
		)
		(fp_line
			(start 0.120396 0.3048)
			(end 0.120396 0.2794)
			(stroke
				(width 0.1)
				(type default)
			)
			(layer "F.Fab")
		)
		(fp_line
			(start -0.12065 0.3048)
			(end -0.67945 0.3048)
			(stroke
				(width 0.1)
				(type default)
			)
			(layer "F.Fab")
		)
		(fp_line
			(start -0.67945 0.3048)
			(end -0.67945 -0.305054)
			(stroke
				(width 0.1)
				(type default)
			)
			(layer "F.Fab")
		)
		(pad "1" smd circle
			(at -0.40005 0 90)
			(size 0 0)
			(layers "F.Cu" "F.Mask" "F.Paste")
			(net "GND")
		)
		(pad "2" smd circle
			(at 0.40005 0 90)
			(size 0 0)
			(layers "F.Cu" "F.Mask" "F.Paste")
			(net "PEX3_SPARE1")
		)
	)
	(footprint ""
		(layer "F.Cu")
		(at 164.127942 -35.876738)
		(property "Reference" "R6070"
			(at 0 0 0)
			(layer "F.SilkS")
			(hide yes)
			(effects
				(font
					(size 1.27 1.27)
				)
			)
		)
		(property "Value" ""
			(at 0 0 0)
			(layer "F.Fab")
			(effects
				(font
					(size 1.27 1.27)
				)
			)
		)
		(duplicate_pad_numbers_are_jumpers no)
		(fp_line
			(start -0.7874 -0.4064)
			(end 0.7874 -0.4064)
			(stroke
				(width 0.1524)
				(type default)
			)
			(layer "F.SilkS")
		)
		(fp_line
			(start -0.7874 0.4064)
			(end -0.7874 -0.4064)
			(stroke
				(width 0.1524)
				(type default)
			)
			(layer "F.SilkS")
		)
		(fp_line
			(start 0.7874 -0.4064)
			(end 0.7874 0.4064)
			(stroke
				(width 0.1524)
				(type default)
			)
			(layer "F.SilkS")
		)
		(fp_line
			(start 0.7874 0.4064)
			(end -0.7874 0.4064)
			(stroke
				(width 0.1524)
				(type default)
			)
			(layer "F.SilkS")
		)
		(fp_line
			(start -0.67945 -0.305054)
			(end -0.12065 -0.305054)
			(stroke
				(width 0.1)
				(type default)
			)
			(layer "F.Fab")
		)
		(fp_line
			(start -0.67945 0.3048)
			(end -0.67945 -0.305054)
			(stroke
				(width 0.1)
				(type default)
			)
			(layer "F.Fab")
		)
		(fp_line
			(start -0.12065 -0.305054)
			(end -0.12065 -0.2794)
			(stroke
				(width 0.1)
				(type default)
			)
			(layer "F.Fab")
		)
		(fp_line
			(start -0.12065 -0.2794)
			(end 0.12065 -0.2794)
			(stroke
				(width 0.1)
				(type default)
			)
			(layer "F.Fab")
		)
		(fp_line
			(start -0.12065 0.2794)
			(end -0.12065 0.3048)
			(stroke
				(width 0.1)
				(type default)
			)
			(layer "F.Fab")
		)
		(fp_line
			(start -0.12065 0.3048)
			(end -0.67945 0.3048)
			(stroke
				(width 0.1)
				(type default)
			)
			(layer "F.Fab")
		)
		(fp_line
			(start 0.120396 0.2794)
			(end -0.12065 0.2794)
			(stroke
				(width 0.1)
				(type default)
			)
			(layer "F.Fab")
		)
		(fp_line
			(start 0.120396 0.3048)
			(end 0.120396 0.2794)
			(stroke
				(width 0.1)
				(type default)
			)
			(layer "F.Fab")
		)
		(fp_line
			(start 0.12065 -0.3048)
			(end 0.67945 -0.3048)
			(stroke
				(width 0.1)
				(type default)
			)
			(layer "F.Fab")
		)
		(fp_line
			(start 0.12065 -0.2794)
			(end 0.12065 -0.3048)
			(stroke
				(width 0.1)
				(type default)
			)
			(layer "F.Fab")
		)
		(fp_line
			(start 0.67945 -0.3048)
			(end 0.67945 0.3048)
			(stroke
				(width 0.1)
				(type default)
			)
			(layer "F.Fab")
		)
		(fp_line
			(start 0.67945 0.3048)
			(end 0.120396 0.3048)
			(stroke
				(width 0.1)
				(type default)
			)
			(layer "F.Fab")
		)
		(pad "1" smd circle
			(at -0.40005 0)
			(size 0 0)
			(layers "F.Cu" "F.Mask" "F.Paste")
			(net "PWRGD_P3V3_SSD6_D")
		)
		(pad "2" smd circle
			(at 0.40005 0)
			(size 0 0)
			(layers "F.Cu" "F.Mask" "F.Paste")
			(net "PWRGD_P3V3_SSD6_R")
		)
	)
	(footprint ""
		(layer "F.Cu")
		(at 379.633988 -5.852922)
		(property "Reference" "R5816"
			(at 0 0 0)
			(layer "F.SilkS")
			(hide yes)
			(effects
				(font
					(size 1.27 1.27)
				)
			)
		)
		(property "Value" ""
			(at 0 0 0)
			(layer "F.Fab")
			(effects
				(font
					(size 1.27 1.27)
				)
			)
		)
		(duplicate_pad_numbers_are_jumpers no)
		(fp_line
			(start -0.7874 -0.4064)
			(end 0.7874 -0.4064)
			(stroke
				(width 0.1524)
				(type default)
			)
			(layer "F.SilkS")
		)
		(fp_line
			(start -0.7874 0.4064)
			(end -0.7874 -0.4064)
			(stroke
				(width 0.1524)
				(type default)
			)
			(layer "F.SilkS")
		)
		(fp_line
			(start 0.7874 -0.4064)
			(end 0.7874 0.4064)
			(stroke
				(width 0.1524)
				(type default)
			)
			(layer "F.SilkS")
		)
		(fp_line
			(start 0.7874 0.4064)
			(end -0.7874 0.4064)
			(stroke
				(width 0.1524)
				(type default)
			)
			(layer "F.SilkS")
		)
		(fp_line
			(start -0.67945 -0.305054)
			(end -0.12065 -0.305054)
			(stroke
				(width 0.1)
				(type default)
			)
			(layer "F.Fab")
		)
		(fp_line
			(start -0.67945 0.3048)
			(end -0.67945 -0.305054)
			(stroke
				(width 0.1)
				(type default)
			)
			(layer "F.Fab")
		)
		(fp_line
			(start -0.12065 -0.305054)
			(end -0.12065 -0.2794)
			(stroke
				(width 0.1)
				(type default)
			)
			(layer "F.Fab")
		)
		(fp_line
			(start -0.12065 -0.2794)
			(end 0.12065 -0.2794)
			(stroke
				(width 0.1)
				(type default)
			)
			(layer "F.Fab")
		)
		(fp_line
			(start -0.12065 0.2794)
			(end -0.12065 0.3048)
			(stroke
				(width 0.1)
				(type default)
			)
			(layer "F.Fab")
		)
		(fp_line
			(start -0.12065 0.3048)
			(end -0.67945 0.3048)
			(stroke
				(width 0.1)
				(type default)
			)
			(layer "F.Fab")
		)
		(fp_line
			(start 0.120396 0.2794)
			(end -0.12065 0.2794)
			(stroke
				(width 0.1)
				(type default)
			)
			(layer "F.Fab")
		)
		(fp_line
			(start 0.120396 0.3048)
			(end 0.120396 0.2794)
			(stroke
				(width 0.1)
				(type default)
			)
			(layer "F.Fab")
		)
		(fp_line
			(start 0.12065 -0.3048)
			(end 0.67945 -0.3048)
			(stroke
				(width 0.1)
				(type default)
			)
			(layer "F.Fab")
		)
		(fp_line
			(start 0.12065 -0.2794)
			(end 0.12065 -0.3048)
			(stroke
				(width 0.1)
				(type default)
			)
			(layer "F.Fab")
		)
		(fp_line
			(start 0.67945 -0.3048)
			(end 0.67945 0.3048)
			(stroke
				(width 0.1)
				(type default)
			)
			(layer "F.Fab")
		)
		(fp_line
			(start 0.67945 0.3048)
			(end 0.120396 0.3048)
			(stroke
				(width 0.1)
				(type default)
			)
			(layer "F.Fab")
		)
		(pad "1" smd circle
			(at -0.40005 0)
			(size 0 0)
			(layers "F.Cu" "F.Mask" "F.Paste")
			(net "LM75_3_A1")
		)
		(pad "2" smd circle
			(at 0.40005 0)
			(size 0 0)
			(layers "F.Cu" "F.Mask" "F.Paste")
			(net "P3V3_AUX")
		)
	)
	(footprint ""
		(layer "F.Cu")
		(at 325.26605 -306.074572 90)
		(property "Reference" "R4181"
			(at 0 0 90)
			(layer "F.SilkS")
			(hide yes)
			(effects
				(font
					(size 1.27 1.27)
				)
			)
		)
		(property "Value" ""
			(at 0 0 90)
			(layer "F.Fab")
			(effects
				(font
					(size 1.27 1.27)
				)
			)
		)
		(duplicate_pad_numbers_are_jumpers no)
		(fp_line
			(start 0.7874 -0.4064)
			(end 0.7874 0.4064)
			(stroke
				(width 0.1524)
				(type default)
			)
			(layer "F.SilkS")
		)
		(fp_line
			(start -0.7874 -0.4064)
			(end 0.7874 -0.4064)
			(stroke
				(width 0.1524)
				(type default)
			)
			(layer "F.SilkS")
		)
		(fp_line
			(start 0.7874 0.4064)
			(end -0.7874 0.4064)
			(stroke
				(width 0.1524)
				(type default)
			)
			(layer "F.SilkS")
		)
		(fp_line
			(start -0.7874 0.4064)
			(end -0.7874 -0.4064)
			(stroke
				(width 0.1524)
				(type default)
			)
			(layer "F.SilkS")
		)
		(fp_line
			(start -0.12065 -0.305054)
			(end -0.12065 -0.2794)
			(stroke
				(width 0.1)
				(type default)
			)
			(layer "F.Fab")
		)
		(fp_line
			(start -0.67945 -0.305054)
			(end -0.12065 -0.305054)
			(stroke
				(width 0.1)
				(type default)
			)
			(layer "F.Fab")
		)
		(fp_line
			(start 0.67945 -0.3048)
			(end 0.67945 0.3048)
			(stroke
				(width 0.1)
				(type default)
			)
			(layer "F.Fab")
		)
		(fp_line
			(start 0.12065 -0.3048)
			(end 0.67945 -0.3048)
			(stroke
				(width 0.1)
				(type default)
			)
			(layer "F.Fab")
		)
		(fp_line
			(start 0.12065 -0.2794)
			(end 0.12065 -0.3048)
			(stroke
				(width 0.1)
				(type default)
			)
			(layer "F.Fab")
		)
		(fp_line
			(start -0.12065 -0.2794)
			(end 0.12065 -0.2794)
			(stroke
				(width 0.1)
				(type default)
			)
			(layer "F.Fab")
		)
		(fp_line
			(start 0.120396 0.2794)
			(end -0.12065 0.2794)
			(stroke
				(width 0.1)
				(type default)
			)
			(layer "F.Fab")
		)
		(fp_line
			(start -0.12065 0.2794)
			(end -0.12065 0.3048)
			(stroke
				(width 0.1)
				(type default)
			)
			(layer "F.Fab")
		)
		(fp_line
			(start 0.67945 0.3048)
			(end 0.120396 0.3048)
			(stroke
				(width 0.1)
				(type default)
			)
			(layer "F.Fab")
		)
		(fp_line
			(start 0.120396 0.3048)
			(end 0.120396 0.2794)
			(stroke
				(width 0.1)
				(type default)
			)
			(layer "F.Fab")
		)
		(fp_line
			(start -0.12065 0.3048)
			(end -0.67945 0.3048)
			(stroke
				(width 0.1)
				(type default)
			)
			(layer "F.Fab")
		)
		(fp_line
			(start -0.67945 0.3048)
			(end -0.67945 -0.305054)
			(stroke
				(width 0.1)
				(type default)
			)
			(layer "F.Fab")
		)
		(pad "1" smd circle
			(at -0.40005 0 90)
			(size 0 0)
			(layers "F.Cu" "F.Mask" "F.Paste")
			(net "PEX2_EXT_GPIO_LATCH_N")
		)
		(pad "2" smd circle
			(at 0.40005 0 90)
			(size 0 0)
			(layers "F.Cu" "F.Mask" "F.Paste")
			(net "P1V8_PEX")
		)
	)
	(footprint ""
		(layer "F.Cu")
		(at 407.009092 -26.03373)
		(property "Reference" "R4080"
			(at 0 0 0)
			(layer "F.SilkS")
			(hide yes)
			(effects
				(font
					(size 1.27 1.27)
				)
			)
		)
		(property "Value" ""
			(at 0 0 0)
			(layer "F.Fab")
			(effects
				(font
					(size 1.27 1.27)
				)
			)
		)
		(duplicate_pad_numbers_are_jumpers no)
		(fp_line
			(start -0.7874 -0.4064)
			(end 0.7874 -0.4064)
			(stroke
				(width 0.1524)
				(type default)
			)
			(layer "F.SilkS")
		)
		(fp_line
			(start -0.7874 0.4064)
			(end -0.7874 -0.4064)
			(stroke
				(width 0.1524)
				(type default)
			)
			(layer "F.SilkS")
		)
		(fp_line
			(start 0.7874 -0.4064)
			(end 0.7874 0.4064)
			(stroke
				(width 0.1524)
				(type default)
			)
			(layer "F.SilkS")
		)
		(fp_line
			(start 0.7874 0.4064)
			(end -0.7874 0.4064)
			(stroke
				(width 0.1524)
				(type default)
			)
			(layer "F.SilkS")
		)
		(fp_line
			(start -0.67945 -0.305054)
			(end -0.12065 -0.305054)
			(stroke
				(width 0.1)
				(type default)
			)
			(layer "F.Fab")
		)
		(fp_line
			(start -0.67945 0.3048)
			(end -0.67945 -0.305054)
			(stroke
				(width 0.1)
				(type default)
			)
			(layer "F.Fab")
		)
		(fp_line
			(start -0.12065 -0.305054)
			(end -0.12065 -0.2794)
			(stroke
				(width 0.1)
				(type default)
			)
			(layer "F.Fab")
		)
		(fp_line
			(start -0.12065 -0.2794)
			(end 0.12065 -0.2794)
			(stroke
				(width 0.1)
				(type default)
			)
			(layer "F.Fab")
		)
		(fp_line
			(start -0.12065 0.2794)
			(end -0.12065 0.3048)
			(stroke
				(width 0.1)
				(type default)
			)
			(layer "F.Fab")
		)
		(fp_line
			(start -0.12065 0.3048)
			(end -0.67945 0.3048)
			(stroke
				(width 0.1)
				(type default)
			)
			(layer "F.Fab")
		)
		(fp_line
			(start 0.120396 0.2794)
			(end -0.12065 0.2794)
			(stroke
				(width 0.1)
				(type default)
			)
			(layer "F.Fab")
		)
		(fp_line
			(start 0.120396 0.3048)
			(end 0.120396 0.2794)
			(stroke
				(width 0.1)
				(type default)
			)
			(layer "F.Fab")
		)
		(fp_line
			(start 0.12065 -0.3048)
			(end 0.67945 -0.3048)
			(stroke
				(width 0.1)
				(type default)
			)
			(layer "F.Fab")
		)
		(fp_line
			(start 0.12065 -0.2794)
			(end 0.12065 -0.3048)
			(stroke
				(width 0.1)
				(type default)
			)
			(layer "F.Fab")
		)
		(fp_line
			(start 0.67945 -0.3048)
			(end 0.67945 0.3048)
			(stroke
				(width 0.1)
				(type default)
			)
			(layer "F.Fab")
		)
		(fp_line
			(start 0.67945 0.3048)
			(end 0.120396 0.3048)
			(stroke
				(width 0.1)
				(type default)
			)
			(layer "F.Fab")
		)
		(pad "1" smd circle
			(at -0.40005 0)
			(size 0 0)
			(layers "F.Cu" "F.Mask" "F.Paste")
			(net "P3V3_AUX")
		)
		(pad "2" smd circle
			(at 0.40005 0)
			(size 0 0)
			(layers "F.Cu" "F.Mask" "F.Paste")
			(net "PRSNT_SSD14_R_N")
		)
	)
	(footprint ""
		(layer "F.Cu")
		(at 194.164712 -350.098614 90)
		(property "Reference" "C2541"
			(at 0 0 90)
			(layer "F.SilkS")
			(hide yes)
			(effects
				(font
					(size 1.27 1.27)
				)
			)
		)
		(property "Value" ""
			(at 0 0 90)
			(layer "F.Fab")
			(effects
				(font
					(size 1.27 1.27)
				)
			)
		)
		(duplicate_pad_numbers_are_jumpers no)
		(fp_line
			(start 0.299974 -0.150114)
			(end 0.299974 0.150114)
			(stroke
				(width 0.1)
				(type default)
			)
			(layer "F.Fab")
		)
		(fp_line
			(start -0.299974 -0.150114)
			(end 0.299974 -0.150114)
			(stroke
				(width 0.1)
				(type default)
			)
			(layer "F.Fab")
		)
		(fp_line
			(start 0.299974 0.150114)
			(end -0.299974 0.150114)
			(stroke
				(width 0.1)
				(type default)
			)
			(layer "F.Fab")
		)
		(fp_line
			(start -0.299974 0.150114)
			(end -0.299974 -0.150114)
			(stroke
				(width 0.1)
				(type default)
			)
			(layer "F.Fab")
		)
		(pad "1" smd rect
			(at -0.2667 0 90)
			(size 0.3048 0.381)
			(layers "F.Cu" "F.Mask" "F.Paste")
			(net "P5E_PEX1_STN4_TX_DN<65>")
		)
		(pad "2" smd rect
			(at 0.2667 0 90)
			(size 0.3048 0.381)
			(layers "F.Cu" "F.Mask" "F.Paste")
			(net "P5E_PEX1_STN4_TX_C_DN<65>")
		)
	)
	(footprint ""
		(layer "F.Cu")
		(at 144.205198 -307.084984 45)
		(property "Reference" "R1282"
			(at 0 0 45)
			(layer "F.SilkS")
			(hide yes)
			(effects
				(font
					(size 1.27 1.27)
				)
			)
		)
		(property "Value" ""
			(at 0 0 45)
			(layer "F.Fab")
			(effects
				(font
					(size 1.27 1.27)
				)
			)
		)
		(duplicate_pad_numbers_are_jumpers no)
		(fp_line
			(start -0.787389 -0.406267)
			(end 0.787389 -0.406267)
			(stroke
				(width 0.1524)
				(type default)
			)
			(layer "F.SilkS")
		)
		(fp_line
			(start -0.787389 0.406267)
			(end -0.787389 -0.406267)
			(stroke
				(width 0.1524)
				(type default)
			)
			(layer "F.SilkS")
		)
		(fp_line
			(start 0.787389 -0.406267)
			(end 0.787389 0.406267)
			(stroke
				(width 0.1524)
				(type default)
			)
			(layer "F.SilkS")
		)
		(fp_line
			(start 0.787389 0.406267)
			(end -0.787389 0.406267)
			(stroke
				(width 0.1524)
				(type default)
			)
			(layer "F.SilkS")
		)
		(fp_line
			(start -0.679446 -0.305149)
			(end -0.120695 -0.304969)
			(stroke
				(width 0.1)
				(type default)
			)
			(layer "F.Fab")
		)
		(fp_line
			(start -0.120695 -0.304969)
			(end -0.120695 -0.279466)
			(stroke
				(width 0.1)
				(type default)
			)
			(layer "F.Fab")
		)
		(fp_line
			(start -0.120695 -0.279466)
			(end 0.120695 -0.279466)
			(stroke
				(width 0.1)
				(type default)
			)
			(layer "F.Fab")
		)
		(fp_line
			(start -0.679446 0.30479)
			(end -0.679446 -0.305149)
			(stroke
				(width 0.1)
				(type default)
			)
			(layer "F.Fab")
		)
		(fp_line
			(start 0.120515 -0.30479)
			(end 0.679446 -0.30479)
			(stroke
				(width 0.1)
				(type default)
			)
			(layer "F.Fab")
		)
		(fp_line
			(start 0.120695 -0.279466)
			(end 0.120515 -0.30479)
			(stroke
				(width 0.1)
				(type default)
			)
			(layer "F.Fab")
		)
		(fp_line
			(start -0.120695 0.279466)
			(end -0.120515 0.30479)
			(stroke
				(width 0.1)
				(type default)
			)
			(layer "F.Fab")
		)
		(fp_line
			(start -0.120515 0.30479)
			(end -0.679446 0.30479)
			(stroke
				(width 0.1)
				(type default)
			)
			(layer "F.Fab")
		)
		(fp_line
			(start 0.679446 -0.30479)
			(end 0.679446 0.30479)
			(stroke
				(width 0.1)
				(type default)
			)
			(layer "F.Fab")
		)
		(fp_line
			(start 0.120335 0.279466)
			(end -0.120695 0.279466)
			(stroke
				(width 0.1)
				(type default)
			)
			(layer "F.Fab")
		)
		(fp_line
			(start 0.120515 0.30479)
			(end 0.120335 0.279466)
			(stroke
				(width 0.1)
				(type default)
			)
			(layer "F.Fab")
		)
		(fp_line
			(start 0.679446 0.30479)
			(end 0.120515 0.30479)
			(stroke
				(width 0.1)
				(type default)
			)
			(layer "F.Fab")
		)
		(pad "1" smd circle
			(at -0.40005 0 45)
			(size 0 0)
			(layers "F.Cu" "F.Mask" "F.Paste")
			(net "GND")
		)
		(pad "2" smd circle
			(at 0.40005 0 45)
			(size 0 0)
			(layers "F.Cu" "F.Mask" "F.Paste")
			(net "PEX1_DBG_SEL0")
		)
	)
	(footprint ""
		(layer "F.Cu")
		(at 34.75609 -115.590574 90)
		(property "Reference" "U9"
			(at 2.670556 -1.22809 0)
			(unlocked yes)
			(layer "F.SilkS")
			(effects
				(font
					(size 0.7874 0.5842)
					(thickness 0.1524)
				)
			)
		)
		(property "Value" ""
			(at 0 0 90)
			(layer "F.Fab")
			(effects
				(font
					(size 1.27 1.27)
				)
			)
		)
		(duplicate_pad_numbers_are_jumpers no)
		(fp_line
			(start -1.949958 -1.610106)
			(end 1.949958 -1.610106)
			(stroke
				(width 0.1524)
				(type default)
			)
			(layer "F.SilkS")
		)
		(fp_line
			(start 1.949958 -1.560068)
			(end 1.949958 1.610106)
			(stroke
				(width 0.1524)
				(type default)
			)
			(layer "F.SilkS")
		)
		(fp_line
			(start 1.949958 1.610106)
			(end -1.949958 1.610106)
			(stroke
				(width 0.1524)
				(type default)
			)
			(layer "F.SilkS")
		)
		(fp_line
			(start -1.949958 1.610106)
			(end -1.949958 -1.610106)
			(stroke
				(width 0.1524)
				(type default)
			)
			(layer "F.SilkS")
		)
		(fp_line
			(start 0.750062 -1.560068)
			(end 0.750062 1.560068)
			(stroke
				(width 0.1)
				(type default)
			)
			(layer "F.Fab")
		)
		(fp_line
			(start -0.750062 -1.560068)
			(end 0.750062 -1.560068)
			(stroke
				(width 0.1)
				(type default)
			)
			(layer "F.Fab")
		)
		(fp_line
			(start 0.750062 1.560068)
			(end -0.750062 1.560068)
			(stroke
				(width 0.1)
				(type default)
			)
			(layer "F.Fab")
		)
		(fp_line
			(start -0.750062 1.560068)
			(end -0.750062 -1.560068)
			(stroke
				(width 0.1)
				(type default)
			)
			(layer "F.Fab")
		)
		(pad "D" smd rect
			(at 1.100074 0)
			(size 1.016 1.4224)
			(layers "F.Cu" "F.Mask" "F.Paste")
			(net "HP_NIC0_EN")
		)
		(pad "G" smd rect
			(at -1.100074 -0.94996)
			(size 1.016 1.4224)
			(layers "F.Cu" "F.Mask" "F.Paste")
			(net "PRSNT_NIC0_R_N")
		)
		(pad "S" smd rect
			(at -1.100074 0.94996)
			(size 1.016 1.4224)
			(layers "F.Cu" "F.Mask" "F.Paste")
			(net "GND")
		)
	)
	(footprint ""
		(layer "F.Cu")
		(at 214.454486 -212.206586)
		(property "Reference" "R5719"
			(at 0 0 0)
			(layer "F.SilkS")
			(hide yes)
			(effects
				(font
					(size 1.27 1.27)
				)
			)
		)
		(property "Value" ""
			(at 0 0 0)
			(layer "F.Fab")
			(effects
				(font
					(size 1.27 1.27)
				)
			)
		)
		(duplicate_pad_numbers_are_jumpers no)
		(fp_line
			(start -0.7874 -0.4064)
			(end 0.7874 -0.4064)
			(stroke
				(width 0.1524)
				(type default)
			)
			(layer "F.SilkS")
		)
		(fp_line
			(start -0.7874 0.4064)
			(end -0.7874 -0.4064)
			(stroke
				(width 0.1524)
				(type default)
			)
			(layer "F.SilkS")
		)
		(fp_line
			(start 0.7874 -0.4064)
			(end 0.7874 0.4064)
			(stroke
				(width 0.1524)
				(type default)
			)
			(layer "F.SilkS")
		)
		(fp_line
			(start 0.7874 0.4064)
			(end -0.7874 0.4064)
			(stroke
				(width 0.1524)
				(type default)
			)
			(layer "F.SilkS")
		)
		(fp_line
			(start -0.67945 -0.305054)
			(end -0.12065 -0.305054)
			(stroke
				(width 0.1)
				(type default)
			)
			(layer "F.Fab")
		)
		(fp_line
			(start -0.67945 0.3048)
			(end -0.67945 -0.305054)
			(stroke
				(width 0.1)
				(type default)
			)
			(layer "F.Fab")
		)
		(fp_line
			(start -0.12065 -0.305054)
			(end -0.12065 -0.2794)
			(stroke
				(width 0.1)
				(type default)
			)
			(layer "F.Fab")
		)
		(fp_line
			(start -0.12065 -0.2794)
			(end 0.12065 -0.2794)
			(stroke
				(width 0.1)
				(type default)
			)
			(layer "F.Fab")
		)
		(fp_line
			(start -0.12065 0.2794)
			(end -0.12065 0.3048)
			(stroke
				(width 0.1)
				(type default)
			)
			(layer "F.Fab")
		)
		(fp_line
			(start -0.12065 0.3048)
			(end -0.67945 0.3048)
			(stroke
				(width 0.1)
				(type default)
			)
			(layer "F.Fab")
		)
		(fp_line
			(start 0.120396 0.2794)
			(end -0.12065 0.2794)
			(stroke
				(width 0.1)
				(type default)
			)
			(layer "F.Fab")
		)
		(fp_line
			(start 0.120396 0.3048)
			(end 0.120396 0.2794)
			(stroke
				(width 0.1)
				(type default)
			)
			(layer "F.Fab")
		)
		(fp_line
			(start 0.12065 -0.3048)
			(end 0.67945 -0.3048)
			(stroke
				(width 0.1)
				(type default)
			)
			(layer "F.Fab")
		)
		(fp_line
			(start 0.12065 -0.2794)
			(end 0.12065 -0.3048)
			(stroke
				(width 0.1)
				(type default)
			)
			(layer "F.Fab")
		)
		(fp_line
			(start 0.67945 -0.3048)
			(end 0.67945 0.3048)
			(stroke
				(width 0.1)
				(type default)
			)
			(layer "F.Fab")
		)
		(fp_line
			(start 0.67945 0.3048)
			(end 0.120396 0.3048)
			(stroke
				(width 0.1)
				(type default)
			)
			(layer "F.Fab")
		)
		(pad "1" smd circle
			(at -0.40005 0)
			(size 0 0)
			(layers "F.Cu" "F.Mask" "F.Paste")
			(net "RST_BIC_I2C9_SSD_MUX1_R_N")
		)
		(pad "2" smd circle
			(at 0.40005 0)
			(size 0 0)
			(layers "F.Cu" "F.Mask" "F.Paste")
			(net "RST_BIC_I2C9_SSD_MUX1_N")
		)
	)
	(footprint ""
		(layer "F.Cu")
		(at 18.451322 -114.914426 -90)
		(property "Reference" "PC661"
			(at 0 0 270)
			(layer "F.SilkS")
			(hide yes)
			(effects
				(font
					(size 1.27 1.27)
				)
			)
		)
		(property "Value" ""
			(at 0 0 270)
			(layer "F.Fab")
			(effects
				(font
					(size 1.27 1.27)
				)
			)
		)
		(duplicate_pad_numbers_are_jumpers no)
		(fp_line
			(start -1.524 0.762)
			(end -1.524 -0.762)
			(stroke
				(width 0.1524)
				(type default)
			)
			(layer "F.SilkS")
		)
		(fp_line
			(start 1.524 0.762)
			(end -1.524 0.762)
			(stroke
				(width 0.1524)
				(type default)
			)
			(layer "F.SilkS")
		)
		(fp_line
			(start -1.524 -0.762)
			(end 1.524 -0.762)
			(stroke
				(width 0.1524)
				(type default)
			)
			(layer "F.SilkS")
		)
		(fp_line
			(start 1.524 -0.762)
			(end 1.524 0.762)
			(stroke
				(width 0.1524)
				(type default)
			)
			(layer "F.SilkS")
		)
		(fp_line
			(start -1.1049 0.724916)
			(end 1.1049 0.724916)
			(stroke
				(width 0.1)
				(type default)
			)
			(layer "F.Fab")
		)
		(fp_line
			(start 1.1049 0.724916)
			(end 1.1049 -0.724916)
			(stroke
				(width 0.1)
				(type default)
			)
			(layer "F.Fab")
		)
		(fp_line
			(start -1.1049 -0.724916)
			(end -1.1049 0.724916)
			(stroke
				(width 0.1)
				(type default)
			)
			(layer "F.Fab")
		)
		(fp_line
			(start 1.1049 -0.724916)
			(end -1.1049 -0.724916)
			(stroke
				(width 0.1)
				(type default)
			)
			(layer "F.Fab")
		)
		(pad "1" smd rect
			(at -0.889 0 90)
			(size 1.016 1.27)
			(layers "F.Cu" "F.Mask" "F.Paste")
			(net "P3V3_NIC0")
		)
		(pad "2" smd rect
			(at 0.889 0 90)
			(size 1.016 1.27)
			(layers "F.Cu" "F.Mask" "F.Paste")
			(net "GND")
		)
	)
	(footprint ""
		(layer "F.Cu")
		(at 87.132922 -343.952322 90)
		(property "Reference" "C152"
			(at 0 0 90)
			(layer "F.SilkS")
			(hide yes)
			(effects
				(font
					(size 1.27 1.27)
				)
			)
		)
		(property "Value" ""
			(at 0 0 90)
			(layer "F.Fab")
			(effects
				(font
					(size 1.27 1.27)
				)
			)
		)
		(duplicate_pad_numbers_are_jumpers no)
		(fp_line
			(start 0.299974 -0.150114)
			(end 0.299974 0.150114)
			(stroke
				(width 0.1)
				(type default)
			)
			(layer "F.Fab")
		)
		(fp_line
			(start -0.299974 -0.150114)
			(end 0.299974 -0.150114)
			(stroke
				(width 0.1)
				(type default)
			)
			(layer "F.Fab")
		)
		(fp_line
			(start 0.299974 0.150114)
			(end -0.299974 0.150114)
			(stroke
				(width 0.1)
				(type default)
			)
			(layer "F.Fab")
		)
		(fp_line
			(start -0.299974 0.150114)
			(end -0.299974 -0.150114)
			(stroke
				(width 0.1)
				(type default)
			)
			(layer "F.Fab")
		)
		(pad "1" smd rect
			(at -0.2667 0 90)
			(size 0.3048 0.381)
			(layers "F.Cu" "F.Mask" "F.Paste")
			(net "P5E_PEX0_STN6_TX_DN<100>")
		)
		(pad "2" smd rect
			(at 0.2667 0 90)
			(size 0.3048 0.381)
			(layers "F.Cu" "F.Mask" "F.Paste")
			(net "P5E_PEX0_STN6_TX_C_DN<100>")
		)
	)
	(footprint ""
		(layer "F.Cu")
		(at 338.074 -160.782 180)
		(property "Reference" "R4824"
			(at 0 0 180)
			(layer "F.SilkS")
			(hide yes)
			(effects
				(font
					(size 1.27 1.27)
				)
			)
		)
		(property "Value" ""
			(at 0 0 180)
			(layer "F.Fab")
			(effects
				(font
					(size 1.27 1.27)
				)
			)
		)
		(duplicate_pad_numbers_are_jumpers no)
		(fp_line
			(start 0.7874 0.4064)
			(end -0.7874 0.4064)
			(stroke
				(width 0.1524)
				(type default)
			)
			(layer "F.SilkS")
		)
		(fp_line
			(start 0.7874 -0.4064)
			(end 0.7874 0.4064)
			(stroke
				(width 0.1524)
				(type default)
			)
			(layer "F.SilkS")
		)
		(fp_line
			(start -0.7874 0.4064)
			(end -0.7874 -0.4064)
			(stroke
				(width 0.1524)
				(type default)
			)
			(layer "F.SilkS")
		)
		(fp_line
			(start -0.7874 -0.4064)
			(end 0.7874 -0.4064)
			(stroke
				(width 0.1524)
				(type default)
			)
			(layer "F.SilkS")
		)
		(fp_line
			(start 0.67945 0.3048)
			(end 0.120396 0.3048)
			(stroke
				(width 0.1)
				(type default)
			)
			(layer "F.Fab")
		)
		(fp_line
			(start 0.67945 -0.3048)
			(end 0.67945 0.3048)
			(stroke
				(width 0.1)
				(type default)
			)
			(layer "F.Fab")
		)
		(fp_line
			(start 0.12065 -0.2794)
			(end 0.12065 -0.3048)
			(stroke
				(width 0.1)
				(type default)
			)
			(layer "F.Fab")
		)
		(fp_line
			(start 0.12065 -0.3048)
			(end 0.67945 -0.3048)
			(stroke
				(width 0.1)
				(type default)
			)
			(layer "F.Fab")
		)
		(fp_line
			(start 0.120396 0.3048)
			(end 0.120396 0.2794)
			(stroke
				(width 0.1)
				(type default)
			)
			(layer "F.Fab")
		)
		(fp_line
			(start 0.120396 0.2794)
			(end -0.12065 0.2794)
			(stroke
				(width 0.1)
				(type default)
			)
			(layer "F.Fab")
		)
		(fp_line
			(start -0.12065 0.3048)
			(end -0.67945 0.3048)
			(stroke
				(width 0.1)
				(type default)
			)
			(layer "F.Fab")
		)
		(fp_line
			(start -0.12065 0.2794)
			(end -0.12065 0.3048)
			(stroke
				(width 0.1)
				(type default)
			)
			(layer "F.Fab")
		)
		(fp_line
			(start -0.12065 -0.2794)
			(end 0.12065 -0.2794)
			(stroke
				(width 0.1)
				(type default)
			)
			(layer "F.Fab")
		)
		(fp_line
			(start -0.12065 -0.305054)
			(end -0.12065 -0.2794)
			(stroke
				(width 0.1)
				(type default)
			)
			(layer "F.Fab")
		)
		(fp_line
			(start -0.67945 0.3048)
			(end -0.67945 -0.305054)
			(stroke
				(width 0.1)
				(type default)
			)
			(layer "F.Fab")
		)
		(fp_line
			(start -0.67945 -0.305054)
			(end -0.12065 -0.305054)
			(stroke
				(width 0.1)
				(type default)
			)
			(layer "F.Fab")
		)
		(pad "1" smd circle
			(at -0.40005 0 180)
			(size 0 0)
			(layers "F.Cu" "F.Mask" "F.Paste")
			(net "GND")
		)
		(pad "2" smd circle
			(at 0.40005 0 180)
			(size 0 0)
			(layers "F.Cu" "F.Mask" "F.Paste")
			(net "PCA9555_0_PEX3_A2")
		)
	)
	(footprint ""
		(layer "F.Cu")
		(at 334.240124 -343.952322 90)
		(property "Reference" "C529"
			(at 0 0 90)
			(layer "F.SilkS")
			(hide yes)
			(effects
				(font
					(size 1.27 1.27)
				)
			)
		)
		(property "Value" ""
			(at 0 0 90)
			(layer "F.Fab")
			(effects
				(font
					(size 1.27 1.27)
				)
			)
		)
		(duplicate_pad_numbers_are_jumpers no)
		(fp_line
			(start 0.299974 -0.150114)
			(end 0.299974 0.150114)
			(stroke
				(width 0.1)
				(type default)
			)
			(layer "F.Fab")
		)
		(fp_line
			(start -0.299974 -0.150114)
			(end 0.299974 -0.150114)
			(stroke
				(width 0.1)
				(type default)
			)
			(layer "F.Fab")
		)
		(fp_line
			(start 0.299974 0.150114)
			(end -0.299974 0.150114)
			(stroke
				(width 0.1)
				(type default)
			)
			(layer "F.Fab")
		)
		(fp_line
			(start -0.299974 0.150114)
			(end -0.299974 -0.150114)
			(stroke
				(width 0.1)
				(type default)
			)
			(layer "F.Fab")
		)
		(pad "1" smd rect
			(at -0.2667 0 90)
			(size 0.3048 0.381)
			(layers "F.Cu" "F.Mask" "F.Paste")
			(net "P5E_PEX2_STN5_TX_DP<90>")
		)
		(pad "2" smd rect
			(at 0.2667 0 90)
			(size 0.3048 0.381)
			(layers "F.Cu" "F.Mask" "F.Paste")
			(net "P5E_PEX2_STN5_TX_C_DP<90>")
		)
	)
	(footprint ""
		(layer "F.Cu")
		(at 452.567802 -53.051456)
		(property "Reference" "R4473"
			(at 0 0 0)
			(layer "F.SilkS")
			(hide yes)
			(effects
				(font
					(size 1.27 1.27)
				)
			)
		)
		(property "Value" ""
			(at 0 0 0)
			(layer "F.Fab")
			(effects
				(font
					(size 1.27 1.27)
				)
			)
		)
		(duplicate_pad_numbers_are_jumpers no)
		(fp_line
			(start -0.7874 -0.4064)
			(end 0.7874 -0.4064)
			(stroke
				(width 0.1524)
				(type default)
			)
			(layer "F.SilkS")
		)
		(fp_line
			(start -0.7874 0.4064)
			(end -0.7874 -0.4064)
			(stroke
				(width 0.1524)
				(type default)
			)
			(layer "F.SilkS")
		)
		(fp_line
			(start 0.7874 -0.4064)
			(end 0.7874 0.4064)
			(stroke
				(width 0.1524)
				(type default)
			)
			(layer "F.SilkS")
		)
		(fp_line
			(start 0.7874 0.4064)
			(end -0.7874 0.4064)
			(stroke
				(width 0.1524)
				(type default)
			)
			(layer "F.SilkS")
		)
		(fp_line
			(start -0.67945 -0.305054)
			(end -0.12065 -0.305054)
			(stroke
				(width 0.1)
				(type default)
			)
			(layer "F.Fab")
		)
		(fp_line
			(start -0.67945 0.3048)
			(end -0.67945 -0.305054)
			(stroke
				(width 0.1)
				(type default)
			)
			(layer "F.Fab")
		)
		(fp_line
			(start -0.12065 -0.305054)
			(end -0.12065 -0.2794)
			(stroke
				(width 0.1)
				(type default)
			)
			(layer "F.Fab")
		)
		(fp_line
			(start -0.12065 -0.2794)
			(end 0.12065 -0.2794)
			(stroke
				(width 0.1)
				(type default)
			)
			(layer "F.Fab")
		)
		(fp_line
			(start -0.12065 0.2794)
			(end -0.12065 0.3048)
			(stroke
				(width 0.1)
				(type default)
			)
			(layer "F.Fab")
		)
		(fp_line
			(start -0.12065 0.3048)
			(end -0.67945 0.3048)
			(stroke
				(width 0.1)
				(type default)
			)
			(layer "F.Fab")
		)
		(fp_line
			(start 0.120396 0.2794)
			(end -0.12065 0.2794)
			(stroke
				(width 0.1)
				(type default)
			)
			(layer "F.Fab")
		)
		(fp_line
			(start 0.120396 0.3048)
			(end 0.120396 0.2794)
			(stroke
				(width 0.1)
				(type default)
			)
			(layer "F.Fab")
		)
		(fp_line
			(start 0.12065 -0.3048)
			(end 0.67945 -0.3048)
			(stroke
				(width 0.1)
				(type default)
			)
			(layer "F.Fab")
		)
		(fp_line
			(start 0.12065 -0.2794)
			(end 0.12065 -0.3048)
			(stroke
				(width 0.1)
				(type default)
			)
			(layer "F.Fab")
		)
		(fp_line
			(start 0.67945 -0.3048)
			(end 0.67945 0.3048)
			(stroke
				(width 0.1)
				(type default)
			)
			(layer "F.Fab")
		)
		(fp_line
			(start 0.67945 0.3048)
			(end 0.120396 0.3048)
			(stroke
				(width 0.1)
				(type default)
			)
			(layer "F.Fab")
		)
		(pad "1" smd circle
			(at -0.40005 0)
			(size 0 0)
			(layers "F.Cu" "F.Mask" "F.Paste")
			(net "PWRGD_P12V_SSD15")
		)
		(pad "2" smd circle
			(at 0.40005 0)
			(size 0 0)
			(layers "F.Cu" "F.Mask" "F.Paste")
			(net "PWRGD_P12V_SSD15_R")
		)
	)
	(footprint ""
		(layer "F.Cu")
		(at 219.39123 -86.475316)
		(property "Reference" "C2809"
			(at 0 0 0)
			(layer "F.SilkS")
			(hide yes)
			(effects
				(font
					(size 1.27 1.27)
				)
			)
		)
		(property "Value" ""
			(at 0 0 0)
			(layer "F.Fab")
			(effects
				(font
					(size 1.27 1.27)
				)
			)
		)
		(duplicate_pad_numbers_are_jumpers no)
		(fp_line
			(start -0.7874 -0.4064)
			(end 0.7874 -0.4064)
			(stroke
				(width 0.1524)
				(type default)
			)
			(layer "F.SilkS")
		)
		(fp_line
			(start -0.7874 0.4064)
			(end -0.7874 -0.4064)
			(stroke
				(width 0.1524)
				(type default)
			)
			(layer "F.SilkS")
		)
		(fp_line
			(start 0.7874 -0.4064)
			(end 0.7874 0.4064)
			(stroke
				(width 0.1524)
				(type default)
			)
			(layer "F.SilkS")
		)
		(fp_line
			(start 0.7874 0.4064)
			(end -0.7874 0.4064)
			(stroke
				(width 0.1524)
				(type default)
			)
			(layer "F.SilkS")
		)
		(fp_line
			(start -0.67945 -0.305054)
			(end -0.12065 -0.305054)
			(stroke
				(width 0.1)
				(type default)
			)
			(layer "F.Fab")
		)
		(fp_line
			(start -0.67945 0.3048)
			(end -0.67945 -0.305054)
			(stroke
				(width 0.1)
				(type default)
			)
			(layer "F.Fab")
		)
		(fp_line
			(start -0.12065 -0.305054)
			(end -0.12065 -0.2794)
			(stroke
				(width 0.1)
				(type default)
			)
			(layer "F.Fab")
		)
		(fp_line
			(start -0.12065 -0.2794)
			(end 0.12065 -0.2794)
			(stroke
				(width 0.1)
				(type default)
			)
			(layer "F.Fab")
		)
		(fp_line
			(start -0.12065 0.2794)
			(end -0.12065 0.3048)
			(stroke
				(width 0.1)
				(type default)
			)
			(layer "F.Fab")
		)
		(fp_line
			(start -0.12065 0.3048)
			(end -0.67945 0.3048)
			(stroke
				(width 0.1)
				(type default)
			)
			(layer "F.Fab")
		)
		(fp_line
			(start 0.120396 0.2794)
			(end -0.12065 0.2794)
			(stroke
				(width 0.1)
				(type default)
			)
			(layer "F.Fab")
		)
		(fp_line
			(start 0.120396 0.3048)
			(end 0.120396 0.2794)
			(stroke
				(width 0.1)
				(type default)
			)
			(layer "F.Fab")
		)
		(fp_line
			(start 0.12065 -0.3048)
			(end 0.67945 -0.3048)
			(stroke
				(width 0.1)
				(type default)
			)
			(layer "F.Fab")
		)
		(fp_line
			(start 0.12065 -0.2794)
			(end 0.12065 -0.3048)
			(stroke
				(width 0.1)
				(type default)
			)
			(layer "F.Fab")
		)
		(fp_line
			(start 0.67945 -0.3048)
			(end 0.67945 0.3048)
			(stroke
				(width 0.1)
				(type default)
			)
			(layer "F.Fab")
		)
		(fp_line
			(start 0.67945 0.3048)
			(end 0.120396 0.3048)
			(stroke
				(width 0.1)
				(type default)
			)
			(layer "F.Fab")
		)
		(pad "1" smd circle
			(at -0.40005 0)
			(size 0 0)
			(layers "F.Cu" "F.Mask" "F.Paste")
			(net "P3V3_AUX")
		)
		(pad "2" smd circle
			(at 0.40005 0)
			(size 0 0)
			(layers "F.Cu" "F.Mask" "F.Paste")
			(net "GND")
		)
	)
	(footprint ""
		(layer "F.Cu")
		(at 152.738328 -131.323334)
		(property "Reference" "C251"
			(at 0 0 0)
			(layer "F.SilkS")
			(hide yes)
			(effects
				(font
					(size 1.27 1.27)
				)
			)
		)
		(property "Value" ""
			(at 0 0 0)
			(layer "F.Fab")
			(effects
				(font
					(size 1.27 1.27)
				)
			)
		)
		(duplicate_pad_numbers_are_jumpers no)
		(fp_line
			(start -0.299974 -0.150114)
			(end 0.299974 -0.150114)
			(stroke
				(width 0.1)
				(type default)
			)
			(layer "F.Fab")
		)
		(fp_line
			(start -0.299974 0.150114)
			(end -0.299974 -0.150114)
			(stroke
				(width 0.1)
				(type default)
			)
			(layer "F.Fab")
		)
		(fp_line
			(start 0.299974 -0.150114)
			(end 0.299974 0.150114)
			(stroke
				(width 0.1)
				(type default)
			)
			(layer "F.Fab")
		)
		(fp_line
			(start 0.299974 0.150114)
			(end -0.299974 0.150114)
			(stroke
				(width 0.1)
				(type default)
			)
			(layer "F.Fab")
		)
		(pad "1" smd rect
			(at -0.2667 0)
			(size 0.3048 0.381)
			(layers "F.Cu" "F.Mask" "F.Paste")
			(net "P5E_PEX1_STN1_TX_DN<28>")
		)
		(pad "2" smd rect
			(at 0.2667 0)
			(size 0.3048 0.381)
			(layers "F.Cu" "F.Mask" "F.Paste")
			(net "P5E_PEX1_STN1_TX_C_DN<28>")
		)
	)
	(footprint ""
		(layer "F.Cu")
		(at 361.521756 -129.799334 180)
		(property "Reference" "PD9"
			(at 4.346956 2.584196 0)
			(unlocked yes)
			(layer "F.SilkS")
			(effects
				(font
					(size 0.7874 0.5842)
					(thickness 0.1524)
				)
				(justify left)
			)
		)
		(property "Value" ""
			(at 0 0 180)
			(layer "F.Fab")
			(effects
				(font
					(size 1.27 1.27)
				)
			)
		)
		(duplicate_pad_numbers_are_jumpers no)
		(fp_line
			(start 4.240784 1.970024)
			(end 4.240784 -1.970024)
			(stroke
				(width 0.1524)
				(type default)
			)
			(layer "F.SilkS")
		)
		(fp_line
			(start 4.240784 -1.970024)
			(end -3.656584 -1.970024)
			(stroke
				(width 0.1524)
				(type default)
			)
			(layer "F.SilkS")
		)
		(fp_line
			(start -3.656584 1.970024)
			(end 4.240784 1.970024)
			(stroke
				(width 0.1524)
				(type default)
			)
			(layer "F.SilkS")
		)
		(fp_line
			(start -3.656584 -1.970024)
			(end -3.656584 1.970024)
			(stroke
				(width 0.1524)
				(type default)
			)
			(layer "F.SilkS")
		)
		(fp_poly
			(pts
				(xy 3.580384 1.970024) (xy 3.580384 -1.970024) (xy 4.240784 -1.970024) (xy 4.240784 1.970024)
			)
			(stroke
				(width 0)
				(type default)
			)
			(fill yes)
			(layer "F.SilkS")
		)
		(fp_line
			(start 2.3749 1.970024)
			(end 2.3749 -1.970024)
			(stroke
				(width 0.1)
				(type default)
			)
			(layer "F.Fab")
		)
		(fp_line
			(start 2.3749 -1.970024)
			(end -2.3749 -1.970024)
			(stroke
				(width 0.1)
				(type default)
			)
			(layer "F.Fab")
		)
		(fp_line
			(start -2.3749 1.970024)
			(end 2.3749 1.970024)
			(stroke
				(width 0.1)
				(type default)
			)
			(layer "F.Fab")
		)
		(fp_line
			(start -2.3749 -1.970024)
			(end -2.3749 1.970024)
			(stroke
				(width 0.1)
				(type default)
			)
			(layer "F.Fab")
		)
		(fp_text user "-"
			(at 4.1656 -0.23495 180)
			(unlocked yes)
			(layer "F.Fab")
			(effects
				(font
					(size 1.905 1.4224)
					(thickness 0.1524)
				)
				(justify left)
			)
		)
		(fp_text user "+"
			(at -4.9784 -0.23495 180)
			(unlocked yes)
			(layer "F.Fab")
			(effects
				(font
					(size 1.905 1.4224)
					(thickness 0.1524)
				)
				(justify left)
			)
		)
		(pad "A" smd rect
			(at -2.450084 0 180)
			(size 2.159 2.2606)
			(layers "F.Cu" "F.Mask" "F.Paste")
			(net "GND")
		)
		(pad "C" smd rect
			(at 2.450084 0 180)
			(size 2.159 2.2606)
			(layers "F.Cu" "F.Mask" "F.Paste")
			(net "P12V_AUX")
		)
	)
	(footprint ""
		(layer "F.Cu")
		(at 426.543724 -47.92091)
		(property "Reference" "R658"
			(at 0 0 0)
			(layer "F.SilkS")
			(hide yes)
			(effects
				(font
					(size 1.27 1.27)
				)
			)
		)
		(property "Value" ""
			(at 0 0 0)
			(layer "F.Fab")
			(effects
				(font
					(size 1.27 1.27)
				)
			)
		)
		(duplicate_pad_numbers_are_jumpers no)
		(fp_line
			(start -0.7874 -0.4064)
			(end 0.7874 -0.4064)
			(stroke
				(width 0.1524)
				(type default)
			)
			(layer "F.SilkS")
		)
		(fp_line
			(start -0.7874 0.4064)
			(end -0.7874 -0.4064)
			(stroke
				(width 0.1524)
				(type default)
			)
			(layer "F.SilkS")
		)
		(fp_line
			(start 0.7874 -0.4064)
			(end 0.7874 0.4064)
			(stroke
				(width 0.1524)
				(type default)
			)
			(layer "F.SilkS")
		)
		(fp_line
			(start 0.7874 0.4064)
			(end -0.7874 0.4064)
			(stroke
				(width 0.1524)
				(type default)
			)
			(layer "F.SilkS")
		)
		(fp_line
			(start -0.67945 -0.305054)
			(end -0.12065 -0.305054)
			(stroke
				(width 0.1)
				(type default)
			)
			(layer "F.Fab")
		)
		(fp_line
			(start -0.67945 0.3048)
			(end -0.67945 -0.305054)
			(stroke
				(width 0.1)
				(type default)
			)
			(layer "F.Fab")
		)
		(fp_line
			(start -0.12065 -0.305054)
			(end -0.12065 -0.2794)
			(stroke
				(width 0.1)
				(type default)
			)
			(layer "F.Fab")
		)
		(fp_line
			(start -0.12065 -0.2794)
			(end 0.12065 -0.2794)
			(stroke
				(width 0.1)
				(type default)
			)
			(layer "F.Fab")
		)
		(fp_line
			(start -0.12065 0.2794)
			(end -0.12065 0.3048)
			(stroke
				(width 0.1)
				(type default)
			)
			(layer "F.Fab")
		)
		(fp_line
			(start -0.12065 0.3048)
			(end -0.67945 0.3048)
			(stroke
				(width 0.1)
				(type default)
			)
			(layer "F.Fab")
		)
		(fp_line
			(start 0.120396 0.2794)
			(end -0.12065 0.2794)
			(stroke
				(width 0.1)
				(type default)
			)
			(layer "F.Fab")
		)
		(fp_line
			(start 0.120396 0.3048)
			(end 0.120396 0.2794)
			(stroke
				(width 0.1)
				(type default)
			)
			(layer "F.Fab")
		)
		(fp_line
			(start 0.12065 -0.3048)
			(end 0.67945 -0.3048)
			(stroke
				(width 0.1)
				(type default)
			)
			(layer "F.Fab")
		)
		(fp_line
			(start 0.12065 -0.2794)
			(end 0.12065 -0.3048)
			(stroke
				(width 0.1)
				(type default)
			)
			(layer "F.Fab")
		)
		(fp_line
			(start 0.67945 -0.3048)
			(end 0.67945 0.3048)
			(stroke
				(width 0.1)
				(type default)
			)
			(layer "F.Fab")
		)
		(fp_line
			(start 0.67945 0.3048)
			(end 0.120396 0.3048)
			(stroke
				(width 0.1)
				(type default)
			)
			(layer "F.Fab")
		)
		(pad "1" smd circle
			(at -0.40005 0)
			(size 0 0)
			(layers "F.Cu" "F.Mask" "F.Paste")
			(net "P3V3_AUX")
		)
		(pad "2" smd circle
			(at 0.40005 0)
			(size 0 0)
			(layers "F.Cu" "F.Mask" "F.Paste")
			(net "SSD_8_15_ADC_ALERT_N")
		)
	)
	(footprint ""
		(layer "F.Cu")
		(at 372.782084 -37.025072)
		(property "Reference" "R5697"
			(at 0 0 0)
			(layer "F.SilkS")
			(hide yes)
			(effects
				(font
					(size 1.27 1.27)
				)
			)
		)
		(property "Value" ""
			(at 0 0 0)
			(layer "F.Fab")
			(effects
				(font
					(size 1.27 1.27)
				)
			)
		)
		(duplicate_pad_numbers_are_jumpers no)
		(fp_line
			(start -0.7874 -0.4064)
			(end 0.7874 -0.4064)
			(stroke
				(width 0.1524)
				(type default)
			)
			(layer "F.SilkS")
		)
		(fp_line
			(start -0.7874 0.4064)
			(end -0.7874 -0.4064)
			(stroke
				(width 0.1524)
				(type default)
			)
			(layer "F.SilkS")
		)
		(fp_line
			(start 0.7874 -0.4064)
			(end 0.7874 0.4064)
			(stroke
				(width 0.1524)
				(type default)
			)
			(layer "F.SilkS")
		)
		(fp_line
			(start 0.7874 0.4064)
			(end -0.7874 0.4064)
			(stroke
				(width 0.1524)
				(type default)
			)
			(layer "F.SilkS")
		)
		(fp_line
			(start -0.67945 -0.305054)
			(end -0.12065 -0.305054)
			(stroke
				(width 0.1)
				(type default)
			)
			(layer "F.Fab")
		)
		(fp_line
			(start -0.67945 0.3048)
			(end -0.67945 -0.305054)
			(stroke
				(width 0.1)
				(type default)
			)
			(layer "F.Fab")
		)
		(fp_line
			(start -0.12065 -0.305054)
			(end -0.12065 -0.2794)
			(stroke
				(width 0.1)
				(type default)
			)
			(layer "F.Fab")
		)
		(fp_line
			(start -0.12065 -0.2794)
			(end 0.12065 -0.2794)
			(stroke
				(width 0.1)
				(type default)
			)
			(layer "F.Fab")
		)
		(fp_line
			(start -0.12065 0.2794)
			(end -0.12065 0.3048)
			(stroke
				(width 0.1)
				(type default)
			)
			(layer "F.Fab")
		)
		(fp_line
			(start -0.12065 0.3048)
			(end -0.67945 0.3048)
			(stroke
				(width 0.1)
				(type default)
			)
			(layer "F.Fab")
		)
		(fp_line
			(start 0.120396 0.2794)
			(end -0.12065 0.2794)
			(stroke
				(width 0.1)
				(type default)
			)
			(layer "F.Fab")
		)
		(fp_line
			(start 0.120396 0.3048)
			(end 0.120396 0.2794)
			(stroke
				(width 0.1)
				(type default)
			)
			(layer "F.Fab")
		)
		(fp_line
			(start 0.12065 -0.3048)
			(end 0.67945 -0.3048)
			(stroke
				(width 0.1)
				(type default)
			)
			(layer "F.Fab")
		)
		(fp_line
			(start 0.12065 -0.2794)
			(end 0.12065 -0.3048)
			(stroke
				(width 0.1)
				(type default)
			)
			(layer "F.Fab")
		)
		(fp_line
			(start 0.67945 -0.3048)
			(end 0.67945 0.3048)
			(stroke
				(width 0.1)
				(type default)
			)
			(layer "F.Fab")
		)
		(fp_line
			(start 0.67945 0.3048)
			(end 0.120396 0.3048)
			(stroke
				(width 0.1)
				(type default)
			)
			(layer "F.Fab")
		)
		(pad "1" smd circle
			(at -0.40005 0)
			(size 0 0)
			(layers "F.Cu" "F.Mask" "F.Paste")
			(net "RST_SMB_SSD_R_N")
		)
		(pad "2" smd circle
			(at 0.40005 0)
			(size 0 0)
			(layers "F.Cu" "F.Mask" "F.Paste")
			(net "RST_SMB_SSD13_N")
		)
	)
	(footprint ""
		(layer "F.Cu")
		(at 239.14989 -209.564478 -90)
		(property "Reference" "C193"
			(at 0 0 270)
			(layer "F.SilkS")
			(hide yes)
			(effects
				(font
					(size 1.27 1.27)
				)
			)
		)
		(property "Value" ""
			(at 0 0 270)
			(layer "F.Fab")
			(effects
				(font
					(size 1.27 1.27)
				)
			)
		)
		(duplicate_pad_numbers_are_jumpers no)
		(fp_line
			(start -0.7874 0.4064)
			(end -0.7874 -0.4064)
			(stroke
				(width 0.1524)
				(type default)
			)
			(layer "F.SilkS")
		)
		(fp_line
			(start 0.7874 0.4064)
			(end -0.7874 0.4064)
			(stroke
				(width 0.1524)
				(type default)
			)
			(layer "F.SilkS")
		)
		(fp_line
			(start -0.7874 -0.4064)
			(end 0.7874 -0.4064)
			(stroke
				(width 0.1524)
				(type default)
			)
			(layer "F.SilkS")
		)
		(fp_line
			(start 0.7874 -0.4064)
			(end 0.7874 0.4064)
			(stroke
				(width 0.1524)
				(type default)
			)
			(layer "F.SilkS")
		)
		(fp_line
			(start -0.67945 0.3048)
			(end -0.67945 -0.305054)
			(stroke
				(width 0.1)
				(type default)
			)
			(layer "F.Fab")
		)
		(fp_line
			(start -0.12065 0.3048)
			(end -0.67945 0.3048)
			(stroke
				(width 0.1)
				(type default)
			)
			(layer "F.Fab")
		)
		(fp_line
			(start 0.120396 0.3048)
			(end 0.120396 0.2794)
			(stroke
				(width 0.1)
				(type default)
			)
			(layer "F.Fab")
		)
		(fp_line
			(start 0.67945 0.3048)
			(end 0.120396 0.3048)
			(stroke
				(width 0.1)
				(type default)
			)
			(layer "F.Fab")
		)
		(fp_line
			(start -0.12065 0.2794)
			(end -0.12065 0.3048)
			(stroke
				(width 0.1)
				(type default)
			)
			(layer "F.Fab")
		)
		(fp_line
			(start 0.120396 0.2794)
			(end -0.12065 0.2794)
			(stroke
				(width 0.1)
				(type default)
			)
			(layer "F.Fab")
		)
		(fp_line
			(start -0.12065 -0.2794)
			(end 0.12065 -0.2794)
			(stroke
				(width 0.1)
				(type default)
			)
			(layer "F.Fab")
		)
		(fp_line
			(start 0.12065 -0.2794)
			(end 0.12065 -0.3048)
			(stroke
				(width 0.1)
				(type default)
			)
			(layer "F.Fab")
		)
		(fp_line
			(start 0.12065 -0.3048)
			(end 0.67945 -0.3048)
			(stroke
				(width 0.1)
				(type default)
			)
			(layer "F.Fab")
		)
		(fp_line
			(start 0.67945 -0.3048)
			(end 0.67945 0.3048)
			(stroke
				(width 0.1)
				(type default)
			)
			(layer "F.Fab")
		)
		(fp_line
			(start -0.67945 -0.305054)
			(end -0.12065 -0.305054)
			(stroke
				(width 0.1)
				(type default)
			)
			(layer "F.Fab")
		)
		(fp_line
			(start -0.12065 -0.305054)
			(end -0.12065 -0.2794)
			(stroke
				(width 0.1)
				(type default)
			)
			(layer "F.Fab")
		)
		(pad "1" smd circle
			(at -0.40005 0 270)
			(size 0 0)
			(layers "F.Cu" "F.Mask" "F.Paste")
			(net "P5V_AUX_SCALED")
		)
		(pad "2" smd circle
			(at 0.40005 0 270)
			(size 0 0)
			(layers "F.Cu" "F.Mask" "F.Paste")
			(net "GND")
		)
	)
	(footprint ""
		(layer "F.Cu")
		(at 204.752194 -113.876836)
		(property "Reference" "R5955"
			(at 0 0 0)
			(layer "F.SilkS")
			(hide yes)
			(effects
				(font
					(size 1.27 1.27)
				)
			)
		)
		(property "Value" ""
			(at 0 0 0)
			(layer "F.Fab")
			(effects
				(font
					(size 1.27 1.27)
				)
			)
		)
		(duplicate_pad_numbers_are_jumpers no)
		(fp_line
			(start -0.7874 -0.4064)
			(end 0.7874 -0.4064)
			(stroke
				(width 0.1524)
				(type default)
			)
			(layer "F.SilkS")
		)
		(fp_line
			(start -0.7874 0.4064)
			(end -0.7874 -0.4064)
			(stroke
				(width 0.1524)
				(type default)
			)
			(layer "F.SilkS")
		)
		(fp_line
			(start 0.7874 -0.4064)
			(end 0.7874 0.4064)
			(stroke
				(width 0.1524)
				(type default)
			)
			(layer "F.SilkS")
		)
		(fp_line
			(start 0.7874 0.4064)
			(end -0.7874 0.4064)
			(stroke
				(width 0.1524)
				(type default)
			)
			(layer "F.SilkS")
		)
		(fp_line
			(start -0.67945 -0.305054)
			(end -0.12065 -0.305054)
			(stroke
				(width 0.1)
				(type default)
			)
			(layer "F.Fab")
		)
		(fp_line
			(start -0.67945 0.3048)
			(end -0.67945 -0.305054)
			(stroke
				(width 0.1)
				(type default)
			)
			(layer "F.Fab")
		)
		(fp_line
			(start -0.12065 -0.305054)
			(end -0.12065 -0.2794)
			(stroke
				(width 0.1)
				(type default)
			)
			(layer "F.Fab")
		)
		(fp_line
			(start -0.12065 -0.2794)
			(end 0.12065 -0.2794)
			(stroke
				(width 0.1)
				(type default)
			)
			(layer "F.Fab")
		)
		(fp_line
			(start -0.12065 0.2794)
			(end -0.12065 0.3048)
			(stroke
				(width 0.1)
				(type default)
			)
			(layer "F.Fab")
		)
		(fp_line
			(start -0.12065 0.3048)
			(end -0.67945 0.3048)
			(stroke
				(width 0.1)
				(type default)
			)
			(layer "F.Fab")
		)
		(fp_line
			(start 0.120396 0.2794)
			(end -0.12065 0.2794)
			(stroke
				(width 0.1)
				(type default)
			)
			(layer "F.Fab")
		)
		(fp_line
			(start 0.120396 0.3048)
			(end 0.120396 0.2794)
			(stroke
				(width 0.1)
				(type default)
			)
			(layer "F.Fab")
		)
		(fp_line
			(start 0.12065 -0.3048)
			(end 0.67945 -0.3048)
			(stroke
				(width 0.1)
				(type default)
			)
			(layer "F.Fab")
		)
		(fp_line
			(start 0.12065 -0.2794)
			(end 0.12065 -0.3048)
			(stroke
				(width 0.1)
				(type default)
			)
			(layer "F.Fab")
		)
		(fp_line
			(start 0.67945 -0.3048)
			(end 0.67945 0.3048)
			(stroke
				(width 0.1)
				(type default)
			)
			(layer "F.Fab")
		)
		(fp_line
			(start 0.67945 0.3048)
			(end 0.120396 0.3048)
			(stroke
				(width 0.1)
				(type default)
			)
			(layer "F.Fab")
		)
		(pad "1" smd circle
			(at -0.40005 0)
			(size 0 0)
			(layers "F.Cu" "F.Mask" "F.Paste")
			(net "HP_NIC3_EN")
		)
		(pad "2" smd circle
			(at 0.40005 0)
			(size 0 0)
			(layers "F.Cu" "F.Mask" "F.Paste")
			(net "P3V3_NIC3_CO_EN")
		)
	)
	(footprint ""
		(layer "F.Cu")
		(at 378.852684 -81.9658)
		(property "Reference" "R1777"
			(at 0 0 0)
			(layer "F.SilkS")
			(hide yes)
			(effects
				(font
					(size 1.27 1.27)
				)
			)
		)
		(property "Value" ""
			(at 0 0 0)
			(layer "F.Fab")
			(effects
				(font
					(size 1.27 1.27)
				)
			)
		)
		(duplicate_pad_numbers_are_jumpers no)
		(fp_line
			(start -0.7874 -0.4064)
			(end 0.7874 -0.4064)
			(stroke
				(width 0.1524)
				(type default)
			)
			(layer "F.SilkS")
		)
		(fp_line
			(start -0.7874 0.4064)
			(end -0.7874 -0.4064)
			(stroke
				(width 0.1524)
				(type default)
			)
			(layer "F.SilkS")
		)
		(fp_line
			(start 0.7874 -0.4064)
			(end 0.7874 0.4064)
			(stroke
				(width 0.1524)
				(type default)
			)
			(layer "F.SilkS")
		)
		(fp_line
			(start 0.7874 0.4064)
			(end -0.7874 0.4064)
			(stroke
				(width 0.1524)
				(type default)
			)
			(layer "F.SilkS")
		)
		(fp_line
			(start -0.67945 -0.305054)
			(end -0.12065 -0.305054)
			(stroke
				(width 0.1)
				(type default)
			)
			(layer "F.Fab")
		)
		(fp_line
			(start -0.67945 0.3048)
			(end -0.67945 -0.305054)
			(stroke
				(width 0.1)
				(type default)
			)
			(layer "F.Fab")
		)
		(fp_line
			(start -0.12065 -0.305054)
			(end -0.12065 -0.2794)
			(stroke
				(width 0.1)
				(type default)
			)
			(layer "F.Fab")
		)
		(fp_line
			(start -0.12065 -0.2794)
			(end 0.12065 -0.2794)
			(stroke
				(width 0.1)
				(type default)
			)
			(layer "F.Fab")
		)
		(fp_line
			(start -0.12065 0.2794)
			(end -0.12065 0.3048)
			(stroke
				(width 0.1)
				(type default)
			)
			(layer "F.Fab")
		)
		(fp_line
			(start -0.12065 0.3048)
			(end -0.67945 0.3048)
			(stroke
				(width 0.1)
				(type default)
			)
			(layer "F.Fab")
		)
		(fp_line
			(start 0.120396 0.2794)
			(end -0.12065 0.2794)
			(stroke
				(width 0.1)
				(type default)
			)
			(layer "F.Fab")
		)
		(fp_line
			(start 0.120396 0.3048)
			(end 0.120396 0.2794)
			(stroke
				(width 0.1)
				(type default)
			)
			(layer "F.Fab")
		)
		(fp_line
			(start 0.12065 -0.3048)
			(end 0.67945 -0.3048)
			(stroke
				(width 0.1)
				(type default)
			)
			(layer "F.Fab")
		)
		(fp_line
			(start 0.12065 -0.2794)
			(end 0.12065 -0.3048)
			(stroke
				(width 0.1)
				(type default)
			)
			(layer "F.Fab")
		)
		(fp_line
			(start 0.67945 -0.3048)
			(end 0.67945 0.3048)
			(stroke
				(width 0.1)
				(type default)
			)
			(layer "F.Fab")
		)
		(fp_line
			(start 0.67945 0.3048)
			(end 0.120396 0.3048)
			(stroke
				(width 0.1)
				(type default)
			)
			(layer "F.Fab")
		)
		(pad "1" smd circle
			(at -0.40005 0)
			(size 0 0)
			(layers "F.Cu" "F.Mask" "F.Paste")
			(net "SMB_BIC_I2C6_MUX_SSD_0_7_ADC_R_SDA")
		)
		(pad "2" smd circle
			(at 0.40005 0)
			(size 0 0)
			(layers "F.Cu" "F.Mask" "F.Paste")
			(net "SMB_BIC_I2C6_MUX_SSD_0_7_ADC_SDA")
		)
	)
	(footprint ""
		(layer "F.Cu")
		(at 243.248434 -250.759722 90)
		(property "Reference" "R6238"
			(at 0 0 90)
			(layer "F.SilkS")
			(hide yes)
			(effects
				(font
					(size 1.27 1.27)
				)
			)
		)
		(property "Value" ""
			(at 0 0 90)
			(layer "F.Fab")
			(effects
				(font
					(size 1.27 1.27)
				)
			)
		)
		(duplicate_pad_numbers_are_jumpers no)
		(fp_line
			(start 0.7874 -0.4064)
			(end 0.7874 0.4064)
			(stroke
				(width 0.1524)
				(type default)
			)
			(layer "F.SilkS")
		)
		(fp_line
			(start -0.7874 -0.4064)
			(end 0.7874 -0.4064)
			(stroke
				(width 0.1524)
				(type default)
			)
			(layer "F.SilkS")
		)
		(fp_line
			(start 0.7874 0.4064)
			(end -0.7874 0.4064)
			(stroke
				(width 0.1524)
				(type default)
			)
			(layer "F.SilkS")
		)
		(fp_line
			(start -0.7874 0.4064)
			(end -0.7874 -0.4064)
			(stroke
				(width 0.1524)
				(type default)
			)
			(layer "F.SilkS")
		)
		(fp_line
			(start -0.12065 -0.305054)
			(end -0.12065 -0.2794)
			(stroke
				(width 0.1)
				(type default)
			)
			(layer "F.Fab")
		)
		(fp_line
			(start -0.67945 -0.305054)
			(end -0.12065 -0.305054)
			(stroke
				(width 0.1)
				(type default)
			)
			(layer "F.Fab")
		)
		(fp_line
			(start 0.67945 -0.3048)
			(end 0.67945 0.3048)
			(stroke
				(width 0.1)
				(type default)
			)
			(layer "F.Fab")
		)
		(fp_line
			(start 0.12065 -0.3048)
			(end 0.67945 -0.3048)
			(stroke
				(width 0.1)
				(type default)
			)
			(layer "F.Fab")
		)
		(fp_line
			(start 0.12065 -0.2794)
			(end 0.12065 -0.3048)
			(stroke
				(width 0.1)
				(type default)
			)
			(layer "F.Fab")
		)
		(fp_line
			(start -0.12065 -0.2794)
			(end 0.12065 -0.2794)
			(stroke
				(width 0.1)
				(type default)
			)
			(layer "F.Fab")
		)
		(fp_line
			(start 0.120396 0.2794)
			(end -0.12065 0.2794)
			(stroke
				(width 0.1)
				(type default)
			)
			(layer "F.Fab")
		)
		(fp_line
			(start -0.12065 0.2794)
			(end -0.12065 0.3048)
			(stroke
				(width 0.1)
				(type default)
			)
			(layer "F.Fab")
		)
		(fp_line
			(start 0.67945 0.3048)
			(end 0.120396 0.3048)
			(stroke
				(width 0.1)
				(type default)
			)
			(layer "F.Fab")
		)
		(fp_line
			(start 0.120396 0.3048)
			(end 0.120396 0.2794)
			(stroke
				(width 0.1)
				(type default)
			)
			(layer "F.Fab")
		)
		(fp_line
			(start -0.12065 0.3048)
			(end -0.67945 0.3048)
			(stroke
				(width 0.1)
				(type default)
			)
			(layer "F.Fab")
		)
		(fp_line
			(start -0.67945 0.3048)
			(end -0.67945 -0.305054)
			(stroke
				(width 0.1)
				(type default)
			)
			(layer "F.Fab")
		)
		(pad "1" smd circle
			(at -0.40005 0 90)
			(size 0 0)
			(layers "F.Cu" "F.Mask" "F.Paste")
			(net "BIC_RECOVER_IOEXP_A1")
		)
		(pad "2" smd circle
			(at 0.40005 0 90)
			(size 0 0)
			(layers "F.Cu" "F.Mask" "F.Paste")
			(net "GND")
		)
	)
	(footprint ""
		(layer "F.Cu")
		(at 338.074 -155.702 180)
		(property "Reference" "R4816"
			(at 0 0 180)
			(layer "F.SilkS")
			(hide yes)
			(effects
				(font
					(size 1.27 1.27)
				)
			)
		)
		(property "Value" ""
			(at 0 0 180)
			(layer "F.Fab")
			(effects
				(font
					(size 1.27 1.27)
				)
			)
		)
		(duplicate_pad_numbers_are_jumpers no)
		(fp_line
			(start 0.7874 0.4064)
			(end -0.7874 0.4064)
			(stroke
				(width 0.1524)
				(type default)
			)
			(layer "F.SilkS")
		)
		(fp_line
			(start 0.7874 -0.4064)
			(end 0.7874 0.4064)
			(stroke
				(width 0.1524)
				(type default)
			)
			(layer "F.SilkS")
		)
		(fp_line
			(start -0.7874 0.4064)
			(end -0.7874 -0.4064)
			(stroke
				(width 0.1524)
				(type default)
			)
			(layer "F.SilkS")
		)
		(fp_line
			(start -0.7874 -0.4064)
			(end 0.7874 -0.4064)
			(stroke
				(width 0.1524)
				(type default)
			)
			(layer "F.SilkS")
		)
		(fp_line
			(start 0.67945 0.3048)
			(end 0.120396 0.3048)
			(stroke
				(width 0.1)
				(type default)
			)
			(layer "F.Fab")
		)
		(fp_line
			(start 0.67945 -0.3048)
			(end 0.67945 0.3048)
			(stroke
				(width 0.1)
				(type default)
			)
			(layer "F.Fab")
		)
		(fp_line
			(start 0.12065 -0.2794)
			(end 0.12065 -0.3048)
			(stroke
				(width 0.1)
				(type default)
			)
			(layer "F.Fab")
		)
		(fp_line
			(start 0.12065 -0.3048)
			(end 0.67945 -0.3048)
			(stroke
				(width 0.1)
				(type default)
			)
			(layer "F.Fab")
		)
		(fp_line
			(start 0.120396 0.3048)
			(end 0.120396 0.2794)
			(stroke
				(width 0.1)
				(type default)
			)
			(layer "F.Fab")
		)
		(fp_line
			(start 0.120396 0.2794)
			(end -0.12065 0.2794)
			(stroke
				(width 0.1)
				(type default)
			)
			(layer "F.Fab")
		)
		(fp_line
			(start -0.12065 0.3048)
			(end -0.67945 0.3048)
			(stroke
				(width 0.1)
				(type default)
			)
			(layer "F.Fab")
		)
		(fp_line
			(start -0.12065 0.2794)
			(end -0.12065 0.3048)
			(stroke
				(width 0.1)
				(type default)
			)
			(layer "F.Fab")
		)
		(fp_line
			(start -0.12065 -0.2794)
			(end 0.12065 -0.2794)
			(stroke
				(width 0.1)
				(type default)
			)
			(layer "F.Fab")
		)
		(fp_line
			(start -0.12065 -0.305054)
			(end -0.12065 -0.2794)
			(stroke
				(width 0.1)
				(type default)
			)
			(layer "F.Fab")
		)
		(fp_line
			(start -0.67945 0.3048)
			(end -0.67945 -0.305054)
			(stroke
				(width 0.1)
				(type default)
			)
			(layer "F.Fab")
		)
		(fp_line
			(start -0.67945 -0.305054)
			(end -0.12065 -0.305054)
			(stroke
				(width 0.1)
				(type default)
			)
			(layer "F.Fab")
		)
		(pad "1" smd circle
			(at -0.40005 0 180)
			(size 0 0)
			(layers "F.Cu" "F.Mask" "F.Paste")
			(net "PRSNT_SSD13_FPGA_PCA9555_N")
		)
		(pad "2" smd circle
			(at 0.40005 0 180)
			(size 0 0)
			(layers "F.Cu" "F.Mask" "F.Paste")
			(net "PRSNT_SSD13_FPGA_R_N")
		)
	)
	(footprint ""
		(layer "F.Cu")
		(at 262.353298 -284.990032)
		(property "Reference" "L127"
			(at 0 0 0)
			(layer "F.SilkS")
			(hide yes)
			(effects
				(font
					(size 1.27 1.27)
				)
			)
		)
		(property "Value" ""
			(at 0 0 0)
			(layer "F.Fab")
			(effects
				(font
					(size 1.27 1.27)
				)
			)
		)
		(duplicate_pad_numbers_are_jumpers no)
		(fp_line
			(start -1.63576 -0.8128)
			(end -1.63576 0.8128)
			(stroke
				(width 0.1524)
				(type default)
			)
			(layer "F.SilkS")
		)
		(fp_line
			(start -1.63576 -0.8128)
			(end 1.63576 -0.8128)
			(stroke
				(width 0.1524)
				(type default)
			)
			(layer "F.SilkS")
		)
		(fp_line
			(start 1.63576 -0.8128)
			(end 1.63576 0.8128)
			(stroke
				(width 0.1524)
				(type default)
			)
			(layer "F.SilkS")
		)
		(fp_line
			(start 1.63576 0.8128)
			(end -1.63576 0.8128)
			(stroke
				(width 0.1524)
				(type default)
			)
			(layer "F.SilkS")
		)
		(fp_line
			(start -1.56083 -0.738632)
			(end -1.56083 0.7366)
			(stroke
				(width 0.1)
				(type default)
			)
			(layer "F.Fab")
		)
		(fp_line
			(start -1.56083 0.7366)
			(end -1.524 0.7366)
			(stroke
				(width 0.1)
				(type default)
			)
			(layer "F.Fab")
		)
		(fp_line
			(start -1.524 0.7366)
			(end 1.524 0.7366)
			(stroke
				(width 0.1)
				(type default)
			)
			(layer "F.Fab")
		)
		(fp_line
			(start 1.524 0.7366)
			(end 1.560576 0.7366)
			(stroke
				(width 0.1)
				(type default)
			)
			(layer "F.Fab")
		)
		(fp_line
			(start 1.560576 -0.738632)
			(end -1.56083 -0.738632)
			(stroke
				(width 0.1)
				(type default)
			)
			(layer "F.Fab")
		)
		(fp_line
			(start 1.560576 0.7366)
			(end 1.560576 -0.738632)
			(stroke
				(width 0.1)
				(type default)
			)
			(layer "F.Fab")
		)
		(pad "1" smd rect
			(at -0.94996 0 180)
			(size 1.1176 1.3716)
			(layers "F.Cu" "F.Mask" "F.Paste")
			(net "P1V8_PLL0_PEX2")
		)
		(pad "2" smd rect
			(at 0.94996 0 180)
			(size 1.1176 1.3716)
			(layers "F.Cu" "F.Mask" "F.Paste")
			(net "PCEPLL7_VDDA18_PEX2")
		)
	)
	(footprint ""
		(layer "F.Cu")
		(at 139.817348 -350.098614 90)
		(property "Reference" "C2247"
			(at 0 0 90)
			(layer "F.SilkS")
			(hide yes)
			(effects
				(font
					(size 1.27 1.27)
				)
			)
		)
		(property "Value" ""
			(at 0 0 90)
			(layer "F.Fab")
			(effects
				(font
					(size 1.27 1.27)
				)
			)
		)
		(duplicate_pad_numbers_are_jumpers no)
		(fp_line
			(start 0.299974 -0.150114)
			(end 0.299974 0.150114)
			(stroke
				(width 0.1)
				(type default)
			)
			(layer "F.Fab")
		)
		(fp_line
			(start -0.299974 -0.150114)
			(end 0.299974 -0.150114)
			(stroke
				(width 0.1)
				(type default)
			)
			(layer "F.Fab")
		)
		(fp_line
			(start 0.299974 0.150114)
			(end -0.299974 0.150114)
			(stroke
				(width 0.1)
				(type default)
			)
			(layer "F.Fab")
		)
		(fp_line
			(start -0.299974 0.150114)
			(end -0.299974 -0.150114)
			(stroke
				(width 0.1)
				(type default)
			)
			(layer "F.Fab")
		)
		(pad "1" smd rect
			(at -0.2667 0 90)
			(size 0.3048 0.381)
			(layers "F.Cu" "F.Mask" "F.Paste")
			(net "P5E_PEX1_STN5_TX_DP<93>")
		)
		(pad "2" smd rect
			(at 0.2667 0 90)
			(size 0.3048 0.381)
			(layers "F.Cu" "F.Mask" "F.Paste")
			(net "P5E_PEX1_STN5_TX_C_DP<93>")
		)
	)
	(footprint ""
		(layer "F.Cu")
		(at 241.38509 -209.513678 90)
		(property "Reference" "R473"
			(at 0 0 90)
			(layer "F.SilkS")
			(hide yes)
			(effects
				(font
					(size 1.27 1.27)
				)
			)
		)
		(property "Value" ""
			(at 0 0 90)
			(layer "F.Fab")
			(effects
				(font
					(size 1.27 1.27)
				)
			)
		)
		(duplicate_pad_numbers_are_jumpers no)
		(fp_line
			(start 0.7874 -0.4064)
			(end 0.7874 0.4064)
			(stroke
				(width 0.1524)
				(type default)
			)
			(layer "F.SilkS")
		)
		(fp_line
			(start -0.7874 -0.4064)
			(end 0.7874 -0.4064)
			(stroke
				(width 0.1524)
				(type default)
			)
			(layer "F.SilkS")
		)
		(fp_line
			(start 0.7874 0.4064)
			(end -0.7874 0.4064)
			(stroke
				(width 0.1524)
				(type default)
			)
			(layer "F.SilkS")
		)
		(fp_line
			(start -0.7874 0.4064)
			(end -0.7874 -0.4064)
			(stroke
				(width 0.1524)
				(type default)
			)
			(layer "F.SilkS")
		)
		(fp_line
			(start -0.12065 -0.305054)
			(end -0.12065 -0.2794)
			(stroke
				(width 0.1)
				(type default)
			)
			(layer "F.Fab")
		)
		(fp_line
			(start -0.67945 -0.305054)
			(end -0.12065 -0.305054)
			(stroke
				(width 0.1)
				(type default)
			)
			(layer "F.Fab")
		)
		(fp_line
			(start 0.67945 -0.3048)
			(end 0.67945 0.3048)
			(stroke
				(width 0.1)
				(type default)
			)
			(layer "F.Fab")
		)
		(fp_line
			(start 0.12065 -0.3048)
			(end 0.67945 -0.3048)
			(stroke
				(width 0.1)
				(type default)
			)
			(layer "F.Fab")
		)
		(fp_line
			(start 0.12065 -0.2794)
			(end 0.12065 -0.3048)
			(stroke
				(width 0.1)
				(type default)
			)
			(layer "F.Fab")
		)
		(fp_line
			(start -0.12065 -0.2794)
			(end 0.12065 -0.2794)
			(stroke
				(width 0.1)
				(type default)
			)
			(layer "F.Fab")
		)
		(fp_line
			(start 0.120396 0.2794)
			(end -0.12065 0.2794)
			(stroke
				(width 0.1)
				(type default)
			)
			(layer "F.Fab")
		)
		(fp_line
			(start -0.12065 0.2794)
			(end -0.12065 0.3048)
			(stroke
				(width 0.1)
				(type default)
			)
			(layer "F.Fab")
		)
		(fp_line
			(start 0.67945 0.3048)
			(end 0.120396 0.3048)
			(stroke
				(width 0.1)
				(type default)
			)
			(layer "F.Fab")
		)
		(fp_line
			(start 0.120396 0.3048)
			(end 0.120396 0.2794)
			(stroke
				(width 0.1)
				(type default)
			)
			(layer "F.Fab")
		)
		(fp_line
			(start -0.12065 0.3048)
			(end -0.67945 0.3048)
			(stroke
				(width 0.1)
				(type default)
			)
			(layer "F.Fab")
		)
		(fp_line
			(start -0.67945 0.3048)
			(end -0.67945 -0.305054)
			(stroke
				(width 0.1)
				(type default)
			)
			(layer "F.Fab")
		)
		(pad "1" smd circle
			(at -0.40005 0 90)
			(size 0 0)
			(layers "F.Cu" "F.Mask" "F.Paste")
			(net "P5V_AUX")
		)
		(pad "2" smd circle
			(at 0.40005 0 90)
			(size 0 0)
			(layers "F.Cu" "F.Mask" "F.Paste")
			(net "P5V_AUX_SCALED")
		)
	)
	(footprint ""
		(layer "F.Cu")
		(at 217.254074 -210.176872)
		(property "Reference" "R5721"
			(at 0 0 0)
			(layer "F.SilkS")
			(hide yes)
			(effects
				(font
					(size 1.27 1.27)
				)
			)
		)
		(property "Value" ""
			(at 0 0 0)
			(layer "F.Fab")
			(effects
				(font
					(size 1.27 1.27)
				)
			)
		)
		(duplicate_pad_numbers_are_jumpers no)
		(fp_line
			(start -0.7874 -0.4064)
			(end 0.7874 -0.4064)
			(stroke
				(width 0.1524)
				(type default)
			)
			(layer "F.SilkS")
		)
		(fp_line
			(start -0.7874 0.4064)
			(end -0.7874 -0.4064)
			(stroke
				(width 0.1524)
				(type default)
			)
			(layer "F.SilkS")
		)
		(fp_line
			(start 0.7874 -0.4064)
			(end 0.7874 0.4064)
			(stroke
				(width 0.1524)
				(type default)
			)
			(layer "F.SilkS")
		)
		(fp_line
			(start 0.7874 0.4064)
			(end -0.7874 0.4064)
			(stroke
				(width 0.1524)
				(type default)
			)
			(layer "F.SilkS")
		)
		(fp_line
			(start -0.67945 -0.305054)
			(end -0.12065 -0.305054)
			(stroke
				(width 0.1)
				(type default)
			)
			(layer "F.Fab")
		)
		(fp_line
			(start -0.67945 0.3048)
			(end -0.67945 -0.305054)
			(stroke
				(width 0.1)
				(type default)
			)
			(layer "F.Fab")
		)
		(fp_line
			(start -0.12065 -0.305054)
			(end -0.12065 -0.2794)
			(stroke
				(width 0.1)
				(type default)
			)
			(layer "F.Fab")
		)
		(fp_line
			(start -0.12065 -0.2794)
			(end 0.12065 -0.2794)
			(stroke
				(width 0.1)
				(type default)
			)
			(layer "F.Fab")
		)
		(fp_line
			(start -0.12065 0.2794)
			(end -0.12065 0.3048)
			(stroke
				(width 0.1)
				(type default)
			)
			(layer "F.Fab")
		)
		(fp_line
			(start -0.12065 0.3048)
			(end -0.67945 0.3048)
			(stroke
				(width 0.1)
				(type default)
			)
			(layer "F.Fab")
		)
		(fp_line
			(start 0.120396 0.2794)
			(end -0.12065 0.2794)
			(stroke
				(width 0.1)
				(type default)
			)
			(layer "F.Fab")
		)
		(fp_line
			(start 0.120396 0.3048)
			(end 0.120396 0.2794)
			(stroke
				(width 0.1)
				(type default)
			)
			(layer "F.Fab")
		)
		(fp_line
			(start 0.12065 -0.3048)
			(end 0.67945 -0.3048)
			(stroke
				(width 0.1)
				(type default)
			)
			(layer "F.Fab")
		)
		(fp_line
			(start 0.12065 -0.2794)
			(end 0.12065 -0.3048)
			(stroke
				(width 0.1)
				(type default)
			)
			(layer "F.Fab")
		)
		(fp_line
			(start 0.67945 -0.3048)
			(end 0.67945 0.3048)
			(stroke
				(width 0.1)
				(type default)
			)
			(layer "F.Fab")
		)
		(fp_line
			(start 0.67945 0.3048)
			(end 0.120396 0.3048)
			(stroke
				(width 0.1)
				(type default)
			)
			(layer "F.Fab")
		)
		(pad "1" smd circle
			(at -0.40005 0)
			(size 0 0)
			(layers "F.Cu" "F.Mask" "F.Paste")
			(net "RST_SSD_LED_IOEXP_R_N")
		)
		(pad "2" smd circle
			(at 0.40005 0)
			(size 0 0)
			(layers "F.Cu" "F.Mask" "F.Paste")
			(net "RST_SSD_LED_IOEXP_N")
		)
	)
	(footprint ""
		(layer "F.Cu")
		(at 372.642384 -250.070874 -90)
		(property "Reference" "R1414"
			(at 0 0 270)
			(layer "F.SilkS")
			(hide yes)
			(effects
				(font
					(size 1.27 1.27)
				)
			)
		)
		(property "Value" ""
			(at 0 0 270)
			(layer "F.Fab")
			(effects
				(font
					(size 1.27 1.27)
				)
			)
		)
		(duplicate_pad_numbers_are_jumpers no)
		(fp_line
			(start -0.7874 0.4064)
			(end -0.7874 -0.4064)
			(stroke
				(width 0.1524)
				(type default)
			)
			(layer "F.SilkS")
		)
		(fp_line
			(start 0.7874 0.4064)
			(end -0.7874 0.4064)
			(stroke
				(width 0.1524)
				(type default)
			)
			(layer "F.SilkS")
		)
		(fp_line
			(start -0.7874 -0.4064)
			(end 0.7874 -0.4064)
			(stroke
				(width 0.1524)
				(type default)
			)
			(layer "F.SilkS")
		)
		(fp_line
			(start 0.7874 -0.4064)
			(end 0.7874 0.4064)
			(stroke
				(width 0.1524)
				(type default)
			)
			(layer "F.SilkS")
		)
		(fp_line
			(start -0.67945 0.3048)
			(end -0.67945 -0.305054)
			(stroke
				(width 0.1)
				(type default)
			)
			(layer "F.Fab")
		)
		(fp_line
			(start -0.12065 0.3048)
			(end -0.67945 0.3048)
			(stroke
				(width 0.1)
				(type default)
			)
			(layer "F.Fab")
		)
		(fp_line
			(start 0.120396 0.3048)
			(end 0.120396 0.2794)
			(stroke
				(width 0.1)
				(type default)
			)
			(layer "F.Fab")
		)
		(fp_line
			(start 0.67945 0.3048)
			(end 0.120396 0.3048)
			(stroke
				(width 0.1)
				(type default)
			)
			(layer "F.Fab")
		)
		(fp_line
			(start -0.12065 0.2794)
			(end -0.12065 0.3048)
			(stroke
				(width 0.1)
				(type default)
			)
			(layer "F.Fab")
		)
		(fp_line
			(start 0.120396 0.2794)
			(end -0.12065 0.2794)
			(stroke
				(width 0.1)
				(type default)
			)
			(layer "F.Fab")
		)
		(fp_line
			(start -0.12065 -0.2794)
			(end 0.12065 -0.2794)
			(stroke
				(width 0.1)
				(type default)
			)
			(layer "F.Fab")
		)
		(fp_line
			(start 0.12065 -0.2794)
			(end 0.12065 -0.3048)
			(stroke
				(width 0.1)
				(type default)
			)
			(layer "F.Fab")
		)
		(fp_line
			(start 0.12065 -0.3048)
			(end 0.67945 -0.3048)
			(stroke
				(width 0.1)
				(type default)
			)
			(layer "F.Fab")
		)
		(fp_line
			(start 0.67945 -0.3048)
			(end 0.67945 0.3048)
			(stroke
				(width 0.1)
				(type default)
			)
			(layer "F.Fab")
		)
		(fp_line
			(start -0.67945 -0.305054)
			(end -0.12065 -0.305054)
			(stroke
				(width 0.1)
				(type default)
			)
			(layer "F.Fab")
		)
		(fp_line
			(start -0.12065 -0.305054)
			(end -0.12065 -0.2794)
			(stroke
				(width 0.1)
				(type default)
			)
			(layer "F.Fab")
		)
		(pad "1" smd circle
			(at -0.40005 0 270)
			(size 0 0)
			(layers "F.Cu" "F.Mask" "F.Paste")
			(net "PEX3_MODE_SEL9")
		)
		(pad "2" smd circle
			(at 0.40005 0 270)
			(size 0 0)
			(layers "F.Cu" "F.Mask" "F.Paste")
			(net "P1V8_PEX")
		)
	)
	(footprint ""
		(layer "F.Cu")
		(at 461.011524 -553.91304 180)
		(property "Reference" "SCREW_SSD14_1"
			(at -5.6007 -1.402334 0)
			(unlocked yes)
			(layer "B.SilkS")
			(effects
				(font
					(size 0.7874 0.5842)
					(thickness 0.1524)
				)
				(justify mirror)
			)
		)
		(property "Value" ""
			(at 0 0 180)
			(layer "F.Fab")
			(effects
				(font
					(size 1.27 1.27)
				)
			)
		)
		(duplicate_pad_numbers_are_jumpers no)
		(pad "1" thru_hole circle
			(at 0 0 180)
			(size 0.4572 0.4572)
			(drill 0.2032)
			(layers "*.Cu" "*.Mask")
			(remove_unused_layers no)
			(net "Net_9146")
			(clearance 0.127)
			(thermal_gap 0.127)
			(padstack
				(mode front_inner_back)
				(layer "Inner"
					(shape circle)
					(size 0.4572 0.4572)
					(clearance 0.127)
				)
				(layer "B.Cu"
					(shape circle)
					(size 0.508 0.508)
					(clearance 0.1016)
				)
			)
		)
	)
	(footprint ""
		(layer "F.Cu")
		(at 194.367912 -51.019456)
		(property "Reference" "PC387"
			(at 0 0 0)
			(layer "F.SilkS")
			(hide yes)
			(effects
				(font
					(size 1.27 1.27)
				)
			)
		)
		(property "Value" ""
			(at 0 0 0)
			(layer "F.Fab")
			(effects
				(font
					(size 1.27 1.27)
				)
			)
		)
		(duplicate_pad_numbers_are_jumpers no)
		(fp_line
			(start -0.7874 -0.4064)
			(end 0.7874 -0.4064)
			(stroke
				(width 0.1524)
				(type default)
			)
			(layer "F.SilkS")
		)
		(fp_line
			(start -0.7874 0.4064)
			(end -0.7874 -0.4064)
			(stroke
				(width 0.1524)
				(type default)
			)
			(layer "F.SilkS")
		)
		(fp_line
			(start 0.7874 -0.4064)
			(end 0.7874 0.4064)
			(stroke
				(width 0.1524)
				(type default)
			)
			(layer "F.SilkS")
		)
		(fp_line
			(start 0.7874 0.4064)
			(end -0.7874 0.4064)
			(stroke
				(width 0.1524)
				(type default)
			)
			(layer "F.SilkS")
		)
		(fp_line
			(start -0.67945 -0.305054)
			(end -0.12065 -0.305054)
			(stroke
				(width 0.1)
				(type default)
			)
			(layer "F.Fab")
		)
		(fp_line
			(start -0.67945 0.3048)
			(end -0.67945 -0.305054)
			(stroke
				(width 0.1)
				(type default)
			)
			(layer "F.Fab")
		)
		(fp_line
			(start -0.12065 -0.305054)
			(end -0.12065 -0.2794)
			(stroke
				(width 0.1)
				(type default)
			)
			(layer "F.Fab")
		)
		(fp_line
			(start -0.12065 -0.2794)
			(end 0.12065 -0.2794)
			(stroke
				(width 0.1)
				(type default)
			)
			(layer "F.Fab")
		)
		(fp_line
			(start -0.12065 0.2794)
			(end -0.12065 0.3048)
			(stroke
				(width 0.1)
				(type default)
			)
			(layer "F.Fab")
		)
		(fp_line
			(start -0.12065 0.3048)
			(end -0.67945 0.3048)
			(stroke
				(width 0.1)
				(type default)
			)
			(layer "F.Fab")
		)
		(fp_line
			(start 0.120396 0.2794)
			(end -0.12065 0.2794)
			(stroke
				(width 0.1)
				(type default)
			)
			(layer "F.Fab")
		)
		(fp_line
			(start 0.120396 0.3048)
			(end 0.120396 0.2794)
			(stroke
				(width 0.1)
				(type default)
			)
			(layer "F.Fab")
		)
		(fp_line
			(start 0.12065 -0.3048)
			(end 0.67945 -0.3048)
			(stroke
				(width 0.1)
				(type default)
			)
			(layer "F.Fab")
		)
		(fp_line
			(start 0.12065 -0.2794)
			(end 0.12065 -0.3048)
			(stroke
				(width 0.1)
				(type default)
			)
			(layer "F.Fab")
		)
		(fp_line
			(start 0.67945 -0.3048)
			(end 0.67945 0.3048)
			(stroke
				(width 0.1)
				(type default)
			)
			(layer "F.Fab")
		)
		(fp_line
			(start 0.67945 0.3048)
			(end 0.120396 0.3048)
			(stroke
				(width 0.1)
				(type default)
			)
			(layer "F.Fab")
		)
		(pad "1" smd circle
			(at -0.40005 0)
			(size 0 0)
			(layers "F.Cu" "F.Mask" "F.Paste")
			(net "P12V_SSD6_SS")
		)
		(pad "2" smd circle
			(at 0.40005 0)
			(size 0 0)
			(layers "F.Cu" "F.Mask" "F.Paste")
			(net "GND")
		)
	)
	(footprint ""
		(layer "F.Cu")
		(at 322.65366 -233.414824)
		(property "Reference" "R5646"
			(at 0 0 0)
			(layer "F.SilkS")
			(hide yes)
			(effects
				(font
					(size 1.27 1.27)
				)
			)
		)
		(property "Value" ""
			(at 0 0 0)
			(layer "F.Fab")
			(effects
				(font
					(size 1.27 1.27)
				)
			)
		)
		(duplicate_pad_numbers_are_jumpers no)
		(fp_line
			(start -0.7874 -0.4064)
			(end 0.7874 -0.4064)
			(stroke
				(width 0.1524)
				(type default)
			)
			(layer "F.SilkS")
		)
		(fp_line
			(start -0.7874 0.4064)
			(end -0.7874 -0.4064)
			(stroke
				(width 0.1524)
				(type default)
			)
			(layer "F.SilkS")
		)
		(fp_line
			(start 0.7874 -0.4064)
			(end 0.7874 0.4064)
			(stroke
				(width 0.1524)
				(type default)
			)
			(layer "F.SilkS")
		)
		(fp_line
			(start 0.7874 0.4064)
			(end -0.7874 0.4064)
			(stroke
				(width 0.1524)
				(type default)
			)
			(layer "F.SilkS")
		)
		(fp_line
			(start -0.67945 -0.305054)
			(end -0.12065 -0.305054)
			(stroke
				(width 0.1)
				(type default)
			)
			(layer "F.Fab")
		)
		(fp_line
			(start -0.67945 0.3048)
			(end -0.67945 -0.305054)
			(stroke
				(width 0.1)
				(type default)
			)
			(layer "F.Fab")
		)
		(fp_line
			(start -0.12065 -0.305054)
			(end -0.12065 -0.2794)
			(stroke
				(width 0.1)
				(type default)
			)
			(layer "F.Fab")
		)
		(fp_line
			(start -0.12065 -0.2794)
			(end 0.12065 -0.2794)
			(stroke
				(width 0.1)
				(type default)
			)
			(layer "F.Fab")
		)
		(fp_line
			(start -0.12065 0.2794)
			(end -0.12065 0.3048)
			(stroke
				(width 0.1)
				(type default)
			)
			(layer "F.Fab")
		)
		(fp_line
			(start -0.12065 0.3048)
			(end -0.67945 0.3048)
			(stroke
				(width 0.1)
				(type default)
			)
			(layer "F.Fab")
		)
		(fp_line
			(start 0.120396 0.2794)
			(end -0.12065 0.2794)
			(stroke
				(width 0.1)
				(type default)
			)
			(layer "F.Fab")
		)
		(fp_line
			(start 0.120396 0.3048)
			(end 0.120396 0.2794)
			(stroke
				(width 0.1)
				(type default)
			)
			(layer "F.Fab")
		)
		(fp_line
			(start 0.12065 -0.3048)
			(end 0.67945 -0.3048)
			(stroke
				(width 0.1)
				(type default)
			)
			(layer "F.Fab")
		)
		(fp_line
			(start 0.12065 -0.2794)
			(end 0.12065 -0.3048)
			(stroke
				(width 0.1)
				(type default)
			)
			(layer "F.Fab")
		)
		(fp_line
			(start 0.67945 -0.3048)
			(end 0.67945 0.3048)
			(stroke
				(width 0.1)
				(type default)
			)
			(layer "F.Fab")
		)
		(fp_line
			(start 0.67945 0.3048)
			(end 0.120396 0.3048)
			(stroke
				(width 0.1)
				(type default)
			)
			(layer "F.Fab")
		)
		(pad "1" smd circle
			(at -0.40005 0)
			(size 0 0)
			(layers "F.Cu" "F.Mask" "F.Paste")
			(net "SMB_MB_R_SCL")
		)
		(pad "2" smd circle
			(at 0.40005 0)
			(size 0 0)
			(layers "F.Cu" "F.Mask" "F.Paste")
			(net "SMB_MB_BMC_ISO_FPGA_SCL")
		)
	)
	(footprint ""
		(layer "F.Cu")
		(at 112.311942 -107.848654 180)
		(property "Reference" "R906"
			(at 0 0 180)
			(layer "F.SilkS")
			(hide yes)
			(effects
				(font
					(size 1.27 1.27)
				)
			)
		)
		(property "Value" ""
			(at 0 0 180)
			(layer "F.Fab")
			(effects
				(font
					(size 1.27 1.27)
				)
			)
		)
		(duplicate_pad_numbers_are_jumpers no)
		(fp_line
			(start 0.7874 0.4064)
			(end -0.7874 0.4064)
			(stroke
				(width 0.1524)
				(type default)
			)
			(layer "F.SilkS")
		)
		(fp_line
			(start 0.7874 -0.4064)
			(end 0.7874 0.4064)
			(stroke
				(width 0.1524)
				(type default)
			)
			(layer "F.SilkS")
		)
		(fp_line
			(start -0.7874 0.4064)
			(end -0.7874 -0.4064)
			(stroke
				(width 0.1524)
				(type default)
			)
			(layer "F.SilkS")
		)
		(fp_line
			(start -0.7874 -0.4064)
			(end 0.7874 -0.4064)
			(stroke
				(width 0.1524)
				(type default)
			)
			(layer "F.SilkS")
		)
		(fp_line
			(start 0.67945 0.3048)
			(end 0.120396 0.3048)
			(stroke
				(width 0.1)
				(type default)
			)
			(layer "F.Fab")
		)
		(fp_line
			(start 0.67945 -0.3048)
			(end 0.67945 0.3048)
			(stroke
				(width 0.1)
				(type default)
			)
			(layer "F.Fab")
		)
		(fp_line
			(start 0.12065 -0.2794)
			(end 0.12065 -0.3048)
			(stroke
				(width 0.1)
				(type default)
			)
			(layer "F.Fab")
		)
		(fp_line
			(start 0.12065 -0.3048)
			(end 0.67945 -0.3048)
			(stroke
				(width 0.1)
				(type default)
			)
			(layer "F.Fab")
		)
		(fp_line
			(start 0.120396 0.3048)
			(end 0.120396 0.2794)
			(stroke
				(width 0.1)
				(type default)
			)
			(layer "F.Fab")
		)
		(fp_line
			(start 0.120396 0.2794)
			(end -0.12065 0.2794)
			(stroke
				(width 0.1)
				(type default)
			)
			(layer "F.Fab")
		)
		(fp_line
			(start -0.12065 0.3048)
			(end -0.67945 0.3048)
			(stroke
				(width 0.1)
				(type default)
			)
			(layer "F.Fab")
		)
		(fp_line
			(start -0.12065 0.2794)
			(end -0.12065 0.3048)
			(stroke
				(width 0.1)
				(type default)
			)
			(layer "F.Fab")
		)
		(fp_line
			(start -0.12065 -0.2794)
			(end 0.12065 -0.2794)
			(stroke
				(width 0.1)
				(type default)
			)
			(layer "F.Fab")
		)
		(fp_line
			(start -0.12065 -0.305054)
			(end -0.12065 -0.2794)
			(stroke
				(width 0.1)
				(type default)
			)
			(layer "F.Fab")
		)
		(fp_line
			(start -0.67945 0.3048)
			(end -0.67945 -0.305054)
			(stroke
				(width 0.1)
				(type default)
			)
			(layer "F.Fab")
		)
		(fp_line
			(start -0.67945 -0.305054)
			(end -0.12065 -0.305054)
			(stroke
				(width 0.1)
				(type default)
			)
			(layer "F.Fab")
		)
		(pad "1" smd circle
			(at -0.40005 0 180)
			(size 0 0)
			(layers "F.Cu" "F.Mask" "F.Paste")
			(net "HP_NIC1_EN")
		)
		(pad "2" smd circle
			(at 0.40005 0 180)
			(size 0 0)
			(layers "F.Cu" "F.Mask" "F.Paste")
			(net "P12V_NIC1_CO_EN")
		)
	)
	(footprint ""
		(layer "F.Cu")
		(at 394.734542 -30.94609 180)
		(property "Reference" "C710"
			(at 0 0 180)
			(layer "F.SilkS")
			(hide yes)
			(effects
				(font
					(size 1.27 1.27)
				)
			)
		)
		(property "Value" ""
			(at 0 0 180)
			(layer "F.Fab")
			(effects
				(font
					(size 1.27 1.27)
				)
			)
		)
		(duplicate_pad_numbers_are_jumpers no)
		(fp_line
			(start 0.299974 0.150114)
			(end -0.299974 0.150114)
			(stroke
				(width 0.1)
				(type default)
			)
			(layer "F.Fab")
		)
		(fp_line
			(start 0.299974 -0.150114)
			(end 0.299974 0.150114)
			(stroke
				(width 0.1)
				(type default)
			)
			(layer "F.Fab")
		)
		(fp_line
			(start -0.299974 0.150114)
			(end -0.299974 -0.150114)
			(stroke
				(width 0.1)
				(type default)
			)
			(layer "F.Fab")
		)
		(fp_line
			(start -0.299974 -0.150114)
			(end 0.299974 -0.150114)
			(stroke
				(width 0.1)
				(type default)
			)
			(layer "F.Fab")
		)
		(pad "1" smd rect
			(at -0.2667 0 180)
			(size 0.3048 0.381)
			(layers "F.Cu" "F.Mask" "F.Paste")
			(net "P5E_PEX3_STN2_TX_DP<41>")
		)
		(pad "2" smd rect
			(at 0.2667 0 180)
			(size 0.3048 0.381)
			(layers "F.Cu" "F.Mask" "F.Paste")
			(net "P5E_PEX3_STN2_TX_C_DP<41>")
		)
	)
	(footprint ""
		(layer "F.Cu")
		(at 345.76131 -262.703564 180)
		(property "Reference" "PR131"
			(at 0 0 180)
			(layer "F.SilkS")
			(hide yes)
			(effects
				(font
					(size 1.27 1.27)
				)
			)
		)
		(property "Value" ""
			(at 0 0 180)
			(layer "F.Fab")
			(effects
				(font
					(size 1.27 1.27)
				)
			)
		)
		(duplicate_pad_numbers_are_jumpers no)
		(fp_line
			(start 0.7874 0.4064)
			(end -0.7874 0.4064)
			(stroke
				(width 0.1524)
				(type default)
			)
			(layer "F.SilkS")
		)
		(fp_line
			(start 0.7874 -0.4064)
			(end 0.7874 0.4064)
			(stroke
				(width 0.1524)
				(type default)
			)
			(layer "F.SilkS")
		)
		(fp_line
			(start -0.7874 0.4064)
			(end -0.7874 -0.4064)
			(stroke
				(width 0.1524)
				(type default)
			)
			(layer "F.SilkS")
		)
		(fp_line
			(start -0.7874 -0.4064)
			(end 0.7874 -0.4064)
			(stroke
				(width 0.1524)
				(type default)
			)
			(layer "F.SilkS")
		)
		(fp_line
			(start 0.67945 0.3048)
			(end 0.120396 0.3048)
			(stroke
				(width 0.1)
				(type default)
			)
			(layer "F.Fab")
		)
		(fp_line
			(start 0.67945 -0.3048)
			(end 0.67945 0.3048)
			(stroke
				(width 0.1)
				(type default)
			)
			(layer "F.Fab")
		)
		(fp_line
			(start 0.12065 -0.2794)
			(end 0.12065 -0.3048)
			(stroke
				(width 0.1)
				(type default)
			)
			(layer "F.Fab")
		)
		(fp_line
			(start 0.12065 -0.3048)
			(end 0.67945 -0.3048)
			(stroke
				(width 0.1)
				(type default)
			)
			(layer "F.Fab")
		)
		(fp_line
			(start 0.120396 0.3048)
			(end 0.120396 0.2794)
			(stroke
				(width 0.1)
				(type default)
			)
			(layer "F.Fab")
		)
		(fp_line
			(start 0.120396 0.2794)
			(end -0.12065 0.2794)
			(stroke
				(width 0.1)
				(type default)
			)
			(layer "F.Fab")
		)
		(fp_line
			(start -0.12065 0.3048)
			(end -0.67945 0.3048)
			(stroke
				(width 0.1)
				(type default)
			)
			(layer "F.Fab")
		)
		(fp_line
			(start -0.12065 0.2794)
			(end -0.12065 0.3048)
			(stroke
				(width 0.1)
				(type default)
			)
			(layer "F.Fab")
		)
		(fp_line
			(start -0.12065 -0.2794)
			(end 0.12065 -0.2794)
			(stroke
				(width 0.1)
				(type default)
			)
			(layer "F.Fab")
		)
		(fp_line
			(start -0.12065 -0.305054)
			(end -0.12065 -0.2794)
			(stroke
				(width 0.1)
				(type default)
			)
			(layer "F.Fab")
		)
		(fp_line
			(start -0.67945 0.3048)
			(end -0.67945 -0.305054)
			(stroke
				(width 0.1)
				(type default)
			)
			(layer "F.Fab")
		)
		(fp_line
			(start -0.67945 -0.305054)
			(end -0.12065 -0.305054)
			(stroke
				(width 0.1)
				(type default)
			)
			(layer "F.Fab")
		)
		(pad "1" smd circle
			(at -0.40005 0 180)
			(size 0 0)
			(layers "F.Cu" "F.Mask" "F.Paste")
			(net "P0V8_PEX2_VR_CONFIG")
		)
		(pad "2" smd circle
			(at 0.40005 0 180)
			(size 0 0)
			(layers "F.Cu" "F.Mask" "F.Paste")
			(net "P3V3_AUX")
		)
	)
	(footprint ""
		(layer "F.Cu")
		(at 210.542886 -231.150922 90)
		(property "Reference" "R1545"
			(at 0 0 90)
			(layer "F.SilkS")
			(hide yes)
			(effects
				(font
					(size 1.27 1.27)
				)
			)
		)
		(property "Value" ""
			(at 0 0 90)
			(layer "F.Fab")
			(effects
				(font
					(size 1.27 1.27)
				)
			)
		)
		(duplicate_pad_numbers_are_jumpers no)
		(fp_line
			(start 0.7874 -0.4064)
			(end 0.7874 0.4064)
			(stroke
				(width 0.1524)
				(type default)
			)
			(layer "F.SilkS")
		)
		(fp_line
			(start -0.7874 -0.4064)
			(end 0.7874 -0.4064)
			(stroke
				(width 0.1524)
				(type default)
			)
			(layer "F.SilkS")
		)
		(fp_line
			(start 0.7874 0.4064)
			(end -0.7874 0.4064)
			(stroke
				(width 0.1524)
				(type default)
			)
			(layer "F.SilkS")
		)
		(fp_line
			(start -0.7874 0.4064)
			(end -0.7874 -0.4064)
			(stroke
				(width 0.1524)
				(type default)
			)
			(layer "F.SilkS")
		)
		(fp_line
			(start -0.12065 -0.305054)
			(end -0.12065 -0.2794)
			(stroke
				(width 0.1)
				(type default)
			)
			(layer "F.Fab")
		)
		(fp_line
			(start -0.67945 -0.305054)
			(end -0.12065 -0.305054)
			(stroke
				(width 0.1)
				(type default)
			)
			(layer "F.Fab")
		)
		(fp_line
			(start 0.67945 -0.3048)
			(end 0.67945 0.3048)
			(stroke
				(width 0.1)
				(type default)
			)
			(layer "F.Fab")
		)
		(fp_line
			(start 0.12065 -0.3048)
			(end 0.67945 -0.3048)
			(stroke
				(width 0.1)
				(type default)
			)
			(layer "F.Fab")
		)
		(fp_line
			(start 0.12065 -0.2794)
			(end 0.12065 -0.3048)
			(stroke
				(width 0.1)
				(type default)
			)
			(layer "F.Fab")
		)
		(fp_line
			(start -0.12065 -0.2794)
			(end 0.12065 -0.2794)
			(stroke
				(width 0.1)
				(type default)
			)
			(layer "F.Fab")
		)
		(fp_line
			(start 0.120396 0.2794)
			(end -0.12065 0.2794)
			(stroke
				(width 0.1)
				(type default)
			)
			(layer "F.Fab")
		)
		(fp_line
			(start -0.12065 0.2794)
			(end -0.12065 0.3048)
			(stroke
				(width 0.1)
				(type default)
			)
			(layer "F.Fab")
		)
		(fp_line
			(start 0.67945 0.3048)
			(end 0.120396 0.3048)
			(stroke
				(width 0.1)
				(type default)
			)
			(layer "F.Fab")
		)
		(fp_line
			(start 0.120396 0.3048)
			(end 0.120396 0.2794)
			(stroke
				(width 0.1)
				(type default)
			)
			(layer "F.Fab")
		)
		(fp_line
			(start -0.12065 0.3048)
			(end -0.67945 0.3048)
			(stroke
				(width 0.1)
				(type default)
			)
			(layer "F.Fab")
		)
		(fp_line
			(start -0.67945 0.3048)
			(end -0.67945 -0.305054)
			(stroke
				(width 0.1)
				(type default)
			)
			(layer "F.Fab")
		)
		(pad "1" smd circle
			(at -0.40005 0 90)
			(size 0 0)
			(layers "F.Cu" "F.Mask" "F.Paste")
			(net "SMB_PEX_LS_R_SDA")
		)
		(pad "2" smd circle
			(at 0.40005 0 90)
			(size 0 0)
			(layers "F.Cu" "F.Mask" "F.Paste")
			(net "SMB_PEX1_SDA")
		)
	)
	(footprint ""
		(layer "F.Cu")
		(at 426.434504 -87.599012)
		(property "Reference" "U45"
			(at -0.933704 -1.706118 0)
			(unlocked yes)
			(layer "F.SilkS")
			(effects
				(font
					(size 0.7874 0.5842)
					(thickness 0.1524)
				)
				(justify left)
			)
		)
		(property "Value" ""
			(at 0 0 0)
			(layer "F.Fab")
			(effects
				(font
					(size 1.27 1.27)
				)
			)
		)
		(duplicate_pad_numbers_are_jumpers no)
		(fp_line
			(start -1.684274 -1.074928)
			(end -0.381 -1.074928)
			(stroke
				(width 0.1524)
				(type default)
			)
			(layer "F.SilkS")
		)
		(fp_line
			(start -1.684274 1.074928)
			(end -1.684274 -1.074928)
			(stroke
				(width 0.1524)
				(type default)
			)
			(layer "F.SilkS")
		)
		(fp_line
			(start -0.381 -1.074928)
			(end 0 -0.625094)
			(stroke
				(width 0.1524)
				(type default)
			)
			(layer "F.SilkS")
		)
		(fp_line
			(start 0 -0.625094)
			(end 0.381 -1.074928)
			(stroke
				(width 0.1524)
				(type default)
			)
			(layer "F.SilkS")
		)
		(fp_line
			(start 0.381 -1.074928)
			(end 1.684274 -1.074928)
			(stroke
				(width 0.1524)
				(type default)
			)
			(layer "F.SilkS")
		)
		(fp_line
			(start 1.684274 -1.074928)
			(end 1.684274 1.074928)
			(stroke
				(width 0.1524)
				(type default)
			)
			(layer "F.SilkS")
		)
		(fp_line
			(start 1.684274 1.074928)
			(end -1.684274 1.074928)
			(stroke
				(width 0.1524)
				(type default)
			)
			(layer "F.SilkS")
		)
		(fp_poly
			(pts
				(xy -2.637282 -0.903986) (xy -2.637282 -0.395986) (xy -1.875282 -0.649986)
			)
			(stroke
				(width 0)
				(type default)
			)
			(fill yes)
			(layer "F.SilkS")
		)
		(fp_line
			(start -0.700024 -1.074928)
			(end -0.700024 1.074928)
			(stroke
				(width 0.1)
				(type default)
			)
			(layer "F.Fab")
		)
		(fp_line
			(start -0.700024 1.074928)
			(end 0.700024 1.074928)
			(stroke
				(width 0.1)
				(type default)
			)
			(layer "F.Fab")
		)
		(fp_line
			(start 0.700024 -1.074928)
			(end -0.700024 -1.074928)
			(stroke
				(width 0.1)
				(type default)
			)
			(layer "F.Fab")
		)
		(fp_line
			(start 0.700024 1.074928)
			(end 0.700024 -1.074928)
			(stroke
				(width 0.1)
				(type default)
			)
			(layer "F.Fab")
		)
		(fp_poly
			(pts
				(xy -2.637282 -0.903986) (xy -2.637282 -0.395986) (xy -1.875282 -0.649986)
			)
			(stroke
				(width 0)
				(type default)
			)
			(fill yes)
			(layer "F.Fab")
		)
		(pad "1" smd rect
			(at -1.100074 -0.649986 270)
			(size 0.4064 0.9144)
			(layers "F.Cu" "F.Mask" "F.Paste")
			(net "Net_8449")
		)
		(pad "2" smd rect
			(at -1.100074 0 270)
			(size 0.4064 0.9144)
			(layers "F.Cu" "F.Mask" "F.Paste")
			(net "RST_HP_NIC7_N")
		)
		(pad "3" smd rect
			(at -1.100074 0.649986 270)
			(size 0.4064 0.9144)
			(layers "F.Cu" "F.Mask" "F.Paste")
			(net "GND")
		)
		(pad "4" smd rect
			(at 1.100074 0.649986 270)
			(size 0.4064 0.9144)
			(layers "F.Cu" "F.Mask" "F.Paste")
			(net "RST_HP_NIC7_BUF_N")
		)
		(pad "5" smd rect
			(at 1.100074 -0.649986 270)
			(size 0.4064 0.9144)
			(layers "F.Cu" "F.Mask" "F.Paste")
			(net "P3V3_AUX")
		)
	)
	(footprint ""
		(layer "F.Cu")
		(at 343.615518 -201.168 90)
		(property "Reference" "R6417"
			(at 0 0 90)
			(layer "F.SilkS")
			(hide yes)
			(effects
				(font
					(size 1.27 1.27)
				)
			)
		)
		(property "Value" ""
			(at 0 0 90)
			(layer "F.Fab")
			(effects
				(font
					(size 1.27 1.27)
				)
			)
		)
		(duplicate_pad_numbers_are_jumpers no)
		(fp_line
			(start 0.7874 -0.4064)
			(end 0.7874 0.4064)
			(stroke
				(width 0.1524)
				(type default)
			)
			(layer "F.SilkS")
		)
		(fp_line
			(start -0.7874 -0.4064)
			(end 0.7874 -0.4064)
			(stroke
				(width 0.1524)
				(type default)
			)
			(layer "F.SilkS")
		)
		(fp_line
			(start 0.7874 0.4064)
			(end -0.7874 0.4064)
			(stroke
				(width 0.1524)
				(type default)
			)
			(layer "F.SilkS")
		)
		(fp_line
			(start -0.7874 0.4064)
			(end -0.7874 -0.4064)
			(stroke
				(width 0.1524)
				(type default)
			)
			(layer "F.SilkS")
		)
		(fp_line
			(start -0.12065 -0.305054)
			(end -0.12065 -0.2794)
			(stroke
				(width 0.1)
				(type default)
			)
			(layer "F.Fab")
		)
		(fp_line
			(start -0.67945 -0.305054)
			(end -0.12065 -0.305054)
			(stroke
				(width 0.1)
				(type default)
			)
			(layer "F.Fab")
		)
		(fp_line
			(start 0.67945 -0.3048)
			(end 0.67945 0.3048)
			(stroke
				(width 0.1)
				(type default)
			)
			(layer "F.Fab")
		)
		(fp_line
			(start 0.12065 -0.3048)
			(end 0.67945 -0.3048)
			(stroke
				(width 0.1)
				(type default)
			)
			(layer "F.Fab")
		)
		(fp_line
			(start 0.12065 -0.2794)
			(end 0.12065 -0.3048)
			(stroke
				(width 0.1)
				(type default)
			)
			(layer "F.Fab")
		)
		(fp_line
			(start -0.12065 -0.2794)
			(end 0.12065 -0.2794)
			(stroke
				(width 0.1)
				(type default)
			)
			(layer "F.Fab")
		)
		(fp_line
			(start 0.120396 0.2794)
			(end -0.12065 0.2794)
			(stroke
				(width 0.1)
				(type default)
			)
			(layer "F.Fab")
		)
		(fp_line
			(start -0.12065 0.2794)
			(end -0.12065 0.3048)
			(stroke
				(width 0.1)
				(type default)
			)
			(layer "F.Fab")
		)
		(fp_line
			(start 0.67945 0.3048)
			(end 0.120396 0.3048)
			(stroke
				(width 0.1)
				(type default)
			)
			(layer "F.Fab")
		)
		(fp_line
			(start 0.120396 0.3048)
			(end 0.120396 0.2794)
			(stroke
				(width 0.1)
				(type default)
			)
			(layer "F.Fab")
		)
		(fp_line
			(start -0.12065 0.3048)
			(end -0.67945 0.3048)
			(stroke
				(width 0.1)
				(type default)
			)
			(layer "F.Fab")
		)
		(fp_line
			(start -0.67945 0.3048)
			(end -0.67945 -0.305054)
			(stroke
				(width 0.1)
				(type default)
			)
			(layer "F.Fab")
		)
		(pad "1" smd circle
			(at -0.40005 0 90)
			(size 0 0)
			(layers "F.Cu" "F.Mask" "F.Paste")
			(net "FPGA_PEX0_MODE_SEL1_R")
		)
		(pad "2" smd circle
			(at 0.40005 0 90)
			(size 0 0)
			(layers "F.Cu" "F.Mask" "F.Paste")
			(net "FPGA_PEX0_MODE_SEL1")
		)
	)
	(footprint ""
		(layer "F.Cu")
		(at 92.0496 -304.036476 90)
		(property "Reference" "R1253"
			(at 0 0 90)
			(layer "F.SilkS")
			(hide yes)
			(effects
				(font
					(size 1.27 1.27)
				)
			)
		)
		(property "Value" ""
			(at 0 0 90)
			(layer "F.Fab")
			(effects
				(font
					(size 1.27 1.27)
				)
			)
		)
		(duplicate_pad_numbers_are_jumpers no)
		(fp_line
			(start 0.7874 -0.4064)
			(end 0.7874 0.4064)
			(stroke
				(width 0.1524)
				(type default)
			)
			(layer "F.SilkS")
		)
		(fp_line
			(start -0.7874 -0.4064)
			(end 0.7874 -0.4064)
			(stroke
				(width 0.1524)
				(type default)
			)
			(layer "F.SilkS")
		)
		(fp_line
			(start 0.7874 0.4064)
			(end -0.7874 0.4064)
			(stroke
				(width 0.1524)
				(type default)
			)
			(layer "F.SilkS")
		)
		(fp_line
			(start -0.7874 0.4064)
			(end -0.7874 -0.4064)
			(stroke
				(width 0.1524)
				(type default)
			)
			(layer "F.SilkS")
		)
		(fp_line
			(start -0.12065 -0.305054)
			(end -0.12065 -0.2794)
			(stroke
				(width 0.1)
				(type default)
			)
			(layer "F.Fab")
		)
		(fp_line
			(start -0.67945 -0.305054)
			(end -0.12065 -0.305054)
			(stroke
				(width 0.1)
				(type default)
			)
			(layer "F.Fab")
		)
		(fp_line
			(start 0.67945 -0.3048)
			(end 0.67945 0.3048)
			(stroke
				(width 0.1)
				(type default)
			)
			(layer "F.Fab")
		)
		(fp_line
			(start 0.12065 -0.3048)
			(end 0.67945 -0.3048)
			(stroke
				(width 0.1)
				(type default)
			)
			(layer "F.Fab")
		)
		(fp_line
			(start 0.12065 -0.2794)
			(end 0.12065 -0.3048)
			(stroke
				(width 0.1)
				(type default)
			)
			(layer "F.Fab")
		)
		(fp_line
			(start -0.12065 -0.2794)
			(end 0.12065 -0.2794)
			(stroke
				(width 0.1)
				(type default)
			)
			(layer "F.Fab")
		)
		(fp_line
			(start 0.120396 0.2794)
			(end -0.12065 0.2794)
			(stroke
				(width 0.1)
				(type default)
			)
			(layer "F.Fab")
		)
		(fp_line
			(start -0.12065 0.2794)
			(end -0.12065 0.3048)
			(stroke
				(width 0.1)
				(type default)
			)
			(layer "F.Fab")
		)
		(fp_line
			(start 0.67945 0.3048)
			(end 0.120396 0.3048)
			(stroke
				(width 0.1)
				(type default)
			)
			(layer "F.Fab")
		)
		(fp_line
			(start 0.120396 0.3048)
			(end 0.120396 0.2794)
			(stroke
				(width 0.1)
				(type default)
			)
			(layer "F.Fab")
		)
		(fp_line
			(start -0.12065 0.3048)
			(end -0.67945 0.3048)
			(stroke
				(width 0.1)
				(type default)
			)
			(layer "F.Fab")
		)
		(fp_line
			(start -0.67945 0.3048)
			(end -0.67945 -0.305054)
			(stroke
				(width 0.1)
				(type default)
			)
			(layer "F.Fab")
		)
		(pad "1" smd circle
			(at -0.40005 0 90)
			(size 0 0)
			(layers "F.Cu" "F.Mask" "F.Paste")
			(net "GND")
		)
		(pad "2" smd circle
			(at 0.40005 0 90)
			(size 0 0)
			(layers "F.Cu" "F.Mask" "F.Paste")
			(net "PEX0_SPARE6")
		)
	)
	(footprint ""
		(layer "F.Cu")
		(at 264.670286 -250.070874 -90)
		(property "Reference" "R1344"
			(at 0 0 270)
			(layer "F.SilkS")
			(hide yes)
			(effects
				(font
					(size 1.27 1.27)
				)
			)
		)
		(property "Value" ""
			(at 0 0 270)
			(layer "F.Fab")
			(effects
				(font
					(size 1.27 1.27)
				)
			)
		)
		(duplicate_pad_numbers_are_jumpers no)
		(fp_line
			(start -0.7874 0.4064)
			(end -0.7874 -0.4064)
			(stroke
				(width 0.1524)
				(type default)
			)
			(layer "F.SilkS")
		)
		(fp_line
			(start 0.7874 0.4064)
			(end -0.7874 0.4064)
			(stroke
				(width 0.1524)
				(type default)
			)
			(layer "F.SilkS")
		)
		(fp_line
			(start -0.7874 -0.4064)
			(end 0.7874 -0.4064)
			(stroke
				(width 0.1524)
				(type default)
			)
			(layer "F.SilkS")
		)
		(fp_line
			(start 0.7874 -0.4064)
			(end 0.7874 0.4064)
			(stroke
				(width 0.1524)
				(type default)
			)
			(layer "F.SilkS")
		)
		(fp_line
			(start -0.67945 0.3048)
			(end -0.67945 -0.305054)
			(stroke
				(width 0.1)
				(type default)
			)
			(layer "F.Fab")
		)
		(fp_line
			(start -0.12065 0.3048)
			(end -0.67945 0.3048)
			(stroke
				(width 0.1)
				(type default)
			)
			(layer "F.Fab")
		)
		(fp_line
			(start 0.120396 0.3048)
			(end 0.120396 0.2794)
			(stroke
				(width 0.1)
				(type default)
			)
			(layer "F.Fab")
		)
		(fp_line
			(start 0.67945 0.3048)
			(end 0.120396 0.3048)
			(stroke
				(width 0.1)
				(type default)
			)
			(layer "F.Fab")
		)
		(fp_line
			(start -0.12065 0.2794)
			(end -0.12065 0.3048)
			(stroke
				(width 0.1)
				(type default)
			)
			(layer "F.Fab")
		)
		(fp_line
			(start 0.120396 0.2794)
			(end -0.12065 0.2794)
			(stroke
				(width 0.1)
				(type default)
			)
			(layer "F.Fab")
		)
		(fp_line
			(start -0.12065 -0.2794)
			(end 0.12065 -0.2794)
			(stroke
				(width 0.1)
				(type default)
			)
			(layer "F.Fab")
		)
		(fp_line
			(start 0.12065 -0.2794)
			(end 0.12065 -0.3048)
			(stroke
				(width 0.1)
				(type default)
			)
			(layer "F.Fab")
		)
		(fp_line
			(start 0.12065 -0.3048)
			(end 0.67945 -0.3048)
			(stroke
				(width 0.1)
				(type default)
			)
			(layer "F.Fab")
		)
		(fp_line
			(start 0.67945 -0.3048)
			(end 0.67945 0.3048)
			(stroke
				(width 0.1)
				(type default)
			)
			(layer "F.Fab")
		)
		(fp_line
			(start -0.67945 -0.305054)
			(end -0.12065 -0.305054)
			(stroke
				(width 0.1)
				(type default)
			)
			(layer "F.Fab")
		)
		(fp_line
			(start -0.12065 -0.305054)
			(end -0.12065 -0.2794)
			(stroke
				(width 0.1)
				(type default)
			)
			(layer "F.Fab")
		)
		(pad "1" smd circle
			(at -0.40005 0 270)
			(size 0 0)
			(layers "F.Cu" "F.Mask" "F.Paste")
			(net "PEX2_MODE_SEL8")
		)
		(pad "2" smd circle
			(at 0.40005 0 270)
			(size 0 0)
			(layers "F.Cu" "F.Mask" "F.Paste")
			(net "P1V8_PEX")
		)
	)
	(footprint ""
		(layer "F.Cu")
		(at 202.278996 -59.577986 -90)
		(property "Reference" "R892"
			(at 0 0 270)
			(layer "F.SilkS")
			(hide yes)
			(effects
				(font
					(size 1.27 1.27)
				)
			)
		)
		(property "Value" ""
			(at 0 0 270)
			(layer "F.Fab")
			(effects
				(font
					(size 1.27 1.27)
				)
			)
		)
		(duplicate_pad_numbers_are_jumpers no)
		(fp_line
			(start -0.7874 0.4064)
			(end -0.7874 -0.4064)
			(stroke
				(width 0.1524)
				(type default)
			)
			(layer "F.SilkS")
		)
		(fp_line
			(start 0.7874 0.4064)
			(end -0.7874 0.4064)
			(stroke
				(width 0.1524)
				(type default)
			)
			(layer "F.SilkS")
		)
		(fp_line
			(start -0.7874 -0.4064)
			(end 0.7874 -0.4064)
			(stroke
				(width 0.1524)
				(type default)
			)
			(layer "F.SilkS")
		)
		(fp_line
			(start 0.7874 -0.4064)
			(end 0.7874 0.4064)
			(stroke
				(width 0.1524)
				(type default)
			)
			(layer "F.SilkS")
		)
		(fp_line
			(start -0.67945 0.3048)
			(end -0.67945 -0.305054)
			(stroke
				(width 0.1)
				(type default)
			)
			(layer "F.Fab")
		)
		(fp_line
			(start -0.12065 0.3048)
			(end -0.67945 0.3048)
			(stroke
				(width 0.1)
				(type default)
			)
			(layer "F.Fab")
		)
		(fp_line
			(start 0.120396 0.3048)
			(end 0.120396 0.2794)
			(stroke
				(width 0.1)
				(type default)
			)
			(layer "F.Fab")
		)
		(fp_line
			(start 0.67945 0.3048)
			(end 0.120396 0.3048)
			(stroke
				(width 0.1)
				(type default)
			)
			(layer "F.Fab")
		)
		(fp_line
			(start -0.12065 0.2794)
			(end -0.12065 0.3048)
			(stroke
				(width 0.1)
				(type default)
			)
			(layer "F.Fab")
		)
		(fp_line
			(start 0.120396 0.2794)
			(end -0.12065 0.2794)
			(stroke
				(width 0.1)
				(type default)
			)
			(layer "F.Fab")
		)
		(fp_line
			(start -0.12065 -0.2794)
			(end 0.12065 -0.2794)
			(stroke
				(width 0.1)
				(type default)
			)
			(layer "F.Fab")
		)
		(fp_line
			(start 0.12065 -0.2794)
			(end 0.12065 -0.3048)
			(stroke
				(width 0.1)
				(type default)
			)
			(layer "F.Fab")
		)
		(fp_line
			(start 0.12065 -0.3048)
			(end 0.67945 -0.3048)
			(stroke
				(width 0.1)
				(type default)
			)
			(layer "F.Fab")
		)
		(fp_line
			(start 0.67945 -0.3048)
			(end 0.67945 0.3048)
			(stroke
				(width 0.1)
				(type default)
			)
			(layer "F.Fab")
		)
		(fp_line
			(start -0.67945 -0.305054)
			(end -0.12065 -0.305054)
			(stroke
				(width 0.1)
				(type default)
			)
			(layer "F.Fab")
		)
		(fp_line
			(start -0.12065 -0.305054)
			(end -0.12065 -0.2794)
			(stroke
				(width 0.1)
				(type default)
			)
			(layer "F.Fab")
		)
		(pad "1" smd circle
			(at -0.40005 0 270)
			(size 0 0)
			(layers "F.Cu" "F.Mask" "F.Paste")
			(net "P3V3_SSD7")
		)
		(pad "2" smd circle
			(at 0.40005 0 270)
			(size 0 0)
			(layers "F.Cu" "F.Mask" "F.Paste")
			(net "PWRGD_P3V3_SSD7")
		)
	)
	(footprint ""
		(layer "F.Cu")
		(at 386.70738 -356.244906 90)
		(property "Reference" "C760"
			(at 0 0 90)
			(layer "F.SilkS")
			(hide yes)
			(effects
				(font
					(size 1.27 1.27)
				)
			)
		)
		(property "Value" ""
			(at 0 0 90)
			(layer "F.Fab")
			(effects
				(font
					(size 1.27 1.27)
				)
			)
		)
		(duplicate_pad_numbers_are_jumpers no)
		(fp_line
			(start 0.299974 -0.150114)
			(end 0.299974 0.150114)
			(stroke
				(width 0.1)
				(type default)
			)
			(layer "F.Fab")
		)
		(fp_line
			(start -0.299974 -0.150114)
			(end 0.299974 -0.150114)
			(stroke
				(width 0.1)
				(type default)
			)
			(layer "F.Fab")
		)
		(fp_line
			(start 0.299974 0.150114)
			(end -0.299974 0.150114)
			(stroke
				(width 0.1)
				(type default)
			)
			(layer "F.Fab")
		)
		(fp_line
			(start -0.299974 0.150114)
			(end -0.299974 -0.150114)
			(stroke
				(width 0.1)
				(type default)
			)
			(layer "F.Fab")
		)
		(pad "1" smd rect
			(at -0.2667 0 90)
			(size 0.3048 0.381)
			(layers "F.Cu" "F.Mask" "F.Paste")
			(net "P5E_PEX3_STN5_TX_DP<80>")
		)
		(pad "2" smd rect
			(at 0.2667 0 90)
			(size 0.3048 0.381)
			(layers "F.Cu" "F.Mask" "F.Paste")
			(net "P5E_PEX3_STN5_TX_C_DP<80>")
		)
	)
	(footprint ""
		(layer "F.Cu")
		(at 122.023124 -164.837872)
		(property "Reference" "R6670"
			(at 0 0 0)
			(layer "F.SilkS")
			(hide yes)
			(effects
				(font
					(size 1.27 1.27)
				)
			)
		)
		(property "Value" ""
			(at 0 0 0)
			(layer "F.Fab")
			(effects
				(font
					(size 1.27 1.27)
				)
			)
		)
		(duplicate_pad_numbers_are_jumpers no)
		(fp_line
			(start -0.7874 -0.4064)
			(end 0.7874 -0.4064)
			(stroke
				(width 0.1524)
				(type default)
			)
			(layer "F.SilkS")
		)
		(fp_line
			(start -0.7874 0.4064)
			(end -0.7874 -0.4064)
			(stroke
				(width 0.1524)
				(type default)
			)
			(layer "F.SilkS")
		)
		(fp_line
			(start 0.7874 -0.4064)
			(end 0.7874 0.4064)
			(stroke
				(width 0.1524)
				(type default)
			)
			(layer "F.SilkS")
		)
		(fp_line
			(start 0.7874 0.4064)
			(end -0.7874 0.4064)
			(stroke
				(width 0.1524)
				(type default)
			)
			(layer "F.SilkS")
		)
		(fp_line
			(start -0.67945 -0.305054)
			(end -0.12065 -0.305054)
			(stroke
				(width 0.1)
				(type default)
			)
			(layer "F.Fab")
		)
		(fp_line
			(start -0.67945 0.3048)
			(end -0.67945 -0.305054)
			(stroke
				(width 0.1)
				(type default)
			)
			(layer "F.Fab")
		)
		(fp_line
			(start -0.12065 -0.305054)
			(end -0.12065 -0.2794)
			(stroke
				(width 0.1)
				(type default)
			)
			(layer "F.Fab")
		)
		(fp_line
			(start -0.12065 -0.2794)
			(end 0.12065 -0.2794)
			(stroke
				(width 0.1)
				(type default)
			)
			(layer "F.Fab")
		)
		(fp_line
			(start -0.12065 0.2794)
			(end -0.12065 0.3048)
			(stroke
				(width 0.1)
				(type default)
			)
			(layer "F.Fab")
		)
		(fp_line
			(start -0.12065 0.3048)
			(end -0.67945 0.3048)
			(stroke
				(width 0.1)
				(type default)
			)
			(layer "F.Fab")
		)
		(fp_line
			(start 0.120396 0.2794)
			(end -0.12065 0.2794)
			(stroke
				(width 0.1)
				(type default)
			)
			(layer "F.Fab")
		)
		(fp_line
			(start 0.120396 0.3048)
			(end 0.120396 0.2794)
			(stroke
				(width 0.1)
				(type default)
			)
			(layer "F.Fab")
		)
		(fp_line
			(start 0.12065 -0.3048)
			(end 0.67945 -0.3048)
			(stroke
				(width 0.1)
				(type default)
			)
			(layer "F.Fab")
		)
		(fp_line
			(start 0.12065 -0.2794)
			(end 0.12065 -0.3048)
			(stroke
				(width 0.1)
				(type default)
			)
			(layer "F.Fab")
		)
		(fp_line
			(start 0.67945 -0.3048)
			(end 0.67945 0.3048)
			(stroke
				(width 0.1)
				(type default)
			)
			(layer "F.Fab")
		)
		(fp_line
			(start 0.67945 0.3048)
			(end 0.120396 0.3048)
			(stroke
				(width 0.1)
				(type default)
			)
			(layer "F.Fab")
		)
		(pad "1" smd circle
			(at -0.40005 0)
			(size 0 0)
			(layers "F.Cu" "F.Mask" "F.Paste")
			(net "NIC1_CLK_EN_BUF_R_N")
		)
		(pad "2" smd circle
			(at 0.40005 0)
			(size 0 0)
			(layers "F.Cu" "F.Mask" "F.Paste")
			(net "P3V3")
		)
	)
	(footprint ""
		(layer "F.Cu")
		(at 429.939704 -87.349076 -90)
		(property "Reference" "R402"
			(at 0 0 270)
			(layer "F.SilkS")
			(hide yes)
			(effects
				(font
					(size 1.27 1.27)
				)
			)
		)
		(property "Value" ""
			(at 0 0 270)
			(layer "F.Fab")
			(effects
				(font
					(size 1.27 1.27)
				)
			)
		)
		(duplicate_pad_numbers_are_jumpers no)
		(fp_line
			(start -0.7874 0.4064)
			(end -0.7874 -0.4064)
			(stroke
				(width 0.1524)
				(type default)
			)
			(layer "F.SilkS")
		)
		(fp_line
			(start 0.7874 0.4064)
			(end -0.7874 0.4064)
			(stroke
				(width 0.1524)
				(type default)
			)
			(layer "F.SilkS")
		)
		(fp_line
			(start -0.7874 -0.4064)
			(end 0.7874 -0.4064)
			(stroke
				(width 0.1524)
				(type default)
			)
			(layer "F.SilkS")
		)
		(fp_line
			(start 0.7874 -0.4064)
			(end 0.7874 0.4064)
			(stroke
				(width 0.1524)
				(type default)
			)
			(layer "F.SilkS")
		)
		(fp_line
			(start -0.67945 0.3048)
			(end -0.67945 -0.305054)
			(stroke
				(width 0.1)
				(type default)
			)
			(layer "F.Fab")
		)
		(fp_line
			(start -0.12065 0.3048)
			(end -0.67945 0.3048)
			(stroke
				(width 0.1)
				(type default)
			)
			(layer "F.Fab")
		)
		(fp_line
			(start 0.120396 0.3048)
			(end 0.120396 0.2794)
			(stroke
				(width 0.1)
				(type default)
			)
			(layer "F.Fab")
		)
		(fp_line
			(start 0.67945 0.3048)
			(end 0.120396 0.3048)
			(stroke
				(width 0.1)
				(type default)
			)
			(layer "F.Fab")
		)
		(fp_line
			(start -0.12065 0.2794)
			(end -0.12065 0.3048)
			(stroke
				(width 0.1)
				(type default)
			)
			(layer "F.Fab")
		)
		(fp_line
			(start 0.120396 0.2794)
			(end -0.12065 0.2794)
			(stroke
				(width 0.1)
				(type default)
			)
			(layer "F.Fab")
		)
		(fp_line
			(start -0.12065 -0.2794)
			(end 0.12065 -0.2794)
			(stroke
				(width 0.1)
				(type default)
			)
			(layer "F.Fab")
		)
		(fp_line
			(start 0.12065 -0.2794)
			(end 0.12065 -0.3048)
			(stroke
				(width 0.1)
				(type default)
			)
			(layer "F.Fab")
		)
		(fp_line
			(start 0.12065 -0.3048)
			(end 0.67945 -0.3048)
			(stroke
				(width 0.1)
				(type default)
			)
			(layer "F.Fab")
		)
		(fp_line
			(start 0.67945 -0.3048)
			(end 0.67945 0.3048)
			(stroke
				(width 0.1)
				(type default)
			)
			(layer "F.Fab")
		)
		(fp_line
			(start -0.67945 -0.305054)
			(end -0.12065 -0.305054)
			(stroke
				(width 0.1)
				(type default)
			)
			(layer "F.Fab")
		)
		(fp_line
			(start -0.12065 -0.305054)
			(end -0.12065 -0.2794)
			(stroke
				(width 0.1)
				(type default)
			)
			(layer "F.Fab")
		)
		(pad "1" smd circle
			(at -0.40005 0 270)
			(size 0 0)
			(layers "F.Cu" "F.Mask" "F.Paste")
			(net "RST_NIC7_PERST0_R_N")
		)
		(pad "2" smd circle
			(at 0.40005 0 270)
			(size 0 0)
			(layers "F.Cu" "F.Mask" "F.Paste")
			(net "RST_HP_NIC7_BUF_N")
		)
	)
	(footprint ""
		(layer "F.Cu")
		(at 232.06964 -82.118708 180)
		(property "Reference" "R6725"
			(at 0 0 180)
			(layer "F.SilkS")
			(hide yes)
			(effects
				(font
					(size 1.27 1.27)
				)
			)
		)
		(property "Value" ""
			(at 0 0 180)
			(layer "F.Fab")
			(effects
				(font
					(size 1.27 1.27)
				)
			)
		)
		(duplicate_pad_numbers_are_jumpers no)
		(fp_line
			(start 0.7874 0.4064)
			(end -0.7874 0.4064)
			(stroke
				(width 0.1524)
				(type default)
			)
			(layer "F.SilkS")
		)
		(fp_line
			(start 0.7874 -0.4064)
			(end 0.7874 0.4064)
			(stroke
				(width 0.1524)
				(type default)
			)
			(layer "F.SilkS")
		)
		(fp_line
			(start -0.009652 -0.4064)
			(end 0.7874 -0.4064)
			(stroke
				(width 0.1524)
				(type default)
			)
			(layer "F.SilkS")
		)
		(fp_line
			(start -0.7874 0.4064)
			(end -0.7874 -0.4064)
			(stroke
				(width 0.1524)
				(type default)
			)
			(layer "F.SilkS")
		)
		(fp_line
			(start 0.67945 0.3048)
			(end 0.120396 0.3048)
			(stroke
				(width 0.1)
				(type default)
			)
			(layer "F.Fab")
		)
		(fp_line
			(start 0.67945 -0.3048)
			(end 0.67945 0.3048)
			(stroke
				(width 0.1)
				(type default)
			)
			(layer "F.Fab")
		)
		(fp_line
			(start 0.12065 -0.2794)
			(end 0.12065 -0.3048)
			(stroke
				(width 0.1)
				(type default)
			)
			(layer "F.Fab")
		)
		(fp_line
			(start 0.12065 -0.3048)
			(end 0.67945 -0.3048)
			(stroke
				(width 0.1)
				(type default)
			)
			(layer "F.Fab")
		)
		(fp_line
			(start 0.120396 0.3048)
			(end 0.120396 0.2794)
			(stroke
				(width 0.1)
				(type default)
			)
			(layer "F.Fab")
		)
		(fp_line
			(start 0.120396 0.2794)
			(end -0.12065 0.2794)
			(stroke
				(width 0.1)
				(type default)
			)
			(layer "F.Fab")
		)
		(fp_line
			(start -0.12065 0.3048)
			(end -0.67945 0.3048)
			(stroke
				(width 0.1)
				(type default)
			)
			(layer "F.Fab")
		)
		(fp_line
			(start -0.12065 0.2794)
			(end -0.12065 0.3048)
			(stroke
				(width 0.1)
				(type default)
			)
			(layer "F.Fab")
		)
		(fp_line
			(start -0.12065 -0.2794)
			(end 0.12065 -0.2794)
			(stroke
				(width 0.1)
				(type default)
			)
			(layer "F.Fab")
		)
		(fp_line
			(start -0.12065 -0.305054)
			(end -0.12065 -0.2794)
			(stroke
				(width 0.1)
				(type default)
			)
			(layer "F.Fab")
		)
		(fp_line
			(start -0.67945 0.3048)
			(end -0.67945 -0.305054)
			(stroke
				(width 0.1)
				(type default)
			)
			(layer "F.Fab")
		)
		(fp_line
			(start -0.67945 -0.305054)
			(end -0.12065 -0.305054)
			(stroke
				(width 0.1)
				(type default)
			)
			(layer "F.Fab")
		)
		(pad "1" smd rect
			(at -0.40005 0)
			(size 0.4572 0.508)
			(layers "F.Cu" "F.Mask" "F.Paste")
			(net "USB2_CP2108_SDB_DN")
		)
		(pad "2" smd rect
			(at 0.40005 0)
			(size 0.4572 0.508)
			(layers "F.Cu" "F.Mask" "F.Paste")
			(net "GND")
		)
	)
	(footprint ""
		(layer "F.Cu")
		(at 232.283 -231.394 90)
		(property "Reference" "R4524"
			(at 0 0 90)
			(layer "F.SilkS")
			(hide yes)
			(effects
				(font
					(size 1.27 1.27)
				)
			)
		)
		(property "Value" ""
			(at 0 0 90)
			(layer "F.Fab")
			(effects
				(font
					(size 1.27 1.27)
				)
			)
		)
		(duplicate_pad_numbers_are_jumpers no)
		(fp_line
			(start 0.7874 -0.4064)
			(end 0.7874 0.4064)
			(stroke
				(width 0.1524)
				(type default)
			)
			(layer "F.SilkS")
		)
		(fp_line
			(start -0.7874 -0.4064)
			(end 0.7874 -0.4064)
			(stroke
				(width 0.1524)
				(type default)
			)
			(layer "F.SilkS")
		)
		(fp_line
			(start 0.7874 0.4064)
			(end -0.7874 0.4064)
			(stroke
				(width 0.1524)
				(type default)
			)
			(layer "F.SilkS")
		)
		(fp_line
			(start -0.7874 0.4064)
			(end -0.7874 -0.4064)
			(stroke
				(width 0.1524)
				(type default)
			)
			(layer "F.SilkS")
		)
		(fp_line
			(start -0.12065 -0.305054)
			(end -0.12065 -0.2794)
			(stroke
				(width 0.1)
				(type default)
			)
			(layer "F.Fab")
		)
		(fp_line
			(start -0.67945 -0.305054)
			(end -0.12065 -0.305054)
			(stroke
				(width 0.1)
				(type default)
			)
			(layer "F.Fab")
		)
		(fp_line
			(start 0.67945 -0.3048)
			(end 0.67945 0.3048)
			(stroke
				(width 0.1)
				(type default)
			)
			(layer "F.Fab")
		)
		(fp_line
			(start 0.12065 -0.3048)
			(end 0.67945 -0.3048)
			(stroke
				(width 0.1)
				(type default)
			)
			(layer "F.Fab")
		)
		(fp_line
			(start 0.12065 -0.2794)
			(end 0.12065 -0.3048)
			(stroke
				(width 0.1)
				(type default)
			)
			(layer "F.Fab")
		)
		(fp_line
			(start -0.12065 -0.2794)
			(end 0.12065 -0.2794)
			(stroke
				(width 0.1)
				(type default)
			)
			(layer "F.Fab")
		)
		(fp_line
			(start 0.120396 0.2794)
			(end -0.12065 0.2794)
			(stroke
				(width 0.1)
				(type default)
			)
			(layer "F.Fab")
		)
		(fp_line
			(start -0.12065 0.2794)
			(end -0.12065 0.3048)
			(stroke
				(width 0.1)
				(type default)
			)
			(layer "F.Fab")
		)
		(fp_line
			(start 0.67945 0.3048)
			(end 0.120396 0.3048)
			(stroke
				(width 0.1)
				(type default)
			)
			(layer "F.Fab")
		)
		(fp_line
			(start 0.120396 0.3048)
			(end 0.120396 0.2794)
			(stroke
				(width 0.1)
				(type default)
			)
			(layer "F.Fab")
		)
		(fp_line
			(start -0.12065 0.3048)
			(end -0.67945 0.3048)
			(stroke
				(width 0.1)
				(type default)
			)
			(layer "F.Fab")
		)
		(fp_line
			(start -0.67945 0.3048)
			(end -0.67945 -0.305054)
			(stroke
				(width 0.1)
				(type default)
			)
			(layer "F.Fab")
		)
		(pad "1" smd circle
			(at -0.40005 0 90)
			(size 0 0)
			(layers "F.Cu" "F.Mask" "F.Paste")
			(net "SSD10_PWRDIS_BIC")
		)
		(pad "2" smd circle
			(at 0.40005 0 90)
			(size 0 0)
			(layers "F.Cu" "F.Mask" "F.Paste")
			(net "SSD10_PWRDIS_BIC_R")
		)
	)
	(footprint ""
		(layer "F.Cu")
		(at 335.264252 -29.079952 180)
		(property "Reference" "R6209"
			(at 0 0 180)
			(layer "F.SilkS")
			(hide yes)
			(effects
				(font
					(size 1.27 1.27)
				)
			)
		)
		(property "Value" ""
			(at 0 0 180)
			(layer "F.Fab")
			(effects
				(font
					(size 1.27 1.27)
				)
			)
		)
		(duplicate_pad_numbers_are_jumpers no)
		(fp_line
			(start 0.7874 0.4064)
			(end -0.7874 0.4064)
			(stroke
				(width 0.1524)
				(type default)
			)
			(layer "F.SilkS")
		)
		(fp_line
			(start 0.7874 -0.4064)
			(end 0.7874 0.4064)
			(stroke
				(width 0.1524)
				(type default)
			)
			(layer "F.SilkS")
		)
		(fp_line
			(start -0.7874 0.4064)
			(end -0.7874 -0.4064)
			(stroke
				(width 0.1524)
				(type default)
			)
			(layer "F.SilkS")
		)
		(fp_line
			(start -0.7874 -0.4064)
			(end 0.7874 -0.4064)
			(stroke
				(width 0.1524)
				(type default)
			)
			(layer "F.SilkS")
		)
		(fp_line
			(start 0.67945 0.3048)
			(end 0.120396 0.3048)
			(stroke
				(width 0.1)
				(type default)
			)
			(layer "F.Fab")
		)
		(fp_line
			(start 0.67945 -0.3048)
			(end 0.67945 0.3048)
			(stroke
				(width 0.1)
				(type default)
			)
			(layer "F.Fab")
		)
		(fp_line
			(start 0.12065 -0.2794)
			(end 0.12065 -0.3048)
			(stroke
				(width 0.1)
				(type default)
			)
			(layer "F.Fab")
		)
		(fp_line
			(start 0.12065 -0.3048)
			(end 0.67945 -0.3048)
			(stroke
				(width 0.1)
				(type default)
			)
			(layer "F.Fab")
		)
		(fp_line
			(start 0.120396 0.3048)
			(end 0.120396 0.2794)
			(stroke
				(width 0.1)
				(type default)
			)
			(layer "F.Fab")
		)
		(fp_line
			(start 0.120396 0.2794)
			(end -0.12065 0.2794)
			(stroke
				(width 0.1)
				(type default)
			)
			(layer "F.Fab")
		)
		(fp_line
			(start -0.12065 0.3048)
			(end -0.67945 0.3048)
			(stroke
				(width 0.1)
				(type default)
			)
			(layer "F.Fab")
		)
		(fp_line
			(start -0.12065 0.2794)
			(end -0.12065 0.3048)
			(stroke
				(width 0.1)
				(type default)
			)
			(layer "F.Fab")
		)
		(fp_line
			(start -0.12065 -0.2794)
			(end 0.12065 -0.2794)
			(stroke
				(width 0.1)
				(type default)
			)
			(layer "F.Fab")
		)
		(fp_line
			(start -0.12065 -0.305054)
			(end -0.12065 -0.2794)
			(stroke
				(width 0.1)
				(type default)
			)
			(layer "F.Fab")
		)
		(fp_line
			(start -0.67945 0.3048)
			(end -0.67945 -0.305054)
			(stroke
				(width 0.1)
				(type default)
			)
			(layer "F.Fab")
		)
		(fp_line
			(start -0.67945 -0.305054)
			(end -0.12065 -0.305054)
			(stroke
				(width 0.1)
				(type default)
			)
			(layer "F.Fab")
		)
		(pad "1" smd circle
			(at -0.40005 0 180)
			(size 0 0)
			(layers "F.Cu" "F.Mask" "F.Paste")
			(net "GND")
		)
		(pad "2" smd circle
			(at 0.40005 0 180)
			(size 0 0)
			(layers "F.Cu" "F.Mask" "F.Paste")
			(net "SSD11_PWRDIS_R")
		)
	)
	(footprint ""
		(layer "F.Cu")
		(at 358.41051 -123.947428 180)
		(property "Reference" "PR250"
			(at 0 0 180)
			(layer "F.SilkS")
			(hide yes)
			(effects
				(font
					(size 1.27 1.27)
				)
			)
		)
		(property "Value" ""
			(at 0 0 180)
			(layer "F.Fab")
			(effects
				(font
					(size 1.27 1.27)
				)
			)
		)
		(duplicate_pad_numbers_are_jumpers no)
		(fp_line
			(start 0.7874 0.4064)
			(end -0.7874 0.4064)
			(stroke
				(width 0.1524)
				(type default)
			)
			(layer "F.SilkS")
		)
		(fp_line
			(start 0.7874 -0.4064)
			(end 0.7874 0.4064)
			(stroke
				(width 0.1524)
				(type default)
			)
			(layer "F.SilkS")
		)
		(fp_line
			(start -0.7874 0.4064)
			(end -0.7874 -0.4064)
			(stroke
				(width 0.1524)
				(type default)
			)
			(layer "F.SilkS")
		)
		(fp_line
			(start -0.7874 -0.4064)
			(end 0.7874 -0.4064)
			(stroke
				(width 0.1524)
				(type default)
			)
			(layer "F.SilkS")
		)
		(fp_line
			(start 0.67945 0.3048)
			(end 0.120396 0.3048)
			(stroke
				(width 0.1)
				(type default)
			)
			(layer "F.Fab")
		)
		(fp_line
			(start 0.67945 -0.3048)
			(end 0.67945 0.3048)
			(stroke
				(width 0.1)
				(type default)
			)
			(layer "F.Fab")
		)
		(fp_line
			(start 0.12065 -0.2794)
			(end 0.12065 -0.3048)
			(stroke
				(width 0.1)
				(type default)
			)
			(layer "F.Fab")
		)
		(fp_line
			(start 0.12065 -0.3048)
			(end 0.67945 -0.3048)
			(stroke
				(width 0.1)
				(type default)
			)
			(layer "F.Fab")
		)
		(fp_line
			(start 0.120396 0.3048)
			(end 0.120396 0.2794)
			(stroke
				(width 0.1)
				(type default)
			)
			(layer "F.Fab")
		)
		(fp_line
			(start 0.120396 0.2794)
			(end -0.12065 0.2794)
			(stroke
				(width 0.1)
				(type default)
			)
			(layer "F.Fab")
		)
		(fp_line
			(start -0.12065 0.3048)
			(end -0.67945 0.3048)
			(stroke
				(width 0.1)
				(type default)
			)
			(layer "F.Fab")
		)
		(fp_line
			(start -0.12065 0.2794)
			(end -0.12065 0.3048)
			(stroke
				(width 0.1)
				(type default)
			)
			(layer "F.Fab")
		)
		(fp_line
			(start -0.12065 -0.2794)
			(end 0.12065 -0.2794)
			(stroke
				(width 0.1)
				(type default)
			)
			(layer "F.Fab")
		)
		(fp_line
			(start -0.12065 -0.305054)
			(end -0.12065 -0.2794)
			(stroke
				(width 0.1)
				(type default)
			)
			(layer "F.Fab")
		)
		(fp_line
			(start -0.67945 0.3048)
			(end -0.67945 -0.305054)
			(stroke
				(width 0.1)
				(type default)
			)
			(layer "F.Fab")
		)
		(fp_line
			(start -0.67945 -0.305054)
			(end -0.12065 -0.305054)
			(stroke
				(width 0.1)
				(type default)
			)
			(layer "F.Fab")
		)
		(pad "1" smd circle
			(at -0.40005 0 180)
			(size 0 0)
			(layers "F.Cu" "F.Mask" "F.Paste")
			(net "P3V3_NIC6_OCP")
		)
		(pad "2" smd circle
			(at 0.40005 0 180)
			(size 0 0)
			(layers "F.Cu" "F.Mask" "F.Paste")
			(net "GND")
		)
	)
	(footprint ""
		(layer "F.Cu")
		(at 143.317468 -387.77799 -90)
		(property "Reference" "C4080"
			(at 0 0 270)
			(layer "F.SilkS")
			(hide yes)
			(effects
				(font
					(size 1.27 1.27)
				)
			)
		)
		(property "Value" ""
			(at 0 0 270)
			(layer "F.Fab")
			(effects
				(font
					(size 1.27 1.27)
				)
			)
		)
		(duplicate_pad_numbers_are_jumpers no)
		(fp_line
			(start -0.7874 0.4064)
			(end -0.7874 -0.4064)
			(stroke
				(width 0.1524)
				(type default)
			)
			(layer "F.SilkS")
		)
		(fp_line
			(start 0.7874 0.4064)
			(end -0.7874 0.4064)
			(stroke
				(width 0.1524)
				(type default)
			)
			(layer "F.SilkS")
		)
		(fp_line
			(start -0.7874 -0.4064)
			(end 0.7874 -0.4064)
			(stroke
				(width 0.1524)
				(type default)
			)
			(layer "F.SilkS")
		)
		(fp_line
			(start 0.7874 -0.4064)
			(end 0.7874 0.4064)
			(stroke
				(width 0.1524)
				(type default)
			)
			(layer "F.SilkS")
		)
		(fp_line
			(start -0.67945 0.3048)
			(end -0.67945 -0.305054)
			(stroke
				(width 0.1)
				(type default)
			)
			(layer "F.Fab")
		)
		(fp_line
			(start -0.12065 0.3048)
			(end -0.67945 0.3048)
			(stroke
				(width 0.1)
				(type default)
			)
			(layer "F.Fab")
		)
		(fp_line
			(start 0.120396 0.3048)
			(end 0.120396 0.2794)
			(stroke
				(width 0.1)
				(type default)
			)
			(layer "F.Fab")
		)
		(fp_line
			(start 0.67945 0.3048)
			(end 0.120396 0.3048)
			(stroke
				(width 0.1)
				(type default)
			)
			(layer "F.Fab")
		)
		(fp_line
			(start -0.12065 0.2794)
			(end -0.12065 0.3048)
			(stroke
				(width 0.1)
				(type default)
			)
			(layer "F.Fab")
		)
		(fp_line
			(start 0.120396 0.2794)
			(end -0.12065 0.2794)
			(stroke
				(width 0.1)
				(type default)
			)
			(layer "F.Fab")
		)
		(fp_line
			(start -0.12065 -0.2794)
			(end 0.12065 -0.2794)
			(stroke
				(width 0.1)
				(type default)
			)
			(layer "F.Fab")
		)
		(fp_line
			(start 0.12065 -0.2794)
			(end 0.12065 -0.3048)
			(stroke
				(width 0.1)
				(type default)
			)
			(layer "F.Fab")
		)
		(fp_line
			(start 0.12065 -0.3048)
			(end 0.67945 -0.3048)
			(stroke
				(width 0.1)
				(type default)
			)
			(layer "F.Fab")
		)
		(fp_line
			(start 0.67945 -0.3048)
			(end 0.67945 0.3048)
			(stroke
				(width 0.1)
				(type default)
			)
			(layer "F.Fab")
		)
		(fp_line
			(start -0.67945 -0.305054)
			(end -0.12065 -0.305054)
			(stroke
				(width 0.1)
				(type default)
			)
			(layer "F.Fab")
		)
		(fp_line
			(start -0.12065 -0.305054)
			(end -0.12065 -0.2794)
			(stroke
				(width 0.1)
				(type default)
			)
			(layer "F.Fab")
		)
		(pad "1" smd circle
			(at -0.40005 0 270)
			(size 0 0)
			(layers "F.Cu" "F.Mask" "F.Paste")
			(net "GND")
		)
		(pad "2" smd circle
			(at 0.40005 0 270)
			(size 0 0)
			(layers "F.Cu" "F.Mask" "F.Paste")
			(net "MB_BMC_MON")
		)
	)
	(footprint ""
		(layer "F.Cu")
		(at 126.79299 -151.737822 180)
		(property "Reference" "PR6885"
			(at 0 0 180)
			(layer "F.SilkS")
			(hide yes)
			(effects
				(font
					(size 1.27 1.27)
				)
			)
		)
		(property "Value" ""
			(at 0 0 180)
			(layer "F.Fab")
			(effects
				(font
					(size 1.27 1.27)
				)
			)
		)
		(duplicate_pad_numbers_are_jumpers no)
		(fp_line
			(start 0.7874 0.4064)
			(end -0.7874 0.4064)
			(stroke
				(width 0.1524)
				(type default)
			)
			(layer "F.SilkS")
		)
		(fp_line
			(start 0.7874 -0.4064)
			(end 0.7874 0.4064)
			(stroke
				(width 0.1524)
				(type default)
			)
			(layer "F.SilkS")
		)
		(fp_line
			(start -0.7874 0.4064)
			(end -0.7874 -0.4064)
			(stroke
				(width 0.1524)
				(type default)
			)
			(layer "F.SilkS")
		)
		(fp_line
			(start -0.7874 -0.4064)
			(end 0.7874 -0.4064)
			(stroke
				(width 0.1524)
				(type default)
			)
			(layer "F.SilkS")
		)
		(fp_line
			(start 0.67945 0.3048)
			(end 0.120396 0.3048)
			(stroke
				(width 0.1)
				(type default)
			)
			(layer "F.Fab")
		)
		(fp_line
			(start 0.67945 -0.3048)
			(end 0.67945 0.3048)
			(stroke
				(width 0.1)
				(type default)
			)
			(layer "F.Fab")
		)
		(fp_line
			(start 0.12065 -0.2794)
			(end 0.12065 -0.3048)
			(stroke
				(width 0.1)
				(type default)
			)
			(layer "F.Fab")
		)
		(fp_line
			(start 0.12065 -0.3048)
			(end 0.67945 -0.3048)
			(stroke
				(width 0.1)
				(type default)
			)
			(layer "F.Fab")
		)
		(fp_line
			(start 0.120396 0.3048)
			(end 0.120396 0.2794)
			(stroke
				(width 0.1)
				(type default)
			)
			(layer "F.Fab")
		)
		(fp_line
			(start 0.120396 0.2794)
			(end -0.12065 0.2794)
			(stroke
				(width 0.1)
				(type default)
			)
			(layer "F.Fab")
		)
		(fp_line
			(start -0.12065 0.3048)
			(end -0.67945 0.3048)
			(stroke
				(width 0.1)
				(type default)
			)
			(layer "F.Fab")
		)
		(fp_line
			(start -0.12065 0.2794)
			(end -0.12065 0.3048)
			(stroke
				(width 0.1)
				(type default)
			)
			(layer "F.Fab")
		)
		(fp_line
			(start -0.12065 -0.2794)
			(end 0.12065 -0.2794)
			(stroke
				(width 0.1)
				(type default)
			)
			(layer "F.Fab")
		)
		(fp_line
			(start -0.12065 -0.305054)
			(end -0.12065 -0.2794)
			(stroke
				(width 0.1)
				(type default)
			)
			(layer "F.Fab")
		)
		(fp_line
			(start -0.67945 0.3048)
			(end -0.67945 -0.305054)
			(stroke
				(width 0.1)
				(type default)
			)
			(layer "F.Fab")
		)
		(fp_line
			(start -0.67945 -0.305054)
			(end -0.12065 -0.305054)
			(stroke
				(width 0.1)
				(type default)
			)
			(layer "F.Fab")
		)
		(pad "1" smd circle
			(at -0.40005 0 180)
			(size 0 0)
			(layers "F.Cu" "F.Mask" "F.Paste")
			(net "P12V_NIC2_R")
		)
		(pad "2" smd circle
			(at 0.40005 0 180)
			(size 0 0)
			(layers "F.Cu" "F.Mask" "F.Paste")
			(net "P12V_NIC2_CO_AVIN_PD")
		)
	)
	(footprint ""
		(layer "F.Cu")
		(at 299.875702 -350.098614 90)
		(property "Reference" "C584"
			(at 0 0 90)
			(layer "F.SilkS")
			(hide yes)
			(effects
				(font
					(size 1.27 1.27)
				)
			)
		)
		(property "Value" ""
			(at 0 0 90)
			(layer "F.Fab")
			(effects
				(font
					(size 1.27 1.27)
				)
			)
		)
		(duplicate_pad_numbers_are_jumpers no)
		(fp_line
			(start 0.299974 -0.150114)
			(end 0.299974 0.150114)
			(stroke
				(width 0.1)
				(type default)
			)
			(layer "F.Fab")
		)
		(fp_line
			(start -0.299974 -0.150114)
			(end 0.299974 -0.150114)
			(stroke
				(width 0.1)
				(type default)
			)
			(layer "F.Fab")
		)
		(fp_line
			(start 0.299974 0.150114)
			(end -0.299974 0.150114)
			(stroke
				(width 0.1)
				(type default)
			)
			(layer "F.Fab")
		)
		(fp_line
			(start -0.299974 0.150114)
			(end -0.299974 -0.150114)
			(stroke
				(width 0.1)
				(type default)
			)
			(layer "F.Fab")
		)
		(pad "1" smd rect
			(at -0.2667 0 90)
			(size 0.3048 0.381)
			(layers "F.Cu" "F.Mask" "F.Paste")
			(net "P5E_PEX2_STN7_TX_DN<127>")
		)
		(pad "2" smd rect
			(at 0.2667 0 90)
			(size 0.3048 0.381)
			(layers "F.Cu" "F.Mask" "F.Paste")
			(net "P5E_PEX2_STN7_TX_C_DN<127>")
		)
	)
	(footprint ""
		(layer "F.Cu")
		(at 376.40514 -307.084984 45)
		(property "Reference" "R1418"
			(at 0 0 45)
			(layer "F.SilkS")
			(hide yes)
			(effects
				(font
					(size 1.27 1.27)
				)
			)
		)
		(property "Value" ""
			(at 0 0 45)
			(layer "F.Fab")
			(effects
				(font
					(size 1.27 1.27)
				)
			)
		)
		(duplicate_pad_numbers_are_jumpers no)
		(fp_line
			(start -0.787389 -0.406267)
			(end 0.787389 -0.406267)
			(stroke
				(width 0.1524)
				(type default)
			)
			(layer "F.SilkS")
		)
		(fp_line
			(start -0.787389 0.406267)
			(end -0.787389 -0.406267)
			(stroke
				(width 0.1524)
				(type default)
			)
			(layer "F.SilkS")
		)
		(fp_line
			(start 0.787389 -0.406267)
			(end 0.787389 0.406267)
			(stroke
				(width 0.1524)
				(type default)
			)
			(layer "F.SilkS")
		)
		(fp_line
			(start 0.787389 0.406267)
			(end -0.787389 0.406267)
			(stroke
				(width 0.1524)
				(type default)
			)
			(layer "F.SilkS")
		)
		(fp_line
			(start -0.679446 -0.305149)
			(end -0.120695 -0.304969)
			(stroke
				(width 0.1)
				(type default)
			)
			(layer "F.Fab")
		)
		(fp_line
			(start -0.120695 -0.304969)
			(end -0.120695 -0.279466)
			(stroke
				(width 0.1)
				(type default)
			)
			(layer "F.Fab")
		)
		(fp_line
			(start -0.120695 -0.279466)
			(end 0.120695 -0.279466)
			(stroke
				(width 0.1)
				(type default)
			)
			(layer "F.Fab")
		)
		(fp_line
			(start -0.679446 0.30479)
			(end -0.679446 -0.305149)
			(stroke
				(width 0.1)
				(type default)
			)
			(layer "F.Fab")
		)
		(fp_line
			(start 0.120515 -0.30479)
			(end 0.679446 -0.30479)
			(stroke
				(width 0.1)
				(type default)
			)
			(layer "F.Fab")
		)
		(fp_line
			(start 0.120695 -0.279466)
			(end 0.120515 -0.30479)
			(stroke
				(width 0.1)
				(type default)
			)
			(layer "F.Fab")
		)
		(fp_line
			(start -0.120695 0.279466)
			(end -0.120515 0.30479)
			(stroke
				(width 0.1)
				(type default)
			)
			(layer "F.Fab")
		)
		(fp_line
			(start -0.120515 0.30479)
			(end -0.679446 0.30479)
			(stroke
				(width 0.1)
				(type default)
			)
			(layer "F.Fab")
		)
		(fp_line
			(start 0.679446 -0.30479)
			(end 0.679446 0.30479)
			(stroke
				(width 0.1)
				(type default)
			)
			(layer "F.Fab")
		)
		(fp_line
			(start 0.120335 0.279466)
			(end -0.120695 0.279466)
			(stroke
				(width 0.1)
				(type default)
			)
			(layer "F.Fab")
		)
		(fp_line
			(start 0.120515 0.30479)
			(end 0.120335 0.279466)
			(stroke
				(width 0.1)
				(type default)
			)
			(layer "F.Fab")
		)
		(fp_line
			(start 0.679446 0.30479)
			(end 0.120515 0.30479)
			(stroke
				(width 0.1)
				(type default)
			)
			(layer "F.Fab")
		)
		(pad "1" smd circle
			(at -0.40005 0 45)
			(size 0 0)
			(layers "F.Cu" "F.Mask" "F.Paste")
			(net "GND")
		)
		(pad "2" smd circle
			(at 0.40005 0 45)
			(size 0 0)
			(layers "F.Cu" "F.Mask" "F.Paste")
			(net "PEX3_DBG_SEL0")
		)
	)
	(footprint ""
		(layer "F.Cu")
		(at 278.257 -388.8486 90)
		(property "Reference" "PU6601"
			(at -1.703578 2.51587 90)
			(unlocked yes)
			(layer "F.SilkS")
			(effects
				(font
					(size 0.7874 0.5842)
					(thickness 0.1524)
				)
				(justify left)
			)
		)
		(property "Value" ""
			(at 0 0 90)
			(layer "F.Fab")
			(effects
				(font
					(size 1.27 1.27)
				)
			)
		)
		(duplicate_pad_numbers_are_jumpers no)
		(fp_line
			(start 1.448308 -1.549908)
			(end 1.448308 1.549908)
			(stroke
				(width 0.1524)
				(type default)
			)
			(layer "F.SilkS")
		)
		(fp_line
			(start 0.774954 -1.549908)
			(end 1.448308 -1.549908)
			(stroke
				(width 0.1524)
				(type default)
			)
			(layer "F.SilkS")
		)
		(fp_line
			(start -0.774954 -1.549908)
			(end 0 -0.533908)
			(stroke
				(width 0.1524)
				(type default)
			)
			(layer "F.SilkS")
		)
		(fp_line
			(start -1.448308 -1.549908)
			(end -0.774954 -1.549908)
			(stroke
				(width 0.1524)
				(type default)
			)
			(layer "F.SilkS")
		)
		(fp_line
			(start 0 -0.533908)
			(end 0.774954 -1.549908)
			(stroke
				(width 0.1524)
				(type default)
			)
			(layer "F.SilkS")
		)
		(fp_line
			(start 1.448308 1.549908)
			(end -1.448308 1.549908)
			(stroke
				(width 0.1524)
				(type default)
			)
			(layer "F.SilkS")
		)
		(fp_line
			(start -1.448308 1.549908)
			(end -1.448308 -1.549908)
			(stroke
				(width 0.1524)
				(type default)
			)
			(layer "F.SilkS")
		)
		(fp_poly
			(pts
				(xy -1.549908 -1.549908) (xy -0.787908 -1.549908) (xy -0.787908 -1.880108) (xy -1.549908 -1.880108)
			)
			(stroke
				(width 0)
				(type default)
			)
			(fill yes)
			(layer "F.SilkS")
		)
		(fp_line
			(start 1.549908 -1.549908)
			(end 1.549908 1.549908)
			(stroke
				(width 0.1)
				(type default)
			)
			(layer "F.Fab")
		)
		(fp_line
			(start -1.549908 -1.549908)
			(end 1.549908 -1.549908)
			(stroke
				(width 0.1)
				(type default)
			)
			(layer "F.Fab")
		)
		(fp_line
			(start 1.549908 1.549908)
			(end -1.549908 1.549908)
			(stroke
				(width 0.1)
				(type default)
			)
			(layer "F.Fab")
		)
		(fp_line
			(start -1.549908 1.549908)
			(end -1.549908 -1.549908)
			(stroke
				(width 0.1)
				(type default)
			)
			(layer "F.Fab")
		)
		(fp_poly
			(pts
				(xy -1.549908 -1.549908) (xy -0.787908 -1.549908) (xy -0.787908 -1.880108) (xy -1.549908 -1.880108)
			)
			(stroke
				(width 0)
				(type default)
			)
			(fill yes)
			(layer "F.Fab")
		)
		(pad "1" smd rect
			(at -2.350008 -0.975106)
			(size 0.4318 1.4986)
			(layers "F.Cu" "F.Mask" "F.Paste")
			(net "P3V3_AUX")
		)
		(pad "2" smd rect
			(at -2.350008 -0.32512)
			(size 0.4318 1.4986)
			(layers "F.Cu" "F.Mask" "F.Paste")
			(net "LTC4282_TEMP_D+")
		)
		(pad "3" smd rect
			(at -2.350008 0.32512)
			(size 0.4318 1.4986)
			(layers "F.Cu" "F.Mask" "F.Paste")
			(net "LTC4282_TEMP_D-")
		)
		(pad "4" smd rect
			(at -2.350008 0.975106)
			(size 0.4318 1.4986)
			(layers "F.Cu" "F.Mask" "F.Paste")
			(net "LTC4282_T_CRIT_N")
		)
		(pad "5" smd rect
			(at 2.350008 0.975106)
			(size 0.4318 1.4986)
			(layers "F.Cu" "F.Mask" "F.Paste")
			(net "GND")
		)
		(pad "6" smd rect
			(at 2.350008 0.32512)
			(size 0.4318 1.4986)
			(layers "F.Cu" "F.Mask" "F.Paste")
			(net "LTC4282_ALERT1_R_N")
		)
		(pad "7" smd rect
			(at 2.350008 -0.32512)
			(size 0.4318 1.4986)
			(layers "F.Cu" "F.Mask" "F.Paste")
			(net "SMB_LTC4282_TEMP_SDA")
		)
		(pad "8" smd rect
			(at 2.350008 -0.975106)
			(size 0.4318 1.4986)
			(layers "F.Cu" "F.Mask" "F.Paste")
			(net "SMB_LTC4282_TEMP_SCL")
		)
	)
	(footprint ""
		(layer "F.Cu")
		(at 146.538442 -252.356874 -90)
		(property "Reference" "R1289"
			(at 0 0 270)
			(layer "F.SilkS")
			(hide yes)
			(effects
				(font
					(size 1.27 1.27)
				)
			)
		)
		(property "Value" ""
			(at 0 0 270)
			(layer "F.Fab")
			(effects
				(font
					(size 1.27 1.27)
				)
			)
		)
		(duplicate_pad_numbers_are_jumpers no)
		(fp_line
			(start -0.7874 0.4064)
			(end -0.7874 -0.4064)
			(stroke
				(width 0.1524)
				(type default)
			)
			(layer "F.SilkS")
		)
		(fp_line
			(start 0.7874 0.4064)
			(end -0.7874 0.4064)
			(stroke
				(width 0.1524)
				(type default)
			)
			(layer "F.SilkS")
		)
		(fp_line
			(start -0.7874 -0.4064)
			(end 0.7874 -0.4064)
			(stroke
				(width 0.1524)
				(type default)
			)
			(layer "F.SilkS")
		)
		(fp_line
			(start 0.7874 -0.4064)
			(end 0.7874 0.4064)
			(stroke
				(width 0.1524)
				(type default)
			)
			(layer "F.SilkS")
		)
		(fp_line
			(start -0.67945 0.3048)
			(end -0.67945 -0.305054)
			(stroke
				(width 0.1)
				(type default)
			)
			(layer "F.Fab")
		)
		(fp_line
			(start -0.12065 0.3048)
			(end -0.67945 0.3048)
			(stroke
				(width 0.1)
				(type default)
			)
			(layer "F.Fab")
		)
		(fp_line
			(start 0.120396 0.3048)
			(end 0.120396 0.2794)
			(stroke
				(width 0.1)
				(type default)
			)
			(layer "F.Fab")
		)
		(fp_line
			(start 0.67945 0.3048)
			(end 0.120396 0.3048)
			(stroke
				(width 0.1)
				(type default)
			)
			(layer "F.Fab")
		)
		(fp_line
			(start -0.12065 0.2794)
			(end -0.12065 0.3048)
			(stroke
				(width 0.1)
				(type default)
			)
			(layer "F.Fab")
		)
		(fp_line
			(start 0.120396 0.2794)
			(end -0.12065 0.2794)
			(stroke
				(width 0.1)
				(type default)
			)
			(layer "F.Fab")
		)
		(fp_line
			(start -0.12065 -0.2794)
			(end 0.12065 -0.2794)
			(stroke
				(width 0.1)
				(type default)
			)
			(layer "F.Fab")
		)
		(fp_line
			(start 0.12065 -0.2794)
			(end 0.12065 -0.3048)
			(stroke
				(width 0.1)
				(type default)
			)
			(layer "F.Fab")
		)
		(fp_line
			(start 0.12065 -0.3048)
			(end 0.67945 -0.3048)
			(stroke
				(width 0.1)
				(type default)
			)
			(layer "F.Fab")
		)
		(fp_line
			(start 0.67945 -0.3048)
			(end 0.67945 0.3048)
			(stroke
				(width 0.1)
				(type default)
			)
			(layer "F.Fab")
		)
		(fp_line
			(start -0.67945 -0.305054)
			(end -0.12065 -0.305054)
			(stroke
				(width 0.1)
				(type default)
			)
			(layer "F.Fab")
		)
		(fp_line
			(start -0.12065 -0.305054)
			(end -0.12065 -0.2794)
			(stroke
				(width 0.1)
				(type default)
			)
			(layer "F.Fab")
		)
		(pad "1" smd circle
			(at -0.40005 0 270)
			(size 0 0)
			(layers "F.Cu" "F.Mask" "F.Paste")
			(net "GND")
		)
		(pad "2" smd circle
			(at 0.40005 0 270)
			(size 0 0)
			(layers "F.Cu" "F.Mask" "F.Paste")
			(net "PEX1_MODE_SEL0")
		)
	)
	(footprint ""
		(layer "F.Cu")
		(at 261.115048 -412.187898 -90)
		(property "Reference" "J1"
			(at 13.812012 52.36083 0)
			(unlocked yes)
			(layer "F.SilkS")
			(effects
				(font
					(size 2.032 1.524)
					(thickness 0.1524)
				)
			)
		)
		(property "Value" ""
			(at 0 0 270)
			(layer "F.Fab")
			(effects
				(font
					(size 1.27 1.27)
				)
			)
		)
		(duplicate_pad_numbers_are_jumpers no)
		(fp_line
			(start -18.370042 58.755026)
			(end -18.370042 -11.765026)
			(stroke
				(width 0.1524)
				(type default)
			)
			(layer "F.SilkS")
		)
		(fp_line
			(start 11.679936 58.755026)
			(end -18.370042 58.755026)
			(stroke
				(width 0.1524)
				(type default)
			)
			(layer "F.SilkS")
		)
		(fp_line
			(start -15.370048 55.755032)
			(end -15.370048 -8.765032)
			(stroke
				(width 0.1524)
				(type default)
			)
			(layer "F.SilkS")
		)
		(fp_line
			(start 8.24992 55.755032)
			(end -15.370048 55.755032)
			(stroke
				(width 0.1524)
				(type default)
			)
			(layer "F.SilkS")
		)
		(fp_line
			(start 8.24992 47.8155)
			(end 8.24992 55.755032)
			(stroke
				(width 0.1524)
				(type default)
			)
			(layer "F.SilkS")
		)
		(fp_line
			(start 8.24992 45.2628)
			(end 8.24992 46.1645)
			(stroke
				(width 0.1524)
				(type default)
			)
			(layer "F.SilkS")
		)
		(fp_line
			(start 8.24992 38.9128)
			(end 8.24992 43.6372)
			(stroke
				(width 0.1524)
				(type default)
			)
			(layer "F.SilkS")
		)
		(fp_line
			(start 8.24992 36.38296)
			(end 8.24992 37.27704)
			(stroke
				(width 0.1524)
				(type default)
			)
			(layer "F.SilkS")
		)
		(fp_line
			(start 8.24992 30.0355)
			(end 8.24992 34.73704)
			(stroke
				(width 0.1524)
				(type default)
			)
			(layer "F.SilkS")
		)
		(fp_line
			(start 8.24992 27.50312)
			(end 8.24992 28.3972)
			(stroke
				(width 0.1524)
				(type default)
			)
			(layer "F.SilkS")
		)
		(fp_line
			(start 8.24992 21.15058)
			(end 8.24992 25.84704)
			(stroke
				(width 0.1524)
				(type default)
			)
			(layer "F.SilkS")
		)
		(fp_line
			(start 8.24992 18.60296)
			(end 8.24992 19.49958)
			(stroke
				(width 0.1524)
				(type default)
			)
			(layer "F.SilkS")
		)
		(fp_line
			(start 8.24992 12.26312)
			(end 8.24992 16.96212)
			(stroke
				(width 0.1524)
				(type default)
			)
			(layer "F.SilkS")
		)
		(fp_line
			(start 8.24992 9.7028)
			(end 8.24992 10.6045)
			(stroke
				(width 0.1524)
				(type default)
			)
			(layer "F.SilkS")
		)
		(fp_line
			(start 8.24992 3.3655)
			(end 8.24992 8.0645)
			(stroke
				(width 0.1524)
				(type default)
			)
			(layer "F.SilkS")
		)
		(fp_line
			(start 8.24992 0.81788)
			(end 8.24992 1.7272)
			(stroke
				(width 0.1524)
				(type default)
			)
			(layer "F.SilkS")
		)
		(fp_line
			(start -15.370048 -8.765032)
			(end 8.24992 -8.765032)
			(stroke
				(width 0.1524)
				(type default)
			)
			(layer "F.SilkS")
		)
		(fp_line
			(start -5.08 -8.765032)
			(end -5.08 55.755032)
			(stroke
				(width 0.1524)
				(type default)
			)
			(layer "F.SilkS")
		)
		(fp_line
			(start 8.24992 -8.765032)
			(end 8.24992 -0.8128)
			(stroke
				(width 0.1524)
				(type default)
			)
			(layer "F.SilkS")
		)
		(fp_line
			(start -18.370042 -11.765026)
			(end 11.679936 -11.765026)
			(stroke
				(width 0.1524)
				(type default)
			)
			(layer "F.SilkS")
		)
		(fp_line
			(start 11.679936 -11.765026)
			(end 11.679936 58.755026)
			(stroke
				(width 0.1524)
				(type default)
			)
			(layer "F.SilkS")
		)
		(fp_poly
			(pts
				(xy 0.508 -10.211816) (xy -0.508 -10.211816) (xy 0 -9.195816)
			)
			(stroke
				(width 0)
				(type default)
			)
			(fill yes)
			(layer "F.SilkS")
		)
		(fp_line
			(start -18.370042 58.755026)
			(end -18.370042 -11.765026)
			(stroke
				(width 0.1524)
				(type default)
			)
			(layer "B.SilkS")
		)
		(fp_line
			(start 11.679936 58.755026)
			(end -18.370042 58.755026)
			(stroke
				(width 0.1524)
				(type default)
			)
			(layer "B.SilkS")
		)
		(fp_line
			(start -18.370042 -11.765026)
			(end 11.679936 -11.765026)
			(stroke
				(width 0.1524)
				(type default)
			)
			(layer "B.SilkS")
		)
		(fp_line
			(start 11.679936 -11.765026)
			(end 11.679936 58.755026)
			(stroke
				(width 0.1524)
				(type default)
			)
			(layer "B.SilkS")
		)
		(fp_line
			(start -18.370042 58.755026)
			(end -18.370042 -11.765026)
			(stroke
				(width 0.1)
				(type default)
			)
			(layer "B.Fab")
		)
		(fp_line
			(start 11.679936 58.755026)
			(end -18.370042 58.755026)
			(stroke
				(width 0.1)
				(type default)
			)
			(layer "B.Fab")
		)
		(fp_line
			(start -18.370042 -11.765026)
			(end 11.679936 -11.765026)
			(stroke
				(width 0.1)
				(type default)
			)
			(layer "B.Fab")
		)
		(fp_line
			(start 11.679936 -11.765026)
			(end 11.679936 58.755026)
			(stroke
				(width 0.1)
				(type default)
			)
			(layer "B.Fab")
		)
		(fp_line
			(start -15.370048 55.755032)
			(end -15.370048 -8.765032)
			(stroke
				(width 0.1)
				(type default)
			)
			(layer "F.Fab")
		)
		(fp_line
			(start 8.24992 55.755032)
			(end -15.370048 55.755032)
			(stroke
				(width 0.1)
				(type default)
			)
			(layer "F.Fab")
		)
		(fp_line
			(start -15.370048 -8.765032)
			(end 8.24992 -8.765032)
			(stroke
				(width 0.1)
				(type default)
			)
			(layer "F.Fab")
		)
		(fp_line
			(start 8.24992 -8.765032)
			(end 8.24992 55.755032)
			(stroke
				(width 0.1)
				(type default)
			)
			(layer "F.Fab")
		)
		(fp_poly
			(pts
				(xy 0.508 -10.211816) (xy -0.508 -10.211816) (xy 0 -9.195816)
			)
			(stroke
				(width 0)
				(type default)
			)
			(fill yes)
			(layer "F.Fab")
		)
		(fp_text user "PRESS-FIT"
			(at 10.12825 31.1023 0)
			(unlocked yes)
			(layer "F.SilkS")
			(effects
				(font
					(size 1.905 1.4224)
					(thickness 0.1524)
				)
				(justify left)
			)
		)
		(fp_text user "PRESS-FIT"
			(at 10.07745 15.3289 0)
			(unlocked yes)
			(layer "B.SilkS")
			(effects
				(font
					(size 1.905 1.4224)
					(thickness 0.1524)
				)
				(justify left mirror)
			)
		)
		(fp_text user "PRESS-FIT"
			(at 10.07745 15.3289 0)
			(unlocked yes)
			(layer "B.Fab")
			(effects
				(font
					(size 1.905 1.4224)
					(thickness 0.1524)
				)
				(justify left mirror)
			)
		)
		(fp_text user "PRESS-FIT"
			(at 10.12825 31.1023 0)
			(unlocked yes)
			(layer "F.Fab")
			(effects
				(font
					(size 1.905 1.4224)
					(thickness 0.1524)
				)
				(justify left)
			)
		)
		(pad "P1_1" thru_hole rect
			(at 0 0 270)
			(size 1.790954 1.790954)
			(drill 1.015746)
			(layers "*.Cu" "*.Mask")
			(remove_unused_layers no)
			(net "GND")
			(clearance -0.133604)
			(padstack
				(mode front_inner_back)
				(layer "Inner"
					(shape circle)
					(size 1.790954 1.790954)
					(clearance -0.133604)
				)
				(layer "B.Cu"
					(shape rect)
					(size 1.790954 1.790954)
					(clearance -0.133604)
				)
			)
		)
		(pad "P1_2" thru_hole circle
			(at 2.54 0 270)
			(size 1.790954 1.790954)
			(drill 1.015746)
			(layers "*.Cu" "*.Mask")
			(remove_unused_layers no)
			(net "GND")
			(clearance -0.133604)
		)
		(pad "P1_3" thru_hole circle
			(at 5.08 0 270)
			(size 1.790954 1.790954)
			(drill 1.015746)
			(layers "*.Cu" "*.Mask")
			(remove_unused_layers no)
			(net "GND")
			(clearance -0.133604)
		)
		(pad "P1_4" thru_hole circle
			(at 7.62 0 270)
			(size 1.790954 1.790954)
			(drill 1.015746)
			(layers "*.Cu" "*.Mask")
			(remove_unused_layers no)
			(net "GND")
			(clearance -0.133604)
		)
		(pad "P1_5" thru_hole circle
			(at 0 2.54 270)
			(size 1.790954 1.790954)
			(drill 1.015746)
			(layers "*.Cu" "*.Mask")
			(remove_unused_layers no)
			(net "GND")
			(clearance -0.133604)
		)
		(pad "P1_6" thru_hole circle
			(at 2.54 2.54 270)
			(size 1.790954 1.790954)
			(drill 1.015746)
			(layers "*.Cu" "*.Mask")
			(remove_unused_layers no)
			(net "GND")
			(clearance -0.133604)
		)
		(pad "P1_7" thru_hole circle
			(at 5.08 2.54 270)
			(size 1.790954 1.790954)
			(drill 1.015746)
			(layers "*.Cu" "*.Mask")
			(remove_unused_layers no)
			(net "GND")
			(clearance -0.133604)
		)
		(pad "P1_8" thru_hole circle
			(at 7.62 2.54 270)
			(size 1.790954 1.790954)
			(drill 1.015746)
			(layers "*.Cu" "*.Mask")
			(remove_unused_layers no)
			(net "GND")
			(clearance -0.133604)
		)
		(pad "P2_1" thru_hole circle
			(at 0 8.89 270)
			(size 1.790954 1.790954)
			(drill 1.015746)
			(layers "*.Cu" "*.Mask")
			(remove_unused_layers no)
			(net "GND")
			(clearance -0.133604)
		)
		(pad "P2_2" thru_hole circle
			(at 2.54 8.89 270)
			(size 1.790954 1.790954)
			(drill 1.015746)
			(layers "*.Cu" "*.Mask")
			(remove_unused_layers no)
			(net "GND")
			(clearance -0.133604)
		)
		(pad "P2_3" thru_hole circle
			(at 5.08 8.89 270)
			(size 1.790954 1.790954)
			(drill 1.015746)
			(layers "*.Cu" "*.Mask")
			(remove_unused_layers no)
			(net "GND")
			(clearance -0.133604)
		)
		(pad "P2_4" thru_hole circle
			(at 7.62 8.89 270)
			(size 1.790954 1.790954)
			(drill 1.015746)
			(layers "*.Cu" "*.Mask")
			(remove_unused_layers no)
			(net "GND")
			(clearance -0.133604)
		)
		(pad "P2_5" thru_hole circle
			(at 0 11.43 270)
			(size 1.790954 1.790954)
			(drill 1.015746)
			(layers "*.Cu" "*.Mask")
			(remove_unused_layers no)
			(net "GND")
			(clearance -0.133604)
		)
		(pad "P2_6" thru_hole circle
			(at 2.54 11.43 270)
			(size 1.790954 1.790954)
			(drill 1.015746)
			(layers "*.Cu" "*.Mask")
			(remove_unused_layers no)
			(net "GND")
			(clearance -0.133604)
		)
		(pad "P2_7" thru_hole circle
			(at 5.08 11.43 270)
			(size 1.790954 1.790954)
			(drill 1.015746)
			(layers "*.Cu" "*.Mask")
			(remove_unused_layers no)
			(net "GND")
			(clearance -0.133604)
		)
		(pad "P2_8" thru_hole circle
			(at 7.62 11.43 270)
			(size 1.790954 1.790954)
			(drill 1.015746)
			(layers "*.Cu" "*.Mask")
			(remove_unused_layers no)
			(net "GND")
			(clearance -0.133604)
		)
		(pad "P3_1" thru_hole circle
			(at 0 17.78 270)
			(size 1.790954 1.790954)
			(drill 1.015746)
			(layers "*.Cu" "*.Mask")
			(remove_unused_layers no)
			(net "GND")
			(clearance -0.133604)
		)
		(pad "P3_2" thru_hole circle
			(at 2.54 17.78 270)
			(size 1.790954 1.790954)
			(drill 1.015746)
			(layers "*.Cu" "*.Mask")
			(remove_unused_layers no)
			(net "GND")
			(clearance -0.133604)
		)
		(pad "P3_3" thru_hole circle
			(at 5.08 17.78 270)
			(size 1.790954 1.790954)
			(drill 1.015746)
			(layers "*.Cu" "*.Mask")
			(remove_unused_layers no)
			(net "GND")
			(clearance -0.133604)
		)
		(pad "P3_4" thru_hole circle
			(at 7.62 17.78 270)
			(size 1.790954 1.790954)
			(drill 1.015746)
			(layers "*.Cu" "*.Mask")
			(remove_unused_layers no)
			(net "GND")
			(clearance -0.133604)
		)
		(pad "P3_5" thru_hole circle
			(at 0 20.32 270)
			(size 1.790954 1.790954)
			(drill 1.015746)
			(layers "*.Cu" "*.Mask")
			(remove_unused_layers no)
			(net "GND")
			(clearance -0.133604)
		)
		(pad "P3_6" thru_hole circle
			(at 2.54 20.32 270)
			(size 1.790954 1.790954)
			(drill 1.015746)
			(layers "*.Cu" "*.Mask")
			(remove_unused_layers no)
			(net "GND")
			(clearance -0.133604)
		)
		(pad "P3_7" thru_hole circle
			(at 5.08 20.32 270)
			(size 1.790954 1.790954)
			(drill 1.015746)
			(layers "*.Cu" "*.Mask")
			(remove_unused_layers no)
			(net "GND")
			(clearance -0.133604)
		)
		(pad "P3_8" thru_hole circle
			(at 7.62 20.32 270)
			(size 1.790954 1.790954)
			(drill 1.015746)
			(layers "*.Cu" "*.Mask")
			(remove_unused_layers no)
			(net "GND")
			(clearance -0.133604)
		)
		(pad "P4_1" thru_hole circle
			(at 0 26.67 270)
			(size 1.790954 1.790954)
			(drill 1.015746)
			(layers "*.Cu" "*.Mask")
			(remove_unused_layers no)
			(net "P12V_STBY")
			(clearance -0.133604)
		)
		(pad "P4_2" thru_hole circle
			(at 2.54 26.67 270)
			(size 1.790954 1.790954)
			(drill 1.015746)
			(layers "*.Cu" "*.Mask")
			(remove_unused_layers no)
			(net "P12V_STBY")
			(clearance -0.133604)
		)
		(pad "P4_3" thru_hole circle
			(at 5.08 26.67 270)
			(size 1.790954 1.790954)
			(drill 1.015746)
			(layers "*.Cu" "*.Mask")
			(remove_unused_layers no)
			(net "P12V_STBY")
			(clearance -0.133604)
		)
		(pad "P4_4" thru_hole circle
			(at 7.62 26.67 270)
			(size 1.790954 1.790954)
			(drill 1.015746)
			(layers "*.Cu" "*.Mask")
			(remove_unused_layers no)
			(net "P12V_STBY")
			(clearance -0.133604)
		)
		(pad "P4_5" thru_hole circle
			(at 0 29.21 270)
			(size 1.790954 1.790954)
			(drill 1.015746)
			(layers "*.Cu" "*.Mask")
			(remove_unused_layers no)
			(net "P12V_STBY")
			(clearance -0.133604)
		)
		(pad "P4_6" thru_hole circle
			(at 2.54 29.21 270)
			(size 1.790954 1.790954)
			(drill 1.015746)
			(layers "*.Cu" "*.Mask")
			(remove_unused_layers no)
			(net "P12V_STBY")
			(clearance -0.133604)
		)
		(pad "P4_7" thru_hole circle
			(at 5.08 29.21 270)
			(size 1.790954 1.790954)
			(drill 1.015746)
			(layers "*.Cu" "*.Mask")
			(remove_unused_layers no)
			(net "P12V_STBY")
			(clearance -0.133604)
		)
		(pad "P4_8" thru_hole circle
			(at 7.62 29.21 270)
			(size 1.790954 1.790954)
			(drill 1.015746)
			(layers "*.Cu" "*.Mask")
			(remove_unused_layers no)
			(net "P12V_STBY")
			(clearance -0.133604)
		)
		(pad "P5_1" thru_hole circle
			(at 0 35.56 270)
			(size 1.790954 1.790954)
			(drill 1.015746)
			(layers "*.Cu" "*.Mask")
			(remove_unused_layers no)
			(net "P12V_STBY")
			(clearance -0.133604)
		)
		(pad "P5_2" thru_hole circle
			(at 2.54 35.56 270)
			(size 1.790954 1.790954)
			(drill 1.015746)
			(layers "*.Cu" "*.Mask")
			(remove_unused_layers no)
			(net "P12V_STBY")
			(clearance -0.133604)
		)
		(pad "P5_3" thru_hole circle
			(at 5.08 35.56 270)
			(size 1.790954 1.790954)
			(drill 1.015746)
			(layers "*.Cu" "*.Mask")
			(remove_unused_layers no)
			(net "P12V_STBY")
			(clearance -0.133604)
		)
		(pad "P5_4" thru_hole circle
			(at 7.62 35.56 270)
			(size 1.790954 1.790954)
			(drill 1.015746)
			(layers "*.Cu" "*.Mask")
			(remove_unused_layers no)
			(net "P12V_STBY")
			(clearance -0.133604)
		)
		(pad "P5_5" thru_hole circle
			(at 0 38.1 270)
			(size 1.790954 1.790954)
			(drill 1.015746)
			(layers "*.Cu" "*.Mask")
			(remove_unused_layers no)
			(net "P12V_STBY")
			(clearance -0.133604)
		)
		(pad "P5_6" thru_hole circle
			(at 2.54 38.1 270)
			(size 1.790954 1.790954)
			(drill 1.015746)
			(layers "*.Cu" "*.Mask")
			(remove_unused_layers no)
			(net "P12V_STBY")
			(clearance -0.133604)
		)
		(pad "P5_7" thru_hole circle
			(at 5.08 38.1 270)
			(size 1.790954 1.790954)
			(drill 1.015746)
			(layers "*.Cu" "*.Mask")
			(remove_unused_layers no)
			(net "P12V_STBY")
			(clearance -0.133604)
		)
		(pad "P5_8" thru_hole circle
			(at 7.62 38.1 270)
			(size 1.790954 1.790954)
			(drill 1.015746)
			(layers "*.Cu" "*.Mask")
			(remove_unused_layers no)
			(net "P12V_STBY")
			(clearance -0.133604)
		)
		(pad "P6_1" thru_hole circle
			(at 0 44.45 270)
			(size 1.790954 1.790954)
			(drill 1.015746)
			(layers "*.Cu" "*.Mask")
			(remove_unused_layers no)
			(net "P12V_STBY")
			(clearance -0.133604)
		)
		(pad "P6_2" thru_hole circle
			(at 2.54 44.45 270)
			(size 1.790954 1.790954)
			(drill 1.015746)
			(layers "*.Cu" "*.Mask")
			(remove_unused_layers no)
			(net "P12V_STBY")
			(clearance -0.133604)
		)
		(pad "P6_3" thru_hole circle
			(at 5.08 44.45 270)
			(size 1.790954 1.790954)
			(drill 1.015746)
			(layers "*.Cu" "*.Mask")
			(remove_unused_layers no)
			(net "P12V_STBY")
			(clearance -0.133604)
		)
		(pad "P6_4" thru_hole circle
			(at 7.62 44.45 270)
			(size 1.790954 1.790954)
			(drill 1.015746)
			(layers "*.Cu" "*.Mask")
			(remove_unused_layers no)
			(net "P12V_STBY")
			(clearance -0.133604)
		)
		(pad "P6_5" thru_hole circle
			(at 0 46.99 270)
			(size 1.790954 1.790954)
			(drill 1.015746)
			(layers "*.Cu" "*.Mask")
			(remove_unused_layers no)
			(net "P12V_STBY")
			(clearance -0.133604)
		)
		(pad "P6_6" thru_hole circle
			(at 2.54 46.99 270)
			(size 1.790954 1.790954)
			(drill 1.015746)
			(layers "*.Cu" "*.Mask")
			(remove_unused_layers no)
			(net "P12V_STBY")
			(clearance -0.133604)
		)
		(pad "P6_7" thru_hole circle
			(at 5.08 46.99 270)
			(size 1.790954 1.790954)
			(drill 1.015746)
			(layers "*.Cu" "*.Mask")
			(remove_unused_layers no)
			(net "P12V_STBY")
			(clearance -0.133604)
		)
		(pad "P6_8" thru_hole circle
			(at 7.62 46.99 270)
			(size 1.790954 1.790954)
			(drill 1.015746)
			(layers "*.Cu" "*.Mask")
			(remove_unused_layers no)
			(net "P12V_STBY")
			(clearance -0.133604)
		)
		(zone
			(layer "B.Cu")
			(hatch none 0.5)
			(connect_pads
				(clearance 0)
			)
			(min_thickness 0.25)
			(keepout
				(tracks allowed)
				(vias not_allowed)
				(pads allowed)
				(copperpour not_allowed)
				(footprints allowed)
			)
			(placement
				(enabled no)
				(sheetname "")
			)
			(fill
				(thermal_gap 0.5)
				(thermal_bridge_width 0.5)
				(island_removal_mode 0)
			)
			(polygon
				(pts
					(xy 217.624152 -413.147002) (xy 213.165944 -413.147002) (xy 213.165944 -403.608794) (xy 217.624152 -403.608794)
				)
			)
		)
		(zone
			(layer "B.Cu")
			(hatch none 0.5)
			(connect_pads
				(clearance 0)
			)
			(min_thickness 0.25)
			(keepout
				(tracks allowed)
				(vias not_allowed)
				(pads allowed)
				(copperpour not_allowed)
				(footprints allowed)
			)
			(placement
				(enabled no)
				(sheetname "")
			)
			(fill
				(thermal_gap 0.5)
				(thermal_bridge_width 0.5)
				(island_removal_mode 0)
			)
			(polygon
				(pts
					(xy 226.514152 -413.147002) (xy 222.055944 -413.147002) (xy 222.055944 -403.608794) (xy 226.514152 -403.608794)
				)
			)
		)
		(zone
			(layer "B.Cu")
			(hatch none 0.5)
			(connect_pads
				(clearance 0)
			)
			(min_thickness 0.25)
			(keepout
				(tracks allowed)
				(vias not_allowed)
				(pads allowed)
				(copperpour not_allowed)
				(footprints allowed)
			)
			(placement
				(enabled no)
				(sheetname "")
			)
			(fill
				(thermal_gap 0.5)
				(thermal_bridge_width 0.5)
				(island_removal_mode 0)
			)
			(polygon
				(pts
					(xy 235.404152 -413.147002) (xy 230.945944 -413.147002) (xy 230.945944 -403.608794) (xy 235.404152 -403.608794)
				)
			)
		)
		(zone
			(layer "B.Cu")
			(hatch none 0.5)
			(connect_pads
				(clearance 0)
			)
			(min_thickness 0.25)
			(keepout
				(tracks allowed)
				(vias not_allowed)
				(pads allowed)
				(copperpour not_allowed)
				(footprints allowed)
			)
			(placement
				(enabled no)
				(sheetname "")
			)
			(fill
				(thermal_gap 0.5)
				(thermal_bridge_width 0.5)
				(island_removal_mode 0)
			)
			(polygon
				(pts
					(xy 244.294152 -413.147002) (xy 239.835944 -413.147002) (xy 239.835944 -403.608794) (xy 244.294152 -403.608794)
				)
			)
		)
		(zone
			(layer "B.Cu")
			(hatch none 0.5)
			(connect_pads
				(clearance 0)
			)
			(min_thickness 0.25)
			(keepout
				(tracks allowed)
				(vias not_allowed)
				(pads allowed)
				(copperpour not_allowed)
				(footprints allowed)
			)
			(placement
				(enabled no)
				(sheetname "")
			)
			(fill
				(thermal_gap 0.5)
				(thermal_bridge_width 0.5)
				(island_removal_mode 0)
			)
			(polygon
				(pts
					(xy 253.184152 -413.147002) (xy 248.725944 -413.147002) (xy 248.725944 -403.608794) (xy 253.184152 -403.608794)
				)
			)
		)
		(zone
			(layer "B.Cu")
			(hatch none 0.5)
			(connect_pads
				(clearance 0)
			)
			(min_thickness 0.25)
			(keepout
				(tracks allowed)
				(vias not_allowed)
				(pads allowed)
				(copperpour not_allowed)
				(footprints allowed)
			)
			(placement
				(enabled no)
				(sheetname "")
			)
			(fill
				(thermal_gap 0.5)
				(thermal_bridge_width 0.5)
				(island_removal_mode 0)
			)
			(polygon
				(pts
					(xy 262.074152 -413.147002) (xy 257.615944 -413.147002) (xy 257.615944 -403.608794) (xy 262.074152 -403.608794)
				)
			)
		)
	)
	(footprint ""
		(layer "F.Cu")
		(at 59.10326 -59.571636 90)
		(property "Reference" "PR265"
			(at 0 0 90)
			(layer "F.SilkS")
			(hide yes)
			(effects
				(font
					(size 1.27 1.27)
				)
			)
		)
		(property "Value" ""
			(at 0 0 90)
			(layer "F.Fab")
			(effects
				(font
					(size 1.27 1.27)
				)
			)
		)
		(duplicate_pad_numbers_are_jumpers no)
		(fp_line
			(start 0.7874 -0.4064)
			(end 0.7874 0.4064)
			(stroke
				(width 0.1524)
				(type default)
			)
			(layer "F.SilkS")
		)
		(fp_line
			(start -0.7874 -0.4064)
			(end 0.7874 -0.4064)
			(stroke
				(width 0.1524)
				(type default)
			)
			(layer "F.SilkS")
		)
		(fp_line
			(start 0.7874 0.4064)
			(end -0.7874 0.4064)
			(stroke
				(width 0.1524)
				(type default)
			)
			(layer "F.SilkS")
		)
		(fp_line
			(start -0.7874 0.4064)
			(end -0.7874 -0.4064)
			(stroke
				(width 0.1524)
				(type default)
			)
			(layer "F.SilkS")
		)
		(fp_line
			(start -0.12065 -0.305054)
			(end -0.12065 -0.2794)
			(stroke
				(width 0.1)
				(type default)
			)
			(layer "F.Fab")
		)
		(fp_line
			(start -0.67945 -0.305054)
			(end -0.12065 -0.305054)
			(stroke
				(width 0.1)
				(type default)
			)
			(layer "F.Fab")
		)
		(fp_line
			(start 0.67945 -0.3048)
			(end 0.67945 0.3048)
			(stroke
				(width 0.1)
				(type default)
			)
			(layer "F.Fab")
		)
		(fp_line
			(start 0.12065 -0.3048)
			(end 0.67945 -0.3048)
			(stroke
				(width 0.1)
				(type default)
			)
			(layer "F.Fab")
		)
		(fp_line
			(start 0.12065 -0.2794)
			(end 0.12065 -0.3048)
			(stroke
				(width 0.1)
				(type default)
			)
			(layer "F.Fab")
		)
		(fp_line
			(start -0.12065 -0.2794)
			(end 0.12065 -0.2794)
			(stroke
				(width 0.1)
				(type default)
			)
			(layer "F.Fab")
		)
		(fp_line
			(start 0.120396 0.2794)
			(end -0.12065 0.2794)
			(stroke
				(width 0.1)
				(type default)
			)
			(layer "F.Fab")
		)
		(fp_line
			(start -0.12065 0.2794)
			(end -0.12065 0.3048)
			(stroke
				(width 0.1)
				(type default)
			)
			(layer "F.Fab")
		)
		(fp_line
			(start 0.67945 0.3048)
			(end 0.120396 0.3048)
			(stroke
				(width 0.1)
				(type default)
			)
			(layer "F.Fab")
		)
		(fp_line
			(start 0.120396 0.3048)
			(end 0.120396 0.2794)
			(stroke
				(width 0.1)
				(type default)
			)
			(layer "F.Fab")
		)
		(fp_line
			(start -0.12065 0.3048)
			(end -0.67945 0.3048)
			(stroke
				(width 0.1)
				(type default)
			)
			(layer "F.Fab")
		)
		(fp_line
			(start -0.67945 0.3048)
			(end -0.67945 -0.305054)
			(stroke
				(width 0.1)
				(type default)
			)
			(layer "F.Fab")
		)
		(pad "1" smd circle
			(at -0.40005 0 90)
			(size 0 0)
			(layers "F.Cu" "F.Mask" "F.Paste")
			(net "P3V3_SSD2_OCP")
		)
		(pad "2" smd circle
			(at 0.40005 0 90)
			(size 0 0)
			(layers "F.Cu" "F.Mask" "F.Paste")
			(net "GND")
		)
	)
	(footprint ""
		(layer "F.Cu")
		(at 254.521208 -355.742748 -90)
		(property "Reference" "PC6606"
			(at 0 0 270)
			(layer "F.SilkS")
			(hide yes)
			(effects
				(font
					(size 1.27 1.27)
				)
			)
		)
		(property "Value" ""
			(at 0 0 270)
			(layer "F.Fab")
			(effects
				(font
					(size 1.27 1.27)
				)
			)
		)
		(duplicate_pad_numbers_are_jumpers no)
		(fp_line
			(start -1.2954 0.5842)
			(end -1.2954 -0.5842)
			(stroke
				(width 0.1524)
				(type default)
			)
			(layer "F.SilkS")
		)
		(fp_line
			(start 1.2954 0.5842)
			(end -1.2954 0.5842)
			(stroke
				(width 0.1524)
				(type default)
			)
			(layer "F.SilkS")
		)
		(fp_line
			(start -1.2954 -0.5842)
			(end 1.2954 -0.5842)
			(stroke
				(width 0.1524)
				(type default)
			)
			(layer "F.SilkS")
		)
		(fp_line
			(start 1.2954 -0.5842)
			(end 1.2954 0.5842)
			(stroke
				(width 0.1524)
				(type default)
			)
			(layer "F.SilkS")
		)
		(fp_line
			(start -0.8636 0.4572)
			(end -0.8636 0.4064)
			(stroke
				(width 0.1)
				(type default)
			)
			(layer "F.Fab")
		)
		(fp_line
			(start 0.8636 0.4572)
			(end -0.8636 0.4572)
			(stroke
				(width 0.1)
				(type default)
			)
			(layer "F.Fab")
		)
		(fp_line
			(start -1.1938 0.4064)
			(end -1.1938 -0.4064)
			(stroke
				(width 0.1)
				(type default)
			)
			(layer "F.Fab")
		)
		(fp_line
			(start -0.8636 0.4064)
			(end -1.1938 0.4064)
			(stroke
				(width 0.1)
				(type default)
			)
			(layer "F.Fab")
		)
		(fp_line
			(start 0.8636 0.4064)
			(end 0.8636 0.4572)
			(stroke
				(width 0.1)
				(type default)
			)
			(layer "F.Fab")
		)
		(fp_line
			(start 1.1938 0.4064)
			(end 0.8636 0.4064)
			(stroke
				(width 0.1)
				(type default)
			)
			(layer "F.Fab")
		)
		(fp_line
			(start -1.1938 -0.4064)
			(end -0.8636 -0.4064)
			(stroke
				(width 0.1)
				(type default)
			)
			(layer "F.Fab")
		)
		(fp_line
			(start -0.8636 -0.4064)
			(end -0.8636 -0.4572)
			(stroke
				(width 0.1)
				(type default)
			)
			(layer "F.Fab")
		)
		(fp_line
			(start 0.8636 -0.4064)
			(end 1.1938 -0.4064)
			(stroke
				(width 0.1)
				(type default)
			)
			(layer "F.Fab")
		)
		(fp_line
			(start 1.1938 -0.4064)
			(end 1.1938 0.4064)
			(stroke
				(width 0.1)
				(type default)
			)
			(layer "F.Fab")
		)
		(fp_line
			(start -0.8636 -0.4572)
			(end 0.8636 -0.4572)
			(stroke
				(width 0.1)
				(type default)
			)
			(layer "F.Fab")
		)
		(fp_line
			(start 0.8636 -0.4572)
			(end 0.8636 -0.4064)
			(stroke
				(width 0.1)
				(type default)
			)
			(layer "F.Fab")
		)
		(pad "1" smd rect
			(at -0.7366 0 180)
			(size 0.7112 0.8128)
			(layers "F.Cu" "F.Mask" "F.Paste")
			(net "P12V_AUX")
		)
		(pad "2" smd rect
			(at 0.7366 0 180)
			(size 0.7112 0.8128)
			(layers "F.Cu" "F.Mask" "F.Paste")
			(net "GND")
		)
	)
	(footprint ""
		(layer "F.Cu")
		(at 407.693114 -392.016742)
		(property "Reference" "R6775"
			(at 0 0 0)
			(layer "F.SilkS")
			(hide yes)
			(effects
				(font
					(size 1.27 1.27)
				)
			)
		)
		(property "Value" ""
			(at 0 0 0)
			(layer "F.Fab")
			(effects
				(font
					(size 1.27 1.27)
				)
			)
		)
		(duplicate_pad_numbers_are_jumpers no)
		(fp_line
			(start -0.7874 -0.4064)
			(end 0.7874 -0.4064)
			(stroke
				(width 0.1524)
				(type default)
			)
			(layer "F.SilkS")
		)
		(fp_line
			(start -0.7874 0.4064)
			(end -0.7874 -0.4064)
			(stroke
				(width 0.1524)
				(type default)
			)
			(layer "F.SilkS")
		)
		(fp_line
			(start 0.7874 -0.4064)
			(end 0.7874 0.4064)
			(stroke
				(width 0.1524)
				(type default)
			)
			(layer "F.SilkS")
		)
		(fp_line
			(start 0.7874 0.4064)
			(end -0.7874 0.4064)
			(stroke
				(width 0.1524)
				(type default)
			)
			(layer "F.SilkS")
		)
		(fp_line
			(start -0.67945 -0.305054)
			(end -0.12065 -0.305054)
			(stroke
				(width 0.1)
				(type default)
			)
			(layer "F.Fab")
		)
		(fp_line
			(start -0.67945 0.3048)
			(end -0.67945 -0.305054)
			(stroke
				(width 0.1)
				(type default)
			)
			(layer "F.Fab")
		)
		(fp_line
			(start -0.12065 -0.305054)
			(end -0.12065 -0.2794)
			(stroke
				(width 0.1)
				(type default)
			)
			(layer "F.Fab")
		)
		(fp_line
			(start -0.12065 -0.2794)
			(end 0.12065 -0.2794)
			(stroke
				(width 0.1)
				(type default)
			)
			(layer "F.Fab")
		)
		(fp_line
			(start -0.12065 0.2794)
			(end -0.12065 0.3048)
			(stroke
				(width 0.1)
				(type default)
			)
			(layer "F.Fab")
		)
		(fp_line
			(start -0.12065 0.3048)
			(end -0.67945 0.3048)
			(stroke
				(width 0.1)
				(type default)
			)
			(layer "F.Fab")
		)
		(fp_line
			(start 0.120396 0.2794)
			(end -0.12065 0.2794)
			(stroke
				(width 0.1)
				(type default)
			)
			(layer "F.Fab")
		)
		(fp_line
			(start 0.120396 0.3048)
			(end 0.120396 0.2794)
			(stroke
				(width 0.1)
				(type default)
			)
			(layer "F.Fab")
		)
		(fp_line
			(start 0.12065 -0.3048)
			(end 0.67945 -0.3048)
			(stroke
				(width 0.1)
				(type default)
			)
			(layer "F.Fab")
		)
		(fp_line
			(start 0.12065 -0.2794)
			(end 0.12065 -0.3048)
			(stroke
				(width 0.1)
				(type default)
			)
			(layer "F.Fab")
		)
		(fp_line
			(start 0.67945 -0.3048)
			(end 0.67945 0.3048)
			(stroke
				(width 0.1)
				(type default)
			)
			(layer "F.Fab")
		)
		(fp_line
			(start 0.67945 0.3048)
			(end 0.120396 0.3048)
			(stroke
				(width 0.1)
				(type default)
			)
			(layer "F.Fab")
		)
		(pad "1" smd circle
			(at -0.40005 0)
			(size 0 0)
			(layers "F.Cu" "F.Mask" "F.Paste")
			(net "PRSNT_GPU_A1_R_N")
		)
		(pad "2" smd circle
			(at 0.40005 0)
			(size 0 0)
			(layers "F.Cu" "F.Mask" "F.Paste")
			(net "PRSNT_GPU_A1_N")
		)
	)
	(footprint ""
		(layer "F.Cu")
		(at 82.661506 -124.991114 180)
		(property "Reference" "C25"
			(at 0 0 180)
			(layer "F.SilkS")
			(hide yes)
			(effects
				(font
					(size 1.27 1.27)
				)
			)
		)
		(property "Value" ""
			(at 0 0 180)
			(layer "F.Fab")
			(effects
				(font
					(size 1.27 1.27)
				)
			)
		)
		(duplicate_pad_numbers_are_jumpers no)
		(fp_line
			(start 0.299974 0.150114)
			(end -0.299974 0.150114)
			(stroke
				(width 0.1)
				(type default)
			)
			(layer "F.Fab")
		)
		(fp_line
			(start 0.299974 -0.150114)
			(end 0.299974 0.150114)
			(stroke
				(width 0.1)
				(type default)
			)
			(layer "F.Fab")
		)
		(fp_line
			(start -0.299974 0.150114)
			(end -0.299974 -0.150114)
			(stroke
				(width 0.1)
				(type default)
			)
			(layer "F.Fab")
		)
		(fp_line
			(start -0.299974 -0.150114)
			(end 0.299974 -0.150114)
			(stroke
				(width 0.1)
				(type default)
			)
			(layer "F.Fab")
		)
		(pad "1" smd rect
			(at -0.2667 0 180)
			(size 0.3048 0.381)
			(layers "F.Cu" "F.Mask" "F.Paste")
			(net "P5E_PEX0_STN0_TX_DP<3>")
		)
		(pad "2" smd rect
			(at 0.2667 0 180)
			(size 0.3048 0.381)
			(layers "F.Cu" "F.Mask" "F.Paste")
			(net "P5E_PEX0_STN0_TX_C_DP<3>")
		)
	)
	(footprint ""
		(layer "F.Cu")
		(at 303.99609 -47.20082 90)
		(property "Reference" "C328"
			(at 0 0 90)
			(layer "F.SilkS")
			(hide yes)
			(effects
				(font
					(size 1.27 1.27)
				)
			)
		)
		(property "Value" ""
			(at 0 0 90)
			(layer "F.Fab")
			(effects
				(font
					(size 1.27 1.27)
				)
			)
		)
		(duplicate_pad_numbers_are_jumpers no)
		(fp_line
			(start 0.7874 -0.4064)
			(end 0.7874 0.4064)
			(stroke
				(width 0.1524)
				(type default)
			)
			(layer "F.SilkS")
		)
		(fp_line
			(start -0.7874 -0.4064)
			(end 0.7874 -0.4064)
			(stroke
				(width 0.1524)
				(type default)
			)
			(layer "F.SilkS")
		)
		(fp_line
			(start 0.7874 0.4064)
			(end -0.7874 0.4064)
			(stroke
				(width 0.1524)
				(type default)
			)
			(layer "F.SilkS")
		)
		(fp_line
			(start -0.7874 0.4064)
			(end -0.7874 -0.4064)
			(stroke
				(width 0.1524)
				(type default)
			)
			(layer "F.SilkS")
		)
		(fp_line
			(start -0.12065 -0.305054)
			(end -0.12065 -0.2794)
			(stroke
				(width 0.1)
				(type default)
			)
			(layer "F.Fab")
		)
		(fp_line
			(start -0.67945 -0.305054)
			(end -0.12065 -0.305054)
			(stroke
				(width 0.1)
				(type default)
			)
			(layer "F.Fab")
		)
		(fp_line
			(start 0.67945 -0.3048)
			(end 0.67945 0.3048)
			(stroke
				(width 0.1)
				(type default)
			)
			(layer "F.Fab")
		)
		(fp_line
			(start 0.12065 -0.3048)
			(end 0.67945 -0.3048)
			(stroke
				(width 0.1)
				(type default)
			)
			(layer "F.Fab")
		)
		(fp_line
			(start 0.12065 -0.2794)
			(end 0.12065 -0.3048)
			(stroke
				(width 0.1)
				(type default)
			)
			(layer "F.Fab")
		)
		(fp_line
			(start -0.12065 -0.2794)
			(end 0.12065 -0.2794)
			(stroke
				(width 0.1)
				(type default)
			)
			(layer "F.Fab")
		)
		(fp_line
			(start 0.120396 0.2794)
			(end -0.12065 0.2794)
			(stroke
				(width 0.1)
				(type default)
			)
			(layer "F.Fab")
		)
		(fp_line
			(start -0.12065 0.2794)
			(end -0.12065 0.3048)
			(stroke
				(width 0.1)
				(type default)
			)
			(layer "F.Fab")
		)
		(fp_line
			(start 0.67945 0.3048)
			(end 0.120396 0.3048)
			(stroke
				(width 0.1)
				(type default)
			)
			(layer "F.Fab")
		)
		(fp_line
			(start 0.120396 0.3048)
			(end 0.120396 0.2794)
			(stroke
				(width 0.1)
				(type default)
			)
			(layer "F.Fab")
		)
		(fp_line
			(start -0.12065 0.3048)
			(end -0.67945 0.3048)
			(stroke
				(width 0.1)
				(type default)
			)
			(layer "F.Fab")
		)
		(fp_line
			(start -0.67945 0.3048)
			(end -0.67945 -0.305054)
			(stroke
				(width 0.1)
				(type default)
			)
			(layer "F.Fab")
		)
		(pad "1" smd circle
			(at -0.40005 0 90)
			(size 0 0)
			(layers "F.Cu" "F.Mask" "F.Paste")
			(net "P12V_SSD10_R")
		)
		(pad "2" smd circle
			(at 0.40005 0 90)
			(size 0 0)
			(layers "F.Cu" "F.Mask" "F.Paste")
			(net "GND")
		)
	)
	(footprint ""
		(layer "F.Cu")
		(at 426.543724 -42.84091)
		(property "Reference" "R659"
			(at 0 0 0)
			(layer "F.SilkS")
			(hide yes)
			(effects
				(font
					(size 1.27 1.27)
				)
			)
		)
		(property "Value" ""
			(at 0 0 0)
			(layer "F.Fab")
			(effects
				(font
					(size 1.27 1.27)
				)
			)
		)
		(duplicate_pad_numbers_are_jumpers no)
		(fp_line
			(start -0.7874 -0.4064)
			(end 0.7874 -0.4064)
			(stroke
				(width 0.1524)
				(type default)
			)
			(layer "F.SilkS")
		)
		(fp_line
			(start -0.7874 0.4064)
			(end -0.7874 -0.4064)
			(stroke
				(width 0.1524)
				(type default)
			)
			(layer "F.SilkS")
		)
		(fp_line
			(start 0.7874 -0.4064)
			(end 0.7874 0.4064)
			(stroke
				(width 0.1524)
				(type default)
			)
			(layer "F.SilkS")
		)
		(fp_line
			(start 0.7874 0.4064)
			(end -0.7874 0.4064)
			(stroke
				(width 0.1524)
				(type default)
			)
			(layer "F.SilkS")
		)
		(fp_line
			(start -0.67945 -0.305054)
			(end -0.12065 -0.305054)
			(stroke
				(width 0.1)
				(type default)
			)
			(layer "F.Fab")
		)
		(fp_line
			(start -0.67945 0.3048)
			(end -0.67945 -0.305054)
			(stroke
				(width 0.1)
				(type default)
			)
			(layer "F.Fab")
		)
		(fp_line
			(start -0.12065 -0.305054)
			(end -0.12065 -0.2794)
			(stroke
				(width 0.1)
				(type default)
			)
			(layer "F.Fab")
		)
		(fp_line
			(start -0.12065 -0.2794)
			(end 0.12065 -0.2794)
			(stroke
				(width 0.1)
				(type default)
			)
			(layer "F.Fab")
		)
		(fp_line
			(start -0.12065 0.2794)
			(end -0.12065 0.3048)
			(stroke
				(width 0.1)
				(type default)
			)
			(layer "F.Fab")
		)
		(fp_line
			(start -0.12065 0.3048)
			(end -0.67945 0.3048)
			(stroke
				(width 0.1)
				(type default)
			)
			(layer "F.Fab")
		)
		(fp_line
			(start 0.120396 0.2794)
			(end -0.12065 0.2794)
			(stroke
				(width 0.1)
				(type default)
			)
			(layer "F.Fab")
		)
		(fp_line
			(start 0.120396 0.3048)
			(end 0.120396 0.2794)
			(stroke
				(width 0.1)
				(type default)
			)
			(layer "F.Fab")
		)
		(fp_line
			(start 0.12065 -0.3048)
			(end 0.67945 -0.3048)
			(stroke
				(width 0.1)
				(type default)
			)
			(layer "F.Fab")
		)
		(fp_line
			(start 0.12065 -0.2794)
			(end 0.12065 -0.3048)
			(stroke
				(width 0.1)
				(type default)
			)
			(layer "F.Fab")
		)
		(fp_line
			(start 0.67945 -0.3048)
			(end 0.67945 0.3048)
			(stroke
				(width 0.1)
				(type default)
			)
			(layer "F.Fab")
		)
		(fp_line
			(start 0.67945 0.3048)
			(end 0.120396 0.3048)
			(stroke
				(width 0.1)
				(type default)
			)
			(layer "F.Fab")
		)
		(pad "1" smd circle
			(at -0.40005 0)
			(size 0 0)
			(layers "F.Cu" "F.Mask" "F.Paste")
			(net "SSD14_ADC_A1")
		)
		(pad "2" smd circle
			(at 0.40005 0)
			(size 0 0)
			(layers "F.Cu" "F.Mask" "F.Paste")
			(net "P3V3_AUX")
		)
	)
	(footprint ""
		(layer "F.Cu")
		(at 180.814472 -356.244906 90)
		(property "Reference" "C383"
			(at 0 0 90)
			(layer "F.SilkS")
			(hide yes)
			(effects
				(font
					(size 1.27 1.27)
				)
			)
		)
		(property "Value" ""
			(at 0 0 90)
			(layer "F.Fab")
			(effects
				(font
					(size 1.27 1.27)
				)
			)
		)
		(duplicate_pad_numbers_are_jumpers no)
		(fp_line
			(start 0.299974 -0.150114)
			(end 0.299974 0.150114)
			(stroke
				(width 0.1)
				(type default)
			)
			(layer "F.Fab")
		)
		(fp_line
			(start -0.299974 -0.150114)
			(end 0.299974 -0.150114)
			(stroke
				(width 0.1)
				(type default)
			)
			(layer "F.Fab")
		)
		(fp_line
			(start 0.299974 0.150114)
			(end -0.299974 0.150114)
			(stroke
				(width 0.1)
				(type default)
			)
			(layer "F.Fab")
		)
		(fp_line
			(start -0.299974 0.150114)
			(end -0.299974 -0.150114)
			(stroke
				(width 0.1)
				(type default)
			)
			(layer "F.Fab")
		)
		(pad "1" smd rect
			(at -0.2667 0 90)
			(size 0.3048 0.381)
			(layers "F.Cu" "F.Mask" "F.Paste")
			(net "P5E_PEX1_STN7_TX_DN<122>")
		)
		(pad "2" smd rect
			(at 0.2667 0 90)
			(size 0.3048 0.381)
			(layers "F.Cu" "F.Mask" "F.Paste")
			(net "P5E_PEX1_STN7_TX_C_DN<122>")
		)
	)
	(footprint ""
		(layer "F.Cu")
		(at 91.034108 -306.074572 90)
		(property "Reference" "R1239"
			(at 0 0 90)
			(layer "F.SilkS")
			(hide yes)
			(effects
				(font
					(size 1.27 1.27)
				)
			)
		)
		(property "Value" ""
			(at 0 0 90)
			(layer "F.Fab")
			(effects
				(font
					(size 1.27 1.27)
				)
			)
		)
		(duplicate_pad_numbers_are_jumpers no)
		(fp_line
			(start 0.7874 -0.4064)
			(end 0.7874 0.4064)
			(stroke
				(width 0.1524)
				(type default)
			)
			(layer "F.SilkS")
		)
		(fp_line
			(start -0.7874 -0.4064)
			(end 0.7874 -0.4064)
			(stroke
				(width 0.1524)
				(type default)
			)
			(layer "F.SilkS")
		)
		(fp_line
			(start 0.7874 0.4064)
			(end -0.7874 0.4064)
			(stroke
				(width 0.1524)
				(type default)
			)
			(layer "F.SilkS")
		)
		(fp_line
			(start -0.7874 0.4064)
			(end -0.7874 -0.4064)
			(stroke
				(width 0.1524)
				(type default)
			)
			(layer "F.SilkS")
		)
		(fp_line
			(start -0.12065 -0.305054)
			(end -0.12065 -0.2794)
			(stroke
				(width 0.1)
				(type default)
			)
			(layer "F.Fab")
		)
		(fp_line
			(start -0.67945 -0.305054)
			(end -0.12065 -0.305054)
			(stroke
				(width 0.1)
				(type default)
			)
			(layer "F.Fab")
		)
		(fp_line
			(start 0.67945 -0.3048)
			(end 0.67945 0.3048)
			(stroke
				(width 0.1)
				(type default)
			)
			(layer "F.Fab")
		)
		(fp_line
			(start 0.12065 -0.3048)
			(end 0.67945 -0.3048)
			(stroke
				(width 0.1)
				(type default)
			)
			(layer "F.Fab")
		)
		(fp_line
			(start 0.12065 -0.2794)
			(end 0.12065 -0.3048)
			(stroke
				(width 0.1)
				(type default)
			)
			(layer "F.Fab")
		)
		(fp_line
			(start -0.12065 -0.2794)
			(end 0.12065 -0.2794)
			(stroke
				(width 0.1)
				(type default)
			)
			(layer "F.Fab")
		)
		(fp_line
			(start 0.120396 0.2794)
			(end -0.12065 0.2794)
			(stroke
				(width 0.1)
				(type default)
			)
			(layer "F.Fab")
		)
		(fp_line
			(start -0.12065 0.2794)
			(end -0.12065 0.3048)
			(stroke
				(width 0.1)
				(type default)
			)
			(layer "F.Fab")
		)
		(fp_line
			(start 0.67945 0.3048)
			(end 0.120396 0.3048)
			(stroke
				(width 0.1)
				(type default)
			)
			(layer "F.Fab")
		)
		(fp_line
			(start 0.120396 0.3048)
			(end 0.120396 0.2794)
			(stroke
				(width 0.1)
				(type default)
			)
			(layer "F.Fab")
		)
		(fp_line
			(start -0.12065 0.3048)
			(end -0.67945 0.3048)
			(stroke
				(width 0.1)
				(type default)
			)
			(layer "F.Fab")
		)
		(fp_line
			(start -0.67945 0.3048)
			(end -0.67945 -0.305054)
			(stroke
				(width 0.1)
				(type default)
			)
			(layer "F.Fab")
		)
		(pad "1" smd circle
			(at -0.40005 0 90)
			(size 0 0)
			(layers "F.Cu" "F.Mask" "F.Paste")
			(net "PEX0_SPARE1")
		)
		(pad "2" smd circle
			(at 0.40005 0 90)
			(size 0 0)
			(layers "F.Cu" "F.Mask" "F.Paste")
			(net "P1V8_PEX")
		)
	)
	(footprint ""
		(layer "F.Cu")
		(at 418.092382 -32.739584 180)
		(property "Reference" "C716"
			(at 0 0 180)
			(layer "F.SilkS")
			(hide yes)
			(effects
				(font
					(size 1.27 1.27)
				)
			)
		)
		(property "Value" ""
			(at 0 0 180)
			(layer "F.Fab")
			(effects
				(font
					(size 1.27 1.27)
				)
			)
		)
		(duplicate_pad_numbers_are_jumpers no)
		(fp_line
			(start 0.299974 0.150114)
			(end -0.299974 0.150114)
			(stroke
				(width 0.1)
				(type default)
			)
			(layer "F.Fab")
		)
		(fp_line
			(start 0.299974 -0.150114)
			(end 0.299974 0.150114)
			(stroke
				(width 0.1)
				(type default)
			)
			(layer "F.Fab")
		)
		(fp_line
			(start -0.299974 0.150114)
			(end -0.299974 -0.150114)
			(stroke
				(width 0.1)
				(type default)
			)
			(layer "F.Fab")
		)
		(fp_line
			(start -0.299974 -0.150114)
			(end 0.299974 -0.150114)
			(stroke
				(width 0.1)
				(type default)
			)
			(layer "F.Fab")
		)
		(pad "1" smd rect
			(at -0.2667 0 180)
			(size 0.3048 0.381)
			(layers "F.Cu" "F.Mask" "F.Paste")
			(net "P5E_PEX3_STN2_TX_DP<38>")
		)
		(pad "2" smd rect
			(at 0.2667 0 180)
			(size 0.3048 0.381)
			(layers "F.Cu" "F.Mask" "F.Paste")
			(net "P5E_PEX3_STN2_TX_C_DP<38>")
		)
	)
	(footprint ""
		(layer "F.Cu")
		(at 36.2458 -261.663434)
		(property "Reference" "C3039"
			(at 0 0 0)
			(layer "F.SilkS")
			(hide yes)
			(effects
				(font
					(size 1.27 1.27)
				)
			)
		)
		(property "Value" ""
			(at 0 0 0)
			(layer "F.Fab")
			(effects
				(font
					(size 1.27 1.27)
				)
			)
		)
		(duplicate_pad_numbers_are_jumpers no)
		(fp_line
			(start -1.2954 -0.5842)
			(end 1.2954 -0.5842)
			(stroke
				(width 0.1524)
				(type default)
			)
			(layer "F.SilkS")
		)
		(fp_line
			(start -1.2954 0.5842)
			(end -1.2954 -0.5842)
			(stroke
				(width 0.1524)
				(type default)
			)
			(layer "F.SilkS")
		)
		(fp_line
			(start 1.2954 -0.5842)
			(end 1.2954 0.5842)
			(stroke
				(width 0.1524)
				(type default)
			)
			(layer "F.SilkS")
		)
		(fp_line
			(start 1.2954 0.5842)
			(end -1.2954 0.5842)
			(stroke
				(width 0.1524)
				(type default)
			)
			(layer "F.SilkS")
		)
		(fp_line
			(start -1.1938 -0.4064)
			(end -0.8636 -0.4064)
			(stroke
				(width 0.1)
				(type default)
			)
			(layer "F.Fab")
		)
		(fp_line
			(start -1.1938 0.4064)
			(end -1.1938 -0.4064)
			(stroke
				(width 0.1)
				(type default)
			)
			(layer "F.Fab")
		)
		(fp_line
			(start -0.8636 -0.4572)
			(end 0.8636 -0.4572)
			(stroke
				(width 0.1)
				(type default)
			)
			(layer "F.Fab")
		)
		(fp_line
			(start -0.8636 -0.4064)
			(end -0.8636 -0.4572)
			(stroke
				(width 0.1)
				(type default)
			)
			(layer "F.Fab")
		)
		(fp_line
			(start -0.8636 0.4064)
			(end -1.1938 0.4064)
			(stroke
				(width 0.1)
				(type default)
			)
			(layer "F.Fab")
		)
		(fp_line
			(start -0.8636 0.4572)
			(end -0.8636 0.4064)
			(stroke
				(width 0.1)
				(type default)
			)
			(layer "F.Fab")
		)
		(fp_line
			(start 0.8636 -0.4572)
			(end 0.8636 -0.4064)
			(stroke
				(width 0.1)
				(type default)
			)
			(layer "F.Fab")
		)
		(fp_line
			(start 0.8636 -0.4064)
			(end 1.1938 -0.4064)
			(stroke
				(width 0.1)
				(type default)
			)
			(layer "F.Fab")
		)
		(fp_line
			(start 0.8636 0.4064)
			(end 0.8636 0.4572)
			(stroke
				(width 0.1)
				(type default)
			)
			(layer "F.Fab")
		)
		(fp_line
			(start 0.8636 0.4572)
			(end -0.8636 0.4572)
			(stroke
				(width 0.1)
				(type default)
			)
			(layer "F.Fab")
		)
		(fp_line
			(start 1.1938 -0.4064)
			(end 1.1938 0.4064)
			(stroke
				(width 0.1)
				(type default)
			)
			(layer "F.Fab")
		)
		(fp_line
			(start 1.1938 0.4064)
			(end 0.8636 0.4064)
			(stroke
				(width 0.1)
				(type default)
			)
			(layer "F.Fab")
		)
		(pad "1" smd rect
			(at -0.7366 0 270)
			(size 0.7112 0.8128)
			(layers "F.Cu" "F.Mask" "F.Paste")
			(net "PCEPLL3_VDDA18_PEX0")
		)
		(pad "2" smd rect
			(at 0.7366 0 270)
			(size 0.7112 0.8128)
			(layers "F.Cu" "F.Mask" "F.Paste")
			(net "GND")
		)
	)
	(footprint ""
		(layer "F.Cu")
		(at 290.264342 -139.6238)
		(property "Reference" "R241"
			(at 0 0 0)
			(layer "F.SilkS")
			(hide yes)
			(effects
				(font
					(size 1.27 1.27)
				)
			)
		)
		(property "Value" ""
			(at 0 0 0)
			(layer "F.Fab")
			(effects
				(font
					(size 1.27 1.27)
				)
			)
		)
		(duplicate_pad_numbers_are_jumpers no)
		(fp_line
			(start -0.7874 -0.4064)
			(end 0.7874 -0.4064)
			(stroke
				(width 0.1524)
				(type default)
			)
			(layer "F.SilkS")
		)
		(fp_line
			(start -0.7874 0.4064)
			(end -0.7874 -0.4064)
			(stroke
				(width 0.1524)
				(type default)
			)
			(layer "F.SilkS")
		)
		(fp_line
			(start 0.7874 -0.4064)
			(end 0.7874 0.4064)
			(stroke
				(width 0.1524)
				(type default)
			)
			(layer "F.SilkS")
		)
		(fp_line
			(start 0.7874 0.4064)
			(end -0.7874 0.4064)
			(stroke
				(width 0.1524)
				(type default)
			)
			(layer "F.SilkS")
		)
		(fp_line
			(start -0.67945 -0.305054)
			(end -0.12065 -0.305054)
			(stroke
				(width 0.1)
				(type default)
			)
			(layer "F.Fab")
		)
		(fp_line
			(start -0.67945 0.3048)
			(end -0.67945 -0.305054)
			(stroke
				(width 0.1)
				(type default)
			)
			(layer "F.Fab")
		)
		(fp_line
			(start -0.12065 -0.305054)
			(end -0.12065 -0.2794)
			(stroke
				(width 0.1)
				(type default)
			)
			(layer "F.Fab")
		)
		(fp_line
			(start -0.12065 -0.2794)
			(end 0.12065 -0.2794)
			(stroke
				(width 0.1)
				(type default)
			)
			(layer "F.Fab")
		)
		(fp_line
			(start -0.12065 0.2794)
			(end -0.12065 0.3048)
			(stroke
				(width 0.1)
				(type default)
			)
			(layer "F.Fab")
		)
		(fp_line
			(start -0.12065 0.3048)
			(end -0.67945 0.3048)
			(stroke
				(width 0.1)
				(type default)
			)
			(layer "F.Fab")
		)
		(fp_line
			(start 0.120396 0.2794)
			(end -0.12065 0.2794)
			(stroke
				(width 0.1)
				(type default)
			)
			(layer "F.Fab")
		)
		(fp_line
			(start 0.120396 0.3048)
			(end 0.120396 0.2794)
			(stroke
				(width 0.1)
				(type default)
			)
			(layer "F.Fab")
		)
		(fp_line
			(start 0.12065 -0.3048)
			(end 0.67945 -0.3048)
			(stroke
				(width 0.1)
				(type default)
			)
			(layer "F.Fab")
		)
		(fp_line
			(start 0.12065 -0.2794)
			(end 0.12065 -0.3048)
			(stroke
				(width 0.1)
				(type default)
			)
			(layer "F.Fab")
		)
		(fp_line
			(start 0.67945 -0.3048)
			(end 0.67945 0.3048)
			(stroke
				(width 0.1)
				(type default)
			)
			(layer "F.Fab")
		)
		(fp_line
			(start 0.67945 0.3048)
			(end 0.120396 0.3048)
			(stroke
				(width 0.1)
				(type default)
			)
			(layer "F.Fab")
		)
		(pad "1" smd circle
			(at -0.40005 0)
			(size 0 0)
			(layers "F.Cu" "F.Mask" "F.Paste")
			(net "RST_SMB_NIC4_MUX_ISO_R_N")
		)
		(pad "2" smd circle
			(at 0.40005 0)
			(size 0 0)
			(layers "F.Cu" "F.Mask" "F.Paste")
			(net "RST_SMB_NIC4_MUX_ISO_N")
		)
	)
	(footprint ""
		(layer "F.Cu")
		(at 314.163456 -450.437758 -90)
		(property "Reference" "J51"
			(at -2.4257 -5.635752 90)
			(unlocked yes)
			(layer "F.SilkS")
			(effects
				(font
					(size 0.7874 0.5842)
					(thickness 0.1524)
				)
			)
		)
		(property "Value" ""
			(at 0 0 270)
			(layer "F.Fab")
			(effects
				(font
					(size 1.27 1.27)
				)
			)
		)
		(duplicate_pad_numbers_are_jumpers no)
		(fp_line
			(start 0 4.011168)
			(end -3.330702 -4.771136)
			(stroke
				(width 0.1524)
				(type default)
			)
			(layer "F.SilkS")
		)
		(fp_line
			(start -3.330702 -4.771136)
			(end 3.330702 -4.771136)
			(stroke
				(width 0.1524)
				(type default)
			)
			(layer "F.SilkS")
		)
		(fp_line
			(start 3.330702 -4.771136)
			(end 0 4.011168)
			(stroke
				(width 0.1524)
				(type default)
			)
			(layer "F.SilkS")
		)
		(fp_line
			(start 0 4.011168)
			(end -3.330702 -4.771136)
			(stroke
				(width 0.1)
				(type default)
			)
			(layer "F.Fab")
		)
		(fp_line
			(start -3.330702 -4.771136)
			(end 3.330702 -4.771136)
			(stroke
				(width 0.1)
				(type default)
			)
			(layer "F.Fab")
		)
		(fp_line
			(start 3.330702 -4.771136)
			(end 0 4.011168)
			(stroke
				(width 0.1)
				(type default)
			)
			(layer "F.Fab")
		)
		(pad "1" thru_hole circle
			(at 0 0 270)
			(size 2.159 2.159)
			(drill 1.7018)
			(layers "*.Cu" "*.Mask")
			(remove_unused_layers no)
			(net "COUPON_GND1")
			(clearance 0.0254)
			(thermal_gap 0.0254)
		)
		(pad "2" thru_hole circle
			(at -1.27 -3.348736 270)
			(size 2.159 2.159)
			(drill 1.7018)
			(layers "*.Cu" "*.Mask")
			(remove_unused_layers no)
			(net "TDR_SE_50_OHM_IN5")
			(clearance 0.0254)
			(thermal_gap 0.0254)
		)
		(pad "3" thru_hole circle
			(at 1.27 -3.348736 270)
			(size 2.159 2.159)
			(drill 1.7018)
			(layers "*.Cu" "*.Mask")
			(remove_unused_layers no)
			(net "TDR_SE_50_OHM_IN5")
			(clearance 0.0254)
			(thermal_gap 0.0254)
		)
	)
	(footprint ""
		(layer "F.Cu")
		(at 115.815872 -307.130958 -90)
		(property "Reference" "C4206"
			(at 0 0 270)
			(layer "F.SilkS")
			(hide yes)
			(effects
				(font
					(size 1.27 1.27)
				)
			)
		)
		(property "Value" ""
			(at 0 0 270)
			(layer "F.Fab")
			(effects
				(font
					(size 1.27 1.27)
				)
			)
		)
		(duplicate_pad_numbers_are_jumpers no)
		(fp_line
			(start -1.2954 0.5842)
			(end -1.2954 -0.5842)
			(stroke
				(width 0.1524)
				(type default)
			)
			(layer "F.SilkS")
		)
		(fp_line
			(start 1.2954 0.5842)
			(end -1.2954 0.5842)
			(stroke
				(width 0.1524)
				(type default)
			)
			(layer "F.SilkS")
		)
		(fp_line
			(start -1.2954 -0.5842)
			(end 1.2954 -0.5842)
			(stroke
				(width 0.1524)
				(type default)
			)
			(layer "F.SilkS")
		)
		(fp_line
			(start 1.2954 -0.5842)
			(end 1.2954 0.5842)
			(stroke
				(width 0.1524)
				(type default)
			)
			(layer "F.SilkS")
		)
		(fp_line
			(start -0.8636 0.4572)
			(end -0.8636 0.4064)
			(stroke
				(width 0.1)
				(type default)
			)
			(layer "F.Fab")
		)
		(fp_line
			(start 0.8636 0.4572)
			(end -0.8636 0.4572)
			(stroke
				(width 0.1)
				(type default)
			)
			(layer "F.Fab")
		)
		(fp_line
			(start -1.1938 0.4064)
			(end -1.1938 -0.4064)
			(stroke
				(width 0.1)
				(type default)
			)
			(layer "F.Fab")
		)
		(fp_line
			(start -0.8636 0.4064)
			(end -1.1938 0.4064)
			(stroke
				(width 0.1)
				(type default)
			)
			(layer "F.Fab")
		)
		(fp_line
			(start 0.8636 0.4064)
			(end 0.8636 0.4572)
			(stroke
				(width 0.1)
				(type default)
			)
			(layer "F.Fab")
		)
		(fp_line
			(start 1.1938 0.4064)
			(end 0.8636 0.4064)
			(stroke
				(width 0.1)
				(type default)
			)
			(layer "F.Fab")
		)
		(fp_line
			(start -1.1938 -0.4064)
			(end -0.8636 -0.4064)
			(stroke
				(width 0.1)
				(type default)
			)
			(layer "F.Fab")
		)
		(fp_line
			(start -0.8636 -0.4064)
			(end -0.8636 -0.4572)
			(stroke
				(width 0.1)
				(type default)
			)
			(layer "F.Fab")
		)
		(fp_line
			(start 0.8636 -0.4064)
			(end 1.1938 -0.4064)
			(stroke
				(width 0.1)
				(type default)
			)
			(layer "F.Fab")
		)
		(fp_line
			(start 1.1938 -0.4064)
			(end 1.1938 0.4064)
			(stroke
				(width 0.1)
				(type default)
			)
			(layer "F.Fab")
		)
		(fp_line
			(start -0.8636 -0.4572)
			(end 0.8636 -0.4572)
			(stroke
				(width 0.1)
				(type default)
			)
			(layer "F.Fab")
		)
		(fp_line
			(start 0.8636 -0.4572)
			(end 0.8636 -0.4064)
			(stroke
				(width 0.1)
				(type default)
			)
			(layer "F.Fab")
		)
		(pad "1" smd rect
			(at -0.7366 0 180)
			(size 0.7112 0.8128)
			(layers "F.Cu" "F.Mask" "F.Paste")
			(net "P0V8_SERDES_VDDA_PEX0_C4")
		)
		(pad "2" smd rect
			(at 0.7366 0 180)
			(size 0.7112 0.8128)
			(layers "F.Cu" "F.Mask" "F.Paste")
			(net "GND")
		)
	)
	(footprint ""
		(layer "F.Cu")
		(at 460.611982 -112.547654)
		(property "Reference" "PC837"
			(at 0 0 0)
			(layer "F.SilkS")
			(hide yes)
			(effects
				(font
					(size 1.27 1.27)
				)
			)
		)
		(property "Value" ""
			(at 0 0 0)
			(layer "F.Fab")
			(effects
				(font
					(size 1.27 1.27)
				)
			)
		)
		(duplicate_pad_numbers_are_jumpers no)
		(fp_line
			(start -0.7874 -0.4064)
			(end 0.7874 -0.4064)
			(stroke
				(width 0.1524)
				(type default)
			)
			(layer "F.SilkS")
		)
		(fp_line
			(start -0.7874 0.4064)
			(end -0.7874 -0.4064)
			(stroke
				(width 0.1524)
				(type default)
			)
			(layer "F.SilkS")
		)
		(fp_line
			(start 0.7874 -0.4064)
			(end 0.7874 0.4064)
			(stroke
				(width 0.1524)
				(type default)
			)
			(layer "F.SilkS")
		)
		(fp_line
			(start 0.7874 0.4064)
			(end -0.7874 0.4064)
			(stroke
				(width 0.1524)
				(type default)
			)
			(layer "F.SilkS")
		)
		(fp_line
			(start -0.67945 -0.305054)
			(end -0.12065 -0.305054)
			(stroke
				(width 0.1)
				(type default)
			)
			(layer "F.Fab")
		)
		(fp_line
			(start -0.67945 0.3048)
			(end -0.67945 -0.305054)
			(stroke
				(width 0.1)
				(type default)
			)
			(layer "F.Fab")
		)
		(fp_line
			(start -0.12065 -0.305054)
			(end -0.12065 -0.2794)
			(stroke
				(width 0.1)
				(type default)
			)
			(layer "F.Fab")
		)
		(fp_line
			(start -0.12065 -0.2794)
			(end 0.12065 -0.2794)
			(stroke
				(width 0.1)
				(type default)
			)
			(layer "F.Fab")
		)
		(fp_line
			(start -0.12065 0.2794)
			(end -0.12065 0.3048)
			(stroke
				(width 0.1)
				(type default)
			)
			(layer "F.Fab")
		)
		(fp_line
			(start -0.12065 0.3048)
			(end -0.67945 0.3048)
			(stroke
				(width 0.1)
				(type default)
			)
			(layer "F.Fab")
		)
		(fp_line
			(start 0.120396 0.2794)
			(end -0.12065 0.2794)
			(stroke
				(width 0.1)
				(type default)
			)
			(layer "F.Fab")
		)
		(fp_line
			(start 0.120396 0.3048)
			(end 0.120396 0.2794)
			(stroke
				(width 0.1)
				(type default)
			)
			(layer "F.Fab")
		)
		(fp_line
			(start 0.12065 -0.3048)
			(end 0.67945 -0.3048)
			(stroke
				(width 0.1)
				(type default)
			)
			(layer "F.Fab")
		)
		(fp_line
			(start 0.12065 -0.2794)
			(end 0.12065 -0.3048)
			(stroke
				(width 0.1)
				(type default)
			)
			(layer "F.Fab")
		)
		(fp_line
			(start 0.67945 -0.3048)
			(end 0.67945 0.3048)
			(stroke
				(width 0.1)
				(type default)
			)
			(layer "F.Fab")
		)
		(fp_line
			(start 0.67945 0.3048)
			(end 0.120396 0.3048)
			(stroke
				(width 0.1)
				(type default)
			)
			(layer "F.Fab")
		)
		(pad "1" smd circle
			(at -0.40005 0)
			(size 0 0)
			(layers "F.Cu" "F.Mask" "F.Paste")
			(net "P12V_NIC7_CO_ISET_R")
		)
		(pad "2" smd circle
			(at 0.40005 0)
			(size 0 0)
			(layers "F.Cu" "F.Mask" "F.Paste")
			(net "GND")
		)
	)
	(footprint ""
		(layer "F.Cu")
		(at 430.961546 -152.511252 180)
		(property "Reference" "C638"
			(at 0 0 180)
			(layer "F.SilkS")
			(hide yes)
			(effects
				(font
					(size 1.27 1.27)
				)
			)
		)
		(property "Value" ""
			(at 0 0 180)
			(layer "F.Fab")
			(effects
				(font
					(size 1.27 1.27)
				)
			)
		)
		(duplicate_pad_numbers_are_jumpers no)
		(fp_line
			(start 0.299974 0.150114)
			(end -0.299974 0.150114)
			(stroke
				(width 0.1)
				(type default)
			)
			(layer "F.Fab")
		)
		(fp_line
			(start 0.299974 -0.150114)
			(end 0.299974 0.150114)
			(stroke
				(width 0.1)
				(type default)
			)
			(layer "F.Fab")
		)
		(fp_line
			(start -0.299974 0.150114)
			(end -0.299974 -0.150114)
			(stroke
				(width 0.1)
				(type default)
			)
			(layer "F.Fab")
		)
		(fp_line
			(start -0.299974 -0.150114)
			(end 0.299974 -0.150114)
			(stroke
				(width 0.1)
				(type default)
			)
			(layer "F.Fab")
		)
		(pad "1" smd rect
			(at -0.2667 0 180)
			(size 0.3048 0.381)
			(layers "F.Cu" "F.Mask" "F.Paste")
			(net "P5E_PEX3_STN0_TX_DP<13>")
		)
		(pad "2" smd rect
			(at 0.2667 0 180)
			(size 0.3048 0.381)
			(layers "F.Cu" "F.Mask" "F.Paste")
			(net "P5E_PEX3_STN0_TX_C_DP<13>")
		)
	)
	(footprint ""
		(layer "F.Cu")
		(at 229.771956 -86.833456 -90)
		(property "Reference" "R1010"
			(at 0 0 270)
			(layer "F.SilkS")
			(hide yes)
			(effects
				(font
					(size 1.27 1.27)
				)
			)
		)
		(property "Value" ""
			(at 0 0 270)
			(layer "F.Fab")
			(effects
				(font
					(size 1.27 1.27)
				)
			)
		)
		(duplicate_pad_numbers_are_jumpers no)
		(fp_line
			(start 0.7874 0.4064)
			(end -0.7874 0.4064)
			(stroke
				(width 0.1524)
				(type default)
			)
			(layer "F.SilkS")
		)
		(fp_line
			(start -0.67945 0.3048)
			(end -0.67945 -0.305054)
			(stroke
				(width 0.1)
				(type default)
			)
			(layer "F.Fab")
		)
		(fp_line
			(start -0.12065 0.3048)
			(end -0.67945 0.3048)
			(stroke
				(width 0.1)
				(type default)
			)
			(layer "F.Fab")
		)
		(fp_line
			(start 0.120396 0.3048)
			(end 0.120396 0.2794)
			(stroke
				(width 0.1)
				(type default)
			)
			(layer "F.Fab")
		)
		(fp_line
			(start 0.67945 0.3048)
			(end 0.120396 0.3048)
			(stroke
				(width 0.1)
				(type default)
			)
			(layer "F.Fab")
		)
		(fp_line
			(start -0.12065 0.2794)
			(end -0.12065 0.3048)
			(stroke
				(width 0.1)
				(type default)
			)
			(layer "F.Fab")
		)
		(fp_line
			(start 0.120396 0.2794)
			(end -0.12065 0.2794)
			(stroke
				(width 0.1)
				(type default)
			)
			(layer "F.Fab")
		)
		(fp_line
			(start -0.12065 -0.2794)
			(end 0.12065 -0.2794)
			(stroke
				(width 0.1)
				(type default)
			)
			(layer "F.Fab")
		)
		(fp_line
			(start 0.12065 -0.2794)
			(end 0.12065 -0.3048)
			(stroke
				(width 0.1)
				(type default)
			)
			(layer "F.Fab")
		)
		(fp_line
			(start 0.12065 -0.3048)
			(end 0.67945 -0.3048)
			(stroke
				(width 0.1)
				(type default)
			)
			(layer "F.Fab")
		)
		(fp_line
			(start 0.67945 -0.3048)
			(end 0.67945 0.3048)
			(stroke
				(width 0.1)
				(type default)
			)
			(layer "F.Fab")
		)
		(fp_line
			(start -0.67945 -0.305054)
			(end -0.12065 -0.305054)
			(stroke
				(width 0.1)
				(type default)
			)
			(layer "F.Fab")
		)
		(fp_line
			(start -0.12065 -0.305054)
			(end -0.12065 -0.2794)
			(stroke
				(width 0.1)
				(type default)
			)
			(layer "F.Fab")
		)
		(pad "1" smd circle
			(at -0.40005 0 270)
			(size 0 0)
			(layers "F.Cu" "F.Mask" "F.Paste")
			(net "USB2_PEX_HUB_R_DN")
		)
		(pad "2" smd circle
			(at 0.40005 0 270)
			(size 0 0)
			(layers "F.Cu" "F.Mask" "F.Paste")
			(net "USB2_PEX_HUB_DN")
		)
	)
	(footprint ""
		(layer "F.Cu")
		(at 231.844596 -278.551386)
		(property "Reference" "R779"
			(at 0 0 0)
			(layer "F.SilkS")
			(hide yes)
			(effects
				(font
					(size 1.27 1.27)
				)
			)
		)
		(property "Value" ""
			(at 0 0 0)
			(layer "F.Fab")
			(effects
				(font
					(size 1.27 1.27)
				)
			)
		)
		(duplicate_pad_numbers_are_jumpers no)
		(fp_line
			(start -0.7874 -0.4064)
			(end 0.7874 -0.4064)
			(stroke
				(width 0.1524)
				(type default)
			)
			(layer "F.SilkS")
		)
		(fp_line
			(start -0.7874 0.4064)
			(end -0.7874 -0.4064)
			(stroke
				(width 0.1524)
				(type default)
			)
			(layer "F.SilkS")
		)
		(fp_line
			(start 0.7874 -0.4064)
			(end 0.7874 0.4064)
			(stroke
				(width 0.1524)
				(type default)
			)
			(layer "F.SilkS")
		)
		(fp_line
			(start 0.7874 0.4064)
			(end -0.7874 0.4064)
			(stroke
				(width 0.1524)
				(type default)
			)
			(layer "F.SilkS")
		)
		(fp_line
			(start -0.67945 -0.305054)
			(end -0.12065 -0.305054)
			(stroke
				(width 0.1)
				(type default)
			)
			(layer "F.Fab")
		)
		(fp_line
			(start -0.67945 0.3048)
			(end -0.67945 -0.305054)
			(stroke
				(width 0.1)
				(type default)
			)
			(layer "F.Fab")
		)
		(fp_line
			(start -0.12065 -0.305054)
			(end -0.12065 -0.2794)
			(stroke
				(width 0.1)
				(type default)
			)
			(layer "F.Fab")
		)
		(fp_line
			(start -0.12065 -0.2794)
			(end 0.12065 -0.2794)
			(stroke
				(width 0.1)
				(type default)
			)
			(layer "F.Fab")
		)
		(fp_line
			(start -0.12065 0.2794)
			(end -0.12065 0.3048)
			(stroke
				(width 0.1)
				(type default)
			)
			(layer "F.Fab")
		)
		(fp_line
			(start -0.12065 0.3048)
			(end -0.67945 0.3048)
			(stroke
				(width 0.1)
				(type default)
			)
			(layer "F.Fab")
		)
		(fp_line
			(start 0.120396 0.2794)
			(end -0.12065 0.2794)
			(stroke
				(width 0.1)
				(type default)
			)
			(layer "F.Fab")
		)
		(fp_line
			(start 0.120396 0.3048)
			(end 0.120396 0.2794)
			(stroke
				(width 0.1)
				(type default)
			)
			(layer "F.Fab")
		)
		(fp_line
			(start 0.12065 -0.3048)
			(end 0.67945 -0.3048)
			(stroke
				(width 0.1)
				(type default)
			)
			(layer "F.Fab")
		)
		(fp_line
			(start 0.12065 -0.2794)
			(end 0.12065 -0.3048)
			(stroke
				(width 0.1)
				(type default)
			)
			(layer "F.Fab")
		)
		(fp_line
			(start 0.67945 -0.3048)
			(end 0.67945 0.3048)
			(stroke
				(width 0.1)
				(type default)
			)
			(layer "F.Fab")
		)
		(fp_line
			(start 0.67945 0.3048)
			(end 0.120396 0.3048)
			(stroke
				(width 0.1)
				(type default)
			)
			(layer "F.Fab")
		)
		(pad "1" smd circle
			(at -0.40005 0)
			(size 0 0)
			(layers "F.Cu" "F.Mask" "F.Paste")
			(net "P3V3_AUX")
		)
		(pad "2" smd circle
			(at 0.40005 0)
			(size 0 0)
			(layers "F.Cu" "F.Mask" "F.Paste")
			(net "PEX_ADC_ALERT_N")
		)
	)
	(footprint ""
		(layer "F.Cu")
		(at 374.8786 -308.611524 45)
		(property "Reference" "R4363"
			(at 0 0 45)
			(layer "F.SilkS")
			(hide yes)
			(effects
				(font
					(size 1.27 1.27)
				)
			)
		)
		(property "Value" ""
			(at 0 0 45)
			(layer "F.Fab")
			(effects
				(font
					(size 1.27 1.27)
				)
			)
		)
		(duplicate_pad_numbers_are_jumpers no)
		(fp_line
			(start -0.787389 -0.406267)
			(end 0.787389 -0.406267)
			(stroke
				(width 0.1524)
				(type default)
			)
			(layer "F.SilkS")
		)
		(fp_line
			(start -0.787389 0.406267)
			(end -0.787389 -0.406267)
			(stroke
				(width 0.1524)
				(type default)
			)
			(layer "F.SilkS")
		)
		(fp_line
			(start 0.787389 -0.406267)
			(end 0.787389 0.406267)
			(stroke
				(width 0.1524)
				(type default)
			)
			(layer "F.SilkS")
		)
		(fp_line
			(start 0.787389 0.406267)
			(end -0.787389 0.406267)
			(stroke
				(width 0.1524)
				(type default)
			)
			(layer "F.SilkS")
		)
		(fp_line
			(start -0.679446 -0.305149)
			(end -0.120695 -0.304969)
			(stroke
				(width 0.1)
				(type default)
			)
			(layer "F.Fab")
		)
		(fp_line
			(start -0.120695 -0.304969)
			(end -0.120695 -0.279466)
			(stroke
				(width 0.1)
				(type default)
			)
			(layer "F.Fab")
		)
		(fp_line
			(start -0.120695 -0.279466)
			(end 0.120695 -0.279466)
			(stroke
				(width 0.1)
				(type default)
			)
			(layer "F.Fab")
		)
		(fp_line
			(start -0.679446 0.30479)
			(end -0.679446 -0.305149)
			(stroke
				(width 0.1)
				(type default)
			)
			(layer "F.Fab")
		)
		(fp_line
			(start 0.120515 -0.30479)
			(end 0.679446 -0.30479)
			(stroke
				(width 0.1)
				(type default)
			)
			(layer "F.Fab")
		)
		(fp_line
			(start 0.120695 -0.279466)
			(end 0.120515 -0.30479)
			(stroke
				(width 0.1)
				(type default)
			)
			(layer "F.Fab")
		)
		(fp_line
			(start -0.120695 0.279466)
			(end -0.120515 0.30479)
			(stroke
				(width 0.1)
				(type default)
			)
			(layer "F.Fab")
		)
		(fp_line
			(start -0.120515 0.30479)
			(end -0.679446 0.30479)
			(stroke
				(width 0.1)
				(type default)
			)
			(layer "F.Fab")
		)
		(fp_line
			(start 0.679446 -0.30479)
			(end 0.679446 0.30479)
			(stroke
				(width 0.1)
				(type default)
			)
			(layer "F.Fab")
		)
		(fp_line
			(start 0.120335 0.279466)
			(end -0.120695 0.279466)
			(stroke
				(width 0.1)
				(type default)
			)
			(layer "F.Fab")
		)
		(fp_line
			(start 0.120515 0.30479)
			(end 0.120335 0.279466)
			(stroke
				(width 0.1)
				(type default)
			)
			(layer "F.Fab")
		)
		(fp_line
			(start 0.679446 0.30479)
			(end 0.120515 0.30479)
			(stroke
				(width 0.1)
				(type default)
			)
			(layer "F.Fab")
		)
		(pad "1" smd circle
			(at -0.40005 0 45)
			(size 0 0)
			(layers "F.Cu" "F.Mask" "F.Paste")
			(net "P1V8_PEX")
		)
		(pad "2" smd circle
			(at 0.40005 0 45)
			(size 0 0)
			(layers "F.Cu" "F.Mask" "F.Paste")
			(net "IRQ_PEX3_CLKREQ_INT_N")
		)
	)
	(footprint ""
		(layer "F.Cu")
		(at 82.150458 -80.581246 90)
		(property "Reference" "U17"
			(at -0.672846 2.382012 90)
			(unlocked yes)
			(layer "F.SilkS")
			(effects
				(font
					(size 0.7874 0.5842)
					(thickness 0.1524)
				)
			)
		)
		(property "Value" ""
			(at 0 0 90)
			(layer "F.Fab")
			(effects
				(font
					(size 1.27 1.27)
				)
			)
		)
		(duplicate_pad_numbers_are_jumpers no)
		(fp_line
			(start 1.905 -1.651)
			(end 1.905 1.651)
			(stroke
				(width 0.1524)
				(type default)
			)
			(layer "F.SilkS")
		)
		(fp_line
			(start -1.905 -1.651)
			(end 1.905 -1.651)
			(stroke
				(width 0.1524)
				(type default)
			)
			(layer "F.SilkS")
		)
		(fp_line
			(start 1.905 1.651)
			(end -1.905 1.651)
			(stroke
				(width 0.1524)
				(type default)
			)
			(layer "F.SilkS")
		)
		(fp_line
			(start -1.905 1.651)
			(end -1.905 -1.651)
			(stroke
				(width 0.1524)
				(type default)
			)
			(layer "F.SilkS")
		)
		(fp_line
			(start 0.6985 -1.524)
			(end 0.6985 -0.219964)
			(stroke
				(width 0.1)
				(type default)
			)
			(layer "F.Fab")
		)
		(fp_line
			(start -0.649986 -1.524)
			(end 0.6985 -1.524)
			(stroke
				(width 0.1)
				(type default)
			)
			(layer "F.Fab")
		)
		(fp_line
			(start -0.649986 -1.169924)
			(end -0.649986 -1.524)
			(stroke
				(width 0.1)
				(type default)
			)
			(layer "F.Fab")
		)
		(fp_line
			(start -1.249934 -1.169924)
			(end -0.649986 -1.169924)
			(stroke
				(width 0.1)
				(type default)
			)
			(layer "F.Fab")
		)
		(fp_line
			(start -0.6985 -0.729996)
			(end -1.249934 -0.729996)
			(stroke
				(width 0.1)
				(type default)
			)
			(layer "F.Fab")
		)
		(fp_line
			(start -1.249934 -0.729996)
			(end -1.249934 -1.169924)
			(stroke
				(width 0.1)
				(type default)
			)
			(layer "F.Fab")
		)
		(fp_line
			(start 1.249934 -0.219964)
			(end 1.249934 0.219964)
			(stroke
				(width 0.1)
				(type default)
			)
			(layer "F.Fab")
		)
		(fp_line
			(start 0.6985 -0.219964)
			(end 1.249934 -0.219964)
			(stroke
				(width 0.1)
				(type default)
			)
			(layer "F.Fab")
		)
		(fp_line
			(start 1.249934 0.219964)
			(end 0.6985 0.219964)
			(stroke
				(width 0.1)
				(type default)
			)
			(layer "F.Fab")
		)
		(fp_line
			(start 0.6985 0.219964)
			(end 0.6985 1.524)
			(stroke
				(width 0.1)
				(type default)
			)
			(layer "F.Fab")
		)
		(fp_line
			(start -0.6985 0.729996)
			(end -0.6985 -0.729996)
			(stroke
				(width 0.1)
				(type default)
			)
			(layer "F.Fab")
		)
		(fp_line
			(start -1.249934 0.729996)
			(end -0.6985 0.729996)
			(stroke
				(width 0.1)
				(type default)
			)
			(layer "F.Fab")
		)
		(fp_line
			(start -0.649986 1.169924)
			(end -1.249934 1.169924)
			(stroke
				(width 0.1)
				(type default)
			)
			(layer "F.Fab")
		)
		(fp_line
			(start -1.249934 1.169924)
			(end -1.249934 0.729996)
			(stroke
				(width 0.1)
				(type default)
			)
			(layer "F.Fab")
		)
		(fp_line
			(start 0.6985 1.524)
			(end -0.649986 1.524)
			(stroke
				(width 0.1)
				(type default)
			)
			(layer "F.Fab")
		)
		(fp_line
			(start -0.649986 1.524)
			(end -0.649986 1.169924)
			(stroke
				(width 0.1)
				(type default)
			)
			(layer "F.Fab")
		)
		(pad "1" smd rect
			(at -1.1176 -1.016)
			(size 1.016 1.27)
			(layers "F.Cu" "F.Mask" "F.Paste")
			(net "HP_NIC1_PWRGD")
		)
		(pad "2" smd rect
			(at -1.1176 1.016)
			(size 1.016 1.27)
			(layers "F.Cu" "F.Mask" "F.Paste")
			(net "P3V3_NIC1")
		)
		(pad "3" smd rect
			(at 1.1176 0)
			(size 1.016 1.27)
			(layers "F.Cu" "F.Mask" "F.Paste")
			(net "GND")
		)
	)
	(footprint ""
		(layer "F.Cu")
		(at 467.58225 -529.13661 180)
		(property "Reference" "J32_OTH"
			(at -3.2385 -1.402334 0)
			(unlocked yes)
			(layer "B.SilkS")
			(effects
				(font
					(size 0.7874 0.5842)
					(thickness 0.1524)
				)
				(justify mirror)
			)
		)
		(property "Value" ""
			(at 0 0 180)
			(layer "F.Fab")
			(effects
				(font
					(size 1.27 1.27)
				)
			)
		)
		(duplicate_pad_numbers_are_jumpers no)
		(pad "1" thru_hole circle
			(at 0 0 180)
			(size 0.4572 0.4572)
			(drill 0.2032)
			(layers "*.Cu" "*.Mask")
			(remove_unused_layers no)
			(net "Net_9104")
			(clearance 0.127)
			(thermal_gap 0.127)
			(padstack
				(mode front_inner_back)
				(layer "Inner"
					(shape circle)
					(size 0.4572 0.4572)
					(clearance 0.127)
				)
				(layer "B.Cu"
					(shape circle)
					(size 0.508 0.508)
					(clearance 0.1016)
				)
			)
		)
	)
	(footprint ""
		(layer "F.Cu")
		(at 235.524294 -49.701958 90)
		(property "Reference" "PC547"
			(at 0 0 90)
			(layer "F.SilkS")
			(hide yes)
			(effects
				(font
					(size 1.27 1.27)
				)
			)
		)
		(property "Value" ""
			(at 0 0 90)
			(layer "F.Fab")
			(effects
				(font
					(size 1.27 1.27)
				)
			)
		)
		(duplicate_pad_numbers_are_jumpers no)
		(fp_line
			(start 1.524 -0.762)
			(end 1.524 0.762)
			(stroke
				(width 0.1524)
				(type default)
			)
			(layer "F.SilkS")
		)
		(fp_line
			(start -1.524 -0.762)
			(end 1.524 -0.762)
			(stroke
				(width 0.1524)
				(type default)
			)
			(layer "F.SilkS")
		)
		(fp_line
			(start 1.524 0.762)
			(end -1.524 0.762)
			(stroke
				(width 0.1524)
				(type default)
			)
			(layer "F.SilkS")
		)
		(fp_line
			(start -1.524 0.762)
			(end -1.524 -0.762)
			(stroke
				(width 0.1524)
				(type default)
			)
			(layer "F.SilkS")
		)
		(fp_line
			(start 1.1049 -0.724916)
			(end -1.1049 -0.724916)
			(stroke
				(width 0.1)
				(type default)
			)
			(layer "F.Fab")
		)
		(fp_line
			(start -1.1049 -0.724916)
			(end -1.1049 0.724916)
			(stroke
				(width 0.1)
				(type default)
			)
			(layer "F.Fab")
		)
		(fp_line
			(start 1.1049 0.724916)
			(end 1.1049 -0.724916)
			(stroke
				(width 0.1)
				(type default)
			)
			(layer "F.Fab")
		)
		(fp_line
			(start -1.1049 0.724916)
			(end 1.1049 0.724916)
			(stroke
				(width 0.1)
				(type default)
			)
			(layer "F.Fab")
		)
		(pad "1" smd rect
			(at -0.889 0 270)
			(size 1.016 1.27)
			(layers "F.Cu" "F.Mask" "F.Paste")
			(net "GND")
		)
		(pad "2" smd rect
			(at 0.889 0 270)
			(size 1.016 1.27)
			(layers "F.Cu" "F.Mask" "F.Paste")
			(net "P3V3_AUX")
		)
	)
	(footprint ""
		(layer "F.Cu")
		(at 365.506 -205.867 180)
		(property "Reference" "R4629"
			(at 0 0 180)
			(layer "F.SilkS")
			(hide yes)
			(effects
				(font
					(size 1.27 1.27)
				)
			)
		)
		(property "Value" ""
			(at 0 0 180)
			(layer "F.Fab")
			(effects
				(font
					(size 1.27 1.27)
				)
			)
		)
		(duplicate_pad_numbers_are_jumpers no)
		(fp_line
			(start 0.7874 0.4064)
			(end -0.7874 0.4064)
			(stroke
				(width 0.1524)
				(type default)
			)
			(layer "F.SilkS")
		)
		(fp_line
			(start 0.7874 -0.4064)
			(end 0.7874 0.4064)
			(stroke
				(width 0.1524)
				(type default)
			)
			(layer "F.SilkS")
		)
		(fp_line
			(start -0.7874 0.4064)
			(end -0.7874 -0.4064)
			(stroke
				(width 0.1524)
				(type default)
			)
			(layer "F.SilkS")
		)
		(fp_line
			(start -0.7874 -0.4064)
			(end 0.7874 -0.4064)
			(stroke
				(width 0.1524)
				(type default)
			)
			(layer "F.SilkS")
		)
		(fp_line
			(start 0.67945 0.3048)
			(end 0.120396 0.3048)
			(stroke
				(width 0.1)
				(type default)
			)
			(layer "F.Fab")
		)
		(fp_line
			(start 0.67945 -0.3048)
			(end 0.67945 0.3048)
			(stroke
				(width 0.1)
				(type default)
			)
			(layer "F.Fab")
		)
		(fp_line
			(start 0.12065 -0.2794)
			(end 0.12065 -0.3048)
			(stroke
				(width 0.1)
				(type default)
			)
			(layer "F.Fab")
		)
		(fp_line
			(start 0.12065 -0.3048)
			(end 0.67945 -0.3048)
			(stroke
				(width 0.1)
				(type default)
			)
			(layer "F.Fab")
		)
		(fp_line
			(start 0.120396 0.3048)
			(end 0.120396 0.2794)
			(stroke
				(width 0.1)
				(type default)
			)
			(layer "F.Fab")
		)
		(fp_line
			(start 0.120396 0.2794)
			(end -0.12065 0.2794)
			(stroke
				(width 0.1)
				(type default)
			)
			(layer "F.Fab")
		)
		(fp_line
			(start -0.12065 0.3048)
			(end -0.67945 0.3048)
			(stroke
				(width 0.1)
				(type default)
			)
			(layer "F.Fab")
		)
		(fp_line
			(start -0.12065 0.2794)
			(end -0.12065 0.3048)
			(stroke
				(width 0.1)
				(type default)
			)
			(layer "F.Fab")
		)
		(fp_line
			(start -0.12065 -0.2794)
			(end 0.12065 -0.2794)
			(stroke
				(width 0.1)
				(type default)
			)
			(layer "F.Fab")
		)
		(fp_line
			(start -0.12065 -0.305054)
			(end -0.12065 -0.2794)
			(stroke
				(width 0.1)
				(type default)
			)
			(layer "F.Fab")
		)
		(fp_line
			(start -0.67945 0.3048)
			(end -0.67945 -0.305054)
			(stroke
				(width 0.1)
				(type default)
			)
			(layer "F.Fab")
		)
		(fp_line
			(start -0.67945 -0.305054)
			(end -0.12065 -0.305054)
			(stroke
				(width 0.1)
				(type default)
			)
			(layer "F.Fab")
		)
		(pad "1" smd circle
			(at -0.40005 0 180)
			(size 0 0)
			(layers "F.Cu" "F.Mask" "F.Paste")
			(net "RST_PEX_SSD1_PERST_N")
		)
		(pad "2" smd circle
			(at 0.40005 0 180)
			(size 0 0)
			(layers "F.Cu" "F.Mask" "F.Paste")
			(net "RST_PEX_SSD1_PERST_R_N")
		)
	)
	(footprint ""
		(layer "F.Cu")
		(at 213.801198 -220.322902)
		(property "Reference" "R4874"
			(at 0 0 0)
			(layer "F.SilkS")
			(hide yes)
			(effects
				(font
					(size 1.27 1.27)
				)
			)
		)
		(property "Value" ""
			(at 0 0 0)
			(layer "F.Fab")
			(effects
				(font
					(size 1.27 1.27)
				)
			)
		)
		(duplicate_pad_numbers_are_jumpers no)
		(fp_line
			(start -0.7874 -0.4064)
			(end 0.7874 -0.4064)
			(stroke
				(width 0.1524)
				(type default)
			)
			(layer "F.SilkS")
		)
		(fp_line
			(start -0.7874 0.4064)
			(end -0.7874 -0.4064)
			(stroke
				(width 0.1524)
				(type default)
			)
			(layer "F.SilkS")
		)
		(fp_line
			(start 0.7874 -0.4064)
			(end 0.7874 0.4064)
			(stroke
				(width 0.1524)
				(type default)
			)
			(layer "F.SilkS")
		)
		(fp_line
			(start 0.7874 0.4064)
			(end -0.7874 0.4064)
			(stroke
				(width 0.1524)
				(type default)
			)
			(layer "F.SilkS")
		)
		(fp_line
			(start -0.67945 -0.305054)
			(end -0.12065 -0.305054)
			(stroke
				(width 0.1)
				(type default)
			)
			(layer "F.Fab")
		)
		(fp_line
			(start -0.67945 0.3048)
			(end -0.67945 -0.305054)
			(stroke
				(width 0.1)
				(type default)
			)
			(layer "F.Fab")
		)
		(fp_line
			(start -0.12065 -0.305054)
			(end -0.12065 -0.2794)
			(stroke
				(width 0.1)
				(type default)
			)
			(layer "F.Fab")
		)
		(fp_line
			(start -0.12065 -0.2794)
			(end 0.12065 -0.2794)
			(stroke
				(width 0.1)
				(type default)
			)
			(layer "F.Fab")
		)
		(fp_line
			(start -0.12065 0.2794)
			(end -0.12065 0.3048)
			(stroke
				(width 0.1)
				(type default)
			)
			(layer "F.Fab")
		)
		(fp_line
			(start -0.12065 0.3048)
			(end -0.67945 0.3048)
			(stroke
				(width 0.1)
				(type default)
			)
			(layer "F.Fab")
		)
		(fp_line
			(start 0.120396 0.2794)
			(end -0.12065 0.2794)
			(stroke
				(width 0.1)
				(type default)
			)
			(layer "F.Fab")
		)
		(fp_line
			(start 0.120396 0.3048)
			(end 0.120396 0.2794)
			(stroke
				(width 0.1)
				(type default)
			)
			(layer "F.Fab")
		)
		(fp_line
			(start 0.12065 -0.3048)
			(end 0.67945 -0.3048)
			(stroke
				(width 0.1)
				(type default)
			)
			(layer "F.Fab")
		)
		(fp_line
			(start 0.12065 -0.2794)
			(end 0.12065 -0.3048)
			(stroke
				(width 0.1)
				(type default)
			)
			(layer "F.Fab")
		)
		(fp_line
			(start 0.67945 -0.3048)
			(end 0.67945 0.3048)
			(stroke
				(width 0.1)
				(type default)
			)
			(layer "F.Fab")
		)
		(fp_line
			(start 0.67945 0.3048)
			(end 0.120396 0.3048)
			(stroke
				(width 0.1)
				(type default)
			)
			(layer "F.Fab")
		)
		(pad "1" smd circle
			(at -0.40005 0)
			(size 0 0)
			(layers "F.Cu" "F.Mask" "F.Paste")
			(net "P1V2_AUX")
		)
		(pad "2" smd circle
			(at 0.40005 0)
			(size 0 0)
			(layers "F.Cu" "F.Mask" "F.Paste")
			(net "SMB_NIC4_SDA")
		)
	)
	(footprint ""
		(layer "F.Cu")
		(at 233.326178 -39.73576 -90)
		(property "Reference" "R5563"
			(at 0 0 270)
			(layer "F.SilkS")
			(hide yes)
			(effects
				(font
					(size 1.27 1.27)
				)
			)
		)
		(property "Value" ""
			(at 0 0 270)
			(layer "F.Fab")
			(effects
				(font
					(size 1.27 1.27)
				)
			)
		)
		(duplicate_pad_numbers_are_jumpers no)
		(fp_line
			(start -0.7874 0.4064)
			(end -0.7874 -0.4064)
			(stroke
				(width 0.1524)
				(type default)
			)
			(layer "F.SilkS")
		)
		(fp_line
			(start 0.7874 0.4064)
			(end -0.7874 0.4064)
			(stroke
				(width 0.1524)
				(type default)
			)
			(layer "F.SilkS")
		)
		(fp_line
			(start -0.7874 -0.4064)
			(end 0.7874 -0.4064)
			(stroke
				(width 0.1524)
				(type default)
			)
			(layer "F.SilkS")
		)
		(fp_line
			(start 0.7874 -0.4064)
			(end 0.7874 0.4064)
			(stroke
				(width 0.1524)
				(type default)
			)
			(layer "F.SilkS")
		)
		(fp_line
			(start -0.67945 0.3048)
			(end -0.67945 -0.305054)
			(stroke
				(width 0.1)
				(type default)
			)
			(layer "F.Fab")
		)
		(fp_line
			(start -0.12065 0.3048)
			(end -0.67945 0.3048)
			(stroke
				(width 0.1)
				(type default)
			)
			(layer "F.Fab")
		)
		(fp_line
			(start 0.120396 0.3048)
			(end 0.120396 0.2794)
			(stroke
				(width 0.1)
				(type default)
			)
			(layer "F.Fab")
		)
		(fp_line
			(start 0.67945 0.3048)
			(end 0.120396 0.3048)
			(stroke
				(width 0.1)
				(type default)
			)
			(layer "F.Fab")
		)
		(fp_line
			(start -0.12065 0.2794)
			(end -0.12065 0.3048)
			(stroke
				(width 0.1)
				(type default)
			)
			(layer "F.Fab")
		)
		(fp_line
			(start 0.120396 0.2794)
			(end -0.12065 0.2794)
			(stroke
				(width 0.1)
				(type default)
			)
			(layer "F.Fab")
		)
		(fp_line
			(start -0.12065 -0.2794)
			(end 0.12065 -0.2794)
			(stroke
				(width 0.1)
				(type default)
			)
			(layer "F.Fab")
		)
		(fp_line
			(start 0.12065 -0.2794)
			(end 0.12065 -0.3048)
			(stroke
				(width 0.1)
				(type default)
			)
			(layer "F.Fab")
		)
		(fp_line
			(start 0.12065 -0.3048)
			(end 0.67945 -0.3048)
			(stroke
				(width 0.1)
				(type default)
			)
			(layer "F.Fab")
		)
		(fp_line
			(start 0.67945 -0.3048)
			(end 0.67945 0.3048)
			(stroke
				(width 0.1)
				(type default)
			)
			(layer "F.Fab")
		)
		(fp_line
			(start -0.67945 -0.305054)
			(end -0.12065 -0.305054)
			(stroke
				(width 0.1)
				(type default)
			)
			(layer "F.Fab")
		)
		(fp_line
			(start -0.12065 -0.305054)
			(end -0.12065 -0.2794)
			(stroke
				(width 0.1)
				(type default)
			)
			(layer "F.Fab")
		)
		(pad "1" smd circle
			(at -0.40005 0 270)
			(size 0 0)
			(layers "F.Cu" "F.Mask" "F.Paste")
			(net "P3V3_AUX")
		)
		(pad "2" smd circle
			(at 0.40005 0 270)
			(size 0 0)
			(layers "F.Cu" "F.Mask" "F.Paste")
			(net "SSD8_AUX_P3V3_EN")
		)
	)
	(footprint ""
		(layer "F.Cu")
		(at 138.363452 -146.592798 -90)
		(property "Reference" "R711"
			(at 0 0 270)
			(layer "F.SilkS")
			(hide yes)
			(effects
				(font
					(size 1.27 1.27)
				)
			)
		)
		(property "Value" ""
			(at 0 0 270)
			(layer "F.Fab")
			(effects
				(font
					(size 1.27 1.27)
				)
			)
		)
		(duplicate_pad_numbers_are_jumpers no)
		(fp_line
			(start -0.7874 0.4064)
			(end -0.7874 -0.4064)
			(stroke
				(width 0.1524)
				(type default)
			)
			(layer "F.SilkS")
		)
		(fp_line
			(start 0.7874 0.4064)
			(end -0.7874 0.4064)
			(stroke
				(width 0.1524)
				(type default)
			)
			(layer "F.SilkS")
		)
		(fp_line
			(start -0.7874 -0.4064)
			(end 0.7874 -0.4064)
			(stroke
				(width 0.1524)
				(type default)
			)
			(layer "F.SilkS")
		)
		(fp_line
			(start 0.7874 -0.4064)
			(end 0.7874 0.4064)
			(stroke
				(width 0.1524)
				(type default)
			)
			(layer "F.SilkS")
		)
		(fp_line
			(start -0.67945 0.3048)
			(end -0.67945 -0.305054)
			(stroke
				(width 0.1)
				(type default)
			)
			(layer "F.Fab")
		)
		(fp_line
			(start -0.12065 0.3048)
			(end -0.67945 0.3048)
			(stroke
				(width 0.1)
				(type default)
			)
			(layer "F.Fab")
		)
		(fp_line
			(start 0.120396 0.3048)
			(end 0.120396 0.2794)
			(stroke
				(width 0.1)
				(type default)
			)
			(layer "F.Fab")
		)
		(fp_line
			(start 0.67945 0.3048)
			(end 0.120396 0.3048)
			(stroke
				(width 0.1)
				(type default)
			)
			(layer "F.Fab")
		)
		(fp_line
			(start -0.12065 0.2794)
			(end -0.12065 0.3048)
			(stroke
				(width 0.1)
				(type default)
			)
			(layer "F.Fab")
		)
		(fp_line
			(start 0.120396 0.2794)
			(end -0.12065 0.2794)
			(stroke
				(width 0.1)
				(type default)
			)
			(layer "F.Fab")
		)
		(fp_line
			(start -0.12065 -0.2794)
			(end 0.12065 -0.2794)
			(stroke
				(width 0.1)
				(type default)
			)
			(layer "F.Fab")
		)
		(fp_line
			(start 0.12065 -0.2794)
			(end 0.12065 -0.3048)
			(stroke
				(width 0.1)
				(type default)
			)
			(layer "F.Fab")
		)
		(fp_line
			(start 0.12065 -0.3048)
			(end 0.67945 -0.3048)
			(stroke
				(width 0.1)
				(type default)
			)
			(layer "F.Fab")
		)
		(fp_line
			(start 0.67945 -0.3048)
			(end 0.67945 0.3048)
			(stroke
				(width 0.1)
				(type default)
			)
			(layer "F.Fab")
		)
		(fp_line
			(start -0.67945 -0.305054)
			(end -0.12065 -0.305054)
			(stroke
				(width 0.1)
				(type default)
			)
			(layer "F.Fab")
		)
		(fp_line
			(start -0.12065 -0.305054)
			(end -0.12065 -0.2794)
			(stroke
				(width 0.1)
				(type default)
			)
			(layer "F.Fab")
		)
		(pad "1" smd circle
			(at -0.40005 0 270)
			(size 0 0)
			(layers "F.Cu" "F.Mask" "F.Paste")
			(net "P12V_NIC2_R")
		)
		(pad "2" smd circle
			(at 0.40005 0 270)
			(size 0 0)
			(layers "F.Cu" "F.Mask" "F.Paste")
			(net "P12V_NIC2_VIN_P")
		)
	)
	(footprint ""
		(layer "F.Cu")
		(at 268.838426 -122.79884)
		(property "Reference" "C465"
			(at 0 0 0)
			(layer "F.SilkS")
			(hide yes)
			(effects
				(font
					(size 1.27 1.27)
				)
			)
		)
		(property "Value" ""
			(at 0 0 0)
			(layer "F.Fab")
			(effects
				(font
					(size 1.27 1.27)
				)
			)
		)
		(duplicate_pad_numbers_are_jumpers no)
		(fp_line
			(start -0.299974 -0.150114)
			(end 0.299974 -0.150114)
			(stroke
				(width 0.1)
				(type default)
			)
			(layer "F.Fab")
		)
		(fp_line
			(start -0.299974 0.150114)
			(end -0.299974 -0.150114)
			(stroke
				(width 0.1)
				(type default)
			)
			(layer "F.Fab")
		)
		(fp_line
			(start 0.299974 -0.150114)
			(end 0.299974 0.150114)
			(stroke
				(width 0.1)
				(type default)
			)
			(layer "F.Fab")
		)
		(fp_line
			(start 0.299974 0.150114)
			(end -0.299974 0.150114)
			(stroke
				(width 0.1)
				(type default)
			)
			(layer "F.Fab")
		)
		(pad "1" smd rect
			(at -0.2667 0)
			(size 0.3048 0.381)
			(layers "F.Cu" "F.Mask" "F.Paste")
			(net "P5E_PEX2_STN1_TX_DP<26>")
		)
		(pad "2" smd rect
			(at 0.2667 0)
			(size 0.3048 0.381)
			(layers "F.Cu" "F.Mask" "F.Paste")
			(net "P5E_PEX2_STN1_TX_C_DP<26>")
		)
	)
	(footprint ""
		(layer "F.Cu")
		(at 262.638286 -250.070874 -90)
		(property "Reference" "R1336"
			(at 0 0 270)
			(layer "F.SilkS")
			(hide yes)
			(effects
				(font
					(size 1.27 1.27)
				)
			)
		)
		(property "Value" ""
			(at 0 0 270)
			(layer "F.Fab")
			(effects
				(font
					(size 1.27 1.27)
				)
			)
		)
		(duplicate_pad_numbers_are_jumpers no)
		(fp_line
			(start -0.7874 0.4064)
			(end -0.7874 -0.4064)
			(stroke
				(width 0.1524)
				(type default)
			)
			(layer "F.SilkS")
		)
		(fp_line
			(start 0.7874 0.4064)
			(end -0.7874 0.4064)
			(stroke
				(width 0.1524)
				(type default)
			)
			(layer "F.SilkS")
		)
		(fp_line
			(start -0.7874 -0.4064)
			(end 0.7874 -0.4064)
			(stroke
				(width 0.1524)
				(type default)
			)
			(layer "F.SilkS")
		)
		(fp_line
			(start 0.7874 -0.4064)
			(end 0.7874 0.4064)
			(stroke
				(width 0.1524)
				(type default)
			)
			(layer "F.SilkS")
		)
		(fp_line
			(start -0.67945 0.3048)
			(end -0.67945 -0.305054)
			(stroke
				(width 0.1)
				(type default)
			)
			(layer "F.Fab")
		)
		(fp_line
			(start -0.12065 0.3048)
			(end -0.67945 0.3048)
			(stroke
				(width 0.1)
				(type default)
			)
			(layer "F.Fab")
		)
		(fp_line
			(start 0.120396 0.3048)
			(end 0.120396 0.2794)
			(stroke
				(width 0.1)
				(type default)
			)
			(layer "F.Fab")
		)
		(fp_line
			(start 0.67945 0.3048)
			(end 0.120396 0.3048)
			(stroke
				(width 0.1)
				(type default)
			)
			(layer "F.Fab")
		)
		(fp_line
			(start -0.12065 0.2794)
			(end -0.12065 0.3048)
			(stroke
				(width 0.1)
				(type default)
			)
			(layer "F.Fab")
		)
		(fp_line
			(start 0.120396 0.2794)
			(end -0.12065 0.2794)
			(stroke
				(width 0.1)
				(type default)
			)
			(layer "F.Fab")
		)
		(fp_line
			(start -0.12065 -0.2794)
			(end 0.12065 -0.2794)
			(stroke
				(width 0.1)
				(type default)
			)
			(layer "F.Fab")
		)
		(fp_line
			(start 0.12065 -0.2794)
			(end 0.12065 -0.3048)
			(stroke
				(width 0.1)
				(type default)
			)
			(layer "F.Fab")
		)
		(fp_line
			(start 0.12065 -0.3048)
			(end 0.67945 -0.3048)
			(stroke
				(width 0.1)
				(type default)
			)
			(layer "F.Fab")
		)
		(fp_line
			(start 0.67945 -0.3048)
			(end 0.67945 0.3048)
			(stroke
				(width 0.1)
				(type default)
			)
			(layer "F.Fab")
		)
		(fp_line
			(start -0.67945 -0.305054)
			(end -0.12065 -0.305054)
			(stroke
				(width 0.1)
				(type default)
			)
			(layer "F.Fab")
		)
		(fp_line
			(start -0.12065 -0.305054)
			(end -0.12065 -0.2794)
			(stroke
				(width 0.1)
				(type default)
			)
			(layer "F.Fab")
		)
		(pad "1" smd circle
			(at -0.40005 0 270)
			(size 0 0)
			(layers "F.Cu" "F.Mask" "F.Paste")
			(net "PEX2_MODE_SEL0")
		)
		(pad "2" smd circle
			(at 0.40005 0 270)
			(size 0 0)
			(layers "F.Cu" "F.Mask" "F.Paste")
			(net "P1V8_PEX")
		)
	)
	(footprint ""
		(layer "F.Cu")
		(at 263.85012 -50.96383 180)
		(property "Reference" "PC561"
			(at 0 0 180)
			(layer "F.SilkS")
			(hide yes)
			(effects
				(font
					(size 1.27 1.27)
				)
			)
		)
		(property "Value" ""
			(at 0 0 180)
			(layer "F.Fab")
			(effects
				(font
					(size 1.27 1.27)
				)
			)
		)
		(duplicate_pad_numbers_are_jumpers no)
		(fp_line
			(start 1.524 0.762)
			(end -1.524 0.762)
			(stroke
				(width 0.1524)
				(type default)
			)
			(layer "F.SilkS")
		)
		(fp_line
			(start 1.524 -0.762)
			(end 1.524 0.762)
			(stroke
				(width 0.1524)
				(type default)
			)
			(layer "F.SilkS")
		)
		(fp_line
			(start -1.524 0.762)
			(end -1.524 -0.762)
			(stroke
				(width 0.1524)
				(type default)
			)
			(layer "F.SilkS")
		)
		(fp_line
			(start -1.524 -0.762)
			(end 1.524 -0.762)
			(stroke
				(width 0.1524)
				(type default)
			)
			(layer "F.SilkS")
		)
		(fp_line
			(start 1.1049 0.724916)
			(end 1.1049 -0.724916)
			(stroke
				(width 0.1)
				(type default)
			)
			(layer "F.Fab")
		)
		(fp_line
			(start 1.1049 -0.724916)
			(end -1.1049 -0.724916)
			(stroke
				(width 0.1)
				(type default)
			)
			(layer "F.Fab")
		)
		(fp_line
			(start -1.1049 0.724916)
			(end 1.1049 0.724916)
			(stroke
				(width 0.1)
				(type default)
			)
			(layer "F.Fab")
		)
		(fp_line
			(start -1.1049 -0.724916)
			(end -1.1049 0.724916)
			(stroke
				(width 0.1)
				(type default)
			)
			(layer "F.Fab")
		)
		(pad "1" smd rect
			(at -0.889 0)
			(size 1.016 1.27)
			(layers "F.Cu" "F.Mask" "F.Paste")
			(net "P3V3_SSD9")
		)
		(pad "2" smd rect
			(at 0.889 0)
			(size 1.016 1.27)
			(layers "F.Cu" "F.Mask" "F.Paste")
			(net "GND")
		)
	)
	(footprint ""
		(layer "F.Cu")
		(at 478.274888 -552.440348 180)
		(property "Reference" "J42_OTH"
			(at -3.2385 -1.402334 0)
			(unlocked yes)
			(layer "B.SilkS")
			(effects
				(font
					(size 0.7874 0.5842)
					(thickness 0.1524)
				)
				(justify mirror)
			)
		)
		(property "Value" ""
			(at 0 0 180)
			(layer "F.Fab")
			(effects
				(font
					(size 1.27 1.27)
				)
			)
		)
		(duplicate_pad_numbers_are_jumpers no)
		(pad "1" thru_hole circle
			(at 0 0 180)
			(size 0.4572 0.4572)
			(drill 0.2032)
			(layers "*.Cu" "*.Mask")
			(remove_unused_layers no)
			(net "Net_9094")
			(clearance 0.127)
			(thermal_gap 0.127)
			(padstack
				(mode front_inner_back)
				(layer "Inner"
					(shape circle)
					(size 0.4572 0.4572)
					(clearance 0.127)
				)
				(layer "B.Cu"
					(shape circle)
					(size 0.508 0.508)
					(clearance 0.1016)
				)
			)
		)
	)
	(footprint ""
		(layer "F.Cu")
		(at 198.76135 -148.91131 180)
		(property "Reference" "C220"
			(at 0 0 180)
			(layer "F.SilkS")
			(hide yes)
			(effects
				(font
					(size 1.27 1.27)
				)
			)
		)
		(property "Value" ""
			(at 0 0 180)
			(layer "F.Fab")
			(effects
				(font
					(size 1.27 1.27)
				)
			)
		)
		(duplicate_pad_numbers_are_jumpers no)
		(fp_line
			(start 0.299974 0.150114)
			(end -0.299974 0.150114)
			(stroke
				(width 0.1)
				(type default)
			)
			(layer "F.Fab")
		)
		(fp_line
			(start 0.299974 -0.150114)
			(end 0.299974 0.150114)
			(stroke
				(width 0.1)
				(type default)
			)
			(layer "F.Fab")
		)
		(fp_line
			(start -0.299974 0.150114)
			(end -0.299974 -0.150114)
			(stroke
				(width 0.1)
				(type default)
			)
			(layer "F.Fab")
		)
		(fp_line
			(start -0.299974 -0.150114)
			(end 0.299974 -0.150114)
			(stroke
				(width 0.1)
				(type default)
			)
			(layer "F.Fab")
		)
		(pad "1" smd rect
			(at -0.2667 0 180)
			(size 0.3048 0.381)
			(layers "F.Cu" "F.Mask" "F.Paste")
			(net "P5E_PEX1_STN0_TX_DP<11>")
		)
		(pad "2" smd rect
			(at 0.2667 0 180)
			(size 0.3048 0.381)
			(layers "F.Cu" "F.Mask" "F.Paste")
			(net "P5E_PEX1_STN0_TX_C_DP<11>")
		)
	)
	(footprint ""
		(layer "F.Cu")
		(at 36.534344 -250.070874 -90)
		(property "Reference" "R1158"
			(at 0 0 270)
			(layer "F.SilkS")
			(hide yes)
			(effects
				(font
					(size 1.27 1.27)
				)
			)
		)
		(property "Value" ""
			(at 0 0 270)
			(layer "F.Fab")
			(effects
				(font
					(size 1.27 1.27)
				)
			)
		)
		(duplicate_pad_numbers_are_jumpers no)
		(fp_line
			(start -0.7874 0.4064)
			(end -0.7874 -0.4064)
			(stroke
				(width 0.1524)
				(type default)
			)
			(layer "F.SilkS")
		)
		(fp_line
			(start 0.7874 0.4064)
			(end -0.7874 0.4064)
			(stroke
				(width 0.1524)
				(type default)
			)
			(layer "F.SilkS")
		)
		(fp_line
			(start -0.7874 -0.4064)
			(end 0.7874 -0.4064)
			(stroke
				(width 0.1524)
				(type default)
			)
			(layer "F.SilkS")
		)
		(fp_line
			(start 0.7874 -0.4064)
			(end 0.7874 0.4064)
			(stroke
				(width 0.1524)
				(type default)
			)
			(layer "F.SilkS")
		)
		(fp_line
			(start -0.67945 0.3048)
			(end -0.67945 -0.305054)
			(stroke
				(width 0.1)
				(type default)
			)
			(layer "F.Fab")
		)
		(fp_line
			(start -0.12065 0.3048)
			(end -0.67945 0.3048)
			(stroke
				(width 0.1)
				(type default)
			)
			(layer "F.Fab")
		)
		(fp_line
			(start 0.120396 0.3048)
			(end 0.120396 0.2794)
			(stroke
				(width 0.1)
				(type default)
			)
			(layer "F.Fab")
		)
		(fp_line
			(start 0.67945 0.3048)
			(end 0.120396 0.3048)
			(stroke
				(width 0.1)
				(type default)
			)
			(layer "F.Fab")
		)
		(fp_line
			(start -0.12065 0.2794)
			(end -0.12065 0.3048)
			(stroke
				(width 0.1)
				(type default)
			)
			(layer "F.Fab")
		)
		(fp_line
			(start 0.120396 0.2794)
			(end -0.12065 0.2794)
			(stroke
				(width 0.1)
				(type default)
			)
			(layer "F.Fab")
		)
		(fp_line
			(start -0.12065 -0.2794)
			(end 0.12065 -0.2794)
			(stroke
				(width 0.1)
				(type default)
			)
			(layer "F.Fab")
		)
		(fp_line
			(start 0.12065 -0.2794)
			(end 0.12065 -0.3048)
			(stroke
				(width 0.1)
				(type default)
			)
			(layer "F.Fab")
		)
		(fp_line
			(start 0.12065 -0.3048)
			(end 0.67945 -0.3048)
			(stroke
				(width 0.1)
				(type default)
			)
			(layer "F.Fab")
		)
		(fp_line
			(start 0.67945 -0.3048)
			(end 0.67945 0.3048)
			(stroke
				(width 0.1)
				(type default)
			)
			(layer "F.Fab")
		)
		(fp_line
			(start -0.67945 -0.305054)
			(end -0.12065 -0.305054)
			(stroke
				(width 0.1)
				(type default)
			)
			(layer "F.Fab")
		)
		(fp_line
			(start -0.12065 -0.305054)
			(end -0.12065 -0.2794)
			(stroke
				(width 0.1)
				(type default)
			)
			(layer "F.Fab")
		)
		(pad "1" smd circle
			(at -0.40005 0 270)
			(size 0 0)
			(layers "F.Cu" "F.Mask" "F.Paste")
			(net "PEX0_MODE_SEL6")
		)
		(pad "2" smd circle
			(at 0.40005 0 270)
			(size 0 0)
			(layers "F.Cu" "F.Mask" "F.Paste")
			(net "P1V8_PEX")
		)
	)
	(footprint ""
		(layer "F.Cu")
		(at 10.716514 -277.814278 180)
		(property "Reference" "C625"
			(at 0 0 180)
			(layer "F.SilkS")
			(hide yes)
			(effects
				(font
					(size 1.27 1.27)
				)
			)
		)
		(property "Value" ""
			(at 0 0 180)
			(layer "F.Fab")
			(effects
				(font
					(size 1.27 1.27)
				)
			)
		)
		(duplicate_pad_numbers_are_jumpers no)
		(fp_line
			(start 0.7874 0.4064)
			(end -0.7874 0.4064)
			(stroke
				(width 0.1524)
				(type default)
			)
			(layer "F.SilkS")
		)
		(fp_line
			(start 0.7874 -0.4064)
			(end 0.7874 0.4064)
			(stroke
				(width 0.1524)
				(type default)
			)
			(layer "F.SilkS")
		)
		(fp_line
			(start -0.7874 0.4064)
			(end -0.7874 -0.4064)
			(stroke
				(width 0.1524)
				(type default)
			)
			(layer "F.SilkS")
		)
		(fp_line
			(start -0.7874 -0.4064)
			(end 0.7874 -0.4064)
			(stroke
				(width 0.1524)
				(type default)
			)
			(layer "F.SilkS")
		)
		(fp_line
			(start 0.67945 0.3048)
			(end 0.120396 0.3048)
			(stroke
				(width 0.1)
				(type default)
			)
			(layer "F.Fab")
		)
		(fp_line
			(start 0.67945 -0.3048)
			(end 0.67945 0.3048)
			(stroke
				(width 0.1)
				(type default)
			)
			(layer "F.Fab")
		)
		(fp_line
			(start 0.12065 -0.2794)
			(end 0.12065 -0.3048)
			(stroke
				(width 0.1)
				(type default)
			)
			(layer "F.Fab")
		)
		(fp_line
			(start 0.12065 -0.3048)
			(end 0.67945 -0.3048)
			(stroke
				(width 0.1)
				(type default)
			)
			(layer "F.Fab")
		)
		(fp_line
			(start 0.120396 0.3048)
			(end 0.120396 0.2794)
			(stroke
				(width 0.1)
				(type default)
			)
			(layer "F.Fab")
		)
		(fp_line
			(start 0.120396 0.2794)
			(end -0.12065 0.2794)
			(stroke
				(width 0.1)
				(type default)
			)
			(layer "F.Fab")
		)
		(fp_line
			(start -0.12065 0.3048)
			(end -0.67945 0.3048)
			(stroke
				(width 0.1)
				(type default)
			)
			(layer "F.Fab")
		)
		(fp_line
			(start -0.12065 0.2794)
			(end -0.12065 0.3048)
			(stroke
				(width 0.1)
				(type default)
			)
			(layer "F.Fab")
		)
		(fp_line
			(start -0.12065 -0.2794)
			(end 0.12065 -0.2794)
			(stroke
				(width 0.1)
				(type default)
			)
			(layer "F.Fab")
		)
		(fp_line
			(start -0.12065 -0.305054)
			(end -0.12065 -0.2794)
			(stroke
				(width 0.1)
				(type default)
			)
			(layer "F.Fab")
		)
		(fp_line
			(start -0.67945 0.3048)
			(end -0.67945 -0.305054)
			(stroke
				(width 0.1)
				(type default)
			)
			(layer "F.Fab")
		)
		(fp_line
			(start -0.67945 -0.305054)
			(end -0.12065 -0.305054)
			(stroke
				(width 0.1)
				(type default)
			)
			(layer "F.Fab")
		)
		(pad "1" smd circle
			(at -0.40005 0 180)
			(size 0 0)
			(layers "F.Cu" "F.Mask" "F.Paste")
			(net "P3V3_AUX")
		)
		(pad "2" smd circle
			(at 0.40005 0 180)
			(size 0 0)
			(layers "F.Cu" "F.Mask" "F.Paste")
			(net "GND")
		)
	)
	(footprint ""
		(layer "F.Cu")
		(at 224.514664 -207.02016 90)
		(property "Reference" "R5715"
			(at 0 0 90)
			(layer "F.SilkS")
			(hide yes)
			(effects
				(font
					(size 1.27 1.27)
				)
			)
		)
		(property "Value" ""
			(at 0 0 90)
			(layer "F.Fab")
			(effects
				(font
					(size 1.27 1.27)
				)
			)
		)
		(duplicate_pad_numbers_are_jumpers no)
		(fp_line
			(start 0.7874 -0.4064)
			(end 0.7874 0.4064)
			(stroke
				(width 0.1524)
				(type default)
			)
			(layer "F.SilkS")
		)
		(fp_line
			(start -0.7874 -0.4064)
			(end 0.7874 -0.4064)
			(stroke
				(width 0.1524)
				(type default)
			)
			(layer "F.SilkS")
		)
		(fp_line
			(start 0.7874 0.4064)
			(end -0.7874 0.4064)
			(stroke
				(width 0.1524)
				(type default)
			)
			(layer "F.SilkS")
		)
		(fp_line
			(start -0.7874 0.4064)
			(end -0.7874 -0.4064)
			(stroke
				(width 0.1524)
				(type default)
			)
			(layer "F.SilkS")
		)
		(fp_line
			(start -0.12065 -0.305054)
			(end -0.12065 -0.2794)
			(stroke
				(width 0.1)
				(type default)
			)
			(layer "F.Fab")
		)
		(fp_line
			(start -0.67945 -0.305054)
			(end -0.12065 -0.305054)
			(stroke
				(width 0.1)
				(type default)
			)
			(layer "F.Fab")
		)
		(fp_line
			(start 0.67945 -0.3048)
			(end 0.67945 0.3048)
			(stroke
				(width 0.1)
				(type default)
			)
			(layer "F.Fab")
		)
		(fp_line
			(start 0.12065 -0.3048)
			(end 0.67945 -0.3048)
			(stroke
				(width 0.1)
				(type default)
			)
			(layer "F.Fab")
		)
		(fp_line
			(start 0.12065 -0.2794)
			(end 0.12065 -0.3048)
			(stroke
				(width 0.1)
				(type default)
			)
			(layer "F.Fab")
		)
		(fp_line
			(start -0.12065 -0.2794)
			(end 0.12065 -0.2794)
			(stroke
				(width 0.1)
				(type default)
			)
			(layer "F.Fab")
		)
		(fp_line
			(start 0.120396 0.2794)
			(end -0.12065 0.2794)
			(stroke
				(width 0.1)
				(type default)
			)
			(layer "F.Fab")
		)
		(fp_line
			(start -0.12065 0.2794)
			(end -0.12065 0.3048)
			(stroke
				(width 0.1)
				(type default)
			)
			(layer "F.Fab")
		)
		(fp_line
			(start 0.67945 0.3048)
			(end 0.120396 0.3048)
			(stroke
				(width 0.1)
				(type default)
			)
			(layer "F.Fab")
		)
		(fp_line
			(start 0.120396 0.3048)
			(end 0.120396 0.2794)
			(stroke
				(width 0.1)
				(type default)
			)
			(layer "F.Fab")
		)
		(fp_line
			(start -0.12065 0.3048)
			(end -0.67945 0.3048)
			(stroke
				(width 0.1)
				(type default)
			)
			(layer "F.Fab")
		)
		(fp_line
			(start -0.67945 0.3048)
			(end -0.67945 -0.305054)
			(stroke
				(width 0.1)
				(type default)
			)
			(layer "F.Fab")
		)
		(pad "1" smd circle
			(at -0.40005 0 90)
			(size 0 0)
			(layers "F.Cu" "F.Mask" "F.Paste")
			(net "RST_SMB_FPGA_R_N")
		)
		(pad "2" smd circle
			(at 0.40005 0 90)
			(size 0 0)
			(layers "F.Cu" "F.Mask" "F.Paste")
			(net "RST_SMB_FPGA_N")
		)
	)
	(footprint ""
		(layer "F.Cu")
		(at 304.179986 -127.700024 180)
		(property "Reference" "J25"
			(at 5.322316 -34.482024 90)
			(unlocked yes)
			(layer "F.SilkS")
			(effects
				(font
					(size 0.7874 0.5842)
					(thickness 0.1524)
				)
				(justify left)
			)
		)
		(property "Value" ""
			(at 0 0 180)
			(layer "F.Fab")
			(effects
				(font
					(size 1.27 1.27)
				)
			)
		)
		(duplicate_pad_numbers_are_jumpers no)
		(fp_line
			(start 4.507484 -21.5265)
			(end 4.507484 -34.720022)
			(stroke
				(width 0.1524)
				(type default)
			)
			(layer "F.SilkS")
		)
		(fp_line
			(start 4.507484 -34.720022)
			(end 2.6162 -34.720022)
			(stroke
				(width 0.1524)
				(type default)
			)
			(layer "F.SilkS")
		)
		(fp_line
			(start 2.6035 34.720022)
			(end 4.507484 34.720022)
			(stroke
				(width 0.1524)
				(type default)
			)
			(layer "F.SilkS")
		)
		(fp_line
			(start -0.57658 -34.720022)
			(end -4.507484 -34.720022)
			(stroke
				(width 0.1524)
				(type default)
			)
			(layer "F.SilkS")
		)
		(fp_line
			(start -4.507484 34.720022)
			(end -0.5588 34.720022)
			(stroke
				(width 0.1524)
				(type default)
			)
			(layer "F.SilkS")
		)
		(fp_poly
			(pts
				(xy 5.735574 -17.957038) (xy 5.735574 -18.973038) (xy 4.719574 -18.465038)
			)
			(stroke
				(width 0)
				(type default)
			)
			(fill yes)
			(layer "F.SilkS")
		)
		(fp_line
			(start 4.507484 34.720022)
			(end 4.507484 -34.720022)
			(stroke
				(width 0.1)
				(type default)
			)
			(layer "F.Fab")
		)
		(fp_line
			(start 4.507484 -34.720022)
			(end -4.507484 -34.720022)
			(stroke
				(width 0.1)
				(type default)
			)
			(layer "F.Fab")
		)
		(fp_line
			(start -4.507484 34.720022)
			(end 4.507484 34.720022)
			(stroke
				(width 0.1)
				(type default)
			)
			(layer "F.Fab")
		)
		(fp_line
			(start -4.507484 -34.720022)
			(end -4.507484 34.720022)
			(stroke
				(width 0.1)
				(type default)
			)
			(layer "F.Fab")
		)
		(fp_poly
			(pts
				(xy 5.735574 -17.957038) (xy 5.735574 -18.973038) (xy 4.719574 -18.465038)
			)
			(stroke
				(width 0)
				(type default)
			)
			(fill yes)
			(layer "F.Fab")
		)
		(pad "" np_thru_hole circle
			(at -0.727456 -32.485076 180)
			(size 1.1176 1.1176)
			(drill 1.1176)
			(layers "*.Cu" "*.Mask")
			(clearance 0.381)
			(thermal_gap 0.381)
		)
		(pad "" np_thru_hole circle
			(at 1.022604 32.485076 180)
			(size 1.1176 1.1176)
			(drill 1.1176)
			(layers "*.Cu" "*.Mask")
			(clearance 0.381)
			(thermal_gap 0.381)
		)
		(pad "A1" smd rect
			(at 3.322574 -18.465038 90)
			(size 0.3556 1.2192)
			(layers "F.Cu" "F.Mask" "F.Paste")
			(net "GND")
		)
		(pad "A2" smd rect
			(at 3.322574 -17.86509 90)
			(size 0.3556 1.2192)
			(layers "F.Cu" "F.Mask" "F.Paste")
			(net "GND")
		)
		(pad "A3" smd rect
			(at 3.322574 -17.264888 90)
			(size 0.3556 1.2192)
			(layers "F.Cu" "F.Mask" "F.Paste")
			(net "GND")
		)
		(pad "A4" smd rect
			(at 3.322574 -16.66494 90)
			(size 0.3556 1.2192)
			(layers "F.Cu" "F.Mask" "F.Paste")
			(net "GND")
		)
		(pad "A5" smd rect
			(at 3.322574 -16.064992 90)
			(size 0.3556 1.2192)
			(layers "F.Cu" "F.Mask" "F.Paste")
			(net "GND")
		)
		(pad "A6" smd rect
			(at 3.322574 -15.465044 90)
			(size 0.3556 1.2192)
			(layers "F.Cu" "F.Mask" "F.Paste")
			(net "GND")
		)
		(pad "A7" smd rect
			(at 3.322574 -14.865096 90)
			(size 0.3556 1.2192)
			(layers "F.Cu" "F.Mask" "F.Paste")
			(net "SMB_NIC5_LS_SCL")
		)
		(pad "A8" smd rect
			(at 3.322574 -14.264894 90)
			(size 0.3556 1.2192)
			(layers "F.Cu" "F.Mask" "F.Paste")
			(net "SMB_NIC5_LS_SDA")
		)
		(pad "A9" smd rect
			(at 3.322574 -13.664946 90)
			(size 0.3556 1.2192)
			(layers "F.Cu" "F.Mask" "F.Paste")
			(net "RST_SMB_NIC5_MUX_ISO_R_N")
		)
		(pad "A10" smd rect
			(at 3.322574 -13.064998 90)
			(size 0.3556 1.2192)
			(layers "F.Cu" "F.Mask" "F.Paste")
			(net "GND")
		)
		(pad "A11" smd rect
			(at 3.322574 -12.46505 90)
			(size 0.3556 1.2192)
			(layers "F.Cu" "F.Mask" "F.Paste")
			(net "RST_NIC5_PERST1_R_N")
		)
		(pad "A12" smd rect
			(at 3.322574 -11.865102 90)
			(size 0.3556 1.2192)
			(layers "F.Cu" "F.Mask" "F.Paste")
			(net "PRSNTB2_NIC5_N")
		)
		(pad "A13" smd rect
			(at 3.322574 -11.2649 90)
			(size 0.3556 1.2192)
			(layers "F.Cu" "F.Mask" "F.Paste")
			(net "GND")
		)
		(pad "A14" smd rect
			(at 3.322574 -10.664952 90)
			(size 0.3556 1.2192)
			(layers "F.Cu" "F.Mask" "F.Paste")
			(net "Net_2640")
		)
		(pad "A15" smd rect
			(at 3.322574 -10.065004 90)
			(size 0.3556 1.2192)
			(layers "F.Cu" "F.Mask" "F.Paste")
			(net "Net_2643")
		)
		(pad "A16" smd rect
			(at 3.322574 -9.465056 90)
			(size 0.3556 1.2192)
			(layers "F.Cu" "F.Mask" "F.Paste")
			(net "GND")
		)
		(pad "A17" smd rect
			(at 3.322574 -8.865108 90)
			(size 0.3556 1.2192)
			(layers "F.Cu" "F.Mask" "F.Paste")
			(net "P5E_PEX2_STN0_RX_DN<0>")
		)
		(pad "A18" smd rect
			(at 3.322574 -8.264906 90)
			(size 0.3556 1.2192)
			(layers "F.Cu" "F.Mask" "F.Paste")
			(net "P5E_PEX2_STN0_RX_DP<0>")
		)
		(pad "A19" smd rect
			(at 3.322574 -7.664958 90)
			(size 0.3556 1.2192)
			(layers "F.Cu" "F.Mask" "F.Paste")
			(net "GND")
		)
		(pad "A20" smd rect
			(at 3.322574 -7.06501 90)
			(size 0.3556 1.2192)
			(layers "F.Cu" "F.Mask" "F.Paste")
			(net "P5E_PEX2_STN0_RX_DN<1>")
		)
		(pad "A21" smd rect
			(at 3.322574 -6.465062 90)
			(size 0.3556 1.2192)
			(layers "F.Cu" "F.Mask" "F.Paste")
			(net "P5E_PEX2_STN0_RX_DP<1>")
		)
		(pad "A22" smd rect
			(at 3.322574 -5.865114 90)
			(size 0.3556 1.2192)
			(layers "F.Cu" "F.Mask" "F.Paste")
			(net "GND")
		)
		(pad "A23" smd rect
			(at 3.322574 -5.264912 90)
			(size 0.3556 1.2192)
			(layers "F.Cu" "F.Mask" "F.Paste")
			(net "P5E_PEX2_STN0_RX_DN<2>")
		)
		(pad "A24" smd rect
			(at 3.322574 -4.664964 90)
			(size 0.3556 1.2192)
			(layers "F.Cu" "F.Mask" "F.Paste")
			(net "P5E_PEX2_STN0_RX_DP<2>")
		)
		(pad "A25" smd rect
			(at 3.322574 -4.065016 90)
			(size 0.3556 1.2192)
			(layers "F.Cu" "F.Mask" "F.Paste")
			(net "GND")
		)
		(pad "A26" smd rect
			(at 3.322574 -3.465068 90)
			(size 0.3556 1.2192)
			(layers "F.Cu" "F.Mask" "F.Paste")
			(net "P5E_PEX2_STN0_RX_DN<3>")
		)
		(pad "A27" smd rect
			(at 3.322574 -2.86512 90)
			(size 0.3556 1.2192)
			(layers "F.Cu" "F.Mask" "F.Paste")
			(net "P5E_PEX2_STN0_RX_DP<3>")
		)
		(pad "A28" smd rect
			(at 3.322574 -2.264918 90)
			(size 0.3556 1.2192)
			(layers "F.Cu" "F.Mask" "F.Paste")
			(net "GND")
		)
		(pad "A29" smd rect
			(at 3.322574 1.74498 90)
			(size 0.3556 1.2192)
			(layers "F.Cu" "F.Mask" "F.Paste")
			(net "GND")
		)
		(pad "A30" smd rect
			(at 3.322574 2.344928 90)
			(size 0.3556 1.2192)
			(layers "F.Cu" "F.Mask" "F.Paste")
			(net "P5E_PEX2_STN0_RX_DN<4>")
		)
		(pad "A31" smd rect
			(at 3.322574 2.944876 90)
			(size 0.3556 1.2192)
			(layers "F.Cu" "F.Mask" "F.Paste")
			(net "P5E_PEX2_STN0_RX_DP<4>")
		)
		(pad "A32" smd rect
			(at 3.322574 3.545078 90)
			(size 0.3556 1.2192)
			(layers "F.Cu" "F.Mask" "F.Paste")
			(net "GND")
		)
		(pad "A33" smd rect
			(at 3.322574 4.145026 90)
			(size 0.3556 1.2192)
			(layers "F.Cu" "F.Mask" "F.Paste")
			(net "P5E_PEX2_STN0_RX_DN<5>")
		)
		(pad "A34" smd rect
			(at 3.322574 4.744974 90)
			(size 0.3556 1.2192)
			(layers "F.Cu" "F.Mask" "F.Paste")
			(net "P5E_PEX2_STN0_RX_DP<5>")
		)
		(pad "A35" smd rect
			(at 3.322574 5.344922 90)
			(size 0.3556 1.2192)
			(layers "F.Cu" "F.Mask" "F.Paste")
			(net "GND")
		)
		(pad "A36" smd rect
			(at 3.322574 5.945124 90)
			(size 0.3556 1.2192)
			(layers "F.Cu" "F.Mask" "F.Paste")
			(net "P5E_PEX2_STN0_RX_DN<6>")
		)
		(pad "A37" smd rect
			(at 3.322574 6.545072 90)
			(size 0.3556 1.2192)
			(layers "F.Cu" "F.Mask" "F.Paste")
			(net "P5E_PEX2_STN0_RX_DP<6>")
		)
		(pad "A38" smd rect
			(at 3.322574 7.14502 90)
			(size 0.3556 1.2192)
			(layers "F.Cu" "F.Mask" "F.Paste")
			(net "GND")
		)
		(pad "A39" smd rect
			(at 3.322574 7.744968 90)
			(size 0.3556 1.2192)
			(layers "F.Cu" "F.Mask" "F.Paste")
			(net "P5E_PEX2_STN0_RX_DN<7>")
		)
		(pad "A40" smd rect
			(at 3.322574 8.344916 90)
			(size 0.3556 1.2192)
			(layers "F.Cu" "F.Mask" "F.Paste")
			(net "P5E_PEX2_STN0_RX_DP<7>")
		)
		(pad "A41" smd rect
			(at 3.322574 8.945118 90)
			(size 0.3556 1.2192)
			(layers "F.Cu" "F.Mask" "F.Paste")
			(net "GND")
		)
		(pad "A42" smd rect
			(at 3.322574 9.545066 90)
			(size 0.3556 1.2192)
			(layers "F.Cu" "F.Mask" "F.Paste")
			(net "PRSNTB1_NIC5_N")
		)
		(pad "A43" smd rect
			(at 3.322574 14.454886 90)
			(size 0.3556 1.2192)
			(layers "F.Cu" "F.Mask" "F.Paste")
			(net "GND")
		)
		(pad "A44" smd rect
			(at 3.322574 15.055088 90)
			(size 0.3556 1.2192)
			(layers "F.Cu" "F.Mask" "F.Paste")
			(net "P5E_PEX2_STN0_RX_DN<8>")
		)
		(pad "A45" smd rect
			(at 3.322574 15.655036 90)
			(size 0.3556 1.2192)
			(layers "F.Cu" "F.Mask" "F.Paste")
			(net "P5E_PEX2_STN0_RX_DP<8>")
		)
		(pad "A46" smd rect
			(at 3.322574 16.254984 90)
			(size 0.3556 1.2192)
			(layers "F.Cu" "F.Mask" "F.Paste")
			(net "GND")
		)
		(pad "A47" smd rect
			(at 3.322574 16.854932 90)
			(size 0.3556 1.2192)
			(layers "F.Cu" "F.Mask" "F.Paste")
			(net "P5E_PEX2_STN0_RX_DN<9>")
		)
		(pad "A48" smd rect
			(at 3.322574 17.45488 90)
			(size 0.3556 1.2192)
			(layers "F.Cu" "F.Mask" "F.Paste")
			(net "P5E_PEX2_STN0_RX_DP<9>")
		)
		(pad "A49" smd rect
			(at 3.322574 18.055082 90)
			(size 0.3556 1.2192)
			(layers "F.Cu" "F.Mask" "F.Paste")
			(net "GND")
		)
		(pad "A50" smd rect
			(at 3.322574 18.65503 90)
			(size 0.3556 1.2192)
			(layers "F.Cu" "F.Mask" "F.Paste")
			(net "P5E_PEX2_STN0_RX_DN<10>")
		)
		(pad "A51" smd rect
			(at 3.322574 19.254978 90)
			(size 0.3556 1.2192)
			(layers "F.Cu" "F.Mask" "F.Paste")
			(net "P5E_PEX2_STN0_RX_DP<10>")
		)
		(pad "A52" smd rect
			(at 3.322574 19.854926 90)
			(size 0.3556 1.2192)
			(layers "F.Cu" "F.Mask" "F.Paste")
			(net "GND")
		)
		(pad "A53" smd rect
			(at 3.322574 20.455128 90)
			(size 0.3556 1.2192)
			(layers "F.Cu" "F.Mask" "F.Paste")
			(net "P5E_PEX2_STN0_RX_DN<11>")
		)
		(pad "A54" smd rect
			(at 3.322574 21.055076 90)
			(size 0.3556 1.2192)
			(layers "F.Cu" "F.Mask" "F.Paste")
			(net "P5E_PEX2_STN0_RX_DP<11>")
		)
		(pad "A55" smd rect
			(at 3.322574 21.655024 90)
			(size 0.3556 1.2192)
			(layers "F.Cu" "F.Mask" "F.Paste")
			(net "GND")
		)
		(pad "A56" smd rect
			(at 3.322574 22.254972 90)
			(size 0.3556 1.2192)
			(layers "F.Cu" "F.Mask" "F.Paste")
			(net "P5E_PEX2_STN0_RX_DN<12>")
		)
		(pad "A57" smd rect
			(at 3.322574 22.85492 90)
			(size 0.3556 1.2192)
			(layers "F.Cu" "F.Mask" "F.Paste")
			(net "P5E_PEX2_STN0_RX_DP<12>")
		)
		(pad "A58" smd rect
			(at 3.322574 23.455122 90)
			(size 0.3556 1.2192)
			(layers "F.Cu" "F.Mask" "F.Paste")
			(net "GND")
		)
		(pad "A59" smd rect
			(at 3.322574 24.05507 90)
			(size 0.3556 1.2192)
			(layers "F.Cu" "F.Mask" "F.Paste")
			(net "P5E_PEX2_STN0_RX_DN<13>")
		)
		(pad "A60" smd rect
			(at 3.322574 24.655018 90)
			(size 0.3556 1.2192)
			(layers "F.Cu" "F.Mask" "F.Paste")
			(net "P5E_PEX2_STN0_RX_DP<13>")
		)
		(pad "A61" smd rect
			(at 3.322574 25.254966 90)
			(size 0.3556 1.2192)
			(layers "F.Cu" "F.Mask" "F.Paste")
			(net "GND")
		)
		(pad "A62" smd rect
			(at 3.322574 25.854914 90)
			(size 0.3556 1.2192)
			(layers "F.Cu" "F.Mask" "F.Paste")
			(net "P5E_PEX2_STN0_RX_DN<14>")
		)
		(pad "A63" smd rect
			(at 3.322574 26.455116 90)
			(size 0.3556 1.2192)
			(layers "F.Cu" "F.Mask" "F.Paste")
			(net "P5E_PEX2_STN0_RX_DP<14>")
		)
		(pad "A64" smd rect
			(at 3.322574 27.055064 90)
			(size 0.3556 1.2192)
			(layers "F.Cu" "F.Mask" "F.Paste")
			(net "GND")
		)
		(pad "A65" smd rect
			(at 3.322574 27.655012 90)
			(size 0.3556 1.2192)
			(layers "F.Cu" "F.Mask" "F.Paste")
			(net "P5E_PEX2_STN0_RX_DN<15>")
		)
		(pad "A66" smd rect
			(at 3.322574 28.25496 90)
			(size 0.3556 1.2192)
			(layers "F.Cu" "F.Mask" "F.Paste")
			(net "P5E_PEX2_STN0_RX_DP<15>")
		)
		(pad "A67" smd rect
			(at 3.322574 28.854908 90)
			(size 0.3556 1.2192)
			(layers "F.Cu" "F.Mask" "F.Paste")
			(net "GND")
		)
		(pad "A68" smd rect
			(at 3.322574 29.45511 90)
			(size 0.3556 1.2192)
			(layers "F.Cu" "F.Mask" "F.Paste")
			(net "Net_2648")
		)
		(pad "A69" smd rect
			(at 3.322574 30.055058 90)
			(size 0.3556 1.2192)
			(layers "F.Cu" "F.Mask" "F.Paste")
			(net "Net_2649")
		)
		(pad "A70" smd rect
			(at 3.322574 30.655006 90)
			(size 0.3556 1.2192)
			(layers "F.Cu" "F.Mask" "F.Paste")
			(net "NIC5_PWRBRK_R_N")
		)
		(pad "B1" smd rect
			(at -1.27762 -18.465038 90)
			(size 0.3556 1.2192)
			(layers "F.Cu" "F.Mask" "F.Paste")
			(net "P12V_NIC5")
		)
		(pad "B2" smd rect
			(at -1.27762 -17.86509 90)
			(size 0.3556 1.2192)
			(layers "F.Cu" "F.Mask" "F.Paste")
			(net "P12V_NIC5")
		)
		(pad "B3" smd rect
			(at -1.27762 -17.264888 90)
			(size 0.3556 1.2192)
			(layers "F.Cu" "F.Mask" "F.Paste")
			(net "P12V_NIC5")
		)
		(pad "B4" smd rect
			(at -1.27762 -16.66494 90)
			(size 0.3556 1.2192)
			(layers "F.Cu" "F.Mask" "F.Paste")
			(net "P12V_NIC5")
		)
		(pad "B5" smd rect
			(at -1.27762 -16.064992 90)
			(size 0.3556 1.2192)
			(layers "F.Cu" "F.Mask" "F.Paste")
			(net "P12V_NIC5")
		)
		(pad "B6" smd rect
			(at -1.27762 -15.465044 90)
			(size 0.3556 1.2192)
			(layers "F.Cu" "F.Mask" "F.Paste")
			(net "P12V_NIC5")
		)
		(pad "B7" smd rect
			(at -1.27762 -14.865096 90)
			(size 0.3556 1.2192)
			(layers "F.Cu" "F.Mask" "F.Paste")
			(net "NIC5_BIF0_N")
		)
		(pad "B8" smd rect
			(at -1.27762 -14.264894 90)
			(size 0.3556 1.2192)
			(layers "F.Cu" "F.Mask" "F.Paste")
			(net "NIC5_BIF1_N")
		)
		(pad "B9" smd rect
			(at -1.27762 -13.664946 90)
			(size 0.3556 1.2192)
			(layers "F.Cu" "F.Mask" "F.Paste")
			(net "NIC5_BIF2_N")
		)
		(pad "B10" smd rect
			(at -1.27762 -13.064998 90)
			(size 0.3556 1.2192)
			(layers "F.Cu" "F.Mask" "F.Paste")
			(net "RST_NIC5_PERST0_R_N")
		)
		(pad "B11" smd rect
			(at -1.27762 -12.46505 90)
			(size 0.3556 1.2192)
			(layers "F.Cu" "F.Mask" "F.Paste")
			(net "P3V3_NIC5")
		)
		(pad "B12" smd rect
			(at -1.27762 -11.865102 90)
			(size 0.3556 1.2192)
			(layers "F.Cu" "F.Mask" "F.Paste")
			(net "NIC5_AUX_PWR_EN_R")
		)
		(pad "B13" smd rect
			(at -1.27762 -11.2649 90)
			(size 0.3556 1.2192)
			(layers "F.Cu" "F.Mask" "F.Paste")
			(net "GND")
		)
		(pad "B14" smd rect
			(at -1.27762 -10.664952 90)
			(size 0.3556 1.2192)
			(layers "F.Cu" "F.Mask" "F.Paste")
			(net "CLK_100M_DB2000QL_NIC5_R_DN")
		)
		(pad "B15" smd rect
			(at -1.27762 -10.065004 90)
			(size 0.3556 1.2192)
			(layers "F.Cu" "F.Mask" "F.Paste")
			(net "CLK_100M_DB2000QL_NIC5_R_DP")
		)
		(pad "B16" smd rect
			(at -1.27762 -9.465056 90)
			(size 0.3556 1.2192)
			(layers "F.Cu" "F.Mask" "F.Paste")
			(net "GND")
		)
		(pad "B17" smd rect
			(at -1.27762 -8.865108 90)
			(size 0.3556 1.2192)
			(layers "F.Cu" "F.Mask" "F.Paste")
			(net "P5E_PEX2_STN0_TX_C_DN<0>")
		)
		(pad "B18" smd rect
			(at -1.27762 -8.264906 90)
			(size 0.3556 1.2192)
			(layers "F.Cu" "F.Mask" "F.Paste")
			(net "P5E_PEX2_STN0_TX_C_DP<0>")
		)
		(pad "B19" smd rect
			(at -1.27762 -7.664958 90)
			(size 0.3556 1.2192)
			(layers "F.Cu" "F.Mask" "F.Paste")
			(net "GND")
		)
		(pad "B20" smd rect
			(at -1.27762 -7.06501 90)
			(size 0.3556 1.2192)
			(layers "F.Cu" "F.Mask" "F.Paste")
			(net "P5E_PEX2_STN0_TX_C_DN<1>")
		)
		(pad "B21" smd rect
			(at -1.27762 -6.465062 90)
			(size 0.3556 1.2192)
			(layers "F.Cu" "F.Mask" "F.Paste")
			(net "P5E_PEX2_STN0_TX_C_DP<1>")
		)
		(pad "B22" smd rect
			(at -1.27762 -5.865114 90)
			(size 0.3556 1.2192)
			(layers "F.Cu" "F.Mask" "F.Paste")
			(net "GND")
		)
		(pad "B23" smd rect
			(at -1.27762 -5.264912 90)
			(size 0.3556 1.2192)
			(layers "F.Cu" "F.Mask" "F.Paste")
			(net "P5E_PEX2_STN0_TX_C_DN<2>")
		)
		(pad "B24" smd rect
			(at -1.27762 -4.664964 90)
			(size 0.3556 1.2192)
			(layers "F.Cu" "F.Mask" "F.Paste")
			(net "P5E_PEX2_STN0_TX_C_DP<2>")
		)
		(pad "B25" smd rect
			(at -1.27762 -4.065016 90)
			(size 0.3556 1.2192)
			(layers "F.Cu" "F.Mask" "F.Paste")
			(net "GND")
		)
		(pad "B26" smd rect
			(at -1.27762 -3.465068 90)
			(size 0.3556 1.2192)
			(layers "F.Cu" "F.Mask" "F.Paste")
			(net "P5E_PEX2_STN0_TX_C_DN<3>")
		)
		(pad "B27" smd rect
			(at -1.27762 -2.86512 90)
			(size 0.3556 1.2192)
			(layers "F.Cu" "F.Mask" "F.Paste")
			(net "P5E_PEX2_STN0_TX_C_DP<3>")
		)
		(pad "B28" smd rect
			(at -1.27762 -2.264918 90)
			(size 0.3556 1.2192)
			(layers "F.Cu" "F.Mask" "F.Paste")
			(net "GND")
		)
		(pad "B29" smd rect
			(at -1.27762 1.74498 90)
			(size 0.3556 1.2192)
			(layers "F.Cu" "F.Mask" "F.Paste")
			(net "GND")
		)
		(pad "B30" smd rect
			(at -1.27762 2.344928 90)
			(size 0.3556 1.2192)
			(layers "F.Cu" "F.Mask" "F.Paste")
			(net "P5E_PEX2_STN0_TX_C_DN<4>")
		)
		(pad "B31" smd rect
			(at -1.27762 2.944876 90)
			(size 0.3556 1.2192)
			(layers "F.Cu" "F.Mask" "F.Paste")
			(net "P5E_PEX2_STN0_TX_C_DP<4>")
		)
		(pad "B32" smd rect
			(at -1.27762 3.545078 90)
			(size 0.3556 1.2192)
			(layers "F.Cu" "F.Mask" "F.Paste")
			(net "GND")
		)
		(pad "B33" smd rect
			(at -1.27762 4.145026 90)
			(size 0.3556 1.2192)
			(layers "F.Cu" "F.Mask" "F.Paste")
			(net "P5E_PEX2_STN0_TX_C_DN<5>")
		)
		(pad "B34" smd rect
			(at -1.27762 4.744974 90)
			(size 0.3556 1.2192)
			(layers "F.Cu" "F.Mask" "F.Paste")
			(net "P5E_PEX2_STN0_TX_C_DP<5>")
		)
		(pad "B35" smd rect
			(at -1.27762 5.344922 90)
			(size 0.3556 1.2192)
			(layers "F.Cu" "F.Mask" "F.Paste")
			(net "GND")
		)
		(pad "B36" smd rect
			(at -1.27762 5.945124 90)
			(size 0.3556 1.2192)
			(layers "F.Cu" "F.Mask" "F.Paste")
			(net "P5E_PEX2_STN0_TX_C_DN<6>")
		)
		(pad "B37" smd rect
			(at -1.27762 6.545072 90)
			(size 0.3556 1.2192)
			(layers "F.Cu" "F.Mask" "F.Paste")
			(net "P5E_PEX2_STN0_TX_C_DP<6>")
		)
		(pad "B38" smd rect
			(at -1.27762 7.14502 90)
			(size 0.3556 1.2192)
			(layers "F.Cu" "F.Mask" "F.Paste")
			(net "GND")
		)
		(pad "B39" smd rect
			(at -1.27762 7.744968 90)
			(size 0.3556 1.2192)
			(layers "F.Cu" "F.Mask" "F.Paste")
			(net "P5E_PEX2_STN0_TX_C_DN<7>")
		)
		(pad "B40" smd rect
			(at -1.27762 8.344916 90)
			(size 0.3556 1.2192)
			(layers "F.Cu" "F.Mask" "F.Paste")
			(net "P5E_PEX2_STN0_TX_C_DP<7>")
		)
		(pad "B41" smd rect
			(at -1.27762 8.945118 90)
			(size 0.3556 1.2192)
			(layers "F.Cu" "F.Mask" "F.Paste")
			(net "GND")
		)
		(pad "B42" smd rect
			(at -1.27762 9.545066 90)
			(size 0.3556 1.2192)
			(layers "F.Cu" "F.Mask" "F.Paste")
			(net "PRSNTB0_NIC5_N")
		)
		(pad "B43" smd rect
			(at -1.27762 14.454886 90)
			(size 0.3556 1.2192)
			(layers "F.Cu" "F.Mask" "F.Paste")
			(net "GND")
		)
		(pad "B44" smd rect
			(at -1.27762 15.055088 90)
			(size 0.3556 1.2192)
			(layers "F.Cu" "F.Mask" "F.Paste")
			(net "P5E_PEX2_STN0_TX_C_DN<8>")
		)
		(pad "B45" smd rect
			(at -1.27762 15.655036 90)
			(size 0.3556 1.2192)
			(layers "F.Cu" "F.Mask" "F.Paste")
			(net "P5E_PEX2_STN0_TX_C_DP<8>")
		)
		(pad "B46" smd rect
			(at -1.27762 16.254984 90)
			(size 0.3556 1.2192)
			(layers "F.Cu" "F.Mask" "F.Paste")
			(net "GND")
		)
		(pad "B47" smd rect
			(at -1.27762 16.854932 90)
			(size 0.3556 1.2192)
			(layers "F.Cu" "F.Mask" "F.Paste")
			(net "P5E_PEX2_STN0_TX_C_DN<9>")
		)
		(pad "B48" smd rect
			(at -1.27762 17.45488 90)
			(size 0.3556 1.2192)
			(layers "F.Cu" "F.Mask" "F.Paste")
			(net "P5E_PEX2_STN0_TX_C_DP<9>")
		)
		(pad "B49" smd rect
			(at -1.27762 18.055082 90)
			(size 0.3556 1.2192)
			(layers "F.Cu" "F.Mask" "F.Paste")
			(net "GND")
		)
		(pad "B50" smd rect
			(at -1.27762 18.65503 90)
			(size 0.3556 1.2192)
			(layers "F.Cu" "F.Mask" "F.Paste")
			(net "P5E_PEX2_STN0_TX_C_DN<10>")
		)
		(pad "B51" smd rect
			(at -1.27762 19.254978 90)
			(size 0.3556 1.2192)
			(layers "F.Cu" "F.Mask" "F.Paste")
			(net "P5E_PEX2_STN0_TX_C_DP<10>")
		)
		(pad "B52" smd rect
			(at -1.27762 19.854926 90)
			(size 0.3556 1.2192)
			(layers "F.Cu" "F.Mask" "F.Paste")
			(net "GND")
		)
		(pad "B53" smd rect
			(at -1.27762 20.455128 90)
			(size 0.3556 1.2192)
			(layers "F.Cu" "F.Mask" "F.Paste")
			(net "P5E_PEX2_STN0_TX_C_DN<11>")
		)
		(pad "B54" smd rect
			(at -1.27762 21.055076 90)
			(size 0.3556 1.2192)
			(layers "F.Cu" "F.Mask" "F.Paste")
			(net "P5E_PEX2_STN0_TX_C_DP<11>")
		)
		(pad "B55" smd rect
			(at -1.27762 21.655024 90)
			(size 0.3556 1.2192)
			(layers "F.Cu" "F.Mask" "F.Paste")
			(net "GND")
		)
		(pad "B56" smd rect
			(at -1.27762 22.254972 90)
			(size 0.3556 1.2192)
			(layers "F.Cu" "F.Mask" "F.Paste")
			(net "P5E_PEX2_STN0_TX_C_DP<12>")
		)
		(pad "B57" smd rect
			(at -1.27762 22.85492 90)
			(size 0.3556 1.2192)
			(layers "F.Cu" "F.Mask" "F.Paste")
			(net "P5E_PEX2_STN0_TX_C_DN<12>")
		)
		(pad "B58" smd rect
			(at -1.27762 23.455122 90)
			(size 0.3556 1.2192)
			(layers "F.Cu" "F.Mask" "F.Paste")
			(net "GND")
		)
		(pad "B59" smd rect
			(at -1.27762 24.05507 90)
			(size 0.3556 1.2192)
			(layers "F.Cu" "F.Mask" "F.Paste")
			(net "P5E_PEX2_STN0_TX_C_DN<13>")
		)
		(pad "B60" smd rect
			(at -1.27762 24.655018 90)
			(size 0.3556 1.2192)
			(layers "F.Cu" "F.Mask" "F.Paste")
			(net "P5E_PEX2_STN0_TX_C_DP<13>")
		)
		(pad "B61" smd rect
			(at -1.27762 25.254966 90)
			(size 0.3556 1.2192)
			(layers "F.Cu" "F.Mask" "F.Paste")
			(net "GND")
		)
		(pad "B62" smd rect
			(at -1.27762 25.854914 90)
			(size 0.3556 1.2192)
			(layers "F.Cu" "F.Mask" "F.Paste")
			(net "P5E_PEX2_STN0_TX_C_DP<14>")
		)
		(pad "B63" smd rect
			(at -1.27762 26.455116 90)
			(size 0.3556 1.2192)
			(layers "F.Cu" "F.Mask" "F.Paste")
			(net "P5E_PEX2_STN0_TX_C_DN<14>")
		)
		(pad "B64" smd rect
			(at -1.27762 27.055064 90)
			(size 0.3556 1.2192)
			(layers "F.Cu" "F.Mask" "F.Paste")
			(net "GND")
		)
		(pad "B65" smd rect
			(at -1.27762 27.655012 90)
			(size 0.3556 1.2192)
			(layers "F.Cu" "F.Mask" "F.Paste")
			(net "P5E_PEX2_STN0_TX_C_DN<15>")
		)
		(pad "B66" smd rect
			(at -1.27762 28.25496 90)
			(size 0.3556 1.2192)
			(layers "F.Cu" "F.Mask" "F.Paste")
			(net "P5E_PEX2_STN0_TX_C_DP<15>")
		)
		(pad "B67" smd rect
			(at -1.27762 28.854908 90)
			(size 0.3556 1.2192)
			(layers "F.Cu" "F.Mask" "F.Paste")
			(net "GND")
		)
		(pad "B68" smd rect
			(at -1.27762 29.45511 90)
			(size 0.3556 1.2192)
			(layers "F.Cu" "F.Mask" "F.Paste")
			(net "Net_2646")
		)
		(pad "B69" smd rect
			(at -1.27762 30.055058 90)
			(size 0.3556 1.2192)
			(layers "F.Cu" "F.Mask" "F.Paste")
			(net "Net_2647")
		)
		(pad "B70" smd rect
			(at -1.27762 30.655006 90)
			(size 0.3556 1.2192)
			(layers "F.Cu" "F.Mask" "F.Paste")
			(net "PRSNTB3_NIC5_N")
		)
		(pad "G1" thru_hole oval
			(at 1.022604 -34.034984 90)
			(size 1.6256 3.4798)
			(drill oval 1.1176 2.4638)
			(layers "*.Cu" "*.Mask")
			(remove_unused_layers no)
			(net "GND")
			(clearance 0.127)
			(thermal_gap 0.127)
		)
		(pad "G2" thru_hole oval
			(at 1.022604 -20.625054 90)
			(size 1.6256 3.4798)
			(drill oval 1.1176 2.4638)
			(layers "*.Cu" "*.Mask")
			(remove_unused_layers no)
			(net "GND")
			(clearance 0.127)
			(thermal_gap 0.127)
		)
		(pad "G3" thru_hole oval
			(at 1.022604 -0.255016 90)
			(size 1.6256 3.4798)
			(drill oval 1.1176 2.4638)
			(layers "*.Cu" "*.Mask")
			(remove_unused_layers no)
			(net "GND")
			(clearance 0.127)
			(thermal_gap 0.127)
		)
		(pad "G4" thru_hole oval
			(at 1.022604 12.005056 90)
			(size 1.6256 3.4798)
			(drill oval 1.1176 2.4638)
			(layers "*.Cu" "*.Mask")
			(remove_unused_layers no)
			(net "GND")
			(clearance 0.127)
			(thermal_gap 0.127)
		)
		(pad "G5" thru_hole oval
			(at 1.022604 34.034984 90)
			(size 1.5748 3.4798)
			(drill oval 1.1176 2.4638)
			(layers "*.Cu" "*.Mask")
			(remove_unused_layers no)
			(net "GND")
			(clearance 0.1524)
			(thermal_gap 0.1524)
		)
		(pad "G6" thru_hole circle
			(at -3.16738 -20.625054 180)
			(size 1.6256 1.6256)
			(drill 1.1176)
			(layers "*.Cu" "*.Mask")
			(remove_unused_layers no)
			(net "GND")
			(clearance 0)
		)
		(pad "G7" thru_hole circle
			(at -3.16738 12.005056 180)
			(size 1.6256 1.6256)
			(drill 1.1176)
			(layers "*.Cu" "*.Mask")
			(remove_unused_layers no)
			(net "GND")
			(clearance 0)
		)
		(pad "G8" thru_hole circle
			(at 4.20243 -20.625054 180)
			(size 1.6256 1.6256)
			(drill 1.1176)
			(layers "*.Cu" "*.Mask")
			(remove_unused_layers no)
			(net "GND")
			(clearance 0)
		)
		(pad "G9" thru_hole circle
			(at 4.20243 12.005056 180)
			(size 1.6256 1.6256)
			(drill 1.1176)
			(layers "*.Cu" "*.Mask")
			(remove_unused_layers no)
			(net "GND")
			(clearance 0)
		)
		(pad "OA1" smd rect
			(at 3.322574 -30.660086 90)
			(size 0.3556 1.2192)
			(layers "F.Cu" "F.Mask" "F.Paste")
			(net "RST_NIC5_PERST2_R_N")
		)
		(pad "OA2" smd rect
			(at 3.322574 -30.059884 90)
			(size 0.3556 1.2192)
			(layers "F.Cu" "F.Mask" "F.Paste")
			(net "RST_NIC5_PERST3_R_N")
		)
		(pad "OA3" smd rect
			(at 3.322574 -29.459936 90)
			(size 0.3556 1.2192)
			(layers "F.Cu" "F.Mask" "F.Paste")
			(net "Net_2650")
		)
		(pad "OA4" smd rect
			(at 3.322574 -28.859988 90)
			(size 0.3556 1.2192)
			(layers "F.Cu" "F.Mask" "F.Paste")
			(net "NIC5_RBT_ARB_IN")
		)
		(pad "OA5" smd rect
			(at 3.322574 -28.26004 90)
			(size 0.3556 1.2192)
			(layers "F.Cu" "F.Mask" "F.Paste")
			(net "NIC5_RBT_ARB_OUT")
		)
		(pad "OA6" smd rect
			(at 3.322574 -27.660092 90)
			(size 0.3556 1.2192)
			(layers "F.Cu" "F.Mask" "F.Paste")
			(net "NIC5_SLOT_ID1")
		)
		(pad "OA7" smd rect
			(at 3.322574 -27.05989 90)
			(size 0.3556 1.2192)
			(layers "F.Cu" "F.Mask" "F.Paste")
			(net "NCSI_NIC5_TX_EN")
		)
		(pad "OA8" smd rect
			(at 3.322574 -26.459942 90)
			(size 0.3556 1.2192)
			(layers "F.Cu" "F.Mask" "F.Paste")
			(net "NCSI_NIC5_TXD1")
		)
		(pad "OA9" smd rect
			(at 3.322574 -25.859994 90)
			(size 0.3556 1.2192)
			(layers "F.Cu" "F.Mask" "F.Paste")
			(net "NCSI_NIC5_TXD0")
		)
		(pad "OA10" smd rect
			(at 3.322574 -25.260046 90)
			(size 0.3556 1.2192)
			(layers "F.Cu" "F.Mask" "F.Paste")
			(net "GND")
		)
		(pad "OA11" smd rect
			(at 3.322574 -24.660098 90)
			(size 0.3556 1.2192)
			(layers "F.Cu" "F.Mask" "F.Paste")
			(net "Net_2642")
		)
		(pad "OA12" smd rect
			(at 3.322574 -24.059896 90)
			(size 0.3556 1.2192)
			(layers "F.Cu" "F.Mask" "F.Paste")
			(net "Net_2645")
		)
		(pad "OA13" smd rect
			(at 3.322574 -23.459948 90)
			(size 0.3556 1.2192)
			(layers "F.Cu" "F.Mask" "F.Paste")
			(net "GND")
		)
		(pad "OA14" smd rect
			(at 3.322574 -22.86 90)
			(size 0.3556 1.2192)
			(layers "F.Cu" "F.Mask" "F.Paste")
			(net "CLK_50M_NIC5_RBT_REF")
		)
		(pad "OB1" smd rect
			(at -1.27762 -30.660086 90)
			(size 0.3556 1.2192)
			(layers "F.Cu" "F.Mask" "F.Paste")
			(net "PWRGD_NIC5_PWR_GOOD")
		)
		(pad "OB2" smd rect
			(at -1.27762 -30.059884 90)
			(size 0.3556 1.2192)
			(layers "F.Cu" "F.Mask" "F.Paste")
			(net "NIC5_MAIN_PWR_EN_R")
		)
		(pad "OB3" smd rect
			(at -1.27762 -29.459936 90)
			(size 0.3556 1.2192)
			(layers "F.Cu" "F.Mask" "F.Paste")
			(net "NIC5_LD_N")
		)
		(pad "OB4" smd rect
			(at -1.27762 -28.859988 90)
			(size 0.3556 1.2192)
			(layers "F.Cu" "F.Mask" "F.Paste")
			(net "NIC5_DATA_IN")
		)
		(pad "OB5" smd rect
			(at -1.27762 -28.26004 90)
			(size 0.3556 1.2192)
			(layers "F.Cu" "F.Mask" "F.Paste")
			(net "NIC5_DATA_OUT")
		)
		(pad "OB6" smd rect
			(at -1.27762 -27.660092 90)
			(size 0.3556 1.2192)
			(layers "F.Cu" "F.Mask" "F.Paste")
			(net "NIC5_CLK")
		)
		(pad "OB7" smd rect
			(at -1.27762 -27.05989 90)
			(size 0.3556 1.2192)
			(layers "F.Cu" "F.Mask" "F.Paste")
			(net "NIC5_SLOT_ID0")
		)
		(pad "OB8" smd rect
			(at -1.27762 -26.459942 90)
			(size 0.3556 1.2192)
			(layers "F.Cu" "F.Mask" "F.Paste")
			(net "NCSI_NIC5_RXD1")
		)
		(pad "OB9" smd rect
			(at -1.27762 -25.859994 90)
			(size 0.3556 1.2192)
			(layers "F.Cu" "F.Mask" "F.Paste")
			(net "NCSI_NIC5_RXD0")
		)
		(pad "OB10" smd rect
			(at -1.27762 -25.260046 90)
			(size 0.3556 1.2192)
			(layers "F.Cu" "F.Mask" "F.Paste")
			(net "GND")
		)
		(pad "OB11" smd rect
			(at -1.27762 -24.660098 90)
			(size 0.3556 1.2192)
			(layers "F.Cu" "F.Mask" "F.Paste")
			(net "Net_2641")
		)
		(pad "OB12" smd rect
			(at -1.27762 -24.059896 90)
			(size 0.3556 1.2192)
			(layers "F.Cu" "F.Mask" "F.Paste")
			(net "Net_2644")
		)
		(pad "OB13" smd rect
			(at -1.27762 -23.459948 90)
			(size 0.3556 1.2192)
			(layers "F.Cu" "F.Mask" "F.Paste")
			(net "GND")
		)
		(pad "OB14" smd rect
			(at -1.27762 -22.86 90)
			(size 0.3556 1.2192)
			(layers "F.Cu" "F.Mask" "F.Paste")
			(net "NCSI_NIC5_CRS_DV")
		)
		(zone
			(layers "F.Cu" "B.Cu" "In1.Cu" "In2.Cu" "In3.Cu" "In4.Cu" "In5.Cu" "In6.Cu"
				"In7.Cu" "In8.Cu" "In9.Cu" "In10.Cu" "In11.Cu" "In12.Cu" "In13.Cu" "In14.Cu"
				"In15.Cu" "In16.Cu"
			)
			(hatch none 0.5)
			(connect_pads
				(clearance 0)
			)
			(min_thickness 0.25)
			(keepout
				(tracks not_allowed)
				(vias allowed)
				(pads allowed)
				(copperpour not_allowed)
				(footprints allowed)
			)
			(placement
				(enabled no)
				(sheetname "")
			)
			(fill
				(thermal_gap 0.5)
				(thermal_bridge_width 0.5)
				(island_removal_mode 0)
			)
			(polygon
				(pts
					(arc
						(start 304.224436 -160.1851)
						(mid 302.090328 -160.1851)
						(end 304.224436 -160.1851)
					)
				)
			)
		)
		(zone
			(layers "F.Cu" "B.Cu" "In1.Cu" "In2.Cu" "In3.Cu" "In4.Cu" "In5.Cu" "In6.Cu"
				"In7.Cu" "In8.Cu" "In9.Cu" "In10.Cu" "In11.Cu" "In12.Cu" "In13.Cu" "In14.Cu"
				"In15.Cu" "In16.Cu"
			)
			(hatch none 0.5)
			(connect_pads
				(clearance 0)
			)
			(min_thickness 0.25)
			(keepout
				(tracks not_allowed)
				(vias allowed)
				(pads allowed)
				(copperpour not_allowed)
				(footprints allowed)
			)
			(placement
				(enabled no)
				(sheetname "")
			)
			(fill
				(thermal_gap 0.5)
				(thermal_bridge_width 0.5)
				(island_removal_mode 0)
			)
			(polygon
				(pts
					(arc
						(start 305.974242 -95.214948)
						(mid 303.840642 -95.214948)
						(end 305.974242 -95.214948)
					)
				)
			)
		)
	)
	(footprint ""
		(layer "F.Cu")
		(at 384.938524 -112.809782)
		(property "Reference" "C683"
			(at 0 0 0)
			(layer "F.SilkS")
			(hide yes)
			(effects
				(font
					(size 1.27 1.27)
				)
			)
		)
		(property "Value" ""
			(at 0 0 0)
			(layer "F.Fab")
			(effects
				(font
					(size 1.27 1.27)
				)
			)
		)
		(duplicate_pad_numbers_are_jumpers no)
		(fp_line
			(start -0.299974 -0.150114)
			(end 0.299974 -0.150114)
			(stroke
				(width 0.1)
				(type default)
			)
			(layer "F.Fab")
		)
		(fp_line
			(start -0.299974 0.150114)
			(end -0.299974 -0.150114)
			(stroke
				(width 0.1)
				(type default)
			)
			(layer "F.Fab")
		)
		(fp_line
			(start 0.299974 -0.150114)
			(end 0.299974 0.150114)
			(stroke
				(width 0.1)
				(type default)
			)
			(layer "F.Fab")
		)
		(fp_line
			(start 0.299974 0.150114)
			(end -0.299974 0.150114)
			(stroke
				(width 0.1)
				(type default)
			)
			(layer "F.Fab")
		)
		(pad "1" smd rect
			(at -0.2667 0)
			(size 0.3048 0.381)
			(layers "F.Cu" "F.Mask" "F.Paste")
			(net "P5E_PEX3_STN1_TX_DP<23>")
		)
		(pad "2" smd rect
			(at 0.2667 0)
			(size 0.3048 0.381)
			(layers "F.Cu" "F.Mask" "F.Paste")
			(net "P5E_PEX3_STN1_TX_C_DP<23>")
		)
	)
	(footprint ""
		(layer "F.Cu")
		(at 71.65467 -22.867366 90)
		(property "Reference" "C3888"
			(at 0 0 90)
			(layer "F.SilkS")
			(hide yes)
			(effects
				(font
					(size 1.27 1.27)
				)
			)
		)
		(property "Value" ""
			(at 0 0 90)
			(layer "F.Fab")
			(effects
				(font
					(size 1.27 1.27)
				)
			)
		)
		(duplicate_pad_numbers_are_jumpers no)
		(fp_line
			(start 0.7874 -0.4064)
			(end 0.7874 0.4064)
			(stroke
				(width 0.1524)
				(type default)
			)
			(layer "F.SilkS")
		)
		(fp_line
			(start -0.7874 -0.4064)
			(end 0.7874 -0.4064)
			(stroke
				(width 0.1524)
				(type default)
			)
			(layer "F.SilkS")
		)
		(fp_line
			(start 0.7874 0.4064)
			(end -0.7874 0.4064)
			(stroke
				(width 0.1524)
				(type default)
			)
			(layer "F.SilkS")
		)
		(fp_line
			(start -0.7874 0.4064)
			(end -0.7874 -0.4064)
			(stroke
				(width 0.1524)
				(type default)
			)
			(layer "F.SilkS")
		)
		(fp_line
			(start -0.12065 -0.305054)
			(end -0.12065 -0.2794)
			(stroke
				(width 0.1)
				(type default)
			)
			(layer "F.Fab")
		)
		(fp_line
			(start -0.67945 -0.305054)
			(end -0.12065 -0.305054)
			(stroke
				(width 0.1)
				(type default)
			)
			(layer "F.Fab")
		)
		(fp_line
			(start 0.67945 -0.3048)
			(end 0.67945 0.3048)
			(stroke
				(width 0.1)
				(type default)
			)
			(layer "F.Fab")
		)
		(fp_line
			(start 0.12065 -0.3048)
			(end 0.67945 -0.3048)
			(stroke
				(width 0.1)
				(type default)
			)
			(layer "F.Fab")
		)
		(fp_line
			(start 0.12065 -0.2794)
			(end 0.12065 -0.3048)
			(stroke
				(width 0.1)
				(type default)
			)
			(layer "F.Fab")
		)
		(fp_line
			(start -0.12065 -0.2794)
			(end 0.12065 -0.2794)
			(stroke
				(width 0.1)
				(type default)
			)
			(layer "F.Fab")
		)
		(fp_line
			(start 0.120396 0.2794)
			(end -0.12065 0.2794)
			(stroke
				(width 0.1)
				(type default)
			)
			(layer "F.Fab")
		)
		(fp_line
			(start -0.12065 0.2794)
			(end -0.12065 0.3048)
			(stroke
				(width 0.1)
				(type default)
			)
			(layer "F.Fab")
		)
		(fp_line
			(start 0.67945 0.3048)
			(end 0.120396 0.3048)
			(stroke
				(width 0.1)
				(type default)
			)
			(layer "F.Fab")
		)
		(fp_line
			(start 0.120396 0.3048)
			(end 0.120396 0.2794)
			(stroke
				(width 0.1)
				(type default)
			)
			(layer "F.Fab")
		)
		(fp_line
			(start -0.12065 0.3048)
			(end -0.67945 0.3048)
			(stroke
				(width 0.1)
				(type default)
			)
			(layer "F.Fab")
		)
		(fp_line
			(start -0.67945 0.3048)
			(end -0.67945 -0.305054)
			(stroke
				(width 0.1)
				(type default)
			)
			(layer "F.Fab")
		)
		(pad "1" smd circle
			(at -0.40005 0 90)
			(size 0 0)
			(layers "F.Cu" "F.Mask" "F.Paste")
			(net "P12V_SSD2")
		)
		(pad "2" smd circle
			(at 0.40005 0 90)
			(size 0 0)
			(layers "F.Cu" "F.Mask" "F.Paste")
			(net "GND")
		)
	)
	(footprint ""
		(layer "F.Cu")
		(at 275.004022 -350.098614 90)
		(property "Reference" "C608"
			(at 0 0 90)
			(layer "F.SilkS")
			(hide yes)
			(effects
				(font
					(size 1.27 1.27)
				)
			)
		)
		(property "Value" ""
			(at 0 0 90)
			(layer "F.Fab")
			(effects
				(font
					(size 1.27 1.27)
				)
			)
		)
		(duplicate_pad_numbers_are_jumpers no)
		(fp_line
			(start 0.299974 -0.150114)
			(end 0.299974 0.150114)
			(stroke
				(width 0.1)
				(type default)
			)
			(layer "F.Fab")
		)
		(fp_line
			(start -0.299974 -0.150114)
			(end 0.299974 -0.150114)
			(stroke
				(width 0.1)
				(type default)
			)
			(layer "F.Fab")
		)
		(fp_line
			(start 0.299974 0.150114)
			(end -0.299974 0.150114)
			(stroke
				(width 0.1)
				(type default)
			)
			(layer "F.Fab")
		)
		(fp_line
			(start -0.299974 0.150114)
			(end -0.299974 -0.150114)
			(stroke
				(width 0.1)
				(type default)
			)
			(layer "F.Fab")
		)
		(pad "1" smd rect
			(at -0.2667 0 90)
			(size 0.3048 0.381)
			(layers "F.Cu" "F.Mask" "F.Paste")
			(net "P5E_PEX2_STN7_TX_DN<115>")
		)
		(pad "2" smd rect
			(at 0.2667 0 90)
			(size 0.3048 0.381)
			(layers "F.Cu" "F.Mask" "F.Paste")
			(net "P5E_PEX2_STN7_TX_C_DN<115>")
		)
	)
	(footprint ""
		(layer "F.Cu")
		(at 231.887522 -259.813806 180)
		(property "Reference" "C4337"
			(at 0 0 180)
			(layer "F.SilkS")
			(hide yes)
			(effects
				(font
					(size 1.27 1.27)
				)
			)
		)
		(property "Value" ""
			(at 0 0 180)
			(layer "F.Fab")
			(effects
				(font
					(size 1.27 1.27)
				)
			)
		)
		(duplicate_pad_numbers_are_jumpers no)
		(fp_line
			(start 0.299974 0.150114)
			(end -0.299974 0.150114)
			(stroke
				(width 0.1)
				(type default)
			)
			(layer "F.Fab")
		)
		(fp_line
			(start 0.299974 -0.150114)
			(end 0.299974 0.150114)
			(stroke
				(width 0.1)
				(type default)
			)
			(layer "F.Fab")
		)
		(fp_line
			(start -0.299974 0.150114)
			(end -0.299974 -0.150114)
			(stroke
				(width 0.1)
				(type default)
			)
			(layer "F.Fab")
		)
		(fp_line
			(start -0.299974 -0.150114)
			(end 0.299974 -0.150114)
			(stroke
				(width 0.1)
				(type default)
			)
			(layer "F.Fab")
		)
		(pad "1" smd rect
			(at -0.2667 0 180)
			(size 0.3048 0.381)
			(layers "F.Cu" "F.Mask" "F.Paste")
			(net "P1V25_SERDES_VDDPLL_PEX2")
		)
		(pad "2" smd rect
			(at 0.2667 0 180)
			(size 0.3048 0.381)
			(layers "F.Cu" "F.Mask" "F.Paste")
			(net "GND")
		)
	)
	(footprint ""
		(layer "F.Cu")
		(at 221.990158 -80.611472)
		(property "Reference" "R5765"
			(at 0 0 0)
			(layer "F.SilkS")
			(hide yes)
			(effects
				(font
					(size 1.27 1.27)
				)
			)
		)
		(property "Value" ""
			(at 0 0 0)
			(layer "F.Fab")
			(effects
				(font
					(size 1.27 1.27)
				)
			)
		)
		(duplicate_pad_numbers_are_jumpers no)
		(fp_line
			(start -0.7874 -0.4064)
			(end 0.7874 -0.4064)
			(stroke
				(width 0.1524)
				(type default)
			)
			(layer "F.SilkS")
		)
		(fp_line
			(start -0.7874 0.4064)
			(end -0.7874 -0.4064)
			(stroke
				(width 0.1524)
				(type default)
			)
			(layer "F.SilkS")
		)
		(fp_line
			(start 0.7874 -0.4064)
			(end 0.7874 0.4064)
			(stroke
				(width 0.1524)
				(type default)
			)
			(layer "F.SilkS")
		)
		(fp_line
			(start 0.7874 0.4064)
			(end -0.7874 0.4064)
			(stroke
				(width 0.1524)
				(type default)
			)
			(layer "F.SilkS")
		)
		(fp_line
			(start -0.67945 -0.305054)
			(end -0.12065 -0.305054)
			(stroke
				(width 0.1)
				(type default)
			)
			(layer "F.Fab")
		)
		(fp_line
			(start -0.67945 0.3048)
			(end -0.67945 -0.305054)
			(stroke
				(width 0.1)
				(type default)
			)
			(layer "F.Fab")
		)
		(fp_line
			(start -0.12065 -0.305054)
			(end -0.12065 -0.2794)
			(stroke
				(width 0.1)
				(type default)
			)
			(layer "F.Fab")
		)
		(fp_line
			(start -0.12065 -0.2794)
			(end 0.12065 -0.2794)
			(stroke
				(width 0.1)
				(type default)
			)
			(layer "F.Fab")
		)
		(fp_line
			(start -0.12065 0.2794)
			(end -0.12065 0.3048)
			(stroke
				(width 0.1)
				(type default)
			)
			(layer "F.Fab")
		)
		(fp_line
			(start -0.12065 0.3048)
			(end -0.67945 0.3048)
			(stroke
				(width 0.1)
				(type default)
			)
			(layer "F.Fab")
		)
		(fp_line
			(start 0.120396 0.2794)
			(end -0.12065 0.2794)
			(stroke
				(width 0.1)
				(type default)
			)
			(layer "F.Fab")
		)
		(fp_line
			(start 0.120396 0.3048)
			(end 0.120396 0.2794)
			(stroke
				(width 0.1)
				(type default)
			)
			(layer "F.Fab")
		)
		(fp_line
			(start 0.12065 -0.3048)
			(end 0.67945 -0.3048)
			(stroke
				(width 0.1)
				(type default)
			)
			(layer "F.Fab")
		)
		(fp_line
			(start 0.12065 -0.2794)
			(end 0.12065 -0.3048)
			(stroke
				(width 0.1)
				(type default)
			)
			(layer "F.Fab")
		)
		(fp_line
			(start 0.67945 -0.3048)
			(end 0.67945 0.3048)
			(stroke
				(width 0.1)
				(type default)
			)
			(layer "F.Fab")
		)
		(fp_line
			(start 0.67945 0.3048)
			(end 0.120396 0.3048)
			(stroke
				(width 0.1)
				(type default)
			)
			(layer "F.Fab")
		)
		(pad "1" smd circle
			(at -0.40005 0)
			(size 0 0)
			(layers "F.Cu" "F.Mask" "F.Paste")
			(net "SSD11_LED")
		)
		(pad "2" smd circle
			(at 0.40005 0)
			(size 0 0)
			(layers "F.Cu" "F.Mask" "F.Paste")
			(net "SSD11_LED_R")
		)
	)
	(footprint ""
		(layer "F.Cu")
		(at 138.735308 -189.614556)
		(property "Reference" "C4497"
			(at 0 0 0)
			(layer "F.SilkS")
			(hide yes)
			(effects
				(font
					(size 1.27 1.27)
				)
			)
		)
		(property "Value" ""
			(at 0 0 0)
			(layer "F.Fab")
			(effects
				(font
					(size 1.27 1.27)
				)
			)
		)
		(duplicate_pad_numbers_are_jumpers no)
		(fp_line
			(start -0.7874 -0.4064)
			(end 0.7874 -0.4064)
			(stroke
				(width 0.1524)
				(type default)
			)
			(layer "F.SilkS")
		)
		(fp_line
			(start -0.7874 0.4064)
			(end -0.7874 -0.4064)
			(stroke
				(width 0.1524)
				(type default)
			)
			(layer "F.SilkS")
		)
		(fp_line
			(start 0.7874 -0.4064)
			(end 0.7874 0.4064)
			(stroke
				(width 0.1524)
				(type default)
			)
			(layer "F.SilkS")
		)
		(fp_line
			(start 0.7874 0.4064)
			(end -0.7874 0.4064)
			(stroke
				(width 0.1524)
				(type default)
			)
			(layer "F.SilkS")
		)
		(fp_line
			(start -0.67945 -0.305054)
			(end -0.12065 -0.305054)
			(stroke
				(width 0.1)
				(type default)
			)
			(layer "F.Fab")
		)
		(fp_line
			(start -0.67945 0.3048)
			(end -0.67945 -0.305054)
			(stroke
				(width 0.1)
				(type default)
			)
			(layer "F.Fab")
		)
		(fp_line
			(start -0.12065 -0.305054)
			(end -0.12065 -0.2794)
			(stroke
				(width 0.1)
				(type default)
			)
			(layer "F.Fab")
		)
		(fp_line
			(start -0.12065 -0.2794)
			(end 0.12065 -0.2794)
			(stroke
				(width 0.1)
				(type default)
			)
			(layer "F.Fab")
		)
		(fp_line
			(start -0.12065 0.2794)
			(end -0.12065 0.3048)
			(stroke
				(width 0.1)
				(type default)
			)
			(layer "F.Fab")
		)
		(fp_line
			(start -0.12065 0.3048)
			(end -0.67945 0.3048)
			(stroke
				(width 0.1)
				(type default)
			)
			(layer "F.Fab")
		)
		(fp_line
			(start 0.120396 0.2794)
			(end -0.12065 0.2794)
			(stroke
				(width 0.1)
				(type default)
			)
			(layer "F.Fab")
		)
		(fp_line
			(start 0.120396 0.3048)
			(end 0.120396 0.2794)
			(stroke
				(width 0.1)
				(type default)
			)
			(layer "F.Fab")
		)
		(fp_line
			(start 0.12065 -0.3048)
			(end 0.67945 -0.3048)
			(stroke
				(width 0.1)
				(type default)
			)
			(layer "F.Fab")
		)
		(fp_line
			(start 0.12065 -0.2794)
			(end 0.12065 -0.3048)
			(stroke
				(width 0.1)
				(type default)
			)
			(layer "F.Fab")
		)
		(fp_line
			(start 0.67945 -0.3048)
			(end 0.67945 0.3048)
			(stroke
				(width 0.1)
				(type default)
			)
			(layer "F.Fab")
		)
		(fp_line
			(start 0.67945 0.3048)
			(end 0.120396 0.3048)
			(stroke
				(width 0.1)
				(type default)
			)
			(layer "F.Fab")
		)
		(pad "1" smd circle
			(at -0.40005 0)
			(size 0 0)
			(layers "F.Cu" "F.Mask" "F.Paste")
			(net "NIC4_CLK_EN_R_N")
		)
		(pad "2" smd circle
			(at 0.40005 0)
			(size 0 0)
			(layers "F.Cu" "F.Mask" "F.Paste")
			(net "GND")
		)
	)
	(footprint ""
		(layer "F.Cu")
		(at 239.721898 -85.151468 90)
		(property "Reference" "R1015"
			(at 0 0 90)
			(layer "F.SilkS")
			(hide yes)
			(effects
				(font
					(size 1.27 1.27)
				)
			)
		)
		(property "Value" ""
			(at 0 0 90)
			(layer "F.Fab")
			(effects
				(font
					(size 1.27 1.27)
				)
			)
		)
		(duplicate_pad_numbers_are_jumpers no)
		(fp_line
			(start -0.011176 -0.4064)
			(end 0.7874 -0.4064)
			(stroke
				(width 0.1524)
				(type default)
			)
			(layer "F.SilkS")
		)
		(fp_line
			(start -0.009398 0.4064)
			(end -0.7874 0.4064)
			(stroke
				(width 0.1524)
				(type default)
			)
			(layer "F.SilkS")
		)
		(fp_line
			(start -0.12065 -0.305054)
			(end -0.12065 -0.2794)
			(stroke
				(width 0.1)
				(type default)
			)
			(layer "F.Fab")
		)
		(fp_line
			(start -0.67945 -0.305054)
			(end -0.12065 -0.305054)
			(stroke
				(width 0.1)
				(type default)
			)
			(layer "F.Fab")
		)
		(fp_line
			(start 0.67945 -0.3048)
			(end 0.67945 0.3048)
			(stroke
				(width 0.1)
				(type default)
			)
			(layer "F.Fab")
		)
		(fp_line
			(start 0.12065 -0.3048)
			(end 0.67945 -0.3048)
			(stroke
				(width 0.1)
				(type default)
			)
			(layer "F.Fab")
		)
		(fp_line
			(start 0.12065 -0.2794)
			(end 0.12065 -0.3048)
			(stroke
				(width 0.1)
				(type default)
			)
			(layer "F.Fab")
		)
		(fp_line
			(start -0.12065 -0.2794)
			(end 0.12065 -0.2794)
			(stroke
				(width 0.1)
				(type default)
			)
			(layer "F.Fab")
		)
		(fp_line
			(start 0.120396 0.2794)
			(end -0.12065 0.2794)
			(stroke
				(width 0.1)
				(type default)
			)
			(layer "F.Fab")
		)
		(fp_line
			(start -0.12065 0.2794)
			(end -0.12065 0.3048)
			(stroke
				(width 0.1)
				(type default)
			)
			(layer "F.Fab")
		)
		(fp_line
			(start 0.67945 0.3048)
			(end 0.120396 0.3048)
			(stroke
				(width 0.1)
				(type default)
			)
			(layer "F.Fab")
		)
		(fp_line
			(start 0.120396 0.3048)
			(end 0.120396 0.2794)
			(stroke
				(width 0.1)
				(type default)
			)
			(layer "F.Fab")
		)
		(fp_line
			(start -0.12065 0.3048)
			(end -0.67945 0.3048)
			(stroke
				(width 0.1)
				(type default)
			)
			(layer "F.Fab")
		)
		(fp_line
			(start -0.67945 0.3048)
			(end -0.67945 -0.305054)
			(stroke
				(width 0.1)
				(type default)
			)
			(layer "F.Fab")
		)
		(pad "1" smd rect
			(at -0.40005 0 270)
			(size 0.4572 0.508)
			(layers "F.Cu" "F.Mask" "F.Paste")
			(net "USB2_FT4232_CLI_R_DP")
		)
		(pad "2" smd rect
			(at 0.40005 0 270)
			(size 0.4572 0.508)
			(layers "F.Cu" "F.Mask" "F.Paste")
			(net "USB2_FT4232_CLI_DP")
		)
	)
	(footprint ""
		(layer "F.Cu")
		(at 344.261186 -37.951156)
		(property "Reference" "Q228"
			(at -0.040386 -1.874774 0)
			(unlocked yes)
			(layer "F.SilkS")
			(effects
				(font
					(size 0.7874 0.5842)
					(thickness 0.1524)
				)
			)
		)
		(property "Value" ""
			(at 0 0 0)
			(layer "F.Fab")
			(effects
				(font
					(size 1.27 1.27)
				)
			)
		)
		(duplicate_pad_numbers_are_jumpers no)
		(fp_line
			(start -1.376172 -1.199896)
			(end -0.508 -1.199896)
			(stroke
				(width 0.1524)
				(type default)
			)
			(layer "F.SilkS")
		)
		(fp_line
			(start -1.376172 1.199896)
			(end -1.376172 -1.199896)
			(stroke
				(width 0.1524)
				(type default)
			)
			(layer "F.SilkS")
		)
		(fp_line
			(start -0.508 -1.199896)
			(end 0 -0.762)
			(stroke
				(width 0.1524)
				(type default)
			)
			(layer "F.SilkS")
		)
		(fp_line
			(start 0 -0.762)
			(end 0.508 -1.199896)
			(stroke
				(width 0.1524)
				(type default)
			)
			(layer "F.SilkS")
		)
		(fp_line
			(start 0.508 -1.199896)
			(end 1.376172 -1.199896)
			(stroke
				(width 0.1524)
				(type default)
			)
			(layer "F.SilkS")
		)
		(fp_line
			(start 1.376172 -1.199896)
			(end 1.376172 1.199896)
			(stroke
				(width 0.1524)
				(type default)
			)
			(layer "F.SilkS")
		)
		(fp_line
			(start 1.376172 1.199896)
			(end -1.376172 1.199896)
			(stroke
				(width 0.1524)
				(type default)
			)
			(layer "F.SilkS")
		)
		(fp_poly
			(pts
				(xy -1.486662 -0.941578) (xy -1.756156 -1.749806) (xy -2.29489 -1.211072)
			)
			(stroke
				(width 0)
				(type default)
			)
			(fill yes)
			(layer "F.SilkS")
		)
		(fp_line
			(start -0.674878 -1.100074)
			(end 0.674878 -1.100074)
			(stroke
				(width 0.1)
				(type default)
			)
			(layer "F.Fab")
		)
		(fp_line
			(start -0.674878 1.100074)
			(end -0.674878 -1.100074)
			(stroke
				(width 0.1)
				(type default)
			)
			(layer "F.Fab")
		)
		(fp_line
			(start 0.674878 -1.100074)
			(end 0.674878 1.100074)
			(stroke
				(width 0.1)
				(type default)
			)
			(layer "F.Fab")
		)
		(fp_line
			(start 0.674878 1.100074)
			(end -0.674878 1.100074)
			(stroke
				(width 0.1)
				(type default)
			)
			(layer "F.Fab")
		)
		(fp_poly
			(pts
				(xy -1.4605 -0.7493) (xy -2.2225 -1.1303) (xy -2.2225 -0.3683)
			)
			(stroke
				(width 0)
				(type default)
			)
			(fill yes)
			(layer "F.Fab")
		)
		(pad "1" smd rect
			(at -0.899922 -0.750062 270)
			(size 0.6096 0.6096)
			(layers "F.Cu" "F.Mask" "F.Paste")
			(net "GND")
		)
		(pad "2" smd rect
			(at -0.899922 0 270)
			(size 0.4064 0.6096)
			(layers "F.Cu" "F.Mask" "F.Paste")
			(net "P3V3_SSD12_PG_G1")
		)
		(pad "3" smd rect
			(at -0.899922 0.750062 270)
			(size 0.6096 0.6096)
			(layers "F.Cu" "F.Mask" "F.Paste")
			(net "PWRGD_P3V3_SSD12_D")
		)
		(pad "4" smd rect
			(at 0.899922 0.750062 270)
			(size 0.6096 0.6096)
			(layers "F.Cu" "F.Mask" "F.Paste")
			(net "GND")
		)
		(pad "5" smd rect
			(at 0.899922 0 270)
			(size 0.4064 0.6096)
			(layers "F.Cu" "F.Mask" "F.Paste")
			(net "P3V3_SSD12_PG_G2")
		)
		(pad "6" smd rect
			(at 0.899922 -0.750062 270)
			(size 0.6096 0.6096)
			(layers "F.Cu" "F.Mask" "F.Paste")
			(net "P3V3_SSD12_PG_G2")
		)
	)
	(footprint ""
		(layer "F.Cu")
		(at 359.385362 -115.549426 -90)
		(property "Reference" "Q218"
			(at -0.071374 1.853692 90)
			(unlocked yes)
			(layer "F.SilkS")
			(effects
				(font
					(size 0.7874 0.5842)
					(thickness 0.1524)
				)
			)
		)
		(property "Value" ""
			(at 0 0 270)
			(layer "F.Fab")
			(effects
				(font
					(size 1.27 1.27)
				)
			)
		)
		(duplicate_pad_numbers_are_jumpers no)
		(fp_line
			(start -1.376172 1.199896)
			(end -1.376172 -1.199896)
			(stroke
				(width 0.1524)
				(type default)
			)
			(layer "F.SilkS")
		)
		(fp_line
			(start 1.376172 1.199896)
			(end -1.376172 1.199896)
			(stroke
				(width 0.1524)
				(type default)
			)
			(layer "F.SilkS")
		)
		(fp_line
			(start 0 -0.762)
			(end 0.508 -1.199896)
			(stroke
				(width 0.1524)
				(type default)
			)
			(layer "F.SilkS")
		)
		(fp_line
			(start -1.376172 -1.199896)
			(end -0.508 -1.199896)
			(stroke
				(width 0.1524)
				(type default)
			)
			(layer "F.SilkS")
		)
		(fp_line
			(start -0.508 -1.199896)
			(end 0 -0.762)
			(stroke
				(width 0.1524)
				(type default)
			)
			(layer "F.SilkS")
		)
		(fp_line
			(start 0.508 -1.199896)
			(end 1.376172 -1.199896)
			(stroke
				(width 0.1524)
				(type default)
			)
			(layer "F.SilkS")
		)
		(fp_line
			(start 1.376172 -1.199896)
			(end 1.376172 1.199896)
			(stroke
				(width 0.1524)
				(type default)
			)
			(layer "F.SilkS")
		)
		(fp_poly
			(pts
				(xy -1.175004 -1.325372) (xy -1.444498 -2.1336) (xy -1.983232 -1.594866)
			)
			(stroke
				(width 0)
				(type default)
			)
			(fill yes)
			(layer "F.SilkS")
		)
		(fp_line
			(start -0.674878 1.100074)
			(end -0.674878 -1.100074)
			(stroke
				(width 0.1)
				(type default)
			)
			(layer "F.Fab")
		)
		(fp_line
			(start 0.674878 1.100074)
			(end -0.674878 1.100074)
			(stroke
				(width 0.1)
				(type default)
			)
			(layer "F.Fab")
		)
		(fp_line
			(start -0.674878 -1.100074)
			(end 0.674878 -1.100074)
			(stroke
				(width 0.1)
				(type default)
			)
			(layer "F.Fab")
		)
		(fp_line
			(start 0.674878 -1.100074)
			(end 0.674878 1.100074)
			(stroke
				(width 0.1)
				(type default)
			)
			(layer "F.Fab")
		)
		(fp_poly
			(pts
				(xy -1.4605 -0.7493) (xy -2.2225 -1.1303) (xy -2.2225 -0.3683)
			)
			(stroke
				(width 0)
				(type default)
			)
			(fill yes)
			(layer "F.Fab")
		)
		(pad "1" smd rect
			(at -0.899922 -0.750062 180)
			(size 0.6096 0.6096)
			(layers "F.Cu" "F.Mask" "F.Paste")
			(net "GND")
		)
		(pad "2" smd rect
			(at -0.899922 0 180)
			(size 0.4064 0.6096)
			(layers "F.Cu" "F.Mask" "F.Paste")
			(net "P3V3_NIC6_PG_G1")
		)
		(pad "3" smd rect
			(at -0.899922 0.750062 180)
			(size 0.6096 0.6096)
			(layers "F.Cu" "F.Mask" "F.Paste")
			(net "PWRGD_P3V3_NIC6_D")
		)
		(pad "4" smd rect
			(at 0.899922 0.750062 180)
			(size 0.6096 0.6096)
			(layers "F.Cu" "F.Mask" "F.Paste")
			(net "GND")
		)
		(pad "5" smd rect
			(at 0.899922 0 180)
			(size 0.4064 0.6096)
			(layers "F.Cu" "F.Mask" "F.Paste")
			(net "P3V3_NIC6_PG_G2")
		)
		(pad "6" smd rect
			(at 0.899922 -0.750062 180)
			(size 0.6096 0.6096)
			(layers "F.Cu" "F.Mask" "F.Paste")
			(net "P3V3_NIC6_PG_G2")
		)
	)
	(footprint ""
		(layer "F.Cu")
		(at 262.638286 -252.356874 -90)
		(property "Reference" "R1356"
			(at 0 0 270)
			(layer "F.SilkS")
			(hide yes)
			(effects
				(font
					(size 1.27 1.27)
				)
			)
		)
		(property "Value" ""
			(at 0 0 270)
			(layer "F.Fab")
			(effects
				(font
					(size 1.27 1.27)
				)
			)
		)
		(duplicate_pad_numbers_are_jumpers no)
		(fp_line
			(start -0.7874 0.4064)
			(end -0.7874 -0.4064)
			(stroke
				(width 0.1524)
				(type default)
			)
			(layer "F.SilkS")
		)
		(fp_line
			(start 0.7874 0.4064)
			(end -0.7874 0.4064)
			(stroke
				(width 0.1524)
				(type default)
			)
			(layer "F.SilkS")
		)
		(fp_line
			(start -0.7874 -0.4064)
			(end 0.7874 -0.4064)
			(stroke
				(width 0.1524)
				(type default)
			)
			(layer "F.SilkS")
		)
		(fp_line
			(start 0.7874 -0.4064)
			(end 0.7874 0.4064)
			(stroke
				(width 0.1524)
				(type default)
			)
			(layer "F.SilkS")
		)
		(fp_line
			(start -0.67945 0.3048)
			(end -0.67945 -0.305054)
			(stroke
				(width 0.1)
				(type default)
			)
			(layer "F.Fab")
		)
		(fp_line
			(start -0.12065 0.3048)
			(end -0.67945 0.3048)
			(stroke
				(width 0.1)
				(type default)
			)
			(layer "F.Fab")
		)
		(fp_line
			(start 0.120396 0.3048)
			(end 0.120396 0.2794)
			(stroke
				(width 0.1)
				(type default)
			)
			(layer "F.Fab")
		)
		(fp_line
			(start 0.67945 0.3048)
			(end 0.120396 0.3048)
			(stroke
				(width 0.1)
				(type default)
			)
			(layer "F.Fab")
		)
		(fp_line
			(start -0.12065 0.2794)
			(end -0.12065 0.3048)
			(stroke
				(width 0.1)
				(type default)
			)
			(layer "F.Fab")
		)
		(fp_line
			(start 0.120396 0.2794)
			(end -0.12065 0.2794)
			(stroke
				(width 0.1)
				(type default)
			)
			(layer "F.Fab")
		)
		(fp_line
			(start -0.12065 -0.2794)
			(end 0.12065 -0.2794)
			(stroke
				(width 0.1)
				(type default)
			)
			(layer "F.Fab")
		)
		(fp_line
			(start 0.12065 -0.2794)
			(end 0.12065 -0.3048)
			(stroke
				(width 0.1)
				(type default)
			)
			(layer "F.Fab")
		)
		(fp_line
			(start 0.12065 -0.3048)
			(end 0.67945 -0.3048)
			(stroke
				(width 0.1)
				(type default)
			)
			(layer "F.Fab")
		)
		(fp_line
			(start 0.67945 -0.3048)
			(end 0.67945 0.3048)
			(stroke
				(width 0.1)
				(type default)
			)
			(layer "F.Fab")
		)
		(fp_line
			(start -0.67945 -0.305054)
			(end -0.12065 -0.305054)
			(stroke
				(width 0.1)
				(type default)
			)
			(layer "F.Fab")
		)
		(fp_line
			(start -0.12065 -0.305054)
			(end -0.12065 -0.2794)
			(stroke
				(width 0.1)
				(type default)
			)
			(layer "F.Fab")
		)
		(pad "1" smd circle
			(at -0.40005 0 270)
			(size 0 0)
			(layers "F.Cu" "F.Mask" "F.Paste")
			(net "GND")
		)
		(pad "2" smd circle
			(at 0.40005 0 270)
			(size 0 0)
			(layers "F.Cu" "F.Mask" "F.Paste")
			(net "PEX2_MODE_SEL0")
		)
	)
	(footprint ""
		(layer "F.Cu")
		(at 268.838426 -131.323334)
		(property "Reference" "C462"
			(at 0 0 0)
			(layer "F.SilkS")
			(hide yes)
			(effects
				(font
					(size 1.27 1.27)
				)
			)
		)
		(property "Value" ""
			(at 0 0 0)
			(layer "F.Fab")
			(effects
				(font
					(size 1.27 1.27)
				)
			)
		)
		(duplicate_pad_numbers_are_jumpers no)
		(fp_line
			(start -0.299974 -0.150114)
			(end 0.299974 -0.150114)
			(stroke
				(width 0.1)
				(type default)
			)
			(layer "F.Fab")
		)
		(fp_line
			(start -0.299974 0.150114)
			(end -0.299974 -0.150114)
			(stroke
				(width 0.1)
				(type default)
			)
			(layer "F.Fab")
		)
		(fp_line
			(start 0.299974 -0.150114)
			(end 0.299974 0.150114)
			(stroke
				(width 0.1)
				(type default)
			)
			(layer "F.Fab")
		)
		(fp_line
			(start 0.299974 0.150114)
			(end -0.299974 0.150114)
			(stroke
				(width 0.1)
				(type default)
			)
			(layer "F.Fab")
		)
		(pad "1" smd rect
			(at -0.2667 0)
			(size 0.3048 0.381)
			(layers "F.Cu" "F.Mask" "F.Paste")
			(net "P5E_PEX2_STN1_TX_DN<28>")
		)
		(pad "2" smd rect
			(at 0.2667 0)
			(size 0.3048 0.381)
			(layers "F.Cu" "F.Mask" "F.Paste")
			(net "P5E_PEX2_STN1_TX_C_DN<28>")
		)
	)
	(footprint ""
		(layer "F.Cu")
		(at 20.434554 -33.631886 180)
		(property "Reference" "C66"
			(at 0 0 180)
			(layer "F.SilkS")
			(hide yes)
			(effects
				(font
					(size 1.27 1.27)
				)
			)
		)
		(property "Value" ""
			(at 0 0 180)
			(layer "F.Fab")
			(effects
				(font
					(size 1.27 1.27)
				)
			)
		)
		(duplicate_pad_numbers_are_jumpers no)
		(fp_line
			(start 0.299974 0.150114)
			(end -0.299974 0.150114)
			(stroke
				(width 0.1)
				(type default)
			)
			(layer "F.Fab")
		)
		(fp_line
			(start 0.299974 -0.150114)
			(end 0.299974 0.150114)
			(stroke
				(width 0.1)
				(type default)
			)
			(layer "F.Fab")
		)
		(fp_line
			(start -0.299974 0.150114)
			(end -0.299974 -0.150114)
			(stroke
				(width 0.1)
				(type default)
			)
			(layer "F.Fab")
		)
		(fp_line
			(start -0.299974 -0.150114)
			(end 0.299974 -0.150114)
			(stroke
				(width 0.1)
				(type default)
			)
			(layer "F.Fab")
		)
		(pad "1" smd rect
			(at -0.2667 0 180)
			(size 0.3048 0.381)
			(layers "F.Cu" "F.Mask" "F.Paste")
			(net "P5E_PEX0_STN2_TX_DN<47>")
		)
		(pad "2" smd rect
			(at 0.2667 0 180)
			(size 0.3048 0.381)
			(layers "F.Cu" "F.Mask" "F.Paste")
			(net "P5E_PEX0_STN2_TX_C_DN<47>")
		)
	)
	(footprint ""
		(layer "F.Cu")
		(at 395.247368 -20.35556)
		(property "Reference" "C3968"
			(at 0 0 0)
			(layer "F.SilkS")
			(hide yes)
			(effects
				(font
					(size 1.27 1.27)
				)
			)
		)
		(property "Value" ""
			(at 0 0 0)
			(layer "F.Fab")
			(effects
				(font
					(size 1.27 1.27)
				)
			)
		)
		(duplicate_pad_numbers_are_jumpers no)
		(fp_line
			(start -0.7874 -0.4064)
			(end 0.7874 -0.4064)
			(stroke
				(width 0.1524)
				(type default)
			)
			(layer "F.SilkS")
		)
		(fp_line
			(start -0.7874 0.4064)
			(end -0.7874 -0.4064)
			(stroke
				(width 0.1524)
				(type default)
			)
			(layer "F.SilkS")
		)
		(fp_line
			(start 0.7874 -0.4064)
			(end 0.7874 0.4064)
			(stroke
				(width 0.1524)
				(type default)
			)
			(layer "F.SilkS")
		)
		(fp_line
			(start 0.7874 0.4064)
			(end -0.7874 0.4064)
			(stroke
				(width 0.1524)
				(type default)
			)
			(layer "F.SilkS")
		)
		(fp_line
			(start -0.67945 -0.305054)
			(end -0.12065 -0.305054)
			(stroke
				(width 0.1)
				(type default)
			)
			(layer "F.Fab")
		)
		(fp_line
			(start -0.67945 0.3048)
			(end -0.67945 -0.305054)
			(stroke
				(width 0.1)
				(type default)
			)
			(layer "F.Fab")
		)
		(fp_line
			(start -0.12065 -0.305054)
			(end -0.12065 -0.2794)
			(stroke
				(width 0.1)
				(type default)
			)
			(layer "F.Fab")
		)
		(fp_line
			(start -0.12065 -0.2794)
			(end 0.12065 -0.2794)
			(stroke
				(width 0.1)
				(type default)
			)
			(layer "F.Fab")
		)
		(fp_line
			(start -0.12065 0.2794)
			(end -0.12065 0.3048)
			(stroke
				(width 0.1)
				(type default)
			)
			(layer "F.Fab")
		)
		(fp_line
			(start -0.12065 0.3048)
			(end -0.67945 0.3048)
			(stroke
				(width 0.1)
				(type default)
			)
			(layer "F.Fab")
		)
		(fp_line
			(start 0.120396 0.2794)
			(end -0.12065 0.2794)
			(stroke
				(width 0.1)
				(type default)
			)
			(layer "F.Fab")
		)
		(fp_line
			(start 0.120396 0.3048)
			(end 0.120396 0.2794)
			(stroke
				(width 0.1)
				(type default)
			)
			(layer "F.Fab")
		)
		(fp_line
			(start 0.12065 -0.3048)
			(end 0.67945 -0.3048)
			(stroke
				(width 0.1)
				(type default)
			)
			(layer "F.Fab")
		)
		(fp_line
			(start 0.12065 -0.2794)
			(end 0.12065 -0.3048)
			(stroke
				(width 0.1)
				(type default)
			)
			(layer "F.Fab")
		)
		(fp_line
			(start 0.67945 -0.3048)
			(end 0.67945 0.3048)
			(stroke
				(width 0.1)
				(type default)
			)
			(layer "F.Fab")
		)
		(fp_line
			(start 0.67945 0.3048)
			(end 0.120396 0.3048)
			(stroke
				(width 0.1)
				(type default)
			)
			(layer "F.Fab")
		)
		(pad "1" smd circle
			(at -0.40005 0)
			(size 0 0)
			(layers "F.Cu" "F.Mask" "F.Paste")
			(net "P12V_SSD13")
		)
		(pad "2" smd circle
			(at 0.40005 0)
			(size 0 0)
			(layers "F.Cu" "F.Mask" "F.Paste")
			(net "GND")
		)
	)
	(footprint ""
		(layer "F.Cu")
		(at 314.072016 -32.848042 90)
		(property "Reference" "PC952"
			(at 0 0 90)
			(layer "F.SilkS")
			(hide yes)
			(effects
				(font
					(size 1.27 1.27)
				)
			)
		)
		(property "Value" ""
			(at 0 0 90)
			(layer "F.Fab")
			(effects
				(font
					(size 1.27 1.27)
				)
			)
		)
		(duplicate_pad_numbers_are_jumpers no)
		(fp_line
			(start 0.7874 -0.4064)
			(end 0.7874 0.4064)
			(stroke
				(width 0.1524)
				(type default)
			)
			(layer "F.SilkS")
		)
		(fp_line
			(start -0.7874 -0.4064)
			(end 0.7874 -0.4064)
			(stroke
				(width 0.1524)
				(type default)
			)
			(layer "F.SilkS")
		)
		(fp_line
			(start 0.7874 0.4064)
			(end -0.7874 0.4064)
			(stroke
				(width 0.1524)
				(type default)
			)
			(layer "F.SilkS")
		)
		(fp_line
			(start -0.7874 0.4064)
			(end -0.7874 -0.4064)
			(stroke
				(width 0.1524)
				(type default)
			)
			(layer "F.SilkS")
		)
		(fp_line
			(start -0.12065 -0.305054)
			(end -0.12065 -0.2794)
			(stroke
				(width 0.1)
				(type default)
			)
			(layer "F.Fab")
		)
		(fp_line
			(start -0.67945 -0.305054)
			(end -0.12065 -0.305054)
			(stroke
				(width 0.1)
				(type default)
			)
			(layer "F.Fab")
		)
		(fp_line
			(start 0.67945 -0.3048)
			(end 0.67945 0.3048)
			(stroke
				(width 0.1)
				(type default)
			)
			(layer "F.Fab")
		)
		(fp_line
			(start 0.12065 -0.3048)
			(end 0.67945 -0.3048)
			(stroke
				(width 0.1)
				(type default)
			)
			(layer "F.Fab")
		)
		(fp_line
			(start 0.12065 -0.2794)
			(end 0.12065 -0.3048)
			(stroke
				(width 0.1)
				(type default)
			)
			(layer "F.Fab")
		)
		(fp_line
			(start -0.12065 -0.2794)
			(end 0.12065 -0.2794)
			(stroke
				(width 0.1)
				(type default)
			)
			(layer "F.Fab")
		)
		(fp_line
			(start 0.120396 0.2794)
			(end -0.12065 0.2794)
			(stroke
				(width 0.1)
				(type default)
			)
			(layer "F.Fab")
		)
		(fp_line
			(start -0.12065 0.2794)
			(end -0.12065 0.3048)
			(stroke
				(width 0.1)
				(type default)
			)
			(layer "F.Fab")
		)
		(fp_line
			(start 0.67945 0.3048)
			(end 0.120396 0.3048)
			(stroke
				(width 0.1)
				(type default)
			)
			(layer "F.Fab")
		)
		(fp_line
			(start 0.120396 0.3048)
			(end 0.120396 0.2794)
			(stroke
				(width 0.1)
				(type default)
			)
			(layer "F.Fab")
		)
		(fp_line
			(start -0.12065 0.3048)
			(end -0.67945 0.3048)
			(stroke
				(width 0.1)
				(type default)
			)
			(layer "F.Fab")
		)
		(fp_line
			(start -0.67945 0.3048)
			(end -0.67945 -0.305054)
			(stroke
				(width 0.1)
				(type default)
			)
			(layer "F.Fab")
		)
		(pad "1" smd circle
			(at -0.40005 0 90)
			(size 0 0)
			(layers "F.Cu" "F.Mask" "F.Paste")
			(net "P3V3_SSD11_CO_GATE")
		)
		(pad "2" smd circle
			(at 0.40005 0 90)
			(size 0 0)
			(layers "F.Cu" "F.Mask" "F.Paste")
			(net "GND")
		)
	)
	(footprint ""
		(layer "F.Cu")
		(at 32.411416 -293.245032 -90)
		(property "Reference" "R4560"
			(at 0 0 270)
			(layer "F.SilkS")
			(hide yes)
			(effects
				(font
					(size 1.27 1.27)
				)
			)
		)
		(property "Value" ""
			(at 0 0 270)
			(layer "F.Fab")
			(effects
				(font
					(size 1.27 1.27)
				)
			)
		)
		(duplicate_pad_numbers_are_jumpers no)
		(fp_line
			(start -0.7874 0.4064)
			(end -0.7874 -0.4064)
			(stroke
				(width 0.1524)
				(type default)
			)
			(layer "F.SilkS")
		)
		(fp_line
			(start 0.7874 0.4064)
			(end -0.7874 0.4064)
			(stroke
				(width 0.1524)
				(type default)
			)
			(layer "F.SilkS")
		)
		(fp_line
			(start -0.7874 -0.4064)
			(end 0.7874 -0.4064)
			(stroke
				(width 0.1524)
				(type default)
			)
			(layer "F.SilkS")
		)
		(fp_line
			(start 0.7874 -0.4064)
			(end 0.7874 0.4064)
			(stroke
				(width 0.1524)
				(type default)
			)
			(layer "F.SilkS")
		)
		(fp_line
			(start -0.67945 0.3048)
			(end -0.67945 -0.305054)
			(stroke
				(width 0.1)
				(type default)
			)
			(layer "F.Fab")
		)
		(fp_line
			(start -0.12065 0.3048)
			(end -0.67945 0.3048)
			(stroke
				(width 0.1)
				(type default)
			)
			(layer "F.Fab")
		)
		(fp_line
			(start 0.120396 0.3048)
			(end 0.120396 0.2794)
			(stroke
				(width 0.1)
				(type default)
			)
			(layer "F.Fab")
		)
		(fp_line
			(start 0.67945 0.3048)
			(end 0.120396 0.3048)
			(stroke
				(width 0.1)
				(type default)
			)
			(layer "F.Fab")
		)
		(fp_line
			(start -0.12065 0.2794)
			(end -0.12065 0.3048)
			(stroke
				(width 0.1)
				(type default)
			)
			(layer "F.Fab")
		)
		(fp_line
			(start 0.120396 0.2794)
			(end -0.12065 0.2794)
			(stroke
				(width 0.1)
				(type default)
			)
			(layer "F.Fab")
		)
		(fp_line
			(start -0.12065 -0.2794)
			(end 0.12065 -0.2794)
			(stroke
				(width 0.1)
				(type default)
			)
			(layer "F.Fab")
		)
		(fp_line
			(start 0.12065 -0.2794)
			(end 0.12065 -0.3048)
			(stroke
				(width 0.1)
				(type default)
			)
			(layer "F.Fab")
		)
		(fp_line
			(start 0.12065 -0.3048)
			(end 0.67945 -0.3048)
			(stroke
				(width 0.1)
				(type default)
			)
			(layer "F.Fab")
		)
		(fp_line
			(start 0.67945 -0.3048)
			(end 0.67945 0.3048)
			(stroke
				(width 0.1)
				(type default)
			)
			(layer "F.Fab")
		)
		(fp_line
			(start -0.67945 -0.305054)
			(end -0.12065 -0.305054)
			(stroke
				(width 0.1)
				(type default)
			)
			(layer "F.Fab")
		)
		(fp_line
			(start -0.12065 -0.305054)
			(end -0.12065 -0.2794)
			(stroke
				(width 0.1)
				(type default)
			)
			(layer "F.Fab")
		)
		(pad "1" smd circle
			(at -0.40005 0 270)
			(size 0 0)
			(layers "F.Cu" "F.Mask" "F.Paste")
			(net "PCEPLL2_VDDA18_PEX0")
		)
		(pad "2" smd circle
			(at 0.40005 0 270)
			(size 0 0)
			(layers "F.Cu" "F.Mask" "F.Paste")
			(net "PCEPLL2_VDDA18_PEX0_R")
		)
	)
	(footprint ""
		(layer "F.Cu")
		(at 196.119242 -130.794506 180)
		(property "Reference" "C234"
			(at 0 0 180)
			(layer "F.SilkS")
			(hide yes)
			(effects
				(font
					(size 1.27 1.27)
				)
			)
		)
		(property "Value" ""
			(at 0 0 180)
			(layer "F.Fab")
			(effects
				(font
					(size 1.27 1.27)
				)
			)
		)
		(duplicate_pad_numbers_are_jumpers no)
		(fp_line
			(start 0.299974 0.150114)
			(end -0.299974 0.150114)
			(stroke
				(width 0.1)
				(type default)
			)
			(layer "F.Fab")
		)
		(fp_line
			(start 0.299974 -0.150114)
			(end 0.299974 0.150114)
			(stroke
				(width 0.1)
				(type default)
			)
			(layer "F.Fab")
		)
		(fp_line
			(start -0.299974 0.150114)
			(end -0.299974 -0.150114)
			(stroke
				(width 0.1)
				(type default)
			)
			(layer "F.Fab")
		)
		(fp_line
			(start -0.299974 -0.150114)
			(end 0.299974 -0.150114)
			(stroke
				(width 0.1)
				(type default)
			)
			(layer "F.Fab")
		)
		(pad "1" smd rect
			(at -0.2667 0 180)
			(size 0.3048 0.381)
			(layers "F.Cu" "F.Mask" "F.Paste")
			(net "P5E_PEX1_STN0_TX_DP<4>")
		)
		(pad "2" smd rect
			(at 0.2667 0 180)
			(size 0.3048 0.381)
			(layers "F.Cu" "F.Mask" "F.Paste")
			(net "P5E_PEX1_STN0_TX_C_DP<4>")
		)
	)
	(footprint ""
		(layer "F.Cu")
		(at 164.06114 -37.951156)
		(property "Reference" "Q222"
			(at -0.02794 -1.925574 0)
			(unlocked yes)
			(layer "F.SilkS")
			(effects
				(font
					(size 0.7874 0.5842)
					(thickness 0.1524)
				)
			)
		)
		(property "Value" ""
			(at 0 0 0)
			(layer "F.Fab")
			(effects
				(font
					(size 1.27 1.27)
				)
			)
		)
		(duplicate_pad_numbers_are_jumpers no)
		(fp_line
			(start -1.376172 -1.199896)
			(end -0.508 -1.199896)
			(stroke
				(width 0.1524)
				(type default)
			)
			(layer "F.SilkS")
		)
		(fp_line
			(start -1.376172 1.199896)
			(end -1.376172 -1.199896)
			(stroke
				(width 0.1524)
				(type default)
			)
			(layer "F.SilkS")
		)
		(fp_line
			(start -0.508 -1.199896)
			(end 0 -0.762)
			(stroke
				(width 0.1524)
				(type default)
			)
			(layer "F.SilkS")
		)
		(fp_line
			(start 0 -0.762)
			(end 0.508 -1.199896)
			(stroke
				(width 0.1524)
				(type default)
			)
			(layer "F.SilkS")
		)
		(fp_line
			(start 0.508 -1.199896)
			(end 1.376172 -1.199896)
			(stroke
				(width 0.1524)
				(type default)
			)
			(layer "F.SilkS")
		)
		(fp_line
			(start 1.376172 -1.199896)
			(end 1.376172 1.199896)
			(stroke
				(width 0.1524)
				(type default)
			)
			(layer "F.SilkS")
		)
		(fp_line
			(start 1.376172 1.199896)
			(end -1.376172 1.199896)
			(stroke
				(width 0.1524)
				(type default)
			)
			(layer "F.SilkS")
		)
		(fp_poly
			(pts
				(xy -1.471422 -0.894334) (xy -1.740916 -1.702562) (xy -2.27965 -1.163828)
			)
			(stroke
				(width 0)
				(type default)
			)
			(fill yes)
			(layer "F.SilkS")
		)
		(fp_line
			(start -0.674878 -1.100074)
			(end 0.674878 -1.100074)
			(stroke
				(width 0.1)
				(type default)
			)
			(layer "F.Fab")
		)
		(fp_line
			(start -0.674878 1.100074)
			(end -0.674878 -1.100074)
			(stroke
				(width 0.1)
				(type default)
			)
			(layer "F.Fab")
		)
		(fp_line
			(start 0.674878 -1.100074)
			(end 0.674878 1.100074)
			(stroke
				(width 0.1)
				(type default)
			)
			(layer "F.Fab")
		)
		(fp_line
			(start 0.674878 1.100074)
			(end -0.674878 1.100074)
			(stroke
				(width 0.1)
				(type default)
			)
			(layer "F.Fab")
		)
		(fp_poly
			(pts
				(xy -1.4605 -0.7493) (xy -2.2225 -1.1303) (xy -2.2225 -0.3683)
			)
			(stroke
				(width 0)
				(type default)
			)
			(fill yes)
			(layer "F.Fab")
		)
		(pad "1" smd rect
			(at -0.899922 -0.750062 270)
			(size 0.6096 0.6096)
			(layers "F.Cu" "F.Mask" "F.Paste")
			(net "GND")
		)
		(pad "2" smd rect
			(at -0.899922 0 270)
			(size 0.4064 0.6096)
			(layers "F.Cu" "F.Mask" "F.Paste")
			(net "P3V3_SSD6_PG_G1")
		)
		(pad "3" smd rect
			(at -0.899922 0.750062 270)
			(size 0.6096 0.6096)
			(layers "F.Cu" "F.Mask" "F.Paste")
			(net "PWRGD_P3V3_SSD6_D")
		)
		(pad "4" smd rect
			(at 0.899922 0.750062 270)
			(size 0.6096 0.6096)
			(layers "F.Cu" "F.Mask" "F.Paste")
			(net "GND")
		)
		(pad "5" smd rect
			(at 0.899922 0 270)
			(size 0.4064 0.6096)
			(layers "F.Cu" "F.Mask" "F.Paste")
			(net "P3V3_SSD6_PG_G2")
		)
		(pad "6" smd rect
			(at 0.899922 -0.750062 270)
			(size 0.6096 0.6096)
			(layers "F.Cu" "F.Mask" "F.Paste")
			(net "P3V3_SSD6_PG_G2")
		)
	)
	(footprint ""
		(layer "F.Cu")
		(at 112.937798 -157.595824)
		(property "Reference" "PC31"
			(at 0 0 0)
			(layer "F.SilkS")
			(hide yes)
			(effects
				(font
					(size 1.27 1.27)
				)
			)
		)
		(property "Value" ""
			(at 0 0 0)
			(layer "F.Fab")
			(effects
				(font
					(size 1.27 1.27)
				)
			)
		)
		(duplicate_pad_numbers_are_jumpers no)
		(fp_line
			(start -0.7874 -0.4064)
			(end 0.7874 -0.4064)
			(stroke
				(width 0.1524)
				(type default)
			)
			(layer "F.SilkS")
		)
		(fp_line
			(start -0.7874 0.4064)
			(end -0.7874 -0.4064)
			(stroke
				(width 0.1524)
				(type default)
			)
			(layer "F.SilkS")
		)
		(fp_line
			(start 0.7874 -0.4064)
			(end 0.7874 0.4064)
			(stroke
				(width 0.1524)
				(type default)
			)
			(layer "F.SilkS")
		)
		(fp_line
			(start 0.7874 0.4064)
			(end -0.7874 0.4064)
			(stroke
				(width 0.1524)
				(type default)
			)
			(layer "F.SilkS")
		)
		(fp_line
			(start -0.67945 -0.305054)
			(end -0.12065 -0.305054)
			(stroke
				(width 0.1)
				(type default)
			)
			(layer "F.Fab")
		)
		(fp_line
			(start -0.67945 0.3048)
			(end -0.67945 -0.305054)
			(stroke
				(width 0.1)
				(type default)
			)
			(layer "F.Fab")
		)
		(fp_line
			(start -0.12065 -0.305054)
			(end -0.12065 -0.2794)
			(stroke
				(width 0.1)
				(type default)
			)
			(layer "F.Fab")
		)
		(fp_line
			(start -0.12065 -0.2794)
			(end 0.12065 -0.2794)
			(stroke
				(width 0.1)
				(type default)
			)
			(layer "F.Fab")
		)
		(fp_line
			(start -0.12065 0.2794)
			(end -0.12065 0.3048)
			(stroke
				(width 0.1)
				(type default)
			)
			(layer "F.Fab")
		)
		(fp_line
			(start -0.12065 0.3048)
			(end -0.67945 0.3048)
			(stroke
				(width 0.1)
				(type default)
			)
			(layer "F.Fab")
		)
		(fp_line
			(start 0.120396 0.2794)
			(end -0.12065 0.2794)
			(stroke
				(width 0.1)
				(type default)
			)
			(layer "F.Fab")
		)
		(fp_line
			(start 0.120396 0.3048)
			(end 0.120396 0.2794)
			(stroke
				(width 0.1)
				(type default)
			)
			(layer "F.Fab")
		)
		(fp_line
			(start 0.12065 -0.3048)
			(end 0.67945 -0.3048)
			(stroke
				(width 0.1)
				(type default)
			)
			(layer "F.Fab")
		)
		(fp_line
			(start 0.12065 -0.2794)
			(end 0.12065 -0.3048)
			(stroke
				(width 0.1)
				(type default)
			)
			(layer "F.Fab")
		)
		(fp_line
			(start 0.67945 -0.3048)
			(end 0.67945 0.3048)
			(stroke
				(width 0.1)
				(type default)
			)
			(layer "F.Fab")
		)
		(fp_line
			(start 0.67945 0.3048)
			(end 0.120396 0.3048)
			(stroke
				(width 0.1)
				(type default)
			)
			(layer "F.Fab")
		)
		(pad "1" smd circle
			(at -0.40005 0)
			(size 0 0)
			(layers "F.Cu" "F.Mask" "F.Paste")
			(net "SW_P3V3_AUX_BT")
		)
		(pad "2" smd circle
			(at 0.40005 0)
			(size 0 0)
			(layers "F.Cu" "F.Mask" "F.Paste")
			(net "SW_P3V3_AUX_PH")
		)
	)
	(footprint ""
		(layer "F.Cu")
		(at 238.48822 -55.808118 90)
		(property "Reference" "PC553"
			(at 0 0 90)
			(layer "F.SilkS")
			(hide yes)
			(effects
				(font
					(size 1.27 1.27)
				)
			)
		)
		(property "Value" ""
			(at 0 0 90)
			(layer "F.Fab")
			(effects
				(font
					(size 1.27 1.27)
				)
			)
		)
		(duplicate_pad_numbers_are_jumpers no)
		(fp_line
			(start 0.7874 -0.4064)
			(end 0.7874 0.4064)
			(stroke
				(width 0.1524)
				(type default)
			)
			(layer "F.SilkS")
		)
		(fp_line
			(start -0.7874 -0.4064)
			(end 0.7874 -0.4064)
			(stroke
				(width 0.1524)
				(type default)
			)
			(layer "F.SilkS")
		)
		(fp_line
			(start 0.7874 0.4064)
			(end -0.7874 0.4064)
			(stroke
				(width 0.1524)
				(type default)
			)
			(layer "F.SilkS")
		)
		(fp_line
			(start -0.7874 0.4064)
			(end -0.7874 -0.4064)
			(stroke
				(width 0.1524)
				(type default)
			)
			(layer "F.SilkS")
		)
		(fp_line
			(start -0.12065 -0.305054)
			(end -0.12065 -0.2794)
			(stroke
				(width 0.1)
				(type default)
			)
			(layer "F.Fab")
		)
		(fp_line
			(start -0.67945 -0.305054)
			(end -0.12065 -0.305054)
			(stroke
				(width 0.1)
				(type default)
			)
			(layer "F.Fab")
		)
		(fp_line
			(start 0.67945 -0.3048)
			(end 0.67945 0.3048)
			(stroke
				(width 0.1)
				(type default)
			)
			(layer "F.Fab")
		)
		(fp_line
			(start 0.12065 -0.3048)
			(end 0.67945 -0.3048)
			(stroke
				(width 0.1)
				(type default)
			)
			(layer "F.Fab")
		)
		(fp_line
			(start 0.12065 -0.2794)
			(end 0.12065 -0.3048)
			(stroke
				(width 0.1)
				(type default)
			)
			(layer "F.Fab")
		)
		(fp_line
			(start -0.12065 -0.2794)
			(end 0.12065 -0.2794)
			(stroke
				(width 0.1)
				(type default)
			)
			(layer "F.Fab")
		)
		(fp_line
			(start 0.120396 0.2794)
			(end -0.12065 0.2794)
			(stroke
				(width 0.1)
				(type default)
			)
			(layer "F.Fab")
		)
		(fp_line
			(start -0.12065 0.2794)
			(end -0.12065 0.3048)
			(stroke
				(width 0.1)
				(type default)
			)
			(layer "F.Fab")
		)
		(fp_line
			(start 0.67945 0.3048)
			(end 0.120396 0.3048)
			(stroke
				(width 0.1)
				(type default)
			)
			(layer "F.Fab")
		)
		(fp_line
			(start 0.120396 0.3048)
			(end 0.120396 0.2794)
			(stroke
				(width 0.1)
				(type default)
			)
			(layer "F.Fab")
		)
		(fp_line
			(start -0.12065 0.3048)
			(end -0.67945 0.3048)
			(stroke
				(width 0.1)
				(type default)
			)
			(layer "F.Fab")
		)
		(fp_line
			(start -0.67945 0.3048)
			(end -0.67945 -0.305054)
			(stroke
				(width 0.1)
				(type default)
			)
			(layer "F.Fab")
		)
		(pad "1" smd circle
			(at -0.40005 0 90)
			(size 0 0)
			(layers "F.Cu" "F.Mask" "F.Paste")
			(net "P5V_AUX")
		)
		(pad "2" smd circle
			(at 0.40005 0 90)
			(size 0 0)
			(layers "F.Cu" "F.Mask" "F.Paste")
			(net "GND")
		)
	)
	(footprint ""
		(layer "F.Cu")
		(at 121.13514 -94.891606)
		(property "Reference" "R1553"
			(at 0 0 0)
			(layer "F.SilkS")
			(hide yes)
			(effects
				(font
					(size 1.27 1.27)
				)
			)
		)
		(property "Value" ""
			(at 0 0 0)
			(layer "F.Fab")
			(effects
				(font
					(size 1.27 1.27)
				)
			)
		)
		(duplicate_pad_numbers_are_jumpers no)
		(fp_line
			(start -0.7874 -0.4064)
			(end 0.7874 -0.4064)
			(stroke
				(width 0.1524)
				(type default)
			)
			(layer "F.SilkS")
		)
		(fp_line
			(start -0.7874 0.4064)
			(end -0.7874 -0.4064)
			(stroke
				(width 0.1524)
				(type default)
			)
			(layer "F.SilkS")
		)
		(fp_line
			(start 0.7874 -0.4064)
			(end 0.7874 0.4064)
			(stroke
				(width 0.1524)
				(type default)
			)
			(layer "F.SilkS")
		)
		(fp_line
			(start 0.7874 0.4064)
			(end -0.7874 0.4064)
			(stroke
				(width 0.1524)
				(type default)
			)
			(layer "F.SilkS")
		)
		(fp_line
			(start -0.67945 -0.305054)
			(end -0.12065 -0.305054)
			(stroke
				(width 0.1)
				(type default)
			)
			(layer "F.Fab")
		)
		(fp_line
			(start -0.67945 0.3048)
			(end -0.67945 -0.305054)
			(stroke
				(width 0.1)
				(type default)
			)
			(layer "F.Fab")
		)
		(fp_line
			(start -0.12065 -0.305054)
			(end -0.12065 -0.2794)
			(stroke
				(width 0.1)
				(type default)
			)
			(layer "F.Fab")
		)
		(fp_line
			(start -0.12065 -0.2794)
			(end 0.12065 -0.2794)
			(stroke
				(width 0.1)
				(type default)
			)
			(layer "F.Fab")
		)
		(fp_line
			(start -0.12065 0.2794)
			(end -0.12065 0.3048)
			(stroke
				(width 0.1)
				(type default)
			)
			(layer "F.Fab")
		)
		(fp_line
			(start -0.12065 0.3048)
			(end -0.67945 0.3048)
			(stroke
				(width 0.1)
				(type default)
			)
			(layer "F.Fab")
		)
		(fp_line
			(start 0.120396 0.2794)
			(end -0.12065 0.2794)
			(stroke
				(width 0.1)
				(type default)
			)
			(layer "F.Fab")
		)
		(fp_line
			(start 0.120396 0.3048)
			(end 0.120396 0.2794)
			(stroke
				(width 0.1)
				(type default)
			)
			(layer "F.Fab")
		)
		(fp_line
			(start 0.12065 -0.3048)
			(end 0.67945 -0.3048)
			(stroke
				(width 0.1)
				(type default)
			)
			(layer "F.Fab")
		)
		(fp_line
			(start 0.12065 -0.2794)
			(end 0.12065 -0.3048)
			(stroke
				(width 0.1)
				(type default)
			)
			(layer "F.Fab")
		)
		(fp_line
			(start 0.67945 -0.3048)
			(end 0.67945 0.3048)
			(stroke
				(width 0.1)
				(type default)
			)
			(layer "F.Fab")
		)
		(fp_line
			(start 0.67945 0.3048)
			(end 0.120396 0.3048)
			(stroke
				(width 0.1)
				(type default)
			)
			(layer "F.Fab")
		)
		(pad "1" smd circle
			(at -0.40005 0)
			(size 0 0)
			(layers "F.Cu" "F.Mask" "F.Paste")
			(net "P3V3_AUX")
		)
		(pad "2" smd circle
			(at 0.40005 0)
			(size 0 0)
			(layers "F.Cu" "F.Mask" "F.Paste")
			(net "SMB_BIC_I2C9_MUX0_SSD1_R_SDA")
		)
	)
	(footprint ""
		(layer "F.Cu")
		(at 212.65769 -233.830622 -90)
		(property "Reference" "R1541"
			(at 0 0 270)
			(layer "F.SilkS")
			(hide yes)
			(effects
				(font
					(size 1.27 1.27)
				)
			)
		)
		(property "Value" ""
			(at 0 0 270)
			(layer "F.Fab")
			(effects
				(font
					(size 1.27 1.27)
				)
			)
		)
		(duplicate_pad_numbers_are_jumpers no)
		(fp_line
			(start -0.7874 0.4064)
			(end -0.7874 -0.4064)
			(stroke
				(width 0.1524)
				(type default)
			)
			(layer "F.SilkS")
		)
		(fp_line
			(start 0.7874 0.4064)
			(end -0.7874 0.4064)
			(stroke
				(width 0.1524)
				(type default)
			)
			(layer "F.SilkS")
		)
		(fp_line
			(start -0.7874 -0.4064)
			(end 0.7874 -0.4064)
			(stroke
				(width 0.1524)
				(type default)
			)
			(layer "F.SilkS")
		)
		(fp_line
			(start 0.7874 -0.4064)
			(end 0.7874 0.4064)
			(stroke
				(width 0.1524)
				(type default)
			)
			(layer "F.SilkS")
		)
		(fp_line
			(start -0.67945 0.3048)
			(end -0.67945 -0.305054)
			(stroke
				(width 0.1)
				(type default)
			)
			(layer "F.Fab")
		)
		(fp_line
			(start -0.12065 0.3048)
			(end -0.67945 0.3048)
			(stroke
				(width 0.1)
				(type default)
			)
			(layer "F.Fab")
		)
		(fp_line
			(start 0.120396 0.3048)
			(end 0.120396 0.2794)
			(stroke
				(width 0.1)
				(type default)
			)
			(layer "F.Fab")
		)
		(fp_line
			(start 0.67945 0.3048)
			(end 0.120396 0.3048)
			(stroke
				(width 0.1)
				(type default)
			)
			(layer "F.Fab")
		)
		(fp_line
			(start -0.12065 0.2794)
			(end -0.12065 0.3048)
			(stroke
				(width 0.1)
				(type default)
			)
			(layer "F.Fab")
		)
		(fp_line
			(start 0.120396 0.2794)
			(end -0.12065 0.2794)
			(stroke
				(width 0.1)
				(type default)
			)
			(layer "F.Fab")
		)
		(fp_line
			(start -0.12065 -0.2794)
			(end 0.12065 -0.2794)
			(stroke
				(width 0.1)
				(type default)
			)
			(layer "F.Fab")
		)
		(fp_line
			(start 0.12065 -0.2794)
			(end 0.12065 -0.3048)
			(stroke
				(width 0.1)
				(type default)
			)
			(layer "F.Fab")
		)
		(fp_line
			(start 0.12065 -0.3048)
			(end 0.67945 -0.3048)
			(stroke
				(width 0.1)
				(type default)
			)
			(layer "F.Fab")
		)
		(fp_line
			(start 0.67945 -0.3048)
			(end 0.67945 0.3048)
			(stroke
				(width 0.1)
				(type default)
			)
			(layer "F.Fab")
		)
		(fp_line
			(start -0.67945 -0.305054)
			(end -0.12065 -0.305054)
			(stroke
				(width 0.1)
				(type default)
			)
			(layer "F.Fab")
		)
		(fp_line
			(start -0.12065 -0.305054)
			(end -0.12065 -0.2794)
			(stroke
				(width 0.1)
				(type default)
			)
			(layer "F.Fab")
		)
		(pad "1" smd circle
			(at -0.40005 0 270)
			(size 0 0)
			(layers "F.Cu" "F.Mask" "F.Paste")
			(net "SMB_PEX_LS_R_SCL")
		)
		(pad "2" smd circle
			(at 0.40005 0 270)
			(size 0 0)
			(layers "F.Cu" "F.Mask" "F.Paste")
			(net "SMB_PEX0_SCL")
		)
	)
	(footprint ""
		(layer "F.Cu")
		(at 414.273492 -186.787282)
		(property "Reference" "Q232"
			(at -4.003294 -1.501394 0)
			(unlocked yes)
			(layer "F.SilkS")
			(effects
				(font
					(size 0.7874 0.5842)
					(thickness 0.1524)
				)
			)
		)
		(property "Value" ""
			(at 0 0 0)
			(layer "F.Fab")
			(effects
				(font
					(size 1.27 1.27)
				)
			)
		)
		(duplicate_pad_numbers_are_jumpers no)
		(fp_line
			(start -1.376172 -1.199896)
			(end -0.508 -1.199896)
			(stroke
				(width 0.1524)
				(type default)
			)
			(layer "F.SilkS")
		)
		(fp_line
			(start -1.376172 1.199896)
			(end -1.376172 -1.199896)
			(stroke
				(width 0.1524)
				(type default)
			)
			(layer "F.SilkS")
		)
		(fp_line
			(start -0.508 -1.199896)
			(end 0 -0.762)
			(stroke
				(width 0.1524)
				(type default)
			)
			(layer "F.SilkS")
		)
		(fp_line
			(start 0 -0.762)
			(end 0.508 -1.199896)
			(stroke
				(width 0.1524)
				(type default)
			)
			(layer "F.SilkS")
		)
		(fp_line
			(start 0.508 -1.199896)
			(end 1.376172 -1.199896)
			(stroke
				(width 0.1524)
				(type default)
			)
			(layer "F.SilkS")
		)
		(fp_line
			(start 1.376172 -1.199896)
			(end 1.376172 1.199896)
			(stroke
				(width 0.1524)
				(type default)
			)
			(layer "F.SilkS")
		)
		(fp_line
			(start 1.376172 1.199896)
			(end -1.376172 1.199896)
			(stroke
				(width 0.1524)
				(type default)
			)
			(layer "F.SilkS")
		)
		(fp_poly
			(pts
				(xy -1.4605 -0.7493) (xy -2.2225 -1.1303) (xy -2.2225 -0.3683)
			)
			(stroke
				(width 0)
				(type default)
			)
			(fill yes)
			(layer "F.SilkS")
		)
		(fp_line
			(start -0.674878 -1.100074)
			(end 0.674878 -1.100074)
			(stroke
				(width 0.1)
				(type default)
			)
			(layer "F.Fab")
		)
		(fp_line
			(start -0.674878 1.100074)
			(end -0.674878 -1.100074)
			(stroke
				(width 0.1)
				(type default)
			)
			(layer "F.Fab")
		)
		(fp_line
			(start 0.674878 -1.100074)
			(end 0.674878 1.100074)
			(stroke
				(width 0.1)
				(type default)
			)
			(layer "F.Fab")
		)
		(fp_line
			(start 0.674878 1.100074)
			(end -0.674878 1.100074)
			(stroke
				(width 0.1)
				(type default)
			)
			(layer "F.Fab")
		)
		(fp_poly
			(pts
				(xy -1.4605 -0.7493) (xy -2.2225 -1.1303) (xy -2.2225 -0.3683)
			)
			(stroke
				(width 0)
				(type default)
			)
			(fill yes)
			(layer "F.Fab")
		)
		(pad "1" smd rect
			(at -0.899922 -0.750062 270)
			(size 0.6096 0.6096)
			(layers "F.Cu" "F.Mask" "F.Paste")
			(net "GND")
		)
		(pad "2" smd rect
			(at -0.899922 0 270)
			(size 0.4064 0.6096)
			(layers "F.Cu" "F.Mask" "F.Paste")
			(net "FPGA_PEX0_MODE_SEL2_R")
		)
		(pad "3" smd rect
			(at -0.899922 0.750062 270)
			(size 0.6096 0.6096)
			(layers "F.Cu" "F.Mask" "F.Paste")
			(net "FPGA_PEX0_MODE_SEL2_ISO")
		)
		(pad "4" smd rect
			(at 0.899922 0.750062 270)
			(size 0.6096 0.6096)
			(layers "F.Cu" "F.Mask" "F.Paste")
			(net "GND")
		)
		(pad "5" smd rect
			(at 0.899922 0 270)
			(size 0.4064 0.6096)
			(layers "F.Cu" "F.Mask" "F.Paste")
			(net "FPGA_PEX0_MODE_SEL2_D_N")
		)
		(pad "6" smd rect
			(at 0.899922 -0.750062 270)
			(size 0.6096 0.6096)
			(layers "F.Cu" "F.Mask" "F.Paste")
			(net "FPGA_PEX0_MODE_SEL2_D_N")
		)
	)
	(footprint ""
		(layer "F.Cu")
		(at 301.992284 -32.739584 180)
		(property "Reference" "C505"
			(at 0 0 180)
			(layer "F.SilkS")
			(hide yes)
			(effects
				(font
					(size 1.27 1.27)
				)
			)
		)
		(property "Value" ""
			(at 0 0 180)
			(layer "F.Fab")
			(effects
				(font
					(size 1.27 1.27)
				)
			)
		)
		(duplicate_pad_numbers_are_jumpers no)
		(fp_line
			(start 0.299974 0.150114)
			(end -0.299974 0.150114)
			(stroke
				(width 0.1)
				(type default)
			)
			(layer "F.Fab")
		)
		(fp_line
			(start 0.299974 -0.150114)
			(end 0.299974 0.150114)
			(stroke
				(width 0.1)
				(type default)
			)
			(layer "F.Fab")
		)
		(fp_line
			(start -0.299974 0.150114)
			(end -0.299974 -0.150114)
			(stroke
				(width 0.1)
				(type default)
			)
			(layer "F.Fab")
		)
		(fp_line
			(start -0.299974 -0.150114)
			(end 0.299974 -0.150114)
			(stroke
				(width 0.1)
				(type default)
			)
			(layer "F.Fab")
		)
		(pad "1" smd rect
			(at -0.2667 0 180)
			(size 0.3048 0.381)
			(layers "F.Cu" "F.Mask" "F.Paste")
			(net "P5E_PEX2_STN2_TX_DP<38>")
		)
		(pad "2" smd rect
			(at 0.2667 0 180)
			(size 0.3048 0.381)
			(layers "F.Cu" "F.Mask" "F.Paste")
			(net "P5E_PEX2_STN2_TX_C_DP<38>")
		)
	)
	(footprint ""
		(layer "F.Cu")
		(at 168.343834 -44.87291)
		(property "Reference" "R561"
			(at 0 0 0)
			(layer "F.SilkS")
			(hide yes)
			(effects
				(font
					(size 1.27 1.27)
				)
			)
		)
		(property "Value" ""
			(at 0 0 0)
			(layer "F.Fab")
			(effects
				(font
					(size 1.27 1.27)
				)
			)
		)
		(duplicate_pad_numbers_are_jumpers no)
		(fp_line
			(start -0.7874 -0.4064)
			(end 0.7874 -0.4064)
			(stroke
				(width 0.1524)
				(type default)
			)
			(layer "F.SilkS")
		)
		(fp_line
			(start -0.7874 0.4064)
			(end -0.7874 -0.4064)
			(stroke
				(width 0.1524)
				(type default)
			)
			(layer "F.SilkS")
		)
		(fp_line
			(start 0.7874 -0.4064)
			(end 0.7874 0.4064)
			(stroke
				(width 0.1524)
				(type default)
			)
			(layer "F.SilkS")
		)
		(fp_line
			(start 0.7874 0.4064)
			(end -0.7874 0.4064)
			(stroke
				(width 0.1524)
				(type default)
			)
			(layer "F.SilkS")
		)
		(fp_line
			(start -0.67945 -0.305054)
			(end -0.12065 -0.305054)
			(stroke
				(width 0.1)
				(type default)
			)
			(layer "F.Fab")
		)
		(fp_line
			(start -0.67945 0.3048)
			(end -0.67945 -0.305054)
			(stroke
				(width 0.1)
				(type default)
			)
			(layer "F.Fab")
		)
		(fp_line
			(start -0.12065 -0.305054)
			(end -0.12065 -0.2794)
			(stroke
				(width 0.1)
				(type default)
			)
			(layer "F.Fab")
		)
		(fp_line
			(start -0.12065 -0.2794)
			(end 0.12065 -0.2794)
			(stroke
				(width 0.1)
				(type default)
			)
			(layer "F.Fab")
		)
		(fp_line
			(start -0.12065 0.2794)
			(end -0.12065 0.3048)
			(stroke
				(width 0.1)
				(type default)
			)
			(layer "F.Fab")
		)
		(fp_line
			(start -0.12065 0.3048)
			(end -0.67945 0.3048)
			(stroke
				(width 0.1)
				(type default)
			)
			(layer "F.Fab")
		)
		(fp_line
			(start 0.120396 0.2794)
			(end -0.12065 0.2794)
			(stroke
				(width 0.1)
				(type default)
			)
			(layer "F.Fab")
		)
		(fp_line
			(start 0.120396 0.3048)
			(end 0.120396 0.2794)
			(stroke
				(width 0.1)
				(type default)
			)
			(layer "F.Fab")
		)
		(fp_line
			(start 0.12065 -0.3048)
			(end 0.67945 -0.3048)
			(stroke
				(width 0.1)
				(type default)
			)
			(layer "F.Fab")
		)
		(fp_line
			(start 0.12065 -0.2794)
			(end 0.12065 -0.3048)
			(stroke
				(width 0.1)
				(type default)
			)
			(layer "F.Fab")
		)
		(fp_line
			(start 0.67945 -0.3048)
			(end 0.67945 0.3048)
			(stroke
				(width 0.1)
				(type default)
			)
			(layer "F.Fab")
		)
		(fp_line
			(start 0.67945 0.3048)
			(end 0.120396 0.3048)
			(stroke
				(width 0.1)
				(type default)
			)
			(layer "F.Fab")
		)
		(pad "1" smd circle
			(at -0.40005 0)
			(size 0 0)
			(layers "F.Cu" "F.Mask" "F.Paste")
			(net "SSD5_ADC_A0")
		)
		(pad "2" smd circle
			(at 0.40005 0)
			(size 0 0)
			(layers "F.Cu" "F.Mask" "F.Paste")
			(net "P3V3_AUX")
		)
	)
	(footprint ""
		(layer "F.Cu")
		(at 249.391678 -152.71115 90)
		(property "Reference" "R724"
			(at 0 0 90)
			(layer "F.SilkS")
			(hide yes)
			(effects
				(font
					(size 1.27 1.27)
				)
			)
		)
		(property "Value" ""
			(at 0 0 90)
			(layer "F.Fab")
			(effects
				(font
					(size 1.27 1.27)
				)
			)
		)
		(duplicate_pad_numbers_are_jumpers no)
		(fp_line
			(start 0.7874 -0.4064)
			(end 0.7874 0.4064)
			(stroke
				(width 0.1524)
				(type default)
			)
			(layer "F.SilkS")
		)
		(fp_line
			(start -0.7874 -0.4064)
			(end 0.7874 -0.4064)
			(stroke
				(width 0.1524)
				(type default)
			)
			(layer "F.SilkS")
		)
		(fp_line
			(start 0.7874 0.4064)
			(end -0.7874 0.4064)
			(stroke
				(width 0.1524)
				(type default)
			)
			(layer "F.SilkS")
		)
		(fp_line
			(start -0.7874 0.4064)
			(end -0.7874 -0.4064)
			(stroke
				(width 0.1524)
				(type default)
			)
			(layer "F.SilkS")
		)
		(fp_line
			(start -0.12065 -0.305054)
			(end -0.12065 -0.2794)
			(stroke
				(width 0.1)
				(type default)
			)
			(layer "F.Fab")
		)
		(fp_line
			(start -0.67945 -0.305054)
			(end -0.12065 -0.305054)
			(stroke
				(width 0.1)
				(type default)
			)
			(layer "F.Fab")
		)
		(fp_line
			(start 0.67945 -0.3048)
			(end 0.67945 0.3048)
			(stroke
				(width 0.1)
				(type default)
			)
			(layer "F.Fab")
		)
		(fp_line
			(start 0.12065 -0.3048)
			(end 0.67945 -0.3048)
			(stroke
				(width 0.1)
				(type default)
			)
			(layer "F.Fab")
		)
		(fp_line
			(start 0.12065 -0.2794)
			(end 0.12065 -0.3048)
			(stroke
				(width 0.1)
				(type default)
			)
			(layer "F.Fab")
		)
		(fp_line
			(start -0.12065 -0.2794)
			(end 0.12065 -0.2794)
			(stroke
				(width 0.1)
				(type default)
			)
			(layer "F.Fab")
		)
		(fp_line
			(start 0.120396 0.2794)
			(end -0.12065 0.2794)
			(stroke
				(width 0.1)
				(type default)
			)
			(layer "F.Fab")
		)
		(fp_line
			(start -0.12065 0.2794)
			(end -0.12065 0.3048)
			(stroke
				(width 0.1)
				(type default)
			)
			(layer "F.Fab")
		)
		(fp_line
			(start 0.67945 0.3048)
			(end 0.120396 0.3048)
			(stroke
				(width 0.1)
				(type default)
			)
			(layer "F.Fab")
		)
		(fp_line
			(start 0.120396 0.3048)
			(end 0.120396 0.2794)
			(stroke
				(width 0.1)
				(type default)
			)
			(layer "F.Fab")
		)
		(fp_line
			(start -0.12065 0.3048)
			(end -0.67945 0.3048)
			(stroke
				(width 0.1)
				(type default)
			)
			(layer "F.Fab")
		)
		(fp_line
			(start -0.67945 0.3048)
			(end -0.67945 -0.305054)
			(stroke
				(width 0.1)
				(type default)
			)
			(layer "F.Fab")
		)
		(pad "1" smd circle
			(at -0.40005 0 90)
			(size 0 0)
			(layers "F.Cu" "F.Mask" "F.Paste")
			(net "P3V3_AUX")
		)
		(pad "2" smd circle
			(at 0.40005 0 90)
			(size 0 0)
			(layers "F.Cu" "F.Mask" "F.Paste")
			(net "NIC_ADC_ALERT_N")
		)
	)
	(footprint ""
		(layer "F.Cu")
		(at 193.916808 -410.296868 -90)
		(property "Reference" "R499"
			(at 0 0 270)
			(layer "F.SilkS")
			(hide yes)
			(effects
				(font
					(size 1.27 1.27)
				)
			)
		)
		(property "Value" ""
			(at 0 0 270)
			(layer "F.Fab")
			(effects
				(font
					(size 1.27 1.27)
				)
			)
		)
		(duplicate_pad_numbers_are_jumpers no)
		(fp_line
			(start -0.7874 0.4064)
			(end -0.7874 -0.4064)
			(stroke
				(width 0.1524)
				(type default)
			)
			(layer "F.SilkS")
		)
		(fp_line
			(start 0.7874 0.4064)
			(end -0.7874 0.4064)
			(stroke
				(width 0.1524)
				(type default)
			)
			(layer "F.SilkS")
		)
		(fp_line
			(start -0.7874 -0.4064)
			(end 0.7874 -0.4064)
			(stroke
				(width 0.1524)
				(type default)
			)
			(layer "F.SilkS")
		)
		(fp_line
			(start 0.7874 -0.4064)
			(end 0.7874 0.4064)
			(stroke
				(width 0.1524)
				(type default)
			)
			(layer "F.SilkS")
		)
		(fp_line
			(start -0.67945 0.3048)
			(end -0.67945 -0.305054)
			(stroke
				(width 0.1)
				(type default)
			)
			(layer "F.Fab")
		)
		(fp_line
			(start -0.12065 0.3048)
			(end -0.67945 0.3048)
			(stroke
				(width 0.1)
				(type default)
			)
			(layer "F.Fab")
		)
		(fp_line
			(start 0.120396 0.3048)
			(end 0.120396 0.2794)
			(stroke
				(width 0.1)
				(type default)
			)
			(layer "F.Fab")
		)
		(fp_line
			(start 0.67945 0.3048)
			(end 0.120396 0.3048)
			(stroke
				(width 0.1)
				(type default)
			)
			(layer "F.Fab")
		)
		(fp_line
			(start -0.12065 0.2794)
			(end -0.12065 0.3048)
			(stroke
				(width 0.1)
				(type default)
			)
			(layer "F.Fab")
		)
		(fp_line
			(start 0.120396 0.2794)
			(end -0.12065 0.2794)
			(stroke
				(width 0.1)
				(type default)
			)
			(layer "F.Fab")
		)
		(fp_line
			(start -0.12065 -0.2794)
			(end 0.12065 -0.2794)
			(stroke
				(width 0.1)
				(type default)
			)
			(layer "F.Fab")
		)
		(fp_line
			(start 0.12065 -0.2794)
			(end 0.12065 -0.3048)
			(stroke
				(width 0.1)
				(type default)
			)
			(layer "F.Fab")
		)
		(fp_line
			(start 0.12065 -0.3048)
			(end 0.67945 -0.3048)
			(stroke
				(width 0.1)
				(type default)
			)
			(layer "F.Fab")
		)
		(fp_line
			(start 0.67945 -0.3048)
			(end 0.67945 0.3048)
			(stroke
				(width 0.1)
				(type default)
			)
			(layer "F.Fab")
		)
		(fp_line
			(start -0.67945 -0.305054)
			(end -0.12065 -0.305054)
			(stroke
				(width 0.1)
				(type default)
			)
			(layer "F.Fab")
		)
		(fp_line
			(start -0.12065 -0.305054)
			(end -0.12065 -0.2794)
			(stroke
				(width 0.1)
				(type default)
			)
			(layer "F.Fab")
		)
		(pad "1" smd circle
			(at -0.40005 0 270)
			(size 0 0)
			(layers "F.Cu" "F.Mask" "F.Paste")
			(net "P3V3_AUX")
		)
		(pad "2" smd circle
			(at 0.40005 0 270)
			(size 0 0)
			(layers "F.Cu" "F.Mask" "F.Paste")
			(net "SMB_ALERT_HSC_R_N")
		)
	)
	(footprint ""
		(layer "F.Cu")
		(at 117.958362 -124.883926)
		(property "Reference" "PC303"
			(at 0 0 0)
			(layer "F.SilkS")
			(hide yes)
			(effects
				(font
					(size 1.27 1.27)
				)
			)
		)
		(property "Value" ""
			(at 0 0 0)
			(layer "F.Fab")
			(effects
				(font
					(size 1.27 1.27)
				)
			)
		)
		(duplicate_pad_numbers_are_jumpers no)
		(fp_line
			(start -0.7874 -0.4064)
			(end 0.7874 -0.4064)
			(stroke
				(width 0.1524)
				(type default)
			)
			(layer "F.SilkS")
		)
		(fp_line
			(start -0.7874 0.4064)
			(end -0.7874 -0.4064)
			(stroke
				(width 0.1524)
				(type default)
			)
			(layer "F.SilkS")
		)
		(fp_line
			(start 0.7874 -0.4064)
			(end 0.7874 0.4064)
			(stroke
				(width 0.1524)
				(type default)
			)
			(layer "F.SilkS")
		)
		(fp_line
			(start 0.7874 0.4064)
			(end -0.7874 0.4064)
			(stroke
				(width 0.1524)
				(type default)
			)
			(layer "F.SilkS")
		)
		(fp_line
			(start -0.67945 -0.305054)
			(end -0.12065 -0.305054)
			(stroke
				(width 0.1)
				(type default)
			)
			(layer "F.Fab")
		)
		(fp_line
			(start -0.67945 0.3048)
			(end -0.67945 -0.305054)
			(stroke
				(width 0.1)
				(type default)
			)
			(layer "F.Fab")
		)
		(fp_line
			(start -0.12065 -0.305054)
			(end -0.12065 -0.2794)
			(stroke
				(width 0.1)
				(type default)
			)
			(layer "F.Fab")
		)
		(fp_line
			(start -0.12065 -0.2794)
			(end 0.12065 -0.2794)
			(stroke
				(width 0.1)
				(type default)
			)
			(layer "F.Fab")
		)
		(fp_line
			(start -0.12065 0.2794)
			(end -0.12065 0.3048)
			(stroke
				(width 0.1)
				(type default)
			)
			(layer "F.Fab")
		)
		(fp_line
			(start -0.12065 0.3048)
			(end -0.67945 0.3048)
			(stroke
				(width 0.1)
				(type default)
			)
			(layer "F.Fab")
		)
		(fp_line
			(start 0.120396 0.2794)
			(end -0.12065 0.2794)
			(stroke
				(width 0.1)
				(type default)
			)
			(layer "F.Fab")
		)
		(fp_line
			(start 0.120396 0.3048)
			(end 0.120396 0.2794)
			(stroke
				(width 0.1)
				(type default)
			)
			(layer "F.Fab")
		)
		(fp_line
			(start 0.12065 -0.3048)
			(end 0.67945 -0.3048)
			(stroke
				(width 0.1)
				(type default)
			)
			(layer "F.Fab")
		)
		(fp_line
			(start 0.12065 -0.2794)
			(end 0.12065 -0.3048)
			(stroke
				(width 0.1)
				(type default)
			)
			(layer "F.Fab")
		)
		(fp_line
			(start 0.67945 -0.3048)
			(end 0.67945 0.3048)
			(stroke
				(width 0.1)
				(type default)
			)
			(layer "F.Fab")
		)
		(fp_line
			(start 0.67945 0.3048)
			(end 0.120396 0.3048)
			(stroke
				(width 0.1)
				(type default)
			)
			(layer "F.Fab")
		)
		(pad "1" smd circle
			(at -0.40005 0)
			(size 0 0)
			(layers "F.Cu" "F.Mask" "F.Paste")
			(net "P3V3_SS")
		)
		(pad "2" smd circle
			(at 0.40005 0)
			(size 0 0)
			(layers "F.Cu" "F.Mask" "F.Paste")
			(net "GND")
		)
	)
	(footprint ""
		(layer "F.Cu")
		(at 178.746404 -177.711862)
		(property "Reference" "U439"
			(at -1.58877 1.958594 0)
			(unlocked yes)
			(layer "F.SilkS")
			(effects
				(font
					(size 0.7874 0.5842)
					(thickness 0.1524)
				)
			)
		)
		(property "Value" ""
			(at 0 0 0)
			(layer "F.Fab")
			(effects
				(font
					(size 1.27 1.27)
				)
			)
		)
		(duplicate_pad_numbers_are_jumpers no)
		(fp_line
			(start -1.7272 1.1176)
			(end -1.7272 -1.1176)
			(stroke
				(width 0.1524)
				(type default)
			)
			(layer "F.SilkS")
		)
		(fp_line
			(start -0.254 -1.1176)
			(end -1.7272 -1.1176)
			(stroke
				(width 0.1524)
				(type default)
			)
			(layer "F.SilkS")
		)
		(fp_line
			(start 0 -0.7366)
			(end -0.254 -1.1176)
			(stroke
				(width 0.1524)
				(type default)
			)
			(layer "F.SilkS")
		)
		(fp_line
			(start 0.254 -1.1176)
			(end 0 -0.7366)
			(stroke
				(width 0.1524)
				(type default)
			)
			(layer "F.SilkS")
		)
		(fp_line
			(start 1.7272 -1.1176)
			(end 0.254 -1.1176)
			(stroke
				(width 0.1524)
				(type default)
			)
			(layer "F.SilkS")
		)
		(fp_line
			(start 1.7272 -1.1176)
			(end 1.7272 1.1176)
			(stroke
				(width 0.1524)
				(type default)
			)
			(layer "F.SilkS")
		)
		(fp_line
			(start 1.7272 1.1176)
			(end -1.7272 1.1176)
			(stroke
				(width 0.1524)
				(type default)
			)
			(layer "F.SilkS")
		)
		(fp_poly
			(pts
				(xy -1.9558 -0.649986) (xy -2.7178 -0.268986) (xy -2.7178 -1.030986)
			)
			(stroke
				(width 0)
				(type default)
			)
			(fill yes)
			(layer "F.SilkS")
		)
		(fp_line
			(start -1.5748 -1.1176)
			(end -1.5748 1.1176)
			(stroke
				(width 0.1)
				(type default)
			)
			(layer "F.Fab")
		)
		(fp_line
			(start -1.5748 1.1176)
			(end 1.5748 1.1176)
			(stroke
				(width 0.1)
				(type default)
			)
			(layer "F.Fab")
		)
		(fp_line
			(start 1.5748 -1.1176)
			(end -1.5748 -1.1176)
			(stroke
				(width 0.1)
				(type default)
			)
			(layer "F.Fab")
		)
		(fp_line
			(start 1.5748 1.1176)
			(end 1.5748 -1.1176)
			(stroke
				(width 0.1)
				(type default)
			)
			(layer "F.Fab")
		)
		(fp_poly
			(pts
				(xy -1.9558 -0.649986) (xy -2.7178 -0.268986) (xy -2.7178 -1.030986)
			)
			(stroke
				(width 0)
				(type default)
			)
			(fill yes)
			(layer "F.Fab")
		)
		(pad "1" smd rect
			(at -0.999998 -0.649986 270)
			(size 0.3556 1.1176)
			(layers "F.Cu" "F.Mask" "F.Paste")
			(net "NIC2_CLK_EN_R_N")
		)
		(pad "2" smd rect
			(at -0.999998 0 270)
			(size 0.3556 1.1176)
			(layers "F.Cu" "F.Mask" "F.Paste")
			(net "GND")
		)
		(pad "3" smd rect
			(at -0.999998 0.649986 270)
			(size 0.3556 1.1176)
			(layers "F.Cu" "F.Mask" "F.Paste")
			(net "NIC3_CLK_EN_R_N")
		)
		(pad "4" smd rect
			(at 0.999998 0.649986 270)
			(size 0.3556 1.1176)
			(layers "F.Cu" "F.Mask" "F.Paste")
			(net "NIC3_CLK_EN_BUF_N")
		)
		(pad "5" smd rect
			(at 0.999998 0 270)
			(size 0.3556 1.1176)
			(layers "F.Cu" "F.Mask" "F.Paste")
			(net "P3V3_AUX")
		)
		(pad "6" smd rect
			(at 0.999998 -0.649986 270)
			(size 0.3556 1.1176)
			(layers "F.Cu" "F.Mask" "F.Paste")
			(net "NIC2_CLK_EN_BUF_N")
		)
	)
	(footprint ""
		(layer "F.Cu")
		(at 47.319946 -127.700024)
		(property "Reference" "J20"
			(at -5.307076 34.685224 90)
			(unlocked yes)
			(layer "F.SilkS")
			(effects
				(font
					(size 0.7874 0.5842)
					(thickness 0.1524)
				)
				(justify left)
			)
		)
		(property "Value" ""
			(at 0 0 0)
			(layer "F.Fab")
			(effects
				(font
					(size 1.27 1.27)
				)
			)
		)
		(duplicate_pad_numbers_are_jumpers no)
		(fp_line
			(start -4.507484 34.720022)
			(end -0.5588 34.720022)
			(stroke
				(width 0.1524)
				(type default)
			)
			(layer "F.SilkS")
		)
		(fp_line
			(start -0.57658 -34.720022)
			(end -4.507484 -34.720022)
			(stroke
				(width 0.1524)
				(type default)
			)
			(layer "F.SilkS")
		)
		(fp_line
			(start 2.6035 34.720022)
			(end 4.507484 34.720022)
			(stroke
				(width 0.1524)
				(type default)
			)
			(layer "F.SilkS")
		)
		(fp_line
			(start 4.507484 -34.720022)
			(end 2.6162 -34.720022)
			(stroke
				(width 0.1524)
				(type default)
			)
			(layer "F.SilkS")
		)
		(fp_line
			(start 4.507484 -21.5265)
			(end 4.507484 -34.720022)
			(stroke
				(width 0.1524)
				(type default)
			)
			(layer "F.SilkS")
		)
		(fp_poly
			(pts
				(xy 5.735574 -17.957038) (xy 5.735574 -18.973038) (xy 4.719574 -18.465038)
			)
			(stroke
				(width 0)
				(type default)
			)
			(fill yes)
			(layer "F.SilkS")
		)
		(fp_line
			(start -4.507484 -34.720022)
			(end -4.507484 34.720022)
			(stroke
				(width 0.1)
				(type default)
			)
			(layer "F.Fab")
		)
		(fp_line
			(start -4.507484 34.720022)
			(end 4.507484 34.720022)
			(stroke
				(width 0.1)
				(type default)
			)
			(layer "F.Fab")
		)
		(fp_line
			(start 4.507484 -34.720022)
			(end -4.507484 -34.720022)
			(stroke
				(width 0.1)
				(type default)
			)
			(layer "F.Fab")
		)
		(fp_line
			(start 4.507484 34.720022)
			(end 4.507484 -34.720022)
			(stroke
				(width 0.1)
				(type default)
			)
			(layer "F.Fab")
		)
		(fp_poly
			(pts
				(xy 5.735574 -17.957038) (xy 5.735574 -18.973038) (xy 4.719574 -18.465038)
			)
			(stroke
				(width 0)
				(type default)
			)
			(fill yes)
			(layer "F.Fab")
		)
		(pad "" np_thru_hole circle
			(at -0.727456 -32.485076)
			(size 1.1176 1.1176)
			(drill 1.1176)
			(layers "*.Cu" "*.Mask")
			(clearance 0.381)
			(thermal_gap 0.381)
		)
		(pad "" np_thru_hole circle
			(at 1.022604 32.485076)
			(size 1.1176 1.1176)
			(drill 1.1176)
			(layers "*.Cu" "*.Mask")
			(clearance 0.381)
			(thermal_gap 0.381)
		)
		(pad "A1" smd rect
			(at 3.322574 -18.465038 270)
			(size 0.3556 1.2192)
			(layers "F.Cu" "F.Mask" "F.Paste")
			(net "GND")
		)
		(pad "A2" smd rect
			(at 3.322574 -17.86509 270)
			(size 0.3556 1.2192)
			(layers "F.Cu" "F.Mask" "F.Paste")
			(net "GND")
		)
		(pad "A3" smd rect
			(at 3.322574 -17.264888 270)
			(size 0.3556 1.2192)
			(layers "F.Cu" "F.Mask" "F.Paste")
			(net "GND")
		)
		(pad "A4" smd rect
			(at 3.322574 -16.66494 270)
			(size 0.3556 1.2192)
			(layers "F.Cu" "F.Mask" "F.Paste")
			(net "GND")
		)
		(pad "A5" smd rect
			(at 3.322574 -16.064992 270)
			(size 0.3556 1.2192)
			(layers "F.Cu" "F.Mask" "F.Paste")
			(net "GND")
		)
		(pad "A6" smd rect
			(at 3.322574 -15.465044 270)
			(size 0.3556 1.2192)
			(layers "F.Cu" "F.Mask" "F.Paste")
			(net "GND")
		)
		(pad "A7" smd rect
			(at 3.322574 -14.865096 270)
			(size 0.3556 1.2192)
			(layers "F.Cu" "F.Mask" "F.Paste")
			(net "SMB_NIC0_R_SCL")
		)
		(pad "A8" smd rect
			(at 3.322574 -14.264894 270)
			(size 0.3556 1.2192)
			(layers "F.Cu" "F.Mask" "F.Paste")
			(net "SMB_NIC0_R_SDA")
		)
		(pad "A9" smd rect
			(at 3.322574 -13.664946 270)
			(size 0.3556 1.2192)
			(layers "F.Cu" "F.Mask" "F.Paste")
			(net "RST_SMB_NIC0_MUX_ISO_R_N")
		)
		(pad "A10" smd rect
			(at 3.322574 -13.064998 270)
			(size 0.3556 1.2192)
			(layers "F.Cu" "F.Mask" "F.Paste")
			(net "GND")
		)
		(pad "A11" smd rect
			(at 3.322574 -12.46505 270)
			(size 0.3556 1.2192)
			(layers "F.Cu" "F.Mask" "F.Paste")
			(net "RST_NIC0_PERST1_R_N")
		)
		(pad "A12" smd rect
			(at 3.322574 -11.865102 270)
			(size 0.3556 1.2192)
			(layers "F.Cu" "F.Mask" "F.Paste")
			(net "PRSNTB2_NIC0_N")
		)
		(pad "A13" smd rect
			(at 3.322574 -11.2649 270)
			(size 0.3556 1.2192)
			(layers "F.Cu" "F.Mask" "F.Paste")
			(net "GND")
		)
		(pad "A14" smd rect
			(at 3.322574 -10.664952 270)
			(size 0.3556 1.2192)
			(layers "F.Cu" "F.Mask" "F.Paste")
			(net "Net_2575")
		)
		(pad "A15" smd rect
			(at 3.322574 -10.065004 270)
			(size 0.3556 1.2192)
			(layers "F.Cu" "F.Mask" "F.Paste")
			(net "Net_2578")
		)
		(pad "A16" smd rect
			(at 3.322574 -9.465056 270)
			(size 0.3556 1.2192)
			(layers "F.Cu" "F.Mask" "F.Paste")
			(net "GND")
		)
		(pad "A17" smd rect
			(at 3.322574 -8.865108 270)
			(size 0.3556 1.2192)
			(layers "F.Cu" "F.Mask" "F.Paste")
			(net "P5E_PEX0_STN1_RX_DN<31>")
		)
		(pad "A18" smd rect
			(at 3.322574 -8.264906 270)
			(size 0.3556 1.2192)
			(layers "F.Cu" "F.Mask" "F.Paste")
			(net "P5E_PEX0_STN1_RX_DP<31>")
		)
		(pad "A19" smd rect
			(at 3.322574 -7.664958 270)
			(size 0.3556 1.2192)
			(layers "F.Cu" "F.Mask" "F.Paste")
			(net "GND")
		)
		(pad "A20" smd rect
			(at 3.322574 -7.06501 270)
			(size 0.3556 1.2192)
			(layers "F.Cu" "F.Mask" "F.Paste")
			(net "P5E_PEX0_STN1_RX_DN<30>")
		)
		(pad "A21" smd rect
			(at 3.322574 -6.465062 270)
			(size 0.3556 1.2192)
			(layers "F.Cu" "F.Mask" "F.Paste")
			(net "P5E_PEX0_STN1_RX_DP<30>")
		)
		(pad "A22" smd rect
			(at 3.322574 -5.865114 270)
			(size 0.3556 1.2192)
			(layers "F.Cu" "F.Mask" "F.Paste")
			(net "GND")
		)
		(pad "A23" smd rect
			(at 3.322574 -5.264912 270)
			(size 0.3556 1.2192)
			(layers "F.Cu" "F.Mask" "F.Paste")
			(net "P5E_PEX0_STN1_RX_DN<29>")
		)
		(pad "A24" smd rect
			(at 3.322574 -4.664964 270)
			(size 0.3556 1.2192)
			(layers "F.Cu" "F.Mask" "F.Paste")
			(net "P5E_PEX0_STN1_RX_DP<29>")
		)
		(pad "A25" smd rect
			(at 3.322574 -4.065016 270)
			(size 0.3556 1.2192)
			(layers "F.Cu" "F.Mask" "F.Paste")
			(net "GND")
		)
		(pad "A26" smd rect
			(at 3.322574 -3.465068 270)
			(size 0.3556 1.2192)
			(layers "F.Cu" "F.Mask" "F.Paste")
			(net "P5E_PEX0_STN1_RX_DN<28>")
		)
		(pad "A27" smd rect
			(at 3.322574 -2.86512 270)
			(size 0.3556 1.2192)
			(layers "F.Cu" "F.Mask" "F.Paste")
			(net "P5E_PEX0_STN1_RX_DP<28>")
		)
		(pad "A28" smd rect
			(at 3.322574 -2.264918 270)
			(size 0.3556 1.2192)
			(layers "F.Cu" "F.Mask" "F.Paste")
			(net "GND")
		)
		(pad "A29" smd rect
			(at 3.322574 1.74498 270)
			(size 0.3556 1.2192)
			(layers "F.Cu" "F.Mask" "F.Paste")
			(net "GND")
		)
		(pad "A30" smd rect
			(at 3.322574 2.344928 270)
			(size 0.3556 1.2192)
			(layers "F.Cu" "F.Mask" "F.Paste")
			(net "P5E_PEX0_STN1_RX_DN<27>")
		)
		(pad "A31" smd rect
			(at 3.322574 2.944876 270)
			(size 0.3556 1.2192)
			(layers "F.Cu" "F.Mask" "F.Paste")
			(net "P5E_PEX0_STN1_RX_DP<27>")
		)
		(pad "A32" smd rect
			(at 3.322574 3.545078 270)
			(size 0.3556 1.2192)
			(layers "F.Cu" "F.Mask" "F.Paste")
			(net "GND")
		)
		(pad "A33" smd rect
			(at 3.322574 4.145026 270)
			(size 0.3556 1.2192)
			(layers "F.Cu" "F.Mask" "F.Paste")
			(net "P5E_PEX0_STN1_RX_DN<26>")
		)
		(pad "A34" smd rect
			(at 3.322574 4.744974 270)
			(size 0.3556 1.2192)
			(layers "F.Cu" "F.Mask" "F.Paste")
			(net "P5E_PEX0_STN1_RX_DP<26>")
		)
		(pad "A35" smd rect
			(at 3.322574 5.344922 270)
			(size 0.3556 1.2192)
			(layers "F.Cu" "F.Mask" "F.Paste")
			(net "GND")
		)
		(pad "A36" smd rect
			(at 3.322574 5.945124 270)
			(size 0.3556 1.2192)
			(layers "F.Cu" "F.Mask" "F.Paste")
			(net "P5E_PEX0_STN1_RX_DN<25>")
		)
		(pad "A37" smd rect
			(at 3.322574 6.545072 270)
			(size 0.3556 1.2192)
			(layers "F.Cu" "F.Mask" "F.Paste")
			(net "P5E_PEX0_STN1_RX_DP<25>")
		)
		(pad "A38" smd rect
			(at 3.322574 7.14502 270)
			(size 0.3556 1.2192)
			(layers "F.Cu" "F.Mask" "F.Paste")
			(net "GND")
		)
		(pad "A39" smd rect
			(at 3.322574 7.744968 270)
			(size 0.3556 1.2192)
			(layers "F.Cu" "F.Mask" "F.Paste")
			(net "P5E_PEX0_STN1_RX_DN<24>")
		)
		(pad "A40" smd rect
			(at 3.322574 8.344916 270)
			(size 0.3556 1.2192)
			(layers "F.Cu" "F.Mask" "F.Paste")
			(net "P5E_PEX0_STN1_RX_DP<24>")
		)
		(pad "A41" smd rect
			(at 3.322574 8.945118 270)
			(size 0.3556 1.2192)
			(layers "F.Cu" "F.Mask" "F.Paste")
			(net "GND")
		)
		(pad "A42" smd rect
			(at 3.322574 9.545066 270)
			(size 0.3556 1.2192)
			(layers "F.Cu" "F.Mask" "F.Paste")
			(net "PRSNTB1_NIC0_N")
		)
		(pad "A43" smd rect
			(at 3.322574 14.454886 270)
			(size 0.3556 1.2192)
			(layers "F.Cu" "F.Mask" "F.Paste")
			(net "GND")
		)
		(pad "A44" smd rect
			(at 3.322574 15.055088 270)
			(size 0.3556 1.2192)
			(layers "F.Cu" "F.Mask" "F.Paste")
			(net "P5E_PEX0_STN1_RX_DN<23>")
		)
		(pad "A45" smd rect
			(at 3.322574 15.655036 270)
			(size 0.3556 1.2192)
			(layers "F.Cu" "F.Mask" "F.Paste")
			(net "P5E_PEX0_STN1_RX_DP<23>")
		)
		(pad "A46" smd rect
			(at 3.322574 16.254984 270)
			(size 0.3556 1.2192)
			(layers "F.Cu" "F.Mask" "F.Paste")
			(net "GND")
		)
		(pad "A47" smd rect
			(at 3.322574 16.854932 270)
			(size 0.3556 1.2192)
			(layers "F.Cu" "F.Mask" "F.Paste")
			(net "P5E_PEX0_STN1_RX_DN<22>")
		)
		(pad "A48" smd rect
			(at 3.322574 17.45488 270)
			(size 0.3556 1.2192)
			(layers "F.Cu" "F.Mask" "F.Paste")
			(net "P5E_PEX0_STN1_RX_DP<22>")
		)
		(pad "A49" smd rect
			(at 3.322574 18.055082 270)
			(size 0.3556 1.2192)
			(layers "F.Cu" "F.Mask" "F.Paste")
			(net "GND")
		)
		(pad "A50" smd rect
			(at 3.322574 18.65503 270)
			(size 0.3556 1.2192)
			(layers "F.Cu" "F.Mask" "F.Paste")
			(net "P5E_PEX0_STN1_RX_DN<21>")
		)
		(pad "A51" smd rect
			(at 3.322574 19.254978 270)
			(size 0.3556 1.2192)
			(layers "F.Cu" "F.Mask" "F.Paste")
			(net "P5E_PEX0_STN1_RX_DP<21>")
		)
		(pad "A52" smd rect
			(at 3.322574 19.854926 270)
			(size 0.3556 1.2192)
			(layers "F.Cu" "F.Mask" "F.Paste")
			(net "GND")
		)
		(pad "A53" smd rect
			(at 3.322574 20.455128 270)
			(size 0.3556 1.2192)
			(layers "F.Cu" "F.Mask" "F.Paste")
			(net "P5E_PEX0_STN1_RX_DN<20>")
		)
		(pad "A54" smd rect
			(at 3.322574 21.055076 270)
			(size 0.3556 1.2192)
			(layers "F.Cu" "F.Mask" "F.Paste")
			(net "P5E_PEX0_STN1_RX_DP<20>")
		)
		(pad "A55" smd rect
			(at 3.322574 21.655024 270)
			(size 0.3556 1.2192)
			(layers "F.Cu" "F.Mask" "F.Paste")
			(net "GND")
		)
		(pad "A56" smd rect
			(at 3.322574 22.254972 270)
			(size 0.3556 1.2192)
			(layers "F.Cu" "F.Mask" "F.Paste")
			(net "P5E_PEX0_STN1_RX_DN<19>")
		)
		(pad "A57" smd rect
			(at 3.322574 22.85492 270)
			(size 0.3556 1.2192)
			(layers "F.Cu" "F.Mask" "F.Paste")
			(net "P5E_PEX0_STN1_RX_DP<19>")
		)
		(pad "A58" smd rect
			(at 3.322574 23.455122 270)
			(size 0.3556 1.2192)
			(layers "F.Cu" "F.Mask" "F.Paste")
			(net "GND")
		)
		(pad "A59" smd rect
			(at 3.322574 24.05507 270)
			(size 0.3556 1.2192)
			(layers "F.Cu" "F.Mask" "F.Paste")
			(net "P5E_PEX0_STN1_RX_DN<18>")
		)
		(pad "A60" smd rect
			(at 3.322574 24.655018 270)
			(size 0.3556 1.2192)
			(layers "F.Cu" "F.Mask" "F.Paste")
			(net "P5E_PEX0_STN1_RX_DP<18>")
		)
		(pad "A61" smd rect
			(at 3.322574 25.254966 270)
			(size 0.3556 1.2192)
			(layers "F.Cu" "F.Mask" "F.Paste")
			(net "GND")
		)
		(pad "A62" smd rect
			(at 3.322574 25.854914 270)
			(size 0.3556 1.2192)
			(layers "F.Cu" "F.Mask" "F.Paste")
			(net "P5E_PEX0_STN1_RX_DN<17>")
		)
		(pad "A63" smd rect
			(at 3.322574 26.455116 270)
			(size 0.3556 1.2192)
			(layers "F.Cu" "F.Mask" "F.Paste")
			(net "P5E_PEX0_STN1_RX_DP<17>")
		)
		(pad "A64" smd rect
			(at 3.322574 27.055064 270)
			(size 0.3556 1.2192)
			(layers "F.Cu" "F.Mask" "F.Paste")
			(net "GND")
		)
		(pad "A65" smd rect
			(at 3.322574 27.655012 270)
			(size 0.3556 1.2192)
			(layers "F.Cu" "F.Mask" "F.Paste")
			(net "P5E_PEX0_STN1_RX_DN<16>")
		)
		(pad "A66" smd rect
			(at 3.322574 28.25496 270)
			(size 0.3556 1.2192)
			(layers "F.Cu" "F.Mask" "F.Paste")
			(net "P5E_PEX0_STN1_RX_DP<16>")
		)
		(pad "A67" smd rect
			(at 3.322574 28.854908 270)
			(size 0.3556 1.2192)
			(layers "F.Cu" "F.Mask" "F.Paste")
			(net "GND")
		)
		(pad "A68" smd rect
			(at 3.322574 29.45511 270)
			(size 0.3556 1.2192)
			(layers "F.Cu" "F.Mask" "F.Paste")
			(net "Net_2583")
		)
		(pad "A69" smd rect
			(at 3.322574 30.055058 270)
			(size 0.3556 1.2192)
			(layers "F.Cu" "F.Mask" "F.Paste")
			(net "Net_2584")
		)
		(pad "A70" smd rect
			(at 3.322574 30.655006 270)
			(size 0.3556 1.2192)
			(layers "F.Cu" "F.Mask" "F.Paste")
			(net "NIC0_PWRBRK_R_N")
		)
		(pad "B1" smd rect
			(at -1.27762 -18.465038 270)
			(size 0.3556 1.2192)
			(layers "F.Cu" "F.Mask" "F.Paste")
			(net "P12V_NIC0")
		)
		(pad "B2" smd rect
			(at -1.27762 -17.86509 270)
			(size 0.3556 1.2192)
			(layers "F.Cu" "F.Mask" "F.Paste")
			(net "P12V_NIC0")
		)
		(pad "B3" smd rect
			(at -1.27762 -17.264888 270)
			(size 0.3556 1.2192)
			(layers "F.Cu" "F.Mask" "F.Paste")
			(net "P12V_NIC0")
		)
		(pad "B4" smd rect
			(at -1.27762 -16.66494 270)
			(size 0.3556 1.2192)
			(layers "F.Cu" "F.Mask" "F.Paste")
			(net "P12V_NIC0")
		)
		(pad "B5" smd rect
			(at -1.27762 -16.064992 270)
			(size 0.3556 1.2192)
			(layers "F.Cu" "F.Mask" "F.Paste")
			(net "P12V_NIC0")
		)
		(pad "B6" smd rect
			(at -1.27762 -15.465044 270)
			(size 0.3556 1.2192)
			(layers "F.Cu" "F.Mask" "F.Paste")
			(net "P12V_NIC0")
		)
		(pad "B7" smd rect
			(at -1.27762 -14.865096 270)
			(size 0.3556 1.2192)
			(layers "F.Cu" "F.Mask" "F.Paste")
			(net "NIC0_BIF0_N")
		)
		(pad "B8" smd rect
			(at -1.27762 -14.264894 270)
			(size 0.3556 1.2192)
			(layers "F.Cu" "F.Mask" "F.Paste")
			(net "NIC0_BIF1_N")
		)
		(pad "B9" smd rect
			(at -1.27762 -13.664946 270)
			(size 0.3556 1.2192)
			(layers "F.Cu" "F.Mask" "F.Paste")
			(net "NIC0_BIF2_N")
		)
		(pad "B10" smd rect
			(at -1.27762 -13.064998 270)
			(size 0.3556 1.2192)
			(layers "F.Cu" "F.Mask" "F.Paste")
			(net "RST_NIC0_PERST0_R_N")
		)
		(pad "B11" smd rect
			(at -1.27762 -12.46505 270)
			(size 0.3556 1.2192)
			(layers "F.Cu" "F.Mask" "F.Paste")
			(net "P3V3_NIC0")
		)
		(pad "B12" smd rect
			(at -1.27762 -11.865102 270)
			(size 0.3556 1.2192)
			(layers "F.Cu" "F.Mask" "F.Paste")
			(net "NIC0_AUX_PWR_EN_R")
		)
		(pad "B13" smd rect
			(at -1.27762 -11.2649 270)
			(size 0.3556 1.2192)
			(layers "F.Cu" "F.Mask" "F.Paste")
			(net "GND")
		)
		(pad "B14" smd rect
			(at -1.27762 -10.664952 270)
			(size 0.3556 1.2192)
			(layers "F.Cu" "F.Mask" "F.Paste")
			(net "CLK_100M_DB2000QL_NIC0_R_DN")
		)
		(pad "B15" smd rect
			(at -1.27762 -10.065004 270)
			(size 0.3556 1.2192)
			(layers "F.Cu" "F.Mask" "F.Paste")
			(net "CLK_100M_DB2000QL_NIC0_R_DP")
		)
		(pad "B16" smd rect
			(at -1.27762 -9.465056 270)
			(size 0.3556 1.2192)
			(layers "F.Cu" "F.Mask" "F.Paste")
			(net "GND")
		)
		(pad "B17" smd rect
			(at -1.27762 -8.865108 270)
			(size 0.3556 1.2192)
			(layers "F.Cu" "F.Mask" "F.Paste")
			(net "P5E_PEX0_STN1_TX_C_DP<31>")
		)
		(pad "B18" smd rect
			(at -1.27762 -8.264906 270)
			(size 0.3556 1.2192)
			(layers "F.Cu" "F.Mask" "F.Paste")
			(net "P5E_PEX0_STN1_TX_C_DN<31>")
		)
		(pad "B19" smd rect
			(at -1.27762 -7.664958 270)
			(size 0.3556 1.2192)
			(layers "F.Cu" "F.Mask" "F.Paste")
			(net "GND")
		)
		(pad "B20" smd rect
			(at -1.27762 -7.06501 270)
			(size 0.3556 1.2192)
			(layers "F.Cu" "F.Mask" "F.Paste")
			(net "P5E_PEX0_STN1_TX_C_DN<30>")
		)
		(pad "B21" smd rect
			(at -1.27762 -6.465062 270)
			(size 0.3556 1.2192)
			(layers "F.Cu" "F.Mask" "F.Paste")
			(net "P5E_PEX0_STN1_TX_C_DP<30>")
		)
		(pad "B22" smd rect
			(at -1.27762 -5.865114 270)
			(size 0.3556 1.2192)
			(layers "F.Cu" "F.Mask" "F.Paste")
			(net "GND")
		)
		(pad "B23" smd rect
			(at -1.27762 -5.264912 270)
			(size 0.3556 1.2192)
			(layers "F.Cu" "F.Mask" "F.Paste")
			(net "P5E_PEX0_STN1_TX_C_DP<29>")
		)
		(pad "B24" smd rect
			(at -1.27762 -4.664964 270)
			(size 0.3556 1.2192)
			(layers "F.Cu" "F.Mask" "F.Paste")
			(net "P5E_PEX0_STN1_TX_C_DN<29>")
		)
		(pad "B25" smd rect
			(at -1.27762 -4.065016 270)
			(size 0.3556 1.2192)
			(layers "F.Cu" "F.Mask" "F.Paste")
			(net "GND")
		)
		(pad "B26" smd rect
			(at -1.27762 -3.465068 270)
			(size 0.3556 1.2192)
			(layers "F.Cu" "F.Mask" "F.Paste")
			(net "P5E_PEX0_STN1_TX_C_DN<28>")
		)
		(pad "B27" smd rect
			(at -1.27762 -2.86512 270)
			(size 0.3556 1.2192)
			(layers "F.Cu" "F.Mask" "F.Paste")
			(net "P5E_PEX0_STN1_TX_C_DP<28>")
		)
		(pad "B28" smd rect
			(at -1.27762 -2.264918 270)
			(size 0.3556 1.2192)
			(layers "F.Cu" "F.Mask" "F.Paste")
			(net "GND")
		)
		(pad "B29" smd rect
			(at -1.27762 1.74498 270)
			(size 0.3556 1.2192)
			(layers "F.Cu" "F.Mask" "F.Paste")
			(net "GND")
		)
		(pad "B30" smd rect
			(at -1.27762 2.344928 270)
			(size 0.3556 1.2192)
			(layers "F.Cu" "F.Mask" "F.Paste")
			(net "P5E_PEX0_STN1_TX_C_DP<27>")
		)
		(pad "B31" smd rect
			(at -1.27762 2.944876 270)
			(size 0.3556 1.2192)
			(layers "F.Cu" "F.Mask" "F.Paste")
			(net "P5E_PEX0_STN1_TX_C_DN<27>")
		)
		(pad "B32" smd rect
			(at -1.27762 3.545078 270)
			(size 0.3556 1.2192)
			(layers "F.Cu" "F.Mask" "F.Paste")
			(net "GND")
		)
		(pad "B33" smd rect
			(at -1.27762 4.145026 270)
			(size 0.3556 1.2192)
			(layers "F.Cu" "F.Mask" "F.Paste")
			(net "P5E_PEX0_STN1_TX_C_DN<26>")
		)
		(pad "B34" smd rect
			(at -1.27762 4.744974 270)
			(size 0.3556 1.2192)
			(layers "F.Cu" "F.Mask" "F.Paste")
			(net "P5E_PEX0_STN1_TX_C_DP<26>")
		)
		(pad "B35" smd rect
			(at -1.27762 5.344922 270)
			(size 0.3556 1.2192)
			(layers "F.Cu" "F.Mask" "F.Paste")
			(net "GND")
		)
		(pad "B36" smd rect
			(at -1.27762 5.945124 270)
			(size 0.3556 1.2192)
			(layers "F.Cu" "F.Mask" "F.Paste")
			(net "P5E_PEX0_STN1_TX_C_DP<25>")
		)
		(pad "B37" smd rect
			(at -1.27762 6.545072 270)
			(size 0.3556 1.2192)
			(layers "F.Cu" "F.Mask" "F.Paste")
			(net "P5E_PEX0_STN1_TX_C_DN<25>")
		)
		(pad "B38" smd rect
			(at -1.27762 7.14502 270)
			(size 0.3556 1.2192)
			(layers "F.Cu" "F.Mask" "F.Paste")
			(net "GND")
		)
		(pad "B39" smd rect
			(at -1.27762 7.744968 270)
			(size 0.3556 1.2192)
			(layers "F.Cu" "F.Mask" "F.Paste")
			(net "P5E_PEX0_STN1_TX_C_DN<24>")
		)
		(pad "B40" smd rect
			(at -1.27762 8.344916 270)
			(size 0.3556 1.2192)
			(layers "F.Cu" "F.Mask" "F.Paste")
			(net "P5E_PEX0_STN1_TX_C_DP<24>")
		)
		(pad "B41" smd rect
			(at -1.27762 8.945118 270)
			(size 0.3556 1.2192)
			(layers "F.Cu" "F.Mask" "F.Paste")
			(net "GND")
		)
		(pad "B42" smd rect
			(at -1.27762 9.545066 270)
			(size 0.3556 1.2192)
			(layers "F.Cu" "F.Mask" "F.Paste")
			(net "PRSNTB0_NIC0_N")
		)
		(pad "B43" smd rect
			(at -1.27762 14.454886 270)
			(size 0.3556 1.2192)
			(layers "F.Cu" "F.Mask" "F.Paste")
			(net "GND")
		)
		(pad "B44" smd rect
			(at -1.27762 15.055088 270)
			(size 0.3556 1.2192)
			(layers "F.Cu" "F.Mask" "F.Paste")
			(net "P5E_PEX0_STN1_TX_C_DP<23>")
		)
		(pad "B45" smd rect
			(at -1.27762 15.655036 270)
			(size 0.3556 1.2192)
			(layers "F.Cu" "F.Mask" "F.Paste")
			(net "P5E_PEX0_STN1_TX_C_DN<23>")
		)
		(pad "B46" smd rect
			(at -1.27762 16.254984 270)
			(size 0.3556 1.2192)
			(layers "F.Cu" "F.Mask" "F.Paste")
			(net "GND")
		)
		(pad "B47" smd rect
			(at -1.27762 16.854932 270)
			(size 0.3556 1.2192)
			(layers "F.Cu" "F.Mask" "F.Paste")
			(net "P5E_PEX0_STN1_TX_C_DN<22>")
		)
		(pad "B48" smd rect
			(at -1.27762 17.45488 270)
			(size 0.3556 1.2192)
			(layers "F.Cu" "F.Mask" "F.Paste")
			(net "P5E_PEX0_STN1_TX_C_DP<22>")
		)
		(pad "B49" smd rect
			(at -1.27762 18.055082 270)
			(size 0.3556 1.2192)
			(layers "F.Cu" "F.Mask" "F.Paste")
			(net "GND")
		)
		(pad "B50" smd rect
			(at -1.27762 18.65503 270)
			(size 0.3556 1.2192)
			(layers "F.Cu" "F.Mask" "F.Paste")
			(net "P5E_PEX0_STN1_TX_C_DP<21>")
		)
		(pad "B51" smd rect
			(at -1.27762 19.254978 270)
			(size 0.3556 1.2192)
			(layers "F.Cu" "F.Mask" "F.Paste")
			(net "P5E_PEX0_STN1_TX_C_DN<21>")
		)
		(pad "B52" smd rect
			(at -1.27762 19.854926 270)
			(size 0.3556 1.2192)
			(layers "F.Cu" "F.Mask" "F.Paste")
			(net "GND")
		)
		(pad "B53" smd rect
			(at -1.27762 20.455128 270)
			(size 0.3556 1.2192)
			(layers "F.Cu" "F.Mask" "F.Paste")
			(net "P5E_PEX0_STN1_TX_C_DN<20>")
		)
		(pad "B54" smd rect
			(at -1.27762 21.055076 270)
			(size 0.3556 1.2192)
			(layers "F.Cu" "F.Mask" "F.Paste")
			(net "P5E_PEX0_STN1_TX_C_DP<20>")
		)
		(pad "B55" smd rect
			(at -1.27762 21.655024 270)
			(size 0.3556 1.2192)
			(layers "F.Cu" "F.Mask" "F.Paste")
			(net "GND")
		)
		(pad "B56" smd rect
			(at -1.27762 22.254972 270)
			(size 0.3556 1.2192)
			(layers "F.Cu" "F.Mask" "F.Paste")
			(net "P5E_PEX0_STN1_TX_C_DP<19>")
		)
		(pad "B57" smd rect
			(at -1.27762 22.85492 270)
			(size 0.3556 1.2192)
			(layers "F.Cu" "F.Mask" "F.Paste")
			(net "P5E_PEX0_STN1_TX_C_DN<19>")
		)
		(pad "B58" smd rect
			(at -1.27762 23.455122 270)
			(size 0.3556 1.2192)
			(layers "F.Cu" "F.Mask" "F.Paste")
			(net "GND")
		)
		(pad "B59" smd rect
			(at -1.27762 24.05507 270)
			(size 0.3556 1.2192)
			(layers "F.Cu" "F.Mask" "F.Paste")
			(net "P5E_PEX0_STN1_TX_C_DN<18>")
		)
		(pad "B60" smd rect
			(at -1.27762 24.655018 270)
			(size 0.3556 1.2192)
			(layers "F.Cu" "F.Mask" "F.Paste")
			(net "P5E_PEX0_STN1_TX_C_DP<18>")
		)
		(pad "B61" smd rect
			(at -1.27762 25.254966 270)
			(size 0.3556 1.2192)
			(layers "F.Cu" "F.Mask" "F.Paste")
			(net "GND")
		)
		(pad "B62" smd rect
			(at -1.27762 25.854914 270)
			(size 0.3556 1.2192)
			(layers "F.Cu" "F.Mask" "F.Paste")
			(net "P5E_PEX0_STN1_TX_C_DP<17>")
		)
		(pad "B63" smd rect
			(at -1.27762 26.455116 270)
			(size 0.3556 1.2192)
			(layers "F.Cu" "F.Mask" "F.Paste")
			(net "P5E_PEX0_STN1_TX_C_DN<17>")
		)
		(pad "B64" smd rect
			(at -1.27762 27.055064 270)
			(size 0.3556 1.2192)
			(layers "F.Cu" "F.Mask" "F.Paste")
			(net "GND")
		)
		(pad "B65" smd rect
			(at -1.27762 27.655012 270)
			(size 0.3556 1.2192)
			(layers "F.Cu" "F.Mask" "F.Paste")
			(net "P5E_PEX0_STN1_TX_C_DN<16>")
		)
		(pad "B66" smd rect
			(at -1.27762 28.25496 270)
			(size 0.3556 1.2192)
			(layers "F.Cu" "F.Mask" "F.Paste")
			(net "P5E_PEX0_STN1_TX_C_DP<16>")
		)
		(pad "B67" smd rect
			(at -1.27762 28.854908 270)
			(size 0.3556 1.2192)
			(layers "F.Cu" "F.Mask" "F.Paste")
			(net "GND")
		)
		(pad "B68" smd rect
			(at -1.27762 29.45511 270)
			(size 0.3556 1.2192)
			(layers "F.Cu" "F.Mask" "F.Paste")
			(net "Net_2581")
		)
		(pad "B69" smd rect
			(at -1.27762 30.055058 270)
			(size 0.3556 1.2192)
			(layers "F.Cu" "F.Mask" "F.Paste")
			(net "Net_2582")
		)
		(pad "B70" smd rect
			(at -1.27762 30.655006 270)
			(size 0.3556 1.2192)
			(layers "F.Cu" "F.Mask" "F.Paste")
			(net "PRSNTB3_NIC0_N")
		)
		(pad "G1" thru_hole oval
			(at 1.022604 -34.034984 270)
			(size 1.6256 3.4798)
			(drill oval 1.1176 2.4638)
			(layers "*.Cu" "*.Mask")
			(remove_unused_layers no)
			(net "GND")
			(clearance 0.127)
			(thermal_gap 0.127)
		)
		(pad "G2" thru_hole oval
			(at 1.022604 -20.625054 270)
			(size 1.6256 3.4798)
			(drill oval 1.1176 2.4638)
			(layers "*.Cu" "*.Mask")
			(remove_unused_layers no)
			(net "GND")
			(clearance 0.127)
			(thermal_gap 0.127)
		)
		(pad "G3" thru_hole oval
			(at 1.022604 -0.255016 270)
			(size 1.6256 3.4798)
			(drill oval 1.1176 2.4638)
			(layers "*.Cu" "*.Mask")
			(remove_unused_layers no)
			(net "GND")
			(clearance 0.127)
			(thermal_gap 0.127)
		)
		(pad "G4" thru_hole oval
			(at 1.022604 12.005056 270)
			(size 1.6256 3.4798)
			(drill oval 1.1176 2.4638)
			(layers "*.Cu" "*.Mask")
			(remove_unused_layers no)
			(net "GND")
			(clearance 0.127)
			(thermal_gap 0.127)
		)
		(pad "G5" thru_hole oval
			(at 1.022604 34.034984 270)
			(size 1.5748 3.4798)
			(drill oval 1.1176 2.4638)
			(layers "*.Cu" "*.Mask")
			(remove_unused_layers no)
			(net "GND")
			(clearance 0.1524)
			(thermal_gap 0.1524)
		)
		(pad "G6" thru_hole circle
			(at -3.16738 -20.625054)
			(size 1.6256 1.6256)
			(drill 1.1176)
			(layers "*.Cu" "*.Mask")
			(remove_unused_layers no)
			(net "GND")
			(clearance 0)
		)
		(pad "G7" thru_hole circle
			(at -3.16738 12.005056)
			(size 1.6256 1.6256)
			(drill 1.1176)
			(layers "*.Cu" "*.Mask")
			(remove_unused_layers no)
			(net "GND")
			(clearance 0)
		)
		(pad "G8" thru_hole circle
			(at 4.20243 -20.625054)
			(size 1.6256 1.6256)
			(drill 1.1176)
			(layers "*.Cu" "*.Mask")
			(remove_unused_layers no)
			(net "GND")
			(clearance 0)
		)
		(pad "G9" thru_hole circle
			(at 4.20243 12.005056)
			(size 1.6256 1.6256)
			(drill 1.1176)
			(layers "*.Cu" "*.Mask")
			(remove_unused_layers no)
			(net "GND")
			(clearance 0)
		)
		(pad "OA1" smd rect
			(at 3.322574 -30.660086 270)
			(size 0.3556 1.2192)
			(layers "F.Cu" "F.Mask" "F.Paste")
			(net "RST_NIC0_PERST2_R_N")
		)
		(pad "OA2" smd rect
			(at 3.322574 -30.059884 270)
			(size 0.3556 1.2192)
			(layers "F.Cu" "F.Mask" "F.Paste")
			(net "RST_NIC0_PERST3_R_N")
		)
		(pad "OA3" smd rect
			(at 3.322574 -29.459936 270)
			(size 0.3556 1.2192)
			(layers "F.Cu" "F.Mask" "F.Paste")
			(net "Net_2585")
		)
		(pad "OA4" smd rect
			(at 3.322574 -28.859988 270)
			(size 0.3556 1.2192)
			(layers "F.Cu" "F.Mask" "F.Paste")
			(net "NIC0_RBT_ARB_IN")
		)
		(pad "OA5" smd rect
			(at 3.322574 -28.26004 270)
			(size 0.3556 1.2192)
			(layers "F.Cu" "F.Mask" "F.Paste")
			(net "NIC0_RBT_ARB_OUT")
		)
		(pad "OA6" smd rect
			(at 3.322574 -27.660092 270)
			(size 0.3556 1.2192)
			(layers "F.Cu" "F.Mask" "F.Paste")
			(net "NIC0_SLOT_ID1")
		)
		(pad "OA7" smd rect
			(at 3.322574 -27.05989 270)
			(size 0.3556 1.2192)
			(layers "F.Cu" "F.Mask" "F.Paste")
			(net "NCSI_NIC0_TX_EN")
		)
		(pad "OA8" smd rect
			(at 3.322574 -26.459942 270)
			(size 0.3556 1.2192)
			(layers "F.Cu" "F.Mask" "F.Paste")
			(net "NCSI_NIC0_TXD1")
		)
		(pad "OA9" smd rect
			(at 3.322574 -25.859994 270)
			(size 0.3556 1.2192)
			(layers "F.Cu" "F.Mask" "F.Paste")
			(net "NCSI_NIC0_TXD0")
		)
		(pad "OA10" smd rect
			(at 3.322574 -25.260046 270)
			(size 0.3556 1.2192)
			(layers "F.Cu" "F.Mask" "F.Paste")
			(net "GND")
		)
		(pad "OA11" smd rect
			(at 3.322574 -24.660098 270)
			(size 0.3556 1.2192)
			(layers "F.Cu" "F.Mask" "F.Paste")
			(net "Net_2577")
		)
		(pad "OA12" smd rect
			(at 3.322574 -24.059896 270)
			(size 0.3556 1.2192)
			(layers "F.Cu" "F.Mask" "F.Paste")
			(net "Net_2580")
		)
		(pad "OA13" smd rect
			(at 3.322574 -23.459948 270)
			(size 0.3556 1.2192)
			(layers "F.Cu" "F.Mask" "F.Paste")
			(net "GND")
		)
		(pad "OA14" smd rect
			(at 3.322574 -22.86 270)
			(size 0.3556 1.2192)
			(layers "F.Cu" "F.Mask" "F.Paste")
			(net "CLK_50M_NIC0_RBT_REF")
		)
		(pad "OB1" smd rect
			(at -1.27762 -30.660086 270)
			(size 0.3556 1.2192)
			(layers "F.Cu" "F.Mask" "F.Paste")
			(net "PWRGD_NIC0_PWR_GOOD")
		)
		(pad "OB2" smd rect
			(at -1.27762 -30.059884 270)
			(size 0.3556 1.2192)
			(layers "F.Cu" "F.Mask" "F.Paste")
			(net "NIC0_MAIN_PWR_EN_R")
		)
		(pad "OB3" smd rect
			(at -1.27762 -29.459936 270)
			(size 0.3556 1.2192)
			(layers "F.Cu" "F.Mask" "F.Paste")
			(net "NIC0_LD_N")
		)
		(pad "OB4" smd rect
			(at -1.27762 -28.859988 270)
			(size 0.3556 1.2192)
			(layers "F.Cu" "F.Mask" "F.Paste")
			(net "NIC0_DATA_IN")
		)
		(pad "OB5" smd rect
			(at -1.27762 -28.26004 270)
			(size 0.3556 1.2192)
			(layers "F.Cu" "F.Mask" "F.Paste")
			(net "NIC0_DATA_OUT")
		)
		(pad "OB6" smd rect
			(at -1.27762 -27.660092 270)
			(size 0.3556 1.2192)
			(layers "F.Cu" "F.Mask" "F.Paste")
			(net "NIC0_CLK")
		)
		(pad "OB7" smd rect
			(at -1.27762 -27.05989 270)
			(size 0.3556 1.2192)
			(layers "F.Cu" "F.Mask" "F.Paste")
			(net "NIC0_SLOT_ID0")
		)
		(pad "OB8" smd rect
			(at -1.27762 -26.459942 270)
			(size 0.3556 1.2192)
			(layers "F.Cu" "F.Mask" "F.Paste")
			(net "NCSI_NIC0_RXD1")
		)
		(pad "OB9" smd rect
			(at -1.27762 -25.859994 270)
			(size 0.3556 1.2192)
			(layers "F.Cu" "F.Mask" "F.Paste")
			(net "NCSI_NIC0_RXD0")
		)
		(pad "OB10" smd rect
			(at -1.27762 -25.260046 270)
			(size 0.3556 1.2192)
			(layers "F.Cu" "F.Mask" "F.Paste")
			(net "GND")
		)
		(pad "OB11" smd rect
			(at -1.27762 -24.660098 270)
			(size 0.3556 1.2192)
			(layers "F.Cu" "F.Mask" "F.Paste")
			(net "Net_2576")
		)
		(pad "OB12" smd rect
			(at -1.27762 -24.059896 270)
			(size 0.3556 1.2192)
			(layers "F.Cu" "F.Mask" "F.Paste")
			(net "Net_2579")
		)
		(pad "OB13" smd rect
			(at -1.27762 -23.459948 270)
			(size 0.3556 1.2192)
			(layers "F.Cu" "F.Mask" "F.Paste")
			(net "GND")
		)
		(pad "OB14" smd rect
			(at -1.27762 -22.86 270)
			(size 0.3556 1.2192)
			(layers "F.Cu" "F.Mask" "F.Paste")
			(net "NCSI_NIC0_CRS_DV")
		)
		(zone
			(layers "F.Cu" "B.Cu" "In1.Cu" "In2.Cu" "In3.Cu" "In4.Cu" "In5.Cu" "In6.Cu"
				"In7.Cu" "In8.Cu" "In9.Cu" "In10.Cu" "In11.Cu" "In12.Cu" "In13.Cu" "In14.Cu"
				"In15.Cu" "In16.Cu"
			)
			(hatch none 0.5)
			(connect_pads
				(clearance 0)
			)
			(min_thickness 0.25)
			(keepout
				(tracks not_allowed)
				(vias allowed)
				(pads allowed)
				(copperpour not_allowed)
				(footprints allowed)
			)
			(placement
				(enabled no)
				(sheetname "")
			)
			(fill
				(thermal_gap 0.5)
				(thermal_bridge_width 0.5)
				(island_removal_mode 0)
			)
			(polygon
				(pts
					(arc
						(start 47.65929 -160.1851)
						(mid 45.52569 -160.1851)
						(end 47.65929 -160.1851)
					)
				)
			)
		)
		(zone
			(layers "F.Cu" "B.Cu" "In1.Cu" "In2.Cu" "In3.Cu" "In4.Cu" "In5.Cu" "In6.Cu"
				"In7.Cu" "In8.Cu" "In9.Cu" "In10.Cu" "In11.Cu" "In12.Cu" "In13.Cu" "In14.Cu"
				"In15.Cu" "In16.Cu"
			)
			(hatch none 0.5)
			(connect_pads
				(clearance 0)
			)
			(min_thickness 0.25)
			(keepout
				(tracks not_allowed)
				(vias allowed)
				(pads allowed)
				(copperpour not_allowed)
				(footprints allowed)
			)
			(placement
				(enabled no)
				(sheetname "")
			)
			(fill
				(thermal_gap 0.5)
				(thermal_bridge_width 0.5)
				(island_removal_mode 0)
			)
			(polygon
				(pts
					(arc
						(start 49.40935 -95.214948)
						(mid 47.27575 -95.214948)
						(end 49.40935 -95.214948)
					)
				)
			)
		)
	)
	(footprint ""
		(layer "F.Cu")
		(at 129.243074 -277.644352)
		(property "Reference" "PC96"
			(at 0 0 0)
			(layer "F.SilkS")
			(hide yes)
			(effects
				(font
					(size 1.27 1.27)
				)
			)
		)
		(property "Value" ""
			(at 0 0 0)
			(layer "F.Fab")
			(effects
				(font
					(size 1.27 1.27)
				)
			)
		)
		(duplicate_pad_numbers_are_jumpers no)
		(fp_line
			(start -1.524 -0.762)
			(end 1.524 -0.762)
			(stroke
				(width 0.1524)
				(type default)
			)
			(layer "F.SilkS")
		)
		(fp_line
			(start -1.524 0.762)
			(end -1.524 -0.762)
			(stroke
				(width 0.1524)
				(type default)
			)
			(layer "F.SilkS")
		)
		(fp_line
			(start 1.524 -0.762)
			(end 1.524 0.762)
			(stroke
				(width 0.1524)
				(type default)
			)
			(layer "F.SilkS")
		)
		(fp_line
			(start 1.524 0.762)
			(end -1.524 0.762)
			(stroke
				(width 0.1524)
				(type default)
			)
			(layer "F.SilkS")
		)
		(fp_line
			(start -1.1049 -0.724916)
			(end -1.1049 0.724916)
			(stroke
				(width 0.1)
				(type default)
			)
			(layer "F.Fab")
		)
		(fp_line
			(start -1.1049 0.724916)
			(end 1.1049 0.724916)
			(stroke
				(width 0.1)
				(type default)
			)
			(layer "F.Fab")
		)
		(fp_line
			(start 1.1049 -0.724916)
			(end -1.1049 -0.724916)
			(stroke
				(width 0.1)
				(type default)
			)
			(layer "F.Fab")
		)
		(fp_line
			(start 1.1049 0.724916)
			(end 1.1049 -0.724916)
			(stroke
				(width 0.1)
				(type default)
			)
			(layer "F.Fab")
		)
		(pad "1" smd rect
			(at -0.889 0 180)
			(size 1.016 1.27)
			(layers "F.Cu" "F.Mask" "F.Paste")
			(net "SW_P12V_P0V8_PEX1_FLT")
		)
		(pad "2" smd rect
			(at 0.889 0 180)
			(size 1.016 1.27)
			(layers "F.Cu" "F.Mask" "F.Paste")
			(net "GND")
		)
	)
	(footprint ""
		(layer "F.Cu")
		(at 46.273974 -72.766682 90)
		(property "Reference" "PR6903"
			(at 0 0 90)
			(layer "F.SilkS")
			(hide yes)
			(effects
				(font
					(size 1.27 1.27)
				)
			)
		)
		(property "Value" ""
			(at 0 0 90)
			(layer "F.Fab")
			(effects
				(font
					(size 1.27 1.27)
				)
			)
		)
		(duplicate_pad_numbers_are_jumpers no)
		(fp_line
			(start 0.7874 -0.4064)
			(end 0.7874 0.4064)
			(stroke
				(width 0.1524)
				(type default)
			)
			(layer "F.SilkS")
		)
		(fp_line
			(start -0.7874 -0.4064)
			(end 0.7874 -0.4064)
			(stroke
				(width 0.1524)
				(type default)
			)
			(layer "F.SilkS")
		)
		(fp_line
			(start 0.7874 0.4064)
			(end -0.7874 0.4064)
			(stroke
				(width 0.1524)
				(type default)
			)
			(layer "F.SilkS")
		)
		(fp_line
			(start -0.7874 0.4064)
			(end -0.7874 -0.4064)
			(stroke
				(width 0.1524)
				(type default)
			)
			(layer "F.SilkS")
		)
		(fp_line
			(start -0.12065 -0.305054)
			(end -0.12065 -0.2794)
			(stroke
				(width 0.1)
				(type default)
			)
			(layer "F.Fab")
		)
		(fp_line
			(start -0.67945 -0.305054)
			(end -0.12065 -0.305054)
			(stroke
				(width 0.1)
				(type default)
			)
			(layer "F.Fab")
		)
		(fp_line
			(start 0.67945 -0.3048)
			(end 0.67945 0.3048)
			(stroke
				(width 0.1)
				(type default)
			)
			(layer "F.Fab")
		)
		(fp_line
			(start 0.12065 -0.3048)
			(end 0.67945 -0.3048)
			(stroke
				(width 0.1)
				(type default)
			)
			(layer "F.Fab")
		)
		(fp_line
			(start 0.12065 -0.2794)
			(end 0.12065 -0.3048)
			(stroke
				(width 0.1)
				(type default)
			)
			(layer "F.Fab")
		)
		(fp_line
			(start -0.12065 -0.2794)
			(end 0.12065 -0.2794)
			(stroke
				(width 0.1)
				(type default)
			)
			(layer "F.Fab")
		)
		(fp_line
			(start 0.120396 0.2794)
			(end -0.12065 0.2794)
			(stroke
				(width 0.1)
				(type default)
			)
			(layer "F.Fab")
		)
		(fp_line
			(start -0.12065 0.2794)
			(end -0.12065 0.3048)
			(stroke
				(width 0.1)
				(type default)
			)
			(layer "F.Fab")
		)
		(fp_line
			(start 0.67945 0.3048)
			(end 0.120396 0.3048)
			(stroke
				(width 0.1)
				(type default)
			)
			(layer "F.Fab")
		)
		(fp_line
			(start 0.120396 0.3048)
			(end 0.120396 0.2794)
			(stroke
				(width 0.1)
				(type default)
			)
			(layer "F.Fab")
		)
		(fp_line
			(start -0.12065 0.3048)
			(end -0.67945 0.3048)
			(stroke
				(width 0.1)
				(type default)
			)
			(layer "F.Fab")
		)
		(fp_line
			(start -0.67945 0.3048)
			(end -0.67945 -0.305054)
			(stroke
				(width 0.1)
				(type default)
			)
			(layer "F.Fab")
		)
		(pad "1" smd circle
			(at -0.40005 0 90)
			(size 0 0)
			(layers "F.Cu" "F.Mask" "F.Paste")
			(net "P12V_SSD1_CO_MODE")
		)
		(pad "2" smd circle
			(at 0.40005 0 90)
			(size 0 0)
			(layers "F.Cu" "F.Mask" "F.Paste")
			(net "GND")
		)
	)
	(footprint ""
		(layer "F.Cu")
		(at 330.874878 -56.977534 180)
		(property "Reference" "PC436"
			(at 0 0 180)
			(layer "F.SilkS")
			(hide yes)
			(effects
				(font
					(size 1.27 1.27)
				)
			)
		)
		(property "Value" ""
			(at 0 0 180)
			(layer "F.Fab")
			(effects
				(font
					(size 1.27 1.27)
				)
			)
		)
		(duplicate_pad_numbers_are_jumpers no)
		(fp_line
			(start 0.7874 0.4064)
			(end -0.7874 0.4064)
			(stroke
				(width 0.1524)
				(type default)
			)
			(layer "F.SilkS")
		)
		(fp_line
			(start 0.7874 -0.4064)
			(end 0.7874 0.4064)
			(stroke
				(width 0.1524)
				(type default)
			)
			(layer "F.SilkS")
		)
		(fp_line
			(start -0.7874 0.4064)
			(end -0.7874 -0.4064)
			(stroke
				(width 0.1524)
				(type default)
			)
			(layer "F.SilkS")
		)
		(fp_line
			(start -0.7874 -0.4064)
			(end 0.7874 -0.4064)
			(stroke
				(width 0.1524)
				(type default)
			)
			(layer "F.SilkS")
		)
		(fp_line
			(start 0.67945 0.3048)
			(end 0.120396 0.3048)
			(stroke
				(width 0.1)
				(type default)
			)
			(layer "F.Fab")
		)
		(fp_line
			(start 0.67945 -0.3048)
			(end 0.67945 0.3048)
			(stroke
				(width 0.1)
				(type default)
			)
			(layer "F.Fab")
		)
		(fp_line
			(start 0.12065 -0.2794)
			(end 0.12065 -0.3048)
			(stroke
				(width 0.1)
				(type default)
			)
			(layer "F.Fab")
		)
		(fp_line
			(start 0.12065 -0.3048)
			(end 0.67945 -0.3048)
			(stroke
				(width 0.1)
				(type default)
			)
			(layer "F.Fab")
		)
		(fp_line
			(start 0.120396 0.3048)
			(end 0.120396 0.2794)
			(stroke
				(width 0.1)
				(type default)
			)
			(layer "F.Fab")
		)
		(fp_line
			(start 0.120396 0.2794)
			(end -0.12065 0.2794)
			(stroke
				(width 0.1)
				(type default)
			)
			(layer "F.Fab")
		)
		(fp_line
			(start -0.12065 0.3048)
			(end -0.67945 0.3048)
			(stroke
				(width 0.1)
				(type default)
			)
			(layer "F.Fab")
		)
		(fp_line
			(start -0.12065 0.2794)
			(end -0.12065 0.3048)
			(stroke
				(width 0.1)
				(type default)
			)
			(layer "F.Fab")
		)
		(fp_line
			(start -0.12065 -0.2794)
			(end 0.12065 -0.2794)
			(stroke
				(width 0.1)
				(type default)
			)
			(layer "F.Fab")
		)
		(fp_line
			(start -0.12065 -0.305054)
			(end -0.12065 -0.2794)
			(stroke
				(width 0.1)
				(type default)
			)
			(layer "F.Fab")
		)
		(fp_line
			(start -0.67945 0.3048)
			(end -0.67945 -0.305054)
			(stroke
				(width 0.1)
				(type default)
			)
			(layer "F.Fab")
		)
		(fp_line
			(start -0.67945 -0.305054)
			(end -0.12065 -0.305054)
			(stroke
				(width 0.1)
				(type default)
			)
			(layer "F.Fab")
		)
		(pad "1" smd circle
			(at -0.40005 0 180)
			(size 0 0)
			(layers "F.Cu" "F.Mask" "F.Paste")
			(net "P12V_AUX")
		)
		(pad "2" smd circle
			(at 0.40005 0 180)
			(size 0 0)
			(layers "F.Cu" "F.Mask" "F.Paste")
			(net "GND")
		)
	)
	(footprint ""
		(layer "F.Cu")
		(at 132.91439 -184.656984 -90)
		(property "Reference" "R1114"
			(at 0 0 270)
			(layer "F.SilkS")
			(hide yes)
			(effects
				(font
					(size 1.27 1.27)
				)
			)
		)
		(property "Value" ""
			(at 0 0 270)
			(layer "F.Fab")
			(effects
				(font
					(size 1.27 1.27)
				)
			)
		)
		(duplicate_pad_numbers_are_jumpers no)
		(fp_line
			(start -0.7874 -0.4064)
			(end 0.7874 -0.4064)
			(stroke
				(width 0.1524)
				(type default)
			)
			(layer "F.SilkS")
		)
		(fp_line
			(start -0.67945 0.3048)
			(end -0.67945 -0.305054)
			(stroke
				(width 0.1)
				(type default)
			)
			(layer "F.Fab")
		)
		(fp_line
			(start -0.12065 0.3048)
			(end -0.67945 0.3048)
			(stroke
				(width 0.1)
				(type default)
			)
			(layer "F.Fab")
		)
		(fp_line
			(start 0.120396 0.3048)
			(end 0.120396 0.2794)
			(stroke
				(width 0.1)
				(type default)
			)
			(layer "F.Fab")
		)
		(fp_line
			(start 0.67945 0.3048)
			(end 0.120396 0.3048)
			(stroke
				(width 0.1)
				(type default)
			)
			(layer "F.Fab")
		)
		(fp_line
			(start -0.12065 0.2794)
			(end -0.12065 0.3048)
			(stroke
				(width 0.1)
				(type default)
			)
			(layer "F.Fab")
		)
		(fp_line
			(start 0.120396 0.2794)
			(end -0.12065 0.2794)
			(stroke
				(width 0.1)
				(type default)
			)
			(layer "F.Fab")
		)
		(fp_line
			(start -0.12065 -0.2794)
			(end 0.12065 -0.2794)
			(stroke
				(width 0.1)
				(type default)
			)
			(layer "F.Fab")
		)
		(fp_line
			(start 0.12065 -0.2794)
			(end 0.12065 -0.3048)
			(stroke
				(width 0.1)
				(type default)
			)
			(layer "F.Fab")
		)
		(fp_line
			(start 0.12065 -0.3048)
			(end 0.67945 -0.3048)
			(stroke
				(width 0.1)
				(type default)
			)
			(layer "F.Fab")
		)
		(fp_line
			(start 0.67945 -0.3048)
			(end 0.67945 0.3048)
			(stroke
				(width 0.1)
				(type default)
			)
			(layer "F.Fab")
		)
		(fp_line
			(start -0.67945 -0.305054)
			(end -0.12065 -0.305054)
			(stroke
				(width 0.1)
				(type default)
			)
			(layer "F.Fab")
		)
		(fp_line
			(start -0.12065 -0.305054)
			(end -0.12065 -0.2794)
			(stroke
				(width 0.1)
				(type default)
			)
			(layer "F.Fab")
		)
		(pad "1" smd circle
			(at -0.40005 0 270)
			(size 0 0)
			(layers "F.Cu" "F.Mask" "F.Paste")
			(net "CLK_100M_DB2000QL_GPU_REF1_R_DP")
		)
		(pad "2" smd circle
			(at 0.40005 0 270)
			(size 0 0)
			(layers "F.Cu" "F.Mask" "F.Paste")
			(net "CLK_100M_DB2000QL_GPU_REF1_DP")
		)
	)
	(footprint ""
		(layer "F.Cu")
		(at 106.596942 -117.627654 180)
		(property "Reference" "PR6864"
			(at 0 0 180)
			(layer "F.SilkS")
			(hide yes)
			(effects
				(font
					(size 1.27 1.27)
				)
			)
		)
		(property "Value" ""
			(at 0 0 180)
			(layer "F.Fab")
			(effects
				(font
					(size 1.27 1.27)
				)
			)
		)
		(duplicate_pad_numbers_are_jumpers no)
		(fp_line
			(start 0.7874 0.4064)
			(end -0.7874 0.4064)
			(stroke
				(width 0.1524)
				(type default)
			)
			(layer "F.SilkS")
		)
		(fp_line
			(start 0.7874 -0.4064)
			(end 0.7874 0.4064)
			(stroke
				(width 0.1524)
				(type default)
			)
			(layer "F.SilkS")
		)
		(fp_line
			(start -0.7874 0.4064)
			(end -0.7874 -0.4064)
			(stroke
				(width 0.1524)
				(type default)
			)
			(layer "F.SilkS")
		)
		(fp_line
			(start -0.7874 -0.4064)
			(end 0.7874 -0.4064)
			(stroke
				(width 0.1524)
				(type default)
			)
			(layer "F.SilkS")
		)
		(fp_line
			(start 0.67945 0.3048)
			(end 0.120396 0.3048)
			(stroke
				(width 0.1)
				(type default)
			)
			(layer "F.Fab")
		)
		(fp_line
			(start 0.67945 -0.3048)
			(end 0.67945 0.3048)
			(stroke
				(width 0.1)
				(type default)
			)
			(layer "F.Fab")
		)
		(fp_line
			(start 0.12065 -0.2794)
			(end 0.12065 -0.3048)
			(stroke
				(width 0.1)
				(type default)
			)
			(layer "F.Fab")
		)
		(fp_line
			(start 0.12065 -0.3048)
			(end 0.67945 -0.3048)
			(stroke
				(width 0.1)
				(type default)
			)
			(layer "F.Fab")
		)
		(fp_line
			(start 0.120396 0.3048)
			(end 0.120396 0.2794)
			(stroke
				(width 0.1)
				(type default)
			)
			(layer "F.Fab")
		)
		(fp_line
			(start 0.120396 0.2794)
			(end -0.12065 0.2794)
			(stroke
				(width 0.1)
				(type default)
			)
			(layer "F.Fab")
		)
		(fp_line
			(start -0.12065 0.3048)
			(end -0.67945 0.3048)
			(stroke
				(width 0.1)
				(type default)
			)
			(layer "F.Fab")
		)
		(fp_line
			(start -0.12065 0.2794)
			(end -0.12065 0.3048)
			(stroke
				(width 0.1)
				(type default)
			)
			(layer "F.Fab")
		)
		(fp_line
			(start -0.12065 -0.2794)
			(end 0.12065 -0.2794)
			(stroke
				(width 0.1)
				(type default)
			)
			(layer "F.Fab")
		)
		(fp_line
			(start -0.12065 -0.305054)
			(end -0.12065 -0.2794)
			(stroke
				(width 0.1)
				(type default)
			)
			(layer "F.Fab")
		)
		(fp_line
			(start -0.67945 0.3048)
			(end -0.67945 -0.305054)
			(stroke
				(width 0.1)
				(type default)
			)
			(layer "F.Fab")
		)
		(fp_line
			(start -0.67945 -0.305054)
			(end -0.12065 -0.305054)
			(stroke
				(width 0.1)
				(type default)
			)
			(layer "F.Fab")
		)
		(pad "1" smd circle
			(at -0.40005 0 180)
			(size 0 0)
			(layers "F.Cu" "F.Mask" "F.Paste")
			(net "P12V_NIC1_CO_OV_FB")
		)
		(pad "2" smd circle
			(at 0.40005 0 180)
			(size 0 0)
			(layers "F.Cu" "F.Mask" "F.Paste")
			(net "P12V_NIC1_R")
		)
	)
	(footprint ""
		(layer "F.Cu")
		(at 387.082792 -140.85697)
		(property "Reference" "R340"
			(at 0 0 0)
			(layer "F.SilkS")
			(hide yes)
			(effects
				(font
					(size 1.27 1.27)
				)
			)
		)
		(property "Value" ""
			(at 0 0 0)
			(layer "F.Fab")
			(effects
				(font
					(size 1.27 1.27)
				)
			)
		)
		(duplicate_pad_numbers_are_jumpers no)
		(fp_line
			(start -0.7874 -0.4064)
			(end 0.7874 -0.4064)
			(stroke
				(width 0.1524)
				(type default)
			)
			(layer "F.SilkS")
		)
		(fp_line
			(start -0.7874 0.4064)
			(end -0.7874 -0.4064)
			(stroke
				(width 0.1524)
				(type default)
			)
			(layer "F.SilkS")
		)
		(fp_line
			(start 0.7874 -0.4064)
			(end 0.7874 0.4064)
			(stroke
				(width 0.1524)
				(type default)
			)
			(layer "F.SilkS")
		)
		(fp_line
			(start 0.7874 0.4064)
			(end -0.7874 0.4064)
			(stroke
				(width 0.1524)
				(type default)
			)
			(layer "F.SilkS")
		)
		(fp_line
			(start -0.67945 -0.305054)
			(end -0.12065 -0.305054)
			(stroke
				(width 0.1)
				(type default)
			)
			(layer "F.Fab")
		)
		(fp_line
			(start -0.67945 0.3048)
			(end -0.67945 -0.305054)
			(stroke
				(width 0.1)
				(type default)
			)
			(layer "F.Fab")
		)
		(fp_line
			(start -0.12065 -0.305054)
			(end -0.12065 -0.2794)
			(stroke
				(width 0.1)
				(type default)
			)
			(layer "F.Fab")
		)
		(fp_line
			(start -0.12065 -0.2794)
			(end 0.12065 -0.2794)
			(stroke
				(width 0.1)
				(type default)
			)
			(layer "F.Fab")
		)
		(fp_line
			(start -0.12065 0.2794)
			(end -0.12065 0.3048)
			(stroke
				(width 0.1)
				(type default)
			)
			(layer "F.Fab")
		)
		(fp_line
			(start -0.12065 0.3048)
			(end -0.67945 0.3048)
			(stroke
				(width 0.1)
				(type default)
			)
			(layer "F.Fab")
		)
		(fp_line
			(start 0.120396 0.2794)
			(end -0.12065 0.2794)
			(stroke
				(width 0.1)
				(type default)
			)
			(layer "F.Fab")
		)
		(fp_line
			(start 0.120396 0.3048)
			(end 0.120396 0.2794)
			(stroke
				(width 0.1)
				(type default)
			)
			(layer "F.Fab")
		)
		(fp_line
			(start 0.12065 -0.3048)
			(end 0.67945 -0.3048)
			(stroke
				(width 0.1)
				(type default)
			)
			(layer "F.Fab")
		)
		(fp_line
			(start 0.12065 -0.2794)
			(end 0.12065 -0.3048)
			(stroke
				(width 0.1)
				(type default)
			)
			(layer "F.Fab")
		)
		(fp_line
			(start 0.67945 -0.3048)
			(end 0.67945 0.3048)
			(stroke
				(width 0.1)
				(type default)
			)
			(layer "F.Fab")
		)
		(fp_line
			(start 0.67945 0.3048)
			(end 0.120396 0.3048)
			(stroke
				(width 0.1)
				(type default)
			)
			(layer "F.Fab")
		)
		(pad "1" smd circle
			(at -0.40005 0)
			(size 0 0)
			(layers "F.Cu" "F.Mask" "F.Paste")
			(net "NIC6_BIF2_N")
		)
		(pad "2" smd circle
			(at 0.40005 0)
			(size 0 0)
			(layers "F.Cu" "F.Mask" "F.Paste")
			(net "GND")
		)
	)
	(footprint ""
		(layer "F.Cu")
		(at 296.54119 -213.523068 -90)
		(property "Reference" "R3400"
			(at 0 0 270)
			(layer "F.SilkS")
			(hide yes)
			(effects
				(font
					(size 1.27 1.27)
				)
			)
		)
		(property "Value" ""
			(at 0 0 270)
			(layer "F.Fab")
			(effects
				(font
					(size 1.27 1.27)
				)
			)
		)
		(duplicate_pad_numbers_are_jumpers no)
		(fp_line
			(start -0.7874 0.4064)
			(end -0.7874 -0.4064)
			(stroke
				(width 0.1524)
				(type default)
			)
			(layer "F.SilkS")
		)
		(fp_line
			(start 0.7874 0.4064)
			(end -0.7874 0.4064)
			(stroke
				(width 0.1524)
				(type default)
			)
			(layer "F.SilkS")
		)
		(fp_line
			(start -0.7874 -0.4064)
			(end 0.7874 -0.4064)
			(stroke
				(width 0.1524)
				(type default)
			)
			(layer "F.SilkS")
		)
		(fp_line
			(start 0.7874 -0.4064)
			(end 0.7874 0.4064)
			(stroke
				(width 0.1524)
				(type default)
			)
			(layer "F.SilkS")
		)
		(fp_line
			(start -0.67945 0.3048)
			(end -0.67945 -0.305054)
			(stroke
				(width 0.1)
				(type default)
			)
			(layer "F.Fab")
		)
		(fp_line
			(start -0.12065 0.3048)
			(end -0.67945 0.3048)
			(stroke
				(width 0.1)
				(type default)
			)
			(layer "F.Fab")
		)
		(fp_line
			(start 0.120396 0.3048)
			(end 0.120396 0.2794)
			(stroke
				(width 0.1)
				(type default)
			)
			(layer "F.Fab")
		)
		(fp_line
			(start 0.67945 0.3048)
			(end 0.120396 0.3048)
			(stroke
				(width 0.1)
				(type default)
			)
			(layer "F.Fab")
		)
		(fp_line
			(start -0.12065 0.2794)
			(end -0.12065 0.3048)
			(stroke
				(width 0.1)
				(type default)
			)
			(layer "F.Fab")
		)
		(fp_line
			(start 0.120396 0.2794)
			(end -0.12065 0.2794)
			(stroke
				(width 0.1)
				(type default)
			)
			(layer "F.Fab")
		)
		(fp_line
			(start -0.12065 -0.2794)
			(end 0.12065 -0.2794)
			(stroke
				(width 0.1)
				(type default)
			)
			(layer "F.Fab")
		)
		(fp_line
			(start 0.12065 -0.2794)
			(end 0.12065 -0.3048)
			(stroke
				(width 0.1)
				(type default)
			)
			(layer "F.Fab")
		)
		(fp_line
			(start 0.12065 -0.3048)
			(end 0.67945 -0.3048)
			(stroke
				(width 0.1)
				(type default)
			)
			(layer "F.Fab")
		)
		(fp_line
			(start 0.67945 -0.3048)
			(end 0.67945 0.3048)
			(stroke
				(width 0.1)
				(type default)
			)
			(layer "F.Fab")
		)
		(fp_line
			(start -0.67945 -0.305054)
			(end -0.12065 -0.305054)
			(stroke
				(width 0.1)
				(type default)
			)
			(layer "F.Fab")
		)
		(fp_line
			(start -0.12065 -0.305054)
			(end -0.12065 -0.2794)
			(stroke
				(width 0.1)
				(type default)
			)
			(layer "F.Fab")
		)
		(pad "1" smd circle
			(at -0.40005 0 270)
			(size 0 0)
			(layers "F.Cu" "F.Mask" "F.Paste")
			(net "SPI_BIC1_MOSI_LS23_R2")
		)
		(pad "2" smd circle
			(at 0.40005 0 270)
			(size 0 0)
			(layers "F.Cu" "F.Mask" "F.Paste")
			(net "SPI_BIC1_MOSI_LS23_R")
		)
	)
	(footprint ""
		(layer "F.Cu")
		(at 285.326074 -39.73576 -90)
		(property "Reference" "R5575"
			(at 0 0 270)
			(layer "F.SilkS")
			(hide yes)
			(effects
				(font
					(size 1.27 1.27)
				)
			)
		)
		(property "Value" ""
			(at 0 0 270)
			(layer "F.Fab")
			(effects
				(font
					(size 1.27 1.27)
				)
			)
		)
		(duplicate_pad_numbers_are_jumpers no)
		(fp_line
			(start -0.7874 0.4064)
			(end -0.7874 -0.4064)
			(stroke
				(width 0.1524)
				(type default)
			)
			(layer "F.SilkS")
		)
		(fp_line
			(start 0.7874 0.4064)
			(end -0.7874 0.4064)
			(stroke
				(width 0.1524)
				(type default)
			)
			(layer "F.SilkS")
		)
		(fp_line
			(start -0.7874 -0.4064)
			(end 0.7874 -0.4064)
			(stroke
				(width 0.1524)
				(type default)
			)
			(layer "F.SilkS")
		)
		(fp_line
			(start 0.7874 -0.4064)
			(end 0.7874 0.4064)
			(stroke
				(width 0.1524)
				(type default)
			)
			(layer "F.SilkS")
		)
		(fp_line
			(start -0.67945 0.3048)
			(end -0.67945 -0.305054)
			(stroke
				(width 0.1)
				(type default)
			)
			(layer "F.Fab")
		)
		(fp_line
			(start -0.12065 0.3048)
			(end -0.67945 0.3048)
			(stroke
				(width 0.1)
				(type default)
			)
			(layer "F.Fab")
		)
		(fp_line
			(start 0.120396 0.3048)
			(end 0.120396 0.2794)
			(stroke
				(width 0.1)
				(type default)
			)
			(layer "F.Fab")
		)
		(fp_line
			(start 0.67945 0.3048)
			(end 0.120396 0.3048)
			(stroke
				(width 0.1)
				(type default)
			)
			(layer "F.Fab")
		)
		(fp_line
			(start -0.12065 0.2794)
			(end -0.12065 0.3048)
			(stroke
				(width 0.1)
				(type default)
			)
			(layer "F.Fab")
		)
		(fp_line
			(start 0.120396 0.2794)
			(end -0.12065 0.2794)
			(stroke
				(width 0.1)
				(type default)
			)
			(layer "F.Fab")
		)
		(fp_line
			(start -0.12065 -0.2794)
			(end 0.12065 -0.2794)
			(stroke
				(width 0.1)
				(type default)
			)
			(layer "F.Fab")
		)
		(fp_line
			(start 0.12065 -0.2794)
			(end 0.12065 -0.3048)
			(stroke
				(width 0.1)
				(type default)
			)
			(layer "F.Fab")
		)
		(fp_line
			(start 0.12065 -0.3048)
			(end 0.67945 -0.3048)
			(stroke
				(width 0.1)
				(type default)
			)
			(layer "F.Fab")
		)
		(fp_line
			(start 0.67945 -0.3048)
			(end 0.67945 0.3048)
			(stroke
				(width 0.1)
				(type default)
			)
			(layer "F.Fab")
		)
		(fp_line
			(start -0.67945 -0.305054)
			(end -0.12065 -0.305054)
			(stroke
				(width 0.1)
				(type default)
			)
			(layer "F.Fab")
		)
		(fp_line
			(start -0.12065 -0.305054)
			(end -0.12065 -0.2794)
			(stroke
				(width 0.1)
				(type default)
			)
			(layer "F.Fab")
		)
		(pad "1" smd circle
			(at -0.40005 0 270)
			(size 0 0)
			(layers "F.Cu" "F.Mask" "F.Paste")
			(net "P3V3_AUX")
		)
		(pad "2" smd circle
			(at 0.40005 0 270)
			(size 0 0)
			(layers "F.Cu" "F.Mask" "F.Paste")
			(net "SSD10_AUX_P3V3_EN")
		)
	)
	(footprint ""
		(layer "F.Cu")
		(at 197.457822 -27.006296 -90)
		(property "Reference" "PR7113"
			(at 0 0 270)
			(layer "F.SilkS")
			(hide yes)
			(effects
				(font
					(size 1.27 1.27)
				)
			)
		)
		(property "Value" ""
			(at 0 0 270)
			(layer "F.Fab")
			(effects
				(font
					(size 1.27 1.27)
				)
			)
		)
		(duplicate_pad_numbers_are_jumpers no)
		(fp_line
			(start -0.7874 0.4064)
			(end -0.7874 -0.4064)
			(stroke
				(width 0.1524)
				(type default)
			)
			(layer "F.SilkS")
		)
		(fp_line
			(start 0.7874 0.4064)
			(end -0.7874 0.4064)
			(stroke
				(width 0.1524)
				(type default)
			)
			(layer "F.SilkS")
		)
		(fp_line
			(start -0.7874 -0.4064)
			(end 0.7874 -0.4064)
			(stroke
				(width 0.1524)
				(type default)
			)
			(layer "F.SilkS")
		)
		(fp_line
			(start 0.7874 -0.4064)
			(end 0.7874 0.4064)
			(stroke
				(width 0.1524)
				(type default)
			)
			(layer "F.SilkS")
		)
		(fp_line
			(start -0.67945 0.3048)
			(end -0.67945 -0.305054)
			(stroke
				(width 0.1)
				(type default)
			)
			(layer "F.Fab")
		)
		(fp_line
			(start -0.12065 0.3048)
			(end -0.67945 0.3048)
			(stroke
				(width 0.1)
				(type default)
			)
			(layer "F.Fab")
		)
		(fp_line
			(start 0.120396 0.3048)
			(end 0.120396 0.2794)
			(stroke
				(width 0.1)
				(type default)
			)
			(layer "F.Fab")
		)
		(fp_line
			(start 0.67945 0.3048)
			(end 0.120396 0.3048)
			(stroke
				(width 0.1)
				(type default)
			)
			(layer "F.Fab")
		)
		(fp_line
			(start -0.12065 0.2794)
			(end -0.12065 0.3048)
			(stroke
				(width 0.1)
				(type default)
			)
			(layer "F.Fab")
		)
		(fp_line
			(start 0.120396 0.2794)
			(end -0.12065 0.2794)
			(stroke
				(width 0.1)
				(type default)
			)
			(layer "F.Fab")
		)
		(fp_line
			(start -0.12065 -0.2794)
			(end 0.12065 -0.2794)
			(stroke
				(width 0.1)
				(type default)
			)
			(layer "F.Fab")
		)
		(fp_line
			(start 0.12065 -0.2794)
			(end 0.12065 -0.3048)
			(stroke
				(width 0.1)
				(type default)
			)
			(layer "F.Fab")
		)
		(fp_line
			(start 0.12065 -0.3048)
			(end 0.67945 -0.3048)
			(stroke
				(width 0.1)
				(type default)
			)
			(layer "F.Fab")
		)
		(fp_line
			(start 0.67945 -0.3048)
			(end 0.67945 0.3048)
			(stroke
				(width 0.1)
				(type default)
			)
			(layer "F.Fab")
		)
		(fp_line
			(start -0.67945 -0.305054)
			(end -0.12065 -0.305054)
			(stroke
				(width 0.1)
				(type default)
			)
			(layer "F.Fab")
		)
		(fp_line
			(start -0.12065 -0.305054)
			(end -0.12065 -0.2794)
			(stroke
				(width 0.1)
				(type default)
			)
			(layer "F.Fab")
		)
		(pad "1" smd circle
			(at -0.40005 0 270)
			(size 0 0)
			(layers "F.Cu" "F.Mask" "F.Paste")
			(net "P3V3_SSD7_CO_MODE")
		)
		(pad "2" smd circle
			(at 0.40005 0 270)
			(size 0 0)
			(layers "F.Cu" "F.Mask" "F.Paste")
			(net "GND")
		)
	)
	(footprint ""
		(layer "F.Cu")
		(at 137.985754 -25.1587 -90)
		(property "Reference" "R5740"
			(at 0 0 270)
			(layer "F.SilkS")
			(hide yes)
			(effects
				(font
					(size 1.27 1.27)
				)
			)
		)
		(property "Value" ""
			(at 0 0 270)
			(layer "F.Fab")
			(effects
				(font
					(size 1.27 1.27)
				)
			)
		)
		(duplicate_pad_numbers_are_jumpers no)
		(fp_line
			(start -0.7874 0.4064)
			(end -0.7874 -0.4064)
			(stroke
				(width 0.1524)
				(type default)
			)
			(layer "F.SilkS")
		)
		(fp_line
			(start 0.7874 0.4064)
			(end -0.7874 0.4064)
			(stroke
				(width 0.1524)
				(type default)
			)
			(layer "F.SilkS")
		)
		(fp_line
			(start -0.7874 -0.4064)
			(end 0.7874 -0.4064)
			(stroke
				(width 0.1524)
				(type default)
			)
			(layer "F.SilkS")
		)
		(fp_line
			(start 0.7874 -0.4064)
			(end 0.7874 0.4064)
			(stroke
				(width 0.1524)
				(type default)
			)
			(layer "F.SilkS")
		)
		(fp_line
			(start -0.67945 0.3048)
			(end -0.67945 -0.305054)
			(stroke
				(width 0.1)
				(type default)
			)
			(layer "F.Fab")
		)
		(fp_line
			(start -0.12065 0.3048)
			(end -0.67945 0.3048)
			(stroke
				(width 0.1)
				(type default)
			)
			(layer "F.Fab")
		)
		(fp_line
			(start 0.120396 0.3048)
			(end 0.120396 0.2794)
			(stroke
				(width 0.1)
				(type default)
			)
			(layer "F.Fab")
		)
		(fp_line
			(start 0.67945 0.3048)
			(end 0.120396 0.3048)
			(stroke
				(width 0.1)
				(type default)
			)
			(layer "F.Fab")
		)
		(fp_line
			(start -0.12065 0.2794)
			(end -0.12065 0.3048)
			(stroke
				(width 0.1)
				(type default)
			)
			(layer "F.Fab")
		)
		(fp_line
			(start 0.120396 0.2794)
			(end -0.12065 0.2794)
			(stroke
				(width 0.1)
				(type default)
			)
			(layer "F.Fab")
		)
		(fp_line
			(start -0.12065 -0.2794)
			(end 0.12065 -0.2794)
			(stroke
				(width 0.1)
				(type default)
			)
			(layer "F.Fab")
		)
		(fp_line
			(start 0.12065 -0.2794)
			(end 0.12065 -0.3048)
			(stroke
				(width 0.1)
				(type default)
			)
			(layer "F.Fab")
		)
		(fp_line
			(start 0.12065 -0.3048)
			(end 0.67945 -0.3048)
			(stroke
				(width 0.1)
				(type default)
			)
			(layer "F.Fab")
		)
		(fp_line
			(start 0.67945 -0.3048)
			(end 0.67945 0.3048)
			(stroke
				(width 0.1)
				(type default)
			)
			(layer "F.Fab")
		)
		(fp_line
			(start -0.67945 -0.305054)
			(end -0.12065 -0.305054)
			(stroke
				(width 0.1)
				(type default)
			)
			(layer "F.Fab")
		)
		(fp_line
			(start -0.12065 -0.305054)
			(end -0.12065 -0.2794)
			(stroke
				(width 0.1)
				(type default)
			)
			(layer "F.Fab")
		)
		(pad "1" smd circle
			(at -0.40005 0 270)
			(size 0 0)
			(layers "F.Cu" "F.Mask" "F.Paste")
			(net "SSD4_LED_ISO_N")
		)
		(pad "2" smd circle
			(at 0.40005 0 270)
			(size 0 0)
			(layers "F.Cu" "F.Mask" "F.Paste")
			(net "SSD4_LED_ISO_R_N")
		)
	)
	(footprint ""
		(layer "F.Cu")
		(at 439.673746 -298.885102 -90)
		(property "Reference" "R4019"
			(at 0 0 270)
			(layer "F.SilkS")
			(hide yes)
			(effects
				(font
					(size 1.27 1.27)
				)
			)
		)
		(property "Value" ""
			(at 0 0 270)
			(layer "F.Fab")
			(effects
				(font
					(size 1.27 1.27)
				)
			)
		)
		(duplicate_pad_numbers_are_jumpers no)
		(fp_line
			(start -0.7874 0.4064)
			(end -0.7874 -0.4064)
			(stroke
				(width 0.1524)
				(type default)
			)
			(layer "F.SilkS")
		)
		(fp_line
			(start 0.7874 0.4064)
			(end -0.7874 0.4064)
			(stroke
				(width 0.1524)
				(type default)
			)
			(layer "F.SilkS")
		)
		(fp_line
			(start -0.7874 -0.4064)
			(end 0.7874 -0.4064)
			(stroke
				(width 0.1524)
				(type default)
			)
			(layer "F.SilkS")
		)
		(fp_line
			(start 0.7874 -0.4064)
			(end 0.7874 0.4064)
			(stroke
				(width 0.1524)
				(type default)
			)
			(layer "F.SilkS")
		)
		(fp_line
			(start -0.67945 0.3048)
			(end -0.67945 -0.305054)
			(stroke
				(width 0.1)
				(type default)
			)
			(layer "F.Fab")
		)
		(fp_line
			(start -0.12065 0.3048)
			(end -0.67945 0.3048)
			(stroke
				(width 0.1)
				(type default)
			)
			(layer "F.Fab")
		)
		(fp_line
			(start 0.120396 0.3048)
			(end 0.120396 0.2794)
			(stroke
				(width 0.1)
				(type default)
			)
			(layer "F.Fab")
		)
		(fp_line
			(start 0.67945 0.3048)
			(end 0.120396 0.3048)
			(stroke
				(width 0.1)
				(type default)
			)
			(layer "F.Fab")
		)
		(fp_line
			(start -0.12065 0.2794)
			(end -0.12065 0.3048)
			(stroke
				(width 0.1)
				(type default)
			)
			(layer "F.Fab")
		)
		(fp_line
			(start 0.120396 0.2794)
			(end -0.12065 0.2794)
			(stroke
				(width 0.1)
				(type default)
			)
			(layer "F.Fab")
		)
		(fp_line
			(start -0.12065 -0.2794)
			(end 0.12065 -0.2794)
			(stroke
				(width 0.1)
				(type default)
			)
			(layer "F.Fab")
		)
		(fp_line
			(start 0.12065 -0.2794)
			(end 0.12065 -0.3048)
			(stroke
				(width 0.1)
				(type default)
			)
			(layer "F.Fab")
		)
		(fp_line
			(start 0.12065 -0.3048)
			(end 0.67945 -0.3048)
			(stroke
				(width 0.1)
				(type default)
			)
			(layer "F.Fab")
		)
		(fp_line
			(start 0.67945 -0.3048)
			(end 0.67945 0.3048)
			(stroke
				(width 0.1)
				(type default)
			)
			(layer "F.Fab")
		)
		(fp_line
			(start -0.67945 -0.305054)
			(end -0.12065 -0.305054)
			(stroke
				(width 0.1)
				(type default)
			)
			(layer "F.Fab")
		)
		(fp_line
			(start -0.12065 -0.305054)
			(end -0.12065 -0.2794)
			(stroke
				(width 0.1)
				(type default)
			)
			(layer "F.Fab")
		)
		(pad "1" smd circle
			(at -0.40005 0 270)
			(size 0 0)
			(layers "F.Cu" "F.Mask" "F.Paste")
			(net "P1V8_PEX")
		)
		(pad "2" smd circle
			(at 0.40005 0 270)
			(size 0 0)
			(layers "F.Cu" "F.Mask" "F.Paste")
			(net "I2C_PEX3_HOST_R_SCL")
		)
	)
	(footprint ""
		(layer "F.Cu")
		(at 366.955578 -83.784694 180)
		(property "Reference" "R1620"
			(at 0 0 180)
			(layer "F.SilkS")
			(hide yes)
			(effects
				(font
					(size 1.27 1.27)
				)
			)
		)
		(property "Value" ""
			(at 0 0 180)
			(layer "F.Fab")
			(effects
				(font
					(size 1.27 1.27)
				)
			)
		)
		(duplicate_pad_numbers_are_jumpers no)
		(fp_line
			(start 0.7874 0.4064)
			(end -0.7874 0.4064)
			(stroke
				(width 0.1524)
				(type default)
			)
			(layer "F.SilkS")
		)
		(fp_line
			(start 0.7874 -0.4064)
			(end 0.7874 0.4064)
			(stroke
				(width 0.1524)
				(type default)
			)
			(layer "F.SilkS")
		)
		(fp_line
			(start -0.7874 0.4064)
			(end -0.7874 -0.4064)
			(stroke
				(width 0.1524)
				(type default)
			)
			(layer "F.SilkS")
		)
		(fp_line
			(start -0.7874 -0.4064)
			(end 0.7874 -0.4064)
			(stroke
				(width 0.1524)
				(type default)
			)
			(layer "F.SilkS")
		)
		(fp_line
			(start 0.67945 0.3048)
			(end 0.120396 0.3048)
			(stroke
				(width 0.1)
				(type default)
			)
			(layer "F.Fab")
		)
		(fp_line
			(start 0.67945 -0.3048)
			(end 0.67945 0.3048)
			(stroke
				(width 0.1)
				(type default)
			)
			(layer "F.Fab")
		)
		(fp_line
			(start 0.12065 -0.2794)
			(end 0.12065 -0.3048)
			(stroke
				(width 0.1)
				(type default)
			)
			(layer "F.Fab")
		)
		(fp_line
			(start 0.12065 -0.3048)
			(end 0.67945 -0.3048)
			(stroke
				(width 0.1)
				(type default)
			)
			(layer "F.Fab")
		)
		(fp_line
			(start 0.120396 0.3048)
			(end 0.120396 0.2794)
			(stroke
				(width 0.1)
				(type default)
			)
			(layer "F.Fab")
		)
		(fp_line
			(start 0.120396 0.2794)
			(end -0.12065 0.2794)
			(stroke
				(width 0.1)
				(type default)
			)
			(layer "F.Fab")
		)
		(fp_line
			(start -0.12065 0.3048)
			(end -0.67945 0.3048)
			(stroke
				(width 0.1)
				(type default)
			)
			(layer "F.Fab")
		)
		(fp_line
			(start -0.12065 0.2794)
			(end -0.12065 0.3048)
			(stroke
				(width 0.1)
				(type default)
			)
			(layer "F.Fab")
		)
		(fp_line
			(start -0.12065 -0.2794)
			(end 0.12065 -0.2794)
			(stroke
				(width 0.1)
				(type default)
			)
			(layer "F.Fab")
		)
		(fp_line
			(start -0.12065 -0.305054)
			(end -0.12065 -0.2794)
			(stroke
				(width 0.1)
				(type default)
			)
			(layer "F.Fab")
		)
		(fp_line
			(start -0.67945 0.3048)
			(end -0.67945 -0.305054)
			(stroke
				(width 0.1)
				(type default)
			)
			(layer "F.Fab")
		)
		(fp_line
			(start -0.67945 -0.305054)
			(end -0.12065 -0.305054)
			(stroke
				(width 0.1)
				(type default)
			)
			(layer "F.Fab")
		)
		(pad "1" smd circle
			(at -0.40005 0 180)
			(size 0 0)
			(layers "F.Cu" "F.Mask" "F.Paste")
			(net "SMB_BIC_I2C9_MUX1_SSD13_R_SDA")
		)
		(pad "2" smd circle
			(at 0.40005 0 180)
			(size 0 0)
			(layers "F.Cu" "F.Mask" "F.Paste")
			(net "SMB_BIC_I2C9_MUX1_SSD13_SDA")
		)
	)
	(footprint ""
		(layer "F.Cu")
		(at 46.947328 -21.37156)
		(property "Reference" "C3881"
			(at 0 0 0)
			(layer "F.SilkS")
			(hide yes)
			(effects
				(font
					(size 1.27 1.27)
				)
			)
		)
		(property "Value" ""
			(at 0 0 0)
			(layer "F.Fab")
			(effects
				(font
					(size 1.27 1.27)
				)
			)
		)
		(duplicate_pad_numbers_are_jumpers no)
		(fp_line
			(start -0.7874 -0.4064)
			(end 0.7874 -0.4064)
			(stroke
				(width 0.1524)
				(type default)
			)
			(layer "F.SilkS")
		)
		(fp_line
			(start -0.7874 0.4064)
			(end -0.7874 -0.4064)
			(stroke
				(width 0.1524)
				(type default)
			)
			(layer "F.SilkS")
		)
		(fp_line
			(start 0.7874 -0.4064)
			(end 0.7874 0.4064)
			(stroke
				(width 0.1524)
				(type default)
			)
			(layer "F.SilkS")
		)
		(fp_line
			(start 0.7874 0.4064)
			(end -0.7874 0.4064)
			(stroke
				(width 0.1524)
				(type default)
			)
			(layer "F.SilkS")
		)
		(fp_line
			(start -0.67945 -0.305054)
			(end -0.12065 -0.305054)
			(stroke
				(width 0.1)
				(type default)
			)
			(layer "F.Fab")
		)
		(fp_line
			(start -0.67945 0.3048)
			(end -0.67945 -0.305054)
			(stroke
				(width 0.1)
				(type default)
			)
			(layer "F.Fab")
		)
		(fp_line
			(start -0.12065 -0.305054)
			(end -0.12065 -0.2794)
			(stroke
				(width 0.1)
				(type default)
			)
			(layer "F.Fab")
		)
		(fp_line
			(start -0.12065 -0.2794)
			(end 0.12065 -0.2794)
			(stroke
				(width 0.1)
				(type default)
			)
			(layer "F.Fab")
		)
		(fp_line
			(start -0.12065 0.2794)
			(end -0.12065 0.3048)
			(stroke
				(width 0.1)
				(type default)
			)
			(layer "F.Fab")
		)
		(fp_line
			(start -0.12065 0.3048)
			(end -0.67945 0.3048)
			(stroke
				(width 0.1)
				(type default)
			)
			(layer "F.Fab")
		)
		(fp_line
			(start 0.120396 0.2794)
			(end -0.12065 0.2794)
			(stroke
				(width 0.1)
				(type default)
			)
			(layer "F.Fab")
		)
		(fp_line
			(start 0.120396 0.3048)
			(end 0.120396 0.2794)
			(stroke
				(width 0.1)
				(type default)
			)
			(layer "F.Fab")
		)
		(fp_line
			(start 0.12065 -0.3048)
			(end 0.67945 -0.3048)
			(stroke
				(width 0.1)
				(type default)
			)
			(layer "F.Fab")
		)
		(fp_line
			(start 0.12065 -0.2794)
			(end 0.12065 -0.3048)
			(stroke
				(width 0.1)
				(type default)
			)
			(layer "F.Fab")
		)
		(fp_line
			(start 0.67945 -0.3048)
			(end 0.67945 0.3048)
			(stroke
				(width 0.1)
				(type default)
			)
			(layer "F.Fab")
		)
		(fp_line
			(start 0.67945 0.3048)
			(end 0.120396 0.3048)
			(stroke
				(width 0.1)
				(type default)
			)
			(layer "F.Fab")
		)
		(pad "1" smd circle
			(at -0.40005 0)
			(size 0 0)
			(layers "F.Cu" "F.Mask" "F.Paste")
			(net "P12V_SSD1")
		)
		(pad "2" smd circle
			(at 0.40005 0)
			(size 0 0)
			(layers "F.Cu" "F.Mask" "F.Paste")
			(net "GND")
		)
	)
	(footprint ""
		(layer "F.Cu")
		(at 5.462524 -255.046734 -90)
		(property "Reference" "R6472"
			(at 0 0 270)
			(layer "F.SilkS")
			(hide yes)
			(effects
				(font
					(size 1.27 1.27)
				)
			)
		)
		(property "Value" ""
			(at 0 0 270)
			(layer "F.Fab")
			(effects
				(font
					(size 1.27 1.27)
				)
			)
		)
		(duplicate_pad_numbers_are_jumpers no)
		(fp_line
			(start -0.7874 0.4064)
			(end -0.7874 -0.4064)
			(stroke
				(width 0.1524)
				(type default)
			)
			(layer "F.SilkS")
		)
		(fp_line
			(start 0.7874 0.4064)
			(end -0.7874 0.4064)
			(stroke
				(width 0.1524)
				(type default)
			)
			(layer "F.SilkS")
		)
		(fp_line
			(start -0.7874 -0.4064)
			(end 0.7874 -0.4064)
			(stroke
				(width 0.1524)
				(type default)
			)
			(layer "F.SilkS")
		)
		(fp_line
			(start 0.7874 -0.4064)
			(end 0.7874 0.4064)
			(stroke
				(width 0.1524)
				(type default)
			)
			(layer "F.SilkS")
		)
		(fp_line
			(start -0.67945 0.3048)
			(end -0.67945 -0.305054)
			(stroke
				(width 0.1)
				(type default)
			)
			(layer "F.Fab")
		)
		(fp_line
			(start -0.12065 0.3048)
			(end -0.67945 0.3048)
			(stroke
				(width 0.1)
				(type default)
			)
			(layer "F.Fab")
		)
		(fp_line
			(start 0.120396 0.3048)
			(end 0.120396 0.2794)
			(stroke
				(width 0.1)
				(type default)
			)
			(layer "F.Fab")
		)
		(fp_line
			(start 0.67945 0.3048)
			(end 0.120396 0.3048)
			(stroke
				(width 0.1)
				(type default)
			)
			(layer "F.Fab")
		)
		(fp_line
			(start -0.12065 0.2794)
			(end -0.12065 0.3048)
			(stroke
				(width 0.1)
				(type default)
			)
			(layer "F.Fab")
		)
		(fp_line
			(start 0.120396 0.2794)
			(end -0.12065 0.2794)
			(stroke
				(width 0.1)
				(type default)
			)
			(layer "F.Fab")
		)
		(fp_line
			(start -0.12065 -0.2794)
			(end 0.12065 -0.2794)
			(stroke
				(width 0.1)
				(type default)
			)
			(layer "F.Fab")
		)
		(fp_line
			(start 0.12065 -0.2794)
			(end 0.12065 -0.3048)
			(stroke
				(width 0.1)
				(type default)
			)
			(layer "F.Fab")
		)
		(fp_line
			(start 0.12065 -0.3048)
			(end 0.67945 -0.3048)
			(stroke
				(width 0.1)
				(type default)
			)
			(layer "F.Fab")
		)
		(fp_line
			(start 0.67945 -0.3048)
			(end 0.67945 0.3048)
			(stroke
				(width 0.1)
				(type default)
			)
			(layer "F.Fab")
		)
		(fp_line
			(start -0.67945 -0.305054)
			(end -0.12065 -0.305054)
			(stroke
				(width 0.1)
				(type default)
			)
			(layer "F.Fab")
		)
		(fp_line
			(start -0.12065 -0.305054)
			(end -0.12065 -0.2794)
			(stroke
				(width 0.1)
				(type default)
			)
			(layer "F.Fab")
		)
		(pad "1" smd circle
			(at -0.40005 0 270)
			(size 0 0)
			(layers "F.Cu" "F.Mask" "F.Paste")
			(net "P1V25_SERDES_VDDPLL_PEX0")
		)
		(pad "2" smd circle
			(at 0.40005 0 270)
			(size 0 0)
			(layers "F.Cu" "F.Mask" "F.Paste")
			(net "P1V25_SERDES_VDDPLL_PEX0_C9")
		)
	)
	(footprint ""
		(layer "F.Cu")
		(at 405.015192 -59.546236 90)
		(property "Reference" "C2898"
			(at 0 0 90)
			(layer "F.SilkS")
			(hide yes)
			(effects
				(font
					(size 1.27 1.27)
				)
			)
		)
		(property "Value" ""
			(at 0 0 90)
			(layer "F.Fab")
			(effects
				(font
					(size 1.27 1.27)
				)
			)
		)
		(duplicate_pad_numbers_are_jumpers no)
		(fp_line
			(start 0.7874 -0.4064)
			(end 0.7874 0.4064)
			(stroke
				(width 0.1524)
				(type default)
			)
			(layer "F.SilkS")
		)
		(fp_line
			(start -0.7874 -0.4064)
			(end 0.7874 -0.4064)
			(stroke
				(width 0.1524)
				(type default)
			)
			(layer "F.SilkS")
		)
		(fp_line
			(start 0.7874 0.4064)
			(end -0.7874 0.4064)
			(stroke
				(width 0.1524)
				(type default)
			)
			(layer "F.SilkS")
		)
		(fp_line
			(start -0.7874 0.4064)
			(end -0.7874 -0.4064)
			(stroke
				(width 0.1524)
				(type default)
			)
			(layer "F.SilkS")
		)
		(fp_line
			(start -0.12065 -0.305054)
			(end -0.12065 -0.2794)
			(stroke
				(width 0.1)
				(type default)
			)
			(layer "F.Fab")
		)
		(fp_line
			(start -0.67945 -0.305054)
			(end -0.12065 -0.305054)
			(stroke
				(width 0.1)
				(type default)
			)
			(layer "F.Fab")
		)
		(fp_line
			(start 0.67945 -0.3048)
			(end 0.67945 0.3048)
			(stroke
				(width 0.1)
				(type default)
			)
			(layer "F.Fab")
		)
		(fp_line
			(start 0.12065 -0.3048)
			(end 0.67945 -0.3048)
			(stroke
				(width 0.1)
				(type default)
			)
			(layer "F.Fab")
		)
		(fp_line
			(start 0.12065 -0.2794)
			(end 0.12065 -0.3048)
			(stroke
				(width 0.1)
				(type default)
			)
			(layer "F.Fab")
		)
		(fp_line
			(start -0.12065 -0.2794)
			(end 0.12065 -0.2794)
			(stroke
				(width 0.1)
				(type default)
			)
			(layer "F.Fab")
		)
		(fp_line
			(start 0.120396 0.2794)
			(end -0.12065 0.2794)
			(stroke
				(width 0.1)
				(type default)
			)
			(layer "F.Fab")
		)
		(fp_line
			(start -0.12065 0.2794)
			(end -0.12065 0.3048)
			(stroke
				(width 0.1)
				(type default)
			)
			(layer "F.Fab")
		)
		(fp_line
			(start 0.67945 0.3048)
			(end 0.120396 0.3048)
			(stroke
				(width 0.1)
				(type default)
			)
			(layer "F.Fab")
		)
		(fp_line
			(start 0.120396 0.3048)
			(end 0.120396 0.2794)
			(stroke
				(width 0.1)
				(type default)
			)
			(layer "F.Fab")
		)
		(fp_line
			(start -0.12065 0.3048)
			(end -0.67945 0.3048)
			(stroke
				(width 0.1)
				(type default)
			)
			(layer "F.Fab")
		)
		(fp_line
			(start -0.67945 0.3048)
			(end -0.67945 -0.305054)
			(stroke
				(width 0.1)
				(type default)
			)
			(layer "F.Fab")
		)
		(pad "1" smd circle
			(at -0.40005 0 90)
			(size 0 0)
			(layers "F.Cu" "F.Mask" "F.Paste")
			(net "SSD14_AUX_P3V3_EN_R")
		)
		(pad "2" smd circle
			(at 0.40005 0 90)
			(size 0 0)
			(layers "F.Cu" "F.Mask" "F.Paste")
			(net "GND")
		)
	)
	(footprint ""
		(layer "F.Cu")
		(at 233.871008 -83.318858 90)
		(property "Reference" "R1011"
			(at 0 0 90)
			(layer "F.SilkS")
			(hide yes)
			(effects
				(font
					(size 1.27 1.27)
				)
			)
		)
		(property "Value" ""
			(at 0 0 90)
			(layer "F.Fab")
			(effects
				(font
					(size 1.27 1.27)
				)
			)
		)
		(duplicate_pad_numbers_are_jumpers no)
		(fp_line
			(start -0.015748 -0.4064)
			(end 0.7874 -0.4064)
			(stroke
				(width 0.1524)
				(type default)
			)
			(layer "F.SilkS")
		)
		(fp_line
			(start 0.7874 0.4064)
			(end -0.7874 0.4064)
			(stroke
				(width 0.1524)
				(type default)
			)
			(layer "F.SilkS")
		)
		(fp_line
			(start -0.7874 0.4064)
			(end -0.7874 -0.4064)
			(stroke
				(width 0.1524)
				(type default)
			)
			(layer "F.SilkS")
		)
		(fp_line
			(start -0.12065 -0.305054)
			(end -0.12065 -0.2794)
			(stroke
				(width 0.1)
				(type default)
			)
			(layer "F.Fab")
		)
		(fp_line
			(start -0.67945 -0.305054)
			(end -0.12065 -0.305054)
			(stroke
				(width 0.1)
				(type default)
			)
			(layer "F.Fab")
		)
		(fp_line
			(start 0.67945 -0.3048)
			(end 0.67945 0.3048)
			(stroke
				(width 0.1)
				(type default)
			)
			(layer "F.Fab")
		)
		(fp_line
			(start 0.12065 -0.3048)
			(end 0.67945 -0.3048)
			(stroke
				(width 0.1)
				(type default)
			)
			(layer "F.Fab")
		)
		(fp_line
			(start 0.12065 -0.2794)
			(end 0.12065 -0.3048)
			(stroke
				(width 0.1)
				(type default)
			)
			(layer "F.Fab")
		)
		(fp_line
			(start -0.12065 -0.2794)
			(end 0.12065 -0.2794)
			(stroke
				(width 0.1)
				(type default)
			)
			(layer "F.Fab")
		)
		(fp_line
			(start 0.120396 0.2794)
			(end -0.12065 0.2794)
			(stroke
				(width 0.1)
				(type default)
			)
			(layer "F.Fab")
		)
		(fp_line
			(start -0.12065 0.2794)
			(end -0.12065 0.3048)
			(stroke
				(width 0.1)
				(type default)
			)
			(layer "F.Fab")
		)
		(fp_line
			(start 0.67945 0.3048)
			(end 0.120396 0.3048)
			(stroke
				(width 0.1)
				(type default)
			)
			(layer "F.Fab")
		)
		(fp_line
			(start 0.120396 0.3048)
			(end 0.120396 0.2794)
			(stroke
				(width 0.1)
				(type default)
			)
			(layer "F.Fab")
		)
		(fp_line
			(start -0.12065 0.3048)
			(end -0.67945 0.3048)
			(stroke
				(width 0.1)
				(type default)
			)
			(layer "F.Fab")
		)
		(fp_line
			(start -0.67945 0.3048)
			(end -0.67945 -0.305054)
			(stroke
				(width 0.1)
				(type default)
			)
			(layer "F.Fab")
		)
		(pad "1" smd rect
			(at -0.40005 0 270)
			(size 0.4572 0.508)
			(layers "F.Cu" "F.Mask" "F.Paste")
			(net "USB2_FT4232_SDB_R_DP")
		)
		(pad "2" smd rect
			(at 0.40005 0 270)
			(size 0.4572 0.508)
			(layers "F.Cu" "F.Mask" "F.Paste")
			(net "USB2_FT4232_SDB_DP")
		)
	)
	(footprint ""
		(layer "F.Cu")
		(at 188.775086 -56.977534 180)
		(property "Reference" "PC378"
			(at 0 0 180)
			(layer "F.SilkS")
			(hide yes)
			(effects
				(font
					(size 1.27 1.27)
				)
			)
		)
		(property "Value" ""
			(at 0 0 180)
			(layer "F.Fab")
			(effects
				(font
					(size 1.27 1.27)
				)
			)
		)
		(duplicate_pad_numbers_are_jumpers no)
		(fp_line
			(start 0.7874 0.4064)
			(end -0.7874 0.4064)
			(stroke
				(width 0.1524)
				(type default)
			)
			(layer "F.SilkS")
		)
		(fp_line
			(start 0.7874 -0.4064)
			(end 0.7874 0.4064)
			(stroke
				(width 0.1524)
				(type default)
			)
			(layer "F.SilkS")
		)
		(fp_line
			(start -0.7874 0.4064)
			(end -0.7874 -0.4064)
			(stroke
				(width 0.1524)
				(type default)
			)
			(layer "F.SilkS")
		)
		(fp_line
			(start -0.7874 -0.4064)
			(end 0.7874 -0.4064)
			(stroke
				(width 0.1524)
				(type default)
			)
			(layer "F.SilkS")
		)
		(fp_line
			(start 0.67945 0.3048)
			(end 0.120396 0.3048)
			(stroke
				(width 0.1)
				(type default)
			)
			(layer "F.Fab")
		)
		(fp_line
			(start 0.67945 -0.3048)
			(end 0.67945 0.3048)
			(stroke
				(width 0.1)
				(type default)
			)
			(layer "F.Fab")
		)
		(fp_line
			(start 0.12065 -0.2794)
			(end 0.12065 -0.3048)
			(stroke
				(width 0.1)
				(type default)
			)
			(layer "F.Fab")
		)
		(fp_line
			(start 0.12065 -0.3048)
			(end 0.67945 -0.3048)
			(stroke
				(width 0.1)
				(type default)
			)
			(layer "F.Fab")
		)
		(fp_line
			(start 0.120396 0.3048)
			(end 0.120396 0.2794)
			(stroke
				(width 0.1)
				(type default)
			)
			(layer "F.Fab")
		)
		(fp_line
			(start 0.120396 0.2794)
			(end -0.12065 0.2794)
			(stroke
				(width 0.1)
				(type default)
			)
			(layer "F.Fab")
		)
		(fp_line
			(start -0.12065 0.3048)
			(end -0.67945 0.3048)
			(stroke
				(width 0.1)
				(type default)
			)
			(layer "F.Fab")
		)
		(fp_line
			(start -0.12065 0.2794)
			(end -0.12065 0.3048)
			(stroke
				(width 0.1)
				(type default)
			)
			(layer "F.Fab")
		)
		(fp_line
			(start -0.12065 -0.2794)
			(end 0.12065 -0.2794)
			(stroke
				(width 0.1)
				(type default)
			)
			(layer "F.Fab")
		)
		(fp_line
			(start -0.12065 -0.305054)
			(end -0.12065 -0.2794)
			(stroke
				(width 0.1)
				(type default)
			)
			(layer "F.Fab")
		)
		(fp_line
			(start -0.67945 0.3048)
			(end -0.67945 -0.305054)
			(stroke
				(width 0.1)
				(type default)
			)
			(layer "F.Fab")
		)
		(fp_line
			(start -0.67945 -0.305054)
			(end -0.12065 -0.305054)
			(stroke
				(width 0.1)
				(type default)
			)
			(layer "F.Fab")
		)
		(pad "1" smd circle
			(at -0.40005 0 180)
			(size 0 0)
			(layers "F.Cu" "F.Mask" "F.Paste")
			(net "P12V_AUX")
		)
		(pad "2" smd circle
			(at 0.40005 0 180)
			(size 0 0)
			(layers "F.Cu" "F.Mask" "F.Paste")
			(net "GND")
		)
	)
	(footprint ""
		(layer "F.Cu")
		(at 326.694038 -117.426486)
		(property "Reference" "PC906"
			(at 0 0 0)
			(layer "F.SilkS")
			(hide yes)
			(effects
				(font
					(size 1.27 1.27)
				)
			)
		)
		(property "Value" ""
			(at 0 0 0)
			(layer "F.Fab")
			(effects
				(font
					(size 1.27 1.27)
				)
			)
		)
		(duplicate_pad_numbers_are_jumpers no)
		(fp_line
			(start -0.7874 -0.4064)
			(end 0.7874 -0.4064)
			(stroke
				(width 0.1524)
				(type default)
			)
			(layer "F.SilkS")
		)
		(fp_line
			(start -0.7874 0.4064)
			(end -0.7874 -0.4064)
			(stroke
				(width 0.1524)
				(type default)
			)
			(layer "F.SilkS")
		)
		(fp_line
			(start 0.7874 -0.4064)
			(end 0.7874 0.4064)
			(stroke
				(width 0.1524)
				(type default)
			)
			(layer "F.SilkS")
		)
		(fp_line
			(start 0.7874 0.4064)
			(end -0.7874 0.4064)
			(stroke
				(width 0.1524)
				(type default)
			)
			(layer "F.SilkS")
		)
		(fp_line
			(start -0.67945 -0.305054)
			(end -0.12065 -0.305054)
			(stroke
				(width 0.1)
				(type default)
			)
			(layer "F.Fab")
		)
		(fp_line
			(start -0.67945 0.3048)
			(end -0.67945 -0.305054)
			(stroke
				(width 0.1)
				(type default)
			)
			(layer "F.Fab")
		)
		(fp_line
			(start -0.12065 -0.305054)
			(end -0.12065 -0.2794)
			(stroke
				(width 0.1)
				(type default)
			)
			(layer "F.Fab")
		)
		(fp_line
			(start -0.12065 -0.2794)
			(end 0.12065 -0.2794)
			(stroke
				(width 0.1)
				(type default)
			)
			(layer "F.Fab")
		)
		(fp_line
			(start -0.12065 0.2794)
			(end -0.12065 0.3048)
			(stroke
				(width 0.1)
				(type default)
			)
			(layer "F.Fab")
		)
		(fp_line
			(start -0.12065 0.3048)
			(end -0.67945 0.3048)
			(stroke
				(width 0.1)
				(type default)
			)
			(layer "F.Fab")
		)
		(fp_line
			(start 0.120396 0.2794)
			(end -0.12065 0.2794)
			(stroke
				(width 0.1)
				(type default)
			)
			(layer "F.Fab")
		)
		(fp_line
			(start 0.120396 0.3048)
			(end 0.120396 0.2794)
			(stroke
				(width 0.1)
				(type default)
			)
			(layer "F.Fab")
		)
		(fp_line
			(start 0.12065 -0.3048)
			(end 0.67945 -0.3048)
			(stroke
				(width 0.1)
				(type default)
			)
			(layer "F.Fab")
		)
		(fp_line
			(start 0.12065 -0.2794)
			(end 0.12065 -0.3048)
			(stroke
				(width 0.1)
				(type default)
			)
			(layer "F.Fab")
		)
		(fp_line
			(start 0.67945 -0.3048)
			(end 0.67945 0.3048)
			(stroke
				(width 0.1)
				(type default)
			)
			(layer "F.Fab")
		)
		(fp_line
			(start 0.67945 0.3048)
			(end 0.120396 0.3048)
			(stroke
				(width 0.1)
				(type default)
			)
			(layer "F.Fab")
		)
		(pad "1" smd circle
			(at -0.40005 0)
			(size 0 0)
			(layers "F.Cu" "F.Mask" "F.Paste")
			(net "P3V3_NIC5_CO_MODE")
		)
		(pad "2" smd circle
			(at 0.40005 0)
			(size 0 0)
			(layers "F.Cu" "F.Mask" "F.Paste")
			(net "GND")
		)
	)
	(footprint ""
		(layer "F.Cu")
		(at 294.50919 -210.094068 -90)
		(property "Reference" "R3368"
			(at 0 0 270)
			(layer "F.SilkS")
			(hide yes)
			(effects
				(font
					(size 1.27 1.27)
				)
			)
		)
		(property "Value" ""
			(at 0 0 270)
			(layer "F.Fab")
			(effects
				(font
					(size 1.27 1.27)
				)
			)
		)
		(duplicate_pad_numbers_are_jumpers no)
		(fp_line
			(start -0.7874 0.4064)
			(end -0.7874 -0.4064)
			(stroke
				(width 0.1524)
				(type default)
			)
			(layer "F.SilkS")
		)
		(fp_line
			(start 0.7874 0.4064)
			(end -0.7874 0.4064)
			(stroke
				(width 0.1524)
				(type default)
			)
			(layer "F.SilkS")
		)
		(fp_line
			(start -0.7874 -0.4064)
			(end 0.7874 -0.4064)
			(stroke
				(width 0.1524)
				(type default)
			)
			(layer "F.SilkS")
		)
		(fp_line
			(start 0.7874 -0.4064)
			(end 0.7874 0.4064)
			(stroke
				(width 0.1524)
				(type default)
			)
			(layer "F.SilkS")
		)
		(fp_line
			(start -0.67945 0.3048)
			(end -0.67945 -0.305054)
			(stroke
				(width 0.1)
				(type default)
			)
			(layer "F.Fab")
		)
		(fp_line
			(start -0.12065 0.3048)
			(end -0.67945 0.3048)
			(stroke
				(width 0.1)
				(type default)
			)
			(layer "F.Fab")
		)
		(fp_line
			(start 0.120396 0.3048)
			(end 0.120396 0.2794)
			(stroke
				(width 0.1)
				(type default)
			)
			(layer "F.Fab")
		)
		(fp_line
			(start 0.67945 0.3048)
			(end 0.120396 0.3048)
			(stroke
				(width 0.1)
				(type default)
			)
			(layer "F.Fab")
		)
		(fp_line
			(start -0.12065 0.2794)
			(end -0.12065 0.3048)
			(stroke
				(width 0.1)
				(type default)
			)
			(layer "F.Fab")
		)
		(fp_line
			(start 0.120396 0.2794)
			(end -0.12065 0.2794)
			(stroke
				(width 0.1)
				(type default)
			)
			(layer "F.Fab")
		)
		(fp_line
			(start -0.12065 -0.2794)
			(end 0.12065 -0.2794)
			(stroke
				(width 0.1)
				(type default)
			)
			(layer "F.Fab")
		)
		(fp_line
			(start 0.12065 -0.2794)
			(end 0.12065 -0.3048)
			(stroke
				(width 0.1)
				(type default)
			)
			(layer "F.Fab")
		)
		(fp_line
			(start 0.12065 -0.3048)
			(end 0.67945 -0.3048)
			(stroke
				(width 0.1)
				(type default)
			)
			(layer "F.Fab")
		)
		(fp_line
			(start 0.67945 -0.3048)
			(end 0.67945 0.3048)
			(stroke
				(width 0.1)
				(type default)
			)
			(layer "F.Fab")
		)
		(fp_line
			(start -0.67945 -0.305054)
			(end -0.12065 -0.305054)
			(stroke
				(width 0.1)
				(type default)
			)
			(layer "F.Fab")
		)
		(fp_line
			(start -0.12065 -0.305054)
			(end -0.12065 -0.2794)
			(stroke
				(width 0.1)
				(type default)
			)
			(layer "F.Fab")
		)
		(pad "1" smd circle
			(at -0.40005 0 270)
			(size 0 0)
			(layers "F.Cu" "F.Mask" "F.Paste")
			(net "SPI_BIC1_MISO_LS23_R")
		)
		(pad "2" smd circle
			(at 0.40005 0 270)
			(size 0 0)
			(layers "F.Cu" "F.Mask" "F.Paste")
			(net "SPI_BIC1_MISO_LS23")
		)
	)
	(footprint ""
		(layer "F.Cu")
		(at 284.784038 -29.222954 -90)
		(property "Reference" "PC939"
			(at 0 0 270)
			(layer "F.SilkS")
			(hide yes)
			(effects
				(font
					(size 1.27 1.27)
				)
			)
		)
		(property "Value" ""
			(at 0 0 270)
			(layer "F.Fab")
			(effects
				(font
					(size 1.27 1.27)
				)
			)
		)
		(duplicate_pad_numbers_are_jumpers no)
		(fp_line
			(start -0.7874 0.4064)
			(end -0.7874 -0.4064)
			(stroke
				(width 0.1524)
				(type default)
			)
			(layer "F.SilkS")
		)
		(fp_line
			(start 0.7874 0.4064)
			(end -0.7874 0.4064)
			(stroke
				(width 0.1524)
				(type default)
			)
			(layer "F.SilkS")
		)
		(fp_line
			(start -0.7874 -0.4064)
			(end 0.7874 -0.4064)
			(stroke
				(width 0.1524)
				(type default)
			)
			(layer "F.SilkS")
		)
		(fp_line
			(start 0.7874 -0.4064)
			(end 0.7874 0.4064)
			(stroke
				(width 0.1524)
				(type default)
			)
			(layer "F.SilkS")
		)
		(fp_line
			(start -0.67945 0.3048)
			(end -0.67945 -0.305054)
			(stroke
				(width 0.1)
				(type default)
			)
			(layer "F.Fab")
		)
		(fp_line
			(start -0.12065 0.3048)
			(end -0.67945 0.3048)
			(stroke
				(width 0.1)
				(type default)
			)
			(layer "F.Fab")
		)
		(fp_line
			(start 0.120396 0.3048)
			(end 0.120396 0.2794)
			(stroke
				(width 0.1)
				(type default)
			)
			(layer "F.Fab")
		)
		(fp_line
			(start 0.67945 0.3048)
			(end 0.120396 0.3048)
			(stroke
				(width 0.1)
				(type default)
			)
			(layer "F.Fab")
		)
		(fp_line
			(start -0.12065 0.2794)
			(end -0.12065 0.3048)
			(stroke
				(width 0.1)
				(type default)
			)
			(layer "F.Fab")
		)
		(fp_line
			(start 0.120396 0.2794)
			(end -0.12065 0.2794)
			(stroke
				(width 0.1)
				(type default)
			)
			(layer "F.Fab")
		)
		(fp_line
			(start -0.12065 -0.2794)
			(end 0.12065 -0.2794)
			(stroke
				(width 0.1)
				(type default)
			)
			(layer "F.Fab")
		)
		(fp_line
			(start 0.12065 -0.2794)
			(end 0.12065 -0.3048)
			(stroke
				(width 0.1)
				(type default)
			)
			(layer "F.Fab")
		)
		(fp_line
			(start 0.12065 -0.3048)
			(end 0.67945 -0.3048)
			(stroke
				(width 0.1)
				(type default)
			)
			(layer "F.Fab")
		)
		(fp_line
			(start 0.67945 -0.3048)
			(end 0.67945 0.3048)
			(stroke
				(width 0.1)
				(type default)
			)
			(layer "F.Fab")
		)
		(fp_line
			(start -0.67945 -0.305054)
			(end -0.12065 -0.305054)
			(stroke
				(width 0.1)
				(type default)
			)
			(layer "F.Fab")
		)
		(fp_line
			(start -0.12065 -0.305054)
			(end -0.12065 -0.2794)
			(stroke
				(width 0.1)
				(type default)
			)
			(layer "F.Fab")
		)
		(pad "1" smd circle
			(at -0.40005 0 270)
			(size 0 0)
			(layers "F.Cu" "F.Mask" "F.Paste")
			(net "P3V3_AUX")
		)
		(pad "2" smd circle
			(at 0.40005 0 270)
			(size 0 0)
			(layers "F.Cu" "F.Mask" "F.Paste")
			(net "GND")
		)
	)
	(footprint ""
		(layer "F.Cu")
		(at 172.081444 -158.8516)
		(property "Reference" "R149"
			(at 0 0 0)
			(layer "F.SilkS")
			(hide yes)
			(effects
				(font
					(size 1.27 1.27)
				)
			)
		)
		(property "Value" ""
			(at 0 0 0)
			(layer "F.Fab")
			(effects
				(font
					(size 1.27 1.27)
				)
			)
		)
		(duplicate_pad_numbers_are_jumpers no)
		(fp_line
			(start -0.7874 -0.4064)
			(end 0.7874 -0.4064)
			(stroke
				(width 0.1524)
				(type default)
			)
			(layer "F.SilkS")
		)
		(fp_line
			(start -0.7874 0.4064)
			(end -0.7874 -0.4064)
			(stroke
				(width 0.1524)
				(type default)
			)
			(layer "F.SilkS")
		)
		(fp_line
			(start 0.7874 -0.4064)
			(end 0.7874 0.4064)
			(stroke
				(width 0.1524)
				(type default)
			)
			(layer "F.SilkS")
		)
		(fp_line
			(start 0.7874 0.4064)
			(end -0.7874 0.4064)
			(stroke
				(width 0.1524)
				(type default)
			)
			(layer "F.SilkS")
		)
		(fp_line
			(start -0.67945 -0.305054)
			(end -0.12065 -0.305054)
			(stroke
				(width 0.1)
				(type default)
			)
			(layer "F.Fab")
		)
		(fp_line
			(start -0.67945 0.3048)
			(end -0.67945 -0.305054)
			(stroke
				(width 0.1)
				(type default)
			)
			(layer "F.Fab")
		)
		(fp_line
			(start -0.12065 -0.305054)
			(end -0.12065 -0.2794)
			(stroke
				(width 0.1)
				(type default)
			)
			(layer "F.Fab")
		)
		(fp_line
			(start -0.12065 -0.2794)
			(end 0.12065 -0.2794)
			(stroke
				(width 0.1)
				(type default)
			)
			(layer "F.Fab")
		)
		(fp_line
			(start -0.12065 0.2794)
			(end -0.12065 0.3048)
			(stroke
				(width 0.1)
				(type default)
			)
			(layer "F.Fab")
		)
		(fp_line
			(start -0.12065 0.3048)
			(end -0.67945 0.3048)
			(stroke
				(width 0.1)
				(type default)
			)
			(layer "F.Fab")
		)
		(fp_line
			(start 0.120396 0.2794)
			(end -0.12065 0.2794)
			(stroke
				(width 0.1)
				(type default)
			)
			(layer "F.Fab")
		)
		(fp_line
			(start 0.120396 0.3048)
			(end 0.120396 0.2794)
			(stroke
				(width 0.1)
				(type default)
			)
			(layer "F.Fab")
		)
		(fp_line
			(start 0.12065 -0.3048)
			(end 0.67945 -0.3048)
			(stroke
				(width 0.1)
				(type default)
			)
			(layer "F.Fab")
		)
		(fp_line
			(start 0.12065 -0.2794)
			(end 0.12065 -0.3048)
			(stroke
				(width 0.1)
				(type default)
			)
			(layer "F.Fab")
		)
		(fp_line
			(start 0.67945 -0.3048)
			(end 0.67945 0.3048)
			(stroke
				(width 0.1)
				(type default)
			)
			(layer "F.Fab")
		)
		(fp_line
			(start 0.67945 0.3048)
			(end 0.120396 0.3048)
			(stroke
				(width 0.1)
				(type default)
			)
			(layer "F.Fab")
		)
		(pad "1" smd circle
			(at -0.40005 0)
			(size 0 0)
			(layers "F.Cu" "F.Mask" "F.Paste")
			(net "RST_NIC2_PERST2_R_N")
		)
		(pad "2" smd circle
			(at 0.40005 0)
			(size 0 0)
			(layers "F.Cu" "F.Mask" "F.Paste")
			(net "RST_HP_NIC2_BUF_N")
		)
	)
	(footprint ""
		(layer "F.Cu")
		(at 201.415142 -20.72513)
		(property "Reference" "H130"
			(at 1.661668 -2.573274 0)
			(unlocked yes)
			(layer "B.SilkS")
			(effects
				(font
					(size 0.7874 0.5842)
					(thickness 0.1524)
				)
				(justify left mirror)
			)
		)
		(property "Value" ""
			(at 0 0 0)
			(layer "F.Fab")
			(effects
				(font
					(size 1.27 1.27)
				)
			)
		)
		(duplicate_pad_numbers_are_jumpers no)
		(pad "1" thru_hole rect
			(at 0 0)
			(size 4.2164 5.0038)
			(drill 2.0066
				(offset 0.099822 0)
			)
			(layers "*.Cu" "*.Mask")
			(remove_unused_layers no)
			(net "Net_8533")
			(clearance -0.8509)
			(padstack
				(mode front_inner_back)
				(layer "Inner"
					(shape circle)
					(size 4.0132 4.0132)
					(clearance -0.7493)
				)
				(layer "B.Cu"
					(shape circle)
					(size 4.0132 4.0132)
					(clearance -0.7493)
				)
			)
		)
	)
	(footprint ""
		(layer "F.Cu")
		(at 121.39422 -35.264852)
		(property "Reference" "R5671"
			(at 0 0 0)
			(layer "F.SilkS")
			(hide yes)
			(effects
				(font
					(size 1.27 1.27)
				)
			)
		)
		(property "Value" ""
			(at 0 0 0)
			(layer "F.Fab")
			(effects
				(font
					(size 1.27 1.27)
				)
			)
		)
		(duplicate_pad_numbers_are_jumpers no)
		(fp_line
			(start -0.7874 -0.4064)
			(end 0.7874 -0.4064)
			(stroke
				(width 0.1524)
				(type default)
			)
			(layer "F.SilkS")
		)
		(fp_line
			(start -0.7874 0.4064)
			(end -0.7874 -0.4064)
			(stroke
				(width 0.1524)
				(type default)
			)
			(layer "F.SilkS")
		)
		(fp_line
			(start 0.7874 -0.4064)
			(end 0.7874 0.4064)
			(stroke
				(width 0.1524)
				(type default)
			)
			(layer "F.SilkS")
		)
		(fp_line
			(start 0.7874 0.4064)
			(end -0.7874 0.4064)
			(stroke
				(width 0.1524)
				(type default)
			)
			(layer "F.SilkS")
		)
		(fp_line
			(start -0.67945 -0.305054)
			(end -0.12065 -0.305054)
			(stroke
				(width 0.1)
				(type default)
			)
			(layer "F.Fab")
		)
		(fp_line
			(start -0.67945 0.3048)
			(end -0.67945 -0.305054)
			(stroke
				(width 0.1)
				(type default)
			)
			(layer "F.Fab")
		)
		(fp_line
			(start -0.12065 -0.305054)
			(end -0.12065 -0.2794)
			(stroke
				(width 0.1)
				(type default)
			)
			(layer "F.Fab")
		)
		(fp_line
			(start -0.12065 -0.2794)
			(end 0.12065 -0.2794)
			(stroke
				(width 0.1)
				(type default)
			)
			(layer "F.Fab")
		)
		(fp_line
			(start -0.12065 0.2794)
			(end -0.12065 0.3048)
			(stroke
				(width 0.1)
				(type default)
			)
			(layer "F.Fab")
		)
		(fp_line
			(start -0.12065 0.3048)
			(end -0.67945 0.3048)
			(stroke
				(width 0.1)
				(type default)
			)
			(layer "F.Fab")
		)
		(fp_line
			(start 0.120396 0.2794)
			(end -0.12065 0.2794)
			(stroke
				(width 0.1)
				(type default)
			)
			(layer "F.Fab")
		)
		(fp_line
			(start 0.120396 0.3048)
			(end 0.120396 0.2794)
			(stroke
				(width 0.1)
				(type default)
			)
			(layer "F.Fab")
		)
		(fp_line
			(start 0.12065 -0.3048)
			(end 0.67945 -0.3048)
			(stroke
				(width 0.1)
				(type default)
			)
			(layer "F.Fab")
		)
		(fp_line
			(start 0.12065 -0.2794)
			(end 0.12065 -0.3048)
			(stroke
				(width 0.1)
				(type default)
			)
			(layer "F.Fab")
		)
		(fp_line
			(start 0.67945 -0.3048)
			(end 0.67945 0.3048)
			(stroke
				(width 0.1)
				(type default)
			)
			(layer "F.Fab")
		)
		(fp_line
			(start 0.67945 0.3048)
			(end 0.120396 0.3048)
			(stroke
				(width 0.1)
				(type default)
			)
			(layer "F.Fab")
		)
		(pad "1" smd circle
			(at -0.40005 0)
			(size 0 0)
			(layers "F.Cu" "F.Mask" "F.Paste")
			(net "RST_SMB_SSD4_ISO_N")
		)
		(pad "2" smd circle
			(at 0.40005 0)
			(size 0 0)
			(layers "F.Cu" "F.Mask" "F.Paste")
			(net "GND")
		)
	)
	(footprint ""
		(layer "F.Cu")
		(at 106.350816 -386.917184)
		(property "Reference" "R6291"
			(at 0 0 0)
			(layer "F.SilkS")
			(hide yes)
			(effects
				(font
					(size 1.27 1.27)
				)
			)
		)
		(property "Value" ""
			(at 0 0 0)
			(layer "F.Fab")
			(effects
				(font
					(size 1.27 1.27)
				)
			)
		)
		(duplicate_pad_numbers_are_jumpers no)
		(fp_line
			(start -0.536702 -0.4064)
			(end 0.7874 -0.4064)
			(stroke
				(width 0.1524)
				(type default)
			)
			(layer "F.SilkS")
		)
		(fp_line
			(start 0.7874 -0.4064)
			(end 0.7874 0.4064)
			(stroke
				(width 0.1524)
				(type default)
			)
			(layer "F.SilkS")
		)
		(fp_line
			(start 0.7874 0.4064)
			(end -0.563372 0.4064)
			(stroke
				(width 0.1524)
				(type default)
			)
			(layer "F.SilkS")
		)
		(fp_line
			(start -0.67945 -0.305054)
			(end -0.12065 -0.305054)
			(stroke
				(width 0.1)
				(type default)
			)
			(layer "F.Fab")
		)
		(fp_line
			(start -0.67945 0.3048)
			(end -0.67945 -0.305054)
			(stroke
				(width 0.1)
				(type default)
			)
			(layer "F.Fab")
		)
		(fp_line
			(start -0.12065 -0.305054)
			(end -0.12065 -0.2794)
			(stroke
				(width 0.1)
				(type default)
			)
			(layer "F.Fab")
		)
		(fp_line
			(start -0.12065 -0.2794)
			(end 0.12065 -0.2794)
			(stroke
				(width 0.1)
				(type default)
			)
			(layer "F.Fab")
		)
		(fp_line
			(start -0.12065 0.2794)
			(end -0.12065 0.3048)
			(stroke
				(width 0.1)
				(type default)
			)
			(layer "F.Fab")
		)
		(fp_line
			(start -0.12065 0.3048)
			(end -0.67945 0.3048)
			(stroke
				(width 0.1)
				(type default)
			)
			(layer "F.Fab")
		)
		(fp_line
			(start 0.120396 0.2794)
			(end -0.12065 0.2794)
			(stroke
				(width 0.1)
				(type default)
			)
			(layer "F.Fab")
		)
		(fp_line
			(start 0.120396 0.3048)
			(end 0.120396 0.2794)
			(stroke
				(width 0.1)
				(type default)
			)
			(layer "F.Fab")
		)
		(fp_line
			(start 0.12065 -0.3048)
			(end 0.67945 -0.3048)
			(stroke
				(width 0.1)
				(type default)
			)
			(layer "F.Fab")
		)
		(fp_line
			(start 0.12065 -0.2794)
			(end 0.12065 -0.3048)
			(stroke
				(width 0.1)
				(type default)
			)
			(layer "F.Fab")
		)
		(fp_line
			(start 0.67945 -0.3048)
			(end 0.67945 0.3048)
			(stroke
				(width 0.1)
				(type default)
			)
			(layer "F.Fab")
		)
		(fp_line
			(start 0.67945 0.3048)
			(end 0.120396 0.3048)
			(stroke
				(width 0.1)
				(type default)
			)
			(layer "F.Fab")
		)
		(pad "1" smd circle
			(at -0.40005 0)
			(size 0 0)
			(layers "F.Cu" "F.Mask" "F.Paste")
			(net "USB2_GPU_HMC_R_DP")
		)
		(pad "2" smd circle
			(at 0.40005 0)
			(size 0 0)
			(layers "F.Cu" "F.Mask" "F.Paste")
			(net "GND")
		)
	)
	(footprint ""
		(layer "F.Cu")
		(at 117.958362 -127.931926)
		(property "Reference" "PR190"
			(at 0 0 0)
			(layer "F.SilkS")
			(hide yes)
			(effects
				(font
					(size 1.27 1.27)
				)
			)
		)
		(property "Value" ""
			(at 0 0 0)
			(layer "F.Fab")
			(effects
				(font
					(size 1.27 1.27)
				)
			)
		)
		(duplicate_pad_numbers_are_jumpers no)
		(fp_line
			(start -0.7874 -0.4064)
			(end 0.7874 -0.4064)
			(stroke
				(width 0.1524)
				(type default)
			)
			(layer "F.SilkS")
		)
		(fp_line
			(start -0.7874 0.4064)
			(end -0.7874 -0.4064)
			(stroke
				(width 0.1524)
				(type default)
			)
			(layer "F.SilkS")
		)
		(fp_line
			(start 0.7874 -0.4064)
			(end 0.7874 0.4064)
			(stroke
				(width 0.1524)
				(type default)
			)
			(layer "F.SilkS")
		)
		(fp_line
			(start 0.7874 0.4064)
			(end -0.7874 0.4064)
			(stroke
				(width 0.1524)
				(type default)
			)
			(layer "F.SilkS")
		)
		(fp_line
			(start -0.67945 -0.305054)
			(end -0.12065 -0.305054)
			(stroke
				(width 0.1)
				(type default)
			)
			(layer "F.Fab")
		)
		(fp_line
			(start -0.67945 0.3048)
			(end -0.67945 -0.305054)
			(stroke
				(width 0.1)
				(type default)
			)
			(layer "F.Fab")
		)
		(fp_line
			(start -0.12065 -0.305054)
			(end -0.12065 -0.2794)
			(stroke
				(width 0.1)
				(type default)
			)
			(layer "F.Fab")
		)
		(fp_line
			(start -0.12065 -0.2794)
			(end 0.12065 -0.2794)
			(stroke
				(width 0.1)
				(type default)
			)
			(layer "F.Fab")
		)
		(fp_line
			(start -0.12065 0.2794)
			(end -0.12065 0.3048)
			(stroke
				(width 0.1)
				(type default)
			)
			(layer "F.Fab")
		)
		(fp_line
			(start -0.12065 0.3048)
			(end -0.67945 0.3048)
			(stroke
				(width 0.1)
				(type default)
			)
			(layer "F.Fab")
		)
		(fp_line
			(start 0.120396 0.2794)
			(end -0.12065 0.2794)
			(stroke
				(width 0.1)
				(type default)
			)
			(layer "F.Fab")
		)
		(fp_line
			(start 0.120396 0.3048)
			(end 0.120396 0.2794)
			(stroke
				(width 0.1)
				(type default)
			)
			(layer "F.Fab")
		)
		(fp_line
			(start 0.12065 -0.3048)
			(end 0.67945 -0.3048)
			(stroke
				(width 0.1)
				(type default)
			)
			(layer "F.Fab")
		)
		(fp_line
			(start 0.12065 -0.2794)
			(end 0.12065 -0.3048)
			(stroke
				(width 0.1)
				(type default)
			)
			(layer "F.Fab")
		)
		(fp_line
			(start 0.67945 -0.3048)
			(end 0.67945 0.3048)
			(stroke
				(width 0.1)
				(type default)
			)
			(layer "F.Fab")
		)
		(fp_line
			(start 0.67945 0.3048)
			(end 0.120396 0.3048)
			(stroke
				(width 0.1)
				(type default)
			)
			(layer "F.Fab")
		)
		(pad "1" smd circle
			(at -0.40005 0)
			(size 0 0)
			(layers "F.Cu" "F.Mask" "F.Paste")
			(net "P3V3_OCP")
		)
		(pad "2" smd circle
			(at 0.40005 0)
			(size 0 0)
			(layers "F.Cu" "F.Mask" "F.Paste")
			(net "GND")
		)
	)
	(footprint ""
		(layer "F.Cu")
		(at 500.158512 -546.502082 180)
		(property "Reference" "SCREW_5"
			(at -3.2385 -1.402334 0)
			(unlocked yes)
			(layer "B.SilkS")
			(effects
				(font
					(size 0.7874 0.5842)
					(thickness 0.1524)
				)
				(justify mirror)
			)
		)
		(property "Value" ""
			(at 0 0 180)
			(layer "F.Fab")
			(effects
				(font
					(size 1.27 1.27)
				)
			)
		)
		(duplicate_pad_numbers_are_jumpers no)
		(pad "1" thru_hole circle
			(at 0 0 180)
			(size 0.4572 0.4572)
			(drill 0.2032)
			(layers "*.Cu" "*.Mask")
			(remove_unused_layers no)
			(net "Net_9159")
			(clearance 0.127)
			(thermal_gap 0.127)
			(padstack
				(mode front_inner_back)
				(layer "Inner"
					(shape circle)
					(size 0.4572 0.4572)
					(clearance 0.127)
				)
				(layer "B.Cu"
					(shape circle)
					(size 0.508 0.508)
					(clearance 0.1016)
				)
			)
		)
	)
	(footprint ""
		(layer "F.Cu")
		(at 159.892492 -32.739584 180)
		(property "Reference" "C286"
			(at 0 0 180)
			(layer "F.SilkS")
			(hide yes)
			(effects
				(font
					(size 1.27 1.27)
				)
			)
		)
		(property "Value" ""
			(at 0 0 180)
			(layer "F.Fab")
			(effects
				(font
					(size 1.27 1.27)
				)
			)
		)
		(duplicate_pad_numbers_are_jumpers no)
		(fp_line
			(start 0.299974 0.150114)
			(end -0.299974 0.150114)
			(stroke
				(width 0.1)
				(type default)
			)
			(layer "F.Fab")
		)
		(fp_line
			(start 0.299974 -0.150114)
			(end 0.299974 0.150114)
			(stroke
				(width 0.1)
				(type default)
			)
			(layer "F.Fab")
		)
		(fp_line
			(start -0.299974 0.150114)
			(end -0.299974 -0.150114)
			(stroke
				(width 0.1)
				(type default)
			)
			(layer "F.Fab")
		)
		(fp_line
			(start -0.299974 -0.150114)
			(end 0.299974 -0.150114)
			(stroke
				(width 0.1)
				(type default)
			)
			(layer "F.Fab")
		)
		(pad "1" smd rect
			(at -0.2667 0 180)
			(size 0.3048 0.381)
			(layers "F.Cu" "F.Mask" "F.Paste")
			(net "P5E_PEX1_STN2_TX_DP<42>")
		)
		(pad "2" smd rect
			(at 0.2667 0 180)
			(size 0.3048 0.381)
			(layers "F.Cu" "F.Mask" "F.Paste")
			(net "P5E_PEX1_STN2_TX_C_DP<42>")
		)
	)
	(footprint ""
		(layer "F.Cu")
		(at 419.546786 -37.47516)
		(property "Reference" "R6123"
			(at 0 0 0)
			(layer "F.SilkS")
			(hide yes)
			(effects
				(font
					(size 1.27 1.27)
				)
			)
		)
		(property "Value" ""
			(at 0 0 0)
			(layer "F.Fab")
			(effects
				(font
					(size 1.27 1.27)
				)
			)
		)
		(duplicate_pad_numbers_are_jumpers no)
		(fp_line
			(start -0.7874 -0.4064)
			(end 0.7874 -0.4064)
			(stroke
				(width 0.1524)
				(type default)
			)
			(layer "F.SilkS")
		)
		(fp_line
			(start -0.7874 0.4064)
			(end -0.7874 -0.4064)
			(stroke
				(width 0.1524)
				(type default)
			)
			(layer "F.SilkS")
		)
		(fp_line
			(start 0.7874 -0.4064)
			(end 0.7874 0.4064)
			(stroke
				(width 0.1524)
				(type default)
			)
			(layer "F.SilkS")
		)
		(fp_line
			(start 0.7874 0.4064)
			(end -0.7874 0.4064)
			(stroke
				(width 0.1524)
				(type default)
			)
			(layer "F.SilkS")
		)
		(fp_line
			(start -0.67945 -0.305054)
			(end -0.12065 -0.305054)
			(stroke
				(width 0.1)
				(type default)
			)
			(layer "F.Fab")
		)
		(fp_line
			(start -0.67945 0.3048)
			(end -0.67945 -0.305054)
			(stroke
				(width 0.1)
				(type default)
			)
			(layer "F.Fab")
		)
		(fp_line
			(start -0.12065 -0.305054)
			(end -0.12065 -0.2794)
			(stroke
				(width 0.1)
				(type default)
			)
			(layer "F.Fab")
		)
		(fp_line
			(start -0.12065 -0.2794)
			(end 0.12065 -0.2794)
			(stroke
				(width 0.1)
				(type default)
			)
			(layer "F.Fab")
		)
		(fp_line
			(start -0.12065 0.2794)
			(end -0.12065 0.3048)
			(stroke
				(width 0.1)
				(type default)
			)
			(layer "F.Fab")
		)
		(fp_line
			(start -0.12065 0.3048)
			(end -0.67945 0.3048)
			(stroke
				(width 0.1)
				(type default)
			)
			(layer "F.Fab")
		)
		(fp_line
			(start 0.120396 0.2794)
			(end -0.12065 0.2794)
			(stroke
				(width 0.1)
				(type default)
			)
			(layer "F.Fab")
		)
		(fp_line
			(start 0.120396 0.3048)
			(end 0.120396 0.2794)
			(stroke
				(width 0.1)
				(type default)
			)
			(layer "F.Fab")
		)
		(fp_line
			(start 0.12065 -0.3048)
			(end 0.67945 -0.3048)
			(stroke
				(width 0.1)
				(type default)
			)
			(layer "F.Fab")
		)
		(fp_line
			(start 0.12065 -0.2794)
			(end 0.12065 -0.3048)
			(stroke
				(width 0.1)
				(type default)
			)
			(layer "F.Fab")
		)
		(fp_line
			(start 0.67945 -0.3048)
			(end 0.67945 0.3048)
			(stroke
				(width 0.1)
				(type default)
			)
			(layer "F.Fab")
		)
		(fp_line
			(start 0.67945 0.3048)
			(end 0.120396 0.3048)
			(stroke
				(width 0.1)
				(type default)
			)
			(layer "F.Fab")
		)
		(pad "1" smd circle
			(at -0.40005 0)
			(size 0 0)
			(layers "F.Cu" "F.Mask" "F.Paste")
			(net "P3V3_SSD15")
		)
		(pad "2" smd circle
			(at 0.40005 0)
			(size 0 0)
			(layers "F.Cu" "F.Mask" "F.Paste")
			(net "P3V3_SSD15_PG_G1")
		)
	)
	(footprint ""
		(layer "F.Cu")
		(at 146.18208 -280.189432 180)
		(property "Reference" "C3247"
			(at 0 0 180)
			(layer "F.SilkS")
			(hide yes)
			(effects
				(font
					(size 1.27 1.27)
				)
			)
		)
		(property "Value" ""
			(at 0 0 180)
			(layer "F.Fab")
			(effects
				(font
					(size 1.27 1.27)
				)
			)
		)
		(duplicate_pad_numbers_are_jumpers no)
		(fp_line
			(start 1.2954 0.5842)
			(end -1.2954 0.5842)
			(stroke
				(width 0.1524)
				(type default)
			)
			(layer "F.SilkS")
		)
		(fp_line
			(start 1.2954 -0.5842)
			(end 1.2954 0.5842)
			(stroke
				(width 0.1524)
				(type default)
			)
			(layer "F.SilkS")
		)
		(fp_line
			(start -1.2954 0.5842)
			(end -1.2954 -0.5842)
			(stroke
				(width 0.1524)
				(type default)
			)
			(layer "F.SilkS")
		)
		(fp_line
			(start -1.2954 -0.5842)
			(end 1.2954 -0.5842)
			(stroke
				(width 0.1524)
				(type default)
			)
			(layer "F.SilkS")
		)
		(fp_line
			(start 1.1938 0.4064)
			(end 0.8636 0.4064)
			(stroke
				(width 0.1)
				(type default)
			)
			(layer "F.Fab")
		)
		(fp_line
			(start 1.1938 -0.4064)
			(end 1.1938 0.4064)
			(stroke
				(width 0.1)
				(type default)
			)
			(layer "F.Fab")
		)
		(fp_line
			(start 0.8636 0.4572)
			(end -0.8636 0.4572)
			(stroke
				(width 0.1)
				(type default)
			)
			(layer "F.Fab")
		)
		(fp_line
			(start 0.8636 0.4064)
			(end 0.8636 0.4572)
			(stroke
				(width 0.1)
				(type default)
			)
			(layer "F.Fab")
		)
		(fp_line
			(start 0.8636 -0.4064)
			(end 1.1938 -0.4064)
			(stroke
				(width 0.1)
				(type default)
			)
			(layer "F.Fab")
		)
		(fp_line
			(start 0.8636 -0.4572)
			(end 0.8636 -0.4064)
			(stroke
				(width 0.1)
				(type default)
			)
			(layer "F.Fab")
		)
		(fp_line
			(start -0.8636 0.4572)
			(end -0.8636 0.4064)
			(stroke
				(width 0.1)
				(type default)
			)
			(layer "F.Fab")
		)
		(fp_line
			(start -0.8636 0.4064)
			(end -1.1938 0.4064)
			(stroke
				(width 0.1)
				(type default)
			)
			(layer "F.Fab")
		)
		(fp_line
			(start -0.8636 -0.4064)
			(end -0.8636 -0.4572)
			(stroke
				(width 0.1)
				(type default)
			)
			(layer "F.Fab")
		)
		(fp_line
			(start -0.8636 -0.4572)
			(end 0.8636 -0.4572)
			(stroke
				(width 0.1)
				(type default)
			)
			(layer "F.Fab")
		)
		(fp_line
			(start -1.1938 0.4064)
			(end -1.1938 -0.4064)
			(stroke
				(width 0.1)
				(type default)
			)
			(layer "F.Fab")
		)
		(fp_line
			(start -1.1938 -0.4064)
			(end -0.8636 -0.4064)
			(stroke
				(width 0.1)
				(type default)
			)
			(layer "F.Fab")
		)
		(pad "1" smd rect
			(at -0.7366 0 90)
			(size 0.7112 0.8128)
			(layers "F.Cu" "F.Mask" "F.Paste")
			(net "SYSPLL_VDDA18_PEX1_R")
		)
		(pad "2" smd rect
			(at 0.7366 0 90)
			(size 0.7112 0.8128)
			(layers "F.Cu" "F.Mask" "F.Paste")
			(net "GND")
		)
	)
	(footprint ""
		(layer "F.Cu")
		(at 400.910552 -18.61439 90)
		(property "Reference" "U139"
			(at -1.44399 2.341118 90)
			(unlocked yes)
			(layer "F.SilkS")
			(effects
				(font
					(size 0.7874 0.5842)
					(thickness 0.1524)
				)
				(justify left)
			)
		)
		(property "Value" ""
			(at 0 0 90)
			(layer "F.Fab")
			(effects
				(font
					(size 1.27 1.27)
				)
			)
		)
		(duplicate_pad_numbers_are_jumpers no)
		(fp_line
			(start 1.463548 -1.549908)
			(end 1.463548 1.549908)
			(stroke
				(width 0.1524)
				(type default)
			)
			(layer "F.SilkS")
		)
		(fp_line
			(start 0.762 -1.549908)
			(end 1.463548 -1.549908)
			(stroke
				(width 0.1524)
				(type default)
			)
			(layer "F.SilkS")
		)
		(fp_line
			(start -0.787908 -1.549908)
			(end 0 -0.762)
			(stroke
				(width 0.1524)
				(type default)
			)
			(layer "F.SilkS")
		)
		(fp_line
			(start -1.463548 -1.549908)
			(end -0.787908 -1.549908)
			(stroke
				(width 0.1524)
				(type default)
			)
			(layer "F.SilkS")
		)
		(fp_line
			(start 0 -0.762)
			(end 0.762 -1.549908)
			(stroke
				(width 0.1524)
				(type default)
			)
			(layer "F.SilkS")
		)
		(fp_line
			(start 1.463548 1.549908)
			(end -1.463548 1.549908)
			(stroke
				(width 0.1524)
				(type default)
			)
			(layer "F.SilkS")
		)
		(fp_line
			(start -1.463548 1.549908)
			(end -1.463548 -1.549908)
			(stroke
				(width 0.1524)
				(type default)
			)
			(layer "F.SilkS")
		)
		(fp_poly
			(pts
				(xy -3.4798 -1.359916) (xy -2.86004 -1.050036) (xy -3.4798 -0.740156)
			)
			(stroke
				(width 0)
				(type default)
			)
			(fill yes)
			(layer "F.SilkS")
		)
		(fp_line
			(start 1.549908 -1.549908)
			(end 1.549908 1.549908)
			(stroke
				(width 0.1)
				(type default)
			)
			(layer "F.Fab")
		)
		(fp_line
			(start -1.549908 -1.549908)
			(end 1.549908 -1.549908)
			(stroke
				(width 0.1)
				(type default)
			)
			(layer "F.Fab")
		)
		(fp_line
			(start 1.549908 1.549908)
			(end -1.549908 1.549908)
			(stroke
				(width 0.1)
				(type default)
			)
			(layer "F.Fab")
		)
		(fp_line
			(start -1.549908 1.549908)
			(end -1.549908 -1.549908)
			(stroke
				(width 0.1)
				(type default)
			)
			(layer "F.Fab")
		)
		(fp_poly
			(pts
				(xy -3.4798 -1.359916) (xy -2.86004 -1.050036) (xy -3.4798 -0.740156)
			)
			(stroke
				(width 0)
				(type default)
			)
			(fill yes)
			(layer "F.Fab")
		)
		(pad "1" smd rect
			(at -2.175002 -1.050036 180)
			(size 0.6096 1.1684)
			(layers "F.Cu" "F.Mask" "F.Paste")
			(net "P3V3_SSD13")
		)
		(pad "2" smd rect
			(at -2.175002 -0.32512 180)
			(size 0.4318 1.1684)
			(layers "F.Cu" "F.Mask" "F.Paste")
			(net "SMB_ISO_SSD13_SCL")
		)
		(pad "3" smd rect
			(at -2.175002 0.32512 180)
			(size 0.4318 1.1684)
			(layers "F.Cu" "F.Mask" "F.Paste")
			(net "SMB_ISO_SSD13_SDA")
		)
		(pad "4" smd rect
			(at -2.175002 1.050036 180)
			(size 0.6096 1.1684)
			(layers "F.Cu" "F.Mask" "F.Paste")
			(net "GND")
		)
		(pad "5" smd rect
			(at 2.175002 1.050036 180)
			(size 0.6096 1.1684)
			(layers "F.Cu" "F.Mask" "F.Paste")
			(net "SMB_SSD13_ISO_EN")
		)
		(pad "6" smd rect
			(at 2.175002 0.32512 180)
			(size 0.4318 1.1684)
			(layers "F.Cu" "F.Mask" "F.Paste")
			(net "SMB_BIC_I2C9_MUX1_SSD13_R_SDA")
		)
		(pad "7" smd rect
			(at 2.175002 -0.32512 180)
			(size 0.4318 1.1684)
			(layers "F.Cu" "F.Mask" "F.Paste")
			(net "SMB_BIC_I2C9_MUX1_SSD13_R_SCL")
		)
		(pad "8" smd rect
			(at 2.175002 -1.050036 180)
			(size 0.6096 1.1684)
			(layers "F.Cu" "F.Mask" "F.Paste")
			(net "P3V3_AUX")
		)
	)
	(footprint ""
		(layer "F.Cu")
		(at 365.506 -194.691 180)
		(property "Reference" "R4692"
			(at 0 0 180)
			(layer "F.SilkS")
			(hide yes)
			(effects
				(font
					(size 1.27 1.27)
				)
			)
		)
		(property "Value" ""
			(at 0 0 180)
			(layer "F.Fab")
			(effects
				(font
					(size 1.27 1.27)
				)
			)
		)
		(duplicate_pad_numbers_are_jumpers no)
		(fp_line
			(start 0.7874 0.4064)
			(end -0.7874 0.4064)
			(stroke
				(width 0.1524)
				(type default)
			)
			(layer "F.SilkS")
		)
		(fp_line
			(start 0.7874 -0.4064)
			(end 0.7874 0.4064)
			(stroke
				(width 0.1524)
				(type default)
			)
			(layer "F.SilkS")
		)
		(fp_line
			(start -0.7874 0.4064)
			(end -0.7874 -0.4064)
			(stroke
				(width 0.1524)
				(type default)
			)
			(layer "F.SilkS")
		)
		(fp_line
			(start -0.7874 -0.4064)
			(end 0.7874 -0.4064)
			(stroke
				(width 0.1524)
				(type default)
			)
			(layer "F.SilkS")
		)
		(fp_line
			(start 0.67945 0.3048)
			(end 0.120396 0.3048)
			(stroke
				(width 0.1)
				(type default)
			)
			(layer "F.Fab")
		)
		(fp_line
			(start 0.67945 -0.3048)
			(end 0.67945 0.3048)
			(stroke
				(width 0.1)
				(type default)
			)
			(layer "F.Fab")
		)
		(fp_line
			(start 0.12065 -0.2794)
			(end 0.12065 -0.3048)
			(stroke
				(width 0.1)
				(type default)
			)
			(layer "F.Fab")
		)
		(fp_line
			(start 0.12065 -0.3048)
			(end 0.67945 -0.3048)
			(stroke
				(width 0.1)
				(type default)
			)
			(layer "F.Fab")
		)
		(fp_line
			(start 0.120396 0.3048)
			(end 0.120396 0.2794)
			(stroke
				(width 0.1)
				(type default)
			)
			(layer "F.Fab")
		)
		(fp_line
			(start 0.120396 0.2794)
			(end -0.12065 0.2794)
			(stroke
				(width 0.1)
				(type default)
			)
			(layer "F.Fab")
		)
		(fp_line
			(start -0.12065 0.3048)
			(end -0.67945 0.3048)
			(stroke
				(width 0.1)
				(type default)
			)
			(layer "F.Fab")
		)
		(fp_line
			(start -0.12065 0.2794)
			(end -0.12065 0.3048)
			(stroke
				(width 0.1)
				(type default)
			)
			(layer "F.Fab")
		)
		(fp_line
			(start -0.12065 -0.2794)
			(end 0.12065 -0.2794)
			(stroke
				(width 0.1)
				(type default)
			)
			(layer "F.Fab")
		)
		(fp_line
			(start -0.12065 -0.305054)
			(end -0.12065 -0.2794)
			(stroke
				(width 0.1)
				(type default)
			)
			(layer "F.Fab")
		)
		(fp_line
			(start -0.67945 0.3048)
			(end -0.67945 -0.305054)
			(stroke
				(width 0.1)
				(type default)
			)
			(layer "F.Fab")
		)
		(fp_line
			(start -0.67945 -0.305054)
			(end -0.12065 -0.305054)
			(stroke
				(width 0.1)
				(type default)
			)
			(layer "F.Fab")
		)
		(pad "1" smd circle
			(at -0.40005 0 180)
			(size 0 0)
			(layers "F.Cu" "F.Mask" "F.Paste")
			(net "RST_PEX_SSD5_PERST_N")
		)
		(pad "2" smd circle
			(at 0.40005 0 180)
			(size 0 0)
			(layers "F.Cu" "F.Mask" "F.Paste")
			(net "RST_PEX_SSD5_PERST_R_N")
		)
	)
	(footprint ""
		(layer "F.Cu")
		(at 288.029142 -116.5352 180)
		(property "Reference" "R244"
			(at 0 0 180)
			(layer "F.SilkS")
			(hide yes)
			(effects
				(font
					(size 1.27 1.27)
				)
			)
		)
		(property "Value" ""
			(at 0 0 180)
			(layer "F.Fab")
			(effects
				(font
					(size 1.27 1.27)
				)
			)
		)
		(duplicate_pad_numbers_are_jumpers no)
		(fp_line
			(start 0.7874 0.4064)
			(end -0.7874 0.4064)
			(stroke
				(width 0.1524)
				(type default)
			)
			(layer "F.SilkS")
		)
		(fp_line
			(start 0.7874 -0.4064)
			(end 0.7874 0.4064)
			(stroke
				(width 0.1524)
				(type default)
			)
			(layer "F.SilkS")
		)
		(fp_line
			(start -0.7874 0.4064)
			(end -0.7874 -0.4064)
			(stroke
				(width 0.1524)
				(type default)
			)
			(layer "F.SilkS")
		)
		(fp_line
			(start -0.7874 -0.4064)
			(end 0.7874 -0.4064)
			(stroke
				(width 0.1524)
				(type default)
			)
			(layer "F.SilkS")
		)
		(fp_line
			(start 0.67945 0.3048)
			(end 0.120396 0.3048)
			(stroke
				(width 0.1)
				(type default)
			)
			(layer "F.Fab")
		)
		(fp_line
			(start 0.67945 -0.3048)
			(end 0.67945 0.3048)
			(stroke
				(width 0.1)
				(type default)
			)
			(layer "F.Fab")
		)
		(fp_line
			(start 0.12065 -0.2794)
			(end 0.12065 -0.3048)
			(stroke
				(width 0.1)
				(type default)
			)
			(layer "F.Fab")
		)
		(fp_line
			(start 0.12065 -0.3048)
			(end 0.67945 -0.3048)
			(stroke
				(width 0.1)
				(type default)
			)
			(layer "F.Fab")
		)
		(fp_line
			(start 0.120396 0.3048)
			(end 0.120396 0.2794)
			(stroke
				(width 0.1)
				(type default)
			)
			(layer "F.Fab")
		)
		(fp_line
			(start 0.120396 0.2794)
			(end -0.12065 0.2794)
			(stroke
				(width 0.1)
				(type default)
			)
			(layer "F.Fab")
		)
		(fp_line
			(start -0.12065 0.3048)
			(end -0.67945 0.3048)
			(stroke
				(width 0.1)
				(type default)
			)
			(layer "F.Fab")
		)
		(fp_line
			(start -0.12065 0.2794)
			(end -0.12065 0.3048)
			(stroke
				(width 0.1)
				(type default)
			)
			(layer "F.Fab")
		)
		(fp_line
			(start -0.12065 -0.2794)
			(end 0.12065 -0.2794)
			(stroke
				(width 0.1)
				(type default)
			)
			(layer "F.Fab")
		)
		(fp_line
			(start -0.12065 -0.305054)
			(end -0.12065 -0.2794)
			(stroke
				(width 0.1)
				(type default)
			)
			(layer "F.Fab")
		)
		(fp_line
			(start -0.67945 0.3048)
			(end -0.67945 -0.305054)
			(stroke
				(width 0.1)
				(type default)
			)
			(layer "F.Fab")
		)
		(fp_line
			(start -0.67945 -0.305054)
			(end -0.12065 -0.305054)
			(stroke
				(width 0.1)
				(type default)
			)
			(layer "F.Fab")
		)
		(pad "1" smd circle
			(at -0.40005 0 180)
			(size 0 0)
			(layers "F.Cu" "F.Mask" "F.Paste")
			(net "PRSNT_NIC4_N")
		)
		(pad "2" smd circle
			(at 0.40005 0 180)
			(size 0 0)
			(layers "F.Cu" "F.Mask" "F.Paste")
			(net "PRSNTB1_NIC4_N")
		)
	)
	(footprint ""
		(layer "F.Cu")
		(at 422.619932 -350.098614 90)
		(property "Reference" "C2452"
			(at 0 0 90)
			(layer "F.SilkS")
			(hide yes)
			(effects
				(font
					(size 1.27 1.27)
				)
			)
		)
		(property "Value" ""
			(at 0 0 90)
			(layer "F.Fab")
			(effects
				(font
					(size 1.27 1.27)
				)
			)
		)
		(duplicate_pad_numbers_are_jumpers no)
		(fp_line
			(start 0.299974 -0.150114)
			(end 0.299974 0.150114)
			(stroke
				(width 0.1)
				(type default)
			)
			(layer "F.Fab")
		)
		(fp_line
			(start -0.299974 -0.150114)
			(end 0.299974 -0.150114)
			(stroke
				(width 0.1)
				(type default)
			)
			(layer "F.Fab")
		)
		(fp_line
			(start 0.299974 0.150114)
			(end -0.299974 0.150114)
			(stroke
				(width 0.1)
				(type default)
			)
			(layer "F.Fab")
		)
		(fp_line
			(start -0.299974 0.150114)
			(end -0.299974 -0.150114)
			(stroke
				(width 0.1)
				(type default)
			)
			(layer "F.Fab")
		)
		(pad "1" smd rect
			(at -0.2667 0 90)
			(size 0.3048 0.381)
			(layers "F.Cu" "F.Mask" "F.Paste")
			(net "P5E_PEX3_STN4_TX_DN<73>")
		)
		(pad "2" smd rect
			(at 0.2667 0 90)
			(size 0.3048 0.381)
			(layers "F.Cu" "F.Mask" "F.Paste")
			(net "P5E_PEX3_STN4_TX_C_DN<73>")
		)
	)
	(footprint ""
		(layer "F.Cu")
		(at 101.553264 -242.480338 -90)
		(property "Reference" "C830"
			(at 0 0 270)
			(layer "F.SilkS")
			(hide yes)
			(effects
				(font
					(size 1.27 1.27)
				)
			)
		)
		(property "Value" ""
			(at 0 0 270)
			(layer "F.Fab")
			(effects
				(font
					(size 1.27 1.27)
				)
			)
		)
		(duplicate_pad_numbers_are_jumpers no)
		(fp_line
			(start -0.7874 0.4064)
			(end -0.7874 -0.4064)
			(stroke
				(width 0.1524)
				(type default)
			)
			(layer "F.SilkS")
		)
		(fp_line
			(start 0.7874 0.4064)
			(end -0.7874 0.4064)
			(stroke
				(width 0.1524)
				(type default)
			)
			(layer "F.SilkS")
		)
		(fp_line
			(start -0.7874 -0.4064)
			(end 0.7874 -0.4064)
			(stroke
				(width 0.1524)
				(type default)
			)
			(layer "F.SilkS")
		)
		(fp_line
			(start 0.7874 -0.4064)
			(end 0.7874 0.4064)
			(stroke
				(width 0.1524)
				(type default)
			)
			(layer "F.SilkS")
		)
		(fp_line
			(start -0.67945 0.3048)
			(end -0.67945 -0.305054)
			(stroke
				(width 0.1)
				(type default)
			)
			(layer "F.Fab")
		)
		(fp_line
			(start -0.12065 0.3048)
			(end -0.67945 0.3048)
			(stroke
				(width 0.1)
				(type default)
			)
			(layer "F.Fab")
		)
		(fp_line
			(start 0.120396 0.3048)
			(end 0.120396 0.2794)
			(stroke
				(width 0.1)
				(type default)
			)
			(layer "F.Fab")
		)
		(fp_line
			(start 0.67945 0.3048)
			(end 0.120396 0.3048)
			(stroke
				(width 0.1)
				(type default)
			)
			(layer "F.Fab")
		)
		(fp_line
			(start -0.12065 0.2794)
			(end -0.12065 0.3048)
			(stroke
				(width 0.1)
				(type default)
			)
			(layer "F.Fab")
		)
		(fp_line
			(start 0.120396 0.2794)
			(end -0.12065 0.2794)
			(stroke
				(width 0.1)
				(type default)
			)
			(layer "F.Fab")
		)
		(fp_line
			(start -0.12065 -0.2794)
			(end 0.12065 -0.2794)
			(stroke
				(width 0.1)
				(type default)
			)
			(layer "F.Fab")
		)
		(fp_line
			(start 0.12065 -0.2794)
			(end 0.12065 -0.3048)
			(stroke
				(width 0.1)
				(type default)
			)
			(layer "F.Fab")
		)
		(fp_line
			(start 0.12065 -0.3048)
			(end 0.67945 -0.3048)
			(stroke
				(width 0.1)
				(type default)
			)
			(layer "F.Fab")
		)
		(fp_line
			(start 0.67945 -0.3048)
			(end 0.67945 0.3048)
			(stroke
				(width 0.1)
				(type default)
			)
			(layer "F.Fab")
		)
		(fp_line
			(start -0.67945 -0.305054)
			(end -0.12065 -0.305054)
			(stroke
				(width 0.1)
				(type default)
			)
			(layer "F.Fab")
		)
		(fp_line
			(start -0.12065 -0.305054)
			(end -0.12065 -0.2794)
			(stroke
				(width 0.1)
				(type default)
			)
			(layer "F.Fab")
		)
		(pad "1" smd circle
			(at -0.40005 0 270)
			(size 0 0)
			(layers "F.Cu" "F.Mask" "F.Paste")
			(net "P1V8_PEX_R")
		)
		(pad "2" smd circle
			(at 0.40005 0 270)
			(size 0 0)
			(layers "F.Cu" "F.Mask" "F.Paste")
			(net "GND")
		)
	)
	(footprint ""
		(layer "F.Cu")
		(at 136.708388 -356.244906 90)
		(property "Reference" "C2249"
			(at 0 0 90)
			(layer "F.SilkS")
			(hide yes)
			(effects
				(font
					(size 1.27 1.27)
				)
			)
		)
		(property "Value" ""
			(at 0 0 90)
			(layer "F.Fab")
			(effects
				(font
					(size 1.27 1.27)
				)
			)
		)
		(duplicate_pad_numbers_are_jumpers no)
		(fp_line
			(start 0.299974 -0.150114)
			(end 0.299974 0.150114)
			(stroke
				(width 0.1)
				(type default)
			)
			(layer "F.Fab")
		)
		(fp_line
			(start -0.299974 -0.150114)
			(end 0.299974 -0.150114)
			(stroke
				(width 0.1)
				(type default)
			)
			(layer "F.Fab")
		)
		(fp_line
			(start 0.299974 0.150114)
			(end -0.299974 0.150114)
			(stroke
				(width 0.1)
				(type default)
			)
			(layer "F.Fab")
		)
		(fp_line
			(start -0.299974 0.150114)
			(end -0.299974 -0.150114)
			(stroke
				(width 0.1)
				(type default)
			)
			(layer "F.Fab")
		)
		(pad "1" smd rect
			(at -0.2667 0 90)
			(size 0.3048 0.381)
			(layers "F.Cu" "F.Mask" "F.Paste")
			(net "P5E_PEX1_STN5_TX_DP<92>")
		)
		(pad "2" smd rect
			(at 0.2667 0 90)
			(size 0.3048 0.381)
			(layers "F.Cu" "F.Mask" "F.Paste")
			(net "P5E_PEX1_STN5_TX_C_DP<92>")
		)
	)
	(footprint ""
		(layer "F.Cu")
		(at 44.638722 -22.867366 90)
		(property "Reference" "C3885"
			(at 0 0 90)
			(layer "F.SilkS")
			(hide yes)
			(effects
				(font
					(size 1.27 1.27)
				)
			)
		)
		(property "Value" ""
			(at 0 0 90)
			(layer "F.Fab")
			(effects
				(font
					(size 1.27 1.27)
				)
			)
		)
		(duplicate_pad_numbers_are_jumpers no)
		(fp_line
			(start 0.7874 -0.4064)
			(end 0.7874 0.4064)
			(stroke
				(width 0.1524)
				(type default)
			)
			(layer "F.SilkS")
		)
		(fp_line
			(start -0.7874 -0.4064)
			(end 0.7874 -0.4064)
			(stroke
				(width 0.1524)
				(type default)
			)
			(layer "F.SilkS")
		)
		(fp_line
			(start 0.7874 0.4064)
			(end -0.7874 0.4064)
			(stroke
				(width 0.1524)
				(type default)
			)
			(layer "F.SilkS")
		)
		(fp_line
			(start -0.7874 0.4064)
			(end -0.7874 -0.4064)
			(stroke
				(width 0.1524)
				(type default)
			)
			(layer "F.SilkS")
		)
		(fp_line
			(start -0.12065 -0.305054)
			(end -0.12065 -0.2794)
			(stroke
				(width 0.1)
				(type default)
			)
			(layer "F.Fab")
		)
		(fp_line
			(start -0.67945 -0.305054)
			(end -0.12065 -0.305054)
			(stroke
				(width 0.1)
				(type default)
			)
			(layer "F.Fab")
		)
		(fp_line
			(start 0.67945 -0.3048)
			(end 0.67945 0.3048)
			(stroke
				(width 0.1)
				(type default)
			)
			(layer "F.Fab")
		)
		(fp_line
			(start 0.12065 -0.3048)
			(end 0.67945 -0.3048)
			(stroke
				(width 0.1)
				(type default)
			)
			(layer "F.Fab")
		)
		(fp_line
			(start 0.12065 -0.2794)
			(end 0.12065 -0.3048)
			(stroke
				(width 0.1)
				(type default)
			)
			(layer "F.Fab")
		)
		(fp_line
			(start -0.12065 -0.2794)
			(end 0.12065 -0.2794)
			(stroke
				(width 0.1)
				(type default)
			)
			(layer "F.Fab")
		)
		(fp_line
			(start 0.120396 0.2794)
			(end -0.12065 0.2794)
			(stroke
				(width 0.1)
				(type default)
			)
			(layer "F.Fab")
		)
		(fp_line
			(start -0.12065 0.2794)
			(end -0.12065 0.3048)
			(stroke
				(width 0.1)
				(type default)
			)
			(layer "F.Fab")
		)
		(fp_line
			(start 0.67945 0.3048)
			(end 0.120396 0.3048)
			(stroke
				(width 0.1)
				(type default)
			)
			(layer "F.Fab")
		)
		(fp_line
			(start 0.120396 0.3048)
			(end 0.120396 0.2794)
			(stroke
				(width 0.1)
				(type default)
			)
			(layer "F.Fab")
		)
		(fp_line
			(start -0.12065 0.3048)
			(end -0.67945 0.3048)
			(stroke
				(width 0.1)
				(type default)
			)
			(layer "F.Fab")
		)
		(fp_line
			(start -0.67945 0.3048)
			(end -0.67945 -0.305054)
			(stroke
				(width 0.1)
				(type default)
			)
			(layer "F.Fab")
		)
		(pad "1" smd circle
			(at -0.40005 0 90)
			(size 0 0)
			(layers "F.Cu" "F.Mask" "F.Paste")
			(net "P12V_SSD1")
		)
		(pad "2" smd circle
			(at 0.40005 0 90)
			(size 0 0)
			(layers "F.Cu" "F.Mask" "F.Paste")
			(net "GND")
		)
	)
	(footprint ""
		(layer "F.Cu")
		(at 258.22529 -77.279754 -90)
		(property "Reference" "R1081"
			(at 0 0 270)
			(layer "F.SilkS")
			(hide yes)
			(effects
				(font
					(size 1.27 1.27)
				)
			)
		)
		(property "Value" ""
			(at 0 0 270)
			(layer "F.Fab")
			(effects
				(font
					(size 1.27 1.27)
				)
			)
		)
		(duplicate_pad_numbers_are_jumpers no)
		(fp_line
			(start -0.7874 0.4064)
			(end -0.7874 -0.4064)
			(stroke
				(width 0.1524)
				(type default)
			)
			(layer "F.SilkS")
		)
		(fp_line
			(start 0.7874 0.4064)
			(end -0.7874 0.4064)
			(stroke
				(width 0.1524)
				(type default)
			)
			(layer "F.SilkS")
		)
		(fp_line
			(start -0.7874 -0.4064)
			(end 0.7874 -0.4064)
			(stroke
				(width 0.1524)
				(type default)
			)
			(layer "F.SilkS")
		)
		(fp_line
			(start 0.7874 -0.4064)
			(end 0.7874 0.4064)
			(stroke
				(width 0.1524)
				(type default)
			)
			(layer "F.SilkS")
		)
		(fp_line
			(start -0.67945 0.3048)
			(end -0.67945 -0.305054)
			(stroke
				(width 0.1)
				(type default)
			)
			(layer "F.Fab")
		)
		(fp_line
			(start -0.12065 0.3048)
			(end -0.67945 0.3048)
			(stroke
				(width 0.1)
				(type default)
			)
			(layer "F.Fab")
		)
		(fp_line
			(start 0.120396 0.3048)
			(end 0.120396 0.2794)
			(stroke
				(width 0.1)
				(type default)
			)
			(layer "F.Fab")
		)
		(fp_line
			(start 0.67945 0.3048)
			(end 0.120396 0.3048)
			(stroke
				(width 0.1)
				(type default)
			)
			(layer "F.Fab")
		)
		(fp_line
			(start -0.12065 0.2794)
			(end -0.12065 0.3048)
			(stroke
				(width 0.1)
				(type default)
			)
			(layer "F.Fab")
		)
		(fp_line
			(start 0.120396 0.2794)
			(end -0.12065 0.2794)
			(stroke
				(width 0.1)
				(type default)
			)
			(layer "F.Fab")
		)
		(fp_line
			(start -0.12065 -0.2794)
			(end 0.12065 -0.2794)
			(stroke
				(width 0.1)
				(type default)
			)
			(layer "F.Fab")
		)
		(fp_line
			(start 0.12065 -0.2794)
			(end 0.12065 -0.3048)
			(stroke
				(width 0.1)
				(type default)
			)
			(layer "F.Fab")
		)
		(fp_line
			(start 0.12065 -0.3048)
			(end 0.67945 -0.3048)
			(stroke
				(width 0.1)
				(type default)
			)
			(layer "F.Fab")
		)
		(fp_line
			(start 0.67945 -0.3048)
			(end 0.67945 0.3048)
			(stroke
				(width 0.1)
				(type default)
			)
			(layer "F.Fab")
		)
		(fp_line
			(start -0.67945 -0.305054)
			(end -0.12065 -0.305054)
			(stroke
				(width 0.1)
				(type default)
			)
			(layer "F.Fab")
		)
		(fp_line
			(start -0.12065 -0.305054)
			(end -0.12065 -0.2794)
			(stroke
				(width 0.1)
				(type default)
			)
			(layer "F.Fab")
		)
		(pad "1" smd circle
			(at -0.40005 0 270)
			(size 0 0)
			(layers "F.Cu" "F.Mask" "F.Paste")
			(net "CLK_GEN_CK440_OE6_N")
		)
		(pad "2" smd circle
			(at 0.40005 0 270)
			(size 0 0)
			(layers "F.Cu" "F.Mask" "F.Paste")
			(net "P3V3")
		)
	)
	(footprint ""
		(layer "F.Cu")
		(at 169.293032 -343.952322 90)
		(property "Reference" "C397"
			(at 0 0 90)
			(layer "F.SilkS")
			(hide yes)
			(effects
				(font
					(size 1.27 1.27)
				)
			)
		)
		(property "Value" ""
			(at 0 0 90)
			(layer "F.Fab")
			(effects
				(font
					(size 1.27 1.27)
				)
			)
		)
		(duplicate_pad_numbers_are_jumpers no)
		(fp_line
			(start 0.299974 -0.150114)
			(end 0.299974 0.150114)
			(stroke
				(width 0.1)
				(type default)
			)
			(layer "F.Fab")
		)
		(fp_line
			(start -0.299974 -0.150114)
			(end 0.299974 -0.150114)
			(stroke
				(width 0.1)
				(type default)
			)
			(layer "F.Fab")
		)
		(fp_line
			(start 0.299974 0.150114)
			(end -0.299974 0.150114)
			(stroke
				(width 0.1)
				(type default)
			)
			(layer "F.Fab")
		)
		(fp_line
			(start -0.299974 0.150114)
			(end -0.299974 -0.150114)
			(stroke
				(width 0.1)
				(type default)
			)
			(layer "F.Fab")
		)
		(pad "1" smd rect
			(at -0.2667 0 90)
			(size 0.3048 0.381)
			(layers "F.Cu" "F.Mask" "F.Paste")
			(net "P5E_PEX1_STN7_TX_DN<115>")
		)
		(pad "2" smd rect
			(at 0.2667 0 90)
			(size 0.3048 0.381)
			(layers "F.Cu" "F.Mask" "F.Paste")
			(net "P5E_PEX1_STN7_TX_C_DN<115>")
		)
	)
	(footprint ""
		(layer "F.Cu")
		(at 386.90804 -157.3784 180)
		(property "Reference" "R318"
			(at 0 0 180)
			(layer "F.SilkS")
			(hide yes)
			(effects
				(font
					(size 1.27 1.27)
				)
			)
		)
		(property "Value" ""
			(at 0 0 180)
			(layer "F.Fab")
			(effects
				(font
					(size 1.27 1.27)
				)
			)
		)
		(duplicate_pad_numbers_are_jumpers no)
		(fp_line
			(start 0.7874 0.4064)
			(end -0.7874 0.4064)
			(stroke
				(width 0.1524)
				(type default)
			)
			(layer "F.SilkS")
		)
		(fp_line
			(start 0.7874 -0.4064)
			(end 0.7874 0.4064)
			(stroke
				(width 0.1524)
				(type default)
			)
			(layer "F.SilkS")
		)
		(fp_line
			(start -0.7874 0.4064)
			(end -0.7874 -0.4064)
			(stroke
				(width 0.1524)
				(type default)
			)
			(layer "F.SilkS")
		)
		(fp_line
			(start -0.7874 -0.4064)
			(end 0.7874 -0.4064)
			(stroke
				(width 0.1524)
				(type default)
			)
			(layer "F.SilkS")
		)
		(fp_line
			(start 0.67945 0.3048)
			(end 0.120396 0.3048)
			(stroke
				(width 0.1)
				(type default)
			)
			(layer "F.Fab")
		)
		(fp_line
			(start 0.67945 -0.3048)
			(end 0.67945 0.3048)
			(stroke
				(width 0.1)
				(type default)
			)
			(layer "F.Fab")
		)
		(fp_line
			(start 0.12065 -0.2794)
			(end 0.12065 -0.3048)
			(stroke
				(width 0.1)
				(type default)
			)
			(layer "F.Fab")
		)
		(fp_line
			(start 0.12065 -0.3048)
			(end 0.67945 -0.3048)
			(stroke
				(width 0.1)
				(type default)
			)
			(layer "F.Fab")
		)
		(fp_line
			(start 0.120396 0.3048)
			(end 0.120396 0.2794)
			(stroke
				(width 0.1)
				(type default)
			)
			(layer "F.Fab")
		)
		(fp_line
			(start 0.120396 0.2794)
			(end -0.12065 0.2794)
			(stroke
				(width 0.1)
				(type default)
			)
			(layer "F.Fab")
		)
		(fp_line
			(start -0.12065 0.3048)
			(end -0.67945 0.3048)
			(stroke
				(width 0.1)
				(type default)
			)
			(layer "F.Fab")
		)
		(fp_line
			(start -0.12065 0.2794)
			(end -0.12065 0.3048)
			(stroke
				(width 0.1)
				(type default)
			)
			(layer "F.Fab")
		)
		(fp_line
			(start -0.12065 -0.2794)
			(end 0.12065 -0.2794)
			(stroke
				(width 0.1)
				(type default)
			)
			(layer "F.Fab")
		)
		(fp_line
			(start -0.12065 -0.305054)
			(end -0.12065 -0.2794)
			(stroke
				(width 0.1)
				(type default)
			)
			(layer "F.Fab")
		)
		(fp_line
			(start -0.67945 0.3048)
			(end -0.67945 -0.305054)
			(stroke
				(width 0.1)
				(type default)
			)
			(layer "F.Fab")
		)
		(fp_line
			(start -0.67945 -0.305054)
			(end -0.12065 -0.305054)
			(stroke
				(width 0.1)
				(type default)
			)
			(layer "F.Fab")
		)
		(pad "1" smd circle
			(at -0.40005 0 180)
			(size 0 0)
			(layers "F.Cu" "F.Mask" "F.Paste")
			(net "NIC6_DATA_IN")
		)
		(pad "2" smd circle
			(at 0.40005 0 180)
			(size 0 0)
			(layers "F.Cu" "F.Mask" "F.Paste")
			(net "P3V3_NIC6")
		)
	)
	(footprint ""
		(layer "F.Cu")
		(at 112.311942 -114.960654)
		(property "Reference" "PR6878"
			(at 0 0 0)
			(layer "F.SilkS")
			(hide yes)
			(effects
				(font
					(size 1.27 1.27)
				)
			)
		)
		(property "Value" ""
			(at 0 0 0)
			(layer "F.Fab")
			(effects
				(font
					(size 1.27 1.27)
				)
			)
		)
		(duplicate_pad_numbers_are_jumpers no)
		(fp_line
			(start -0.7874 -0.4064)
			(end 0.7874 -0.4064)
			(stroke
				(width 0.1524)
				(type default)
			)
			(layer "F.SilkS")
		)
		(fp_line
			(start -0.7874 0.4064)
			(end -0.7874 -0.4064)
			(stroke
				(width 0.1524)
				(type default)
			)
			(layer "F.SilkS")
		)
		(fp_line
			(start 0.7874 -0.4064)
			(end 0.7874 0.4064)
			(stroke
				(width 0.1524)
				(type default)
			)
			(layer "F.SilkS")
		)
		(fp_line
			(start 0.7874 0.4064)
			(end -0.7874 0.4064)
			(stroke
				(width 0.1524)
				(type default)
			)
			(layer "F.SilkS")
		)
		(fp_line
			(start -0.67945 -0.305054)
			(end -0.12065 -0.305054)
			(stroke
				(width 0.1)
				(type default)
			)
			(layer "F.Fab")
		)
		(fp_line
			(start -0.67945 0.3048)
			(end -0.67945 -0.305054)
			(stroke
				(width 0.1)
				(type default)
			)
			(layer "F.Fab")
		)
		(fp_line
			(start -0.12065 -0.305054)
			(end -0.12065 -0.2794)
			(stroke
				(width 0.1)
				(type default)
			)
			(layer "F.Fab")
		)
		(fp_line
			(start -0.12065 -0.2794)
			(end 0.12065 -0.2794)
			(stroke
				(width 0.1)
				(type default)
			)
			(layer "F.Fab")
		)
		(fp_line
			(start -0.12065 0.2794)
			(end -0.12065 0.3048)
			(stroke
				(width 0.1)
				(type default)
			)
			(layer "F.Fab")
		)
		(fp_line
			(start -0.12065 0.3048)
			(end -0.67945 0.3048)
			(stroke
				(width 0.1)
				(type default)
			)
			(layer "F.Fab")
		)
		(fp_line
			(start 0.120396 0.2794)
			(end -0.12065 0.2794)
			(stroke
				(width 0.1)
				(type default)
			)
			(layer "F.Fab")
		)
		(fp_line
			(start 0.120396 0.3048)
			(end 0.120396 0.2794)
			(stroke
				(width 0.1)
				(type default)
			)
			(layer "F.Fab")
		)
		(fp_line
			(start 0.12065 -0.3048)
			(end 0.67945 -0.3048)
			(stroke
				(width 0.1)
				(type default)
			)
			(layer "F.Fab")
		)
		(fp_line
			(start 0.12065 -0.2794)
			(end 0.12065 -0.3048)
			(stroke
				(width 0.1)
				(type default)
			)
			(layer "F.Fab")
		)
		(fp_line
			(start 0.67945 -0.3048)
			(end 0.67945 0.3048)
			(stroke
				(width 0.1)
				(type default)
			)
			(layer "F.Fab")
		)
		(fp_line
			(start 0.67945 0.3048)
			(end 0.120396 0.3048)
			(stroke
				(width 0.1)
				(type default)
			)
			(layer "F.Fab")
		)
		(pad "1" smd circle
			(at -0.40005 0)
			(size 0 0)
			(layers "F.Cu" "F.Mask" "F.Paste")
			(net "P12V_NIC1_CO_IMON_VR")
		)
		(pad "2" smd circle
			(at 0.40005 0)
			(size 0 0)
			(layers "F.Cu" "F.Mask" "F.Paste")
			(net "GND")
		)
	)
	(footprint ""
		(layer "F.Cu")
		(at 459.505812 -550.105834 180)
		(property "Reference" "SCREW_SSD13_2"
			(at -5.6007 -1.402334 0)
			(unlocked yes)
			(layer "B.SilkS")
			(effects
				(font
					(size 0.7874 0.5842)
					(thickness 0.1524)
				)
				(justify mirror)
			)
		)
		(property "Value" ""
			(at 0 0 180)
			(layer "F.Fab")
			(effects
				(font
					(size 1.27 1.27)
				)
			)
		)
		(duplicate_pad_numbers_are_jumpers no)
		(pad "1" thru_hole circle
			(at 0 0 180)
			(size 0.4572 0.4572)
			(drill 0.2032)
			(layers "*.Cu" "*.Mask")
			(remove_unused_layers no)
			(net "Net_9147")
			(clearance 0.127)
			(thermal_gap 0.127)
			(padstack
				(mode front_inner_back)
				(layer "Inner"
					(shape circle)
					(size 0.4572 0.4572)
					(clearance 0.127)
				)
				(layer "B.Cu"
					(shape circle)
					(size 0.508 0.508)
					(clearance 0.1016)
				)
			)
		)
	)
	(footprint ""
		(layer "F.Cu")
		(at 21.176996 -124.008134 90)
		(property "Reference" "PD52"
			(at -2.850134 2.243074 90)
			(unlocked yes)
			(layer "F.SilkS")
			(effects
				(font
					(size 0.7874 0.5842)
					(thickness 0.1524)
				)
				(justify left)
			)
		)
		(property "Value" ""
			(at 0 0 90)
			(layer "F.Fab")
			(effects
				(font
					(size 1.27 1.27)
				)
			)
		)
		(duplicate_pad_numbers_are_jumpers no)
		(fp_line
			(start 4.107942 -1.459992)
			(end 4.107942 1.459992)
			(stroke
				(width 0.1524)
				(type default)
			)
			(layer "F.SilkS")
		)
		(fp_line
			(start -3.400044 -1.459992)
			(end 4.107942 -1.459992)
			(stroke
				(width 0.1524)
				(type default)
			)
			(layer "F.SilkS")
		)
		(fp_line
			(start 4.107942 1.459992)
			(end -3.400044 1.459992)
			(stroke
				(width 0.1524)
				(type default)
			)
			(layer "F.SilkS")
		)
		(fp_line
			(start -3.400044 1.459992)
			(end -3.400044 -1.459992)
			(stroke
				(width 0.1524)
				(type default)
			)
			(layer "F.SilkS")
		)
		(fp_poly
			(pts
				(xy 4.107942 -1.459992) (xy 4.107942 1.459992) (xy 3.308096 1.459992) (xy 3.308096 -1.459992)
			)
			(stroke
				(width 0)
				(type default)
			)
			(fill yes)
			(layer "F.SilkS")
		)
		(fp_line
			(start 2.29997 -1.459992)
			(end 2.29997 1.459992)
			(stroke
				(width 0.1)
				(type default)
			)
			(layer "F.Fab")
		)
		(fp_line
			(start -2.29997 -1.459992)
			(end 2.29997 -1.459992)
			(stroke
				(width 0.1)
				(type default)
			)
			(layer "F.Fab")
		)
		(fp_line
			(start 2.29997 1.459992)
			(end -2.29997 1.459992)
			(stroke
				(width 0.1)
				(type default)
			)
			(layer "F.Fab")
		)
		(fp_line
			(start -2.29997 1.459992)
			(end -2.29997 -1.459992)
			(stroke
				(width 0.1)
				(type default)
			)
			(layer "F.Fab")
		)
		(fp_text user "+"
			(at -4.7752 -0.12065 90)
			(unlocked yes)
			(layer "F.SilkS")
			(effects
				(font
					(size 1.905 1.4224)
					(thickness 0.1524)
				)
				(justify left)
			)
		)
		(fp_text user "-"
			(at 5.4102 0.29845 270)
			(unlocked yes)
			(layer "F.SilkS")
			(effects
				(font
					(size 1.905 1.4224)
					(thickness 0.1524)
				)
				(justify left)
			)
		)
		(fp_text user "+"
			(at -4.7752 -0.12065 90)
			(unlocked yes)
			(layer "F.Fab")
			(effects
				(font
					(size 1.905 1.4224)
					(thickness 0.1524)
				)
				(justify left)
			)
		)
		(fp_text user "-"
			(at 5.4102 0.29845 270)
			(unlocked yes)
			(layer "F.Fab")
			(effects
				(font
					(size 1.905 1.4224)
					(thickness 0.1524)
				)
				(justify left)
			)
		)
		(pad "A" smd rect
			(at -1.999996 0 180)
			(size 1.7018 2.5146)
			(layers "F.Cu" "F.Mask" "F.Paste")
			(net "GND")
		)
		(pad "C" smd rect
			(at 1.999996 0 180)
			(size 1.7018 2.5146)
			(layers "F.Cu" "F.Mask" "F.Paste")
			(net "P3V3_NIC0")
		)
	)
	(footprint ""
		(layer "F.Cu")
		(at 174.219108 -59.574684 90)
		(property "Reference" "PC504"
			(at 0 0 90)
			(layer "F.SilkS")
			(hide yes)
			(effects
				(font
					(size 1.27 1.27)
				)
			)
		)
		(property "Value" ""
			(at 0 0 90)
			(layer "F.Fab")
			(effects
				(font
					(size 1.27 1.27)
				)
			)
		)
		(duplicate_pad_numbers_are_jumpers no)
		(fp_line
			(start 0.7874 -0.4064)
			(end 0.7874 0.4064)
			(stroke
				(width 0.1524)
				(type default)
			)
			(layer "F.SilkS")
		)
		(fp_line
			(start -0.7874 -0.4064)
			(end 0.7874 -0.4064)
			(stroke
				(width 0.1524)
				(type default)
			)
			(layer "F.SilkS")
		)
		(fp_line
			(start 0.7874 0.4064)
			(end -0.7874 0.4064)
			(stroke
				(width 0.1524)
				(type default)
			)
			(layer "F.SilkS")
		)
		(fp_line
			(start -0.7874 0.4064)
			(end -0.7874 -0.4064)
			(stroke
				(width 0.1524)
				(type default)
			)
			(layer "F.SilkS")
		)
		(fp_line
			(start -0.12065 -0.305054)
			(end -0.12065 -0.2794)
			(stroke
				(width 0.1)
				(type default)
			)
			(layer "F.Fab")
		)
		(fp_line
			(start -0.67945 -0.305054)
			(end -0.12065 -0.305054)
			(stroke
				(width 0.1)
				(type default)
			)
			(layer "F.Fab")
		)
		(fp_line
			(start 0.67945 -0.3048)
			(end 0.67945 0.3048)
			(stroke
				(width 0.1)
				(type default)
			)
			(layer "F.Fab")
		)
		(fp_line
			(start 0.12065 -0.3048)
			(end 0.67945 -0.3048)
			(stroke
				(width 0.1)
				(type default)
			)
			(layer "F.Fab")
		)
		(fp_line
			(start 0.12065 -0.2794)
			(end 0.12065 -0.3048)
			(stroke
				(width 0.1)
				(type default)
			)
			(layer "F.Fab")
		)
		(fp_line
			(start -0.12065 -0.2794)
			(end 0.12065 -0.2794)
			(stroke
				(width 0.1)
				(type default)
			)
			(layer "F.Fab")
		)
		(fp_line
			(start 0.120396 0.2794)
			(end -0.12065 0.2794)
			(stroke
				(width 0.1)
				(type default)
			)
			(layer "F.Fab")
		)
		(fp_line
			(start -0.12065 0.2794)
			(end -0.12065 0.3048)
			(stroke
				(width 0.1)
				(type default)
			)
			(layer "F.Fab")
		)
		(fp_line
			(start 0.67945 0.3048)
			(end 0.120396 0.3048)
			(stroke
				(width 0.1)
				(type default)
			)
			(layer "F.Fab")
		)
		(fp_line
			(start 0.120396 0.3048)
			(end 0.120396 0.2794)
			(stroke
				(width 0.1)
				(type default)
			)
			(layer "F.Fab")
		)
		(fp_line
			(start -0.12065 0.3048)
			(end -0.67945 0.3048)
			(stroke
				(width 0.1)
				(type default)
			)
			(layer "F.Fab")
		)
		(fp_line
			(start -0.67945 0.3048)
			(end -0.67945 -0.305054)
			(stroke
				(width 0.1)
				(type default)
			)
			(layer "F.Fab")
		)
		(pad "1" smd circle
			(at -0.40005 0 90)
			(size 0 0)
			(layers "F.Cu" "F.Mask" "F.Paste")
			(net "P5V_AUX")
		)
		(pad "2" smd circle
			(at 0.40005 0 90)
			(size 0 0)
			(layers "F.Cu" "F.Mask" "F.Paste")
			(net "GND")
		)
	)
	(footprint ""
		(layer "F.Cu")
		(at 301.992284 -29.139642 180)
		(property "Reference" "C509"
			(at 0 0 180)
			(layer "F.SilkS")
			(hide yes)
			(effects
				(font
					(size 1.27 1.27)
				)
			)
		)
		(property "Value" ""
			(at 0 0 180)
			(layer "F.Fab")
			(effects
				(font
					(size 1.27 1.27)
				)
			)
		)
		(duplicate_pad_numbers_are_jumpers no)
		(fp_line
			(start 0.299974 0.150114)
			(end -0.299974 0.150114)
			(stroke
				(width 0.1)
				(type default)
			)
			(layer "F.Fab")
		)
		(fp_line
			(start 0.299974 -0.150114)
			(end 0.299974 0.150114)
			(stroke
				(width 0.1)
				(type default)
			)
			(layer "F.Fab")
		)
		(fp_line
			(start -0.299974 0.150114)
			(end -0.299974 -0.150114)
			(stroke
				(width 0.1)
				(type default)
			)
			(layer "F.Fab")
		)
		(fp_line
			(start -0.299974 -0.150114)
			(end 0.299974 -0.150114)
			(stroke
				(width 0.1)
				(type default)
			)
			(layer "F.Fab")
		)
		(pad "1" smd rect
			(at -0.2667 0 180)
			(size 0.3048 0.381)
			(layers "F.Cu" "F.Mask" "F.Paste")
			(net "P5E_PEX2_STN2_TX_DP<36>")
		)
		(pad "2" smd rect
			(at 0.2667 0 180)
			(size 0.3048 0.381)
			(layers "F.Cu" "F.Mask" "F.Paste")
			(net "P5E_PEX2_STN2_TX_C_DP<36>")
		)
	)
	(footprint ""
		(layer "F.Cu")
		(at 234.855512 -231.416606 90)
		(property "Reference" "R4522"
			(at 0 0 90)
			(layer "F.SilkS")
			(hide yes)
			(effects
				(font
					(size 1.27 1.27)
				)
			)
		)
		(property "Value" ""
			(at 0 0 90)
			(layer "F.Fab")
			(effects
				(font
					(size 1.27 1.27)
				)
			)
		)
		(duplicate_pad_numbers_are_jumpers no)
		(fp_line
			(start 0.7874 -0.4064)
			(end 0.7874 0.4064)
			(stroke
				(width 0.1524)
				(type default)
			)
			(layer "F.SilkS")
		)
		(fp_line
			(start -0.7874 -0.4064)
			(end 0.7874 -0.4064)
			(stroke
				(width 0.1524)
				(type default)
			)
			(layer "F.SilkS")
		)
		(fp_line
			(start 0.7874 0.4064)
			(end -0.7874 0.4064)
			(stroke
				(width 0.1524)
				(type default)
			)
			(layer "F.SilkS")
		)
		(fp_line
			(start -0.7874 0.4064)
			(end -0.7874 -0.4064)
			(stroke
				(width 0.1524)
				(type default)
			)
			(layer "F.SilkS")
		)
		(fp_line
			(start -0.12065 -0.305054)
			(end -0.12065 -0.2794)
			(stroke
				(width 0.1)
				(type default)
			)
			(layer "F.Fab")
		)
		(fp_line
			(start -0.67945 -0.305054)
			(end -0.12065 -0.305054)
			(stroke
				(width 0.1)
				(type default)
			)
			(layer "F.Fab")
		)
		(fp_line
			(start 0.67945 -0.3048)
			(end 0.67945 0.3048)
			(stroke
				(width 0.1)
				(type default)
			)
			(layer "F.Fab")
		)
		(fp_line
			(start 0.12065 -0.3048)
			(end 0.67945 -0.3048)
			(stroke
				(width 0.1)
				(type default)
			)
			(layer "F.Fab")
		)
		(fp_line
			(start 0.12065 -0.2794)
			(end 0.12065 -0.3048)
			(stroke
				(width 0.1)
				(type default)
			)
			(layer "F.Fab")
		)
		(fp_line
			(start -0.12065 -0.2794)
			(end 0.12065 -0.2794)
			(stroke
				(width 0.1)
				(type default)
			)
			(layer "F.Fab")
		)
		(fp_line
			(start 0.120396 0.2794)
			(end -0.12065 0.2794)
			(stroke
				(width 0.1)
				(type default)
			)
			(layer "F.Fab")
		)
		(fp_line
			(start -0.12065 0.2794)
			(end -0.12065 0.3048)
			(stroke
				(width 0.1)
				(type default)
			)
			(layer "F.Fab")
		)
		(fp_line
			(start 0.67945 0.3048)
			(end 0.120396 0.3048)
			(stroke
				(width 0.1)
				(type default)
			)
			(layer "F.Fab")
		)
		(fp_line
			(start 0.120396 0.3048)
			(end 0.120396 0.2794)
			(stroke
				(width 0.1)
				(type default)
			)
			(layer "F.Fab")
		)
		(fp_line
			(start -0.12065 0.3048)
			(end -0.67945 0.3048)
			(stroke
				(width 0.1)
				(type default)
			)
			(layer "F.Fab")
		)
		(fp_line
			(start -0.67945 0.3048)
			(end -0.67945 -0.305054)
			(stroke
				(width 0.1)
				(type default)
			)
			(layer "F.Fab")
		)
		(pad "1" smd circle
			(at -0.40005 0 90)
			(size 0 0)
			(layers "F.Cu" "F.Mask" "F.Paste")
			(net "SSD8_PWRDIS_BIC")
		)
		(pad "2" smd circle
			(at 0.40005 0 90)
			(size 0 0)
			(layers "F.Cu" "F.Mask" "F.Paste")
			(net "SSD8_PWRDIS_BIC_R")
		)
	)
	(footprint ""
		(layer "F.Cu")
		(at 359.161842 -194.397122 180)
		(property "Reference" "R4617"
			(at 0 0 180)
			(layer "F.SilkS")
			(hide yes)
			(effects
				(font
					(size 1.27 1.27)
				)
			)
		)
		(property "Value" ""
			(at 0 0 180)
			(layer "F.Fab")
			(effects
				(font
					(size 1.27 1.27)
				)
			)
		)
		(duplicate_pad_numbers_are_jumpers no)
		(fp_line
			(start 0.7874 0.4064)
			(end -0.7874 0.4064)
			(stroke
				(width 0.1524)
				(type default)
			)
			(layer "F.SilkS")
		)
		(fp_line
			(start 0.7874 -0.4064)
			(end 0.7874 0.4064)
			(stroke
				(width 0.1524)
				(type default)
			)
			(layer "F.SilkS")
		)
		(fp_line
			(start -0.7874 0.4064)
			(end -0.7874 -0.4064)
			(stroke
				(width 0.1524)
				(type default)
			)
			(layer "F.SilkS")
		)
		(fp_line
			(start -0.7874 -0.4064)
			(end 0.7874 -0.4064)
			(stroke
				(width 0.1524)
				(type default)
			)
			(layer "F.SilkS")
		)
		(fp_line
			(start 0.67945 0.3048)
			(end 0.120396 0.3048)
			(stroke
				(width 0.1)
				(type default)
			)
			(layer "F.Fab")
		)
		(fp_line
			(start 0.67945 -0.3048)
			(end 0.67945 0.3048)
			(stroke
				(width 0.1)
				(type default)
			)
			(layer "F.Fab")
		)
		(fp_line
			(start 0.12065 -0.2794)
			(end 0.12065 -0.3048)
			(stroke
				(width 0.1)
				(type default)
			)
			(layer "F.Fab")
		)
		(fp_line
			(start 0.12065 -0.3048)
			(end 0.67945 -0.3048)
			(stroke
				(width 0.1)
				(type default)
			)
			(layer "F.Fab")
		)
		(fp_line
			(start 0.120396 0.3048)
			(end 0.120396 0.2794)
			(stroke
				(width 0.1)
				(type default)
			)
			(layer "F.Fab")
		)
		(fp_line
			(start 0.120396 0.2794)
			(end -0.12065 0.2794)
			(stroke
				(width 0.1)
				(type default)
			)
			(layer "F.Fab")
		)
		(fp_line
			(start -0.12065 0.3048)
			(end -0.67945 0.3048)
			(stroke
				(width 0.1)
				(type default)
			)
			(layer "F.Fab")
		)
		(fp_line
			(start -0.12065 0.2794)
			(end -0.12065 0.3048)
			(stroke
				(width 0.1)
				(type default)
			)
			(layer "F.Fab")
		)
		(fp_line
			(start -0.12065 -0.2794)
			(end 0.12065 -0.2794)
			(stroke
				(width 0.1)
				(type default)
			)
			(layer "F.Fab")
		)
		(fp_line
			(start -0.12065 -0.305054)
			(end -0.12065 -0.2794)
			(stroke
				(width 0.1)
				(type default)
			)
			(layer "F.Fab")
		)
		(fp_line
			(start -0.67945 0.3048)
			(end -0.67945 -0.305054)
			(stroke
				(width 0.1)
				(type default)
			)
			(layer "F.Fab")
		)
		(fp_line
			(start -0.67945 -0.305054)
			(end -0.12065 -0.305054)
			(stroke
				(width 0.1)
				(type default)
			)
			(layer "F.Fab")
		)
		(pad "1" smd circle
			(at -0.40005 0 180)
			(size 0 0)
			(layers "F.Cu" "F.Mask" "F.Paste")
			(net "PEX0_PCA9555_INT_R_N")
		)
		(pad "2" smd circle
			(at 0.40005 0 180)
			(size 0 0)
			(layers "F.Cu" "F.Mask" "F.Paste")
			(net "PEX0_PCA9555_INT_N")
		)
	)
	(footprint ""
		(layer "F.Cu")
		(at 371.968014 -18.437098)
		(property "Reference" "R1721"
			(at 0 0 0)
			(layer "F.SilkS")
			(hide yes)
			(effects
				(font
					(size 1.27 1.27)
				)
			)
		)
		(property "Value" ""
			(at 0 0 0)
			(layer "F.Fab")
			(effects
				(font
					(size 1.27 1.27)
				)
			)
		)
		(duplicate_pad_numbers_are_jumpers no)
		(fp_line
			(start -0.7874 -0.4064)
			(end 0.7874 -0.4064)
			(stroke
				(width 0.1524)
				(type default)
			)
			(layer "F.SilkS")
		)
		(fp_line
			(start -0.7874 0.4064)
			(end -0.7874 -0.4064)
			(stroke
				(width 0.1524)
				(type default)
			)
			(layer "F.SilkS")
		)
		(fp_line
			(start 0.7874 -0.4064)
			(end 0.7874 0.4064)
			(stroke
				(width 0.1524)
				(type default)
			)
			(layer "F.SilkS")
		)
		(fp_line
			(start 0.7874 0.4064)
			(end -0.7874 0.4064)
			(stroke
				(width 0.1524)
				(type default)
			)
			(layer "F.SilkS")
		)
		(fp_line
			(start -0.67945 -0.305054)
			(end -0.12065 -0.305054)
			(stroke
				(width 0.1)
				(type default)
			)
			(layer "F.Fab")
		)
		(fp_line
			(start -0.67945 0.3048)
			(end -0.67945 -0.305054)
			(stroke
				(width 0.1)
				(type default)
			)
			(layer "F.Fab")
		)
		(fp_line
			(start -0.12065 -0.305054)
			(end -0.12065 -0.2794)
			(stroke
				(width 0.1)
				(type default)
			)
			(layer "F.Fab")
		)
		(fp_line
			(start -0.12065 -0.2794)
			(end 0.12065 -0.2794)
			(stroke
				(width 0.1)
				(type default)
			)
			(layer "F.Fab")
		)
		(fp_line
			(start -0.12065 0.2794)
			(end -0.12065 0.3048)
			(stroke
				(width 0.1)
				(type default)
			)
			(layer "F.Fab")
		)
		(fp_line
			(start -0.12065 0.3048)
			(end -0.67945 0.3048)
			(stroke
				(width 0.1)
				(type default)
			)
			(layer "F.Fab")
		)
		(fp_line
			(start 0.120396 0.2794)
			(end -0.12065 0.2794)
			(stroke
				(width 0.1)
				(type default)
			)
			(layer "F.Fab")
		)
		(fp_line
			(start 0.120396 0.3048)
			(end 0.120396 0.2794)
			(stroke
				(width 0.1)
				(type default)
			)
			(layer "F.Fab")
		)
		(fp_line
			(start 0.12065 -0.3048)
			(end 0.67945 -0.3048)
			(stroke
				(width 0.1)
				(type default)
			)
			(layer "F.Fab")
		)
		(fp_line
			(start 0.12065 -0.2794)
			(end 0.12065 -0.3048)
			(stroke
				(width 0.1)
				(type default)
			)
			(layer "F.Fab")
		)
		(fp_line
			(start 0.67945 -0.3048)
			(end 0.67945 0.3048)
			(stroke
				(width 0.1)
				(type default)
			)
			(layer "F.Fab")
		)
		(fp_line
			(start 0.67945 0.3048)
			(end 0.120396 0.3048)
			(stroke
				(width 0.1)
				(type default)
			)
			(layer "F.Fab")
		)
		(pad "1" smd circle
			(at -0.40005 0)
			(size 0 0)
			(layers "F.Cu" "F.Mask" "F.Paste")
			(net "SMB_ISO_SSD12_R_SCL")
		)
		(pad "2" smd circle
			(at 0.40005 0)
			(size 0 0)
			(layers "F.Cu" "F.Mask" "F.Paste")
			(net "SMB_ISO_SSD12_SCL")
		)
	)
	(footprint ""
		(layer "F.Cu")
		(at 102.483412 -222.064072 -90)
		(property "Reference" "PR188"
			(at 0 0 270)
			(layer "F.SilkS")
			(hide yes)
			(effects
				(font
					(size 1.27 1.27)
				)
			)
		)
		(property "Value" ""
			(at 0 0 270)
			(layer "F.Fab")
			(effects
				(font
					(size 1.27 1.27)
				)
			)
		)
		(duplicate_pad_numbers_are_jumpers no)
		(fp_line
			(start -0.7874 0.4064)
			(end -0.7874 -0.4064)
			(stroke
				(width 0.1524)
				(type default)
			)
			(layer "F.SilkS")
		)
		(fp_line
			(start 0.7874 0.4064)
			(end -0.7874 0.4064)
			(stroke
				(width 0.1524)
				(type default)
			)
			(layer "F.SilkS")
		)
		(fp_line
			(start -0.7874 -0.4064)
			(end 0.7874 -0.4064)
			(stroke
				(width 0.1524)
				(type default)
			)
			(layer "F.SilkS")
		)
		(fp_line
			(start 0.7874 -0.4064)
			(end 0.7874 0.4064)
			(stroke
				(width 0.1524)
				(type default)
			)
			(layer "F.SilkS")
		)
		(fp_line
			(start -0.67945 0.3048)
			(end -0.67945 -0.305054)
			(stroke
				(width 0.1)
				(type default)
			)
			(layer "F.Fab")
		)
		(fp_line
			(start -0.12065 0.3048)
			(end -0.67945 0.3048)
			(stroke
				(width 0.1)
				(type default)
			)
			(layer "F.Fab")
		)
		(fp_line
			(start 0.120396 0.3048)
			(end 0.120396 0.2794)
			(stroke
				(width 0.1)
				(type default)
			)
			(layer "F.Fab")
		)
		(fp_line
			(start 0.67945 0.3048)
			(end 0.120396 0.3048)
			(stroke
				(width 0.1)
				(type default)
			)
			(layer "F.Fab")
		)
		(fp_line
			(start -0.12065 0.2794)
			(end -0.12065 0.3048)
			(stroke
				(width 0.1)
				(type default)
			)
			(layer "F.Fab")
		)
		(fp_line
			(start 0.120396 0.2794)
			(end -0.12065 0.2794)
			(stroke
				(width 0.1)
				(type default)
			)
			(layer "F.Fab")
		)
		(fp_line
			(start -0.12065 -0.2794)
			(end 0.12065 -0.2794)
			(stroke
				(width 0.1)
				(type default)
			)
			(layer "F.Fab")
		)
		(fp_line
			(start 0.12065 -0.2794)
			(end 0.12065 -0.3048)
			(stroke
				(width 0.1)
				(type default)
			)
			(layer "F.Fab")
		)
		(fp_line
			(start 0.12065 -0.3048)
			(end 0.67945 -0.3048)
			(stroke
				(width 0.1)
				(type default)
			)
			(layer "F.Fab")
		)
		(fp_line
			(start 0.67945 -0.3048)
			(end 0.67945 0.3048)
			(stroke
				(width 0.1)
				(type default)
			)
			(layer "F.Fab")
		)
		(fp_line
			(start -0.67945 -0.305054)
			(end -0.12065 -0.305054)
			(stroke
				(width 0.1)
				(type default)
			)
			(layer "F.Fab")
		)
		(fp_line
			(start -0.12065 -0.305054)
			(end -0.12065 -0.2794)
			(stroke
				(width 0.1)
				(type default)
			)
			(layer "F.Fab")
		)
		(pad "1" smd circle
			(at -0.40005 0 270)
			(size 0 0)
			(layers "F.Cu" "F.Mask" "F.Paste")
			(net "GND")
		)
		(pad "2" smd circle
			(at 0.40005 0 270)
			(size 0 0)
			(layers "F.Cu" "F.Mask" "F.Paste")
			(net "P1V8_PEX_FB")
		)
	)
	(footprint ""
		(layer "F.Cu")
		(at 248.902728 -112.139476 -90)
		(property "Reference" "PC904"
			(at 0 0 270)
			(layer "F.SilkS")
			(hide yes)
			(effects
				(font
					(size 1.27 1.27)
				)
			)
		)
		(property "Value" ""
			(at 0 0 270)
			(layer "F.Fab")
			(effects
				(font
					(size 1.27 1.27)
				)
			)
		)
		(duplicate_pad_numbers_are_jumpers no)
		(fp_line
			(start -0.7874 0.4064)
			(end -0.7874 -0.4064)
			(stroke
				(width 0.1524)
				(type default)
			)
			(layer "F.SilkS")
		)
		(fp_line
			(start 0.7874 0.4064)
			(end -0.7874 0.4064)
			(stroke
				(width 0.1524)
				(type default)
			)
			(layer "F.SilkS")
		)
		(fp_line
			(start -0.7874 -0.4064)
			(end 0.7874 -0.4064)
			(stroke
				(width 0.1524)
				(type default)
			)
			(layer "F.SilkS")
		)
		(fp_line
			(start 0.7874 -0.4064)
			(end 0.7874 0.4064)
			(stroke
				(width 0.1524)
				(type default)
			)
			(layer "F.SilkS")
		)
		(fp_line
			(start -0.67945 0.3048)
			(end -0.67945 -0.305054)
			(stroke
				(width 0.1)
				(type default)
			)
			(layer "F.Fab")
		)
		(fp_line
			(start -0.12065 0.3048)
			(end -0.67945 0.3048)
			(stroke
				(width 0.1)
				(type default)
			)
			(layer "F.Fab")
		)
		(fp_line
			(start 0.120396 0.3048)
			(end 0.120396 0.2794)
			(stroke
				(width 0.1)
				(type default)
			)
			(layer "F.Fab")
		)
		(fp_line
			(start 0.67945 0.3048)
			(end 0.120396 0.3048)
			(stroke
				(width 0.1)
				(type default)
			)
			(layer "F.Fab")
		)
		(fp_line
			(start -0.12065 0.2794)
			(end -0.12065 0.3048)
			(stroke
				(width 0.1)
				(type default)
			)
			(layer "F.Fab")
		)
		(fp_line
			(start 0.120396 0.2794)
			(end -0.12065 0.2794)
			(stroke
				(width 0.1)
				(type default)
			)
			(layer "F.Fab")
		)
		(fp_line
			(start -0.12065 -0.2794)
			(end 0.12065 -0.2794)
			(stroke
				(width 0.1)
				(type default)
			)
			(layer "F.Fab")
		)
		(fp_line
			(start 0.12065 -0.2794)
			(end 0.12065 -0.3048)
			(stroke
				(width 0.1)
				(type default)
			)
			(layer "F.Fab")
		)
		(fp_line
			(start 0.12065 -0.3048)
			(end 0.67945 -0.3048)
			(stroke
				(width 0.1)
				(type default)
			)
			(layer "F.Fab")
		)
		(fp_line
			(start 0.67945 -0.3048)
			(end 0.67945 0.3048)
			(stroke
				(width 0.1)
				(type default)
			)
			(layer "F.Fab")
		)
		(fp_line
			(start -0.67945 -0.305054)
			(end -0.12065 -0.305054)
			(stroke
				(width 0.1)
				(type default)
			)
			(layer "F.Fab")
		)
		(fp_line
			(start -0.12065 -0.305054)
			(end -0.12065 -0.2794)
			(stroke
				(width 0.1)
				(type default)
			)
			(layer "F.Fab")
		)
		(pad "1" smd circle
			(at -0.40005 0 270)
			(size 0 0)
			(layers "F.Cu" "F.Mask" "F.Paste")
			(net "P3V3_NIC4_CO_MODE")
		)
		(pad "2" smd circle
			(at 0.40005 0 270)
			(size 0 0)
			(layers "F.Cu" "F.Mask" "F.Paste")
			(net "GND")
		)
	)
	(footprint ""
		(layer "F.Cu")
		(at 215.047322 -19.33956)
		(property "Reference" "C3927"
			(at 0 0 0)
			(layer "F.SilkS")
			(hide yes)
			(effects
				(font
					(size 1.27 1.27)
				)
			)
		)
		(property "Value" ""
			(at 0 0 0)
			(layer "F.Fab")
			(effects
				(font
					(size 1.27 1.27)
				)
			)
		)
		(duplicate_pad_numbers_are_jumpers no)
		(fp_line
			(start -0.7874 -0.4064)
			(end 0.7874 -0.4064)
			(stroke
				(width 0.1524)
				(type default)
			)
			(layer "F.SilkS")
		)
		(fp_line
			(start -0.7874 0.4064)
			(end -0.7874 -0.4064)
			(stroke
				(width 0.1524)
				(type default)
			)
			(layer "F.SilkS")
		)
		(fp_line
			(start 0.7874 -0.4064)
			(end 0.7874 0.4064)
			(stroke
				(width 0.1524)
				(type default)
			)
			(layer "F.SilkS")
		)
		(fp_line
			(start 0.7874 0.4064)
			(end -0.7874 0.4064)
			(stroke
				(width 0.1524)
				(type default)
			)
			(layer "F.SilkS")
		)
		(fp_line
			(start -0.67945 -0.305054)
			(end -0.12065 -0.305054)
			(stroke
				(width 0.1)
				(type default)
			)
			(layer "F.Fab")
		)
		(fp_line
			(start -0.67945 0.3048)
			(end -0.67945 -0.305054)
			(stroke
				(width 0.1)
				(type default)
			)
			(layer "F.Fab")
		)
		(fp_line
			(start -0.12065 -0.305054)
			(end -0.12065 -0.2794)
			(stroke
				(width 0.1)
				(type default)
			)
			(layer "F.Fab")
		)
		(fp_line
			(start -0.12065 -0.2794)
			(end 0.12065 -0.2794)
			(stroke
				(width 0.1)
				(type default)
			)
			(layer "F.Fab")
		)
		(fp_line
			(start -0.12065 0.2794)
			(end -0.12065 0.3048)
			(stroke
				(width 0.1)
				(type default)
			)
			(layer "F.Fab")
		)
		(fp_line
			(start -0.12065 0.3048)
			(end -0.67945 0.3048)
			(stroke
				(width 0.1)
				(type default)
			)
			(layer "F.Fab")
		)
		(fp_line
			(start 0.120396 0.2794)
			(end -0.12065 0.2794)
			(stroke
				(width 0.1)
				(type default)
			)
			(layer "F.Fab")
		)
		(fp_line
			(start 0.120396 0.3048)
			(end 0.120396 0.2794)
			(stroke
				(width 0.1)
				(type default)
			)
			(layer "F.Fab")
		)
		(fp_line
			(start 0.12065 -0.3048)
			(end 0.67945 -0.3048)
			(stroke
				(width 0.1)
				(type default)
			)
			(layer "F.Fab")
		)
		(fp_line
			(start 0.12065 -0.2794)
			(end 0.12065 -0.3048)
			(stroke
				(width 0.1)
				(type default)
			)
			(layer "F.Fab")
		)
		(fp_line
			(start 0.67945 -0.3048)
			(end 0.67945 0.3048)
			(stroke
				(width 0.1)
				(type default)
			)
			(layer "F.Fab")
		)
		(fp_line
			(start 0.67945 0.3048)
			(end 0.120396 0.3048)
			(stroke
				(width 0.1)
				(type default)
			)
			(layer "F.Fab")
		)
		(pad "1" smd circle
			(at -0.40005 0)
			(size 0 0)
			(layers "F.Cu" "F.Mask" "F.Paste")
			(net "P12V_SSD7")
		)
		(pad "2" smd circle
			(at 0.40005 0)
			(size 0 0)
			(layers "F.Cu" "F.Mask" "F.Paste")
			(net "GND")
		)
	)
	(footprint ""
		(layer "F.Cu")
		(at 63.6778 -113.251742)
		(property "Reference" "R86"
			(at 0 0 0)
			(layer "F.SilkS")
			(hide yes)
			(effects
				(font
					(size 1.27 1.27)
				)
			)
		)
		(property "Value" ""
			(at 0 0 0)
			(layer "F.Fab")
			(effects
				(font
					(size 1.27 1.27)
				)
			)
		)
		(duplicate_pad_numbers_are_jumpers no)
		(fp_line
			(start -0.7874 -0.4064)
			(end 0.7874 -0.4064)
			(stroke
				(width 0.1524)
				(type default)
			)
			(layer "F.SilkS")
		)
		(fp_line
			(start -0.7874 0.4064)
			(end -0.7874 -0.4064)
			(stroke
				(width 0.1524)
				(type default)
			)
			(layer "F.SilkS")
		)
		(fp_line
			(start 0.7874 -0.4064)
			(end 0.7874 0.4064)
			(stroke
				(width 0.1524)
				(type default)
			)
			(layer "F.SilkS")
		)
		(fp_line
			(start 0.7874 0.4064)
			(end -0.7874 0.4064)
			(stroke
				(width 0.1524)
				(type default)
			)
			(layer "F.SilkS")
		)
		(fp_line
			(start -0.67945 -0.305054)
			(end -0.12065 -0.305054)
			(stroke
				(width 0.1)
				(type default)
			)
			(layer "F.Fab")
		)
		(fp_line
			(start -0.67945 0.3048)
			(end -0.67945 -0.305054)
			(stroke
				(width 0.1)
				(type default)
			)
			(layer "F.Fab")
		)
		(fp_line
			(start -0.12065 -0.305054)
			(end -0.12065 -0.2794)
			(stroke
				(width 0.1)
				(type default)
			)
			(layer "F.Fab")
		)
		(fp_line
			(start -0.12065 -0.2794)
			(end 0.12065 -0.2794)
			(stroke
				(width 0.1)
				(type default)
			)
			(layer "F.Fab")
		)
		(fp_line
			(start -0.12065 0.2794)
			(end -0.12065 0.3048)
			(stroke
				(width 0.1)
				(type default)
			)
			(layer "F.Fab")
		)
		(fp_line
			(start -0.12065 0.3048)
			(end -0.67945 0.3048)
			(stroke
				(width 0.1)
				(type default)
			)
			(layer "F.Fab")
		)
		(fp_line
			(start 0.120396 0.2794)
			(end -0.12065 0.2794)
			(stroke
				(width 0.1)
				(type default)
			)
			(layer "F.Fab")
		)
		(fp_line
			(start 0.120396 0.3048)
			(end 0.120396 0.2794)
			(stroke
				(width 0.1)
				(type default)
			)
			(layer "F.Fab")
		)
		(fp_line
			(start 0.12065 -0.3048)
			(end 0.67945 -0.3048)
			(stroke
				(width 0.1)
				(type default)
			)
			(layer "F.Fab")
		)
		(fp_line
			(start 0.12065 -0.2794)
			(end 0.12065 -0.3048)
			(stroke
				(width 0.1)
				(type default)
			)
			(layer "F.Fab")
		)
		(fp_line
			(start 0.67945 -0.3048)
			(end 0.67945 0.3048)
			(stroke
				(width 0.1)
				(type default)
			)
			(layer "F.Fab")
		)
		(fp_line
			(start 0.67945 0.3048)
			(end 0.120396 0.3048)
			(stroke
				(width 0.1)
				(type default)
			)
			(layer "F.Fab")
		)
		(pad "1" smd circle
			(at -0.40005 0)
			(size 0 0)
			(layers "F.Cu" "F.Mask" "F.Paste")
			(net "RST_SMB_NIC1_MUX_ISO_N")
		)
		(pad "2" smd circle
			(at 0.40005 0)
			(size 0 0)
			(layers "F.Cu" "F.Mask" "F.Paste")
			(net "P3V3_NIC1")
		)
	)
	(footprint ""
		(layer "F.Cu")
		(at 268.734286 -250.070874 -90)
		(property "Reference" "R1342"
			(at 0 0 270)
			(layer "F.SilkS")
			(hide yes)
			(effects
				(font
					(size 1.27 1.27)
				)
			)
		)
		(property "Value" ""
			(at 0 0 270)
			(layer "F.Fab")
			(effects
				(font
					(size 1.27 1.27)
				)
			)
		)
		(duplicate_pad_numbers_are_jumpers no)
		(fp_line
			(start -0.7874 0.4064)
			(end -0.7874 -0.4064)
			(stroke
				(width 0.1524)
				(type default)
			)
			(layer "F.SilkS")
		)
		(fp_line
			(start 0.7874 0.4064)
			(end -0.7874 0.4064)
			(stroke
				(width 0.1524)
				(type default)
			)
			(layer "F.SilkS")
		)
		(fp_line
			(start -0.7874 -0.4064)
			(end 0.7874 -0.4064)
			(stroke
				(width 0.1524)
				(type default)
			)
			(layer "F.SilkS")
		)
		(fp_line
			(start 0.7874 -0.4064)
			(end 0.7874 0.4064)
			(stroke
				(width 0.1524)
				(type default)
			)
			(layer "F.SilkS")
		)
		(fp_line
			(start -0.67945 0.3048)
			(end -0.67945 -0.305054)
			(stroke
				(width 0.1)
				(type default)
			)
			(layer "F.Fab")
		)
		(fp_line
			(start -0.12065 0.3048)
			(end -0.67945 0.3048)
			(stroke
				(width 0.1)
				(type default)
			)
			(layer "F.Fab")
		)
		(fp_line
			(start 0.120396 0.3048)
			(end 0.120396 0.2794)
			(stroke
				(width 0.1)
				(type default)
			)
			(layer "F.Fab")
		)
		(fp_line
			(start 0.67945 0.3048)
			(end 0.120396 0.3048)
			(stroke
				(width 0.1)
				(type default)
			)
			(layer "F.Fab")
		)
		(fp_line
			(start -0.12065 0.2794)
			(end -0.12065 0.3048)
			(stroke
				(width 0.1)
				(type default)
			)
			(layer "F.Fab")
		)
		(fp_line
			(start 0.120396 0.2794)
			(end -0.12065 0.2794)
			(stroke
				(width 0.1)
				(type default)
			)
			(layer "F.Fab")
		)
		(fp_line
			(start -0.12065 -0.2794)
			(end 0.12065 -0.2794)
			(stroke
				(width 0.1)
				(type default)
			)
			(layer "F.Fab")
		)
		(fp_line
			(start 0.12065 -0.2794)
			(end 0.12065 -0.3048)
			(stroke
				(width 0.1)
				(type default)
			)
			(layer "F.Fab")
		)
		(fp_line
			(start 0.12065 -0.3048)
			(end 0.67945 -0.3048)
			(stroke
				(width 0.1)
				(type default)
			)
			(layer "F.Fab")
		)
		(fp_line
			(start 0.67945 -0.3048)
			(end 0.67945 0.3048)
			(stroke
				(width 0.1)
				(type default)
			)
			(layer "F.Fab")
		)
		(fp_line
			(start -0.67945 -0.305054)
			(end -0.12065 -0.305054)
			(stroke
				(width 0.1)
				(type default)
			)
			(layer "F.Fab")
		)
		(fp_line
			(start -0.12065 -0.305054)
			(end -0.12065 -0.2794)
			(stroke
				(width 0.1)
				(type default)
			)
			(layer "F.Fab")
		)
		(pad "1" smd circle
			(at -0.40005 0 270)
			(size 0 0)
			(layers "F.Cu" "F.Mask" "F.Paste")
			(net "PEX2_MODE_SEL6")
		)
		(pad "2" smd circle
			(at 0.40005 0 270)
			(size 0 0)
			(layers "F.Cu" "F.Mask" "F.Paste")
			(net "P1V8_PEX")
		)
	)
	(footprint ""
		(layer "F.Cu")
		(at 219.825316 -124.790962 180)
		(property "Reference" "R5965"
			(at 0 0 180)
			(layer "F.SilkS")
			(hide yes)
			(effects
				(font
					(size 1.27 1.27)
				)
			)
		)
		(property "Value" ""
			(at 0 0 180)
			(layer "F.Fab")
			(effects
				(font
					(size 1.27 1.27)
				)
			)
		)
		(duplicate_pad_numbers_are_jumpers no)
		(fp_line
			(start 0.7874 0.4064)
			(end -0.7874 0.4064)
			(stroke
				(width 0.1524)
				(type default)
			)
			(layer "F.SilkS")
		)
		(fp_line
			(start 0.7874 -0.4064)
			(end 0.7874 0.4064)
			(stroke
				(width 0.1524)
				(type default)
			)
			(layer "F.SilkS")
		)
		(fp_line
			(start -0.7874 0.4064)
			(end -0.7874 -0.4064)
			(stroke
				(width 0.1524)
				(type default)
			)
			(layer "F.SilkS")
		)
		(fp_line
			(start -0.7874 -0.4064)
			(end 0.7874 -0.4064)
			(stroke
				(width 0.1524)
				(type default)
			)
			(layer "F.SilkS")
		)
		(fp_line
			(start 0.67945 0.3048)
			(end 0.120396 0.3048)
			(stroke
				(width 0.1)
				(type default)
			)
			(layer "F.Fab")
		)
		(fp_line
			(start 0.67945 -0.3048)
			(end 0.67945 0.3048)
			(stroke
				(width 0.1)
				(type default)
			)
			(layer "F.Fab")
		)
		(fp_line
			(start 0.12065 -0.2794)
			(end 0.12065 -0.3048)
			(stroke
				(width 0.1)
				(type default)
			)
			(layer "F.Fab")
		)
		(fp_line
			(start 0.12065 -0.3048)
			(end 0.67945 -0.3048)
			(stroke
				(width 0.1)
				(type default)
			)
			(layer "F.Fab")
		)
		(fp_line
			(start 0.120396 0.3048)
			(end 0.120396 0.2794)
			(stroke
				(width 0.1)
				(type default)
			)
			(layer "F.Fab")
		)
		(fp_line
			(start 0.120396 0.2794)
			(end -0.12065 0.2794)
			(stroke
				(width 0.1)
				(type default)
			)
			(layer "F.Fab")
		)
		(fp_line
			(start -0.12065 0.3048)
			(end -0.67945 0.3048)
			(stroke
				(width 0.1)
				(type default)
			)
			(layer "F.Fab")
		)
		(fp_line
			(start -0.12065 0.2794)
			(end -0.12065 0.3048)
			(stroke
				(width 0.1)
				(type default)
			)
			(layer "F.Fab")
		)
		(fp_line
			(start -0.12065 -0.2794)
			(end 0.12065 -0.2794)
			(stroke
				(width 0.1)
				(type default)
			)
			(layer "F.Fab")
		)
		(fp_line
			(start -0.12065 -0.305054)
			(end -0.12065 -0.2794)
			(stroke
				(width 0.1)
				(type default)
			)
			(layer "F.Fab")
		)
		(fp_line
			(start -0.67945 0.3048)
			(end -0.67945 -0.305054)
			(stroke
				(width 0.1)
				(type default)
			)
			(layer "F.Fab")
		)
		(fp_line
			(start -0.67945 -0.305054)
			(end -0.12065 -0.305054)
			(stroke
				(width 0.1)
				(type default)
			)
			(layer "F.Fab")
		)
		(pad "1" smd circle
			(at -0.40005 0 180)
			(size 0 0)
			(layers "F.Cu" "F.Mask" "F.Paste")
			(net "P3V3_NIC3_PG_G1")
		)
		(pad "2" smd circle
			(at 0.40005 0 180)
			(size 0 0)
			(layers "F.Cu" "F.Mask" "F.Paste")
			(net "GND")
		)
	)
	(footprint ""
		(layer "F.Cu")
		(at 243.793264 -119.105426 -90)
		(property "Reference" "R6032"
			(at 0 0 270)
			(layer "F.SilkS")
			(hide yes)
			(effects
				(font
					(size 1.27 1.27)
				)
			)
		)
		(property "Value" ""
			(at 0 0 270)
			(layer "F.Fab")
			(effects
				(font
					(size 1.27 1.27)
				)
			)
		)
		(duplicate_pad_numbers_are_jumpers no)
		(fp_line
			(start -0.7874 0.4064)
			(end -0.7874 -0.4064)
			(stroke
				(width 0.1524)
				(type default)
			)
			(layer "F.SilkS")
		)
		(fp_line
			(start 0.7874 0.4064)
			(end -0.7874 0.4064)
			(stroke
				(width 0.1524)
				(type default)
			)
			(layer "F.SilkS")
		)
		(fp_line
			(start -0.7874 -0.4064)
			(end 0.7874 -0.4064)
			(stroke
				(width 0.1524)
				(type default)
			)
			(layer "F.SilkS")
		)
		(fp_line
			(start 0.7874 -0.4064)
			(end 0.7874 0.4064)
			(stroke
				(width 0.1524)
				(type default)
			)
			(layer "F.SilkS")
		)
		(fp_line
			(start -0.67945 0.3048)
			(end -0.67945 -0.305054)
			(stroke
				(width 0.1)
				(type default)
			)
			(layer "F.Fab")
		)
		(fp_line
			(start -0.12065 0.3048)
			(end -0.67945 0.3048)
			(stroke
				(width 0.1)
				(type default)
			)
			(layer "F.Fab")
		)
		(fp_line
			(start 0.120396 0.3048)
			(end 0.120396 0.2794)
			(stroke
				(width 0.1)
				(type default)
			)
			(layer "F.Fab")
		)
		(fp_line
			(start 0.67945 0.3048)
			(end 0.120396 0.3048)
			(stroke
				(width 0.1)
				(type default)
			)
			(layer "F.Fab")
		)
		(fp_line
			(start -0.12065 0.2794)
			(end -0.12065 0.3048)
			(stroke
				(width 0.1)
				(type default)
			)
			(layer "F.Fab")
		)
		(fp_line
			(start 0.120396 0.2794)
			(end -0.12065 0.2794)
			(stroke
				(width 0.1)
				(type default)
			)
			(layer "F.Fab")
		)
		(fp_line
			(start -0.12065 -0.2794)
			(end 0.12065 -0.2794)
			(stroke
				(width 0.1)
				(type default)
			)
			(layer "F.Fab")
		)
		(fp_line
			(start 0.12065 -0.2794)
			(end 0.12065 -0.3048)
			(stroke
				(width 0.1)
				(type default)
			)
			(layer "F.Fab")
		)
		(fp_line
			(start 0.12065 -0.3048)
			(end 0.67945 -0.3048)
			(stroke
				(width 0.1)
				(type default)
			)
			(layer "F.Fab")
		)
		(fp_line
			(start 0.67945 -0.3048)
			(end 0.67945 0.3048)
			(stroke
				(width 0.1)
				(type default)
			)
			(layer "F.Fab")
		)
		(fp_line
			(start -0.67945 -0.305054)
			(end -0.12065 -0.305054)
			(stroke
				(width 0.1)
				(type default)
			)
			(layer "F.Fab")
		)
		(fp_line
			(start -0.12065 -0.305054)
			(end -0.12065 -0.2794)
			(stroke
				(width 0.1)
				(type default)
			)
			(layer "F.Fab")
		)
		(pad "1" smd circle
			(at -0.40005 0 270)
			(size 0 0)
			(layers "F.Cu" "F.Mask" "F.Paste")
			(net "P3V3_AUX")
		)
		(pad "2" smd circle
			(at 0.40005 0 270)
			(size 0 0)
			(layers "F.Cu" "F.Mask" "F.Paste")
			(net "PWRGD_P3V3_NIC4_D")
		)
	)
	(footprint ""
		(layer "F.Cu")
		(at 140.731748 -350.098614 90)
		(property "Reference" "C2248"
			(at 0 0 90)
			(layer "F.SilkS")
			(hide yes)
			(effects
				(font
					(size 1.27 1.27)
				)
			)
		)
		(property "Value" ""
			(at 0 0 90)
			(layer "F.Fab")
			(effects
				(font
					(size 1.27 1.27)
				)
			)
		)
		(duplicate_pad_numbers_are_jumpers no)
		(fp_line
			(start 0.299974 -0.150114)
			(end 0.299974 0.150114)
			(stroke
				(width 0.1)
				(type default)
			)
			(layer "F.Fab")
		)
		(fp_line
			(start -0.299974 -0.150114)
			(end 0.299974 -0.150114)
			(stroke
				(width 0.1)
				(type default)
			)
			(layer "F.Fab")
		)
		(fp_line
			(start 0.299974 0.150114)
			(end -0.299974 0.150114)
			(stroke
				(width 0.1)
				(type default)
			)
			(layer "F.Fab")
		)
		(fp_line
			(start -0.299974 0.150114)
			(end -0.299974 -0.150114)
			(stroke
				(width 0.1)
				(type default)
			)
			(layer "F.Fab")
		)
		(pad "1" smd rect
			(at -0.2667 0 90)
			(size 0.3048 0.381)
			(layers "F.Cu" "F.Mask" "F.Paste")
			(net "P5E_PEX1_STN5_TX_DN<93>")
		)
		(pad "2" smd rect
			(at 0.2667 0 90)
			(size 0.3048 0.381)
			(layers "F.Cu" "F.Mask" "F.Paste")
			(net "P5E_PEX1_STN5_TX_C_DN<93>")
		)
	)
	(footprint ""
		(layer "F.Cu")
		(at 419.48989 -412.090108)
		(property "Reference" "J9"
			(at -5.783834 6.071108 90)
			(unlocked yes)
			(layer "F.SilkS")
			(effects
				(font
					(size 2.032 1.524)
					(thickness 0.1524)
				)
				(justify left)
			)
		)
		(property "Value" ""
			(at 0 0 0)
			(layer "F.Fab")
			(effects
				(font
					(size 1.27 1.27)
				)
			)
		)
		(duplicate_pad_numbers_are_jumpers no)
		(fp_line
			(start -4.249928 -16.999966)
			(end 24.45004 -16.999966)
			(stroke
				(width 0.1524)
				(type default)
			)
			(layer "F.SilkS")
		)
		(fp_line
			(start -4.249928 50.099976)
			(end -4.249928 -16.999966)
			(stroke
				(width 0.1524)
				(type default)
			)
			(layer "F.SilkS")
		)
		(fp_line
			(start -1.249934 -13.999972)
			(end -1.249934 47.099982)
			(stroke
				(width 0.1524)
				(type default)
			)
			(layer "F.SilkS")
		)
		(fp_line
			(start -1.249934 -6.500114)
			(end 21.450046 -6.500114)
			(stroke
				(width 0.1524)
				(type default)
			)
			(layer "F.SilkS")
		)
		(fp_line
			(start -1.249934 47.099982)
			(end 21.450046 47.099982)
			(stroke
				(width 0.1524)
				(type default)
			)
			(layer "F.SilkS")
		)
		(fp_line
			(start 21.450046 -13.999972)
			(end -1.249934 -13.999972)
			(stroke
				(width 0.1524)
				(type default)
			)
			(layer "F.SilkS")
		)
		(fp_line
			(start 21.450046 47.099982)
			(end 21.450046 -13.999972)
			(stroke
				(width 0.1524)
				(type default)
			)
			(layer "F.SilkS")
		)
		(fp_line
			(start 24.45004 -16.999966)
			(end 24.45004 50.099976)
			(stroke
				(width 0.1524)
				(type default)
			)
			(layer "F.SilkS")
		)
		(fp_line
			(start 24.45004 50.099976)
			(end -4.249928 50.099976)
			(stroke
				(width 0.1524)
				(type default)
			)
			(layer "F.SilkS")
		)
		(fp_poly
			(pts
				(xy -2.413 -0.508) (xy -2.413 0.508) (xy -1.397 0)
			)
			(stroke
				(width 0)
				(type default)
			)
			(fill yes)
			(layer "F.SilkS")
		)
		(fp_line
			(start -4.249928 -16.999966)
			(end 24.45004 -16.999966)
			(stroke
				(width 0.1524)
				(type default)
			)
			(layer "B.SilkS")
		)
		(fp_line
			(start -4.249928 50.099976)
			(end -4.249928 -16.999966)
			(stroke
				(width 0.1524)
				(type default)
			)
			(layer "B.SilkS")
		)
		(fp_line
			(start 24.45004 -16.999966)
			(end 24.45004 50.099976)
			(stroke
				(width 0.1524)
				(type default)
			)
			(layer "B.SilkS")
		)
		(fp_line
			(start 24.45004 50.099976)
			(end -4.249928 50.099976)
			(stroke
				(width 0.1524)
				(type default)
			)
			(layer "B.SilkS")
		)
		(fp_line
			(start -4.249928 -16.999966)
			(end 24.45004 -16.999966)
			(stroke
				(width 0.1)
				(type default)
			)
			(layer "B.Fab")
		)
		(fp_line
			(start -4.249928 50.099976)
			(end -4.249928 -16.999966)
			(stroke
				(width 0.1)
				(type default)
			)
			(layer "B.Fab")
		)
		(fp_line
			(start 24.45004 -16.999966)
			(end 24.45004 50.099976)
			(stroke
				(width 0.1)
				(type default)
			)
			(layer "B.Fab")
		)
		(fp_line
			(start 24.45004 50.099976)
			(end -4.249928 50.099976)
			(stroke
				(width 0.1)
				(type default)
			)
			(layer "B.Fab")
		)
		(fp_line
			(start -1.249934 -13.999972)
			(end -1.249934 47.099982)
			(stroke
				(width 0.1)
				(type default)
			)
			(layer "F.Fab")
		)
		(fp_line
			(start -1.249934 47.099982)
			(end 21.450046 47.099982)
			(stroke
				(width 0.1)
				(type default)
			)
			(layer "F.Fab")
		)
		(fp_line
			(start 21.450046 -13.999972)
			(end -1.249934 -13.999972)
			(stroke
				(width 0.1)
				(type default)
			)
			(layer "F.Fab")
		)
		(fp_line
			(start 21.450046 47.099982)
			(end 21.450046 -13.999972)
			(stroke
				(width 0.1)
				(type default)
			)
			(layer "F.Fab")
		)
		(fp_poly
			(pts
				(xy -2.413 -0.508) (xy -2.413 0.508) (xy -1.397 0)
			)
			(stroke
				(width 0)
				(type default)
			)
			(fill yes)
			(layer "F.Fab")
		)
		(fp_text user "PRESS-FIT"
			(at 23.118826 42.122344 90)
			(unlocked yes)
			(layer "F.SilkS")
			(effects
				(font
					(size 1.905 1.4224)
					(thickness 0.1524)
				)
				(justify left)
			)
		)
		(fp_text user "PRESS-FIT"
			(at -6.201918 31.739332 90)
			(unlocked yes)
			(layer "B.SilkS")
			(effects
				(font
					(size 1.905 1.4224)
					(thickness 0.1524)
				)
				(justify left mirror)
			)
		)
		(fp_text user "PRESS-FIT"
			(at 18.326862 48.74895 0)
			(unlocked yes)
			(layer "B.Fab")
			(effects
				(font
					(size 1.905 1.4224)
					(thickness 0.1524)
				)
				(justify left mirror)
			)
		)
		(fp_text user "PRESS-FIT"
			(at 1.5875 48.73625 0)
			(unlocked yes)
			(layer "F.Fab")
			(effects
				(font
					(size 1.905 1.4224)
					(thickness 0.1524)
				)
				(justify left)
			)
		)
		(pad "A1" thru_hole rect
			(at 0 0 180)
			(size 0.71628 0.71628)
			(drill 0.30988)
			(layers "*.Cu" "*.Mask")
			(remove_unused_layers no)
			(net "Net_8781")
			(clearance 0.0508)
			(thermal_gap 0.0508)
			(padstack
				(mode front_inner_back)
				(layer "Inner"
					(shape circle)
					(size 0.71628 0.71628)
					(clearance 0.0508)
				)
				(layer "B.Cu"
					(shape rect)
					(size 0.71628 0.71628)
					(clearance 0.0508)
				)
			)
		)
		(pad "A2" thru_hole circle
			(at 2.199894 0.199898 180)
			(size 0.906272 0.906272)
			(drill 0.499872)
			(layers "*.Cu" "*.Mask")
			(remove_unused_layers no)
			(net "GND")
			(clearance 0.0508)
			(thermal_gap 0.0508)
		)
		(pad "A3" thru_hole circle
			(at 4.400042 0 180)
			(size 0.71628 0.71628)
			(drill 0.30988)
			(layers "*.Cu" "*.Mask")
			(remove_unused_layers no)
			(net "Net_8779")
			(clearance 0.0508)
			(thermal_gap 0.0508)
		)
		(pad "A4" thru_hole circle
			(at 6.599936 0.199898 180)
			(size 0.906272 0.906272)
			(drill 0.499872)
			(layers "*.Cu" "*.Mask")
			(remove_unused_layers no)
			(net "GND")
			(clearance 0.0508)
			(thermal_gap 0.0508)
		)
		(pad "A5" thru_hole circle
			(at 8.800084 0 180)
			(size 0.71628 0.71628)
			(drill 0.30988)
			(layers "*.Cu" "*.Mask")
			(remove_unused_layers no)
			(net "Net_8777")
			(clearance 0.0508)
			(thermal_gap 0.0508)
		)
		(pad "A6" thru_hole circle
			(at 10.999978 0.199898 180)
			(size 0.906272 0.906272)
			(drill 0.499872)
			(layers "*.Cu" "*.Mask")
			(remove_unused_layers no)
			(net "GND")
			(clearance 0.0508)
			(thermal_gap 0.0508)
		)
		(pad "A7" thru_hole circle
			(at 13.199872 0 180)
			(size 0.71628 0.71628)
			(drill 0.30988)
			(layers "*.Cu" "*.Mask")
			(remove_unused_layers no)
			(net "PRSNT_GPU_A1_N")
			(clearance 0.0508)
			(thermal_gap 0.0508)
		)
		(pad "A8" thru_hole circle
			(at 15.40002 0.199898 180)
			(size 0.906272 0.906272)
			(drill 0.499872)
			(layers "*.Cu" "*.Mask")
			(remove_unused_layers no)
			(net "GND")
			(clearance 0.0508)
			(thermal_gap 0.0508)
		)
		(pad "A9" thru_hole circle
			(at 17.599914 0 180)
			(size 0.71628 0.71628)
			(drill 0.30988)
			(layers "*.Cu" "*.Mask")
			(remove_unused_layers no)
			(net "GPU_3V3IO_RSVD1")
			(clearance 0.0508)
			(thermal_gap 0.0508)
		)
		(pad "A10" thru_hole circle
			(at 19.800062 0.199898 180)
			(size 0.906272 0.906272)
			(drill 0.499872)
			(layers "*.Cu" "*.Mask")
			(remove_unused_layers no)
			(net "GND")
			(clearance 0.0508)
			(thermal_gap 0.0508)
		)
		(pad "B1" thru_hole circle
			(at 0 1.299972 180)
			(size 0.906272 0.906272)
			(drill 0.499872)
			(layers "*.Cu" "*.Mask")
			(remove_unused_layers no)
			(net "GND")
			(clearance 0.0508)
			(thermal_gap 0.0508)
		)
		(pad "B3" thru_hole circle
			(at 4.400042 1.299972 180)
			(size 0.906272 0.906272)
			(drill 0.499872)
			(layers "*.Cu" "*.Mask")
			(remove_unused_layers no)
			(net "GND")
			(clearance 0.0508)
			(thermal_gap 0.0508)
		)
		(pad "B5" thru_hole circle
			(at 8.800084 1.299972 180)
			(size 0.906272 0.906272)
			(drill 0.499872)
			(layers "*.Cu" "*.Mask")
			(remove_unused_layers no)
			(net "GND")
			(clearance 0.0508)
			(thermal_gap 0.0508)
		)
		(pad "B7" thru_hole circle
			(at 13.199872 1.299972 180)
			(size 0.906272 0.906272)
			(drill 0.499872)
			(layers "*.Cu" "*.Mask")
			(remove_unused_layers no)
			(net "GND")
			(clearance 0.0508)
			(thermal_gap 0.0508)
		)
		(pad "B9" thru_hole circle
			(at 17.599914 1.299972 180)
			(size 0.906272 0.906272)
			(drill 0.499872)
			(layers "*.Cu" "*.Mask")
			(remove_unused_layers no)
			(net "GND")
			(clearance 0.0508)
			(thermal_gap 0.0508)
		)
		(pad "B10" thru_hole circle
			(at 19.800062 1.500124 180)
			(size 0.71628 0.71628)
			(drill 0.30988)
			(layers "*.Cu" "*.Mask")
			(remove_unused_layers no)
			(net "Net_8774")
			(clearance 0.0508)
			(thermal_gap 0.0508)
		)
		(pad "C9" thru_hole circle
			(at 17.599914 2.599944 180)
			(size 0.71628 0.71628)
			(drill 0.30988)
			(layers "*.Cu" "*.Mask")
			(remove_unused_layers no)
			(net "Net_8772")
			(clearance 0.0508)
			(thermal_gap 0.0508)
		)
		(pad "C10" thru_hole circle
			(at 19.800062 2.800096 180)
			(size 0.71628 0.71628)
			(drill 0.30988)
			(layers "*.Cu" "*.Mask")
			(remove_unused_layers no)
			(net "Net_8773")
			(clearance 0.0508)
			(thermal_gap 0.0508)
		)
		(pad "D2" thru_hole circle
			(at 2.199894 4.100068 180)
			(size 0.906272 0.906272)
			(drill 0.499872)
			(layers "*.Cu" "*.Mask")
			(remove_unused_layers no)
			(net "GND")
			(clearance 0.0508)
			(thermal_gap 0.0508)
		)
		(pad "D4" thru_hole circle
			(at 6.599936 4.100068 180)
			(size 0.906272 0.906272)
			(drill 0.499872)
			(layers "*.Cu" "*.Mask")
			(remove_unused_layers no)
			(net "GND")
			(clearance 0.0508)
			(thermal_gap 0.0508)
		)
		(pad "D6" thru_hole circle
			(at 10.999978 4.100068 180)
			(size 0.906272 0.906272)
			(drill 0.499872)
			(layers "*.Cu" "*.Mask")
			(remove_unused_layers no)
			(net "GND")
			(clearance 0.0508)
			(thermal_gap 0.0508)
		)
		(pad "D8" thru_hole circle
			(at 15.40002 4.100068 180)
			(size 0.906272 0.906272)
			(drill 0.499872)
			(layers "*.Cu" "*.Mask")
			(remove_unused_layers no)
			(net "GND")
			(clearance 0.0508)
			(thermal_gap 0.0508)
		)
		(pad "D9" thru_hole circle
			(at 17.599914 3.899916 180)
			(size 0.71628 0.71628)
			(drill 0.30988)
			(layers "*.Cu" "*.Mask")
			(remove_unused_layers no)
			(net "GPU_3V3IO_RSVD3")
			(clearance 0.0508)
			(thermal_gap 0.0508)
		)
		(pad "D10" thru_hole circle
			(at 19.800062 4.100068 180)
			(size 0.906272 0.906272)
			(drill 0.499872)
			(layers "*.Cu" "*.Mask")
			(remove_unused_layers no)
			(net "GND")
			(clearance 0.0508)
			(thermal_gap 0.0508)
		)
		(pad "E1" thru_hole circle
			(at 0 5.199888 180)
			(size 0.906272 0.906272)
			(drill 0.499872)
			(layers "*.Cu" "*.Mask")
			(remove_unused_layers no)
			(net "GND")
			(clearance 0.0508)
			(thermal_gap 0.0508)
		)
		(pad "E3" thru_hole circle
			(at 4.400042 5.199888 180)
			(size 0.906272 0.906272)
			(drill 0.499872)
			(layers "*.Cu" "*.Mask")
			(remove_unused_layers no)
			(net "GND")
			(clearance 0.0508)
			(thermal_gap 0.0508)
		)
		(pad "E5" thru_hole circle
			(at 8.800084 5.199888 180)
			(size 0.906272 0.906272)
			(drill 0.499872)
			(layers "*.Cu" "*.Mask")
			(remove_unused_layers no)
			(net "GND")
			(clearance 0.0508)
			(thermal_gap 0.0508)
		)
		(pad "E7" thru_hole circle
			(at 13.199872 5.199888 180)
			(size 0.906272 0.906272)
			(drill 0.499872)
			(layers "*.Cu" "*.Mask")
			(remove_unused_layers no)
			(net "GND")
			(clearance 0.0508)
			(thermal_gap 0.0508)
		)
		(pad "E9" thru_hole circle
			(at 17.599914 5.199888 180)
			(size 0.906272 0.906272)
			(drill 0.499872)
			(layers "*.Cu" "*.Mask")
			(remove_unused_layers no)
			(net "GND")
			(clearance 0.0508)
			(thermal_gap 0.0508)
		)
		(pad "E10" thru_hole circle
			(at 19.800062 5.40004 180)
			(size 0.71628 0.71628)
			(drill 0.30988)
			(layers "*.Cu" "*.Mask")
			(remove_unused_layers no)
			(net "Net_8771")
			(clearance 0.0508)
			(thermal_gap 0.0508)
		)
		(pad "F9" thru_hole circle
			(at 17.599914 6.500114 180)
			(size 0.71628 0.71628)
			(drill 0.30988)
			(layers "*.Cu" "*.Mask")
			(remove_unused_layers no)
			(net "Net_8769")
			(clearance 0.0508)
			(thermal_gap 0.0508)
		)
		(pad "F10" thru_hole circle
			(at 19.800062 6.700012 180)
			(size 0.71628 0.71628)
			(drill 0.30988)
			(layers "*.Cu" "*.Mask")
			(remove_unused_layers no)
			(net "Net_8770")
			(clearance 0.0508)
			(thermal_gap 0.0508)
		)
		(pad "G2" thru_hole circle
			(at 2.199894 7.999984 180)
			(size 0.906272 0.906272)
			(drill 0.499872)
			(layers "*.Cu" "*.Mask")
			(remove_unused_layers no)
			(net "GND")
			(clearance 0.0508)
			(thermal_gap 0.0508)
		)
		(pad "G4" thru_hole circle
			(at 6.599936 7.999984 180)
			(size 0.906272 0.906272)
			(drill 0.499872)
			(layers "*.Cu" "*.Mask")
			(remove_unused_layers no)
			(net "GND")
			(clearance 0.0508)
			(thermal_gap 0.0508)
		)
		(pad "G6" thru_hole circle
			(at 10.999978 7.999984 180)
			(size 0.906272 0.906272)
			(drill 0.499872)
			(layers "*.Cu" "*.Mask")
			(remove_unused_layers no)
			(net "GND")
			(clearance 0.0508)
			(thermal_gap 0.0508)
		)
		(pad "G8" thru_hole circle
			(at 15.40002 7.999984 180)
			(size 0.906272 0.906272)
			(drill 0.499872)
			(layers "*.Cu" "*.Mask")
			(remove_unused_layers no)
			(net "GND")
			(clearance 0.0508)
			(thermal_gap 0.0508)
		)
		(pad "G9" thru_hole circle
			(at 17.599914 7.800086 180)
			(size 0.71628 0.71628)
			(drill 0.30988)
			(layers "*.Cu" "*.Mask")
			(remove_unused_layers no)
			(net "GPU_WP_HW_CTRL_R_N")
			(clearance 0.0508)
			(thermal_gap 0.0508)
		)
		(pad "G10" thru_hole circle
			(at 19.800062 7.999984 180)
			(size 0.906272 0.906272)
			(drill 0.499872)
			(layers "*.Cu" "*.Mask")
			(remove_unused_layers no)
			(net "GND")
			(clearance 0.0508)
			(thermal_gap 0.0508)
		)
		(pad "H1" thru_hole circle
			(at 0 9.100058 180)
			(size 0.906272 0.906272)
			(drill 0.499872)
			(layers "*.Cu" "*.Mask")
			(remove_unused_layers no)
			(net "GND")
			(clearance 0.0508)
			(thermal_gap 0.0508)
		)
		(pad "H3" thru_hole circle
			(at 4.400042 9.100058 180)
			(size 0.906272 0.906272)
			(drill 0.499872)
			(layers "*.Cu" "*.Mask")
			(remove_unused_layers no)
			(net "GND")
			(clearance 0.0508)
			(thermal_gap 0.0508)
		)
		(pad "H5" thru_hole circle
			(at 8.800084 9.100058 180)
			(size 0.906272 0.906272)
			(drill 0.499872)
			(layers "*.Cu" "*.Mask")
			(remove_unused_layers no)
			(net "GND")
			(clearance 0.0508)
			(thermal_gap 0.0508)
		)
		(pad "H7" thru_hole circle
			(at 13.199872 9.100058 180)
			(size 0.906272 0.906272)
			(drill 0.499872)
			(layers "*.Cu" "*.Mask")
			(remove_unused_layers no)
			(net "GND")
			(clearance 0.0508)
			(thermal_gap 0.0508)
		)
		(pad "H9" thru_hole circle
			(at 17.599914 9.100058 180)
			(size 0.906272 0.906272)
			(drill 0.499872)
			(layers "*.Cu" "*.Mask")
			(remove_unused_layers no)
			(net "GND")
			(clearance 0.0508)
			(thermal_gap 0.0508)
		)
		(pad "H10" thru_hole circle
			(at 19.800062 9.299956 180)
			(size 0.71628 0.71628)
			(drill 0.30988)
			(layers "*.Cu" "*.Mask")
			(remove_unused_layers no)
			(net "Net_8768")
			(clearance 0.0508)
			(thermal_gap 0.0508)
		)
		(pad "I9" thru_hole circle
			(at 17.599914 10.40003 180)
			(size 0.71628 0.71628)
			(drill 0.30988)
			(layers "*.Cu" "*.Mask")
			(remove_unused_layers no)
			(net "Net_8767")
			(clearance 0.0508)
			(thermal_gap 0.0508)
		)
		(pad "I10" thru_hole circle
			(at 19.800062 10.599928 180)
			(size 0.71628 0.71628)
			(drill 0.30988)
			(layers "*.Cu" "*.Mask")
			(remove_unused_layers no)
			(net "GPU_3V3IO_RSVD4")
			(clearance 0.0508)
			(thermal_gap 0.0508)
		)
		(pad "J2" thru_hole circle
			(at 2.199894 11.8999 180)
			(size 0.906272 0.906272)
			(drill 0.499872)
			(layers "*.Cu" "*.Mask")
			(remove_unused_layers no)
			(net "GND")
			(clearance 0.0508)
			(thermal_gap 0.0508)
		)
		(pad "J4" thru_hole circle
			(at 6.599936 11.8999 180)
			(size 0.906272 0.906272)
			(drill 0.499872)
			(layers "*.Cu" "*.Mask")
			(remove_unused_layers no)
			(net "GND")
			(clearance 0.0508)
			(thermal_gap 0.0508)
		)
		(pad "J6" thru_hole circle
			(at 10.999978 11.8999 180)
			(size 0.906272 0.906272)
			(drill 0.499872)
			(layers "*.Cu" "*.Mask")
			(remove_unused_layers no)
			(net "GND")
			(clearance 0.0508)
			(thermal_gap 0.0508)
		)
		(pad "J8" thru_hole circle
			(at 15.40002 11.8999 180)
			(size 0.906272 0.906272)
			(drill 0.499872)
			(layers "*.Cu" "*.Mask")
			(remove_unused_layers no)
			(net "GND")
			(clearance 0.0508)
			(thermal_gap 0.0508)
		)
		(pad "J9" thru_hole circle
			(at 17.599914 11.700002 180)
			(size 0.71628 0.71628)
			(drill 0.30988)
			(layers "*.Cu" "*.Mask")
			(remove_unused_layers no)
			(net "Net_8766")
			(clearance 0.0508)
			(thermal_gap 0.0508)
		)
		(pad "J10" thru_hole circle
			(at 19.800062 11.8999 180)
			(size 0.906272 0.906272)
			(drill 0.499872)
			(layers "*.Cu" "*.Mask")
			(remove_unused_layers no)
			(net "GND")
			(clearance 0.0508)
			(thermal_gap 0.0508)
		)
		(pad "K1" thru_hole circle
			(at 0 12.999974 180)
			(size 0.906272 0.906272)
			(drill 0.499872)
			(layers "*.Cu" "*.Mask")
			(remove_unused_layers no)
			(net "GND")
			(clearance 0.0508)
			(thermal_gap 0.0508)
		)
		(pad "K3" thru_hole circle
			(at 4.400042 12.999974 180)
			(size 0.906272 0.906272)
			(drill 0.499872)
			(layers "*.Cu" "*.Mask")
			(remove_unused_layers no)
			(net "GND")
			(clearance 0.0508)
			(thermal_gap 0.0508)
		)
		(pad "K5" thru_hole circle
			(at 8.800084 12.999974 180)
			(size 0.906272 0.906272)
			(drill 0.499872)
			(layers "*.Cu" "*.Mask")
			(remove_unused_layers no)
			(net "GND")
			(clearance 0.0508)
			(thermal_gap 0.0508)
		)
		(pad "K7" thru_hole circle
			(at 13.199872 12.999974 180)
			(size 0.906272 0.906272)
			(drill 0.499872)
			(layers "*.Cu" "*.Mask")
			(remove_unused_layers no)
			(net "GND")
			(clearance 0.0508)
			(thermal_gap 0.0508)
		)
		(pad "K9" thru_hole circle
			(at 17.599914 12.999974 180)
			(size 0.906272 0.906272)
			(drill 0.499872)
			(layers "*.Cu" "*.Mask")
			(remove_unused_layers no)
			(net "GND")
			(clearance 0.0508)
			(thermal_gap 0.0508)
		)
		(pad "K10" thru_hole circle
			(at 19.800062 13.199872 180)
			(size 0.71628 0.71628)
			(drill 0.30988)
			(layers "*.Cu" "*.Mask")
			(remove_unused_layers no)
			(net "Net_8765")
			(clearance 0.0508)
			(thermal_gap 0.0508)
		)
		(pad "L9" thru_hole circle
			(at 17.599914 14.299946 180)
			(size 0.71628 0.71628)
			(drill 0.30988)
			(layers "*.Cu" "*.Mask")
			(remove_unused_layers no)
			(net "Net_8763")
			(clearance 0.0508)
			(thermal_gap 0.0508)
		)
		(pad "L10" thru_hole circle
			(at 19.800062 14.500098 180)
			(size 0.71628 0.71628)
			(drill 0.30988)
			(layers "*.Cu" "*.Mask")
			(remove_unused_layers no)
			(net "Net_8764")
			(clearance 0.0508)
			(thermal_gap 0.0508)
		)
		(pad "M1_2" thru_hole circle
			(at 2.199894 15.80007 180)
			(size 0.906272 0.906272)
			(drill 0.499872)
			(layers "*.Cu" "*.Mask")
			(remove_unused_layers no)
			(net "GND")
			(clearance 0.0508)
			(thermal_gap 0.0508)
		)
		(pad "M1_4" thru_hole circle
			(at 6.599936 15.80007 180)
			(size 0.906272 0.906272)
			(drill 0.499872)
			(layers "*.Cu" "*.Mask")
			(remove_unused_layers no)
			(net "GND")
			(clearance 0.0508)
			(thermal_gap 0.0508)
		)
		(pad "M1_6" thru_hole circle
			(at 10.999978 15.80007 180)
			(size 0.906272 0.906272)
			(drill 0.499872)
			(layers "*.Cu" "*.Mask")
			(remove_unused_layers no)
			(net "GND")
			(clearance 0.0508)
			(thermal_gap 0.0508)
		)
		(pad "M1_8" thru_hole circle
			(at 15.40002 15.80007 180)
			(size 0.906272 0.906272)
			(drill 0.499872)
			(layers "*.Cu" "*.Mask")
			(remove_unused_layers no)
			(net "GND")
			(clearance 0.0508)
			(thermal_gap 0.0508)
		)
		(pad "M1_10" thru_hole circle
			(at 19.800062 15.80007 180)
			(size 0.906272 0.906272)
			(drill 0.499872)
			(layers "*.Cu" "*.Mask")
			(remove_unused_layers no)
			(net "GND")
			(clearance 0.0508)
			(thermal_gap 0.0508)
		)
		(pad "M2_2" thru_hole circle
			(at 2.199894 26.2001 180)
			(size 0.906272 0.906272)
			(drill 0.499872)
			(layers "*.Cu" "*.Mask")
			(remove_unused_layers no)
			(net "GND")
			(clearance 0.0508)
			(thermal_gap 0.0508)
		)
		(pad "M2_4" thru_hole circle
			(at 6.599936 26.2001 180)
			(size 0.906272 0.906272)
			(drill 0.499872)
			(layers "*.Cu" "*.Mask")
			(remove_unused_layers no)
			(net "GND")
			(clearance 0.0508)
			(thermal_gap 0.0508)
		)
		(pad "M2_6" thru_hole circle
			(at 10.999978 26.2001 180)
			(size 0.906272 0.906272)
			(drill 0.499872)
			(layers "*.Cu" "*.Mask")
			(remove_unused_layers no)
			(net "GND")
			(clearance 0.0508)
			(thermal_gap 0.0508)
		)
		(pad "M2_8" thru_hole circle
			(at 15.40002 26.2001 180)
			(size 0.906272 0.906272)
			(drill 0.499872)
			(layers "*.Cu" "*.Mask")
			(remove_unused_layers no)
			(net "GND")
			(clearance 0.0508)
			(thermal_gap 0.0508)
		)
		(pad "M2_10" thru_hole circle
			(at 19.800062 26.2001 180)
			(size 0.906272 0.906272)
			(drill 0.499872)
			(layers "*.Cu" "*.Mask")
			(remove_unused_layers no)
			(net "GND")
			(clearance 0.0508)
			(thermal_gap 0.0508)
		)
		(pad "M9" thru_hole circle
			(at 17.599914 15.599918 180)
			(size 0.71628 0.71628)
			(drill 0.30988)
			(layers "*.Cu" "*.Mask")
			(remove_unused_layers no)
			(net "Net_8762")
			(clearance 0.0508)
			(thermal_gap 0.0508)
		)
		(pad "N1_1" thru_hole circle
			(at 0 16.89989 180)
			(size 0.906272 0.906272)
			(drill 0.499872)
			(layers "*.Cu" "*.Mask")
			(remove_unused_layers no)
			(net "GND")
			(clearance 0.0508)
			(thermal_gap 0.0508)
		)
		(pad "N1_3" thru_hole circle
			(at 4.400042 16.89989 180)
			(size 0.906272 0.906272)
			(drill 0.499872)
			(layers "*.Cu" "*.Mask")
			(remove_unused_layers no)
			(net "GND")
			(clearance 0.0508)
			(thermal_gap 0.0508)
		)
		(pad "N1_5" thru_hole circle
			(at 8.800084 16.89989 180)
			(size 0.906272 0.906272)
			(drill 0.499872)
			(layers "*.Cu" "*.Mask")
			(remove_unused_layers no)
			(net "GND")
			(clearance 0.0508)
			(thermal_gap 0.0508)
		)
		(pad "N1_7" thru_hole circle
			(at 13.199872 16.89989 180)
			(size 0.906272 0.906272)
			(drill 0.499872)
			(layers "*.Cu" "*.Mask")
			(remove_unused_layers no)
			(net "GND")
			(clearance 0.0508)
			(thermal_gap 0.0508)
		)
		(pad "N1_9" thru_hole circle
			(at 17.599914 16.89989 180)
			(size 0.906272 0.906272)
			(drill 0.499872)
			(layers "*.Cu" "*.Mask")
			(remove_unused_layers no)
			(net "GND")
			(clearance 0.0508)
			(thermal_gap 0.0508)
		)
		(pad "N2_1" thru_hole circle
			(at 0 27.29992 180)
			(size 0.906272 0.906272)
			(drill 0.499872)
			(layers "*.Cu" "*.Mask")
			(remove_unused_layers no)
			(net "GND")
			(clearance 0.0508)
			(thermal_gap 0.0508)
		)
		(pad "N2_3" thru_hole circle
			(at 4.400042 27.29992 180)
			(size 0.906272 0.906272)
			(drill 0.499872)
			(layers "*.Cu" "*.Mask")
			(remove_unused_layers no)
			(net "GND")
			(clearance 0.0508)
			(thermal_gap 0.0508)
		)
		(pad "N2_5" thru_hole circle
			(at 8.800084 27.29992 180)
			(size 0.906272 0.906272)
			(drill 0.499872)
			(layers "*.Cu" "*.Mask")
			(remove_unused_layers no)
			(net "GND")
			(clearance 0.0508)
			(thermal_gap 0.0508)
		)
		(pad "N2_7" thru_hole circle
			(at 13.199872 27.29992 180)
			(size 0.906272 0.906272)
			(drill 0.499872)
			(layers "*.Cu" "*.Mask")
			(remove_unused_layers no)
			(net "GND")
			(clearance 0.0508)
			(thermal_gap 0.0508)
		)
		(pad "N2_9" thru_hole circle
			(at 17.599914 27.29992 180)
			(size 0.906272 0.906272)
			(drill 0.499872)
			(layers "*.Cu" "*.Mask")
			(remove_unused_layers no)
			(net "GND")
			(clearance 0.0508)
			(thermal_gap 0.0508)
		)
		(pad "N10" thru_hole circle
			(at 19.800062 27.500072 180)
			(size 0.71628 0.71628)
			(drill 0.30988)
			(layers "*.Cu" "*.Mask")
			(remove_unused_layers no)
			(net "Net_8761")
			(clearance 0.0508)
			(thermal_gap 0.0508)
		)
		(pad "O9" thru_hole circle
			(at 17.599914 28.599892 180)
			(size 0.71628 0.71628)
			(drill 0.30988)
			(layers "*.Cu" "*.Mask")
			(remove_unused_layers no)
			(net "Net_8759")
			(clearance 0.0508)
			(thermal_gap 0.0508)
		)
		(pad "O10" thru_hole circle
			(at 19.800062 28.800044 180)
			(size 0.71628 0.71628)
			(drill 0.30988)
			(layers "*.Cu" "*.Mask")
			(remove_unused_layers no)
			(net "Net_8760")
			(clearance 0.0508)
			(thermal_gap 0.0508)
		)
		(pad "P2" thru_hole circle
			(at 2.199894 30.100016 180)
			(size 0.906272 0.906272)
			(drill 0.499872)
			(layers "*.Cu" "*.Mask")
			(remove_unused_layers no)
			(net "GND")
			(clearance 0.0508)
			(thermal_gap 0.0508)
		)
		(pad "P4" thru_hole circle
			(at 6.599936 30.100016 180)
			(size 0.906272 0.906272)
			(drill 0.499872)
			(layers "*.Cu" "*.Mask")
			(remove_unused_layers no)
			(net "GND")
			(clearance 0.0508)
			(thermal_gap 0.0508)
		)
		(pad "P6" thru_hole circle
			(at 10.999978 30.100016 180)
			(size 0.906272 0.906272)
			(drill 0.499872)
			(layers "*.Cu" "*.Mask")
			(remove_unused_layers no)
			(net "GND")
			(clearance 0.0508)
			(thermal_gap 0.0508)
		)
		(pad "P8" thru_hole circle
			(at 15.40002 30.100016 180)
			(size 0.906272 0.906272)
			(drill 0.499872)
			(layers "*.Cu" "*.Mask")
			(remove_unused_layers no)
			(net "GND")
			(clearance 0.0508)
			(thermal_gap 0.0508)
		)
		(pad "P9" thru_hole circle
			(at 17.599914 29.900118 180)
			(size 0.71628 0.71628)
			(drill 0.30988)
			(layers "*.Cu" "*.Mask")
			(remove_unused_layers no)
			(net "Net_8758")
			(clearance 0.0508)
			(thermal_gap 0.0508)
		)
		(pad "P10" thru_hole circle
			(at 19.800062 30.100016 180)
			(size 0.906272 0.906272)
			(drill 0.499872)
			(layers "*.Cu" "*.Mask")
			(remove_unused_layers no)
			(net "GND")
			(clearance 0.0508)
			(thermal_gap 0.0508)
		)
		(pad "Q1" thru_hole circle
			(at 0 31.20009 180)
			(size 0.906272 0.906272)
			(drill 0.499872)
			(layers "*.Cu" "*.Mask")
			(remove_unused_layers no)
			(net "GND")
			(clearance 0.0508)
			(thermal_gap 0.0508)
		)
		(pad "Q3" thru_hole circle
			(at 4.400042 31.20009 180)
			(size 0.906272 0.906272)
			(drill 0.499872)
			(layers "*.Cu" "*.Mask")
			(remove_unused_layers no)
			(net "GND")
			(clearance 0.0508)
			(thermal_gap 0.0508)
		)
		(pad "Q5" thru_hole circle
			(at 8.800084 31.20009 180)
			(size 0.906272 0.906272)
			(drill 0.499872)
			(layers "*.Cu" "*.Mask")
			(remove_unused_layers no)
			(net "GND")
			(clearance 0.0508)
			(thermal_gap 0.0508)
		)
		(pad "Q7" thru_hole circle
			(at 13.199872 31.20009 180)
			(size 0.906272 0.906272)
			(drill 0.499872)
			(layers "*.Cu" "*.Mask")
			(remove_unused_layers no)
			(net "GND")
			(clearance 0.0508)
			(thermal_gap 0.0508)
		)
		(pad "Q9" thru_hole circle
			(at 17.599914 31.20009 180)
			(size 0.906272 0.906272)
			(drill 0.499872)
			(layers "*.Cu" "*.Mask")
			(remove_unused_layers no)
			(net "GND")
			(clearance 0.0508)
			(thermal_gap 0.0508)
		)
		(pad "Q10" thru_hole circle
			(at 19.800062 31.399988 180)
			(size 0.71628 0.71628)
			(drill 0.30988)
			(layers "*.Cu" "*.Mask")
			(remove_unused_layers no)
			(net "Net_8757")
			(clearance 0.0508)
			(thermal_gap 0.0508)
		)
		(pad "R9" thru_hole circle
			(at 17.599914 32.500062 180)
			(size 0.71628 0.71628)
			(drill 0.30988)
			(layers "*.Cu" "*.Mask")
			(remove_unused_layers no)
			(net "Net_8755")
			(clearance 0.0508)
			(thermal_gap 0.0508)
		)
		(pad "R10" thru_hole circle
			(at 19.800062 32.69996 180)
			(size 0.71628 0.71628)
			(drill 0.30988)
			(layers "*.Cu" "*.Mask")
			(remove_unused_layers no)
			(net "Net_8756")
			(clearance 0.0508)
			(thermal_gap 0.0508)
		)
		(pad "S2" thru_hole circle
			(at 2.199894 33.999932 180)
			(size 0.906272 0.906272)
			(drill 0.499872)
			(layers "*.Cu" "*.Mask")
			(remove_unused_layers no)
			(net "GND")
			(clearance 0.0508)
			(thermal_gap 0.0508)
		)
		(pad "S4" thru_hole circle
			(at 6.599936 33.999932 180)
			(size 0.906272 0.906272)
			(drill 0.499872)
			(layers "*.Cu" "*.Mask")
			(remove_unused_layers no)
			(net "GND")
			(clearance 0.0508)
			(thermal_gap 0.0508)
		)
		(pad "S6" thru_hole circle
			(at 10.999978 33.999932 180)
			(size 0.906272 0.906272)
			(drill 0.499872)
			(layers "*.Cu" "*.Mask")
			(remove_unused_layers no)
			(net "GND")
			(clearance 0.0508)
			(thermal_gap 0.0508)
		)
		(pad "S8" thru_hole circle
			(at 15.40002 33.999932 180)
			(size 0.906272 0.906272)
			(drill 0.499872)
			(layers "*.Cu" "*.Mask")
			(remove_unused_layers no)
			(net "GND")
			(clearance 0.0508)
			(thermal_gap 0.0508)
		)
		(pad "S9" thru_hole circle
			(at 17.599914 33.800034 180)
			(size 0.71628 0.71628)
			(drill 0.30988)
			(layers "*.Cu" "*.Mask")
			(remove_unused_layers no)
			(net "Net_8754")
			(clearance 0.0508)
			(thermal_gap 0.0508)
		)
		(pad "S10" thru_hole circle
			(at 19.800062 33.999932 180)
			(size 0.906272 0.906272)
			(drill 0.499872)
			(layers "*.Cu" "*.Mask")
			(remove_unused_layers no)
			(net "GND")
			(clearance 0.0508)
			(thermal_gap 0.0508)
		)
		(pad "T1" thru_hole circle
			(at 0 35.100006 180)
			(size 0.906272 0.906272)
			(drill 0.499872)
			(layers "*.Cu" "*.Mask")
			(remove_unused_layers no)
			(net "GND")
			(clearance 0.0508)
			(thermal_gap 0.0508)
		)
		(pad "T3" thru_hole circle
			(at 4.400042 35.100006 180)
			(size 0.906272 0.906272)
			(drill 0.499872)
			(layers "*.Cu" "*.Mask")
			(remove_unused_layers no)
			(net "GND")
			(clearance 0.0508)
			(thermal_gap 0.0508)
		)
		(pad "T5" thru_hole circle
			(at 8.800084 35.100006 180)
			(size 0.906272 0.906272)
			(drill 0.499872)
			(layers "*.Cu" "*.Mask")
			(remove_unused_layers no)
			(net "GND")
			(clearance 0.0508)
			(thermal_gap 0.0508)
		)
		(pad "T7" thru_hole circle
			(at 13.199872 35.100006 180)
			(size 0.906272 0.906272)
			(drill 0.499872)
			(layers "*.Cu" "*.Mask")
			(remove_unused_layers no)
			(net "GND")
			(clearance 0.0508)
			(thermal_gap 0.0508)
		)
		(pad "T9" thru_hole circle
			(at 17.599914 35.100006 180)
			(size 0.906272 0.906272)
			(drill 0.499872)
			(layers "*.Cu" "*.Mask")
			(remove_unused_layers no)
			(net "GND")
			(clearance 0.0508)
			(thermal_gap 0.0508)
		)
		(pad "T10" thru_hole circle
			(at 19.800062 35.299904 180)
			(size 0.71628 0.71628)
			(drill 0.30988)
			(layers "*.Cu" "*.Mask")
			(remove_unused_layers no)
			(net "Net_8753")
			(clearance 0.0508)
			(thermal_gap 0.0508)
		)
		(pad "U9" thru_hole circle
			(at 17.599914 36.399978 180)
			(size 0.71628 0.71628)
			(drill 0.30988)
			(layers "*.Cu" "*.Mask")
			(remove_unused_layers no)
			(net "Net_8751")
			(clearance 0.0508)
			(thermal_gap 0.0508)
		)
		(pad "U10" thru_hole circle
			(at 19.800062 36.599876 180)
			(size 0.71628 0.71628)
			(drill 0.30988)
			(layers "*.Cu" "*.Mask")
			(remove_unused_layers no)
			(net "Net_8752")
			(clearance 0.0508)
			(thermal_gap 0.0508)
		)
		(pad "V2" thru_hole circle
			(at 2.199894 37.900102 180)
			(size 0.906272 0.906272)
			(drill 0.499872)
			(layers "*.Cu" "*.Mask")
			(remove_unused_layers no)
			(net "GND")
			(clearance 0.0508)
			(thermal_gap 0.0508)
		)
		(pad "V4" thru_hole circle
			(at 6.599936 37.900102 180)
			(size 0.906272 0.906272)
			(drill 0.499872)
			(layers "*.Cu" "*.Mask")
			(remove_unused_layers no)
			(net "GND")
			(clearance 0.0508)
			(thermal_gap 0.0508)
		)
		(pad "V6" thru_hole circle
			(at 10.999978 37.900102 180)
			(size 0.906272 0.906272)
			(drill 0.499872)
			(layers "*.Cu" "*.Mask")
			(remove_unused_layers no)
			(net "GND")
			(clearance 0.0508)
			(thermal_gap 0.0508)
		)
		(pad "V8" thru_hole circle
			(at 15.40002 37.900102 180)
			(size 0.906272 0.906272)
			(drill 0.499872)
			(layers "*.Cu" "*.Mask")
			(remove_unused_layers no)
			(net "GND")
			(clearance 0.0508)
			(thermal_gap 0.0508)
		)
		(pad "V9" thru_hole circle
			(at 17.599914 37.69995 180)
			(size 0.71628 0.71628)
			(drill 0.30988)
			(layers "*.Cu" "*.Mask")
			(remove_unused_layers no)
			(net "Net_8750")
			(clearance 0.0508)
			(thermal_gap 0.0508)
		)
		(pad "V10" thru_hole circle
			(at 19.800062 37.900102 180)
			(size 0.906272 0.906272)
			(drill 0.499872)
			(layers "*.Cu" "*.Mask")
			(remove_unused_layers no)
			(net "GND")
			(clearance 0.0508)
			(thermal_gap 0.0508)
		)
		(pad "W1" thru_hole circle
			(at 0 38.999922 180)
			(size 0.906272 0.906272)
			(drill 0.499872)
			(layers "*.Cu" "*.Mask")
			(remove_unused_layers no)
			(net "GND")
			(clearance 0.0508)
			(thermal_gap 0.0508)
		)
		(pad "W3" thru_hole circle
			(at 4.400042 38.999922 180)
			(size 0.906272 0.906272)
			(drill 0.499872)
			(layers "*.Cu" "*.Mask")
			(remove_unused_layers no)
			(net "GND")
			(clearance 0.0508)
			(thermal_gap 0.0508)
		)
		(pad "W5" thru_hole circle
			(at 8.800084 38.999922 180)
			(size 0.906272 0.906272)
			(drill 0.499872)
			(layers "*.Cu" "*.Mask")
			(remove_unused_layers no)
			(net "GND")
			(clearance 0.0508)
			(thermal_gap 0.0508)
		)
		(pad "W7" thru_hole circle
			(at 13.199872 38.999922 180)
			(size 0.906272 0.906272)
			(drill 0.499872)
			(layers "*.Cu" "*.Mask")
			(remove_unused_layers no)
			(net "GND")
			(clearance 0.0508)
			(thermal_gap 0.0508)
		)
		(pad "W9" thru_hole circle
			(at 17.599914 38.999922 180)
			(size 0.906272 0.906272)
			(drill 0.499872)
			(layers "*.Cu" "*.Mask")
			(remove_unused_layers no)
			(net "GND")
			(clearance 0.0508)
			(thermal_gap 0.0508)
		)
		(pad "W10" thru_hole circle
			(at 19.800062 39.200074 180)
			(size 0.71628 0.71628)
			(drill 0.30988)
			(layers "*.Cu" "*.Mask")
			(remove_unused_layers no)
			(net "Net_8749")
			(clearance 0.0508)
			(thermal_gap 0.0508)
		)
		(pad "X9" thru_hole circle
			(at 17.599914 40.299894 180)
			(size 0.71628 0.71628)
			(drill 0.30988)
			(layers "*.Cu" "*.Mask")
			(remove_unused_layers no)
			(net "Net_8747")
			(clearance 0.0508)
			(thermal_gap 0.0508)
		)
		(pad "X10" thru_hole circle
			(at 19.800062 40.500046 180)
			(size 0.71628 0.71628)
			(drill 0.30988)
			(layers "*.Cu" "*.Mask")
			(remove_unused_layers no)
			(net "Net_8748")
			(clearance 0.0508)
			(thermal_gap 0.0508)
		)
		(pad "Y2" thru_hole circle
			(at 2.199894 41.800018 180)
			(size 0.906272 0.906272)
			(drill 0.499872)
			(layers "*.Cu" "*.Mask")
			(remove_unused_layers no)
			(net "GND")
			(clearance 0.0508)
			(thermal_gap 0.0508)
		)
		(pad "Y4" thru_hole circle
			(at 6.599936 41.800018 180)
			(size 0.906272 0.906272)
			(drill 0.499872)
			(layers "*.Cu" "*.Mask")
			(remove_unused_layers no)
			(net "GND")
			(clearance 0.0508)
			(thermal_gap 0.0508)
		)
		(pad "Y6" thru_hole circle
			(at 10.999978 41.800018 180)
			(size 0.906272 0.906272)
			(drill 0.499872)
			(layers "*.Cu" "*.Mask")
			(remove_unused_layers no)
			(net "GND")
			(clearance 0.0508)
			(thermal_gap 0.0508)
		)
		(pad "Y8" thru_hole circle
			(at 15.40002 41.800018 180)
			(size 0.906272 0.906272)
			(drill 0.499872)
			(layers "*.Cu" "*.Mask")
			(remove_unused_layers no)
			(net "GND")
			(clearance 0.0508)
			(thermal_gap 0.0508)
		)
		(pad "Y9" thru_hole circle
			(at 17.599914 41.60012 180)
			(size 0.71628 0.71628)
			(drill 0.30988)
			(layers "*.Cu" "*.Mask")
			(remove_unused_layers no)
			(net "Net_8746")
			(clearance 0.0508)
			(thermal_gap 0.0508)
		)
		(pad "Y10" thru_hole circle
			(at 19.800062 41.800018 180)
			(size 0.906272 0.906272)
			(drill 0.499872)
			(layers "*.Cu" "*.Mask")
			(remove_unused_layers no)
			(net "GND")
			(clearance 0.0508)
			(thermal_gap 0.0508)
		)
		(pad "Z1" thru_hole circle
			(at 0 42.900092 180)
			(size 0.906272 0.906272)
			(drill 0.499872)
			(layers "*.Cu" "*.Mask")
			(remove_unused_layers no)
			(net "GND")
			(clearance 0.0508)
			(thermal_gap 0.0508)
		)
		(pad "Z2" thru_hole circle
			(at 2.199894 43.09999 180)
			(size 0.71628 0.71628)
			(drill 0.30988)
			(layers "*.Cu" "*.Mask")
			(remove_unused_layers no)
			(net "Net_8780")
			(clearance 0.0508)
			(thermal_gap 0.0508)
		)
		(pad "Z3" thru_hole circle
			(at 4.400042 42.900092 180)
			(size 0.906272 0.906272)
			(drill 0.499872)
			(layers "*.Cu" "*.Mask")
			(remove_unused_layers no)
			(net "GND")
			(clearance 0.0508)
			(thermal_gap 0.0508)
		)
		(pad "Z4" thru_hole circle
			(at 6.599936 43.09999 180)
			(size 0.71628 0.71628)
			(drill 0.30988)
			(layers "*.Cu" "*.Mask")
			(remove_unused_layers no)
			(net "Net_8778")
			(clearance 0.0508)
			(thermal_gap 0.0508)
		)
		(pad "Z5" thru_hole circle
			(at 8.800084 42.900092 180)
			(size 0.906272 0.906272)
			(drill 0.499872)
			(layers "*.Cu" "*.Mask")
			(remove_unused_layers no)
			(net "GND")
			(clearance 0.0508)
			(thermal_gap 0.0508)
		)
		(pad "Z6" thru_hole circle
			(at 10.999978 43.09999 180)
			(size 0.71628 0.71628)
			(drill 0.30988)
			(layers "*.Cu" "*.Mask")
			(remove_unused_layers no)
			(net "Net_8776")
			(clearance 0.0508)
			(thermal_gap 0.0508)
		)
		(pad "Z7" thru_hole circle
			(at 13.199872 42.900092 180)
			(size 0.906272 0.906272)
			(drill 0.499872)
			(layers "*.Cu" "*.Mask")
			(remove_unused_layers no)
			(net "GND")
			(clearance 0.0508)
			(thermal_gap 0.0508)
		)
		(pad "Z8" thru_hole circle
			(at 15.40002 43.09999 180)
			(size 0.71628 0.71628)
			(drill 0.30988)
			(layers "*.Cu" "*.Mask")
			(remove_unused_layers no)
			(net "Net_8775")
			(clearance 0.0508)
			(thermal_gap 0.0508)
		)
		(pad "Z9" thru_hole circle
			(at 17.599914 42.900092 180)
			(size 0.906272 0.906272)
			(drill 0.499872)
			(layers "*.Cu" "*.Mask")
			(remove_unused_layers no)
			(net "GND")
			(clearance 0.0508)
			(thermal_gap 0.0508)
		)
		(pad "Z10" thru_hole circle
			(at 19.800062 43.09999 180)
			(size 0.71628 0.71628)
			(drill 0.30988)
			(layers "*.Cu" "*.Mask")
			(remove_unused_layers no)
			(net "Net_8745")
			(clearance 0.0508)
			(thermal_gap 0.0508)
		)
		(zone
			(layer "B.Cu")
			(hatch none 0.5)
			(connect_pads
				(clearance 0)
			)
			(min_thickness 0.25)
			(keepout
				(tracks allowed)
				(vias not_allowed)
				(pads allowed)
				(copperpour not_allowed)
				(footprints allowed)
			)
			(placement
				(enabled no)
				(sheetname "")
			)
			(fill
				(thermal_gap 0.5)
				(thermal_bridge_width 0.5)
				(island_removal_mode 0)
			)
			(polygon
				(pts
					(xy 418.972746 -394.665708) (xy 439.800746 -394.665708) (xy 439.800746 -412.50743) (xy 418.972746 -412.50743)
				)
			)
		)
		(zone
			(layer "B.Cu")
			(hatch none 0.5)
			(connect_pads
				(clearance 0)
			)
			(min_thickness 0.25)
			(keepout
				(tracks allowed)
				(vias not_allowed)
				(pads allowed)
				(copperpour not_allowed)
				(footprints allowed)
			)
			(placement
				(enabled no)
				(sheetname "")
			)
			(fill
				(thermal_gap 0.5)
				(thermal_bridge_width 0.5)
				(island_removal_mode 0)
			)
			(polygon
				(pts
					(xy 418.972746 -368.572796) (xy 439.800746 -368.572796) (xy 439.800746 -386.414518) (xy 418.972746 -386.414518)
				)
			)
		)
	)
	(footprint ""
		(layer "F.Cu")
		(at 388.898384 -252.356874 -90)
		(property "Reference" "R1426"
			(at 0 0 270)
			(layer "F.SilkS")
			(hide yes)
			(effects
				(font
					(size 1.27 1.27)
				)
			)
		)
		(property "Value" ""
			(at 0 0 270)
			(layer "F.Fab")
			(effects
				(font
					(size 1.27 1.27)
				)
			)
		)
		(duplicate_pad_numbers_are_jumpers no)
		(fp_line
			(start -0.7874 0.4064)
			(end -0.7874 -0.4064)
			(stroke
				(width 0.1524)
				(type default)
			)
			(layer "F.SilkS")
		)
		(fp_line
			(start 0.7874 0.4064)
			(end -0.7874 0.4064)
			(stroke
				(width 0.1524)
				(type default)
			)
			(layer "F.SilkS")
		)
		(fp_line
			(start -0.7874 -0.4064)
			(end 0.7874 -0.4064)
			(stroke
				(width 0.1524)
				(type default)
			)
			(layer "F.SilkS")
		)
		(fp_line
			(start 0.7874 -0.4064)
			(end 0.7874 0.4064)
			(stroke
				(width 0.1524)
				(type default)
			)
			(layer "F.SilkS")
		)
		(fp_line
			(start -0.67945 0.3048)
			(end -0.67945 -0.305054)
			(stroke
				(width 0.1)
				(type default)
			)
			(layer "F.Fab")
		)
		(fp_line
			(start -0.12065 0.3048)
			(end -0.67945 0.3048)
			(stroke
				(width 0.1)
				(type default)
			)
			(layer "F.Fab")
		)
		(fp_line
			(start 0.120396 0.3048)
			(end 0.120396 0.2794)
			(stroke
				(width 0.1)
				(type default)
			)
			(layer "F.Fab")
		)
		(fp_line
			(start 0.67945 0.3048)
			(end 0.120396 0.3048)
			(stroke
				(width 0.1)
				(type default)
			)
			(layer "F.Fab")
		)
		(fp_line
			(start -0.12065 0.2794)
			(end -0.12065 0.3048)
			(stroke
				(width 0.1)
				(type default)
			)
			(layer "F.Fab")
		)
		(fp_line
			(start 0.120396 0.2794)
			(end -0.12065 0.2794)
			(stroke
				(width 0.1)
				(type default)
			)
			(layer "F.Fab")
		)
		(fp_line
			(start -0.12065 -0.2794)
			(end 0.12065 -0.2794)
			(stroke
				(width 0.1)
				(type default)
			)
			(layer "F.Fab")
		)
		(fp_line
			(start 0.12065 -0.2794)
			(end 0.12065 -0.3048)
			(stroke
				(width 0.1)
				(type default)
			)
			(layer "F.Fab")
		)
		(fp_line
			(start 0.12065 -0.3048)
			(end 0.67945 -0.3048)
			(stroke
				(width 0.1)
				(type default)
			)
			(layer "F.Fab")
		)
		(fp_line
			(start 0.67945 -0.3048)
			(end 0.67945 0.3048)
			(stroke
				(width 0.1)
				(type default)
			)
			(layer "F.Fab")
		)
		(fp_line
			(start -0.67945 -0.305054)
			(end -0.12065 -0.305054)
			(stroke
				(width 0.1)
				(type default)
			)
			(layer "F.Fab")
		)
		(fp_line
			(start -0.12065 -0.305054)
			(end -0.12065 -0.2794)
			(stroke
				(width 0.1)
				(type default)
			)
			(layer "F.Fab")
		)
		(pad "1" smd circle
			(at -0.40005 0 270)
			(size 0 0)
			(layers "F.Cu" "F.Mask" "F.Paste")
			(net "GND")
		)
		(pad "2" smd circle
			(at 0.40005 0 270)
			(size 0 0)
			(layers "F.Cu" "F.Mask" "F.Paste")
			(net "PEX3_MODE_SEL1")
		)
	)
	(footprint ""
		(layer "F.Cu")
		(at 253.028958 -79.921862)
		(property "Reference" "R1045"
			(at 0 0 0)
			(layer "F.SilkS")
			(hide yes)
			(effects
				(font
					(size 1.27 1.27)
				)
			)
		)
		(property "Value" ""
			(at 0 0 0)
			(layer "F.Fab")
			(effects
				(font
					(size 1.27 1.27)
				)
			)
		)
		(duplicate_pad_numbers_are_jumpers no)
		(fp_line
			(start -0.7874 -0.4064)
			(end 0.7874 -0.4064)
			(stroke
				(width 0.1524)
				(type default)
			)
			(layer "F.SilkS")
		)
		(fp_line
			(start -0.7874 0.4064)
			(end -0.7874 -0.4064)
			(stroke
				(width 0.1524)
				(type default)
			)
			(layer "F.SilkS")
		)
		(fp_line
			(start 0.7874 -0.4064)
			(end 0.7874 0.4064)
			(stroke
				(width 0.1524)
				(type default)
			)
			(layer "F.SilkS")
		)
		(fp_line
			(start 0.7874 0.4064)
			(end -0.7874 0.4064)
			(stroke
				(width 0.1524)
				(type default)
			)
			(layer "F.SilkS")
		)
		(fp_line
			(start -0.67945 -0.305054)
			(end -0.12065 -0.305054)
			(stroke
				(width 0.1)
				(type default)
			)
			(layer "F.Fab")
		)
		(fp_line
			(start -0.67945 0.3048)
			(end -0.67945 -0.305054)
			(stroke
				(width 0.1)
				(type default)
			)
			(layer "F.Fab")
		)
		(fp_line
			(start -0.12065 -0.305054)
			(end -0.12065 -0.2794)
			(stroke
				(width 0.1)
				(type default)
			)
			(layer "F.Fab")
		)
		(fp_line
			(start -0.12065 -0.2794)
			(end 0.12065 -0.2794)
			(stroke
				(width 0.1)
				(type default)
			)
			(layer "F.Fab")
		)
		(fp_line
			(start -0.12065 0.2794)
			(end -0.12065 0.3048)
			(stroke
				(width 0.1)
				(type default)
			)
			(layer "F.Fab")
		)
		(fp_line
			(start -0.12065 0.3048)
			(end -0.67945 0.3048)
			(stroke
				(width 0.1)
				(type default)
			)
			(layer "F.Fab")
		)
		(fp_line
			(start 0.120396 0.2794)
			(end -0.12065 0.2794)
			(stroke
				(width 0.1)
				(type default)
			)
			(layer "F.Fab")
		)
		(fp_line
			(start 0.120396 0.3048)
			(end 0.120396 0.2794)
			(stroke
				(width 0.1)
				(type default)
			)
			(layer "F.Fab")
		)
		(fp_line
			(start 0.12065 -0.3048)
			(end 0.67945 -0.3048)
			(stroke
				(width 0.1)
				(type default)
			)
			(layer "F.Fab")
		)
		(fp_line
			(start 0.12065 -0.2794)
			(end 0.12065 -0.3048)
			(stroke
				(width 0.1)
				(type default)
			)
			(layer "F.Fab")
		)
		(fp_line
			(start 0.67945 -0.3048)
			(end 0.67945 0.3048)
			(stroke
				(width 0.1)
				(type default)
			)
			(layer "F.Fab")
		)
		(fp_line
			(start 0.67945 0.3048)
			(end 0.120396 0.3048)
			(stroke
				(width 0.1)
				(type default)
			)
			(layer "F.Fab")
		)
		(pad "1" smd circle
			(at -0.40005 0)
			(size 0 0)
			(layers "F.Cu" "F.Mask" "F.Paste")
			(net "XTAL_CK440_25M_R_XIN")
		)
		(pad "2" smd circle
			(at 0.40005 0)
			(size 0 0)
			(layers "F.Cu" "F.Mask" "F.Paste")
			(net "XTAL_CK440_25M_XIN")
		)
	)
	(footprint ""
		(layer "F.Cu")
		(at 130.4544 -135.993632 -90)
		(property "Reference" "PC332"
			(at 0 0 270)
			(layer "F.SilkS")
			(hide yes)
			(effects
				(font
					(size 1.27 1.27)
				)
			)
		)
		(property "Value" ""
			(at 0 0 270)
			(layer "F.Fab")
			(effects
				(font
					(size 1.27 1.27)
				)
			)
		)
		(duplicate_pad_numbers_are_jumpers no)
		(fp_line
			(start -0.7874 0.4064)
			(end -0.7874 -0.4064)
			(stroke
				(width 0.1524)
				(type default)
			)
			(layer "F.SilkS")
		)
		(fp_line
			(start 0.7874 0.4064)
			(end -0.7874 0.4064)
			(stroke
				(width 0.1524)
				(type default)
			)
			(layer "F.SilkS")
		)
		(fp_line
			(start -0.7874 -0.4064)
			(end 0.7874 -0.4064)
			(stroke
				(width 0.1524)
				(type default)
			)
			(layer "F.SilkS")
		)
		(fp_line
			(start 0.7874 -0.4064)
			(end 0.7874 0.4064)
			(stroke
				(width 0.1524)
				(type default)
			)
			(layer "F.SilkS")
		)
		(fp_line
			(start -0.67945 0.3048)
			(end -0.67945 -0.305054)
			(stroke
				(width 0.1)
				(type default)
			)
			(layer "F.Fab")
		)
		(fp_line
			(start -0.12065 0.3048)
			(end -0.67945 0.3048)
			(stroke
				(width 0.1)
				(type default)
			)
			(layer "F.Fab")
		)
		(fp_line
			(start 0.120396 0.3048)
			(end 0.120396 0.2794)
			(stroke
				(width 0.1)
				(type default)
			)
			(layer "F.Fab")
		)
		(fp_line
			(start 0.67945 0.3048)
			(end 0.120396 0.3048)
			(stroke
				(width 0.1)
				(type default)
			)
			(layer "F.Fab")
		)
		(fp_line
			(start -0.12065 0.2794)
			(end -0.12065 0.3048)
			(stroke
				(width 0.1)
				(type default)
			)
			(layer "F.Fab")
		)
		(fp_line
			(start 0.120396 0.2794)
			(end -0.12065 0.2794)
			(stroke
				(width 0.1)
				(type default)
			)
			(layer "F.Fab")
		)
		(fp_line
			(start -0.12065 -0.2794)
			(end 0.12065 -0.2794)
			(stroke
				(width 0.1)
				(type default)
			)
			(layer "F.Fab")
		)
		(fp_line
			(start 0.12065 -0.2794)
			(end 0.12065 -0.3048)
			(stroke
				(width 0.1)
				(type default)
			)
			(layer "F.Fab")
		)
		(fp_line
			(start 0.12065 -0.3048)
			(end 0.67945 -0.3048)
			(stroke
				(width 0.1)
				(type default)
			)
			(layer "F.Fab")
		)
		(fp_line
			(start 0.67945 -0.3048)
			(end 0.67945 0.3048)
			(stroke
				(width 0.1)
				(type default)
			)
			(layer "F.Fab")
		)
		(fp_line
			(start -0.67945 -0.305054)
			(end -0.12065 -0.305054)
			(stroke
				(width 0.1)
				(type default)
			)
			(layer "F.Fab")
		)
		(fp_line
			(start -0.12065 -0.305054)
			(end -0.12065 -0.2794)
			(stroke
				(width 0.1)
				(type default)
			)
			(layer "F.Fab")
		)
		(pad "1" smd circle
			(at -0.40005 0 270)
			(size 0 0)
			(layers "F.Cu" "F.Mask" "F.Paste")
			(net "P12V_NIC2_R")
		)
		(pad "2" smd circle
			(at 0.40005 0 270)
			(size 0 0)
			(layers "F.Cu" "F.Mask" "F.Paste")
			(net "GND")
		)
	)
	(footprint ""
		(layer "F.Cu")
		(at 22.10435 -168.682416)
		(property "Reference" "PC16"
			(at 0 0 0)
			(layer "F.SilkS")
			(hide yes)
			(effects
				(font
					(size 1.27 1.27)
				)
			)
		)
		(property "Value" ""
			(at 0 0 0)
			(layer "F.Fab")
			(effects
				(font
					(size 1.27 1.27)
				)
			)
		)
		(duplicate_pad_numbers_are_jumpers no)
		(fp_line
			(start -1.524 -0.762)
			(end 1.524 -0.762)
			(stroke
				(width 0.1524)
				(type default)
			)
			(layer "F.SilkS")
		)
		(fp_line
			(start -1.524 0.762)
			(end -1.524 -0.762)
			(stroke
				(width 0.1524)
				(type default)
			)
			(layer "F.SilkS")
		)
		(fp_line
			(start 1.524 -0.762)
			(end 1.524 0.762)
			(stroke
				(width 0.1524)
				(type default)
			)
			(layer "F.SilkS")
		)
		(fp_line
			(start 1.524 0.762)
			(end -1.524 0.762)
			(stroke
				(width 0.1524)
				(type default)
			)
			(layer "F.SilkS")
		)
		(fp_line
			(start -1.1049 -0.724916)
			(end -1.1049 0.724916)
			(stroke
				(width 0.1)
				(type default)
			)
			(layer "F.Fab")
		)
		(fp_line
			(start -1.1049 0.724916)
			(end 1.1049 0.724916)
			(stroke
				(width 0.1)
				(type default)
			)
			(layer "F.Fab")
		)
		(fp_line
			(start 1.1049 -0.724916)
			(end -1.1049 -0.724916)
			(stroke
				(width 0.1)
				(type default)
			)
			(layer "F.Fab")
		)
		(fp_line
			(start 1.1049 0.724916)
			(end 1.1049 -0.724916)
			(stroke
				(width 0.1)
				(type default)
			)
			(layer "F.Fab")
		)
		(pad "1" smd rect
			(at -0.889 0 180)
			(size 1.016 1.27)
			(layers "F.Cu" "F.Mask" "F.Paste")
			(net "SW_P12V_P5V_AUX_FLT")
		)
		(pad "2" smd rect
			(at 0.889 0 180)
			(size 1.016 1.27)
			(layers "F.Cu" "F.Mask" "F.Paste")
			(net "GND")
		)
	)
	(footprint ""
		(layer "F.Cu")
		(at 119.696484 -271.703546 -90)
		(property "Reference" "PC97"
			(at 0 0 270)
			(layer "F.SilkS")
			(hide yes)
			(effects
				(font
					(size 1.27 1.27)
				)
			)
		)
		(property "Value" ""
			(at 0 0 270)
			(layer "F.Fab")
			(effects
				(font
					(size 1.27 1.27)
				)
			)
		)
		(duplicate_pad_numbers_are_jumpers no)
		(fp_line
			(start -2.146046 3.400044)
			(end -3.400044 2.146046)
			(stroke
				(width 0.1524)
				(type default)
			)
			(layer "F.SilkS")
		)
		(fp_line
			(start 3.400044 3.400044)
			(end -2.146046 3.400044)
			(stroke
				(width 0.1524)
				(type default)
			)
			(layer "F.SilkS")
		)
		(fp_line
			(start -3.400044 2.146046)
			(end -3.400044 0.9398)
			(stroke
				(width 0.1524)
				(type default)
			)
			(layer "F.SilkS")
		)
		(fp_line
			(start 3.400044 0.9398)
			(end 3.400044 3.400044)
			(stroke
				(width 0.1524)
				(type default)
			)
			(layer "F.SilkS")
		)
		(fp_line
			(start 3.400044 -0.9398)
			(end 3.400044 -3.400044)
			(stroke
				(width 0.1524)
				(type default)
			)
			(layer "F.SilkS")
		)
		(fp_line
			(start -3.400044 -2.146046)
			(end -3.400044 -0.9398)
			(stroke
				(width 0.1524)
				(type default)
			)
			(layer "F.SilkS")
		)
		(fp_line
			(start -2.146046 -3.400044)
			(end -3.400044 -2.146046)
			(stroke
				(width 0.1524)
				(type default)
			)
			(layer "F.SilkS")
		)
		(fp_line
			(start 3.400044 -3.400044)
			(end -2.146046 -3.400044)
			(stroke
				(width 0.1524)
				(type default)
			)
			(layer "F.SilkS")
		)
		(fp_line
			(start -3.400044 3.400044)
			(end 3.400044 3.400044)
			(stroke
				(width 0.1)
				(type default)
			)
			(layer "F.Fab")
		)
		(fp_line
			(start 3.400044 3.400044)
			(end 3.400044 -3.400044)
			(stroke
				(width 0.1)
				(type default)
			)
			(layer "F.Fab")
		)
		(fp_line
			(start -3.400044 -3.400044)
			(end -3.400044 3.400044)
			(stroke
				(width 0.1)
				(type default)
			)
			(layer "F.Fab")
		)
		(fp_line
			(start 3.400044 -3.400044)
			(end -3.400044 -3.400044)
			(stroke
				(width 0.1)
				(type default)
			)
			(layer "F.Fab")
		)
		(pad "1" smd rect
			(at -2.70002 0 180)
			(size 1.6002 3.5052)
			(layers "F.Cu" "F.Mask" "F.Paste")
			(net "SW_P12V_P0V8_PEX1_FLT")
		)
		(pad "2" smd rect
			(at 2.70002 0 180)
			(size 1.6002 3.5052)
			(layers "F.Cu" "F.Mask" "F.Paste")
			(net "GND")
		)
	)
	(footprint ""
		(layer "F.Cu")
		(at 330.724764 -204.551534 90)
		(property "Reference" "OSC1"
			(at 1.898396 -4.233164 0)
			(unlocked yes)
			(layer "F.SilkS")
			(effects
				(font
					(size 0.7874 0.5842)
					(thickness 0.1524)
				)
				(justify left)
			)
		)
		(property "Value" ""
			(at 0 0 90)
			(layer "F.Fab")
			(effects
				(font
					(size 1.27 1.27)
				)
			)
		)
		(duplicate_pad_numbers_are_jumpers no)
		(fp_line
			(start 1.299972 -1.599946)
			(end 1.299972 1.599946)
			(stroke
				(width 0.1524)
				(type default)
			)
			(layer "F.SilkS")
		)
		(fp_line
			(start -1.299972 -1.599946)
			(end 1.299972 -1.599946)
			(stroke
				(width 0.1524)
				(type default)
			)
			(layer "F.SilkS")
		)
		(fp_line
			(start 1.299972 1.599946)
			(end -1.299972 1.599946)
			(stroke
				(width 0.1524)
				(type default)
			)
			(layer "F.SilkS")
		)
		(fp_line
			(start -1.299972 1.599946)
			(end -1.299972 -1.599946)
			(stroke
				(width 0.1524)
				(type default)
			)
			(layer "F.SilkS")
		)
		(fp_poly
			(pts
				(xy -1.84912 0.629412) (xy -2.567686 -0.0889) (xy -1.489964 -0.448056)
			)
			(stroke
				(width 0)
				(type default)
			)
			(fill yes)
			(layer "F.SilkS")
		)
		(fp_line
			(start 1.050036 -1.299972)
			(end 1.050036 1.299972)
			(stroke
				(width 0.1)
				(type default)
			)
			(layer "F.Fab")
		)
		(fp_line
			(start -1.050036 -1.299972)
			(end 1.050036 -1.299972)
			(stroke
				(width 0.1)
				(type default)
			)
			(layer "F.Fab")
		)
		(fp_line
			(start 1.050036 1.299972)
			(end -1.050036 1.299972)
			(stroke
				(width 0.1)
				(type default)
			)
			(layer "F.Fab")
		)
		(fp_line
			(start -1.050036 1.299972)
			(end -1.050036 -1.299972)
			(stroke
				(width 0.1)
				(type default)
			)
			(layer "F.Fab")
		)
		(fp_poly
			(pts
				(xy -2.4892 -0.24892) (xy -2.4892 -1.26492) (xy -1.4732 -0.75692)
			)
			(stroke
				(width 0)
				(type default)
			)
			(fill yes)
			(layer "F.Fab")
		)
		(pad "1" smd rect
			(at -0.649986 -0.849884 90)
			(size 1.016 1.2192)
			(layers "F.Cu" "F.Mask" "F.Paste")
			(net "PU_CLK_25M_FPGA_EN")
		)
		(pad "2" smd rect
			(at -0.649986 0.849884 90)
			(size 1.016 1.2192)
			(layers "F.Cu" "F.Mask" "F.Paste")
			(net "GND")
		)
		(pad "3" smd rect
			(at 0.649986 0.849884 90)
			(size 1.016 1.2192)
			(layers "F.Cu" "F.Mask" "F.Paste")
			(net "CLK_25M_FPGA")
		)
		(pad "4" smd rect
			(at 0.649986 -0.849884 90)
			(size 1.016 1.2192)
			(layers "F.Cu" "F.Mask" "F.Paste")
			(net "P3V3_AUX")
		)
	)
	(footprint ""
		(layer "F.Cu")
		(at 46.514512 -66.32194 90)
		(property "Reference" "R5834"
			(at 0 0 90)
			(layer "F.SilkS")
			(hide yes)
			(effects
				(font
					(size 1.27 1.27)
				)
			)
		)
		(property "Value" ""
			(at 0 0 90)
			(layer "F.Fab")
			(effects
				(font
					(size 1.27 1.27)
				)
			)
		)
		(duplicate_pad_numbers_are_jumpers no)
		(fp_line
			(start 0.7874 -0.4064)
			(end 0.7874 0.4064)
			(stroke
				(width 0.1524)
				(type default)
			)
			(layer "F.SilkS")
		)
		(fp_line
			(start -0.7874 -0.4064)
			(end 0.7874 -0.4064)
			(stroke
				(width 0.1524)
				(type default)
			)
			(layer "F.SilkS")
		)
		(fp_line
			(start 0.7874 0.4064)
			(end -0.7874 0.4064)
			(stroke
				(width 0.1524)
				(type default)
			)
			(layer "F.SilkS")
		)
		(fp_line
			(start -0.7874 0.4064)
			(end -0.7874 -0.4064)
			(stroke
				(width 0.1524)
				(type default)
			)
			(layer "F.SilkS")
		)
		(fp_line
			(start -0.12065 -0.305054)
			(end -0.12065 -0.2794)
			(stroke
				(width 0.1)
				(type default)
			)
			(layer "F.Fab")
		)
		(fp_line
			(start -0.67945 -0.305054)
			(end -0.12065 -0.305054)
			(stroke
				(width 0.1)
				(type default)
			)
			(layer "F.Fab")
		)
		(fp_line
			(start 0.67945 -0.3048)
			(end 0.67945 0.3048)
			(stroke
				(width 0.1)
				(type default)
			)
			(layer "F.Fab")
		)
		(fp_line
			(start 0.12065 -0.3048)
			(end 0.67945 -0.3048)
			(stroke
				(width 0.1)
				(type default)
			)
			(layer "F.Fab")
		)
		(fp_line
			(start 0.12065 -0.2794)
			(end 0.12065 -0.3048)
			(stroke
				(width 0.1)
				(type default)
			)
			(layer "F.Fab")
		)
		(fp_line
			(start -0.12065 -0.2794)
			(end 0.12065 -0.2794)
			(stroke
				(width 0.1)
				(type default)
			)
			(layer "F.Fab")
		)
		(fp_line
			(start 0.120396 0.2794)
			(end -0.12065 0.2794)
			(stroke
				(width 0.1)
				(type default)
			)
			(layer "F.Fab")
		)
		(fp_line
			(start -0.12065 0.2794)
			(end -0.12065 0.3048)
			(stroke
				(width 0.1)
				(type default)
			)
			(layer "F.Fab")
		)
		(fp_line
			(start 0.67945 0.3048)
			(end 0.120396 0.3048)
			(stroke
				(width 0.1)
				(type default)
			)
			(layer "F.Fab")
		)
		(fp_line
			(start 0.120396 0.3048)
			(end 0.120396 0.2794)
			(stroke
				(width 0.1)
				(type default)
			)
			(layer "F.Fab")
		)
		(fp_line
			(start -0.12065 0.3048)
			(end -0.67945 0.3048)
			(stroke
				(width 0.1)
				(type default)
			)
			(layer "F.Fab")
		)
		(fp_line
			(start -0.67945 0.3048)
			(end -0.67945 -0.305054)
			(stroke
				(width 0.1)
				(type default)
			)
			(layer "F.Fab")
		)
		(pad "1" smd circle
			(at -0.40005 0 90)
			(size 0 0)
			(layers "F.Cu" "F.Mask" "F.Paste")
			(net "SSD1_PWR_EN_R")
		)
		(pad "2" smd circle
			(at 0.40005 0 90)
			(size 0 0)
			(layers "F.Cu" "F.Mask" "F.Paste")
			(net "P12V_SSD1_CO_EN")
		)
	)
	(footprint ""
		(layer "F.Cu")
		(at 252.634496 -30.94609 180)
		(property "Reference" "C491"
			(at 0 0 180)
			(layer "F.SilkS")
			(hide yes)
			(effects
				(font
					(size 1.27 1.27)
				)
			)
		)
		(property "Value" ""
			(at 0 0 180)
			(layer "F.Fab")
			(effects
				(font
					(size 1.27 1.27)
				)
			)
		)
		(duplicate_pad_numbers_are_jumpers no)
		(fp_line
			(start 0.299974 0.150114)
			(end -0.299974 0.150114)
			(stroke
				(width 0.1)
				(type default)
			)
			(layer "F.Fab")
		)
		(fp_line
			(start 0.299974 -0.150114)
			(end 0.299974 0.150114)
			(stroke
				(width 0.1)
				(type default)
			)
			(layer "F.Fab")
		)
		(fp_line
			(start -0.299974 0.150114)
			(end -0.299974 -0.150114)
			(stroke
				(width 0.1)
				(type default)
			)
			(layer "F.Fab")
		)
		(fp_line
			(start -0.299974 -0.150114)
			(end 0.299974 -0.150114)
			(stroke
				(width 0.1)
				(type default)
			)
			(layer "F.Fab")
		)
		(pad "1" smd rect
			(at -0.2667 0 180)
			(size 0.3048 0.381)
			(layers "F.Cu" "F.Mask" "F.Paste")
			(net "P5E_PEX2_STN2_TX_DP<45>")
		)
		(pad "2" smd rect
			(at 0.2667 0 180)
			(size 0.3048 0.381)
			(layers "F.Cu" "F.Mask" "F.Paste")
			(net "P5E_PEX2_STN2_TX_C_DP<45>")
		)
	)
	(footprint ""
		(layer "F.Cu")
		(at 87.73795 -291.102034 180)
		(property "Reference" "R6389"
			(at 0 0 180)
			(layer "F.SilkS")
			(hide yes)
			(effects
				(font
					(size 1.27 1.27)
				)
			)
		)
		(property "Value" ""
			(at 0 0 180)
			(layer "F.Fab")
			(effects
				(font
					(size 1.27 1.27)
				)
			)
		)
		(duplicate_pad_numbers_are_jumpers no)
		(fp_line
			(start 0.7874 0.4064)
			(end -0.7874 0.4064)
			(stroke
				(width 0.1524)
				(type default)
			)
			(layer "F.SilkS")
		)
		(fp_line
			(start 0.7874 -0.4064)
			(end 0.7874 0.4064)
			(stroke
				(width 0.1524)
				(type default)
			)
			(layer "F.SilkS")
		)
		(fp_line
			(start -0.7874 0.4064)
			(end -0.7874 -0.4064)
			(stroke
				(width 0.1524)
				(type default)
			)
			(layer "F.SilkS")
		)
		(fp_line
			(start -0.7874 -0.4064)
			(end 0.7874 -0.4064)
			(stroke
				(width 0.1524)
				(type default)
			)
			(layer "F.SilkS")
		)
		(fp_line
			(start 0.67945 0.3048)
			(end 0.120396 0.3048)
			(stroke
				(width 0.1)
				(type default)
			)
			(layer "F.Fab")
		)
		(fp_line
			(start 0.67945 -0.3048)
			(end 0.67945 0.3048)
			(stroke
				(width 0.1)
				(type default)
			)
			(layer "F.Fab")
		)
		(fp_line
			(start 0.12065 -0.2794)
			(end 0.12065 -0.3048)
			(stroke
				(width 0.1)
				(type default)
			)
			(layer "F.Fab")
		)
		(fp_line
			(start 0.12065 -0.3048)
			(end 0.67945 -0.3048)
			(stroke
				(width 0.1)
				(type default)
			)
			(layer "F.Fab")
		)
		(fp_line
			(start 0.120396 0.3048)
			(end 0.120396 0.2794)
			(stroke
				(width 0.1)
				(type default)
			)
			(layer "F.Fab")
		)
		(fp_line
			(start 0.120396 0.2794)
			(end -0.12065 0.2794)
			(stroke
				(width 0.1)
				(type default)
			)
			(layer "F.Fab")
		)
		(fp_line
			(start -0.12065 0.3048)
			(end -0.67945 0.3048)
			(stroke
				(width 0.1)
				(type default)
			)
			(layer "F.Fab")
		)
		(fp_line
			(start -0.12065 0.2794)
			(end -0.12065 0.3048)
			(stroke
				(width 0.1)
				(type default)
			)
			(layer "F.Fab")
		)
		(fp_line
			(start -0.12065 -0.2794)
			(end 0.12065 -0.2794)
			(stroke
				(width 0.1)
				(type default)
			)
			(layer "F.Fab")
		)
		(fp_line
			(start -0.12065 -0.305054)
			(end -0.12065 -0.2794)
			(stroke
				(width 0.1)
				(type default)
			)
			(layer "F.Fab")
		)
		(fp_line
			(start -0.67945 0.3048)
			(end -0.67945 -0.305054)
			(stroke
				(width 0.1)
				(type default)
			)
			(layer "F.Fab")
		)
		(fp_line
			(start -0.67945 -0.305054)
			(end -0.12065 -0.305054)
			(stroke
				(width 0.1)
				(type default)
			)
			(layer "F.Fab")
		)
		(pad "1" smd circle
			(at -0.40005 0 180)
			(size 0 0)
			(layers "F.Cu" "F.Mask" "F.Paste")
			(net "GND")
		)
		(pad "2" smd circle
			(at 0.40005 0 180)
			(size 0 0)
			(layers "F.Cu" "F.Mask" "F.Paste")
			(net "RST_PEX0_PERST_R_N")
		)
	)
	(footprint ""
		(layer "F.Cu")
		(at 213.754716 -22.867366 90)
		(property "Reference" "C3923"
			(at 0 0 90)
			(layer "F.SilkS")
			(hide yes)
			(effects
				(font
					(size 1.27 1.27)
				)
			)
		)
		(property "Value" ""
			(at 0 0 90)
			(layer "F.Fab")
			(effects
				(font
					(size 1.27 1.27)
				)
			)
		)
		(duplicate_pad_numbers_are_jumpers no)
		(fp_line
			(start 0.7874 -0.4064)
			(end 0.7874 0.4064)
			(stroke
				(width 0.1524)
				(type default)
			)
			(layer "F.SilkS")
		)
		(fp_line
			(start -0.7874 -0.4064)
			(end 0.7874 -0.4064)
			(stroke
				(width 0.1524)
				(type default)
			)
			(layer "F.SilkS")
		)
		(fp_line
			(start 0.7874 0.4064)
			(end -0.7874 0.4064)
			(stroke
				(width 0.1524)
				(type default)
			)
			(layer "F.SilkS")
		)
		(fp_line
			(start -0.7874 0.4064)
			(end -0.7874 -0.4064)
			(stroke
				(width 0.1524)
				(type default)
			)
			(layer "F.SilkS")
		)
		(fp_line
			(start -0.12065 -0.305054)
			(end -0.12065 -0.2794)
			(stroke
				(width 0.1)
				(type default)
			)
			(layer "F.Fab")
		)
		(fp_line
			(start -0.67945 -0.305054)
			(end -0.12065 -0.305054)
			(stroke
				(width 0.1)
				(type default)
			)
			(layer "F.Fab")
		)
		(fp_line
			(start 0.67945 -0.3048)
			(end 0.67945 0.3048)
			(stroke
				(width 0.1)
				(type default)
			)
			(layer "F.Fab")
		)
		(fp_line
			(start 0.12065 -0.3048)
			(end 0.67945 -0.3048)
			(stroke
				(width 0.1)
				(type default)
			)
			(layer "F.Fab")
		)
		(fp_line
			(start 0.12065 -0.2794)
			(end 0.12065 -0.3048)
			(stroke
				(width 0.1)
				(type default)
			)
			(layer "F.Fab")
		)
		(fp_line
			(start -0.12065 -0.2794)
			(end 0.12065 -0.2794)
			(stroke
				(width 0.1)
				(type default)
			)
			(layer "F.Fab")
		)
		(fp_line
			(start 0.120396 0.2794)
			(end -0.12065 0.2794)
			(stroke
				(width 0.1)
				(type default)
			)
			(layer "F.Fab")
		)
		(fp_line
			(start -0.12065 0.2794)
			(end -0.12065 0.3048)
			(stroke
				(width 0.1)
				(type default)
			)
			(layer "F.Fab")
		)
		(fp_line
			(start 0.67945 0.3048)
			(end 0.120396 0.3048)
			(stroke
				(width 0.1)
				(type default)
			)
			(layer "F.Fab")
		)
		(fp_line
			(start 0.120396 0.3048)
			(end 0.120396 0.2794)
			(stroke
				(width 0.1)
				(type default)
			)
			(layer "F.Fab")
		)
		(fp_line
			(start -0.12065 0.3048)
			(end -0.67945 0.3048)
			(stroke
				(width 0.1)
				(type default)
			)
			(layer "F.Fab")
		)
		(fp_line
			(start -0.67945 0.3048)
			(end -0.67945 -0.305054)
			(stroke
				(width 0.1)
				(type default)
			)
			(layer "F.Fab")
		)
		(pad "1" smd circle
			(at -0.40005 0 90)
			(size 0 0)
			(layers "F.Cu" "F.Mask" "F.Paste")
			(net "P12V_SSD7")
		)
		(pad "2" smd circle
			(at 0.40005 0 90)
			(size 0 0)
			(layers "F.Cu" "F.Mask" "F.Paste")
			(net "GND")
		)
	)
	(footprint ""
		(layer "F.Cu")
		(at 121.13514 -97.177606)
		(property "Reference" "R1551"
			(at 0 0 0)
			(layer "F.SilkS")
			(hide yes)
			(effects
				(font
					(size 1.27 1.27)
				)
			)
		)
		(property "Value" ""
			(at 0 0 0)
			(layer "F.Fab")
			(effects
				(font
					(size 1.27 1.27)
				)
			)
		)
		(duplicate_pad_numbers_are_jumpers no)
		(fp_line
			(start -0.7874 -0.4064)
			(end 0.7874 -0.4064)
			(stroke
				(width 0.1524)
				(type default)
			)
			(layer "F.SilkS")
		)
		(fp_line
			(start -0.7874 0.4064)
			(end -0.7874 -0.4064)
			(stroke
				(width 0.1524)
				(type default)
			)
			(layer "F.SilkS")
		)
		(fp_line
			(start 0.7874 -0.4064)
			(end 0.7874 0.4064)
			(stroke
				(width 0.1524)
				(type default)
			)
			(layer "F.SilkS")
		)
		(fp_line
			(start 0.7874 0.4064)
			(end -0.7874 0.4064)
			(stroke
				(width 0.1524)
				(type default)
			)
			(layer "F.SilkS")
		)
		(fp_line
			(start -0.67945 -0.305054)
			(end -0.12065 -0.305054)
			(stroke
				(width 0.1)
				(type default)
			)
			(layer "F.Fab")
		)
		(fp_line
			(start -0.67945 0.3048)
			(end -0.67945 -0.305054)
			(stroke
				(width 0.1)
				(type default)
			)
			(layer "F.Fab")
		)
		(fp_line
			(start -0.12065 -0.305054)
			(end -0.12065 -0.2794)
			(stroke
				(width 0.1)
				(type default)
			)
			(layer "F.Fab")
		)
		(fp_line
			(start -0.12065 -0.2794)
			(end 0.12065 -0.2794)
			(stroke
				(width 0.1)
				(type default)
			)
			(layer "F.Fab")
		)
		(fp_line
			(start -0.12065 0.2794)
			(end -0.12065 0.3048)
			(stroke
				(width 0.1)
				(type default)
			)
			(layer "F.Fab")
		)
		(fp_line
			(start -0.12065 0.3048)
			(end -0.67945 0.3048)
			(stroke
				(width 0.1)
				(type default)
			)
			(layer "F.Fab")
		)
		(fp_line
			(start 0.120396 0.2794)
			(end -0.12065 0.2794)
			(stroke
				(width 0.1)
				(type default)
			)
			(layer "F.Fab")
		)
		(fp_line
			(start 0.120396 0.3048)
			(end 0.120396 0.2794)
			(stroke
				(width 0.1)
				(type default)
			)
			(layer "F.Fab")
		)
		(fp_line
			(start 0.12065 -0.3048)
			(end 0.67945 -0.3048)
			(stroke
				(width 0.1)
				(type default)
			)
			(layer "F.Fab")
		)
		(fp_line
			(start 0.12065 -0.2794)
			(end 0.12065 -0.3048)
			(stroke
				(width 0.1)
				(type default)
			)
			(layer "F.Fab")
		)
		(fp_line
			(start 0.67945 -0.3048)
			(end 0.67945 0.3048)
			(stroke
				(width 0.1)
				(type default)
			)
			(layer "F.Fab")
		)
		(fp_line
			(start 0.67945 0.3048)
			(end 0.120396 0.3048)
			(stroke
				(width 0.1)
				(type default)
			)
			(layer "F.Fab")
		)
		(pad "1" smd circle
			(at -0.40005 0)
			(size 0 0)
			(layers "F.Cu" "F.Mask" "F.Paste")
			(net "P3V3_AUX")
		)
		(pad "2" smd circle
			(at 0.40005 0)
			(size 0 0)
			(layers "F.Cu" "F.Mask" "F.Paste")
			(net "SMB_BIC_I2C9_MUX0_SSD0_R_SDA")
		)
	)
	(footprint ""
		(layer "F.Cu")
		(at 228.953568 -306.386992 -90)
		(property "Reference" "PC241"
			(at 0 0 270)
			(layer "F.SilkS")
			(hide yes)
			(effects
				(font
					(size 1.27 1.27)
				)
			)
		)
		(property "Value" ""
			(at 0 0 270)
			(layer "F.Fab")
			(effects
				(font
					(size 1.27 1.27)
				)
			)
		)
		(duplicate_pad_numbers_are_jumpers no)
		(fp_line
			(start -0.7874 0.4064)
			(end -0.7874 -0.4064)
			(stroke
				(width 0.1524)
				(type default)
			)
			(layer "F.SilkS")
		)
		(fp_line
			(start 0.7874 0.4064)
			(end -0.7874 0.4064)
			(stroke
				(width 0.1524)
				(type default)
			)
			(layer "F.SilkS")
		)
		(fp_line
			(start -0.7874 -0.4064)
			(end 0.7874 -0.4064)
			(stroke
				(width 0.1524)
				(type default)
			)
			(layer "F.SilkS")
		)
		(fp_line
			(start 0.7874 -0.4064)
			(end 0.7874 0.4064)
			(stroke
				(width 0.1524)
				(type default)
			)
			(layer "F.SilkS")
		)
		(fp_line
			(start -0.67945 0.3048)
			(end -0.67945 -0.305054)
			(stroke
				(width 0.1)
				(type default)
			)
			(layer "F.Fab")
		)
		(fp_line
			(start -0.12065 0.3048)
			(end -0.67945 0.3048)
			(stroke
				(width 0.1)
				(type default)
			)
			(layer "F.Fab")
		)
		(fp_line
			(start 0.120396 0.3048)
			(end 0.120396 0.2794)
			(stroke
				(width 0.1)
				(type default)
			)
			(layer "F.Fab")
		)
		(fp_line
			(start 0.67945 0.3048)
			(end 0.120396 0.3048)
			(stroke
				(width 0.1)
				(type default)
			)
			(layer "F.Fab")
		)
		(fp_line
			(start -0.12065 0.2794)
			(end -0.12065 0.3048)
			(stroke
				(width 0.1)
				(type default)
			)
			(layer "F.Fab")
		)
		(fp_line
			(start 0.120396 0.2794)
			(end -0.12065 0.2794)
			(stroke
				(width 0.1)
				(type default)
			)
			(layer "F.Fab")
		)
		(fp_line
			(start -0.12065 -0.2794)
			(end 0.12065 -0.2794)
			(stroke
				(width 0.1)
				(type default)
			)
			(layer "F.Fab")
		)
		(fp_line
			(start 0.12065 -0.2794)
			(end 0.12065 -0.3048)
			(stroke
				(width 0.1)
				(type default)
			)
			(layer "F.Fab")
		)
		(fp_line
			(start 0.12065 -0.3048)
			(end 0.67945 -0.3048)
			(stroke
				(width 0.1)
				(type default)
			)
			(layer "F.Fab")
		)
		(fp_line
			(start 0.67945 -0.3048)
			(end 0.67945 0.3048)
			(stroke
				(width 0.1)
				(type default)
			)
			(layer "F.Fab")
		)
		(fp_line
			(start -0.67945 -0.305054)
			(end -0.12065 -0.305054)
			(stroke
				(width 0.1)
				(type default)
			)
			(layer "F.Fab")
		)
		(fp_line
			(start -0.12065 -0.305054)
			(end -0.12065 -0.2794)
			(stroke
				(width 0.1)
				(type default)
			)
			(layer "F.Fab")
		)
		(pad "1" smd circle
			(at -0.40005 0 270)
			(size 0 0)
			(layers "F.Cu" "F.Mask" "F.Paste")
			(net "P1V25_PEX1_REF")
		)
		(pad "2" smd circle
			(at 0.40005 0 270)
			(size 0 0)
			(layers "F.Cu" "F.Mask" "F.Paste")
			(net "GND")
		)
	)
	(footprint ""
		(layer "F.Cu")
		(at 457.555092 -375.090182)
		(property "Reference" "R6684"
			(at 0 0 0)
			(layer "F.SilkS")
			(hide yes)
			(effects
				(font
					(size 1.27 1.27)
				)
			)
		)
		(property "Value" ""
			(at 0 0 0)
			(layer "F.Fab")
			(effects
				(font
					(size 1.27 1.27)
				)
			)
		)
		(duplicate_pad_numbers_are_jumpers no)
		(fp_line
			(start -0.7874 -0.4064)
			(end 0.7874 -0.4064)
			(stroke
				(width 0.1524)
				(type default)
			)
			(layer "F.SilkS")
		)
		(fp_line
			(start -0.7874 0.4064)
			(end -0.7874 -0.4064)
			(stroke
				(width 0.1524)
				(type default)
			)
			(layer "F.SilkS")
		)
		(fp_line
			(start 0.7874 -0.4064)
			(end 0.7874 0.4064)
			(stroke
				(width 0.1524)
				(type default)
			)
			(layer "F.SilkS")
		)
		(fp_line
			(start 0.7874 0.4064)
			(end -0.7874 0.4064)
			(stroke
				(width 0.1524)
				(type default)
			)
			(layer "F.SilkS")
		)
		(fp_line
			(start -0.67945 -0.305054)
			(end -0.12065 -0.305054)
			(stroke
				(width 0.1)
				(type default)
			)
			(layer "F.Fab")
		)
		(fp_line
			(start -0.67945 0.3048)
			(end -0.67945 -0.305054)
			(stroke
				(width 0.1)
				(type default)
			)
			(layer "F.Fab")
		)
		(fp_line
			(start -0.12065 -0.305054)
			(end -0.12065 -0.2794)
			(stroke
				(width 0.1)
				(type default)
			)
			(layer "F.Fab")
		)
		(fp_line
			(start -0.12065 -0.2794)
			(end 0.12065 -0.2794)
			(stroke
				(width 0.1)
				(type default)
			)
			(layer "F.Fab")
		)
		(fp_line
			(start -0.12065 0.2794)
			(end -0.12065 0.3048)
			(stroke
				(width 0.1)
				(type default)
			)
			(layer "F.Fab")
		)
		(fp_line
			(start -0.12065 0.3048)
			(end -0.67945 0.3048)
			(stroke
				(width 0.1)
				(type default)
			)
			(layer "F.Fab")
		)
		(fp_line
			(start 0.120396 0.2794)
			(end -0.12065 0.2794)
			(stroke
				(width 0.1)
				(type default)
			)
			(layer "F.Fab")
		)
		(fp_line
			(start 0.120396 0.3048)
			(end 0.120396 0.2794)
			(stroke
				(width 0.1)
				(type default)
			)
			(layer "F.Fab")
		)
		(fp_line
			(start 0.12065 -0.3048)
			(end 0.67945 -0.3048)
			(stroke
				(width 0.1)
				(type default)
			)
			(layer "F.Fab")
		)
		(fp_line
			(start 0.12065 -0.2794)
			(end 0.12065 -0.3048)
			(stroke
				(width 0.1)
				(type default)
			)
			(layer "F.Fab")
		)
		(fp_line
			(start 0.67945 -0.3048)
			(end 0.67945 0.3048)
			(stroke
				(width 0.1)
				(type default)
			)
			(layer "F.Fab")
		)
		(fp_line
			(start 0.67945 0.3048)
			(end 0.120396 0.3048)
			(stroke
				(width 0.1)
				(type default)
			)
			(layer "F.Fab")
		)
		(pad "1" smd circle
			(at -0.40005 0)
			(size 0 0)
			(layers "F.Cu" "F.Mask" "F.Paste")
			(net "GPU_3V3IO_RSVD3_N")
		)
		(pad "2" smd circle
			(at 0.40005 0)
			(size 0 0)
			(layers "F.Cu" "F.Mask" "F.Paste")
			(net "P3V3_AUX")
		)
	)
	(footprint ""
		(layer "F.Cu")
		(at 282.681934 -37.025072)
		(property "Reference" "R5693"
			(at 0 0 0)
			(layer "F.SilkS")
			(hide yes)
			(effects
				(font
					(size 1.27 1.27)
				)
			)
		)
		(property "Value" ""
			(at 0 0 0)
			(layer "F.Fab")
			(effects
				(font
					(size 1.27 1.27)
				)
			)
		)
		(duplicate_pad_numbers_are_jumpers no)
		(fp_line
			(start -0.7874 -0.4064)
			(end 0.7874 -0.4064)
			(stroke
				(width 0.1524)
				(type default)
			)
			(layer "F.SilkS")
		)
		(fp_line
			(start -0.7874 0.4064)
			(end -0.7874 -0.4064)
			(stroke
				(width 0.1524)
				(type default)
			)
			(layer "F.SilkS")
		)
		(fp_line
			(start 0.7874 -0.4064)
			(end 0.7874 0.4064)
			(stroke
				(width 0.1524)
				(type default)
			)
			(layer "F.SilkS")
		)
		(fp_line
			(start 0.7874 0.4064)
			(end -0.7874 0.4064)
			(stroke
				(width 0.1524)
				(type default)
			)
			(layer "F.SilkS")
		)
		(fp_line
			(start -0.67945 -0.305054)
			(end -0.12065 -0.305054)
			(stroke
				(width 0.1)
				(type default)
			)
			(layer "F.Fab")
		)
		(fp_line
			(start -0.67945 0.3048)
			(end -0.67945 -0.305054)
			(stroke
				(width 0.1)
				(type default)
			)
			(layer "F.Fab")
		)
		(fp_line
			(start -0.12065 -0.305054)
			(end -0.12065 -0.2794)
			(stroke
				(width 0.1)
				(type default)
			)
			(layer "F.Fab")
		)
		(fp_line
			(start -0.12065 -0.2794)
			(end 0.12065 -0.2794)
			(stroke
				(width 0.1)
				(type default)
			)
			(layer "F.Fab")
		)
		(fp_line
			(start -0.12065 0.2794)
			(end -0.12065 0.3048)
			(stroke
				(width 0.1)
				(type default)
			)
			(layer "F.Fab")
		)
		(fp_line
			(start -0.12065 0.3048)
			(end -0.67945 0.3048)
			(stroke
				(width 0.1)
				(type default)
			)
			(layer "F.Fab")
		)
		(fp_line
			(start 0.120396 0.2794)
			(end -0.12065 0.2794)
			(stroke
				(width 0.1)
				(type default)
			)
			(layer "F.Fab")
		)
		(fp_line
			(start 0.120396 0.3048)
			(end 0.120396 0.2794)
			(stroke
				(width 0.1)
				(type default)
			)
			(layer "F.Fab")
		)
		(fp_line
			(start 0.12065 -0.3048)
			(end 0.67945 -0.3048)
			(stroke
				(width 0.1)
				(type default)
			)
			(layer "F.Fab")
		)
		(fp_line
			(start 0.12065 -0.2794)
			(end 0.12065 -0.3048)
			(stroke
				(width 0.1)
				(type default)
			)
			(layer "F.Fab")
		)
		(fp_line
			(start 0.67945 -0.3048)
			(end 0.67945 0.3048)
			(stroke
				(width 0.1)
				(type default)
			)
			(layer "F.Fab")
		)
		(fp_line
			(start 0.67945 0.3048)
			(end 0.120396 0.3048)
			(stroke
				(width 0.1)
				(type default)
			)
			(layer "F.Fab")
		)
		(pad "1" smd circle
			(at -0.40005 0)
			(size 0 0)
			(layers "F.Cu" "F.Mask" "F.Paste")
			(net "RST_SMB_SSD_R_N")
		)
		(pad "2" smd circle
			(at 0.40005 0)
			(size 0 0)
			(layers "F.Cu" "F.Mask" "F.Paste")
			(net "RST_SMB_SSD10_N")
		)
	)
	(footprint ""
		(layer "F.Cu")
		(at 22.263608 -146.592798 -90)
		(property "Reference" "R689"
			(at 0 0 270)
			(layer "F.SilkS")
			(hide yes)
			(effects
				(font
					(size 1.27 1.27)
				)
			)
		)
		(property "Value" ""
			(at 0 0 270)
			(layer "F.Fab")
			(effects
				(font
					(size 1.27 1.27)
				)
			)
		)
		(duplicate_pad_numbers_are_jumpers no)
		(fp_line
			(start -0.7874 0.4064)
			(end -0.7874 -0.4064)
			(stroke
				(width 0.1524)
				(type default)
			)
			(layer "F.SilkS")
		)
		(fp_line
			(start 0.7874 0.4064)
			(end -0.7874 0.4064)
			(stroke
				(width 0.1524)
				(type default)
			)
			(layer "F.SilkS")
		)
		(fp_line
			(start -0.7874 -0.4064)
			(end 0.7874 -0.4064)
			(stroke
				(width 0.1524)
				(type default)
			)
			(layer "F.SilkS")
		)
		(fp_line
			(start 0.7874 -0.4064)
			(end 0.7874 0.4064)
			(stroke
				(width 0.1524)
				(type default)
			)
			(layer "F.SilkS")
		)
		(fp_line
			(start -0.67945 0.3048)
			(end -0.67945 -0.305054)
			(stroke
				(width 0.1)
				(type default)
			)
			(layer "F.Fab")
		)
		(fp_line
			(start -0.12065 0.3048)
			(end -0.67945 0.3048)
			(stroke
				(width 0.1)
				(type default)
			)
			(layer "F.Fab")
		)
		(fp_line
			(start 0.120396 0.3048)
			(end 0.120396 0.2794)
			(stroke
				(width 0.1)
				(type default)
			)
			(layer "F.Fab")
		)
		(fp_line
			(start 0.67945 0.3048)
			(end 0.120396 0.3048)
			(stroke
				(width 0.1)
				(type default)
			)
			(layer "F.Fab")
		)
		(fp_line
			(start -0.12065 0.2794)
			(end -0.12065 0.3048)
			(stroke
				(width 0.1)
				(type default)
			)
			(layer "F.Fab")
		)
		(fp_line
			(start 0.120396 0.2794)
			(end -0.12065 0.2794)
			(stroke
				(width 0.1)
				(type default)
			)
			(layer "F.Fab")
		)
		(fp_line
			(start -0.12065 -0.2794)
			(end 0.12065 -0.2794)
			(stroke
				(width 0.1)
				(type default)
			)
			(layer "F.Fab")
		)
		(fp_line
			(start 0.12065 -0.2794)
			(end 0.12065 -0.3048)
			(stroke
				(width 0.1)
				(type default)
			)
			(layer "F.Fab")
		)
		(fp_line
			(start 0.12065 -0.3048)
			(end 0.67945 -0.3048)
			(stroke
				(width 0.1)
				(type default)
			)
			(layer "F.Fab")
		)
		(fp_line
			(start 0.67945 -0.3048)
			(end 0.67945 0.3048)
			(stroke
				(width 0.1)
				(type default)
			)
			(layer "F.Fab")
		)
		(fp_line
			(start -0.67945 -0.305054)
			(end -0.12065 -0.305054)
			(stroke
				(width 0.1)
				(type default)
			)
			(layer "F.Fab")
		)
		(fp_line
			(start -0.12065 -0.305054)
			(end -0.12065 -0.2794)
			(stroke
				(width 0.1)
				(type default)
			)
			(layer "F.Fab")
		)
		(pad "1" smd circle
			(at -0.40005 0 270)
			(size 0 0)
			(layers "F.Cu" "F.Mask" "F.Paste")
			(net "P12V_NIC0_R")
		)
		(pad "2" smd circle
			(at 0.40005 0 270)
			(size 0 0)
			(layers "F.Cu" "F.Mask" "F.Paste")
			(net "P12V_NIC0_VIN_P")
		)
	)
	(footprint ""
		(layer "F.Cu")
		(at 314.861448 -121.391172 180)
		(property "Reference" "C451"
			(at 0 0 180)
			(layer "F.SilkS")
			(hide yes)
			(effects
				(font
					(size 1.27 1.27)
				)
			)
		)
		(property "Value" ""
			(at 0 0 180)
			(layer "F.Fab")
			(effects
				(font
					(size 1.27 1.27)
				)
			)
		)
		(duplicate_pad_numbers_are_jumpers no)
		(fp_line
			(start 0.299974 0.150114)
			(end -0.299974 0.150114)
			(stroke
				(width 0.1)
				(type default)
			)
			(layer "F.Fab")
		)
		(fp_line
			(start 0.299974 -0.150114)
			(end 0.299974 0.150114)
			(stroke
				(width 0.1)
				(type default)
			)
			(layer "F.Fab")
		)
		(fp_line
			(start -0.299974 0.150114)
			(end -0.299974 -0.150114)
			(stroke
				(width 0.1)
				(type default)
			)
			(layer "F.Fab")
		)
		(fp_line
			(start -0.299974 -0.150114)
			(end 0.299974 -0.150114)
			(stroke
				(width 0.1)
				(type default)
			)
			(layer "F.Fab")
		)
		(pad "1" smd rect
			(at -0.2667 0 180)
			(size 0.3048 0.381)
			(layers "F.Cu" "F.Mask" "F.Paste")
			(net "P5E_PEX2_STN0_TX_DP<1>")
		)
		(pad "2" smd rect
			(at 0.2667 0 180)
			(size 0.3048 0.381)
			(layers "F.Cu" "F.Mask" "F.Paste")
			(net "P5E_PEX2_STN0_TX_C_DP<1>")
		)
	)
	(footprint ""
		(layer "F.Cu")
		(at 441.297822 -296.365168 90)
		(property "Reference" "C2761"
			(at 0 0 90)
			(layer "F.SilkS")
			(hide yes)
			(effects
				(font
					(size 1.27 1.27)
				)
			)
		)
		(property "Value" ""
			(at 0 0 90)
			(layer "F.Fab")
			(effects
				(font
					(size 1.27 1.27)
				)
			)
		)
		(duplicate_pad_numbers_are_jumpers no)
		(fp_line
			(start 0.7874 -0.4064)
			(end 0.7874 0.4064)
			(stroke
				(width 0.1524)
				(type default)
			)
			(layer "F.SilkS")
		)
		(fp_line
			(start -0.7874 -0.4064)
			(end 0.7874 -0.4064)
			(stroke
				(width 0.1524)
				(type default)
			)
			(layer "F.SilkS")
		)
		(fp_line
			(start 0.7874 0.4064)
			(end -0.7874 0.4064)
			(stroke
				(width 0.1524)
				(type default)
			)
			(layer "F.SilkS")
		)
		(fp_line
			(start -0.7874 0.4064)
			(end -0.7874 -0.4064)
			(stroke
				(width 0.1524)
				(type default)
			)
			(layer "F.SilkS")
		)
		(fp_line
			(start -0.12065 -0.305054)
			(end -0.12065 -0.2794)
			(stroke
				(width 0.1)
				(type default)
			)
			(layer "F.Fab")
		)
		(fp_line
			(start -0.67945 -0.305054)
			(end -0.12065 -0.305054)
			(stroke
				(width 0.1)
				(type default)
			)
			(layer "F.Fab")
		)
		(fp_line
			(start 0.67945 -0.3048)
			(end 0.67945 0.3048)
			(stroke
				(width 0.1)
				(type default)
			)
			(layer "F.Fab")
		)
		(fp_line
			(start 0.12065 -0.3048)
			(end 0.67945 -0.3048)
			(stroke
				(width 0.1)
				(type default)
			)
			(layer "F.Fab")
		)
		(fp_line
			(start 0.12065 -0.2794)
			(end 0.12065 -0.3048)
			(stroke
				(width 0.1)
				(type default)
			)
			(layer "F.Fab")
		)
		(fp_line
			(start -0.12065 -0.2794)
			(end 0.12065 -0.2794)
			(stroke
				(width 0.1)
				(type default)
			)
			(layer "F.Fab")
		)
		(fp_line
			(start 0.120396 0.2794)
			(end -0.12065 0.2794)
			(stroke
				(width 0.1)
				(type default)
			)
			(layer "F.Fab")
		)
		(fp_line
			(start -0.12065 0.2794)
			(end -0.12065 0.3048)
			(stroke
				(width 0.1)
				(type default)
			)
			(layer "F.Fab")
		)
		(fp_line
			(start 0.67945 0.3048)
			(end 0.120396 0.3048)
			(stroke
				(width 0.1)
				(type default)
			)
			(layer "F.Fab")
		)
		(fp_line
			(start 0.120396 0.3048)
			(end 0.120396 0.2794)
			(stroke
				(width 0.1)
				(type default)
			)
			(layer "F.Fab")
		)
		(fp_line
			(start -0.12065 0.3048)
			(end -0.67945 0.3048)
			(stroke
				(width 0.1)
				(type default)
			)
			(layer "F.Fab")
		)
		(fp_line
			(start -0.67945 0.3048)
			(end -0.67945 -0.305054)
			(stroke
				(width 0.1)
				(type default)
			)
			(layer "F.Fab")
		)
		(pad "1" smd circle
			(at -0.40005 0 90)
			(size 0 0)
			(layers "F.Cu" "F.Mask" "F.Paste")
			(net "GND")
		)
		(pad "2" smd circle
			(at 0.40005 0 90)
			(size 0 0)
			(layers "F.Cu" "F.Mask" "F.Paste")
			(net "P1V8_PEX")
		)
	)
	(footprint ""
		(layer "F.Cu")
		(at 336.55 -201.168 -90)
		(property "Reference" "R4120"
			(at 0 0 270)
			(layer "F.SilkS")
			(hide yes)
			(effects
				(font
					(size 1.27 1.27)
				)
			)
		)
		(property "Value" ""
			(at 0 0 270)
			(layer "F.Fab")
			(effects
				(font
					(size 1.27 1.27)
				)
			)
		)
		(duplicate_pad_numbers_are_jumpers no)
		(fp_line
			(start -0.7874 0.4064)
			(end -0.7874 -0.4064)
			(stroke
				(width 0.1524)
				(type default)
			)
			(layer "F.SilkS")
		)
		(fp_line
			(start 0.7874 0.4064)
			(end -0.7874 0.4064)
			(stroke
				(width 0.1524)
				(type default)
			)
			(layer "F.SilkS")
		)
		(fp_line
			(start -0.7874 -0.4064)
			(end 0.7874 -0.4064)
			(stroke
				(width 0.1524)
				(type default)
			)
			(layer "F.SilkS")
		)
		(fp_line
			(start 0.7874 -0.4064)
			(end 0.7874 0.4064)
			(stroke
				(width 0.1524)
				(type default)
			)
			(layer "F.SilkS")
		)
		(fp_line
			(start -0.67945 0.3048)
			(end -0.67945 -0.305054)
			(stroke
				(width 0.1)
				(type default)
			)
			(layer "F.Fab")
		)
		(fp_line
			(start -0.12065 0.3048)
			(end -0.67945 0.3048)
			(stroke
				(width 0.1)
				(type default)
			)
			(layer "F.Fab")
		)
		(fp_line
			(start 0.120396 0.3048)
			(end 0.120396 0.2794)
			(stroke
				(width 0.1)
				(type default)
			)
			(layer "F.Fab")
		)
		(fp_line
			(start 0.67945 0.3048)
			(end 0.120396 0.3048)
			(stroke
				(width 0.1)
				(type default)
			)
			(layer "F.Fab")
		)
		(fp_line
			(start -0.12065 0.2794)
			(end -0.12065 0.3048)
			(stroke
				(width 0.1)
				(type default)
			)
			(layer "F.Fab")
		)
		(fp_line
			(start 0.120396 0.2794)
			(end -0.12065 0.2794)
			(stroke
				(width 0.1)
				(type default)
			)
			(layer "F.Fab")
		)
		(fp_line
			(start -0.12065 -0.2794)
			(end 0.12065 -0.2794)
			(stroke
				(width 0.1)
				(type default)
			)
			(layer "F.Fab")
		)
		(fp_line
			(start 0.12065 -0.2794)
			(end 0.12065 -0.3048)
			(stroke
				(width 0.1)
				(type default)
			)
			(layer "F.Fab")
		)
		(fp_line
			(start 0.12065 -0.3048)
			(end 0.67945 -0.3048)
			(stroke
				(width 0.1)
				(type default)
			)
			(layer "F.Fab")
		)
		(fp_line
			(start 0.67945 -0.3048)
			(end 0.67945 0.3048)
			(stroke
				(width 0.1)
				(type default)
			)
			(layer "F.Fab")
		)
		(fp_line
			(start -0.67945 -0.305054)
			(end -0.12065 -0.305054)
			(stroke
				(width 0.1)
				(type default)
			)
			(layer "F.Fab")
		)
		(fp_line
			(start -0.12065 -0.305054)
			(end -0.12065 -0.2794)
			(stroke
				(width 0.1)
				(type default)
			)
			(layer "F.Fab")
		)
		(pad "1" smd circle
			(at -0.40005 0 270)
			(size 0 0)
			(layers "F.Cu" "F.Mask" "F.Paste")
			(net "SSD9_PWRDIS")
		)
		(pad "2" smd circle
			(at 0.40005 0 270)
			(size 0 0)
			(layers "F.Cu" "F.Mask" "F.Paste")
			(net "SSD9_PWRDIS_R")
		)
	)
	(footprint ""
		(layer "F.Cu")
		(at 230.421942 -113.583212 -90)
		(property "Reference" "PC627"
			(at 0 0 270)
			(layer "F.SilkS")
			(hide yes)
			(effects
				(font
					(size 1.27 1.27)
				)
			)
		)
		(property "Value" ""
			(at 0 0 270)
			(layer "F.Fab")
			(effects
				(font
					(size 1.27 1.27)
				)
			)
		)
		(duplicate_pad_numbers_are_jumpers no)
		(fp_line
			(start -0.7874 0.4064)
			(end -0.7874 -0.4064)
			(stroke
				(width 0.1524)
				(type default)
			)
			(layer "F.SilkS")
		)
		(fp_line
			(start 0.7874 0.4064)
			(end -0.7874 0.4064)
			(stroke
				(width 0.1524)
				(type default)
			)
			(layer "F.SilkS")
		)
		(fp_line
			(start -0.7874 -0.4064)
			(end 0.7874 -0.4064)
			(stroke
				(width 0.1524)
				(type default)
			)
			(layer "F.SilkS")
		)
		(fp_line
			(start 0.7874 -0.4064)
			(end 0.7874 0.4064)
			(stroke
				(width 0.1524)
				(type default)
			)
			(layer "F.SilkS")
		)
		(fp_line
			(start -0.67945 0.3048)
			(end -0.67945 -0.305054)
			(stroke
				(width 0.1)
				(type default)
			)
			(layer "F.Fab")
		)
		(fp_line
			(start -0.12065 0.3048)
			(end -0.67945 0.3048)
			(stroke
				(width 0.1)
				(type default)
			)
			(layer "F.Fab")
		)
		(fp_line
			(start 0.120396 0.3048)
			(end 0.120396 0.2794)
			(stroke
				(width 0.1)
				(type default)
			)
			(layer "F.Fab")
		)
		(fp_line
			(start 0.67945 0.3048)
			(end 0.120396 0.3048)
			(stroke
				(width 0.1)
				(type default)
			)
			(layer "F.Fab")
		)
		(fp_line
			(start -0.12065 0.2794)
			(end -0.12065 0.3048)
			(stroke
				(width 0.1)
				(type default)
			)
			(layer "F.Fab")
		)
		(fp_line
			(start 0.120396 0.2794)
			(end -0.12065 0.2794)
			(stroke
				(width 0.1)
				(type default)
			)
			(layer "F.Fab")
		)
		(fp_line
			(start -0.12065 -0.2794)
			(end 0.12065 -0.2794)
			(stroke
				(width 0.1)
				(type default)
			)
			(layer "F.Fab")
		)
		(fp_line
			(start 0.12065 -0.2794)
			(end 0.12065 -0.3048)
			(stroke
				(width 0.1)
				(type default)
			)
			(layer "F.Fab")
		)
		(fp_line
			(start 0.12065 -0.3048)
			(end 0.67945 -0.3048)
			(stroke
				(width 0.1)
				(type default)
			)
			(layer "F.Fab")
		)
		(fp_line
			(start 0.67945 -0.3048)
			(end 0.67945 0.3048)
			(stroke
				(width 0.1)
				(type default)
			)
			(layer "F.Fab")
		)
		(fp_line
			(start -0.67945 -0.305054)
			(end -0.12065 -0.305054)
			(stroke
				(width 0.1)
				(type default)
			)
			(layer "F.Fab")
		)
		(fp_line
			(start -0.12065 -0.305054)
			(end -0.12065 -0.2794)
			(stroke
				(width 0.1)
				(type default)
			)
			(layer "F.Fab")
		)
		(pad "1" smd circle
			(at -0.40005 0 270)
			(size 0 0)
			(layers "F.Cu" "F.Mask" "F.Paste")
			(net "P12V_NIC3_R")
		)
		(pad "2" smd circle
			(at 0.40005 0 270)
			(size 0 0)
			(layers "F.Cu" "F.Mask" "F.Paste")
			(net "GND")
		)
	)
	(footprint ""
		(layer "F.Cu")
		(at 5.744972 -72.156828)
		(property "Reference" "U383"
			(at -3.888994 -1.82118 0)
			(unlocked yes)
			(layer "F.SilkS")
			(effects
				(font
					(size 0.7874 0.5842)
					(thickness 0.1524)
				)
				(justify left)
			)
		)
		(property "Value" ""
			(at 0 0 0)
			(layer "F.Fab")
			(effects
				(font
					(size 1.27 1.27)
				)
			)
		)
		(duplicate_pad_numbers_are_jumpers no)
		(fp_line
			(start -1.3462 -1.1938)
			(end -1.3462 1.1684)
			(stroke
				(width 0.1524)
				(type default)
			)
			(layer "F.SilkS")
		)
		(fp_line
			(start -1.3462 1.1938)
			(end 1.3462 1.1938)
			(stroke
				(width 0.1524)
				(type default)
			)
			(layer "F.SilkS")
		)
		(fp_line
			(start 1.3462 -1.1938)
			(end -1.3462 -1.1938)
			(stroke
				(width 0.1524)
				(type default)
			)
			(layer "F.SilkS")
		)
		(fp_line
			(start 1.3462 1.1938)
			(end 1.3462 -1.1938)
			(stroke
				(width 0.1524)
				(type default)
			)
			(layer "F.SilkS")
		)
		(fp_poly
			(pts
				(xy -1.490218 -0.64135) (xy -2.095246 -0.338836) (xy -2.095246 -0.943864)
			)
			(stroke
				(width 0)
				(type default)
			)
			(fill yes)
			(layer "F.SilkS")
		)
		(fp_line
			(start -0.674878 -1.124966)
			(end -0.674878 1.124966)
			(stroke
				(width 0.1)
				(type default)
			)
			(layer "F.Fab")
		)
		(fp_line
			(start -0.674878 1.124966)
			(end 0.674878 1.124966)
			(stroke
				(width 0.1)
				(type default)
			)
			(layer "F.Fab")
		)
		(fp_line
			(start 0.674878 -1.124966)
			(end -0.674878 -1.124966)
			(stroke
				(width 0.1)
				(type default)
			)
			(layer "F.Fab")
		)
		(fp_line
			(start 0.674878 1.124966)
			(end 0.674878 -1.124966)
			(stroke
				(width 0.1)
				(type default)
			)
			(layer "F.Fab")
		)
		(fp_poly
			(pts
				(xy -1.447038 -0.760476) (xy -2.052066 -0.457962) (xy -2.052066 -1.06299)
			)
			(stroke
				(width 0)
				(type default)
			)
			(fill yes)
			(layer "F.Fab")
		)
		(pad "1" smd rect
			(at -0.899922 -0.750062)
			(size 0.6096 0.6096)
			(layers "F.Cu" "F.Mask" "F.Paste")
			(net "PWRGD_P3V3_SSD0_R")
		)
		(pad "2" smd rect
			(at -0.899922 0 90)
			(size 0.4064 0.6096)
			(layers "F.Cu" "F.Mask" "F.Paste")
			(net "RST_SMB_SSD0_N")
		)
		(pad "3" smd rect
			(at -0.899922 0.750062)
			(size 0.6096 0.6096)
			(layers "F.Cu" "F.Mask" "F.Paste")
			(net "GND")
		)
		(pad "4" smd rect
			(at 0.899922 0.750062)
			(size 0.6096 0.6096)
			(layers "F.Cu" "F.Mask" "F.Paste")
			(net "RST_SMB_SSD0_ISO_N")
		)
		(pad "5" smd rect
			(at 0.899922 -0.750062)
			(size 0.6096 0.6096)
			(layers "F.Cu" "F.Mask" "F.Paste")
			(net "P3V3_AUX")
		)
	)
	(footprint ""
		(layer "F.Cu")
		(at 344.511884 -107.848654 180)
		(property "Reference" "R955"
			(at 0 0 180)
			(layer "F.SilkS")
			(hide yes)
			(effects
				(font
					(size 1.27 1.27)
				)
			)
		)
		(property "Value" ""
			(at 0 0 180)
			(layer "F.Fab")
			(effects
				(font
					(size 1.27 1.27)
				)
			)
		)
		(duplicate_pad_numbers_are_jumpers no)
		(fp_line
			(start 0.7874 0.4064)
			(end -0.7874 0.4064)
			(stroke
				(width 0.1524)
				(type default)
			)
			(layer "F.SilkS")
		)
		(fp_line
			(start 0.7874 -0.4064)
			(end 0.7874 0.4064)
			(stroke
				(width 0.1524)
				(type default)
			)
			(layer "F.SilkS")
		)
		(fp_line
			(start -0.7874 0.4064)
			(end -0.7874 -0.4064)
			(stroke
				(width 0.1524)
				(type default)
			)
			(layer "F.SilkS")
		)
		(fp_line
			(start -0.7874 -0.4064)
			(end 0.7874 -0.4064)
			(stroke
				(width 0.1524)
				(type default)
			)
			(layer "F.SilkS")
		)
		(fp_line
			(start 0.67945 0.3048)
			(end 0.120396 0.3048)
			(stroke
				(width 0.1)
				(type default)
			)
			(layer "F.Fab")
		)
		(fp_line
			(start 0.67945 -0.3048)
			(end 0.67945 0.3048)
			(stroke
				(width 0.1)
				(type default)
			)
			(layer "F.Fab")
		)
		(fp_line
			(start 0.12065 -0.2794)
			(end 0.12065 -0.3048)
			(stroke
				(width 0.1)
				(type default)
			)
			(layer "F.Fab")
		)
		(fp_line
			(start 0.12065 -0.3048)
			(end 0.67945 -0.3048)
			(stroke
				(width 0.1)
				(type default)
			)
			(layer "F.Fab")
		)
		(fp_line
			(start 0.120396 0.3048)
			(end 0.120396 0.2794)
			(stroke
				(width 0.1)
				(type default)
			)
			(layer "F.Fab")
		)
		(fp_line
			(start 0.120396 0.2794)
			(end -0.12065 0.2794)
			(stroke
				(width 0.1)
				(type default)
			)
			(layer "F.Fab")
		)
		(fp_line
			(start -0.12065 0.3048)
			(end -0.67945 0.3048)
			(stroke
				(width 0.1)
				(type default)
			)
			(layer "F.Fab")
		)
		(fp_line
			(start -0.12065 0.2794)
			(end -0.12065 0.3048)
			(stroke
				(width 0.1)
				(type default)
			)
			(layer "F.Fab")
		)
		(fp_line
			(start -0.12065 -0.2794)
			(end 0.12065 -0.2794)
			(stroke
				(width 0.1)
				(type default)
			)
			(layer "F.Fab")
		)
		(fp_line
			(start -0.12065 -0.305054)
			(end -0.12065 -0.2794)
			(stroke
				(width 0.1)
				(type default)
			)
			(layer "F.Fab")
		)
		(fp_line
			(start -0.67945 0.3048)
			(end -0.67945 -0.305054)
			(stroke
				(width 0.1)
				(type default)
			)
			(layer "F.Fab")
		)
		(fp_line
			(start -0.67945 -0.305054)
			(end -0.12065 -0.305054)
			(stroke
				(width 0.1)
				(type default)
			)
			(layer "F.Fab")
		)
		(pad "1" smd circle
			(at -0.40005 0 180)
			(size 0 0)
			(layers "F.Cu" "F.Mask" "F.Paste")
			(net "HP_NIC5_EN")
		)
		(pad "2" smd circle
			(at 0.40005 0 180)
			(size 0 0)
			(layers "F.Cu" "F.Mask" "F.Paste")
			(net "P12V_NIC5_CO_EN")
		)
	)
	(footprint ""
		(layer "F.Cu")
		(at 251.446792 -38.49116 180)
		(property "Reference" "R6089"
			(at 0 0 180)
			(layer "F.SilkS")
			(hide yes)
			(effects
				(font
					(size 1.27 1.27)
				)
			)
		)
		(property "Value" ""
			(at 0 0 180)
			(layer "F.Fab")
			(effects
				(font
					(size 1.27 1.27)
				)
			)
		)
		(duplicate_pad_numbers_are_jumpers no)
		(fp_line
			(start 0.7874 0.4064)
			(end -0.7874 0.4064)
			(stroke
				(width 0.1524)
				(type default)
			)
			(layer "F.SilkS")
		)
		(fp_line
			(start 0.7874 -0.4064)
			(end 0.7874 0.4064)
			(stroke
				(width 0.1524)
				(type default)
			)
			(layer "F.SilkS")
		)
		(fp_line
			(start -0.7874 0.4064)
			(end -0.7874 -0.4064)
			(stroke
				(width 0.1524)
				(type default)
			)
			(layer "F.SilkS")
		)
		(fp_line
			(start -0.7874 -0.4064)
			(end 0.7874 -0.4064)
			(stroke
				(width 0.1524)
				(type default)
			)
			(layer "F.SilkS")
		)
		(fp_line
			(start 0.67945 0.3048)
			(end 0.120396 0.3048)
			(stroke
				(width 0.1)
				(type default)
			)
			(layer "F.Fab")
		)
		(fp_line
			(start 0.67945 -0.3048)
			(end 0.67945 0.3048)
			(stroke
				(width 0.1)
				(type default)
			)
			(layer "F.Fab")
		)
		(fp_line
			(start 0.12065 -0.2794)
			(end 0.12065 -0.3048)
			(stroke
				(width 0.1)
				(type default)
			)
			(layer "F.Fab")
		)
		(fp_line
			(start 0.12065 -0.3048)
			(end 0.67945 -0.3048)
			(stroke
				(width 0.1)
				(type default)
			)
			(layer "F.Fab")
		)
		(fp_line
			(start 0.120396 0.3048)
			(end 0.120396 0.2794)
			(stroke
				(width 0.1)
				(type default)
			)
			(layer "F.Fab")
		)
		(fp_line
			(start 0.120396 0.2794)
			(end -0.12065 0.2794)
			(stroke
				(width 0.1)
				(type default)
			)
			(layer "F.Fab")
		)
		(fp_line
			(start -0.12065 0.3048)
			(end -0.67945 0.3048)
			(stroke
				(width 0.1)
				(type default)
			)
			(layer "F.Fab")
		)
		(fp_line
			(start -0.12065 0.2794)
			(end -0.12065 0.3048)
			(stroke
				(width 0.1)
				(type default)
			)
			(layer "F.Fab")
		)
		(fp_line
			(start -0.12065 -0.2794)
			(end 0.12065 -0.2794)
			(stroke
				(width 0.1)
				(type default)
			)
			(layer "F.Fab")
		)
		(fp_line
			(start -0.12065 -0.305054)
			(end -0.12065 -0.2794)
			(stroke
				(width 0.1)
				(type default)
			)
			(layer "F.Fab")
		)
		(fp_line
			(start -0.67945 0.3048)
			(end -0.67945 -0.305054)
			(stroke
				(width 0.1)
				(type default)
			)
			(layer "F.Fab")
		)
		(fp_line
			(start -0.67945 -0.305054)
			(end -0.12065 -0.305054)
			(stroke
				(width 0.1)
				(type default)
			)
			(layer "F.Fab")
		)
		(pad "1" smd circle
			(at -0.40005 0 180)
			(size 0 0)
			(layers "F.Cu" "F.Mask" "F.Paste")
			(net "P3V3_SSD9_PG_G1")
		)
		(pad "2" smd circle
			(at 0.40005 0 180)
			(size 0 0)
			(layers "F.Cu" "F.Mask" "F.Paste")
			(net "GND")
		)
	)
	(footprint ""
		(layer "F.Cu")
		(at 400.05762 -343.952322 90)
		(property "Reference" "C751"
			(at 0 0 90)
			(layer "F.SilkS")
			(hide yes)
			(effects
				(font
					(size 1.27 1.27)
				)
			)
		)
		(property "Value" ""
			(at 0 0 90)
			(layer "F.Fab")
			(effects
				(font
					(size 1.27 1.27)
				)
			)
		)
		(duplicate_pad_numbers_are_jumpers no)
		(fp_line
			(start 0.299974 -0.150114)
			(end 0.299974 0.150114)
			(stroke
				(width 0.1)
				(type default)
			)
			(layer "F.Fab")
		)
		(fp_line
			(start -0.299974 -0.150114)
			(end 0.299974 -0.150114)
			(stroke
				(width 0.1)
				(type default)
			)
			(layer "F.Fab")
		)
		(fp_line
			(start 0.299974 0.150114)
			(end -0.299974 0.150114)
			(stroke
				(width 0.1)
				(type default)
			)
			(layer "F.Fab")
		)
		(fp_line
			(start -0.299974 0.150114)
			(end -0.299974 -0.150114)
			(stroke
				(width 0.1)
				(type default)
			)
			(layer "F.Fab")
		)
		(pad "1" smd rect
			(at -0.2667 0 90)
			(size 0.3048 0.381)
			(layers "F.Cu" "F.Mask" "F.Paste")
			(net "P5E_PEX3_STN5_TX_DN<85>")
		)
		(pad "2" smd rect
			(at 0.2667 0 90)
			(size 0.3048 0.381)
			(layers "F.Cu" "F.Mask" "F.Paste")
			(net "P5E_PEX3_STN5_TX_C_DN<85>")
		)
	)
	(footprint ""
		(layer "F.Cu")
		(at 318.695324 -350.098614 90)
		(property "Reference" "C543"
			(at 0 0 90)
			(layer "F.SilkS")
			(hide yes)
			(effects
				(font
					(size 1.27 1.27)
				)
			)
		)
		(property "Value" ""
			(at 0 0 90)
			(layer "F.Fab")
			(effects
				(font
					(size 1.27 1.27)
				)
			)
		)
		(duplicate_pad_numbers_are_jumpers no)
		(fp_line
			(start 0.299974 -0.150114)
			(end 0.299974 0.150114)
			(stroke
				(width 0.1)
				(type default)
			)
			(layer "F.Fab")
		)
		(fp_line
			(start -0.299974 -0.150114)
			(end 0.299974 -0.150114)
			(stroke
				(width 0.1)
				(type default)
			)
			(layer "F.Fab")
		)
		(fp_line
			(start 0.299974 0.150114)
			(end -0.299974 0.150114)
			(stroke
				(width 0.1)
				(type default)
			)
			(layer "F.Fab")
		)
		(fp_line
			(start -0.299974 0.150114)
			(end -0.299974 -0.150114)
			(stroke
				(width 0.1)
				(type default)
			)
			(layer "F.Fab")
		)
		(pad "1" smd rect
			(at -0.2667 0 90)
			(size 0.3048 0.381)
			(layers "F.Cu" "F.Mask" "F.Paste")
			(net "P5E_PEX2_STN5_TX_DP<83>")
		)
		(pad "2" smd rect
			(at 0.2667 0 90)
			(size 0.3048 0.381)
			(layers "F.Cu" "F.Mask" "F.Paste")
			(net "P5E_PEX2_STN5_TX_C_DP<83>")
		)
	)
	(footprint ""
		(layer "F.Cu")
		(at 234.154472 -369.787424 90)
		(property "Reference" "PR40"
			(at 0 0 90)
			(layer "F.SilkS")
			(hide yes)
			(effects
				(font
					(size 1.27 1.27)
				)
			)
		)
		(property "Value" ""
			(at 0 0 90)
			(layer "F.Fab")
			(effects
				(font
					(size 1.27 1.27)
				)
			)
		)
		(duplicate_pad_numbers_are_jumpers no)
		(fp_line
			(start 0.7874 -0.4064)
			(end 0.7874 0.4064)
			(stroke
				(width 0.1524)
				(type default)
			)
			(layer "F.SilkS")
		)
		(fp_line
			(start -0.7874 -0.4064)
			(end 0.7874 -0.4064)
			(stroke
				(width 0.1524)
				(type default)
			)
			(layer "F.SilkS")
		)
		(fp_line
			(start 0.7874 0.4064)
			(end -0.7874 0.4064)
			(stroke
				(width 0.1524)
				(type default)
			)
			(layer "F.SilkS")
		)
		(fp_line
			(start -0.7874 0.4064)
			(end -0.7874 -0.4064)
			(stroke
				(width 0.1524)
				(type default)
			)
			(layer "F.SilkS")
		)
		(fp_line
			(start -0.12065 -0.305054)
			(end -0.12065 -0.2794)
			(stroke
				(width 0.1)
				(type default)
			)
			(layer "F.Fab")
		)
		(fp_line
			(start -0.67945 -0.305054)
			(end -0.12065 -0.305054)
			(stroke
				(width 0.1)
				(type default)
			)
			(layer "F.Fab")
		)
		(fp_line
			(start 0.67945 -0.3048)
			(end 0.67945 0.3048)
			(stroke
				(width 0.1)
				(type default)
			)
			(layer "F.Fab")
		)
		(fp_line
			(start 0.12065 -0.3048)
			(end 0.67945 -0.3048)
			(stroke
				(width 0.1)
				(type default)
			)
			(layer "F.Fab")
		)
		(fp_line
			(start 0.12065 -0.2794)
			(end 0.12065 -0.3048)
			(stroke
				(width 0.1)
				(type default)
			)
			(layer "F.Fab")
		)
		(fp_line
			(start -0.12065 -0.2794)
			(end 0.12065 -0.2794)
			(stroke
				(width 0.1)
				(type default)
			)
			(layer "F.Fab")
		)
		(fp_line
			(start 0.120396 0.2794)
			(end -0.12065 0.2794)
			(stroke
				(width 0.1)
				(type default)
			)
			(layer "F.Fab")
		)
		(fp_line
			(start -0.12065 0.2794)
			(end -0.12065 0.3048)
			(stroke
				(width 0.1)
				(type default)
			)
			(layer "F.Fab")
		)
		(fp_line
			(start 0.67945 0.3048)
			(end 0.120396 0.3048)
			(stroke
				(width 0.1)
				(type default)
			)
			(layer "F.Fab")
		)
		(fp_line
			(start 0.120396 0.3048)
			(end 0.120396 0.2794)
			(stroke
				(width 0.1)
				(type default)
			)
			(layer "F.Fab")
		)
		(fp_line
			(start -0.12065 0.3048)
			(end -0.67945 0.3048)
			(stroke
				(width 0.1)
				(type default)
			)
			(layer "F.Fab")
		)
		(fp_line
			(start -0.67945 0.3048)
			(end -0.67945 -0.305054)
			(stroke
				(width 0.1)
				(type default)
			)
			(layer "F.Fab")
		)
		(pad "1" smd circle
			(at -0.40005 0 90)
			(size 0 0)
			(layers "F.Cu" "F.Mask" "F.Paste")
			(net "HSC_FAULT_N_2")
		)
		(pad "2" smd circle
			(at 0.40005 0 90)
			(size 0 0)
			(layers "F.Cu" "F.Mask" "F.Paste")
			(net "HSC_FAULT_N")
		)
	)
	(footprint ""
		(layer "F.Cu")
		(at 169.293032 -350.098614 90)
		(property "Reference" "C2519"
			(at 0 0 90)
			(layer "F.SilkS")
			(hide yes)
			(effects
				(font
					(size 1.27 1.27)
				)
			)
		)
		(property "Value" ""
			(at 0 0 90)
			(layer "F.Fab")
			(effects
				(font
					(size 1.27 1.27)
				)
			)
		)
		(duplicate_pad_numbers_are_jumpers no)
		(fp_line
			(start 0.299974 -0.150114)
			(end 0.299974 0.150114)
			(stroke
				(width 0.1)
				(type default)
			)
			(layer "F.Fab")
		)
		(fp_line
			(start -0.299974 -0.150114)
			(end 0.299974 -0.150114)
			(stroke
				(width 0.1)
				(type default)
			)
			(layer "F.Fab")
		)
		(fp_line
			(start 0.299974 0.150114)
			(end -0.299974 0.150114)
			(stroke
				(width 0.1)
				(type default)
			)
			(layer "F.Fab")
		)
		(fp_line
			(start -0.299974 0.150114)
			(end -0.299974 -0.150114)
			(stroke
				(width 0.1)
				(type default)
			)
			(layer "F.Fab")
		)
		(pad "1" smd rect
			(at -0.2667 0 90)
			(size 0.3048 0.381)
			(layers "F.Cu" "F.Mask" "F.Paste")
			(net "P5E_PEX1_STN4_TX_DN<76>")
		)
		(pad "2" smd rect
			(at 0.2667 0 90)
			(size 0.3048 0.381)
			(layers "F.Cu" "F.Mask" "F.Paste")
			(net "P5E_PEX1_STN4_TX_C_DN<76>")
		)
	)
	(footprint ""
		(layer "F.Cu")
		(at 164.946076 -46.4439 180)
		(property "Reference" "U60"
			(at 0.100076 -2.45237 0)
			(unlocked yes)
			(layer "F.SilkS")
			(effects
				(font
					(size 0.7874 0.5842)
					(thickness 0.1524)
				)
			)
		)
		(property "Value" ""
			(at 0 0 180)
			(layer "F.Fab")
			(effects
				(font
					(size 1.27 1.27)
				)
			)
		)
		(duplicate_pad_numbers_are_jumpers no)
		(fp_line
			(start 1.500124 1.500124)
			(end 1.004062 1.500124)
			(stroke
				(width 0.1524)
				(type default)
			)
			(layer "F.SilkS")
		)
		(fp_line
			(start 1.500124 1.004062)
			(end 1.500124 1.500124)
			(stroke
				(width 0.1524)
				(type default)
			)
			(layer "F.SilkS")
		)
		(fp_line
			(start 1.500124 -1.500124)
			(end 1.500124 -1.004062)
			(stroke
				(width 0.1524)
				(type default)
			)
			(layer "F.SilkS")
		)
		(fp_line
			(start 1.004062 -1.500124)
			(end 1.500124 -1.500124)
			(stroke
				(width 0.1524)
				(type default)
			)
			(layer "F.SilkS")
		)
		(fp_line
			(start -1.004062 1.500124)
			(end -1.500124 1.500124)
			(stroke
				(width 0.1524)
				(type default)
			)
			(layer "F.SilkS")
		)
		(fp_line
			(start -1.500124 1.500124)
			(end -1.500124 1.004062)
			(stroke
				(width 0.1524)
				(type default)
			)
			(layer "F.SilkS")
		)
		(fp_line
			(start -1.500124 -1.004062)
			(end -1.500124 -1.500124)
			(stroke
				(width 0.1524)
				(type default)
			)
			(layer "F.SilkS")
		)
		(fp_line
			(start -1.500124 -1.500124)
			(end -1.004062 -1.500124)
			(stroke
				(width 0.1524)
				(type default)
			)
			(layer "F.SilkS")
		)
		(fp_poly
			(pts
				(xy -1.95834 -2.057146) (xy -2.676906 -1.338834) (xy -1.599184 -0.979678)
			)
			(stroke
				(width 0)
				(type default)
			)
			(fill yes)
			(layer "F.SilkS")
		)
		(fp_line
			(start 1.500124 1.500124)
			(end -1.500124 1.500124)
			(stroke
				(width 0.1)
				(type default)
			)
			(layer "F.Fab")
		)
		(fp_line
			(start 1.500124 -1.500124)
			(end 1.500124 1.500124)
			(stroke
				(width 0.1)
				(type default)
			)
			(layer "F.Fab")
		)
		(fp_line
			(start -1.500124 1.500124)
			(end -1.500124 -1.500124)
			(stroke
				(width 0.1)
				(type default)
			)
			(layer "F.Fab")
		)
		(fp_line
			(start -1.500124 -1.500124)
			(end 1.500124 -1.500124)
			(stroke
				(width 0.1)
				(type default)
			)
			(layer "F.Fab")
		)
		(fp_poly
			(pts
				(xy -2.847848 -1.258062) (xy -2.847848 -0.242062) (xy -1.831848 -0.750062)
			)
			(stroke
				(width 0)
				(type default)
			)
			(fill yes)
			(layer "F.Fab")
		)
		(pad "1" smd rect
			(at -1.400048 -0.750062 90)
			(size 0.2286 0.6096)
			(layers "F.Cu" "F.Mask" "F.Paste")
			(net "SSD5_ADC_A1")
		)
		(pad "2" smd rect
			(at -1.400048 -0.249936 90)
			(size 0.2286 0.6096)
			(layers "F.Cu" "F.Mask" "F.Paste")
			(net "SSD5_ADC_A0")
		)
		(pad "3" smd rect
			(at -1.400048 0.249936 90)
			(size 0.2286 0.6096)
			(layers "F.Cu" "F.Mask" "F.Paste")
			(net "SSD5_ADC_ALERT_N")
		)
		(pad "4" smd rect
			(at -1.400048 0.750062 90)
			(size 0.2286 0.6096)
			(layers "F.Cu" "F.Mask" "F.Paste")
			(net "SMB_SSD5_ADC_SDA")
		)
		(pad "5" smd rect
			(at -0.750062 1.400048 180)
			(size 0.2286 0.6096)
			(layers "F.Cu" "F.Mask" "F.Paste")
			(net "SMB_SSD5_ADC_SCL")
		)
		(pad "6" smd rect
			(at -0.249936 1.400048 180)
			(size 0.2286 0.6096)
			(layers "F.Cu" "F.Mask" "F.Paste")
			(net "Net_8732")
		)
		(pad "7" smd rect
			(at 0.249936 1.400048 180)
			(size 0.2286 0.6096)
			(layers "F.Cu" "F.Mask" "F.Paste")
			(net "Net_8731")
		)
		(pad "8" smd rect
			(at 0.750062 1.400048 180)
			(size 0.2286 0.6096)
			(layers "F.Cu" "F.Mask" "F.Paste")
			(net "Net_8730")
		)
		(pad "9" smd rect
			(at 1.400048 0.750062 90)
			(size 0.2286 0.6096)
			(layers "F.Cu" "F.Mask" "F.Paste")
			(net "P3V3_AUX")
		)
		(pad "10" smd rect
			(at 1.400048 0.249936 90)
			(size 0.2286 0.6096)
			(layers "F.Cu" "F.Mask" "F.Paste")
			(net "GND")
		)
		(pad "11" smd rect
			(at 1.400048 -0.249936 90)
			(size 0.2286 0.6096)
			(layers "F.Cu" "F.Mask" "F.Paste")
			(net "P12V_SSD5_R")
		)
		(pad "12" smd rect
			(at 1.400048 -0.750062 90)
			(size 0.2286 0.6096)
			(layers "F.Cu" "F.Mask" "F.Paste")
			(net "P12V_SSD5_VIN_N")
		)
		(pad "13" smd rect
			(at 0.750062 -1.400048 180)
			(size 0.2286 0.6096)
			(layers "F.Cu" "F.Mask" "F.Paste")
			(net "P12V_SSD5_VIN_P")
		)
		(pad "14" smd rect
			(at 0.249936 -1.400048 180)
			(size 0.2286 0.6096)
			(layers "F.Cu" "F.Mask" "F.Paste")
			(net "Net_8729")
		)
		(pad "15" smd rect
			(at -0.249936 -1.400048 180)
			(size 0.2286 0.6096)
			(layers "F.Cu" "F.Mask" "F.Paste")
			(net "Net_8728")
		)
		(pad "16" smd rect
			(at -0.750062 -1.400048 180)
			(size 0.2286 0.6096)
			(layers "F.Cu" "F.Mask" "F.Paste")
			(net "Net_8727")
		)
		(pad "TH" smd rect
			(at 0 0 180)
			(size 1.7018 1.7018)
			(layers "F.Cu" "F.Mask" "F.Paste")
			(net "GND")
		)
		(zone
			(layer "F.Cu")
			(hatch none 0.5)
			(connect_pads
				(clearance 0)
			)
			(min_thickness 0.25)
			(keepout
				(tracks not_allowed)
				(vias allowed)
				(pads allowed)
				(copperpour not_allowed)
				(footprints allowed)
			)
			(placement
				(enabled no)
				(sheetname "")
			)
			(fill
				(thermal_gap 0.5)
				(thermal_bridge_width 0.5)
				(island_removal_mode 0)
			)
			(polygon
				(pts
					(xy 165.990524 -46.4185) (xy 165.990524 -45.399452) (xy 163.901628 -45.399452) (xy 163.901628 -47.488348)
					(xy 165.990524 -47.488348) (xy 165.990524 -46.4439) (xy 165.847776 -46.4439) (xy 165.847776 -47.3456)
					(xy 164.044376 -47.3456) (xy 164.044376 -45.5422) (xy 165.847776 -45.5422) (xy 165.847776 -46.4185)
				)
			)
		)
	)
	(footprint ""
		(layer "F.Cu")
		(at 328.936604 -356.244906 90)
		(property "Reference" "C534"
			(at 0 0 90)
			(layer "F.SilkS")
			(hide yes)
			(effects
				(font
					(size 1.27 1.27)
				)
			)
		)
		(property "Value" ""
			(at 0 0 90)
			(layer "F.Fab")
			(effects
				(font
					(size 1.27 1.27)
				)
			)
		)
		(duplicate_pad_numbers_are_jumpers no)
		(fp_line
			(start 0.299974 -0.150114)
			(end 0.299974 0.150114)
			(stroke
				(width 0.1)
				(type default)
			)
			(layer "F.Fab")
		)
		(fp_line
			(start -0.299974 -0.150114)
			(end 0.299974 -0.150114)
			(stroke
				(width 0.1)
				(type default)
			)
			(layer "F.Fab")
		)
		(fp_line
			(start 0.299974 0.150114)
			(end -0.299974 0.150114)
			(stroke
				(width 0.1)
				(type default)
			)
			(layer "F.Fab")
		)
		(fp_line
			(start -0.299974 0.150114)
			(end -0.299974 -0.150114)
			(stroke
				(width 0.1)
				(type default)
			)
			(layer "F.Fab")
		)
		(pad "1" smd rect
			(at -0.2667 0 90)
			(size 0.3048 0.381)
			(layers "F.Cu" "F.Mask" "F.Paste")
			(net "P5E_PEX2_STN5_TX_DN<88>")
		)
		(pad "2" smd rect
			(at 0.2667 0 90)
			(size 0.3048 0.381)
			(layers "F.Cu" "F.Mask" "F.Paste")
			(net "P5E_PEX2_STN5_TX_C_DN<88>")
		)
	)
	(footprint ""
		(layer "F.Cu")
		(at 230.18877 -258.389374 -90)
		(property "Reference" "R6495"
			(at 0 0 270)
			(layer "F.SilkS")
			(hide yes)
			(effects
				(font
					(size 1.27 1.27)
				)
			)
		)
		(property "Value" ""
			(at 0 0 270)
			(layer "F.Fab")
			(effects
				(font
					(size 1.27 1.27)
				)
			)
		)
		(duplicate_pad_numbers_are_jumpers no)
		(fp_line
			(start -0.7874 0.4064)
			(end -0.7874 -0.4064)
			(stroke
				(width 0.1524)
				(type default)
			)
			(layer "F.SilkS")
		)
		(fp_line
			(start 0.7874 0.4064)
			(end -0.7874 0.4064)
			(stroke
				(width 0.1524)
				(type default)
			)
			(layer "F.SilkS")
		)
		(fp_line
			(start -0.7874 -0.4064)
			(end 0.7874 -0.4064)
			(stroke
				(width 0.1524)
				(type default)
			)
			(layer "F.SilkS")
		)
		(fp_line
			(start 0.7874 -0.4064)
			(end 0.7874 0.4064)
			(stroke
				(width 0.1524)
				(type default)
			)
			(layer "F.SilkS")
		)
		(fp_line
			(start -0.67945 0.3048)
			(end -0.67945 -0.305054)
			(stroke
				(width 0.1)
				(type default)
			)
			(layer "F.Fab")
		)
		(fp_line
			(start -0.12065 0.3048)
			(end -0.67945 0.3048)
			(stroke
				(width 0.1)
				(type default)
			)
			(layer "F.Fab")
		)
		(fp_line
			(start 0.120396 0.3048)
			(end 0.120396 0.2794)
			(stroke
				(width 0.1)
				(type default)
			)
			(layer "F.Fab")
		)
		(fp_line
			(start 0.67945 0.3048)
			(end 0.120396 0.3048)
			(stroke
				(width 0.1)
				(type default)
			)
			(layer "F.Fab")
		)
		(fp_line
			(start -0.12065 0.2794)
			(end -0.12065 0.3048)
			(stroke
				(width 0.1)
				(type default)
			)
			(layer "F.Fab")
		)
		(fp_line
			(start 0.120396 0.2794)
			(end -0.12065 0.2794)
			(stroke
				(width 0.1)
				(type default)
			)
			(layer "F.Fab")
		)
		(fp_line
			(start -0.12065 -0.2794)
			(end 0.12065 -0.2794)
			(stroke
				(width 0.1)
				(type default)
			)
			(layer "F.Fab")
		)
		(fp_line
			(start 0.12065 -0.2794)
			(end 0.12065 -0.3048)
			(stroke
				(width 0.1)
				(type default)
			)
			(layer "F.Fab")
		)
		(fp_line
			(start 0.12065 -0.3048)
			(end 0.67945 -0.3048)
			(stroke
				(width 0.1)
				(type default)
			)
			(layer "F.Fab")
		)
		(fp_line
			(start 0.67945 -0.3048)
			(end 0.67945 0.3048)
			(stroke
				(width 0.1)
				(type default)
			)
			(layer "F.Fab")
		)
		(fp_line
			(start -0.67945 -0.305054)
			(end -0.12065 -0.305054)
			(stroke
				(width 0.1)
				(type default)
			)
			(layer "F.Fab")
		)
		(fp_line
			(start -0.12065 -0.305054)
			(end -0.12065 -0.2794)
			(stroke
				(width 0.1)
				(type default)
			)
			(layer "F.Fab")
		)
		(pad "1" smd circle
			(at -0.40005 0 270)
			(size 0 0)
			(layers "F.Cu" "F.Mask" "F.Paste")
			(net "P1V25_SERDES_VDDPLL_PEX1")
		)
		(pad "2" smd circle
			(at 0.40005 0 270)
			(size 0 0)
			(layers "F.Cu" "F.Mask" "F.Paste")
			(net "P1V25_SERDES_VDDPLL_PEX1_C4")
		)
	)
	(footprint ""
		(layer "F.Cu")
		(at 228.695504 -155.940506 -90)
		(property "Reference" "R1205"
			(at 0 0 270)
			(layer "F.SilkS")
			(hide yes)
			(effects
				(font
					(size 1.27 1.27)
				)
			)
		)
		(property "Value" ""
			(at 0 0 270)
			(layer "F.Fab")
			(effects
				(font
					(size 1.27 1.27)
				)
			)
		)
		(duplicate_pad_numbers_are_jumpers no)
		(fp_line
			(start 0.7874 0.4064)
			(end -0.7874 0.4064)
			(stroke
				(width 0.1524)
				(type default)
			)
			(layer "F.SilkS")
		)
		(fp_line
			(start -0.67945 0.3048)
			(end -0.67945 -0.305054)
			(stroke
				(width 0.1)
				(type default)
			)
			(layer "F.Fab")
		)
		(fp_line
			(start -0.12065 0.3048)
			(end -0.67945 0.3048)
			(stroke
				(width 0.1)
				(type default)
			)
			(layer "F.Fab")
		)
		(fp_line
			(start 0.120396 0.3048)
			(end 0.120396 0.2794)
			(stroke
				(width 0.1)
				(type default)
			)
			(layer "F.Fab")
		)
		(fp_line
			(start 0.67945 0.3048)
			(end 0.120396 0.3048)
			(stroke
				(width 0.1)
				(type default)
			)
			(layer "F.Fab")
		)
		(fp_line
			(start -0.12065 0.2794)
			(end -0.12065 0.3048)
			(stroke
				(width 0.1)
				(type default)
			)
			(layer "F.Fab")
		)
		(fp_line
			(start 0.120396 0.2794)
			(end -0.12065 0.2794)
			(stroke
				(width 0.1)
				(type default)
			)
			(layer "F.Fab")
		)
		(fp_line
			(start -0.12065 -0.2794)
			(end 0.12065 -0.2794)
			(stroke
				(width 0.1)
				(type default)
			)
			(layer "F.Fab")
		)
		(fp_line
			(start 0.12065 -0.2794)
			(end 0.12065 -0.3048)
			(stroke
				(width 0.1)
				(type default)
			)
			(layer "F.Fab")
		)
		(fp_line
			(start 0.12065 -0.3048)
			(end 0.67945 -0.3048)
			(stroke
				(width 0.1)
				(type default)
			)
			(layer "F.Fab")
		)
		(fp_line
			(start 0.67945 -0.3048)
			(end 0.67945 0.3048)
			(stroke
				(width 0.1)
				(type default)
			)
			(layer "F.Fab")
		)
		(fp_line
			(start -0.67945 -0.305054)
			(end -0.12065 -0.305054)
			(stroke
				(width 0.1)
				(type default)
			)
			(layer "F.Fab")
		)
		(fp_line
			(start -0.12065 -0.305054)
			(end -0.12065 -0.2794)
			(stroke
				(width 0.1)
				(type default)
			)
			(layer "F.Fab")
		)
		(pad "1" smd circle
			(at -0.40005 0 270)
			(size 0 0)
			(layers "F.Cu" "F.Mask" "F.Paste")
			(net "CLK_100M_PEX0_REF_R_DP")
		)
		(pad "2" smd circle
			(at 0.40005 0 270)
			(size 0 0)
			(layers "F.Cu" "F.Mask" "F.Paste")
			(net "CLK_100M_PEX0_REF_DP")
		)
	)
	(footprint ""
		(layer "F.Cu")
		(at 363.474 -203.835)
		(property "Reference" "R4673"
			(at 0 0 0)
			(layer "F.SilkS")
			(hide yes)
			(effects
				(font
					(size 1.27 1.27)
				)
			)
		)
		(property "Value" ""
			(at 0 0 0)
			(layer "F.Fab")
			(effects
				(font
					(size 1.27 1.27)
				)
			)
		)
		(duplicate_pad_numbers_are_jumpers no)
		(fp_line
			(start -0.7874 -0.4064)
			(end 0.7874 -0.4064)
			(stroke
				(width 0.1524)
				(type default)
			)
			(layer "F.SilkS")
		)
		(fp_line
			(start -0.7874 0.4064)
			(end -0.7874 -0.4064)
			(stroke
				(width 0.1524)
				(type default)
			)
			(layer "F.SilkS")
		)
		(fp_line
			(start 0.7874 -0.4064)
			(end 0.7874 0.4064)
			(stroke
				(width 0.1524)
				(type default)
			)
			(layer "F.SilkS")
		)
		(fp_line
			(start 0.7874 0.4064)
			(end -0.7874 0.4064)
			(stroke
				(width 0.1524)
				(type default)
			)
			(layer "F.SilkS")
		)
		(fp_line
			(start -0.67945 -0.305054)
			(end -0.12065 -0.305054)
			(stroke
				(width 0.1)
				(type default)
			)
			(layer "F.Fab")
		)
		(fp_line
			(start -0.67945 0.3048)
			(end -0.67945 -0.305054)
			(stroke
				(width 0.1)
				(type default)
			)
			(layer "F.Fab")
		)
		(fp_line
			(start -0.12065 -0.305054)
			(end -0.12065 -0.2794)
			(stroke
				(width 0.1)
				(type default)
			)
			(layer "F.Fab")
		)
		(fp_line
			(start -0.12065 -0.2794)
			(end 0.12065 -0.2794)
			(stroke
				(width 0.1)
				(type default)
			)
			(layer "F.Fab")
		)
		(fp_line
			(start -0.12065 0.2794)
			(end -0.12065 0.3048)
			(stroke
				(width 0.1)
				(type default)
			)
			(layer "F.Fab")
		)
		(fp_line
			(start -0.12065 0.3048)
			(end -0.67945 0.3048)
			(stroke
				(width 0.1)
				(type default)
			)
			(layer "F.Fab")
		)
		(fp_line
			(start 0.120396 0.2794)
			(end -0.12065 0.2794)
			(stroke
				(width 0.1)
				(type default)
			)
			(layer "F.Fab")
		)
		(fp_line
			(start 0.120396 0.3048)
			(end 0.120396 0.2794)
			(stroke
				(width 0.1)
				(type default)
			)
			(layer "F.Fab")
		)
		(fp_line
			(start 0.12065 -0.3048)
			(end 0.67945 -0.3048)
			(stroke
				(width 0.1)
				(type default)
			)
			(layer "F.Fab")
		)
		(fp_line
			(start 0.12065 -0.2794)
			(end 0.12065 -0.3048)
			(stroke
				(width 0.1)
				(type default)
			)
			(layer "F.Fab")
		)
		(fp_line
			(start 0.67945 -0.3048)
			(end 0.67945 0.3048)
			(stroke
				(width 0.1)
				(type default)
			)
			(layer "F.Fab")
		)
		(fp_line
			(start 0.67945 0.3048)
			(end 0.120396 0.3048)
			(stroke
				(width 0.1)
				(type default)
			)
			(layer "F.Fab")
		)
		(pad "1" smd circle
			(at -0.40005 0)
			(size 0 0)
			(layers "F.Cu" "F.Mask" "F.Paste")
			(net "PEX1_PCA9555_INT_N")
		)
		(pad "2" smd circle
			(at 0.40005 0)
			(size 0 0)
			(layers "F.Cu" "F.Mask" "F.Paste")
			(net "PEX1_PCA9555_0_INT_N")
		)
	)
	(footprint ""
		(layer "F.Cu")
		(at 248.93143 -92.096336 90)
		(property "Reference" "R1058"
			(at 0 0 90)
			(layer "F.SilkS")
			(hide yes)
			(effects
				(font
					(size 1.27 1.27)
				)
			)
		)
		(property "Value" ""
			(at 0 0 90)
			(layer "F.Fab")
			(effects
				(font
					(size 1.27 1.27)
				)
			)
		)
		(duplicate_pad_numbers_are_jumpers no)
		(fp_line
			(start 0.7874 -0.4064)
			(end 0.7874 0.4064)
			(stroke
				(width 0.1524)
				(type default)
			)
			(layer "F.SilkS")
		)
		(fp_line
			(start -0.7874 -0.4064)
			(end 0.7874 -0.4064)
			(stroke
				(width 0.1524)
				(type default)
			)
			(layer "F.SilkS")
		)
		(fp_line
			(start 0.7874 0.4064)
			(end -0.7874 0.4064)
			(stroke
				(width 0.1524)
				(type default)
			)
			(layer "F.SilkS")
		)
		(fp_line
			(start -0.7874 0.4064)
			(end -0.7874 -0.4064)
			(stroke
				(width 0.1524)
				(type default)
			)
			(layer "F.SilkS")
		)
		(fp_line
			(start -0.12065 -0.305054)
			(end -0.12065 -0.2794)
			(stroke
				(width 0.1)
				(type default)
			)
			(layer "F.Fab")
		)
		(fp_line
			(start -0.67945 -0.305054)
			(end -0.12065 -0.305054)
			(stroke
				(width 0.1)
				(type default)
			)
			(layer "F.Fab")
		)
		(fp_line
			(start 0.67945 -0.3048)
			(end 0.67945 0.3048)
			(stroke
				(width 0.1)
				(type default)
			)
			(layer "F.Fab")
		)
		(fp_line
			(start 0.12065 -0.3048)
			(end 0.67945 -0.3048)
			(stroke
				(width 0.1)
				(type default)
			)
			(layer "F.Fab")
		)
		(fp_line
			(start 0.12065 -0.2794)
			(end 0.12065 -0.3048)
			(stroke
				(width 0.1)
				(type default)
			)
			(layer "F.Fab")
		)
		(fp_line
			(start -0.12065 -0.2794)
			(end 0.12065 -0.2794)
			(stroke
				(width 0.1)
				(type default)
			)
			(layer "F.Fab")
		)
		(fp_line
			(start 0.120396 0.2794)
			(end -0.12065 0.2794)
			(stroke
				(width 0.1)
				(type default)
			)
			(layer "F.Fab")
		)
		(fp_line
			(start -0.12065 0.2794)
			(end -0.12065 0.3048)
			(stroke
				(width 0.1)
				(type default)
			)
			(layer "F.Fab")
		)
		(fp_line
			(start 0.67945 0.3048)
			(end 0.120396 0.3048)
			(stroke
				(width 0.1)
				(type default)
			)
			(layer "F.Fab")
		)
		(fp_line
			(start 0.120396 0.3048)
			(end 0.120396 0.2794)
			(stroke
				(width 0.1)
				(type default)
			)
			(layer "F.Fab")
		)
		(fp_line
			(start -0.12065 0.3048)
			(end -0.67945 0.3048)
			(stroke
				(width 0.1)
				(type default)
			)
			(layer "F.Fab")
		)
		(fp_line
			(start -0.67945 0.3048)
			(end -0.67945 -0.305054)
			(stroke
				(width 0.1)
				(type default)
			)
			(layer "F.Fab")
		)
		(pad "1" smd circle
			(at -0.40005 0 90)
			(size 0 0)
			(layers "F.Cu" "F.Mask" "F.Paste")
			(net "FM_CK440Q_DEV_25M_EN")
		)
		(pad "2" smd circle
			(at 0.40005 0 90)
			(size 0 0)
			(layers "F.Cu" "F.Mask" "F.Paste")
			(net "P3V3")
		)
	)
	(footprint ""
		(layer "F.Cu")
		(at 344.481404 -356.244906 90)
		(property "Reference" "C582"
			(at 0 0 90)
			(layer "F.SilkS")
			(hide yes)
			(effects
				(font
					(size 1.27 1.27)
				)
			)
		)
		(property "Value" ""
			(at 0 0 90)
			(layer "F.Fab")
			(effects
				(font
					(size 1.27 1.27)
				)
			)
		)
		(duplicate_pad_numbers_are_jumpers no)
		(fp_line
			(start 0.299974 -0.150114)
			(end 0.299974 0.150114)
			(stroke
				(width 0.1)
				(type default)
			)
			(layer "F.Fab")
		)
		(fp_line
			(start -0.299974 -0.150114)
			(end 0.299974 -0.150114)
			(stroke
				(width 0.1)
				(type default)
			)
			(layer "F.Fab")
		)
		(fp_line
			(start 0.299974 0.150114)
			(end -0.299974 0.150114)
			(stroke
				(width 0.1)
				(type default)
			)
			(layer "F.Fab")
		)
		(fp_line
			(start -0.299974 0.150114)
			(end -0.299974 -0.150114)
			(stroke
				(width 0.1)
				(type default)
			)
			(layer "F.Fab")
		)
		(pad "1" smd rect
			(at -0.2667 0 90)
			(size 0.3048 0.381)
			(layers "F.Cu" "F.Mask" "F.Paste")
			(net "P5E_PEX2_STN6_TX_DN<96>")
		)
		(pad "2" smd rect
			(at 0.2667 0 90)
			(size 0.3048 0.381)
			(layers "F.Cu" "F.Mask" "F.Paste")
			(net "P5E_PEX2_STN6_TX_C_DN<96>")
		)
	)
	(footprint ""
		(layer "F.Cu")
		(at 264.611358 -290.044632 -90)
		(property "Reference" "R4582"
			(at 0 0 270)
			(layer "F.SilkS")
			(hide yes)
			(effects
				(font
					(size 1.27 1.27)
				)
			)
		)
		(property "Value" ""
			(at 0 0 270)
			(layer "F.Fab")
			(effects
				(font
					(size 1.27 1.27)
				)
			)
		)
		(duplicate_pad_numbers_are_jumpers no)
		(fp_line
			(start -0.7874 0.4064)
			(end -0.7874 -0.4064)
			(stroke
				(width 0.1524)
				(type default)
			)
			(layer "F.SilkS")
		)
		(fp_line
			(start 0.7874 0.4064)
			(end -0.7874 0.4064)
			(stroke
				(width 0.1524)
				(type default)
			)
			(layer "F.SilkS")
		)
		(fp_line
			(start -0.7874 -0.4064)
			(end 0.7874 -0.4064)
			(stroke
				(width 0.1524)
				(type default)
			)
			(layer "F.SilkS")
		)
		(fp_line
			(start 0.7874 -0.4064)
			(end 0.7874 0.4064)
			(stroke
				(width 0.1524)
				(type default)
			)
			(layer "F.SilkS")
		)
		(fp_line
			(start -0.67945 0.3048)
			(end -0.67945 -0.305054)
			(stroke
				(width 0.1)
				(type default)
			)
			(layer "F.Fab")
		)
		(fp_line
			(start -0.12065 0.3048)
			(end -0.67945 0.3048)
			(stroke
				(width 0.1)
				(type default)
			)
			(layer "F.Fab")
		)
		(fp_line
			(start 0.120396 0.3048)
			(end 0.120396 0.2794)
			(stroke
				(width 0.1)
				(type default)
			)
			(layer "F.Fab")
		)
		(fp_line
			(start 0.67945 0.3048)
			(end 0.120396 0.3048)
			(stroke
				(width 0.1)
				(type default)
			)
			(layer "F.Fab")
		)
		(fp_line
			(start -0.12065 0.2794)
			(end -0.12065 0.3048)
			(stroke
				(width 0.1)
				(type default)
			)
			(layer "F.Fab")
		)
		(fp_line
			(start 0.120396 0.2794)
			(end -0.12065 0.2794)
			(stroke
				(width 0.1)
				(type default)
			)
			(layer "F.Fab")
		)
		(fp_line
			(start -0.12065 -0.2794)
			(end 0.12065 -0.2794)
			(stroke
				(width 0.1)
				(type default)
			)
			(layer "F.Fab")
		)
		(fp_line
			(start 0.12065 -0.2794)
			(end 0.12065 -0.3048)
			(stroke
				(width 0.1)
				(type default)
			)
			(layer "F.Fab")
		)
		(fp_line
			(start 0.12065 -0.3048)
			(end 0.67945 -0.3048)
			(stroke
				(width 0.1)
				(type default)
			)
			(layer "F.Fab")
		)
		(fp_line
			(start 0.67945 -0.3048)
			(end 0.67945 0.3048)
			(stroke
				(width 0.1)
				(type default)
			)
			(layer "F.Fab")
		)
		(fp_line
			(start -0.67945 -0.305054)
			(end -0.12065 -0.305054)
			(stroke
				(width 0.1)
				(type default)
			)
			(layer "F.Fab")
		)
		(fp_line
			(start -0.12065 -0.305054)
			(end -0.12065 -0.2794)
			(stroke
				(width 0.1)
				(type default)
			)
			(layer "F.Fab")
		)
		(pad "1" smd circle
			(at -0.40005 0 270)
			(size 0 0)
			(layers "F.Cu" "F.Mask" "F.Paste")
			(net "PCEPLL4_VDDA18_PEX2")
		)
		(pad "2" smd circle
			(at 0.40005 0 270)
			(size 0 0)
			(layers "F.Cu" "F.Mask" "F.Paste")
			(net "PCEPLL4_VDDA18_PEX2_R")
		)
	)
	(footprint ""
		(layer "F.Cu")
		(at 335.811368 -71.458074 -90)
		(property "Reference" "PD108"
			(at 4.148074 -2.822702 90)
			(unlocked yes)
			(layer "F.SilkS")
			(effects
				(font
					(size 0.7874 0.5842)
					(thickness 0.1524)
				)
				(justify left)
			)
		)
		(property "Value" ""
			(at 0 0 270)
			(layer "F.Fab")
			(effects
				(font
					(size 1.27 1.27)
				)
			)
		)
		(duplicate_pad_numbers_are_jumpers no)
		(fp_line
			(start -3.656584 1.970024)
			(end 4.240784 1.970024)
			(stroke
				(width 0.1524)
				(type default)
			)
			(layer "F.SilkS")
		)
		(fp_line
			(start 4.240784 1.970024)
			(end 4.240784 -1.970024)
			(stroke
				(width 0.1524)
				(type default)
			)
			(layer "F.SilkS")
		)
		(fp_line
			(start -3.656584 -1.970024)
			(end -3.656584 1.970024)
			(stroke
				(width 0.1524)
				(type default)
			)
			(layer "F.SilkS")
		)
		(fp_line
			(start 4.240784 -1.970024)
			(end -3.656584 -1.970024)
			(stroke
				(width 0.1524)
				(type default)
			)
			(layer "F.SilkS")
		)
		(fp_poly
			(pts
				(xy 3.580384 1.970024) (xy 3.580384 -1.970024) (xy 4.240784 -1.970024) (xy 4.240784 1.970024)
			)
			(stroke
				(width 0)
				(type default)
			)
			(fill yes)
			(layer "F.SilkS")
		)
		(fp_line
			(start -2.3749 1.970024)
			(end 2.3749 1.970024)
			(stroke
				(width 0.1)
				(type default)
			)
			(layer "F.Fab")
		)
		(fp_line
			(start 2.3749 1.970024)
			(end 2.3749 -1.970024)
			(stroke
				(width 0.1)
				(type default)
			)
			(layer "F.Fab")
		)
		(fp_line
			(start -2.3749 -1.970024)
			(end -2.3749 1.970024)
			(stroke
				(width 0.1)
				(type default)
			)
			(layer "F.Fab")
		)
		(fp_line
			(start 2.3749 -1.970024)
			(end -2.3749 -1.970024)
			(stroke
				(width 0.1)
				(type default)
			)
			(layer "F.Fab")
		)
		(fp_text user "+"
			(at -4.9784 -0.23495 270)
			(unlocked yes)
			(layer "F.Fab")
			(effects
				(font
					(size 1.905 1.4224)
					(thickness 0.1524)
				)
				(justify left)
			)
		)
		(fp_text user "-"
			(at 4.1656 -0.23495 270)
			(unlocked yes)
			(layer "F.Fab")
			(effects
				(font
					(size 1.905 1.4224)
					(thickness 0.1524)
				)
				(justify left)
			)
		)
		(pad "A" smd rect
			(at -2.450084 0 270)
			(size 2.159 2.2606)
			(layers "F.Cu" "F.Mask" "F.Paste")
			(net "GND")
		)
		(pad "C" smd rect
			(at 2.450084 0 270)
			(size 2.159 2.2606)
			(layers "F.Cu" "F.Mask" "F.Paste")
			(net "P12V_AUX")
		)
	)
	(footprint ""
		(layer "F.Cu")
		(at 323.23405 -306.074572 90)
		(property "Reference" "R1373"
			(at 0 0 90)
			(layer "F.SilkS")
			(hide yes)
			(effects
				(font
					(size 1.27 1.27)
				)
			)
		)
		(property "Value" ""
			(at 0 0 90)
			(layer "F.Fab")
			(effects
				(font
					(size 1.27 1.27)
				)
			)
		)
		(duplicate_pad_numbers_are_jumpers no)
		(fp_line
			(start 0.7874 -0.4064)
			(end 0.7874 0.4064)
			(stroke
				(width 0.1524)
				(type default)
			)
			(layer "F.SilkS")
		)
		(fp_line
			(start -0.7874 -0.4064)
			(end 0.7874 -0.4064)
			(stroke
				(width 0.1524)
				(type default)
			)
			(layer "F.SilkS")
		)
		(fp_line
			(start 0.7874 0.4064)
			(end -0.7874 0.4064)
			(stroke
				(width 0.1524)
				(type default)
			)
			(layer "F.SilkS")
		)
		(fp_line
			(start -0.7874 0.4064)
			(end -0.7874 -0.4064)
			(stroke
				(width 0.1524)
				(type default)
			)
			(layer "F.SilkS")
		)
		(fp_line
			(start -0.12065 -0.305054)
			(end -0.12065 -0.2794)
			(stroke
				(width 0.1)
				(type default)
			)
			(layer "F.Fab")
		)
		(fp_line
			(start -0.67945 -0.305054)
			(end -0.12065 -0.305054)
			(stroke
				(width 0.1)
				(type default)
			)
			(layer "F.Fab")
		)
		(fp_line
			(start 0.67945 -0.3048)
			(end 0.67945 0.3048)
			(stroke
				(width 0.1)
				(type default)
			)
			(layer "F.Fab")
		)
		(fp_line
			(start 0.12065 -0.3048)
			(end 0.67945 -0.3048)
			(stroke
				(width 0.1)
				(type default)
			)
			(layer "F.Fab")
		)
		(fp_line
			(start 0.12065 -0.2794)
			(end 0.12065 -0.3048)
			(stroke
				(width 0.1)
				(type default)
			)
			(layer "F.Fab")
		)
		(fp_line
			(start -0.12065 -0.2794)
			(end 0.12065 -0.2794)
			(stroke
				(width 0.1)
				(type default)
			)
			(layer "F.Fab")
		)
		(fp_line
			(start 0.120396 0.2794)
			(end -0.12065 0.2794)
			(stroke
				(width 0.1)
				(type default)
			)
			(layer "F.Fab")
		)
		(fp_line
			(start -0.12065 0.2794)
			(end -0.12065 0.3048)
			(stroke
				(width 0.1)
				(type default)
			)
			(layer "F.Fab")
		)
		(fp_line
			(start 0.67945 0.3048)
			(end 0.120396 0.3048)
			(stroke
				(width 0.1)
				(type default)
			)
			(layer "F.Fab")
		)
		(fp_line
			(start 0.120396 0.3048)
			(end 0.120396 0.2794)
			(stroke
				(width 0.1)
				(type default)
			)
			(layer "F.Fab")
		)
		(fp_line
			(start -0.12065 0.3048)
			(end -0.67945 0.3048)
			(stroke
				(width 0.1)
				(type default)
			)
			(layer "F.Fab")
		)
		(fp_line
			(start -0.67945 0.3048)
			(end -0.67945 -0.305054)
			(stroke
				(width 0.1)
				(type default)
			)
			(layer "F.Fab")
		)
		(pad "1" smd circle
			(at -0.40005 0 90)
			(size 0 0)
			(layers "F.Cu" "F.Mask" "F.Paste")
			(net "PEX2_SPARE1")
		)
		(pad "2" smd circle
			(at 0.40005 0 90)
			(size 0 0)
			(layers "F.Cu" "F.Mask" "F.Paste")
			(net "P1V8_PEX")
		)
	)
	(footprint ""
		(layer "F.Cu")
		(at 363.793532 -357.96601 90)
		(property "Reference" "C4164"
			(at 0 0 90)
			(layer "F.SilkS")
			(hide yes)
			(effects
				(font
					(size 1.27 1.27)
				)
			)
		)
		(property "Value" ""
			(at 0 0 90)
			(layer "F.Fab")
			(effects
				(font
					(size 1.27 1.27)
				)
			)
		)
		(duplicate_pad_numbers_are_jumpers no)
		(fp_line
			(start 0.7874 -0.4064)
			(end 0.7874 0.4064)
			(stroke
				(width 0.1524)
				(type default)
			)
			(layer "F.SilkS")
		)
		(fp_line
			(start -0.7874 -0.4064)
			(end 0.7874 -0.4064)
			(stroke
				(width 0.1524)
				(type default)
			)
			(layer "F.SilkS")
		)
		(fp_line
			(start 0.7874 0.4064)
			(end -0.7874 0.4064)
			(stroke
				(width 0.1524)
				(type default)
			)
			(layer "F.SilkS")
		)
		(fp_line
			(start -0.7874 0.4064)
			(end -0.7874 -0.4064)
			(stroke
				(width 0.1524)
				(type default)
			)
			(layer "F.SilkS")
		)
		(fp_line
			(start -0.12065 -0.305054)
			(end -0.12065 -0.2794)
			(stroke
				(width 0.1)
				(type default)
			)
			(layer "F.Fab")
		)
		(fp_line
			(start -0.67945 -0.305054)
			(end -0.12065 -0.305054)
			(stroke
				(width 0.1)
				(type default)
			)
			(layer "F.Fab")
		)
		(fp_line
			(start 0.67945 -0.3048)
			(end 0.67945 0.3048)
			(stroke
				(width 0.1)
				(type default)
			)
			(layer "F.Fab")
		)
		(fp_line
			(start 0.12065 -0.3048)
			(end 0.67945 -0.3048)
			(stroke
				(width 0.1)
				(type default)
			)
			(layer "F.Fab")
		)
		(fp_line
			(start 0.12065 -0.2794)
			(end 0.12065 -0.3048)
			(stroke
				(width 0.1)
				(type default)
			)
			(layer "F.Fab")
		)
		(fp_line
			(start -0.12065 -0.2794)
			(end 0.12065 -0.2794)
			(stroke
				(width 0.1)
				(type default)
			)
			(layer "F.Fab")
		)
		(fp_line
			(start 0.120396 0.2794)
			(end -0.12065 0.2794)
			(stroke
				(width 0.1)
				(type default)
			)
			(layer "F.Fab")
		)
		(fp_line
			(start -0.12065 0.2794)
			(end -0.12065 0.3048)
			(stroke
				(width 0.1)
				(type default)
			)
			(layer "F.Fab")
		)
		(fp_line
			(start 0.67945 0.3048)
			(end 0.120396 0.3048)
			(stroke
				(width 0.1)
				(type default)
			)
			(layer "F.Fab")
		)
		(fp_line
			(start 0.120396 0.3048)
			(end 0.120396 0.2794)
			(stroke
				(width 0.1)
				(type default)
			)
			(layer "F.Fab")
		)
		(fp_line
			(start -0.12065 0.3048)
			(end -0.67945 0.3048)
			(stroke
				(width 0.1)
				(type default)
			)
			(layer "F.Fab")
		)
		(fp_line
			(start -0.67945 0.3048)
			(end -0.67945 -0.305054)
			(stroke
				(width 0.1)
				(type default)
			)
			(layer "F.Fab")
		)
		(pad "1" smd circle
			(at -0.40005 0 90)
			(size 0 0)
			(layers "F.Cu" "F.Mask" "F.Paste")
			(net "GND")
		)
		(pad "2" smd circle
			(at 0.40005 0 90)
			(size 0 0)
			(layers "F.Cu" "F.Mask" "F.Paste")
			(net "MB_SWB_PWR_EN")
		)
	)
	(footprint ""
		(layer "F.Cu")
		(at 3.856736 -37.795962 -90)
		(property "Reference" "PR6920"
			(at 0 0 270)
			(layer "F.SilkS")
			(hide yes)
			(effects
				(font
					(size 1.27 1.27)
				)
			)
		)
		(property "Value" ""
			(at 0 0 270)
			(layer "F.Fab")
			(effects
				(font
					(size 1.27 1.27)
				)
			)
		)
		(duplicate_pad_numbers_are_jumpers no)
		(fp_line
			(start -0.7874 0.4064)
			(end -0.7874 -0.4064)
			(stroke
				(width 0.1524)
				(type default)
			)
			(layer "F.SilkS")
		)
		(fp_line
			(start 0.7874 0.4064)
			(end -0.7874 0.4064)
			(stroke
				(width 0.1524)
				(type default)
			)
			(layer "F.SilkS")
		)
		(fp_line
			(start -0.7874 -0.4064)
			(end 0.7874 -0.4064)
			(stroke
				(width 0.1524)
				(type default)
			)
			(layer "F.SilkS")
		)
		(fp_line
			(start 0.7874 -0.4064)
			(end 0.7874 0.4064)
			(stroke
				(width 0.1524)
				(type default)
			)
			(layer "F.SilkS")
		)
		(fp_line
			(start -0.67945 0.3048)
			(end -0.67945 -0.305054)
			(stroke
				(width 0.1)
				(type default)
			)
			(layer "F.Fab")
		)
		(fp_line
			(start -0.12065 0.3048)
			(end -0.67945 0.3048)
			(stroke
				(width 0.1)
				(type default)
			)
			(layer "F.Fab")
		)
		(fp_line
			(start 0.120396 0.3048)
			(end 0.120396 0.2794)
			(stroke
				(width 0.1)
				(type default)
			)
			(layer "F.Fab")
		)
		(fp_line
			(start 0.67945 0.3048)
			(end 0.120396 0.3048)
			(stroke
				(width 0.1)
				(type default)
			)
			(layer "F.Fab")
		)
		(fp_line
			(start -0.12065 0.2794)
			(end -0.12065 0.3048)
			(stroke
				(width 0.1)
				(type default)
			)
			(layer "F.Fab")
		)
		(fp_line
			(start 0.120396 0.2794)
			(end -0.12065 0.2794)
			(stroke
				(width 0.1)
				(type default)
			)
			(layer "F.Fab")
		)
		(fp_line
			(start -0.12065 -0.2794)
			(end 0.12065 -0.2794)
			(stroke
				(width 0.1)
				(type default)
			)
			(layer "F.Fab")
		)
		(fp_line
			(start 0.12065 -0.2794)
			(end 0.12065 -0.3048)
			(stroke
				(width 0.1)
				(type default)
			)
			(layer "F.Fab")
		)
		(fp_line
			(start 0.12065 -0.3048)
			(end 0.67945 -0.3048)
			(stroke
				(width 0.1)
				(type default)
			)
			(layer "F.Fab")
		)
		(fp_line
			(start 0.67945 -0.3048)
			(end 0.67945 0.3048)
			(stroke
				(width 0.1)
				(type default)
			)
			(layer "F.Fab")
		)
		(fp_line
			(start -0.67945 -0.305054)
			(end -0.12065 -0.305054)
			(stroke
				(width 0.1)
				(type default)
			)
			(layer "F.Fab")
		)
		(fp_line
			(start -0.12065 -0.305054)
			(end -0.12065 -0.2794)
			(stroke
				(width 0.1)
				(type default)
			)
			(layer "F.Fab")
		)
		(pad "1" smd circle
			(at -0.40005 0 270)
			(size 0 0)
			(layers "F.Cu" "F.Mask" "F.Paste")
			(net "P3V3_SSD0_CO_ILIMIT")
		)
		(pad "2" smd circle
			(at 0.40005 0 270)
			(size 0 0)
			(layers "F.Cu" "F.Mask" "F.Paste")
			(net "GND")
		)
	)
	(footprint ""
		(layer "F.Cu")
		(at 214.757 -202.692)
		(property "Reference" "U120"
			(at 0.338328 -2.096008 0)
			(unlocked yes)
			(layer "F.SilkS")
			(effects
				(font
					(size 0.7874 0.5842)
					(thickness 0.1524)
				)
				(justify left)
			)
		)
		(property "Value" ""
			(at 0 0 0)
			(layer "F.Fab")
			(effects
				(font
					(size 1.27 1.27)
				)
			)
		)
		(duplicate_pad_numbers_are_jumpers no)
		(fp_line
			(start -1.3208 -1.525016)
			(end -0.508 -1.525016)
			(stroke
				(width 0.1524)
				(type default)
			)
			(layer "F.SilkS")
		)
		(fp_line
			(start -1.3208 1.525016)
			(end -1.3208 -1.525016)
			(stroke
				(width 0.1524)
				(type default)
			)
			(layer "F.SilkS")
		)
		(fp_line
			(start -0.508 -1.525016)
			(end 0 -0.999998)
			(stroke
				(width 0.1524)
				(type default)
			)
			(layer "F.SilkS")
		)
		(fp_line
			(start 0 -0.999998)
			(end 0.508 -1.525016)
			(stroke
				(width 0.1524)
				(type default)
			)
			(layer "F.SilkS")
		)
		(fp_line
			(start 0.508 -1.525016)
			(end 1.3208 -1.525016)
			(stroke
				(width 0.1524)
				(type default)
			)
			(layer "F.SilkS")
		)
		(fp_line
			(start 1.3208 -1.525016)
			(end 1.3208 1.525016)
			(stroke
				(width 0.1524)
				(type default)
			)
			(layer "F.SilkS")
		)
		(fp_line
			(start 1.3208 1.525016)
			(end -1.3208 1.525016)
			(stroke
				(width 0.1524)
				(type default)
			)
			(layer "F.SilkS")
		)
		(fp_poly
			(pts
				(xy -2.877566 -1.364996) (xy -3.685794 -1.634236) (xy -3.14706 -2.173224)
			)
			(stroke
				(width 0)
				(type default)
			)
			(fill yes)
			(layer "F.SilkS")
		)
		(fp_line
			(start -3.037078 -1.20777)
			(end -1.524 -1.20777)
			(stroke
				(width 0.1)
				(type default)
			)
			(layer "F.Fab")
		)
		(fp_line
			(start -3.037078 1.203706)
			(end -3.037078 -1.20777)
			(stroke
				(width 0.1)
				(type default)
			)
			(layer "F.Fab")
		)
		(fp_line
			(start -1.5494 1.203706)
			(end -3.037078 1.203706)
			(stroke
				(width 0.1)
				(type default)
			)
			(layer "F.Fab")
		)
		(fp_line
			(start -1.5494 1.5494)
			(end -1.5494 1.203706)
			(stroke
				(width 0.1)
				(type default)
			)
			(layer "F.Fab")
		)
		(fp_line
			(start -1.524 -1.524)
			(end 1.524 -1.524)
			(stroke
				(width 0.1)
				(type default)
			)
			(layer "F.Fab")
		)
		(fp_line
			(start -1.524 -1.20777)
			(end -1.524 -1.524)
			(stroke
				(width 0.1)
				(type default)
			)
			(layer "F.Fab")
		)
		(fp_line
			(start 1.524 -1.524)
			(end 1.524 -1.20777)
			(stroke
				(width 0.1)
				(type default)
			)
			(layer "F.Fab")
		)
		(fp_line
			(start 1.524 -1.20777)
			(end 3.0353 -1.20777)
			(stroke
				(width 0.1)
				(type default)
			)
			(layer "F.Fab")
		)
		(fp_line
			(start 1.524 1.208786)
			(end 1.524 1.5494)
			(stroke
				(width 0.1)
				(type default)
			)
			(layer "F.Fab")
		)
		(fp_line
			(start 1.524 1.5494)
			(end -1.5494 1.5494)
			(stroke
				(width 0.1)
				(type default)
			)
			(layer "F.Fab")
		)
		(fp_line
			(start 3.0353 -1.20777)
			(end 3.0353 1.208786)
			(stroke
				(width 0.1)
				(type default)
			)
			(layer "F.Fab")
		)
		(fp_line
			(start 3.0353 1.208786)
			(end 1.524 1.208786)
			(stroke
				(width 0.1)
				(type default)
			)
			(layer "F.Fab")
		)
		(fp_poly
			(pts
				(xy -3.175 -1.016) (xy -3.937 -0.635) (xy -3.937 -1.397)
			)
			(stroke
				(width 0)
				(type default)
			)
			(fill yes)
			(layer "F.Fab")
		)
		(pad "1" smd rect
			(at -2.234946 -0.975106 270)
			(size 0.3556 1.4986)
			(layers "F.Cu" "F.Mask" "F.Paste")
			(net "P1V2_AUX")
		)
		(pad "2" smd rect
			(at -2.234946 -0.32512 270)
			(size 0.3556 1.4986)
			(layers "F.Cu" "F.Mask" "F.Paste")
			(net "SMB_NIC5_R_SDA")
		)
		(pad "3" smd rect
			(at -2.234946 0.32512 270)
			(size 0.3556 1.4986)
			(layers "F.Cu" "F.Mask" "F.Paste")
			(net "SMB_NIC5_R_SCL")
		)
		(pad "4" smd rect
			(at -2.234946 0.975106 270)
			(size 0.3556 1.4986)
			(layers "F.Cu" "F.Mask" "F.Paste")
			(net "GND")
		)
		(pad "5" smd rect
			(at 2.234946 0.975106 270)
			(size 0.3556 1.4986)
			(layers "F.Cu" "F.Mask" "F.Paste")
			(net "SMB_NIC5_LS_EN")
		)
		(pad "6" smd rect
			(at 2.234946 0.32512 270)
			(size 0.3556 1.4986)
			(layers "F.Cu" "F.Mask" "F.Paste")
			(net "SMB_NIC5_LS_R_SCL")
		)
		(pad "7" smd rect
			(at 2.234946 -0.32512 270)
			(size 0.3556 1.4986)
			(layers "F.Cu" "F.Mask" "F.Paste")
			(net "SMB_NIC5_LS_R_SDA")
		)
		(pad "8" smd rect
			(at 2.234946 -0.975106 270)
			(size 0.3556 1.4986)
			(layers "F.Cu" "F.Mask" "F.Paste")
			(net "P3V3_NIC5")
		)
	)
	(footprint ""
		(layer "F.Cu")
		(at 98.487484 -25.342342 -90)
		(property "Reference" "R420"
			(at 0 0 270)
			(layer "F.SilkS")
			(hide yes)
			(effects
				(font
					(size 1.27 1.27)
				)
			)
		)
		(property "Value" ""
			(at 0 0 270)
			(layer "F.Fab")
			(effects
				(font
					(size 1.27 1.27)
				)
			)
		)
		(duplicate_pad_numbers_are_jumpers no)
		(fp_line
			(start -0.7874 0.4064)
			(end -0.7874 -0.4064)
			(stroke
				(width 0.1524)
				(type default)
			)
			(layer "F.SilkS")
		)
		(fp_line
			(start 0.7874 0.4064)
			(end -0.7874 0.4064)
			(stroke
				(width 0.1524)
				(type default)
			)
			(layer "F.SilkS")
		)
		(fp_line
			(start -0.7874 -0.4064)
			(end 0.7874 -0.4064)
			(stroke
				(width 0.1524)
				(type default)
			)
			(layer "F.SilkS")
		)
		(fp_line
			(start 0.7874 -0.4064)
			(end 0.7874 0.4064)
			(stroke
				(width 0.1524)
				(type default)
			)
			(layer "F.SilkS")
		)
		(fp_line
			(start -0.67945 0.3048)
			(end -0.67945 -0.305054)
			(stroke
				(width 0.1)
				(type default)
			)
			(layer "F.Fab")
		)
		(fp_line
			(start -0.12065 0.3048)
			(end -0.67945 0.3048)
			(stroke
				(width 0.1)
				(type default)
			)
			(layer "F.Fab")
		)
		(fp_line
			(start 0.120396 0.3048)
			(end 0.120396 0.2794)
			(stroke
				(width 0.1)
				(type default)
			)
			(layer "F.Fab")
		)
		(fp_line
			(start 0.67945 0.3048)
			(end 0.120396 0.3048)
			(stroke
				(width 0.1)
				(type default)
			)
			(layer "F.Fab")
		)
		(fp_line
			(start -0.12065 0.2794)
			(end -0.12065 0.3048)
			(stroke
				(width 0.1)
				(type default)
			)
			(layer "F.Fab")
		)
		(fp_line
			(start 0.120396 0.2794)
			(end -0.12065 0.2794)
			(stroke
				(width 0.1)
				(type default)
			)
			(layer "F.Fab")
		)
		(fp_line
			(start -0.12065 -0.2794)
			(end 0.12065 -0.2794)
			(stroke
				(width 0.1)
				(type default)
			)
			(layer "F.Fab")
		)
		(fp_line
			(start 0.12065 -0.2794)
			(end 0.12065 -0.3048)
			(stroke
				(width 0.1)
				(type default)
			)
			(layer "F.Fab")
		)
		(fp_line
			(start 0.12065 -0.3048)
			(end 0.67945 -0.3048)
			(stroke
				(width 0.1)
				(type default)
			)
			(layer "F.Fab")
		)
		(fp_line
			(start 0.67945 -0.3048)
			(end 0.67945 0.3048)
			(stroke
				(width 0.1)
				(type default)
			)
			(layer "F.Fab")
		)
		(fp_line
			(start -0.67945 -0.305054)
			(end -0.12065 -0.305054)
			(stroke
				(width 0.1)
				(type default)
			)
			(layer "F.Fab")
		)
		(fp_line
			(start -0.12065 -0.305054)
			(end -0.12065 -0.2794)
			(stroke
				(width 0.1)
				(type default)
			)
			(layer "F.Fab")
		)
		(pad "1" smd circle
			(at -0.40005 0 270)
			(size 0 0)
			(layers "F.Cu" "F.Mask" "F.Paste")
			(net "GND")
		)
		(pad "2" smd circle
			(at 0.40005 0 270)
			(size 0 0)
			(layers "F.Cu" "F.Mask" "F.Paste")
			(net "DUALPORT_N_SSD3")
		)
	)
	(footprint ""
		(layer "F.Cu")
		(at 115.910106 -412.090108)
		(property "Reference" "J12"
			(at 26.161492 4.719066 90)
			(unlocked yes)
			(layer "F.SilkS")
			(effects
				(font
					(size 2.032 1.524)
					(thickness 0.1524)
				)
				(justify left)
			)
		)
		(property "Value" ""
			(at 0 0 0)
			(layer "F.Fab")
			(effects
				(font
					(size 1.27 1.27)
				)
			)
		)
		(duplicate_pad_numbers_are_jumpers no)
		(fp_line
			(start -4.249928 -16.999966)
			(end 24.45004 -16.999966)
			(stroke
				(width 0.1524)
				(type default)
			)
			(layer "F.SilkS")
		)
		(fp_line
			(start -4.249928 43.310302)
			(end -4.249928 -16.999966)
			(stroke
				(width 0.1524)
				(type default)
			)
			(layer "F.SilkS")
		)
		(fp_line
			(start -4.249928 50.099976)
			(end -4.249928 44.874688)
			(stroke
				(width 0.1524)
				(type default)
			)
			(layer "F.SilkS")
		)
		(fp_line
			(start -1.249934 -13.999972)
			(end -1.249934 46.03369)
			(stroke
				(width 0.1524)
				(type default)
			)
			(layer "F.SilkS")
		)
		(fp_line
			(start -1.249934 -6.500114)
			(end 21.450046 -6.500114)
			(stroke
				(width 0.1524)
				(type default)
			)
			(layer "F.SilkS")
		)
		(fp_line
			(start -1.249934 47.099982)
			(end 21.450046 47.099982)
			(stroke
				(width 0.1524)
				(type default)
			)
			(layer "F.SilkS")
		)
		(fp_line
			(start 21.450046 -13.999972)
			(end -1.249934 -13.999972)
			(stroke
				(width 0.1524)
				(type default)
			)
			(layer "F.SilkS")
		)
		(fp_line
			(start 21.450046 46.066456)
			(end 21.450046 -13.999972)
			(stroke
				(width 0.1524)
				(type default)
			)
			(layer "F.SilkS")
		)
		(fp_line
			(start 24.45004 -16.999966)
			(end 24.45004 45.99686)
			(stroke
				(width 0.1524)
				(type default)
			)
			(layer "F.SilkS")
		)
		(fp_line
			(start 24.45004 47.314866)
			(end 24.45004 50.099976)
			(stroke
				(width 0.1524)
				(type default)
			)
			(layer "F.SilkS")
		)
		(fp_line
			(start 24.45004 50.099976)
			(end -4.249928 50.099976)
			(stroke
				(width 0.1524)
				(type default)
			)
			(layer "F.SilkS")
		)
		(fp_poly
			(pts
				(xy -2.413 -0.508) (xy -2.413 0.508) (xy -1.397 0)
			)
			(stroke
				(width 0)
				(type default)
			)
			(fill yes)
			(layer "F.SilkS")
		)
		(fp_line
			(start -4.249928 -16.999966)
			(end 24.45004 -16.999966)
			(stroke
				(width 0.1524)
				(type default)
			)
			(layer "B.SilkS")
		)
		(fp_line
			(start -4.249928 50.099976)
			(end -4.249928 -16.999966)
			(stroke
				(width 0.1524)
				(type default)
			)
			(layer "B.SilkS")
		)
		(fp_line
			(start 24.45004 -16.999966)
			(end 24.45004 50.099976)
			(stroke
				(width 0.1524)
				(type default)
			)
			(layer "B.SilkS")
		)
		(fp_line
			(start 24.45004 50.099976)
			(end -4.249928 50.099976)
			(stroke
				(width 0.1524)
				(type default)
			)
			(layer "B.SilkS")
		)
		(fp_line
			(start -4.249928 -16.999966)
			(end 24.45004 -16.999966)
			(stroke
				(width 0.1)
				(type default)
			)
			(layer "B.Fab")
		)
		(fp_line
			(start -4.249928 50.099976)
			(end -4.249928 -16.999966)
			(stroke
				(width 0.1)
				(type default)
			)
			(layer "B.Fab")
		)
		(fp_line
			(start 24.45004 -16.999966)
			(end 24.45004 50.099976)
			(stroke
				(width 0.1)
				(type default)
			)
			(layer "B.Fab")
		)
		(fp_line
			(start 24.45004 50.099976)
			(end -4.249928 50.099976)
			(stroke
				(width 0.1)
				(type default)
			)
			(layer "B.Fab")
		)
		(fp_line
			(start -1.249934 -13.999972)
			(end -1.249934 47.099982)
			(stroke
				(width 0.1)
				(type default)
			)
			(layer "F.Fab")
		)
		(fp_line
			(start -1.249934 47.099982)
			(end 21.450046 47.099982)
			(stroke
				(width 0.1)
				(type default)
			)
			(layer "F.Fab")
		)
		(fp_line
			(start 21.450046 -13.999972)
			(end -1.249934 -13.999972)
			(stroke
				(width 0.1)
				(type default)
			)
			(layer "F.Fab")
		)
		(fp_line
			(start 21.450046 47.099982)
			(end 21.450046 -13.999972)
			(stroke
				(width 0.1)
				(type default)
			)
			(layer "F.Fab")
		)
		(fp_poly
			(pts
				(xy -2.413 -0.508) (xy -2.413 0.508) (xy -1.397 0)
			)
			(stroke
				(width 0)
				(type default)
			)
			(fill yes)
			(layer "F.Fab")
		)
		(fp_text user "PRESS-FIT"
			(at 23.264876 43.098974 90)
			(unlocked yes)
			(layer "F.SilkS")
			(effects
				(font
					(size 1.905 1.4224)
					(thickness 0.1524)
				)
				(justify left)
			)
		)
		(fp_text user "PRESS-FIT"
			(at -5.773166 27.788108 90)
			(unlocked yes)
			(layer "B.SilkS")
			(effects
				(font
					(size 1.905 1.4224)
					(thickness 0.1524)
				)
				(justify left mirror)
			)
		)
		(fp_text user "PRESS-FIT"
			(at 18.326862 48.74895 0)
			(unlocked yes)
			(layer "B.Fab")
			(effects
				(font
					(size 1.905 1.4224)
					(thickness 0.1524)
				)
				(justify left mirror)
			)
		)
		(fp_text user "PRESS-FIT"
			(at 1.5875 48.73625 0)
			(unlocked yes)
			(layer "F.Fab")
			(effects
				(font
					(size 1.905 1.4224)
					(thickness 0.1524)
				)
				(justify left)
			)
		)
		(pad "A1" thru_hole rect
			(at 0 0 180)
			(size 0.71628 0.71628)
			(drill 0.30988)
			(layers "*.Cu" "*.Mask")
			(remove_unused_layers no)
			(net "GPU_FPGA_EROT_RECOV_N")
			(clearance 0.0508)
			(thermal_gap 0.0508)
			(padstack
				(mode front_inner_back)
				(layer "Inner"
					(shape circle)
					(size 0.71628 0.71628)
					(clearance 0.0508)
				)
				(layer "B.Cu"
					(shape rect)
					(size 0.71628 0.71628)
					(clearance 0.0508)
				)
			)
		)
		(pad "A2" thru_hole circle
			(at 2.199894 0.199898 180)
			(size 0.906272 0.906272)
			(drill 0.499872)
			(layers "*.Cu" "*.Mask")
			(remove_unused_layers no)
			(net "GND")
			(clearance 0.0508)
			(thermal_gap 0.0508)
		)
		(pad "A3" thru_hole circle
			(at 4.400042 0 180)
			(size 0.71628 0.71628)
			(drill 0.30988)
			(layers "*.Cu" "*.Mask")
			(remove_unused_layers no)
			(net "PRSNT_GPU_HMC_R_N")
			(clearance 0.0508)
			(thermal_gap 0.0508)
		)
		(pad "A4" thru_hole circle
			(at 6.599936 0.199898 180)
			(size 0.906272 0.906272)
			(drill 0.499872)
			(layers "*.Cu" "*.Mask")
			(remove_unused_layers no)
			(net "GND")
			(clearance 0.0508)
			(thermal_gap 0.0508)
		)
		(pad "A5" thru_hole circle
			(at 8.800084 0 180)
			(size 0.71628 0.71628)
			(drill 0.30988)
			(layers "*.Cu" "*.Mask")
			(remove_unused_layers no)
			(net "GPU_BASE_HMC_READY_R")
			(clearance 0.0508)
			(thermal_gap 0.0508)
		)
		(pad "A6" thru_hole circle
			(at 10.999978 0.199898 180)
			(size 0.906272 0.906272)
			(drill 0.499872)
			(layers "*.Cu" "*.Mask")
			(remove_unused_layers no)
			(net "GND")
			(clearance 0.0508)
			(thermal_gap 0.0508)
		)
		(pad "A7" thru_hole circle
			(at 13.199872 0 180)
			(size 0.71628 0.71628)
			(drill 0.30988)
			(layers "*.Cu" "*.Mask")
			(remove_unused_layers no)
			(net "GPU_BASE_STBY_EN")
			(clearance 0.0508)
			(thermal_gap 0.0508)
		)
		(pad "A8" thru_hole circle
			(at 15.40002 0.199898 180)
			(size 0.906272 0.906272)
			(drill 0.499872)
			(layers "*.Cu" "*.Mask")
			(remove_unused_layers no)
			(net "GND")
			(clearance 0.0508)
			(thermal_gap 0.0508)
		)
		(pad "A9" thru_hole circle
			(at 17.599914 0 180)
			(size 0.71628 0.71628)
			(drill 0.30988)
			(layers "*.Cu" "*.Mask")
			(remove_unused_layers no)
			(net "SMB_MB_BMC_SDA")
			(clearance 0.0508)
			(thermal_gap 0.0508)
		)
		(pad "A10" thru_hole circle
			(at 19.800062 0.199898 180)
			(size 0.906272 0.906272)
			(drill 0.499872)
			(layers "*.Cu" "*.Mask")
			(remove_unused_layers no)
			(net "GND")
			(clearance 0.0508)
			(thermal_gap 0.0508)
		)
		(pad "B1" thru_hole circle
			(at 0 1.299972 180)
			(size 0.906272 0.906272)
			(drill 0.499872)
			(layers "*.Cu" "*.Mask")
			(remove_unused_layers no)
			(net "GND")
			(clearance 0.0508)
			(thermal_gap 0.0508)
		)
		(pad "B3" thru_hole circle
			(at 4.400042 1.299972 180)
			(size 0.906272 0.906272)
			(drill 0.499872)
			(layers "*.Cu" "*.Mask")
			(remove_unused_layers no)
			(net "GND")
			(clearance 0.0508)
			(thermal_gap 0.0508)
		)
		(pad "B5" thru_hole circle
			(at 8.800084 1.299972 180)
			(size 0.906272 0.906272)
			(drill 0.499872)
			(layers "*.Cu" "*.Mask")
			(remove_unused_layers no)
			(net "GND")
			(clearance 0.0508)
			(thermal_gap 0.0508)
		)
		(pad "B7" thru_hole circle
			(at 13.199872 1.299972 180)
			(size 0.906272 0.906272)
			(drill 0.499872)
			(layers "*.Cu" "*.Mask")
			(remove_unused_layers no)
			(net "GND")
			(clearance 0.0508)
			(thermal_gap 0.0508)
		)
		(pad "B9" thru_hole circle
			(at 17.599914 1.299972 180)
			(size 0.906272 0.906272)
			(drill 0.499872)
			(layers "*.Cu" "*.Mask")
			(remove_unused_layers no)
			(net "GND")
			(clearance 0.0508)
			(thermal_gap 0.0508)
		)
		(pad "B10" thru_hole circle
			(at 19.800062 1.500124 180)
			(size 0.71628 0.71628)
			(drill 0.30988)
			(layers "*.Cu" "*.Mask")
			(remove_unused_layers no)
			(net "Net_4583")
			(clearance 0.0508)
			(thermal_gap 0.0508)
		)
		(pad "C9" thru_hole circle
			(at 17.599914 2.599944 180)
			(size 0.71628 0.71628)
			(drill 0.30988)
			(layers "*.Cu" "*.Mask")
			(remove_unused_layers no)
			(net "SMB_GPU2_ALERT_R_N")
			(clearance 0.0508)
			(thermal_gap 0.0508)
		)
		(pad "C10" thru_hole circle
			(at 19.800062 2.800096 180)
			(size 0.71628 0.71628)
			(drill 0.30988)
			(layers "*.Cu" "*.Mask")
			(remove_unused_layers no)
			(net "Net_4584")
			(clearance 0.0508)
			(thermal_gap 0.0508)
		)
		(pad "D2" thru_hole circle
			(at 2.199894 4.100068 180)
			(size 0.906272 0.906272)
			(drill 0.499872)
			(layers "*.Cu" "*.Mask")
			(remove_unused_layers no)
			(net "GND")
			(clearance 0.0508)
			(thermal_gap 0.0508)
		)
		(pad "D4" thru_hole circle
			(at 6.599936 4.100068 180)
			(size 0.906272 0.906272)
			(drill 0.499872)
			(layers "*.Cu" "*.Mask")
			(remove_unused_layers no)
			(net "GND")
			(clearance 0.0508)
			(thermal_gap 0.0508)
		)
		(pad "D6" thru_hole circle
			(at 10.999978 4.100068 180)
			(size 0.906272 0.906272)
			(drill 0.499872)
			(layers "*.Cu" "*.Mask")
			(remove_unused_layers no)
			(net "GND")
			(clearance 0.0508)
			(thermal_gap 0.0508)
		)
		(pad "D8" thru_hole circle
			(at 15.40002 4.100068 180)
			(size 0.906272 0.906272)
			(drill 0.499872)
			(layers "*.Cu" "*.Mask")
			(remove_unused_layers no)
			(net "GND")
			(clearance 0.0508)
			(thermal_gap 0.0508)
		)
		(pad "D9" thru_hole circle
			(at 17.599914 3.899916 180)
			(size 0.71628 0.71628)
			(drill 0.30988)
			(layers "*.Cu" "*.Mask")
			(remove_unused_layers no)
			(net "SMB_MB_BMC_SCL")
			(clearance 0.0508)
			(thermal_gap 0.0508)
		)
		(pad "D10" thru_hole circle
			(at 19.800062 4.100068 180)
			(size 0.906272 0.906272)
			(drill 0.499872)
			(layers "*.Cu" "*.Mask")
			(remove_unused_layers no)
			(net "GND")
			(clearance 0.0508)
			(thermal_gap 0.0508)
		)
		(pad "E1" thru_hole circle
			(at 0 5.199888 180)
			(size 0.906272 0.906272)
			(drill 0.499872)
			(layers "*.Cu" "*.Mask")
			(remove_unused_layers no)
			(net "GND")
			(clearance 0.0508)
			(thermal_gap 0.0508)
		)
		(pad "E3" thru_hole circle
			(at 4.400042 5.199888 180)
			(size 0.906272 0.906272)
			(drill 0.499872)
			(layers "*.Cu" "*.Mask")
			(remove_unused_layers no)
			(net "GND")
			(clearance 0.0508)
			(thermal_gap 0.0508)
		)
		(pad "E5" thru_hole circle
			(at 8.800084 5.199888 180)
			(size 0.906272 0.906272)
			(drill 0.499872)
			(layers "*.Cu" "*.Mask")
			(remove_unused_layers no)
			(net "GND")
			(clearance 0.0508)
			(thermal_gap 0.0508)
		)
		(pad "E7" thru_hole circle
			(at 13.199872 5.199888 180)
			(size 0.906272 0.906272)
			(drill 0.499872)
			(layers "*.Cu" "*.Mask")
			(remove_unused_layers no)
			(net "GND")
			(clearance 0.0508)
			(thermal_gap 0.0508)
		)
		(pad "E9" thru_hole circle
			(at 17.599914 5.199888 180)
			(size 0.906272 0.906272)
			(drill 0.499872)
			(layers "*.Cu" "*.Mask")
			(remove_unused_layers no)
			(net "GND")
			(clearance 0.0508)
			(thermal_gap 0.0508)
		)
		(pad "E10" thru_hole circle
			(at 19.800062 5.40004 180)
			(size 0.71628 0.71628)
			(drill 0.30988)
			(layers "*.Cu" "*.Mask")
			(remove_unused_layers no)
			(net "Net_4585")
			(clearance 0.0508)
			(thermal_gap 0.0508)
		)
		(pad "F9" thru_hole circle
			(at 17.599914 6.500114 180)
			(size 0.71628 0.71628)
			(drill 0.30988)
			(layers "*.Cu" "*.Mask")
			(remove_unused_layers no)
			(net "SMB_GPU1_ALERT_R_N")
			(clearance 0.0508)
			(thermal_gap 0.0508)
		)
		(pad "F10" thru_hole circle
			(at 19.800062 6.700012 180)
			(size 0.71628 0.71628)
			(drill 0.30988)
			(layers "*.Cu" "*.Mask")
			(remove_unused_layers no)
			(net "Net_4586")
			(clearance 0.0508)
			(thermal_gap 0.0508)
		)
		(pad "G2" thru_hole circle
			(at 2.199894 7.999984 180)
			(size 0.906272 0.906272)
			(drill 0.499872)
			(layers "*.Cu" "*.Mask")
			(remove_unused_layers no)
			(net "GND")
			(clearance 0.0508)
			(thermal_gap 0.0508)
		)
		(pad "G4" thru_hole circle
			(at 6.599936 7.999984 180)
			(size 0.906272 0.906272)
			(drill 0.499872)
			(layers "*.Cu" "*.Mask")
			(remove_unused_layers no)
			(net "GND")
			(clearance 0.0508)
			(thermal_gap 0.0508)
		)
		(pad "G6" thru_hole circle
			(at 10.999978 7.999984 180)
			(size 0.906272 0.906272)
			(drill 0.499872)
			(layers "*.Cu" "*.Mask")
			(remove_unused_layers no)
			(net "GND")
			(clearance 0.0508)
			(thermal_gap 0.0508)
		)
		(pad "G8" thru_hole circle
			(at 15.40002 7.999984 180)
			(size 0.906272 0.906272)
			(drill 0.499872)
			(layers "*.Cu" "*.Mask")
			(remove_unused_layers no)
			(net "GND")
			(clearance 0.0508)
			(thermal_gap 0.0508)
		)
		(pad "G9" thru_hole circle
			(at 17.599914 7.800086 180)
			(size 0.71628 0.71628)
			(drill 0.30988)
			(layers "*.Cu" "*.Mask")
			(remove_unused_layers no)
			(net "MB_BIC_MON_BUF_R")
			(clearance 0.0508)
			(thermal_gap 0.0508)
		)
		(pad "G10" thru_hole circle
			(at 19.800062 7.999984 180)
			(size 0.906272 0.906272)
			(drill 0.499872)
			(layers "*.Cu" "*.Mask")
			(remove_unused_layers no)
			(net "GND")
			(clearance 0.0508)
			(thermal_gap 0.0508)
		)
		(pad "H1" thru_hole circle
			(at 0 9.100058 180)
			(size 0.906272 0.906272)
			(drill 0.499872)
			(layers "*.Cu" "*.Mask")
			(remove_unused_layers no)
			(net "GND")
			(clearance 0.0508)
			(thermal_gap 0.0508)
		)
		(pad "H3" thru_hole circle
			(at 4.400042 9.100058 180)
			(size 0.906272 0.906272)
			(drill 0.499872)
			(layers "*.Cu" "*.Mask")
			(remove_unused_layers no)
			(net "GND")
			(clearance 0.0508)
			(thermal_gap 0.0508)
		)
		(pad "H5" thru_hole circle
			(at 8.800084 9.100058 180)
			(size 0.906272 0.906272)
			(drill 0.499872)
			(layers "*.Cu" "*.Mask")
			(remove_unused_layers no)
			(net "GND")
			(clearance 0.0508)
			(thermal_gap 0.0508)
		)
		(pad "H7" thru_hole circle
			(at 13.199872 9.100058 180)
			(size 0.906272 0.906272)
			(drill 0.499872)
			(layers "*.Cu" "*.Mask")
			(remove_unused_layers no)
			(net "GND")
			(clearance 0.0508)
			(thermal_gap 0.0508)
		)
		(pad "H9" thru_hole circle
			(at 17.599914 9.100058 180)
			(size 0.906272 0.906272)
			(drill 0.499872)
			(layers "*.Cu" "*.Mask")
			(remove_unused_layers no)
			(net "GND")
			(clearance 0.0508)
			(thermal_gap 0.0508)
		)
		(pad "H10" thru_hole circle
			(at 19.800062 9.299956 180)
			(size 0.71628 0.71628)
			(drill 0.30988)
			(layers "*.Cu" "*.Mask")
			(remove_unused_layers no)
			(net "GPU_FPGA_BOOT_EN")
			(clearance 0.0508)
			(thermal_gap 0.0508)
		)
		(pad "I9" thru_hole circle
			(at 17.599914 10.40003 180)
			(size 0.71628 0.71628)
			(drill 0.30988)
			(layers "*.Cu" "*.Mask")
			(remove_unused_layers no)
			(net "Net_4587")
			(clearance 0.0508)
			(thermal_gap 0.0508)
		)
		(pad "I10" thru_hole circle
			(at 19.800062 10.599928 180)
			(size 0.71628 0.71628)
			(drill 0.30988)
			(layers "*.Cu" "*.Mask")
			(remove_unused_layers no)
			(net "MB_BMC_MON")
			(clearance 0.0508)
			(thermal_gap 0.0508)
		)
		(pad "J2" thru_hole circle
			(at 2.199894 11.8999 180)
			(size 0.906272 0.906272)
			(drill 0.499872)
			(layers "*.Cu" "*.Mask")
			(remove_unused_layers no)
			(net "GND")
			(clearance 0.0508)
			(thermal_gap 0.0508)
		)
		(pad "J4" thru_hole circle
			(at 6.599936 11.8999 180)
			(size 0.906272 0.906272)
			(drill 0.499872)
			(layers "*.Cu" "*.Mask")
			(remove_unused_layers no)
			(net "GND")
			(clearance 0.0508)
			(thermal_gap 0.0508)
		)
		(pad "J6" thru_hole circle
			(at 10.999978 11.8999 180)
			(size 0.906272 0.906272)
			(drill 0.499872)
			(layers "*.Cu" "*.Mask")
			(remove_unused_layers no)
			(net "GND")
			(clearance 0.0508)
			(thermal_gap 0.0508)
		)
		(pad "J8" thru_hole circle
			(at 15.40002 11.8999 180)
			(size 0.906272 0.906272)
			(drill 0.499872)
			(layers "*.Cu" "*.Mask")
			(remove_unused_layers no)
			(net "GND")
			(clearance 0.0508)
			(thermal_gap 0.0508)
		)
		(pad "J9" thru_hole circle
			(at 17.599914 11.700002 180)
			(size 0.71628 0.71628)
			(drill 0.30988)
			(layers "*.Cu" "*.Mask")
			(remove_unused_layers no)
			(net "Net_4588")
			(clearance 0.0508)
			(thermal_gap 0.0508)
		)
		(pad "J10" thru_hole circle
			(at 19.800062 11.8999 180)
			(size 0.906272 0.906272)
			(drill 0.499872)
			(layers "*.Cu" "*.Mask")
			(remove_unused_layers no)
			(net "GND")
			(clearance 0.0508)
			(thermal_gap 0.0508)
		)
		(pad "K1" thru_hole circle
			(at 0 12.999974 180)
			(size 0.906272 0.906272)
			(drill 0.499872)
			(layers "*.Cu" "*.Mask")
			(remove_unused_layers no)
			(net "GND")
			(clearance 0.0508)
			(thermal_gap 0.0508)
		)
		(pad "K3" thru_hole circle
			(at 4.400042 12.999974 180)
			(size 0.906272 0.906272)
			(drill 0.499872)
			(layers "*.Cu" "*.Mask")
			(remove_unused_layers no)
			(net "GND")
			(clearance 0.0508)
			(thermal_gap 0.0508)
		)
		(pad "K5" thru_hole circle
			(at 8.800084 12.999974 180)
			(size 0.906272 0.906272)
			(drill 0.499872)
			(layers "*.Cu" "*.Mask")
			(remove_unused_layers no)
			(net "GND")
			(clearance 0.0508)
			(thermal_gap 0.0508)
		)
		(pad "K7" thru_hole circle
			(at 13.199872 12.999974 180)
			(size 0.906272 0.906272)
			(drill 0.499872)
			(layers "*.Cu" "*.Mask")
			(remove_unused_layers no)
			(net "GND")
			(clearance 0.0508)
			(thermal_gap 0.0508)
		)
		(pad "K9" thru_hole circle
			(at 17.599914 12.999974 180)
			(size 0.906272 0.906272)
			(drill 0.499872)
			(layers "*.Cu" "*.Mask")
			(remove_unused_layers no)
			(net "GND")
			(clearance 0.0508)
			(thermal_gap 0.0508)
		)
		(pad "K10" thru_hole circle
			(at 19.800062 13.199872 180)
			(size 0.71628 0.71628)
			(drill 0.30988)
			(layers "*.Cu" "*.Mask")
			(remove_unused_layers no)
			(net "Net_4589")
			(clearance 0.0508)
			(thermal_gap 0.0508)
		)
		(pad "L9" thru_hole circle
			(at 17.599914 14.299946 180)
			(size 0.71628 0.71628)
			(drill 0.30988)
			(layers "*.Cu" "*.Mask")
			(remove_unused_layers no)
			(net "Net_4591")
			(clearance 0.0508)
			(thermal_gap 0.0508)
		)
		(pad "L10" thru_hole circle
			(at 19.800062 14.500098 180)
			(size 0.71628 0.71628)
			(drill 0.30988)
			(layers "*.Cu" "*.Mask")
			(remove_unused_layers no)
			(net "Net_4590")
			(clearance 0.0508)
			(thermal_gap 0.0508)
		)
		(pad "M1_2" thru_hole circle
			(at 2.199894 15.80007 180)
			(size 0.906272 0.906272)
			(drill 0.499872)
			(layers "*.Cu" "*.Mask")
			(remove_unused_layers no)
			(net "GND")
			(clearance 0.0508)
			(thermal_gap 0.0508)
		)
		(pad "M1_4" thru_hole circle
			(at 6.599936 15.80007 180)
			(size 0.906272 0.906272)
			(drill 0.499872)
			(layers "*.Cu" "*.Mask")
			(remove_unused_layers no)
			(net "GND")
			(clearance 0.0508)
			(thermal_gap 0.0508)
		)
		(pad "M1_6" thru_hole circle
			(at 10.999978 15.80007 180)
			(size 0.906272 0.906272)
			(drill 0.499872)
			(layers "*.Cu" "*.Mask")
			(remove_unused_layers no)
			(net "GND")
			(clearance 0.0508)
			(thermal_gap 0.0508)
		)
		(pad "M1_8" thru_hole circle
			(at 15.40002 15.80007 180)
			(size 0.906272 0.906272)
			(drill 0.499872)
			(layers "*.Cu" "*.Mask")
			(remove_unused_layers no)
			(net "GND")
			(clearance 0.0508)
			(thermal_gap 0.0508)
		)
		(pad "M1_10" thru_hole circle
			(at 19.800062 15.80007 180)
			(size 0.906272 0.906272)
			(drill 0.499872)
			(layers "*.Cu" "*.Mask")
			(remove_unused_layers no)
			(net "GND")
			(clearance 0.0508)
			(thermal_gap 0.0508)
		)
		(pad "M2_2" thru_hole circle
			(at 2.199894 26.2001 180)
			(size 0.906272 0.906272)
			(drill 0.499872)
			(layers "*.Cu" "*.Mask")
			(remove_unused_layers no)
			(net "GND")
			(clearance 0.0508)
			(thermal_gap 0.0508)
		)
		(pad "M2_4" thru_hole circle
			(at 6.599936 26.2001 180)
			(size 0.906272 0.906272)
			(drill 0.499872)
			(layers "*.Cu" "*.Mask")
			(remove_unused_layers no)
			(net "GND")
			(clearance 0.0508)
			(thermal_gap 0.0508)
		)
		(pad "M2_6" thru_hole circle
			(at 10.999978 26.2001 180)
			(size 0.906272 0.906272)
			(drill 0.499872)
			(layers "*.Cu" "*.Mask")
			(remove_unused_layers no)
			(net "GND")
			(clearance 0.0508)
			(thermal_gap 0.0508)
		)
		(pad "M2_8" thru_hole circle
			(at 15.40002 26.2001 180)
			(size 0.906272 0.906272)
			(drill 0.499872)
			(layers "*.Cu" "*.Mask")
			(remove_unused_layers no)
			(net "GND")
			(clearance 0.0508)
			(thermal_gap 0.0508)
		)
		(pad "M2_10" thru_hole circle
			(at 19.800062 26.2001 180)
			(size 0.906272 0.906272)
			(drill 0.499872)
			(layers "*.Cu" "*.Mask")
			(remove_unused_layers no)
			(net "GND")
			(clearance 0.0508)
			(thermal_gap 0.0508)
		)
		(pad "M9" thru_hole circle
			(at 17.599914 15.599918 180)
			(size 0.71628 0.71628)
			(drill 0.30988)
			(layers "*.Cu" "*.Mask")
			(remove_unused_layers no)
			(net "Net_4592")
			(clearance 0.0508)
			(thermal_gap 0.0508)
		)
		(pad "N1_1" thru_hole circle
			(at 0 16.89989 180)
			(size 0.906272 0.906272)
			(drill 0.499872)
			(layers "*.Cu" "*.Mask")
			(remove_unused_layers no)
			(net "GND")
			(clearance 0.0508)
			(thermal_gap 0.0508)
		)
		(pad "N1_3" thru_hole circle
			(at 4.400042 16.89989 180)
			(size 0.906272 0.906272)
			(drill 0.499872)
			(layers "*.Cu" "*.Mask")
			(remove_unused_layers no)
			(net "GND")
			(clearance 0.0508)
			(thermal_gap 0.0508)
		)
		(pad "N1_5" thru_hole circle
			(at 8.800084 16.89989 180)
			(size 0.906272 0.906272)
			(drill 0.499872)
			(layers "*.Cu" "*.Mask")
			(remove_unused_layers no)
			(net "GND")
			(clearance 0.0508)
			(thermal_gap 0.0508)
		)
		(pad "N1_7" thru_hole circle
			(at 13.199872 16.89989 180)
			(size 0.906272 0.906272)
			(drill 0.499872)
			(layers "*.Cu" "*.Mask")
			(remove_unused_layers no)
			(net "GND")
			(clearance 0.0508)
			(thermal_gap 0.0508)
		)
		(pad "N1_9" thru_hole circle
			(at 17.599914 16.89989 180)
			(size 0.906272 0.906272)
			(drill 0.499872)
			(layers "*.Cu" "*.Mask")
			(remove_unused_layers no)
			(net "GND")
			(clearance 0.0508)
			(thermal_gap 0.0508)
		)
		(pad "N2_1" thru_hole circle
			(at 0 27.29992 180)
			(size 0.906272 0.906272)
			(drill 0.499872)
			(layers "*.Cu" "*.Mask")
			(remove_unused_layers no)
			(net "GND")
			(clearance 0.0508)
			(thermal_gap 0.0508)
		)
		(pad "N2_3" thru_hole circle
			(at 4.400042 27.29992 180)
			(size 0.906272 0.906272)
			(drill 0.499872)
			(layers "*.Cu" "*.Mask")
			(remove_unused_layers no)
			(net "GND")
			(clearance 0.0508)
			(thermal_gap 0.0508)
		)
		(pad "N2_5" thru_hole circle
			(at 8.800084 27.29992 180)
			(size 0.906272 0.906272)
			(drill 0.499872)
			(layers "*.Cu" "*.Mask")
			(remove_unused_layers no)
			(net "GND")
			(clearance 0.0508)
			(thermal_gap 0.0508)
		)
		(pad "N2_7" thru_hole circle
			(at 13.199872 27.29992 180)
			(size 0.906272 0.906272)
			(drill 0.499872)
			(layers "*.Cu" "*.Mask")
			(remove_unused_layers no)
			(net "GND")
			(clearance 0.0508)
			(thermal_gap 0.0508)
		)
		(pad "N2_9" thru_hole circle
			(at 17.599914 27.29992 180)
			(size 0.906272 0.906272)
			(drill 0.499872)
			(layers "*.Cu" "*.Mask")
			(remove_unused_layers no)
			(net "GND")
			(clearance 0.0508)
			(thermal_gap 0.0508)
		)
		(pad "N10" thru_hole circle
			(at 19.800062 27.500072 180)
			(size 0.71628 0.71628)
			(drill 0.30988)
			(layers "*.Cu" "*.Mask")
			(remove_unused_layers no)
			(net "Net_4593")
			(clearance 0.0508)
			(thermal_gap 0.0508)
		)
		(pad "O9" thru_hole circle
			(at 17.599914 28.599892 180)
			(size 0.71628 0.71628)
			(drill 0.30988)
			(layers "*.Cu" "*.Mask")
			(remove_unused_layers no)
			(net "Net_4595")
			(clearance 0.0508)
			(thermal_gap 0.0508)
		)
		(pad "O10" thru_hole circle
			(at 19.800062 28.800044 180)
			(size 0.71628 0.71628)
			(drill 0.30988)
			(layers "*.Cu" "*.Mask")
			(remove_unused_layers no)
			(net "Net_4594")
			(clearance 0.0508)
			(thermal_gap 0.0508)
		)
		(pad "P2" thru_hole circle
			(at 2.199894 30.100016 180)
			(size 0.906272 0.906272)
			(drill 0.499872)
			(layers "*.Cu" "*.Mask")
			(remove_unused_layers no)
			(net "GND")
			(clearance 0.0508)
			(thermal_gap 0.0508)
		)
		(pad "P4" thru_hole circle
			(at 6.599936 30.100016 180)
			(size 0.906272 0.906272)
			(drill 0.499872)
			(layers "*.Cu" "*.Mask")
			(remove_unused_layers no)
			(net "GND")
			(clearance 0.0508)
			(thermal_gap 0.0508)
		)
		(pad "P6" thru_hole circle
			(at 10.999978 30.100016 180)
			(size 0.906272 0.906272)
			(drill 0.499872)
			(layers "*.Cu" "*.Mask")
			(remove_unused_layers no)
			(net "GND")
			(clearance 0.0508)
			(thermal_gap 0.0508)
		)
		(pad "P8" thru_hole circle
			(at 15.40002 30.100016 180)
			(size 0.906272 0.906272)
			(drill 0.499872)
			(layers "*.Cu" "*.Mask")
			(remove_unused_layers no)
			(net "GND")
			(clearance 0.0508)
			(thermal_gap 0.0508)
		)
		(pad "P9" thru_hole circle
			(at 17.599914 29.900118 180)
			(size 0.71628 0.71628)
			(drill 0.30988)
			(layers "*.Cu" "*.Mask")
			(remove_unused_layers no)
			(net "Net_4596")
			(clearance 0.0508)
			(thermal_gap 0.0508)
		)
		(pad "P10" thru_hole circle
			(at 19.800062 30.100016 180)
			(size 0.906272 0.906272)
			(drill 0.499872)
			(layers "*.Cu" "*.Mask")
			(remove_unused_layers no)
			(net "GND")
			(clearance 0.0508)
			(thermal_gap 0.0508)
		)
		(pad "Q1" thru_hole circle
			(at 0 31.20009 180)
			(size 0.906272 0.906272)
			(drill 0.499872)
			(layers "*.Cu" "*.Mask")
			(remove_unused_layers no)
			(net "GND")
			(clearance 0.0508)
			(thermal_gap 0.0508)
		)
		(pad "Q3" thru_hole circle
			(at 4.400042 31.20009 180)
			(size 0.906272 0.906272)
			(drill 0.499872)
			(layers "*.Cu" "*.Mask")
			(remove_unused_layers no)
			(net "GND")
			(clearance 0.0508)
			(thermal_gap 0.0508)
		)
		(pad "Q5" thru_hole circle
			(at 8.800084 31.20009 180)
			(size 0.906272 0.906272)
			(drill 0.499872)
			(layers "*.Cu" "*.Mask")
			(remove_unused_layers no)
			(net "GND")
			(clearance 0.0508)
			(thermal_gap 0.0508)
		)
		(pad "Q7" thru_hole circle
			(at 13.199872 31.20009 180)
			(size 0.906272 0.906272)
			(drill 0.499872)
			(layers "*.Cu" "*.Mask")
			(remove_unused_layers no)
			(net "GND")
			(clearance 0.0508)
			(thermal_gap 0.0508)
		)
		(pad "Q9" thru_hole circle
			(at 17.599914 31.20009 180)
			(size 0.906272 0.906272)
			(drill 0.499872)
			(layers "*.Cu" "*.Mask")
			(remove_unused_layers no)
			(net "GND")
			(clearance 0.0508)
			(thermal_gap 0.0508)
		)
		(pad "Q10" thru_hole circle
			(at 19.800062 31.399988 180)
			(size 0.71628 0.71628)
			(drill 0.30988)
			(layers "*.Cu" "*.Mask")
			(remove_unused_layers no)
			(net "Net_4597")
			(clearance 0.0508)
			(thermal_gap 0.0508)
		)
		(pad "R9" thru_hole circle
			(at 17.599914 32.500062 180)
			(size 0.71628 0.71628)
			(drill 0.30988)
			(layers "*.Cu" "*.Mask")
			(remove_unused_layers no)
			(net "Net_4599")
			(clearance 0.0508)
			(thermal_gap 0.0508)
		)
		(pad "R10" thru_hole circle
			(at 19.800062 32.69996 180)
			(size 0.71628 0.71628)
			(drill 0.30988)
			(layers "*.Cu" "*.Mask")
			(remove_unused_layers no)
			(net "Net_4598")
			(clearance 0.0508)
			(thermal_gap 0.0508)
		)
		(pad "S2" thru_hole circle
			(at 2.199894 33.999932 180)
			(size 0.906272 0.906272)
			(drill 0.499872)
			(layers "*.Cu" "*.Mask")
			(remove_unused_layers no)
			(net "GND")
			(clearance 0.0508)
			(thermal_gap 0.0508)
		)
		(pad "S4" thru_hole circle
			(at 6.599936 33.999932 180)
			(size 0.906272 0.906272)
			(drill 0.499872)
			(layers "*.Cu" "*.Mask")
			(remove_unused_layers no)
			(net "GND")
			(clearance 0.0508)
			(thermal_gap 0.0508)
		)
		(pad "S6" thru_hole circle
			(at 10.999978 33.999932 180)
			(size 0.906272 0.906272)
			(drill 0.499872)
			(layers "*.Cu" "*.Mask")
			(remove_unused_layers no)
			(net "GND")
			(clearance 0.0508)
			(thermal_gap 0.0508)
		)
		(pad "S8" thru_hole circle
			(at 15.40002 33.999932 180)
			(size 0.906272 0.906272)
			(drill 0.499872)
			(layers "*.Cu" "*.Mask")
			(remove_unused_layers no)
			(net "GND")
			(clearance 0.0508)
			(thermal_gap 0.0508)
		)
		(pad "S9" thru_hole circle
			(at 17.599914 33.800034 180)
			(size 0.71628 0.71628)
			(drill 0.30988)
			(layers "*.Cu" "*.Mask")
			(remove_unused_layers no)
			(net "Net_4600")
			(clearance 0.0508)
			(thermal_gap 0.0508)
		)
		(pad "S10" thru_hole circle
			(at 19.800062 33.999932 180)
			(size 0.906272 0.906272)
			(drill 0.499872)
			(layers "*.Cu" "*.Mask")
			(remove_unused_layers no)
			(net "GND")
			(clearance 0.0508)
			(thermal_gap 0.0508)
		)
		(pad "T1" thru_hole circle
			(at 0 35.100006 180)
			(size 0.906272 0.906272)
			(drill 0.499872)
			(layers "*.Cu" "*.Mask")
			(remove_unused_layers no)
			(net "GND")
			(clearance 0.0508)
			(thermal_gap 0.0508)
		)
		(pad "T3" thru_hole circle
			(at 4.400042 35.100006 180)
			(size 0.906272 0.906272)
			(drill 0.499872)
			(layers "*.Cu" "*.Mask")
			(remove_unused_layers no)
			(net "GND")
			(clearance 0.0508)
			(thermal_gap 0.0508)
		)
		(pad "T5" thru_hole circle
			(at 8.800084 35.100006 180)
			(size 0.906272 0.906272)
			(drill 0.499872)
			(layers "*.Cu" "*.Mask")
			(remove_unused_layers no)
			(net "GND")
			(clearance 0.0508)
			(thermal_gap 0.0508)
		)
		(pad "T7" thru_hole circle
			(at 13.199872 35.100006 180)
			(size 0.906272 0.906272)
			(drill 0.499872)
			(layers "*.Cu" "*.Mask")
			(remove_unused_layers no)
			(net "GND")
			(clearance 0.0508)
			(thermal_gap 0.0508)
		)
		(pad "T9" thru_hole circle
			(at 17.599914 35.100006 180)
			(size 0.906272 0.906272)
			(drill 0.499872)
			(layers "*.Cu" "*.Mask")
			(remove_unused_layers no)
			(net "GND")
			(clearance 0.0508)
			(thermal_gap 0.0508)
		)
		(pad "T10" thru_hole circle
			(at 19.800062 35.299904 180)
			(size 0.71628 0.71628)
			(drill 0.30988)
			(layers "*.Cu" "*.Mask")
			(remove_unused_layers no)
			(net "Net_4601")
			(clearance 0.0508)
			(thermal_gap 0.0508)
		)
		(pad "U9" thru_hole circle
			(at 17.599914 36.399978 180)
			(size 0.71628 0.71628)
			(drill 0.30988)
			(layers "*.Cu" "*.Mask")
			(remove_unused_layers no)
			(net "Net_4603")
			(clearance 0.0508)
			(thermal_gap 0.0508)
		)
		(pad "U10" thru_hole circle
			(at 19.800062 36.599876 180)
			(size 0.71628 0.71628)
			(drill 0.30988)
			(layers "*.Cu" "*.Mask")
			(remove_unused_layers no)
			(net "Net_4602")
			(clearance 0.0508)
			(thermal_gap 0.0508)
		)
		(pad "V2" thru_hole circle
			(at 2.199894 37.900102 180)
			(size 0.906272 0.906272)
			(drill 0.499872)
			(layers "*.Cu" "*.Mask")
			(remove_unused_layers no)
			(net "GND")
			(clearance 0.0508)
			(thermal_gap 0.0508)
		)
		(pad "V4" thru_hole circle
			(at 6.599936 37.900102 180)
			(size 0.906272 0.906272)
			(drill 0.499872)
			(layers "*.Cu" "*.Mask")
			(remove_unused_layers no)
			(net "GND")
			(clearance 0.0508)
			(thermal_gap 0.0508)
		)
		(pad "V6" thru_hole circle
			(at 10.999978 37.900102 180)
			(size 0.906272 0.906272)
			(drill 0.499872)
			(layers "*.Cu" "*.Mask")
			(remove_unused_layers no)
			(net "GND")
			(clearance 0.0508)
			(thermal_gap 0.0508)
		)
		(pad "V8" thru_hole circle
			(at 15.40002 37.900102 180)
			(size 0.906272 0.906272)
			(drill 0.499872)
			(layers "*.Cu" "*.Mask")
			(remove_unused_layers no)
			(net "GND")
			(clearance 0.0508)
			(thermal_gap 0.0508)
		)
		(pad "V9" thru_hole circle
			(at 17.599914 37.69995 180)
			(size 0.71628 0.71628)
			(drill 0.30988)
			(layers "*.Cu" "*.Mask")
			(remove_unused_layers no)
			(net "Net_4604")
			(clearance 0.0508)
			(thermal_gap 0.0508)
		)
		(pad "V10" thru_hole circle
			(at 19.800062 37.900102 180)
			(size 0.906272 0.906272)
			(drill 0.499872)
			(layers "*.Cu" "*.Mask")
			(remove_unused_layers no)
			(net "GND")
			(clearance 0.0508)
			(thermal_gap 0.0508)
		)
		(pad "W1" thru_hole circle
			(at 0 38.999922 180)
			(size 0.906272 0.906272)
			(drill 0.499872)
			(layers "*.Cu" "*.Mask")
			(remove_unused_layers no)
			(net "GND")
			(clearance 0.0508)
			(thermal_gap 0.0508)
		)
		(pad "W3" thru_hole circle
			(at 4.400042 38.999922 180)
			(size 0.906272 0.906272)
			(drill 0.499872)
			(layers "*.Cu" "*.Mask")
			(remove_unused_layers no)
			(net "GND")
			(clearance 0.0508)
			(thermal_gap 0.0508)
		)
		(pad "W5" thru_hole circle
			(at 8.800084 38.999922 180)
			(size 0.906272 0.906272)
			(drill 0.499872)
			(layers "*.Cu" "*.Mask")
			(remove_unused_layers no)
			(net "GND")
			(clearance 0.0508)
			(thermal_gap 0.0508)
		)
		(pad "W7" thru_hole circle
			(at 13.199872 38.999922 180)
			(size 0.906272 0.906272)
			(drill 0.499872)
			(layers "*.Cu" "*.Mask")
			(remove_unused_layers no)
			(net "GND")
			(clearance 0.0508)
			(thermal_gap 0.0508)
		)
		(pad "W9" thru_hole circle
			(at 17.599914 38.999922 180)
			(size 0.906272 0.906272)
			(drill 0.499872)
			(layers "*.Cu" "*.Mask")
			(remove_unused_layers no)
			(net "GND")
			(clearance 0.0508)
			(thermal_gap 0.0508)
		)
		(pad "W10" thru_hole circle
			(at 19.800062 39.200074 180)
			(size 0.71628 0.71628)
			(drill 0.30988)
			(layers "*.Cu" "*.Mask")
			(remove_unused_layers no)
			(net "Net_4605")
			(clearance 0.0508)
			(thermal_gap 0.0508)
		)
		(pad "X9" thru_hole circle
			(at 17.599914 40.299894 180)
			(size 0.71628 0.71628)
			(drill 0.30988)
			(layers "*.Cu" "*.Mask")
			(remove_unused_layers no)
			(net "Net_4607")
			(clearance 0.0508)
			(thermal_gap 0.0508)
		)
		(pad "X10" thru_hole circle
			(at 19.800062 40.500046 180)
			(size 0.71628 0.71628)
			(drill 0.30988)
			(layers "*.Cu" "*.Mask")
			(remove_unused_layers no)
			(net "Net_4606")
			(clearance 0.0508)
			(thermal_gap 0.0508)
		)
		(pad "Y2" thru_hole circle
			(at 2.199894 41.800018 180)
			(size 0.906272 0.906272)
			(drill 0.499872)
			(layers "*.Cu" "*.Mask")
			(remove_unused_layers no)
			(net "GND")
			(clearance 0.0508)
			(thermal_gap 0.0508)
		)
		(pad "Y4" thru_hole circle
			(at 6.599936 41.800018 180)
			(size 0.906272 0.906272)
			(drill 0.499872)
			(layers "*.Cu" "*.Mask")
			(remove_unused_layers no)
			(net "GND")
			(clearance 0.0508)
			(thermal_gap 0.0508)
		)
		(pad "Y6" thru_hole circle
			(at 10.999978 41.800018 180)
			(size 0.906272 0.906272)
			(drill 0.499872)
			(layers "*.Cu" "*.Mask")
			(remove_unused_layers no)
			(net "GND")
			(clearance 0.0508)
			(thermal_gap 0.0508)
		)
		(pad "Y8" thru_hole circle
			(at 15.40002 41.800018 180)
			(size 0.906272 0.906272)
			(drill 0.499872)
			(layers "*.Cu" "*.Mask")
			(remove_unused_layers no)
			(net "GND")
			(clearance 0.0508)
			(thermal_gap 0.0508)
		)
		(pad "Y9" thru_hole circle
			(at 17.599914 41.60012 180)
			(size 0.71628 0.71628)
			(drill 0.30988)
			(layers "*.Cu" "*.Mask")
			(remove_unused_layers no)
			(net "Net_4608")
			(clearance 0.0508)
			(thermal_gap 0.0508)
		)
		(pad "Y10" thru_hole circle
			(at 19.800062 41.800018 180)
			(size 0.906272 0.906272)
			(drill 0.499872)
			(layers "*.Cu" "*.Mask")
			(remove_unused_layers no)
			(net "GND")
			(clearance 0.0508)
			(thermal_gap 0.0508)
		)
		(pad "Z1" thru_hole circle
			(at 0 42.900092 180)
			(size 0.906272 0.906272)
			(drill 0.499872)
			(layers "*.Cu" "*.Mask")
			(remove_unused_layers no)
			(net "GND")
			(clearance 0.0508)
			(thermal_gap 0.0508)
		)
		(pad "Z2" thru_hole circle
			(at 2.199894 43.09999 180)
			(size 0.71628 0.71628)
			(drill 0.30988)
			(layers "*.Cu" "*.Mask")
			(remove_unused_layers no)
			(net "GPU_FPGA_EROT_FATALERR_R_N")
			(clearance 0.0508)
			(thermal_gap 0.0508)
		)
		(pad "Z3" thru_hole circle
			(at 4.400042 42.900092 180)
			(size 0.906272 0.906272)
			(drill 0.499872)
			(layers "*.Cu" "*.Mask")
			(remove_unused_layers no)
			(net "GND")
			(clearance 0.0508)
			(thermal_gap 0.0508)
		)
		(pad "Z4" thru_hole circle
			(at 6.599936 43.09999 180)
			(size 0.71628 0.71628)
			(drill 0.30988)
			(layers "*.Cu" "*.Mask")
			(remove_unused_layers no)
			(net "GPU_3V3IO_RSVD0_FFU_R")
			(clearance 0.0508)
			(thermal_gap 0.0508)
		)
		(pad "Z5" thru_hole circle
			(at 8.800084 42.900092 180)
			(size 0.906272 0.906272)
			(drill 0.499872)
			(layers "*.Cu" "*.Mask")
			(remove_unused_layers no)
			(net "GND")
			(clearance 0.0508)
			(thermal_gap 0.0508)
		)
		(pad "Z6" thru_hole circle
			(at 10.999978 43.09999 180)
			(size 0.71628 0.71628)
			(drill 0.30988)
			(layers "*.Cu" "*.Mask")
			(remove_unused_layers no)
			(net "GPU_3V3IO_RSVD1_FFU_R")
			(clearance 0.0508)
			(thermal_gap 0.0508)
		)
		(pad "Z7" thru_hole circle
			(at 13.199872 42.900092 180)
			(size 0.906272 0.906272)
			(drill 0.499872)
			(layers "*.Cu" "*.Mask")
			(remove_unused_layers no)
			(net "GND")
			(clearance 0.0508)
			(thermal_gap 0.0508)
		)
		(pad "Z8" thru_hole circle
			(at 15.40002 43.09999 180)
			(size 0.71628 0.71628)
			(drill 0.30988)
			(layers "*.Cu" "*.Mask")
			(remove_unused_layers no)
			(net "PRSNT_SWB_B3_N")
			(clearance 0.0508)
			(thermal_gap 0.0508)
		)
		(pad "Z9" thru_hole circle
			(at 17.599914 42.900092 180)
			(size 0.906272 0.906272)
			(drill 0.499872)
			(layers "*.Cu" "*.Mask")
			(remove_unused_layers no)
			(net "GND")
			(clearance 0.0508)
			(thermal_gap 0.0508)
		)
		(pad "Z10" thru_hole circle
			(at 19.800062 43.09999 180)
			(size 0.71628 0.71628)
			(drill 0.30988)
			(layers "*.Cu" "*.Mask")
			(remove_unused_layers no)
			(net "RST_GPU_FPGA_EROT_N")
			(clearance 0.0508)
			(thermal_gap 0.0508)
		)
		(zone
			(layer "B.Cu")
			(hatch none 0.5)
			(connect_pads
				(clearance 0)
			)
			(min_thickness 0.25)
			(keepout
				(tracks allowed)
				(vias not_allowed)
				(pads allowed)
				(copperpour not_allowed)
				(footprints allowed)
			)
			(placement
				(enabled no)
				(sheetname "")
			)
			(fill
				(thermal_gap 0.5)
				(thermal_bridge_width 0.5)
				(island_removal_mode 0)
			)
			(polygon
				(pts
					(xy 115.392962 -394.665708) (xy 136.220962 -394.665708) (xy 136.220962 -412.50743) (xy 115.392962 -412.50743)
				)
			)
		)
		(zone
			(layer "B.Cu")
			(hatch none 0.5)
			(connect_pads
				(clearance 0)
			)
			(min_thickness 0.25)
			(keepout
				(tracks allowed)
				(vias not_allowed)
				(pads allowed)
				(copperpour not_allowed)
				(footprints allowed)
			)
			(placement
				(enabled no)
				(sheetname "")
			)
			(fill
				(thermal_gap 0.5)
				(thermal_bridge_width 0.5)
				(island_removal_mode 0)
			)
			(polygon
				(pts
					(xy 115.392962 -368.572796) (xy 136.220962 -368.572796) (xy 136.220962 -386.414518) (xy 115.392962 -386.414518)
				)
			)
		)
	)
	(footprint ""
		(layer "F.Cu")
		(at 241.3254 -216.408 90)
		(property "Reference" "C4434"
			(at 0 0 90)
			(layer "F.SilkS")
			(hide yes)
			(effects
				(font
					(size 1.27 1.27)
				)
			)
		)
		(property "Value" ""
			(at 0 0 90)
			(layer "F.Fab")
			(effects
				(font
					(size 1.27 1.27)
				)
			)
		)
		(duplicate_pad_numbers_are_jumpers no)
		(fp_line
			(start 0.7874 -0.4064)
			(end 0.7874 0.4064)
			(stroke
				(width 0.1524)
				(type default)
			)
			(layer "F.SilkS")
		)
		(fp_line
			(start -0.7874 -0.4064)
			(end 0.7874 -0.4064)
			(stroke
				(width 0.1524)
				(type default)
			)
			(layer "F.SilkS")
		)
		(fp_line
			(start 0.7874 0.4064)
			(end -0.7874 0.4064)
			(stroke
				(width 0.1524)
				(type default)
			)
			(layer "F.SilkS")
		)
		(fp_line
			(start -0.7874 0.4064)
			(end -0.7874 -0.4064)
			(stroke
				(width 0.1524)
				(type default)
			)
			(layer "F.SilkS")
		)
		(fp_line
			(start -0.12065 -0.305054)
			(end -0.12065 -0.2794)
			(stroke
				(width 0.1)
				(type default)
			)
			(layer "F.Fab")
		)
		(fp_line
			(start -0.67945 -0.305054)
			(end -0.12065 -0.305054)
			(stroke
				(width 0.1)
				(type default)
			)
			(layer "F.Fab")
		)
		(fp_line
			(start 0.67945 -0.3048)
			(end 0.67945 0.3048)
			(stroke
				(width 0.1)
				(type default)
			)
			(layer "F.Fab")
		)
		(fp_line
			(start 0.12065 -0.3048)
			(end 0.67945 -0.3048)
			(stroke
				(width 0.1)
				(type default)
			)
			(layer "F.Fab")
		)
		(fp_line
			(start 0.12065 -0.2794)
			(end 0.12065 -0.3048)
			(stroke
				(width 0.1)
				(type default)
			)
			(layer "F.Fab")
		)
		(fp_line
			(start -0.12065 -0.2794)
			(end 0.12065 -0.2794)
			(stroke
				(width 0.1)
				(type default)
			)
			(layer "F.Fab")
		)
		(fp_line
			(start 0.120396 0.2794)
			(end -0.12065 0.2794)
			(stroke
				(width 0.1)
				(type default)
			)
			(layer "F.Fab")
		)
		(fp_line
			(start -0.12065 0.2794)
			(end -0.12065 0.3048)
			(stroke
				(width 0.1)
				(type default)
			)
			(layer "F.Fab")
		)
		(fp_line
			(start 0.67945 0.3048)
			(end 0.120396 0.3048)
			(stroke
				(width 0.1)
				(type default)
			)
			(layer "F.Fab")
		)
		(fp_line
			(start 0.120396 0.3048)
			(end 0.120396 0.2794)
			(stroke
				(width 0.1)
				(type default)
			)
			(layer "F.Fab")
		)
		(fp_line
			(start -0.12065 0.3048)
			(end -0.67945 0.3048)
			(stroke
				(width 0.1)
				(type default)
			)
			(layer "F.Fab")
		)
		(fp_line
			(start -0.67945 0.3048)
			(end -0.67945 -0.305054)
			(stroke
				(width 0.1)
				(type default)
			)
			(layer "F.Fab")
		)
		(pad "1" smd circle
			(at -0.40005 0 90)
			(size 0 0)
			(layers "F.Cu" "F.Mask" "F.Paste")
			(net "P1V8_PLL0_PEX0_SCALED")
		)
		(pad "2" smd circle
			(at 0.40005 0 90)
			(size 0 0)
			(layers "F.Cu" "F.Mask" "F.Paste")
			(net "GND")
		)
	)
	(footprint ""
		(layer "F.Cu")
		(at 275.992336 -29.139642 180)
		(property "Reference" "C501"
			(at 0 0 180)
			(layer "F.SilkS")
			(hide yes)
			(effects
				(font
					(size 1.27 1.27)
				)
			)
		)
		(property "Value" ""
			(at 0 0 180)
			(layer "F.Fab")
			(effects
				(font
					(size 1.27 1.27)
				)
			)
		)
		(duplicate_pad_numbers_are_jumpers no)
		(fp_line
			(start 0.299974 0.150114)
			(end -0.299974 0.150114)
			(stroke
				(width 0.1)
				(type default)
			)
			(layer "F.Fab")
		)
		(fp_line
			(start 0.299974 -0.150114)
			(end 0.299974 0.150114)
			(stroke
				(width 0.1)
				(type default)
			)
			(layer "F.Fab")
		)
		(fp_line
			(start -0.299974 0.150114)
			(end -0.299974 -0.150114)
			(stroke
				(width 0.1)
				(type default)
			)
			(layer "F.Fab")
		)
		(fp_line
			(start -0.299974 -0.150114)
			(end 0.299974 -0.150114)
			(stroke
				(width 0.1)
				(type default)
			)
			(layer "F.Fab")
		)
		(pad "1" smd rect
			(at -0.2667 0 180)
			(size 0.3048 0.381)
			(layers "F.Cu" "F.Mask" "F.Paste")
			(net "P5E_PEX2_STN2_TX_DP<40>")
		)
		(pad "2" smd rect
			(at 0.2667 0 180)
			(size 0.3048 0.381)
			(layers "F.Cu" "F.Mask" "F.Paste")
			(net "P5E_PEX2_STN2_TX_C_DP<40>")
		)
	)
	(footprint ""
		(layer "F.Cu")
		(at 256.47396 -26.31186 -90)
		(property "Reference" "U412"
			(at -0.00254 -2.35331 90)
			(unlocked yes)
			(layer "F.SilkS")
			(effects
				(font
					(size 0.7874 0.5842)
					(thickness 0.1524)
				)
			)
		)
		(property "Value" ""
			(at 0 0 270)
			(layer "F.Fab")
			(effects
				(font
					(size 1.27 1.27)
				)
			)
		)
		(duplicate_pad_numbers_are_jumpers no)
		(fp_line
			(start -1.949958 1.610106)
			(end -1.949958 -1.610106)
			(stroke
				(width 0.1524)
				(type default)
			)
			(layer "F.SilkS")
		)
		(fp_line
			(start 1.949958 1.610106)
			(end -1.949958 1.610106)
			(stroke
				(width 0.1524)
				(type default)
			)
			(layer "F.SilkS")
		)
		(fp_line
			(start 1.949958 -1.560068)
			(end 1.949958 1.610106)
			(stroke
				(width 0.1524)
				(type default)
			)
			(layer "F.SilkS")
		)
		(fp_line
			(start -1.949958 -1.610106)
			(end 1.949958 -1.610106)
			(stroke
				(width 0.1524)
				(type default)
			)
			(layer "F.SilkS")
		)
		(fp_line
			(start -0.750062 1.560068)
			(end -0.750062 -1.560068)
			(stroke
				(width 0.1)
				(type default)
			)
			(layer "F.Fab")
		)
		(fp_line
			(start 0.750062 1.560068)
			(end -0.750062 1.560068)
			(stroke
				(width 0.1)
				(type default)
			)
			(layer "F.Fab")
		)
		(fp_line
			(start -0.750062 -1.560068)
			(end 0.750062 -1.560068)
			(stroke
				(width 0.1)
				(type default)
			)
			(layer "F.Fab")
		)
		(fp_line
			(start 0.750062 -1.560068)
			(end 0.750062 1.560068)
			(stroke
				(width 0.1)
				(type default)
			)
			(layer "F.Fab")
		)
		(pad "D" smd rect
			(at 1.100074 0 180)
			(size 1.016 1.4224)
			(layers "F.Cu" "F.Mask" "F.Paste")
			(net "SSD8_LED_ISO_N")
		)
		(pad "G" smd rect
			(at -1.100074 -0.94996 180)
			(size 1.016 1.4224)
			(layers "F.Cu" "F.Mask" "F.Paste")
			(net "SSD8_LED_R")
		)
		(pad "S" smd rect
			(at -1.100074 0.94996 180)
			(size 1.016 1.4224)
			(layers "F.Cu" "F.Mask" "F.Paste")
			(net "GND")
		)
	)
	(footprint ""
		(layer "F.Cu")
		(at 439.679334 -300.641004 -90)
		(property "Reference" "R3991"
			(at 0 0 270)
			(layer "F.SilkS")
			(hide yes)
			(effects
				(font
					(size 1.27 1.27)
				)
			)
		)
		(property "Value" ""
			(at 0 0 270)
			(layer "F.Fab")
			(effects
				(font
					(size 1.27 1.27)
				)
			)
		)
		(duplicate_pad_numbers_are_jumpers no)
		(fp_line
			(start -0.7874 0.4064)
			(end -0.7874 -0.4064)
			(stroke
				(width 0.1524)
				(type default)
			)
			(layer "F.SilkS")
		)
		(fp_line
			(start 0.7874 0.4064)
			(end -0.7874 0.4064)
			(stroke
				(width 0.1524)
				(type default)
			)
			(layer "F.SilkS")
		)
		(fp_line
			(start -0.7874 -0.4064)
			(end 0.7874 -0.4064)
			(stroke
				(width 0.1524)
				(type default)
			)
			(layer "F.SilkS")
		)
		(fp_line
			(start 0.7874 -0.4064)
			(end 0.7874 0.4064)
			(stroke
				(width 0.1524)
				(type default)
			)
			(layer "F.SilkS")
		)
		(fp_line
			(start -0.67945 0.3048)
			(end -0.67945 -0.305054)
			(stroke
				(width 0.1)
				(type default)
			)
			(layer "F.Fab")
		)
		(fp_line
			(start -0.12065 0.3048)
			(end -0.67945 0.3048)
			(stroke
				(width 0.1)
				(type default)
			)
			(layer "F.Fab")
		)
		(fp_line
			(start 0.120396 0.3048)
			(end 0.120396 0.2794)
			(stroke
				(width 0.1)
				(type default)
			)
			(layer "F.Fab")
		)
		(fp_line
			(start 0.67945 0.3048)
			(end 0.120396 0.3048)
			(stroke
				(width 0.1)
				(type default)
			)
			(layer "F.Fab")
		)
		(fp_line
			(start -0.12065 0.2794)
			(end -0.12065 0.3048)
			(stroke
				(width 0.1)
				(type default)
			)
			(layer "F.Fab")
		)
		(fp_line
			(start 0.120396 0.2794)
			(end -0.12065 0.2794)
			(stroke
				(width 0.1)
				(type default)
			)
			(layer "F.Fab")
		)
		(fp_line
			(start -0.12065 -0.2794)
			(end 0.12065 -0.2794)
			(stroke
				(width 0.1)
				(type default)
			)
			(layer "F.Fab")
		)
		(fp_line
			(start 0.12065 -0.2794)
			(end 0.12065 -0.3048)
			(stroke
				(width 0.1)
				(type default)
			)
			(layer "F.Fab")
		)
		(fp_line
			(start 0.12065 -0.3048)
			(end 0.67945 -0.3048)
			(stroke
				(width 0.1)
				(type default)
			)
			(layer "F.Fab")
		)
		(fp_line
			(start 0.67945 -0.3048)
			(end 0.67945 0.3048)
			(stroke
				(width 0.1)
				(type default)
			)
			(layer "F.Fab")
		)
		(fp_line
			(start -0.67945 -0.305054)
			(end -0.12065 -0.305054)
			(stroke
				(width 0.1)
				(type default)
			)
			(layer "F.Fab")
		)
		(fp_line
			(start -0.12065 -0.305054)
			(end -0.12065 -0.2794)
			(stroke
				(width 0.1)
				(type default)
			)
			(layer "F.Fab")
		)
		(pad "1" smd circle
			(at -0.40005 0 270)
			(size 0 0)
			(layers "F.Cu" "F.Mask" "F.Paste")
			(net "I2C0_PEX3_SCL")
		)
		(pad "2" smd circle
			(at 0.40005 0 270)
			(size 0 0)
			(layers "F.Cu" "F.Mask" "F.Paste")
			(net "I2C_PEX3_HOST_SCL")
		)
	)
	(footprint ""
		(layer "F.Cu")
		(at 109.581696 -92.333572 -90)
		(property "Reference" "R1151"
			(at 0 0 270)
			(layer "F.SilkS")
			(hide yes)
			(effects
				(font
					(size 1.27 1.27)
				)
			)
		)
		(property "Value" ""
			(at 0 0 270)
			(layer "F.Fab")
			(effects
				(font
					(size 1.27 1.27)
				)
			)
		)
		(duplicate_pad_numbers_are_jumpers no)
		(fp_line
			(start 0.7874 0.4064)
			(end -0.7874 0.4064)
			(stroke
				(width 0.1524)
				(type default)
			)
			(layer "F.SilkS")
		)
		(fp_line
			(start -0.67945 0.3048)
			(end -0.67945 -0.305054)
			(stroke
				(width 0.1)
				(type default)
			)
			(layer "F.Fab")
		)
		(fp_line
			(start -0.12065 0.3048)
			(end -0.67945 0.3048)
			(stroke
				(width 0.1)
				(type default)
			)
			(layer "F.Fab")
		)
		(fp_line
			(start 0.120396 0.3048)
			(end 0.120396 0.2794)
			(stroke
				(width 0.1)
				(type default)
			)
			(layer "F.Fab")
		)
		(fp_line
			(start 0.67945 0.3048)
			(end 0.120396 0.3048)
			(stroke
				(width 0.1)
				(type default)
			)
			(layer "F.Fab")
		)
		(fp_line
			(start -0.12065 0.2794)
			(end -0.12065 0.3048)
			(stroke
				(width 0.1)
				(type default)
			)
			(layer "F.Fab")
		)
		(fp_line
			(start 0.120396 0.2794)
			(end -0.12065 0.2794)
			(stroke
				(width 0.1)
				(type default)
			)
			(layer "F.Fab")
		)
		(fp_line
			(start -0.12065 -0.2794)
			(end 0.12065 -0.2794)
			(stroke
				(width 0.1)
				(type default)
			)
			(layer "F.Fab")
		)
		(fp_line
			(start 0.12065 -0.2794)
			(end 0.12065 -0.3048)
			(stroke
				(width 0.1)
				(type default)
			)
			(layer "F.Fab")
		)
		(fp_line
			(start 0.12065 -0.3048)
			(end 0.67945 -0.3048)
			(stroke
				(width 0.1)
				(type default)
			)
			(layer "F.Fab")
		)
		(fp_line
			(start 0.67945 -0.3048)
			(end 0.67945 0.3048)
			(stroke
				(width 0.1)
				(type default)
			)
			(layer "F.Fab")
		)
		(fp_line
			(start -0.67945 -0.305054)
			(end -0.12065 -0.305054)
			(stroke
				(width 0.1)
				(type default)
			)
			(layer "F.Fab")
		)
		(fp_line
			(start -0.12065 -0.305054)
			(end -0.12065 -0.2794)
			(stroke
				(width 0.1)
				(type default)
			)
			(layer "F.Fab")
		)
		(pad "1" smd circle
			(at -0.40005 0 270)
			(size 0 0)
			(layers "F.Cu" "F.Mask" "F.Paste")
			(net "CLK_100M_DB800ZL_SSD7_R_DN")
		)
		(pad "2" smd circle
			(at 0.40005 0 270)
			(size 0 0)
			(layers "F.Cu" "F.Mask" "F.Paste")
			(net "CLK_100M_DB800ZL_SSD7_DN")
		)
	)
	(footprint ""
		(layer "F.Cu")
		(at 104.848406 -225.945954 180)
		(property "Reference" "PC288"
			(at 0 0 180)
			(layer "F.SilkS")
			(hide yes)
			(effects
				(font
					(size 1.27 1.27)
				)
			)
		)
		(property "Value" ""
			(at 0 0 180)
			(layer "F.Fab")
			(effects
				(font
					(size 1.27 1.27)
				)
			)
		)
		(duplicate_pad_numbers_are_jumpers no)
		(fp_line
			(start 0.7874 0.4064)
			(end -0.7874 0.4064)
			(stroke
				(width 0.1524)
				(type default)
			)
			(layer "F.SilkS")
		)
		(fp_line
			(start 0.7874 -0.4064)
			(end 0.7874 0.4064)
			(stroke
				(width 0.1524)
				(type default)
			)
			(layer "F.SilkS")
		)
		(fp_line
			(start -0.7874 0.4064)
			(end -0.7874 -0.4064)
			(stroke
				(width 0.1524)
				(type default)
			)
			(layer "F.SilkS")
		)
		(fp_line
			(start -0.7874 -0.4064)
			(end 0.7874 -0.4064)
			(stroke
				(width 0.1524)
				(type default)
			)
			(layer "F.SilkS")
		)
		(fp_line
			(start 0.67945 0.3048)
			(end 0.120396 0.3048)
			(stroke
				(width 0.1)
				(type default)
			)
			(layer "F.Fab")
		)
		(fp_line
			(start 0.67945 -0.3048)
			(end 0.67945 0.3048)
			(stroke
				(width 0.1)
				(type default)
			)
			(layer "F.Fab")
		)
		(fp_line
			(start 0.12065 -0.2794)
			(end 0.12065 -0.3048)
			(stroke
				(width 0.1)
				(type default)
			)
			(layer "F.Fab")
		)
		(fp_line
			(start 0.12065 -0.3048)
			(end 0.67945 -0.3048)
			(stroke
				(width 0.1)
				(type default)
			)
			(layer "F.Fab")
		)
		(fp_line
			(start 0.120396 0.3048)
			(end 0.120396 0.2794)
			(stroke
				(width 0.1)
				(type default)
			)
			(layer "F.Fab")
		)
		(fp_line
			(start 0.120396 0.2794)
			(end -0.12065 0.2794)
			(stroke
				(width 0.1)
				(type default)
			)
			(layer "F.Fab")
		)
		(fp_line
			(start -0.12065 0.3048)
			(end -0.67945 0.3048)
			(stroke
				(width 0.1)
				(type default)
			)
			(layer "F.Fab")
		)
		(fp_line
			(start -0.12065 0.2794)
			(end -0.12065 0.3048)
			(stroke
				(width 0.1)
				(type default)
			)
			(layer "F.Fab")
		)
		(fp_line
			(start -0.12065 -0.2794)
			(end 0.12065 -0.2794)
			(stroke
				(width 0.1)
				(type default)
			)
			(layer "F.Fab")
		)
		(fp_line
			(start -0.12065 -0.305054)
			(end -0.12065 -0.2794)
			(stroke
				(width 0.1)
				(type default)
			)
			(layer "F.Fab")
		)
		(fp_line
			(start -0.67945 0.3048)
			(end -0.67945 -0.305054)
			(stroke
				(width 0.1)
				(type default)
			)
			(layer "F.Fab")
		)
		(fp_line
			(start -0.67945 -0.305054)
			(end -0.12065 -0.305054)
			(stroke
				(width 0.1)
				(type default)
			)
			(layer "F.Fab")
		)
		(pad "1" smd circle
			(at -0.40005 0 180)
			(size 0 0)
			(layers "F.Cu" "F.Mask" "F.Paste")
			(net "SW_P12V_P1V8_PEX_FLT")
		)
		(pad "2" smd circle
			(at 0.40005 0 180)
			(size 0 0)
			(layers "F.Cu" "F.Mask" "F.Paste")
			(net "GND")
		)
	)
	(footprint ""
		(layer "F.Cu")
		(at 201.871834 -24.807418)
		(property "Reference" "R431"
			(at 0 0 0)
			(layer "F.SilkS")
			(hide yes)
			(effects
				(font
					(size 1.27 1.27)
				)
			)
		)
		(property "Value" ""
			(at 0 0 0)
			(layer "F.Fab")
			(effects
				(font
					(size 1.27 1.27)
				)
			)
		)
		(duplicate_pad_numbers_are_jumpers no)
		(fp_line
			(start -0.7874 -0.4064)
			(end 0.7874 -0.4064)
			(stroke
				(width 0.1524)
				(type default)
			)
			(layer "F.SilkS")
		)
		(fp_line
			(start -0.7874 0.4064)
			(end -0.7874 -0.4064)
			(stroke
				(width 0.1524)
				(type default)
			)
			(layer "F.SilkS")
		)
		(fp_line
			(start 0.7874 -0.4064)
			(end 0.7874 0.4064)
			(stroke
				(width 0.1524)
				(type default)
			)
			(layer "F.SilkS")
		)
		(fp_line
			(start 0.7874 0.4064)
			(end -0.7874 0.4064)
			(stroke
				(width 0.1524)
				(type default)
			)
			(layer "F.SilkS")
		)
		(fp_line
			(start -0.67945 -0.305054)
			(end -0.12065 -0.305054)
			(stroke
				(width 0.1)
				(type default)
			)
			(layer "F.Fab")
		)
		(fp_line
			(start -0.67945 0.3048)
			(end -0.67945 -0.305054)
			(stroke
				(width 0.1)
				(type default)
			)
			(layer "F.Fab")
		)
		(fp_line
			(start -0.12065 -0.305054)
			(end -0.12065 -0.2794)
			(stroke
				(width 0.1)
				(type default)
			)
			(layer "F.Fab")
		)
		(fp_line
			(start -0.12065 -0.2794)
			(end 0.12065 -0.2794)
			(stroke
				(width 0.1)
				(type default)
			)
			(layer "F.Fab")
		)
		(fp_line
			(start -0.12065 0.2794)
			(end -0.12065 0.3048)
			(stroke
				(width 0.1)
				(type default)
			)
			(layer "F.Fab")
		)
		(fp_line
			(start -0.12065 0.3048)
			(end -0.67945 0.3048)
			(stroke
				(width 0.1)
				(type default)
			)
			(layer "F.Fab")
		)
		(fp_line
			(start 0.120396 0.2794)
			(end -0.12065 0.2794)
			(stroke
				(width 0.1)
				(type default)
			)
			(layer "F.Fab")
		)
		(fp_line
			(start 0.120396 0.3048)
			(end 0.120396 0.2794)
			(stroke
				(width 0.1)
				(type default)
			)
			(layer "F.Fab")
		)
		(fp_line
			(start 0.12065 -0.3048)
			(end 0.67945 -0.3048)
			(stroke
				(width 0.1)
				(type default)
			)
			(layer "F.Fab")
		)
		(fp_line
			(start 0.12065 -0.2794)
			(end 0.12065 -0.3048)
			(stroke
				(width 0.1)
				(type default)
			)
			(layer "F.Fab")
		)
		(fp_line
			(start 0.67945 -0.3048)
			(end 0.67945 0.3048)
			(stroke
				(width 0.1)
				(type default)
			)
			(layer "F.Fab")
		)
		(fp_line
			(start 0.67945 0.3048)
			(end 0.120396 0.3048)
			(stroke
				(width 0.1)
				(type default)
			)
			(layer "F.Fab")
		)
		(pad "1" smd circle
			(at -0.40005 0)
			(size 0 0)
			(layers "F.Cu" "F.Mask" "F.Paste")
			(net "P3V3_SSD7")
		)
		(pad "2" smd circle
			(at 0.40005 0)
			(size 0 0)
			(layers "F.Cu" "F.Mask" "F.Paste")
			(net "PU_CLKREQ7")
		)
	)
	(footprint ""
		(layer "F.Cu")
		(at 67.201288 -55.78475 -90)
		(property "Reference" "PD30"
			(at 3.96875 2.176018 90)
			(unlocked yes)
			(layer "F.SilkS")
			(effects
				(font
					(size 0.7874 0.5842)
					(thickness 0.1524)
				)
				(justify left)
			)
		)
		(property "Value" ""
			(at 0 0 270)
			(layer "F.Fab")
			(effects
				(font
					(size 1.27 1.27)
				)
			)
		)
		(duplicate_pad_numbers_are_jumpers no)
		(fp_line
			(start -3.400044 1.459992)
			(end -3.400044 -1.459992)
			(stroke
				(width 0.1524)
				(type default)
			)
			(layer "F.SilkS")
		)
		(fp_line
			(start 4.107942 1.459992)
			(end -3.400044 1.459992)
			(stroke
				(width 0.1524)
				(type default)
			)
			(layer "F.SilkS")
		)
		(fp_line
			(start -3.400044 -1.459992)
			(end 4.107942 -1.459992)
			(stroke
				(width 0.1524)
				(type default)
			)
			(layer "F.SilkS")
		)
		(fp_line
			(start 4.107942 -1.459992)
			(end 4.107942 1.459992)
			(stroke
				(width 0.1524)
				(type default)
			)
			(layer "F.SilkS")
		)
		(fp_poly
			(pts
				(xy 4.107942 -1.459992) (xy 4.107942 1.459992) (xy 3.308096 1.459992) (xy 3.308096 -1.459992)
			)
			(stroke
				(width 0)
				(type default)
			)
			(fill yes)
			(layer "F.SilkS")
		)
		(fp_line
			(start -2.29997 1.459992)
			(end -2.29997 -1.459992)
			(stroke
				(width 0.1)
				(type default)
			)
			(layer "F.Fab")
		)
		(fp_line
			(start 2.29997 1.459992)
			(end -2.29997 1.459992)
			(stroke
				(width 0.1)
				(type default)
			)
			(layer "F.Fab")
		)
		(fp_line
			(start -2.29997 -1.459992)
			(end 2.29997 -1.459992)
			(stroke
				(width 0.1)
				(type default)
			)
			(layer "F.Fab")
		)
		(fp_line
			(start 2.29997 -1.459992)
			(end 2.29997 1.459992)
			(stroke
				(width 0.1)
				(type default)
			)
			(layer "F.Fab")
		)
		(fp_text user "-"
			(at 5.4102 0.29845 90)
			(unlocked yes)
			(layer "F.SilkS")
			(effects
				(font
					(size 1.905 1.4224)
					(thickness 0.1524)
				)
				(justify left)
			)
		)
		(fp_text user "+"
			(at -4.7752 -0.12065 270)
			(unlocked yes)
			(layer "F.SilkS")
			(effects
				(font
					(size 1.905 1.4224)
					(thickness 0.1524)
				)
				(justify left)
			)
		)
		(fp_text user "-"
			(at 5.4102 0.29845 90)
			(unlocked yes)
			(layer "F.Fab")
			(effects
				(font
					(size 1.905 1.4224)
					(thickness 0.1524)
				)
				(justify left)
			)
		)
		(fp_text user "+"
			(at -4.7752 -0.12065 270)
			(unlocked yes)
			(layer "F.Fab")
			(effects
				(font
					(size 1.905 1.4224)
					(thickness 0.1524)
				)
				(justify left)
			)
		)
		(pad "A" smd rect
			(at -1.999996 0)
			(size 1.7018 2.5146)
			(layers "F.Cu" "F.Mask" "F.Paste")
			(net "GND")
		)
		(pad "C" smd rect
			(at 1.999996 0)
			(size 1.7018 2.5146)
			(layers "F.Cu" "F.Mask" "F.Paste")
			(net "P12V_SSD2_R")
		)
	)
	(footprint ""
		(layer "F.Cu")
		(at 381.579882 -229.16896 180)
		(property "Reference" "R907"
			(at 0 0 180)
			(layer "F.SilkS")
			(hide yes)
			(effects
				(font
					(size 1.27 1.27)
				)
			)
		)
		(property "Value" ""
			(at 0 0 180)
			(layer "F.Fab")
			(effects
				(font
					(size 1.27 1.27)
				)
			)
		)
		(duplicate_pad_numbers_are_jumpers no)
		(fp_line
			(start 1.2954 0.5842)
			(end -1.2954 0.5842)
			(stroke
				(width 0.1524)
				(type default)
			)
			(layer "F.SilkS")
		)
		(fp_line
			(start 1.2954 -0.5842)
			(end 1.2954 0.5842)
			(stroke
				(width 0.1524)
				(type default)
			)
			(layer "F.SilkS")
		)
		(fp_line
			(start -1.2954 0.5842)
			(end -1.2954 -0.5842)
			(stroke
				(width 0.1524)
				(type default)
			)
			(layer "F.SilkS")
		)
		(fp_line
			(start -1.2954 -0.5842)
			(end 1.2954 -0.5842)
			(stroke
				(width 0.1524)
				(type default)
			)
			(layer "F.SilkS")
		)
		(fp_line
			(start 1.1938 0.4064)
			(end 0.8636 0.4064)
			(stroke
				(width 0.1)
				(type default)
			)
			(layer "F.Fab")
		)
		(fp_line
			(start 1.1938 -0.406654)
			(end 1.1938 0.4064)
			(stroke
				(width 0.1)
				(type default)
			)
			(layer "F.Fab")
		)
		(fp_line
			(start 0.8636 0.4572)
			(end -0.8636 0.4572)
			(stroke
				(width 0.1)
				(type default)
			)
			(layer "F.Fab")
		)
		(fp_line
			(start 0.8636 0.4064)
			(end 0.8636 0.4572)
			(stroke
				(width 0.1)
				(type default)
			)
			(layer "F.Fab")
		)
		(fp_line
			(start 0.8636 -0.406654)
			(end 1.1938 -0.406654)
			(stroke
				(width 0.1)
				(type default)
			)
			(layer "F.Fab")
		)
		(fp_line
			(start 0.8636 -0.4572)
			(end 0.8636 -0.406654)
			(stroke
				(width 0.1)
				(type default)
			)
			(layer "F.Fab")
		)
		(fp_line
			(start -0.8636 0.4572)
			(end -0.8636 0.4318)
			(stroke
				(width 0.1)
				(type default)
			)
			(layer "F.Fab")
		)
		(fp_line
			(start -0.8636 0.4318)
			(end -0.8636 0.4064)
			(stroke
				(width 0.1)
				(type default)
			)
			(layer "F.Fab")
		)
		(fp_line
			(start -0.8636 0.4064)
			(end -1.1938 0.4064)
			(stroke
				(width 0.1)
				(type default)
			)
			(layer "F.Fab")
		)
		(fp_line
			(start -0.8636 -0.406654)
			(end -0.8636 -0.4572)
			(stroke
				(width 0.1)
				(type default)
			)
			(layer "F.Fab")
		)
		(fp_line
			(start -0.8636 -0.4572)
			(end 0.8636 -0.4572)
			(stroke
				(width 0.1)
				(type default)
			)
			(layer "F.Fab")
		)
		(fp_line
			(start -1.1938 0.4064)
			(end -1.1938 -0.406654)
			(stroke
				(width 0.1)
				(type default)
			)
			(layer "F.Fab")
		)
		(fp_line
			(start -1.1938 -0.406654)
			(end -0.8636 -0.406654)
			(stroke
				(width 0.1)
				(type default)
			)
			(layer "F.Fab")
		)
		(pad "1" smd rect
			(at -0.7366 0 90)
			(size 0.7112 0.8128)
			(layers "F.Cu" "F.Mask" "F.Paste")
			(net "OSC_SDB_OUT")
		)
		(pad "2" smd rect
			(at 0.7366 0 90)
			(size 0.7112 0.8128)
			(layers "F.Cu" "F.Mask" "F.Paste")
			(net "OSC_SDB_IN")
		)
	)
	(footprint ""
		(layer "F.Cu")
		(at 221.105476 -177.390552 180)
		(property "Reference" "C3649"
			(at 0 0 180)
			(layer "F.SilkS")
			(hide yes)
			(effects
				(font
					(size 1.27 1.27)
				)
			)
		)
		(property "Value" ""
			(at 0 0 180)
			(layer "F.Fab")
			(effects
				(font
					(size 1.27 1.27)
				)
			)
		)
		(duplicate_pad_numbers_are_jumpers no)
		(fp_line
			(start 0.7874 0.4064)
			(end -0.7874 0.4064)
			(stroke
				(width 0.1524)
				(type default)
			)
			(layer "F.SilkS")
		)
		(fp_line
			(start 0.7874 -0.4064)
			(end 0.7874 0.4064)
			(stroke
				(width 0.1524)
				(type default)
			)
			(layer "F.SilkS")
		)
		(fp_line
			(start -0.7874 0.4064)
			(end -0.7874 -0.4064)
			(stroke
				(width 0.1524)
				(type default)
			)
			(layer "F.SilkS")
		)
		(fp_line
			(start -0.7874 -0.4064)
			(end 0.7874 -0.4064)
			(stroke
				(width 0.1524)
				(type default)
			)
			(layer "F.SilkS")
		)
		(fp_line
			(start 0.67945 0.3048)
			(end 0.120396 0.3048)
			(stroke
				(width 0.1)
				(type default)
			)
			(layer "F.Fab")
		)
		(fp_line
			(start 0.67945 -0.3048)
			(end 0.67945 0.3048)
			(stroke
				(width 0.1)
				(type default)
			)
			(layer "F.Fab")
		)
		(fp_line
			(start 0.12065 -0.2794)
			(end 0.12065 -0.3048)
			(stroke
				(width 0.1)
				(type default)
			)
			(layer "F.Fab")
		)
		(fp_line
			(start 0.12065 -0.3048)
			(end 0.67945 -0.3048)
			(stroke
				(width 0.1)
				(type default)
			)
			(layer "F.Fab")
		)
		(fp_line
			(start 0.120396 0.3048)
			(end 0.120396 0.2794)
			(stroke
				(width 0.1)
				(type default)
			)
			(layer "F.Fab")
		)
		(fp_line
			(start 0.120396 0.2794)
			(end -0.12065 0.2794)
			(stroke
				(width 0.1)
				(type default)
			)
			(layer "F.Fab")
		)
		(fp_line
			(start -0.12065 0.3048)
			(end -0.67945 0.3048)
			(stroke
				(width 0.1)
				(type default)
			)
			(layer "F.Fab")
		)
		(fp_line
			(start -0.12065 0.2794)
			(end -0.12065 0.3048)
			(stroke
				(width 0.1)
				(type default)
			)
			(layer "F.Fab")
		)
		(fp_line
			(start -0.12065 -0.2794)
			(end 0.12065 -0.2794)
			(stroke
				(width 0.1)
				(type default)
			)
			(layer "F.Fab")
		)
		(fp_line
			(start -0.12065 -0.305054)
			(end -0.12065 -0.2794)
			(stroke
				(width 0.1)
				(type default)
			)
			(layer "F.Fab")
		)
		(fp_line
			(start -0.67945 0.3048)
			(end -0.67945 -0.305054)
			(stroke
				(width 0.1)
				(type default)
			)
			(layer "F.Fab")
		)
		(fp_line
			(start -0.67945 -0.305054)
			(end -0.12065 -0.305054)
			(stroke
				(width 0.1)
				(type default)
			)
			(layer "F.Fab")
		)
		(pad "1" smd circle
			(at -0.40005 0 180)
			(size 0 0)
			(layers "F.Cu" "F.Mask" "F.Paste")
			(net "GND")
		)
		(pad "2" smd circle
			(at 0.40005 0 180)
			(size 0 0)
			(layers "F.Cu" "F.Mask" "F.Paste")
			(net "P3V3_AUX")
		)
	)
	(footprint ""
		(layer "F.Cu")
		(at 77.611478 -71.458074 -90)
		(property "Reference" "PD85"
			(at 4.300474 -2.755392 90)
			(unlocked yes)
			(layer "F.SilkS")
			(effects
				(font
					(size 0.7874 0.5842)
					(thickness 0.1524)
				)
				(justify left)
			)
		)
		(property "Value" ""
			(at 0 0 270)
			(layer "F.Fab")
			(effects
				(font
					(size 1.27 1.27)
				)
			)
		)
		(duplicate_pad_numbers_are_jumpers no)
		(fp_line
			(start -3.656584 1.970024)
			(end 4.240784 1.970024)
			(stroke
				(width 0.1524)
				(type default)
			)
			(layer "F.SilkS")
		)
		(fp_line
			(start 4.240784 1.970024)
			(end 4.240784 -1.970024)
			(stroke
				(width 0.1524)
				(type default)
			)
			(layer "F.SilkS")
		)
		(fp_line
			(start -3.656584 -1.970024)
			(end -3.656584 1.970024)
			(stroke
				(width 0.1524)
				(type default)
			)
			(layer "F.SilkS")
		)
		(fp_line
			(start 4.240784 -1.970024)
			(end -3.656584 -1.970024)
			(stroke
				(width 0.1524)
				(type default)
			)
			(layer "F.SilkS")
		)
		(fp_poly
			(pts
				(xy 3.580384 1.970024) (xy 3.580384 -1.970024) (xy 4.240784 -1.970024) (xy 4.240784 1.970024)
			)
			(stroke
				(width 0)
				(type default)
			)
			(fill yes)
			(layer "F.SilkS")
		)
		(fp_line
			(start -2.3749 1.970024)
			(end 2.3749 1.970024)
			(stroke
				(width 0.1)
				(type default)
			)
			(layer "F.Fab")
		)
		(fp_line
			(start 2.3749 1.970024)
			(end 2.3749 -1.970024)
			(stroke
				(width 0.1)
				(type default)
			)
			(layer "F.Fab")
		)
		(fp_line
			(start -2.3749 -1.970024)
			(end -2.3749 1.970024)
			(stroke
				(width 0.1)
				(type default)
			)
			(layer "F.Fab")
		)
		(fp_line
			(start 2.3749 -1.970024)
			(end -2.3749 -1.970024)
			(stroke
				(width 0.1)
				(type default)
			)
			(layer "F.Fab")
		)
		(fp_text user "+"
			(at -4.9784 -0.23495 270)
			(unlocked yes)
			(layer "F.Fab")
			(effects
				(font
					(size 1.905 1.4224)
					(thickness 0.1524)
				)
				(justify left)
			)
		)
		(fp_text user "-"
			(at 4.1656 -0.23495 270)
			(unlocked yes)
			(layer "F.Fab")
			(effects
				(font
					(size 1.905 1.4224)
					(thickness 0.1524)
				)
				(justify left)
			)
		)
		(pad "A" smd rect
			(at -2.450084 0 270)
			(size 2.159 2.2606)
			(layers "F.Cu" "F.Mask" "F.Paste")
			(net "GND")
		)
		(pad "C" smd rect
			(at 2.450084 0 270)
			(size 2.159 2.2606)
			(layers "F.Cu" "F.Mask" "F.Paste")
			(net "P12V_AUX")
		)
	)
	(footprint ""
		(layer "F.Cu")
		(at 25.611582 -71.458074 -90)
		(property "Reference" "PD84"
			(at 2.370074 -2.736088 90)
			(unlocked yes)
			(layer "F.SilkS")
			(effects
				(font
					(size 0.7874 0.5842)
					(thickness 0.1524)
				)
				(justify left)
			)
		)
		(property "Value" ""
			(at 0 0 270)
			(layer "F.Fab")
			(effects
				(font
					(size 1.27 1.27)
				)
			)
		)
		(duplicate_pad_numbers_are_jumpers no)
		(fp_line
			(start -3.656584 1.970024)
			(end 4.240784 1.970024)
			(stroke
				(width 0.1524)
				(type default)
			)
			(layer "F.SilkS")
		)
		(fp_line
			(start 4.240784 1.970024)
			(end 4.240784 -1.970024)
			(stroke
				(width 0.1524)
				(type default)
			)
			(layer "F.SilkS")
		)
		(fp_line
			(start -3.656584 -1.970024)
			(end -3.656584 1.970024)
			(stroke
				(width 0.1524)
				(type default)
			)
			(layer "F.SilkS")
		)
		(fp_line
			(start 4.240784 -1.970024)
			(end -3.656584 -1.970024)
			(stroke
				(width 0.1524)
				(type default)
			)
			(layer "F.SilkS")
		)
		(fp_poly
			(pts
				(xy 3.580384 1.970024) (xy 3.580384 -1.970024) (xy 4.240784 -1.970024) (xy 4.240784 1.970024)
			)
			(stroke
				(width 0)
				(type default)
			)
			(fill yes)
			(layer "F.SilkS")
		)
		(fp_line
			(start -2.3749 1.970024)
			(end 2.3749 1.970024)
			(stroke
				(width 0.1)
				(type default)
			)
			(layer "F.Fab")
		)
		(fp_line
			(start 2.3749 1.970024)
			(end 2.3749 -1.970024)
			(stroke
				(width 0.1)
				(type default)
			)
			(layer "F.Fab")
		)
		(fp_line
			(start -2.3749 -1.970024)
			(end -2.3749 1.970024)
			(stroke
				(width 0.1)
				(type default)
			)
			(layer "F.Fab")
		)
		(fp_line
			(start 2.3749 -1.970024)
			(end -2.3749 -1.970024)
			(stroke
				(width 0.1)
				(type default)
			)
			(layer "F.Fab")
		)
		(fp_text user "+"
			(at -4.9784 -0.23495 270)
			(unlocked yes)
			(layer "F.Fab")
			(effects
				(font
					(size 1.905 1.4224)
					(thickness 0.1524)
				)
				(justify left)
			)
		)
		(fp_text user "-"
			(at 4.1656 -0.23495 270)
			(unlocked yes)
			(layer "F.Fab")
			(effects
				(font
					(size 1.905 1.4224)
					(thickness 0.1524)
				)
				(justify left)
			)
		)
		(pad "A" smd rect
			(at -2.450084 0 270)
			(size 2.159 2.2606)
			(layers "F.Cu" "F.Mask" "F.Paste")
			(net "GND")
		)
		(pad "C" smd rect
			(at 2.450084 0 270)
			(size 2.159 2.2606)
			(layers "F.Cu" "F.Mask" "F.Paste")
			(net "P12V_AUX")
		)
	)
	(footprint ""
		(layer "F.Cu")
		(at 328.311764 -204.678534 -90)
		(property "Reference" "C2842"
			(at 0 0 270)
			(layer "F.SilkS")
			(hide yes)
			(effects
				(font
					(size 1.27 1.27)
				)
			)
		)
		(property "Value" ""
			(at 0 0 270)
			(layer "F.Fab")
			(effects
				(font
					(size 1.27 1.27)
				)
			)
		)
		(duplicate_pad_numbers_are_jumpers no)
		(fp_line
			(start -0.7874 0.4064)
			(end -0.7874 -0.4064)
			(stroke
				(width 0.1524)
				(type default)
			)
			(layer "F.SilkS")
		)
		(fp_line
			(start 0.7874 0.4064)
			(end -0.7874 0.4064)
			(stroke
				(width 0.1524)
				(type default)
			)
			(layer "F.SilkS")
		)
		(fp_line
			(start -0.7874 -0.4064)
			(end 0.7874 -0.4064)
			(stroke
				(width 0.1524)
				(type default)
			)
			(layer "F.SilkS")
		)
		(fp_line
			(start 0.7874 -0.4064)
			(end 0.7874 0.4064)
			(stroke
				(width 0.1524)
				(type default)
			)
			(layer "F.SilkS")
		)
		(fp_line
			(start -0.67945 0.3048)
			(end -0.67945 -0.305054)
			(stroke
				(width 0.1)
				(type default)
			)
			(layer "F.Fab")
		)
		(fp_line
			(start -0.12065 0.3048)
			(end -0.67945 0.3048)
			(stroke
				(width 0.1)
				(type default)
			)
			(layer "F.Fab")
		)
		(fp_line
			(start 0.120396 0.3048)
			(end 0.120396 0.2794)
			(stroke
				(width 0.1)
				(type default)
			)
			(layer "F.Fab")
		)
		(fp_line
			(start 0.67945 0.3048)
			(end 0.120396 0.3048)
			(stroke
				(width 0.1)
				(type default)
			)
			(layer "F.Fab")
		)
		(fp_line
			(start -0.12065 0.2794)
			(end -0.12065 0.3048)
			(stroke
				(width 0.1)
				(type default)
			)
			(layer "F.Fab")
		)
		(fp_line
			(start 0.120396 0.2794)
			(end -0.12065 0.2794)
			(stroke
				(width 0.1)
				(type default)
			)
			(layer "F.Fab")
		)
		(fp_line
			(start -0.12065 -0.2794)
			(end 0.12065 -0.2794)
			(stroke
				(width 0.1)
				(type default)
			)
			(layer "F.Fab")
		)
		(fp_line
			(start 0.12065 -0.2794)
			(end 0.12065 -0.3048)
			(stroke
				(width 0.1)
				(type default)
			)
			(layer "F.Fab")
		)
		(fp_line
			(start 0.12065 -0.3048)
			(end 0.67945 -0.3048)
			(stroke
				(width 0.1)
				(type default)
			)
			(layer "F.Fab")
		)
		(fp_line
			(start 0.67945 -0.3048)
			(end 0.67945 0.3048)
			(stroke
				(width 0.1)
				(type default)
			)
			(layer "F.Fab")
		)
		(fp_line
			(start -0.67945 -0.305054)
			(end -0.12065 -0.305054)
			(stroke
				(width 0.1)
				(type default)
			)
			(layer "F.Fab")
		)
		(fp_line
			(start -0.12065 -0.305054)
			(end -0.12065 -0.2794)
			(stroke
				(width 0.1)
				(type default)
			)
			(layer "F.Fab")
		)
		(pad "1" smd circle
			(at -0.40005 0 270)
			(size 0 0)
			(layers "F.Cu" "F.Mask" "F.Paste")
			(net "P3V3_AUX")
		)
		(pad "2" smd circle
			(at 0.40005 0 270)
			(size 0 0)
			(layers "F.Cu" "F.Mask" "F.Paste")
			(net "GND")
		)
	)
	(footprint ""
		(layer "F.Cu")
		(at 185.939938 -70.52437 90)
		(property "Reference" "PC854"
			(at 0 0 90)
			(layer "F.SilkS")
			(hide yes)
			(effects
				(font
					(size 1.27 1.27)
				)
			)
		)
		(property "Value" ""
			(at 0 0 90)
			(layer "F.Fab")
			(effects
				(font
					(size 1.27 1.27)
				)
			)
		)
		(duplicate_pad_numbers_are_jumpers no)
		(fp_line
			(start 1.524 -0.762)
			(end 1.524 0.762)
			(stroke
				(width 0.1524)
				(type default)
			)
			(layer "F.SilkS")
		)
		(fp_line
			(start -1.524 -0.762)
			(end 1.524 -0.762)
			(stroke
				(width 0.1524)
				(type default)
			)
			(layer "F.SilkS")
		)
		(fp_line
			(start 1.524 0.762)
			(end -1.524 0.762)
			(stroke
				(width 0.1524)
				(type default)
			)
			(layer "F.SilkS")
		)
		(fp_line
			(start -1.524 0.762)
			(end -1.524 -0.762)
			(stroke
				(width 0.1524)
				(type default)
			)
			(layer "F.SilkS")
		)
		(fp_line
			(start 1.1049 -0.724916)
			(end -1.1049 -0.724916)
			(stroke
				(width 0.1)
				(type default)
			)
			(layer "F.Fab")
		)
		(fp_line
			(start -1.1049 -0.724916)
			(end -1.1049 0.724916)
			(stroke
				(width 0.1)
				(type default)
			)
			(layer "F.Fab")
		)
		(fp_line
			(start 1.1049 0.724916)
			(end 1.1049 -0.724916)
			(stroke
				(width 0.1)
				(type default)
			)
			(layer "F.Fab")
		)
		(fp_line
			(start -1.1049 0.724916)
			(end 1.1049 0.724916)
			(stroke
				(width 0.1)
				(type default)
			)
			(layer "F.Fab")
		)
		(pad "1" smd rect
			(at -0.889 0 270)
			(size 1.016 1.27)
			(layers "F.Cu" "F.Mask" "F.Paste")
			(net "P12V_SSD6_R")
		)
		(pad "2" smd rect
			(at 0.889 0 270)
			(size 1.016 1.27)
			(layers "F.Cu" "F.Mask" "F.Paste")
			(net "GND")
		)
	)
	(footprint ""
		(layer "F.Cu")
		(at 264.616946 -308.852062 -135)
		(property "Reference" "R1395"
			(at 0 0 225)
			(layer "F.SilkS")
			(hide yes)
			(effects
				(font
					(size 1.27 1.27)
				)
			)
		)
		(property "Value" ""
			(at 0 0 225)
			(layer "F.Fab")
			(effects
				(font
					(size 1.27 1.27)
				)
			)
		)
		(duplicate_pad_numbers_are_jumpers no)
		(fp_line
			(start 0.787389 0.406267)
			(end -0.787389 0.406267)
			(stroke
				(width 0.1524)
				(type default)
			)
			(layer "F.SilkS")
		)
		(fp_line
			(start 0.787389 -0.406267)
			(end 0.787389 0.406267)
			(stroke
				(width 0.1524)
				(type default)
			)
			(layer "F.SilkS")
		)
		(fp_line
			(start -0.787389 0.406267)
			(end -0.787389 -0.406267)
			(stroke
				(width 0.1524)
				(type default)
			)
			(layer "F.SilkS")
		)
		(fp_line
			(start -0.787389 -0.406267)
			(end 0.787389 -0.406267)
			(stroke
				(width 0.1524)
				(type default)
			)
			(layer "F.SilkS")
		)
		(fp_line
			(start 0.679446 0.30479)
			(end 0.120515 0.30479)
			(stroke
				(width 0.1)
				(type default)
			)
			(layer "F.Fab")
		)
		(fp_line
			(start 0.120515 0.30479)
			(end 0.120335 0.279466)
			(stroke
				(width 0.1)
				(type default)
			)
			(layer "F.Fab")
		)
		(fp_line
			(start 0.120335 0.279466)
			(end -0.120695 0.279466)
			(stroke
				(width 0.1)
				(type default)
			)
			(layer "F.Fab")
		)
		(fp_line
			(start 0.679446 -0.30479)
			(end 0.679446 0.30479)
			(stroke
				(width 0.1)
				(type default)
			)
			(layer "F.Fab")
		)
		(fp_line
			(start -0.120515 0.30479)
			(end -0.679446 0.30479)
			(stroke
				(width 0.1)
				(type default)
			)
			(layer "F.Fab")
		)
		(fp_line
			(start -0.120695 0.279466)
			(end -0.120515 0.30479)
			(stroke
				(width 0.1)
				(type default)
			)
			(layer "F.Fab")
		)
		(fp_line
			(start 0.120695 -0.279466)
			(end 0.120515 -0.30479)
			(stroke
				(width 0.1)
				(type default)
			)
			(layer "F.Fab")
		)
		(fp_line
			(start 0.120515 -0.30479)
			(end 0.679446 -0.30479)
			(stroke
				(width 0.1)
				(type default)
			)
			(layer "F.Fab")
		)
		(fp_line
			(start -0.679446 0.30479)
			(end -0.679446 -0.305149)
			(stroke
				(width 0.1)
				(type default)
			)
			(layer "F.Fab")
		)
		(fp_line
			(start -0.120695 -0.279466)
			(end 0.120695 -0.279466)
			(stroke
				(width 0.1)
				(type default)
			)
			(layer "F.Fab")
		)
		(fp_line
			(start -0.120695 -0.304969)
			(end -0.120695 -0.279466)
			(stroke
				(width 0.1)
				(type default)
			)
			(layer "F.Fab")
		)
		(fp_line
			(start -0.679446 -0.305149)
			(end -0.120695 -0.304969)
			(stroke
				(width 0.1)
				(type default)
			)
			(layer "F.Fab")
		)
		(pad "1" smd circle
			(at -0.40005 0 225)
			(size 0 0)
			(layers "F.Cu" "F.Mask" "F.Paste")
			(net "PU_PEX2_ATPG_MODE_L")
		)
		(pad "2" smd circle
			(at 0.40005 0 225)
			(size 0 0)
			(layers "F.Cu" "F.Mask" "F.Paste")
			(net "P1V8_PEX")
		)
	)
	(footprint ""
		(layer "F.Cu")
		(at 43.94708 -55.63489 90)
		(property "Reference" "PC645"
			(at 0 0 90)
			(layer "F.SilkS")
			(hide yes)
			(effects
				(font
					(size 1.27 1.27)
				)
			)
		)
		(property "Value" ""
			(at 0 0 90)
			(layer "F.Fab")
			(effects
				(font
					(size 1.27 1.27)
				)
			)
		)
		(duplicate_pad_numbers_are_jumpers no)
		(fp_line
			(start 1.524 -0.762)
			(end 1.524 0.762)
			(stroke
				(width 0.1524)
				(type default)
			)
			(layer "F.SilkS")
		)
		(fp_line
			(start -1.524 -0.762)
			(end 1.524 -0.762)
			(stroke
				(width 0.1524)
				(type default)
			)
			(layer "F.SilkS")
		)
		(fp_line
			(start 1.524 0.762)
			(end -1.524 0.762)
			(stroke
				(width 0.1524)
				(type default)
			)
			(layer "F.SilkS")
		)
		(fp_line
			(start -1.524 0.762)
			(end -1.524 -0.762)
			(stroke
				(width 0.1524)
				(type default)
			)
			(layer "F.SilkS")
		)
		(fp_line
			(start 1.1049 -0.724916)
			(end -1.1049 -0.724916)
			(stroke
				(width 0.1)
				(type default)
			)
			(layer "F.Fab")
		)
		(fp_line
			(start -1.1049 -0.724916)
			(end -1.1049 0.724916)
			(stroke
				(width 0.1)
				(type default)
			)
			(layer "F.Fab")
		)
		(fp_line
			(start 1.1049 0.724916)
			(end 1.1049 -0.724916)
			(stroke
				(width 0.1)
				(type default)
			)
			(layer "F.Fab")
		)
		(fp_line
			(start -1.1049 0.724916)
			(end 1.1049 0.724916)
			(stroke
				(width 0.1)
				(type default)
			)
			(layer "F.Fab")
		)
		(pad "1" smd rect
			(at -0.889 0 270)
			(size 1.016 1.27)
			(layers "F.Cu" "F.Mask" "F.Paste")
			(net "P12V_SSD1_R")
		)
		(pad "2" smd rect
			(at 0.889 0 270)
			(size 1.016 1.27)
			(layers "F.Cu" "F.Mask" "F.Paste")
			(net "GND")
		)
	)
	(footprint ""
		(layer "F.Cu")
		(at 286.982408 -29.875734)
		(property "Reference" "PU129"
			(at -3.447796 -2.207768 90)
			(unlocked yes)
			(layer "F.SilkS")
			(effects
				(font
					(size 0.7874 0.5842)
					(thickness 0.1524)
				)
			)
		)
		(property "Value" ""
			(at 0 0 0)
			(layer "F.Fab")
			(effects
				(font
					(size 1.27 1.27)
				)
			)
		)
		(duplicate_pad_numbers_are_jumpers no)
		(fp_line
			(start -1.239774 -1.495298)
			(end 1.239774 -1.495298)
			(stroke
				(width 0.1524)
				(type default)
			)
			(layer "F.SilkS")
		)
		(fp_line
			(start -1.239774 1.495298)
			(end -1.239774 -1.495298)
			(stroke
				(width 0.1524)
				(type default)
			)
			(layer "F.SilkS")
		)
		(fp_line
			(start 1.239774 -1.495298)
			(end 1.239774 1.495298)
			(stroke
				(width 0.1524)
				(type default)
			)
			(layer "F.SilkS")
		)
		(fp_line
			(start 1.239774 1.495298)
			(end -1.239774 1.495298)
			(stroke
				(width 0.1524)
				(type default)
			)
			(layer "F.SilkS")
		)
		(fp_poly
			(pts
				(xy -2.232914 -1.512824) (xy -2.951226 -0.794258) (xy -1.873504 -0.435102)
			)
			(stroke
				(width 0)
				(type default)
			)
			(fill yes)
			(layer "F.SilkS")
		)
		(fp_line
			(start -0.8001 -1.050036)
			(end 0.8001 -1.050036)
			(stroke
				(width 0.1)
				(type default)
			)
			(layer "F.Fab")
		)
		(fp_line
			(start -0.8001 1.050036)
			(end -0.8001 -1.050036)
			(stroke
				(width 0.1)
				(type default)
			)
			(layer "F.Fab")
		)
		(fp_line
			(start 0.8001 -1.050036)
			(end 0.8001 1.050036)
			(stroke
				(width 0.1)
				(type default)
			)
			(layer "F.Fab")
		)
		(fp_line
			(start 0.8001 1.050036)
			(end -0.8001 1.050036)
			(stroke
				(width 0.1)
				(type default)
			)
			(layer "F.Fab")
		)
		(fp_poly
			(pts
				(xy -2.458974 -0.508) (xy -2.458974 0.508) (xy -1.442974 0)
			)
			(stroke
				(width 0)
				(type default)
			)
			(fill yes)
			(layer "F.Fab")
		)
		(pad "1_2" smd circle
			(at -0.374904 0 90)
			(size 0 0)
			(layers "F.Cu" "F.Mask" "F.Paste")
			(net "P3V3_AUX")
		)
		(pad "3" smd rect
			(at -0.499872 0.999998)
			(size 0.254 0.7112)
			(layers "F.Cu" "F.Mask" "F.Paste")
			(net "GND")
		)
		(pad "4" smd rect
			(at 0 0.999998)
			(size 0.254 0.7112)
			(layers "F.Cu" "F.Mask" "F.Paste")
			(net "P3V3_SSD10_CO_ILIMIT")
		)
		(pad "5" smd rect
			(at 0.499872 0.999998)
			(size 0.254 0.7112)
			(layers "F.Cu" "F.Mask" "F.Paste")
			(net "P3V3_SSD10_CO_MODE")
		)
		(pad "6_7" smd circle
			(at 0.374904 0 270)
			(size 0 0)
			(layers "F.Cu" "F.Mask" "F.Paste")
			(net "P3V3_SSD10")
		)
		(pad "8" smd rect
			(at 0.499872 -0.999998)
			(size 0.254 0.7112)
			(layers "F.Cu" "F.Mask" "F.Paste")
			(net "P3V3_SSD10_CO_GATE")
		)
		(pad "9" smd rect
			(at 0 -0.999998)
			(size 0.254 0.7112)
			(layers "F.Cu" "F.Mask" "F.Paste")
			(net "P3V3_SSD10_CO_EN")
		)
		(pad "10" smd rect
			(at -0.499872 -0.999998)
			(size 0.254 0.7112)
			(layers "F.Cu" "F.Mask" "F.Paste")
			(net "P3V3_SSD10_CO_DV_DT")
		)
	)
	(footprint ""
		(layer "F.Cu")
		(at 248.187972 -45.704252 90)
		(property "Reference" "R593"
			(at 0 0 90)
			(layer "F.SilkS")
			(hide yes)
			(effects
				(font
					(size 1.27 1.27)
				)
			)
		)
		(property "Value" ""
			(at 0 0 90)
			(layer "F.Fab")
			(effects
				(font
					(size 1.27 1.27)
				)
			)
		)
		(duplicate_pad_numbers_are_jumpers no)
		(fp_line
			(start 3.937508 -1.8796)
			(end -3.937508 -1.8796)
			(stroke
				(width 0.1524)
				(type default)
			)
			(layer "F.SilkS")
		)
		(fp_line
			(start -3.937508 -1.8796)
			(end -3.937508 1.8796)
			(stroke
				(width 0.1524)
				(type default)
			)
			(layer "F.SilkS")
		)
		(fp_line
			(start 3.937508 1.8796)
			(end 3.937508 -1.8796)
			(stroke
				(width 0.1524)
				(type default)
			)
			(layer "F.SilkS")
		)
		(fp_line
			(start -3.937508 1.8796)
			(end 3.937508 1.8796)
			(stroke
				(width 0.1524)
				(type default)
			)
			(layer "F.SilkS")
		)
		(fp_line
			(start 3.275076 -1.674876)
			(end -3.275076 -1.674876)
			(stroke
				(width 0.1)
				(type default)
			)
			(layer "F.Fab")
		)
		(fp_line
			(start -3.275076 -1.674876)
			(end -3.275076 1.674876)
			(stroke
				(width 0.1)
				(type default)
			)
			(layer "F.Fab")
		)
		(fp_line
			(start 3.275076 1.674876)
			(end 3.275076 -1.674876)
			(stroke
				(width 0.1)
				(type default)
			)
			(layer "F.Fab")
		)
		(fp_line
			(start -3.275076 1.674876)
			(end 3.275076 1.674876)
			(stroke
				(width 0.1)
				(type default)
			)
			(layer "F.Fab")
		)
		(pad "1" smd rect
			(at -2.350008 0 90)
			(size 2.921 3.5052)
			(layers "F.Cu" "F.Mask" "F.Paste")
			(net "P12V_SSD8")
		)
		(pad "2" smd rect
			(at 2.350008 0 90)
			(size 2.921 3.5052)
			(layers "F.Cu" "F.Mask" "F.Paste")
			(net "P12V_SSD8_R")
		)
	)
	(footprint ""
		(layer "F.Cu")
		(at 95.818198 -95.31477 90)
		(property "Reference" "R855"
			(at 0 0 90)
			(layer "F.SilkS")
			(hide yes)
			(effects
				(font
					(size 1.27 1.27)
				)
			)
		)
		(property "Value" ""
			(at 0 0 90)
			(layer "F.Fab")
			(effects
				(font
					(size 1.27 1.27)
				)
			)
		)
		(duplicate_pad_numbers_are_jumpers no)
		(fp_line
			(start 0.7874 -0.4064)
			(end 0.7874 0.4064)
			(stroke
				(width 0.1524)
				(type default)
			)
			(layer "F.SilkS")
		)
		(fp_line
			(start -0.7874 -0.4064)
			(end 0.7874 -0.4064)
			(stroke
				(width 0.1524)
				(type default)
			)
			(layer "F.SilkS")
		)
		(fp_line
			(start 0.7874 0.4064)
			(end -0.7874 0.4064)
			(stroke
				(width 0.1524)
				(type default)
			)
			(layer "F.SilkS")
		)
		(fp_line
			(start -0.7874 0.4064)
			(end -0.7874 -0.4064)
			(stroke
				(width 0.1524)
				(type default)
			)
			(layer "F.SilkS")
		)
		(fp_line
			(start -0.12065 -0.305054)
			(end -0.12065 -0.2794)
			(stroke
				(width 0.1)
				(type default)
			)
			(layer "F.Fab")
		)
		(fp_line
			(start -0.67945 -0.305054)
			(end -0.12065 -0.305054)
			(stroke
				(width 0.1)
				(type default)
			)
			(layer "F.Fab")
		)
		(fp_line
			(start 0.67945 -0.3048)
			(end 0.67945 0.3048)
			(stroke
				(width 0.1)
				(type default)
			)
			(layer "F.Fab")
		)
		(fp_line
			(start 0.12065 -0.3048)
			(end 0.67945 -0.3048)
			(stroke
				(width 0.1)
				(type default)
			)
			(layer "F.Fab")
		)
		(fp_line
			(start 0.12065 -0.2794)
			(end 0.12065 -0.3048)
			(stroke
				(width 0.1)
				(type default)
			)
			(layer "F.Fab")
		)
		(fp_line
			(start -0.12065 -0.2794)
			(end 0.12065 -0.2794)
			(stroke
				(width 0.1)
				(type default)
			)
			(layer "F.Fab")
		)
		(fp_line
			(start 0.120396 0.2794)
			(end -0.12065 0.2794)
			(stroke
				(width 0.1)
				(type default)
			)
			(layer "F.Fab")
		)
		(fp_line
			(start -0.12065 0.2794)
			(end -0.12065 0.3048)
			(stroke
				(width 0.1)
				(type default)
			)
			(layer "F.Fab")
		)
		(fp_line
			(start 0.67945 0.3048)
			(end 0.120396 0.3048)
			(stroke
				(width 0.1)
				(type default)
			)
			(layer "F.Fab")
		)
		(fp_line
			(start 0.120396 0.3048)
			(end 0.120396 0.2794)
			(stroke
				(width 0.1)
				(type default)
			)
			(layer "F.Fab")
		)
		(fp_line
			(start -0.12065 0.3048)
			(end -0.67945 0.3048)
			(stroke
				(width 0.1)
				(type default)
			)
			(layer "F.Fab")
		)
		(fp_line
			(start -0.67945 0.3048)
			(end -0.67945 -0.305054)
			(stroke
				(width 0.1)
				(type default)
			)
			(layer "F.Fab")
		)
		(pad "1" smd circle
			(at -0.40005 0 90)
			(size 0 0)
			(layers "F.Cu" "F.Mask" "F.Paste")
			(net "P3V3_AUX")
		)
		(pad "2" smd circle
			(at 0.40005 0 90)
			(size 0 0)
			(layers "F.Cu" "F.Mask" "F.Paste")
			(net "PWRGD_P12V_NIC1")
		)
	)
	(footprint ""
		(layer "F.Cu")
		(at 227.104956 -305.118262)
		(property "Reference" "PC231"
			(at 0 0 0)
			(layer "F.SilkS")
			(hide yes)
			(effects
				(font
					(size 1.27 1.27)
				)
			)
		)
		(property "Value" ""
			(at 0 0 0)
			(layer "F.Fab")
			(effects
				(font
					(size 1.27 1.27)
				)
			)
		)
		(duplicate_pad_numbers_are_jumpers no)
		(fp_line
			(start -0.7874 -0.4064)
			(end 0.7874 -0.4064)
			(stroke
				(width 0.1524)
				(type default)
			)
			(layer "F.SilkS")
		)
		(fp_line
			(start -0.7874 0.4064)
			(end -0.7874 -0.4064)
			(stroke
				(width 0.1524)
				(type default)
			)
			(layer "F.SilkS")
		)
		(fp_line
			(start 0.7874 -0.4064)
			(end 0.7874 0.4064)
			(stroke
				(width 0.1524)
				(type default)
			)
			(layer "F.SilkS")
		)
		(fp_line
			(start 0.7874 0.4064)
			(end -0.7874 0.4064)
			(stroke
				(width 0.1524)
				(type default)
			)
			(layer "F.SilkS")
		)
		(fp_line
			(start -0.67945 -0.305054)
			(end -0.12065 -0.305054)
			(stroke
				(width 0.1)
				(type default)
			)
			(layer "F.Fab")
		)
		(fp_line
			(start -0.67945 0.3048)
			(end -0.67945 -0.305054)
			(stroke
				(width 0.1)
				(type default)
			)
			(layer "F.Fab")
		)
		(fp_line
			(start -0.12065 -0.305054)
			(end -0.12065 -0.2794)
			(stroke
				(width 0.1)
				(type default)
			)
			(layer "F.Fab")
		)
		(fp_line
			(start -0.12065 -0.2794)
			(end 0.12065 -0.2794)
			(stroke
				(width 0.1)
				(type default)
			)
			(layer "F.Fab")
		)
		(fp_line
			(start -0.12065 0.2794)
			(end -0.12065 0.3048)
			(stroke
				(width 0.1)
				(type default)
			)
			(layer "F.Fab")
		)
		(fp_line
			(start -0.12065 0.3048)
			(end -0.67945 0.3048)
			(stroke
				(width 0.1)
				(type default)
			)
			(layer "F.Fab")
		)
		(fp_line
			(start 0.120396 0.2794)
			(end -0.12065 0.2794)
			(stroke
				(width 0.1)
				(type default)
			)
			(layer "F.Fab")
		)
		(fp_line
			(start 0.120396 0.3048)
			(end 0.120396 0.2794)
			(stroke
				(width 0.1)
				(type default)
			)
			(layer "F.Fab")
		)
		(fp_line
			(start 0.12065 -0.3048)
			(end 0.67945 -0.3048)
			(stroke
				(width 0.1)
				(type default)
			)
			(layer "F.Fab")
		)
		(fp_line
			(start 0.12065 -0.2794)
			(end 0.12065 -0.3048)
			(stroke
				(width 0.1)
				(type default)
			)
			(layer "F.Fab")
		)
		(fp_line
			(start 0.67945 -0.3048)
			(end 0.67945 0.3048)
			(stroke
				(width 0.1)
				(type default)
			)
			(layer "F.Fab")
		)
		(fp_line
			(start 0.67945 0.3048)
			(end 0.120396 0.3048)
			(stroke
				(width 0.1)
				(type default)
			)
			(layer "F.Fab")
		)
		(pad "1" smd circle
			(at -0.40005 0)
			(size 0 0)
			(layers "F.Cu" "F.Mask" "F.Paste")
			(net "SW_P1V25_PEX1_BT")
		)
		(pad "2" smd circle
			(at 0.40005 0)
			(size 0 0)
			(layers "F.Cu" "F.Mask" "F.Paste")
			(net "SW_P1V25_PEX1_PH")
		)
	)
	(footprint ""
		(layer "F.Cu")
		(at 411.86735 -171.675806)
		(property "Reference" "R355"
			(at 0 0 0)
			(layer "F.SilkS")
			(hide yes)
			(effects
				(font
					(size 1.27 1.27)
				)
			)
		)
		(property "Value" ""
			(at 0 0 0)
			(layer "F.Fab")
			(effects
				(font
					(size 1.27 1.27)
				)
			)
		)
		(duplicate_pad_numbers_are_jumpers no)
		(fp_line
			(start -0.7874 -0.4064)
			(end 0.7874 -0.4064)
			(stroke
				(width 0.1524)
				(type default)
			)
			(layer "F.SilkS")
		)
		(fp_line
			(start -0.7874 0.4064)
			(end -0.7874 -0.4064)
			(stroke
				(width 0.1524)
				(type default)
			)
			(layer "F.SilkS")
		)
		(fp_line
			(start 0.7874 -0.4064)
			(end 0.7874 0.4064)
			(stroke
				(width 0.1524)
				(type default)
			)
			(layer "F.SilkS")
		)
		(fp_line
			(start 0.7874 0.4064)
			(end -0.7874 0.4064)
			(stroke
				(width 0.1524)
				(type default)
			)
			(layer "F.SilkS")
		)
		(fp_line
			(start -0.67945 -0.305054)
			(end -0.12065 -0.305054)
			(stroke
				(width 0.1)
				(type default)
			)
			(layer "F.Fab")
		)
		(fp_line
			(start -0.67945 0.3048)
			(end -0.67945 -0.305054)
			(stroke
				(width 0.1)
				(type default)
			)
			(layer "F.Fab")
		)
		(fp_line
			(start -0.12065 -0.305054)
			(end -0.12065 -0.2794)
			(stroke
				(width 0.1)
				(type default)
			)
			(layer "F.Fab")
		)
		(fp_line
			(start -0.12065 -0.2794)
			(end 0.12065 -0.2794)
			(stroke
				(width 0.1)
				(type default)
			)
			(layer "F.Fab")
		)
		(fp_line
			(start -0.12065 0.2794)
			(end -0.12065 0.3048)
			(stroke
				(width 0.1)
				(type default)
			)
			(layer "F.Fab")
		)
		(fp_line
			(start -0.12065 0.3048)
			(end -0.67945 0.3048)
			(stroke
				(width 0.1)
				(type default)
			)
			(layer "F.Fab")
		)
		(fp_line
			(start 0.120396 0.2794)
			(end -0.12065 0.2794)
			(stroke
				(width 0.1)
				(type default)
			)
			(layer "F.Fab")
		)
		(fp_line
			(start 0.120396 0.3048)
			(end 0.120396 0.2794)
			(stroke
				(width 0.1)
				(type default)
			)
			(layer "F.Fab")
		)
		(fp_line
			(start 0.12065 -0.3048)
			(end 0.67945 -0.3048)
			(stroke
				(width 0.1)
				(type default)
			)
			(layer "F.Fab")
		)
		(fp_line
			(start 0.12065 -0.2794)
			(end 0.12065 -0.3048)
			(stroke
				(width 0.1)
				(type default)
			)
			(layer "F.Fab")
		)
		(fp_line
			(start 0.67945 -0.3048)
			(end 0.67945 0.3048)
			(stroke
				(width 0.1)
				(type default)
			)
			(layer "F.Fab")
		)
		(fp_line
			(start 0.67945 0.3048)
			(end 0.120396 0.3048)
			(stroke
				(width 0.1)
				(type default)
			)
			(layer "F.Fab")
		)
		(pad "1" smd circle
			(at -0.40005 0)
			(size 0 0)
			(layers "F.Cu" "F.Mask" "F.Paste")
			(net "P3V3_NIC6")
		)
		(pad "2" smd circle
			(at 0.40005 0)
			(size 0 0)
			(layers "F.Cu" "F.Mask" "F.Paste")
			(net "HP_NIC6_PWRGD")
		)
	)
	(footprint ""
		(layer "F.Cu")
		(at 123.982226 -279.486868 -90)
		(property "Reference" "PR110"
			(at 0 0 270)
			(layer "F.SilkS")
			(hide yes)
			(effects
				(font
					(size 1.27 1.27)
				)
			)
		)
		(property "Value" ""
			(at 0 0 270)
			(layer "F.Fab")
			(effects
				(font
					(size 1.27 1.27)
				)
			)
		)
		(duplicate_pad_numbers_are_jumpers no)
		(fp_line
			(start -0.7874 0.4064)
			(end -0.7874 -0.4064)
			(stroke
				(width 0.1524)
				(type default)
			)
			(layer "F.SilkS")
		)
		(fp_line
			(start 0.7874 0.4064)
			(end -0.7874 0.4064)
			(stroke
				(width 0.1524)
				(type default)
			)
			(layer "F.SilkS")
		)
		(fp_line
			(start -0.7874 -0.4064)
			(end 0.7874 -0.4064)
			(stroke
				(width 0.1524)
				(type default)
			)
			(layer "F.SilkS")
		)
		(fp_line
			(start 0.7874 -0.4064)
			(end 0.7874 0.4064)
			(stroke
				(width 0.1524)
				(type default)
			)
			(layer "F.SilkS")
		)
		(fp_line
			(start -0.67945 0.3048)
			(end -0.67945 -0.305054)
			(stroke
				(width 0.1)
				(type default)
			)
			(layer "F.Fab")
		)
		(fp_line
			(start -0.12065 0.3048)
			(end -0.67945 0.3048)
			(stroke
				(width 0.1)
				(type default)
			)
			(layer "F.Fab")
		)
		(fp_line
			(start 0.120396 0.3048)
			(end 0.120396 0.2794)
			(stroke
				(width 0.1)
				(type default)
			)
			(layer "F.Fab")
		)
		(fp_line
			(start 0.67945 0.3048)
			(end 0.120396 0.3048)
			(stroke
				(width 0.1)
				(type default)
			)
			(layer "F.Fab")
		)
		(fp_line
			(start -0.12065 0.2794)
			(end -0.12065 0.3048)
			(stroke
				(width 0.1)
				(type default)
			)
			(layer "F.Fab")
		)
		(fp_line
			(start 0.120396 0.2794)
			(end -0.12065 0.2794)
			(stroke
				(width 0.1)
				(type default)
			)
			(layer "F.Fab")
		)
		(fp_line
			(start -0.12065 -0.2794)
			(end 0.12065 -0.2794)
			(stroke
				(width 0.1)
				(type default)
			)
			(layer "F.Fab")
		)
		(fp_line
			(start 0.12065 -0.2794)
			(end 0.12065 -0.3048)
			(stroke
				(width 0.1)
				(type default)
			)
			(layer "F.Fab")
		)
		(fp_line
			(start 0.12065 -0.3048)
			(end 0.67945 -0.3048)
			(stroke
				(width 0.1)
				(type default)
			)
			(layer "F.Fab")
		)
		(fp_line
			(start 0.67945 -0.3048)
			(end 0.67945 0.3048)
			(stroke
				(width 0.1)
				(type default)
			)
			(layer "F.Fab")
		)
		(fp_line
			(start -0.67945 -0.305054)
			(end -0.12065 -0.305054)
			(stroke
				(width 0.1)
				(type default)
			)
			(layer "F.Fab")
		)
		(fp_line
			(start -0.12065 -0.305054)
			(end -0.12065 -0.2794)
			(stroke
				(width 0.1)
				(type default)
			)
			(layer "F.Fab")
		)
		(pad "1" smd circle
			(at -0.40005 0 270)
			(size 0 0)
			(layers "F.Cu" "F.Mask" "F.Paste")
			(net "P0V8_PEX1_LSET1")
		)
		(pad "2" smd circle
			(at 0.40005 0 270)
			(size 0 0)
			(layers "F.Cu" "F.Mask" "F.Paste")
			(net "GND")
		)
	)
	(footprint ""
		(layer "F.Cu")
		(at 13.137896 -272.481294 180)
		(property "Reference" "R777"
			(at 0 0 180)
			(layer "F.SilkS")
			(hide yes)
			(effects
				(font
					(size 1.27 1.27)
				)
			)
		)
		(property "Value" ""
			(at 0 0 180)
			(layer "F.Fab")
			(effects
				(font
					(size 1.27 1.27)
				)
			)
		)
		(duplicate_pad_numbers_are_jumpers no)
		(fp_line
			(start 0.7874 0.4064)
			(end -0.7874 0.4064)
			(stroke
				(width 0.1524)
				(type default)
			)
			(layer "F.SilkS")
		)
		(fp_line
			(start 0.7874 -0.4064)
			(end 0.7874 0.4064)
			(stroke
				(width 0.1524)
				(type default)
			)
			(layer "F.SilkS")
		)
		(fp_line
			(start -0.7874 0.4064)
			(end -0.7874 -0.4064)
			(stroke
				(width 0.1524)
				(type default)
			)
			(layer "F.SilkS")
		)
		(fp_line
			(start -0.7874 -0.4064)
			(end 0.7874 -0.4064)
			(stroke
				(width 0.1524)
				(type default)
			)
			(layer "F.SilkS")
		)
		(fp_line
			(start 0.67945 0.3048)
			(end 0.120396 0.3048)
			(stroke
				(width 0.1)
				(type default)
			)
			(layer "F.Fab")
		)
		(fp_line
			(start 0.67945 -0.3048)
			(end 0.67945 0.3048)
			(stroke
				(width 0.1)
				(type default)
			)
			(layer "F.Fab")
		)
		(fp_line
			(start 0.12065 -0.2794)
			(end 0.12065 -0.3048)
			(stroke
				(width 0.1)
				(type default)
			)
			(layer "F.Fab")
		)
		(fp_line
			(start 0.12065 -0.3048)
			(end 0.67945 -0.3048)
			(stroke
				(width 0.1)
				(type default)
			)
			(layer "F.Fab")
		)
		(fp_line
			(start 0.120396 0.3048)
			(end 0.120396 0.2794)
			(stroke
				(width 0.1)
				(type default)
			)
			(layer "F.Fab")
		)
		(fp_line
			(start 0.120396 0.2794)
			(end -0.12065 0.2794)
			(stroke
				(width 0.1)
				(type default)
			)
			(layer "F.Fab")
		)
		(fp_line
			(start -0.12065 0.3048)
			(end -0.67945 0.3048)
			(stroke
				(width 0.1)
				(type default)
			)
			(layer "F.Fab")
		)
		(fp_line
			(start -0.12065 0.2794)
			(end -0.12065 0.3048)
			(stroke
				(width 0.1)
				(type default)
			)
			(layer "F.Fab")
		)
		(fp_line
			(start -0.12065 -0.2794)
			(end 0.12065 -0.2794)
			(stroke
				(width 0.1)
				(type default)
			)
			(layer "F.Fab")
		)
		(fp_line
			(start -0.12065 -0.305054)
			(end -0.12065 -0.2794)
			(stroke
				(width 0.1)
				(type default)
			)
			(layer "F.Fab")
		)
		(fp_line
			(start -0.67945 0.3048)
			(end -0.67945 -0.305054)
			(stroke
				(width 0.1)
				(type default)
			)
			(layer "F.Fab")
		)
		(fp_line
			(start -0.67945 -0.305054)
			(end -0.12065 -0.305054)
			(stroke
				(width 0.1)
				(type default)
			)
			(layer "F.Fab")
		)
		(pad "1" smd circle
			(at -0.40005 0 180)
			(size 0 0)
			(layers "F.Cu" "F.Mask" "F.Paste")
			(net "P1V25_PEX0_R")
		)
		(pad "2" smd circle
			(at 0.40005 0 180)
			(size 0 0)
			(layers "F.Cu" "F.Mask" "F.Paste")
			(net "P12V_PEX0_P1V25_VIN_P")
		)
	)
	(footprint ""
		(layer "F.Cu")
		(at 323.917818 -222.119698 180)
		(property "Reference" "R2981"
			(at 0 0 180)
			(layer "F.SilkS")
			(hide yes)
			(effects
				(font
					(size 1.27 1.27)
				)
			)
		)
		(property "Value" ""
			(at 0 0 180)
			(layer "F.Fab")
			(effects
				(font
					(size 1.27 1.27)
				)
			)
		)
		(duplicate_pad_numbers_are_jumpers no)
		(fp_line
			(start 0.7874 0.4064)
			(end -0.7874 0.4064)
			(stroke
				(width 0.1524)
				(type default)
			)
			(layer "F.SilkS")
		)
		(fp_line
			(start 0.7874 -0.4064)
			(end 0.7874 0.4064)
			(stroke
				(width 0.1524)
				(type default)
			)
			(layer "F.SilkS")
		)
		(fp_line
			(start -0.7874 0.4064)
			(end -0.7874 -0.4064)
			(stroke
				(width 0.1524)
				(type default)
			)
			(layer "F.SilkS")
		)
		(fp_line
			(start -0.7874 -0.4064)
			(end 0.7874 -0.4064)
			(stroke
				(width 0.1524)
				(type default)
			)
			(layer "F.SilkS")
		)
		(fp_line
			(start 0.67945 0.3048)
			(end 0.120396 0.3048)
			(stroke
				(width 0.1)
				(type default)
			)
			(layer "F.Fab")
		)
		(fp_line
			(start 0.67945 -0.3048)
			(end 0.67945 0.3048)
			(stroke
				(width 0.1)
				(type default)
			)
			(layer "F.Fab")
		)
		(fp_line
			(start 0.12065 -0.2794)
			(end 0.12065 -0.3048)
			(stroke
				(width 0.1)
				(type default)
			)
			(layer "F.Fab")
		)
		(fp_line
			(start 0.12065 -0.3048)
			(end 0.67945 -0.3048)
			(stroke
				(width 0.1)
				(type default)
			)
			(layer "F.Fab")
		)
		(fp_line
			(start 0.120396 0.3048)
			(end 0.120396 0.2794)
			(stroke
				(width 0.1)
				(type default)
			)
			(layer "F.Fab")
		)
		(fp_line
			(start 0.120396 0.2794)
			(end -0.12065 0.2794)
			(stroke
				(width 0.1)
				(type default)
			)
			(layer "F.Fab")
		)
		(fp_line
			(start -0.12065 0.3048)
			(end -0.67945 0.3048)
			(stroke
				(width 0.1)
				(type default)
			)
			(layer "F.Fab")
		)
		(fp_line
			(start -0.12065 0.2794)
			(end -0.12065 0.3048)
			(stroke
				(width 0.1)
				(type default)
			)
			(layer "F.Fab")
		)
		(fp_line
			(start -0.12065 -0.2794)
			(end 0.12065 -0.2794)
			(stroke
				(width 0.1)
				(type default)
			)
			(layer "F.Fab")
		)
		(fp_line
			(start -0.12065 -0.305054)
			(end -0.12065 -0.2794)
			(stroke
				(width 0.1)
				(type default)
			)
			(layer "F.Fab")
		)
		(fp_line
			(start -0.67945 0.3048)
			(end -0.67945 -0.305054)
			(stroke
				(width 0.1)
				(type default)
			)
			(layer "F.Fab")
		)
		(fp_line
			(start -0.67945 -0.305054)
			(end -0.12065 -0.305054)
			(stroke
				(width 0.1)
				(type default)
			)
			(layer "F.Fab")
		)
		(pad "1" smd circle
			(at -0.40005 0 180)
			(size 0 0)
			(layers "F.Cu" "F.Mask" "F.Paste")
			(net "LED_POSTCODE_3")
		)
		(pad "2" smd circle
			(at 0.40005 0 180)
			(size 0 0)
			(layers "F.Cu" "F.Mask" "F.Paste")
			(net "LED_POSTCODE_R_3")
		)
	)
	(footprint ""
		(layer "F.Cu")
		(at 232.46969 -82.518758 90)
		(property "Reference" "R6604"
			(at 0 0 90)
			(layer "F.SilkS")
			(hide yes)
			(effects
				(font
					(size 1.27 1.27)
				)
			)
		)
		(property "Value" ""
			(at 0 0 90)
			(layer "F.Fab")
			(effects
				(font
					(size 1.27 1.27)
				)
			)
		)
		(duplicate_pad_numbers_are_jumpers no)
		(fp_line
			(start 0.7874 -0.4064)
			(end 0.7874 0.4064)
			(stroke
				(width 0.1524)
				(type default)
			)
			(layer "F.SilkS")
		)
		(fp_line
			(start -0.7874 -0.4064)
			(end 0.7874 -0.4064)
			(stroke
				(width 0.1524)
				(type default)
			)
			(layer "F.SilkS")
		)
		(fp_line
			(start 0.007112 0.4064)
			(end -0.7874 0.4064)
			(stroke
				(width 0.1524)
				(type default)
			)
			(layer "F.SilkS")
		)
		(fp_line
			(start -0.12065 -0.305054)
			(end -0.12065 -0.2794)
			(stroke
				(width 0.1)
				(type default)
			)
			(layer "F.Fab")
		)
		(fp_line
			(start -0.67945 -0.305054)
			(end -0.12065 -0.305054)
			(stroke
				(width 0.1)
				(type default)
			)
			(layer "F.Fab")
		)
		(fp_line
			(start 0.67945 -0.3048)
			(end 0.67945 0.3048)
			(stroke
				(width 0.1)
				(type default)
			)
			(layer "F.Fab")
		)
		(fp_line
			(start 0.12065 -0.3048)
			(end 0.67945 -0.3048)
			(stroke
				(width 0.1)
				(type default)
			)
			(layer "F.Fab")
		)
		(fp_line
			(start 0.12065 -0.2794)
			(end 0.12065 -0.3048)
			(stroke
				(width 0.1)
				(type default)
			)
			(layer "F.Fab")
		)
		(fp_line
			(start -0.12065 -0.2794)
			(end 0.12065 -0.2794)
			(stroke
				(width 0.1)
				(type default)
			)
			(layer "F.Fab")
		)
		(fp_line
			(start 0.120396 0.2794)
			(end -0.12065 0.2794)
			(stroke
				(width 0.1)
				(type default)
			)
			(layer "F.Fab")
		)
		(fp_line
			(start -0.12065 0.2794)
			(end -0.12065 0.3048)
			(stroke
				(width 0.1)
				(type default)
			)
			(layer "F.Fab")
		)
		(fp_line
			(start 0.67945 0.3048)
			(end 0.120396 0.3048)
			(stroke
				(width 0.1)
				(type default)
			)
			(layer "F.Fab")
		)
		(fp_line
			(start 0.120396 0.3048)
			(end 0.120396 0.2794)
			(stroke
				(width 0.1)
				(type default)
			)
			(layer "F.Fab")
		)
		(fp_line
			(start -0.12065 0.3048)
			(end -0.67945 0.3048)
			(stroke
				(width 0.1)
				(type default)
			)
			(layer "F.Fab")
		)
		(fp_line
			(start -0.67945 0.3048)
			(end -0.67945 -0.305054)
			(stroke
				(width 0.1)
				(type default)
			)
			(layer "F.Fab")
		)
		(pad "1" smd rect
			(at -0.40005 0 270)
			(size 0.4572 0.508)
			(layers "F.Cu" "F.Mask" "F.Paste")
			(net "USB2_CP2108_SDB_DN")
		)
		(pad "2" smd rect
			(at 0.40005 0 270)
			(size 0.4572 0.508)
			(layers "F.Cu" "F.Mask" "F.Paste")
			(net "USB2_FT4232_SDB_R_DN")
		)
	)
	(footprint ""
		(layer "F.Cu")
		(at 217.767916 -18.437098)
		(property "Reference" "R1680"
			(at 0 0 0)
			(layer "F.SilkS")
			(hide yes)
			(effects
				(font
					(size 1.27 1.27)
				)
			)
		)
		(property "Value" ""
			(at 0 0 0)
			(layer "F.Fab")
			(effects
				(font
					(size 1.27 1.27)
				)
			)
		)
		(duplicate_pad_numbers_are_jumpers no)
		(fp_line
			(start -0.7874 -0.4064)
			(end 0.7874 -0.4064)
			(stroke
				(width 0.1524)
				(type default)
			)
			(layer "F.SilkS")
		)
		(fp_line
			(start -0.7874 0.4064)
			(end -0.7874 -0.4064)
			(stroke
				(width 0.1524)
				(type default)
			)
			(layer "F.SilkS")
		)
		(fp_line
			(start 0.7874 -0.4064)
			(end 0.7874 0.4064)
			(stroke
				(width 0.1524)
				(type default)
			)
			(layer "F.SilkS")
		)
		(fp_line
			(start 0.7874 0.4064)
			(end -0.7874 0.4064)
			(stroke
				(width 0.1524)
				(type default)
			)
			(layer "F.SilkS")
		)
		(fp_line
			(start -0.67945 -0.305054)
			(end -0.12065 -0.305054)
			(stroke
				(width 0.1)
				(type default)
			)
			(layer "F.Fab")
		)
		(fp_line
			(start -0.67945 0.3048)
			(end -0.67945 -0.305054)
			(stroke
				(width 0.1)
				(type default)
			)
			(layer "F.Fab")
		)
		(fp_line
			(start -0.12065 -0.305054)
			(end -0.12065 -0.2794)
			(stroke
				(width 0.1)
				(type default)
			)
			(layer "F.Fab")
		)
		(fp_line
			(start -0.12065 -0.2794)
			(end 0.12065 -0.2794)
			(stroke
				(width 0.1)
				(type default)
			)
			(layer "F.Fab")
		)
		(fp_line
			(start -0.12065 0.2794)
			(end -0.12065 0.3048)
			(stroke
				(width 0.1)
				(type default)
			)
			(layer "F.Fab")
		)
		(fp_line
			(start -0.12065 0.3048)
			(end -0.67945 0.3048)
			(stroke
				(width 0.1)
				(type default)
			)
			(layer "F.Fab")
		)
		(fp_line
			(start 0.120396 0.2794)
			(end -0.12065 0.2794)
			(stroke
				(width 0.1)
				(type default)
			)
			(layer "F.Fab")
		)
		(fp_line
			(start 0.120396 0.3048)
			(end 0.120396 0.2794)
			(stroke
				(width 0.1)
				(type default)
			)
			(layer "F.Fab")
		)
		(fp_line
			(start 0.12065 -0.3048)
			(end 0.67945 -0.3048)
			(stroke
				(width 0.1)
				(type default)
			)
			(layer "F.Fab")
		)
		(fp_line
			(start 0.12065 -0.2794)
			(end 0.12065 -0.3048)
			(stroke
				(width 0.1)
				(type default)
			)
			(layer "F.Fab")
		)
		(fp_line
			(start 0.67945 -0.3048)
			(end 0.67945 0.3048)
			(stroke
				(width 0.1)
				(type default)
			)
			(layer "F.Fab")
		)
		(fp_line
			(start 0.67945 0.3048)
			(end 0.120396 0.3048)
			(stroke
				(width 0.1)
				(type default)
			)
			(layer "F.Fab")
		)
		(pad "1" smd circle
			(at -0.40005 0)
			(size 0 0)
			(layers "F.Cu" "F.Mask" "F.Paste")
			(net "SMB_ISO_SSD7_R_SCL")
		)
		(pad "2" smd circle
			(at 0.40005 0)
			(size 0 0)
			(layers "F.Cu" "F.Mask" "F.Paste")
			(net "SMB_ISO_SSD7_SCL")
		)
	)
	(footprint ""
		(layer "F.Cu")
		(at 301.822612 -22.867366 90)
		(property "Reference" "C3945"
			(at 0 0 90)
			(layer "F.SilkS")
			(hide yes)
			(effects
				(font
					(size 1.27 1.27)
				)
			)
		)
		(property "Value" ""
			(at 0 0 90)
			(layer "F.Fab")
			(effects
				(font
					(size 1.27 1.27)
				)
			)
		)
		(duplicate_pad_numbers_are_jumpers no)
		(fp_line
			(start 0.7874 -0.4064)
			(end 0.7874 0.4064)
			(stroke
				(width 0.1524)
				(type default)
			)
			(layer "F.SilkS")
		)
		(fp_line
			(start -0.7874 -0.4064)
			(end 0.7874 -0.4064)
			(stroke
				(width 0.1524)
				(type default)
			)
			(layer "F.SilkS")
		)
		(fp_line
			(start 0.7874 0.4064)
			(end -0.7874 0.4064)
			(stroke
				(width 0.1524)
				(type default)
			)
			(layer "F.SilkS")
		)
		(fp_line
			(start -0.7874 0.4064)
			(end -0.7874 -0.4064)
			(stroke
				(width 0.1524)
				(type default)
			)
			(layer "F.SilkS")
		)
		(fp_line
			(start -0.12065 -0.305054)
			(end -0.12065 -0.2794)
			(stroke
				(width 0.1)
				(type default)
			)
			(layer "F.Fab")
		)
		(fp_line
			(start -0.67945 -0.305054)
			(end -0.12065 -0.305054)
			(stroke
				(width 0.1)
				(type default)
			)
			(layer "F.Fab")
		)
		(fp_line
			(start 0.67945 -0.3048)
			(end 0.67945 0.3048)
			(stroke
				(width 0.1)
				(type default)
			)
			(layer "F.Fab")
		)
		(fp_line
			(start 0.12065 -0.3048)
			(end 0.67945 -0.3048)
			(stroke
				(width 0.1)
				(type default)
			)
			(layer "F.Fab")
		)
		(fp_line
			(start 0.12065 -0.2794)
			(end 0.12065 -0.3048)
			(stroke
				(width 0.1)
				(type default)
			)
			(layer "F.Fab")
		)
		(fp_line
			(start -0.12065 -0.2794)
			(end 0.12065 -0.2794)
			(stroke
				(width 0.1)
				(type default)
			)
			(layer "F.Fab")
		)
		(fp_line
			(start 0.120396 0.2794)
			(end -0.12065 0.2794)
			(stroke
				(width 0.1)
				(type default)
			)
			(layer "F.Fab")
		)
		(fp_line
			(start -0.12065 0.2794)
			(end -0.12065 0.3048)
			(stroke
				(width 0.1)
				(type default)
			)
			(layer "F.Fab")
		)
		(fp_line
			(start 0.67945 0.3048)
			(end 0.120396 0.3048)
			(stroke
				(width 0.1)
				(type default)
			)
			(layer "F.Fab")
		)
		(fp_line
			(start 0.120396 0.3048)
			(end 0.120396 0.2794)
			(stroke
				(width 0.1)
				(type default)
			)
			(layer "F.Fab")
		)
		(fp_line
			(start -0.12065 0.3048)
			(end -0.67945 0.3048)
			(stroke
				(width 0.1)
				(type default)
			)
			(layer "F.Fab")
		)
		(fp_line
			(start -0.67945 0.3048)
			(end -0.67945 -0.305054)
			(stroke
				(width 0.1)
				(type default)
			)
			(layer "F.Fab")
		)
		(pad "1" smd circle
			(at -0.40005 0 90)
			(size 0 0)
			(layers "F.Cu" "F.Mask" "F.Paste")
			(net "P12V_SSD10")
		)
		(pad "2" smd circle
			(at 0.40005 0 90)
			(size 0 0)
			(layers "F.Cu" "F.Mask" "F.Paste")
			(net "GND")
		)
	)
	(footprint ""
		(layer "F.Cu")
		(at 221.297246 -277.128224 90)
		(property "Reference" "R781"
			(at 0 0 90)
			(layer "F.SilkS")
			(hide yes)
			(effects
				(font
					(size 1.27 1.27)
				)
			)
		)
		(property "Value" ""
			(at 0 0 90)
			(layer "F.Fab")
			(effects
				(font
					(size 1.27 1.27)
				)
			)
		)
		(duplicate_pad_numbers_are_jumpers no)
		(fp_line
			(start 3.937508 -1.8796)
			(end -3.937508 -1.8796)
			(stroke
				(width 0.1524)
				(type default)
			)
			(layer "F.SilkS")
		)
		(fp_line
			(start -3.937508 -1.8796)
			(end -3.937508 1.8796)
			(stroke
				(width 0.1524)
				(type default)
			)
			(layer "F.SilkS")
		)
		(fp_line
			(start 3.937508 1.8796)
			(end 3.937508 -1.8796)
			(stroke
				(width 0.1524)
				(type default)
			)
			(layer "F.SilkS")
		)
		(fp_line
			(start -3.937508 1.8796)
			(end 3.937508 1.8796)
			(stroke
				(width 0.1524)
				(type default)
			)
			(layer "F.SilkS")
		)
		(fp_line
			(start 3.275076 -1.674876)
			(end -3.275076 -1.674876)
			(stroke
				(width 0.1)
				(type default)
			)
			(layer "F.Fab")
		)
		(fp_line
			(start -3.275076 -1.674876)
			(end -3.275076 1.674876)
			(stroke
				(width 0.1)
				(type default)
			)
			(layer "F.Fab")
		)
		(fp_line
			(start 3.275076 1.674876)
			(end 3.275076 -1.674876)
			(stroke
				(width 0.1)
				(type default)
			)
			(layer "F.Fab")
		)
		(fp_line
			(start -3.275076 1.674876)
			(end 3.275076 1.674876)
			(stroke
				(width 0.1)
				(type default)
			)
			(layer "F.Fab")
		)
		(pad "1" smd rect
			(at -2.350008 0 90)
			(size 2.921 3.5052)
			(layers "F.Cu" "F.Mask" "F.Paste")
			(net "P1V25_PEX1")
		)
		(pad "2" smd rect
			(at 2.350008 0 90)
			(size 2.921 3.5052)
			(layers "F.Cu" "F.Mask" "F.Paste")
			(net "P1V25_PEX1_R")
		)
	)
	(footprint ""
		(layer "F.Cu")
		(at 2.231644 -21.317712 -90)
		(property "Reference" "R5731"
			(at 0 0 270)
			(layer "F.SilkS")
			(hide yes)
			(effects
				(font
					(size 1.27 1.27)
				)
			)
		)
		(property "Value" ""
			(at 0 0 270)
			(layer "F.Fab")
			(effects
				(font
					(size 1.27 1.27)
				)
			)
		)
		(duplicate_pad_numbers_are_jumpers no)
		(fp_line
			(start -0.7874 0.4064)
			(end -0.7874 -0.4064)
			(stroke
				(width 0.1524)
				(type default)
			)
			(layer "F.SilkS")
		)
		(fp_line
			(start 0.7874 0.4064)
			(end -0.7874 0.4064)
			(stroke
				(width 0.1524)
				(type default)
			)
			(layer "F.SilkS")
		)
		(fp_line
			(start -0.7874 -0.4064)
			(end 0.7874 -0.4064)
			(stroke
				(width 0.1524)
				(type default)
			)
			(layer "F.SilkS")
		)
		(fp_line
			(start 0.7874 -0.4064)
			(end 0.7874 0.4064)
			(stroke
				(width 0.1524)
				(type default)
			)
			(layer "F.SilkS")
		)
		(fp_line
			(start -0.67945 0.3048)
			(end -0.67945 -0.305054)
			(stroke
				(width 0.1)
				(type default)
			)
			(layer "F.Fab")
		)
		(fp_line
			(start -0.12065 0.3048)
			(end -0.67945 0.3048)
			(stroke
				(width 0.1)
				(type default)
			)
			(layer "F.Fab")
		)
		(fp_line
			(start 0.120396 0.3048)
			(end 0.120396 0.2794)
			(stroke
				(width 0.1)
				(type default)
			)
			(layer "F.Fab")
		)
		(fp_line
			(start 0.67945 0.3048)
			(end 0.120396 0.3048)
			(stroke
				(width 0.1)
				(type default)
			)
			(layer "F.Fab")
		)
		(fp_line
			(start -0.12065 0.2794)
			(end -0.12065 0.3048)
			(stroke
				(width 0.1)
				(type default)
			)
			(layer "F.Fab")
		)
		(fp_line
			(start 0.120396 0.2794)
			(end -0.12065 0.2794)
			(stroke
				(width 0.1)
				(type default)
			)
			(layer "F.Fab")
		)
		(fp_line
			(start -0.12065 -0.2794)
			(end 0.12065 -0.2794)
			(stroke
				(width 0.1)
				(type default)
			)
			(layer "F.Fab")
		)
		(fp_line
			(start 0.12065 -0.2794)
			(end 0.12065 -0.3048)
			(stroke
				(width 0.1)
				(type default)
			)
			(layer "F.Fab")
		)
		(fp_line
			(start 0.12065 -0.3048)
			(end 0.67945 -0.3048)
			(stroke
				(width 0.1)
				(type default)
			)
			(layer "F.Fab")
		)
		(fp_line
			(start 0.67945 -0.3048)
			(end 0.67945 0.3048)
			(stroke
				(width 0.1)
				(type default)
			)
			(layer "F.Fab")
		)
		(fp_line
			(start -0.67945 -0.305054)
			(end -0.12065 -0.305054)
			(stroke
				(width 0.1)
				(type default)
			)
			(layer "F.Fab")
		)
		(fp_line
			(start -0.12065 -0.305054)
			(end -0.12065 -0.2794)
			(stroke
				(width 0.1)
				(type default)
			)
			(layer "F.Fab")
		)
		(pad "1" smd circle
			(at -0.40005 0 270)
			(size 0 0)
			(layers "F.Cu" "F.Mask" "F.Paste")
			(net "P3V3_SSD0")
		)
		(pad "2" smd circle
			(at 0.40005 0 270)
			(size 0 0)
			(layers "F.Cu" "F.Mask" "F.Paste")
			(net "SSD0_LED_ISO_N")
		)
	)
	(footprint ""
		(layer "F.Cu")
		(at 278.451056 -399.00098 90)
		(property "Reference" "U146"
			(at 0.051562 2.121154 90)
			(unlocked yes)
			(layer "F.SilkS")
			(effects
				(font
					(size 0.7874 0.5842)
					(thickness 0.1524)
				)
			)
		)
		(property "Value" ""
			(at 0 0 90)
			(layer "F.Fab")
			(effects
				(font
					(size 1.27 1.27)
				)
			)
		)
		(duplicate_pad_numbers_are_jumpers no)
		(fp_line
			(start 1.7272 -1.1176)
			(end 0.254 -1.1176)
			(stroke
				(width 0.1524)
				(type default)
			)
			(layer "F.SilkS")
		)
		(fp_line
			(start 1.7272 -1.1176)
			(end 1.7272 1.1176)
			(stroke
				(width 0.1524)
				(type default)
			)
			(layer "F.SilkS")
		)
		(fp_line
			(start 0.254 -1.1176)
			(end 0 -0.7366)
			(stroke
				(width 0.1524)
				(type default)
			)
			(layer "F.SilkS")
		)
		(fp_line
			(start -0.254 -1.1176)
			(end -1.7272 -1.1176)
			(stroke
				(width 0.1524)
				(type default)
			)
			(layer "F.SilkS")
		)
		(fp_line
			(start 0 -0.7366)
			(end -0.254 -1.1176)
			(stroke
				(width 0.1524)
				(type default)
			)
			(layer "F.SilkS")
		)
		(fp_line
			(start 1.7272 1.1176)
			(end -1.7272 1.1176)
			(stroke
				(width 0.1524)
				(type default)
			)
			(layer "F.SilkS")
		)
		(fp_line
			(start -1.7272 1.1176)
			(end -1.7272 -1.1176)
			(stroke
				(width 0.1524)
				(type default)
			)
			(layer "F.SilkS")
		)
		(fp_poly
			(pts
				(xy -1.9558 -0.649986) (xy -2.7178 -0.268986) (xy -2.7178 -1.030986)
			)
			(stroke
				(width 0)
				(type default)
			)
			(fill yes)
			(layer "F.SilkS")
		)
		(fp_line
			(start 1.5748 -1.1176)
			(end -1.5748 -1.1176)
			(stroke
				(width 0.1)
				(type default)
			)
			(layer "F.Fab")
		)
		(fp_line
			(start -1.5748 -1.1176)
			(end -1.5748 1.1176)
			(stroke
				(width 0.1)
				(type default)
			)
			(layer "F.Fab")
		)
		(fp_line
			(start 1.5748 1.1176)
			(end 1.5748 -1.1176)
			(stroke
				(width 0.1)
				(type default)
			)
			(layer "F.Fab")
		)
		(fp_line
			(start -1.5748 1.1176)
			(end 1.5748 1.1176)
			(stroke
				(width 0.1)
				(type default)
			)
			(layer "F.Fab")
		)
		(fp_poly
			(pts
				(xy -1.9558 -0.649986) (xy -2.7178 -0.268986) (xy -2.7178 -1.030986)
			)
			(stroke
				(width 0)
				(type default)
			)
			(fill yes)
			(layer "F.Fab")
		)
		(pad "1" smd rect
			(at -0.999998 -0.649986)
			(size 0.3556 1.1176)
			(layers "F.Cu" "F.Mask" "F.Paste")
			(net "MB_BMC_MON")
		)
		(pad "2" smd rect
			(at -0.999998 0)
			(size 0.3556 1.1176)
			(layers "F.Cu" "F.Mask" "F.Paste")
			(net "GND")
		)
		(pad "3" smd rect
			(at -0.999998 0.649986)
			(size 0.3556 1.1176)
			(layers "F.Cu" "F.Mask" "F.Paste")
			(net "RST_MB_BIC_N")
		)
		(pad "4" smd rect
			(at 0.999998 0.649986)
			(size 0.3556 1.1176)
			(layers "F.Cu" "F.Mask" "F.Paste")
			(net "RST_MB_BIC_ISO_N")
		)
		(pad "5" smd rect
			(at 0.999998 0)
			(size 0.3556 1.1176)
			(layers "F.Cu" "F.Mask" "F.Paste")
			(net "P3V3_AUX")
		)
		(pad "6" smd rect
			(at 0.999998 -0.649986)
			(size 0.3556 1.1176)
			(layers "F.Cu" "F.Mask" "F.Paste")
			(net "MB_BMC_MON_ISO")
		)
	)
	(footprint ""
		(layer "F.Cu")
		(at 476.630238 -525.953736)
		(property "Reference" "J19_12"
			(at -0.5842 -1.31953 0)
			(unlocked yes)
			(layer "B.SilkS")
			(effects
				(font
					(size 0.7874 0.5842)
					(thickness 0.1524)
				)
				(justify left mirror)
			)
		)
		(property "Value" ""
			(at 0 0 0)
			(layer "F.Fab")
			(effects
				(font
					(size 1.27 1.27)
				)
			)
		)
		(duplicate_pad_numbers_are_jumpers no)
		(pad "1" thru_hole circle
			(at 0 0)
			(size 0.4572 0.4572)
			(drill 0.2032)
			(layers "*.Cu" "*.Mask")
			(remove_unused_layers no)
			(net "Net_468")
			(clearance 0.127)
			(thermal_gap 0.127)
			(padstack
				(mode front_inner_back)
				(layer "Inner"
					(shape circle)
					(size 0.4572 0.4572)
					(clearance 0.127)
				)
				(layer "B.Cu"
					(shape circle)
					(size 0.508 0.508)
					(clearance 0.1016)
				)
			)
		)
	)
	(footprint ""
		(layer "F.Cu")
		(at 37.248084 -101.095302)
		(property "Reference" "C61"
			(at 0 0 0)
			(layer "F.SilkS")
			(hide yes)
			(effects
				(font
					(size 1.27 1.27)
				)
			)
		)
		(property "Value" ""
			(at 0 0 0)
			(layer "F.Fab")
			(effects
				(font
					(size 1.27 1.27)
				)
			)
		)
		(duplicate_pad_numbers_are_jumpers no)
		(fp_line
			(start -0.299974 -0.150114)
			(end 0.299974 -0.150114)
			(stroke
				(width 0.1)
				(type default)
			)
			(layer "F.Fab")
		)
		(fp_line
			(start -0.299974 0.150114)
			(end -0.299974 -0.150114)
			(stroke
				(width 0.1)
				(type default)
			)
			(layer "F.Fab")
		)
		(fp_line
			(start 0.299974 -0.150114)
			(end 0.299974 0.150114)
			(stroke
				(width 0.1)
				(type default)
			)
			(layer "F.Fab")
		)
		(fp_line
			(start 0.299974 0.150114)
			(end -0.299974 0.150114)
			(stroke
				(width 0.1)
				(type default)
			)
			(layer "F.Fab")
		)
		(pad "1" smd rect
			(at -0.2667 0)
			(size 0.3048 0.381)
			(layers "F.Cu" "F.Mask" "F.Paste")
			(net "P5E_PEX0_STN1_TX_DN<17>")
		)
		(pad "2" smd rect
			(at 0.2667 0)
			(size 0.3048 0.381)
			(layers "F.Cu" "F.Mask" "F.Paste")
			(net "P5E_PEX0_STN1_TX_C_DN<17>")
		)
	)
	(footprint ""
		(layer "F.Cu")
		(at 151.228044 -441.600082)
		(property "Reference" "X15"
			(at -0.1778 -1.92913 0)
			(unlocked yes)
			(layer "F.SilkS")
			(effects
				(font
					(size 0.7874 0.5842)
					(thickness 0.1524)
				)
				(justify left)
			)
		)
		(property "Value" ""
			(at 0 0 0)
			(layer "F.Fab")
			(effects
				(font
					(size 1.27 1.27)
				)
			)
		)
		(property "Device Type" "TP_TDR_4P_FTS_MPKT4_H025P0200_IO_TP15_TP_TDR_4P_DIP"
			(at 1.30175 1.27 90)
			(unlocked yes)
			(layer "F.Fab")
			(hide yes)
			(effects
				(font
					(size 0.635 0.4064)
					(thickness 0.1524)
				)
			)
		)
		(property "User Part Number" "TP15"
			(at 1.30175 1.27 90)
			(unlocked yes)
			(layer "Cmts.User")
			(hide yes)
			(effects
				(font
					(size 0.635 0.4064)
					(thickness 0.1524)
				)
			)
		)
		(duplicate_pad_numbers_are_jumpers no)
		(fp_line
			(start 0 -1.27)
			(end 0 -0.635)
			(stroke
				(width 0.1524)
				(type default)
			)
			(layer "F.SilkS")
		)
		(fp_line
			(start 0 0.635)
			(end 0 1.905)
			(stroke
				(width 0.1524)
				(type default)
			)
			(layer "F.SilkS")
		)
		(fp_line
			(start 0 3.175)
			(end 0 3.81)
			(stroke
				(width 0.1524)
				(type default)
			)
			(layer "F.SilkS")
		)
		(fp_line
			(start 0 3.81)
			(end 2.54 3.81)
			(stroke
				(width 0.1524)
				(type default)
			)
			(layer "F.SilkS")
		)
		(fp_line
			(start 2.54 -1.27)
			(end 0 -1.27)
			(stroke
				(width 0.1524)
				(type default)
			)
			(layer "F.SilkS")
		)
		(fp_line
			(start 2.54 -1.1303)
			(end 2.54 -1.27)
			(stroke
				(width 0.1524)
				(type default)
			)
			(layer "F.SilkS")
		)
		(fp_line
			(start 2.54 1.4097)
			(end 2.54 1.1303)
			(stroke
				(width 0.1524)
				(type default)
			)
			(layer "F.SilkS")
		)
		(fp_line
			(start 2.54 3.81)
			(end 2.54 3.6703)
			(stroke
				(width 0.1524)
				(type default)
			)
			(layer "F.SilkS")
		)
		(fp_poly
			(pts
				(xy -0.761746 0) (xy -2.285746 -0.762) (xy -2.285746 0.762)
			)
			(stroke
				(width 0)
				(type default)
			)
			(fill yes)
			(layer "F.SilkS")
		)
		(fp_line
			(start 0 -1.27)
			(end 0 3.81)
			(stroke
				(width 0.1)
				(type default)
			)
			(layer "F.Fab")
		)
		(fp_line
			(start 0 3.81)
			(end 2.54 3.81)
			(stroke
				(width 0.1)
				(type default)
			)
			(layer "F.Fab")
		)
		(fp_line
			(start 2.54 -1.27)
			(end 0 -1.27)
			(stroke
				(width 0.1)
				(type default)
			)
			(layer "F.Fab")
		)
		(fp_line
			(start 2.54 3.81)
			(end 2.54 -1.27)
			(stroke
				(width 0.1)
				(type default)
			)
			(layer "F.Fab")
		)
		(fp_poly
			(pts
				(xy -0.761746 0) (xy -2.285746 -0.762) (xy -2.285746 0.762)
			)
			(stroke
				(width 0)
				(type default)
			)
			(fill yes)
			(layer "F.Fab")
		)
		(pad "1" thru_hole circle
			(at 0 0)
			(size 1.0033 1.0033)
			(drill 0.249936)
			(layers "*.Cu" "*.Mask")
			(remove_unused_layers no)
			(net "TDR_DIFF_85_IN2_DIN")
			(clearance 0.10795)
			(thermal_gap 0.10795)
			(padstack
				(mode front_inner_back)
				(layer "Inner"
					(shape circle)
					(size 0.8001 0.8001)
					(clearance 0.1524)
				)
				(layer "B.Cu"
					(shape circle)
					(size 1.0033 1.0033)
					(clearance 0.10795)
				)
			)
		)
		(pad "2" thru_hole circle
			(at 2.54 0)
			(size 1.9939 1.9939)
			(drill 0.249936)
			(layers "*.Cu" "*.Mask")
			(remove_unused_layers no)
			(net "COUPON_GND1")
			(clearance 0.10795)
			(thermal_gap 0.10795)
			(padstack
				(mode front_inner_back)
				(layer "Inner"
					(shape circle)
					(size 0.8001 0.8001)
					(clearance 0.1524)
				)
				(layer "B.Cu"
					(shape circle)
					(size 1.9939 1.9939)
					(clearance 0.10795)
				)
			)
		)
		(pad "3" thru_hole circle
			(at 2.54 2.54)
			(size 1.9939 1.9939)
			(drill 0.249936)
			(layers "*.Cu" "*.Mask")
			(remove_unused_layers no)
			(net "COUPON_GND1")
			(clearance 0.10795)
			(thermal_gap 0.10795)
			(padstack
				(mode front_inner_back)
				(layer "Inner"
					(shape circle)
					(size 0.8001 0.8001)
					(clearance 0.1524)
				)
				(layer "B.Cu"
					(shape circle)
					(size 1.9939 1.9939)
					(clearance 0.10795)
				)
			)
		)
		(pad "4" thru_hole circle
			(at 0 2.54)
			(size 1.0033 1.0033)
			(drill 0.249936)
			(layers "*.Cu" "*.Mask")
			(remove_unused_layers no)
			(net "TDR_DIFF_85_IN2_DIP")
			(clearance 0.10795)
			(thermal_gap 0.10795)
			(padstack
				(mode front_inner_back)
				(layer "Inner"
					(shape circle)
					(size 0.8001 0.8001)
					(clearance 0.1524)
				)
				(layer "B.Cu"
					(shape circle)
					(size 1.0033 1.0033)
					(clearance 0.10795)
				)
			)
		)
	)
	(footprint ""
		(layer "F.Cu")
		(at 309.262272 -22.955504 -90)
		(property "Reference" "C2729"
			(at 0 0 270)
			(layer "F.SilkS")
			(hide yes)
			(effects
				(font
					(size 1.27 1.27)
				)
			)
		)
		(property "Value" ""
			(at 0 0 270)
			(layer "F.Fab")
			(effects
				(font
					(size 1.27 1.27)
				)
			)
		)
		(duplicate_pad_numbers_are_jumpers no)
		(fp_line
			(start -0.7874 0.4064)
			(end -0.7874 -0.4064)
			(stroke
				(width 0.1524)
				(type default)
			)
			(layer "F.SilkS")
		)
		(fp_line
			(start 0.7874 0.4064)
			(end -0.7874 0.4064)
			(stroke
				(width 0.1524)
				(type default)
			)
			(layer "F.SilkS")
		)
		(fp_line
			(start -0.7874 -0.4064)
			(end 0.7874 -0.4064)
			(stroke
				(width 0.1524)
				(type default)
			)
			(layer "F.SilkS")
		)
		(fp_line
			(start 0.7874 -0.4064)
			(end 0.7874 0.4064)
			(stroke
				(width 0.1524)
				(type default)
			)
			(layer "F.SilkS")
		)
		(fp_line
			(start -0.67945 0.3048)
			(end -0.67945 -0.305054)
			(stroke
				(width 0.1)
				(type default)
			)
			(layer "F.Fab")
		)
		(fp_line
			(start -0.12065 0.3048)
			(end -0.67945 0.3048)
			(stroke
				(width 0.1)
				(type default)
			)
			(layer "F.Fab")
		)
		(fp_line
			(start 0.120396 0.3048)
			(end 0.120396 0.2794)
			(stroke
				(width 0.1)
				(type default)
			)
			(layer "F.Fab")
		)
		(fp_line
			(start 0.67945 0.3048)
			(end 0.120396 0.3048)
			(stroke
				(width 0.1)
				(type default)
			)
			(layer "F.Fab")
		)
		(fp_line
			(start -0.12065 0.2794)
			(end -0.12065 0.3048)
			(stroke
				(width 0.1)
				(type default)
			)
			(layer "F.Fab")
		)
		(fp_line
			(start 0.120396 0.2794)
			(end -0.12065 0.2794)
			(stroke
				(width 0.1)
				(type default)
			)
			(layer "F.Fab")
		)
		(fp_line
			(start -0.12065 -0.2794)
			(end 0.12065 -0.2794)
			(stroke
				(width 0.1)
				(type default)
			)
			(layer "F.Fab")
		)
		(fp_line
			(start 0.12065 -0.2794)
			(end 0.12065 -0.3048)
			(stroke
				(width 0.1)
				(type default)
			)
			(layer "F.Fab")
		)
		(fp_line
			(start 0.12065 -0.3048)
			(end 0.67945 -0.3048)
			(stroke
				(width 0.1)
				(type default)
			)
			(layer "F.Fab")
		)
		(fp_line
			(start 0.67945 -0.3048)
			(end 0.67945 0.3048)
			(stroke
				(width 0.1)
				(type default)
			)
			(layer "F.Fab")
		)
		(fp_line
			(start -0.67945 -0.305054)
			(end -0.12065 -0.305054)
			(stroke
				(width 0.1)
				(type default)
			)
			(layer "F.Fab")
		)
		(fp_line
			(start -0.12065 -0.305054)
			(end -0.12065 -0.2794)
			(stroke
				(width 0.1)
				(type default)
			)
			(layer "F.Fab")
		)
		(pad "1" smd circle
			(at -0.40005 0 270)
			(size 0 0)
			(layers "F.Cu" "F.Mask" "F.Paste")
			(net "GND")
		)
		(pad "2" smd circle
			(at 0.40005 0 270)
			(size 0 0)
			(layers "F.Cu" "F.Mask" "F.Paste")
			(net "P3V3_AUX")
		)
	)
	(footprint ""
		(layer "F.Cu")
		(at 387.082792 -141.87297)
		(property "Reference" "R338"
			(at 0 0 0)
			(layer "F.SilkS")
			(hide yes)
			(effects
				(font
					(size 1.27 1.27)
				)
			)
		)
		(property "Value" ""
			(at 0 0 0)
			(layer "F.Fab")
			(effects
				(font
					(size 1.27 1.27)
				)
			)
		)
		(duplicate_pad_numbers_are_jumpers no)
		(fp_line
			(start -0.7874 -0.4064)
			(end 0.7874 -0.4064)
			(stroke
				(width 0.1524)
				(type default)
			)
			(layer "F.SilkS")
		)
		(fp_line
			(start -0.7874 0.4064)
			(end -0.7874 -0.4064)
			(stroke
				(width 0.1524)
				(type default)
			)
			(layer "F.SilkS")
		)
		(fp_line
			(start 0.7874 -0.4064)
			(end 0.7874 0.4064)
			(stroke
				(width 0.1524)
				(type default)
			)
			(layer "F.SilkS")
		)
		(fp_line
			(start 0.7874 0.4064)
			(end -0.7874 0.4064)
			(stroke
				(width 0.1524)
				(type default)
			)
			(layer "F.SilkS")
		)
		(fp_line
			(start -0.67945 -0.305054)
			(end -0.12065 -0.305054)
			(stroke
				(width 0.1)
				(type default)
			)
			(layer "F.Fab")
		)
		(fp_line
			(start -0.67945 0.3048)
			(end -0.67945 -0.305054)
			(stroke
				(width 0.1)
				(type default)
			)
			(layer "F.Fab")
		)
		(fp_line
			(start -0.12065 -0.305054)
			(end -0.12065 -0.2794)
			(stroke
				(width 0.1)
				(type default)
			)
			(layer "F.Fab")
		)
		(fp_line
			(start -0.12065 -0.2794)
			(end 0.12065 -0.2794)
			(stroke
				(width 0.1)
				(type default)
			)
			(layer "F.Fab")
		)
		(fp_line
			(start -0.12065 0.2794)
			(end -0.12065 0.3048)
			(stroke
				(width 0.1)
				(type default)
			)
			(layer "F.Fab")
		)
		(fp_line
			(start -0.12065 0.3048)
			(end -0.67945 0.3048)
			(stroke
				(width 0.1)
				(type default)
			)
			(layer "F.Fab")
		)
		(fp_line
			(start 0.120396 0.2794)
			(end -0.12065 0.2794)
			(stroke
				(width 0.1)
				(type default)
			)
			(layer "F.Fab")
		)
		(fp_line
			(start 0.120396 0.3048)
			(end 0.120396 0.2794)
			(stroke
				(width 0.1)
				(type default)
			)
			(layer "F.Fab")
		)
		(fp_line
			(start 0.12065 -0.3048)
			(end 0.67945 -0.3048)
			(stroke
				(width 0.1)
				(type default)
			)
			(layer "F.Fab")
		)
		(fp_line
			(start 0.12065 -0.2794)
			(end 0.12065 -0.3048)
			(stroke
				(width 0.1)
				(type default)
			)
			(layer "F.Fab")
		)
		(fp_line
			(start 0.67945 -0.3048)
			(end 0.67945 0.3048)
			(stroke
				(width 0.1)
				(type default)
			)
			(layer "F.Fab")
		)
		(fp_line
			(start 0.67945 0.3048)
			(end 0.120396 0.3048)
			(stroke
				(width 0.1)
				(type default)
			)
			(layer "F.Fab")
		)
		(pad "1" smd circle
			(at -0.40005 0)
			(size 0 0)
			(layers "F.Cu" "F.Mask" "F.Paste")
			(net "NIC6_BIF1_N")
		)
		(pad "2" smd circle
			(at 0.40005 0)
			(size 0 0)
			(layers "F.Cu" "F.Mask" "F.Paste")
			(net "GND")
		)
	)
	(footprint ""
		(layer "F.Cu")
		(at 352.232214 -144.526)
		(property "Reference" "R4841"
			(at 0 0 0)
			(layer "F.SilkS")
			(hide yes)
			(effects
				(font
					(size 1.27 1.27)
				)
			)
		)
		(property "Value" ""
			(at 0 0 0)
			(layer "F.Fab")
			(effects
				(font
					(size 1.27 1.27)
				)
			)
		)
		(duplicate_pad_numbers_are_jumpers no)
		(fp_line
			(start -0.7874 -0.4064)
			(end 0.7874 -0.4064)
			(stroke
				(width 0.1524)
				(type default)
			)
			(layer "F.SilkS")
		)
		(fp_line
			(start -0.7874 0.4064)
			(end -0.7874 -0.4064)
			(stroke
				(width 0.1524)
				(type default)
			)
			(layer "F.SilkS")
		)
		(fp_line
			(start 0.7874 -0.4064)
			(end 0.7874 0.4064)
			(stroke
				(width 0.1524)
				(type default)
			)
			(layer "F.SilkS")
		)
		(fp_line
			(start 0.7874 0.4064)
			(end -0.7874 0.4064)
			(stroke
				(width 0.1524)
				(type default)
			)
			(layer "F.SilkS")
		)
		(fp_line
			(start -0.67945 -0.305054)
			(end -0.12065 -0.305054)
			(stroke
				(width 0.1)
				(type default)
			)
			(layer "F.Fab")
		)
		(fp_line
			(start -0.67945 0.3048)
			(end -0.67945 -0.305054)
			(stroke
				(width 0.1)
				(type default)
			)
			(layer "F.Fab")
		)
		(fp_line
			(start -0.12065 -0.305054)
			(end -0.12065 -0.2794)
			(stroke
				(width 0.1)
				(type default)
			)
			(layer "F.Fab")
		)
		(fp_line
			(start -0.12065 -0.2794)
			(end 0.12065 -0.2794)
			(stroke
				(width 0.1)
				(type default)
			)
			(layer "F.Fab")
		)
		(fp_line
			(start -0.12065 0.2794)
			(end -0.12065 0.3048)
			(stroke
				(width 0.1)
				(type default)
			)
			(layer "F.Fab")
		)
		(fp_line
			(start -0.12065 0.3048)
			(end -0.67945 0.3048)
			(stroke
				(width 0.1)
				(type default)
			)
			(layer "F.Fab")
		)
		(fp_line
			(start 0.120396 0.2794)
			(end -0.12065 0.2794)
			(stroke
				(width 0.1)
				(type default)
			)
			(layer "F.Fab")
		)
		(fp_line
			(start 0.120396 0.3048)
			(end 0.120396 0.2794)
			(stroke
				(width 0.1)
				(type default)
			)
			(layer "F.Fab")
		)
		(fp_line
			(start 0.12065 -0.3048)
			(end 0.67945 -0.3048)
			(stroke
				(width 0.1)
				(type default)
			)
			(layer "F.Fab")
		)
		(fp_line
			(start 0.12065 -0.2794)
			(end 0.12065 -0.3048)
			(stroke
				(width 0.1)
				(type default)
			)
			(layer "F.Fab")
		)
		(fp_line
			(start 0.67945 -0.3048)
			(end 0.67945 0.3048)
			(stroke
				(width 0.1)
				(type default)
			)
			(layer "F.Fab")
		)
		(fp_line
			(start 0.67945 0.3048)
			(end 0.120396 0.3048)
			(stroke
				(width 0.1)
				(type default)
			)
			(layer "F.Fab")
		)
		(pad "1" smd circle
			(at -0.40005 0)
			(size 0 0)
			(layers "F.Cu" "F.Mask" "F.Paste")
			(net "RST_PEX_NIC7_PERST_N")
		)
		(pad "2" smd circle
			(at 0.40005 0)
			(size 0 0)
			(layers "F.Cu" "F.Mask" "F.Paste")
			(net "RST_PEX_NIC7_PERST_R_N")
		)
	)
	(footprint ""
		(layer "F.Cu")
		(at 20.446492 -58.323734)
		(property "Reference" "PC367"
			(at 0 0 0)
			(layer "F.SilkS")
			(hide yes)
			(effects
				(font
					(size 1.27 1.27)
				)
			)
		)
		(property "Value" ""
			(at 0 0 0)
			(layer "F.Fab")
			(effects
				(font
					(size 1.27 1.27)
				)
			)
		)
		(duplicate_pad_numbers_are_jumpers no)
		(fp_line
			(start -1.524 -0.762)
			(end 1.524 -0.762)
			(stroke
				(width 0.1524)
				(type default)
			)
			(layer "F.SilkS")
		)
		(fp_line
			(start -1.524 0.762)
			(end -1.524 -0.762)
			(stroke
				(width 0.1524)
				(type default)
			)
			(layer "F.SilkS")
		)
		(fp_line
			(start 1.524 -0.762)
			(end 1.524 0.762)
			(stroke
				(width 0.1524)
				(type default)
			)
			(layer "F.SilkS")
		)
		(fp_line
			(start 1.524 0.762)
			(end -1.524 0.762)
			(stroke
				(width 0.1524)
				(type default)
			)
			(layer "F.SilkS")
		)
		(fp_line
			(start -1.1049 -0.724916)
			(end -1.1049 0.724916)
			(stroke
				(width 0.1)
				(type default)
			)
			(layer "F.Fab")
		)
		(fp_line
			(start -1.1049 0.724916)
			(end 1.1049 0.724916)
			(stroke
				(width 0.1)
				(type default)
			)
			(layer "F.Fab")
		)
		(fp_line
			(start 1.1049 -0.724916)
			(end -1.1049 -0.724916)
			(stroke
				(width 0.1)
				(type default)
			)
			(layer "F.Fab")
		)
		(fp_line
			(start 1.1049 0.724916)
			(end 1.1049 -0.724916)
			(stroke
				(width 0.1)
				(type default)
			)
			(layer "F.Fab")
		)
		(pad "1" smd rect
			(at -0.889 0 180)
			(size 1.016 1.27)
			(layers "F.Cu" "F.Mask" "F.Paste")
			(net "GND")
		)
		(pad "2" smd rect
			(at 0.889 0 180)
			(size 1.016 1.27)
			(layers "F.Cu" "F.Mask" "F.Paste")
			(net "P12V_AUX")
		)
	)
	(footprint ""
		(layer "F.Cu")
		(at 204.591158 -85.691472)
		(property "Reference" "R4358"
			(at 0 0 0)
			(layer "F.SilkS")
			(hide yes)
			(effects
				(font
					(size 1.27 1.27)
				)
			)
		)
		(property "Value" ""
			(at 0 0 0)
			(layer "F.Fab")
			(effects
				(font
					(size 1.27 1.27)
				)
			)
		)
		(duplicate_pad_numbers_are_jumpers no)
		(fp_line
			(start -0.7874 -0.4064)
			(end 0.7874 -0.4064)
			(stroke
				(width 0.1524)
				(type default)
			)
			(layer "F.SilkS")
		)
		(fp_line
			(start -0.7874 0.4064)
			(end -0.7874 -0.4064)
			(stroke
				(width 0.1524)
				(type default)
			)
			(layer "F.SilkS")
		)
		(fp_line
			(start 0.7874 -0.4064)
			(end 0.7874 0.4064)
			(stroke
				(width 0.1524)
				(type default)
			)
			(layer "F.SilkS")
		)
		(fp_line
			(start 0.7874 0.4064)
			(end -0.7874 0.4064)
			(stroke
				(width 0.1524)
				(type default)
			)
			(layer "F.SilkS")
		)
		(fp_line
			(start -0.67945 -0.305054)
			(end -0.12065 -0.305054)
			(stroke
				(width 0.1)
				(type default)
			)
			(layer "F.Fab")
		)
		(fp_line
			(start -0.67945 0.3048)
			(end -0.67945 -0.305054)
			(stroke
				(width 0.1)
				(type default)
			)
			(layer "F.Fab")
		)
		(fp_line
			(start -0.12065 -0.305054)
			(end -0.12065 -0.2794)
			(stroke
				(width 0.1)
				(type default)
			)
			(layer "F.Fab")
		)
		(fp_line
			(start -0.12065 -0.2794)
			(end 0.12065 -0.2794)
			(stroke
				(width 0.1)
				(type default)
			)
			(layer "F.Fab")
		)
		(fp_line
			(start -0.12065 0.2794)
			(end -0.12065 0.3048)
			(stroke
				(width 0.1)
				(type default)
			)
			(layer "F.Fab")
		)
		(fp_line
			(start -0.12065 0.3048)
			(end -0.67945 0.3048)
			(stroke
				(width 0.1)
				(type default)
			)
			(layer "F.Fab")
		)
		(fp_line
			(start 0.120396 0.2794)
			(end -0.12065 0.2794)
			(stroke
				(width 0.1)
				(type default)
			)
			(layer "F.Fab")
		)
		(fp_line
			(start 0.120396 0.3048)
			(end 0.120396 0.2794)
			(stroke
				(width 0.1)
				(type default)
			)
			(layer "F.Fab")
		)
		(fp_line
			(start 0.12065 -0.3048)
			(end 0.67945 -0.3048)
			(stroke
				(width 0.1)
				(type default)
			)
			(layer "F.Fab")
		)
		(fp_line
			(start 0.12065 -0.2794)
			(end 0.12065 -0.3048)
			(stroke
				(width 0.1)
				(type default)
			)
			(layer "F.Fab")
		)
		(fp_line
			(start 0.67945 -0.3048)
			(end 0.67945 0.3048)
			(stroke
				(width 0.1)
				(type default)
			)
			(layer "F.Fab")
		)
		(fp_line
			(start 0.67945 0.3048)
			(end 0.120396 0.3048)
			(stroke
				(width 0.1)
				(type default)
			)
			(layer "F.Fab")
		)
		(pad "1" smd circle
			(at -0.40005 0)
			(size 0 0)
			(layers "F.Cu" "F.Mask" "F.Paste")
			(net "P3V3_AUX")
		)
		(pad "2" smd circle
			(at 0.40005 0)
			(size 0 0)
			(layers "F.Cu" "F.Mask" "F.Paste")
			(net "RST_SSD_LED_IOEXP_R_N")
		)
	)
	(footprint ""
		(layer "F.Cu")
		(at 162.160712 -356.244906 90)
		(property "Reference" "C400"
			(at 0 0 90)
			(layer "F.SilkS")
			(hide yes)
			(effects
				(font
					(size 1.27 1.27)
				)
			)
		)
		(property "Value" ""
			(at 0 0 90)
			(layer "F.Fab")
			(effects
				(font
					(size 1.27 1.27)
				)
			)
		)
		(duplicate_pad_numbers_are_jumpers no)
		(fp_line
			(start 0.299974 -0.150114)
			(end 0.299974 0.150114)
			(stroke
				(width 0.1)
				(type default)
			)
			(layer "F.Fab")
		)
		(fp_line
			(start -0.299974 -0.150114)
			(end 0.299974 -0.150114)
			(stroke
				(width 0.1)
				(type default)
			)
			(layer "F.Fab")
		)
		(fp_line
			(start 0.299974 0.150114)
			(end -0.299974 0.150114)
			(stroke
				(width 0.1)
				(type default)
			)
			(layer "F.Fab")
		)
		(fp_line
			(start -0.299974 0.150114)
			(end -0.299974 -0.150114)
			(stroke
				(width 0.1)
				(type default)
			)
			(layer "F.Fab")
		)
		(pad "1" smd rect
			(at -0.2667 0 90)
			(size 0.3048 0.381)
			(layers "F.Cu" "F.Mask" "F.Paste")
			(net "P5E_PEX1_STN7_TX_DP<113>")
		)
		(pad "2" smd rect
			(at 0.2667 0 90)
			(size 0.3048 0.381)
			(layers "F.Cu" "F.Mask" "F.Paste")
			(net "P5E_PEX1_STN7_TX_C_DP<113>")
		)
	)
	(footprint ""
		(layer "F.Cu")
		(at 139.756642 -20.467574 180)
		(property "Reference" "R1661"
			(at 0 0 180)
			(layer "F.SilkS")
			(hide yes)
			(effects
				(font
					(size 1.27 1.27)
				)
			)
		)
		(property "Value" ""
			(at 0 0 180)
			(layer "F.Fab")
			(effects
				(font
					(size 1.27 1.27)
				)
			)
		)
		(duplicate_pad_numbers_are_jumpers no)
		(fp_line
			(start 0.7874 0.4064)
			(end -0.7874 0.4064)
			(stroke
				(width 0.1524)
				(type default)
			)
			(layer "F.SilkS")
		)
		(fp_line
			(start 0.7874 -0.4064)
			(end 0.7874 0.4064)
			(stroke
				(width 0.1524)
				(type default)
			)
			(layer "F.SilkS")
		)
		(fp_line
			(start -0.7874 0.4064)
			(end -0.7874 -0.4064)
			(stroke
				(width 0.1524)
				(type default)
			)
			(layer "F.SilkS")
		)
		(fp_line
			(start -0.7874 -0.4064)
			(end 0.7874 -0.4064)
			(stroke
				(width 0.1524)
				(type default)
			)
			(layer "F.SilkS")
		)
		(fp_line
			(start 0.67945 0.3048)
			(end 0.120396 0.3048)
			(stroke
				(width 0.1)
				(type default)
			)
			(layer "F.Fab")
		)
		(fp_line
			(start 0.67945 -0.3048)
			(end 0.67945 0.3048)
			(stroke
				(width 0.1)
				(type default)
			)
			(layer "F.Fab")
		)
		(fp_line
			(start 0.12065 -0.2794)
			(end 0.12065 -0.3048)
			(stroke
				(width 0.1)
				(type default)
			)
			(layer "F.Fab")
		)
		(fp_line
			(start 0.12065 -0.3048)
			(end 0.67945 -0.3048)
			(stroke
				(width 0.1)
				(type default)
			)
			(layer "F.Fab")
		)
		(fp_line
			(start 0.120396 0.3048)
			(end 0.120396 0.2794)
			(stroke
				(width 0.1)
				(type default)
			)
			(layer "F.Fab")
		)
		(fp_line
			(start 0.120396 0.2794)
			(end -0.12065 0.2794)
			(stroke
				(width 0.1)
				(type default)
			)
			(layer "F.Fab")
		)
		(fp_line
			(start -0.12065 0.3048)
			(end -0.67945 0.3048)
			(stroke
				(width 0.1)
				(type default)
			)
			(layer "F.Fab")
		)
		(fp_line
			(start -0.12065 0.2794)
			(end -0.12065 0.3048)
			(stroke
				(width 0.1)
				(type default)
			)
			(layer "F.Fab")
		)
		(fp_line
			(start -0.12065 -0.2794)
			(end 0.12065 -0.2794)
			(stroke
				(width 0.1)
				(type default)
			)
			(layer "F.Fab")
		)
		(fp_line
			(start -0.12065 -0.305054)
			(end -0.12065 -0.2794)
			(stroke
				(width 0.1)
				(type default)
			)
			(layer "F.Fab")
		)
		(fp_line
			(start -0.67945 0.3048)
			(end -0.67945 -0.305054)
			(stroke
				(width 0.1)
				(type default)
			)
			(layer "F.Fab")
		)
		(fp_line
			(start -0.67945 -0.305054)
			(end -0.12065 -0.305054)
			(stroke
				(width 0.1)
				(type default)
			)
			(layer "F.Fab")
		)
		(pad "1" smd circle
			(at -0.40005 0 180)
			(size 0 0)
			(layers "F.Cu" "F.Mask" "F.Paste")
			(net "P3V3_SSD4")
		)
		(pad "2" smd circle
			(at 0.40005 0 180)
			(size 0 0)
			(layers "F.Cu" "F.Mask" "F.Paste")
			(net "SMB_ISO_SSD4_SDA")
		)
	)
	(footprint ""
		(layer "F.Cu")
		(at 261.355078 -53.468524 90)
		(property "Reference" "PC557"
			(at 0 0 90)
			(layer "F.SilkS")
			(hide yes)
			(effects
				(font
					(size 1.27 1.27)
				)
			)
		)
		(property "Value" ""
			(at 0 0 90)
			(layer "F.Fab")
			(effects
				(font
					(size 1.27 1.27)
				)
			)
		)
		(duplicate_pad_numbers_are_jumpers no)
		(fp_line
			(start 1.524 -0.762)
			(end 1.524 0.762)
			(stroke
				(width 0.1524)
				(type default)
			)
			(layer "F.SilkS")
		)
		(fp_line
			(start -1.524 -0.762)
			(end 1.524 -0.762)
			(stroke
				(width 0.1524)
				(type default)
			)
			(layer "F.SilkS")
		)
		(fp_line
			(start 1.524 0.762)
			(end -1.524 0.762)
			(stroke
				(width 0.1524)
				(type default)
			)
			(layer "F.SilkS")
		)
		(fp_line
			(start -1.524 0.762)
			(end -1.524 -0.762)
			(stroke
				(width 0.1524)
				(type default)
			)
			(layer "F.SilkS")
		)
		(fp_line
			(start 1.1049 -0.724916)
			(end -1.1049 -0.724916)
			(stroke
				(width 0.1)
				(type default)
			)
			(layer "F.Fab")
		)
		(fp_line
			(start -1.1049 -0.724916)
			(end -1.1049 0.724916)
			(stroke
				(width 0.1)
				(type default)
			)
			(layer "F.Fab")
		)
		(fp_line
			(start 1.1049 0.724916)
			(end 1.1049 -0.724916)
			(stroke
				(width 0.1)
				(type default)
			)
			(layer "F.Fab")
		)
		(fp_line
			(start -1.1049 0.724916)
			(end 1.1049 0.724916)
			(stroke
				(width 0.1)
				(type default)
			)
			(layer "F.Fab")
		)
		(pad "1" smd rect
			(at -0.889 0 270)
			(size 1.016 1.27)
			(layers "F.Cu" "F.Mask" "F.Paste")
			(net "GND")
		)
		(pad "2" smd rect
			(at 0.889 0 270)
			(size 1.016 1.27)
			(layers "F.Cu" "F.Mask" "F.Paste")
			(net "P3V3_AUX")
		)
	)
	(footprint ""
		(layer "F.Cu")
		(at 323.917818 -223.389698 180)
		(property "Reference" "R2980"
			(at 0 0 180)
			(layer "F.SilkS")
			(hide yes)
			(effects
				(font
					(size 1.27 1.27)
				)
			)
		)
		(property "Value" ""
			(at 0 0 180)
			(layer "F.Fab")
			(effects
				(font
					(size 1.27 1.27)
				)
			)
		)
		(duplicate_pad_numbers_are_jumpers no)
		(fp_line
			(start 0.7874 0.4064)
			(end -0.7874 0.4064)
			(stroke
				(width 0.1524)
				(type default)
			)
			(layer "F.SilkS")
		)
		(fp_line
			(start 0.7874 -0.4064)
			(end 0.7874 0.4064)
			(stroke
				(width 0.1524)
				(type default)
			)
			(layer "F.SilkS")
		)
		(fp_line
			(start -0.7874 0.4064)
			(end -0.7874 -0.4064)
			(stroke
				(width 0.1524)
				(type default)
			)
			(layer "F.SilkS")
		)
		(fp_line
			(start -0.7874 -0.4064)
			(end 0.7874 -0.4064)
			(stroke
				(width 0.1524)
				(type default)
			)
			(layer "F.SilkS")
		)
		(fp_line
			(start 0.67945 0.3048)
			(end 0.120396 0.3048)
			(stroke
				(width 0.1)
				(type default)
			)
			(layer "F.Fab")
		)
		(fp_line
			(start 0.67945 -0.3048)
			(end 0.67945 0.3048)
			(stroke
				(width 0.1)
				(type default)
			)
			(layer "F.Fab")
		)
		(fp_line
			(start 0.12065 -0.2794)
			(end 0.12065 -0.3048)
			(stroke
				(width 0.1)
				(type default)
			)
			(layer "F.Fab")
		)
		(fp_line
			(start 0.12065 -0.3048)
			(end 0.67945 -0.3048)
			(stroke
				(width 0.1)
				(type default)
			)
			(layer "F.Fab")
		)
		(fp_line
			(start 0.120396 0.3048)
			(end 0.120396 0.2794)
			(stroke
				(width 0.1)
				(type default)
			)
			(layer "F.Fab")
		)
		(fp_line
			(start 0.120396 0.2794)
			(end -0.12065 0.2794)
			(stroke
				(width 0.1)
				(type default)
			)
			(layer "F.Fab")
		)
		(fp_line
			(start -0.12065 0.3048)
			(end -0.67945 0.3048)
			(stroke
				(width 0.1)
				(type default)
			)
			(layer "F.Fab")
		)
		(fp_line
			(start -0.12065 0.2794)
			(end -0.12065 0.3048)
			(stroke
				(width 0.1)
				(type default)
			)
			(layer "F.Fab")
		)
		(fp_line
			(start -0.12065 -0.2794)
			(end 0.12065 -0.2794)
			(stroke
				(width 0.1)
				(type default)
			)
			(layer "F.Fab")
		)
		(fp_line
			(start -0.12065 -0.305054)
			(end -0.12065 -0.2794)
			(stroke
				(width 0.1)
				(type default)
			)
			(layer "F.Fab")
		)
		(fp_line
			(start -0.67945 0.3048)
			(end -0.67945 -0.305054)
			(stroke
				(width 0.1)
				(type default)
			)
			(layer "F.Fab")
		)
		(fp_line
			(start -0.67945 -0.305054)
			(end -0.12065 -0.305054)
			(stroke
				(width 0.1)
				(type default)
			)
			(layer "F.Fab")
		)
		(pad "1" smd circle
			(at -0.40005 0 180)
			(size 0 0)
			(layers "F.Cu" "F.Mask" "F.Paste")
			(net "LED_POSTCODE_2")
		)
		(pad "2" smd circle
			(at 0.40005 0 180)
			(size 0 0)
			(layers "F.Cu" "F.Mask" "F.Paste")
			(net "LED_POSTCODE_R_2")
		)
	)
	(footprint ""
		(layer "F.Cu")
		(at 340.614 -205.232 -90)
		(property "Reference" "R4133"
			(at 0 0 270)
			(layer "F.SilkS")
			(hide yes)
			(effects
				(font
					(size 1.27 1.27)
				)
			)
		)
		(property "Value" ""
			(at 0 0 270)
			(layer "F.Fab")
			(effects
				(font
					(size 1.27 1.27)
				)
			)
		)
		(duplicate_pad_numbers_are_jumpers no)
		(fp_line
			(start -0.7874 0.4064)
			(end -0.7874 -0.4064)
			(stroke
				(width 0.1524)
				(type default)
			)
			(layer "F.SilkS")
		)
		(fp_line
			(start 0.7874 0.4064)
			(end -0.7874 0.4064)
			(stroke
				(width 0.1524)
				(type default)
			)
			(layer "F.SilkS")
		)
		(fp_line
			(start -0.7874 -0.4064)
			(end 0.7874 -0.4064)
			(stroke
				(width 0.1524)
				(type default)
			)
			(layer "F.SilkS")
		)
		(fp_line
			(start 0.7874 -0.4064)
			(end 0.7874 0.4064)
			(stroke
				(width 0.1524)
				(type default)
			)
			(layer "F.SilkS")
		)
		(fp_line
			(start -0.67945 0.3048)
			(end -0.67945 -0.305054)
			(stroke
				(width 0.1)
				(type default)
			)
			(layer "F.Fab")
		)
		(fp_line
			(start -0.12065 0.3048)
			(end -0.67945 0.3048)
			(stroke
				(width 0.1)
				(type default)
			)
			(layer "F.Fab")
		)
		(fp_line
			(start 0.120396 0.3048)
			(end 0.120396 0.2794)
			(stroke
				(width 0.1)
				(type default)
			)
			(layer "F.Fab")
		)
		(fp_line
			(start 0.67945 0.3048)
			(end 0.120396 0.3048)
			(stroke
				(width 0.1)
				(type default)
			)
			(layer "F.Fab")
		)
		(fp_line
			(start -0.12065 0.2794)
			(end -0.12065 0.3048)
			(stroke
				(width 0.1)
				(type default)
			)
			(layer "F.Fab")
		)
		(fp_line
			(start 0.120396 0.2794)
			(end -0.12065 0.2794)
			(stroke
				(width 0.1)
				(type default)
			)
			(layer "F.Fab")
		)
		(fp_line
			(start -0.12065 -0.2794)
			(end 0.12065 -0.2794)
			(stroke
				(width 0.1)
				(type default)
			)
			(layer "F.Fab")
		)
		(fp_line
			(start 0.12065 -0.2794)
			(end 0.12065 -0.3048)
			(stroke
				(width 0.1)
				(type default)
			)
			(layer "F.Fab")
		)
		(fp_line
			(start 0.12065 -0.3048)
			(end 0.67945 -0.3048)
			(stroke
				(width 0.1)
				(type default)
			)
			(layer "F.Fab")
		)
		(fp_line
			(start 0.67945 -0.3048)
			(end 0.67945 0.3048)
			(stroke
				(width 0.1)
				(type default)
			)
			(layer "F.Fab")
		)
		(fp_line
			(start -0.67945 -0.305054)
			(end -0.12065 -0.305054)
			(stroke
				(width 0.1)
				(type default)
			)
			(layer "F.Fab")
		)
		(fp_line
			(start -0.12065 -0.305054)
			(end -0.12065 -0.2794)
			(stroke
				(width 0.1)
				(type default)
			)
			(layer "F.Fab")
		)
		(pad "1" smd circle
			(at -0.40005 0 270)
			(size 0 0)
			(layers "F.Cu" "F.Mask" "F.Paste")
			(net "RST_SSD12_PERST_N")
		)
		(pad "2" smd circle
			(at 0.40005 0 270)
			(size 0 0)
			(layers "F.Cu" "F.Mask" "F.Paste")
			(net "RST_SSD12_PERST_R_N")
		)
	)
	(footprint ""
		(layer "F.Cu")
		(at 239.754918 -314.068714 180)
		(property "Reference" "PC249"
			(at 0 0 180)
			(layer "F.SilkS")
			(hide yes)
			(effects
				(font
					(size 1.27 1.27)
				)
			)
		)
		(property "Value" ""
			(at 0 0 180)
			(layer "F.Fab")
			(effects
				(font
					(size 1.27 1.27)
				)
			)
		)
		(duplicate_pad_numbers_are_jumpers no)
		(fp_line
			(start 1.524 0.762)
			(end -1.524 0.762)
			(stroke
				(width 0.1524)
				(type default)
			)
			(layer "F.SilkS")
		)
		(fp_line
			(start 1.524 -0.762)
			(end 1.524 0.762)
			(stroke
				(width 0.1524)
				(type default)
			)
			(layer "F.SilkS")
		)
		(fp_line
			(start -1.524 0.762)
			(end -1.524 -0.762)
			(stroke
				(width 0.1524)
				(type default)
			)
			(layer "F.SilkS")
		)
		(fp_line
			(start -1.524 -0.762)
			(end 1.524 -0.762)
			(stroke
				(width 0.1524)
				(type default)
			)
			(layer "F.SilkS")
		)
		(fp_line
			(start 1.1049 0.724916)
			(end 1.1049 -0.724916)
			(stroke
				(width 0.1)
				(type default)
			)
			(layer "F.Fab")
		)
		(fp_line
			(start 1.1049 -0.724916)
			(end -1.1049 -0.724916)
			(stroke
				(width 0.1)
				(type default)
			)
			(layer "F.Fab")
		)
		(fp_line
			(start -1.1049 0.724916)
			(end 1.1049 0.724916)
			(stroke
				(width 0.1)
				(type default)
			)
			(layer "F.Fab")
		)
		(fp_line
			(start -1.1049 -0.724916)
			(end -1.1049 0.724916)
			(stroke
				(width 0.1)
				(type default)
			)
			(layer "F.Fab")
		)
		(pad "1" smd rect
			(at -0.889 0)
			(size 1.016 1.27)
			(layers "F.Cu" "F.Mask" "F.Paste")
			(net "SW_P12V_P1V25_PEX2_FLT")
		)
		(pad "2" smd rect
			(at 0.889 0)
			(size 1.016 1.27)
			(layers "F.Cu" "F.Mask" "F.Paste")
			(net "GND")
		)
	)
	(footprint ""
		(layer "F.Cu")
		(at 396.209266 -89.500202 180)
		(property "Reference" "R1751"
			(at 0 0 180)
			(layer "F.SilkS")
			(hide yes)
			(effects
				(font
					(size 1.27 1.27)
				)
			)
		)
		(property "Value" ""
			(at 0 0 180)
			(layer "F.Fab")
			(effects
				(font
					(size 1.27 1.27)
				)
			)
		)
		(duplicate_pad_numbers_are_jumpers no)
		(fp_line
			(start 0.7874 0.4064)
			(end -0.7874 0.4064)
			(stroke
				(width 0.1524)
				(type default)
			)
			(layer "F.SilkS")
		)
		(fp_line
			(start 0.7874 -0.4064)
			(end 0.7874 0.4064)
			(stroke
				(width 0.1524)
				(type default)
			)
			(layer "F.SilkS")
		)
		(fp_line
			(start -0.7874 0.4064)
			(end -0.7874 -0.4064)
			(stroke
				(width 0.1524)
				(type default)
			)
			(layer "F.SilkS")
		)
		(fp_line
			(start -0.7874 -0.4064)
			(end 0.7874 -0.4064)
			(stroke
				(width 0.1524)
				(type default)
			)
			(layer "F.SilkS")
		)
		(fp_line
			(start 0.67945 0.3048)
			(end 0.120396 0.3048)
			(stroke
				(width 0.1)
				(type default)
			)
			(layer "F.Fab")
		)
		(fp_line
			(start 0.67945 -0.3048)
			(end 0.67945 0.3048)
			(stroke
				(width 0.1)
				(type default)
			)
			(layer "F.Fab")
		)
		(fp_line
			(start 0.12065 -0.2794)
			(end 0.12065 -0.3048)
			(stroke
				(width 0.1)
				(type default)
			)
			(layer "F.Fab")
		)
		(fp_line
			(start 0.12065 -0.3048)
			(end 0.67945 -0.3048)
			(stroke
				(width 0.1)
				(type default)
			)
			(layer "F.Fab")
		)
		(fp_line
			(start 0.120396 0.3048)
			(end 0.120396 0.2794)
			(stroke
				(width 0.1)
				(type default)
			)
			(layer "F.Fab")
		)
		(fp_line
			(start 0.120396 0.2794)
			(end -0.12065 0.2794)
			(stroke
				(width 0.1)
				(type default)
			)
			(layer "F.Fab")
		)
		(fp_line
			(start -0.12065 0.3048)
			(end -0.67945 0.3048)
			(stroke
				(width 0.1)
				(type default)
			)
			(layer "F.Fab")
		)
		(fp_line
			(start -0.12065 0.2794)
			(end -0.12065 0.3048)
			(stroke
				(width 0.1)
				(type default)
			)
			(layer "F.Fab")
		)
		(fp_line
			(start -0.12065 -0.2794)
			(end 0.12065 -0.2794)
			(stroke
				(width 0.1)
				(type default)
			)
			(layer "F.Fab")
		)
		(fp_line
			(start -0.12065 -0.305054)
			(end -0.12065 -0.2794)
			(stroke
				(width 0.1)
				(type default)
			)
			(layer "F.Fab")
		)
		(fp_line
			(start -0.67945 0.3048)
			(end -0.67945 -0.305054)
			(stroke
				(width 0.1)
				(type default)
			)
			(layer "F.Fab")
		)
		(fp_line
			(start -0.67945 -0.305054)
			(end -0.12065 -0.305054)
			(stroke
				(width 0.1)
				(type default)
			)
			(layer "F.Fab")
		)
		(pad "1" smd circle
			(at -0.40005 0 180)
			(size 0 0)
			(layers "F.Cu" "F.Mask" "F.Paste")
			(net "P3V3_AUX")
		)
		(pad "2" smd circle
			(at 0.40005 0 180)
			(size 0 0)
			(layers "F.Cu" "F.Mask" "F.Paste")
			(net "BIC_I2C6_MUX_A2")
		)
	)
	(footprint ""
		(layer "F.Cu")
		(at 79.462376 -22.937216 90)
		(property "Reference" "R1655"
			(at 0 0 90)
			(layer "F.SilkS")
			(hide yes)
			(effects
				(font
					(size 1.27 1.27)
				)
			)
		)
		(property "Value" ""
			(at 0 0 90)
			(layer "F.Fab")
			(effects
				(font
					(size 1.27 1.27)
				)
			)
		)
		(duplicate_pad_numbers_are_jumpers no)
		(fp_line
			(start 0.7874 -0.4064)
			(end 0.7874 0.4064)
			(stroke
				(width 0.1524)
				(type default)
			)
			(layer "F.SilkS")
		)
		(fp_line
			(start -0.7874 -0.4064)
			(end 0.7874 -0.4064)
			(stroke
				(width 0.1524)
				(type default)
			)
			(layer "F.SilkS")
		)
		(fp_line
			(start 0.7874 0.4064)
			(end -0.7874 0.4064)
			(stroke
				(width 0.1524)
				(type default)
			)
			(layer "F.SilkS")
		)
		(fp_line
			(start -0.7874 0.4064)
			(end -0.7874 -0.4064)
			(stroke
				(width 0.1524)
				(type default)
			)
			(layer "F.SilkS")
		)
		(fp_line
			(start -0.12065 -0.305054)
			(end -0.12065 -0.2794)
			(stroke
				(width 0.1)
				(type default)
			)
			(layer "F.Fab")
		)
		(fp_line
			(start -0.67945 -0.305054)
			(end -0.12065 -0.305054)
			(stroke
				(width 0.1)
				(type default)
			)
			(layer "F.Fab")
		)
		(fp_line
			(start 0.67945 -0.3048)
			(end 0.67945 0.3048)
			(stroke
				(width 0.1)
				(type default)
			)
			(layer "F.Fab")
		)
		(fp_line
			(start 0.12065 -0.3048)
			(end 0.67945 -0.3048)
			(stroke
				(width 0.1)
				(type default)
			)
			(layer "F.Fab")
		)
		(fp_line
			(start 0.12065 -0.2794)
			(end 0.12065 -0.3048)
			(stroke
				(width 0.1)
				(type default)
			)
			(layer "F.Fab")
		)
		(fp_line
			(start -0.12065 -0.2794)
			(end 0.12065 -0.2794)
			(stroke
				(width 0.1)
				(type default)
			)
			(layer "F.Fab")
		)
		(fp_line
			(start 0.120396 0.2794)
			(end -0.12065 0.2794)
			(stroke
				(width 0.1)
				(type default)
			)
			(layer "F.Fab")
		)
		(fp_line
			(start -0.12065 0.2794)
			(end -0.12065 0.3048)
			(stroke
				(width 0.1)
				(type default)
			)
			(layer "F.Fab")
		)
		(fp_line
			(start 0.67945 0.3048)
			(end 0.120396 0.3048)
			(stroke
				(width 0.1)
				(type default)
			)
			(layer "F.Fab")
		)
		(fp_line
			(start 0.120396 0.3048)
			(end 0.120396 0.2794)
			(stroke
				(width 0.1)
				(type default)
			)
			(layer "F.Fab")
		)
		(fp_line
			(start -0.12065 0.3048)
			(end -0.67945 0.3048)
			(stroke
				(width 0.1)
				(type default)
			)
			(layer "F.Fab")
		)
		(fp_line
			(start -0.67945 0.3048)
			(end -0.67945 -0.305054)
			(stroke
				(width 0.1)
				(type default)
			)
			(layer "F.Fab")
		)
		(pad "1" smd circle
			(at -0.40005 0 90)
			(size 0 0)
			(layers "F.Cu" "F.Mask" "F.Paste")
			(net "SMB_BIC_I2C9_MUX0_SSD2_R_SDA")
		)
		(pad "2" smd circle
			(at 0.40005 0 90)
			(size 0 0)
			(layers "F.Cu" "F.Mask" "F.Paste")
			(net "SMB_ISO_SSD2_SDA")
		)
	)
	(footprint ""
		(layer "F.Cu")
		(at 342.886792 -240.691162 90)
		(property "Reference" "R3584"
			(at 0 0 90)
			(layer "F.SilkS")
			(hide yes)
			(effects
				(font
					(size 1.27 1.27)
				)
			)
		)
		(property "Value" ""
			(at 0 0 90)
			(layer "F.Fab")
			(effects
				(font
					(size 1.27 1.27)
				)
			)
		)
		(duplicate_pad_numbers_are_jumpers no)
		(fp_line
			(start 0.7874 -0.4064)
			(end 0.7874 0.4064)
			(stroke
				(width 0.1524)
				(type default)
			)
			(layer "F.SilkS")
		)
		(fp_line
			(start -0.7874 -0.4064)
			(end 0.7874 -0.4064)
			(stroke
				(width 0.1524)
				(type default)
			)
			(layer "F.SilkS")
		)
		(fp_line
			(start 0.7874 0.4064)
			(end -0.7874 0.4064)
			(stroke
				(width 0.1524)
				(type default)
			)
			(layer "F.SilkS")
		)
		(fp_line
			(start -0.7874 0.4064)
			(end -0.7874 -0.4064)
			(stroke
				(width 0.1524)
				(type default)
			)
			(layer "F.SilkS")
		)
		(fp_line
			(start -0.12065 -0.305054)
			(end -0.12065 -0.2794)
			(stroke
				(width 0.1)
				(type default)
			)
			(layer "F.Fab")
		)
		(fp_line
			(start -0.67945 -0.305054)
			(end -0.12065 -0.305054)
			(stroke
				(width 0.1)
				(type default)
			)
			(layer "F.Fab")
		)
		(fp_line
			(start 0.67945 -0.3048)
			(end 0.67945 0.3048)
			(stroke
				(width 0.1)
				(type default)
			)
			(layer "F.Fab")
		)
		(fp_line
			(start 0.12065 -0.3048)
			(end 0.67945 -0.3048)
			(stroke
				(width 0.1)
				(type default)
			)
			(layer "F.Fab")
		)
		(fp_line
			(start 0.12065 -0.2794)
			(end 0.12065 -0.3048)
			(stroke
				(width 0.1)
				(type default)
			)
			(layer "F.Fab")
		)
		(fp_line
			(start -0.12065 -0.2794)
			(end 0.12065 -0.2794)
			(stroke
				(width 0.1)
				(type default)
			)
			(layer "F.Fab")
		)
		(fp_line
			(start 0.120396 0.2794)
			(end -0.12065 0.2794)
			(stroke
				(width 0.1)
				(type default)
			)
			(layer "F.Fab")
		)
		(fp_line
			(start -0.12065 0.2794)
			(end -0.12065 0.3048)
			(stroke
				(width 0.1)
				(type default)
			)
			(layer "F.Fab")
		)
		(fp_line
			(start 0.67945 0.3048)
			(end 0.120396 0.3048)
			(stroke
				(width 0.1)
				(type default)
			)
			(layer "F.Fab")
		)
		(fp_line
			(start 0.120396 0.3048)
			(end 0.120396 0.2794)
			(stroke
				(width 0.1)
				(type default)
			)
			(layer "F.Fab")
		)
		(fp_line
			(start -0.12065 0.3048)
			(end -0.67945 0.3048)
			(stroke
				(width 0.1)
				(type default)
			)
			(layer "F.Fab")
		)
		(fp_line
			(start -0.67945 0.3048)
			(end -0.67945 -0.305054)
			(stroke
				(width 0.1)
				(type default)
			)
			(layer "F.Fab")
		)
		(pad "1" smd circle
			(at -0.40005 0 90)
			(size 0 0)
			(layers "F.Cu" "F.Mask" "F.Paste")
			(net "RST_SSD0_PERST_N")
		)
		(pad "2" smd circle
			(at 0.40005 0 90)
			(size 0 0)
			(layers "F.Cu" "F.Mask" "F.Paste")
			(net "RST_SSD0_PERST_R_N")
		)
	)
	(footprint ""
		(layer "F.Cu")
		(at 242.205256 -228.57206)
		(property "Reference" "R6760"
			(at 0 0 0)
			(layer "F.SilkS")
			(hide yes)
			(effects
				(font
					(size 1.27 1.27)
				)
			)
		)
		(property "Value" ""
			(at 0 0 0)
			(layer "F.Fab")
			(effects
				(font
					(size 1.27 1.27)
				)
			)
		)
		(duplicate_pad_numbers_are_jumpers no)
		(fp_line
			(start 0.7874 -0.4064)
			(end 0.7874 0.4064)
			(stroke
				(width 0.1524)
				(type default)
			)
			(layer "F.SilkS")
		)
		(fp_line
			(start -0.67945 -0.305054)
			(end -0.12065 -0.305054)
			(stroke
				(width 0.1)
				(type default)
			)
			(layer "F.Fab")
		)
		(fp_line
			(start -0.67945 0.3048)
			(end -0.67945 -0.305054)
			(stroke
				(width 0.1)
				(type default)
			)
			(layer "F.Fab")
		)
		(fp_line
			(start -0.12065 -0.305054)
			(end -0.12065 -0.2794)
			(stroke
				(width 0.1)
				(type default)
			)
			(layer "F.Fab")
		)
		(fp_line
			(start -0.12065 -0.2794)
			(end 0.12065 -0.2794)
			(stroke
				(width 0.1)
				(type default)
			)
			(layer "F.Fab")
		)
		(fp_line
			(start -0.12065 0.2794)
			(end -0.12065 0.3048)
			(stroke
				(width 0.1)
				(type default)
			)
			(layer "F.Fab")
		)
		(fp_line
			(start -0.12065 0.3048)
			(end -0.67945 0.3048)
			(stroke
				(width 0.1)
				(type default)
			)
			(layer "F.Fab")
		)
		(fp_line
			(start 0.120396 0.2794)
			(end -0.12065 0.2794)
			(stroke
				(width 0.1)
				(type default)
			)
			(layer "F.Fab")
		)
		(fp_line
			(start 0.120396 0.3048)
			(end 0.120396 0.2794)
			(stroke
				(width 0.1)
				(type default)
			)
			(layer "F.Fab")
		)
		(fp_line
			(start 0.12065 -0.3048)
			(end 0.67945 -0.3048)
			(stroke
				(width 0.1)
				(type default)
			)
			(layer "F.Fab")
		)
		(fp_line
			(start 0.12065 -0.2794)
			(end 0.12065 -0.3048)
			(stroke
				(width 0.1)
				(type default)
			)
			(layer "F.Fab")
		)
		(fp_line
			(start 0.67945 -0.3048)
			(end 0.67945 0.3048)
			(stroke
				(width 0.1)
				(type default)
			)
			(layer "F.Fab")
		)
		(fp_line
			(start 0.67945 0.3048)
			(end 0.120396 0.3048)
			(stroke
				(width 0.1)
				(type default)
			)
			(layer "F.Fab")
		)
		(pad "1" smd circle
			(at -0.40005 0)
			(size 0 0)
			(layers "F.Cu" "F.Mask" "F.Paste")
			(net "USB2_BIC_DP")
		)
		(pad "2" smd circle
			(at 0.40005 0)
			(size 0 0)
			(layers "F.Cu" "F.Mask" "F.Paste")
			(net "GND")
		)
	)
	(footprint ""
		(layer "F.Cu")
		(at 258.78409 -29.222954 -90)
		(property "Reference" "PC958"
			(at 0 0 270)
			(layer "F.SilkS")
			(hide yes)
			(effects
				(font
					(size 1.27 1.27)
				)
			)
		)
		(property "Value" ""
			(at 0 0 270)
			(layer "F.Fab")
			(effects
				(font
					(size 1.27 1.27)
				)
			)
		)
		(duplicate_pad_numbers_are_jumpers no)
		(fp_line
			(start -0.7874 0.4064)
			(end -0.7874 -0.4064)
			(stroke
				(width 0.1524)
				(type default)
			)
			(layer "F.SilkS")
		)
		(fp_line
			(start 0.7874 0.4064)
			(end -0.7874 0.4064)
			(stroke
				(width 0.1524)
				(type default)
			)
			(layer "F.SilkS")
		)
		(fp_line
			(start -0.7874 -0.4064)
			(end 0.7874 -0.4064)
			(stroke
				(width 0.1524)
				(type default)
			)
			(layer "F.SilkS")
		)
		(fp_line
			(start 0.7874 -0.4064)
			(end 0.7874 0.4064)
			(stroke
				(width 0.1524)
				(type default)
			)
			(layer "F.SilkS")
		)
		(fp_line
			(start -0.67945 0.3048)
			(end -0.67945 -0.305054)
			(stroke
				(width 0.1)
				(type default)
			)
			(layer "F.Fab")
		)
		(fp_line
			(start -0.12065 0.3048)
			(end -0.67945 0.3048)
			(stroke
				(width 0.1)
				(type default)
			)
			(layer "F.Fab")
		)
		(fp_line
			(start 0.120396 0.3048)
			(end 0.120396 0.2794)
			(stroke
				(width 0.1)
				(type default)
			)
			(layer "F.Fab")
		)
		(fp_line
			(start 0.67945 0.3048)
			(end 0.120396 0.3048)
			(stroke
				(width 0.1)
				(type default)
			)
			(layer "F.Fab")
		)
		(fp_line
			(start -0.12065 0.2794)
			(end -0.12065 0.3048)
			(stroke
				(width 0.1)
				(type default)
			)
			(layer "F.Fab")
		)
		(fp_line
			(start 0.120396 0.2794)
			(end -0.12065 0.2794)
			(stroke
				(width 0.1)
				(type default)
			)
			(layer "F.Fab")
		)
		(fp_line
			(start -0.12065 -0.2794)
			(end 0.12065 -0.2794)
			(stroke
				(width 0.1)
				(type default)
			)
			(layer "F.Fab")
		)
		(fp_line
			(start 0.12065 -0.2794)
			(end 0.12065 -0.3048)
			(stroke
				(width 0.1)
				(type default)
			)
			(layer "F.Fab")
		)
		(fp_line
			(start 0.12065 -0.3048)
			(end 0.67945 -0.3048)
			(stroke
				(width 0.1)
				(type default)
			)
			(layer "F.Fab")
		)
		(fp_line
			(start 0.67945 -0.3048)
			(end 0.67945 0.3048)
			(stroke
				(width 0.1)
				(type default)
			)
			(layer "F.Fab")
		)
		(fp_line
			(start -0.67945 -0.305054)
			(end -0.12065 -0.305054)
			(stroke
				(width 0.1)
				(type default)
			)
			(layer "F.Fab")
		)
		(fp_line
			(start -0.12065 -0.305054)
			(end -0.12065 -0.2794)
			(stroke
				(width 0.1)
				(type default)
			)
			(layer "F.Fab")
		)
		(pad "1" smd circle
			(at -0.40005 0 270)
			(size 0 0)
			(layers "F.Cu" "F.Mask" "F.Paste")
			(net "P3V3_AUX")
		)
		(pad "2" smd circle
			(at 0.40005 0 270)
			(size 0 0)
			(layers "F.Cu" "F.Mask" "F.Paste")
			(net "GND")
		)
	)
	(footprint ""
		(layer "F.Cu")
		(at 188.546486 -58.323734)
		(property "Reference" "PC389"
			(at 0 0 0)
			(layer "F.SilkS")
			(hide yes)
			(effects
				(font
					(size 1.27 1.27)
				)
			)
		)
		(property "Value" ""
			(at 0 0 0)
			(layer "F.Fab")
			(effects
				(font
					(size 1.27 1.27)
				)
			)
		)
		(duplicate_pad_numbers_are_jumpers no)
		(fp_line
			(start -1.524 -0.762)
			(end 1.524 -0.762)
			(stroke
				(width 0.1524)
				(type default)
			)
			(layer "F.SilkS")
		)
		(fp_line
			(start -1.524 0.762)
			(end -1.524 -0.762)
			(stroke
				(width 0.1524)
				(type default)
			)
			(layer "F.SilkS")
		)
		(fp_line
			(start 1.524 -0.762)
			(end 1.524 0.762)
			(stroke
				(width 0.1524)
				(type default)
			)
			(layer "F.SilkS")
		)
		(fp_line
			(start 1.524 0.762)
			(end -1.524 0.762)
			(stroke
				(width 0.1524)
				(type default)
			)
			(layer "F.SilkS")
		)
		(fp_line
			(start -1.1049 -0.724916)
			(end -1.1049 0.724916)
			(stroke
				(width 0.1)
				(type default)
			)
			(layer "F.Fab")
		)
		(fp_line
			(start -1.1049 0.724916)
			(end 1.1049 0.724916)
			(stroke
				(width 0.1)
				(type default)
			)
			(layer "F.Fab")
		)
		(fp_line
			(start 1.1049 -0.724916)
			(end -1.1049 -0.724916)
			(stroke
				(width 0.1)
				(type default)
			)
			(layer "F.Fab")
		)
		(fp_line
			(start 1.1049 0.724916)
			(end 1.1049 -0.724916)
			(stroke
				(width 0.1)
				(type default)
			)
			(layer "F.Fab")
		)
		(pad "1" smd rect
			(at -0.889 0 180)
			(size 1.016 1.27)
			(layers "F.Cu" "F.Mask" "F.Paste")
			(net "GND")
		)
		(pad "2" smd rect
			(at 0.889 0 180)
			(size 1.016 1.27)
			(layers "F.Cu" "F.Mask" "F.Paste")
			(net "P12V_AUX")
		)
	)
	(footprint ""
		(layer "F.Cu")
		(at 381.786384 -250.070874 -90)
		(property "Reference" "R1402"
			(at 0 0 270)
			(layer "F.SilkS")
			(hide yes)
			(effects
				(font
					(size 1.27 1.27)
				)
			)
		)
		(property "Value" ""
			(at 0 0 270)
			(layer "F.Fab")
			(effects
				(font
					(size 1.27 1.27)
				)
			)
		)
		(duplicate_pad_numbers_are_jumpers no)
		(fp_line
			(start -0.7874 0.4064)
			(end -0.7874 -0.4064)
			(stroke
				(width 0.1524)
				(type default)
			)
			(layer "F.SilkS")
		)
		(fp_line
			(start 0.7874 0.4064)
			(end -0.7874 0.4064)
			(stroke
				(width 0.1524)
				(type default)
			)
			(layer "F.SilkS")
		)
		(fp_line
			(start -0.7874 -0.4064)
			(end 0.7874 -0.4064)
			(stroke
				(width 0.1524)
				(type default)
			)
			(layer "F.SilkS")
		)
		(fp_line
			(start 0.7874 -0.4064)
			(end 0.7874 0.4064)
			(stroke
				(width 0.1524)
				(type default)
			)
			(layer "F.SilkS")
		)
		(fp_line
			(start -0.67945 0.3048)
			(end -0.67945 -0.305054)
			(stroke
				(width 0.1)
				(type default)
			)
			(layer "F.Fab")
		)
		(fp_line
			(start -0.12065 0.3048)
			(end -0.67945 0.3048)
			(stroke
				(width 0.1)
				(type default)
			)
			(layer "F.Fab")
		)
		(fp_line
			(start 0.120396 0.3048)
			(end 0.120396 0.2794)
			(stroke
				(width 0.1)
				(type default)
			)
			(layer "F.Fab")
		)
		(fp_line
			(start 0.67945 0.3048)
			(end 0.120396 0.3048)
			(stroke
				(width 0.1)
				(type default)
			)
			(layer "F.Fab")
		)
		(fp_line
			(start -0.12065 0.2794)
			(end -0.12065 0.3048)
			(stroke
				(width 0.1)
				(type default)
			)
			(layer "F.Fab")
		)
		(fp_line
			(start 0.120396 0.2794)
			(end -0.12065 0.2794)
			(stroke
				(width 0.1)
				(type default)
			)
			(layer "F.Fab")
		)
		(fp_line
			(start -0.12065 -0.2794)
			(end 0.12065 -0.2794)
			(stroke
				(width 0.1)
				(type default)
			)
			(layer "F.Fab")
		)
		(fp_line
			(start 0.12065 -0.2794)
			(end 0.12065 -0.3048)
			(stroke
				(width 0.1)
				(type default)
			)
			(layer "F.Fab")
		)
		(fp_line
			(start 0.12065 -0.3048)
			(end 0.67945 -0.3048)
			(stroke
				(width 0.1)
				(type default)
			)
			(layer "F.Fab")
		)
		(fp_line
			(start 0.67945 -0.3048)
			(end 0.67945 0.3048)
			(stroke
				(width 0.1)
				(type default)
			)
			(layer "F.Fab")
		)
		(fp_line
			(start -0.67945 -0.305054)
			(end -0.12065 -0.305054)
			(stroke
				(width 0.1)
				(type default)
			)
			(layer "F.Fab")
		)
		(fp_line
			(start -0.12065 -0.305054)
			(end -0.12065 -0.2794)
			(stroke
				(width 0.1)
				(type default)
			)
			(layer "F.Fab")
		)
		(pad "1" smd circle
			(at -0.40005 0 270)
			(size 0 0)
			(layers "F.Cu" "F.Mask" "F.Paste")
			(net "PEX3_DBG_MODE2")
		)
		(pad "2" smd circle
			(at 0.40005 0 270)
			(size 0 0)
			(layers "F.Cu" "F.Mask" "F.Paste")
			(net "P1V8_PEX")
		)
	)
	(footprint ""
		(layer "F.Cu")
		(at 199.394064 -34.248852)
		(property "Reference" "R5672"
			(at 0 0 0)
			(layer "F.SilkS")
			(hide yes)
			(effects
				(font
					(size 1.27 1.27)
				)
			)
		)
		(property "Value" ""
			(at 0 0 0)
			(layer "F.Fab")
			(effects
				(font
					(size 1.27 1.27)
				)
			)
		)
		(duplicate_pad_numbers_are_jumpers no)
		(fp_line
			(start -0.7874 -0.4064)
			(end 0.7874 -0.4064)
			(stroke
				(width 0.1524)
				(type default)
			)
			(layer "F.SilkS")
		)
		(fp_line
			(start -0.7874 0.4064)
			(end -0.7874 -0.4064)
			(stroke
				(width 0.1524)
				(type default)
			)
			(layer "F.SilkS")
		)
		(fp_line
			(start 0.7874 -0.4064)
			(end 0.7874 0.4064)
			(stroke
				(width 0.1524)
				(type default)
			)
			(layer "F.SilkS")
		)
		(fp_line
			(start 0.7874 0.4064)
			(end -0.7874 0.4064)
			(stroke
				(width 0.1524)
				(type default)
			)
			(layer "F.SilkS")
		)
		(fp_line
			(start -0.67945 -0.305054)
			(end -0.12065 -0.305054)
			(stroke
				(width 0.1)
				(type default)
			)
			(layer "F.Fab")
		)
		(fp_line
			(start -0.67945 0.3048)
			(end -0.67945 -0.305054)
			(stroke
				(width 0.1)
				(type default)
			)
			(layer "F.Fab")
		)
		(fp_line
			(start -0.12065 -0.305054)
			(end -0.12065 -0.2794)
			(stroke
				(width 0.1)
				(type default)
			)
			(layer "F.Fab")
		)
		(fp_line
			(start -0.12065 -0.2794)
			(end 0.12065 -0.2794)
			(stroke
				(width 0.1)
				(type default)
			)
			(layer "F.Fab")
		)
		(fp_line
			(start -0.12065 0.2794)
			(end -0.12065 0.3048)
			(stroke
				(width 0.1)
				(type default)
			)
			(layer "F.Fab")
		)
		(fp_line
			(start -0.12065 0.3048)
			(end -0.67945 0.3048)
			(stroke
				(width 0.1)
				(type default)
			)
			(layer "F.Fab")
		)
		(fp_line
			(start 0.120396 0.2794)
			(end -0.12065 0.2794)
			(stroke
				(width 0.1)
				(type default)
			)
			(layer "F.Fab")
		)
		(fp_line
			(start 0.120396 0.3048)
			(end 0.120396 0.2794)
			(stroke
				(width 0.1)
				(type default)
			)
			(layer "F.Fab")
		)
		(fp_line
			(start 0.12065 -0.3048)
			(end 0.67945 -0.3048)
			(stroke
				(width 0.1)
				(type default)
			)
			(layer "F.Fab")
		)
		(fp_line
			(start 0.12065 -0.2794)
			(end 0.12065 -0.3048)
			(stroke
				(width 0.1)
				(type default)
			)
			(layer "F.Fab")
		)
		(fp_line
			(start 0.67945 -0.3048)
			(end 0.67945 0.3048)
			(stroke
				(width 0.1)
				(type default)
			)
			(layer "F.Fab")
		)
		(fp_line
			(start 0.67945 0.3048)
			(end 0.120396 0.3048)
			(stroke
				(width 0.1)
				(type default)
			)
			(layer "F.Fab")
		)
		(pad "1" smd circle
			(at -0.40005 0)
			(size 0 0)
			(layers "F.Cu" "F.Mask" "F.Paste")
			(net "RST_SMB_SSD7_ISO_N")
		)
		(pad "2" smd circle
			(at 0.40005 0)
			(size 0 0)
			(layers "F.Cu" "F.Mask" "F.Paste")
			(net "P3V3_SSD7")
		)
	)
	(footprint ""
		(layer "F.Cu")
		(at 102.626922 -245.339616 -90)
		(property "Reference" "R822"
			(at 0 0 270)
			(layer "F.SilkS")
			(hide yes)
			(effects
				(font
					(size 1.27 1.27)
				)
			)
		)
		(property "Value" ""
			(at 0 0 270)
			(layer "F.Fab")
			(effects
				(font
					(size 1.27 1.27)
				)
			)
		)
		(duplicate_pad_numbers_are_jumpers no)
		(fp_line
			(start -0.7874 0.4064)
			(end -0.7874 -0.4064)
			(stroke
				(width 0.1524)
				(type default)
			)
			(layer "F.SilkS")
		)
		(fp_line
			(start 0.7874 0.4064)
			(end -0.7874 0.4064)
			(stroke
				(width 0.1524)
				(type default)
			)
			(layer "F.SilkS")
		)
		(fp_line
			(start -0.7874 -0.4064)
			(end 0.7874 -0.4064)
			(stroke
				(width 0.1524)
				(type default)
			)
			(layer "F.SilkS")
		)
		(fp_line
			(start 0.7874 -0.4064)
			(end 0.7874 0.4064)
			(stroke
				(width 0.1524)
				(type default)
			)
			(layer "F.SilkS")
		)
		(fp_line
			(start -0.67945 0.3048)
			(end -0.67945 -0.305054)
			(stroke
				(width 0.1)
				(type default)
			)
			(layer "F.Fab")
		)
		(fp_line
			(start -0.12065 0.3048)
			(end -0.67945 0.3048)
			(stroke
				(width 0.1)
				(type default)
			)
			(layer "F.Fab")
		)
		(fp_line
			(start 0.120396 0.3048)
			(end 0.120396 0.2794)
			(stroke
				(width 0.1)
				(type default)
			)
			(layer "F.Fab")
		)
		(fp_line
			(start 0.67945 0.3048)
			(end 0.120396 0.3048)
			(stroke
				(width 0.1)
				(type default)
			)
			(layer "F.Fab")
		)
		(fp_line
			(start -0.12065 0.2794)
			(end -0.12065 0.3048)
			(stroke
				(width 0.1)
				(type default)
			)
			(layer "F.Fab")
		)
		(fp_line
			(start 0.120396 0.2794)
			(end -0.12065 0.2794)
			(stroke
				(width 0.1)
				(type default)
			)
			(layer "F.Fab")
		)
		(fp_line
			(start -0.12065 -0.2794)
			(end 0.12065 -0.2794)
			(stroke
				(width 0.1)
				(type default)
			)
			(layer "F.Fab")
		)
		(fp_line
			(start 0.12065 -0.2794)
			(end 0.12065 -0.3048)
			(stroke
				(width 0.1)
				(type default)
			)
			(layer "F.Fab")
		)
		(fp_line
			(start 0.12065 -0.3048)
			(end 0.67945 -0.3048)
			(stroke
				(width 0.1)
				(type default)
			)
			(layer "F.Fab")
		)
		(fp_line
			(start 0.67945 -0.3048)
			(end 0.67945 0.3048)
			(stroke
				(width 0.1)
				(type default)
			)
			(layer "F.Fab")
		)
		(fp_line
			(start -0.67945 -0.305054)
			(end -0.12065 -0.305054)
			(stroke
				(width 0.1)
				(type default)
			)
			(layer "F.Fab")
		)
		(fp_line
			(start -0.12065 -0.305054)
			(end -0.12065 -0.2794)
			(stroke
				(width 0.1)
				(type default)
			)
			(layer "F.Fab")
		)
		(pad "1" smd circle
			(at -0.40005 0 270)
			(size 0 0)
			(layers "F.Cu" "F.Mask" "F.Paste")
			(net "P1V8_PEX")
		)
		(pad "2" smd circle
			(at 0.40005 0 270)
			(size 0 0)
			(layers "F.Cu" "F.Mask" "F.Paste")
			(net "P12V_PEX_P1V8_VIN_N")
		)
	)
	(footprint ""
		(layer "F.Cu")
		(at 255.045972 -46.4439 180)
		(property "Reference" "U71"
			(at -0.122428 -2.45237 0)
			(unlocked yes)
			(layer "F.SilkS")
			(effects
				(font
					(size 0.7874 0.5842)
					(thickness 0.1524)
				)
			)
		)
		(property "Value" ""
			(at 0 0 180)
			(layer "F.Fab")
			(effects
				(font
					(size 1.27 1.27)
				)
			)
		)
		(duplicate_pad_numbers_are_jumpers no)
		(fp_line
			(start 1.500124 1.500124)
			(end 1.004062 1.500124)
			(stroke
				(width 0.1524)
				(type default)
			)
			(layer "F.SilkS")
		)
		(fp_line
			(start 1.500124 1.004062)
			(end 1.500124 1.500124)
			(stroke
				(width 0.1524)
				(type default)
			)
			(layer "F.SilkS")
		)
		(fp_line
			(start 1.500124 -1.500124)
			(end 1.500124 -1.004062)
			(stroke
				(width 0.1524)
				(type default)
			)
			(layer "F.SilkS")
		)
		(fp_line
			(start 1.004062 -1.500124)
			(end 1.500124 -1.500124)
			(stroke
				(width 0.1524)
				(type default)
			)
			(layer "F.SilkS")
		)
		(fp_line
			(start -1.004062 1.500124)
			(end -1.500124 1.500124)
			(stroke
				(width 0.1524)
				(type default)
			)
			(layer "F.SilkS")
		)
		(fp_line
			(start -1.500124 1.500124)
			(end -1.500124 1.004062)
			(stroke
				(width 0.1524)
				(type default)
			)
			(layer "F.SilkS")
		)
		(fp_line
			(start -1.500124 -1.004062)
			(end -1.500124 -1.500124)
			(stroke
				(width 0.1524)
				(type default)
			)
			(layer "F.SilkS")
		)
		(fp_line
			(start -1.500124 -1.500124)
			(end -1.004062 -1.500124)
			(stroke
				(width 0.1524)
				(type default)
			)
			(layer "F.SilkS")
		)
		(fp_poly
			(pts
				(xy -1.97104 -2.39649) (xy -2.689352 -1.677924) (xy -1.61163 -1.318768)
			)
			(stroke
				(width 0)
				(type default)
			)
			(fill yes)
			(layer "F.SilkS")
		)
		(fp_line
			(start 1.500124 1.500124)
			(end -1.500124 1.500124)
			(stroke
				(width 0.1)
				(type default)
			)
			(layer "F.Fab")
		)
		(fp_line
			(start 1.500124 -1.500124)
			(end 1.500124 1.500124)
			(stroke
				(width 0.1)
				(type default)
			)
			(layer "F.Fab")
		)
		(fp_line
			(start -1.500124 1.500124)
			(end -1.500124 -1.500124)
			(stroke
				(width 0.1)
				(type default)
			)
			(layer "F.Fab")
		)
		(fp_line
			(start -1.500124 -1.500124)
			(end 1.500124 -1.500124)
			(stroke
				(width 0.1)
				(type default)
			)
			(layer "F.Fab")
		)
		(fp_poly
			(pts
				(xy -2.847848 -1.258062) (xy -2.847848 -0.242062) (xy -1.831848 -0.750062)
			)
			(stroke
				(width 0)
				(type default)
			)
			(fill yes)
			(layer "F.Fab")
		)
		(pad "1" smd rect
			(at -1.400048 -0.750062 90)
			(size 0.2286 0.6096)
			(layers "F.Cu" "F.Mask" "F.Paste")
			(net "SSD8_ADC_A1")
		)
		(pad "2" smd rect
			(at -1.400048 -0.249936 90)
			(size 0.2286 0.6096)
			(layers "F.Cu" "F.Mask" "F.Paste")
			(net "SSD8_ADC_A0")
		)
		(pad "3" smd rect
			(at -1.400048 0.249936 90)
			(size 0.2286 0.6096)
			(layers "F.Cu" "F.Mask" "F.Paste")
			(net "SSD8_ADC_ALERT_N")
		)
		(pad "4" smd rect
			(at -1.400048 0.750062 90)
			(size 0.2286 0.6096)
			(layers "F.Cu" "F.Mask" "F.Paste")
			(net "SMB_SSD8_ADC_SDA")
		)
		(pad "5" smd rect
			(at -0.750062 1.400048 180)
			(size 0.2286 0.6096)
			(layers "F.Cu" "F.Mask" "F.Paste")
			(net "SMB_SSD8_ADC_SCL")
		)
		(pad "6" smd rect
			(at -0.249936 1.400048 180)
			(size 0.2286 0.6096)
			(layers "F.Cu" "F.Mask" "F.Paste")
			(net "Net_8714")
		)
		(pad "7" smd rect
			(at 0.249936 1.400048 180)
			(size 0.2286 0.6096)
			(layers "F.Cu" "F.Mask" "F.Paste")
			(net "Net_8713")
		)
		(pad "8" smd rect
			(at 0.750062 1.400048 180)
			(size 0.2286 0.6096)
			(layers "F.Cu" "F.Mask" "F.Paste")
			(net "Net_8712")
		)
		(pad "9" smd rect
			(at 1.400048 0.750062 90)
			(size 0.2286 0.6096)
			(layers "F.Cu" "F.Mask" "F.Paste")
			(net "P3V3_AUX")
		)
		(pad "10" smd rect
			(at 1.400048 0.249936 90)
			(size 0.2286 0.6096)
			(layers "F.Cu" "F.Mask" "F.Paste")
			(net "GND")
		)
		(pad "11" smd rect
			(at 1.400048 -0.249936 90)
			(size 0.2286 0.6096)
			(layers "F.Cu" "F.Mask" "F.Paste")
			(net "P12V_SSD8_R")
		)
		(pad "12" smd rect
			(at 1.400048 -0.750062 90)
			(size 0.2286 0.6096)
			(layers "F.Cu" "F.Mask" "F.Paste")
			(net "P12V_SSD8_VIN_N")
		)
		(pad "13" smd rect
			(at 0.750062 -1.400048 180)
			(size 0.2286 0.6096)
			(layers "F.Cu" "F.Mask" "F.Paste")
			(net "P12V_SSD8_VIN_P")
		)
		(pad "14" smd rect
			(at 0.249936 -1.400048 180)
			(size 0.2286 0.6096)
			(layers "F.Cu" "F.Mask" "F.Paste")
			(net "Net_8711")
		)
		(pad "15" smd rect
			(at -0.249936 -1.400048 180)
			(size 0.2286 0.6096)
			(layers "F.Cu" "F.Mask" "F.Paste")
			(net "Net_8710")
		)
		(pad "16" smd rect
			(at -0.750062 -1.400048 180)
			(size 0.2286 0.6096)
			(layers "F.Cu" "F.Mask" "F.Paste")
			(net "Net_8709")
		)
		(pad "TH" smd rect
			(at 0 0 180)
			(size 1.7018 1.7018)
			(layers "F.Cu" "F.Mask" "F.Paste")
			(net "GND")
		)
		(zone
			(layer "F.Cu")
			(hatch none 0.5)
			(connect_pads
				(clearance 0)
			)
			(min_thickness 0.25)
			(keepout
				(tracks not_allowed)
				(vias allowed)
				(pads allowed)
				(copperpour not_allowed)
				(footprints allowed)
			)
			(placement
				(enabled no)
				(sheetname "")
			)
			(fill
				(thermal_gap 0.5)
				(thermal_bridge_width 0.5)
				(island_removal_mode 0)
			)
			(polygon
				(pts
					(xy 256.09042 -46.4185) (xy 256.09042 -45.399452) (xy 254.001524 -45.399452) (xy 254.001524 -47.488348)
					(xy 256.09042 -47.488348) (xy 256.09042 -46.4439) (xy 255.947672 -46.4439) (xy 255.947672 -47.3456)
					(xy 254.144272 -47.3456) (xy 254.144272 -45.5422) (xy 255.947672 -45.5422) (xy 255.947672 -46.4185)
				)
			)
		)
	)
	(footprint ""
		(layer "F.Cu")
		(at 219.623894 -174.99838)
		(property "Reference" "U360"
			(at -0.929894 2.38125 0)
			(unlocked yes)
			(layer "F.SilkS")
			(effects
				(font
					(size 0.7874 0.5842)
					(thickness 0.1524)
				)
				(justify left)
			)
		)
		(property "Value" ""
			(at 0 0 0)
			(layer "F.Fab")
			(effects
				(font
					(size 1.27 1.27)
				)
			)
		)
		(duplicate_pad_numbers_are_jumpers no)
		(fp_line
			(start -2.0574 -1.651)
			(end -0.381 -1.651)
			(stroke
				(width 0.1524)
				(type default)
			)
			(layer "F.SilkS")
		)
		(fp_line
			(start -2.0574 1.651)
			(end -2.0574 -1.651)
			(stroke
				(width 0.1524)
				(type default)
			)
			(layer "F.SilkS")
		)
		(fp_line
			(start -0.381 -1.651)
			(end 0 -1.016)
			(stroke
				(width 0.1524)
				(type default)
			)
			(layer "F.SilkS")
		)
		(fp_line
			(start 0 -1.016)
			(end 0.381 -1.651)
			(stroke
				(width 0.1524)
				(type default)
			)
			(layer "F.SilkS")
		)
		(fp_line
			(start 0.381 -1.651)
			(end 2.0574 -1.651)
			(stroke
				(width 0.1524)
				(type default)
			)
			(layer "F.SilkS")
		)
		(fp_line
			(start 2.0574 -1.651)
			(end 2.0574 1.651)
			(stroke
				(width 0.1524)
				(type default)
			)
			(layer "F.SilkS")
		)
		(fp_line
			(start 2.0574 1.651)
			(end -2.0574 1.651)
			(stroke
				(width 0.1524)
				(type default)
			)
			(layer "F.SilkS")
		)
		(fp_poly
			(pts
				(xy -3.102864 -0.719328) (xy -3.102864 -1.344168) (xy -2.549144 -1.016)
			)
			(stroke
				(width 0)
				(type default)
			)
			(fill yes)
			(layer "F.SilkS")
		)
		(fp_line
			(start -1.599946 -1.199896)
			(end -0.899922 -1.199896)
			(stroke
				(width 0.1)
				(type default)
			)
			(layer "F.Fab")
		)
		(fp_line
			(start -1.599946 1.199896)
			(end -1.599946 -1.199896)
			(stroke
				(width 0.1)
				(type default)
			)
			(layer "F.Fab")
		)
		(fp_line
			(start -0.899922 -1.549908)
			(end 0.899922 -1.549908)
			(stroke
				(width 0.1)
				(type default)
			)
			(layer "F.Fab")
		)
		(fp_line
			(start -0.899922 -1.199896)
			(end -0.899922 -1.549908)
			(stroke
				(width 0.1)
				(type default)
			)
			(layer "F.Fab")
		)
		(fp_line
			(start -0.899922 1.199896)
			(end -1.599946 1.199896)
			(stroke
				(width 0.1)
				(type default)
			)
			(layer "F.Fab")
		)
		(fp_line
			(start -0.899922 1.549908)
			(end -0.899922 1.199896)
			(stroke
				(width 0.1)
				(type default)
			)
			(layer "F.Fab")
		)
		(fp_line
			(start 0.899922 -1.549908)
			(end 0.899922 -1.199896)
			(stroke
				(width 0.1)
				(type default)
			)
			(layer "F.Fab")
		)
		(fp_line
			(start 0.899922 -1.199896)
			(end 1.599946 -1.199896)
			(stroke
				(width 0.1)
				(type default)
			)
			(layer "F.Fab")
		)
		(fp_line
			(start 0.899922 1.199896)
			(end 0.899922 1.549908)
			(stroke
				(width 0.1)
				(type default)
			)
			(layer "F.Fab")
		)
		(fp_line
			(start 0.899922 1.549908)
			(end -0.899922 1.549908)
			(stroke
				(width 0.1)
				(type default)
			)
			(layer "F.Fab")
		)
		(fp_line
			(start 1.599946 -1.199896)
			(end 1.599946 1.199896)
			(stroke
				(width 0.1)
				(type default)
			)
			(layer "F.Fab")
		)
		(fp_line
			(start 1.599946 1.199896)
			(end 0.899922 1.199896)
			(stroke
				(width 0.1)
				(type default)
			)
			(layer "F.Fab")
		)
		(fp_poly
			(pts
				(xy -2.71272 -0.719328) (xy -2.71272 -1.344168) (xy -2.159 -1.016)
			)
			(stroke
				(width 0)
				(type default)
			)
			(fill yes)
			(layer "F.Fab")
		)
		(pad "1" smd rect
			(at -1.225042 -0.94996 270)
			(size 0.5588 1.3462)
			(layers "F.Cu" "F.Mask" "F.Paste")
			(net "RST_MB_BIC_ISO_R_N")
		)
		(pad "2" smd rect
			(at -1.225042 0 270)
			(size 0.5588 1.3462)
			(layers "F.Cu" "F.Mask" "F.Paste")
			(net "RST_BIC_SELF_HW_RST_R_N")
		)
		(pad "3" smd rect
			(at -1.225042 0.94996 270)
			(size 0.5588 1.3462)
			(layers "F.Cu" "F.Mask" "F.Paste")
			(net "GND")
		)
		(pad "4" smd rect
			(at 1.225042 0.94996 270)
			(size 0.5588 1.3462)
			(layers "F.Cu" "F.Mask" "F.Paste")
			(net "RST_FW_BIC_PLTRST_N")
		)
		(pad "5" smd rect
			(at 1.225042 -0.94996 270)
			(size 0.5588 1.3462)
			(layers "F.Cu" "F.Mask" "F.Paste")
			(net "P3V3_AUX")
		)
	)
	(footprint ""
		(layer "F.Cu")
		(at 236.887512 -234.728004 -90)
		(property "Reference" "R6188"
			(at 0 0 270)
			(layer "F.SilkS")
			(hide yes)
			(effects
				(font
					(size 1.27 1.27)
				)
			)
		)
		(property "Value" ""
			(at 0 0 270)
			(layer "F.Fab")
			(effects
				(font
					(size 1.27 1.27)
				)
			)
		)
		(duplicate_pad_numbers_are_jumpers no)
		(fp_line
			(start -0.7874 0.4064)
			(end -0.7874 -0.4064)
			(stroke
				(width 0.1524)
				(type default)
			)
			(layer "F.SilkS")
		)
		(fp_line
			(start 0.7874 0.4064)
			(end -0.7874 0.4064)
			(stroke
				(width 0.1524)
				(type default)
			)
			(layer "F.SilkS")
		)
		(fp_line
			(start -0.7874 -0.4064)
			(end 0.7874 -0.4064)
			(stroke
				(width 0.1524)
				(type default)
			)
			(layer "F.SilkS")
		)
		(fp_line
			(start 0.7874 -0.4064)
			(end 0.7874 0.4064)
			(stroke
				(width 0.1524)
				(type default)
			)
			(layer "F.SilkS")
		)
		(fp_line
			(start -0.67945 0.3048)
			(end -0.67945 -0.305054)
			(stroke
				(width 0.1)
				(type default)
			)
			(layer "F.Fab")
		)
		(fp_line
			(start -0.12065 0.3048)
			(end -0.67945 0.3048)
			(stroke
				(width 0.1)
				(type default)
			)
			(layer "F.Fab")
		)
		(fp_line
			(start 0.120396 0.3048)
			(end 0.120396 0.2794)
			(stroke
				(width 0.1)
				(type default)
			)
			(layer "F.Fab")
		)
		(fp_line
			(start 0.67945 0.3048)
			(end 0.120396 0.3048)
			(stroke
				(width 0.1)
				(type default)
			)
			(layer "F.Fab")
		)
		(fp_line
			(start -0.12065 0.2794)
			(end -0.12065 0.3048)
			(stroke
				(width 0.1)
				(type default)
			)
			(layer "F.Fab")
		)
		(fp_line
			(start 0.120396 0.2794)
			(end -0.12065 0.2794)
			(stroke
				(width 0.1)
				(type default)
			)
			(layer "F.Fab")
		)
		(fp_line
			(start -0.12065 -0.2794)
			(end 0.12065 -0.2794)
			(stroke
				(width 0.1)
				(type default)
			)
			(layer "F.Fab")
		)
		(fp_line
			(start 0.12065 -0.2794)
			(end 0.12065 -0.3048)
			(stroke
				(width 0.1)
				(type default)
			)
			(layer "F.Fab")
		)
		(fp_line
			(start 0.12065 -0.3048)
			(end 0.67945 -0.3048)
			(stroke
				(width 0.1)
				(type default)
			)
			(layer "F.Fab")
		)
		(fp_line
			(start 0.67945 -0.3048)
			(end 0.67945 0.3048)
			(stroke
				(width 0.1)
				(type default)
			)
			(layer "F.Fab")
		)
		(fp_line
			(start -0.67945 -0.305054)
			(end -0.12065 -0.305054)
			(stroke
				(width 0.1)
				(type default)
			)
			(layer "F.Fab")
		)
		(fp_line
			(start -0.12065 -0.305054)
			(end -0.12065 -0.2794)
			(stroke
				(width 0.1)
				(type default)
			)
			(layer "F.Fab")
		)
		(pad "1" smd circle
			(at -0.40005 0 270)
			(size 0 0)
			(layers "F.Cu" "F.Mask" "F.Paste")
			(net "GND")
		)
		(pad "2" smd circle
			(at 0.40005 0 270)
			(size 0 0)
			(layers "F.Cu" "F.Mask" "F.Paste")
			(net "SSD6_PWRDIS_BIC_R")
		)
	)
	(footprint ""
		(layer "F.Cu")
		(at 265.487658 -301.220632)
		(property "Reference" "C3372"
			(at 0 0 0)
			(layer "F.SilkS")
			(hide yes)
			(effects
				(font
					(size 1.27 1.27)
				)
			)
		)
		(property "Value" ""
			(at 0 0 0)
			(layer "F.Fab")
			(effects
				(font
					(size 1.27 1.27)
				)
			)
		)
		(duplicate_pad_numbers_are_jumpers no)
		(fp_line
			(start -1.2954 -0.5842)
			(end 1.2954 -0.5842)
			(stroke
				(width 0.1524)
				(type default)
			)
			(layer "F.SilkS")
		)
		(fp_line
			(start -1.2954 0.5842)
			(end -1.2954 -0.5842)
			(stroke
				(width 0.1524)
				(type default)
			)
			(layer "F.SilkS")
		)
		(fp_line
			(start 1.2954 -0.5842)
			(end 1.2954 0.5842)
			(stroke
				(width 0.1524)
				(type default)
			)
			(layer "F.SilkS")
		)
		(fp_line
			(start 1.2954 0.5842)
			(end -1.2954 0.5842)
			(stroke
				(width 0.1524)
				(type default)
			)
			(layer "F.SilkS")
		)
		(fp_line
			(start -1.1938 -0.4064)
			(end -0.8636 -0.4064)
			(stroke
				(width 0.1)
				(type default)
			)
			(layer "F.Fab")
		)
		(fp_line
			(start -1.1938 0.4064)
			(end -1.1938 -0.4064)
			(stroke
				(width 0.1)
				(type default)
			)
			(layer "F.Fab")
		)
		(fp_line
			(start -0.8636 -0.4572)
			(end 0.8636 -0.4572)
			(stroke
				(width 0.1)
				(type default)
			)
			(layer "F.Fab")
		)
		(fp_line
			(start -0.8636 -0.4064)
			(end -0.8636 -0.4572)
			(stroke
				(width 0.1)
				(type default)
			)
			(layer "F.Fab")
		)
		(fp_line
			(start -0.8636 0.4064)
			(end -1.1938 0.4064)
			(stroke
				(width 0.1)
				(type default)
			)
			(layer "F.Fab")
		)
		(fp_line
			(start -0.8636 0.4572)
			(end -0.8636 0.4064)
			(stroke
				(width 0.1)
				(type default)
			)
			(layer "F.Fab")
		)
		(fp_line
			(start 0.8636 -0.4572)
			(end 0.8636 -0.4064)
			(stroke
				(width 0.1)
				(type default)
			)
			(layer "F.Fab")
		)
		(fp_line
			(start 0.8636 -0.4064)
			(end 1.1938 -0.4064)
			(stroke
				(width 0.1)
				(type default)
			)
			(layer "F.Fab")
		)
		(fp_line
			(start 0.8636 0.4064)
			(end 0.8636 0.4572)
			(stroke
				(width 0.1)
				(type default)
			)
			(layer "F.Fab")
		)
		(fp_line
			(start 0.8636 0.4572)
			(end -0.8636 0.4572)
			(stroke
				(width 0.1)
				(type default)
			)
			(layer "F.Fab")
		)
		(fp_line
			(start 1.1938 -0.4064)
			(end 1.1938 0.4064)
			(stroke
				(width 0.1)
				(type default)
			)
			(layer "F.Fab")
		)
		(fp_line
			(start 1.1938 0.4064)
			(end 0.8636 0.4064)
			(stroke
				(width 0.1)
				(type default)
			)
			(layer "F.Fab")
		)
		(pad "1" smd rect
			(at -0.7366 0 270)
			(size 0.7112 0.8128)
			(layers "F.Cu" "F.Mask" "F.Paste")
			(net "PCEPLL1_VDDA18_PEX2")
		)
		(pad "2" smd rect
			(at 0.7366 0 270)
			(size 0.7112 0.8128)
			(layers "F.Cu" "F.Mask" "F.Paste")
			(net "GND")
		)
	)
	(footprint ""
		(layer "F.Cu")
		(at 7.668768 -156.288994 -90)
		(property "Reference" "PR6866"
			(at 0 0 270)
			(layer "F.SilkS")
			(hide yes)
			(effects
				(font
					(size 1.27 1.27)
				)
			)
		)
		(property "Value" ""
			(at 0 0 270)
			(layer "F.Fab")
			(effects
				(font
					(size 1.27 1.27)
				)
			)
		)
		(duplicate_pad_numbers_are_jumpers no)
		(fp_line
			(start -0.7874 0.4064)
			(end -0.7874 -0.4064)
			(stroke
				(width 0.1524)
				(type default)
			)
			(layer "F.SilkS")
		)
		(fp_line
			(start 0.7874 0.4064)
			(end -0.7874 0.4064)
			(stroke
				(width 0.1524)
				(type default)
			)
			(layer "F.SilkS")
		)
		(fp_line
			(start -0.7874 -0.4064)
			(end 0.7874 -0.4064)
			(stroke
				(width 0.1524)
				(type default)
			)
			(layer "F.SilkS")
		)
		(fp_line
			(start 0.7874 -0.4064)
			(end 0.7874 0.4064)
			(stroke
				(width 0.1524)
				(type default)
			)
			(layer "F.SilkS")
		)
		(fp_line
			(start -0.67945 0.3048)
			(end -0.67945 -0.305054)
			(stroke
				(width 0.1)
				(type default)
			)
			(layer "F.Fab")
		)
		(fp_line
			(start -0.12065 0.3048)
			(end -0.67945 0.3048)
			(stroke
				(width 0.1)
				(type default)
			)
			(layer "F.Fab")
		)
		(fp_line
			(start 0.120396 0.3048)
			(end 0.120396 0.2794)
			(stroke
				(width 0.1)
				(type default)
			)
			(layer "F.Fab")
		)
		(fp_line
			(start 0.67945 0.3048)
			(end 0.120396 0.3048)
			(stroke
				(width 0.1)
				(type default)
			)
			(layer "F.Fab")
		)
		(fp_line
			(start -0.12065 0.2794)
			(end -0.12065 0.3048)
			(stroke
				(width 0.1)
				(type default)
			)
			(layer "F.Fab")
		)
		(fp_line
			(start 0.120396 0.2794)
			(end -0.12065 0.2794)
			(stroke
				(width 0.1)
				(type default)
			)
			(layer "F.Fab")
		)
		(fp_line
			(start -0.12065 -0.2794)
			(end 0.12065 -0.2794)
			(stroke
				(width 0.1)
				(type default)
			)
			(layer "F.Fab")
		)
		(fp_line
			(start 0.12065 -0.2794)
			(end 0.12065 -0.3048)
			(stroke
				(width 0.1)
				(type default)
			)
			(layer "F.Fab")
		)
		(fp_line
			(start 0.12065 -0.3048)
			(end 0.67945 -0.3048)
			(stroke
				(width 0.1)
				(type default)
			)
			(layer "F.Fab")
		)
		(fp_line
			(start 0.67945 -0.3048)
			(end 0.67945 0.3048)
			(stroke
				(width 0.1)
				(type default)
			)
			(layer "F.Fab")
		)
		(fp_line
			(start -0.67945 -0.305054)
			(end -0.12065 -0.305054)
			(stroke
				(width 0.1)
				(type default)
			)
			(layer "F.Fab")
		)
		(fp_line
			(start -0.12065 -0.305054)
			(end -0.12065 -0.2794)
			(stroke
				(width 0.1)
				(type default)
			)
			(layer "F.Fab")
		)
		(pad "1" smd circle
			(at -0.40005 0 270)
			(size 0 0)
			(layers "F.Cu" "F.Mask" "F.Paste")
			(net "P12V_NIC0_CO_OV_FB")
		)
		(pad "2" smd circle
			(at 0.40005 0 270)
			(size 0 0)
			(layers "F.Cu" "F.Mask" "F.Paste")
			(net "P12V_AUX")
		)
	)
	(footprint ""
		(layer "F.Cu")
		(at 12.807696 -302.8315)
		(property "Reference" "PC211"
			(at 0 0 0)
			(layer "F.SilkS")
			(hide yes)
			(effects
				(font
					(size 1.27 1.27)
				)
			)
		)
		(property "Value" ""
			(at 0 0 0)
			(layer "F.Fab")
			(effects
				(font
					(size 1.27 1.27)
				)
			)
		)
		(duplicate_pad_numbers_are_jumpers no)
		(fp_line
			(start -0.7874 -0.4064)
			(end 0.7874 -0.4064)
			(stroke
				(width 0.1524)
				(type default)
			)
			(layer "F.SilkS")
		)
		(fp_line
			(start -0.7874 0.4064)
			(end -0.7874 -0.4064)
			(stroke
				(width 0.1524)
				(type default)
			)
			(layer "F.SilkS")
		)
		(fp_line
			(start 0.7874 -0.4064)
			(end 0.7874 0.4064)
			(stroke
				(width 0.1524)
				(type default)
			)
			(layer "F.SilkS")
		)
		(fp_line
			(start 0.7874 0.4064)
			(end -0.7874 0.4064)
			(stroke
				(width 0.1524)
				(type default)
			)
			(layer "F.SilkS")
		)
		(fp_line
			(start -0.67945 -0.305054)
			(end -0.12065 -0.305054)
			(stroke
				(width 0.1)
				(type default)
			)
			(layer "F.Fab")
		)
		(fp_line
			(start -0.67945 0.3048)
			(end -0.67945 -0.305054)
			(stroke
				(width 0.1)
				(type default)
			)
			(layer "F.Fab")
		)
		(fp_line
			(start -0.12065 -0.305054)
			(end -0.12065 -0.2794)
			(stroke
				(width 0.1)
				(type default)
			)
			(layer "F.Fab")
		)
		(fp_line
			(start -0.12065 -0.2794)
			(end 0.12065 -0.2794)
			(stroke
				(width 0.1)
				(type default)
			)
			(layer "F.Fab")
		)
		(fp_line
			(start -0.12065 0.2794)
			(end -0.12065 0.3048)
			(stroke
				(width 0.1)
				(type default)
			)
			(layer "F.Fab")
		)
		(fp_line
			(start -0.12065 0.3048)
			(end -0.67945 0.3048)
			(stroke
				(width 0.1)
				(type default)
			)
			(layer "F.Fab")
		)
		(fp_line
			(start 0.120396 0.2794)
			(end -0.12065 0.2794)
			(stroke
				(width 0.1)
				(type default)
			)
			(layer "F.Fab")
		)
		(fp_line
			(start 0.120396 0.3048)
			(end 0.120396 0.2794)
			(stroke
				(width 0.1)
				(type default)
			)
			(layer "F.Fab")
		)
		(fp_line
			(start 0.12065 -0.3048)
			(end 0.67945 -0.3048)
			(stroke
				(width 0.1)
				(type default)
			)
			(layer "F.Fab")
		)
		(fp_line
			(start 0.12065 -0.2794)
			(end 0.12065 -0.3048)
			(stroke
				(width 0.1)
				(type default)
			)
			(layer "F.Fab")
		)
		(fp_line
			(start 0.67945 -0.3048)
			(end 0.67945 0.3048)
			(stroke
				(width 0.1)
				(type default)
			)
			(layer "F.Fab")
		)
		(fp_line
			(start 0.67945 0.3048)
			(end 0.120396 0.3048)
			(stroke
				(width 0.1)
				(type default)
			)
			(layer "F.Fab")
		)
		(pad "1" smd circle
			(at -0.40005 0)
			(size 0 0)
			(layers "F.Cu" "F.Mask" "F.Paste")
			(net "SW_P1V25_PEX0_BT")
		)
		(pad "2" smd circle
			(at 0.40005 0)
			(size 0 0)
			(layers "F.Cu" "F.Mask" "F.Paste")
			(net "SW_P1V25_PEX0_PH")
		)
	)
	(footprint ""
		(layer "F.Cu")
		(at 449.967858 -19.453098)
		(property "Reference" "R1738"
			(at 0 0 0)
			(layer "F.SilkS")
			(hide yes)
			(effects
				(font
					(size 1.27 1.27)
				)
			)
		)
		(property "Value" ""
			(at 0 0 0)
			(layer "F.Fab")
			(effects
				(font
					(size 1.27 1.27)
				)
			)
		)
		(duplicate_pad_numbers_are_jumpers no)
		(fp_line
			(start -0.7874 -0.4064)
			(end 0.7874 -0.4064)
			(stroke
				(width 0.1524)
				(type default)
			)
			(layer "F.SilkS")
		)
		(fp_line
			(start -0.7874 0.4064)
			(end -0.7874 -0.4064)
			(stroke
				(width 0.1524)
				(type default)
			)
			(layer "F.SilkS")
		)
		(fp_line
			(start 0.7874 -0.4064)
			(end 0.7874 0.4064)
			(stroke
				(width 0.1524)
				(type default)
			)
			(layer "F.SilkS")
		)
		(fp_line
			(start 0.7874 0.4064)
			(end -0.7874 0.4064)
			(stroke
				(width 0.1524)
				(type default)
			)
			(layer "F.SilkS")
		)
		(fp_line
			(start -0.67945 -0.305054)
			(end -0.12065 -0.305054)
			(stroke
				(width 0.1)
				(type default)
			)
			(layer "F.Fab")
		)
		(fp_line
			(start -0.67945 0.3048)
			(end -0.67945 -0.305054)
			(stroke
				(width 0.1)
				(type default)
			)
			(layer "F.Fab")
		)
		(fp_line
			(start -0.12065 -0.305054)
			(end -0.12065 -0.2794)
			(stroke
				(width 0.1)
				(type default)
			)
			(layer "F.Fab")
		)
		(fp_line
			(start -0.12065 -0.2794)
			(end 0.12065 -0.2794)
			(stroke
				(width 0.1)
				(type default)
			)
			(layer "F.Fab")
		)
		(fp_line
			(start -0.12065 0.2794)
			(end -0.12065 0.3048)
			(stroke
				(width 0.1)
				(type default)
			)
			(layer "F.Fab")
		)
		(fp_line
			(start -0.12065 0.3048)
			(end -0.67945 0.3048)
			(stroke
				(width 0.1)
				(type default)
			)
			(layer "F.Fab")
		)
		(fp_line
			(start 0.120396 0.2794)
			(end -0.12065 0.2794)
			(stroke
				(width 0.1)
				(type default)
			)
			(layer "F.Fab")
		)
		(fp_line
			(start 0.120396 0.3048)
			(end 0.120396 0.2794)
			(stroke
				(width 0.1)
				(type default)
			)
			(layer "F.Fab")
		)
		(fp_line
			(start 0.12065 -0.3048)
			(end 0.67945 -0.3048)
			(stroke
				(width 0.1)
				(type default)
			)
			(layer "F.Fab")
		)
		(fp_line
			(start 0.12065 -0.2794)
			(end 0.12065 -0.3048)
			(stroke
				(width 0.1)
				(type default)
			)
			(layer "F.Fab")
		)
		(fp_line
			(start 0.67945 -0.3048)
			(end 0.67945 0.3048)
			(stroke
				(width 0.1)
				(type default)
			)
			(layer "F.Fab")
		)
		(fp_line
			(start 0.67945 0.3048)
			(end 0.120396 0.3048)
			(stroke
				(width 0.1)
				(type default)
			)
			(layer "F.Fab")
		)
		(pad "1" smd circle
			(at -0.40005 0)
			(size 0 0)
			(layers "F.Cu" "F.Mask" "F.Paste")
			(net "SMB_ISO_SSD15_R_SDA")
		)
		(pad "2" smd circle
			(at 0.40005 0)
			(size 0 0)
			(layers "F.Cu" "F.Mask" "F.Paste")
			(net "SMB_ISO_SSD15_SDA")
		)
	)
	(footprint ""
		(layer "F.Cu")
		(at 214.310976 -368.035586 180)
		(property "Reference" "PR43"
			(at 0 0 180)
			(layer "F.SilkS")
			(hide yes)
			(effects
				(font
					(size 1.27 1.27)
				)
			)
		)
		(property "Value" ""
			(at 0 0 180)
			(layer "F.Fab")
			(effects
				(font
					(size 1.27 1.27)
				)
			)
		)
		(duplicate_pad_numbers_are_jumpers no)
		(fp_line
			(start 0.7874 0.4064)
			(end -0.7874 0.4064)
			(stroke
				(width 0.1524)
				(type default)
			)
			(layer "F.SilkS")
		)
		(fp_line
			(start 0.7874 -0.4064)
			(end 0.7874 0.4064)
			(stroke
				(width 0.1524)
				(type default)
			)
			(layer "F.SilkS")
		)
		(fp_line
			(start -0.7874 0.4064)
			(end -0.7874 -0.4064)
			(stroke
				(width 0.1524)
				(type default)
			)
			(layer "F.SilkS")
		)
		(fp_line
			(start -0.7874 -0.4064)
			(end 0.7874 -0.4064)
			(stroke
				(width 0.1524)
				(type default)
			)
			(layer "F.SilkS")
		)
		(fp_line
			(start 0.67945 0.3048)
			(end 0.120396 0.3048)
			(stroke
				(width 0.1)
				(type default)
			)
			(layer "F.Fab")
		)
		(fp_line
			(start 0.67945 -0.3048)
			(end 0.67945 0.3048)
			(stroke
				(width 0.1)
				(type default)
			)
			(layer "F.Fab")
		)
		(fp_line
			(start 0.12065 -0.2794)
			(end 0.12065 -0.3048)
			(stroke
				(width 0.1)
				(type default)
			)
			(layer "F.Fab")
		)
		(fp_line
			(start 0.12065 -0.3048)
			(end 0.67945 -0.3048)
			(stroke
				(width 0.1)
				(type default)
			)
			(layer "F.Fab")
		)
		(fp_line
			(start 0.120396 0.3048)
			(end 0.120396 0.2794)
			(stroke
				(width 0.1)
				(type default)
			)
			(layer "F.Fab")
		)
		(fp_line
			(start 0.120396 0.2794)
			(end -0.12065 0.2794)
			(stroke
				(width 0.1)
				(type default)
			)
			(layer "F.Fab")
		)
		(fp_line
			(start -0.12065 0.3048)
			(end -0.67945 0.3048)
			(stroke
				(width 0.1)
				(type default)
			)
			(layer "F.Fab")
		)
		(fp_line
			(start -0.12065 0.2794)
			(end -0.12065 0.3048)
			(stroke
				(width 0.1)
				(type default)
			)
			(layer "F.Fab")
		)
		(fp_line
			(start -0.12065 -0.2794)
			(end 0.12065 -0.2794)
			(stroke
				(width 0.1)
				(type default)
			)
			(layer "F.Fab")
		)
		(fp_line
			(start -0.12065 -0.305054)
			(end -0.12065 -0.2794)
			(stroke
				(width 0.1)
				(type default)
			)
			(layer "F.Fab")
		)
		(fp_line
			(start -0.67945 0.3048)
			(end -0.67945 -0.305054)
			(stroke
				(width 0.1)
				(type default)
			)
			(layer "F.Fab")
		)
		(fp_line
			(start -0.67945 -0.305054)
			(end -0.12065 -0.305054)
			(stroke
				(width 0.1)
				(type default)
			)
			(layer "F.Fab")
		)
		(pad "1" smd circle
			(at -0.40005 0 180)
			(size 0 0)
			(layers "F.Cu" "F.Mask" "F.Paste")
			(net "HSC_IMON")
		)
		(pad "2" smd circle
			(at 0.40005 0 180)
			(size 0 0)
			(layers "F.Cu" "F.Mask" "F.Paste")
			(net "AGND_HSC")
		)
	)
	(footprint ""
		(layer "F.Cu")
		(at 19.820128 -225.49993 180)
		(property "Reference" "JPEX0"
			(at -4.619498 -8.423148 0)
			(unlocked yes)
			(layer "F.SilkS")
			(effects
				(font
					(size 0.7874 0.5842)
					(thickness 0.1524)
				)
				(justify left)
			)
		)
		(property "Value" ""
			(at 0 0 180)
			(layer "F.Fab")
			(effects
				(font
					(size 1.27 1.27)
				)
			)
		)
		(duplicate_pad_numbers_are_jumpers no)
		(fp_line
			(start 12.46505 7.649972)
			(end -12.46505 7.649972)
			(stroke
				(width 0.1524)
				(type default)
			)
			(layer "F.SilkS")
		)
		(fp_line
			(start 12.46505 -7.649972)
			(end 12.46505 7.649972)
			(stroke
				(width 0.1524)
				(type default)
			)
			(layer "F.SilkS")
		)
		(fp_line
			(start 6.945122 7.649972)
			(end -6.945122 7.649972)
			(stroke
				(width 0.1524)
				(type default)
			)
			(layer "F.SilkS")
		)
		(fp_line
			(start 6.945122 -7.649972)
			(end 6.945122 7.649972)
			(stroke
				(width 0.1524)
				(type default)
			)
			(layer "F.SilkS")
		)
		(fp_line
			(start 6.945122 -7.649972)
			(end 0 -7.649972)
			(stroke
				(width 0.1524)
				(type default)
			)
			(layer "F.SilkS")
		)
		(fp_line
			(start 0 -7.649972)
			(end 12.46505 -7.649972)
			(stroke
				(width 0.1524)
				(type default)
			)
			(layer "F.SilkS")
		)
		(fp_line
			(start -6.945122 -7.649972)
			(end 0 -7.649972)
			(stroke
				(width 0.1524)
				(type default)
			)
			(layer "F.SilkS")
		)
		(fp_line
			(start -6.945122 -7.649972)
			(end -6.945122 7.649972)
			(stroke
				(width 0.1524)
				(type default)
			)
			(layer "F.SilkS")
		)
		(fp_line
			(start -12.46505 7.649972)
			(end -12.46505 -7.649972)
			(stroke
				(width 0.1524)
				(type default)
			)
			(layer "F.SilkS")
		)
		(fp_line
			(start -12.46505 -7.649972)
			(end 0 -7.649972)
			(stroke
				(width 0.1524)
				(type default)
			)
			(layer "F.SilkS")
		)
		(fp_poly
			(pts
				(xy -7.112 -4.445) (xy -8.128 -4.953) (xy -8.128 -3.937)
			)
			(stroke
				(width 0)
				(type default)
			)
			(fill yes)
			(layer "F.SilkS")
		)
		(fp_line
			(start 6.945122 7.649972)
			(end -6.945122 7.649972)
			(stroke
				(width 0.1)
				(type default)
			)
			(layer "F.Fab")
		)
		(fp_line
			(start 6.945122 -7.649972)
			(end 6.945122 7.649972)
			(stroke
				(width 0.1)
				(type default)
			)
			(layer "F.Fab")
		)
		(fp_line
			(start -6.945122 7.649972)
			(end -6.945122 -7.649972)
			(stroke
				(width 0.1)
				(type default)
			)
			(layer "F.Fab")
		)
		(fp_line
			(start -6.945122 -7.649972)
			(end 6.945122 -7.649972)
			(stroke
				(width 0.1)
				(type default)
			)
			(layer "F.Fab")
		)
		(fp_poly
			(pts
				(xy -7.112 -4.445) (xy -8.128 -4.953) (xy -8.128 -3.937)
			)
			(stroke
				(width 0)
				(type default)
			)
			(fill yes)
			(layer "F.Fab")
		)
		(fp_text user "9"
			(at 7.51713 4.1656 90)
			(unlocked yes)
			(layer "F.SilkS")
			(effects
				(font
					(size 0.7874 0.5842)
					(thickness 0.1524)
				)
				(justify left)
			)
		)
		(fp_text user "16"
			(at 7.49173 -5.2324 90)
			(unlocked yes)
			(layer "F.SilkS")
			(effects
				(font
					(size 0.7874 0.5842)
					(thickness 0.1524)
				)
				(justify left)
			)
		)
		(fp_text user "8"
			(at -7.77367 4.2164 90)
			(unlocked yes)
			(layer "F.SilkS")
			(effects
				(font
					(size 0.7874 0.5842)
					(thickness 0.1524)
				)
				(justify left)
			)
		)
		(fp_text user "9"
			(at 7.51713 4.1656 90)
			(unlocked yes)
			(layer "F.Fab")
			(effects
				(font
					(size 0.7874 0.5842)
					(thickness 0.1524)
				)
				(justify left)
			)
		)
		(fp_text user "16"
			(at 7.49173 -5.2324 90)
			(unlocked yes)
			(layer "F.Fab")
			(effects
				(font
					(size 0.7874 0.5842)
					(thickness 0.1524)
				)
				(justify left)
			)
		)
		(fp_text user "8"
			(at -7.77367 4.2164 90)
			(unlocked yes)
			(layer "F.Fab")
			(effects
				(font
					(size 0.7874 0.5842)
					(thickness 0.1524)
				)
				(justify left)
			)
		)
		(pad "1" smd rect
			(at -4.800092 -4.445 90)
			(size 0.508 1.524)
			(layers "F.Cu" "F.Mask" "F.Paste")
			(net "SPI_PEX0_SDIO3_R1")
		)
		(pad "2" smd rect
			(at -4.800092 -3.175 90)
			(size 0.508 1.524)
			(layers "F.Cu" "F.Mask" "F.Paste")
			(net "P1V8_PEX")
		)
		(pad "3" smd rect
			(at -4.800092 -1.905 90)
			(size 0.508 1.524)
			(layers "F.Cu" "F.Mask" "F.Paste")
			(net "SPI_PEX0_RST_R_N")
		)
		(pad "4" smd rect
			(at -4.800092 -0.635 90)
			(size 0.508 1.524)
			(layers "F.Cu" "F.Mask" "F.Paste")
			(net "Net_2684")
		)
		(pad "5" smd rect
			(at -4.800092 0.635 90)
			(size 0.508 1.524)
			(layers "F.Cu" "F.Mask" "F.Paste")
			(net "Net_2683")
		)
		(pad "6" smd rect
			(at -4.800092 1.905 90)
			(size 0.508 1.524)
			(layers "F.Cu" "F.Mask" "F.Paste")
			(net "Net_2682")
		)
		(pad "7" smd rect
			(at -4.800092 3.175 90)
			(size 0.508 1.524)
			(layers "F.Cu" "F.Mask" "F.Paste")
			(net "SPI_PEX0_CS_MUX_R_N")
		)
		(pad "8" smd rect
			(at -4.800092 4.445 90)
			(size 0.508 1.524)
			(layers "F.Cu" "F.Mask" "F.Paste")
			(net "SPI_PEX0_SDIO1_MUX_R")
		)
		(pad "9" smd rect
			(at 4.800092 4.445 90)
			(size 0.508 1.524)
			(layers "F.Cu" "F.Mask" "F.Paste")
			(net "SPI_PEX0_SDIO2_R1")
		)
		(pad "10" smd rect
			(at 4.800092 3.175 90)
			(size 0.508 1.524)
			(layers "F.Cu" "F.Mask" "F.Paste")
			(net "GND")
		)
		(pad "11" smd rect
			(at 4.800092 1.905 90)
			(size 0.508 1.524)
			(layers "F.Cu" "F.Mask" "F.Paste")
			(net "Net_2685")
		)
		(pad "12" smd rect
			(at 4.800092 0.635 90)
			(size 0.508 1.524)
			(layers "F.Cu" "F.Mask" "F.Paste")
			(net "Net_2686")
		)
		(pad "13" smd rect
			(at 4.800092 -0.635 90)
			(size 0.508 1.524)
			(layers "F.Cu" "F.Mask" "F.Paste")
			(net "Net_2687")
		)
		(pad "14" smd rect
			(at 4.800092 -1.905 90)
			(size 0.508 1.524)
			(layers "F.Cu" "F.Mask" "F.Paste")
			(net "Net_2688")
		)
		(pad "15" smd rect
			(at 4.800092 -3.175 90)
			(size 0.508 1.524)
			(layers "F.Cu" "F.Mask" "F.Paste")
			(net "SPI_PEX0_SDIO0_MUX_R")
		)
		(pad "16" smd rect
			(at 4.800092 -4.445 90)
			(size 0.508 1.524)
			(layers "F.Cu" "F.Mask" "F.Paste")
			(net "SPI_PEX0_CLK_MUX_R")
		)
	)
	(footprint ""
		(layer "F.Cu")
		(at 336.931 -238.633 -90)
		(property "Reference" "R1795"
			(at 0 0 270)
			(layer "F.SilkS")
			(hide yes)
			(effects
				(font
					(size 1.27 1.27)
				)
			)
		)
		(property "Value" ""
			(at 0 0 270)
			(layer "F.Fab")
			(effects
				(font
					(size 1.27 1.27)
				)
			)
		)
		(duplicate_pad_numbers_are_jumpers no)
		(fp_line
			(start -0.7874 0.4064)
			(end -0.7874 -0.4064)
			(stroke
				(width 0.1524)
				(type default)
			)
			(layer "F.SilkS")
		)
		(fp_line
			(start 0.7874 0.4064)
			(end -0.7874 0.4064)
			(stroke
				(width 0.1524)
				(type default)
			)
			(layer "F.SilkS")
		)
		(fp_line
			(start -0.7874 -0.4064)
			(end 0.7874 -0.4064)
			(stroke
				(width 0.1524)
				(type default)
			)
			(layer "F.SilkS")
		)
		(fp_line
			(start 0.7874 -0.4064)
			(end 0.7874 0.4064)
			(stroke
				(width 0.1524)
				(type default)
			)
			(layer "F.SilkS")
		)
		(fp_line
			(start -0.67945 0.3048)
			(end -0.67945 -0.305054)
			(stroke
				(width 0.1)
				(type default)
			)
			(layer "F.Fab")
		)
		(fp_line
			(start -0.12065 0.3048)
			(end -0.67945 0.3048)
			(stroke
				(width 0.1)
				(type default)
			)
			(layer "F.Fab")
		)
		(fp_line
			(start 0.120396 0.3048)
			(end 0.120396 0.2794)
			(stroke
				(width 0.1)
				(type default)
			)
			(layer "F.Fab")
		)
		(fp_line
			(start 0.67945 0.3048)
			(end 0.120396 0.3048)
			(stroke
				(width 0.1)
				(type default)
			)
			(layer "F.Fab")
		)
		(fp_line
			(start -0.12065 0.2794)
			(end -0.12065 0.3048)
			(stroke
				(width 0.1)
				(type default)
			)
			(layer "F.Fab")
		)
		(fp_line
			(start 0.120396 0.2794)
			(end -0.12065 0.2794)
			(stroke
				(width 0.1)
				(type default)
			)
			(layer "F.Fab")
		)
		(fp_line
			(start -0.12065 -0.2794)
			(end 0.12065 -0.2794)
			(stroke
				(width 0.1)
				(type default)
			)
			(layer "F.Fab")
		)
		(fp_line
			(start 0.12065 -0.2794)
			(end 0.12065 -0.3048)
			(stroke
				(width 0.1)
				(type default)
			)
			(layer "F.Fab")
		)
		(fp_line
			(start 0.12065 -0.3048)
			(end 0.67945 -0.3048)
			(stroke
				(width 0.1)
				(type default)
			)
			(layer "F.Fab")
		)
		(fp_line
			(start 0.67945 -0.3048)
			(end 0.67945 0.3048)
			(stroke
				(width 0.1)
				(type default)
			)
			(layer "F.Fab")
		)
		(fp_line
			(start -0.67945 -0.305054)
			(end -0.12065 -0.305054)
			(stroke
				(width 0.1)
				(type default)
			)
			(layer "F.Fab")
		)
		(fp_line
			(start -0.12065 -0.305054)
			(end -0.12065 -0.2794)
			(stroke
				(width 0.1)
				(type default)
			)
			(layer "F.Fab")
		)
		(pad "1" smd circle
			(at -0.40005 0 270)
			(size 0 0)
			(layers "F.Cu" "F.Mask" "F.Paste")
			(net "MB_SWB_PWR_EN_ISO")
		)
		(pad "2" smd circle
			(at 0.40005 0 270)
			(size 0 0)
			(layers "F.Cu" "F.Mask" "F.Paste")
			(net "MB_SWB_PWR_EN_ISO_R")
		)
	)
	(footprint ""
		(layer "F.Cu")
		(at 291.194998 -98.734372)
		(property "Reference" "R256"
			(at 0 0 0)
			(layer "F.SilkS")
			(hide yes)
			(effects
				(font
					(size 1.27 1.27)
				)
			)
		)
		(property "Value" ""
			(at 0 0 0)
			(layer "F.Fab")
			(effects
				(font
					(size 1.27 1.27)
				)
			)
		)
		(duplicate_pad_numbers_are_jumpers no)
		(fp_line
			(start -0.7874 -0.4064)
			(end 0.7874 -0.4064)
			(stroke
				(width 0.1524)
				(type default)
			)
			(layer "F.SilkS")
		)
		(fp_line
			(start -0.7874 0.4064)
			(end -0.7874 -0.4064)
			(stroke
				(width 0.1524)
				(type default)
			)
			(layer "F.SilkS")
		)
		(fp_line
			(start 0.7874 -0.4064)
			(end 0.7874 0.4064)
			(stroke
				(width 0.1524)
				(type default)
			)
			(layer "F.SilkS")
		)
		(fp_line
			(start 0.7874 0.4064)
			(end -0.7874 0.4064)
			(stroke
				(width 0.1524)
				(type default)
			)
			(layer "F.SilkS")
		)
		(fp_line
			(start -0.67945 -0.305054)
			(end -0.12065 -0.305054)
			(stroke
				(width 0.1)
				(type default)
			)
			(layer "F.Fab")
		)
		(fp_line
			(start -0.67945 0.3048)
			(end -0.67945 -0.305054)
			(stroke
				(width 0.1)
				(type default)
			)
			(layer "F.Fab")
		)
		(fp_line
			(start -0.12065 -0.305054)
			(end -0.12065 -0.2794)
			(stroke
				(width 0.1)
				(type default)
			)
			(layer "F.Fab")
		)
		(fp_line
			(start -0.12065 -0.2794)
			(end 0.12065 -0.2794)
			(stroke
				(width 0.1)
				(type default)
			)
			(layer "F.Fab")
		)
		(fp_line
			(start -0.12065 0.2794)
			(end -0.12065 0.3048)
			(stroke
				(width 0.1)
				(type default)
			)
			(layer "F.Fab")
		)
		(fp_line
			(start -0.12065 0.3048)
			(end -0.67945 0.3048)
			(stroke
				(width 0.1)
				(type default)
			)
			(layer "F.Fab")
		)
		(fp_line
			(start 0.120396 0.2794)
			(end -0.12065 0.2794)
			(stroke
				(width 0.1)
				(type default)
			)
			(layer "F.Fab")
		)
		(fp_line
			(start 0.120396 0.3048)
			(end 0.120396 0.2794)
			(stroke
				(width 0.1)
				(type default)
			)
			(layer "F.Fab")
		)
		(fp_line
			(start 0.12065 -0.3048)
			(end 0.67945 -0.3048)
			(stroke
				(width 0.1)
				(type default)
			)
			(layer "F.Fab")
		)
		(fp_line
			(start 0.12065 -0.2794)
			(end 0.12065 -0.3048)
			(stroke
				(width 0.1)
				(type default)
			)
			(layer "F.Fab")
		)
		(fp_line
			(start 0.67945 -0.3048)
			(end 0.67945 0.3048)
			(stroke
				(width 0.1)
				(type default)
			)
			(layer "F.Fab")
		)
		(fp_line
			(start 0.67945 0.3048)
			(end 0.120396 0.3048)
			(stroke
				(width 0.1)
				(type default)
			)
			(layer "F.Fab")
		)
		(pad "1" smd circle
			(at -0.40005 0)
			(size 0 0)
			(layers "F.Cu" "F.Mask" "F.Paste")
			(net "NIC5_RBT_ARB_OUT")
		)
		(pad "2" smd circle
			(at 0.40005 0)
			(size 0 0)
			(layers "F.Cu" "F.Mask" "F.Paste")
			(net "NIC5_RBT_ARB_IN")
		)
	)
	(footprint ""
		(layer "F.Cu")
		(at 58.176922 -376.540268)
		(property "Reference" "R1870"
			(at 0 0 0)
			(layer "F.SilkS")
			(hide yes)
			(effects
				(font
					(size 1.27 1.27)
				)
			)
		)
		(property "Value" ""
			(at 0 0 0)
			(layer "F.Fab")
			(effects
				(font
					(size 1.27 1.27)
				)
			)
		)
		(duplicate_pad_numbers_are_jumpers no)
		(fp_line
			(start -0.7874 -0.4064)
			(end 0.7874 -0.4064)
			(stroke
				(width 0.1524)
				(type default)
			)
			(layer "F.SilkS")
		)
		(fp_line
			(start -0.7874 0.4064)
			(end -0.7874 -0.4064)
			(stroke
				(width 0.1524)
				(type default)
			)
			(layer "F.SilkS")
		)
		(fp_line
			(start 0.7874 -0.4064)
			(end 0.7874 0.4064)
			(stroke
				(width 0.1524)
				(type default)
			)
			(layer "F.SilkS")
		)
		(fp_line
			(start 0.7874 0.4064)
			(end -0.7874 0.4064)
			(stroke
				(width 0.1524)
				(type default)
			)
			(layer "F.SilkS")
		)
		(fp_line
			(start -0.67945 -0.305054)
			(end -0.12065 -0.305054)
			(stroke
				(width 0.1)
				(type default)
			)
			(layer "F.Fab")
		)
		(fp_line
			(start -0.67945 0.3048)
			(end -0.67945 -0.305054)
			(stroke
				(width 0.1)
				(type default)
			)
			(layer "F.Fab")
		)
		(fp_line
			(start -0.12065 -0.305054)
			(end -0.12065 -0.2794)
			(stroke
				(width 0.1)
				(type default)
			)
			(layer "F.Fab")
		)
		(fp_line
			(start -0.12065 -0.2794)
			(end 0.12065 -0.2794)
			(stroke
				(width 0.1)
				(type default)
			)
			(layer "F.Fab")
		)
		(fp_line
			(start -0.12065 0.2794)
			(end -0.12065 0.3048)
			(stroke
				(width 0.1)
				(type default)
			)
			(layer "F.Fab")
		)
		(fp_line
			(start -0.12065 0.3048)
			(end -0.67945 0.3048)
			(stroke
				(width 0.1)
				(type default)
			)
			(layer "F.Fab")
		)
		(fp_line
			(start 0.120396 0.2794)
			(end -0.12065 0.2794)
			(stroke
				(width 0.1)
				(type default)
			)
			(layer "F.Fab")
		)
		(fp_line
			(start 0.120396 0.3048)
			(end 0.120396 0.2794)
			(stroke
				(width 0.1)
				(type default)
			)
			(layer "F.Fab")
		)
		(fp_line
			(start 0.12065 -0.3048)
			(end 0.67945 -0.3048)
			(stroke
				(width 0.1)
				(type default)
			)
			(layer "F.Fab")
		)
		(fp_line
			(start 0.12065 -0.2794)
			(end 0.12065 -0.3048)
			(stroke
				(width 0.1)
				(type default)
			)
			(layer "F.Fab")
		)
		(fp_line
			(start 0.67945 -0.3048)
			(end 0.67945 0.3048)
			(stroke
				(width 0.1)
				(type default)
			)
			(layer "F.Fab")
		)
		(fp_line
			(start 0.67945 0.3048)
			(end 0.120396 0.3048)
			(stroke
				(width 0.1)
				(type default)
			)
			(layer "F.Fab")
		)
		(pad "1" smd circle
			(at -0.40005 0)
			(size 0 0)
			(layers "F.Cu" "F.Mask" "F.Paste")
			(net "GPU_BASE_PWR_EN_R")
		)
		(pad "2" smd circle
			(at 0.40005 0)
			(size 0 0)
			(layers "F.Cu" "F.Mask" "F.Paste")
			(net "GPU_BASE_PWR_EN")
		)
	)
	(footprint ""
		(layer "F.Cu")
		(at 386.899912 -154.327352 180)
		(property "Reference" "R332"
			(at 0 0 180)
			(layer "F.SilkS")
			(hide yes)
			(effects
				(font
					(size 1.27 1.27)
				)
			)
		)
		(property "Value" ""
			(at 0 0 180)
			(layer "F.Fab")
			(effects
				(font
					(size 1.27 1.27)
				)
			)
		)
		(duplicate_pad_numbers_are_jumpers no)
		(fp_line
			(start 0.7874 0.4064)
			(end -0.7874 0.4064)
			(stroke
				(width 0.1524)
				(type default)
			)
			(layer "F.SilkS")
		)
		(fp_line
			(start 0.7874 -0.4064)
			(end 0.7874 0.4064)
			(stroke
				(width 0.1524)
				(type default)
			)
			(layer "F.SilkS")
		)
		(fp_line
			(start -0.7874 0.4064)
			(end -0.7874 -0.4064)
			(stroke
				(width 0.1524)
				(type default)
			)
			(layer "F.SilkS")
		)
		(fp_line
			(start -0.7874 -0.4064)
			(end 0.7874 -0.4064)
			(stroke
				(width 0.1524)
				(type default)
			)
			(layer "F.SilkS")
		)
		(fp_line
			(start 0.67945 0.3048)
			(end 0.120396 0.3048)
			(stroke
				(width 0.1)
				(type default)
			)
			(layer "F.Fab")
		)
		(fp_line
			(start 0.67945 -0.3048)
			(end 0.67945 0.3048)
			(stroke
				(width 0.1)
				(type default)
			)
			(layer "F.Fab")
		)
		(fp_line
			(start 0.12065 -0.2794)
			(end 0.12065 -0.3048)
			(stroke
				(width 0.1)
				(type default)
			)
			(layer "F.Fab")
		)
		(fp_line
			(start 0.12065 -0.3048)
			(end 0.67945 -0.3048)
			(stroke
				(width 0.1)
				(type default)
			)
			(layer "F.Fab")
		)
		(fp_line
			(start 0.120396 0.3048)
			(end 0.120396 0.2794)
			(stroke
				(width 0.1)
				(type default)
			)
			(layer "F.Fab")
		)
		(fp_line
			(start 0.120396 0.2794)
			(end -0.12065 0.2794)
			(stroke
				(width 0.1)
				(type default)
			)
			(layer "F.Fab")
		)
		(fp_line
			(start -0.12065 0.3048)
			(end -0.67945 0.3048)
			(stroke
				(width 0.1)
				(type default)
			)
			(layer "F.Fab")
		)
		(fp_line
			(start -0.12065 0.2794)
			(end -0.12065 0.3048)
			(stroke
				(width 0.1)
				(type default)
			)
			(layer "F.Fab")
		)
		(fp_line
			(start -0.12065 -0.2794)
			(end 0.12065 -0.2794)
			(stroke
				(width 0.1)
				(type default)
			)
			(layer "F.Fab")
		)
		(fp_line
			(start -0.12065 -0.305054)
			(end -0.12065 -0.2794)
			(stroke
				(width 0.1)
				(type default)
			)
			(layer "F.Fab")
		)
		(fp_line
			(start -0.67945 0.3048)
			(end -0.67945 -0.305054)
			(stroke
				(width 0.1)
				(type default)
			)
			(layer "F.Fab")
		)
		(fp_line
			(start -0.67945 -0.305054)
			(end -0.12065 -0.305054)
			(stroke
				(width 0.1)
				(type default)
			)
			(layer "F.Fab")
		)
		(pad "1" smd circle
			(at -0.40005 0 180)
			(size 0 0)
			(layers "F.Cu" "F.Mask" "F.Paste")
			(net "NIC6_SLOT_ID0")
		)
		(pad "2" smd circle
			(at 0.40005 0 180)
			(size 0 0)
			(layers "F.Cu" "F.Mask" "F.Paste")
			(net "GND")
		)
	)
	(footprint ""
		(layer "F.Cu")
		(at 126.210314 -123.947428 180)
		(property "Reference" "PR249"
			(at 0 0 180)
			(layer "F.SilkS")
			(hide yes)
			(effects
				(font
					(size 1.27 1.27)
				)
			)
		)
		(property "Value" ""
			(at 0 0 180)
			(layer "F.Fab")
			(effects
				(font
					(size 1.27 1.27)
				)
			)
		)
		(duplicate_pad_numbers_are_jumpers no)
		(fp_line
			(start 0.7874 0.4064)
			(end -0.7874 0.4064)
			(stroke
				(width 0.1524)
				(type default)
			)
			(layer "F.SilkS")
		)
		(fp_line
			(start 0.7874 -0.4064)
			(end 0.7874 0.4064)
			(stroke
				(width 0.1524)
				(type default)
			)
			(layer "F.SilkS")
		)
		(fp_line
			(start -0.7874 0.4064)
			(end -0.7874 -0.4064)
			(stroke
				(width 0.1524)
				(type default)
			)
			(layer "F.SilkS")
		)
		(fp_line
			(start -0.7874 -0.4064)
			(end 0.7874 -0.4064)
			(stroke
				(width 0.1524)
				(type default)
			)
			(layer "F.SilkS")
		)
		(fp_line
			(start 0.67945 0.3048)
			(end 0.120396 0.3048)
			(stroke
				(width 0.1)
				(type default)
			)
			(layer "F.Fab")
		)
		(fp_line
			(start 0.67945 -0.3048)
			(end 0.67945 0.3048)
			(stroke
				(width 0.1)
				(type default)
			)
			(layer "F.Fab")
		)
		(fp_line
			(start 0.12065 -0.2794)
			(end 0.12065 -0.3048)
			(stroke
				(width 0.1)
				(type default)
			)
			(layer "F.Fab")
		)
		(fp_line
			(start 0.12065 -0.3048)
			(end 0.67945 -0.3048)
			(stroke
				(width 0.1)
				(type default)
			)
			(layer "F.Fab")
		)
		(fp_line
			(start 0.120396 0.3048)
			(end 0.120396 0.2794)
			(stroke
				(width 0.1)
				(type default)
			)
			(layer "F.Fab")
		)
		(fp_line
			(start 0.120396 0.2794)
			(end -0.12065 0.2794)
			(stroke
				(width 0.1)
				(type default)
			)
			(layer "F.Fab")
		)
		(fp_line
			(start -0.12065 0.3048)
			(end -0.67945 0.3048)
			(stroke
				(width 0.1)
				(type default)
			)
			(layer "F.Fab")
		)
		(fp_line
			(start -0.12065 0.2794)
			(end -0.12065 0.3048)
			(stroke
				(width 0.1)
				(type default)
			)
			(layer "F.Fab")
		)
		(fp_line
			(start -0.12065 -0.2794)
			(end 0.12065 -0.2794)
			(stroke
				(width 0.1)
				(type default)
			)
			(layer "F.Fab")
		)
		(fp_line
			(start -0.12065 -0.305054)
			(end -0.12065 -0.2794)
			(stroke
				(width 0.1)
				(type default)
			)
			(layer "F.Fab")
		)
		(fp_line
			(start -0.67945 0.3048)
			(end -0.67945 -0.305054)
			(stroke
				(width 0.1)
				(type default)
			)
			(layer "F.Fab")
		)
		(fp_line
			(start -0.67945 -0.305054)
			(end -0.12065 -0.305054)
			(stroke
				(width 0.1)
				(type default)
			)
			(layer "F.Fab")
		)
		(pad "1" smd circle
			(at -0.40005 0 180)
			(size 0 0)
			(layers "F.Cu" "F.Mask" "F.Paste")
			(net "P3V3_NIC2_OCP")
		)
		(pad "2" smd circle
			(at 0.40005 0 180)
			(size 0 0)
			(layers "F.Cu" "F.Mask" "F.Paste")
			(net "GND")
		)
	)
	(footprint ""
		(layer "F.Cu")
		(at 132.29463 -111.377476 -90)
		(property "Reference" "PC794"
			(at 0 0 270)
			(layer "F.SilkS")
			(hide yes)
			(effects
				(font
					(size 1.27 1.27)
				)
			)
		)
		(property "Value" ""
			(at 0 0 270)
			(layer "F.Fab")
			(effects
				(font
					(size 1.27 1.27)
				)
			)
		)
		(duplicate_pad_numbers_are_jumpers no)
		(fp_line
			(start -0.7874 0.4064)
			(end -0.7874 -0.4064)
			(stroke
				(width 0.1524)
				(type default)
			)
			(layer "F.SilkS")
		)
		(fp_line
			(start 0.7874 0.4064)
			(end -0.7874 0.4064)
			(stroke
				(width 0.1524)
				(type default)
			)
			(layer "F.SilkS")
		)
		(fp_line
			(start -0.7874 -0.4064)
			(end 0.7874 -0.4064)
			(stroke
				(width 0.1524)
				(type default)
			)
			(layer "F.SilkS")
		)
		(fp_line
			(start 0.7874 -0.4064)
			(end 0.7874 0.4064)
			(stroke
				(width 0.1524)
				(type default)
			)
			(layer "F.SilkS")
		)
		(fp_line
			(start -0.67945 0.3048)
			(end -0.67945 -0.305054)
			(stroke
				(width 0.1)
				(type default)
			)
			(layer "F.Fab")
		)
		(fp_line
			(start -0.12065 0.3048)
			(end -0.67945 0.3048)
			(stroke
				(width 0.1)
				(type default)
			)
			(layer "F.Fab")
		)
		(fp_line
			(start 0.120396 0.3048)
			(end 0.120396 0.2794)
			(stroke
				(width 0.1)
				(type default)
			)
			(layer "F.Fab")
		)
		(fp_line
			(start 0.67945 0.3048)
			(end 0.120396 0.3048)
			(stroke
				(width 0.1)
				(type default)
			)
			(layer "F.Fab")
		)
		(fp_line
			(start -0.12065 0.2794)
			(end -0.12065 0.3048)
			(stroke
				(width 0.1)
				(type default)
			)
			(layer "F.Fab")
		)
		(fp_line
			(start 0.120396 0.2794)
			(end -0.12065 0.2794)
			(stroke
				(width 0.1)
				(type default)
			)
			(layer "F.Fab")
		)
		(fp_line
			(start -0.12065 -0.2794)
			(end 0.12065 -0.2794)
			(stroke
				(width 0.1)
				(type default)
			)
			(layer "F.Fab")
		)
		(fp_line
			(start 0.12065 -0.2794)
			(end 0.12065 -0.3048)
			(stroke
				(width 0.1)
				(type default)
			)
			(layer "F.Fab")
		)
		(fp_line
			(start 0.12065 -0.3048)
			(end 0.67945 -0.3048)
			(stroke
				(width 0.1)
				(type default)
			)
			(layer "F.Fab")
		)
		(fp_line
			(start 0.67945 -0.3048)
			(end 0.67945 0.3048)
			(stroke
				(width 0.1)
				(type default)
			)
			(layer "F.Fab")
		)
		(fp_line
			(start -0.67945 -0.305054)
			(end -0.12065 -0.305054)
			(stroke
				(width 0.1)
				(type default)
			)
			(layer "F.Fab")
		)
		(fp_line
			(start -0.12065 -0.305054)
			(end -0.12065 -0.2794)
			(stroke
				(width 0.1)
				(type default)
			)
			(layer "F.Fab")
		)
		(pad "1" smd circle
			(at -0.40005 0 270)
			(size 0 0)
			(layers "F.Cu" "F.Mask" "F.Paste")
			(net "P3V3_NIC2_CO_MODE")
		)
		(pad "2" smd circle
			(at 0.40005 0 270)
			(size 0 0)
			(layers "F.Cu" "F.Mask" "F.Paste")
			(net "GND")
		)
	)
	(footprint ""
		(layer "F.Cu")
		(at 72.43445 -34.546286 180)
		(property "Reference" "C81"
			(at 0 0 180)
			(layer "F.SilkS")
			(hide yes)
			(effects
				(font
					(size 1.27 1.27)
				)
			)
		)
		(property "Value" ""
			(at 0 0 180)
			(layer "F.Fab")
			(effects
				(font
					(size 1.27 1.27)
				)
			)
		)
		(duplicate_pad_numbers_are_jumpers no)
		(fp_line
			(start 0.299974 0.150114)
			(end -0.299974 0.150114)
			(stroke
				(width 0.1)
				(type default)
			)
			(layer "F.Fab")
		)
		(fp_line
			(start 0.299974 -0.150114)
			(end 0.299974 0.150114)
			(stroke
				(width 0.1)
				(type default)
			)
			(layer "F.Fab")
		)
		(fp_line
			(start -0.299974 0.150114)
			(end -0.299974 -0.150114)
			(stroke
				(width 0.1)
				(type default)
			)
			(layer "F.Fab")
		)
		(fp_line
			(start -0.299974 -0.150114)
			(end 0.299974 -0.150114)
			(stroke
				(width 0.1)
				(type default)
			)
			(layer "F.Fab")
		)
		(pad "1" smd rect
			(at -0.2667 0 180)
			(size 0.3048 0.381)
			(layers "F.Cu" "F.Mask" "F.Paste")
			(net "P5E_PEX0_STN2_TX_DP<39>")
		)
		(pad "2" smd rect
			(at 0.2667 0 180)
			(size 0.3048 0.381)
			(layers "F.Cu" "F.Mask" "F.Paste")
			(net "P5E_PEX0_STN2_TX_C_DP<39>")
		)
	)
	(footprint ""
		(layer "F.Cu")
		(at 247.673114 -210.288378)
		(property "Reference" "R6714"
			(at 0 0 0)
			(layer "F.SilkS")
			(hide yes)
			(effects
				(font
					(size 1.27 1.27)
				)
			)
		)
		(property "Value" ""
			(at 0 0 0)
			(layer "F.Fab")
			(effects
				(font
					(size 1.27 1.27)
				)
			)
		)
		(duplicate_pad_numbers_are_jumpers no)
		(fp_line
			(start -0.7874 -0.4064)
			(end 0.7874 -0.4064)
			(stroke
				(width 0.1524)
				(type default)
			)
			(layer "F.SilkS")
		)
		(fp_line
			(start -0.7874 0.4064)
			(end -0.7874 -0.4064)
			(stroke
				(width 0.1524)
				(type default)
			)
			(layer "F.SilkS")
		)
		(fp_line
			(start 0.7874 -0.4064)
			(end 0.7874 0.4064)
			(stroke
				(width 0.1524)
				(type default)
			)
			(layer "F.SilkS")
		)
		(fp_line
			(start 0.7874 0.4064)
			(end -0.7874 0.4064)
			(stroke
				(width 0.1524)
				(type default)
			)
			(layer "F.SilkS")
		)
		(fp_line
			(start -0.67945 -0.305054)
			(end -0.12065 -0.305054)
			(stroke
				(width 0.1)
				(type default)
			)
			(layer "F.Fab")
		)
		(fp_line
			(start -0.67945 0.3048)
			(end -0.67945 -0.305054)
			(stroke
				(width 0.1)
				(type default)
			)
			(layer "F.Fab")
		)
		(fp_line
			(start -0.12065 -0.305054)
			(end -0.12065 -0.2794)
			(stroke
				(width 0.1)
				(type default)
			)
			(layer "F.Fab")
		)
		(fp_line
			(start -0.12065 -0.2794)
			(end 0.12065 -0.2794)
			(stroke
				(width 0.1)
				(type default)
			)
			(layer "F.Fab")
		)
		(fp_line
			(start -0.12065 0.2794)
			(end -0.12065 0.3048)
			(stroke
				(width 0.1)
				(type default)
			)
			(layer "F.Fab")
		)
		(fp_line
			(start -0.12065 0.3048)
			(end -0.67945 0.3048)
			(stroke
				(width 0.1)
				(type default)
			)
			(layer "F.Fab")
		)
		(fp_line
			(start 0.120396 0.2794)
			(end -0.12065 0.2794)
			(stroke
				(width 0.1)
				(type default)
			)
			(layer "F.Fab")
		)
		(fp_line
			(start 0.120396 0.3048)
			(end 0.120396 0.2794)
			(stroke
				(width 0.1)
				(type default)
			)
			(layer "F.Fab")
		)
		(fp_line
			(start 0.12065 -0.3048)
			(end 0.67945 -0.3048)
			(stroke
				(width 0.1)
				(type default)
			)
			(layer "F.Fab")
		)
		(fp_line
			(start 0.12065 -0.2794)
			(end 0.12065 -0.3048)
			(stroke
				(width 0.1)
				(type default)
			)
			(layer "F.Fab")
		)
		(fp_line
			(start 0.67945 -0.3048)
			(end 0.67945 0.3048)
			(stroke
				(width 0.1)
				(type default)
			)
			(layer "F.Fab")
		)
		(fp_line
			(start 0.67945 0.3048)
			(end 0.120396 0.3048)
			(stroke
				(width 0.1)
				(type default)
			)
			(layer "F.Fab")
		)
		(pad "1" smd circle
			(at -0.40005 0)
			(size 0 0)
			(layers "F.Cu" "F.Mask" "F.Paste")
			(net "HSC_TYPE_ADC_R")
		)
		(pad "2" smd circle
			(at 0.40005 0)
			(size 0 0)
			(layers "F.Cu" "F.Mask" "F.Paste")
			(net "GND")
		)
	)
	(footprint ""
		(layer "F.Cu")
		(at 153.285444 -115.2652 90)
		(property "Reference" "R146"
			(at 0 0 90)
			(layer "F.SilkS")
			(hide yes)
			(effects
				(font
					(size 1.27 1.27)
				)
			)
		)
		(property "Value" ""
			(at 0 0 90)
			(layer "F.Fab")
			(effects
				(font
					(size 1.27 1.27)
				)
			)
		)
		(duplicate_pad_numbers_are_jumpers no)
		(fp_line
			(start 0.7874 -0.4064)
			(end 0.7874 0.4064)
			(stroke
				(width 0.1524)
				(type default)
			)
			(layer "F.SilkS")
		)
		(fp_line
			(start -0.7874 -0.4064)
			(end 0.7874 -0.4064)
			(stroke
				(width 0.1524)
				(type default)
			)
			(layer "F.SilkS")
		)
		(fp_line
			(start 0.7874 0.4064)
			(end -0.7874 0.4064)
			(stroke
				(width 0.1524)
				(type default)
			)
			(layer "F.SilkS")
		)
		(fp_line
			(start -0.7874 0.4064)
			(end -0.7874 -0.4064)
			(stroke
				(width 0.1524)
				(type default)
			)
			(layer "F.SilkS")
		)
		(fp_line
			(start -0.12065 -0.305054)
			(end -0.12065 -0.2794)
			(stroke
				(width 0.1)
				(type default)
			)
			(layer "F.Fab")
		)
		(fp_line
			(start -0.67945 -0.305054)
			(end -0.12065 -0.305054)
			(stroke
				(width 0.1)
				(type default)
			)
			(layer "F.Fab")
		)
		(fp_line
			(start 0.67945 -0.3048)
			(end 0.67945 0.3048)
			(stroke
				(width 0.1)
				(type default)
			)
			(layer "F.Fab")
		)
		(fp_line
			(start 0.12065 -0.3048)
			(end 0.67945 -0.3048)
			(stroke
				(width 0.1)
				(type default)
			)
			(layer "F.Fab")
		)
		(fp_line
			(start 0.12065 -0.2794)
			(end 0.12065 -0.3048)
			(stroke
				(width 0.1)
				(type default)
			)
			(layer "F.Fab")
		)
		(fp_line
			(start -0.12065 -0.2794)
			(end 0.12065 -0.2794)
			(stroke
				(width 0.1)
				(type default)
			)
			(layer "F.Fab")
		)
		(fp_line
			(start 0.120396 0.2794)
			(end -0.12065 0.2794)
			(stroke
				(width 0.1)
				(type default)
			)
			(layer "F.Fab")
		)
		(fp_line
			(start -0.12065 0.2794)
			(end -0.12065 0.3048)
			(stroke
				(width 0.1)
				(type default)
			)
			(layer "F.Fab")
		)
		(fp_line
			(start 0.67945 0.3048)
			(end 0.120396 0.3048)
			(stroke
				(width 0.1)
				(type default)
			)
			(layer "F.Fab")
		)
		(fp_line
			(start 0.120396 0.3048)
			(end 0.120396 0.2794)
			(stroke
				(width 0.1)
				(type default)
			)
			(layer "F.Fab")
		)
		(fp_line
			(start -0.12065 0.3048)
			(end -0.67945 0.3048)
			(stroke
				(width 0.1)
				(type default)
			)
			(layer "F.Fab")
		)
		(fp_line
			(start -0.67945 0.3048)
			(end -0.67945 -0.305054)
			(stroke
				(width 0.1)
				(type default)
			)
			(layer "F.Fab")
		)
		(pad "1" smd circle
			(at -0.40005 0 90)
			(size 0 0)
			(layers "F.Cu" "F.Mask" "F.Paste")
			(net "P3V3_AUX")
		)
		(pad "2" smd circle
			(at 0.40005 0 90)
			(size 0 0)
			(layers "F.Cu" "F.Mask" "F.Paste")
			(net "HP_NIC2_EN")
		)
	)
	(footprint ""
		(layer "F.Cu")
		(at 224.38868 -276.19325)
		(property "Reference" "R789"
			(at 0 0 0)
			(layer "F.SilkS")
			(hide yes)
			(effects
				(font
					(size 1.27 1.27)
				)
			)
		)
		(property "Value" ""
			(at 0 0 0)
			(layer "F.Fab")
			(effects
				(font
					(size 1.27 1.27)
				)
			)
		)
		(duplicate_pad_numbers_are_jumpers no)
		(fp_line
			(start -0.7874 -0.4064)
			(end 0.7874 -0.4064)
			(stroke
				(width 0.1524)
				(type default)
			)
			(layer "F.SilkS")
		)
		(fp_line
			(start -0.7874 0.4064)
			(end -0.7874 -0.4064)
			(stroke
				(width 0.1524)
				(type default)
			)
			(layer "F.SilkS")
		)
		(fp_line
			(start 0.7874 -0.4064)
			(end 0.7874 0.4064)
			(stroke
				(width 0.1524)
				(type default)
			)
			(layer "F.SilkS")
		)
		(fp_line
			(start 0.7874 0.4064)
			(end -0.7874 0.4064)
			(stroke
				(width 0.1524)
				(type default)
			)
			(layer "F.SilkS")
		)
		(fp_line
			(start -0.67945 -0.305054)
			(end -0.12065 -0.305054)
			(stroke
				(width 0.1)
				(type default)
			)
			(layer "F.Fab")
		)
		(fp_line
			(start -0.67945 0.3048)
			(end -0.67945 -0.305054)
			(stroke
				(width 0.1)
				(type default)
			)
			(layer "F.Fab")
		)
		(fp_line
			(start -0.12065 -0.305054)
			(end -0.12065 -0.2794)
			(stroke
				(width 0.1)
				(type default)
			)
			(layer "F.Fab")
		)
		(fp_line
			(start -0.12065 -0.2794)
			(end 0.12065 -0.2794)
			(stroke
				(width 0.1)
				(type default)
			)
			(layer "F.Fab")
		)
		(fp_line
			(start -0.12065 0.2794)
			(end -0.12065 0.3048)
			(stroke
				(width 0.1)
				(type default)
			)
			(layer "F.Fab")
		)
		(fp_line
			(start -0.12065 0.3048)
			(end -0.67945 0.3048)
			(stroke
				(width 0.1)
				(type default)
			)
			(layer "F.Fab")
		)
		(fp_line
			(start 0.120396 0.2794)
			(end -0.12065 0.2794)
			(stroke
				(width 0.1)
				(type default)
			)
			(layer "F.Fab")
		)
		(fp_line
			(start 0.120396 0.3048)
			(end 0.120396 0.2794)
			(stroke
				(width 0.1)
				(type default)
			)
			(layer "F.Fab")
		)
		(fp_line
			(start 0.12065 -0.3048)
			(end 0.67945 -0.3048)
			(stroke
				(width 0.1)
				(type default)
			)
			(layer "F.Fab")
		)
		(fp_line
			(start 0.12065 -0.2794)
			(end 0.12065 -0.3048)
			(stroke
				(width 0.1)
				(type default)
			)
			(layer "F.Fab")
		)
		(fp_line
			(start 0.67945 -0.3048)
			(end 0.67945 0.3048)
			(stroke
				(width 0.1)
				(type default)
			)
			(layer "F.Fab")
		)
		(fp_line
			(start 0.67945 0.3048)
			(end 0.120396 0.3048)
			(stroke
				(width 0.1)
				(type default)
			)
			(layer "F.Fab")
		)
		(pad "1" smd circle
			(at -0.40005 0)
			(size 0 0)
			(layers "F.Cu" "F.Mask" "F.Paste")
			(net "P1V25_PEX1")
		)
		(pad "2" smd circle
			(at 0.40005 0)
			(size 0 0)
			(layers "F.Cu" "F.Mask" "F.Paste")
			(net "P12V_PEX1_P1V25_VIN_N")
		)
	)
	(footprint ""
		(layer "F.Cu")
		(at 264.909046 -27.04973 180)
		(property "Reference" "C2772"
			(at 0 0 180)
			(layer "F.SilkS")
			(hide yes)
			(effects
				(font
					(size 1.27 1.27)
				)
			)
		)
		(property "Value" ""
			(at 0 0 180)
			(layer "F.Fab")
			(effects
				(font
					(size 1.27 1.27)
				)
			)
		)
		(duplicate_pad_numbers_are_jumpers no)
		(fp_line
			(start 0.7874 0.4064)
			(end -0.7874 0.4064)
			(stroke
				(width 0.1524)
				(type default)
			)
			(layer "F.SilkS")
		)
		(fp_line
			(start 0.7874 -0.4064)
			(end 0.7874 0.4064)
			(stroke
				(width 0.1524)
				(type default)
			)
			(layer "F.SilkS")
		)
		(fp_line
			(start -0.7874 0.4064)
			(end -0.7874 -0.4064)
			(stroke
				(width 0.1524)
				(type default)
			)
			(layer "F.SilkS")
		)
		(fp_line
			(start -0.7874 -0.4064)
			(end 0.7874 -0.4064)
			(stroke
				(width 0.1524)
				(type default)
			)
			(layer "F.SilkS")
		)
		(fp_line
			(start 0.67945 0.3048)
			(end 0.120396 0.3048)
			(stroke
				(width 0.1)
				(type default)
			)
			(layer "F.Fab")
		)
		(fp_line
			(start 0.67945 -0.3048)
			(end 0.67945 0.3048)
			(stroke
				(width 0.1)
				(type default)
			)
			(layer "F.Fab")
		)
		(fp_line
			(start 0.12065 -0.2794)
			(end 0.12065 -0.3048)
			(stroke
				(width 0.1)
				(type default)
			)
			(layer "F.Fab")
		)
		(fp_line
			(start 0.12065 -0.3048)
			(end 0.67945 -0.3048)
			(stroke
				(width 0.1)
				(type default)
			)
			(layer "F.Fab")
		)
		(fp_line
			(start 0.120396 0.3048)
			(end 0.120396 0.2794)
			(stroke
				(width 0.1)
				(type default)
			)
			(layer "F.Fab")
		)
		(fp_line
			(start 0.120396 0.2794)
			(end -0.12065 0.2794)
			(stroke
				(width 0.1)
				(type default)
			)
			(layer "F.Fab")
		)
		(fp_line
			(start -0.12065 0.3048)
			(end -0.67945 0.3048)
			(stroke
				(width 0.1)
				(type default)
			)
			(layer "F.Fab")
		)
		(fp_line
			(start -0.12065 0.2794)
			(end -0.12065 0.3048)
			(stroke
				(width 0.1)
				(type default)
			)
			(layer "F.Fab")
		)
		(fp_line
			(start -0.12065 -0.2794)
			(end 0.12065 -0.2794)
			(stroke
				(width 0.1)
				(type default)
			)
			(layer "F.Fab")
		)
		(fp_line
			(start -0.12065 -0.305054)
			(end -0.12065 -0.2794)
			(stroke
				(width 0.1)
				(type default)
			)
			(layer "F.Fab")
		)
		(fp_line
			(start -0.67945 0.3048)
			(end -0.67945 -0.305054)
			(stroke
				(width 0.1)
				(type default)
			)
			(layer "F.Fab")
		)
		(fp_line
			(start -0.67945 -0.305054)
			(end -0.12065 -0.305054)
			(stroke
				(width 0.1)
				(type default)
			)
			(layer "F.Fab")
		)
		(pad "1" smd circle
			(at -0.40005 0 180)
			(size 0 0)
			(layers "F.Cu" "F.Mask" "F.Paste")
			(net "PRSNT_SSD9_R_N")
		)
		(pad "2" smd circle
			(at 0.40005 0 180)
			(size 0 0)
			(layers "F.Cu" "F.Mask" "F.Paste")
			(net "GND")
		)
	)
	(footprint ""
		(layer "F.Cu")
		(at 58.709052 -27.04973 180)
		(property "Reference" "C2765"
			(at 0 0 180)
			(layer "F.SilkS")
			(hide yes)
			(effects
				(font
					(size 1.27 1.27)
				)
			)
		)
		(property "Value" ""
			(at 0 0 180)
			(layer "F.Fab")
			(effects
				(font
					(size 1.27 1.27)
				)
			)
		)
		(duplicate_pad_numbers_are_jumpers no)
		(fp_line
			(start 0.7874 0.4064)
			(end -0.7874 0.4064)
			(stroke
				(width 0.1524)
				(type default)
			)
			(layer "F.SilkS")
		)
		(fp_line
			(start 0.7874 -0.4064)
			(end 0.7874 0.4064)
			(stroke
				(width 0.1524)
				(type default)
			)
			(layer "F.SilkS")
		)
		(fp_line
			(start -0.7874 0.4064)
			(end -0.7874 -0.4064)
			(stroke
				(width 0.1524)
				(type default)
			)
			(layer "F.SilkS")
		)
		(fp_line
			(start -0.7874 -0.4064)
			(end 0.7874 -0.4064)
			(stroke
				(width 0.1524)
				(type default)
			)
			(layer "F.SilkS")
		)
		(fp_line
			(start 0.67945 0.3048)
			(end 0.120396 0.3048)
			(stroke
				(width 0.1)
				(type default)
			)
			(layer "F.Fab")
		)
		(fp_line
			(start 0.67945 -0.3048)
			(end 0.67945 0.3048)
			(stroke
				(width 0.1)
				(type default)
			)
			(layer "F.Fab")
		)
		(fp_line
			(start 0.12065 -0.2794)
			(end 0.12065 -0.3048)
			(stroke
				(width 0.1)
				(type default)
			)
			(layer "F.Fab")
		)
		(fp_line
			(start 0.12065 -0.3048)
			(end 0.67945 -0.3048)
			(stroke
				(width 0.1)
				(type default)
			)
			(layer "F.Fab")
		)
		(fp_line
			(start 0.120396 0.3048)
			(end 0.120396 0.2794)
			(stroke
				(width 0.1)
				(type default)
			)
			(layer "F.Fab")
		)
		(fp_line
			(start 0.120396 0.2794)
			(end -0.12065 0.2794)
			(stroke
				(width 0.1)
				(type default)
			)
			(layer "F.Fab")
		)
		(fp_line
			(start -0.12065 0.3048)
			(end -0.67945 0.3048)
			(stroke
				(width 0.1)
				(type default)
			)
			(layer "F.Fab")
		)
		(fp_line
			(start -0.12065 0.2794)
			(end -0.12065 0.3048)
			(stroke
				(width 0.1)
				(type default)
			)
			(layer "F.Fab")
		)
		(fp_line
			(start -0.12065 -0.2794)
			(end 0.12065 -0.2794)
			(stroke
				(width 0.1)
				(type default)
			)
			(layer "F.Fab")
		)
		(fp_line
			(start -0.12065 -0.305054)
			(end -0.12065 -0.2794)
			(stroke
				(width 0.1)
				(type default)
			)
			(layer "F.Fab")
		)
		(fp_line
			(start -0.67945 0.3048)
			(end -0.67945 -0.305054)
			(stroke
				(width 0.1)
				(type default)
			)
			(layer "F.Fab")
		)
		(fp_line
			(start -0.67945 -0.305054)
			(end -0.12065 -0.305054)
			(stroke
				(width 0.1)
				(type default)
			)
			(layer "F.Fab")
		)
		(pad "1" smd circle
			(at -0.40005 0 180)
			(size 0 0)
			(layers "F.Cu" "F.Mask" "F.Paste")
			(net "PRSNT_SSD2_R_N")
		)
		(pad "2" smd circle
			(at 0.40005 0 180)
			(size 0 0)
			(layers "F.Cu" "F.Mask" "F.Paste")
			(net "GND")
		)
	)
	(footprint ""
		(layer "F.Cu")
		(at 438.339484 -96.811592 -90)
		(property "Reference" "R763"
			(at 0 0 270)
			(layer "F.SilkS")
			(hide yes)
			(effects
				(font
					(size 1.27 1.27)
				)
			)
		)
		(property "Value" ""
			(at 0 0 270)
			(layer "F.Fab")
			(effects
				(font
					(size 1.27 1.27)
				)
			)
		)
		(duplicate_pad_numbers_are_jumpers no)
		(fp_line
			(start -0.7874 0.4064)
			(end -0.7874 -0.4064)
			(stroke
				(width 0.1524)
				(type default)
			)
			(layer "F.SilkS")
		)
		(fp_line
			(start 0.7874 0.4064)
			(end -0.7874 0.4064)
			(stroke
				(width 0.1524)
				(type default)
			)
			(layer "F.SilkS")
		)
		(fp_line
			(start -0.7874 -0.4064)
			(end 0.7874 -0.4064)
			(stroke
				(width 0.1524)
				(type default)
			)
			(layer "F.SilkS")
		)
		(fp_line
			(start 0.7874 -0.4064)
			(end 0.7874 0.4064)
			(stroke
				(width 0.1524)
				(type default)
			)
			(layer "F.SilkS")
		)
		(fp_line
			(start -0.67945 0.3048)
			(end -0.67945 -0.305054)
			(stroke
				(width 0.1)
				(type default)
			)
			(layer "F.Fab")
		)
		(fp_line
			(start -0.12065 0.3048)
			(end -0.67945 0.3048)
			(stroke
				(width 0.1)
				(type default)
			)
			(layer "F.Fab")
		)
		(fp_line
			(start 0.120396 0.3048)
			(end 0.120396 0.2794)
			(stroke
				(width 0.1)
				(type default)
			)
			(layer "F.Fab")
		)
		(fp_line
			(start 0.67945 0.3048)
			(end 0.120396 0.3048)
			(stroke
				(width 0.1)
				(type default)
			)
			(layer "F.Fab")
		)
		(fp_line
			(start -0.12065 0.2794)
			(end -0.12065 0.3048)
			(stroke
				(width 0.1)
				(type default)
			)
			(layer "F.Fab")
		)
		(fp_line
			(start 0.120396 0.2794)
			(end -0.12065 0.2794)
			(stroke
				(width 0.1)
				(type default)
			)
			(layer "F.Fab")
		)
		(fp_line
			(start -0.12065 -0.2794)
			(end 0.12065 -0.2794)
			(stroke
				(width 0.1)
				(type default)
			)
			(layer "F.Fab")
		)
		(fp_line
			(start 0.12065 -0.2794)
			(end 0.12065 -0.3048)
			(stroke
				(width 0.1)
				(type default)
			)
			(layer "F.Fab")
		)
		(fp_line
			(start 0.12065 -0.3048)
			(end 0.67945 -0.3048)
			(stroke
				(width 0.1)
				(type default)
			)
			(layer "F.Fab")
		)
		(fp_line
			(start 0.67945 -0.3048)
			(end 0.67945 0.3048)
			(stroke
				(width 0.1)
				(type default)
			)
			(layer "F.Fab")
		)
		(fp_line
			(start -0.67945 -0.305054)
			(end -0.12065 -0.305054)
			(stroke
				(width 0.1)
				(type default)
			)
			(layer "F.Fab")
		)
		(fp_line
			(start -0.12065 -0.305054)
			(end -0.12065 -0.2794)
			(stroke
				(width 0.1)
				(type default)
			)
			(layer "F.Fab")
		)
		(pad "1" smd circle
			(at -0.40005 0 270)
			(size 0 0)
			(layers "F.Cu" "F.Mask" "F.Paste")
			(net "NIC7_ADC_A0")
		)
		(pad "2" smd circle
			(at 0.40005 0 270)
			(size 0 0)
			(layers "F.Cu" "F.Mask" "F.Paste")
			(net "GND")
		)
	)
	(footprint ""
		(layer "F.Cu")
		(at 228.79304 -94.073726 180)
		(property "Reference" "R5441"
			(at 0 0 180)
			(layer "F.SilkS")
			(hide yes)
			(effects
				(font
					(size 1.27 1.27)
				)
			)
		)
		(property "Value" ""
			(at 0 0 180)
			(layer "F.Fab")
			(effects
				(font
					(size 1.27 1.27)
				)
			)
		)
		(duplicate_pad_numbers_are_jumpers no)
		(fp_line
			(start 0.7874 0.4064)
			(end -0.7874 0.4064)
			(stroke
				(width 0.1524)
				(type default)
			)
			(layer "F.SilkS")
		)
		(fp_line
			(start 0.7874 -0.4064)
			(end 0.7874 0.4064)
			(stroke
				(width 0.1524)
				(type default)
			)
			(layer "F.SilkS")
		)
		(fp_line
			(start -0.7874 0.4064)
			(end -0.7874 -0.4064)
			(stroke
				(width 0.1524)
				(type default)
			)
			(layer "F.SilkS")
		)
		(fp_line
			(start -0.7874 -0.4064)
			(end 0.7874 -0.4064)
			(stroke
				(width 0.1524)
				(type default)
			)
			(layer "F.SilkS")
		)
		(fp_line
			(start 0.67945 0.3048)
			(end 0.120396 0.3048)
			(stroke
				(width 0.1)
				(type default)
			)
			(layer "F.Fab")
		)
		(fp_line
			(start 0.67945 -0.3048)
			(end 0.67945 0.3048)
			(stroke
				(width 0.1)
				(type default)
			)
			(layer "F.Fab")
		)
		(fp_line
			(start 0.12065 -0.2794)
			(end 0.12065 -0.3048)
			(stroke
				(width 0.1)
				(type default)
			)
			(layer "F.Fab")
		)
		(fp_line
			(start 0.12065 -0.3048)
			(end 0.67945 -0.3048)
			(stroke
				(width 0.1)
				(type default)
			)
			(layer "F.Fab")
		)
		(fp_line
			(start 0.120396 0.3048)
			(end 0.120396 0.2794)
			(stroke
				(width 0.1)
				(type default)
			)
			(layer "F.Fab")
		)
		(fp_line
			(start 0.120396 0.2794)
			(end -0.12065 0.2794)
			(stroke
				(width 0.1)
				(type default)
			)
			(layer "F.Fab")
		)
		(fp_line
			(start -0.12065 0.3048)
			(end -0.67945 0.3048)
			(stroke
				(width 0.1)
				(type default)
			)
			(layer "F.Fab")
		)
		(fp_line
			(start -0.12065 0.2794)
			(end -0.12065 0.3048)
			(stroke
				(width 0.1)
				(type default)
			)
			(layer "F.Fab")
		)
		(fp_line
			(start -0.12065 -0.2794)
			(end 0.12065 -0.2794)
			(stroke
				(width 0.1)
				(type default)
			)
			(layer "F.Fab")
		)
		(fp_line
			(start -0.12065 -0.305054)
			(end -0.12065 -0.2794)
			(stroke
				(width 0.1)
				(type default)
			)
			(layer "F.Fab")
		)
		(fp_line
			(start -0.67945 0.3048)
			(end -0.67945 -0.305054)
			(stroke
				(width 0.1)
				(type default)
			)
			(layer "F.Fab")
		)
		(fp_line
			(start -0.67945 -0.305054)
			(end -0.12065 -0.305054)
			(stroke
				(width 0.1)
				(type default)
			)
			(layer "F.Fab")
		)
		(pad "1" smd circle
			(at -0.40005 0 180)
			(size 0 0)
			(layers "F.Cu" "F.Mask" "F.Paste")
			(net "PEX_USB_HUB_PSELF")
		)
		(pad "2" smd circle
			(at 0.40005 0 180)
			(size 0 0)
			(layers "F.Cu" "F.Mask" "F.Paste")
			(net "GND")
		)
	)
	(footprint ""
		(layer "F.Cu")
		(at 363.474 -213.995 180)
		(property "Reference" "R4621"
			(at 0 0 180)
			(layer "F.SilkS")
			(hide yes)
			(effects
				(font
					(size 1.27 1.27)
				)
			)
		)
		(property "Value" ""
			(at 0 0 180)
			(layer "F.Fab")
			(effects
				(font
					(size 1.27 1.27)
				)
			)
		)
		(duplicate_pad_numbers_are_jumpers no)
		(fp_line
			(start 0.7874 0.4064)
			(end -0.7874 0.4064)
			(stroke
				(width 0.1524)
				(type default)
			)
			(layer "F.SilkS")
		)
		(fp_line
			(start 0.7874 -0.4064)
			(end 0.7874 0.4064)
			(stroke
				(width 0.1524)
				(type default)
			)
			(layer "F.SilkS")
		)
		(fp_line
			(start -0.7874 0.4064)
			(end -0.7874 -0.4064)
			(stroke
				(width 0.1524)
				(type default)
			)
			(layer "F.SilkS")
		)
		(fp_line
			(start -0.7874 -0.4064)
			(end 0.7874 -0.4064)
			(stroke
				(width 0.1524)
				(type default)
			)
			(layer "F.SilkS")
		)
		(fp_line
			(start 0.67945 0.3048)
			(end 0.120396 0.3048)
			(stroke
				(width 0.1)
				(type default)
			)
			(layer "F.Fab")
		)
		(fp_line
			(start 0.67945 -0.3048)
			(end 0.67945 0.3048)
			(stroke
				(width 0.1)
				(type default)
			)
			(layer "F.Fab")
		)
		(fp_line
			(start 0.12065 -0.2794)
			(end 0.12065 -0.3048)
			(stroke
				(width 0.1)
				(type default)
			)
			(layer "F.Fab")
		)
		(fp_line
			(start 0.12065 -0.3048)
			(end 0.67945 -0.3048)
			(stroke
				(width 0.1)
				(type default)
			)
			(layer "F.Fab")
		)
		(fp_line
			(start 0.120396 0.3048)
			(end 0.120396 0.2794)
			(stroke
				(width 0.1)
				(type default)
			)
			(layer "F.Fab")
		)
		(fp_line
			(start 0.120396 0.2794)
			(end -0.12065 0.2794)
			(stroke
				(width 0.1)
				(type default)
			)
			(layer "F.Fab")
		)
		(fp_line
			(start -0.12065 0.3048)
			(end -0.67945 0.3048)
			(stroke
				(width 0.1)
				(type default)
			)
			(layer "F.Fab")
		)
		(fp_line
			(start -0.12065 0.2794)
			(end -0.12065 0.3048)
			(stroke
				(width 0.1)
				(type default)
			)
			(layer "F.Fab")
		)
		(fp_line
			(start -0.12065 -0.2794)
			(end 0.12065 -0.2794)
			(stroke
				(width 0.1)
				(type default)
			)
			(layer "F.Fab")
		)
		(fp_line
			(start -0.12065 -0.305054)
			(end -0.12065 -0.2794)
			(stroke
				(width 0.1)
				(type default)
			)
			(layer "F.Fab")
		)
		(fp_line
			(start -0.67945 0.3048)
			(end -0.67945 -0.305054)
			(stroke
				(width 0.1)
				(type default)
			)
			(layer "F.Fab")
		)
		(fp_line
			(start -0.67945 -0.305054)
			(end -0.12065 -0.305054)
			(stroke
				(width 0.1)
				(type default)
			)
			(layer "F.Fab")
		)
		(pad "1" smd circle
			(at -0.40005 0 180)
			(size 0 0)
			(layers "F.Cu" "F.Mask" "F.Paste")
			(net "PCA9555_0_PEX0_A1")
		)
		(pad "2" smd circle
			(at 0.40005 0 180)
			(size 0 0)
			(layers "F.Cu" "F.Mask" "F.Paste")
			(net "P3V3_AUX")
		)
	)
	(footprint ""
		(layer "F.Cu")
		(at 314.861448 -147.99691 180)
		(property "Reference" "C432"
			(at 0 0 180)
			(layer "F.SilkS")
			(hide yes)
			(effects
				(font
					(size 1.27 1.27)
				)
			)
		)
		(property "Value" ""
			(at 0 0 180)
			(layer "F.Fab")
			(effects
				(font
					(size 1.27 1.27)
				)
			)
		)
		(duplicate_pad_numbers_are_jumpers no)
		(fp_line
			(start 0.299974 0.150114)
			(end -0.299974 0.150114)
			(stroke
				(width 0.1)
				(type default)
			)
			(layer "F.Fab")
		)
		(fp_line
			(start 0.299974 -0.150114)
			(end 0.299974 0.150114)
			(stroke
				(width 0.1)
				(type default)
			)
			(layer "F.Fab")
		)
		(fp_line
			(start -0.299974 0.150114)
			(end -0.299974 -0.150114)
			(stroke
				(width 0.1)
				(type default)
			)
			(layer "F.Fab")
		)
		(fp_line
			(start -0.299974 -0.150114)
			(end 0.299974 -0.150114)
			(stroke
				(width 0.1)
				(type default)
			)
			(layer "F.Fab")
		)
		(pad "1" smd rect
			(at -0.2667 0 180)
			(size 0.3048 0.381)
			(layers "F.Cu" "F.Mask" "F.Paste")
			(net "P5E_PEX2_STN0_TX_DN<11>")
		)
		(pad "2" smd rect
			(at 0.2667 0 180)
			(size 0.3048 0.381)
			(layers "F.Cu" "F.Mask" "F.Paste")
			(net "P5E_PEX2_STN0_TX_C_DN<11>")
		)
	)
	(footprint ""
		(layer "F.Cu")
		(at 5.75437 -48.21809)
		(property "Reference" "PD60"
			(at -1.636522 2.105914 0)
			(unlocked yes)
			(layer "F.SilkS")
			(effects
				(font
					(size 0.7874 0.5842)
					(thickness 0.1524)
				)
				(justify left)
			)
		)
		(property "Value" ""
			(at 0 0 0)
			(layer "F.Fab")
			(effects
				(font
					(size 1.27 1.27)
				)
			)
		)
		(duplicate_pad_numbers_are_jumpers no)
		(fp_line
			(start -3.400044 -1.459992)
			(end 4.107942 -1.459992)
			(stroke
				(width 0.1524)
				(type default)
			)
			(layer "F.SilkS")
		)
		(fp_line
			(start -3.400044 1.459992)
			(end -3.400044 -1.459992)
			(stroke
				(width 0.1524)
				(type default)
			)
			(layer "F.SilkS")
		)
		(fp_line
			(start 4.107942 -1.459992)
			(end 4.107942 1.459992)
			(stroke
				(width 0.1524)
				(type default)
			)
			(layer "F.SilkS")
		)
		(fp_line
			(start 4.107942 1.459992)
			(end -3.400044 1.459992)
			(stroke
				(width 0.1524)
				(type default)
			)
			(layer "F.SilkS")
		)
		(fp_poly
			(pts
				(xy 4.107942 -1.459992) (xy 4.107942 1.459992) (xy 3.308096 1.459992) (xy 3.308096 -1.459992)
			)
			(stroke
				(width 0)
				(type default)
			)
			(fill yes)
			(layer "F.SilkS")
		)
		(fp_line
			(start -2.29997 -1.459992)
			(end 2.29997 -1.459992)
			(stroke
				(width 0.1)
				(type default)
			)
			(layer "F.Fab")
		)
		(fp_line
			(start -2.29997 1.459992)
			(end -2.29997 -1.459992)
			(stroke
				(width 0.1)
				(type default)
			)
			(layer "F.Fab")
		)
		(fp_line
			(start 2.29997 -1.459992)
			(end 2.29997 1.459992)
			(stroke
				(width 0.1)
				(type default)
			)
			(layer "F.Fab")
		)
		(fp_line
			(start 2.29997 1.459992)
			(end -2.29997 1.459992)
			(stroke
				(width 0.1)
				(type default)
			)
			(layer "F.Fab")
		)
		(fp_text user "+"
			(at -4.7752 -0.12065 0)
			(unlocked yes)
			(layer "F.SilkS")
			(effects
				(font
					(size 1.905 1.4224)
					(thickness 0.1524)
				)
				(justify left)
			)
		)
		(fp_text user "-"
			(at 5.4102 0.29845 180)
			(unlocked yes)
			(layer "F.SilkS")
			(effects
				(font
					(size 1.905 1.4224)
					(thickness 0.1524)
				)
				(justify left)
			)
		)
		(fp_text user "+"
			(at -4.7752 -0.12065 0)
			(unlocked yes)
			(layer "F.Fab")
			(effects
				(font
					(size 1.905 1.4224)
					(thickness 0.1524)
				)
				(justify left)
			)
		)
		(fp_text user "-"
			(at 5.4102 0.29845 180)
			(unlocked yes)
			(layer "F.Fab")
			(effects
				(font
					(size 1.905 1.4224)
					(thickness 0.1524)
				)
				(justify left)
			)
		)
		(pad "A" smd rect
			(at -1.999996 0 90)
			(size 1.7018 2.5146)
			(layers "F.Cu" "F.Mask" "F.Paste")
			(net "GND")
		)
		(pad "C" smd rect
			(at 1.999996 0 90)
			(size 1.7018 2.5146)
			(layers "F.Cu" "F.Mask" "F.Paste")
			(net "P3V3_SSD0")
		)
	)
	(footprint ""
		(layer "F.Cu")
		(at 215.047322 -21.37156)
		(property "Reference" "C3925"
			(at 0 0 0)
			(layer "F.SilkS")
			(hide yes)
			(effects
				(font
					(size 1.27 1.27)
				)
			)
		)
		(property "Value" ""
			(at 0 0 0)
			(layer "F.Fab")
			(effects
				(font
					(size 1.27 1.27)
				)
			)
		)
		(duplicate_pad_numbers_are_jumpers no)
		(fp_line
			(start -0.7874 -0.4064)
			(end 0.7874 -0.4064)
			(stroke
				(width 0.1524)
				(type default)
			)
			(layer "F.SilkS")
		)
		(fp_line
			(start -0.7874 0.4064)
			(end -0.7874 -0.4064)
			(stroke
				(width 0.1524)
				(type default)
			)
			(layer "F.SilkS")
		)
		(fp_line
			(start 0.7874 -0.4064)
			(end 0.7874 0.4064)
			(stroke
				(width 0.1524)
				(type default)
			)
			(layer "F.SilkS")
		)
		(fp_line
			(start 0.7874 0.4064)
			(end -0.7874 0.4064)
			(stroke
				(width 0.1524)
				(type default)
			)
			(layer "F.SilkS")
		)
		(fp_line
			(start -0.67945 -0.305054)
			(end -0.12065 -0.305054)
			(stroke
				(width 0.1)
				(type default)
			)
			(layer "F.Fab")
		)
		(fp_line
			(start -0.67945 0.3048)
			(end -0.67945 -0.305054)
			(stroke
				(width 0.1)
				(type default)
			)
			(layer "F.Fab")
		)
		(fp_line
			(start -0.12065 -0.305054)
			(end -0.12065 -0.2794)
			(stroke
				(width 0.1)
				(type default)
			)
			(layer "F.Fab")
		)
		(fp_line
			(start -0.12065 -0.2794)
			(end 0.12065 -0.2794)
			(stroke
				(width 0.1)
				(type default)
			)
			(layer "F.Fab")
		)
		(fp_line
			(start -0.12065 0.2794)
			(end -0.12065 0.3048)
			(stroke
				(width 0.1)
				(type default)
			)
			(layer "F.Fab")
		)
		(fp_line
			(start -0.12065 0.3048)
			(end -0.67945 0.3048)
			(stroke
				(width 0.1)
				(type default)
			)
			(layer "F.Fab")
		)
		(fp_line
			(start 0.120396 0.2794)
			(end -0.12065 0.2794)
			(stroke
				(width 0.1)
				(type default)
			)
			(layer "F.Fab")
		)
		(fp_line
			(start 0.120396 0.3048)
			(end 0.120396 0.2794)
			(stroke
				(width 0.1)
				(type default)
			)
			(layer "F.Fab")
		)
		(fp_line
			(start 0.12065 -0.3048)
			(end 0.67945 -0.3048)
			(stroke
				(width 0.1)
				(type default)
			)
			(layer "F.Fab")
		)
		(fp_line
			(start 0.12065 -0.2794)
			(end 0.12065 -0.3048)
			(stroke
				(width 0.1)
				(type default)
			)
			(layer "F.Fab")
		)
		(fp_line
			(start 0.67945 -0.3048)
			(end 0.67945 0.3048)
			(stroke
				(width 0.1)
				(type default)
			)
			(layer "F.Fab")
		)
		(fp_line
			(start 0.67945 0.3048)
			(end 0.120396 0.3048)
			(stroke
				(width 0.1)
				(type default)
			)
			(layer "F.Fab")
		)
		(pad "1" smd circle
			(at -0.40005 0)
			(size 0 0)
			(layers "F.Cu" "F.Mask" "F.Paste")
			(net "P12V_SSD7")
		)
		(pad "2" smd circle
			(at 0.40005 0)
			(size 0 0)
			(layers "F.Cu" "F.Mask" "F.Paste")
			(net "GND")
		)
	)
	(footprint ""
		(layer "F.Cu")
		(at 174.129192 -205.903576)
		(property "Reference" "ME2"
			(at 0 0 0)
			(layer "F.SilkS")
			(hide yes)
			(effects
				(font
					(size 1.27 1.27)
				)
			)
		)
		(property "Value" ""
			(at 0 0 0)
			(layer "F.Fab")
			(effects
				(font
					(size 1.27 1.27)
				)
			)
		)
		(duplicate_pad_numbers_are_jumpers no)
		(fp_poly
			(pts
				(xy 0 -0.5842) (xy 3.3401 -0.5842) (xy 3.3401 0) (xy 0 0)
			)
			(stroke
				(width 0)
				(type default)
			)
			(fill yes)
			(layer "F.SilkS")
		)
		(fp_poly
			(pts
				(xy 1.32715 -3.4417) (xy 2.01295 -3.4417) (xy 2.01295 -3.2512) (xy 1.32715 -3.2512)
			)
			(stroke
				(width 0)
				(type default)
			)
			(fill yes)
			(layer "F.SilkS")
		)
		(fp_poly
			(pts
				(xy -0.070612 -0.681228) (xy -0.197612 -0.820928) (xy 0.852678 -1.91262) (xy 0.728472 -3.29184)
				(xy -0.248412 -4.300728) (xy -0.184912 -4.478528) (xy -0.007112 -4.503928) (xy 0.684022 -3.785616)
				(xy 0.65659 -4.0894) (xy 0.97155 -4.3434) (xy 1.22555 -4.3561) (xy 1.46685 -4.4704) (xy 2.01295 -4.4704)
				(xy 2.15265 -4.4069) (xy 2.44475 -4.191) (xy 2.49555 -4.191) (xy 2.59715 -4.2926) (xy 2.80035 -4.2672)
				(xy 2.88925 -4.1656) (xy 2.88925 -4.029456) (xy 3.345688 -4.503928) (xy 3.523488 -4.478528) (xy 3.586988 -4.300728)
				(xy 2.88925 -3.58013) (xy 2.88925 -3.3147) (xy 2.82575 -3.2385) (xy 2.67335 -3.2385) (xy 2.521966 -1.875282)
				(xy 2.545842 -1.85039)
				(arc
					(start 2.55905 -1.8415)
					(mid 2.648099 -1.766068)
					(end 2.717292 -1.672082)
				)
				(xy 3.536188 -0.820928) (xy 3.409188 -0.681228) (xy 3.244088 -0.693928)
				(arc
					(start 2.737612 -1.216914)
					(mid 2.31728 -0.925553)
					(end 1.86055 -1.1557)
				)
				(xy 0.92075 -1.1557) (xy 0.888492 -1.51384) (xy 0.094488 -0.693928)
			)
			(stroke
				(width 0)
				(type default)
			)
			(fill yes)
			(layer "F.SilkS")
		)
	)
	(footprint ""
		(layer "F.Cu")
		(at 219.202 -198.628)
		(property "Reference" "R1522"
			(at 0 0 0)
			(layer "F.SilkS")
			(hide yes)
			(effects
				(font
					(size 1.27 1.27)
				)
			)
		)
		(property "Value" ""
			(at 0 0 0)
			(layer "F.Fab")
			(effects
				(font
					(size 1.27 1.27)
				)
			)
		)
		(duplicate_pad_numbers_are_jumpers no)
		(fp_line
			(start -0.7874 -0.4064)
			(end 0.7874 -0.4064)
			(stroke
				(width 0.1524)
				(type default)
			)
			(layer "F.SilkS")
		)
		(fp_line
			(start -0.7874 0.4064)
			(end -0.7874 -0.4064)
			(stroke
				(width 0.1524)
				(type default)
			)
			(layer "F.SilkS")
		)
		(fp_line
			(start 0.7874 -0.4064)
			(end 0.7874 0.4064)
			(stroke
				(width 0.1524)
				(type default)
			)
			(layer "F.SilkS")
		)
		(fp_line
			(start 0.7874 0.4064)
			(end -0.7874 0.4064)
			(stroke
				(width 0.1524)
				(type default)
			)
			(layer "F.SilkS")
		)
		(fp_line
			(start -0.67945 -0.305054)
			(end -0.12065 -0.305054)
			(stroke
				(width 0.1)
				(type default)
			)
			(layer "F.Fab")
		)
		(fp_line
			(start -0.67945 0.3048)
			(end -0.67945 -0.305054)
			(stroke
				(width 0.1)
				(type default)
			)
			(layer "F.Fab")
		)
		(fp_line
			(start -0.12065 -0.305054)
			(end -0.12065 -0.2794)
			(stroke
				(width 0.1)
				(type default)
			)
			(layer "F.Fab")
		)
		(fp_line
			(start -0.12065 -0.2794)
			(end 0.12065 -0.2794)
			(stroke
				(width 0.1)
				(type default)
			)
			(layer "F.Fab")
		)
		(fp_line
			(start -0.12065 0.2794)
			(end -0.12065 0.3048)
			(stroke
				(width 0.1)
				(type default)
			)
			(layer "F.Fab")
		)
		(fp_line
			(start -0.12065 0.3048)
			(end -0.67945 0.3048)
			(stroke
				(width 0.1)
				(type default)
			)
			(layer "F.Fab")
		)
		(fp_line
			(start 0.120396 0.2794)
			(end -0.12065 0.2794)
			(stroke
				(width 0.1)
				(type default)
			)
			(layer "F.Fab")
		)
		(fp_line
			(start 0.120396 0.3048)
			(end 0.120396 0.2794)
			(stroke
				(width 0.1)
				(type default)
			)
			(layer "F.Fab")
		)
		(fp_line
			(start 0.12065 -0.3048)
			(end 0.67945 -0.3048)
			(stroke
				(width 0.1)
				(type default)
			)
			(layer "F.Fab")
		)
		(fp_line
			(start 0.12065 -0.2794)
			(end 0.12065 -0.3048)
			(stroke
				(width 0.1)
				(type default)
			)
			(layer "F.Fab")
		)
		(fp_line
			(start 0.67945 -0.3048)
			(end 0.67945 0.3048)
			(stroke
				(width 0.1)
				(type default)
			)
			(layer "F.Fab")
		)
		(fp_line
			(start 0.67945 0.3048)
			(end 0.120396 0.3048)
			(stroke
				(width 0.1)
				(type default)
			)
			(layer "F.Fab")
		)
		(pad "1" smd circle
			(at -0.40005 0)
			(size 0 0)
			(layers "F.Cu" "F.Mask" "F.Paste")
			(net "SMB_NIC6_LS_R_SDA")
		)
		(pad "2" smd circle
			(at 0.40005 0)
			(size 0 0)
			(layers "F.Cu" "F.Mask" "F.Paste")
			(net "P3V3_NIC6")
		)
	)
	(footprint ""
		(layer "F.Cu")
		(at 375.426224 -39.73576 -90)
		(property "Reference" "R5572"
			(at 0 0 270)
			(layer "F.SilkS")
			(hide yes)
			(effects
				(font
					(size 1.27 1.27)
				)
			)
		)
		(property "Value" ""
			(at 0 0 270)
			(layer "F.Fab")
			(effects
				(font
					(size 1.27 1.27)
				)
			)
		)
		(duplicate_pad_numbers_are_jumpers no)
		(fp_line
			(start -0.7874 0.4064)
			(end -0.7874 -0.4064)
			(stroke
				(width 0.1524)
				(type default)
			)
			(layer "F.SilkS")
		)
		(fp_line
			(start 0.7874 0.4064)
			(end -0.7874 0.4064)
			(stroke
				(width 0.1524)
				(type default)
			)
			(layer "F.SilkS")
		)
		(fp_line
			(start -0.7874 -0.4064)
			(end 0.7874 -0.4064)
			(stroke
				(width 0.1524)
				(type default)
			)
			(layer "F.SilkS")
		)
		(fp_line
			(start 0.7874 -0.4064)
			(end 0.7874 0.4064)
			(stroke
				(width 0.1524)
				(type default)
			)
			(layer "F.SilkS")
		)
		(fp_line
			(start -0.67945 0.3048)
			(end -0.67945 -0.305054)
			(stroke
				(width 0.1)
				(type default)
			)
			(layer "F.Fab")
		)
		(fp_line
			(start -0.12065 0.3048)
			(end -0.67945 0.3048)
			(stroke
				(width 0.1)
				(type default)
			)
			(layer "F.Fab")
		)
		(fp_line
			(start 0.120396 0.3048)
			(end 0.120396 0.2794)
			(stroke
				(width 0.1)
				(type default)
			)
			(layer "F.Fab")
		)
		(fp_line
			(start 0.67945 0.3048)
			(end 0.120396 0.3048)
			(stroke
				(width 0.1)
				(type default)
			)
			(layer "F.Fab")
		)
		(fp_line
			(start -0.12065 0.2794)
			(end -0.12065 0.3048)
			(stroke
				(width 0.1)
				(type default)
			)
			(layer "F.Fab")
		)
		(fp_line
			(start 0.120396 0.2794)
			(end -0.12065 0.2794)
			(stroke
				(width 0.1)
				(type default)
			)
			(layer "F.Fab")
		)
		(fp_line
			(start -0.12065 -0.2794)
			(end 0.12065 -0.2794)
			(stroke
				(width 0.1)
				(type default)
			)
			(layer "F.Fab")
		)
		(fp_line
			(start 0.12065 -0.2794)
			(end 0.12065 -0.3048)
			(stroke
				(width 0.1)
				(type default)
			)
			(layer "F.Fab")
		)
		(fp_line
			(start 0.12065 -0.3048)
			(end 0.67945 -0.3048)
			(stroke
				(width 0.1)
				(type default)
			)
			(layer "F.Fab")
		)
		(fp_line
			(start 0.67945 -0.3048)
			(end 0.67945 0.3048)
			(stroke
				(width 0.1)
				(type default)
			)
			(layer "F.Fab")
		)
		(fp_line
			(start -0.67945 -0.305054)
			(end -0.12065 -0.305054)
			(stroke
				(width 0.1)
				(type default)
			)
			(layer "F.Fab")
		)
		(fp_line
			(start -0.12065 -0.305054)
			(end -0.12065 -0.2794)
			(stroke
				(width 0.1)
				(type default)
			)
			(layer "F.Fab")
		)
		(pad "1" smd circle
			(at -0.40005 0 270)
			(size 0 0)
			(layers "F.Cu" "F.Mask" "F.Paste")
			(net "P3V3_AUX")
		)
		(pad "2" smd circle
			(at 0.40005 0 270)
			(size 0 0)
			(layers "F.Cu" "F.Mask" "F.Paste")
			(net "SSD13_AUX_P3V3_EN")
		)
	)
	(footprint ""
		(layer "F.Cu")
		(at 249.992388 -31.825184 180)
		(property "Reference" "C490"
			(at 0 0 180)
			(layer "F.SilkS")
			(hide yes)
			(effects
				(font
					(size 1.27 1.27)
				)
			)
		)
		(property "Value" ""
			(at 0 0 180)
			(layer "F.Fab")
			(effects
				(font
					(size 1.27 1.27)
				)
			)
		)
		(duplicate_pad_numbers_are_jumpers no)
		(fp_line
			(start 0.299974 0.150114)
			(end -0.299974 0.150114)
			(stroke
				(width 0.1)
				(type default)
			)
			(layer "F.Fab")
		)
		(fp_line
			(start 0.299974 -0.150114)
			(end 0.299974 0.150114)
			(stroke
				(width 0.1)
				(type default)
			)
			(layer "F.Fab")
		)
		(fp_line
			(start -0.299974 0.150114)
			(end -0.299974 -0.150114)
			(stroke
				(width 0.1)
				(type default)
			)
			(layer "F.Fab")
		)
		(fp_line
			(start -0.299974 -0.150114)
			(end 0.299974 -0.150114)
			(stroke
				(width 0.1)
				(type default)
			)
			(layer "F.Fab")
		)
		(pad "1" smd rect
			(at -0.2667 0 180)
			(size 0.3048 0.381)
			(layers "F.Cu" "F.Mask" "F.Paste")
			(net "P5E_PEX2_STN2_TX_DN<46>")
		)
		(pad "2" smd rect
			(at 0.2667 0 180)
			(size 0.3048 0.381)
			(layers "F.Cu" "F.Mask" "F.Paste")
			(net "P5E_PEX2_STN2_TX_C_DN<46>")
		)
	)
	(footprint ""
		(layer "F.Cu")
		(at 69.62267 -22.867366 90)
		(property "Reference" "C3890"
			(at 0 0 90)
			(layer "F.SilkS")
			(hide yes)
			(effects
				(font
					(size 1.27 1.27)
				)
			)
		)
		(property "Value" ""
			(at 0 0 90)
			(layer "F.Fab")
			(effects
				(font
					(size 1.27 1.27)
				)
			)
		)
		(duplicate_pad_numbers_are_jumpers no)
		(fp_line
			(start 0.7874 -0.4064)
			(end 0.7874 0.4064)
			(stroke
				(width 0.1524)
				(type default)
			)
			(layer "F.SilkS")
		)
		(fp_line
			(start -0.7874 -0.4064)
			(end 0.7874 -0.4064)
			(stroke
				(width 0.1524)
				(type default)
			)
			(layer "F.SilkS")
		)
		(fp_line
			(start 0.7874 0.4064)
			(end -0.7874 0.4064)
			(stroke
				(width 0.1524)
				(type default)
			)
			(layer "F.SilkS")
		)
		(fp_line
			(start -0.7874 0.4064)
			(end -0.7874 -0.4064)
			(stroke
				(width 0.1524)
				(type default)
			)
			(layer "F.SilkS")
		)
		(fp_line
			(start -0.12065 -0.305054)
			(end -0.12065 -0.2794)
			(stroke
				(width 0.1)
				(type default)
			)
			(layer "F.Fab")
		)
		(fp_line
			(start -0.67945 -0.305054)
			(end -0.12065 -0.305054)
			(stroke
				(width 0.1)
				(type default)
			)
			(layer "F.Fab")
		)
		(fp_line
			(start 0.67945 -0.3048)
			(end 0.67945 0.3048)
			(stroke
				(width 0.1)
				(type default)
			)
			(layer "F.Fab")
		)
		(fp_line
			(start 0.12065 -0.3048)
			(end 0.67945 -0.3048)
			(stroke
				(width 0.1)
				(type default)
			)
			(layer "F.Fab")
		)
		(fp_line
			(start 0.12065 -0.2794)
			(end 0.12065 -0.3048)
			(stroke
				(width 0.1)
				(type default)
			)
			(layer "F.Fab")
		)
		(fp_line
			(start -0.12065 -0.2794)
			(end 0.12065 -0.2794)
			(stroke
				(width 0.1)
				(type default)
			)
			(layer "F.Fab")
		)
		(fp_line
			(start 0.120396 0.2794)
			(end -0.12065 0.2794)
			(stroke
				(width 0.1)
				(type default)
			)
			(layer "F.Fab")
		)
		(fp_line
			(start -0.12065 0.2794)
			(end -0.12065 0.3048)
			(stroke
				(width 0.1)
				(type default)
			)
			(layer "F.Fab")
		)
		(fp_line
			(start 0.67945 0.3048)
			(end 0.120396 0.3048)
			(stroke
				(width 0.1)
				(type default)
			)
			(layer "F.Fab")
		)
		(fp_line
			(start 0.120396 0.3048)
			(end 0.120396 0.2794)
			(stroke
				(width 0.1)
				(type default)
			)
			(layer "F.Fab")
		)
		(fp_line
			(start -0.12065 0.3048)
			(end -0.67945 0.3048)
			(stroke
				(width 0.1)
				(type default)
			)
			(layer "F.Fab")
		)
		(fp_line
			(start -0.67945 0.3048)
			(end -0.67945 -0.305054)
			(stroke
				(width 0.1)
				(type default)
			)
			(layer "F.Fab")
		)
		(pad "1" smd circle
			(at -0.40005 0 90)
			(size 0 0)
			(layers "F.Cu" "F.Mask" "F.Paste")
			(net "P12V_SSD2")
		)
		(pad "2" smd circle
			(at 0.40005 0 90)
			(size 0 0)
			(layers "F.Cu" "F.Mask" "F.Paste")
			(net "GND")
		)
	)
	(footprint ""
		(layer "F.Cu")
		(at 262.353298 -288.190432)
		(property "Reference" "L126"
			(at 0 0 0)
			(layer "F.SilkS")
			(hide yes)
			(effects
				(font
					(size 1.27 1.27)
				)
			)
		)
		(property "Value" ""
			(at 0 0 0)
			(layer "F.Fab")
			(effects
				(font
					(size 1.27 1.27)
				)
			)
		)
		(duplicate_pad_numbers_are_jumpers no)
		(fp_line
			(start -1.63576 -0.8128)
			(end -1.63576 0.8128)
			(stroke
				(width 0.1524)
				(type default)
			)
			(layer "F.SilkS")
		)
		(fp_line
			(start -1.63576 -0.8128)
			(end 1.63576 -0.8128)
			(stroke
				(width 0.1524)
				(type default)
			)
			(layer "F.SilkS")
		)
		(fp_line
			(start 1.63576 -0.8128)
			(end 1.63576 0.8128)
			(stroke
				(width 0.1524)
				(type default)
			)
			(layer "F.SilkS")
		)
		(fp_line
			(start 1.63576 0.8128)
			(end -1.63576 0.8128)
			(stroke
				(width 0.1524)
				(type default)
			)
			(layer "F.SilkS")
		)
		(fp_line
			(start -1.56083 -0.738632)
			(end -1.56083 0.7366)
			(stroke
				(width 0.1)
				(type default)
			)
			(layer "F.Fab")
		)
		(fp_line
			(start -1.56083 0.7366)
			(end -1.524 0.7366)
			(stroke
				(width 0.1)
				(type default)
			)
			(layer "F.Fab")
		)
		(fp_line
			(start -1.524 0.7366)
			(end 1.524 0.7366)
			(stroke
				(width 0.1)
				(type default)
			)
			(layer "F.Fab")
		)
		(fp_line
			(start 1.524 0.7366)
			(end 1.560576 0.7366)
			(stroke
				(width 0.1)
				(type default)
			)
			(layer "F.Fab")
		)
		(fp_line
			(start 1.560576 -0.738632)
			(end -1.56083 -0.738632)
			(stroke
				(width 0.1)
				(type default)
			)
			(layer "F.Fab")
		)
		(fp_line
			(start 1.560576 0.7366)
			(end 1.560576 -0.738632)
			(stroke
				(width 0.1)
				(type default)
			)
			(layer "F.Fab")
		)
		(pad "1" smd rect
			(at -0.94996 0 180)
			(size 1.1176 1.3716)
			(layers "F.Cu" "F.Mask" "F.Paste")
			(net "P1V8_PLL0_PEX2")
		)
		(pad "2" smd rect
			(at 0.94996 0 180)
			(size 1.1176 1.3716)
			(layers "F.Cu" "F.Mask" "F.Paste")
			(net "PCEPLL6_VDDA18_PEX2")
		)
	)
	(footprint ""
		(layer "F.Cu")
		(at 126.205488 -282.421584 -90)
		(property "Reference" "PC98"
			(at 0 0 270)
			(layer "F.SilkS")
			(hide yes)
			(effects
				(font
					(size 1.27 1.27)
				)
			)
		)
		(property "Value" ""
			(at 0 0 270)
			(layer "F.Fab")
			(effects
				(font
					(size 1.27 1.27)
				)
			)
		)
		(duplicate_pad_numbers_are_jumpers no)
		(fp_line
			(start -0.7874 0.4064)
			(end -0.7874 -0.4064)
			(stroke
				(width 0.1524)
				(type default)
			)
			(layer "F.SilkS")
		)
		(fp_line
			(start 0.7874 0.4064)
			(end -0.7874 0.4064)
			(stroke
				(width 0.1524)
				(type default)
			)
			(layer "F.SilkS")
		)
		(fp_line
			(start -0.7874 -0.4064)
			(end 0.7874 -0.4064)
			(stroke
				(width 0.1524)
				(type default)
			)
			(layer "F.SilkS")
		)
		(fp_line
			(start 0.7874 -0.4064)
			(end 0.7874 0.4064)
			(stroke
				(width 0.1524)
				(type default)
			)
			(layer "F.SilkS")
		)
		(fp_line
			(start -0.67945 0.3048)
			(end -0.67945 -0.305054)
			(stroke
				(width 0.1)
				(type default)
			)
			(layer "F.Fab")
		)
		(fp_line
			(start -0.12065 0.3048)
			(end -0.67945 0.3048)
			(stroke
				(width 0.1)
				(type default)
			)
			(layer "F.Fab")
		)
		(fp_line
			(start 0.120396 0.3048)
			(end 0.120396 0.2794)
			(stroke
				(width 0.1)
				(type default)
			)
			(layer "F.Fab")
		)
		(fp_line
			(start 0.67945 0.3048)
			(end 0.120396 0.3048)
			(stroke
				(width 0.1)
				(type default)
			)
			(layer "F.Fab")
		)
		(fp_line
			(start -0.12065 0.2794)
			(end -0.12065 0.3048)
			(stroke
				(width 0.1)
				(type default)
			)
			(layer "F.Fab")
		)
		(fp_line
			(start 0.120396 0.2794)
			(end -0.12065 0.2794)
			(stroke
				(width 0.1)
				(type default)
			)
			(layer "F.Fab")
		)
		(fp_line
			(start -0.12065 -0.2794)
			(end 0.12065 -0.2794)
			(stroke
				(width 0.1)
				(type default)
			)
			(layer "F.Fab")
		)
		(fp_line
			(start 0.12065 -0.2794)
			(end 0.12065 -0.3048)
			(stroke
				(width 0.1)
				(type default)
			)
			(layer "F.Fab")
		)
		(fp_line
			(start 0.12065 -0.3048)
			(end 0.67945 -0.3048)
			(stroke
				(width 0.1)
				(type default)
			)
			(layer "F.Fab")
		)
		(fp_line
			(start 0.67945 -0.3048)
			(end 0.67945 0.3048)
			(stroke
				(width 0.1)
				(type default)
			)
			(layer "F.Fab")
		)
		(fp_line
			(start -0.67945 -0.305054)
			(end -0.12065 -0.305054)
			(stroke
				(width 0.1)
				(type default)
			)
			(layer "F.Fab")
		)
		(fp_line
			(start -0.12065 -0.305054)
			(end -0.12065 -0.2794)
			(stroke
				(width 0.1)
				(type default)
			)
			(layer "F.Fab")
		)
		(pad "1" smd circle
			(at -0.40005 0 270)
			(size 0 0)
			(layers "F.Cu" "F.Mask" "F.Paste")
			(net "P0V8_PEX1_VCC1")
		)
		(pad "2" smd circle
			(at 0.40005 0 270)
			(size 0 0)
			(layers "F.Cu" "F.Mask" "F.Paste")
			(net "GND")
		)
	)
	(footprint ""
		(layer "F.Cu")
		(at 408.503882 -205.918308 -90)
		(property "Reference" "R6446"
			(at 0 0 270)
			(layer "F.SilkS")
			(hide yes)
			(effects
				(font
					(size 1.27 1.27)
				)
			)
		)
		(property "Value" ""
			(at 0 0 270)
			(layer "F.Fab")
			(effects
				(font
					(size 1.27 1.27)
				)
			)
		)
		(duplicate_pad_numbers_are_jumpers no)
		(fp_line
			(start -0.7874 0.4064)
			(end -0.7874 -0.4064)
			(stroke
				(width 0.1524)
				(type default)
			)
			(layer "F.SilkS")
		)
		(fp_line
			(start 0.7874 0.4064)
			(end -0.7874 0.4064)
			(stroke
				(width 0.1524)
				(type default)
			)
			(layer "F.SilkS")
		)
		(fp_line
			(start -0.7874 -0.4064)
			(end 0.7874 -0.4064)
			(stroke
				(width 0.1524)
				(type default)
			)
			(layer "F.SilkS")
		)
		(fp_line
			(start 0.7874 -0.4064)
			(end 0.7874 0.4064)
			(stroke
				(width 0.1524)
				(type default)
			)
			(layer "F.SilkS")
		)
		(fp_line
			(start -0.67945 0.3048)
			(end -0.67945 -0.305054)
			(stroke
				(width 0.1)
				(type default)
			)
			(layer "F.Fab")
		)
		(fp_line
			(start -0.12065 0.3048)
			(end -0.67945 0.3048)
			(stroke
				(width 0.1)
				(type default)
			)
			(layer "F.Fab")
		)
		(fp_line
			(start 0.120396 0.3048)
			(end 0.120396 0.2794)
			(stroke
				(width 0.1)
				(type default)
			)
			(layer "F.Fab")
		)
		(fp_line
			(start 0.67945 0.3048)
			(end 0.120396 0.3048)
			(stroke
				(width 0.1)
				(type default)
			)
			(layer "F.Fab")
		)
		(fp_line
			(start -0.12065 0.2794)
			(end -0.12065 0.3048)
			(stroke
				(width 0.1)
				(type default)
			)
			(layer "F.Fab")
		)
		(fp_line
			(start 0.120396 0.2794)
			(end -0.12065 0.2794)
			(stroke
				(width 0.1)
				(type default)
			)
			(layer "F.Fab")
		)
		(fp_line
			(start -0.12065 -0.2794)
			(end 0.12065 -0.2794)
			(stroke
				(width 0.1)
				(type default)
			)
			(layer "F.Fab")
		)
		(fp_line
			(start 0.12065 -0.2794)
			(end 0.12065 -0.3048)
			(stroke
				(width 0.1)
				(type default)
			)
			(layer "F.Fab")
		)
		(fp_line
			(start 0.12065 -0.3048)
			(end 0.67945 -0.3048)
			(stroke
				(width 0.1)
				(type default)
			)
			(layer "F.Fab")
		)
		(fp_line
			(start 0.67945 -0.3048)
			(end 0.67945 0.3048)
			(stroke
				(width 0.1)
				(type default)
			)
			(layer "F.Fab")
		)
		(fp_line
			(start -0.67945 -0.305054)
			(end -0.12065 -0.305054)
			(stroke
				(width 0.1)
				(type default)
			)
			(layer "F.Fab")
		)
		(fp_line
			(start -0.12065 -0.305054)
			(end -0.12065 -0.2794)
			(stroke
				(width 0.1)
				(type default)
			)
			(layer "F.Fab")
		)
		(pad "1" smd circle
			(at -0.40005 0 270)
			(size 0 0)
			(layers "F.Cu" "F.Mask" "F.Paste")
			(net "FPGA_PEX3_MODE_SEL1_ISO")
		)
		(pad "2" smd circle
			(at 0.40005 0 270)
			(size 0 0)
			(layers "F.Cu" "F.Mask" "F.Paste")
			(net "PEX3_MODE_SEL1")
		)
	)
	(footprint ""
		(layer "F.Cu")
		(at 25.524968 -350.098614 90)
		(property "Reference" "C185"
			(at 0 0 90)
			(layer "F.SilkS")
			(hide yes)
			(effects
				(font
					(size 1.27 1.27)
				)
			)
		)
		(property "Value" ""
			(at 0 0 90)
			(layer "F.Fab")
			(effects
				(font
					(size 1.27 1.27)
				)
			)
		)
		(duplicate_pad_numbers_are_jumpers no)
		(fp_line
			(start 0.299974 -0.150114)
			(end 0.299974 0.150114)
			(stroke
				(width 0.1)
				(type default)
			)
			(layer "F.Fab")
		)
		(fp_line
			(start -0.299974 -0.150114)
			(end 0.299974 -0.150114)
			(stroke
				(width 0.1)
				(type default)
			)
			(layer "F.Fab")
		)
		(fp_line
			(start 0.299974 0.150114)
			(end -0.299974 0.150114)
			(stroke
				(width 0.1)
				(type default)
			)
			(layer "F.Fab")
		)
		(fp_line
			(start -0.299974 0.150114)
			(end -0.299974 -0.150114)
			(stroke
				(width 0.1)
				(type default)
			)
			(layer "F.Fab")
		)
		(pad "1" smd rect
			(at -0.2667 0 90)
			(size 0.3048 0.381)
			(layers "F.Cu" "F.Mask" "F.Paste")
			(net "P5E_PEX0_STN7_TX_DP<115>")
		)
		(pad "2" smd rect
			(at 0.2667 0 90)
			(size 0.3048 0.381)
			(layers "F.Cu" "F.Mask" "F.Paste")
			(net "P5E_PEX0_STN7_TX_C_DP<115>")
		)
	)
	(footprint ""
		(layer "F.Cu")
		(at 379.59411 -34.248852)
		(property "Reference" "R5696"
			(at 0 0 0)
			(layer "F.SilkS")
			(hide yes)
			(effects
				(font
					(size 1.27 1.27)
				)
			)
		)
		(property "Value" ""
			(at 0 0 0)
			(layer "F.Fab")
			(effects
				(font
					(size 1.27 1.27)
				)
			)
		)
		(duplicate_pad_numbers_are_jumpers no)
		(fp_line
			(start -0.7874 -0.4064)
			(end 0.7874 -0.4064)
			(stroke
				(width 0.1524)
				(type default)
			)
			(layer "F.SilkS")
		)
		(fp_line
			(start -0.7874 0.4064)
			(end -0.7874 -0.4064)
			(stroke
				(width 0.1524)
				(type default)
			)
			(layer "F.SilkS")
		)
		(fp_line
			(start 0.7874 -0.4064)
			(end 0.7874 0.4064)
			(stroke
				(width 0.1524)
				(type default)
			)
			(layer "F.SilkS")
		)
		(fp_line
			(start 0.7874 0.4064)
			(end -0.7874 0.4064)
			(stroke
				(width 0.1524)
				(type default)
			)
			(layer "F.SilkS")
		)
		(fp_line
			(start -0.67945 -0.305054)
			(end -0.12065 -0.305054)
			(stroke
				(width 0.1)
				(type default)
			)
			(layer "F.Fab")
		)
		(fp_line
			(start -0.67945 0.3048)
			(end -0.67945 -0.305054)
			(stroke
				(width 0.1)
				(type default)
			)
			(layer "F.Fab")
		)
		(fp_line
			(start -0.12065 -0.305054)
			(end -0.12065 -0.2794)
			(stroke
				(width 0.1)
				(type default)
			)
			(layer "F.Fab")
		)
		(fp_line
			(start -0.12065 -0.2794)
			(end 0.12065 -0.2794)
			(stroke
				(width 0.1)
				(type default)
			)
			(layer "F.Fab")
		)
		(fp_line
			(start -0.12065 0.2794)
			(end -0.12065 0.3048)
			(stroke
				(width 0.1)
				(type default)
			)
			(layer "F.Fab")
		)
		(fp_line
			(start -0.12065 0.3048)
			(end -0.67945 0.3048)
			(stroke
				(width 0.1)
				(type default)
			)
			(layer "F.Fab")
		)
		(fp_line
			(start 0.120396 0.2794)
			(end -0.12065 0.2794)
			(stroke
				(width 0.1)
				(type default)
			)
			(layer "F.Fab")
		)
		(fp_line
			(start 0.120396 0.3048)
			(end 0.120396 0.2794)
			(stroke
				(width 0.1)
				(type default)
			)
			(layer "F.Fab")
		)
		(fp_line
			(start 0.12065 -0.3048)
			(end 0.67945 -0.3048)
			(stroke
				(width 0.1)
				(type default)
			)
			(layer "F.Fab")
		)
		(fp_line
			(start 0.12065 -0.2794)
			(end 0.12065 -0.3048)
			(stroke
				(width 0.1)
				(type default)
			)
			(layer "F.Fab")
		)
		(fp_line
			(start 0.67945 -0.3048)
			(end 0.67945 0.3048)
			(stroke
				(width 0.1)
				(type default)
			)
			(layer "F.Fab")
		)
		(fp_line
			(start 0.67945 0.3048)
			(end 0.120396 0.3048)
			(stroke
				(width 0.1)
				(type default)
			)
			(layer "F.Fab")
		)
		(pad "1" smd circle
			(at -0.40005 0)
			(size 0 0)
			(layers "F.Cu" "F.Mask" "F.Paste")
			(net "RST_SMB_SSD13_ISO_N")
		)
		(pad "2" smd circle
			(at 0.40005 0)
			(size 0 0)
			(layers "F.Cu" "F.Mask" "F.Paste")
			(net "P3V3_SSD13")
		)
	)
	(footprint ""
		(layer "F.Cu")
		(at 348.477586 -255.82372 180)
		(property "Reference" "PC126"
			(at 0 0 180)
			(layer "F.SilkS")
			(hide yes)
			(effects
				(font
					(size 1.27 1.27)
				)
			)
		)
		(property "Value" ""
			(at 0 0 180)
			(layer "F.Fab")
			(effects
				(font
					(size 1.27 1.27)
				)
			)
		)
		(duplicate_pad_numbers_are_jumpers no)
		(fp_line
			(start 0.7874 0.4064)
			(end -0.7874 0.4064)
			(stroke
				(width 0.1524)
				(type default)
			)
			(layer "F.SilkS")
		)
		(fp_line
			(start 0.7874 -0.4064)
			(end 0.7874 0.4064)
			(stroke
				(width 0.1524)
				(type default)
			)
			(layer "F.SilkS")
		)
		(fp_line
			(start -0.7874 0.4064)
			(end -0.7874 -0.4064)
			(stroke
				(width 0.1524)
				(type default)
			)
			(layer "F.SilkS")
		)
		(fp_line
			(start -0.7874 -0.4064)
			(end 0.7874 -0.4064)
			(stroke
				(width 0.1524)
				(type default)
			)
			(layer "F.SilkS")
		)
		(fp_line
			(start 0.67945 0.3048)
			(end 0.120396 0.3048)
			(stroke
				(width 0.1)
				(type default)
			)
			(layer "F.Fab")
		)
		(fp_line
			(start 0.67945 -0.3048)
			(end 0.67945 0.3048)
			(stroke
				(width 0.1)
				(type default)
			)
			(layer "F.Fab")
		)
		(fp_line
			(start 0.12065 -0.2794)
			(end 0.12065 -0.3048)
			(stroke
				(width 0.1)
				(type default)
			)
			(layer "F.Fab")
		)
		(fp_line
			(start 0.12065 -0.3048)
			(end 0.67945 -0.3048)
			(stroke
				(width 0.1)
				(type default)
			)
			(layer "F.Fab")
		)
		(fp_line
			(start 0.120396 0.3048)
			(end 0.120396 0.2794)
			(stroke
				(width 0.1)
				(type default)
			)
			(layer "F.Fab")
		)
		(fp_line
			(start 0.120396 0.2794)
			(end -0.12065 0.2794)
			(stroke
				(width 0.1)
				(type default)
			)
			(layer "F.Fab")
		)
		(fp_line
			(start -0.12065 0.3048)
			(end -0.67945 0.3048)
			(stroke
				(width 0.1)
				(type default)
			)
			(layer "F.Fab")
		)
		(fp_line
			(start -0.12065 0.2794)
			(end -0.12065 0.3048)
			(stroke
				(width 0.1)
				(type default)
			)
			(layer "F.Fab")
		)
		(fp_line
			(start -0.12065 -0.2794)
			(end 0.12065 -0.2794)
			(stroke
				(width 0.1)
				(type default)
			)
			(layer "F.Fab")
		)
		(fp_line
			(start -0.12065 -0.305054)
			(end -0.12065 -0.2794)
			(stroke
				(width 0.1)
				(type default)
			)
			(layer "F.Fab")
		)
		(fp_line
			(start -0.67945 0.3048)
			(end -0.67945 -0.305054)
			(stroke
				(width 0.1)
				(type default)
			)
			(layer "F.Fab")
		)
		(fp_line
			(start -0.67945 -0.305054)
			(end -0.12065 -0.305054)
			(stroke
				(width 0.1)
				(type default)
			)
			(layer "F.Fab")
		)
		(pad "1" smd circle
			(at -0.40005 0 180)
			(size 0 0)
			(layers "F.Cu" "F.Mask" "F.Paste")
			(net "P0V8_PEX2_VDD")
		)
		(pad "2" smd circle
			(at 0.40005 0 180)
			(size 0 0)
			(layers "F.Cu" "F.Mask" "F.Paste")
			(net "GND")
		)
	)
	(footprint ""
		(layer "F.Cu")
		(at 323.917818 -219.579698 180)
		(property "Reference" "R2983"
			(at 0 0 180)
			(layer "F.SilkS")
			(hide yes)
			(effects
				(font
					(size 1.27 1.27)
				)
			)
		)
		(property "Value" ""
			(at 0 0 180)
			(layer "F.Fab")
			(effects
				(font
					(size 1.27 1.27)
				)
			)
		)
		(duplicate_pad_numbers_are_jumpers no)
		(fp_line
			(start 0.7874 0.4064)
			(end -0.7874 0.4064)
			(stroke
				(width 0.1524)
				(type default)
			)
			(layer "F.SilkS")
		)
		(fp_line
			(start 0.7874 -0.4064)
			(end 0.7874 0.4064)
			(stroke
				(width 0.1524)
				(type default)
			)
			(layer "F.SilkS")
		)
		(fp_line
			(start -0.7874 0.4064)
			(end -0.7874 -0.4064)
			(stroke
				(width 0.1524)
				(type default)
			)
			(layer "F.SilkS")
		)
		(fp_line
			(start -0.7874 -0.4064)
			(end 0.7874 -0.4064)
			(stroke
				(width 0.1524)
				(type default)
			)
			(layer "F.SilkS")
		)
		(fp_line
			(start 0.67945 0.3048)
			(end 0.120396 0.3048)
			(stroke
				(width 0.1)
				(type default)
			)
			(layer "F.Fab")
		)
		(fp_line
			(start 0.67945 -0.3048)
			(end 0.67945 0.3048)
			(stroke
				(width 0.1)
				(type default)
			)
			(layer "F.Fab")
		)
		(fp_line
			(start 0.12065 -0.2794)
			(end 0.12065 -0.3048)
			(stroke
				(width 0.1)
				(type default)
			)
			(layer "F.Fab")
		)
		(fp_line
			(start 0.12065 -0.3048)
			(end 0.67945 -0.3048)
			(stroke
				(width 0.1)
				(type default)
			)
			(layer "F.Fab")
		)
		(fp_line
			(start 0.120396 0.3048)
			(end 0.120396 0.2794)
			(stroke
				(width 0.1)
				(type default)
			)
			(layer "F.Fab")
		)
		(fp_line
			(start 0.120396 0.2794)
			(end -0.12065 0.2794)
			(stroke
				(width 0.1)
				(type default)
			)
			(layer "F.Fab")
		)
		(fp_line
			(start -0.12065 0.3048)
			(end -0.67945 0.3048)
			(stroke
				(width 0.1)
				(type default)
			)
			(layer "F.Fab")
		)
		(fp_line
			(start -0.12065 0.2794)
			(end -0.12065 0.3048)
			(stroke
				(width 0.1)
				(type default)
			)
			(layer "F.Fab")
		)
		(fp_line
			(start -0.12065 -0.2794)
			(end 0.12065 -0.2794)
			(stroke
				(width 0.1)
				(type default)
			)
			(layer "F.Fab")
		)
		(fp_line
			(start -0.12065 -0.305054)
			(end -0.12065 -0.2794)
			(stroke
				(width 0.1)
				(type default)
			)
			(layer "F.Fab")
		)
		(fp_line
			(start -0.67945 0.3048)
			(end -0.67945 -0.305054)
			(stroke
				(width 0.1)
				(type default)
			)
			(layer "F.Fab")
		)
		(fp_line
			(start -0.67945 -0.305054)
			(end -0.12065 -0.305054)
			(stroke
				(width 0.1)
				(type default)
			)
			(layer "F.Fab")
		)
		(pad "1" smd circle
			(at -0.40005 0 180)
			(size 0 0)
			(layers "F.Cu" "F.Mask" "F.Paste")
			(net "LED_POSTCODE_5")
		)
		(pad "2" smd circle
			(at 0.40005 0 180)
			(size 0 0)
			(layers "F.Cu" "F.Mask" "F.Paste")
			(net "LED_POSTCODE_R_5")
		)
	)
	(footprint ""
		(layer "F.Cu")
		(at 154.707844 -158.3944 180)
		(property "Reference" "R113"
			(at 0 0 180)
			(layer "F.SilkS")
			(hide yes)
			(effects
				(font
					(size 1.27 1.27)
				)
			)
		)
		(property "Value" ""
			(at 0 0 180)
			(layer "F.Fab")
			(effects
				(font
					(size 1.27 1.27)
				)
			)
		)
		(duplicate_pad_numbers_are_jumpers no)
		(fp_line
			(start 0.7874 0.4064)
			(end -0.7874 0.4064)
			(stroke
				(width 0.1524)
				(type default)
			)
			(layer "F.SilkS")
		)
		(fp_line
			(start 0.7874 -0.4064)
			(end 0.7874 0.4064)
			(stroke
				(width 0.1524)
				(type default)
			)
			(layer "F.SilkS")
		)
		(fp_line
			(start -0.7874 0.4064)
			(end -0.7874 -0.4064)
			(stroke
				(width 0.1524)
				(type default)
			)
			(layer "F.SilkS")
		)
		(fp_line
			(start -0.7874 -0.4064)
			(end 0.7874 -0.4064)
			(stroke
				(width 0.1524)
				(type default)
			)
			(layer "F.SilkS")
		)
		(fp_line
			(start 0.67945 0.3048)
			(end 0.120396 0.3048)
			(stroke
				(width 0.1)
				(type default)
			)
			(layer "F.Fab")
		)
		(fp_line
			(start 0.67945 -0.3048)
			(end 0.67945 0.3048)
			(stroke
				(width 0.1)
				(type default)
			)
			(layer "F.Fab")
		)
		(fp_line
			(start 0.12065 -0.2794)
			(end 0.12065 -0.3048)
			(stroke
				(width 0.1)
				(type default)
			)
			(layer "F.Fab")
		)
		(fp_line
			(start 0.12065 -0.3048)
			(end 0.67945 -0.3048)
			(stroke
				(width 0.1)
				(type default)
			)
			(layer "F.Fab")
		)
		(fp_line
			(start 0.120396 0.3048)
			(end 0.120396 0.2794)
			(stroke
				(width 0.1)
				(type default)
			)
			(layer "F.Fab")
		)
		(fp_line
			(start 0.120396 0.2794)
			(end -0.12065 0.2794)
			(stroke
				(width 0.1)
				(type default)
			)
			(layer "F.Fab")
		)
		(fp_line
			(start -0.12065 0.3048)
			(end -0.67945 0.3048)
			(stroke
				(width 0.1)
				(type default)
			)
			(layer "F.Fab")
		)
		(fp_line
			(start -0.12065 0.2794)
			(end -0.12065 0.3048)
			(stroke
				(width 0.1)
				(type default)
			)
			(layer "F.Fab")
		)
		(fp_line
			(start -0.12065 -0.2794)
			(end 0.12065 -0.2794)
			(stroke
				(width 0.1)
				(type default)
			)
			(layer "F.Fab")
		)
		(fp_line
			(start -0.12065 -0.305054)
			(end -0.12065 -0.2794)
			(stroke
				(width 0.1)
				(type default)
			)
			(layer "F.Fab")
		)
		(fp_line
			(start -0.67945 0.3048)
			(end -0.67945 -0.305054)
			(stroke
				(width 0.1)
				(type default)
			)
			(layer "F.Fab")
		)
		(fp_line
			(start -0.67945 -0.305054)
			(end -0.12065 -0.305054)
			(stroke
				(width 0.1)
				(type default)
			)
			(layer "F.Fab")
		)
		(pad "1" smd circle
			(at -0.40005 0 180)
			(size 0 0)
			(layers "F.Cu" "F.Mask" "F.Paste")
			(net "NIC2_LD_N")
		)
		(pad "2" smd circle
			(at 0.40005 0 180)
			(size 0 0)
			(layers "F.Cu" "F.Mask" "F.Paste")
			(net "P3V3_NIC2")
		)
	)
	(footprint ""
		(layer "F.Cu")
		(at 304.634392 -34.546286 180)
		(property "Reference" "C503"
			(at 0 0 180)
			(layer "F.SilkS")
			(hide yes)
			(effects
				(font
					(size 1.27 1.27)
				)
			)
		)
		(property "Value" ""
			(at 0 0 180)
			(layer "F.Fab")
			(effects
				(font
					(size 1.27 1.27)
				)
			)
		)
		(duplicate_pad_numbers_are_jumpers no)
		(fp_line
			(start 0.299974 0.150114)
			(end -0.299974 0.150114)
			(stroke
				(width 0.1)
				(type default)
			)
			(layer "F.Fab")
		)
		(fp_line
			(start 0.299974 -0.150114)
			(end 0.299974 0.150114)
			(stroke
				(width 0.1)
				(type default)
			)
			(layer "F.Fab")
		)
		(fp_line
			(start -0.299974 0.150114)
			(end -0.299974 -0.150114)
			(stroke
				(width 0.1)
				(type default)
			)
			(layer "F.Fab")
		)
		(fp_line
			(start -0.299974 -0.150114)
			(end 0.299974 -0.150114)
			(stroke
				(width 0.1)
				(type default)
			)
			(layer "F.Fab")
		)
		(pad "1" smd rect
			(at -0.2667 0 180)
			(size 0.3048 0.381)
			(layers "F.Cu" "F.Mask" "F.Paste")
			(net "P5E_PEX2_STN2_TX_DP<39>")
		)
		(pad "2" smd rect
			(at 0.2667 0 180)
			(size 0.3048 0.381)
			(layers "F.Cu" "F.Mask" "F.Paste")
			(net "P5E_PEX2_STN2_TX_C_DP<39>")
		)
	)
	(footprint ""
		(layer "F.Cu")
		(at 382.511046 -61.386974)
		(property "Reference" "R4503"
			(at 0 0 0)
			(layer "F.SilkS")
			(hide yes)
			(effects
				(font
					(size 1.27 1.27)
				)
			)
		)
		(property "Value" ""
			(at 0 0 0)
			(layer "F.Fab")
			(effects
				(font
					(size 1.27 1.27)
				)
			)
		)
		(duplicate_pad_numbers_are_jumpers no)
		(fp_line
			(start -0.7874 -0.4064)
			(end 0.7874 -0.4064)
			(stroke
				(width 0.1524)
				(type default)
			)
			(layer "F.SilkS")
		)
		(fp_line
			(start -0.7874 0.4064)
			(end -0.7874 -0.4064)
			(stroke
				(width 0.1524)
				(type default)
			)
			(layer "F.SilkS")
		)
		(fp_line
			(start 0.7874 -0.4064)
			(end 0.7874 0.4064)
			(stroke
				(width 0.1524)
				(type default)
			)
			(layer "F.SilkS")
		)
		(fp_line
			(start 0.7874 0.4064)
			(end -0.7874 0.4064)
			(stroke
				(width 0.1524)
				(type default)
			)
			(layer "F.SilkS")
		)
		(fp_line
			(start -0.67945 -0.305054)
			(end -0.12065 -0.305054)
			(stroke
				(width 0.1)
				(type default)
			)
			(layer "F.Fab")
		)
		(fp_line
			(start -0.67945 0.3048)
			(end -0.67945 -0.305054)
			(stroke
				(width 0.1)
				(type default)
			)
			(layer "F.Fab")
		)
		(fp_line
			(start -0.12065 -0.305054)
			(end -0.12065 -0.2794)
			(stroke
				(width 0.1)
				(type default)
			)
			(layer "F.Fab")
		)
		(fp_line
			(start -0.12065 -0.2794)
			(end 0.12065 -0.2794)
			(stroke
				(width 0.1)
				(type default)
			)
			(layer "F.Fab")
		)
		(fp_line
			(start -0.12065 0.2794)
			(end -0.12065 0.3048)
			(stroke
				(width 0.1)
				(type default)
			)
			(layer "F.Fab")
		)
		(fp_line
			(start -0.12065 0.3048)
			(end -0.67945 0.3048)
			(stroke
				(width 0.1)
				(type default)
			)
			(layer "F.Fab")
		)
		(fp_line
			(start 0.120396 0.2794)
			(end -0.12065 0.2794)
			(stroke
				(width 0.1)
				(type default)
			)
			(layer "F.Fab")
		)
		(fp_line
			(start 0.120396 0.3048)
			(end 0.120396 0.2794)
			(stroke
				(width 0.1)
				(type default)
			)
			(layer "F.Fab")
		)
		(fp_line
			(start 0.12065 -0.3048)
			(end 0.67945 -0.3048)
			(stroke
				(width 0.1)
				(type default)
			)
			(layer "F.Fab")
		)
		(fp_line
			(start 0.12065 -0.2794)
			(end 0.12065 -0.3048)
			(stroke
				(width 0.1)
				(type default)
			)
			(layer "F.Fab")
		)
		(fp_line
			(start 0.67945 -0.3048)
			(end 0.67945 0.3048)
			(stroke
				(width 0.1)
				(type default)
			)
			(layer "F.Fab")
		)
		(fp_line
			(start 0.67945 0.3048)
			(end 0.120396 0.3048)
			(stroke
				(width 0.1)
				(type default)
			)
			(layer "F.Fab")
		)
		(pad "1" smd circle
			(at -0.40005 0)
			(size 0 0)
			(layers "F.Cu" "F.Mask" "F.Paste")
			(net "PWRGD_P3V3_SSD13")
		)
		(pad "2" smd circle
			(at 0.40005 0)
			(size 0 0)
			(layers "F.Cu" "F.Mask" "F.Paste")
			(net "PWRGD_P3V3_SSD13_R")
		)
	)
	(footprint ""
		(layer "F.Cu")
		(at 147.047458 -36.686998 90)
		(property "Reference" "C3662"
			(at 0 0 90)
			(layer "F.SilkS")
			(hide yes)
			(effects
				(font
					(size 1.27 1.27)
				)
			)
		)
		(property "Value" ""
			(at 0 0 90)
			(layer "F.Fab")
			(effects
				(font
					(size 1.27 1.27)
				)
			)
		)
		(duplicate_pad_numbers_are_jumpers no)
		(fp_line
			(start 0.7874 -0.4064)
			(end 0.7874 0.4064)
			(stroke
				(width 0.1524)
				(type default)
			)
			(layer "F.SilkS")
		)
		(fp_line
			(start -0.7874 -0.4064)
			(end 0.7874 -0.4064)
			(stroke
				(width 0.1524)
				(type default)
			)
			(layer "F.SilkS")
		)
		(fp_line
			(start 0.7874 0.4064)
			(end -0.7874 0.4064)
			(stroke
				(width 0.1524)
				(type default)
			)
			(layer "F.SilkS")
		)
		(fp_line
			(start -0.7874 0.4064)
			(end -0.7874 -0.4064)
			(stroke
				(width 0.1524)
				(type default)
			)
			(layer "F.SilkS")
		)
		(fp_line
			(start -0.12065 -0.305054)
			(end -0.12065 -0.2794)
			(stroke
				(width 0.1)
				(type default)
			)
			(layer "F.Fab")
		)
		(fp_line
			(start -0.67945 -0.305054)
			(end -0.12065 -0.305054)
			(stroke
				(width 0.1)
				(type default)
			)
			(layer "F.Fab")
		)
		(fp_line
			(start 0.67945 -0.3048)
			(end 0.67945 0.3048)
			(stroke
				(width 0.1)
				(type default)
			)
			(layer "F.Fab")
		)
		(fp_line
			(start 0.12065 -0.3048)
			(end 0.67945 -0.3048)
			(stroke
				(width 0.1)
				(type default)
			)
			(layer "F.Fab")
		)
		(fp_line
			(start 0.12065 -0.2794)
			(end 0.12065 -0.3048)
			(stroke
				(width 0.1)
				(type default)
			)
			(layer "F.Fab")
		)
		(fp_line
			(start -0.12065 -0.2794)
			(end 0.12065 -0.2794)
			(stroke
				(width 0.1)
				(type default)
			)
			(layer "F.Fab")
		)
		(fp_line
			(start 0.120396 0.2794)
			(end -0.12065 0.2794)
			(stroke
				(width 0.1)
				(type default)
			)
			(layer "F.Fab")
		)
		(fp_line
			(start -0.12065 0.2794)
			(end -0.12065 0.3048)
			(stroke
				(width 0.1)
				(type default)
			)
			(layer "F.Fab")
		)
		(fp_line
			(start 0.67945 0.3048)
			(end 0.120396 0.3048)
			(stroke
				(width 0.1)
				(type default)
			)
			(layer "F.Fab")
		)
		(fp_line
			(start 0.120396 0.3048)
			(end 0.120396 0.2794)
			(stroke
				(width 0.1)
				(type default)
			)
			(layer "F.Fab")
		)
		(fp_line
			(start -0.12065 0.3048)
			(end -0.67945 0.3048)
			(stroke
				(width 0.1)
				(type default)
			)
			(layer "F.Fab")
		)
		(fp_line
			(start -0.67945 0.3048)
			(end -0.67945 -0.305054)
			(stroke
				(width 0.1)
				(type default)
			)
			(layer "F.Fab")
		)
		(pad "1" smd circle
			(at -0.40005 0 90)
			(size 0 0)
			(layers "F.Cu" "F.Mask" "F.Paste")
			(net "P3V3_AUX")
		)
		(pad "2" smd circle
			(at 0.40005 0 90)
			(size 0 0)
			(layers "F.Cu" "F.Mask" "F.Paste")
			(net "GND")
		)
	)
	(footprint ""
		(layer "F.Cu")
		(at 193.162428 -22.955504 -90)
		(property "Reference" "C2723"
			(at 0 0 270)
			(layer "F.SilkS")
			(hide yes)
			(effects
				(font
					(size 1.27 1.27)
				)
			)
		)
		(property "Value" ""
			(at 0 0 270)
			(layer "F.Fab")
			(effects
				(font
					(size 1.27 1.27)
				)
			)
		)
		(duplicate_pad_numbers_are_jumpers no)
		(fp_line
			(start -0.7874 0.4064)
			(end -0.7874 -0.4064)
			(stroke
				(width 0.1524)
				(type default)
			)
			(layer "F.SilkS")
		)
		(fp_line
			(start 0.7874 0.4064)
			(end -0.7874 0.4064)
			(stroke
				(width 0.1524)
				(type default)
			)
			(layer "F.SilkS")
		)
		(fp_line
			(start -0.7874 -0.4064)
			(end 0.7874 -0.4064)
			(stroke
				(width 0.1524)
				(type default)
			)
			(layer "F.SilkS")
		)
		(fp_line
			(start 0.7874 -0.4064)
			(end 0.7874 0.4064)
			(stroke
				(width 0.1524)
				(type default)
			)
			(layer "F.SilkS")
		)
		(fp_line
			(start -0.67945 0.3048)
			(end -0.67945 -0.305054)
			(stroke
				(width 0.1)
				(type default)
			)
			(layer "F.Fab")
		)
		(fp_line
			(start -0.12065 0.3048)
			(end -0.67945 0.3048)
			(stroke
				(width 0.1)
				(type default)
			)
			(layer "F.Fab")
		)
		(fp_line
			(start 0.120396 0.3048)
			(end 0.120396 0.2794)
			(stroke
				(width 0.1)
				(type default)
			)
			(layer "F.Fab")
		)
		(fp_line
			(start 0.67945 0.3048)
			(end 0.120396 0.3048)
			(stroke
				(width 0.1)
				(type default)
			)
			(layer "F.Fab")
		)
		(fp_line
			(start -0.12065 0.2794)
			(end -0.12065 0.3048)
			(stroke
				(width 0.1)
				(type default)
			)
			(layer "F.Fab")
		)
		(fp_line
			(start 0.120396 0.2794)
			(end -0.12065 0.2794)
			(stroke
				(width 0.1)
				(type default)
			)
			(layer "F.Fab")
		)
		(fp_line
			(start -0.12065 -0.2794)
			(end 0.12065 -0.2794)
			(stroke
				(width 0.1)
				(type default)
			)
			(layer "F.Fab")
		)
		(fp_line
			(start 0.12065 -0.2794)
			(end 0.12065 -0.3048)
			(stroke
				(width 0.1)
				(type default)
			)
			(layer "F.Fab")
		)
		(fp_line
			(start 0.12065 -0.3048)
			(end 0.67945 -0.3048)
			(stroke
				(width 0.1)
				(type default)
			)
			(layer "F.Fab")
		)
		(fp_line
			(start 0.67945 -0.3048)
			(end 0.67945 0.3048)
			(stroke
				(width 0.1)
				(type default)
			)
			(layer "F.Fab")
		)
		(fp_line
			(start -0.67945 -0.305054)
			(end -0.12065 -0.305054)
			(stroke
				(width 0.1)
				(type default)
			)
			(layer "F.Fab")
		)
		(fp_line
			(start -0.12065 -0.305054)
			(end -0.12065 -0.2794)
			(stroke
				(width 0.1)
				(type default)
			)
			(layer "F.Fab")
		)
		(pad "1" smd circle
			(at -0.40005 0 270)
			(size 0 0)
			(layers "F.Cu" "F.Mask" "F.Paste")
			(net "GND")
		)
		(pad "2" smd circle
			(at 0.40005 0 270)
			(size 0 0)
			(layers "F.Cu" "F.Mask" "F.Paste")
			(net "P3V3_AUX")
		)
	)
	(footprint ""
		(layer "F.Cu")
		(at 198.76135 -135.28675 180)
		(property "Reference" "C229"
			(at 0 0 180)
			(layer "F.SilkS")
			(hide yes)
			(effects
				(font
					(size 1.27 1.27)
				)
			)
		)
		(property "Value" ""
			(at 0 0 180)
			(layer "F.Fab")
			(effects
				(font
					(size 1.27 1.27)
				)
			)
		)
		(duplicate_pad_numbers_are_jumpers no)
		(fp_line
			(start 0.299974 0.150114)
			(end -0.299974 0.150114)
			(stroke
				(width 0.1)
				(type default)
			)
			(layer "F.Fab")
		)
		(fp_line
			(start 0.299974 -0.150114)
			(end 0.299974 0.150114)
			(stroke
				(width 0.1)
				(type default)
			)
			(layer "F.Fab")
		)
		(fp_line
			(start -0.299974 0.150114)
			(end -0.299974 -0.150114)
			(stroke
				(width 0.1)
				(type default)
			)
			(layer "F.Fab")
		)
		(fp_line
			(start -0.299974 -0.150114)
			(end 0.299974 -0.150114)
			(stroke
				(width 0.1)
				(type default)
			)
			(layer "F.Fab")
		)
		(pad "1" smd rect
			(at -0.2667 0 180)
			(size 0.3048 0.381)
			(layers "F.Cu" "F.Mask" "F.Paste")
			(net "P5E_PEX1_STN0_TX_DN<7>")
		)
		(pad "2" smd rect
			(at 0.2667 0 180)
			(size 0.3048 0.381)
			(layers "F.Cu" "F.Mask" "F.Paste")
			(net "P5E_PEX1_STN0_TX_C_DN<7>")
		)
	)
	(footprint ""
		(layer "F.Cu")
		(at 357.367586 -262.17372 180)
		(property "Reference" "PR126"
			(at 0 0 180)
			(layer "F.SilkS")
			(hide yes)
			(effects
				(font
					(size 1.27 1.27)
				)
			)
		)
		(property "Value" ""
			(at 0 0 180)
			(layer "F.Fab")
			(effects
				(font
					(size 1.27 1.27)
				)
			)
		)
		(duplicate_pad_numbers_are_jumpers no)
		(fp_line
			(start 0.7874 0.4064)
			(end -0.7874 0.4064)
			(stroke
				(width 0.1524)
				(type default)
			)
			(layer "F.SilkS")
		)
		(fp_line
			(start 0.7874 -0.4064)
			(end 0.7874 0.4064)
			(stroke
				(width 0.1524)
				(type default)
			)
			(layer "F.SilkS")
		)
		(fp_line
			(start -0.7874 0.4064)
			(end -0.7874 -0.4064)
			(stroke
				(width 0.1524)
				(type default)
			)
			(layer "F.SilkS")
		)
		(fp_line
			(start -0.7874 -0.4064)
			(end 0.7874 -0.4064)
			(stroke
				(width 0.1524)
				(type default)
			)
			(layer "F.SilkS")
		)
		(fp_line
			(start 0.67945 0.3048)
			(end 0.120396 0.3048)
			(stroke
				(width 0.1)
				(type default)
			)
			(layer "F.Fab")
		)
		(fp_line
			(start 0.67945 -0.3048)
			(end 0.67945 0.3048)
			(stroke
				(width 0.1)
				(type default)
			)
			(layer "F.Fab")
		)
		(fp_line
			(start 0.12065 -0.2794)
			(end 0.12065 -0.3048)
			(stroke
				(width 0.1)
				(type default)
			)
			(layer "F.Fab")
		)
		(fp_line
			(start 0.12065 -0.3048)
			(end 0.67945 -0.3048)
			(stroke
				(width 0.1)
				(type default)
			)
			(layer "F.Fab")
		)
		(fp_line
			(start 0.120396 0.3048)
			(end 0.120396 0.2794)
			(stroke
				(width 0.1)
				(type default)
			)
			(layer "F.Fab")
		)
		(fp_line
			(start 0.120396 0.2794)
			(end -0.12065 0.2794)
			(stroke
				(width 0.1)
				(type default)
			)
			(layer "F.Fab")
		)
		(fp_line
			(start -0.12065 0.3048)
			(end -0.67945 0.3048)
			(stroke
				(width 0.1)
				(type default)
			)
			(layer "F.Fab")
		)
		(fp_line
			(start -0.12065 0.2794)
			(end -0.12065 0.3048)
			(stroke
				(width 0.1)
				(type default)
			)
			(layer "F.Fab")
		)
		(fp_line
			(start -0.12065 -0.2794)
			(end 0.12065 -0.2794)
			(stroke
				(width 0.1)
				(type default)
			)
			(layer "F.Fab")
		)
		(fp_line
			(start -0.12065 -0.305054)
			(end -0.12065 -0.2794)
			(stroke
				(width 0.1)
				(type default)
			)
			(layer "F.Fab")
		)
		(fp_line
			(start -0.67945 0.3048)
			(end -0.67945 -0.305054)
			(stroke
				(width 0.1)
				(type default)
			)
			(layer "F.Fab")
		)
		(fp_line
			(start -0.67945 -0.305054)
			(end -0.12065 -0.305054)
			(stroke
				(width 0.1)
				(type default)
			)
			(layer "F.Fab")
		)
		(pad "1" smd circle
			(at -0.40005 0 180)
			(size 0 0)
			(layers "F.Cu" "F.Mask" "F.Paste")
			(net "SH_P0V8_PEX2_VSEN2_R")
		)
		(pad "2" smd circle
			(at 0.40005 0 180)
			(size 0 0)
			(layers "F.Cu" "F.Mask" "F.Paste")
			(net "P0V8_PEX2_VSEN2")
		)
	)
	(footprint ""
		(layer "F.Cu")
		(at 52.243736 -49.95291 180)
		(property "Reference" "R522"
			(at 0 0 180)
			(layer "F.SilkS")
			(hide yes)
			(effects
				(font
					(size 1.27 1.27)
				)
			)
		)
		(property "Value" ""
			(at 0 0 180)
			(layer "F.Fab")
			(effects
				(font
					(size 1.27 1.27)
				)
			)
		)
		(duplicate_pad_numbers_are_jumpers no)
		(fp_line
			(start 0.7874 0.4064)
			(end -0.7874 0.4064)
			(stroke
				(width 0.1524)
				(type default)
			)
			(layer "F.SilkS")
		)
		(fp_line
			(start 0.7874 -0.4064)
			(end 0.7874 0.4064)
			(stroke
				(width 0.1524)
				(type default)
			)
			(layer "F.SilkS")
		)
		(fp_line
			(start -0.7874 0.4064)
			(end -0.7874 -0.4064)
			(stroke
				(width 0.1524)
				(type default)
			)
			(layer "F.SilkS")
		)
		(fp_line
			(start -0.7874 -0.4064)
			(end 0.7874 -0.4064)
			(stroke
				(width 0.1524)
				(type default)
			)
			(layer "F.SilkS")
		)
		(fp_line
			(start 0.67945 0.3048)
			(end 0.120396 0.3048)
			(stroke
				(width 0.1)
				(type default)
			)
			(layer "F.Fab")
		)
		(fp_line
			(start 0.67945 -0.3048)
			(end 0.67945 0.3048)
			(stroke
				(width 0.1)
				(type default)
			)
			(layer "F.Fab")
		)
		(fp_line
			(start 0.12065 -0.2794)
			(end 0.12065 -0.3048)
			(stroke
				(width 0.1)
				(type default)
			)
			(layer "F.Fab")
		)
		(fp_line
			(start 0.12065 -0.3048)
			(end 0.67945 -0.3048)
			(stroke
				(width 0.1)
				(type default)
			)
			(layer "F.Fab")
		)
		(fp_line
			(start 0.120396 0.3048)
			(end 0.120396 0.2794)
			(stroke
				(width 0.1)
				(type default)
			)
			(layer "F.Fab")
		)
		(fp_line
			(start 0.120396 0.2794)
			(end -0.12065 0.2794)
			(stroke
				(width 0.1)
				(type default)
			)
			(layer "F.Fab")
		)
		(fp_line
			(start -0.12065 0.3048)
			(end -0.67945 0.3048)
			(stroke
				(width 0.1)
				(type default)
			)
			(layer "F.Fab")
		)
		(fp_line
			(start -0.12065 0.2794)
			(end -0.12065 0.3048)
			(stroke
				(width 0.1)
				(type default)
			)
			(layer "F.Fab")
		)
		(fp_line
			(start -0.12065 -0.2794)
			(end 0.12065 -0.2794)
			(stroke
				(width 0.1)
				(type default)
			)
			(layer "F.Fab")
		)
		(fp_line
			(start -0.12065 -0.305054)
			(end -0.12065 -0.2794)
			(stroke
				(width 0.1)
				(type default)
			)
			(layer "F.Fab")
		)
		(fp_line
			(start -0.67945 0.3048)
			(end -0.67945 -0.305054)
			(stroke
				(width 0.1)
				(type default)
			)
			(layer "F.Fab")
		)
		(fp_line
			(start -0.67945 -0.305054)
			(end -0.12065 -0.305054)
			(stroke
				(width 0.1)
				(type default)
			)
			(layer "F.Fab")
		)
		(pad "1" smd circle
			(at -0.40005 0 180)
			(size 0 0)
			(layers "F.Cu" "F.Mask" "F.Paste")
			(net "SMB_BIC_I2C6_MUX_SSD_0_7_ADC_R_SCL")
		)
		(pad "2" smd circle
			(at 0.40005 0 180)
			(size 0 0)
			(layers "F.Cu" "F.Mask" "F.Paste")
			(net "SMB_SSD1_ADC_SCL")
		)
	)
	(footprint ""
		(layer "F.Cu")
		(at 95.9104 -190.5)
		(property "Reference" "R6627"
			(at 0 0 0)
			(layer "F.SilkS")
			(hide yes)
			(effects
				(font
					(size 1.27 1.27)
				)
			)
		)
		(property "Value" ""
			(at 0 0 0)
			(layer "F.Fab")
			(effects
				(font
					(size 1.27 1.27)
				)
			)
		)
		(duplicate_pad_numbers_are_jumpers no)
		(fp_line
			(start -0.7874 -0.4064)
			(end 0.7874 -0.4064)
			(stroke
				(width 0.1524)
				(type default)
			)
			(layer "F.SilkS")
		)
		(fp_line
			(start -0.7874 0.4064)
			(end -0.7874 -0.4064)
			(stroke
				(width 0.1524)
				(type default)
			)
			(layer "F.SilkS")
		)
		(fp_line
			(start 0.7874 -0.4064)
			(end 0.7874 0.4064)
			(stroke
				(width 0.1524)
				(type default)
			)
			(layer "F.SilkS")
		)
		(fp_line
			(start 0.7874 0.4064)
			(end -0.7874 0.4064)
			(stroke
				(width 0.1524)
				(type default)
			)
			(layer "F.SilkS")
		)
		(fp_line
			(start -0.67945 -0.305054)
			(end -0.12065 -0.305054)
			(stroke
				(width 0.1)
				(type default)
			)
			(layer "F.Fab")
		)
		(fp_line
			(start -0.67945 0.3048)
			(end -0.67945 -0.305054)
			(stroke
				(width 0.1)
				(type default)
			)
			(layer "F.Fab")
		)
		(fp_line
			(start -0.12065 -0.305054)
			(end -0.12065 -0.2794)
			(stroke
				(width 0.1)
				(type default)
			)
			(layer "F.Fab")
		)
		(fp_line
			(start -0.12065 -0.2794)
			(end 0.12065 -0.2794)
			(stroke
				(width 0.1)
				(type default)
			)
			(layer "F.Fab")
		)
		(fp_line
			(start -0.12065 0.2794)
			(end -0.12065 0.3048)
			(stroke
				(width 0.1)
				(type default)
			)
			(layer "F.Fab")
		)
		(fp_line
			(start -0.12065 0.3048)
			(end -0.67945 0.3048)
			(stroke
				(width 0.1)
				(type default)
			)
			(layer "F.Fab")
		)
		(fp_line
			(start 0.120396 0.2794)
			(end -0.12065 0.2794)
			(stroke
				(width 0.1)
				(type default)
			)
			(layer "F.Fab")
		)
		(fp_line
			(start 0.120396 0.3048)
			(end 0.120396 0.2794)
			(stroke
				(width 0.1)
				(type default)
			)
			(layer "F.Fab")
		)
		(fp_line
			(start 0.12065 -0.3048)
			(end 0.67945 -0.3048)
			(stroke
				(width 0.1)
				(type default)
			)
			(layer "F.Fab")
		)
		(fp_line
			(start 0.12065 -0.2794)
			(end 0.12065 -0.3048)
			(stroke
				(width 0.1)
				(type default)
			)
			(layer "F.Fab")
		)
		(fp_line
			(start 0.67945 -0.3048)
			(end 0.67945 0.3048)
			(stroke
				(width 0.1)
				(type default)
			)
			(layer "F.Fab")
		)
		(fp_line
			(start 0.67945 0.3048)
			(end 0.120396 0.3048)
			(stroke
				(width 0.1)
				(type default)
			)
			(layer "F.Fab")
		)
		(pad "1" smd circle
			(at -0.40005 0)
			(size 0 0)
			(layers "F.Cu" "F.Mask" "F.Paste")
			(net "UART_PEX2_CLI_BUF_R_TX")
		)
		(pad "2" smd circle
			(at 0.40005 0)
			(size 0 0)
			(layers "F.Cu" "F.Mask" "F.Paste")
			(net "UART_PEX2_CLI_CP2108_TX")
		)
	)
	(footprint ""
		(layer "F.Cu")
		(at 196.119242 -133.480302 180)
		(property "Reference" "C231"
			(at 0 0 180)
			(layer "F.SilkS")
			(hide yes)
			(effects
				(font
					(size 1.27 1.27)
				)
			)
		)
		(property "Value" ""
			(at 0 0 180)
			(layer "F.Fab")
			(effects
				(font
					(size 1.27 1.27)
				)
			)
		)
		(duplicate_pad_numbers_are_jumpers no)
		(fp_line
			(start 0.299974 0.150114)
			(end -0.299974 0.150114)
			(stroke
				(width 0.1)
				(type default)
			)
			(layer "F.Fab")
		)
		(fp_line
			(start 0.299974 -0.150114)
			(end 0.299974 0.150114)
			(stroke
				(width 0.1)
				(type default)
			)
			(layer "F.Fab")
		)
		(fp_line
			(start -0.299974 0.150114)
			(end -0.299974 -0.150114)
			(stroke
				(width 0.1)
				(type default)
			)
			(layer "F.Fab")
		)
		(fp_line
			(start -0.299974 -0.150114)
			(end 0.299974 -0.150114)
			(stroke
				(width 0.1)
				(type default)
			)
			(layer "F.Fab")
		)
		(pad "1" smd rect
			(at -0.2667 0 180)
			(size 0.3048 0.381)
			(layers "F.Cu" "F.Mask" "F.Paste")
			(net "P5E_PEX1_STN0_TX_DN<6>")
		)
		(pad "2" smd rect
			(at 0.2667 0 180)
			(size 0.3048 0.381)
			(layers "F.Cu" "F.Mask" "F.Paste")
			(net "P5E_PEX1_STN0_TX_C_DN<6>")
		)
	)
	(footprint ""
		(layer "F.Cu")
		(at 316.3189 -59.574684 90)
		(property "Reference" "PC577"
			(at 0 0 90)
			(layer "F.SilkS")
			(hide yes)
			(effects
				(font
					(size 1.27 1.27)
				)
			)
		)
		(property "Value" ""
			(at 0 0 90)
			(layer "F.Fab")
			(effects
				(font
					(size 1.27 1.27)
				)
			)
		)
		(duplicate_pad_numbers_are_jumpers no)
		(fp_line
			(start 0.7874 -0.4064)
			(end 0.7874 0.4064)
			(stroke
				(width 0.1524)
				(type default)
			)
			(layer "F.SilkS")
		)
		(fp_line
			(start -0.7874 -0.4064)
			(end 0.7874 -0.4064)
			(stroke
				(width 0.1524)
				(type default)
			)
			(layer "F.SilkS")
		)
		(fp_line
			(start 0.7874 0.4064)
			(end -0.7874 0.4064)
			(stroke
				(width 0.1524)
				(type default)
			)
			(layer "F.SilkS")
		)
		(fp_line
			(start -0.7874 0.4064)
			(end -0.7874 -0.4064)
			(stroke
				(width 0.1524)
				(type default)
			)
			(layer "F.SilkS")
		)
		(fp_line
			(start -0.12065 -0.305054)
			(end -0.12065 -0.2794)
			(stroke
				(width 0.1)
				(type default)
			)
			(layer "F.Fab")
		)
		(fp_line
			(start -0.67945 -0.305054)
			(end -0.12065 -0.305054)
			(stroke
				(width 0.1)
				(type default)
			)
			(layer "F.Fab")
		)
		(fp_line
			(start 0.67945 -0.3048)
			(end 0.67945 0.3048)
			(stroke
				(width 0.1)
				(type default)
			)
			(layer "F.Fab")
		)
		(fp_line
			(start 0.12065 -0.3048)
			(end 0.67945 -0.3048)
			(stroke
				(width 0.1)
				(type default)
			)
			(layer "F.Fab")
		)
		(fp_line
			(start 0.12065 -0.2794)
			(end 0.12065 -0.3048)
			(stroke
				(width 0.1)
				(type default)
			)
			(layer "F.Fab")
		)
		(fp_line
			(start -0.12065 -0.2794)
			(end 0.12065 -0.2794)
			(stroke
				(width 0.1)
				(type default)
			)
			(layer "F.Fab")
		)
		(fp_line
			(start 0.120396 0.2794)
			(end -0.12065 0.2794)
			(stroke
				(width 0.1)
				(type default)
			)
			(layer "F.Fab")
		)
		(fp_line
			(start -0.12065 0.2794)
			(end -0.12065 0.3048)
			(stroke
				(width 0.1)
				(type default)
			)
			(layer "F.Fab")
		)
		(fp_line
			(start 0.67945 0.3048)
			(end 0.120396 0.3048)
			(stroke
				(width 0.1)
				(type default)
			)
			(layer "F.Fab")
		)
		(fp_line
			(start 0.120396 0.3048)
			(end 0.120396 0.2794)
			(stroke
				(width 0.1)
				(type default)
			)
			(layer "F.Fab")
		)
		(fp_line
			(start -0.12065 0.3048)
			(end -0.67945 0.3048)
			(stroke
				(width 0.1)
				(type default)
			)
			(layer "F.Fab")
		)
		(fp_line
			(start -0.67945 0.3048)
			(end -0.67945 -0.305054)
			(stroke
				(width 0.1)
				(type default)
			)
			(layer "F.Fab")
		)
		(pad "1" smd circle
			(at -0.40005 0 90)
			(size 0 0)
			(layers "F.Cu" "F.Mask" "F.Paste")
			(net "P5V_AUX")
		)
		(pad "2" smd circle
			(at 0.40005 0 90)
			(size 0 0)
			(layers "F.Cu" "F.Mask" "F.Paste")
			(net "GND")
		)
	)
	(footprint ""
		(layer "F.Cu")
		(at 249.733562 -211.622386)
		(property "Reference" "R4432"
			(at 0 0 0)
			(layer "F.SilkS")
			(hide yes)
			(effects
				(font
					(size 1.27 1.27)
				)
			)
		)
		(property "Value" ""
			(at 0 0 0)
			(layer "F.Fab")
			(effects
				(font
					(size 1.27 1.27)
				)
			)
		)
		(duplicate_pad_numbers_are_jumpers no)
		(fp_line
			(start -0.7874 -0.4064)
			(end 0.7874 -0.4064)
			(stroke
				(width 0.1524)
				(type default)
			)
			(layer "F.SilkS")
		)
		(fp_line
			(start -0.7874 0.4064)
			(end -0.7874 -0.4064)
			(stroke
				(width 0.1524)
				(type default)
			)
			(layer "F.SilkS")
		)
		(fp_line
			(start 0.7874 -0.4064)
			(end 0.7874 0.4064)
			(stroke
				(width 0.1524)
				(type default)
			)
			(layer "F.SilkS")
		)
		(fp_line
			(start 0.7874 0.4064)
			(end -0.7874 0.4064)
			(stroke
				(width 0.1524)
				(type default)
			)
			(layer "F.SilkS")
		)
		(fp_line
			(start -0.67945 -0.305054)
			(end -0.12065 -0.305054)
			(stroke
				(width 0.1)
				(type default)
			)
			(layer "F.Fab")
		)
		(fp_line
			(start -0.67945 0.3048)
			(end -0.67945 -0.305054)
			(stroke
				(width 0.1)
				(type default)
			)
			(layer "F.Fab")
		)
		(fp_line
			(start -0.12065 -0.305054)
			(end -0.12065 -0.2794)
			(stroke
				(width 0.1)
				(type default)
			)
			(layer "F.Fab")
		)
		(fp_line
			(start -0.12065 -0.2794)
			(end 0.12065 -0.2794)
			(stroke
				(width 0.1)
				(type default)
			)
			(layer "F.Fab")
		)
		(fp_line
			(start -0.12065 0.2794)
			(end -0.12065 0.3048)
			(stroke
				(width 0.1)
				(type default)
			)
			(layer "F.Fab")
		)
		(fp_line
			(start -0.12065 0.3048)
			(end -0.67945 0.3048)
			(stroke
				(width 0.1)
				(type default)
			)
			(layer "F.Fab")
		)
		(fp_line
			(start 0.120396 0.2794)
			(end -0.12065 0.2794)
			(stroke
				(width 0.1)
				(type default)
			)
			(layer "F.Fab")
		)
		(fp_line
			(start 0.120396 0.3048)
			(end 0.120396 0.2794)
			(stroke
				(width 0.1)
				(type default)
			)
			(layer "F.Fab")
		)
		(fp_line
			(start 0.12065 -0.3048)
			(end 0.67945 -0.3048)
			(stroke
				(width 0.1)
				(type default)
			)
			(layer "F.Fab")
		)
		(fp_line
			(start 0.12065 -0.2794)
			(end 0.12065 -0.3048)
			(stroke
				(width 0.1)
				(type default)
			)
			(layer "F.Fab")
		)
		(fp_line
			(start 0.67945 -0.3048)
			(end 0.67945 0.3048)
			(stroke
				(width 0.1)
				(type default)
			)
			(layer "F.Fab")
		)
		(fp_line
			(start 0.67945 0.3048)
			(end 0.120396 0.3048)
			(stroke
				(width 0.1)
				(type default)
			)
			(layer "F.Fab")
		)
		(pad "1" smd circle
			(at -0.40005 0)
			(size 0 0)
			(layers "F.Cu" "F.Mask" "F.Paste")
			(net "P1V2_AUX")
		)
		(pad "2" smd circle
			(at 0.40005 0)
			(size 0 0)
			(layers "F.Cu" "F.Mask" "F.Paste")
			(net "P1V2_AUX_ADJ")
		)
	)
	(footprint ""
		(layer "F.Cu")
		(at 378.453396 -288.190432)
		(property "Reference" "L142"
			(at 0 0 0)
			(layer "F.SilkS")
			(hide yes)
			(effects
				(font
					(size 1.27 1.27)
				)
			)
		)
		(property "Value" ""
			(at 0 0 0)
			(layer "F.Fab")
			(effects
				(font
					(size 1.27 1.27)
				)
			)
		)
		(duplicate_pad_numbers_are_jumpers no)
		(fp_line
			(start -1.63576 -0.8128)
			(end -1.63576 0.8128)
			(stroke
				(width 0.1524)
				(type default)
			)
			(layer "F.SilkS")
		)
		(fp_line
			(start -1.63576 -0.8128)
			(end 1.63576 -0.8128)
			(stroke
				(width 0.1524)
				(type default)
			)
			(layer "F.SilkS")
		)
		(fp_line
			(start 1.63576 -0.8128)
			(end 1.63576 0.8128)
			(stroke
				(width 0.1524)
				(type default)
			)
			(layer "F.SilkS")
		)
		(fp_line
			(start 1.63576 0.8128)
			(end -1.63576 0.8128)
			(stroke
				(width 0.1524)
				(type default)
			)
			(layer "F.SilkS")
		)
		(fp_line
			(start -1.56083 -0.738632)
			(end -1.56083 0.7366)
			(stroke
				(width 0.1)
				(type default)
			)
			(layer "F.Fab")
		)
		(fp_line
			(start -1.56083 0.7366)
			(end -1.524 0.7366)
			(stroke
				(width 0.1)
				(type default)
			)
			(layer "F.Fab")
		)
		(fp_line
			(start -1.524 0.7366)
			(end 1.524 0.7366)
			(stroke
				(width 0.1)
				(type default)
			)
			(layer "F.Fab")
		)
		(fp_line
			(start 1.524 0.7366)
			(end 1.560576 0.7366)
			(stroke
				(width 0.1)
				(type default)
			)
			(layer "F.Fab")
		)
		(fp_line
			(start 1.560576 -0.738632)
			(end -1.56083 -0.738632)
			(stroke
				(width 0.1)
				(type default)
			)
			(layer "F.Fab")
		)
		(fp_line
			(start 1.560576 0.7366)
			(end 1.560576 -0.738632)
			(stroke
				(width 0.1)
				(type default)
			)
			(layer "F.Fab")
		)
		(pad "1" smd rect
			(at -0.94996 0 180)
			(size 1.1176 1.3716)
			(layers "F.Cu" "F.Mask" "F.Paste")
			(net "P1V8_PLL0_PEX3")
		)
		(pad "2" smd rect
			(at 0.94996 0 180)
			(size 1.1176 1.3716)
			(layers "F.Cu" "F.Mask" "F.Paste")
			(net "PCEPLL6_VDDA18_PEX3")
		)
	)
	(footprint ""
		(layer "F.Cu")
		(at 379.956314 -61.487812 180)
		(property "Reference" "R6013"
			(at 0 0 180)
			(layer "F.SilkS")
			(hide yes)
			(effects
				(font
					(size 1.27 1.27)
				)
			)
		)
		(property "Value" ""
			(at 0 0 180)
			(layer "F.Fab")
			(effects
				(font
					(size 1.27 1.27)
				)
			)
		)
		(duplicate_pad_numbers_are_jumpers no)
		(fp_line
			(start 0.7874 0.4064)
			(end -0.7874 0.4064)
			(stroke
				(width 0.1524)
				(type default)
			)
			(layer "F.SilkS")
		)
		(fp_line
			(start 0.7874 -0.4064)
			(end 0.7874 0.4064)
			(stroke
				(width 0.1524)
				(type default)
			)
			(layer "F.SilkS")
		)
		(fp_line
			(start -0.7874 0.4064)
			(end -0.7874 -0.4064)
			(stroke
				(width 0.1524)
				(type default)
			)
			(layer "F.SilkS")
		)
		(fp_line
			(start -0.7874 -0.4064)
			(end 0.7874 -0.4064)
			(stroke
				(width 0.1524)
				(type default)
			)
			(layer "F.SilkS")
		)
		(fp_line
			(start 0.67945 0.3048)
			(end 0.120396 0.3048)
			(stroke
				(width 0.1)
				(type default)
			)
			(layer "F.Fab")
		)
		(fp_line
			(start 0.67945 -0.3048)
			(end 0.67945 0.3048)
			(stroke
				(width 0.1)
				(type default)
			)
			(layer "F.Fab")
		)
		(fp_line
			(start 0.12065 -0.2794)
			(end 0.12065 -0.3048)
			(stroke
				(width 0.1)
				(type default)
			)
			(layer "F.Fab")
		)
		(fp_line
			(start 0.12065 -0.3048)
			(end 0.67945 -0.3048)
			(stroke
				(width 0.1)
				(type default)
			)
			(layer "F.Fab")
		)
		(fp_line
			(start 0.120396 0.3048)
			(end 0.120396 0.2794)
			(stroke
				(width 0.1)
				(type default)
			)
			(layer "F.Fab")
		)
		(fp_line
			(start 0.120396 0.2794)
			(end -0.12065 0.2794)
			(stroke
				(width 0.1)
				(type default)
			)
			(layer "F.Fab")
		)
		(fp_line
			(start -0.12065 0.3048)
			(end -0.67945 0.3048)
			(stroke
				(width 0.1)
				(type default)
			)
			(layer "F.Fab")
		)
		(fp_line
			(start -0.12065 0.2794)
			(end -0.12065 0.3048)
			(stroke
				(width 0.1)
				(type default)
			)
			(layer "F.Fab")
		)
		(fp_line
			(start -0.12065 -0.2794)
			(end 0.12065 -0.2794)
			(stroke
				(width 0.1)
				(type default)
			)
			(layer "F.Fab")
		)
		(fp_line
			(start -0.12065 -0.305054)
			(end -0.12065 -0.2794)
			(stroke
				(width 0.1)
				(type default)
			)
			(layer "F.Fab")
		)
		(fp_line
			(start -0.67945 0.3048)
			(end -0.67945 -0.305054)
			(stroke
				(width 0.1)
				(type default)
			)
			(layer "F.Fab")
		)
		(fp_line
			(start -0.67945 -0.305054)
			(end -0.12065 -0.305054)
			(stroke
				(width 0.1)
				(type default)
			)
			(layer "F.Fab")
		)
		(pad "1" smd circle
			(at -0.40005 0 180)
			(size 0 0)
			(layers "F.Cu" "F.Mask" "F.Paste")
			(net "P3V3_AUX")
		)
		(pad "2" smd circle
			(at 0.40005 0 180)
			(size 0 0)
			(layers "F.Cu" "F.Mask" "F.Paste")
			(net "PWRGD_P12V_SSD13_D")
		)
	)
	(footprint ""
		(layer "F.Cu")
		(at 422.619932 -356.244906 90)
		(property "Reference" "C813"
			(at 0 0 90)
			(layer "F.SilkS")
			(hide yes)
			(effects
				(font
					(size 1.27 1.27)
				)
			)
		)
		(property "Value" ""
			(at 0 0 90)
			(layer "F.Fab")
			(effects
				(font
					(size 1.27 1.27)
				)
			)
		)
		(duplicate_pad_numbers_are_jumpers no)
		(fp_line
			(start 0.299974 -0.150114)
			(end 0.299974 0.150114)
			(stroke
				(width 0.1)
				(type default)
			)
			(layer "F.Fab")
		)
		(fp_line
			(start -0.299974 -0.150114)
			(end 0.299974 -0.150114)
			(stroke
				(width 0.1)
				(type default)
			)
			(layer "F.Fab")
		)
		(fp_line
			(start 0.299974 0.150114)
			(end -0.299974 0.150114)
			(stroke
				(width 0.1)
				(type default)
			)
			(layer "F.Fab")
		)
		(fp_line
			(start -0.299974 0.150114)
			(end -0.299974 -0.150114)
			(stroke
				(width 0.1)
				(type default)
			)
			(layer "F.Fab")
		)
		(pad "1" smd rect
			(at -0.2667 0 90)
			(size 0.3048 0.381)
			(layers "F.Cu" "F.Mask" "F.Paste")
			(net "P5E_PEX3_STN7_TX_DN<118>")
		)
		(pad "2" smd rect
			(at 0.2667 0 90)
			(size 0.3048 0.381)
			(layers "F.Cu" "F.Mask" "F.Paste")
			(net "P5E_PEX3_STN7_TX_C_DN<118>")
		)
	)
	(footprint ""
		(layer "F.Cu")
		(at 26.930096 -294.005508 -90)
		(property "Reference" "C3035"
			(at 0 0 270)
			(layer "F.SilkS")
			(hide yes)
			(effects
				(font
					(size 1.27 1.27)
				)
			)
		)
		(property "Value" ""
			(at 0 0 270)
			(layer "F.Fab")
			(effects
				(font
					(size 1.27 1.27)
				)
			)
		)
		(duplicate_pad_numbers_are_jumpers no)
		(fp_line
			(start -1.2954 0.5842)
			(end -1.2954 -0.5842)
			(stroke
				(width 0.1524)
				(type default)
			)
			(layer "F.SilkS")
		)
		(fp_line
			(start 1.2954 0.5842)
			(end -1.2954 0.5842)
			(stroke
				(width 0.1524)
				(type default)
			)
			(layer "F.SilkS")
		)
		(fp_line
			(start -1.2954 -0.5842)
			(end 1.2954 -0.5842)
			(stroke
				(width 0.1524)
				(type default)
			)
			(layer "F.SilkS")
		)
		(fp_line
			(start 1.2954 -0.5842)
			(end 1.2954 0.5842)
			(stroke
				(width 0.1524)
				(type default)
			)
			(layer "F.SilkS")
		)
		(fp_line
			(start -0.8636 0.4572)
			(end -0.8636 0.4064)
			(stroke
				(width 0.1)
				(type default)
			)
			(layer "F.Fab")
		)
		(fp_line
			(start 0.8636 0.4572)
			(end -0.8636 0.4572)
			(stroke
				(width 0.1)
				(type default)
			)
			(layer "F.Fab")
		)
		(fp_line
			(start -1.1938 0.4064)
			(end -1.1938 -0.4064)
			(stroke
				(width 0.1)
				(type default)
			)
			(layer "F.Fab")
		)
		(fp_line
			(start -0.8636 0.4064)
			(end -1.1938 0.4064)
			(stroke
				(width 0.1)
				(type default)
			)
			(layer "F.Fab")
		)
		(fp_line
			(start 0.8636 0.4064)
			(end 0.8636 0.4572)
			(stroke
				(width 0.1)
				(type default)
			)
			(layer "F.Fab")
		)
		(fp_line
			(start 1.1938 0.4064)
			(end 0.8636 0.4064)
			(stroke
				(width 0.1)
				(type default)
			)
			(layer "F.Fab")
		)
		(fp_line
			(start -1.1938 -0.4064)
			(end -0.8636 -0.4064)
			(stroke
				(width 0.1)
				(type default)
			)
			(layer "F.Fab")
		)
		(fp_line
			(start -0.8636 -0.4064)
			(end -0.8636 -0.4572)
			(stroke
				(width 0.1)
				(type default)
			)
			(layer "F.Fab")
		)
		(fp_line
			(start 0.8636 -0.4064)
			(end 1.1938 -0.4064)
			(stroke
				(width 0.1)
				(type default)
			)
			(layer "F.Fab")
		)
		(fp_line
			(start 1.1938 -0.4064)
			(end 1.1938 0.4064)
			(stroke
				(width 0.1)
				(type default)
			)
			(layer "F.Fab")
		)
		(fp_line
			(start -0.8636 -0.4572)
			(end 0.8636 -0.4572)
			(stroke
				(width 0.1)
				(type default)
			)
			(layer "F.Fab")
		)
		(fp_line
			(start 0.8636 -0.4572)
			(end 0.8636 -0.4064)
			(stroke
				(width 0.1)
				(type default)
			)
			(layer "F.Fab")
		)
		(pad "1" smd rect
			(at -0.7366 0 180)
			(size 0.7112 0.8128)
			(layers "F.Cu" "F.Mask" "F.Paste")
			(net "P1V8_PLL0_PEX0")
		)
		(pad "2" smd rect
			(at 0.7366 0 180)
			(size 0.7112 0.8128)
			(layers "F.Cu" "F.Mask" "F.Paste")
			(net "GND")
		)
	)
	(footprint ""
		(layer "F.Cu")
		(at 131.435856 -170.599862 90)
		(property "Reference" "R1092"
			(at 0 0 90)
			(layer "F.SilkS")
			(hide yes)
			(effects
				(font
					(size 1.27 1.27)
				)
			)
		)
		(property "Value" ""
			(at 0 0 90)
			(layer "F.Fab")
			(effects
				(font
					(size 1.27 1.27)
				)
			)
		)
		(duplicate_pad_numbers_are_jumpers no)
		(fp_line
			(start 0.7874 0.4064)
			(end -0.7874 0.4064)
			(stroke
				(width 0.1524)
				(type default)
			)
			(layer "F.SilkS")
		)
		(fp_line
			(start -0.12065 -0.305054)
			(end -0.12065 -0.2794)
			(stroke
				(width 0.1)
				(type default)
			)
			(layer "F.Fab")
		)
		(fp_line
			(start -0.67945 -0.305054)
			(end -0.12065 -0.305054)
			(stroke
				(width 0.1)
				(type default)
			)
			(layer "F.Fab")
		)
		(fp_line
			(start 0.67945 -0.3048)
			(end 0.67945 0.3048)
			(stroke
				(width 0.1)
				(type default)
			)
			(layer "F.Fab")
		)
		(fp_line
			(start 0.12065 -0.3048)
			(end 0.67945 -0.3048)
			(stroke
				(width 0.1)
				(type default)
			)
			(layer "F.Fab")
		)
		(fp_line
			(start 0.12065 -0.2794)
			(end 0.12065 -0.3048)
			(stroke
				(width 0.1)
				(type default)
			)
			(layer "F.Fab")
		)
		(fp_line
			(start -0.12065 -0.2794)
			(end 0.12065 -0.2794)
			(stroke
				(width 0.1)
				(type default)
			)
			(layer "F.Fab")
		)
		(fp_line
			(start 0.120396 0.2794)
			(end -0.12065 0.2794)
			(stroke
				(width 0.1)
				(type default)
			)
			(layer "F.Fab")
		)
		(fp_line
			(start -0.12065 0.2794)
			(end -0.12065 0.3048)
			(stroke
				(width 0.1)
				(type default)
			)
			(layer "F.Fab")
		)
		(fp_line
			(start 0.67945 0.3048)
			(end 0.120396 0.3048)
			(stroke
				(width 0.1)
				(type default)
			)
			(layer "F.Fab")
		)
		(fp_line
			(start 0.120396 0.3048)
			(end 0.120396 0.2794)
			(stroke
				(width 0.1)
				(type default)
			)
			(layer "F.Fab")
		)
		(fp_line
			(start -0.12065 0.3048)
			(end -0.67945 0.3048)
			(stroke
				(width 0.1)
				(type default)
			)
			(layer "F.Fab")
		)
		(fp_line
			(start -0.67945 0.3048)
			(end -0.67945 -0.305054)
			(stroke
				(width 0.1)
				(type default)
			)
			(layer "F.Fab")
		)
		(pad "1" smd circle
			(at -0.40005 0 90)
			(size 0 0)
			(layers "F.Cu" "F.Mask" "F.Paste")
			(net "CLK_100M_DB2000QL_PEX3_S1_R_DN")
		)
		(pad "2" smd circle
			(at 0.40005 0 90)
			(size 0 0)
			(layers "F.Cu" "F.Mask" "F.Paste")
			(net "CLK_100M_DB2000QL_PEX3_S1_DN")
		)
	)
	(footprint ""
		(layer "F.Cu")
		(at 170.441874 -27.006296 -90)
		(property "Reference" "PR7112"
			(at 0 0 270)
			(layer "F.SilkS")
			(hide yes)
			(effects
				(font
					(size 1.27 1.27)
				)
			)
		)
		(property "Value" ""
			(at 0 0 270)
			(layer "F.Fab")
			(effects
				(font
					(size 1.27 1.27)
				)
			)
		)
		(duplicate_pad_numbers_are_jumpers no)
		(fp_line
			(start -0.7874 0.4064)
			(end -0.7874 -0.4064)
			(stroke
				(width 0.1524)
				(type default)
			)
			(layer "F.SilkS")
		)
		(fp_line
			(start 0.7874 0.4064)
			(end -0.7874 0.4064)
			(stroke
				(width 0.1524)
				(type default)
			)
			(layer "F.SilkS")
		)
		(fp_line
			(start -0.7874 -0.4064)
			(end 0.7874 -0.4064)
			(stroke
				(width 0.1524)
				(type default)
			)
			(layer "F.SilkS")
		)
		(fp_line
			(start 0.7874 -0.4064)
			(end 0.7874 0.4064)
			(stroke
				(width 0.1524)
				(type default)
			)
			(layer "F.SilkS")
		)
		(fp_line
			(start -0.67945 0.3048)
			(end -0.67945 -0.305054)
			(stroke
				(width 0.1)
				(type default)
			)
			(layer "F.Fab")
		)
		(fp_line
			(start -0.12065 0.3048)
			(end -0.67945 0.3048)
			(stroke
				(width 0.1)
				(type default)
			)
			(layer "F.Fab")
		)
		(fp_line
			(start 0.120396 0.3048)
			(end 0.120396 0.2794)
			(stroke
				(width 0.1)
				(type default)
			)
			(layer "F.Fab")
		)
		(fp_line
			(start 0.67945 0.3048)
			(end 0.120396 0.3048)
			(stroke
				(width 0.1)
				(type default)
			)
			(layer "F.Fab")
		)
		(fp_line
			(start -0.12065 0.2794)
			(end -0.12065 0.3048)
			(stroke
				(width 0.1)
				(type default)
			)
			(layer "F.Fab")
		)
		(fp_line
			(start 0.120396 0.2794)
			(end -0.12065 0.2794)
			(stroke
				(width 0.1)
				(type default)
			)
			(layer "F.Fab")
		)
		(fp_line
			(start -0.12065 -0.2794)
			(end 0.12065 -0.2794)
			(stroke
				(width 0.1)
				(type default)
			)
			(layer "F.Fab")
		)
		(fp_line
			(start 0.12065 -0.2794)
			(end 0.12065 -0.3048)
			(stroke
				(width 0.1)
				(type default)
			)
			(layer "F.Fab")
		)
		(fp_line
			(start 0.12065 -0.3048)
			(end 0.67945 -0.3048)
			(stroke
				(width 0.1)
				(type default)
			)
			(layer "F.Fab")
		)
		(fp_line
			(start 0.67945 -0.3048)
			(end 0.67945 0.3048)
			(stroke
				(width 0.1)
				(type default)
			)
			(layer "F.Fab")
		)
		(fp_line
			(start -0.67945 -0.305054)
			(end -0.12065 -0.305054)
			(stroke
				(width 0.1)
				(type default)
			)
			(layer "F.Fab")
		)
		(fp_line
			(start -0.12065 -0.305054)
			(end -0.12065 -0.2794)
			(stroke
				(width 0.1)
				(type default)
			)
			(layer "F.Fab")
		)
		(pad "1" smd circle
			(at -0.40005 0 270)
			(size 0 0)
			(layers "F.Cu" "F.Mask" "F.Paste")
			(net "P3V3_SSD6_CO_ILIMIT")
		)
		(pad "2" smd circle
			(at 0.40005 0 270)
			(size 0 0)
			(layers "F.Cu" "F.Mask" "F.Paste")
			(net "GND")
		)
	)
	(footprint ""
		(layer "F.Cu")
		(at 127.29972 -166.407846)
		(property "Reference" "R6669"
			(at 0 0 0)
			(layer "F.SilkS")
			(hide yes)
			(effects
				(font
					(size 1.27 1.27)
				)
			)
		)
		(property "Value" ""
			(at 0 0 0)
			(layer "F.Fab")
			(effects
				(font
					(size 1.27 1.27)
				)
			)
		)
		(duplicate_pad_numbers_are_jumpers no)
		(fp_line
			(start -0.7874 -0.4064)
			(end 0.7874 -0.4064)
			(stroke
				(width 0.1524)
				(type default)
			)
			(layer "F.SilkS")
		)
		(fp_line
			(start -0.7874 0.4064)
			(end -0.7874 -0.4064)
			(stroke
				(width 0.1524)
				(type default)
			)
			(layer "F.SilkS")
		)
		(fp_line
			(start 0.7874 -0.4064)
			(end 0.7874 0.4064)
			(stroke
				(width 0.1524)
				(type default)
			)
			(layer "F.SilkS")
		)
		(fp_line
			(start 0.7874 0.4064)
			(end -0.7874 0.4064)
			(stroke
				(width 0.1524)
				(type default)
			)
			(layer "F.SilkS")
		)
		(fp_line
			(start -0.67945 -0.305054)
			(end -0.12065 -0.305054)
			(stroke
				(width 0.1)
				(type default)
			)
			(layer "F.Fab")
		)
		(fp_line
			(start -0.67945 0.3048)
			(end -0.67945 -0.305054)
			(stroke
				(width 0.1)
				(type default)
			)
			(layer "F.Fab")
		)
		(fp_line
			(start -0.12065 -0.305054)
			(end -0.12065 -0.2794)
			(stroke
				(width 0.1)
				(type default)
			)
			(layer "F.Fab")
		)
		(fp_line
			(start -0.12065 -0.2794)
			(end 0.12065 -0.2794)
			(stroke
				(width 0.1)
				(type default)
			)
			(layer "F.Fab")
		)
		(fp_line
			(start -0.12065 0.2794)
			(end -0.12065 0.3048)
			(stroke
				(width 0.1)
				(type default)
			)
			(layer "F.Fab")
		)
		(fp_line
			(start -0.12065 0.3048)
			(end -0.67945 0.3048)
			(stroke
				(width 0.1)
				(type default)
			)
			(layer "F.Fab")
		)
		(fp_line
			(start 0.120396 0.2794)
			(end -0.12065 0.2794)
			(stroke
				(width 0.1)
				(type default)
			)
			(layer "F.Fab")
		)
		(fp_line
			(start 0.120396 0.3048)
			(end 0.120396 0.2794)
			(stroke
				(width 0.1)
				(type default)
			)
			(layer "F.Fab")
		)
		(fp_line
			(start 0.12065 -0.3048)
			(end 0.67945 -0.3048)
			(stroke
				(width 0.1)
				(type default)
			)
			(layer "F.Fab")
		)
		(fp_line
			(start 0.12065 -0.2794)
			(end 0.12065 -0.3048)
			(stroke
				(width 0.1)
				(type default)
			)
			(layer "F.Fab")
		)
		(fp_line
			(start 0.67945 -0.3048)
			(end 0.67945 0.3048)
			(stroke
				(width 0.1)
				(type default)
			)
			(layer "F.Fab")
		)
		(fp_line
			(start 0.67945 0.3048)
			(end 0.120396 0.3048)
			(stroke
				(width 0.1)
				(type default)
			)
			(layer "F.Fab")
		)
		(pad "1" smd circle
			(at -0.40005 0)
			(size 0 0)
			(layers "F.Cu" "F.Mask" "F.Paste")
			(net "NIC0_CLK_EN_BUF_R_N")
		)
		(pad "2" smd circle
			(at 0.40005 0)
			(size 0 0)
			(layers "F.Cu" "F.Mask" "F.Paste")
			(net "P3V3")
		)
	)
	(footprint ""
		(layer "F.Cu")
		(at 198.76135 -131.686808 180)
		(property "Reference" "C233"
			(at 0 0 180)
			(layer "F.SilkS")
			(hide yes)
			(effects
				(font
					(size 1.27 1.27)
				)
			)
		)
		(property "Value" ""
			(at 0 0 180)
			(layer "F.Fab")
			(effects
				(font
					(size 1.27 1.27)
				)
			)
		)
		(duplicate_pad_numbers_are_jumpers no)
		(fp_line
			(start 0.299974 0.150114)
			(end -0.299974 0.150114)
			(stroke
				(width 0.1)
				(type default)
			)
			(layer "F.Fab")
		)
		(fp_line
			(start 0.299974 -0.150114)
			(end 0.299974 0.150114)
			(stroke
				(width 0.1)
				(type default)
			)
			(layer "F.Fab")
		)
		(fp_line
			(start -0.299974 0.150114)
			(end -0.299974 -0.150114)
			(stroke
				(width 0.1)
				(type default)
			)
			(layer "F.Fab")
		)
		(fp_line
			(start -0.299974 -0.150114)
			(end 0.299974 -0.150114)
			(stroke
				(width 0.1)
				(type default)
			)
			(layer "F.Fab")
		)
		(pad "1" smd rect
			(at -0.2667 0 180)
			(size 0.3048 0.381)
			(layers "F.Cu" "F.Mask" "F.Paste")
			(net "P5E_PEX1_STN0_TX_DN<5>")
		)
		(pad "2" smd rect
			(at 0.2667 0 180)
			(size 0.3048 0.381)
			(layers "F.Cu" "F.Mask" "F.Paste")
			(net "P5E_PEX1_STN0_TX_C_DN<5>")
		)
	)
	(footprint ""
		(layer "F.Cu")
		(at 63.008764 -383.576068)
		(property "Reference" "R6301"
			(at 0 0 0)
			(layer "F.SilkS")
			(hide yes)
			(effects
				(font
					(size 1.27 1.27)
				)
			)
		)
		(property "Value" ""
			(at 0 0 0)
			(layer "F.Fab")
			(effects
				(font
					(size 1.27 1.27)
				)
			)
		)
		(duplicate_pad_numbers_are_jumpers no)
		(fp_line
			(start -0.7874 -0.4064)
			(end 0.7874 -0.4064)
			(stroke
				(width 0.1524)
				(type default)
			)
			(layer "F.SilkS")
		)
		(fp_line
			(start -0.7874 0.4064)
			(end -0.7874 -0.4064)
			(stroke
				(width 0.1524)
				(type default)
			)
			(layer "F.SilkS")
		)
		(fp_line
			(start 0.7874 -0.4064)
			(end 0.7874 0.4064)
			(stroke
				(width 0.1524)
				(type default)
			)
			(layer "F.SilkS")
		)
		(fp_line
			(start 0.7874 0.4064)
			(end -0.7874 0.4064)
			(stroke
				(width 0.1524)
				(type default)
			)
			(layer "F.SilkS")
		)
		(fp_line
			(start -0.67945 -0.305054)
			(end -0.12065 -0.305054)
			(stroke
				(width 0.1)
				(type default)
			)
			(layer "F.Fab")
		)
		(fp_line
			(start -0.67945 0.3048)
			(end -0.67945 -0.305054)
			(stroke
				(width 0.1)
				(type default)
			)
			(layer "F.Fab")
		)
		(fp_line
			(start -0.12065 -0.305054)
			(end -0.12065 -0.2794)
			(stroke
				(width 0.1)
				(type default)
			)
			(layer "F.Fab")
		)
		(fp_line
			(start -0.12065 -0.2794)
			(end 0.12065 -0.2794)
			(stroke
				(width 0.1)
				(type default)
			)
			(layer "F.Fab")
		)
		(fp_line
			(start -0.12065 0.2794)
			(end -0.12065 0.3048)
			(stroke
				(width 0.1)
				(type default)
			)
			(layer "F.Fab")
		)
		(fp_line
			(start -0.12065 0.3048)
			(end -0.67945 0.3048)
			(stroke
				(width 0.1)
				(type default)
			)
			(layer "F.Fab")
		)
		(fp_line
			(start 0.120396 0.2794)
			(end -0.12065 0.2794)
			(stroke
				(width 0.1)
				(type default)
			)
			(layer "F.Fab")
		)
		(fp_line
			(start 0.120396 0.3048)
			(end 0.120396 0.2794)
			(stroke
				(width 0.1)
				(type default)
			)
			(layer "F.Fab")
		)
		(fp_line
			(start 0.12065 -0.3048)
			(end 0.67945 -0.3048)
			(stroke
				(width 0.1)
				(type default)
			)
			(layer "F.Fab")
		)
		(fp_line
			(start 0.12065 -0.2794)
			(end 0.12065 -0.3048)
			(stroke
				(width 0.1)
				(type default)
			)
			(layer "F.Fab")
		)
		(fp_line
			(start 0.67945 -0.3048)
			(end 0.67945 0.3048)
			(stroke
				(width 0.1)
				(type default)
			)
			(layer "F.Fab")
		)
		(fp_line
			(start 0.67945 0.3048)
			(end 0.120396 0.3048)
			(stroke
				(width 0.1)
				(type default)
			)
			(layer "F.Fab")
		)
		(pad "1" smd circle
			(at -0.40005 0)
			(size 0 0)
			(layers "F.Cu" "F.Mask" "F.Paste")
			(net "RST_MB_PERST_2_N")
		)
		(pad "2" smd circle
			(at 0.40005 0)
			(size 0 0)
			(layers "F.Cu" "F.Mask" "F.Paste")
			(net "GND")
		)
	)
	(footprint ""
		(layer "F.Cu")
		(at 262.088122 -260.84911 -90)
		(property "Reference" "C3363"
			(at 0 0 270)
			(layer "F.SilkS")
			(hide yes)
			(effects
				(font
					(size 1.27 1.27)
				)
			)
		)
		(property "Value" ""
			(at 0 0 270)
			(layer "F.Fab")
			(effects
				(font
					(size 1.27 1.27)
				)
			)
		)
		(duplicate_pad_numbers_are_jumpers no)
		(fp_line
			(start -1.2954 0.5842)
			(end -1.2954 -0.5842)
			(stroke
				(width 0.1524)
				(type default)
			)
			(layer "F.SilkS")
		)
		(fp_line
			(start 1.2954 0.5842)
			(end -1.2954 0.5842)
			(stroke
				(width 0.1524)
				(type default)
			)
			(layer "F.SilkS")
		)
		(fp_line
			(start -1.2954 -0.5842)
			(end 1.2954 -0.5842)
			(stroke
				(width 0.1524)
				(type default)
			)
			(layer "F.SilkS")
		)
		(fp_line
			(start 1.2954 -0.5842)
			(end 1.2954 0.5842)
			(stroke
				(width 0.1524)
				(type default)
			)
			(layer "F.SilkS")
		)
		(fp_line
			(start -0.8636 0.4572)
			(end -0.8636 0.4064)
			(stroke
				(width 0.1)
				(type default)
			)
			(layer "F.Fab")
		)
		(fp_line
			(start 0.8636 0.4572)
			(end -0.8636 0.4572)
			(stroke
				(width 0.1)
				(type default)
			)
			(layer "F.Fab")
		)
		(fp_line
			(start -1.1938 0.4064)
			(end -1.1938 -0.4064)
			(stroke
				(width 0.1)
				(type default)
			)
			(layer "F.Fab")
		)
		(fp_line
			(start -0.8636 0.4064)
			(end -1.1938 0.4064)
			(stroke
				(width 0.1)
				(type default)
			)
			(layer "F.Fab")
		)
		(fp_line
			(start 0.8636 0.4064)
			(end 0.8636 0.4572)
			(stroke
				(width 0.1)
				(type default)
			)
			(layer "F.Fab")
		)
		(fp_line
			(start 1.1938 0.4064)
			(end 0.8636 0.4064)
			(stroke
				(width 0.1)
				(type default)
			)
			(layer "F.Fab")
		)
		(fp_line
			(start -1.1938 -0.4064)
			(end -0.8636 -0.4064)
			(stroke
				(width 0.1)
				(type default)
			)
			(layer "F.Fab")
		)
		(fp_line
			(start -0.8636 -0.4064)
			(end -0.8636 -0.4572)
			(stroke
				(width 0.1)
				(type default)
			)
			(layer "F.Fab")
		)
		(fp_line
			(start 0.8636 -0.4064)
			(end 1.1938 -0.4064)
			(stroke
				(width 0.1)
				(type default)
			)
			(layer "F.Fab")
		)
		(fp_line
			(start 1.1938 -0.4064)
			(end 1.1938 0.4064)
			(stroke
				(width 0.1)
				(type default)
			)
			(layer "F.Fab")
		)
		(fp_line
			(start -0.8636 -0.4572)
			(end 0.8636 -0.4572)
			(stroke
				(width 0.1)
				(type default)
			)
			(layer "F.Fab")
		)
		(fp_line
			(start 0.8636 -0.4572)
			(end 0.8636 -0.4064)
			(stroke
				(width 0.1)
				(type default)
			)
			(layer "F.Fab")
		)
		(pad "1" smd rect
			(at -0.7366 0 180)
			(size 0.7112 0.8128)
			(layers "F.Cu" "F.Mask" "F.Paste")
			(net "P1V8_PLL0_PEX2")
		)
		(pad "2" smd rect
			(at 0.7366 0 180)
			(size 0.7112 0.8128)
			(layers "F.Cu" "F.Mask" "F.Paste")
			(net "GND")
		)
	)
	(footprint ""
		(layer "F.Cu")
		(at 326.012556 -199.282304)
		(property "Reference" "R4238"
			(at 0 0 0)
			(layer "F.SilkS")
			(hide yes)
			(effects
				(font
					(size 1.27 1.27)
				)
			)
		)
		(property "Value" ""
			(at 0 0 0)
			(layer "F.Fab")
			(effects
				(font
					(size 1.27 1.27)
				)
			)
		)
		(duplicate_pad_numbers_are_jumpers no)
		(fp_line
			(start -0.7874 -0.4064)
			(end 0.7874 -0.4064)
			(stroke
				(width 0.1524)
				(type default)
			)
			(layer "F.SilkS")
		)
		(fp_line
			(start -0.7874 0.4064)
			(end -0.7874 -0.4064)
			(stroke
				(width 0.1524)
				(type default)
			)
			(layer "F.SilkS")
		)
		(fp_line
			(start 0.7874 -0.4064)
			(end 0.7874 0.4064)
			(stroke
				(width 0.1524)
				(type default)
			)
			(layer "F.SilkS")
		)
		(fp_line
			(start 0.7874 0.4064)
			(end -0.7874 0.4064)
			(stroke
				(width 0.1524)
				(type default)
			)
			(layer "F.SilkS")
		)
		(fp_line
			(start -0.67945 -0.305054)
			(end -0.12065 -0.305054)
			(stroke
				(width 0.1)
				(type default)
			)
			(layer "F.Fab")
		)
		(fp_line
			(start -0.67945 0.3048)
			(end -0.67945 -0.305054)
			(stroke
				(width 0.1)
				(type default)
			)
			(layer "F.Fab")
		)
		(fp_line
			(start -0.12065 -0.305054)
			(end -0.12065 -0.2794)
			(stroke
				(width 0.1)
				(type default)
			)
			(layer "F.Fab")
		)
		(fp_line
			(start -0.12065 -0.2794)
			(end 0.12065 -0.2794)
			(stroke
				(width 0.1)
				(type default)
			)
			(layer "F.Fab")
		)
		(fp_line
			(start -0.12065 0.2794)
			(end -0.12065 0.3048)
			(stroke
				(width 0.1)
				(type default)
			)
			(layer "F.Fab")
		)
		(fp_line
			(start -0.12065 0.3048)
			(end -0.67945 0.3048)
			(stroke
				(width 0.1)
				(type default)
			)
			(layer "F.Fab")
		)
		(fp_line
			(start 0.120396 0.2794)
			(end -0.12065 0.2794)
			(stroke
				(width 0.1)
				(type default)
			)
			(layer "F.Fab")
		)
		(fp_line
			(start 0.120396 0.3048)
			(end 0.120396 0.2794)
			(stroke
				(width 0.1)
				(type default)
			)
			(layer "F.Fab")
		)
		(fp_line
			(start 0.12065 -0.3048)
			(end 0.67945 -0.3048)
			(stroke
				(width 0.1)
				(type default)
			)
			(layer "F.Fab")
		)
		(fp_line
			(start 0.12065 -0.2794)
			(end 0.12065 -0.3048)
			(stroke
				(width 0.1)
				(type default)
			)
			(layer "F.Fab")
		)
		(fp_line
			(start 0.67945 -0.3048)
			(end 0.67945 0.3048)
			(stroke
				(width 0.1)
				(type default)
			)
			(layer "F.Fab")
		)
		(fp_line
			(start 0.67945 0.3048)
			(end 0.120396 0.3048)
			(stroke
				(width 0.1)
				(type default)
			)
			(layer "F.Fab")
		)
		(pad "1" smd circle
			(at -0.40005 0)
			(size 0 0)
			(layers "F.Cu" "F.Mask" "F.Paste")
			(net "P3V3_AUX")
		)
		(pad "2" smd circle
			(at 0.40005 0)
			(size 0 0)
			(layers "F.Cu" "F.Mask" "F.Paste")
			(net "IRQ_IOEXP_DBV2_N")
		)
	)
	(footprint ""
		(layer "F.Cu")
		(at 63.54699 -385.561332 180)
		(property "Reference" "C4034"
			(at 0 0 180)
			(layer "F.SilkS")
			(hide yes)
			(effects
				(font
					(size 1.27 1.27)
				)
			)
		)
		(property "Value" ""
			(at 0 0 180)
			(layer "F.Fab")
			(effects
				(font
					(size 1.27 1.27)
				)
			)
		)
		(duplicate_pad_numbers_are_jumpers no)
		(fp_line
			(start 0.7874 0.4064)
			(end -0.7874 0.4064)
			(stroke
				(width 0.1524)
				(type default)
			)
			(layer "F.SilkS")
		)
		(fp_line
			(start 0.7874 -0.4064)
			(end 0.7874 0.4064)
			(stroke
				(width 0.1524)
				(type default)
			)
			(layer "F.SilkS")
		)
		(fp_line
			(start -0.7874 0.4064)
			(end -0.7874 -0.4064)
			(stroke
				(width 0.1524)
				(type default)
			)
			(layer "F.SilkS")
		)
		(fp_line
			(start -0.7874 -0.4064)
			(end 0.7874 -0.4064)
			(stroke
				(width 0.1524)
				(type default)
			)
			(layer "F.SilkS")
		)
		(fp_line
			(start 0.67945 0.3048)
			(end 0.120396 0.3048)
			(stroke
				(width 0.1)
				(type default)
			)
			(layer "F.Fab")
		)
		(fp_line
			(start 0.67945 -0.3048)
			(end 0.67945 0.3048)
			(stroke
				(width 0.1)
				(type default)
			)
			(layer "F.Fab")
		)
		(fp_line
			(start 0.12065 -0.2794)
			(end 0.12065 -0.3048)
			(stroke
				(width 0.1)
				(type default)
			)
			(layer "F.Fab")
		)
		(fp_line
			(start 0.12065 -0.3048)
			(end 0.67945 -0.3048)
			(stroke
				(width 0.1)
				(type default)
			)
			(layer "F.Fab")
		)
		(fp_line
			(start 0.120396 0.3048)
			(end 0.120396 0.2794)
			(stroke
				(width 0.1)
				(type default)
			)
			(layer "F.Fab")
		)
		(fp_line
			(start 0.120396 0.2794)
			(end -0.12065 0.2794)
			(stroke
				(width 0.1)
				(type default)
			)
			(layer "F.Fab")
		)
		(fp_line
			(start -0.12065 0.3048)
			(end -0.67945 0.3048)
			(stroke
				(width 0.1)
				(type default)
			)
			(layer "F.Fab")
		)
		(fp_line
			(start -0.12065 0.2794)
			(end -0.12065 0.3048)
			(stroke
				(width 0.1)
				(type default)
			)
			(layer "F.Fab")
		)
		(fp_line
			(start -0.12065 -0.2794)
			(end 0.12065 -0.2794)
			(stroke
				(width 0.1)
				(type default)
			)
			(layer "F.Fab")
		)
		(fp_line
			(start -0.12065 -0.305054)
			(end -0.12065 -0.2794)
			(stroke
				(width 0.1)
				(type default)
			)
			(layer "F.Fab")
		)
		(fp_line
			(start -0.67945 0.3048)
			(end -0.67945 -0.305054)
			(stroke
				(width 0.1)
				(type default)
			)
			(layer "F.Fab")
		)
		(fp_line
			(start -0.67945 -0.305054)
			(end -0.12065 -0.305054)
			(stroke
				(width 0.1)
				(type default)
			)
			(layer "F.Fab")
		)
		(pad "1" smd circle
			(at -0.40005 0 180)
			(size 0 0)
			(layers "F.Cu" "F.Mask" "F.Paste")
			(net "GND")
		)
		(pad "2" smd circle
			(at 0.40005 0 180)
			(size 0 0)
			(layers "F.Cu" "F.Mask" "F.Paste")
			(net "RST_MB_PERST_1_N")
		)
	)
	(footprint ""
		(layer "F.Cu")
		(at 196.119242 -143.504666 180)
		(property "Reference" "C226"
			(at 0 0 180)
			(layer "F.SilkS")
			(hide yes)
			(effects
				(font
					(size 1.27 1.27)
				)
			)
		)
		(property "Value" ""
			(at 0 0 180)
			(layer "F.Fab")
			(effects
				(font
					(size 1.27 1.27)
				)
			)
		)
		(duplicate_pad_numbers_are_jumpers no)
		(fp_line
			(start 0.299974 0.150114)
			(end -0.299974 0.150114)
			(stroke
				(width 0.1)
				(type default)
			)
			(layer "F.Fab")
		)
		(fp_line
			(start 0.299974 -0.150114)
			(end 0.299974 0.150114)
			(stroke
				(width 0.1)
				(type default)
			)
			(layer "F.Fab")
		)
		(fp_line
			(start -0.299974 0.150114)
			(end -0.299974 -0.150114)
			(stroke
				(width 0.1)
				(type default)
			)
			(layer "F.Fab")
		)
		(fp_line
			(start -0.299974 -0.150114)
			(end 0.299974 -0.150114)
			(stroke
				(width 0.1)
				(type default)
			)
			(layer "F.Fab")
		)
		(pad "1" smd rect
			(at -0.2667 0 180)
			(size 0.3048 0.381)
			(layers "F.Cu" "F.Mask" "F.Paste")
			(net "P5E_PEX1_STN0_TX_DP<8>")
		)
		(pad "2" smd rect
			(at 0.2667 0 180)
			(size 0.3048 0.381)
			(layers "F.Cu" "F.Mask" "F.Paste")
			(net "P5E_PEX1_STN0_TX_C_DP<8>")
		)
	)
	(footprint ""
		(layer "F.Cu")
		(at 332.512162 -236.871256 -90)
		(property "Reference" "R1787"
			(at 0 0 270)
			(layer "F.SilkS")
			(hide yes)
			(effects
				(font
					(size 1.27 1.27)
				)
			)
		)
		(property "Value" ""
			(at 0 0 270)
			(layer "F.Fab")
			(effects
				(font
					(size 1.27 1.27)
				)
			)
		)
		(duplicate_pad_numbers_are_jumpers no)
		(fp_line
			(start -0.7874 0.4064)
			(end -0.7874 -0.4064)
			(stroke
				(width 0.1524)
				(type default)
			)
			(layer "F.SilkS")
		)
		(fp_line
			(start 0.7874 0.4064)
			(end -0.7874 0.4064)
			(stroke
				(width 0.1524)
				(type default)
			)
			(layer "F.SilkS")
		)
		(fp_line
			(start -0.7874 -0.4064)
			(end 0.7874 -0.4064)
			(stroke
				(width 0.1524)
				(type default)
			)
			(layer "F.SilkS")
		)
		(fp_line
			(start 0.7874 -0.4064)
			(end 0.7874 0.4064)
			(stroke
				(width 0.1524)
				(type default)
			)
			(layer "F.SilkS")
		)
		(fp_line
			(start -0.67945 0.3048)
			(end -0.67945 -0.305054)
			(stroke
				(width 0.1)
				(type default)
			)
			(layer "F.Fab")
		)
		(fp_line
			(start -0.12065 0.3048)
			(end -0.67945 0.3048)
			(stroke
				(width 0.1)
				(type default)
			)
			(layer "F.Fab")
		)
		(fp_line
			(start 0.120396 0.3048)
			(end 0.120396 0.2794)
			(stroke
				(width 0.1)
				(type default)
			)
			(layer "F.Fab")
		)
		(fp_line
			(start 0.67945 0.3048)
			(end 0.120396 0.3048)
			(stroke
				(width 0.1)
				(type default)
			)
			(layer "F.Fab")
		)
		(fp_line
			(start -0.12065 0.2794)
			(end -0.12065 0.3048)
			(stroke
				(width 0.1)
				(type default)
			)
			(layer "F.Fab")
		)
		(fp_line
			(start 0.120396 0.2794)
			(end -0.12065 0.2794)
			(stroke
				(width 0.1)
				(type default)
			)
			(layer "F.Fab")
		)
		(fp_line
			(start -0.12065 -0.2794)
			(end 0.12065 -0.2794)
			(stroke
				(width 0.1)
				(type default)
			)
			(layer "F.Fab")
		)
		(fp_line
			(start 0.12065 -0.2794)
			(end 0.12065 -0.3048)
			(stroke
				(width 0.1)
				(type default)
			)
			(layer "F.Fab")
		)
		(fp_line
			(start 0.12065 -0.3048)
			(end 0.67945 -0.3048)
			(stroke
				(width 0.1)
				(type default)
			)
			(layer "F.Fab")
		)
		(fp_line
			(start 0.67945 -0.3048)
			(end 0.67945 0.3048)
			(stroke
				(width 0.1)
				(type default)
			)
			(layer "F.Fab")
		)
		(fp_line
			(start -0.67945 -0.305054)
			(end -0.12065 -0.305054)
			(stroke
				(width 0.1)
				(type default)
			)
			(layer "F.Fab")
		)
		(fp_line
			(start -0.12065 -0.305054)
			(end -0.12065 -0.2794)
			(stroke
				(width 0.1)
				(type default)
			)
			(layer "F.Fab")
		)
		(pad "1" smd circle
			(at -0.40005 0 270)
			(size 0 0)
			(layers "F.Cu" "F.Mask" "F.Paste")
			(net "P3V3_AUX")
		)
		(pad "2" smd circle
			(at 0.40005 0 270)
			(size 0 0)
			(layers "F.Cu" "F.Mask" "F.Paste")
			(net "RST_MB_PERST_1_ISO_R_N")
		)
	)
	(footprint ""
		(layer "F.Cu")
		(at 148.511514 -283.643832 -90)
		(property "Reference" "R4575"
			(at 0 0 270)
			(layer "F.SilkS")
			(hide yes)
			(effects
				(font
					(size 1.27 1.27)
				)
			)
		)
		(property "Value" ""
			(at 0 0 270)
			(layer "F.Fab")
			(effects
				(font
					(size 1.27 1.27)
				)
			)
		)
		(duplicate_pad_numbers_are_jumpers no)
		(fp_line
			(start -0.7874 0.4064)
			(end -0.7874 -0.4064)
			(stroke
				(width 0.1524)
				(type default)
			)
			(layer "F.SilkS")
		)
		(fp_line
			(start 0.7874 0.4064)
			(end -0.7874 0.4064)
			(stroke
				(width 0.1524)
				(type default)
			)
			(layer "F.SilkS")
		)
		(fp_line
			(start -0.7874 -0.4064)
			(end 0.7874 -0.4064)
			(stroke
				(width 0.1524)
				(type default)
			)
			(layer "F.SilkS")
		)
		(fp_line
			(start 0.7874 -0.4064)
			(end 0.7874 0.4064)
			(stroke
				(width 0.1524)
				(type default)
			)
			(layer "F.SilkS")
		)
		(fp_line
			(start -0.67945 0.3048)
			(end -0.67945 -0.305054)
			(stroke
				(width 0.1)
				(type default)
			)
			(layer "F.Fab")
		)
		(fp_line
			(start -0.12065 0.3048)
			(end -0.67945 0.3048)
			(stroke
				(width 0.1)
				(type default)
			)
			(layer "F.Fab")
		)
		(fp_line
			(start 0.120396 0.3048)
			(end 0.120396 0.2794)
			(stroke
				(width 0.1)
				(type default)
			)
			(layer "F.Fab")
		)
		(fp_line
			(start 0.67945 0.3048)
			(end 0.120396 0.3048)
			(stroke
				(width 0.1)
				(type default)
			)
			(layer "F.Fab")
		)
		(fp_line
			(start -0.12065 0.2794)
			(end -0.12065 0.3048)
			(stroke
				(width 0.1)
				(type default)
			)
			(layer "F.Fab")
		)
		(fp_line
			(start 0.120396 0.2794)
			(end -0.12065 0.2794)
			(stroke
				(width 0.1)
				(type default)
			)
			(layer "F.Fab")
		)
		(fp_line
			(start -0.12065 -0.2794)
			(end 0.12065 -0.2794)
			(stroke
				(width 0.1)
				(type default)
			)
			(layer "F.Fab")
		)
		(fp_line
			(start 0.12065 -0.2794)
			(end 0.12065 -0.3048)
			(stroke
				(width 0.1)
				(type default)
			)
			(layer "F.Fab")
		)
		(fp_line
			(start 0.12065 -0.3048)
			(end 0.67945 -0.3048)
			(stroke
				(width 0.1)
				(type default)
			)
			(layer "F.Fab")
		)
		(fp_line
			(start 0.67945 -0.3048)
			(end 0.67945 0.3048)
			(stroke
				(width 0.1)
				(type default)
			)
			(layer "F.Fab")
		)
		(fp_line
			(start -0.67945 -0.305054)
			(end -0.12065 -0.305054)
			(stroke
				(width 0.1)
				(type default)
			)
			(layer "F.Fab")
		)
		(fp_line
			(start -0.12065 -0.305054)
			(end -0.12065 -0.2794)
			(stroke
				(width 0.1)
				(type default)
			)
			(layer "F.Fab")
		)
		(pad "1" smd circle
			(at -0.40005 0 270)
			(size 0 0)
			(layers "F.Cu" "F.Mask" "F.Paste")
			(net "PCEPLL7_VDDA18_PEX1")
		)
		(pad "2" smd circle
			(at 0.40005 0 270)
			(size 0 0)
			(layers "F.Cu" "F.Mask" "F.Paste")
			(net "PCEPLL7_VDDA18_PEX1_R")
		)
	)
	(footprint ""
		(layer "F.Cu")
		(at 201.857864 -299.04055 -90)
		(property "Reference" "C4186"
			(at 0 0 270)
			(layer "F.SilkS")
			(hide yes)
			(effects
				(font
					(size 1.27 1.27)
				)
			)
		)
		(property "Value" ""
			(at 0 0 270)
			(layer "F.Fab")
			(effects
				(font
					(size 1.27 1.27)
				)
			)
		)
		(duplicate_pad_numbers_are_jumpers no)
		(fp_line
			(start -0.7874 0.4064)
			(end -0.7874 -0.4064)
			(stroke
				(width 0.1524)
				(type default)
			)
			(layer "F.SilkS")
		)
		(fp_line
			(start 0.7874 0.4064)
			(end -0.7874 0.4064)
			(stroke
				(width 0.1524)
				(type default)
			)
			(layer "F.SilkS")
		)
		(fp_line
			(start -0.7874 -0.4064)
			(end 0.7874 -0.4064)
			(stroke
				(width 0.1524)
				(type default)
			)
			(layer "F.SilkS")
		)
		(fp_line
			(start 0.7874 -0.4064)
			(end 0.7874 0.4064)
			(stroke
				(width 0.1524)
				(type default)
			)
			(layer "F.SilkS")
		)
		(fp_line
			(start -0.67945 0.3048)
			(end -0.67945 -0.305054)
			(stroke
				(width 0.1)
				(type default)
			)
			(layer "F.Fab")
		)
		(fp_line
			(start -0.12065 0.3048)
			(end -0.67945 0.3048)
			(stroke
				(width 0.1)
				(type default)
			)
			(layer "F.Fab")
		)
		(fp_line
			(start 0.120396 0.3048)
			(end 0.120396 0.2794)
			(stroke
				(width 0.1)
				(type default)
			)
			(layer "F.Fab")
		)
		(fp_line
			(start 0.67945 0.3048)
			(end 0.120396 0.3048)
			(stroke
				(width 0.1)
				(type default)
			)
			(layer "F.Fab")
		)
		(fp_line
			(start -0.12065 0.2794)
			(end -0.12065 0.3048)
			(stroke
				(width 0.1)
				(type default)
			)
			(layer "F.Fab")
		)
		(fp_line
			(start 0.120396 0.2794)
			(end -0.12065 0.2794)
			(stroke
				(width 0.1)
				(type default)
			)
			(layer "F.Fab")
		)
		(fp_line
			(start -0.12065 -0.2794)
			(end 0.12065 -0.2794)
			(stroke
				(width 0.1)
				(type default)
			)
			(layer "F.Fab")
		)
		(fp_line
			(start 0.12065 -0.2794)
			(end 0.12065 -0.3048)
			(stroke
				(width 0.1)
				(type default)
			)
			(layer "F.Fab")
		)
		(fp_line
			(start 0.12065 -0.3048)
			(end 0.67945 -0.3048)
			(stroke
				(width 0.1)
				(type default)
			)
			(layer "F.Fab")
		)
		(fp_line
			(start 0.67945 -0.3048)
			(end 0.67945 0.3048)
			(stroke
				(width 0.1)
				(type default)
			)
			(layer "F.Fab")
		)
		(fp_line
			(start -0.67945 -0.305054)
			(end -0.12065 -0.305054)
			(stroke
				(width 0.1)
				(type default)
			)
			(layer "F.Fab")
		)
		(fp_line
			(start -0.12065 -0.305054)
			(end -0.12065 -0.2794)
			(stroke
				(width 0.1)
				(type default)
			)
			(layer "F.Fab")
		)
		(pad "1" smd circle
			(at -0.40005 0 270)
			(size 0 0)
			(layers "F.Cu" "F.Mask" "F.Paste")
			(net "GND")
		)
		(pad "2" smd circle
			(at 0.40005 0 270)
			(size 0 0)
			(layers "F.Cu" "F.Mask" "F.Paste")
			(net "P1V8_PEX")
		)
	)
	(footprint ""
		(layer "F.Cu")
		(at 319.913 -85.344 180)
		(property "Reference" "R6258"
			(at 0 0 180)
			(layer "F.SilkS")
			(hide yes)
			(effects
				(font
					(size 1.27 1.27)
				)
			)
		)
		(property "Value" ""
			(at 0 0 180)
			(layer "F.Fab")
			(effects
				(font
					(size 1.27 1.27)
				)
			)
		)
		(duplicate_pad_numbers_are_jumpers no)
		(fp_line
			(start 0.7874 0.4064)
			(end -0.7874 0.4064)
			(stroke
				(width 0.1524)
				(type default)
			)
			(layer "F.SilkS")
		)
		(fp_line
			(start 0.7874 -0.4064)
			(end 0.7874 0.4064)
			(stroke
				(width 0.1524)
				(type default)
			)
			(layer "F.SilkS")
		)
		(fp_line
			(start -0.7874 0.4064)
			(end -0.7874 -0.4064)
			(stroke
				(width 0.1524)
				(type default)
			)
			(layer "F.SilkS")
		)
		(fp_line
			(start -0.7874 -0.4064)
			(end 0.7874 -0.4064)
			(stroke
				(width 0.1524)
				(type default)
			)
			(layer "F.SilkS")
		)
		(fp_line
			(start 0.67945 0.3048)
			(end 0.120396 0.3048)
			(stroke
				(width 0.1)
				(type default)
			)
			(layer "F.Fab")
		)
		(fp_line
			(start 0.67945 -0.3048)
			(end 0.67945 0.3048)
			(stroke
				(width 0.1)
				(type default)
			)
			(layer "F.Fab")
		)
		(fp_line
			(start 0.12065 -0.2794)
			(end 0.12065 -0.3048)
			(stroke
				(width 0.1)
				(type default)
			)
			(layer "F.Fab")
		)
		(fp_line
			(start 0.12065 -0.3048)
			(end 0.67945 -0.3048)
			(stroke
				(width 0.1)
				(type default)
			)
			(layer "F.Fab")
		)
		(fp_line
			(start 0.120396 0.3048)
			(end 0.120396 0.2794)
			(stroke
				(width 0.1)
				(type default)
			)
			(layer "F.Fab")
		)
		(fp_line
			(start 0.120396 0.2794)
			(end -0.12065 0.2794)
			(stroke
				(width 0.1)
				(type default)
			)
			(layer "F.Fab")
		)
		(fp_line
			(start -0.12065 0.3048)
			(end -0.67945 0.3048)
			(stroke
				(width 0.1)
				(type default)
			)
			(layer "F.Fab")
		)
		(fp_line
			(start -0.12065 0.2794)
			(end -0.12065 0.3048)
			(stroke
				(width 0.1)
				(type default)
			)
			(layer "F.Fab")
		)
		(fp_line
			(start -0.12065 -0.2794)
			(end 0.12065 -0.2794)
			(stroke
				(width 0.1)
				(type default)
			)
			(layer "F.Fab")
		)
		(fp_line
			(start -0.12065 -0.305054)
			(end -0.12065 -0.2794)
			(stroke
				(width 0.1)
				(type default)
			)
			(layer "F.Fab")
		)
		(fp_line
			(start -0.67945 0.3048)
			(end -0.67945 -0.305054)
			(stroke
				(width 0.1)
				(type default)
			)
			(layer "F.Fab")
		)
		(fp_line
			(start -0.67945 -0.305054)
			(end -0.12065 -0.305054)
			(stroke
				(width 0.1)
				(type default)
			)
			(layer "F.Fab")
		)
		(pad "1" smd circle
			(at -0.40005 0 180)
			(size 0 0)
			(layers "F.Cu" "F.Mask" "F.Paste")
			(net "CB_ISO_EN")
		)
		(pad "2" smd circle
			(at 0.40005 0 180)
			(size 0 0)
			(layers "F.Cu" "F.Mask" "F.Paste")
			(net "P3V3_AUX")
		)
	)
	(footprint ""
		(layer "F.Cu")
		(at 220.34373 -49.95291 180)
		(property "Reference" "R588"
			(at 0 0 180)
			(layer "F.SilkS")
			(hide yes)
			(effects
				(font
					(size 1.27 1.27)
				)
			)
		)
		(property "Value" ""
			(at 0 0 180)
			(layer "F.Fab")
			(effects
				(font
					(size 1.27 1.27)
				)
			)
		)
		(duplicate_pad_numbers_are_jumpers no)
		(fp_line
			(start 0.7874 0.4064)
			(end -0.7874 0.4064)
			(stroke
				(width 0.1524)
				(type default)
			)
			(layer "F.SilkS")
		)
		(fp_line
			(start 0.7874 -0.4064)
			(end 0.7874 0.4064)
			(stroke
				(width 0.1524)
				(type default)
			)
			(layer "F.SilkS")
		)
		(fp_line
			(start -0.7874 0.4064)
			(end -0.7874 -0.4064)
			(stroke
				(width 0.1524)
				(type default)
			)
			(layer "F.SilkS")
		)
		(fp_line
			(start -0.7874 -0.4064)
			(end 0.7874 -0.4064)
			(stroke
				(width 0.1524)
				(type default)
			)
			(layer "F.SilkS")
		)
		(fp_line
			(start 0.67945 0.3048)
			(end 0.120396 0.3048)
			(stroke
				(width 0.1)
				(type default)
			)
			(layer "F.Fab")
		)
		(fp_line
			(start 0.67945 -0.3048)
			(end 0.67945 0.3048)
			(stroke
				(width 0.1)
				(type default)
			)
			(layer "F.Fab")
		)
		(fp_line
			(start 0.12065 -0.2794)
			(end 0.12065 -0.3048)
			(stroke
				(width 0.1)
				(type default)
			)
			(layer "F.Fab")
		)
		(fp_line
			(start 0.12065 -0.3048)
			(end 0.67945 -0.3048)
			(stroke
				(width 0.1)
				(type default)
			)
			(layer "F.Fab")
		)
		(fp_line
			(start 0.120396 0.3048)
			(end 0.120396 0.2794)
			(stroke
				(width 0.1)
				(type default)
			)
			(layer "F.Fab")
		)
		(fp_line
			(start 0.120396 0.2794)
			(end -0.12065 0.2794)
			(stroke
				(width 0.1)
				(type default)
			)
			(layer "F.Fab")
		)
		(fp_line
			(start -0.12065 0.3048)
			(end -0.67945 0.3048)
			(stroke
				(width 0.1)
				(type default)
			)
			(layer "F.Fab")
		)
		(fp_line
			(start -0.12065 0.2794)
			(end -0.12065 0.3048)
			(stroke
				(width 0.1)
				(type default)
			)
			(layer "F.Fab")
		)
		(fp_line
			(start -0.12065 -0.2794)
			(end 0.12065 -0.2794)
			(stroke
				(width 0.1)
				(type default)
			)
			(layer "F.Fab")
		)
		(fp_line
			(start -0.12065 -0.305054)
			(end -0.12065 -0.2794)
			(stroke
				(width 0.1)
				(type default)
			)
			(layer "F.Fab")
		)
		(fp_line
			(start -0.67945 0.3048)
			(end -0.67945 -0.305054)
			(stroke
				(width 0.1)
				(type default)
			)
			(layer "F.Fab")
		)
		(fp_line
			(start -0.67945 -0.305054)
			(end -0.12065 -0.305054)
			(stroke
				(width 0.1)
				(type default)
			)
			(layer "F.Fab")
		)
		(pad "1" smd circle
			(at -0.40005 0 180)
			(size 0 0)
			(layers "F.Cu" "F.Mask" "F.Paste")
			(net "SMB_BIC_I2C6_MUX_SSD_0_7_ADC_R_SCL")
		)
		(pad "2" smd circle
			(at 0.40005 0 180)
			(size 0 0)
			(layers "F.Cu" "F.Mask" "F.Paste")
			(net "SMB_SSD7_ADC_SCL")
		)
	)
	(footprint ""
		(layer "F.Cu")
		(at 409.015438 -85.408008 180)
		(property "Reference" "C3995"
			(at 0 0 180)
			(layer "F.SilkS")
			(hide yes)
			(effects
				(font
					(size 1.27 1.27)
				)
			)
		)
		(property "Value" ""
			(at 0 0 180)
			(layer "F.Fab")
			(effects
				(font
					(size 1.27 1.27)
				)
			)
		)
		(duplicate_pad_numbers_are_jumpers no)
		(fp_line
			(start 0.7874 0.4064)
			(end -0.7874 0.4064)
			(stroke
				(width 0.1524)
				(type default)
			)
			(layer "F.SilkS")
		)
		(fp_line
			(start 0.7874 -0.4064)
			(end 0.7874 0.4064)
			(stroke
				(width 0.1524)
				(type default)
			)
			(layer "F.SilkS")
		)
		(fp_line
			(start -0.7874 0.4064)
			(end -0.7874 -0.4064)
			(stroke
				(width 0.1524)
				(type default)
			)
			(layer "F.SilkS")
		)
		(fp_line
			(start -0.7874 -0.4064)
			(end 0.7874 -0.4064)
			(stroke
				(width 0.1524)
				(type default)
			)
			(layer "F.SilkS")
		)
		(fp_line
			(start 0.67945 0.3048)
			(end 0.120396 0.3048)
			(stroke
				(width 0.1)
				(type default)
			)
			(layer "F.Fab")
		)
		(fp_line
			(start 0.67945 -0.3048)
			(end 0.67945 0.3048)
			(stroke
				(width 0.1)
				(type default)
			)
			(layer "F.Fab")
		)
		(fp_line
			(start 0.12065 -0.2794)
			(end 0.12065 -0.3048)
			(stroke
				(width 0.1)
				(type default)
			)
			(layer "F.Fab")
		)
		(fp_line
			(start 0.12065 -0.3048)
			(end 0.67945 -0.3048)
			(stroke
				(width 0.1)
				(type default)
			)
			(layer "F.Fab")
		)
		(fp_line
			(start 0.120396 0.3048)
			(end 0.120396 0.2794)
			(stroke
				(width 0.1)
				(type default)
			)
			(layer "F.Fab")
		)
		(fp_line
			(start 0.120396 0.2794)
			(end -0.12065 0.2794)
			(stroke
				(width 0.1)
				(type default)
			)
			(layer "F.Fab")
		)
		(fp_line
			(start -0.12065 0.3048)
			(end -0.67945 0.3048)
			(stroke
				(width 0.1)
				(type default)
			)
			(layer "F.Fab")
		)
		(fp_line
			(start -0.12065 0.2794)
			(end -0.12065 0.3048)
			(stroke
				(width 0.1)
				(type default)
			)
			(layer "F.Fab")
		)
		(fp_line
			(start -0.12065 -0.2794)
			(end 0.12065 -0.2794)
			(stroke
				(width 0.1)
				(type default)
			)
			(layer "F.Fab")
		)
		(fp_line
			(start -0.12065 -0.305054)
			(end -0.12065 -0.2794)
			(stroke
				(width 0.1)
				(type default)
			)
			(layer "F.Fab")
		)
		(fp_line
			(start -0.67945 0.3048)
			(end -0.67945 -0.305054)
			(stroke
				(width 0.1)
				(type default)
			)
			(layer "F.Fab")
		)
		(fp_line
			(start -0.67945 -0.305054)
			(end -0.12065 -0.305054)
			(stroke
				(width 0.1)
				(type default)
			)
			(layer "F.Fab")
		)
		(pad "1" smd circle
			(at -0.40005 0 180)
			(size 0 0)
			(layers "F.Cu" "F.Mask" "F.Paste")
			(net "GND")
		)
		(pad "2" smd circle
			(at 0.40005 0 180)
			(size 0 0)
			(layers "F.Cu" "F.Mask" "F.Paste")
			(net "P3V3")
		)
	)
	(footprint ""
		(layer "F.Cu")
		(at 295.877742 -115.283742 180)
		(property "Reference" "R292"
			(at 0 0 180)
			(layer "F.SilkS")
			(hide yes)
			(effects
				(font
					(size 1.27 1.27)
				)
			)
		)
		(property "Value" ""
			(at 0 0 180)
			(layer "F.Fab")
			(effects
				(font
					(size 1.27 1.27)
				)
			)
		)
		(duplicate_pad_numbers_are_jumpers no)
		(fp_line
			(start 0.7874 0.4064)
			(end -0.7874 0.4064)
			(stroke
				(width 0.1524)
				(type default)
			)
			(layer "F.SilkS")
		)
		(fp_line
			(start 0.7874 -0.4064)
			(end 0.7874 0.4064)
			(stroke
				(width 0.1524)
				(type default)
			)
			(layer "F.SilkS")
		)
		(fp_line
			(start -0.7874 0.4064)
			(end -0.7874 -0.4064)
			(stroke
				(width 0.1524)
				(type default)
			)
			(layer "F.SilkS")
		)
		(fp_line
			(start -0.7874 -0.4064)
			(end 0.7874 -0.4064)
			(stroke
				(width 0.1524)
				(type default)
			)
			(layer "F.SilkS")
		)
		(fp_line
			(start 0.67945 0.3048)
			(end 0.120396 0.3048)
			(stroke
				(width 0.1)
				(type default)
			)
			(layer "F.Fab")
		)
		(fp_line
			(start 0.67945 -0.3048)
			(end 0.67945 0.3048)
			(stroke
				(width 0.1)
				(type default)
			)
			(layer "F.Fab")
		)
		(fp_line
			(start 0.12065 -0.2794)
			(end 0.12065 -0.3048)
			(stroke
				(width 0.1)
				(type default)
			)
			(layer "F.Fab")
		)
		(fp_line
			(start 0.12065 -0.3048)
			(end 0.67945 -0.3048)
			(stroke
				(width 0.1)
				(type default)
			)
			(layer "F.Fab")
		)
		(fp_line
			(start 0.120396 0.3048)
			(end 0.120396 0.2794)
			(stroke
				(width 0.1)
				(type default)
			)
			(layer "F.Fab")
		)
		(fp_line
			(start 0.120396 0.2794)
			(end -0.12065 0.2794)
			(stroke
				(width 0.1)
				(type default)
			)
			(layer "F.Fab")
		)
		(fp_line
			(start -0.12065 0.3048)
			(end -0.67945 0.3048)
			(stroke
				(width 0.1)
				(type default)
			)
			(layer "F.Fab")
		)
		(fp_line
			(start -0.12065 0.2794)
			(end -0.12065 0.3048)
			(stroke
				(width 0.1)
				(type default)
			)
			(layer "F.Fab")
		)
		(fp_line
			(start -0.12065 -0.2794)
			(end 0.12065 -0.2794)
			(stroke
				(width 0.1)
				(type default)
			)
			(layer "F.Fab")
		)
		(fp_line
			(start -0.12065 -0.305054)
			(end -0.12065 -0.2794)
			(stroke
				(width 0.1)
				(type default)
			)
			(layer "F.Fab")
		)
		(fp_line
			(start -0.67945 0.3048)
			(end -0.67945 -0.305054)
			(stroke
				(width 0.1)
				(type default)
			)
			(layer "F.Fab")
		)
		(fp_line
			(start -0.67945 -0.305054)
			(end -0.12065 -0.305054)
			(stroke
				(width 0.1)
				(type default)
			)
			(layer "F.Fab")
		)
		(pad "1" smd circle
			(at -0.40005 0 180)
			(size 0 0)
			(layers "F.Cu" "F.Mask" "F.Paste")
			(net "RST_SMB_NIC5_MUX_ISO_R_N")
		)
		(pad "2" smd circle
			(at 0.40005 0 180)
			(size 0 0)
			(layers "F.Cu" "F.Mask" "F.Paste")
			(net "RST_SMB_NIC5_MUX_ISO_N")
		)
	)
	(footprint ""
		(layer "F.Cu")
		(at 17.326102 -266.899136)
		(property "Reference" "C4225"
			(at 0 0 0)
			(layer "F.SilkS")
			(hide yes)
			(effects
				(font
					(size 1.27 1.27)
				)
			)
		)
		(property "Value" ""
			(at 0 0 0)
			(layer "F.Fab")
			(effects
				(font
					(size 1.27 1.27)
				)
			)
		)
		(duplicate_pad_numbers_are_jumpers no)
		(fp_line
			(start -0.299974 -0.150114)
			(end 0.299974 -0.150114)
			(stroke
				(width 0.1)
				(type default)
			)
			(layer "F.Fab")
		)
		(fp_line
			(start -0.299974 0.150114)
			(end -0.299974 -0.150114)
			(stroke
				(width 0.1)
				(type default)
			)
			(layer "F.Fab")
		)
		(fp_line
			(start 0.299974 -0.150114)
			(end 0.299974 0.150114)
			(stroke
				(width 0.1)
				(type default)
			)
			(layer "F.Fab")
		)
		(fp_line
			(start 0.299974 0.150114)
			(end -0.299974 0.150114)
			(stroke
				(width 0.1)
				(type default)
			)
			(layer "F.Fab")
		)
		(pad "1" smd rect
			(at -0.2667 0)
			(size 0.3048 0.381)
			(layers "F.Cu" "F.Mask" "F.Paste")
			(net "P1V25_SERDES_VDDPLL_PEX0")
		)
		(pad "2" smd rect
			(at 0.2667 0)
			(size 0.3048 0.381)
			(layers "F.Cu" "F.Mask" "F.Paste")
			(net "GND")
		)
	)
	(footprint ""
		(layer "F.Cu")
		(at 138.920728 -70.307454 90)
		(property "Reference" "PC839"
			(at 0 0 90)
			(layer "F.SilkS")
			(hide yes)
			(effects
				(font
					(size 1.27 1.27)
				)
			)
		)
		(property "Value" ""
			(at 0 0 90)
			(layer "F.Fab")
			(effects
				(font
					(size 1.27 1.27)
				)
			)
		)
		(duplicate_pad_numbers_are_jumpers no)
		(fp_line
			(start 0.7874 -0.4064)
			(end 0.7874 0.4064)
			(stroke
				(width 0.1524)
				(type default)
			)
			(layer "F.SilkS")
		)
		(fp_line
			(start -0.7874 -0.4064)
			(end 0.7874 -0.4064)
			(stroke
				(width 0.1524)
				(type default)
			)
			(layer "F.SilkS")
		)
		(fp_line
			(start 0.7874 0.4064)
			(end -0.7874 0.4064)
			(stroke
				(width 0.1524)
				(type default)
			)
			(layer "F.SilkS")
		)
		(fp_line
			(start -0.7874 0.4064)
			(end -0.7874 -0.4064)
			(stroke
				(width 0.1524)
				(type default)
			)
			(layer "F.SilkS")
		)
		(fp_line
			(start -0.12065 -0.305054)
			(end -0.12065 -0.2794)
			(stroke
				(width 0.1)
				(type default)
			)
			(layer "F.Fab")
		)
		(fp_line
			(start -0.67945 -0.305054)
			(end -0.12065 -0.305054)
			(stroke
				(width 0.1)
				(type default)
			)
			(layer "F.Fab")
		)
		(fp_line
			(start 0.67945 -0.3048)
			(end 0.67945 0.3048)
			(stroke
				(width 0.1)
				(type default)
			)
			(layer "F.Fab")
		)
		(fp_line
			(start 0.12065 -0.3048)
			(end 0.67945 -0.3048)
			(stroke
				(width 0.1)
				(type default)
			)
			(layer "F.Fab")
		)
		(fp_line
			(start 0.12065 -0.2794)
			(end 0.12065 -0.3048)
			(stroke
				(width 0.1)
				(type default)
			)
			(layer "F.Fab")
		)
		(fp_line
			(start -0.12065 -0.2794)
			(end 0.12065 -0.2794)
			(stroke
				(width 0.1)
				(type default)
			)
			(layer "F.Fab")
		)
		(fp_line
			(start 0.120396 0.2794)
			(end -0.12065 0.2794)
			(stroke
				(width 0.1)
				(type default)
			)
			(layer "F.Fab")
		)
		(fp_line
			(start -0.12065 0.2794)
			(end -0.12065 0.3048)
			(stroke
				(width 0.1)
				(type default)
			)
			(layer "F.Fab")
		)
		(fp_line
			(start 0.67945 0.3048)
			(end 0.120396 0.3048)
			(stroke
				(width 0.1)
				(type default)
			)
			(layer "F.Fab")
		)
		(fp_line
			(start 0.120396 0.3048)
			(end 0.120396 0.2794)
			(stroke
				(width 0.1)
				(type default)
			)
			(layer "F.Fab")
		)
		(fp_line
			(start -0.12065 0.3048)
			(end -0.67945 0.3048)
			(stroke
				(width 0.1)
				(type default)
			)
			(layer "F.Fab")
		)
		(fp_line
			(start -0.67945 0.3048)
			(end -0.67945 -0.305054)
			(stroke
				(width 0.1)
				(type default)
			)
			(layer "F.Fab")
		)
		(pad "1" smd circle
			(at -0.40005 0 90)
			(size 0 0)
			(layers "F.Cu" "F.Mask" "F.Paste")
			(net "P12V_AUX")
		)
		(pad "2" smd circle
			(at 0.40005 0 90)
			(size 0 0)
			(layers "F.Cu" "F.Mask" "F.Paste")
			(net "GND")
		)
	)
	(footprint ""
		(layer "F.Cu")
		(at 353.956366 -61.487812 180)
		(property "Reference" "R6012"
			(at 0 0 180)
			(layer "F.SilkS")
			(hide yes)
			(effects
				(font
					(size 1.27 1.27)
				)
			)
		)
		(property "Value" ""
			(at 0 0 180)
			(layer "F.Fab")
			(effects
				(font
					(size 1.27 1.27)
				)
			)
		)
		(duplicate_pad_numbers_are_jumpers no)
		(fp_line
			(start 0.7874 0.4064)
			(end -0.7874 0.4064)
			(stroke
				(width 0.1524)
				(type default)
			)
			(layer "F.SilkS")
		)
		(fp_line
			(start 0.7874 -0.4064)
			(end 0.7874 0.4064)
			(stroke
				(width 0.1524)
				(type default)
			)
			(layer "F.SilkS")
		)
		(fp_line
			(start -0.7874 0.4064)
			(end -0.7874 -0.4064)
			(stroke
				(width 0.1524)
				(type default)
			)
			(layer "F.SilkS")
		)
		(fp_line
			(start -0.7874 -0.4064)
			(end 0.7874 -0.4064)
			(stroke
				(width 0.1524)
				(type default)
			)
			(layer "F.SilkS")
		)
		(fp_line
			(start 0.67945 0.3048)
			(end 0.120396 0.3048)
			(stroke
				(width 0.1)
				(type default)
			)
			(layer "F.Fab")
		)
		(fp_line
			(start 0.67945 -0.3048)
			(end 0.67945 0.3048)
			(stroke
				(width 0.1)
				(type default)
			)
			(layer "F.Fab")
		)
		(fp_line
			(start 0.12065 -0.2794)
			(end 0.12065 -0.3048)
			(stroke
				(width 0.1)
				(type default)
			)
			(layer "F.Fab")
		)
		(fp_line
			(start 0.12065 -0.3048)
			(end 0.67945 -0.3048)
			(stroke
				(width 0.1)
				(type default)
			)
			(layer "F.Fab")
		)
		(fp_line
			(start 0.120396 0.3048)
			(end 0.120396 0.2794)
			(stroke
				(width 0.1)
				(type default)
			)
			(layer "F.Fab")
		)
		(fp_line
			(start 0.120396 0.2794)
			(end -0.12065 0.2794)
			(stroke
				(width 0.1)
				(type default)
			)
			(layer "F.Fab")
		)
		(fp_line
			(start -0.12065 0.3048)
			(end -0.67945 0.3048)
			(stroke
				(width 0.1)
				(type default)
			)
			(layer "F.Fab")
		)
		(fp_line
			(start -0.12065 0.2794)
			(end -0.12065 0.3048)
			(stroke
				(width 0.1)
				(type default)
			)
			(layer "F.Fab")
		)
		(fp_line
			(start -0.12065 -0.2794)
			(end 0.12065 -0.2794)
			(stroke
				(width 0.1)
				(type default)
			)
			(layer "F.Fab")
		)
		(fp_line
			(start -0.12065 -0.305054)
			(end -0.12065 -0.2794)
			(stroke
				(width 0.1)
				(type default)
			)
			(layer "F.Fab")
		)
		(fp_line
			(start -0.67945 0.3048)
			(end -0.67945 -0.305054)
			(stroke
				(width 0.1)
				(type default)
			)
			(layer "F.Fab")
		)
		(fp_line
			(start -0.67945 -0.305054)
			(end -0.12065 -0.305054)
			(stroke
				(width 0.1)
				(type default)
			)
			(layer "F.Fab")
		)
		(pad "1" smd circle
			(at -0.40005 0 180)
			(size 0 0)
			(layers "F.Cu" "F.Mask" "F.Paste")
			(net "P3V3_AUX")
		)
		(pad "2" smd circle
			(at 0.40005 0 180)
			(size 0 0)
			(layers "F.Cu" "F.Mask" "F.Paste")
			(net "PWRGD_P12V_SSD12_D")
		)
	)
	(footprint ""
		(layer "F.Cu")
		(at 202.90409 -289.230816 90)
		(property "Reference" "R3948"
			(at 0 0 90)
			(layer "F.SilkS")
			(hide yes)
			(effects
				(font
					(size 1.27 1.27)
				)
			)
		)
		(property "Value" ""
			(at 0 0 90)
			(layer "F.Fab")
			(effects
				(font
					(size 1.27 1.27)
				)
			)
		)
		(duplicate_pad_numbers_are_jumpers no)
		(fp_line
			(start 0.7874 -0.4064)
			(end 0.7874 0.4064)
			(stroke
				(width 0.1524)
				(type default)
			)
			(layer "F.SilkS")
		)
		(fp_line
			(start -0.7874 -0.4064)
			(end 0.7874 -0.4064)
			(stroke
				(width 0.1524)
				(type default)
			)
			(layer "F.SilkS")
		)
		(fp_line
			(start 0.7874 0.4064)
			(end -0.7874 0.4064)
			(stroke
				(width 0.1524)
				(type default)
			)
			(layer "F.SilkS")
		)
		(fp_line
			(start -0.7874 0.4064)
			(end -0.7874 -0.4064)
			(stroke
				(width 0.1524)
				(type default)
			)
			(layer "F.SilkS")
		)
		(fp_line
			(start -0.12065 -0.305054)
			(end -0.12065 -0.2794)
			(stroke
				(width 0.1)
				(type default)
			)
			(layer "F.Fab")
		)
		(fp_line
			(start -0.67945 -0.305054)
			(end -0.12065 -0.305054)
			(stroke
				(width 0.1)
				(type default)
			)
			(layer "F.Fab")
		)
		(fp_line
			(start 0.67945 -0.3048)
			(end 0.67945 0.3048)
			(stroke
				(width 0.1)
				(type default)
			)
			(layer "F.Fab")
		)
		(fp_line
			(start 0.12065 -0.3048)
			(end 0.67945 -0.3048)
			(stroke
				(width 0.1)
				(type default)
			)
			(layer "F.Fab")
		)
		(fp_line
			(start 0.12065 -0.2794)
			(end 0.12065 -0.3048)
			(stroke
				(width 0.1)
				(type default)
			)
			(layer "F.Fab")
		)
		(fp_line
			(start -0.12065 -0.2794)
			(end 0.12065 -0.2794)
			(stroke
				(width 0.1)
				(type default)
			)
			(layer "F.Fab")
		)
		(fp_line
			(start 0.120396 0.2794)
			(end -0.12065 0.2794)
			(stroke
				(width 0.1)
				(type default)
			)
			(layer "F.Fab")
		)
		(fp_line
			(start -0.12065 0.2794)
			(end -0.12065 0.3048)
			(stroke
				(width 0.1)
				(type default)
			)
			(layer "F.Fab")
		)
		(fp_line
			(start 0.67945 0.3048)
			(end 0.120396 0.3048)
			(stroke
				(width 0.1)
				(type default)
			)
			(layer "F.Fab")
		)
		(fp_line
			(start 0.120396 0.3048)
			(end 0.120396 0.2794)
			(stroke
				(width 0.1)
				(type default)
			)
			(layer "F.Fab")
		)
		(fp_line
			(start -0.12065 0.3048)
			(end -0.67945 0.3048)
			(stroke
				(width 0.1)
				(type default)
			)
			(layer "F.Fab")
		)
		(fp_line
			(start -0.67945 0.3048)
			(end -0.67945 -0.305054)
			(stroke
				(width 0.1)
				(type default)
			)
			(layer "F.Fab")
		)
		(pad "1" smd circle
			(at -0.40005 0 90)
			(size 0 0)
			(layers "F.Cu" "F.Mask" "F.Paste")
			(net "PWRGD_P1V8_PEX_R")
		)
		(pad "2" smd circle
			(at 0.40005 0 90)
			(size 0 0)
			(layers "F.Cu" "F.Mask" "F.Paste")
			(net "PWRGD_P1V8_PEX1_R")
		)
	)
	(footprint ""
		(layer "F.Cu")
		(at 435.093364 -311.325514 -90)
		(property "Reference" "R6721"
			(at 0 0 270)
			(layer "F.SilkS")
			(hide yes)
			(effects
				(font
					(size 1.27 1.27)
				)
			)
		)
		(property "Value" ""
			(at 0 0 270)
			(layer "F.Fab")
			(effects
				(font
					(size 1.27 1.27)
				)
			)
		)
		(duplicate_pad_numbers_are_jumpers no)
		(fp_line
			(start -0.7874 0.4064)
			(end -0.7874 -0.4064)
			(stroke
				(width 0.1524)
				(type default)
			)
			(layer "F.SilkS")
		)
		(fp_line
			(start 0.7874 0.4064)
			(end -0.7874 0.4064)
			(stroke
				(width 0.1524)
				(type default)
			)
			(layer "F.SilkS")
		)
		(fp_line
			(start -0.7874 -0.4064)
			(end 0.7874 -0.4064)
			(stroke
				(width 0.1524)
				(type default)
			)
			(layer "F.SilkS")
		)
		(fp_line
			(start 0.7874 -0.4064)
			(end 0.7874 0.4064)
			(stroke
				(width 0.1524)
				(type default)
			)
			(layer "F.SilkS")
		)
		(fp_line
			(start -0.67945 0.3048)
			(end -0.67945 -0.305054)
			(stroke
				(width 0.1)
				(type default)
			)
			(layer "F.Fab")
		)
		(fp_line
			(start -0.12065 0.3048)
			(end -0.67945 0.3048)
			(stroke
				(width 0.1)
				(type default)
			)
			(layer "F.Fab")
		)
		(fp_line
			(start 0.120396 0.3048)
			(end 0.120396 0.2794)
			(stroke
				(width 0.1)
				(type default)
			)
			(layer "F.Fab")
		)
		(fp_line
			(start 0.67945 0.3048)
			(end 0.120396 0.3048)
			(stroke
				(width 0.1)
				(type default)
			)
			(layer "F.Fab")
		)
		(fp_line
			(start -0.12065 0.2794)
			(end -0.12065 0.3048)
			(stroke
				(width 0.1)
				(type default)
			)
			(layer "F.Fab")
		)
		(fp_line
			(start 0.120396 0.2794)
			(end -0.12065 0.2794)
			(stroke
				(width 0.1)
				(type default)
			)
			(layer "F.Fab")
		)
		(fp_line
			(start -0.12065 -0.2794)
			(end 0.12065 -0.2794)
			(stroke
				(width 0.1)
				(type default)
			)
			(layer "F.Fab")
		)
		(fp_line
			(start 0.12065 -0.2794)
			(end 0.12065 -0.3048)
			(stroke
				(width 0.1)
				(type default)
			)
			(layer "F.Fab")
		)
		(fp_line
			(start 0.12065 -0.3048)
			(end 0.67945 -0.3048)
			(stroke
				(width 0.1)
				(type default)
			)
			(layer "F.Fab")
		)
		(fp_line
			(start 0.67945 -0.3048)
			(end 0.67945 0.3048)
			(stroke
				(width 0.1)
				(type default)
			)
			(layer "F.Fab")
		)
		(fp_line
			(start -0.67945 -0.305054)
			(end -0.12065 -0.305054)
			(stroke
				(width 0.1)
				(type default)
			)
			(layer "F.Fab")
		)
		(fp_line
			(start -0.12065 -0.305054)
			(end -0.12065 -0.2794)
			(stroke
				(width 0.1)
				(type default)
			)
			(layer "F.Fab")
		)
		(pad "1" smd circle
			(at -0.40005 0 270)
			(size 0 0)
			(layers "F.Cu" "F.Mask" "F.Paste")
			(net "SMB_PEX3_SLAVE1_SDA")
		)
		(pad "2" smd circle
			(at 0.40005 0 270)
			(size 0 0)
			(layers "F.Cu" "F.Mask" "F.Paste")
			(net "SMB_PEX3_R_SDA")
		)
	)
	(footprint ""
		(layer "F.Cu")
		(at 13.194284 -255.046734 -90)
		(property "Reference" "R6474"
			(at 0 0 270)
			(layer "F.SilkS")
			(hide yes)
			(effects
				(font
					(size 1.27 1.27)
				)
			)
		)
		(property "Value" ""
			(at 0 0 270)
			(layer "F.Fab")
			(effects
				(font
					(size 1.27 1.27)
				)
			)
		)
		(duplicate_pad_numbers_are_jumpers no)
		(fp_line
			(start -0.7874 0.4064)
			(end -0.7874 -0.4064)
			(stroke
				(width 0.1524)
				(type default)
			)
			(layer "F.SilkS")
		)
		(fp_line
			(start 0.7874 0.4064)
			(end -0.7874 0.4064)
			(stroke
				(width 0.1524)
				(type default)
			)
			(layer "F.SilkS")
		)
		(fp_line
			(start -0.7874 -0.4064)
			(end 0.7874 -0.4064)
			(stroke
				(width 0.1524)
				(type default)
			)
			(layer "F.SilkS")
		)
		(fp_line
			(start 0.7874 -0.4064)
			(end 0.7874 0.4064)
			(stroke
				(width 0.1524)
				(type default)
			)
			(layer "F.SilkS")
		)
		(fp_line
			(start -0.67945 0.3048)
			(end -0.67945 -0.305054)
			(stroke
				(width 0.1)
				(type default)
			)
			(layer "F.Fab")
		)
		(fp_line
			(start -0.12065 0.3048)
			(end -0.67945 0.3048)
			(stroke
				(width 0.1)
				(type default)
			)
			(layer "F.Fab")
		)
		(fp_line
			(start 0.120396 0.3048)
			(end 0.120396 0.2794)
			(stroke
				(width 0.1)
				(type default)
			)
			(layer "F.Fab")
		)
		(fp_line
			(start 0.67945 0.3048)
			(end 0.120396 0.3048)
			(stroke
				(width 0.1)
				(type default)
			)
			(layer "F.Fab")
		)
		(fp_line
			(start -0.12065 0.2794)
			(end -0.12065 0.3048)
			(stroke
				(width 0.1)
				(type default)
			)
			(layer "F.Fab")
		)
		(fp_line
			(start 0.120396 0.2794)
			(end -0.12065 0.2794)
			(stroke
				(width 0.1)
				(type default)
			)
			(layer "F.Fab")
		)
		(fp_line
			(start -0.12065 -0.2794)
			(end 0.12065 -0.2794)
			(stroke
				(width 0.1)
				(type default)
			)
			(layer "F.Fab")
		)
		(fp_line
			(start 0.12065 -0.2794)
			(end 0.12065 -0.3048)
			(stroke
				(width 0.1)
				(type default)
			)
			(layer "F.Fab")
		)
		(fp_line
			(start 0.12065 -0.3048)
			(end 0.67945 -0.3048)
			(stroke
				(width 0.1)
				(type default)
			)
			(layer "F.Fab")
		)
		(fp_line
			(start 0.67945 -0.3048)
			(end 0.67945 0.3048)
			(stroke
				(width 0.1)
				(type default)
			)
			(layer "F.Fab")
		)
		(fp_line
			(start -0.67945 -0.305054)
			(end -0.12065 -0.305054)
			(stroke
				(width 0.1)
				(type default)
			)
			(layer "F.Fab")
		)
		(fp_line
			(start -0.12065 -0.305054)
			(end -0.12065 -0.2794)
			(stroke
				(width 0.1)
				(type default)
			)
			(layer "F.Fab")
		)
		(pad "1" smd circle
			(at -0.40005 0 270)
			(size 0 0)
			(layers "F.Cu" "F.Mask" "F.Paste")
			(net "P1V25_SERDES_VDDPLL_PEX0")
		)
		(pad "2" smd circle
			(at 0.40005 0 270)
			(size 0 0)
			(layers "F.Cu" "F.Mask" "F.Paste")
			(net "P1V25_SERDES_VDDPLL_PEX0_C11")
		)
	)
	(footprint ""
		(layer "F.Cu")
		(at 407.190956 -55.663846 90)
		(property "Reference" "PU67"
			(at -0.93726 2.791968 90)
			(unlocked yes)
			(layer "F.SilkS")
			(effects
				(font
					(size 0.7874 0.5842)
					(thickness 0.1524)
				)
				(justify left)
			)
		)
		(property "Value" ""
			(at 0 0 90)
			(layer "F.Fab")
			(effects
				(font
					(size 1.27 1.27)
				)
			)
		)
		(duplicate_pad_numbers_are_jumpers no)
		(fp_line
			(start 1.943608 -1.549908)
			(end 1.943608 1.549908)
			(stroke
				(width 0.1524)
				(type default)
			)
			(layer "F.SilkS")
		)
		(fp_line
			(start -1.943608 -1.549908)
			(end 1.943608 -1.549908)
			(stroke
				(width 0.1524)
				(type default)
			)
			(layer "F.SilkS")
		)
		(fp_line
			(start 1.943608 1.549908)
			(end -1.943608 1.549908)
			(stroke
				(width 0.1524)
				(type default)
			)
			(layer "F.SilkS")
		)
		(fp_line
			(start -1.943608 1.549908)
			(end -1.943608 -1.549908)
			(stroke
				(width 0.1524)
				(type default)
			)
			(layer "F.SilkS")
		)
		(fp_poly
			(pts
				(xy -2.019808 -1.549908) (xy -1.257808 -1.549908) (xy -1.257808 -1.880108) (xy -2.019808 -1.880108)
			)
			(stroke
				(width 0)
				(type default)
			)
			(fill yes)
			(layer "F.SilkS")
		)
		(fp_line
			(start 1.549908 -1.549908)
			(end 1.549908 1.549908)
			(stroke
				(width 0.1)
				(type default)
			)
			(layer "F.Fab")
		)
		(fp_line
			(start -1.549908 -1.549908)
			(end 1.549908 -1.549908)
			(stroke
				(width 0.1)
				(type default)
			)
			(layer "F.Fab")
		)
		(fp_line
			(start 1.549908 1.549908)
			(end -1.549908 1.549908)
			(stroke
				(width 0.1)
				(type default)
			)
			(layer "F.Fab")
		)
		(fp_line
			(start -1.549908 1.549908)
			(end -1.549908 -1.549908)
			(stroke
				(width 0.1)
				(type default)
			)
			(layer "F.Fab")
		)
		(fp_poly
			(pts
				(xy -2.019808 -1.549908) (xy -1.257808 -1.549908) (xy -1.257808 -1.880108) (xy -2.019808 -1.880108)
			)
			(stroke
				(width 0)
				(type default)
			)
			(fill yes)
			(layer "F.Fab")
		)
		(pad "1" smd rect
			(at -1.500124 -1.249934)
			(size 0.2794 0.6096)
			(layers "F.Cu" "F.Mask" "F.Paste")
			(net "P3V3_SSD14")
		)
		(pad "2" smd rect
			(at -1.500124 -0.750062)
			(size 0.2794 0.6096)
			(layers "F.Cu" "F.Mask" "F.Paste")
			(net "P3V3_SSD14")
		)
		(pad "3" smd rect
			(at -1.500124 -0.249936)
			(size 0.2794 0.6096)
			(layers "F.Cu" "F.Mask" "F.Paste")
			(net "P3V3_SSD14")
		)
		(pad "4" smd rect
			(at -1.500124 0.249936)
			(size 0.2794 0.6096)
			(layers "F.Cu" "F.Mask" "F.Paste")
			(net "P3V3_SSD14")
		)
		(pad "5" smd rect
			(at -1.500124 0.750062)
			(size 0.2794 0.6096)
			(layers "F.Cu" "F.Mask" "F.Paste")
			(net "P3V3_SSD14")
		)
		(pad "6" smd rect
			(at -1.500124 1.249934)
			(size 0.2794 0.6096)
			(layers "F.Cu" "F.Mask" "F.Paste")
			(net "GND")
		)
		(pad "7" smd rect
			(at 1.500124 1.249934)
			(size 0.2794 0.6096)
			(layers "F.Cu" "F.Mask" "F.Paste")
			(net "P3V3_SSD14_SS")
		)
		(pad "8" smd rect
			(at 1.500124 0.750062)
			(size 0.2794 0.6096)
			(layers "F.Cu" "F.Mask" "F.Paste")
			(net "PWRGD_P3V3_SSD14")
		)
		(pad "9" smd rect
			(at 1.500124 0.249936)
			(size 0.2794 0.6096)
			(layers "F.Cu" "F.Mask" "F.Paste")
			(net "P3V3_SSD14_OCP")
		)
		(pad "10" smd rect
			(at 1.500124 -0.249936)
			(size 0.2794 0.6096)
			(layers "F.Cu" "F.Mask" "F.Paste")
			(net "P5V_AUX")
		)
		(pad "11" smd rect
			(at 1.500124 -0.750062)
			(size 0.2794 0.6096)
			(layers "F.Cu" "F.Mask" "F.Paste")
			(net "SSD14_AUX_P3V3_EN_R")
		)
		(pad "12" smd rect
			(at 1.500124 -1.249934)
			(size 0.2794 0.6096)
			(layers "F.Cu" "F.Mask" "F.Paste")
			(net "P3V3_AUX")
		)
		(pad "13" smd rect
			(at 0 0 90)
			(size 1.9812 2.7178)
			(layers "F.Cu" "F.Mask" "F.Paste")
			(net "P3V3_AUX")
		)
		(zone
			(layer "F.Cu")
			(hatch none 0.5)
			(connect_pads
				(clearance 0)
			)
			(min_thickness 0.25)
			(keepout
				(tracks not_allowed)
				(vias allowed)
				(pads allowed)
				(copperpour not_allowed)
				(footprints allowed)
			)
			(placement
				(enabled no)
				(sheetname "")
			)
			(fill
				(thermal_gap 0.5)
				(thermal_bridge_width 0.5)
				(island_removal_mode 0)
			)
			(polygon
				(pts
					(xy 405.641556 -56.806846) (xy 405.768556 -56.806846) (xy 408.740356 -56.806846) (xy 408.740864 -56.806846)
					(xy 408.740864 -54.520846) (xy 408.740356 -54.520846) (xy 408.613356 -54.520846) (xy 407.190956 -54.520846)
					(xy 407.190956 -54.622446) (xy 408.613356 -54.622446) (xy 408.613356 -56.705246) (xy 405.768556 -56.705246)
					(xy 405.768556 -54.622446) (xy 407.165556 -54.622446) (xy 407.165556 -54.520846) (xy 405.768556 -54.520846)
					(xy 405.641556 -54.520846) (xy 405.641048 -54.520846) (xy 405.641048 -56.806846)
				)
			)
		)
	)
	(footprint ""
		(layer "F.Cu")
		(at 331.175614 -123.795028)
		(property "Reference" "C2880"
			(at 0 0 0)
			(layer "F.SilkS")
			(hide yes)
			(effects
				(font
					(size 1.27 1.27)
				)
			)
		)
		(property "Value" ""
			(at 0 0 0)
			(layer "F.Fab")
			(effects
				(font
					(size 1.27 1.27)
				)
			)
		)
		(duplicate_pad_numbers_are_jumpers no)
		(fp_line
			(start -0.7874 -0.4064)
			(end 0.7874 -0.4064)
			(stroke
				(width 0.1524)
				(type default)
			)
			(layer "F.SilkS")
		)
		(fp_line
			(start -0.7874 0.4064)
			(end -0.7874 -0.4064)
			(stroke
				(width 0.1524)
				(type default)
			)
			(layer "F.SilkS")
		)
		(fp_line
			(start 0.7874 -0.4064)
			(end 0.7874 0.4064)
			(stroke
				(width 0.1524)
				(type default)
			)
			(layer "F.SilkS")
		)
		(fp_line
			(start 0.7874 0.4064)
			(end -0.7874 0.4064)
			(stroke
				(width 0.1524)
				(type default)
			)
			(layer "F.SilkS")
		)
		(fp_line
			(start -0.67945 -0.305054)
			(end -0.12065 -0.305054)
			(stroke
				(width 0.1)
				(type default)
			)
			(layer "F.Fab")
		)
		(fp_line
			(start -0.67945 0.3048)
			(end -0.67945 -0.305054)
			(stroke
				(width 0.1)
				(type default)
			)
			(layer "F.Fab")
		)
		(fp_line
			(start -0.12065 -0.305054)
			(end -0.12065 -0.2794)
			(stroke
				(width 0.1)
				(type default)
			)
			(layer "F.Fab")
		)
		(fp_line
			(start -0.12065 -0.2794)
			(end 0.12065 -0.2794)
			(stroke
				(width 0.1)
				(type default)
			)
			(layer "F.Fab")
		)
		(fp_line
			(start -0.12065 0.2794)
			(end -0.12065 0.3048)
			(stroke
				(width 0.1)
				(type default)
			)
			(layer "F.Fab")
		)
		(fp_line
			(start -0.12065 0.3048)
			(end -0.67945 0.3048)
			(stroke
				(width 0.1)
				(type default)
			)
			(layer "F.Fab")
		)
		(fp_line
			(start 0.120396 0.2794)
			(end -0.12065 0.2794)
			(stroke
				(width 0.1)
				(type default)
			)
			(layer "F.Fab")
		)
		(fp_line
			(start 0.120396 0.3048)
			(end 0.120396 0.2794)
			(stroke
				(width 0.1)
				(type default)
			)
			(layer "F.Fab")
		)
		(fp_line
			(start 0.12065 -0.3048)
			(end 0.67945 -0.3048)
			(stroke
				(width 0.1)
				(type default)
			)
			(layer "F.Fab")
		)
		(fp_line
			(start 0.12065 -0.2794)
			(end 0.12065 -0.3048)
			(stroke
				(width 0.1)
				(type default)
			)
			(layer "F.Fab")
		)
		(fp_line
			(start 0.67945 -0.3048)
			(end 0.67945 0.3048)
			(stroke
				(width 0.1)
				(type default)
			)
			(layer "F.Fab")
		)
		(fp_line
			(start 0.67945 0.3048)
			(end 0.120396 0.3048)
			(stroke
				(width 0.1)
				(type default)
			)
			(layer "F.Fab")
		)
		(pad "1" smd circle
			(at -0.40005 0)
			(size 0 0)
			(layers "F.Cu" "F.Mask" "F.Paste")
			(net "HP_NIC5_EN")
		)
		(pad "2" smd circle
			(at 0.40005 0)
			(size 0 0)
			(layers "F.Cu" "F.Mask" "F.Paste")
			(net "GND")
		)
	)
	(footprint ""
		(layer "F.Cu")
		(at 431.594006 -34.248852)
		(property "Reference" "R5704"
			(at 0 0 0)
			(layer "F.SilkS")
			(hide yes)
			(effects
				(font
					(size 1.27 1.27)
				)
			)
		)
		(property "Value" ""
			(at 0 0 0)
			(layer "F.Fab")
			(effects
				(font
					(size 1.27 1.27)
				)
			)
		)
		(duplicate_pad_numbers_are_jumpers no)
		(fp_line
			(start -0.7874 -0.4064)
			(end 0.7874 -0.4064)
			(stroke
				(width 0.1524)
				(type default)
			)
			(layer "F.SilkS")
		)
		(fp_line
			(start -0.7874 0.4064)
			(end -0.7874 -0.4064)
			(stroke
				(width 0.1524)
				(type default)
			)
			(layer "F.SilkS")
		)
		(fp_line
			(start 0.7874 -0.4064)
			(end 0.7874 0.4064)
			(stroke
				(width 0.1524)
				(type default)
			)
			(layer "F.SilkS")
		)
		(fp_line
			(start 0.7874 0.4064)
			(end -0.7874 0.4064)
			(stroke
				(width 0.1524)
				(type default)
			)
			(layer "F.SilkS")
		)
		(fp_line
			(start -0.67945 -0.305054)
			(end -0.12065 -0.305054)
			(stroke
				(width 0.1)
				(type default)
			)
			(layer "F.Fab")
		)
		(fp_line
			(start -0.67945 0.3048)
			(end -0.67945 -0.305054)
			(stroke
				(width 0.1)
				(type default)
			)
			(layer "F.Fab")
		)
		(fp_line
			(start -0.12065 -0.305054)
			(end -0.12065 -0.2794)
			(stroke
				(width 0.1)
				(type default)
			)
			(layer "F.Fab")
		)
		(fp_line
			(start -0.12065 -0.2794)
			(end 0.12065 -0.2794)
			(stroke
				(width 0.1)
				(type default)
			)
			(layer "F.Fab")
		)
		(fp_line
			(start -0.12065 0.2794)
			(end -0.12065 0.3048)
			(stroke
				(width 0.1)
				(type default)
			)
			(layer "F.Fab")
		)
		(fp_line
			(start -0.12065 0.3048)
			(end -0.67945 0.3048)
			(stroke
				(width 0.1)
				(type default)
			)
			(layer "F.Fab")
		)
		(fp_line
			(start 0.120396 0.2794)
			(end -0.12065 0.2794)
			(stroke
				(width 0.1)
				(type default)
			)
			(layer "F.Fab")
		)
		(fp_line
			(start 0.120396 0.3048)
			(end 0.120396 0.2794)
			(stroke
				(width 0.1)
				(type default)
			)
			(layer "F.Fab")
		)
		(fp_line
			(start 0.12065 -0.3048)
			(end 0.67945 -0.3048)
			(stroke
				(width 0.1)
				(type default)
			)
			(layer "F.Fab")
		)
		(fp_line
			(start 0.12065 -0.2794)
			(end 0.12065 -0.3048)
			(stroke
				(width 0.1)
				(type default)
			)
			(layer "F.Fab")
		)
		(fp_line
			(start 0.67945 -0.3048)
			(end 0.67945 0.3048)
			(stroke
				(width 0.1)
				(type default)
			)
			(layer "F.Fab")
		)
		(fp_line
			(start 0.67945 0.3048)
			(end 0.120396 0.3048)
			(stroke
				(width 0.1)
				(type default)
			)
			(layer "F.Fab")
		)
		(pad "1" smd circle
			(at -0.40005 0)
			(size 0 0)
			(layers "F.Cu" "F.Mask" "F.Paste")
			(net "RST_SMB_SSD15_ISO_N")
		)
		(pad "2" smd circle
			(at 0.40005 0)
			(size 0 0)
			(layers "F.Cu" "F.Mask" "F.Paste")
			(net "P3V3_SSD15")
		)
	)
	(footprint ""
		(layer "F.Cu")
		(at 78.243684 -46.90491)
		(property "Reference" "R530"
			(at 0 0 0)
			(layer "F.SilkS")
			(hide yes)
			(effects
				(font
					(size 1.27 1.27)
				)
			)
		)
		(property "Value" ""
			(at 0 0 0)
			(layer "F.Fab")
			(effects
				(font
					(size 1.27 1.27)
				)
			)
		)
		(duplicate_pad_numbers_are_jumpers no)
		(fp_line
			(start -0.7874 -0.4064)
			(end 0.7874 -0.4064)
			(stroke
				(width 0.1524)
				(type default)
			)
			(layer "F.SilkS")
		)
		(fp_line
			(start -0.7874 0.4064)
			(end -0.7874 -0.4064)
			(stroke
				(width 0.1524)
				(type default)
			)
			(layer "F.SilkS")
		)
		(fp_line
			(start 0.7874 -0.4064)
			(end 0.7874 0.4064)
			(stroke
				(width 0.1524)
				(type default)
			)
			(layer "F.SilkS")
		)
		(fp_line
			(start 0.7874 0.4064)
			(end -0.7874 0.4064)
			(stroke
				(width 0.1524)
				(type default)
			)
			(layer "F.SilkS")
		)
		(fp_line
			(start -0.67945 -0.305054)
			(end -0.12065 -0.305054)
			(stroke
				(width 0.1)
				(type default)
			)
			(layer "F.Fab")
		)
		(fp_line
			(start -0.67945 0.3048)
			(end -0.67945 -0.305054)
			(stroke
				(width 0.1)
				(type default)
			)
			(layer "F.Fab")
		)
		(fp_line
			(start -0.12065 -0.305054)
			(end -0.12065 -0.2794)
			(stroke
				(width 0.1)
				(type default)
			)
			(layer "F.Fab")
		)
		(fp_line
			(start -0.12065 -0.2794)
			(end 0.12065 -0.2794)
			(stroke
				(width 0.1)
				(type default)
			)
			(layer "F.Fab")
		)
		(fp_line
			(start -0.12065 0.2794)
			(end -0.12065 0.3048)
			(stroke
				(width 0.1)
				(type default)
			)
			(layer "F.Fab")
		)
		(fp_line
			(start -0.12065 0.3048)
			(end -0.67945 0.3048)
			(stroke
				(width 0.1)
				(type default)
			)
			(layer "F.Fab")
		)
		(fp_line
			(start 0.120396 0.2794)
			(end -0.12065 0.2794)
			(stroke
				(width 0.1)
				(type default)
			)
			(layer "F.Fab")
		)
		(fp_line
			(start 0.120396 0.3048)
			(end 0.120396 0.2794)
			(stroke
				(width 0.1)
				(type default)
			)
			(layer "F.Fab")
		)
		(fp_line
			(start 0.12065 -0.3048)
			(end 0.67945 -0.3048)
			(stroke
				(width 0.1)
				(type default)
			)
			(layer "F.Fab")
		)
		(fp_line
			(start 0.12065 -0.2794)
			(end 0.12065 -0.3048)
			(stroke
				(width 0.1)
				(type default)
			)
			(layer "F.Fab")
		)
		(fp_line
			(start 0.67945 -0.3048)
			(end 0.67945 0.3048)
			(stroke
				(width 0.1)
				(type default)
			)
			(layer "F.Fab")
		)
		(fp_line
			(start 0.67945 0.3048)
			(end 0.120396 0.3048)
			(stroke
				(width 0.1)
				(type default)
			)
			(layer "F.Fab")
		)
		(pad "1" smd circle
			(at -0.40005 0)
			(size 0 0)
			(layers "F.Cu" "F.Mask" "F.Paste")
			(net "SSD2_ADC_ALERT_N")
		)
		(pad "2" smd circle
			(at 0.40005 0)
			(size 0 0)
			(layers "F.Cu" "F.Mask" "F.Paste")
			(net "SSD_0_7_ADC_ALERT_N")
		)
	)
	(footprint ""
		(layer "F.Cu")
		(at 394.038582 -44.341542 90)
		(property "Reference" "C338"
			(at 0 0 90)
			(layer "F.SilkS")
			(hide yes)
			(effects
				(font
					(size 1.27 1.27)
				)
			)
		)
		(property "Value" ""
			(at 0 0 90)
			(layer "F.Fab")
			(effects
				(font
					(size 1.27 1.27)
				)
			)
		)
		(duplicate_pad_numbers_are_jumpers no)
		(fp_line
			(start 0.7874 -0.4064)
			(end 0.7874 0.4064)
			(stroke
				(width 0.1524)
				(type default)
			)
			(layer "F.SilkS")
		)
		(fp_line
			(start -0.7874 -0.4064)
			(end 0.7874 -0.4064)
			(stroke
				(width 0.1524)
				(type default)
			)
			(layer "F.SilkS")
		)
		(fp_line
			(start 0.7874 0.4064)
			(end -0.7874 0.4064)
			(stroke
				(width 0.1524)
				(type default)
			)
			(layer "F.SilkS")
		)
		(fp_line
			(start -0.7874 0.4064)
			(end -0.7874 -0.4064)
			(stroke
				(width 0.1524)
				(type default)
			)
			(layer "F.SilkS")
		)
		(fp_line
			(start -0.12065 -0.305054)
			(end -0.12065 -0.2794)
			(stroke
				(width 0.1)
				(type default)
			)
			(layer "F.Fab")
		)
		(fp_line
			(start -0.67945 -0.305054)
			(end -0.12065 -0.305054)
			(stroke
				(width 0.1)
				(type default)
			)
			(layer "F.Fab")
		)
		(fp_line
			(start 0.67945 -0.3048)
			(end 0.67945 0.3048)
			(stroke
				(width 0.1)
				(type default)
			)
			(layer "F.Fab")
		)
		(fp_line
			(start 0.12065 -0.3048)
			(end 0.67945 -0.3048)
			(stroke
				(width 0.1)
				(type default)
			)
			(layer "F.Fab")
		)
		(fp_line
			(start 0.12065 -0.2794)
			(end 0.12065 -0.3048)
			(stroke
				(width 0.1)
				(type default)
			)
			(layer "F.Fab")
		)
		(fp_line
			(start -0.12065 -0.2794)
			(end 0.12065 -0.2794)
			(stroke
				(width 0.1)
				(type default)
			)
			(layer "F.Fab")
		)
		(fp_line
			(start 0.120396 0.2794)
			(end -0.12065 0.2794)
			(stroke
				(width 0.1)
				(type default)
			)
			(layer "F.Fab")
		)
		(fp_line
			(start -0.12065 0.2794)
			(end -0.12065 0.3048)
			(stroke
				(width 0.1)
				(type default)
			)
			(layer "F.Fab")
		)
		(fp_line
			(start 0.67945 0.3048)
			(end 0.120396 0.3048)
			(stroke
				(width 0.1)
				(type default)
			)
			(layer "F.Fab")
		)
		(fp_line
			(start 0.120396 0.3048)
			(end 0.120396 0.2794)
			(stroke
				(width 0.1)
				(type default)
			)
			(layer "F.Fab")
		)
		(fp_line
			(start -0.12065 0.3048)
			(end -0.67945 0.3048)
			(stroke
				(width 0.1)
				(type default)
			)
			(layer "F.Fab")
		)
		(fp_line
			(start -0.67945 0.3048)
			(end -0.67945 -0.305054)
			(stroke
				(width 0.1)
				(type default)
			)
			(layer "F.Fab")
		)
		(pad "1" smd circle
			(at -0.40005 0 90)
			(size 0 0)
			(layers "F.Cu" "F.Mask" "F.Paste")
			(net "P12V_SSD13_VIN_P")
		)
		(pad "2" smd circle
			(at 0.40005 0 90)
			(size 0 0)
			(layers "F.Cu" "F.Mask" "F.Paste")
			(net "P12V_SSD13_VIN_N")
		)
	)
	(footprint ""
		(layer "F.Cu")
		(at 336.042 -171.069 180)
		(property "Reference" "R4741"
			(at 0 0 180)
			(layer "F.SilkS")
			(hide yes)
			(effects
				(font
					(size 1.27 1.27)
				)
			)
		)
		(property "Value" ""
			(at 0 0 180)
			(layer "F.Fab")
			(effects
				(font
					(size 1.27 1.27)
				)
			)
		)
		(duplicate_pad_numbers_are_jumpers no)
		(fp_line
			(start 0.7874 0.4064)
			(end -0.7874 0.4064)
			(stroke
				(width 0.1524)
				(type default)
			)
			(layer "F.SilkS")
		)
		(fp_line
			(start 0.7874 -0.4064)
			(end 0.7874 0.4064)
			(stroke
				(width 0.1524)
				(type default)
			)
			(layer "F.SilkS")
		)
		(fp_line
			(start -0.7874 0.4064)
			(end -0.7874 -0.4064)
			(stroke
				(width 0.1524)
				(type default)
			)
			(layer "F.SilkS")
		)
		(fp_line
			(start -0.7874 -0.4064)
			(end 0.7874 -0.4064)
			(stroke
				(width 0.1524)
				(type default)
			)
			(layer "F.SilkS")
		)
		(fp_line
			(start 0.67945 0.3048)
			(end 0.120396 0.3048)
			(stroke
				(width 0.1)
				(type default)
			)
			(layer "F.Fab")
		)
		(fp_line
			(start 0.67945 -0.3048)
			(end 0.67945 0.3048)
			(stroke
				(width 0.1)
				(type default)
			)
			(layer "F.Fab")
		)
		(fp_line
			(start 0.12065 -0.2794)
			(end 0.12065 -0.3048)
			(stroke
				(width 0.1)
				(type default)
			)
			(layer "F.Fab")
		)
		(fp_line
			(start 0.12065 -0.3048)
			(end 0.67945 -0.3048)
			(stroke
				(width 0.1)
				(type default)
			)
			(layer "F.Fab")
		)
		(fp_line
			(start 0.120396 0.3048)
			(end 0.120396 0.2794)
			(stroke
				(width 0.1)
				(type default)
			)
			(layer "F.Fab")
		)
		(fp_line
			(start 0.120396 0.2794)
			(end -0.12065 0.2794)
			(stroke
				(width 0.1)
				(type default)
			)
			(layer "F.Fab")
		)
		(fp_line
			(start -0.12065 0.3048)
			(end -0.67945 0.3048)
			(stroke
				(width 0.1)
				(type default)
			)
			(layer "F.Fab")
		)
		(fp_line
			(start -0.12065 0.2794)
			(end -0.12065 0.3048)
			(stroke
				(width 0.1)
				(type default)
			)
			(layer "F.Fab")
		)
		(fp_line
			(start -0.12065 -0.2794)
			(end 0.12065 -0.2794)
			(stroke
				(width 0.1)
				(type default)
			)
			(layer "F.Fab")
		)
		(fp_line
			(start -0.12065 -0.305054)
			(end -0.12065 -0.2794)
			(stroke
				(width 0.1)
				(type default)
			)
			(layer "F.Fab")
		)
		(fp_line
			(start -0.67945 0.3048)
			(end -0.67945 -0.305054)
			(stroke
				(width 0.1)
				(type default)
			)
			(layer "F.Fab")
		)
		(fp_line
			(start -0.67945 -0.305054)
			(end -0.12065 -0.305054)
			(stroke
				(width 0.1)
				(type default)
			)
			(layer "F.Fab")
		)
		(pad "1" smd circle
			(at -0.40005 0 180)
			(size 0 0)
			(layers "F.Cu" "F.Mask" "F.Paste")
			(net "SSD10_PEX_PWR_EN_R")
		)
		(pad "2" smd circle
			(at 0.40005 0 180)
			(size 0 0)
			(layers "F.Cu" "F.Mask" "F.Paste")
			(net "GND")
		)
	)
	(footprint ""
		(layer "F.Cu")
		(at 430.41443 -140.134848 -90)
		(property "Reference" "R401"
			(at 0 0 270)
			(layer "F.SilkS")
			(hide yes)
			(effects
				(font
					(size 1.27 1.27)
				)
			)
		)
		(property "Value" ""
			(at 0 0 270)
			(layer "F.Fab")
			(effects
				(font
					(size 1.27 1.27)
				)
			)
		)
		(duplicate_pad_numbers_are_jumpers no)
		(fp_line
			(start -0.7874 0.4064)
			(end -0.7874 -0.4064)
			(stroke
				(width 0.1524)
				(type default)
			)
			(layer "F.SilkS")
		)
		(fp_line
			(start 0.7874 0.4064)
			(end -0.7874 0.4064)
			(stroke
				(width 0.1524)
				(type default)
			)
			(layer "F.SilkS")
		)
		(fp_line
			(start -0.7874 -0.4064)
			(end 0.7874 -0.4064)
			(stroke
				(width 0.1524)
				(type default)
			)
			(layer "F.SilkS")
		)
		(fp_line
			(start 0.7874 -0.4064)
			(end 0.7874 0.4064)
			(stroke
				(width 0.1524)
				(type default)
			)
			(layer "F.SilkS")
		)
		(fp_line
			(start -0.67945 0.3048)
			(end -0.67945 -0.305054)
			(stroke
				(width 0.1)
				(type default)
			)
			(layer "F.Fab")
		)
		(fp_line
			(start -0.12065 0.3048)
			(end -0.67945 0.3048)
			(stroke
				(width 0.1)
				(type default)
			)
			(layer "F.Fab")
		)
		(fp_line
			(start 0.120396 0.3048)
			(end 0.120396 0.2794)
			(stroke
				(width 0.1)
				(type default)
			)
			(layer "F.Fab")
		)
		(fp_line
			(start 0.67945 0.3048)
			(end 0.120396 0.3048)
			(stroke
				(width 0.1)
				(type default)
			)
			(layer "F.Fab")
		)
		(fp_line
			(start -0.12065 0.2794)
			(end -0.12065 0.3048)
			(stroke
				(width 0.1)
				(type default)
			)
			(layer "F.Fab")
		)
		(fp_line
			(start 0.120396 0.2794)
			(end -0.12065 0.2794)
			(stroke
				(width 0.1)
				(type default)
			)
			(layer "F.Fab")
		)
		(fp_line
			(start -0.12065 -0.2794)
			(end 0.12065 -0.2794)
			(stroke
				(width 0.1)
				(type default)
			)
			(layer "F.Fab")
		)
		(fp_line
			(start 0.12065 -0.2794)
			(end 0.12065 -0.3048)
			(stroke
				(width 0.1)
				(type default)
			)
			(layer "F.Fab")
		)
		(fp_line
			(start 0.12065 -0.3048)
			(end 0.67945 -0.3048)
			(stroke
				(width 0.1)
				(type default)
			)
			(layer "F.Fab")
		)
		(fp_line
			(start 0.67945 -0.3048)
			(end 0.67945 0.3048)
			(stroke
				(width 0.1)
				(type default)
			)
			(layer "F.Fab")
		)
		(fp_line
			(start -0.67945 -0.305054)
			(end -0.12065 -0.305054)
			(stroke
				(width 0.1)
				(type default)
			)
			(layer "F.Fab")
		)
		(fp_line
			(start -0.12065 -0.305054)
			(end -0.12065 -0.2794)
			(stroke
				(width 0.1)
				(type default)
			)
			(layer "F.Fab")
		)
		(pad "1" smd circle
			(at -0.40005 0 270)
			(size 0 0)
			(layers "F.Cu" "F.Mask" "F.Paste")
			(net "P3V3_AUX")
		)
		(pad "2" smd circle
			(at 0.40005 0 270)
			(size 0 0)
			(layers "F.Cu" "F.Mask" "F.Paste")
			(net "HP_NIC7_EN")
		)
	)
	(footprint ""
		(layer "F.Cu")
		(at 155.380436 -132.215382)
		(property "Reference" "C248"
			(at 0 0 0)
			(layer "F.SilkS")
			(hide yes)
			(effects
				(font
					(size 1.27 1.27)
				)
			)
		)
		(property "Value" ""
			(at 0 0 0)
			(layer "F.Fab")
			(effects
				(font
					(size 1.27 1.27)
				)
			)
		)
		(duplicate_pad_numbers_are_jumpers no)
		(fp_line
			(start -0.299974 -0.150114)
			(end 0.299974 -0.150114)
			(stroke
				(width 0.1)
				(type default)
			)
			(layer "F.Fab")
		)
		(fp_line
			(start -0.299974 0.150114)
			(end -0.299974 -0.150114)
			(stroke
				(width 0.1)
				(type default)
			)
			(layer "F.Fab")
		)
		(fp_line
			(start 0.299974 -0.150114)
			(end 0.299974 0.150114)
			(stroke
				(width 0.1)
				(type default)
			)
			(layer "F.Fab")
		)
		(fp_line
			(start 0.299974 0.150114)
			(end -0.299974 0.150114)
			(stroke
				(width 0.1)
				(type default)
			)
			(layer "F.Fab")
		)
		(pad "1" smd rect
			(at -0.2667 0)
			(size 0.3048 0.381)
			(layers "F.Cu" "F.Mask" "F.Paste")
			(net "P5E_PEX1_STN1_TX_DN<29>")
		)
		(pad "2" smd rect
			(at 0.2667 0)
			(size 0.3048 0.381)
			(layers "F.Cu" "F.Mask" "F.Paste")
			(net "P5E_PEX1_STN1_TX_C_DN<29>")
		)
	)
	(footprint ""
		(layer "F.Cu")
		(at 210.439 -193.675 180)
		(property "Reference" "R1532"
			(at 0 0 180)
			(layer "F.SilkS")
			(hide yes)
			(effects
				(font
					(size 1.27 1.27)
				)
			)
		)
		(property "Value" ""
			(at 0 0 180)
			(layer "F.Fab")
			(effects
				(font
					(size 1.27 1.27)
				)
			)
		)
		(duplicate_pad_numbers_are_jumpers no)
		(fp_line
			(start 0.7874 0.4064)
			(end -0.7874 0.4064)
			(stroke
				(width 0.1524)
				(type default)
			)
			(layer "F.SilkS")
		)
		(fp_line
			(start 0.7874 -0.4064)
			(end 0.7874 0.4064)
			(stroke
				(width 0.1524)
				(type default)
			)
			(layer "F.SilkS")
		)
		(fp_line
			(start -0.7874 0.4064)
			(end -0.7874 -0.4064)
			(stroke
				(width 0.1524)
				(type default)
			)
			(layer "F.SilkS")
		)
		(fp_line
			(start -0.7874 -0.4064)
			(end 0.7874 -0.4064)
			(stroke
				(width 0.1524)
				(type default)
			)
			(layer "F.SilkS")
		)
		(fp_line
			(start 0.67945 0.3048)
			(end 0.120396 0.3048)
			(stroke
				(width 0.1)
				(type default)
			)
			(layer "F.Fab")
		)
		(fp_line
			(start 0.67945 -0.3048)
			(end 0.67945 0.3048)
			(stroke
				(width 0.1)
				(type default)
			)
			(layer "F.Fab")
		)
		(fp_line
			(start 0.12065 -0.2794)
			(end 0.12065 -0.3048)
			(stroke
				(width 0.1)
				(type default)
			)
			(layer "F.Fab")
		)
		(fp_line
			(start 0.12065 -0.3048)
			(end 0.67945 -0.3048)
			(stroke
				(width 0.1)
				(type default)
			)
			(layer "F.Fab")
		)
		(fp_line
			(start 0.120396 0.3048)
			(end 0.120396 0.2794)
			(stroke
				(width 0.1)
				(type default)
			)
			(layer "F.Fab")
		)
		(fp_line
			(start 0.120396 0.2794)
			(end -0.12065 0.2794)
			(stroke
				(width 0.1)
				(type default)
			)
			(layer "F.Fab")
		)
		(fp_line
			(start -0.12065 0.3048)
			(end -0.67945 0.3048)
			(stroke
				(width 0.1)
				(type default)
			)
			(layer "F.Fab")
		)
		(fp_line
			(start -0.12065 0.2794)
			(end -0.12065 0.3048)
			(stroke
				(width 0.1)
				(type default)
			)
			(layer "F.Fab")
		)
		(fp_line
			(start -0.12065 -0.2794)
			(end 0.12065 -0.2794)
			(stroke
				(width 0.1)
				(type default)
			)
			(layer "F.Fab")
		)
		(fp_line
			(start -0.12065 -0.305054)
			(end -0.12065 -0.2794)
			(stroke
				(width 0.1)
				(type default)
			)
			(layer "F.Fab")
		)
		(fp_line
			(start -0.67945 0.3048)
			(end -0.67945 -0.305054)
			(stroke
				(width 0.1)
				(type default)
			)
			(layer "F.Fab")
		)
		(fp_line
			(start -0.67945 -0.305054)
			(end -0.12065 -0.305054)
			(stroke
				(width 0.1)
				(type default)
			)
			(layer "F.Fab")
		)
		(pad "1" smd circle
			(at -0.40005 0 180)
			(size 0 0)
			(layers "F.Cu" "F.Mask" "F.Paste")
			(net "SMB_NIC7_R_SDA")
		)
		(pad "2" smd circle
			(at 0.40005 0 180)
			(size 0 0)
			(layers "F.Cu" "F.Mask" "F.Paste")
			(net "P1V2_AUX")
		)
	)
	(footprint ""
		(layer "F.Cu")
		(at 401.426172 -39.73576 -90)
		(property "Reference" "R5578"
			(at 0 0 270)
			(layer "F.SilkS")
			(hide yes)
			(effects
				(font
					(size 1.27 1.27)
				)
			)
		)
		(property "Value" ""
			(at 0 0 270)
			(layer "F.Fab")
			(effects
				(font
					(size 1.27 1.27)
				)
			)
		)
		(duplicate_pad_numbers_are_jumpers no)
		(fp_line
			(start -0.7874 0.4064)
			(end -0.7874 -0.4064)
			(stroke
				(width 0.1524)
				(type default)
			)
			(layer "F.SilkS")
		)
		(fp_line
			(start 0.7874 0.4064)
			(end -0.7874 0.4064)
			(stroke
				(width 0.1524)
				(type default)
			)
			(layer "F.SilkS")
		)
		(fp_line
			(start -0.7874 -0.4064)
			(end 0.7874 -0.4064)
			(stroke
				(width 0.1524)
				(type default)
			)
			(layer "F.SilkS")
		)
		(fp_line
			(start 0.7874 -0.4064)
			(end 0.7874 0.4064)
			(stroke
				(width 0.1524)
				(type default)
			)
			(layer "F.SilkS")
		)
		(fp_line
			(start -0.67945 0.3048)
			(end -0.67945 -0.305054)
			(stroke
				(width 0.1)
				(type default)
			)
			(layer "F.Fab")
		)
		(fp_line
			(start -0.12065 0.3048)
			(end -0.67945 0.3048)
			(stroke
				(width 0.1)
				(type default)
			)
			(layer "F.Fab")
		)
		(fp_line
			(start 0.120396 0.3048)
			(end 0.120396 0.2794)
			(stroke
				(width 0.1)
				(type default)
			)
			(layer "F.Fab")
		)
		(fp_line
			(start 0.67945 0.3048)
			(end 0.120396 0.3048)
			(stroke
				(width 0.1)
				(type default)
			)
			(layer "F.Fab")
		)
		(fp_line
			(start -0.12065 0.2794)
			(end -0.12065 0.3048)
			(stroke
				(width 0.1)
				(type default)
			)
			(layer "F.Fab")
		)
		(fp_line
			(start 0.120396 0.2794)
			(end -0.12065 0.2794)
			(stroke
				(width 0.1)
				(type default)
			)
			(layer "F.Fab")
		)
		(fp_line
			(start -0.12065 -0.2794)
			(end 0.12065 -0.2794)
			(stroke
				(width 0.1)
				(type default)
			)
			(layer "F.Fab")
		)
		(fp_line
			(start 0.12065 -0.2794)
			(end 0.12065 -0.3048)
			(stroke
				(width 0.1)
				(type default)
			)
			(layer "F.Fab")
		)
		(fp_line
			(start 0.12065 -0.3048)
			(end 0.67945 -0.3048)
			(stroke
				(width 0.1)
				(type default)
			)
			(layer "F.Fab")
		)
		(fp_line
			(start 0.67945 -0.3048)
			(end 0.67945 0.3048)
			(stroke
				(width 0.1)
				(type default)
			)
			(layer "F.Fab")
		)
		(fp_line
			(start -0.67945 -0.305054)
			(end -0.12065 -0.305054)
			(stroke
				(width 0.1)
				(type default)
			)
			(layer "F.Fab")
		)
		(fp_line
			(start -0.12065 -0.305054)
			(end -0.12065 -0.2794)
			(stroke
				(width 0.1)
				(type default)
			)
			(layer "F.Fab")
		)
		(pad "1" smd circle
			(at -0.40005 0 270)
			(size 0 0)
			(layers "F.Cu" "F.Mask" "F.Paste")
			(net "P3V3_AUX")
		)
		(pad "2" smd circle
			(at 0.40005 0 270)
			(size 0 0)
			(layers "F.Cu" "F.Mask" "F.Paste")
			(net "SSD14_AUX_P3V3_EN")
		)
	)
	(footprint ""
		(layer "F.Cu")
		(at 428.319438 -142.590266 180)
		(property "Reference" "C649"
			(at 0 0 180)
			(layer "F.SilkS")
			(hide yes)
			(effects
				(font
					(size 1.27 1.27)
				)
			)
		)
		(property "Value" ""
			(at 0 0 180)
			(layer "F.Fab")
			(effects
				(font
					(size 1.27 1.27)
				)
			)
		)
		(duplicate_pad_numbers_are_jumpers no)
		(fp_line
			(start 0.299974 0.150114)
			(end -0.299974 0.150114)
			(stroke
				(width 0.1)
				(type default)
			)
			(layer "F.Fab")
		)
		(fp_line
			(start 0.299974 -0.150114)
			(end 0.299974 0.150114)
			(stroke
				(width 0.1)
				(type default)
			)
			(layer "F.Fab")
		)
		(fp_line
			(start -0.299974 0.150114)
			(end -0.299974 -0.150114)
			(stroke
				(width 0.1)
				(type default)
			)
			(layer "F.Fab")
		)
		(fp_line
			(start -0.299974 -0.150114)
			(end 0.299974 -0.150114)
			(stroke
				(width 0.1)
				(type default)
			)
			(layer "F.Fab")
		)
		(pad "1" smd rect
			(at -0.2667 0 180)
			(size 0.3048 0.381)
			(layers "F.Cu" "F.Mask" "F.Paste")
			(net "P5E_PEX3_STN0_TX_DN<8>")
		)
		(pad "2" smd rect
			(at 0.2667 0 180)
			(size 0.3048 0.381)
			(layers "F.Cu" "F.Mask" "F.Paste")
			(net "P5E_PEX3_STN0_TX_C_DN<8>")
		)
	)
	(footprint ""
		(layer "F.Cu")
		(at 30.081982 -292.991032 180)
		(property "Reference" "C3032"
			(at 0 0 180)
			(layer "F.SilkS")
			(hide yes)
			(effects
				(font
					(size 1.27 1.27)
				)
			)
		)
		(property "Value" ""
			(at 0 0 180)
			(layer "F.Fab")
			(effects
				(font
					(size 1.27 1.27)
				)
			)
		)
		(duplicate_pad_numbers_are_jumpers no)
		(fp_line
			(start 1.2954 0.5842)
			(end -1.2954 0.5842)
			(stroke
				(width 0.1524)
				(type default)
			)
			(layer "F.SilkS")
		)
		(fp_line
			(start 1.2954 -0.5842)
			(end 1.2954 0.5842)
			(stroke
				(width 0.1524)
				(type default)
			)
			(layer "F.SilkS")
		)
		(fp_line
			(start -1.2954 0.5842)
			(end -1.2954 -0.5842)
			(stroke
				(width 0.1524)
				(type default)
			)
			(layer "F.SilkS")
		)
		(fp_line
			(start -1.2954 -0.5842)
			(end 1.2954 -0.5842)
			(stroke
				(width 0.1524)
				(type default)
			)
			(layer "F.SilkS")
		)
		(fp_line
			(start 1.1938 0.4064)
			(end 0.8636 0.4064)
			(stroke
				(width 0.1)
				(type default)
			)
			(layer "F.Fab")
		)
		(fp_line
			(start 1.1938 -0.4064)
			(end 1.1938 0.4064)
			(stroke
				(width 0.1)
				(type default)
			)
			(layer "F.Fab")
		)
		(fp_line
			(start 0.8636 0.4572)
			(end -0.8636 0.4572)
			(stroke
				(width 0.1)
				(type default)
			)
			(layer "F.Fab")
		)
		(fp_line
			(start 0.8636 0.4064)
			(end 0.8636 0.4572)
			(stroke
				(width 0.1)
				(type default)
			)
			(layer "F.Fab")
		)
		(fp_line
			(start 0.8636 -0.4064)
			(end 1.1938 -0.4064)
			(stroke
				(width 0.1)
				(type default)
			)
			(layer "F.Fab")
		)
		(fp_line
			(start 0.8636 -0.4572)
			(end 0.8636 -0.4064)
			(stroke
				(width 0.1)
				(type default)
			)
			(layer "F.Fab")
		)
		(fp_line
			(start -0.8636 0.4572)
			(end -0.8636 0.4064)
			(stroke
				(width 0.1)
				(type default)
			)
			(layer "F.Fab")
		)
		(fp_line
			(start -0.8636 0.4064)
			(end -1.1938 0.4064)
			(stroke
				(width 0.1)
				(type default)
			)
			(layer "F.Fab")
		)
		(fp_line
			(start -0.8636 -0.4064)
			(end -0.8636 -0.4572)
			(stroke
				(width 0.1)
				(type default)
			)
			(layer "F.Fab")
		)
		(fp_line
			(start -0.8636 -0.4572)
			(end 0.8636 -0.4572)
			(stroke
				(width 0.1)
				(type default)
			)
			(layer "F.Fab")
		)
		(fp_line
			(start -1.1938 0.4064)
			(end -1.1938 -0.4064)
			(stroke
				(width 0.1)
				(type default)
			)
			(layer "F.Fab")
		)
		(fp_line
			(start -1.1938 -0.4064)
			(end -0.8636 -0.4064)
			(stroke
				(width 0.1)
				(type default)
			)
			(layer "F.Fab")
		)
		(pad "1" smd rect
			(at -0.7366 0 90)
			(size 0.7112 0.8128)
			(layers "F.Cu" "F.Mask" "F.Paste")
			(net "PCEPLL2_VDDA18_PEX0_R")
		)
		(pad "2" smd rect
			(at 0.7366 0 90)
			(size 0.7112 0.8128)
			(layers "F.Cu" "F.Mask" "F.Paste")
			(net "GND")
		)
	)
	(footprint ""
		(layer "F.Cu")
		(at 262.353298 -294.591232)
		(property "Reference" "L122"
			(at 0 0 0)
			(layer "F.SilkS")
			(hide yes)
			(effects
				(font
					(size 1.27 1.27)
				)
			)
		)
		(property "Value" ""
			(at 0 0 0)
			(layer "F.Fab")
			(effects
				(font
					(size 1.27 1.27)
				)
			)
		)
		(duplicate_pad_numbers_are_jumpers no)
		(fp_line
			(start -1.63576 -0.8128)
			(end -1.63576 0.8128)
			(stroke
				(width 0.1524)
				(type default)
			)
			(layer "F.SilkS")
		)
		(fp_line
			(start -1.63576 -0.8128)
			(end 1.63576 -0.8128)
			(stroke
				(width 0.1524)
				(type default)
			)
			(layer "F.SilkS")
		)
		(fp_line
			(start 1.63576 -0.8128)
			(end 1.63576 0.8128)
			(stroke
				(width 0.1524)
				(type default)
			)
			(layer "F.SilkS")
		)
		(fp_line
			(start 1.63576 0.8128)
			(end -1.63576 0.8128)
			(stroke
				(width 0.1524)
				(type default)
			)
			(layer "F.SilkS")
		)
		(fp_line
			(start -1.56083 -0.738632)
			(end -1.56083 0.7366)
			(stroke
				(width 0.1)
				(type default)
			)
			(layer "F.Fab")
		)
		(fp_line
			(start -1.56083 0.7366)
			(end -1.524 0.7366)
			(stroke
				(width 0.1)
				(type default)
			)
			(layer "F.Fab")
		)
		(fp_line
			(start -1.524 0.7366)
			(end 1.524 0.7366)
			(stroke
				(width 0.1)
				(type default)
			)
			(layer "F.Fab")
		)
		(fp_line
			(start 1.524 0.7366)
			(end 1.560576 0.7366)
			(stroke
				(width 0.1)
				(type default)
			)
			(layer "F.Fab")
		)
		(fp_line
			(start 1.560576 -0.738632)
			(end -1.56083 -0.738632)
			(stroke
				(width 0.1)
				(type default)
			)
			(layer "F.Fab")
		)
		(fp_line
			(start 1.560576 0.7366)
			(end 1.560576 -0.738632)
			(stroke
				(width 0.1)
				(type default)
			)
			(layer "F.Fab")
		)
		(pad "1" smd rect
			(at -0.94996 0 180)
			(size 1.1176 1.3716)
			(layers "F.Cu" "F.Mask" "F.Paste")
			(net "P1V8_PLL0_PEX2")
		)
		(pad "2" smd rect
			(at 0.94996 0 180)
			(size 1.1176 1.3716)
			(layers "F.Cu" "F.Mask" "F.Paste")
			(net "PCEPLL2_VDDA18_PEX2")
		)
	)
	(footprint ""
		(layer "F.Cu")
		(at 328.022204 -350.098614 90)
		(property "Reference" "C565"
			(at 0 0 90)
			(layer "F.SilkS")
			(hide yes)
			(effects
				(font
					(size 1.27 1.27)
				)
			)
		)
		(property "Value" ""
			(at 0 0 90)
			(layer "F.Fab")
			(effects
				(font
					(size 1.27 1.27)
				)
			)
		)
		(duplicate_pad_numbers_are_jumpers no)
		(fp_line
			(start 0.299974 -0.150114)
			(end 0.299974 0.150114)
			(stroke
				(width 0.1)
				(type default)
			)
			(layer "F.Fab")
		)
		(fp_line
			(start -0.299974 -0.150114)
			(end 0.299974 -0.150114)
			(stroke
				(width 0.1)
				(type default)
			)
			(layer "F.Fab")
		)
		(fp_line
			(start 0.299974 0.150114)
			(end -0.299974 0.150114)
			(stroke
				(width 0.1)
				(type default)
			)
			(layer "F.Fab")
		)
		(fp_line
			(start -0.299974 0.150114)
			(end -0.299974 -0.150114)
			(stroke
				(width 0.1)
				(type default)
			)
			(layer "F.Fab")
		)
		(pad "1" smd rect
			(at -0.2667 0 90)
			(size 0.3048 0.381)
			(layers "F.Cu" "F.Mask" "F.Paste")
			(net "P5E_PEX2_STN6_TX_DP<104>")
		)
		(pad "2" smd rect
			(at 0.2667 0 90)
			(size 0.3048 0.381)
			(layers "F.Cu" "F.Mask" "F.Paste")
			(net "P5E_PEX2_STN6_TX_C_DP<104>")
		)
	)
	(footprint ""
		(layer "F.Cu")
		(at 14.656308 -304.10023 -90)
		(property "Reference" "PC221"
			(at 0 0 270)
			(layer "F.SilkS")
			(hide yes)
			(effects
				(font
					(size 1.27 1.27)
				)
			)
		)
		(property "Value" ""
			(at 0 0 270)
			(layer "F.Fab")
			(effects
				(font
					(size 1.27 1.27)
				)
			)
		)
		(duplicate_pad_numbers_are_jumpers no)
		(fp_line
			(start -0.7874 0.4064)
			(end -0.7874 -0.4064)
			(stroke
				(width 0.1524)
				(type default)
			)
			(layer "F.SilkS")
		)
		(fp_line
			(start 0.7874 0.4064)
			(end -0.7874 0.4064)
			(stroke
				(width 0.1524)
				(type default)
			)
			(layer "F.SilkS")
		)
		(fp_line
			(start -0.7874 -0.4064)
			(end 0.7874 -0.4064)
			(stroke
				(width 0.1524)
				(type default)
			)
			(layer "F.SilkS")
		)
		(fp_line
			(start 0.7874 -0.4064)
			(end 0.7874 0.4064)
			(stroke
				(width 0.1524)
				(type default)
			)
			(layer "F.SilkS")
		)
		(fp_line
			(start -0.67945 0.3048)
			(end -0.67945 -0.305054)
			(stroke
				(width 0.1)
				(type default)
			)
			(layer "F.Fab")
		)
		(fp_line
			(start -0.12065 0.3048)
			(end -0.67945 0.3048)
			(stroke
				(width 0.1)
				(type default)
			)
			(layer "F.Fab")
		)
		(fp_line
			(start 0.120396 0.3048)
			(end 0.120396 0.2794)
			(stroke
				(width 0.1)
				(type default)
			)
			(layer "F.Fab")
		)
		(fp_line
			(start 0.67945 0.3048)
			(end 0.120396 0.3048)
			(stroke
				(width 0.1)
				(type default)
			)
			(layer "F.Fab")
		)
		(fp_line
			(start -0.12065 0.2794)
			(end -0.12065 0.3048)
			(stroke
				(width 0.1)
				(type default)
			)
			(layer "F.Fab")
		)
		(fp_line
			(start 0.120396 0.2794)
			(end -0.12065 0.2794)
			(stroke
				(width 0.1)
				(type default)
			)
			(layer "F.Fab")
		)
		(fp_line
			(start -0.12065 -0.2794)
			(end 0.12065 -0.2794)
			(stroke
				(width 0.1)
				(type default)
			)
			(layer "F.Fab")
		)
		(fp_line
			(start 0.12065 -0.2794)
			(end 0.12065 -0.3048)
			(stroke
				(width 0.1)
				(type default)
			)
			(layer "F.Fab")
		)
		(fp_line
			(start 0.12065 -0.3048)
			(end 0.67945 -0.3048)
			(stroke
				(width 0.1)
				(type default)
			)
			(layer "F.Fab")
		)
		(fp_line
			(start 0.67945 -0.3048)
			(end 0.67945 0.3048)
			(stroke
				(width 0.1)
				(type default)
			)
			(layer "F.Fab")
		)
		(fp_line
			(start -0.67945 -0.305054)
			(end -0.12065 -0.305054)
			(stroke
				(width 0.1)
				(type default)
			)
			(layer "F.Fab")
		)
		(fp_line
			(start -0.12065 -0.305054)
			(end -0.12065 -0.2794)
			(stroke
				(width 0.1)
				(type default)
			)
			(layer "F.Fab")
		)
		(pad "1" smd circle
			(at -0.40005 0 270)
			(size 0 0)
			(layers "F.Cu" "F.Mask" "F.Paste")
			(net "P1V25_PEX0_REF")
		)
		(pad "2" smd circle
			(at 0.40005 0 270)
			(size 0 0)
			(layers "F.Cu" "F.Mask" "F.Paste")
			(net "GND")
		)
	)
	(footprint ""
		(layer "F.Cu")
		(at 3.155188 -53.468524 90)
		(property "Reference" "PC535"
			(at 0 0 90)
			(layer "F.SilkS")
			(hide yes)
			(effects
				(font
					(size 1.27 1.27)
				)
			)
		)
		(property "Value" ""
			(at 0 0 90)
			(layer "F.Fab")
			(effects
				(font
					(size 1.27 1.27)
				)
			)
		)
		(duplicate_pad_numbers_are_jumpers no)
		(fp_line
			(start 1.524 -0.762)
			(end 1.524 0.762)
			(stroke
				(width 0.1524)
				(type default)
			)
			(layer "F.SilkS")
		)
		(fp_line
			(start -1.524 -0.762)
			(end 1.524 -0.762)
			(stroke
				(width 0.1524)
				(type default)
			)
			(layer "F.SilkS")
		)
		(fp_line
			(start 1.524 0.762)
			(end -1.524 0.762)
			(stroke
				(width 0.1524)
				(type default)
			)
			(layer "F.SilkS")
		)
		(fp_line
			(start -1.524 0.762)
			(end -1.524 -0.762)
			(stroke
				(width 0.1524)
				(type default)
			)
			(layer "F.SilkS")
		)
		(fp_line
			(start 1.1049 -0.724916)
			(end -1.1049 -0.724916)
			(stroke
				(width 0.1)
				(type default)
			)
			(layer "F.Fab")
		)
		(fp_line
			(start -1.1049 -0.724916)
			(end -1.1049 0.724916)
			(stroke
				(width 0.1)
				(type default)
			)
			(layer "F.Fab")
		)
		(fp_line
			(start 1.1049 0.724916)
			(end 1.1049 -0.724916)
			(stroke
				(width 0.1)
				(type default)
			)
			(layer "F.Fab")
		)
		(fp_line
			(start -1.1049 0.724916)
			(end 1.1049 0.724916)
			(stroke
				(width 0.1)
				(type default)
			)
			(layer "F.Fab")
		)
		(pad "1" smd rect
			(at -0.889 0 270)
			(size 1.016 1.27)
			(layers "F.Cu" "F.Mask" "F.Paste")
			(net "GND")
		)
		(pad "2" smd rect
			(at 0.889 0 270)
			(size 1.016 1.27)
			(layers "F.Cu" "F.Mask" "F.Paste")
			(net "P3V3_AUX")
		)
	)
	(footprint ""
		(layer "F.Cu")
		(at 151.469598 -256.888234 -90)
		(property "Reference" "R4573"
			(at 0 0 270)
			(layer "F.SilkS")
			(hide yes)
			(effects
				(font
					(size 1.27 1.27)
				)
			)
		)
		(property "Value" ""
			(at 0 0 270)
			(layer "F.Fab")
			(effects
				(font
					(size 1.27 1.27)
				)
			)
		)
		(duplicate_pad_numbers_are_jumpers no)
		(fp_line
			(start -0.7874 0.4064)
			(end -0.7874 -0.4064)
			(stroke
				(width 0.1524)
				(type default)
			)
			(layer "F.SilkS")
		)
		(fp_line
			(start 0.7874 0.4064)
			(end -0.7874 0.4064)
			(stroke
				(width 0.1524)
				(type default)
			)
			(layer "F.SilkS")
		)
		(fp_line
			(start -0.7874 -0.4064)
			(end 0.7874 -0.4064)
			(stroke
				(width 0.1524)
				(type default)
			)
			(layer "F.SilkS")
		)
		(fp_line
			(start 0.7874 -0.4064)
			(end 0.7874 0.4064)
			(stroke
				(width 0.1524)
				(type default)
			)
			(layer "F.SilkS")
		)
		(fp_line
			(start -0.67945 0.3048)
			(end -0.67945 -0.305054)
			(stroke
				(width 0.1)
				(type default)
			)
			(layer "F.Fab")
		)
		(fp_line
			(start -0.12065 0.3048)
			(end -0.67945 0.3048)
			(stroke
				(width 0.1)
				(type default)
			)
			(layer "F.Fab")
		)
		(fp_line
			(start 0.120396 0.3048)
			(end 0.120396 0.2794)
			(stroke
				(width 0.1)
				(type default)
			)
			(layer "F.Fab")
		)
		(fp_line
			(start 0.67945 0.3048)
			(end 0.120396 0.3048)
			(stroke
				(width 0.1)
				(type default)
			)
			(layer "F.Fab")
		)
		(fp_line
			(start -0.12065 0.2794)
			(end -0.12065 0.3048)
			(stroke
				(width 0.1)
				(type default)
			)
			(layer "F.Fab")
		)
		(fp_line
			(start 0.120396 0.2794)
			(end -0.12065 0.2794)
			(stroke
				(width 0.1)
				(type default)
			)
			(layer "F.Fab")
		)
		(fp_line
			(start -0.12065 -0.2794)
			(end 0.12065 -0.2794)
			(stroke
				(width 0.1)
				(type default)
			)
			(layer "F.Fab")
		)
		(fp_line
			(start 0.12065 -0.2794)
			(end 0.12065 -0.3048)
			(stroke
				(width 0.1)
				(type default)
			)
			(layer "F.Fab")
		)
		(fp_line
			(start 0.12065 -0.3048)
			(end 0.67945 -0.3048)
			(stroke
				(width 0.1)
				(type default)
			)
			(layer "F.Fab")
		)
		(fp_line
			(start 0.67945 -0.3048)
			(end 0.67945 0.3048)
			(stroke
				(width 0.1)
				(type default)
			)
			(layer "F.Fab")
		)
		(fp_line
			(start -0.67945 -0.305054)
			(end -0.12065 -0.305054)
			(stroke
				(width 0.1)
				(type default)
			)
			(layer "F.Fab")
		)
		(fp_line
			(start -0.12065 -0.305054)
			(end -0.12065 -0.2794)
			(stroke
				(width 0.1)
				(type default)
			)
			(layer "F.Fab")
		)
		(pad "1" smd circle
			(at -0.40005 0 270)
			(size 0 0)
			(layers "F.Cu" "F.Mask" "F.Paste")
			(net "PCEPLL5_VDDA18_PEX1")
		)
		(pad "2" smd circle
			(at 0.40005 0 270)
			(size 0 0)
			(layers "F.Cu" "F.Mask" "F.Paste")
			(net "PCEPLL5_VDDA18_PEX1_R")
		)
	)
	(footprint ""
		(layer "F.Cu")
		(at 222.482664 -207.02016 -90)
		(property "Reference" "R5537"
			(at 0 0 270)
			(layer "F.SilkS")
			(hide yes)
			(effects
				(font
					(size 1.27 1.27)
				)
			)
		)
		(property "Value" ""
			(at 0 0 270)
			(layer "F.Fab")
			(effects
				(font
					(size 1.27 1.27)
				)
			)
		)
		(duplicate_pad_numbers_are_jumpers no)
		(fp_line
			(start -0.7874 0.4064)
			(end -0.7874 -0.4064)
			(stroke
				(width 0.1524)
				(type default)
			)
			(layer "F.SilkS")
		)
		(fp_line
			(start 0.7874 0.4064)
			(end -0.7874 0.4064)
			(stroke
				(width 0.1524)
				(type default)
			)
			(layer "F.SilkS")
		)
		(fp_line
			(start -0.7874 -0.4064)
			(end 0.7874 -0.4064)
			(stroke
				(width 0.1524)
				(type default)
			)
			(layer "F.SilkS")
		)
		(fp_line
			(start 0.7874 -0.4064)
			(end 0.7874 0.4064)
			(stroke
				(width 0.1524)
				(type default)
			)
			(layer "F.SilkS")
		)
		(fp_line
			(start -0.67945 0.3048)
			(end -0.67945 -0.305054)
			(stroke
				(width 0.1)
				(type default)
			)
			(layer "F.Fab")
		)
		(fp_line
			(start -0.12065 0.3048)
			(end -0.67945 0.3048)
			(stroke
				(width 0.1)
				(type default)
			)
			(layer "F.Fab")
		)
		(fp_line
			(start 0.120396 0.3048)
			(end 0.120396 0.2794)
			(stroke
				(width 0.1)
				(type default)
			)
			(layer "F.Fab")
		)
		(fp_line
			(start 0.67945 0.3048)
			(end 0.120396 0.3048)
			(stroke
				(width 0.1)
				(type default)
			)
			(layer "F.Fab")
		)
		(fp_line
			(start -0.12065 0.2794)
			(end -0.12065 0.3048)
			(stroke
				(width 0.1)
				(type default)
			)
			(layer "F.Fab")
		)
		(fp_line
			(start 0.120396 0.2794)
			(end -0.12065 0.2794)
			(stroke
				(width 0.1)
				(type default)
			)
			(layer "F.Fab")
		)
		(fp_line
			(start -0.12065 -0.2794)
			(end 0.12065 -0.2794)
			(stroke
				(width 0.1)
				(type default)
			)
			(layer "F.Fab")
		)
		(fp_line
			(start 0.12065 -0.2794)
			(end 0.12065 -0.3048)
			(stroke
				(width 0.1)
				(type default)
			)
			(layer "F.Fab")
		)
		(fp_line
			(start 0.12065 -0.3048)
			(end 0.67945 -0.3048)
			(stroke
				(width 0.1)
				(type default)
			)
			(layer "F.Fab")
		)
		(fp_line
			(start 0.67945 -0.3048)
			(end 0.67945 0.3048)
			(stroke
				(width 0.1)
				(type default)
			)
			(layer "F.Fab")
		)
		(fp_line
			(start -0.67945 -0.305054)
			(end -0.12065 -0.305054)
			(stroke
				(width 0.1)
				(type default)
			)
			(layer "F.Fab")
		)
		(fp_line
			(start -0.12065 -0.305054)
			(end -0.12065 -0.2794)
			(stroke
				(width 0.1)
				(type default)
			)
			(layer "F.Fab")
		)
		(pad "1" smd circle
			(at -0.40005 0 270)
			(size 0 0)
			(layers "F.Cu" "F.Mask" "F.Paste")
			(net "GND")
		)
		(pad "2" smd circle
			(at 0.40005 0 270)
			(size 0 0)
			(layers "F.Cu" "F.Mask" "F.Paste")
			(net "SGPIO_BIC_CLK")
		)
	)
	(footprint ""
		(layer "F.Cu")
		(at 107.050586 -159.340804 90)
		(property "Reference" "PC40"
			(at 0 0 90)
			(layer "F.SilkS")
			(hide yes)
			(effects
				(font
					(size 1.27 1.27)
				)
			)
		)
		(property "Value" ""
			(at 0 0 90)
			(layer "F.Fab")
			(effects
				(font
					(size 1.27 1.27)
				)
			)
		)
		(duplicate_pad_numbers_are_jumpers no)
		(fp_line
			(start 0.7874 -0.4064)
			(end 0.7874 0.4064)
			(stroke
				(width 0.1524)
				(type default)
			)
			(layer "F.SilkS")
		)
		(fp_line
			(start -0.7874 -0.4064)
			(end 0.7874 -0.4064)
			(stroke
				(width 0.1524)
				(type default)
			)
			(layer "F.SilkS")
		)
		(fp_line
			(start 0.7874 0.4064)
			(end -0.7874 0.4064)
			(stroke
				(width 0.1524)
				(type default)
			)
			(layer "F.SilkS")
		)
		(fp_line
			(start -0.7874 0.4064)
			(end -0.7874 -0.4064)
			(stroke
				(width 0.1524)
				(type default)
			)
			(layer "F.SilkS")
		)
		(fp_line
			(start -0.12065 -0.305054)
			(end -0.12065 -0.2794)
			(stroke
				(width 0.1)
				(type default)
			)
			(layer "F.Fab")
		)
		(fp_line
			(start -0.67945 -0.305054)
			(end -0.12065 -0.305054)
			(stroke
				(width 0.1)
				(type default)
			)
			(layer "F.Fab")
		)
		(fp_line
			(start 0.67945 -0.3048)
			(end 0.67945 0.3048)
			(stroke
				(width 0.1)
				(type default)
			)
			(layer "F.Fab")
		)
		(fp_line
			(start 0.12065 -0.3048)
			(end 0.67945 -0.3048)
			(stroke
				(width 0.1)
				(type default)
			)
			(layer "F.Fab")
		)
		(fp_line
			(start 0.12065 -0.2794)
			(end 0.12065 -0.3048)
			(stroke
				(width 0.1)
				(type default)
			)
			(layer "F.Fab")
		)
		(fp_line
			(start -0.12065 -0.2794)
			(end 0.12065 -0.2794)
			(stroke
				(width 0.1)
				(type default)
			)
			(layer "F.Fab")
		)
		(fp_line
			(start 0.120396 0.2794)
			(end -0.12065 0.2794)
			(stroke
				(width 0.1)
				(type default)
			)
			(layer "F.Fab")
		)
		(fp_line
			(start -0.12065 0.2794)
			(end -0.12065 0.3048)
			(stroke
				(width 0.1)
				(type default)
			)
			(layer "F.Fab")
		)
		(fp_line
			(start 0.67945 0.3048)
			(end 0.120396 0.3048)
			(stroke
				(width 0.1)
				(type default)
			)
			(layer "F.Fab")
		)
		(fp_line
			(start 0.120396 0.3048)
			(end 0.120396 0.2794)
			(stroke
				(width 0.1)
				(type default)
			)
			(layer "F.Fab")
		)
		(fp_line
			(start -0.12065 0.3048)
			(end -0.67945 0.3048)
			(stroke
				(width 0.1)
				(type default)
			)
			(layer "F.Fab")
		)
		(fp_line
			(start -0.67945 0.3048)
			(end -0.67945 -0.305054)
			(stroke
				(width 0.1)
				(type default)
			)
			(layer "F.Fab")
		)
		(pad "1" smd circle
			(at -0.40005 0 90)
			(size 0 0)
			(layers "F.Cu" "F.Mask" "F.Paste")
			(net "P3V3_AUX_VCC")
		)
		(pad "2" smd circle
			(at 0.40005 0 90)
			(size 0 0)
			(layers "F.Cu" "F.Mask" "F.Paste")
			(net "GND")
		)
	)
	(footprint ""
		(layer "F.Cu")
		(at 217.038936 -188.652404 90)
		(property "Reference" "R5301"
			(at 0 0 90)
			(layer "F.SilkS")
			(hide yes)
			(effects
				(font
					(size 1.27 1.27)
				)
			)
		)
		(property "Value" ""
			(at 0 0 90)
			(layer "F.Fab")
			(effects
				(font
					(size 1.27 1.27)
				)
			)
		)
		(duplicate_pad_numbers_are_jumpers no)
		(fp_line
			(start 0.7874 -0.4064)
			(end 0.7874 0.4064)
			(stroke
				(width 0.1524)
				(type default)
			)
			(layer "F.SilkS")
		)
		(fp_line
			(start -0.7874 -0.4064)
			(end 0.7874 -0.4064)
			(stroke
				(width 0.1524)
				(type default)
			)
			(layer "F.SilkS")
		)
		(fp_line
			(start 0.7874 0.4064)
			(end -0.7874 0.4064)
			(stroke
				(width 0.1524)
				(type default)
			)
			(layer "F.SilkS")
		)
		(fp_line
			(start -0.7874 0.4064)
			(end -0.7874 -0.4064)
			(stroke
				(width 0.1524)
				(type default)
			)
			(layer "F.SilkS")
		)
		(fp_line
			(start -0.12065 -0.305054)
			(end -0.12065 -0.2794)
			(stroke
				(width 0.1)
				(type default)
			)
			(layer "F.Fab")
		)
		(fp_line
			(start -0.67945 -0.305054)
			(end -0.12065 -0.305054)
			(stroke
				(width 0.1)
				(type default)
			)
			(layer "F.Fab")
		)
		(fp_line
			(start 0.67945 -0.3048)
			(end 0.67945 0.3048)
			(stroke
				(width 0.1)
				(type default)
			)
			(layer "F.Fab")
		)
		(fp_line
			(start 0.12065 -0.3048)
			(end 0.67945 -0.3048)
			(stroke
				(width 0.1)
				(type default)
			)
			(layer "F.Fab")
		)
		(fp_line
			(start 0.12065 -0.2794)
			(end 0.12065 -0.3048)
			(stroke
				(width 0.1)
				(type default)
			)
			(layer "F.Fab")
		)
		(fp_line
			(start -0.12065 -0.2794)
			(end 0.12065 -0.2794)
			(stroke
				(width 0.1)
				(type default)
			)
			(layer "F.Fab")
		)
		(fp_line
			(start 0.120396 0.2794)
			(end -0.12065 0.2794)
			(stroke
				(width 0.1)
				(type default)
			)
			(layer "F.Fab")
		)
		(fp_line
			(start -0.12065 0.2794)
			(end -0.12065 0.3048)
			(stroke
				(width 0.1)
				(type default)
			)
			(layer "F.Fab")
		)
		(fp_line
			(start 0.67945 0.3048)
			(end 0.120396 0.3048)
			(stroke
				(width 0.1)
				(type default)
			)
			(layer "F.Fab")
		)
		(fp_line
			(start 0.120396 0.3048)
			(end 0.120396 0.2794)
			(stroke
				(width 0.1)
				(type default)
			)
			(layer "F.Fab")
		)
		(fp_line
			(start -0.12065 0.3048)
			(end -0.67945 0.3048)
			(stroke
				(width 0.1)
				(type default)
			)
			(layer "F.Fab")
		)
		(fp_line
			(start -0.67945 0.3048)
			(end -0.67945 -0.305054)
			(stroke
				(width 0.1)
				(type default)
			)
			(layer "F.Fab")
		)
		(pad "1" smd circle
			(at -0.40005 0 90)
			(size 0 0)
			(layers "F.Cu" "F.Mask" "F.Paste")
			(net "BIC_SEL_FLASH_SW0_R")
		)
		(pad "2" smd circle
			(at 0.40005 0 90)
			(size 0 0)
			(layers "F.Cu" "F.Mask" "F.Paste")
			(net "P3V3_AUX")
		)
	)
	(footprint ""
		(layer "F.Cu")
		(at 314.861448 -155.196794 180)
		(property "Reference" "C424"
			(at 0 0 180)
			(layer "F.SilkS")
			(hide yes)
			(effects
				(font
					(size 1.27 1.27)
				)
			)
		)
		(property "Value" ""
			(at 0 0 180)
			(layer "F.Fab")
			(effects
				(font
					(size 1.27 1.27)
				)
			)
		)
		(duplicate_pad_numbers_are_jumpers no)
		(fp_line
			(start 0.299974 0.150114)
			(end -0.299974 0.150114)
			(stroke
				(width 0.1)
				(type default)
			)
			(layer "F.Fab")
		)
		(fp_line
			(start 0.299974 -0.150114)
			(end 0.299974 0.150114)
			(stroke
				(width 0.1)
				(type default)
			)
			(layer "F.Fab")
		)
		(fp_line
			(start -0.299974 0.150114)
			(end -0.299974 -0.150114)
			(stroke
				(width 0.1)
				(type default)
			)
			(layer "F.Fab")
		)
		(fp_line
			(start -0.299974 -0.150114)
			(end 0.299974 -0.150114)
			(stroke
				(width 0.1)
				(type default)
			)
			(layer "F.Fab")
		)
		(pad "1" smd rect
			(at -0.2667 0 180)
			(size 0.3048 0.381)
			(layers "F.Cu" "F.Mask" "F.Paste")
			(net "P5E_PEX2_STN0_TX_DN<15>")
		)
		(pad "2" smd rect
			(at 0.2667 0 180)
			(size 0.3048 0.381)
			(layers "F.Cu" "F.Mask" "F.Paste")
			(net "P5E_PEX2_STN0_TX_C_DN<15>")
		)
	)
	(footprint ""
		(layer "F.Cu")
		(at 207.609186 -223.82353 -90)
		(property "Reference" "U356"
			(at 1.794002 2.23901 90)
			(unlocked yes)
			(layer "F.SilkS")
			(effects
				(font
					(size 0.7874 0.5842)
					(thickness 0.1524)
				)
				(justify left)
			)
		)
		(property "Value" ""
			(at 0 0 270)
			(layer "F.Fab")
			(effects
				(font
					(size 1.27 1.27)
				)
			)
		)
		(duplicate_pad_numbers_are_jumpers no)
		(fp_line
			(start -1.684274 1.074928)
			(end -1.684274 -1.074928)
			(stroke
				(width 0.1524)
				(type default)
			)
			(layer "F.SilkS")
		)
		(fp_line
			(start 1.684274 1.074928)
			(end -1.684274 1.074928)
			(stroke
				(width 0.1524)
				(type default)
			)
			(layer "F.SilkS")
		)
		(fp_line
			(start 0 -0.625094)
			(end 0.381 -1.074928)
			(stroke
				(width 0.1524)
				(type default)
			)
			(layer "F.SilkS")
		)
		(fp_line
			(start -1.684274 -1.074928)
			(end -0.381 -1.074928)
			(stroke
				(width 0.1524)
				(type default)
			)
			(layer "F.SilkS")
		)
		(fp_line
			(start -0.381 -1.074928)
			(end 0 -0.625094)
			(stroke
				(width 0.1524)
				(type default)
			)
			(layer "F.SilkS")
		)
		(fp_line
			(start 0.381 -1.074928)
			(end 1.684274 -1.074928)
			(stroke
				(width 0.1524)
				(type default)
			)
			(layer "F.SilkS")
		)
		(fp_line
			(start 1.684274 -1.074928)
			(end 1.684274 1.074928)
			(stroke
				(width 0.1524)
				(type default)
			)
			(layer "F.SilkS")
		)
		(fp_poly
			(pts
				(xy -2.191258 -1.78308) (xy -2.550414 -1.42367) (xy -1.832102 -1.064514)
			)
			(stroke
				(width 0)
				(type default)
			)
			(fill yes)
			(layer "F.SilkS")
		)
		(fp_line
			(start -0.700024 1.074928)
			(end 0.700024 1.074928)
			(stroke
				(width 0.1)
				(type default)
			)
			(layer "F.Fab")
		)
		(fp_line
			(start 0.700024 1.074928)
			(end 0.700024 -1.074928)
			(stroke
				(width 0.1)
				(type default)
			)
			(layer "F.Fab")
		)
		(fp_line
			(start -0.700024 -1.074928)
			(end -0.700024 1.074928)
			(stroke
				(width 0.1)
				(type default)
			)
			(layer "F.Fab")
		)
		(fp_line
			(start 0.700024 -1.074928)
			(end -0.700024 -1.074928)
			(stroke
				(width 0.1)
				(type default)
			)
			(layer "F.Fab")
		)
		(fp_poly
			(pts
				(xy -2.637282 -0.903986) (xy -2.637282 -0.395986) (xy -1.875282 -0.649986)
			)
			(stroke
				(width 0)
				(type default)
			)
			(fill yes)
			(layer "F.Fab")
		)
		(pad "1" smd rect
			(at -1.100074 -0.649986 180)
			(size 0.4064 0.9144)
			(layers "F.Cu" "F.Mask" "F.Paste")
			(net "BUF_UART_MB_BIC_RX_EN")
		)
		(pad "2" smd rect
			(at -1.100074 0 180)
			(size 0.4064 0.9144)
			(layers "F.Cu" "F.Mask" "F.Paste")
			(net "UART_MB_BIC_R_RX")
		)
		(pad "3" smd rect
			(at -1.100074 0.649986 180)
			(size 0.4064 0.9144)
			(layers "F.Cu" "F.Mask" "F.Paste")
			(net "GND")
		)
		(pad "4" smd rect
			(at 1.100074 0.649986 180)
			(size 0.4064 0.9144)
			(layers "F.Cu" "F.Mask" "F.Paste")
			(net "UART_MB_BIC_RX_BUF")
		)
		(pad "5" smd rect
			(at 1.100074 -0.649986 180)
			(size 0.4064 0.9144)
			(layers "F.Cu" "F.Mask" "F.Paste")
			(net "P3V3_AUX")
		)
	)
	(footprint ""
		(layer "F.Cu")
		(at 477.21647 -524.295624 180)
		(property "Reference" "SCREW_SSD4_1"
			(at -5.207 -1.402334 0)
			(unlocked yes)
			(layer "B.SilkS")
			(effects
				(font
					(size 0.7874 0.5842)
					(thickness 0.1524)
				)
				(justify mirror)
			)
		)
		(property "Value" ""
			(at 0 0 180)
			(layer "F.Fab")
			(effects
				(font
					(size 1.27 1.27)
				)
			)
		)
		(duplicate_pad_numbers_are_jumpers no)
		(pad "1" thru_hole circle
			(at 0 0 180)
			(size 0.4572 0.4572)
			(drill 0.2032)
			(layers "*.Cu" "*.Mask")
			(remove_unused_layers no)
			(net "Net_9136")
			(clearance 0.127)
			(thermal_gap 0.127)
			(padstack
				(mode front_inner_back)
				(layer "Inner"
					(shape circle)
					(size 0.4572 0.4572)
					(clearance 0.127)
				)
				(layer "B.Cu"
					(shape circle)
					(size 0.508 0.508)
					(clearance 0.1016)
				)
			)
		)
	)
	(footprint ""
		(layer "F.Cu")
		(at 409.269692 -343.952322 90)
		(property "Reference" "C824"
			(at 0 0 90)
			(layer "F.SilkS")
			(hide yes)
			(effects
				(font
					(size 1.27 1.27)
				)
			)
		)
		(property "Value" ""
			(at 0 0 90)
			(layer "F.Fab")
			(effects
				(font
					(size 1.27 1.27)
				)
			)
		)
		(duplicate_pad_numbers_are_jumpers no)
		(fp_line
			(start 0.299974 -0.150114)
			(end 0.299974 0.150114)
			(stroke
				(width 0.1)
				(type default)
			)
			(layer "F.Fab")
		)
		(fp_line
			(start -0.299974 -0.150114)
			(end 0.299974 -0.150114)
			(stroke
				(width 0.1)
				(type default)
			)
			(layer "F.Fab")
		)
		(fp_line
			(start 0.299974 0.150114)
			(end -0.299974 0.150114)
			(stroke
				(width 0.1)
				(type default)
			)
			(layer "F.Fab")
		)
		(fp_line
			(start -0.299974 0.150114)
			(end -0.299974 -0.150114)
			(stroke
				(width 0.1)
				(type default)
			)
			(layer "F.Fab")
		)
		(pad "1" smd rect
			(at -0.2667 0 90)
			(size 0.3048 0.381)
			(layers "F.Cu" "F.Mask" "F.Paste")
			(net "P5E_PEX3_STN7_TX_DP<112>")
		)
		(pad "2" smd rect
			(at 0.2667 0 90)
			(size 0.3048 0.381)
			(layers "F.Cu" "F.Mask" "F.Paste")
			(net "P5E_PEX3_STN7_TX_C_DP<112>")
		)
	)
	(footprint ""
		(layer "F.Cu")
		(at 403.175216 -64.102234 180)
		(property "Reference" "PR7097"
			(at 0 0 180)
			(layer "F.SilkS")
			(hide yes)
			(effects
				(font
					(size 1.27 1.27)
				)
			)
		)
		(property "Value" ""
			(at 0 0 180)
			(layer "F.Fab")
			(effects
				(font
					(size 1.27 1.27)
				)
			)
		)
		(duplicate_pad_numbers_are_jumpers no)
		(fp_line
			(start 0.7874 0.4064)
			(end -0.7874 0.4064)
			(stroke
				(width 0.1524)
				(type default)
			)
			(layer "F.SilkS")
		)
		(fp_line
			(start 0.7874 -0.4064)
			(end 0.7874 0.4064)
			(stroke
				(width 0.1524)
				(type default)
			)
			(layer "F.SilkS")
		)
		(fp_line
			(start -0.7874 0.4064)
			(end -0.7874 -0.4064)
			(stroke
				(width 0.1524)
				(type default)
			)
			(layer "F.SilkS")
		)
		(fp_line
			(start -0.7874 -0.4064)
			(end 0.7874 -0.4064)
			(stroke
				(width 0.1524)
				(type default)
			)
			(layer "F.SilkS")
		)
		(fp_line
			(start 0.67945 0.3048)
			(end 0.120396 0.3048)
			(stroke
				(width 0.1)
				(type default)
			)
			(layer "F.Fab")
		)
		(fp_line
			(start 0.67945 -0.3048)
			(end 0.67945 0.3048)
			(stroke
				(width 0.1)
				(type default)
			)
			(layer "F.Fab")
		)
		(fp_line
			(start 0.12065 -0.2794)
			(end 0.12065 -0.3048)
			(stroke
				(width 0.1)
				(type default)
			)
			(layer "F.Fab")
		)
		(fp_line
			(start 0.12065 -0.3048)
			(end 0.67945 -0.3048)
			(stroke
				(width 0.1)
				(type default)
			)
			(layer "F.Fab")
		)
		(fp_line
			(start 0.120396 0.3048)
			(end 0.120396 0.2794)
			(stroke
				(width 0.1)
				(type default)
			)
			(layer "F.Fab")
		)
		(fp_line
			(start 0.120396 0.2794)
			(end -0.12065 0.2794)
			(stroke
				(width 0.1)
				(type default)
			)
			(layer "F.Fab")
		)
		(fp_line
			(start -0.12065 0.3048)
			(end -0.67945 0.3048)
			(stroke
				(width 0.1)
				(type default)
			)
			(layer "F.Fab")
		)
		(fp_line
			(start -0.12065 0.2794)
			(end -0.12065 0.3048)
			(stroke
				(width 0.1)
				(type default)
			)
			(layer "F.Fab")
		)
		(fp_line
			(start -0.12065 -0.2794)
			(end 0.12065 -0.2794)
			(stroke
				(width 0.1)
				(type default)
			)
			(layer "F.Fab")
		)
		(fp_line
			(start -0.12065 -0.305054)
			(end -0.12065 -0.2794)
			(stroke
				(width 0.1)
				(type default)
			)
			(layer "F.Fab")
		)
		(fp_line
			(start -0.67945 0.3048)
			(end -0.67945 -0.305054)
			(stroke
				(width 0.1)
				(type default)
			)
			(layer "F.Fab")
		)
		(fp_line
			(start -0.67945 -0.305054)
			(end -0.12065 -0.305054)
			(stroke
				(width 0.1)
				(type default)
			)
			(layer "F.Fab")
		)
		(pad "1" smd circle
			(at -0.40005 0 180)
			(size 0 0)
			(layers "F.Cu" "F.Mask" "F.Paste")
			(net "P12V_SSD14_PG_G1")
		)
		(pad "2" smd circle
			(at 0.40005 0 180)
			(size 0 0)
			(layers "F.Cu" "F.Mask" "F.Paste")
			(net "GND")
		)
	)
	(footprint ""
		(layer "F.Cu")
		(at 212.805264 -213.348062 180)
		(property "Reference" "C4502"
			(at 0 0 180)
			(layer "F.SilkS")
			(hide yes)
			(effects
				(font
					(size 1.27 1.27)
				)
			)
		)
		(property "Value" ""
			(at 0 0 180)
			(layer "F.Fab")
			(effects
				(font
					(size 1.27 1.27)
				)
			)
		)
		(duplicate_pad_numbers_are_jumpers no)
		(fp_line
			(start 0.7874 0.4064)
			(end -0.7874 0.4064)
			(stroke
				(width 0.1524)
				(type default)
			)
			(layer "F.SilkS")
		)
		(fp_line
			(start 0.7874 -0.4064)
			(end 0.7874 0.4064)
			(stroke
				(width 0.1524)
				(type default)
			)
			(layer "F.SilkS")
		)
		(fp_line
			(start -0.7874 0.4064)
			(end -0.7874 -0.4064)
			(stroke
				(width 0.1524)
				(type default)
			)
			(layer "F.SilkS")
		)
		(fp_line
			(start -0.7874 -0.4064)
			(end 0.7874 -0.4064)
			(stroke
				(width 0.1524)
				(type default)
			)
			(layer "F.SilkS")
		)
		(fp_line
			(start 0.67945 0.3048)
			(end 0.120396 0.3048)
			(stroke
				(width 0.1)
				(type default)
			)
			(layer "F.Fab")
		)
		(fp_line
			(start 0.67945 -0.3048)
			(end 0.67945 0.3048)
			(stroke
				(width 0.1)
				(type default)
			)
			(layer "F.Fab")
		)
		(fp_line
			(start 0.12065 -0.2794)
			(end 0.12065 -0.3048)
			(stroke
				(width 0.1)
				(type default)
			)
			(layer "F.Fab")
		)
		(fp_line
			(start 0.12065 -0.3048)
			(end 0.67945 -0.3048)
			(stroke
				(width 0.1)
				(type default)
			)
			(layer "F.Fab")
		)
		(fp_line
			(start 0.120396 0.3048)
			(end 0.120396 0.2794)
			(stroke
				(width 0.1)
				(type default)
			)
			(layer "F.Fab")
		)
		(fp_line
			(start 0.120396 0.2794)
			(end -0.12065 0.2794)
			(stroke
				(width 0.1)
				(type default)
			)
			(layer "F.Fab")
		)
		(fp_line
			(start -0.12065 0.3048)
			(end -0.67945 0.3048)
			(stroke
				(width 0.1)
				(type default)
			)
			(layer "F.Fab")
		)
		(fp_line
			(start -0.12065 0.2794)
			(end -0.12065 0.3048)
			(stroke
				(width 0.1)
				(type default)
			)
			(layer "F.Fab")
		)
		(fp_line
			(start -0.12065 -0.2794)
			(end 0.12065 -0.2794)
			(stroke
				(width 0.1)
				(type default)
			)
			(layer "F.Fab")
		)
		(fp_line
			(start -0.12065 -0.305054)
			(end -0.12065 -0.2794)
			(stroke
				(width 0.1)
				(type default)
			)
			(layer "F.Fab")
		)
		(fp_line
			(start -0.67945 0.3048)
			(end -0.67945 -0.305054)
			(stroke
				(width 0.1)
				(type default)
			)
			(layer "F.Fab")
		)
		(fp_line
			(start -0.67945 -0.305054)
			(end -0.12065 -0.305054)
			(stroke
				(width 0.1)
				(type default)
			)
			(layer "F.Fab")
		)
		(pad "1" smd circle
			(at -0.40005 0 180)
			(size 0 0)
			(layers "F.Cu" "F.Mask" "F.Paste")
			(net "SMB_ALERT_PMBUS_R_N")
		)
		(pad "2" smd circle
			(at 0.40005 0 180)
			(size 0 0)
			(layers "F.Cu" "F.Mask" "F.Paste")
			(net "GND")
		)
	)
	(footprint ""
		(layer "F.Cu")
		(at 277.44674 -37.47516)
		(property "Reference" "R6098"
			(at 0 0 0)
			(layer "F.SilkS")
			(hide yes)
			(effects
				(font
					(size 1.27 1.27)
				)
			)
		)
		(property "Value" ""
			(at 0 0 0)
			(layer "F.Fab")
			(effects
				(font
					(size 1.27 1.27)
				)
			)
		)
		(duplicate_pad_numbers_are_jumpers no)
		(fp_line
			(start -0.7874 -0.4064)
			(end 0.7874 -0.4064)
			(stroke
				(width 0.1524)
				(type default)
			)
			(layer "F.SilkS")
		)
		(fp_line
			(start -0.7874 0.4064)
			(end -0.7874 -0.4064)
			(stroke
				(width 0.1524)
				(type default)
			)
			(layer "F.SilkS")
		)
		(fp_line
			(start 0.7874 -0.4064)
			(end 0.7874 0.4064)
			(stroke
				(width 0.1524)
				(type default)
			)
			(layer "F.SilkS")
		)
		(fp_line
			(start 0.7874 0.4064)
			(end -0.7874 0.4064)
			(stroke
				(width 0.1524)
				(type default)
			)
			(layer "F.SilkS")
		)
		(fp_line
			(start -0.67945 -0.305054)
			(end -0.12065 -0.305054)
			(stroke
				(width 0.1)
				(type default)
			)
			(layer "F.Fab")
		)
		(fp_line
			(start -0.67945 0.3048)
			(end -0.67945 -0.305054)
			(stroke
				(width 0.1)
				(type default)
			)
			(layer "F.Fab")
		)
		(fp_line
			(start -0.12065 -0.305054)
			(end -0.12065 -0.2794)
			(stroke
				(width 0.1)
				(type default)
			)
			(layer "F.Fab")
		)
		(fp_line
			(start -0.12065 -0.2794)
			(end 0.12065 -0.2794)
			(stroke
				(width 0.1)
				(type default)
			)
			(layer "F.Fab")
		)
		(fp_line
			(start -0.12065 0.2794)
			(end -0.12065 0.3048)
			(stroke
				(width 0.1)
				(type default)
			)
			(layer "F.Fab")
		)
		(fp_line
			(start -0.12065 0.3048)
			(end -0.67945 0.3048)
			(stroke
				(width 0.1)
				(type default)
			)
			(layer "F.Fab")
		)
		(fp_line
			(start 0.120396 0.2794)
			(end -0.12065 0.2794)
			(stroke
				(width 0.1)
				(type default)
			)
			(layer "F.Fab")
		)
		(fp_line
			(start 0.120396 0.3048)
			(end 0.120396 0.2794)
			(stroke
				(width 0.1)
				(type default)
			)
			(layer "F.Fab")
		)
		(fp_line
			(start 0.12065 -0.3048)
			(end 0.67945 -0.3048)
			(stroke
				(width 0.1)
				(type default)
			)
			(layer "F.Fab")
		)
		(fp_line
			(start 0.12065 -0.2794)
			(end 0.12065 -0.3048)
			(stroke
				(width 0.1)
				(type default)
			)
			(layer "F.Fab")
		)
		(fp_line
			(start 0.67945 -0.3048)
			(end 0.67945 0.3048)
			(stroke
				(width 0.1)
				(type default)
			)
			(layer "F.Fab")
		)
		(fp_line
			(start 0.67945 0.3048)
			(end 0.120396 0.3048)
			(stroke
				(width 0.1)
				(type default)
			)
			(layer "F.Fab")
		)
		(pad "1" smd circle
			(at -0.40005 0)
			(size 0 0)
			(layers "F.Cu" "F.Mask" "F.Paste")
			(net "P3V3_SSD10")
		)
		(pad "2" smd circle
			(at 0.40005 0)
			(size 0 0)
			(layers "F.Cu" "F.Mask" "F.Paste")
			(net "P3V3_SSD10_PG_G1")
		)
	)
	(footprint ""
		(layer "F.Cu")
		(at 385.440174 -85.811614)
		(property "Reference" "U142"
			(at -1.950974 -4.763516 0)
			(unlocked yes)
			(layer "F.SilkS")
			(effects
				(font
					(size 0.7874 0.5842)
					(thickness 0.1524)
				)
				(justify left)
			)
		)
		(property "Value" ""
			(at 0 0 0)
			(layer "F.Fab")
			(effects
				(font
					(size 1.27 1.27)
				)
			)
		)
		(duplicate_pad_numbers_are_jumpers no)
		(fp_line
			(start -1.8542 -3.949954)
			(end -1.8542 3.949954)
			(stroke
				(width 0.1524)
				(type default)
			)
			(layer "F.SilkS")
		)
		(fp_line
			(start -1.8542 3.949954)
			(end 1.8542 3.949954)
			(stroke
				(width 0.1524)
				(type default)
			)
			(layer "F.SilkS")
		)
		(fp_line
			(start -1.282954 -3.949954)
			(end -1.8542 -3.949954)
			(stroke
				(width 0.1524)
				(type default)
			)
			(layer "F.SilkS")
		)
		(fp_line
			(start 0 -2.667)
			(end -1.282954 -3.949954)
			(stroke
				(width 0.1524)
				(type default)
			)
			(layer "F.SilkS")
		)
		(fp_line
			(start 1.282954 -3.949954)
			(end 0 -2.667)
			(stroke
				(width 0.1524)
				(type default)
			)
			(layer "F.SilkS")
		)
		(fp_line
			(start 1.8542 -3.949954)
			(end 1.282954 -3.949954)
			(stroke
				(width 0.1524)
				(type default)
			)
			(layer "F.SilkS")
		)
		(fp_line
			(start 1.8542 3.949954)
			(end 1.8542 -3.949954)
			(stroke
				(width 0.1524)
				(type default)
			)
			(layer "F.SilkS")
		)
		(fp_poly
			(pts
				(xy -4.8006 -4.08305) (xy -4.8006 -3.06705) (xy -3.7846 -3.57505)
			)
			(stroke
				(width 0)
				(type default)
			)
			(fill yes)
			(layer "F.SilkS")
		)
		(fp_line
			(start -2.249932 -3.949954)
			(end -2.249932 3.949954)
			(stroke
				(width 0.1)
				(type default)
			)
			(layer "F.Fab")
		)
		(fp_line
			(start -2.249932 3.949954)
			(end 2.249932 3.949954)
			(stroke
				(width 0.1)
				(type default)
			)
			(layer "F.Fab")
		)
		(fp_line
			(start 2.249932 -3.949954)
			(end -2.249932 -3.949954)
			(stroke
				(width 0.1)
				(type default)
			)
			(layer "F.Fab")
		)
		(fp_line
			(start 2.249932 3.949954)
			(end 2.249932 -3.949954)
			(stroke
				(width 0.1)
				(type default)
			)
			(layer "F.Fab")
		)
		(fp_poly
			(pts
				(xy -4.8006 -4.08305) (xy -4.8006 -3.06705) (xy -3.7846 -3.57505)
			)
			(stroke
				(width 0)
				(type default)
			)
			(fill yes)
			(layer "F.Fab")
		)
		(pad "1" smd rect
			(at -2.800096 -3.57505 270)
			(size 0.3048 1.6002)
			(layers "F.Cu" "F.Mask" "F.Paste")
			(net "BIC_I2C6_MUX_A0")
		)
		(pad "2" smd rect
			(at -2.800096 -2.925064 270)
			(size 0.3048 1.6002)
			(layers "F.Cu" "F.Mask" "F.Paste")
			(net "BIC_I2C6_MUX_A1")
		)
		(pad "3" smd rect
			(at -2.800096 -2.275078 270)
			(size 0.3048 1.6002)
			(layers "F.Cu" "F.Mask" "F.Paste")
			(net "RST_BIC_I2C6_MUX_R_N")
		)
		(pad "4" smd rect
			(at -2.800096 -1.625092 270)
			(size 0.3048 1.6002)
			(layers "F.Cu" "F.Mask" "F.Paste")
			(net "SMB_BIC_I2C6_MUX_NIC_ADC_SDA")
		)
		(pad "5" smd rect
			(at -2.800096 -0.975106 270)
			(size 0.3048 1.6002)
			(layers "F.Cu" "F.Mask" "F.Paste")
			(net "SMB_BIC_I2C6_MUX_NIC_ADC_SCL")
		)
		(pad "6" smd rect
			(at -2.800096 -0.32512 270)
			(size 0.3048 1.6002)
			(layers "F.Cu" "F.Mask" "F.Paste")
			(net "SMB_BIC_I2C6_MUX_PEX_ADC_SDA")
		)
		(pad "7" smd rect
			(at -2.800096 0.32512 270)
			(size 0.3048 1.6002)
			(layers "F.Cu" "F.Mask" "F.Paste")
			(net "SMB_BIC_I2C6_MUX_PEX_ADC_SCL")
		)
		(pad "8" smd rect
			(at -2.800096 0.975106 270)
			(size 0.3048 1.6002)
			(layers "F.Cu" "F.Mask" "F.Paste")
			(net "SMB_BIC_I2C6_MUX_THERMAL_SDA")
		)
		(pad "9" smd rect
			(at -2.800096 1.625092 270)
			(size 0.3048 1.6002)
			(layers "F.Cu" "F.Mask" "F.Paste")
			(net "SMB_BIC_I2C6_MUX_THERMAL_SCL")
		)
		(pad "10" smd rect
			(at -2.800096 2.275078 270)
			(size 0.3048 1.6002)
			(layers "F.Cu" "F.Mask" "F.Paste")
			(net "SMB_BIC_I2C6_MUX_SSD_0_7_ADC_SDA")
		)
		(pad "11" smd rect
			(at -2.800096 2.925064 270)
			(size 0.3048 1.6002)
			(layers "F.Cu" "F.Mask" "F.Paste")
			(net "SMB_BIC_I2C6_MUX_SSD_0_7_ADC_SCL")
		)
		(pad "12" smd rect
			(at -2.800096 3.57505 270)
			(size 0.3048 1.6002)
			(layers "F.Cu" "F.Mask" "F.Paste")
			(net "GND")
		)
		(pad "13" smd rect
			(at 2.800096 3.57505 270)
			(size 0.3048 1.6002)
			(layers "F.Cu" "F.Mask" "F.Paste")
			(net "SMB_BIC_I2C6_MUX_SSD_8_15_ADC_SDA")
		)
		(pad "14" smd rect
			(at 2.800096 2.925064 270)
			(size 0.3048 1.6002)
			(layers "F.Cu" "F.Mask" "F.Paste")
			(net "SMB_BIC_I2C6_MUX_SSD_8_15_ADC_SCL")
		)
		(pad "15" smd rect
			(at 2.800096 2.275078 270)
			(size 0.3048 1.6002)
			(layers "F.Cu" "F.Mask" "F.Paste")
			(net "SMB_BIC_I2C6_MUX_CLK_SDA")
		)
		(pad "16" smd rect
			(at 2.800096 1.625092 270)
			(size 0.3048 1.6002)
			(layers "F.Cu" "F.Mask" "F.Paste")
			(net "SMB_BIC_I2C6_MUX_CLK_SCL")
		)
		(pad "17" smd rect
			(at 2.800096 0.975106 270)
			(size 0.3048 1.6002)
			(layers "F.Cu" "F.Mask" "F.Paste")
			(net "SMB_BIC_I2C6_MUX_VR_SDA")
		)
		(pad "18" smd rect
			(at 2.800096 0.32512 270)
			(size 0.3048 1.6002)
			(layers "F.Cu" "F.Mask" "F.Paste")
			(net "SMB_BIC_I2C6_MUX_VR_SCL")
		)
		(pad "19" smd rect
			(at 2.800096 -0.32512 270)
			(size 0.3048 1.6002)
			(layers "F.Cu" "F.Mask" "F.Paste")
			(net "SMB_BIC_I2C6_MUX_FRU_SDA")
		)
		(pad "20" smd rect
			(at 2.800096 -0.975106 270)
			(size 0.3048 1.6002)
			(layers "F.Cu" "F.Mask" "F.Paste")
			(net "SMB_BIC_I2C6_MUX_FRU_SCL")
		)
		(pad "21" smd rect
			(at 2.800096 -1.625092 270)
			(size 0.3048 1.6002)
			(layers "F.Cu" "F.Mask" "F.Paste")
			(net "BIC_I2C6_MUX_A2")
		)
		(pad "22" smd rect
			(at 2.800096 -2.275078 270)
			(size 0.3048 1.6002)
			(layers "F.Cu" "F.Mask" "F.Paste")
			(net "SMB_BIC_I2C6_SENEOR_SCL")
		)
		(pad "23" smd rect
			(at 2.800096 -2.925064 270)
			(size 0.3048 1.6002)
			(layers "F.Cu" "F.Mask" "F.Paste")
			(net "SMB_BIC_I2C6_SENEOR_SDA")
		)
		(pad "24" smd rect
			(at 2.800096 -3.57505 270)
			(size 0.3048 1.6002)
			(layers "F.Cu" "F.Mask" "F.Paste")
			(net "P3V3_AUX")
		)
	)
	(footprint ""
		(layer "F.Cu")
		(at 196.119242 -146.190208 180)
		(property "Reference" "C223"
			(at 0 0 180)
			(layer "F.SilkS")
			(hide yes)
			(effects
				(font
					(size 1.27 1.27)
				)
			)
		)
		(property "Value" ""
			(at 0 0 180)
			(layer "F.Fab")
			(effects
				(font
					(size 1.27 1.27)
				)
			)
		)
		(duplicate_pad_numbers_are_jumpers no)
		(fp_line
			(start 0.299974 0.150114)
			(end -0.299974 0.150114)
			(stroke
				(width 0.1)
				(type default)
			)
			(layer "F.Fab")
		)
		(fp_line
			(start 0.299974 -0.150114)
			(end 0.299974 0.150114)
			(stroke
				(width 0.1)
				(type default)
			)
			(layer "F.Fab")
		)
		(fp_line
			(start -0.299974 0.150114)
			(end -0.299974 -0.150114)
			(stroke
				(width 0.1)
				(type default)
			)
			(layer "F.Fab")
		)
		(fp_line
			(start -0.299974 -0.150114)
			(end 0.299974 -0.150114)
			(stroke
				(width 0.1)
				(type default)
			)
			(layer "F.Fab")
		)
		(pad "1" smd rect
			(at -0.2667 0 180)
			(size 0.3048 0.381)
			(layers "F.Cu" "F.Mask" "F.Paste")
			(net "P5E_PEX1_STN0_TX_DN<10>")
		)
		(pad "2" smd rect
			(at 0.2667 0 180)
			(size 0.3048 0.381)
			(layers "F.Cu" "F.Mask" "F.Paste")
			(net "P5E_PEX1_STN0_TX_C_DN<10>")
		)
	)
	(footprint ""
		(layer "F.Cu")
		(at 460.611982 -107.848654 180)
		(property "Reference" "R961"
			(at 0 0 180)
			(layer "F.SilkS")
			(hide yes)
			(effects
				(font
					(size 1.27 1.27)
				)
			)
		)
		(property "Value" ""
			(at 0 0 180)
			(layer "F.Fab")
			(effects
				(font
					(size 1.27 1.27)
				)
			)
		)
		(duplicate_pad_numbers_are_jumpers no)
		(fp_line
			(start 0.7874 0.4064)
			(end -0.7874 0.4064)
			(stroke
				(width 0.1524)
				(type default)
			)
			(layer "F.SilkS")
		)
		(fp_line
			(start 0.7874 -0.4064)
			(end 0.7874 0.4064)
			(stroke
				(width 0.1524)
				(type default)
			)
			(layer "F.SilkS")
		)
		(fp_line
			(start -0.7874 0.4064)
			(end -0.7874 -0.4064)
			(stroke
				(width 0.1524)
				(type default)
			)
			(layer "F.SilkS")
		)
		(fp_line
			(start -0.7874 -0.4064)
			(end 0.7874 -0.4064)
			(stroke
				(width 0.1524)
				(type default)
			)
			(layer "F.SilkS")
		)
		(fp_line
			(start 0.67945 0.3048)
			(end 0.120396 0.3048)
			(stroke
				(width 0.1)
				(type default)
			)
			(layer "F.Fab")
		)
		(fp_line
			(start 0.67945 -0.3048)
			(end 0.67945 0.3048)
			(stroke
				(width 0.1)
				(type default)
			)
			(layer "F.Fab")
		)
		(fp_line
			(start 0.12065 -0.2794)
			(end 0.12065 -0.3048)
			(stroke
				(width 0.1)
				(type default)
			)
			(layer "F.Fab")
		)
		(fp_line
			(start 0.12065 -0.3048)
			(end 0.67945 -0.3048)
			(stroke
				(width 0.1)
				(type default)
			)
			(layer "F.Fab")
		)
		(fp_line
			(start 0.120396 0.3048)
			(end 0.120396 0.2794)
			(stroke
				(width 0.1)
				(type default)
			)
			(layer "F.Fab")
		)
		(fp_line
			(start 0.120396 0.2794)
			(end -0.12065 0.2794)
			(stroke
				(width 0.1)
				(type default)
			)
			(layer "F.Fab")
		)
		(fp_line
			(start -0.12065 0.3048)
			(end -0.67945 0.3048)
			(stroke
				(width 0.1)
				(type default)
			)
			(layer "F.Fab")
		)
		(fp_line
			(start -0.12065 0.2794)
			(end -0.12065 0.3048)
			(stroke
				(width 0.1)
				(type default)
			)
			(layer "F.Fab")
		)
		(fp_line
			(start -0.12065 -0.2794)
			(end 0.12065 -0.2794)
			(stroke
				(width 0.1)
				(type default)
			)
			(layer "F.Fab")
		)
		(fp_line
			(start -0.12065 -0.305054)
			(end -0.12065 -0.2794)
			(stroke
				(width 0.1)
				(type default)
			)
			(layer "F.Fab")
		)
		(fp_line
			(start -0.67945 0.3048)
			(end -0.67945 -0.305054)
			(stroke
				(width 0.1)
				(type default)
			)
			(layer "F.Fab")
		)
		(fp_line
			(start -0.67945 -0.305054)
			(end -0.12065 -0.305054)
			(stroke
				(width 0.1)
				(type default)
			)
			(layer "F.Fab")
		)
		(pad "1" smd circle
			(at -0.40005 0 180)
			(size 0 0)
			(layers "F.Cu" "F.Mask" "F.Paste")
			(net "HP_NIC7_EN")
		)
		(pad "2" smd circle
			(at 0.40005 0 180)
			(size 0 0)
			(layers "F.Cu" "F.Mask" "F.Paste")
			(net "P12V_NIC7_CO_EN")
		)
	)
	(footprint ""
		(layer "F.Cu")
		(at 90.039444 -96.811592 -90)
		(property "Reference" "R697"
			(at 0 0 270)
			(layer "F.SilkS")
			(hide yes)
			(effects
				(font
					(size 1.27 1.27)
				)
			)
		)
		(property "Value" ""
			(at 0 0 270)
			(layer "F.Fab")
			(effects
				(font
					(size 1.27 1.27)
				)
			)
		)
		(duplicate_pad_numbers_are_jumpers no)
		(fp_line
			(start -0.7874 0.4064)
			(end -0.7874 -0.4064)
			(stroke
				(width 0.1524)
				(type default)
			)
			(layer "F.SilkS")
		)
		(fp_line
			(start 0.7874 0.4064)
			(end -0.7874 0.4064)
			(stroke
				(width 0.1524)
				(type default)
			)
			(layer "F.SilkS")
		)
		(fp_line
			(start -0.7874 -0.4064)
			(end 0.7874 -0.4064)
			(stroke
				(width 0.1524)
				(type default)
			)
			(layer "F.SilkS")
		)
		(fp_line
			(start 0.7874 -0.4064)
			(end 0.7874 0.4064)
			(stroke
				(width 0.1524)
				(type default)
			)
			(layer "F.SilkS")
		)
		(fp_line
			(start -0.67945 0.3048)
			(end -0.67945 -0.305054)
			(stroke
				(width 0.1)
				(type default)
			)
			(layer "F.Fab")
		)
		(fp_line
			(start -0.12065 0.3048)
			(end -0.67945 0.3048)
			(stroke
				(width 0.1)
				(type default)
			)
			(layer "F.Fab")
		)
		(fp_line
			(start 0.120396 0.3048)
			(end 0.120396 0.2794)
			(stroke
				(width 0.1)
				(type default)
			)
			(layer "F.Fab")
		)
		(fp_line
			(start 0.67945 0.3048)
			(end 0.120396 0.3048)
			(stroke
				(width 0.1)
				(type default)
			)
			(layer "F.Fab")
		)
		(fp_line
			(start -0.12065 0.2794)
			(end -0.12065 0.3048)
			(stroke
				(width 0.1)
				(type default)
			)
			(layer "F.Fab")
		)
		(fp_line
			(start 0.120396 0.2794)
			(end -0.12065 0.2794)
			(stroke
				(width 0.1)
				(type default)
			)
			(layer "F.Fab")
		)
		(fp_line
			(start -0.12065 -0.2794)
			(end 0.12065 -0.2794)
			(stroke
				(width 0.1)
				(type default)
			)
			(layer "F.Fab")
		)
		(fp_line
			(start 0.12065 -0.2794)
			(end 0.12065 -0.3048)
			(stroke
				(width 0.1)
				(type default)
			)
			(layer "F.Fab")
		)
		(fp_line
			(start 0.12065 -0.3048)
			(end 0.67945 -0.3048)
			(stroke
				(width 0.1)
				(type default)
			)
			(layer "F.Fab")
		)
		(fp_line
			(start 0.67945 -0.3048)
			(end 0.67945 0.3048)
			(stroke
				(width 0.1)
				(type default)
			)
			(layer "F.Fab")
		)
		(fp_line
			(start -0.67945 -0.305054)
			(end -0.12065 -0.305054)
			(stroke
				(width 0.1)
				(type default)
			)
			(layer "F.Fab")
		)
		(fp_line
			(start -0.12065 -0.305054)
			(end -0.12065 -0.2794)
			(stroke
				(width 0.1)
				(type default)
			)
			(layer "F.Fab")
		)
		(pad "1" smd circle
			(at -0.40005 0 270)
			(size 0 0)
			(layers "F.Cu" "F.Mask" "F.Paste")
			(net "NIC1_ADC_A0")
		)
		(pad "2" smd circle
			(at 0.40005 0 270)
			(size 0 0)
			(layers "F.Cu" "F.Mask" "F.Paste")
			(net "GND")
		)
	)
	(footprint ""
		(layer "F.Cu")
		(at 473.594938 -554.99508 90)
		(property "Reference" "HS_BP1"
			(at -0.5842 -1.31953 90)
			(unlocked yes)
			(layer "B.SilkS")
			(effects
				(font
					(size 0.7874 0.5842)
					(thickness 0.1524)
				)
				(justify left mirror)
			)
		)
		(property "Value" ""
			(at 0 0 90)
			(layer "F.Fab")
			(effects
				(font
					(size 1.27 1.27)
				)
			)
		)
		(duplicate_pad_numbers_are_jumpers no)
		(pad "1" thru_hole circle
			(at 0 0 90)
			(size 0.4572 0.4572)
			(drill 0.2032)
			(layers "*.Cu" "*.Mask")
			(remove_unused_layers no)
			(net "Net_9201")
			(clearance 0.127)
			(thermal_gap 0.127)
			(padstack
				(mode front_inner_back)
				(layer "Inner"
					(shape circle)
					(size 0.4572 0.4572)
					(clearance 0.127)
				)
				(layer "B.Cu"
					(shape circle)
					(size 0.508 0.508)
					(clearance 0.1016)
				)
			)
		)
	)
	(footprint ""
		(layer "F.Cu")
		(at 99.469956 -237.401354 90)
		(property "Reference" "PC290"
			(at 0 0 90)
			(layer "F.SilkS")
			(hide yes)
			(effects
				(font
					(size 1.27 1.27)
				)
			)
		)
		(property "Value" ""
			(at 0 0 90)
			(layer "F.Fab")
			(effects
				(font
					(size 1.27 1.27)
				)
			)
		)
		(duplicate_pad_numbers_are_jumpers no)
		(fp_line
			(start 0.7874 -0.4064)
			(end 0.7874 0.4064)
			(stroke
				(width 0.1524)
				(type default)
			)
			(layer "F.SilkS")
		)
		(fp_line
			(start -0.7874 -0.4064)
			(end 0.7874 -0.4064)
			(stroke
				(width 0.1524)
				(type default)
			)
			(layer "F.SilkS")
		)
		(fp_line
			(start 0.7874 0.4064)
			(end -0.7874 0.4064)
			(stroke
				(width 0.1524)
				(type default)
			)
			(layer "F.SilkS")
		)
		(fp_line
			(start -0.7874 0.4064)
			(end -0.7874 -0.4064)
			(stroke
				(width 0.1524)
				(type default)
			)
			(layer "F.SilkS")
		)
		(fp_line
			(start -0.12065 -0.305054)
			(end -0.12065 -0.2794)
			(stroke
				(width 0.1)
				(type default)
			)
			(layer "F.Fab")
		)
		(fp_line
			(start -0.67945 -0.305054)
			(end -0.12065 -0.305054)
			(stroke
				(width 0.1)
				(type default)
			)
			(layer "F.Fab")
		)
		(fp_line
			(start 0.67945 -0.3048)
			(end 0.67945 0.3048)
			(stroke
				(width 0.1)
				(type default)
			)
			(layer "F.Fab")
		)
		(fp_line
			(start 0.12065 -0.3048)
			(end 0.67945 -0.3048)
			(stroke
				(width 0.1)
				(type default)
			)
			(layer "F.Fab")
		)
		(fp_line
			(start 0.12065 -0.2794)
			(end 0.12065 -0.3048)
			(stroke
				(width 0.1)
				(type default)
			)
			(layer "F.Fab")
		)
		(fp_line
			(start -0.12065 -0.2794)
			(end 0.12065 -0.2794)
			(stroke
				(width 0.1)
				(type default)
			)
			(layer "F.Fab")
		)
		(fp_line
			(start 0.120396 0.2794)
			(end -0.12065 0.2794)
			(stroke
				(width 0.1)
				(type default)
			)
			(layer "F.Fab")
		)
		(fp_line
			(start -0.12065 0.2794)
			(end -0.12065 0.3048)
			(stroke
				(width 0.1)
				(type default)
			)
			(layer "F.Fab")
		)
		(fp_line
			(start 0.67945 0.3048)
			(end 0.120396 0.3048)
			(stroke
				(width 0.1)
				(type default)
			)
			(layer "F.Fab")
		)
		(fp_line
			(start 0.120396 0.3048)
			(end 0.120396 0.2794)
			(stroke
				(width 0.1)
				(type default)
			)
			(layer "F.Fab")
		)
		(fp_line
			(start -0.12065 0.3048)
			(end -0.67945 0.3048)
			(stroke
				(width 0.1)
				(type default)
			)
			(layer "F.Fab")
		)
		(fp_line
			(start -0.67945 0.3048)
			(end -0.67945 -0.305054)
			(stroke
				(width 0.1)
				(type default)
			)
			(layer "F.Fab")
		)
		(pad "1" smd circle
			(at -0.40005 0 90)
			(size 0 0)
			(layers "F.Cu" "F.Mask" "F.Paste")
			(net "P1V8_PEX_R")
		)
		(pad "2" smd circle
			(at 0.40005 0 90)
			(size 0 0)
			(layers "F.Cu" "F.Mask" "F.Paste")
			(net "GND")
		)
	)
	(footprint ""
		(layer "F.Cu")
		(at 129.545588 -114.385852 -90)
		(property "Reference" "PC788"
			(at 0 0 270)
			(layer "F.SilkS")
			(hide yes)
			(effects
				(font
					(size 1.27 1.27)
				)
			)
		)
		(property "Value" ""
			(at 0 0 270)
			(layer "F.Fab")
			(effects
				(font
					(size 1.27 1.27)
				)
			)
		)
		(duplicate_pad_numbers_are_jumpers no)
		(fp_line
			(start -0.7874 0.4064)
			(end -0.7874 -0.4064)
			(stroke
				(width 0.1524)
				(type default)
			)
			(layer "F.SilkS")
		)
		(fp_line
			(start 0.7874 0.4064)
			(end -0.7874 0.4064)
			(stroke
				(width 0.1524)
				(type default)
			)
			(layer "F.SilkS")
		)
		(fp_line
			(start -0.7874 -0.4064)
			(end 0.7874 -0.4064)
			(stroke
				(width 0.1524)
				(type default)
			)
			(layer "F.SilkS")
		)
		(fp_line
			(start 0.7874 -0.4064)
			(end 0.7874 0.4064)
			(stroke
				(width 0.1524)
				(type default)
			)
			(layer "F.SilkS")
		)
		(fp_line
			(start -0.67945 0.3048)
			(end -0.67945 -0.305054)
			(stroke
				(width 0.1)
				(type default)
			)
			(layer "F.Fab")
		)
		(fp_line
			(start -0.12065 0.3048)
			(end -0.67945 0.3048)
			(stroke
				(width 0.1)
				(type default)
			)
			(layer "F.Fab")
		)
		(fp_line
			(start 0.120396 0.3048)
			(end 0.120396 0.2794)
			(stroke
				(width 0.1)
				(type default)
			)
			(layer "F.Fab")
		)
		(fp_line
			(start 0.67945 0.3048)
			(end 0.120396 0.3048)
			(stroke
				(width 0.1)
				(type default)
			)
			(layer "F.Fab")
		)
		(fp_line
			(start -0.12065 0.2794)
			(end -0.12065 0.3048)
			(stroke
				(width 0.1)
				(type default)
			)
			(layer "F.Fab")
		)
		(fp_line
			(start 0.120396 0.2794)
			(end -0.12065 0.2794)
			(stroke
				(width 0.1)
				(type default)
			)
			(layer "F.Fab")
		)
		(fp_line
			(start -0.12065 -0.2794)
			(end 0.12065 -0.2794)
			(stroke
				(width 0.1)
				(type default)
			)
			(layer "F.Fab")
		)
		(fp_line
			(start 0.12065 -0.2794)
			(end 0.12065 -0.3048)
			(stroke
				(width 0.1)
				(type default)
			)
			(layer "F.Fab")
		)
		(fp_line
			(start 0.12065 -0.3048)
			(end 0.67945 -0.3048)
			(stroke
				(width 0.1)
				(type default)
			)
			(layer "F.Fab")
		)
		(fp_line
			(start 0.67945 -0.3048)
			(end 0.67945 0.3048)
			(stroke
				(width 0.1)
				(type default)
			)
			(layer "F.Fab")
		)
		(fp_line
			(start -0.67945 -0.305054)
			(end -0.12065 -0.305054)
			(stroke
				(width 0.1)
				(type default)
			)
			(layer "F.Fab")
		)
		(fp_line
			(start -0.12065 -0.305054)
			(end -0.12065 -0.2794)
			(stroke
				(width 0.1)
				(type default)
			)
			(layer "F.Fab")
		)
		(pad "1" smd circle
			(at -0.40005 0 270)
			(size 0 0)
			(layers "F.Cu" "F.Mask" "F.Paste")
			(net "P3V3_AUX")
		)
		(pad "2" smd circle
			(at 0.40005 0 270)
			(size 0 0)
			(layers "F.Cu" "F.Mask" "F.Paste")
			(net "GND")
		)
	)
	(footprint ""
		(layer "F.Cu")
		(at 452.543672 -42.84091)
		(property "Reference" "R671"
			(at 0 0 0)
			(layer "F.SilkS")
			(hide yes)
			(effects
				(font
					(size 1.27 1.27)
				)
			)
		)
		(property "Value" ""
			(at 0 0 0)
			(layer "F.Fab")
			(effects
				(font
					(size 1.27 1.27)
				)
			)
		)
		(duplicate_pad_numbers_are_jumpers no)
		(fp_line
			(start -0.7874 -0.4064)
			(end 0.7874 -0.4064)
			(stroke
				(width 0.1524)
				(type default)
			)
			(layer "F.SilkS")
		)
		(fp_line
			(start -0.7874 0.4064)
			(end -0.7874 -0.4064)
			(stroke
				(width 0.1524)
				(type default)
			)
			(layer "F.SilkS")
		)
		(fp_line
			(start 0.7874 -0.4064)
			(end 0.7874 0.4064)
			(stroke
				(width 0.1524)
				(type default)
			)
			(layer "F.SilkS")
		)
		(fp_line
			(start 0.7874 0.4064)
			(end -0.7874 0.4064)
			(stroke
				(width 0.1524)
				(type default)
			)
			(layer "F.SilkS")
		)
		(fp_line
			(start -0.67945 -0.305054)
			(end -0.12065 -0.305054)
			(stroke
				(width 0.1)
				(type default)
			)
			(layer "F.Fab")
		)
		(fp_line
			(start -0.67945 0.3048)
			(end -0.67945 -0.305054)
			(stroke
				(width 0.1)
				(type default)
			)
			(layer "F.Fab")
		)
		(fp_line
			(start -0.12065 -0.305054)
			(end -0.12065 -0.2794)
			(stroke
				(width 0.1)
				(type default)
			)
			(layer "F.Fab")
		)
		(fp_line
			(start -0.12065 -0.2794)
			(end 0.12065 -0.2794)
			(stroke
				(width 0.1)
				(type default)
			)
			(layer "F.Fab")
		)
		(fp_line
			(start -0.12065 0.2794)
			(end -0.12065 0.3048)
			(stroke
				(width 0.1)
				(type default)
			)
			(layer "F.Fab")
		)
		(fp_line
			(start -0.12065 0.3048)
			(end -0.67945 0.3048)
			(stroke
				(width 0.1)
				(type default)
			)
			(layer "F.Fab")
		)
		(fp_line
			(start 0.120396 0.2794)
			(end -0.12065 0.2794)
			(stroke
				(width 0.1)
				(type default)
			)
			(layer "F.Fab")
		)
		(fp_line
			(start 0.120396 0.3048)
			(end 0.120396 0.2794)
			(stroke
				(width 0.1)
				(type default)
			)
			(layer "F.Fab")
		)
		(fp_line
			(start 0.12065 -0.3048)
			(end 0.67945 -0.3048)
			(stroke
				(width 0.1)
				(type default)
			)
			(layer "F.Fab")
		)
		(fp_line
			(start 0.12065 -0.2794)
			(end 0.12065 -0.3048)
			(stroke
				(width 0.1)
				(type default)
			)
			(layer "F.Fab")
		)
		(fp_line
			(start 0.67945 -0.3048)
			(end 0.67945 0.3048)
			(stroke
				(width 0.1)
				(type default)
			)
			(layer "F.Fab")
		)
		(fp_line
			(start 0.67945 0.3048)
			(end 0.120396 0.3048)
			(stroke
				(width 0.1)
				(type default)
			)
			(layer "F.Fab")
		)
		(pad "1" smd circle
			(at -0.40005 0)
			(size 0 0)
			(layers "F.Cu" "F.Mask" "F.Paste")
			(net "SSD15_ADC_A1")
		)
		(pad "2" smd circle
			(at 0.40005 0)
			(size 0 0)
			(layers "F.Cu" "F.Mask" "F.Paste")
			(net "P3V3_AUX")
		)
	)
	(footprint ""
		(layer "F.Cu")
		(at 217.902536 -257.975862 -90)
		(property "Reference" "R6503"
			(at 0 0 270)
			(layer "F.SilkS")
			(hide yes)
			(effects
				(font
					(size 1.27 1.27)
				)
			)
		)
		(property "Value" ""
			(at 0 0 270)
			(layer "F.Fab")
			(effects
				(font
					(size 1.27 1.27)
				)
			)
		)
		(duplicate_pad_numbers_are_jumpers no)
		(fp_line
			(start -0.7874 0.4064)
			(end -0.7874 -0.4064)
			(stroke
				(width 0.1524)
				(type default)
			)
			(layer "F.SilkS")
		)
		(fp_line
			(start 0.7874 0.4064)
			(end -0.7874 0.4064)
			(stroke
				(width 0.1524)
				(type default)
			)
			(layer "F.SilkS")
		)
		(fp_line
			(start -0.7874 -0.4064)
			(end 0.7874 -0.4064)
			(stroke
				(width 0.1524)
				(type default)
			)
			(layer "F.SilkS")
		)
		(fp_line
			(start 0.7874 -0.4064)
			(end 0.7874 0.4064)
			(stroke
				(width 0.1524)
				(type default)
			)
			(layer "F.SilkS")
		)
		(fp_line
			(start -0.67945 0.3048)
			(end -0.67945 -0.305054)
			(stroke
				(width 0.1)
				(type default)
			)
			(layer "F.Fab")
		)
		(fp_line
			(start -0.12065 0.3048)
			(end -0.67945 0.3048)
			(stroke
				(width 0.1)
				(type default)
			)
			(layer "F.Fab")
		)
		(fp_line
			(start 0.120396 0.3048)
			(end 0.120396 0.2794)
			(stroke
				(width 0.1)
				(type default)
			)
			(layer "F.Fab")
		)
		(fp_line
			(start 0.67945 0.3048)
			(end 0.120396 0.3048)
			(stroke
				(width 0.1)
				(type default)
			)
			(layer "F.Fab")
		)
		(fp_line
			(start -0.12065 0.2794)
			(end -0.12065 0.3048)
			(stroke
				(width 0.1)
				(type default)
			)
			(layer "F.Fab")
		)
		(fp_line
			(start 0.120396 0.2794)
			(end -0.12065 0.2794)
			(stroke
				(width 0.1)
				(type default)
			)
			(layer "F.Fab")
		)
		(fp_line
			(start -0.12065 -0.2794)
			(end 0.12065 -0.2794)
			(stroke
				(width 0.1)
				(type default)
			)
			(layer "F.Fab")
		)
		(fp_line
			(start 0.12065 -0.2794)
			(end 0.12065 -0.3048)
			(stroke
				(width 0.1)
				(type default)
			)
			(layer "F.Fab")
		)
		(fp_line
			(start 0.12065 -0.3048)
			(end 0.67945 -0.3048)
			(stroke
				(width 0.1)
				(type default)
			)
			(layer "F.Fab")
		)
		(fp_line
			(start 0.67945 -0.3048)
			(end 0.67945 0.3048)
			(stroke
				(width 0.1)
				(type default)
			)
			(layer "F.Fab")
		)
		(fp_line
			(start -0.67945 -0.305054)
			(end -0.12065 -0.305054)
			(stroke
				(width 0.1)
				(type default)
			)
			(layer "F.Fab")
		)
		(fp_line
			(start -0.12065 -0.305054)
			(end -0.12065 -0.2794)
			(stroke
				(width 0.1)
				(type default)
			)
			(layer "F.Fab")
		)
		(pad "1" smd circle
			(at -0.40005 0 270)
			(size 0 0)
			(layers "F.Cu" "F.Mask" "F.Paste")
			(net "P1V25_SERDES_VDDPLL_PEX1")
		)
		(pad "2" smd circle
			(at 0.40005 0 270)
			(size 0 0)
			(layers "F.Cu" "F.Mask" "F.Paste")
			(net "P1V25_SERDES_VDDPLL_PEX1_C10")
		)
	)
	(footprint ""
		(layer "F.Cu")
		(at 18.869914 -413.969708 90)
		(property "Reference" "R5593"
			(at 0 0 90)
			(layer "F.SilkS")
			(hide yes)
			(effects
				(font
					(size 1.27 1.27)
				)
			)
		)
		(property "Value" ""
			(at 0 0 90)
			(layer "F.Fab")
			(effects
				(font
					(size 1.27 1.27)
				)
			)
		)
		(duplicate_pad_numbers_are_jumpers no)
		(fp_line
			(start 0.7874 -0.4064)
			(end 0.7874 0.4064)
			(stroke
				(width 0.1524)
				(type default)
			)
			(layer "F.SilkS")
		)
		(fp_line
			(start -0.7874 -0.4064)
			(end 0.7874 -0.4064)
			(stroke
				(width 0.1524)
				(type default)
			)
			(layer "F.SilkS")
		)
		(fp_line
			(start 0.7874 0.4064)
			(end -0.7874 0.4064)
			(stroke
				(width 0.1524)
				(type default)
			)
			(layer "F.SilkS")
		)
		(fp_line
			(start -0.7874 0.4064)
			(end -0.7874 -0.4064)
			(stroke
				(width 0.1524)
				(type default)
			)
			(layer "F.SilkS")
		)
		(fp_line
			(start -0.12065 -0.305054)
			(end -0.12065 -0.2794)
			(stroke
				(width 0.1)
				(type default)
			)
			(layer "F.Fab")
		)
		(fp_line
			(start -0.67945 -0.305054)
			(end -0.12065 -0.305054)
			(stroke
				(width 0.1)
				(type default)
			)
			(layer "F.Fab")
		)
		(fp_line
			(start 0.67945 -0.3048)
			(end 0.67945 0.3048)
			(stroke
				(width 0.1)
				(type default)
			)
			(layer "F.Fab")
		)
		(fp_line
			(start 0.12065 -0.3048)
			(end 0.67945 -0.3048)
			(stroke
				(width 0.1)
				(type default)
			)
			(layer "F.Fab")
		)
		(fp_line
			(start 0.12065 -0.2794)
			(end 0.12065 -0.3048)
			(stroke
				(width 0.1)
				(type default)
			)
			(layer "F.Fab")
		)
		(fp_line
			(start -0.12065 -0.2794)
			(end 0.12065 -0.2794)
			(stroke
				(width 0.1)
				(type default)
			)
			(layer "F.Fab")
		)
		(fp_line
			(start 0.120396 0.2794)
			(end -0.12065 0.2794)
			(stroke
				(width 0.1)
				(type default)
			)
			(layer "F.Fab")
		)
		(fp_line
			(start -0.12065 0.2794)
			(end -0.12065 0.3048)
			(stroke
				(width 0.1)
				(type default)
			)
			(layer "F.Fab")
		)
		(fp_line
			(start 0.67945 0.3048)
			(end 0.120396 0.3048)
			(stroke
				(width 0.1)
				(type default)
			)
			(layer "F.Fab")
		)
		(fp_line
			(start 0.120396 0.3048)
			(end 0.120396 0.2794)
			(stroke
				(width 0.1)
				(type default)
			)
			(layer "F.Fab")
		)
		(fp_line
			(start -0.12065 0.3048)
			(end -0.67945 0.3048)
			(stroke
				(width 0.1)
				(type default)
			)
			(layer "F.Fab")
		)
		(fp_line
			(start -0.67945 0.3048)
			(end -0.67945 -0.305054)
			(stroke
				(width 0.1)
				(type default)
			)
			(layer "F.Fab")
		)
		(pad "1" smd circle
			(at -0.40005 0 90)
			(size 0 0)
			(layers "F.Cu" "F.Mask" "F.Paste")
			(net "LM75_0_A1")
		)
		(pad "2" smd circle
			(at 0.40005 0 90)
			(size 0 0)
			(layers "F.Cu" "F.Mask" "F.Paste")
			(net "GND")
		)
	)
	(footprint ""
		(layer "F.Cu")
		(at 289.954208 -48.21809)
		(property "Reference" "PD72"
			(at -3.391408 2.24536 0)
			(unlocked yes)
			(layer "F.SilkS")
			(effects
				(font
					(size 0.7874 0.5842)
					(thickness 0.1524)
				)
				(justify left)
			)
		)
		(property "Value" ""
			(at 0 0 0)
			(layer "F.Fab")
			(effects
				(font
					(size 1.27 1.27)
				)
			)
		)
		(duplicate_pad_numbers_are_jumpers no)
		(fp_line
			(start -3.400044 -1.459992)
			(end 4.107942 -1.459992)
			(stroke
				(width 0.1524)
				(type default)
			)
			(layer "F.SilkS")
		)
		(fp_line
			(start -3.400044 1.459992)
			(end -3.400044 -1.459992)
			(stroke
				(width 0.1524)
				(type default)
			)
			(layer "F.SilkS")
		)
		(fp_line
			(start 4.107942 -1.459992)
			(end 4.107942 1.459992)
			(stroke
				(width 0.1524)
				(type default)
			)
			(layer "F.SilkS")
		)
		(fp_line
			(start 4.107942 1.459992)
			(end -3.400044 1.459992)
			(stroke
				(width 0.1524)
				(type default)
			)
			(layer "F.SilkS")
		)
		(fp_poly
			(pts
				(xy 4.107942 -1.459992) (xy 4.107942 1.459992) (xy 3.308096 1.459992) (xy 3.308096 -1.459992)
			)
			(stroke
				(width 0)
				(type default)
			)
			(fill yes)
			(layer "F.SilkS")
		)
		(fp_line
			(start -2.29997 -1.459992)
			(end 2.29997 -1.459992)
			(stroke
				(width 0.1)
				(type default)
			)
			(layer "F.Fab")
		)
		(fp_line
			(start -2.29997 1.459992)
			(end -2.29997 -1.459992)
			(stroke
				(width 0.1)
				(type default)
			)
			(layer "F.Fab")
		)
		(fp_line
			(start 2.29997 -1.459992)
			(end 2.29997 1.459992)
			(stroke
				(width 0.1)
				(type default)
			)
			(layer "F.Fab")
		)
		(fp_line
			(start 2.29997 1.459992)
			(end -2.29997 1.459992)
			(stroke
				(width 0.1)
				(type default)
			)
			(layer "F.Fab")
		)
		(fp_text user "+"
			(at -4.7752 -0.12065 0)
			(unlocked yes)
			(layer "F.SilkS")
			(effects
				(font
					(size 1.905 1.4224)
					(thickness 0.1524)
				)
				(justify left)
			)
		)
		(fp_text user "-"
			(at 5.4102 0.29845 180)
			(unlocked yes)
			(layer "F.SilkS")
			(effects
				(font
					(size 1.905 1.4224)
					(thickness 0.1524)
				)
				(justify left)
			)
		)
		(fp_text user "+"
			(at -4.7752 -0.12065 0)
			(unlocked yes)
			(layer "F.Fab")
			(effects
				(font
					(size 1.905 1.4224)
					(thickness 0.1524)
				)
				(justify left)
			)
		)
		(fp_text user "-"
			(at 5.4102 0.29845 180)
			(unlocked yes)
			(layer "F.Fab")
			(effects
				(font
					(size 1.905 1.4224)
					(thickness 0.1524)
				)
				(justify left)
			)
		)
		(pad "A" smd rect
			(at -1.999996 0 90)
			(size 1.7018 2.5146)
			(layers "F.Cu" "F.Mask" "F.Paste")
			(net "GND")
		)
		(pad "C" smd rect
			(at 1.999996 0 90)
			(size 1.7018 2.5146)
			(layers "F.Cu" "F.Mask" "F.Paste")
			(net "P3V3_SSD10")
		)
	)
	(footprint ""
		(layer "F.Cu")
		(at 78.243684 -44.87291)
		(property "Reference" "R529"
			(at 0 0 0)
			(layer "F.SilkS")
			(hide yes)
			(effects
				(font
					(size 1.27 1.27)
				)
			)
		)
		(property "Value" ""
			(at 0 0 0)
			(layer "F.Fab")
			(effects
				(font
					(size 1.27 1.27)
				)
			)
		)
		(duplicate_pad_numbers_are_jumpers no)
		(fp_line
			(start -0.7874 -0.4064)
			(end 0.7874 -0.4064)
			(stroke
				(width 0.1524)
				(type default)
			)
			(layer "F.SilkS")
		)
		(fp_line
			(start -0.7874 0.4064)
			(end -0.7874 -0.4064)
			(stroke
				(width 0.1524)
				(type default)
			)
			(layer "F.SilkS")
		)
		(fp_line
			(start 0.7874 -0.4064)
			(end 0.7874 0.4064)
			(stroke
				(width 0.1524)
				(type default)
			)
			(layer "F.SilkS")
		)
		(fp_line
			(start 0.7874 0.4064)
			(end -0.7874 0.4064)
			(stroke
				(width 0.1524)
				(type default)
			)
			(layer "F.SilkS")
		)
		(fp_line
			(start -0.67945 -0.305054)
			(end -0.12065 -0.305054)
			(stroke
				(width 0.1)
				(type default)
			)
			(layer "F.Fab")
		)
		(fp_line
			(start -0.67945 0.3048)
			(end -0.67945 -0.305054)
			(stroke
				(width 0.1)
				(type default)
			)
			(layer "F.Fab")
		)
		(fp_line
			(start -0.12065 -0.305054)
			(end -0.12065 -0.2794)
			(stroke
				(width 0.1)
				(type default)
			)
			(layer "F.Fab")
		)
		(fp_line
			(start -0.12065 -0.2794)
			(end 0.12065 -0.2794)
			(stroke
				(width 0.1)
				(type default)
			)
			(layer "F.Fab")
		)
		(fp_line
			(start -0.12065 0.2794)
			(end -0.12065 0.3048)
			(stroke
				(width 0.1)
				(type default)
			)
			(layer "F.Fab")
		)
		(fp_line
			(start -0.12065 0.3048)
			(end -0.67945 0.3048)
			(stroke
				(width 0.1)
				(type default)
			)
			(layer "F.Fab")
		)
		(fp_line
			(start 0.120396 0.2794)
			(end -0.12065 0.2794)
			(stroke
				(width 0.1)
				(type default)
			)
			(layer "F.Fab")
		)
		(fp_line
			(start 0.120396 0.3048)
			(end 0.120396 0.2794)
			(stroke
				(width 0.1)
				(type default)
			)
			(layer "F.Fab")
		)
		(fp_line
			(start 0.12065 -0.3048)
			(end 0.67945 -0.3048)
			(stroke
				(width 0.1)
				(type default)
			)
			(layer "F.Fab")
		)
		(fp_line
			(start 0.12065 -0.2794)
			(end 0.12065 -0.3048)
			(stroke
				(width 0.1)
				(type default)
			)
			(layer "F.Fab")
		)
		(fp_line
			(start 0.67945 -0.3048)
			(end 0.67945 0.3048)
			(stroke
				(width 0.1)
				(type default)
			)
			(layer "F.Fab")
		)
		(fp_line
			(start 0.67945 0.3048)
			(end 0.120396 0.3048)
			(stroke
				(width 0.1)
				(type default)
			)
			(layer "F.Fab")
		)
		(pad "1" smd circle
			(at -0.40005 0)
			(size 0 0)
			(layers "F.Cu" "F.Mask" "F.Paste")
			(net "SSD2_ADC_A0")
		)
		(pad "2" smd circle
			(at 0.40005 0)
			(size 0 0)
			(layers "F.Cu" "F.Mask" "F.Paste")
			(net "P3V3_AUX")
		)
	)
	(footprint ""
		(layer "F.Cu")
		(at 393.771628 -25.342342 -90)
		(property "Reference" "R448"
			(at 0 0 270)
			(layer "F.SilkS")
			(hide yes)
			(effects
				(font
					(size 1.27 1.27)
				)
			)
		)
		(property "Value" ""
			(at 0 0 270)
			(layer "F.Fab")
			(effects
				(font
					(size 1.27 1.27)
				)
			)
		)
		(duplicate_pad_numbers_are_jumpers no)
		(fp_line
			(start -0.7874 0.4064)
			(end -0.7874 -0.4064)
			(stroke
				(width 0.1524)
				(type default)
			)
			(layer "F.SilkS")
		)
		(fp_line
			(start 0.7874 0.4064)
			(end -0.7874 0.4064)
			(stroke
				(width 0.1524)
				(type default)
			)
			(layer "F.SilkS")
		)
		(fp_line
			(start -0.7874 -0.4064)
			(end 0.7874 -0.4064)
			(stroke
				(width 0.1524)
				(type default)
			)
			(layer "F.SilkS")
		)
		(fp_line
			(start 0.7874 -0.4064)
			(end 0.7874 0.4064)
			(stroke
				(width 0.1524)
				(type default)
			)
			(layer "F.SilkS")
		)
		(fp_line
			(start -0.67945 0.3048)
			(end -0.67945 -0.305054)
			(stroke
				(width 0.1)
				(type default)
			)
			(layer "F.Fab")
		)
		(fp_line
			(start -0.12065 0.3048)
			(end -0.67945 0.3048)
			(stroke
				(width 0.1)
				(type default)
			)
			(layer "F.Fab")
		)
		(fp_line
			(start 0.120396 0.3048)
			(end 0.120396 0.2794)
			(stroke
				(width 0.1)
				(type default)
			)
			(layer "F.Fab")
		)
		(fp_line
			(start 0.67945 0.3048)
			(end 0.120396 0.3048)
			(stroke
				(width 0.1)
				(type default)
			)
			(layer "F.Fab")
		)
		(fp_line
			(start -0.12065 0.2794)
			(end -0.12065 0.3048)
			(stroke
				(width 0.1)
				(type default)
			)
			(layer "F.Fab")
		)
		(fp_line
			(start 0.120396 0.2794)
			(end -0.12065 0.2794)
			(stroke
				(width 0.1)
				(type default)
			)
			(layer "F.Fab")
		)
		(fp_line
			(start -0.12065 -0.2794)
			(end 0.12065 -0.2794)
			(stroke
				(width 0.1)
				(type default)
			)
			(layer "F.Fab")
		)
		(fp_line
			(start 0.12065 -0.2794)
			(end 0.12065 -0.3048)
			(stroke
				(width 0.1)
				(type default)
			)
			(layer "F.Fab")
		)
		(fp_line
			(start 0.12065 -0.3048)
			(end 0.67945 -0.3048)
			(stroke
				(width 0.1)
				(type default)
			)
			(layer "F.Fab")
		)
		(fp_line
			(start 0.67945 -0.3048)
			(end 0.67945 0.3048)
			(stroke
				(width 0.1)
				(type default)
			)
			(layer "F.Fab")
		)
		(fp_line
			(start -0.67945 -0.305054)
			(end -0.12065 -0.305054)
			(stroke
				(width 0.1)
				(type default)
			)
			(layer "F.Fab")
		)
		(fp_line
			(start -0.12065 -0.305054)
			(end -0.12065 -0.2794)
			(stroke
				(width 0.1)
				(type default)
			)
			(layer "F.Fab")
		)
		(pad "1" smd circle
			(at -0.40005 0 270)
			(size 0 0)
			(layers "F.Cu" "F.Mask" "F.Paste")
			(net "P3V3_SSD13")
		)
		(pad "2" smd circle
			(at 0.40005 0 270)
			(size 0 0)
			(layers "F.Cu" "F.Mask" "F.Paste")
			(net "DUALPORT_N_SSD13")
		)
	)
	(footprint ""
		(layer "F.Cu")
		(at 107.581954 -79.822294 90)
		(property "Reference" "R1138"
			(at 0 0 90)
			(layer "F.SilkS")
			(hide yes)
			(effects
				(font
					(size 1.27 1.27)
				)
			)
		)
		(property "Value" ""
			(at 0 0 90)
			(layer "F.Fab")
			(effects
				(font
					(size 1.27 1.27)
				)
			)
		)
		(duplicate_pad_numbers_are_jumpers no)
		(fp_line
			(start -0.7874 -0.4064)
			(end 0.7874 -0.4064)
			(stroke
				(width 0.1524)
				(type default)
			)
			(layer "F.SilkS")
		)
		(fp_line
			(start -0.12065 -0.305054)
			(end -0.12065 -0.2794)
			(stroke
				(width 0.1)
				(type default)
			)
			(layer "F.Fab")
		)
		(fp_line
			(start -0.67945 -0.305054)
			(end -0.12065 -0.305054)
			(stroke
				(width 0.1)
				(type default)
			)
			(layer "F.Fab")
		)
		(fp_line
			(start 0.67945 -0.3048)
			(end 0.67945 0.3048)
			(stroke
				(width 0.1)
				(type default)
			)
			(layer "F.Fab")
		)
		(fp_line
			(start 0.12065 -0.3048)
			(end 0.67945 -0.3048)
			(stroke
				(width 0.1)
				(type default)
			)
			(layer "F.Fab")
		)
		(fp_line
			(start 0.12065 -0.2794)
			(end 0.12065 -0.3048)
			(stroke
				(width 0.1)
				(type default)
			)
			(layer "F.Fab")
		)
		(fp_line
			(start -0.12065 -0.2794)
			(end 0.12065 -0.2794)
			(stroke
				(width 0.1)
				(type default)
			)
			(layer "F.Fab")
		)
		(fp_line
			(start 0.120396 0.2794)
			(end -0.12065 0.2794)
			(stroke
				(width 0.1)
				(type default)
			)
			(layer "F.Fab")
		)
		(fp_line
			(start -0.12065 0.2794)
			(end -0.12065 0.3048)
			(stroke
				(width 0.1)
				(type default)
			)
			(layer "F.Fab")
		)
		(fp_line
			(start 0.67945 0.3048)
			(end 0.120396 0.3048)
			(stroke
				(width 0.1)
				(type default)
			)
			(layer "F.Fab")
		)
		(fp_line
			(start 0.120396 0.3048)
			(end 0.120396 0.2794)
			(stroke
				(width 0.1)
				(type default)
			)
			(layer "F.Fab")
		)
		(fp_line
			(start -0.12065 0.3048)
			(end -0.67945 0.3048)
			(stroke
				(width 0.1)
				(type default)
			)
			(layer "F.Fab")
		)
		(fp_line
			(start -0.67945 0.3048)
			(end -0.67945 -0.305054)
			(stroke
				(width 0.1)
				(type default)
			)
			(layer "F.Fab")
		)
		(pad "1" smd circle
			(at -0.40005 0 90)
			(size 0 0)
			(layers "F.Cu" "F.Mask" "F.Paste")
			(net "CLK_100M_DB800ZL_SSD1_R_DP")
		)
		(pad "2" smd circle
			(at 0.40005 0 90)
			(size 0 0)
			(layers "F.Cu" "F.Mask" "F.Paste")
			(net "CLK_100M_DB800ZL_SSD1_DP")
		)
	)
	(footprint ""
		(layer "F.Cu")
		(at 22.82063 -70.307454 90)
		(property "Reference" "PC639"
			(at 0 0 90)
			(layer "F.SilkS")
			(hide yes)
			(effects
				(font
					(size 1.27 1.27)
				)
			)
		)
		(property "Value" ""
			(at 0 0 90)
			(layer "F.Fab")
			(effects
				(font
					(size 1.27 1.27)
				)
			)
		)
		(duplicate_pad_numbers_are_jumpers no)
		(fp_line
			(start 0.7874 -0.4064)
			(end 0.7874 0.4064)
			(stroke
				(width 0.1524)
				(type default)
			)
			(layer "F.SilkS")
		)
		(fp_line
			(start -0.7874 -0.4064)
			(end 0.7874 -0.4064)
			(stroke
				(width 0.1524)
				(type default)
			)
			(layer "F.SilkS")
		)
		(fp_line
			(start 0.7874 0.4064)
			(end -0.7874 0.4064)
			(stroke
				(width 0.1524)
				(type default)
			)
			(layer "F.SilkS")
		)
		(fp_line
			(start -0.7874 0.4064)
			(end -0.7874 -0.4064)
			(stroke
				(width 0.1524)
				(type default)
			)
			(layer "F.SilkS")
		)
		(fp_line
			(start -0.12065 -0.305054)
			(end -0.12065 -0.2794)
			(stroke
				(width 0.1)
				(type default)
			)
			(layer "F.Fab")
		)
		(fp_line
			(start -0.67945 -0.305054)
			(end -0.12065 -0.305054)
			(stroke
				(width 0.1)
				(type default)
			)
			(layer "F.Fab")
		)
		(fp_line
			(start 0.67945 -0.3048)
			(end 0.67945 0.3048)
			(stroke
				(width 0.1)
				(type default)
			)
			(layer "F.Fab")
		)
		(fp_line
			(start 0.12065 -0.3048)
			(end 0.67945 -0.3048)
			(stroke
				(width 0.1)
				(type default)
			)
			(layer "F.Fab")
		)
		(fp_line
			(start 0.12065 -0.2794)
			(end 0.12065 -0.3048)
			(stroke
				(width 0.1)
				(type default)
			)
			(layer "F.Fab")
		)
		(fp_line
			(start -0.12065 -0.2794)
			(end 0.12065 -0.2794)
			(stroke
				(width 0.1)
				(type default)
			)
			(layer "F.Fab")
		)
		(fp_line
			(start 0.120396 0.2794)
			(end -0.12065 0.2794)
			(stroke
				(width 0.1)
				(type default)
			)
			(layer "F.Fab")
		)
		(fp_line
			(start -0.12065 0.2794)
			(end -0.12065 0.3048)
			(stroke
				(width 0.1)
				(type default)
			)
			(layer "F.Fab")
		)
		(fp_line
			(start 0.67945 0.3048)
			(end 0.120396 0.3048)
			(stroke
				(width 0.1)
				(type default)
			)
			(layer "F.Fab")
		)
		(fp_line
			(start 0.120396 0.3048)
			(end 0.120396 0.2794)
			(stroke
				(width 0.1)
				(type default)
			)
			(layer "F.Fab")
		)
		(fp_line
			(start -0.12065 0.3048)
			(end -0.67945 0.3048)
			(stroke
				(width 0.1)
				(type default)
			)
			(layer "F.Fab")
		)
		(fp_line
			(start -0.67945 0.3048)
			(end -0.67945 -0.305054)
			(stroke
				(width 0.1)
				(type default)
			)
			(layer "F.Fab")
		)
		(pad "1" smd circle
			(at -0.40005 0 90)
			(size 0 0)
			(layers "F.Cu" "F.Mask" "F.Paste")
			(net "P12V_AUX")
		)
		(pad "2" smd circle
			(at 0.40005 0 90)
			(size 0 0)
			(layers "F.Cu" "F.Mask" "F.Paste")
			(net "GND")
		)
	)
	(footprint ""
		(layer "F.Cu")
		(at 30.153356 -284.990032)
		(property "Reference" "L95"
			(at 0 0 0)
			(layer "F.SilkS")
			(hide yes)
			(effects
				(font
					(size 1.27 1.27)
				)
			)
		)
		(property "Value" ""
			(at 0 0 0)
			(layer "F.Fab")
			(effects
				(font
					(size 1.27 1.27)
				)
			)
		)
		(duplicate_pad_numbers_are_jumpers no)
		(fp_line
			(start -1.63576 -0.8128)
			(end -1.63576 0.8128)
			(stroke
				(width 0.1524)
				(type default)
			)
			(layer "F.SilkS")
		)
		(fp_line
			(start -1.63576 -0.8128)
			(end 1.63576 -0.8128)
			(stroke
				(width 0.1524)
				(type default)
			)
			(layer "F.SilkS")
		)
		(fp_line
			(start 1.63576 -0.8128)
			(end 1.63576 0.8128)
			(stroke
				(width 0.1524)
				(type default)
			)
			(layer "F.SilkS")
		)
		(fp_line
			(start 1.63576 0.8128)
			(end -1.63576 0.8128)
			(stroke
				(width 0.1524)
				(type default)
			)
			(layer "F.SilkS")
		)
		(fp_line
			(start -1.56083 -0.738632)
			(end -1.56083 0.7366)
			(stroke
				(width 0.1)
				(type default)
			)
			(layer "F.Fab")
		)
		(fp_line
			(start -1.56083 0.7366)
			(end -1.524 0.7366)
			(stroke
				(width 0.1)
				(type default)
			)
			(layer "F.Fab")
		)
		(fp_line
			(start -1.524 0.7366)
			(end 1.524 0.7366)
			(stroke
				(width 0.1)
				(type default)
			)
			(layer "F.Fab")
		)
		(fp_line
			(start 1.524 0.7366)
			(end 1.560576 0.7366)
			(stroke
				(width 0.1)
				(type default)
			)
			(layer "F.Fab")
		)
		(fp_line
			(start 1.560576 -0.738632)
			(end -1.56083 -0.738632)
			(stroke
				(width 0.1)
				(type default)
			)
			(layer "F.Fab")
		)
		(fp_line
			(start 1.560576 0.7366)
			(end 1.560576 -0.738632)
			(stroke
				(width 0.1)
				(type default)
			)
			(layer "F.Fab")
		)
		(pad "1" smd rect
			(at -0.94996 0 180)
			(size 1.1176 1.3716)
			(layers "F.Cu" "F.Mask" "F.Paste")
			(net "P1V8_PLL0_PEX0")
		)
		(pad "2" smd rect
			(at 0.94996 0 180)
			(size 1.1176 1.3716)
			(layers "F.Cu" "F.Mask" "F.Paste")
			(net "PCEPLL7_VDDA18_PEX0")
		)
	)
	(footprint ""
		(layer "F.Cu")
		(at 237.59414 -29.507688 -90)
		(property "Reference" "PC941"
			(at 0 0 270)
			(layer "F.SilkS")
			(hide yes)
			(effects
				(font
					(size 1.27 1.27)
				)
			)
		)
		(property "Value" ""
			(at 0 0 270)
			(layer "F.Fab")
			(effects
				(font
					(size 1.27 1.27)
				)
			)
		)
		(duplicate_pad_numbers_are_jumpers no)
		(fp_line
			(start -1.524 0.762)
			(end -1.524 -0.762)
			(stroke
				(width 0.1524)
				(type default)
			)
			(layer "F.SilkS")
		)
		(fp_line
			(start 1.524 0.762)
			(end -1.524 0.762)
			(stroke
				(width 0.1524)
				(type default)
			)
			(layer "F.SilkS")
		)
		(fp_line
			(start -1.524 -0.762)
			(end 1.524 -0.762)
			(stroke
				(width 0.1524)
				(type default)
			)
			(layer "F.SilkS")
		)
		(fp_line
			(start 1.524 -0.762)
			(end 1.524 0.762)
			(stroke
				(width 0.1524)
				(type default)
			)
			(layer "F.SilkS")
		)
		(fp_line
			(start -1.1049 0.724916)
			(end 1.1049 0.724916)
			(stroke
				(width 0.1)
				(type default)
			)
			(layer "F.Fab")
		)
		(fp_line
			(start 1.1049 0.724916)
			(end 1.1049 -0.724916)
			(stroke
				(width 0.1)
				(type default)
			)
			(layer "F.Fab")
		)
		(fp_line
			(start -1.1049 -0.724916)
			(end -1.1049 0.724916)
			(stroke
				(width 0.1)
				(type default)
			)
			(layer "F.Fab")
		)
		(fp_line
			(start 1.1049 -0.724916)
			(end -1.1049 -0.724916)
			(stroke
				(width 0.1)
				(type default)
			)
			(layer "F.Fab")
		)
		(pad "1" smd rect
			(at -0.889 0 90)
			(size 1.016 1.27)
			(layers "F.Cu" "F.Mask" "F.Paste")
			(net "P3V3_SSD8")
		)
		(pad "2" smd rect
			(at 0.889 0 90)
			(size 1.016 1.27)
			(layers "F.Cu" "F.Mask" "F.Paste")
			(net "GND")
		)
	)
	(footprint ""
		(layer "F.Cu")
		(at 154.707844 -157.3784 180)
		(property "Reference" "R114"
			(at 0 0 180)
			(layer "F.SilkS")
			(hide yes)
			(effects
				(font
					(size 1.27 1.27)
				)
			)
		)
		(property "Value" ""
			(at 0 0 180)
			(layer "F.Fab")
			(effects
				(font
					(size 1.27 1.27)
				)
			)
		)
		(duplicate_pad_numbers_are_jumpers no)
		(fp_line
			(start 0.7874 0.4064)
			(end -0.7874 0.4064)
			(stroke
				(width 0.1524)
				(type default)
			)
			(layer "F.SilkS")
		)
		(fp_line
			(start 0.7874 -0.4064)
			(end 0.7874 0.4064)
			(stroke
				(width 0.1524)
				(type default)
			)
			(layer "F.SilkS")
		)
		(fp_line
			(start -0.7874 0.4064)
			(end -0.7874 -0.4064)
			(stroke
				(width 0.1524)
				(type default)
			)
			(layer "F.SilkS")
		)
		(fp_line
			(start -0.7874 -0.4064)
			(end 0.7874 -0.4064)
			(stroke
				(width 0.1524)
				(type default)
			)
			(layer "F.SilkS")
		)
		(fp_line
			(start 0.67945 0.3048)
			(end 0.120396 0.3048)
			(stroke
				(width 0.1)
				(type default)
			)
			(layer "F.Fab")
		)
		(fp_line
			(start 0.67945 -0.3048)
			(end 0.67945 0.3048)
			(stroke
				(width 0.1)
				(type default)
			)
			(layer "F.Fab")
		)
		(fp_line
			(start 0.12065 -0.2794)
			(end 0.12065 -0.3048)
			(stroke
				(width 0.1)
				(type default)
			)
			(layer "F.Fab")
		)
		(fp_line
			(start 0.12065 -0.3048)
			(end 0.67945 -0.3048)
			(stroke
				(width 0.1)
				(type default)
			)
			(layer "F.Fab")
		)
		(fp_line
			(start 0.120396 0.3048)
			(end 0.120396 0.2794)
			(stroke
				(width 0.1)
				(type default)
			)
			(layer "F.Fab")
		)
		(fp_line
			(start 0.120396 0.2794)
			(end -0.12065 0.2794)
			(stroke
				(width 0.1)
				(type default)
			)
			(layer "F.Fab")
		)
		(fp_line
			(start -0.12065 0.3048)
			(end -0.67945 0.3048)
			(stroke
				(width 0.1)
				(type default)
			)
			(layer "F.Fab")
		)
		(fp_line
			(start -0.12065 0.2794)
			(end -0.12065 0.3048)
			(stroke
				(width 0.1)
				(type default)
			)
			(layer "F.Fab")
		)
		(fp_line
			(start -0.12065 -0.2794)
			(end 0.12065 -0.2794)
			(stroke
				(width 0.1)
				(type default)
			)
			(layer "F.Fab")
		)
		(fp_line
			(start -0.12065 -0.305054)
			(end -0.12065 -0.2794)
			(stroke
				(width 0.1)
				(type default)
			)
			(layer "F.Fab")
		)
		(fp_line
			(start -0.67945 0.3048)
			(end -0.67945 -0.305054)
			(stroke
				(width 0.1)
				(type default)
			)
			(layer "F.Fab")
		)
		(fp_line
			(start -0.67945 -0.305054)
			(end -0.12065 -0.305054)
			(stroke
				(width 0.1)
				(type default)
			)
			(layer "F.Fab")
		)
		(pad "1" smd circle
			(at -0.40005 0 180)
			(size 0 0)
			(layers "F.Cu" "F.Mask" "F.Paste")
			(net "NIC2_DATA_IN")
		)
		(pad "2" smd circle
			(at 0.40005 0 180)
			(size 0 0)
			(layers "F.Cu" "F.Mask" "F.Paste")
			(net "P3V3_NIC2")
		)
	)
	(footprint ""
		(layer "F.Cu")
		(at 226.455224 -35.876738)
		(property "Reference" "R6080"
			(at 0 0 0)
			(layer "F.SilkS")
			(hide yes)
			(effects
				(font
					(size 1.27 1.27)
				)
			)
		)
		(property "Value" ""
			(at 0 0 0)
			(layer "F.Fab")
			(effects
				(font
					(size 1.27 1.27)
				)
			)
		)
		(duplicate_pad_numbers_are_jumpers no)
		(fp_line
			(start -0.7874 -0.4064)
			(end 0.7874 -0.4064)
			(stroke
				(width 0.1524)
				(type default)
			)
			(layer "F.SilkS")
		)
		(fp_line
			(start -0.7874 0.4064)
			(end -0.7874 -0.4064)
			(stroke
				(width 0.1524)
				(type default)
			)
			(layer "F.SilkS")
		)
		(fp_line
			(start 0.7874 -0.4064)
			(end 0.7874 0.4064)
			(stroke
				(width 0.1524)
				(type default)
			)
			(layer "F.SilkS")
		)
		(fp_line
			(start 0.7874 0.4064)
			(end -0.7874 0.4064)
			(stroke
				(width 0.1524)
				(type default)
			)
			(layer "F.SilkS")
		)
		(fp_line
			(start -0.67945 -0.305054)
			(end -0.12065 -0.305054)
			(stroke
				(width 0.1)
				(type default)
			)
			(layer "F.Fab")
		)
		(fp_line
			(start -0.67945 0.3048)
			(end -0.67945 -0.305054)
			(stroke
				(width 0.1)
				(type default)
			)
			(layer "F.Fab")
		)
		(fp_line
			(start -0.12065 -0.305054)
			(end -0.12065 -0.2794)
			(stroke
				(width 0.1)
				(type default)
			)
			(layer "F.Fab")
		)
		(fp_line
			(start -0.12065 -0.2794)
			(end 0.12065 -0.2794)
			(stroke
				(width 0.1)
				(type default)
			)
			(layer "F.Fab")
		)
		(fp_line
			(start -0.12065 0.2794)
			(end -0.12065 0.3048)
			(stroke
				(width 0.1)
				(type default)
			)
			(layer "F.Fab")
		)
		(fp_line
			(start -0.12065 0.3048)
			(end -0.67945 0.3048)
			(stroke
				(width 0.1)
				(type default)
			)
			(layer "F.Fab")
		)
		(fp_line
			(start 0.120396 0.2794)
			(end -0.12065 0.2794)
			(stroke
				(width 0.1)
				(type default)
			)
			(layer "F.Fab")
		)
		(fp_line
			(start 0.120396 0.3048)
			(end 0.120396 0.2794)
			(stroke
				(width 0.1)
				(type default)
			)
			(layer "F.Fab")
		)
		(fp_line
			(start 0.12065 -0.3048)
			(end 0.67945 -0.3048)
			(stroke
				(width 0.1)
				(type default)
			)
			(layer "F.Fab")
		)
		(fp_line
			(start 0.12065 -0.2794)
			(end 0.12065 -0.3048)
			(stroke
				(width 0.1)
				(type default)
			)
			(layer "F.Fab")
		)
		(fp_line
			(start 0.67945 -0.3048)
			(end 0.67945 0.3048)
			(stroke
				(width 0.1)
				(type default)
			)
			(layer "F.Fab")
		)
		(fp_line
			(start 0.67945 0.3048)
			(end 0.120396 0.3048)
			(stroke
				(width 0.1)
				(type default)
			)
			(layer "F.Fab")
		)
		(pad "1" smd circle
			(at -0.40005 0)
			(size 0 0)
			(layers "F.Cu" "F.Mask" "F.Paste")
			(net "P3V3_AUX")
		)
		(pad "2" smd circle
			(at 0.40005 0)
			(size 0 0)
			(layers "F.Cu" "F.Mask" "F.Paste")
			(net "PWRGD_P3V3_SSD8_D")
		)
	)
	(footprint ""
		(layer "F.Cu")
		(at 234.65536 -368.182144)
		(property "Reference" "PR38"
			(at 0 0 0)
			(layer "F.SilkS")
			(hide yes)
			(effects
				(font
					(size 1.27 1.27)
				)
			)
		)
		(property "Value" ""
			(at 0 0 0)
			(layer "F.Fab")
			(effects
				(font
					(size 1.27 1.27)
				)
			)
		)
		(duplicate_pad_numbers_are_jumpers no)
		(fp_line
			(start -0.7874 -0.4064)
			(end 0.7874 -0.4064)
			(stroke
				(width 0.1524)
				(type default)
			)
			(layer "F.SilkS")
		)
		(fp_line
			(start -0.7874 0.4064)
			(end -0.7874 -0.4064)
			(stroke
				(width 0.1524)
				(type default)
			)
			(layer "F.SilkS")
		)
		(fp_line
			(start 0.7874 -0.4064)
			(end 0.7874 0.4064)
			(stroke
				(width 0.1524)
				(type default)
			)
			(layer "F.SilkS")
		)
		(fp_line
			(start 0.7874 0.4064)
			(end -0.7874 0.4064)
			(stroke
				(width 0.1524)
				(type default)
			)
			(layer "F.SilkS")
		)
		(fp_line
			(start -0.67945 -0.305054)
			(end -0.12065 -0.305054)
			(stroke
				(width 0.1)
				(type default)
			)
			(layer "F.Fab")
		)
		(fp_line
			(start -0.67945 0.3048)
			(end -0.67945 -0.305054)
			(stroke
				(width 0.1)
				(type default)
			)
			(layer "F.Fab")
		)
		(fp_line
			(start -0.12065 -0.305054)
			(end -0.12065 -0.2794)
			(stroke
				(width 0.1)
				(type default)
			)
			(layer "F.Fab")
		)
		(fp_line
			(start -0.12065 -0.2794)
			(end 0.12065 -0.2794)
			(stroke
				(width 0.1)
				(type default)
			)
			(layer "F.Fab")
		)
		(fp_line
			(start -0.12065 0.2794)
			(end -0.12065 0.3048)
			(stroke
				(width 0.1)
				(type default)
			)
			(layer "F.Fab")
		)
		(fp_line
			(start -0.12065 0.3048)
			(end -0.67945 0.3048)
			(stroke
				(width 0.1)
				(type default)
			)
			(layer "F.Fab")
		)
		(fp_line
			(start 0.120396 0.2794)
			(end -0.12065 0.2794)
			(stroke
				(width 0.1)
				(type default)
			)
			(layer "F.Fab")
		)
		(fp_line
			(start 0.120396 0.3048)
			(end 0.120396 0.2794)
			(stroke
				(width 0.1)
				(type default)
			)
			(layer "F.Fab")
		)
		(fp_line
			(start 0.12065 -0.3048)
			(end 0.67945 -0.3048)
			(stroke
				(width 0.1)
				(type default)
			)
			(layer "F.Fab")
		)
		(fp_line
			(start 0.12065 -0.2794)
			(end 0.12065 -0.3048)
			(stroke
				(width 0.1)
				(type default)
			)
			(layer "F.Fab")
		)
		(fp_line
			(start 0.67945 -0.3048)
			(end 0.67945 0.3048)
			(stroke
				(width 0.1)
				(type default)
			)
			(layer "F.Fab")
		)
		(fp_line
			(start 0.67945 0.3048)
			(end 0.120396 0.3048)
			(stroke
				(width 0.1)
				(type default)
			)
			(layer "F.Fab")
		)
		(pad "1" smd circle
			(at -0.40005 0)
			(size 0 0)
			(layers "F.Cu" "F.Mask" "F.Paste")
			(net "HSC_D_OC_2")
		)
		(pad "2" smd circle
			(at 0.40005 0)
			(size 0 0)
			(layers "F.Cu" "F.Mask" "F.Paste")
			(net "HSC_D_OC")
		)
	)
	(footprint ""
		(layer "F.Cu")
		(at 209.24266 -70.844918 -90)
		(property "Reference" "PD35"
			(at 4.093718 2.12979 90)
			(unlocked yes)
			(layer "F.SilkS")
			(effects
				(font
					(size 0.7874 0.5842)
					(thickness 0.1524)
				)
				(justify left)
			)
		)
		(property "Value" ""
			(at 0 0 270)
			(layer "F.Fab")
			(effects
				(font
					(size 1.27 1.27)
				)
			)
		)
		(duplicate_pad_numbers_are_jumpers no)
		(fp_line
			(start -3.400044 1.459992)
			(end -3.400044 -1.459992)
			(stroke
				(width 0.1524)
				(type default)
			)
			(layer "F.SilkS")
		)
		(fp_line
			(start 4.107942 1.459992)
			(end -3.400044 1.459992)
			(stroke
				(width 0.1524)
				(type default)
			)
			(layer "F.SilkS")
		)
		(fp_line
			(start -3.400044 -1.459992)
			(end 4.107942 -1.459992)
			(stroke
				(width 0.1524)
				(type default)
			)
			(layer "F.SilkS")
		)
		(fp_line
			(start 4.107942 -1.459992)
			(end 4.107942 1.459992)
			(stroke
				(width 0.1524)
				(type default)
			)
			(layer "F.SilkS")
		)
		(fp_poly
			(pts
				(xy 4.107942 -1.459992) (xy 4.107942 1.459992) (xy 3.308096 1.459992) (xy 3.308096 -1.459992)
			)
			(stroke
				(width 0)
				(type default)
			)
			(fill yes)
			(layer "F.SilkS")
		)
		(fp_line
			(start -2.29997 1.459992)
			(end -2.29997 -1.459992)
			(stroke
				(width 0.1)
				(type default)
			)
			(layer "F.Fab")
		)
		(fp_line
			(start 2.29997 1.459992)
			(end -2.29997 1.459992)
			(stroke
				(width 0.1)
				(type default)
			)
			(layer "F.Fab")
		)
		(fp_line
			(start -2.29997 -1.459992)
			(end 2.29997 -1.459992)
			(stroke
				(width 0.1)
				(type default)
			)
			(layer "F.Fab")
		)
		(fp_line
			(start 2.29997 -1.459992)
			(end 2.29997 1.459992)
			(stroke
				(width 0.1)
				(type default)
			)
			(layer "F.Fab")
		)
		(fp_text user "-"
			(at 5.4102 0.29845 90)
			(unlocked yes)
			(layer "F.SilkS")
			(effects
				(font
					(size 1.905 1.4224)
					(thickness 0.1524)
				)
				(justify left)
			)
		)
		(fp_text user "+"
			(at -5.202682 -0.188722 270)
			(unlocked yes)
			(layer "F.SilkS")
			(effects
				(font
					(size 1.905 1.4224)
					(thickness 0.1524)
				)
				(justify left)
			)
		)
		(fp_text user "-"
			(at 5.4102 0.29845 90)
			(unlocked yes)
			(layer "F.Fab")
			(effects
				(font
					(size 1.905 1.4224)
					(thickness 0.1524)
				)
				(justify left)
			)
		)
		(fp_text user "+"
			(at -4.7752 -0.12065 270)
			(unlocked yes)
			(layer "F.Fab")
			(effects
				(font
					(size 1.905 1.4224)
					(thickness 0.1524)
				)
				(justify left)
			)
		)
		(pad "A" smd rect
			(at -1.999996 0)
			(size 1.7018 2.5146)
			(layers "F.Cu" "F.Mask" "F.Paste")
			(net "GND")
		)
		(pad "C" smd rect
			(at 1.999996 0)
			(size 1.7018 2.5146)
			(layers "F.Cu" "F.Mask" "F.Paste")
			(net "P12V_SSD7_R")
		)
	)
	(footprint ""
		(layer "F.Cu")
		(at 350.64192 -27.006296 -90)
		(property "Reference" "PR7124"
			(at 0 0 270)
			(layer "F.SilkS")
			(hide yes)
			(effects
				(font
					(size 1.27 1.27)
				)
			)
		)
		(property "Value" ""
			(at 0 0 270)
			(layer "F.Fab")
			(effects
				(font
					(size 1.27 1.27)
				)
			)
		)
		(duplicate_pad_numbers_are_jumpers no)
		(fp_line
			(start -0.7874 0.4064)
			(end -0.7874 -0.4064)
			(stroke
				(width 0.1524)
				(type default)
			)
			(layer "F.SilkS")
		)
		(fp_line
			(start 0.7874 0.4064)
			(end -0.7874 0.4064)
			(stroke
				(width 0.1524)
				(type default)
			)
			(layer "F.SilkS")
		)
		(fp_line
			(start -0.7874 -0.4064)
			(end 0.7874 -0.4064)
			(stroke
				(width 0.1524)
				(type default)
			)
			(layer "F.SilkS")
		)
		(fp_line
			(start 0.7874 -0.4064)
			(end 0.7874 0.4064)
			(stroke
				(width 0.1524)
				(type default)
			)
			(layer "F.SilkS")
		)
		(fp_line
			(start -0.67945 0.3048)
			(end -0.67945 -0.305054)
			(stroke
				(width 0.1)
				(type default)
			)
			(layer "F.Fab")
		)
		(fp_line
			(start -0.12065 0.3048)
			(end -0.67945 0.3048)
			(stroke
				(width 0.1)
				(type default)
			)
			(layer "F.Fab")
		)
		(fp_line
			(start 0.120396 0.3048)
			(end 0.120396 0.2794)
			(stroke
				(width 0.1)
				(type default)
			)
			(layer "F.Fab")
		)
		(fp_line
			(start 0.67945 0.3048)
			(end 0.120396 0.3048)
			(stroke
				(width 0.1)
				(type default)
			)
			(layer "F.Fab")
		)
		(fp_line
			(start -0.12065 0.2794)
			(end -0.12065 0.3048)
			(stroke
				(width 0.1)
				(type default)
			)
			(layer "F.Fab")
		)
		(fp_line
			(start 0.120396 0.2794)
			(end -0.12065 0.2794)
			(stroke
				(width 0.1)
				(type default)
			)
			(layer "F.Fab")
		)
		(fp_line
			(start -0.12065 -0.2794)
			(end 0.12065 -0.2794)
			(stroke
				(width 0.1)
				(type default)
			)
			(layer "F.Fab")
		)
		(fp_line
			(start 0.12065 -0.2794)
			(end 0.12065 -0.3048)
			(stroke
				(width 0.1)
				(type default)
			)
			(layer "F.Fab")
		)
		(fp_line
			(start 0.12065 -0.3048)
			(end 0.67945 -0.3048)
			(stroke
				(width 0.1)
				(type default)
			)
			(layer "F.Fab")
		)
		(fp_line
			(start 0.67945 -0.3048)
			(end 0.67945 0.3048)
			(stroke
				(width 0.1)
				(type default)
			)
			(layer "F.Fab")
		)
		(fp_line
			(start -0.67945 -0.305054)
			(end -0.12065 -0.305054)
			(stroke
				(width 0.1)
				(type default)
			)
			(layer "F.Fab")
		)
		(fp_line
			(start -0.12065 -0.305054)
			(end -0.12065 -0.2794)
			(stroke
				(width 0.1)
				(type default)
			)
			(layer "F.Fab")
		)
		(pad "1" smd circle
			(at -0.40005 0 270)
			(size 0 0)
			(layers "F.Cu" "F.Mask" "F.Paste")
			(net "P3V3_SSD12_CO_ILIMIT")
		)
		(pad "2" smd circle
			(at 0.40005 0 270)
			(size 0 0)
			(layers "F.Cu" "F.Mask" "F.Paste")
			(net "GND")
		)
	)
	(footprint ""
		(layer "F.Cu")
		(at 336.443574 -46.90491)
		(property "Reference" "R629"
			(at 0 0 0)
			(layer "F.SilkS")
			(hide yes)
			(effects
				(font
					(size 1.27 1.27)
				)
			)
		)
		(property "Value" ""
			(at 0 0 0)
			(layer "F.Fab")
			(effects
				(font
					(size 1.27 1.27)
				)
			)
		)
		(duplicate_pad_numbers_are_jumpers no)
		(fp_line
			(start -0.7874 -0.4064)
			(end 0.7874 -0.4064)
			(stroke
				(width 0.1524)
				(type default)
			)
			(layer "F.SilkS")
		)
		(fp_line
			(start -0.7874 0.4064)
			(end -0.7874 -0.4064)
			(stroke
				(width 0.1524)
				(type default)
			)
			(layer "F.SilkS")
		)
		(fp_line
			(start 0.7874 -0.4064)
			(end 0.7874 0.4064)
			(stroke
				(width 0.1524)
				(type default)
			)
			(layer "F.SilkS")
		)
		(fp_line
			(start 0.7874 0.4064)
			(end -0.7874 0.4064)
			(stroke
				(width 0.1524)
				(type default)
			)
			(layer "F.SilkS")
		)
		(fp_line
			(start -0.67945 -0.305054)
			(end -0.12065 -0.305054)
			(stroke
				(width 0.1)
				(type default)
			)
			(layer "F.Fab")
		)
		(fp_line
			(start -0.67945 0.3048)
			(end -0.67945 -0.305054)
			(stroke
				(width 0.1)
				(type default)
			)
			(layer "F.Fab")
		)
		(fp_line
			(start -0.12065 -0.305054)
			(end -0.12065 -0.2794)
			(stroke
				(width 0.1)
				(type default)
			)
			(layer "F.Fab")
		)
		(fp_line
			(start -0.12065 -0.2794)
			(end 0.12065 -0.2794)
			(stroke
				(width 0.1)
				(type default)
			)
			(layer "F.Fab")
		)
		(fp_line
			(start -0.12065 0.2794)
			(end -0.12065 0.3048)
			(stroke
				(width 0.1)
				(type default)
			)
			(layer "F.Fab")
		)
		(fp_line
			(start -0.12065 0.3048)
			(end -0.67945 0.3048)
			(stroke
				(width 0.1)
				(type default)
			)
			(layer "F.Fab")
		)
		(fp_line
			(start 0.120396 0.2794)
			(end -0.12065 0.2794)
			(stroke
				(width 0.1)
				(type default)
			)
			(layer "F.Fab")
		)
		(fp_line
			(start 0.120396 0.3048)
			(end 0.120396 0.2794)
			(stroke
				(width 0.1)
				(type default)
			)
			(layer "F.Fab")
		)
		(fp_line
			(start 0.12065 -0.3048)
			(end 0.67945 -0.3048)
			(stroke
				(width 0.1)
				(type default)
			)
			(layer "F.Fab")
		)
		(fp_line
			(start 0.12065 -0.2794)
			(end 0.12065 -0.3048)
			(stroke
				(width 0.1)
				(type default)
			)
			(layer "F.Fab")
		)
		(fp_line
			(start 0.67945 -0.3048)
			(end 0.67945 0.3048)
			(stroke
				(width 0.1)
				(type default)
			)
			(layer "F.Fab")
		)
		(fp_line
			(start 0.67945 0.3048)
			(end 0.120396 0.3048)
			(stroke
				(width 0.1)
				(type default)
			)
			(layer "F.Fab")
		)
		(pad "1" smd circle
			(at -0.40005 0)
			(size 0 0)
			(layers "F.Cu" "F.Mask" "F.Paste")
			(net "SSD11_ADC_ALERT_N")
		)
		(pad "2" smd circle
			(at 0.40005 0)
			(size 0 0)
			(layers "F.Cu" "F.Mask" "F.Paste")
			(net "SSD_8_15_ADC_ALERT_N")
		)
	)
	(footprint ""
		(layer "F.Cu")
		(at 178.619912 -356.244906 90)
		(property "Reference" "C2529"
			(at 0 0 90)
			(layer "F.SilkS")
			(hide yes)
			(effects
				(font
					(size 1.27 1.27)
				)
			)
		)
		(property "Value" ""
			(at 0 0 90)
			(layer "F.Fab")
			(effects
				(font
					(size 1.27 1.27)
				)
			)
		)
		(duplicate_pad_numbers_are_jumpers no)
		(fp_line
			(start 0.299974 -0.150114)
			(end 0.299974 0.150114)
			(stroke
				(width 0.1)
				(type default)
			)
			(layer "F.Fab")
		)
		(fp_line
			(start -0.299974 -0.150114)
			(end 0.299974 -0.150114)
			(stroke
				(width 0.1)
				(type default)
			)
			(layer "F.Fab")
		)
		(fp_line
			(start 0.299974 0.150114)
			(end -0.299974 0.150114)
			(stroke
				(width 0.1)
				(type default)
			)
			(layer "F.Fab")
		)
		(fp_line
			(start -0.299974 0.150114)
			(end -0.299974 -0.150114)
			(stroke
				(width 0.1)
				(type default)
			)
			(layer "F.Fab")
		)
		(pad "1" smd rect
			(at -0.2667 0 90)
			(size 0.3048 0.381)
			(layers "F.Cu" "F.Mask" "F.Paste")
			(net "P5E_PEX1_STN4_TX_DN<71>")
		)
		(pad "2" smd rect
			(at 0.2667 0 90)
			(size 0.3048 0.381)
			(layers "F.Cu" "F.Mask" "F.Paste")
			(net "P5E_PEX1_STN4_TX_C_DN<71>")
		)
	)
	(footprint ""
		(layer "F.Cu")
		(at 210.16214 -371.465094)
		(property "Reference" "PC1"
			(at 0 0 0)
			(layer "F.SilkS")
			(hide yes)
			(effects
				(font
					(size 1.27 1.27)
				)
			)
		)
		(property "Value" ""
			(at 0 0 0)
			(layer "F.Fab")
			(effects
				(font
					(size 1.27 1.27)
				)
			)
		)
		(duplicate_pad_numbers_are_jumpers no)
		(fp_line
			(start -0.7874 -0.4064)
			(end 0.7874 -0.4064)
			(stroke
				(width 0.1524)
				(type default)
			)
			(layer "F.SilkS")
		)
		(fp_line
			(start -0.7874 0.4064)
			(end -0.7874 -0.4064)
			(stroke
				(width 0.1524)
				(type default)
			)
			(layer "F.SilkS")
		)
		(fp_line
			(start 0.7874 -0.4064)
			(end 0.7874 0.4064)
			(stroke
				(width 0.1524)
				(type default)
			)
			(layer "F.SilkS")
		)
		(fp_line
			(start 0.7874 0.4064)
			(end -0.7874 0.4064)
			(stroke
				(width 0.1524)
				(type default)
			)
			(layer "F.SilkS")
		)
		(fp_line
			(start -0.67945 -0.305054)
			(end -0.12065 -0.305054)
			(stroke
				(width 0.1)
				(type default)
			)
			(layer "F.Fab")
		)
		(fp_line
			(start -0.67945 0.3048)
			(end -0.67945 -0.305054)
			(stroke
				(width 0.1)
				(type default)
			)
			(layer "F.Fab")
		)
		(fp_line
			(start -0.12065 -0.305054)
			(end -0.12065 -0.2794)
			(stroke
				(width 0.1)
				(type default)
			)
			(layer "F.Fab")
		)
		(fp_line
			(start -0.12065 -0.2794)
			(end 0.12065 -0.2794)
			(stroke
				(width 0.1)
				(type default)
			)
			(layer "F.Fab")
		)
		(fp_line
			(start -0.12065 0.2794)
			(end -0.12065 0.3048)
			(stroke
				(width 0.1)
				(type default)
			)
			(layer "F.Fab")
		)
		(fp_line
			(start -0.12065 0.3048)
			(end -0.67945 0.3048)
			(stroke
				(width 0.1)
				(type default)
			)
			(layer "F.Fab")
		)
		(fp_line
			(start 0.120396 0.2794)
			(end -0.12065 0.2794)
			(stroke
				(width 0.1)
				(type default)
			)
			(layer "F.Fab")
		)
		(fp_line
			(start 0.120396 0.3048)
			(end 0.120396 0.2794)
			(stroke
				(width 0.1)
				(type default)
			)
			(layer "F.Fab")
		)
		(fp_line
			(start 0.12065 -0.3048)
			(end 0.67945 -0.3048)
			(stroke
				(width 0.1)
				(type default)
			)
			(layer "F.Fab")
		)
		(fp_line
			(start 0.12065 -0.2794)
			(end 0.12065 -0.3048)
			(stroke
				(width 0.1)
				(type default)
			)
			(layer "F.Fab")
		)
		(fp_line
			(start 0.67945 -0.3048)
			(end 0.67945 0.3048)
			(stroke
				(width 0.1)
				(type default)
			)
			(layer "F.Fab")
		)
		(fp_line
			(start 0.67945 0.3048)
			(end 0.120396 0.3048)
			(stroke
				(width 0.1)
				(type default)
			)
			(layer "F.Fab")
		)
		(pad "1" smd circle
			(at -0.40005 0)
			(size 0 0)
			(layers "F.Cu" "F.Mask" "F.Paste")
			(net "P12V_STBY")
		)
		(pad "2" smd circle
			(at 0.40005 0)
			(size 0 0)
			(layers "F.Cu" "F.Mask" "F.Paste")
			(net "GND")
		)
	)
	(footprint ""
		(layer "F.Cu")
		(at 271.895062 -350.098614 90)
		(property "Reference" "C2344"
			(at 0 0 90)
			(layer "F.SilkS")
			(hide yes)
			(effects
				(font
					(size 1.27 1.27)
				)
			)
		)
		(property "Value" ""
			(at 0 0 90)
			(layer "F.Fab")
			(effects
				(font
					(size 1.27 1.27)
				)
			)
		)
		(duplicate_pad_numbers_are_jumpers no)
		(fp_line
			(start 0.299974 -0.150114)
			(end 0.299974 0.150114)
			(stroke
				(width 0.1)
				(type default)
			)
			(layer "F.Fab")
		)
		(fp_line
			(start -0.299974 -0.150114)
			(end 0.299974 -0.150114)
			(stroke
				(width 0.1)
				(type default)
			)
			(layer "F.Fab")
		)
		(fp_line
			(start 0.299974 0.150114)
			(end -0.299974 0.150114)
			(stroke
				(width 0.1)
				(type default)
			)
			(layer "F.Fab")
		)
		(fp_line
			(start -0.299974 0.150114)
			(end -0.299974 -0.150114)
			(stroke
				(width 0.1)
				(type default)
			)
			(layer "F.Fab")
		)
		(pad "1" smd rect
			(at -0.2667 0 90)
			(size 0.3048 0.381)
			(layers "F.Cu" "F.Mask" "F.Paste")
			(net "P5E_PEX2_STN4_TX_DN<78>")
		)
		(pad "2" smd rect
			(at 0.2667 0 90)
			(size 0.3048 0.381)
			(layers "F.Cu" "F.Mask" "F.Paste")
			(net "P5E_PEX2_STN4_TX_C_DN<78>")
		)
	)
	(footprint ""
		(layer "F.Cu")
		(at 96.499426 -112.903508 90)
		(property "Reference" "PC605"
			(at 0 0 90)
			(layer "F.SilkS")
			(hide yes)
			(effects
				(font
					(size 1.27 1.27)
				)
			)
		)
		(property "Value" ""
			(at 0 0 90)
			(layer "F.Fab")
			(effects
				(font
					(size 1.27 1.27)
				)
			)
		)
		(duplicate_pad_numbers_are_jumpers no)
		(fp_line
			(start 1.524 -0.762)
			(end 1.524 0.762)
			(stroke
				(width 0.1524)
				(type default)
			)
			(layer "F.SilkS")
		)
		(fp_line
			(start -1.524 -0.762)
			(end 1.524 -0.762)
			(stroke
				(width 0.1524)
				(type default)
			)
			(layer "F.SilkS")
		)
		(fp_line
			(start 1.524 0.762)
			(end -1.524 0.762)
			(stroke
				(width 0.1524)
				(type default)
			)
			(layer "F.SilkS")
		)
		(fp_line
			(start -1.524 0.762)
			(end -1.524 -0.762)
			(stroke
				(width 0.1524)
				(type default)
			)
			(layer "F.SilkS")
		)
		(fp_line
			(start 1.1049 -0.724916)
			(end -1.1049 -0.724916)
			(stroke
				(width 0.1)
				(type default)
			)
			(layer "F.Fab")
		)
		(fp_line
			(start -1.1049 -0.724916)
			(end -1.1049 0.724916)
			(stroke
				(width 0.1)
				(type default)
			)
			(layer "F.Fab")
		)
		(fp_line
			(start 1.1049 0.724916)
			(end 1.1049 -0.724916)
			(stroke
				(width 0.1)
				(type default)
			)
			(layer "F.Fab")
		)
		(fp_line
			(start -1.1049 0.724916)
			(end 1.1049 0.724916)
			(stroke
				(width 0.1)
				(type default)
			)
			(layer "F.Fab")
		)
		(pad "1" smd rect
			(at -0.889 0 270)
			(size 1.016 1.27)
			(layers "F.Cu" "F.Mask" "F.Paste")
			(net "P12V_NIC1_R")
		)
		(pad "2" smd rect
			(at 0.889 0 270)
			(size 1.016 1.27)
			(layers "F.Cu" "F.Mask" "F.Paste")
			(net "GND")
		)
	)
	(footprint ""
		(layer "F.Cu")
		(at 394.74648 -58.323734)
		(property "Reference" "PC437"
			(at 0 0 0)
			(layer "F.SilkS")
			(hide yes)
			(effects
				(font
					(size 1.27 1.27)
				)
			)
		)
		(property "Value" ""
			(at 0 0 0)
			(layer "F.Fab")
			(effects
				(font
					(size 1.27 1.27)
				)
			)
		)
		(duplicate_pad_numbers_are_jumpers no)
		(fp_line
			(start -1.524 -0.762)
			(end 1.524 -0.762)
			(stroke
				(width 0.1524)
				(type default)
			)
			(layer "F.SilkS")
		)
		(fp_line
			(start -1.524 0.762)
			(end -1.524 -0.762)
			(stroke
				(width 0.1524)
				(type default)
			)
			(layer "F.SilkS")
		)
		(fp_line
			(start 1.524 -0.762)
			(end 1.524 0.762)
			(stroke
				(width 0.1524)
				(type default)
			)
			(layer "F.SilkS")
		)
		(fp_line
			(start 1.524 0.762)
			(end -1.524 0.762)
			(stroke
				(width 0.1524)
				(type default)
			)
			(layer "F.SilkS")
		)
		(fp_line
			(start -1.1049 -0.724916)
			(end -1.1049 0.724916)
			(stroke
				(width 0.1)
				(type default)
			)
			(layer "F.Fab")
		)
		(fp_line
			(start -1.1049 0.724916)
			(end 1.1049 0.724916)
			(stroke
				(width 0.1)
				(type default)
			)
			(layer "F.Fab")
		)
		(fp_line
			(start 1.1049 -0.724916)
			(end -1.1049 -0.724916)
			(stroke
				(width 0.1)
				(type default)
			)
			(layer "F.Fab")
		)
		(fp_line
			(start 1.1049 0.724916)
			(end 1.1049 -0.724916)
			(stroke
				(width 0.1)
				(type default)
			)
			(layer "F.Fab")
		)
		(pad "1" smd rect
			(at -0.889 0 180)
			(size 1.016 1.27)
			(layers "F.Cu" "F.Mask" "F.Paste")
			(net "GND")
		)
		(pad "2" smd rect
			(at 0.889 0 180)
			(size 1.016 1.27)
			(layers "F.Cu" "F.Mask" "F.Paste")
			(net "P12V_AUX")
		)
	)
	(footprint ""
		(layer "F.Cu")
		(at 128.295908 -356.244906 90)
		(property "Reference" "C2274"
			(at 0 0 90)
			(layer "F.SilkS")
			(hide yes)
			(effects
				(font
					(size 1.27 1.27)
				)
			)
		)
		(property "Value" ""
			(at 0 0 90)
			(layer "F.Fab")
			(effects
				(font
					(size 1.27 1.27)
				)
			)
		)
		(duplicate_pad_numbers_are_jumpers no)
		(fp_line
			(start 0.299974 -0.150114)
			(end 0.299974 0.150114)
			(stroke
				(width 0.1)
				(type default)
			)
			(layer "F.Fab")
		)
		(fp_line
			(start -0.299974 -0.150114)
			(end 0.299974 -0.150114)
			(stroke
				(width 0.1)
				(type default)
			)
			(layer "F.Fab")
		)
		(fp_line
			(start 0.299974 0.150114)
			(end -0.299974 0.150114)
			(stroke
				(width 0.1)
				(type default)
			)
			(layer "F.Fab")
		)
		(fp_line
			(start -0.299974 0.150114)
			(end -0.299974 -0.150114)
			(stroke
				(width 0.1)
				(type default)
			)
			(layer "F.Fab")
		)
		(pad "1" smd rect
			(at -0.2667 0 90)
			(size 0.3048 0.381)
			(layers "F.Cu" "F.Mask" "F.Paste")
			(net "P5E_PEX1_STN5_TX_DN<80>")
		)
		(pad "2" smd rect
			(at 0.2667 0 90)
			(size 0.3048 0.381)
			(layers "F.Cu" "F.Mask" "F.Paste")
			(net "P5E_PEX1_STN5_TX_C_DN<80>")
		)
	)
	(footprint ""
		(layer "F.Cu")
		(at 211.892388 -29.139642 180)
		(property "Reference" "C306"
			(at 0 0 180)
			(layer "F.SilkS")
			(hide yes)
			(effects
				(font
					(size 1.27 1.27)
				)
			)
		)
		(property "Value" ""
			(at 0 0 180)
			(layer "F.Fab")
			(effects
				(font
					(size 1.27 1.27)
				)
			)
		)
		(duplicate_pad_numbers_are_jumpers no)
		(fp_line
			(start 0.299974 0.150114)
			(end -0.299974 0.150114)
			(stroke
				(width 0.1)
				(type default)
			)
			(layer "F.Fab")
		)
		(fp_line
			(start 0.299974 -0.150114)
			(end 0.299974 0.150114)
			(stroke
				(width 0.1)
				(type default)
			)
			(layer "F.Fab")
		)
		(fp_line
			(start -0.299974 0.150114)
			(end -0.299974 -0.150114)
			(stroke
				(width 0.1)
				(type default)
			)
			(layer "F.Fab")
		)
		(fp_line
			(start -0.299974 -0.150114)
			(end 0.299974 -0.150114)
			(stroke
				(width 0.1)
				(type default)
			)
			(layer "F.Fab")
		)
		(pad "1" smd rect
			(at -0.2667 0 180)
			(size 0.3048 0.381)
			(layers "F.Cu" "F.Mask" "F.Paste")
			(net "P5E_PEX1_STN2_TX_DP<32>")
		)
		(pad "2" smd rect
			(at 0.2667 0 180)
			(size 0.3048 0.381)
			(layers "F.Cu" "F.Mask" "F.Paste")
			(net "P5E_PEX1_STN2_TX_C_DP<32>")
		)
	)
	(footprint ""
		(layer "F.Cu")
		(at 262.581644 -77.279754 90)
		(property "Reference" "R1076"
			(at 0 0 90)
			(layer "F.SilkS")
			(hide yes)
			(effects
				(font
					(size 1.27 1.27)
				)
			)
		)
		(property "Value" ""
			(at 0 0 90)
			(layer "F.Fab")
			(effects
				(font
					(size 1.27 1.27)
				)
			)
		)
		(duplicate_pad_numbers_are_jumpers no)
		(fp_line
			(start -0.7874 -0.4064)
			(end 0.7874 -0.4064)
			(stroke
				(width 0.1524)
				(type default)
			)
			(layer "F.SilkS")
		)
		(fp_line
			(start -0.12065 -0.305054)
			(end -0.12065 -0.2794)
			(stroke
				(width 0.1)
				(type default)
			)
			(layer "F.Fab")
		)
		(fp_line
			(start -0.67945 -0.305054)
			(end -0.12065 -0.305054)
			(stroke
				(width 0.1)
				(type default)
			)
			(layer "F.Fab")
		)
		(fp_line
			(start 0.67945 -0.3048)
			(end 0.67945 0.3048)
			(stroke
				(width 0.1)
				(type default)
			)
			(layer "F.Fab")
		)
		(fp_line
			(start 0.12065 -0.3048)
			(end 0.67945 -0.3048)
			(stroke
				(width 0.1)
				(type default)
			)
			(layer "F.Fab")
		)
		(fp_line
			(start 0.12065 -0.2794)
			(end 0.12065 -0.3048)
			(stroke
				(width 0.1)
				(type default)
			)
			(layer "F.Fab")
		)
		(fp_line
			(start -0.12065 -0.2794)
			(end 0.12065 -0.2794)
			(stroke
				(width 0.1)
				(type default)
			)
			(layer "F.Fab")
		)
		(fp_line
			(start 0.120396 0.2794)
			(end -0.12065 0.2794)
			(stroke
				(width 0.1)
				(type default)
			)
			(layer "F.Fab")
		)
		(fp_line
			(start -0.12065 0.2794)
			(end -0.12065 0.3048)
			(stroke
				(width 0.1)
				(type default)
			)
			(layer "F.Fab")
		)
		(fp_line
			(start 0.67945 0.3048)
			(end 0.120396 0.3048)
			(stroke
				(width 0.1)
				(type default)
			)
			(layer "F.Fab")
		)
		(fp_line
			(start 0.120396 0.3048)
			(end 0.120396 0.2794)
			(stroke
				(width 0.1)
				(type default)
			)
			(layer "F.Fab")
		)
		(fp_line
			(start -0.12065 0.3048)
			(end -0.67945 0.3048)
			(stroke
				(width 0.1)
				(type default)
			)
			(layer "F.Fab")
		)
		(fp_line
			(start -0.67945 0.3048)
			(end -0.67945 -0.305054)
			(stroke
				(width 0.1)
				(type default)
			)
			(layer "F.Fab")
		)
		(pad "1" smd circle
			(at -0.40005 0 90)
			(size 0 0)
			(layers "F.Cu" "F.Mask" "F.Paste")
			(net "CLK_100M_CK440Q_2_DB800ZL_R_DN")
		)
		(pad "2" smd circle
			(at 0.40005 0 90)
			(size 0 0)
			(layers "F.Cu" "F.Mask" "F.Paste")
			(net "CLK_100M_CK440Q_2_DB800ZL_DN")
		)
	)
	(footprint ""
		(layer "F.Cu")
		(at 219.162376 -22.955504 -90)
		(property "Reference" "C2725"
			(at 0 0 270)
			(layer "F.SilkS")
			(hide yes)
			(effects
				(font
					(size 1.27 1.27)
				)
			)
		)
		(property "Value" ""
			(at 0 0 270)
			(layer "F.Fab")
			(effects
				(font
					(size 1.27 1.27)
				)
			)
		)
		(duplicate_pad_numbers_are_jumpers no)
		(fp_line
			(start -0.7874 0.4064)
			(end -0.7874 -0.4064)
			(stroke
				(width 0.1524)
				(type default)
			)
			(layer "F.SilkS")
		)
		(fp_line
			(start 0.7874 0.4064)
			(end -0.7874 0.4064)
			(stroke
				(width 0.1524)
				(type default)
			)
			(layer "F.SilkS")
		)
		(fp_line
			(start -0.7874 -0.4064)
			(end 0.7874 -0.4064)
			(stroke
				(width 0.1524)
				(type default)
			)
			(layer "F.SilkS")
		)
		(fp_line
			(start 0.7874 -0.4064)
			(end 0.7874 0.4064)
			(stroke
				(width 0.1524)
				(type default)
			)
			(layer "F.SilkS")
		)
		(fp_line
			(start -0.67945 0.3048)
			(end -0.67945 -0.305054)
			(stroke
				(width 0.1)
				(type default)
			)
			(layer "F.Fab")
		)
		(fp_line
			(start -0.12065 0.3048)
			(end -0.67945 0.3048)
			(stroke
				(width 0.1)
				(type default)
			)
			(layer "F.Fab")
		)
		(fp_line
			(start 0.120396 0.3048)
			(end 0.120396 0.2794)
			(stroke
				(width 0.1)
				(type default)
			)
			(layer "F.Fab")
		)
		(fp_line
			(start 0.67945 0.3048)
			(end 0.120396 0.3048)
			(stroke
				(width 0.1)
				(type default)
			)
			(layer "F.Fab")
		)
		(fp_line
			(start -0.12065 0.2794)
			(end -0.12065 0.3048)
			(stroke
				(width 0.1)
				(type default)
			)
			(layer "F.Fab")
		)
		(fp_line
			(start 0.120396 0.2794)
			(end -0.12065 0.2794)
			(stroke
				(width 0.1)
				(type default)
			)
			(layer "F.Fab")
		)
		(fp_line
			(start -0.12065 -0.2794)
			(end 0.12065 -0.2794)
			(stroke
				(width 0.1)
				(type default)
			)
			(layer "F.Fab")
		)
		(fp_line
			(start 0.12065 -0.2794)
			(end 0.12065 -0.3048)
			(stroke
				(width 0.1)
				(type default)
			)
			(layer "F.Fab")
		)
		(fp_line
			(start 0.12065 -0.3048)
			(end 0.67945 -0.3048)
			(stroke
				(width 0.1)
				(type default)
			)
			(layer "F.Fab")
		)
		(fp_line
			(start 0.67945 -0.3048)
			(end 0.67945 0.3048)
			(stroke
				(width 0.1)
				(type default)
			)
			(layer "F.Fab")
		)
		(fp_line
			(start -0.67945 -0.305054)
			(end -0.12065 -0.305054)
			(stroke
				(width 0.1)
				(type default)
			)
			(layer "F.Fab")
		)
		(fp_line
			(start -0.12065 -0.305054)
			(end -0.12065 -0.2794)
			(stroke
				(width 0.1)
				(type default)
			)
			(layer "F.Fab")
		)
		(pad "1" smd circle
			(at -0.40005 0 270)
			(size 0 0)
			(layers "F.Cu" "F.Mask" "F.Paste")
			(net "GND")
		)
		(pad "2" smd circle
			(at 0.40005 0 270)
			(size 0 0)
			(layers "F.Cu" "F.Mask" "F.Paste")
			(net "P3V3_AUX")
		)
	)
	(footprint ""
		(layer "F.Cu")
		(at 19.24685 -38.49116 180)
		(property "Reference" "R5877"
			(at 0 0 180)
			(layer "F.SilkS")
			(hide yes)
			(effects
				(font
					(size 1.27 1.27)
				)
			)
		)
		(property "Value" ""
			(at 0 0 180)
			(layer "F.Fab")
			(effects
				(font
					(size 1.27 1.27)
				)
			)
		)
		(duplicate_pad_numbers_are_jumpers no)
		(fp_line
			(start 0.7874 0.4064)
			(end -0.7874 0.4064)
			(stroke
				(width 0.1524)
				(type default)
			)
			(layer "F.SilkS")
		)
		(fp_line
			(start 0.7874 -0.4064)
			(end 0.7874 0.4064)
			(stroke
				(width 0.1524)
				(type default)
			)
			(layer "F.SilkS")
		)
		(fp_line
			(start -0.7874 0.4064)
			(end -0.7874 -0.4064)
			(stroke
				(width 0.1524)
				(type default)
			)
			(layer "F.SilkS")
		)
		(fp_line
			(start -0.7874 -0.4064)
			(end 0.7874 -0.4064)
			(stroke
				(width 0.1524)
				(type default)
			)
			(layer "F.SilkS")
		)
		(fp_line
			(start 0.67945 0.3048)
			(end 0.120396 0.3048)
			(stroke
				(width 0.1)
				(type default)
			)
			(layer "F.Fab")
		)
		(fp_line
			(start 0.67945 -0.3048)
			(end 0.67945 0.3048)
			(stroke
				(width 0.1)
				(type default)
			)
			(layer "F.Fab")
		)
		(fp_line
			(start 0.12065 -0.2794)
			(end 0.12065 -0.3048)
			(stroke
				(width 0.1)
				(type default)
			)
			(layer "F.Fab")
		)
		(fp_line
			(start 0.12065 -0.3048)
			(end 0.67945 -0.3048)
			(stroke
				(width 0.1)
				(type default)
			)
			(layer "F.Fab")
		)
		(fp_line
			(start 0.120396 0.3048)
			(end 0.120396 0.2794)
			(stroke
				(width 0.1)
				(type default)
			)
			(layer "F.Fab")
		)
		(fp_line
			(start 0.120396 0.2794)
			(end -0.12065 0.2794)
			(stroke
				(width 0.1)
				(type default)
			)
			(layer "F.Fab")
		)
		(fp_line
			(start -0.12065 0.3048)
			(end -0.67945 0.3048)
			(stroke
				(width 0.1)
				(type default)
			)
			(layer "F.Fab")
		)
		(fp_line
			(start -0.12065 0.2794)
			(end -0.12065 0.3048)
			(stroke
				(width 0.1)
				(type default)
			)
			(layer "F.Fab")
		)
		(fp_line
			(start -0.12065 -0.2794)
			(end 0.12065 -0.2794)
			(stroke
				(width 0.1)
				(type default)
			)
			(layer "F.Fab")
		)
		(fp_line
			(start -0.12065 -0.305054)
			(end -0.12065 -0.2794)
			(stroke
				(width 0.1)
				(type default)
			)
			(layer "F.Fab")
		)
		(fp_line
			(start -0.67945 0.3048)
			(end -0.67945 -0.305054)
			(stroke
				(width 0.1)
				(type default)
			)
			(layer "F.Fab")
		)
		(fp_line
			(start -0.67945 -0.305054)
			(end -0.12065 -0.305054)
			(stroke
				(width 0.1)
				(type default)
			)
			(layer "F.Fab")
		)
		(pad "1" smd circle
			(at -0.40005 0 180)
			(size 0 0)
			(layers "F.Cu" "F.Mask" "F.Paste")
			(net "P3V3_SSD1_PG_G1")
		)
		(pad "2" smd circle
			(at 0.40005 0 180)
			(size 0 0)
			(layers "F.Cu" "F.Mask" "F.Paste")
			(net "GND")
		)
	)
	(footprint ""
		(layer "F.Cu")
		(at 451.911466 -71.458074 -90)
		(property "Reference" "PD120"
			(at 4.148074 -2.800604 90)
			(unlocked yes)
			(layer "F.SilkS")
			(effects
				(font
					(size 0.7874 0.5842)
					(thickness 0.1524)
				)
				(justify left)
			)
		)
		(property "Value" ""
			(at 0 0 270)
			(layer "F.Fab")
			(effects
				(font
					(size 1.27 1.27)
				)
			)
		)
		(duplicate_pad_numbers_are_jumpers no)
		(fp_line
			(start -3.656584 1.970024)
			(end 4.240784 1.970024)
			(stroke
				(width 0.1524)
				(type default)
			)
			(layer "F.SilkS")
		)
		(fp_line
			(start 4.240784 1.970024)
			(end 4.240784 -1.970024)
			(stroke
				(width 0.1524)
				(type default)
			)
			(layer "F.SilkS")
		)
		(fp_line
			(start -3.656584 -1.970024)
			(end -3.656584 1.970024)
			(stroke
				(width 0.1524)
				(type default)
			)
			(layer "F.SilkS")
		)
		(fp_line
			(start 4.240784 -1.970024)
			(end -3.656584 -1.970024)
			(stroke
				(width 0.1524)
				(type default)
			)
			(layer "F.SilkS")
		)
		(fp_poly
			(pts
				(xy 3.580384 1.970024) (xy 3.580384 -1.970024) (xy 4.240784 -1.970024) (xy 4.240784 1.970024)
			)
			(stroke
				(width 0)
				(type default)
			)
			(fill yes)
			(layer "F.SilkS")
		)
		(fp_line
			(start -2.3749 1.970024)
			(end 2.3749 1.970024)
			(stroke
				(width 0.1)
				(type default)
			)
			(layer "F.Fab")
		)
		(fp_line
			(start 2.3749 1.970024)
			(end 2.3749 -1.970024)
			(stroke
				(width 0.1)
				(type default)
			)
			(layer "F.Fab")
		)
		(fp_line
			(start -2.3749 -1.970024)
			(end -2.3749 1.970024)
			(stroke
				(width 0.1)
				(type default)
			)
			(layer "F.Fab")
		)
		(fp_line
			(start 2.3749 -1.970024)
			(end -2.3749 -1.970024)
			(stroke
				(width 0.1)
				(type default)
			)
			(layer "F.Fab")
		)
		(fp_text user "+"
			(at -4.9784 -0.23495 270)
			(unlocked yes)
			(layer "F.Fab")
			(effects
				(font
					(size 1.905 1.4224)
					(thickness 0.1524)
				)
				(justify left)
			)
		)
		(fp_text user "-"
			(at 4.1656 -0.23495 270)
			(unlocked yes)
			(layer "F.Fab")
			(effects
				(font
					(size 1.905 1.4224)
					(thickness 0.1524)
				)
				(justify left)
			)
		)
		(pad "A" smd rect
			(at -2.450084 0 270)
			(size 2.159 2.2606)
			(layers "F.Cu" "F.Mask" "F.Paste")
			(net "GND")
		)
		(pad "C" smd rect
			(at 2.450084 0 270)
			(size 2.159 2.2606)
			(layers "F.Cu" "F.Mask" "F.Paste")
			(net "P12V_AUX")
		)
	)
	(footprint ""
		(layer "F.Cu")
		(at 175.203358 -59.571636 90)
		(property "Reference" "PR266"
			(at 0 0 90)
			(layer "F.SilkS")
			(hide yes)
			(effects
				(font
					(size 1.27 1.27)
				)
			)
		)
		(property "Value" ""
			(at 0 0 90)
			(layer "F.Fab")
			(effects
				(font
					(size 1.27 1.27)
				)
			)
		)
		(duplicate_pad_numbers_are_jumpers no)
		(fp_line
			(start 0.7874 -0.4064)
			(end 0.7874 0.4064)
			(stroke
				(width 0.1524)
				(type default)
			)
			(layer "F.SilkS")
		)
		(fp_line
			(start -0.7874 -0.4064)
			(end 0.7874 -0.4064)
			(stroke
				(width 0.1524)
				(type default)
			)
			(layer "F.SilkS")
		)
		(fp_line
			(start 0.7874 0.4064)
			(end -0.7874 0.4064)
			(stroke
				(width 0.1524)
				(type default)
			)
			(layer "F.SilkS")
		)
		(fp_line
			(start -0.7874 0.4064)
			(end -0.7874 -0.4064)
			(stroke
				(width 0.1524)
				(type default)
			)
			(layer "F.SilkS")
		)
		(fp_line
			(start -0.12065 -0.305054)
			(end -0.12065 -0.2794)
			(stroke
				(width 0.1)
				(type default)
			)
			(layer "F.Fab")
		)
		(fp_line
			(start -0.67945 -0.305054)
			(end -0.12065 -0.305054)
			(stroke
				(width 0.1)
				(type default)
			)
			(layer "F.Fab")
		)
		(fp_line
			(start 0.67945 -0.3048)
			(end 0.67945 0.3048)
			(stroke
				(width 0.1)
				(type default)
			)
			(layer "F.Fab")
		)
		(fp_line
			(start 0.12065 -0.3048)
			(end 0.67945 -0.3048)
			(stroke
				(width 0.1)
				(type default)
			)
			(layer "F.Fab")
		)
		(fp_line
			(start 0.12065 -0.2794)
			(end 0.12065 -0.3048)
			(stroke
				(width 0.1)
				(type default)
			)
			(layer "F.Fab")
		)
		(fp_line
			(start -0.12065 -0.2794)
			(end 0.12065 -0.2794)
			(stroke
				(width 0.1)
				(type default)
			)
			(layer "F.Fab")
		)
		(fp_line
			(start 0.120396 0.2794)
			(end -0.12065 0.2794)
			(stroke
				(width 0.1)
				(type default)
			)
			(layer "F.Fab")
		)
		(fp_line
			(start -0.12065 0.2794)
			(end -0.12065 0.3048)
			(stroke
				(width 0.1)
				(type default)
			)
			(layer "F.Fab")
		)
		(fp_line
			(start 0.67945 0.3048)
			(end 0.120396 0.3048)
			(stroke
				(width 0.1)
				(type default)
			)
			(layer "F.Fab")
		)
		(fp_line
			(start 0.120396 0.3048)
			(end 0.120396 0.2794)
			(stroke
				(width 0.1)
				(type default)
			)
			(layer "F.Fab")
		)
		(fp_line
			(start -0.12065 0.3048)
			(end -0.67945 0.3048)
			(stroke
				(width 0.1)
				(type default)
			)
			(layer "F.Fab")
		)
		(fp_line
			(start -0.67945 0.3048)
			(end -0.67945 -0.305054)
			(stroke
				(width 0.1)
				(type default)
			)
			(layer "F.Fab")
		)
		(pad "1" smd circle
			(at -0.40005 0 90)
			(size 0 0)
			(layers "F.Cu" "F.Mask" "F.Paste")
			(net "P3V3_SSD6_OCP")
		)
		(pad "2" smd circle
			(at 0.40005 0 90)
			(size 0 0)
			(layers "F.Cu" "F.Mask" "F.Paste")
			(net "GND")
		)
	)
	(footprint ""
		(layer "F.Cu")
		(at 392.139932 -70.52437 90)
		(property "Reference" "PC886"
			(at 0 0 90)
			(layer "F.SilkS")
			(hide yes)
			(effects
				(font
					(size 1.27 1.27)
				)
			)
		)
		(property "Value" ""
			(at 0 0 90)
			(layer "F.Fab")
			(effects
				(font
					(size 1.27 1.27)
				)
			)
		)
		(duplicate_pad_numbers_are_jumpers no)
		(fp_line
			(start 1.524 -0.762)
			(end 1.524 0.762)
			(stroke
				(width 0.1524)
				(type default)
			)
			(layer "F.SilkS")
		)
		(fp_line
			(start -1.524 -0.762)
			(end 1.524 -0.762)
			(stroke
				(width 0.1524)
				(type default)
			)
			(layer "F.SilkS")
		)
		(fp_line
			(start 1.524 0.762)
			(end -1.524 0.762)
			(stroke
				(width 0.1524)
				(type default)
			)
			(layer "F.SilkS")
		)
		(fp_line
			(start -1.524 0.762)
			(end -1.524 -0.762)
			(stroke
				(width 0.1524)
				(type default)
			)
			(layer "F.SilkS")
		)
		(fp_line
			(start 1.1049 -0.724916)
			(end -1.1049 -0.724916)
			(stroke
				(width 0.1)
				(type default)
			)
			(layer "F.Fab")
		)
		(fp_line
			(start -1.1049 -0.724916)
			(end -1.1049 0.724916)
			(stroke
				(width 0.1)
				(type default)
			)
			(layer "F.Fab")
		)
		(fp_line
			(start 1.1049 0.724916)
			(end 1.1049 -0.724916)
			(stroke
				(width 0.1)
				(type default)
			)
			(layer "F.Fab")
		)
		(fp_line
			(start -1.1049 0.724916)
			(end 1.1049 0.724916)
			(stroke
				(width 0.1)
				(type default)
			)
			(layer "F.Fab")
		)
		(pad "1" smd rect
			(at -0.889 0 270)
			(size 1.016 1.27)
			(layers "F.Cu" "F.Mask" "F.Paste")
			(net "P12V_SSD13_R")
		)
		(pad "2" smd rect
			(at 0.889 0 270)
			(size 1.016 1.27)
			(layers "F.Cu" "F.Mask" "F.Paste")
			(net "GND")
		)
	)
	(footprint ""
		(layer "F.Cu")
		(at 344.511884 -108.737654 180)
		(property "Reference" "C844"
			(at 0 0 180)
			(layer "F.SilkS")
			(hide yes)
			(effects
				(font
					(size 1.27 1.27)
				)
			)
		)
		(property "Value" ""
			(at 0 0 180)
			(layer "F.Fab")
			(effects
				(font
					(size 1.27 1.27)
				)
			)
		)
		(duplicate_pad_numbers_are_jumpers no)
		(fp_line
			(start 0.7874 0.4064)
			(end -0.7874 0.4064)
			(stroke
				(width 0.1524)
				(type default)
			)
			(layer "F.SilkS")
		)
		(fp_line
			(start 0.7874 -0.4064)
			(end 0.7874 0.4064)
			(stroke
				(width 0.1524)
				(type default)
			)
			(layer "F.SilkS")
		)
		(fp_line
			(start -0.7874 0.4064)
			(end -0.7874 -0.4064)
			(stroke
				(width 0.1524)
				(type default)
			)
			(layer "F.SilkS")
		)
		(fp_line
			(start -0.7874 -0.4064)
			(end 0.7874 -0.4064)
			(stroke
				(width 0.1524)
				(type default)
			)
			(layer "F.SilkS")
		)
		(fp_line
			(start 0.67945 0.3048)
			(end 0.120396 0.3048)
			(stroke
				(width 0.1)
				(type default)
			)
			(layer "F.Fab")
		)
		(fp_line
			(start 0.67945 -0.3048)
			(end 0.67945 0.3048)
			(stroke
				(width 0.1)
				(type default)
			)
			(layer "F.Fab")
		)
		(fp_line
			(start 0.12065 -0.2794)
			(end 0.12065 -0.3048)
			(stroke
				(width 0.1)
				(type default)
			)
			(layer "F.Fab")
		)
		(fp_line
			(start 0.12065 -0.3048)
			(end 0.67945 -0.3048)
			(stroke
				(width 0.1)
				(type default)
			)
			(layer "F.Fab")
		)
		(fp_line
			(start 0.120396 0.3048)
			(end 0.120396 0.2794)
			(stroke
				(width 0.1)
				(type default)
			)
			(layer "F.Fab")
		)
		(fp_line
			(start 0.120396 0.2794)
			(end -0.12065 0.2794)
			(stroke
				(width 0.1)
				(type default)
			)
			(layer "F.Fab")
		)
		(fp_line
			(start -0.12065 0.3048)
			(end -0.67945 0.3048)
			(stroke
				(width 0.1)
				(type default)
			)
			(layer "F.Fab")
		)
		(fp_line
			(start -0.12065 0.2794)
			(end -0.12065 0.3048)
			(stroke
				(width 0.1)
				(type default)
			)
			(layer "F.Fab")
		)
		(fp_line
			(start -0.12065 -0.2794)
			(end 0.12065 -0.2794)
			(stroke
				(width 0.1)
				(type default)
			)
			(layer "F.Fab")
		)
		(fp_line
			(start -0.12065 -0.305054)
			(end -0.12065 -0.2794)
			(stroke
				(width 0.1)
				(type default)
			)
			(layer "F.Fab")
		)
		(fp_line
			(start -0.67945 0.3048)
			(end -0.67945 -0.305054)
			(stroke
				(width 0.1)
				(type default)
			)
			(layer "F.Fab")
		)
		(fp_line
			(start -0.67945 -0.305054)
			(end -0.12065 -0.305054)
			(stroke
				(width 0.1)
				(type default)
			)
			(layer "F.Fab")
		)
		(pad "1" smd circle
			(at -0.40005 0 180)
			(size 0 0)
			(layers "F.Cu" "F.Mask" "F.Paste")
			(net "GND")
		)
		(pad "2" smd circle
			(at 0.40005 0 180)
			(size 0 0)
			(layers "F.Cu" "F.Mask" "F.Paste")
			(net "P12V_NIC5_CO_EN")
		)
	)
	(footprint ""
		(layer "F.Cu")
		(at 258.806188 -204.29601 -90)
		(property "Reference" "R2537"
			(at 0 0 270)
			(layer "F.SilkS")
			(hide yes)
			(effects
				(font
					(size 1.27 1.27)
				)
			)
		)
		(property "Value" ""
			(at 0 0 270)
			(layer "F.Fab")
			(effects
				(font
					(size 1.27 1.27)
				)
			)
		)
		(duplicate_pad_numbers_are_jumpers no)
		(fp_line
			(start -0.7874 0.4064)
			(end -0.7874 -0.4064)
			(stroke
				(width 0.1524)
				(type default)
			)
			(layer "F.SilkS")
		)
		(fp_line
			(start 0.7874 0.4064)
			(end -0.7874 0.4064)
			(stroke
				(width 0.1524)
				(type default)
			)
			(layer "F.SilkS")
		)
		(fp_line
			(start -0.7874 -0.4064)
			(end 0.7874 -0.4064)
			(stroke
				(width 0.1524)
				(type default)
			)
			(layer "F.SilkS")
		)
		(fp_line
			(start 0.7874 -0.4064)
			(end 0.7874 0.4064)
			(stroke
				(width 0.1524)
				(type default)
			)
			(layer "F.SilkS")
		)
		(fp_line
			(start -0.67945 0.3048)
			(end -0.67945 -0.305054)
			(stroke
				(width 0.1)
				(type default)
			)
			(layer "F.Fab")
		)
		(fp_line
			(start -0.12065 0.3048)
			(end -0.67945 0.3048)
			(stroke
				(width 0.1)
				(type default)
			)
			(layer "F.Fab")
		)
		(fp_line
			(start 0.120396 0.3048)
			(end 0.120396 0.2794)
			(stroke
				(width 0.1)
				(type default)
			)
			(layer "F.Fab")
		)
		(fp_line
			(start 0.67945 0.3048)
			(end 0.120396 0.3048)
			(stroke
				(width 0.1)
				(type default)
			)
			(layer "F.Fab")
		)
		(fp_line
			(start -0.12065 0.2794)
			(end -0.12065 0.3048)
			(stroke
				(width 0.1)
				(type default)
			)
			(layer "F.Fab")
		)
		(fp_line
			(start 0.120396 0.2794)
			(end -0.12065 0.2794)
			(stroke
				(width 0.1)
				(type default)
			)
			(layer "F.Fab")
		)
		(fp_line
			(start -0.12065 -0.2794)
			(end 0.12065 -0.2794)
			(stroke
				(width 0.1)
				(type default)
			)
			(layer "F.Fab")
		)
		(fp_line
			(start 0.12065 -0.2794)
			(end 0.12065 -0.3048)
			(stroke
				(width 0.1)
				(type default)
			)
			(layer "F.Fab")
		)
		(fp_line
			(start 0.12065 -0.3048)
			(end 0.67945 -0.3048)
			(stroke
				(width 0.1)
				(type default)
			)
			(layer "F.Fab")
		)
		(fp_line
			(start 0.67945 -0.3048)
			(end 0.67945 0.3048)
			(stroke
				(width 0.1)
				(type default)
			)
			(layer "F.Fab")
		)
		(fp_line
			(start -0.67945 -0.305054)
			(end -0.12065 -0.305054)
			(stroke
				(width 0.1)
				(type default)
			)
			(layer "F.Fab")
		)
		(fp_line
			(start -0.12065 -0.305054)
			(end -0.12065 -0.2794)
			(stroke
				(width 0.1)
				(type default)
			)
			(layer "F.Fab")
		)
		(pad "1" smd circle
			(at -0.40005 0 270)
			(size 0 0)
			(layers "F.Cu" "F.Mask" "F.Paste")
			(net "JTAG_FPGA_TDI")
		)
		(pad "2" smd circle
			(at 0.40005 0 270)
			(size 0 0)
			(layers "F.Cu" "F.Mask" "F.Paste")
			(net "JTAG_CONN_TDI")
		)
	)
	(footprint ""
		(layer "F.Cu")
		(at 345.76131 -259.782564 180)
		(property "Reference" "PR141"
			(at 0 0 180)
			(layer "F.SilkS")
			(hide yes)
			(effects
				(font
					(size 1.27 1.27)
				)
			)
		)
		(property "Value" ""
			(at 0 0 180)
			(layer "F.Fab")
			(effects
				(font
					(size 1.27 1.27)
				)
			)
		)
		(duplicate_pad_numbers_are_jumpers no)
		(fp_line
			(start 0.7874 0.4064)
			(end -0.7874 0.4064)
			(stroke
				(width 0.1524)
				(type default)
			)
			(layer "F.SilkS")
		)
		(fp_line
			(start 0.7874 -0.4064)
			(end 0.7874 0.4064)
			(stroke
				(width 0.1524)
				(type default)
			)
			(layer "F.SilkS")
		)
		(fp_line
			(start -0.7874 0.4064)
			(end -0.7874 -0.4064)
			(stroke
				(width 0.1524)
				(type default)
			)
			(layer "F.SilkS")
		)
		(fp_line
			(start -0.7874 -0.4064)
			(end 0.7874 -0.4064)
			(stroke
				(width 0.1524)
				(type default)
			)
			(layer "F.SilkS")
		)
		(fp_line
			(start 0.67945 0.3048)
			(end 0.120396 0.3048)
			(stroke
				(width 0.1)
				(type default)
			)
			(layer "F.Fab")
		)
		(fp_line
			(start 0.67945 -0.3048)
			(end 0.67945 0.3048)
			(stroke
				(width 0.1)
				(type default)
			)
			(layer "F.Fab")
		)
		(fp_line
			(start 0.12065 -0.2794)
			(end 0.12065 -0.3048)
			(stroke
				(width 0.1)
				(type default)
			)
			(layer "F.Fab")
		)
		(fp_line
			(start 0.12065 -0.3048)
			(end 0.67945 -0.3048)
			(stroke
				(width 0.1)
				(type default)
			)
			(layer "F.Fab")
		)
		(fp_line
			(start 0.120396 0.3048)
			(end 0.120396 0.2794)
			(stroke
				(width 0.1)
				(type default)
			)
			(layer "F.Fab")
		)
		(fp_line
			(start 0.120396 0.2794)
			(end -0.12065 0.2794)
			(stroke
				(width 0.1)
				(type default)
			)
			(layer "F.Fab")
		)
		(fp_line
			(start -0.12065 0.3048)
			(end -0.67945 0.3048)
			(stroke
				(width 0.1)
				(type default)
			)
			(layer "F.Fab")
		)
		(fp_line
			(start -0.12065 0.2794)
			(end -0.12065 0.3048)
			(stroke
				(width 0.1)
				(type default)
			)
			(layer "F.Fab")
		)
		(fp_line
			(start -0.12065 -0.2794)
			(end 0.12065 -0.2794)
			(stroke
				(width 0.1)
				(type default)
			)
			(layer "F.Fab")
		)
		(fp_line
			(start -0.12065 -0.305054)
			(end -0.12065 -0.2794)
			(stroke
				(width 0.1)
				(type default)
			)
			(layer "F.Fab")
		)
		(fp_line
			(start -0.67945 0.3048)
			(end -0.67945 -0.305054)
			(stroke
				(width 0.1)
				(type default)
			)
			(layer "F.Fab")
		)
		(fp_line
			(start -0.67945 -0.305054)
			(end -0.12065 -0.305054)
			(stroke
				(width 0.1)
				(type default)
			)
			(layer "F.Fab")
		)
		(pad "1" smd circle
			(at -0.40005 0 180)
			(size 0 0)
			(layers "F.Cu" "F.Mask" "F.Paste")
			(net "P0V8_PEX2_ADDR")
		)
		(pad "2" smd circle
			(at 0.40005 0 180)
			(size 0 0)
			(layers "F.Cu" "F.Mask" "F.Paste")
			(net "GND")
		)
	)
	(footprint ""
		(layer "F.Cu")
		(at 381.587756 -294.819832)
		(property "Reference" "C3549"
			(at 0 0 0)
			(layer "F.SilkS")
			(hide yes)
			(effects
				(font
					(size 1.27 1.27)
				)
			)
		)
		(property "Value" ""
			(at 0 0 0)
			(layer "F.Fab")
			(effects
				(font
					(size 1.27 1.27)
				)
			)
		)
		(duplicate_pad_numbers_are_jumpers no)
		(fp_line
			(start -1.2954 -0.5842)
			(end 1.2954 -0.5842)
			(stroke
				(width 0.1524)
				(type default)
			)
			(layer "F.SilkS")
		)
		(fp_line
			(start -1.2954 0.5842)
			(end -1.2954 -0.5842)
			(stroke
				(width 0.1524)
				(type default)
			)
			(layer "F.SilkS")
		)
		(fp_line
			(start 1.2954 -0.5842)
			(end 1.2954 0.5842)
			(stroke
				(width 0.1524)
				(type default)
			)
			(layer "F.SilkS")
		)
		(fp_line
			(start 1.2954 0.5842)
			(end -1.2954 0.5842)
			(stroke
				(width 0.1524)
				(type default)
			)
			(layer "F.SilkS")
		)
		(fp_line
			(start -1.1938 -0.4064)
			(end -0.8636 -0.4064)
			(stroke
				(width 0.1)
				(type default)
			)
			(layer "F.Fab")
		)
		(fp_line
			(start -1.1938 0.4064)
			(end -1.1938 -0.4064)
			(stroke
				(width 0.1)
				(type default)
			)
			(layer "F.Fab")
		)
		(fp_line
			(start -0.8636 -0.4572)
			(end 0.8636 -0.4572)
			(stroke
				(width 0.1)
				(type default)
			)
			(layer "F.Fab")
		)
		(fp_line
			(start -0.8636 -0.4064)
			(end -0.8636 -0.4572)
			(stroke
				(width 0.1)
				(type default)
			)
			(layer "F.Fab")
		)
		(fp_line
			(start -0.8636 0.4064)
			(end -1.1938 0.4064)
			(stroke
				(width 0.1)
				(type default)
			)
			(layer "F.Fab")
		)
		(fp_line
			(start -0.8636 0.4572)
			(end -0.8636 0.4064)
			(stroke
				(width 0.1)
				(type default)
			)
			(layer "F.Fab")
		)
		(fp_line
			(start 0.8636 -0.4572)
			(end 0.8636 -0.4064)
			(stroke
				(width 0.1)
				(type default)
			)
			(layer "F.Fab")
		)
		(fp_line
			(start 0.8636 -0.4064)
			(end 1.1938 -0.4064)
			(stroke
				(width 0.1)
				(type default)
			)
			(layer "F.Fab")
		)
		(fp_line
			(start 0.8636 0.4064)
			(end 0.8636 0.4572)
			(stroke
				(width 0.1)
				(type default)
			)
			(layer "F.Fab")
		)
		(fp_line
			(start 0.8636 0.4572)
			(end -0.8636 0.4572)
			(stroke
				(width 0.1)
				(type default)
			)
			(layer "F.Fab")
		)
		(fp_line
			(start 1.1938 -0.4064)
			(end 1.1938 0.4064)
			(stroke
				(width 0.1)
				(type default)
			)
			(layer "F.Fab")
		)
		(fp_line
			(start 1.1938 0.4064)
			(end 0.8636 0.4064)
			(stroke
				(width 0.1)
				(type default)
			)
			(layer "F.Fab")
		)
		(pad "1" smd rect
			(at -0.7366 0 270)
			(size 0.7112 0.8128)
			(layers "F.Cu" "F.Mask" "F.Paste")
			(net "PCEPLL2_VDDA18_PEX3")
		)
		(pad "2" smd rect
			(at 0.7366 0 270)
			(size 0.7112 0.8128)
			(layers "F.Cu" "F.Mask" "F.Paste")
			(net "GND")
		)
	)
	(footprint ""
		(layer "F.Cu")
		(at 250.96343 -92.096336 -90)
		(property "Reference" "R1070"
			(at 0 0 270)
			(layer "F.SilkS")
			(hide yes)
			(effects
				(font
					(size 1.27 1.27)
				)
			)
		)
		(property "Value" ""
			(at 0 0 270)
			(layer "F.Fab")
			(effects
				(font
					(size 1.27 1.27)
				)
			)
		)
		(duplicate_pad_numbers_are_jumpers no)
		(fp_line
			(start -0.7874 0.4064)
			(end -0.7874 -0.4064)
			(stroke
				(width 0.1524)
				(type default)
			)
			(layer "F.SilkS")
		)
		(fp_line
			(start 0.7874 0.4064)
			(end -0.7874 0.4064)
			(stroke
				(width 0.1524)
				(type default)
			)
			(layer "F.SilkS")
		)
		(fp_line
			(start -0.7874 -0.4064)
			(end 0.7874 -0.4064)
			(stroke
				(width 0.1524)
				(type default)
			)
			(layer "F.SilkS")
		)
		(fp_line
			(start 0.7874 -0.4064)
			(end 0.7874 0.4064)
			(stroke
				(width 0.1524)
				(type default)
			)
			(layer "F.SilkS")
		)
		(fp_line
			(start -0.67945 0.3048)
			(end -0.67945 -0.305054)
			(stroke
				(width 0.1)
				(type default)
			)
			(layer "F.Fab")
		)
		(fp_line
			(start -0.12065 0.3048)
			(end -0.67945 0.3048)
			(stroke
				(width 0.1)
				(type default)
			)
			(layer "F.Fab")
		)
		(fp_line
			(start 0.120396 0.3048)
			(end 0.120396 0.2794)
			(stroke
				(width 0.1)
				(type default)
			)
			(layer "F.Fab")
		)
		(fp_line
			(start 0.67945 0.3048)
			(end 0.120396 0.3048)
			(stroke
				(width 0.1)
				(type default)
			)
			(layer "F.Fab")
		)
		(fp_line
			(start -0.12065 0.2794)
			(end -0.12065 0.3048)
			(stroke
				(width 0.1)
				(type default)
			)
			(layer "F.Fab")
		)
		(fp_line
			(start 0.120396 0.2794)
			(end -0.12065 0.2794)
			(stroke
				(width 0.1)
				(type default)
			)
			(layer "F.Fab")
		)
		(fp_line
			(start -0.12065 -0.2794)
			(end 0.12065 -0.2794)
			(stroke
				(width 0.1)
				(type default)
			)
			(layer "F.Fab")
		)
		(fp_line
			(start 0.12065 -0.2794)
			(end 0.12065 -0.3048)
			(stroke
				(width 0.1)
				(type default)
			)
			(layer "F.Fab")
		)
		(fp_line
			(start 0.12065 -0.3048)
			(end 0.67945 -0.3048)
			(stroke
				(width 0.1)
				(type default)
			)
			(layer "F.Fab")
		)
		(fp_line
			(start 0.67945 -0.3048)
			(end 0.67945 0.3048)
			(stroke
				(width 0.1)
				(type default)
			)
			(layer "F.Fab")
		)
		(fp_line
			(start -0.67945 -0.305054)
			(end -0.12065 -0.305054)
			(stroke
				(width 0.1)
				(type default)
			)
			(layer "F.Fab")
		)
		(fp_line
			(start -0.12065 -0.305054)
			(end -0.12065 -0.2794)
			(stroke
				(width 0.1)
				(type default)
			)
			(layer "F.Fab")
		)
		(pad "1" smd circle
			(at -0.40005 0 270)
			(size 0 0)
			(layers "F.Cu" "F.Mask" "F.Paste")
			(net "GND")
		)
		(pad "2" smd circle
			(at 0.40005 0 270)
			(size 0 0)
			(layers "F.Cu" "F.Mask" "F.Paste")
			(net "FM_CK440Q_DEV_25M_EN")
		)
	)
	(footprint ""
		(layer "F.Cu")
		(at 52.243736 -42.84091)
		(property "Reference" "R517"
			(at 0 0 0)
			(layer "F.SilkS")
			(hide yes)
			(effects
				(font
					(size 1.27 1.27)
				)
			)
		)
		(property "Value" ""
			(at 0 0 0)
			(layer "F.Fab")
			(effects
				(font
					(size 1.27 1.27)
				)
			)
		)
		(duplicate_pad_numbers_are_jumpers no)
		(fp_line
			(start -0.7874 -0.4064)
			(end 0.7874 -0.4064)
			(stroke
				(width 0.1524)
				(type default)
			)
			(layer "F.SilkS")
		)
		(fp_line
			(start -0.7874 0.4064)
			(end -0.7874 -0.4064)
			(stroke
				(width 0.1524)
				(type default)
			)
			(layer "F.SilkS")
		)
		(fp_line
			(start 0.7874 -0.4064)
			(end 0.7874 0.4064)
			(stroke
				(width 0.1524)
				(type default)
			)
			(layer "F.SilkS")
		)
		(fp_line
			(start 0.7874 0.4064)
			(end -0.7874 0.4064)
			(stroke
				(width 0.1524)
				(type default)
			)
			(layer "F.SilkS")
		)
		(fp_line
			(start -0.67945 -0.305054)
			(end -0.12065 -0.305054)
			(stroke
				(width 0.1)
				(type default)
			)
			(layer "F.Fab")
		)
		(fp_line
			(start -0.67945 0.3048)
			(end -0.67945 -0.305054)
			(stroke
				(width 0.1)
				(type default)
			)
			(layer "F.Fab")
		)
		(fp_line
			(start -0.12065 -0.305054)
			(end -0.12065 -0.2794)
			(stroke
				(width 0.1)
				(type default)
			)
			(layer "F.Fab")
		)
		(fp_line
			(start -0.12065 -0.2794)
			(end 0.12065 -0.2794)
			(stroke
				(width 0.1)
				(type default)
			)
			(layer "F.Fab")
		)
		(fp_line
			(start -0.12065 0.2794)
			(end -0.12065 0.3048)
			(stroke
				(width 0.1)
				(type default)
			)
			(layer "F.Fab")
		)
		(fp_line
			(start -0.12065 0.3048)
			(end -0.67945 0.3048)
			(stroke
				(width 0.1)
				(type default)
			)
			(layer "F.Fab")
		)
		(fp_line
			(start 0.120396 0.2794)
			(end -0.12065 0.2794)
			(stroke
				(width 0.1)
				(type default)
			)
			(layer "F.Fab")
		)
		(fp_line
			(start 0.120396 0.3048)
			(end 0.120396 0.2794)
			(stroke
				(width 0.1)
				(type default)
			)
			(layer "F.Fab")
		)
		(fp_line
			(start 0.12065 -0.3048)
			(end 0.67945 -0.3048)
			(stroke
				(width 0.1)
				(type default)
			)
			(layer "F.Fab")
		)
		(fp_line
			(start 0.12065 -0.2794)
			(end 0.12065 -0.3048)
			(stroke
				(width 0.1)
				(type default)
			)
			(layer "F.Fab")
		)
		(fp_line
			(start 0.67945 -0.3048)
			(end 0.67945 0.3048)
			(stroke
				(width 0.1)
				(type default)
			)
			(layer "F.Fab")
		)
		(fp_line
			(start 0.67945 0.3048)
			(end 0.120396 0.3048)
			(stroke
				(width 0.1)
				(type default)
			)
			(layer "F.Fab")
		)
		(pad "1" smd circle
			(at -0.40005 0)
			(size 0 0)
			(layers "F.Cu" "F.Mask" "F.Paste")
			(net "SSD1_ADC_A1")
		)
		(pad "2" smd circle
			(at 0.40005 0)
			(size 0 0)
			(layers "F.Cu" "F.Mask" "F.Paste")
			(net "P3V3_AUX")
		)
	)
	(footprint ""
		(layer "F.Cu")
		(at 373.911622 -71.458074 -90)
		(property "Reference" "PD116"
			(at 4.198874 -2.720848 90)
			(unlocked yes)
			(layer "F.SilkS")
			(effects
				(font
					(size 0.7874 0.5842)
					(thickness 0.1524)
				)
				(justify left)
			)
		)
		(property "Value" ""
			(at 0 0 270)
			(layer "F.Fab")
			(effects
				(font
					(size 1.27 1.27)
				)
			)
		)
		(duplicate_pad_numbers_are_jumpers no)
		(fp_line
			(start -3.656584 1.970024)
			(end 4.240784 1.970024)
			(stroke
				(width 0.1524)
				(type default)
			)
			(layer "F.SilkS")
		)
		(fp_line
			(start 4.240784 1.970024)
			(end 4.240784 -1.970024)
			(stroke
				(width 0.1524)
				(type default)
			)
			(layer "F.SilkS")
		)
		(fp_line
			(start -3.656584 -1.970024)
			(end -3.656584 1.970024)
			(stroke
				(width 0.1524)
				(type default)
			)
			(layer "F.SilkS")
		)
		(fp_line
			(start 4.240784 -1.970024)
			(end -3.656584 -1.970024)
			(stroke
				(width 0.1524)
				(type default)
			)
			(layer "F.SilkS")
		)
		(fp_poly
			(pts
				(xy 3.580384 1.970024) (xy 3.580384 -1.970024) (xy 4.240784 -1.970024) (xy 4.240784 1.970024)
			)
			(stroke
				(width 0)
				(type default)
			)
			(fill yes)
			(layer "F.SilkS")
		)
		(fp_line
			(start -2.3749 1.970024)
			(end 2.3749 1.970024)
			(stroke
				(width 0.1)
				(type default)
			)
			(layer "F.Fab")
		)
		(fp_line
			(start 2.3749 1.970024)
			(end 2.3749 -1.970024)
			(stroke
				(width 0.1)
				(type default)
			)
			(layer "F.Fab")
		)
		(fp_line
			(start -2.3749 -1.970024)
			(end -2.3749 1.970024)
			(stroke
				(width 0.1)
				(type default)
			)
			(layer "F.Fab")
		)
		(fp_line
			(start 2.3749 -1.970024)
			(end -2.3749 -1.970024)
			(stroke
				(width 0.1)
				(type default)
			)
			(layer "F.Fab")
		)
		(fp_text user "+"
			(at -4.9784 -0.23495 270)
			(unlocked yes)
			(layer "F.Fab")
			(effects
				(font
					(size 1.905 1.4224)
					(thickness 0.1524)
				)
				(justify left)
			)
		)
		(fp_text user "-"
			(at 4.1656 -0.23495 270)
			(unlocked yes)
			(layer "F.Fab")
			(effects
				(font
					(size 1.905 1.4224)
					(thickness 0.1524)
				)
				(justify left)
			)
		)
		(pad "A" smd rect
			(at -2.450084 0 270)
			(size 2.159 2.2606)
			(layers "F.Cu" "F.Mask" "F.Paste")
			(net "GND")
		)
		(pad "C" smd rect
			(at 2.450084 0 270)
			(size 2.159 2.2606)
			(layers "F.Cu" "F.Mask" "F.Paste")
			(net "P12V_AUX")
		)
	)
	(footprint ""
		(layer "F.Cu")
		(at 323.579236 -300.641004 -90)
		(property "Reference" "R3972"
			(at 0 0 270)
			(layer "F.SilkS")
			(hide yes)
			(effects
				(font
					(size 1.27 1.27)
				)
			)
		)
		(property "Value" ""
			(at 0 0 270)
			(layer "F.Fab")
			(effects
				(font
					(size 1.27 1.27)
				)
			)
		)
		(duplicate_pad_numbers_are_jumpers no)
		(fp_line
			(start -0.7874 0.4064)
			(end -0.7874 -0.4064)
			(stroke
				(width 0.1524)
				(type default)
			)
			(layer "F.SilkS")
		)
		(fp_line
			(start 0.7874 0.4064)
			(end -0.7874 0.4064)
			(stroke
				(width 0.1524)
				(type default)
			)
			(layer "F.SilkS")
		)
		(fp_line
			(start -0.7874 -0.4064)
			(end 0.7874 -0.4064)
			(stroke
				(width 0.1524)
				(type default)
			)
			(layer "F.SilkS")
		)
		(fp_line
			(start 0.7874 -0.4064)
			(end 0.7874 0.4064)
			(stroke
				(width 0.1524)
				(type default)
			)
			(layer "F.SilkS")
		)
		(fp_line
			(start -0.67945 0.3048)
			(end -0.67945 -0.305054)
			(stroke
				(width 0.1)
				(type default)
			)
			(layer "F.Fab")
		)
		(fp_line
			(start -0.12065 0.3048)
			(end -0.67945 0.3048)
			(stroke
				(width 0.1)
				(type default)
			)
			(layer "F.Fab")
		)
		(fp_line
			(start 0.120396 0.3048)
			(end 0.120396 0.2794)
			(stroke
				(width 0.1)
				(type default)
			)
			(layer "F.Fab")
		)
		(fp_line
			(start 0.67945 0.3048)
			(end 0.120396 0.3048)
			(stroke
				(width 0.1)
				(type default)
			)
			(layer "F.Fab")
		)
		(fp_line
			(start -0.12065 0.2794)
			(end -0.12065 0.3048)
			(stroke
				(width 0.1)
				(type default)
			)
			(layer "F.Fab")
		)
		(fp_line
			(start 0.120396 0.2794)
			(end -0.12065 0.2794)
			(stroke
				(width 0.1)
				(type default)
			)
			(layer "F.Fab")
		)
		(fp_line
			(start -0.12065 -0.2794)
			(end 0.12065 -0.2794)
			(stroke
				(width 0.1)
				(type default)
			)
			(layer "F.Fab")
		)
		(fp_line
			(start 0.12065 -0.2794)
			(end 0.12065 -0.3048)
			(stroke
				(width 0.1)
				(type default)
			)
			(layer "F.Fab")
		)
		(fp_line
			(start 0.12065 -0.3048)
			(end 0.67945 -0.3048)
			(stroke
				(width 0.1)
				(type default)
			)
			(layer "F.Fab")
		)
		(fp_line
			(start 0.67945 -0.3048)
			(end 0.67945 0.3048)
			(stroke
				(width 0.1)
				(type default)
			)
			(layer "F.Fab")
		)
		(fp_line
			(start -0.67945 -0.305054)
			(end -0.12065 -0.305054)
			(stroke
				(width 0.1)
				(type default)
			)
			(layer "F.Fab")
		)
		(fp_line
			(start -0.12065 -0.305054)
			(end -0.12065 -0.2794)
			(stroke
				(width 0.1)
				(type default)
			)
			(layer "F.Fab")
		)
		(pad "1" smd circle
			(at -0.40005 0 270)
			(size 0 0)
			(layers "F.Cu" "F.Mask" "F.Paste")
			(net "I2C0_PEX2_SCL")
		)
		(pad "2" smd circle
			(at 0.40005 0 270)
			(size 0 0)
			(layers "F.Cu" "F.Mask" "F.Paste")
			(net "I2C_PEX2_HOST_SCL")
		)
	)
	(footprint ""
		(layer "F.Cu")
		(at 420.425372 -42.849038 180)
		(property "Reference" "R667"
			(at 0 0 180)
			(layer "F.SilkS")
			(hide yes)
			(effects
				(font
					(size 1.27 1.27)
				)
			)
		)
		(property "Value" ""
			(at 0 0 180)
			(layer "F.Fab")
			(effects
				(font
					(size 1.27 1.27)
				)
			)
		)
		(duplicate_pad_numbers_are_jumpers no)
		(fp_line
			(start 0.7874 0.4064)
			(end -0.7874 0.4064)
			(stroke
				(width 0.1524)
				(type default)
			)
			(layer "F.SilkS")
		)
		(fp_line
			(start 0.7874 -0.4064)
			(end 0.7874 0.4064)
			(stroke
				(width 0.1524)
				(type default)
			)
			(layer "F.SilkS")
		)
		(fp_line
			(start -0.7874 0.4064)
			(end -0.7874 -0.4064)
			(stroke
				(width 0.1524)
				(type default)
			)
			(layer "F.SilkS")
		)
		(fp_line
			(start -0.7874 -0.4064)
			(end 0.7874 -0.4064)
			(stroke
				(width 0.1524)
				(type default)
			)
			(layer "F.SilkS")
		)
		(fp_line
			(start 0.67945 0.3048)
			(end 0.120396 0.3048)
			(stroke
				(width 0.1)
				(type default)
			)
			(layer "F.Fab")
		)
		(fp_line
			(start 0.67945 -0.3048)
			(end 0.67945 0.3048)
			(stroke
				(width 0.1)
				(type default)
			)
			(layer "F.Fab")
		)
		(fp_line
			(start 0.12065 -0.2794)
			(end 0.12065 -0.3048)
			(stroke
				(width 0.1)
				(type default)
			)
			(layer "F.Fab")
		)
		(fp_line
			(start 0.12065 -0.3048)
			(end 0.67945 -0.3048)
			(stroke
				(width 0.1)
				(type default)
			)
			(layer "F.Fab")
		)
		(fp_line
			(start 0.120396 0.3048)
			(end 0.120396 0.2794)
			(stroke
				(width 0.1)
				(type default)
			)
			(layer "F.Fab")
		)
		(fp_line
			(start 0.120396 0.2794)
			(end -0.12065 0.2794)
			(stroke
				(width 0.1)
				(type default)
			)
			(layer "F.Fab")
		)
		(fp_line
			(start -0.12065 0.3048)
			(end -0.67945 0.3048)
			(stroke
				(width 0.1)
				(type default)
			)
			(layer "F.Fab")
		)
		(fp_line
			(start -0.12065 0.2794)
			(end -0.12065 0.3048)
			(stroke
				(width 0.1)
				(type default)
			)
			(layer "F.Fab")
		)
		(fp_line
			(start -0.12065 -0.2794)
			(end 0.12065 -0.2794)
			(stroke
				(width 0.1)
				(type default)
			)
			(layer "F.Fab")
		)
		(fp_line
			(start -0.12065 -0.305054)
			(end -0.12065 -0.2794)
			(stroke
				(width 0.1)
				(type default)
			)
			(layer "F.Fab")
		)
		(fp_line
			(start -0.67945 0.3048)
			(end -0.67945 -0.305054)
			(stroke
				(width 0.1)
				(type default)
			)
			(layer "F.Fab")
		)
		(fp_line
			(start -0.67945 -0.305054)
			(end -0.12065 -0.305054)
			(stroke
				(width 0.1)
				(type default)
			)
			(layer "F.Fab")
		)
		(pad "1" smd circle
			(at -0.40005 0 180)
			(size 0 0)
			(layers "F.Cu" "F.Mask" "F.Paste")
			(net "P12V_SSD14_R")
		)
		(pad "2" smd circle
			(at 0.40005 0 180)
			(size 0 0)
			(layers "F.Cu" "F.Mask" "F.Paste")
			(net "P12V_SSD14_VIN_P")
		)
	)
	(footprint ""
		(layer "F.Cu")
		(at 146.18208 -292.991032 180)
		(property "Reference" "C3206"
			(at 0 0 180)
			(layer "F.SilkS")
			(hide yes)
			(effects
				(font
					(size 1.27 1.27)
				)
			)
		)
		(property "Value" ""
			(at 0 0 180)
			(layer "F.Fab")
			(effects
				(font
					(size 1.27 1.27)
				)
			)
		)
		(duplicate_pad_numbers_are_jumpers no)
		(fp_line
			(start 1.2954 0.5842)
			(end -1.2954 0.5842)
			(stroke
				(width 0.1524)
				(type default)
			)
			(layer "F.SilkS")
		)
		(fp_line
			(start 1.2954 -0.5842)
			(end 1.2954 0.5842)
			(stroke
				(width 0.1524)
				(type default)
			)
			(layer "F.SilkS")
		)
		(fp_line
			(start -1.2954 0.5842)
			(end -1.2954 -0.5842)
			(stroke
				(width 0.1524)
				(type default)
			)
			(layer "F.SilkS")
		)
		(fp_line
			(start -1.2954 -0.5842)
			(end 1.2954 -0.5842)
			(stroke
				(width 0.1524)
				(type default)
			)
			(layer "F.SilkS")
		)
		(fp_line
			(start 1.1938 0.4064)
			(end 0.8636 0.4064)
			(stroke
				(width 0.1)
				(type default)
			)
			(layer "F.Fab")
		)
		(fp_line
			(start 1.1938 -0.4064)
			(end 1.1938 0.4064)
			(stroke
				(width 0.1)
				(type default)
			)
			(layer "F.Fab")
		)
		(fp_line
			(start 0.8636 0.4572)
			(end -0.8636 0.4572)
			(stroke
				(width 0.1)
				(type default)
			)
			(layer "F.Fab")
		)
		(fp_line
			(start 0.8636 0.4064)
			(end 0.8636 0.4572)
			(stroke
				(width 0.1)
				(type default)
			)
			(layer "F.Fab")
		)
		(fp_line
			(start 0.8636 -0.4064)
			(end 1.1938 -0.4064)
			(stroke
				(width 0.1)
				(type default)
			)
			(layer "F.Fab")
		)
		(fp_line
			(start 0.8636 -0.4572)
			(end 0.8636 -0.4064)
			(stroke
				(width 0.1)
				(type default)
			)
			(layer "F.Fab")
		)
		(fp_line
			(start -0.8636 0.4572)
			(end -0.8636 0.4064)
			(stroke
				(width 0.1)
				(type default)
			)
			(layer "F.Fab")
		)
		(fp_line
			(start -0.8636 0.4064)
			(end -1.1938 0.4064)
			(stroke
				(width 0.1)
				(type default)
			)
			(layer "F.Fab")
		)
		(fp_line
			(start -0.8636 -0.4064)
			(end -0.8636 -0.4572)
			(stroke
				(width 0.1)
				(type default)
			)
			(layer "F.Fab")
		)
		(fp_line
			(start -0.8636 -0.4572)
			(end 0.8636 -0.4572)
			(stroke
				(width 0.1)
				(type default)
			)
			(layer "F.Fab")
		)
		(fp_line
			(start -1.1938 0.4064)
			(end -1.1938 -0.4064)
			(stroke
				(width 0.1)
				(type default)
			)
			(layer "F.Fab")
		)
		(fp_line
			(start -1.1938 -0.4064)
			(end -0.8636 -0.4064)
			(stroke
				(width 0.1)
				(type default)
			)
			(layer "F.Fab")
		)
		(pad "1" smd rect
			(at -0.7366 0 90)
			(size 0.7112 0.8128)
			(layers "F.Cu" "F.Mask" "F.Paste")
			(net "PCEPLL2_VDDA18_PEX1_R")
		)
		(pad "2" smd rect
			(at 0.7366 0 90)
			(size 0.7112 0.8128)
			(layers "F.Cu" "F.Mask" "F.Paste")
			(net "GND")
		)
	)
	(footprint ""
		(layer "F.Cu")
		(at 319.977262 -309.791354 135)
		(property "Reference" "R1377"
			(at 0 0 135)
			(layer "F.SilkS")
			(hide yes)
			(effects
				(font
					(size 1.27 1.27)
				)
			)
		)
		(property "Value" ""
			(at 0 0 135)
			(layer "F.Fab")
			(effects
				(font
					(size 1.27 1.27)
				)
			)
		)
		(duplicate_pad_numbers_are_jumpers no)
		(fp_line
			(start 0.787389 -0.406267)
			(end 0.787389 0.406267)
			(stroke
				(width 0.1524)
				(type default)
			)
			(layer "F.SilkS")
		)
		(fp_line
			(start 0.787389 0.406267)
			(end -0.787389 0.406267)
			(stroke
				(width 0.1524)
				(type default)
			)
			(layer "F.SilkS")
		)
		(fp_line
			(start -0.787389 -0.406267)
			(end 0.787389 -0.406267)
			(stroke
				(width 0.1524)
				(type default)
			)
			(layer "F.SilkS")
		)
		(fp_line
			(start -0.787389 0.406267)
			(end -0.787389 -0.406267)
			(stroke
				(width 0.1524)
				(type default)
			)
			(layer "F.SilkS")
		)
		(fp_line
			(start 0.679446 -0.30479)
			(end 0.679446 0.30479)
			(stroke
				(width 0.1)
				(type default)
			)
			(layer "F.Fab")
		)
		(fp_line
			(start 0.120515 -0.30479)
			(end 0.679446 -0.30479)
			(stroke
				(width 0.1)
				(type default)
			)
			(layer "F.Fab")
		)
		(fp_line
			(start 0.120695 -0.279466)
			(end 0.120515 -0.30479)
			(stroke
				(width 0.1)
				(type default)
			)
			(layer "F.Fab")
		)
		(fp_line
			(start 0.679446 0.30479)
			(end 0.120515 0.30479)
			(stroke
				(width 0.1)
				(type default)
			)
			(layer "F.Fab")
		)
		(fp_line
			(start -0.120695 -0.304969)
			(end -0.120695 -0.279466)
			(stroke
				(width 0.1)
				(type default)
			)
			(layer "F.Fab")
		)
		(fp_line
			(start -0.120695 -0.279466)
			(end 0.120695 -0.279466)
			(stroke
				(width 0.1)
				(type default)
			)
			(layer "F.Fab")
		)
		(fp_line
			(start 0.120335 0.279466)
			(end -0.120695 0.279466)
			(stroke
				(width 0.1)
				(type default)
			)
			(layer "F.Fab")
		)
		(fp_line
			(start 0.120515 0.30479)
			(end 0.120335 0.279466)
			(stroke
				(width 0.1)
				(type default)
			)
			(layer "F.Fab")
		)
		(fp_line
			(start -0.679446 -0.305149)
			(end -0.120695 -0.304969)
			(stroke
				(width 0.1)
				(type default)
			)
			(layer "F.Fab")
		)
		(fp_line
			(start -0.120695 0.279466)
			(end -0.120515 0.30479)
			(stroke
				(width 0.1)
				(type default)
			)
			(layer "F.Fab")
		)
		(fp_line
			(start -0.120515 0.30479)
			(end -0.679446 0.30479)
			(stroke
				(width 0.1)
				(type default)
			)
			(layer "F.Fab")
		)
		(fp_line
			(start -0.679446 0.30479)
			(end -0.679446 -0.305149)
			(stroke
				(width 0.1)
				(type default)
			)
			(layer "F.Fab")
		)
		(pad "1" smd circle
			(at -0.40005 0 135)
			(size 0 0)
			(layers "F.Cu" "F.Mask" "F.Paste")
			(net "PEX2_SPARE7")
		)
		(pad "2" smd circle
			(at 0.40005 0 135)
			(size 0 0)
			(layers "F.Cu" "F.Mask" "F.Paste")
			(net "P1V8_PEX")
		)
	)
	(footprint ""
		(layer "F.Cu")
		(at 98.947224 -20.35556)
		(property "Reference" "C3895"
			(at 0 0 0)
			(layer "F.SilkS")
			(hide yes)
			(effects
				(font
					(size 1.27 1.27)
				)
			)
		)
		(property "Value" ""
			(at 0 0 0)
			(layer "F.Fab")
			(effects
				(font
					(size 1.27 1.27)
				)
			)
		)
		(duplicate_pad_numbers_are_jumpers no)
		(fp_line
			(start -0.7874 -0.4064)
			(end 0.7874 -0.4064)
			(stroke
				(width 0.1524)
				(type default)
			)
			(layer "F.SilkS")
		)
		(fp_line
			(start -0.7874 0.4064)
			(end -0.7874 -0.4064)
			(stroke
				(width 0.1524)
				(type default)
			)
			(layer "F.SilkS")
		)
		(fp_line
			(start 0.7874 -0.4064)
			(end 0.7874 0.4064)
			(stroke
				(width 0.1524)
				(type default)
			)
			(layer "F.SilkS")
		)
		(fp_line
			(start 0.7874 0.4064)
			(end -0.7874 0.4064)
			(stroke
				(width 0.1524)
				(type default)
			)
			(layer "F.SilkS")
		)
		(fp_line
			(start -0.67945 -0.305054)
			(end -0.12065 -0.305054)
			(stroke
				(width 0.1)
				(type default)
			)
			(layer "F.Fab")
		)
		(fp_line
			(start -0.67945 0.3048)
			(end -0.67945 -0.305054)
			(stroke
				(width 0.1)
				(type default)
			)
			(layer "F.Fab")
		)
		(fp_line
			(start -0.12065 -0.305054)
			(end -0.12065 -0.2794)
			(stroke
				(width 0.1)
				(type default)
			)
			(layer "F.Fab")
		)
		(fp_line
			(start -0.12065 -0.2794)
			(end 0.12065 -0.2794)
			(stroke
				(width 0.1)
				(type default)
			)
			(layer "F.Fab")
		)
		(fp_line
			(start -0.12065 0.2794)
			(end -0.12065 0.3048)
			(stroke
				(width 0.1)
				(type default)
			)
			(layer "F.Fab")
		)
		(fp_line
			(start -0.12065 0.3048)
			(end -0.67945 0.3048)
			(stroke
				(width 0.1)
				(type default)
			)
			(layer "F.Fab")
		)
		(fp_line
			(start 0.120396 0.2794)
			(end -0.12065 0.2794)
			(stroke
				(width 0.1)
				(type default)
			)
			(layer "F.Fab")
		)
		(fp_line
			(start 0.120396 0.3048)
			(end 0.120396 0.2794)
			(stroke
				(width 0.1)
				(type default)
			)
			(layer "F.Fab")
		)
		(fp_line
			(start 0.12065 -0.3048)
			(end 0.67945 -0.3048)
			(stroke
				(width 0.1)
				(type default)
			)
			(layer "F.Fab")
		)
		(fp_line
			(start 0.12065 -0.2794)
			(end 0.12065 -0.3048)
			(stroke
				(width 0.1)
				(type default)
			)
			(layer "F.Fab")
		)
		(fp_line
			(start 0.67945 -0.3048)
			(end 0.67945 0.3048)
			(stroke
				(width 0.1)
				(type default)
			)
			(layer "F.Fab")
		)
		(fp_line
			(start 0.67945 0.3048)
			(end 0.120396 0.3048)
			(stroke
				(width 0.1)
				(type default)
			)
			(layer "F.Fab")
		)
		(pad "1" smd circle
			(at -0.40005 0)
			(size 0 0)
			(layers "F.Cu" "F.Mask" "F.Paste")
			(net "P12V_SSD3")
		)
		(pad "2" smd circle
			(at 0.40005 0)
			(size 0 0)
			(layers "F.Cu" "F.Mask" "F.Paste")
			(net "GND")
		)
	)
	(footprint ""
		(layer "F.Cu")
		(at 134.30758 -152.71115 90)
		(property "Reference" "R706"
			(at 0 0 90)
			(layer "F.SilkS")
			(hide yes)
			(effects
				(font
					(size 1.27 1.27)
				)
			)
		)
		(property "Value" ""
			(at 0 0 90)
			(layer "F.Fab")
			(effects
				(font
					(size 1.27 1.27)
				)
			)
		)
		(duplicate_pad_numbers_are_jumpers no)
		(fp_line
			(start 0.7874 -0.4064)
			(end 0.7874 0.4064)
			(stroke
				(width 0.1524)
				(type default)
			)
			(layer "F.SilkS")
		)
		(fp_line
			(start -0.7874 -0.4064)
			(end 0.7874 -0.4064)
			(stroke
				(width 0.1524)
				(type default)
			)
			(layer "F.SilkS")
		)
		(fp_line
			(start 0.7874 0.4064)
			(end -0.7874 0.4064)
			(stroke
				(width 0.1524)
				(type default)
			)
			(layer "F.SilkS")
		)
		(fp_line
			(start -0.7874 0.4064)
			(end -0.7874 -0.4064)
			(stroke
				(width 0.1524)
				(type default)
			)
			(layer "F.SilkS")
		)
		(fp_line
			(start -0.12065 -0.305054)
			(end -0.12065 -0.2794)
			(stroke
				(width 0.1)
				(type default)
			)
			(layer "F.Fab")
		)
		(fp_line
			(start -0.67945 -0.305054)
			(end -0.12065 -0.305054)
			(stroke
				(width 0.1)
				(type default)
			)
			(layer "F.Fab")
		)
		(fp_line
			(start 0.67945 -0.3048)
			(end 0.67945 0.3048)
			(stroke
				(width 0.1)
				(type default)
			)
			(layer "F.Fab")
		)
		(fp_line
			(start 0.12065 -0.3048)
			(end 0.67945 -0.3048)
			(stroke
				(width 0.1)
				(type default)
			)
			(layer "F.Fab")
		)
		(fp_line
			(start 0.12065 -0.2794)
			(end 0.12065 -0.3048)
			(stroke
				(width 0.1)
				(type default)
			)
			(layer "F.Fab")
		)
		(fp_line
			(start -0.12065 -0.2794)
			(end 0.12065 -0.2794)
			(stroke
				(width 0.1)
				(type default)
			)
			(layer "F.Fab")
		)
		(fp_line
			(start 0.120396 0.2794)
			(end -0.12065 0.2794)
			(stroke
				(width 0.1)
				(type default)
			)
			(layer "F.Fab")
		)
		(fp_line
			(start -0.12065 0.2794)
			(end -0.12065 0.3048)
			(stroke
				(width 0.1)
				(type default)
			)
			(layer "F.Fab")
		)
		(fp_line
			(start 0.67945 0.3048)
			(end 0.120396 0.3048)
			(stroke
				(width 0.1)
				(type default)
			)
			(layer "F.Fab")
		)
		(fp_line
			(start 0.120396 0.3048)
			(end 0.120396 0.2794)
			(stroke
				(width 0.1)
				(type default)
			)
			(layer "F.Fab")
		)
		(fp_line
			(start -0.12065 0.3048)
			(end -0.67945 0.3048)
			(stroke
				(width 0.1)
				(type default)
			)
			(layer "F.Fab")
		)
		(fp_line
			(start -0.67945 0.3048)
			(end -0.67945 -0.305054)
			(stroke
				(width 0.1)
				(type default)
			)
			(layer "F.Fab")
		)
		(pad "1" smd circle
			(at -0.40005 0 90)
			(size 0 0)
			(layers "F.Cu" "F.Mask" "F.Paste")
			(net "NIC2_ADC_ALERT_N")
		)
		(pad "2" smd circle
			(at 0.40005 0 90)
			(size 0 0)
			(layers "F.Cu" "F.Mask" "F.Paste")
			(net "NIC_ADC_ALERT_N")
		)
	)
	(footprint ""
		(layer "F.Cu")
		(at 54.875176 -64.102234 180)
		(property "Reference" "PR6913"
			(at 0 0 180)
			(layer "F.SilkS")
			(hide yes)
			(effects
				(font
					(size 1.27 1.27)
				)
			)
		)
		(property "Value" ""
			(at 0 0 180)
			(layer "F.Fab")
			(effects
				(font
					(size 1.27 1.27)
				)
			)
		)
		(duplicate_pad_numbers_are_jumpers no)
		(fp_line
			(start 0.7874 0.4064)
			(end -0.7874 0.4064)
			(stroke
				(width 0.1524)
				(type default)
			)
			(layer "F.SilkS")
		)
		(fp_line
			(start 0.7874 -0.4064)
			(end 0.7874 0.4064)
			(stroke
				(width 0.1524)
				(type default)
			)
			(layer "F.SilkS")
		)
		(fp_line
			(start -0.7874 0.4064)
			(end -0.7874 -0.4064)
			(stroke
				(width 0.1524)
				(type default)
			)
			(layer "F.SilkS")
		)
		(fp_line
			(start -0.7874 -0.4064)
			(end 0.7874 -0.4064)
			(stroke
				(width 0.1524)
				(type default)
			)
			(layer "F.SilkS")
		)
		(fp_line
			(start 0.67945 0.3048)
			(end 0.120396 0.3048)
			(stroke
				(width 0.1)
				(type default)
			)
			(layer "F.Fab")
		)
		(fp_line
			(start 0.67945 -0.3048)
			(end 0.67945 0.3048)
			(stroke
				(width 0.1)
				(type default)
			)
			(layer "F.Fab")
		)
		(fp_line
			(start 0.12065 -0.2794)
			(end 0.12065 -0.3048)
			(stroke
				(width 0.1)
				(type default)
			)
			(layer "F.Fab")
		)
		(fp_line
			(start 0.12065 -0.3048)
			(end 0.67945 -0.3048)
			(stroke
				(width 0.1)
				(type default)
			)
			(layer "F.Fab")
		)
		(fp_line
			(start 0.120396 0.3048)
			(end 0.120396 0.2794)
			(stroke
				(width 0.1)
				(type default)
			)
			(layer "F.Fab")
		)
		(fp_line
			(start 0.120396 0.2794)
			(end -0.12065 0.2794)
			(stroke
				(width 0.1)
				(type default)
			)
			(layer "F.Fab")
		)
		(fp_line
			(start -0.12065 0.3048)
			(end -0.67945 0.3048)
			(stroke
				(width 0.1)
				(type default)
			)
			(layer "F.Fab")
		)
		(fp_line
			(start -0.12065 0.2794)
			(end -0.12065 0.3048)
			(stroke
				(width 0.1)
				(type default)
			)
			(layer "F.Fab")
		)
		(fp_line
			(start -0.12065 -0.2794)
			(end 0.12065 -0.2794)
			(stroke
				(width 0.1)
				(type default)
			)
			(layer "F.Fab")
		)
		(fp_line
			(start -0.12065 -0.305054)
			(end -0.12065 -0.2794)
			(stroke
				(width 0.1)
				(type default)
			)
			(layer "F.Fab")
		)
		(fp_line
			(start -0.67945 0.3048)
			(end -0.67945 -0.305054)
			(stroke
				(width 0.1)
				(type default)
			)
			(layer "F.Fab")
		)
		(fp_line
			(start -0.67945 -0.305054)
			(end -0.12065 -0.305054)
			(stroke
				(width 0.1)
				(type default)
			)
			(layer "F.Fab")
		)
		(pad "1" smd circle
			(at -0.40005 0 180)
			(size 0 0)
			(layers "F.Cu" "F.Mask" "F.Paste")
			(net "P12V_SSD2_PG_G1")
		)
		(pad "2" smd circle
			(at 0.40005 0 180)
			(size 0 0)
			(layers "F.Cu" "F.Mask" "F.Paste")
			(net "GND")
		)
	)
	(footprint ""
		(layer "F.Cu")
		(at 486.96753 -526.47723 180)
		(property "Reference" "J36_OTH"
			(at -3.2385 -1.402334 0)
			(unlocked yes)
			(layer "B.SilkS")
			(effects
				(font
					(size 0.7874 0.5842)
					(thickness 0.1524)
				)
				(justify mirror)
			)
		)
		(property "Value" ""
			(at 0 0 180)
			(layer "F.Fab")
			(effects
				(font
					(size 1.27 1.27)
				)
			)
		)
		(duplicate_pad_numbers_are_jumpers no)
		(pad "1" thru_hole circle
			(at 0 0 180)
			(size 0.4572 0.4572)
			(drill 0.2032)
			(layers "*.Cu" "*.Mask")
			(remove_unused_layers no)
			(net "Net_9100")
			(clearance 0.127)
			(thermal_gap 0.127)
			(padstack
				(mode front_inner_back)
				(layer "Inner"
					(shape circle)
					(size 0.4572 0.4572)
					(clearance 0.127)
				)
				(layer "B.Cu"
					(shape circle)
					(size 0.508 0.508)
					(clearance 0.1016)
				)
			)
		)
	)
	(footprint ""
		(layer "F.Cu")
		(at 211.506816 -366.991646 180)
		(property "Reference" "PR17"
			(at 0 0 180)
			(layer "F.SilkS")
			(hide yes)
			(effects
				(font
					(size 1.27 1.27)
				)
			)
		)
		(property "Value" ""
			(at 0 0 180)
			(layer "F.Fab")
			(effects
				(font
					(size 1.27 1.27)
				)
			)
		)
		(duplicate_pad_numbers_are_jumpers no)
		(fp_line
			(start 0.7874 0.4064)
			(end -0.7874 0.4064)
			(stroke
				(width 0.1524)
				(type default)
			)
			(layer "F.SilkS")
		)
		(fp_line
			(start 0.7874 -0.4064)
			(end 0.7874 0.4064)
			(stroke
				(width 0.1524)
				(type default)
			)
			(layer "F.SilkS")
		)
		(fp_line
			(start -0.7874 0.4064)
			(end -0.7874 -0.4064)
			(stroke
				(width 0.1524)
				(type default)
			)
			(layer "F.SilkS")
		)
		(fp_line
			(start -0.7874 -0.4064)
			(end 0.7874 -0.4064)
			(stroke
				(width 0.1524)
				(type default)
			)
			(layer "F.SilkS")
		)
		(fp_line
			(start 0.67945 0.3048)
			(end 0.120396 0.3048)
			(stroke
				(width 0.1)
				(type default)
			)
			(layer "F.Fab")
		)
		(fp_line
			(start 0.67945 -0.3048)
			(end 0.67945 0.3048)
			(stroke
				(width 0.1)
				(type default)
			)
			(layer "F.Fab")
		)
		(fp_line
			(start 0.12065 -0.2794)
			(end 0.12065 -0.3048)
			(stroke
				(width 0.1)
				(type default)
			)
			(layer "F.Fab")
		)
		(fp_line
			(start 0.12065 -0.3048)
			(end 0.67945 -0.3048)
			(stroke
				(width 0.1)
				(type default)
			)
			(layer "F.Fab")
		)
		(fp_line
			(start 0.120396 0.3048)
			(end 0.120396 0.2794)
			(stroke
				(width 0.1)
				(type default)
			)
			(layer "F.Fab")
		)
		(fp_line
			(start 0.120396 0.2794)
			(end -0.12065 0.2794)
			(stroke
				(width 0.1)
				(type default)
			)
			(layer "F.Fab")
		)
		(fp_line
			(start -0.12065 0.3048)
			(end -0.67945 0.3048)
			(stroke
				(width 0.1)
				(type default)
			)
			(layer "F.Fab")
		)
		(fp_line
			(start -0.12065 0.2794)
			(end -0.12065 0.3048)
			(stroke
				(width 0.1)
				(type default)
			)
			(layer "F.Fab")
		)
		(fp_line
			(start -0.12065 -0.2794)
			(end 0.12065 -0.2794)
			(stroke
				(width 0.1)
				(type default)
			)
			(layer "F.Fab")
		)
		(fp_line
			(start -0.12065 -0.305054)
			(end -0.12065 -0.2794)
			(stroke
				(width 0.1)
				(type default)
			)
			(layer "F.Fab")
		)
		(fp_line
			(start -0.67945 0.3048)
			(end -0.67945 -0.305054)
			(stroke
				(width 0.1)
				(type default)
			)
			(layer "F.Fab")
		)
		(fp_line
			(start -0.67945 -0.305054)
			(end -0.12065 -0.305054)
			(stroke
				(width 0.1)
				(type default)
			)
			(layer "F.Fab")
		)
		(pad "1" smd circle
			(at -0.40005 0 180)
			(size 0 0)
			(layers "F.Cu" "F.Mask" "F.Paste")
			(net "HSC_ON")
		)
		(pad "2" smd circle
			(at 0.40005 0 180)
			(size 0 0)
			(layers "F.Cu" "F.Mask" "F.Paste")
			(net "HSC_ON_R")
		)
	)
	(footprint ""
		(layer "F.Cu")
		(at 361.188 -189.23 180)
		(property "Reference" "R4643"
			(at 0 0 180)
			(layer "F.SilkS")
			(hide yes)
			(effects
				(font
					(size 1.27 1.27)
				)
			)
		)
		(property "Value" ""
			(at 0 0 180)
			(layer "F.Fab")
			(effects
				(font
					(size 1.27 1.27)
				)
			)
		)
		(duplicate_pad_numbers_are_jumpers no)
		(fp_line
			(start 0.7874 0.4064)
			(end -0.7874 0.4064)
			(stroke
				(width 0.1524)
				(type default)
			)
			(layer "F.SilkS")
		)
		(fp_line
			(start 0.7874 -0.4064)
			(end 0.7874 0.4064)
			(stroke
				(width 0.1524)
				(type default)
			)
			(layer "F.SilkS")
		)
		(fp_line
			(start -0.7874 0.4064)
			(end -0.7874 -0.4064)
			(stroke
				(width 0.1524)
				(type default)
			)
			(layer "F.SilkS")
		)
		(fp_line
			(start -0.7874 -0.4064)
			(end 0.7874 -0.4064)
			(stroke
				(width 0.1524)
				(type default)
			)
			(layer "F.SilkS")
		)
		(fp_line
			(start 0.67945 0.3048)
			(end 0.120396 0.3048)
			(stroke
				(width 0.1)
				(type default)
			)
			(layer "F.Fab")
		)
		(fp_line
			(start 0.67945 -0.3048)
			(end 0.67945 0.3048)
			(stroke
				(width 0.1)
				(type default)
			)
			(layer "F.Fab")
		)
		(fp_line
			(start 0.12065 -0.2794)
			(end 0.12065 -0.3048)
			(stroke
				(width 0.1)
				(type default)
			)
			(layer "F.Fab")
		)
		(fp_line
			(start 0.12065 -0.3048)
			(end 0.67945 -0.3048)
			(stroke
				(width 0.1)
				(type default)
			)
			(layer "F.Fab")
		)
		(fp_line
			(start 0.120396 0.3048)
			(end 0.120396 0.2794)
			(stroke
				(width 0.1)
				(type default)
			)
			(layer "F.Fab")
		)
		(fp_line
			(start 0.120396 0.2794)
			(end -0.12065 0.2794)
			(stroke
				(width 0.1)
				(type default)
			)
			(layer "F.Fab")
		)
		(fp_line
			(start -0.12065 0.3048)
			(end -0.67945 0.3048)
			(stroke
				(width 0.1)
				(type default)
			)
			(layer "F.Fab")
		)
		(fp_line
			(start -0.12065 0.2794)
			(end -0.12065 0.3048)
			(stroke
				(width 0.1)
				(type default)
			)
			(layer "F.Fab")
		)
		(fp_line
			(start -0.12065 -0.2794)
			(end 0.12065 -0.2794)
			(stroke
				(width 0.1)
				(type default)
			)
			(layer "F.Fab")
		)
		(fp_line
			(start -0.12065 -0.305054)
			(end -0.12065 -0.2794)
			(stroke
				(width 0.1)
				(type default)
			)
			(layer "F.Fab")
		)
		(fp_line
			(start -0.67945 0.3048)
			(end -0.67945 -0.305054)
			(stroke
				(width 0.1)
				(type default)
			)
			(layer "F.Fab")
		)
		(fp_line
			(start -0.67945 -0.305054)
			(end -0.12065 -0.305054)
			(stroke
				(width 0.1)
				(type default)
			)
			(layer "F.Fab")
		)
		(pad "1" smd circle
			(at -0.40005 0 180)
			(size 0 0)
			(layers "F.Cu" "F.Mask" "F.Paste")
			(net "SSD2_PEX_PWR_EN")
		)
		(pad "2" smd circle
			(at 0.40005 0 180)
			(size 0 0)
			(layers "F.Cu" "F.Mask" "F.Paste")
			(net "SSD2_PEX_PWR_EN_R")
		)
	)
	(footprint ""
		(layer "F.Cu")
		(at 174.6758 -36.915598 -90)
		(property "Reference" "R5559"
			(at 0 0 270)
			(layer "F.SilkS")
			(hide yes)
			(effects
				(font
					(size 1.27 1.27)
				)
			)
		)
		(property "Value" ""
			(at 0 0 270)
			(layer "F.Fab")
			(effects
				(font
					(size 1.27 1.27)
				)
			)
		)
		(duplicate_pad_numbers_are_jumpers no)
		(fp_line
			(start -0.7874 0.4064)
			(end -0.7874 -0.4064)
			(stroke
				(width 0.1524)
				(type default)
			)
			(layer "F.SilkS")
		)
		(fp_line
			(start 0.7874 0.4064)
			(end -0.7874 0.4064)
			(stroke
				(width 0.1524)
				(type default)
			)
			(layer "F.SilkS")
		)
		(fp_line
			(start -0.7874 -0.4064)
			(end 0.7874 -0.4064)
			(stroke
				(width 0.1524)
				(type default)
			)
			(layer "F.SilkS")
		)
		(fp_line
			(start 0.7874 -0.4064)
			(end 0.7874 0.4064)
			(stroke
				(width 0.1524)
				(type default)
			)
			(layer "F.SilkS")
		)
		(fp_line
			(start -0.67945 0.3048)
			(end -0.67945 -0.305054)
			(stroke
				(width 0.1)
				(type default)
			)
			(layer "F.Fab")
		)
		(fp_line
			(start -0.12065 0.3048)
			(end -0.67945 0.3048)
			(stroke
				(width 0.1)
				(type default)
			)
			(layer "F.Fab")
		)
		(fp_line
			(start 0.120396 0.3048)
			(end 0.120396 0.2794)
			(stroke
				(width 0.1)
				(type default)
			)
			(layer "F.Fab")
		)
		(fp_line
			(start 0.67945 0.3048)
			(end 0.120396 0.3048)
			(stroke
				(width 0.1)
				(type default)
			)
			(layer "F.Fab")
		)
		(fp_line
			(start -0.12065 0.2794)
			(end -0.12065 0.3048)
			(stroke
				(width 0.1)
				(type default)
			)
			(layer "F.Fab")
		)
		(fp_line
			(start 0.120396 0.2794)
			(end -0.12065 0.2794)
			(stroke
				(width 0.1)
				(type default)
			)
			(layer "F.Fab")
		)
		(fp_line
			(start -0.12065 -0.2794)
			(end 0.12065 -0.2794)
			(stroke
				(width 0.1)
				(type default)
			)
			(layer "F.Fab")
		)
		(fp_line
			(start 0.12065 -0.2794)
			(end 0.12065 -0.3048)
			(stroke
				(width 0.1)
				(type default)
			)
			(layer "F.Fab")
		)
		(fp_line
			(start 0.12065 -0.3048)
			(end 0.67945 -0.3048)
			(stroke
				(width 0.1)
				(type default)
			)
			(layer "F.Fab")
		)
		(fp_line
			(start 0.67945 -0.3048)
			(end 0.67945 0.3048)
			(stroke
				(width 0.1)
				(type default)
			)
			(layer "F.Fab")
		)
		(fp_line
			(start -0.67945 -0.305054)
			(end -0.12065 -0.305054)
			(stroke
				(width 0.1)
				(type default)
			)
			(layer "F.Fab")
		)
		(fp_line
			(start -0.12065 -0.305054)
			(end -0.12065 -0.2794)
			(stroke
				(width 0.1)
				(type default)
			)
			(layer "F.Fab")
		)
		(pad "1" smd circle
			(at -0.40005 0 270)
			(size 0 0)
			(layers "F.Cu" "F.Mask" "F.Paste")
			(net "PRSNT_SSD6_R1_N")
		)
		(pad "2" smd circle
			(at 0.40005 0 270)
			(size 0 0)
			(layers "F.Cu" "F.Mask" "F.Paste")
			(net "PRSNT_SSD6_R_N")
		)
	)
	(footprint ""
		(layer "F.Cu")
		(at 7.189216 -17.151858 180)
		(property "Reference" "C3874"
			(at 0 0 180)
			(layer "F.SilkS")
			(hide yes)
			(effects
				(font
					(size 1.27 1.27)
				)
			)
		)
		(property "Value" ""
			(at 0 0 180)
			(layer "F.Fab")
			(effects
				(font
					(size 1.27 1.27)
				)
			)
		)
		(duplicate_pad_numbers_are_jumpers no)
		(fp_line
			(start 0.7874 0.4064)
			(end -0.7874 0.4064)
			(stroke
				(width 0.1524)
				(type default)
			)
			(layer "F.SilkS")
		)
		(fp_line
			(start 0.7874 -0.4064)
			(end 0.7874 0.4064)
			(stroke
				(width 0.1524)
				(type default)
			)
			(layer "F.SilkS")
		)
		(fp_line
			(start -0.7874 0.4064)
			(end -0.7874 -0.4064)
			(stroke
				(width 0.1524)
				(type default)
			)
			(layer "F.SilkS")
		)
		(fp_line
			(start -0.7874 -0.4064)
			(end 0.7874 -0.4064)
			(stroke
				(width 0.1524)
				(type default)
			)
			(layer "F.SilkS")
		)
		(fp_line
			(start 0.67945 0.3048)
			(end 0.120396 0.3048)
			(stroke
				(width 0.1)
				(type default)
			)
			(layer "F.Fab")
		)
		(fp_line
			(start 0.67945 -0.3048)
			(end 0.67945 0.3048)
			(stroke
				(width 0.1)
				(type default)
			)
			(layer "F.Fab")
		)
		(fp_line
			(start 0.12065 -0.2794)
			(end 0.12065 -0.3048)
			(stroke
				(width 0.1)
				(type default)
			)
			(layer "F.Fab")
		)
		(fp_line
			(start 0.12065 -0.3048)
			(end 0.67945 -0.3048)
			(stroke
				(width 0.1)
				(type default)
			)
			(layer "F.Fab")
		)
		(fp_line
			(start 0.120396 0.3048)
			(end 0.120396 0.2794)
			(stroke
				(width 0.1)
				(type default)
			)
			(layer "F.Fab")
		)
		(fp_line
			(start 0.120396 0.2794)
			(end -0.12065 0.2794)
			(stroke
				(width 0.1)
				(type default)
			)
			(layer "F.Fab")
		)
		(fp_line
			(start -0.12065 0.3048)
			(end -0.67945 0.3048)
			(stroke
				(width 0.1)
				(type default)
			)
			(layer "F.Fab")
		)
		(fp_line
			(start -0.12065 0.2794)
			(end -0.12065 0.3048)
			(stroke
				(width 0.1)
				(type default)
			)
			(layer "F.Fab")
		)
		(fp_line
			(start -0.12065 -0.2794)
			(end 0.12065 -0.2794)
			(stroke
				(width 0.1)
				(type default)
			)
			(layer "F.Fab")
		)
		(fp_line
			(start -0.12065 -0.305054)
			(end -0.12065 -0.2794)
			(stroke
				(width 0.1)
				(type default)
			)
			(layer "F.Fab")
		)
		(fp_line
			(start -0.67945 0.3048)
			(end -0.67945 -0.305054)
			(stroke
				(width 0.1)
				(type default)
			)
			(layer "F.Fab")
		)
		(fp_line
			(start -0.67945 -0.305054)
			(end -0.12065 -0.305054)
			(stroke
				(width 0.1)
				(type default)
			)
			(layer "F.Fab")
		)
		(pad "1" smd circle
			(at -0.40005 0 180)
			(size 0 0)
			(layers "F.Cu" "F.Mask" "F.Paste")
			(net "P12V_SSD0")
		)
		(pad "2" smd circle
			(at 0.40005 0 180)
			(size 0 0)
			(layers "F.Cu" "F.Mask" "F.Paste")
			(net "GND")
		)
	)
	(footprint ""
		(layer "F.Cu")
		(at 250.30049 -280.573988 180)
		(property "Reference" "PR6616"
			(at 0 0 180)
			(layer "F.SilkS")
			(hide yes)
			(effects
				(font
					(size 1.27 1.27)
				)
			)
		)
		(property "Value" ""
			(at 0 0 180)
			(layer "F.Fab")
			(effects
				(font
					(size 1.27 1.27)
				)
			)
		)
		(duplicate_pad_numbers_are_jumpers no)
		(fp_line
			(start 0.7874 0.4064)
			(end -0.7874 0.4064)
			(stroke
				(width 0.1524)
				(type default)
			)
			(layer "F.SilkS")
		)
		(fp_line
			(start 0.7874 -0.4064)
			(end 0.7874 0.4064)
			(stroke
				(width 0.1524)
				(type default)
			)
			(layer "F.SilkS")
		)
		(fp_line
			(start -0.7874 0.4064)
			(end -0.7874 -0.4064)
			(stroke
				(width 0.1524)
				(type default)
			)
			(layer "F.SilkS")
		)
		(fp_line
			(start -0.7874 -0.4064)
			(end 0.7874 -0.4064)
			(stroke
				(width 0.1524)
				(type default)
			)
			(layer "F.SilkS")
		)
		(fp_line
			(start 0.67945 0.3048)
			(end 0.120396 0.3048)
			(stroke
				(width 0.1)
				(type default)
			)
			(layer "F.Fab")
		)
		(fp_line
			(start 0.67945 -0.3048)
			(end 0.67945 0.3048)
			(stroke
				(width 0.1)
				(type default)
			)
			(layer "F.Fab")
		)
		(fp_line
			(start 0.12065 -0.2794)
			(end 0.12065 -0.3048)
			(stroke
				(width 0.1)
				(type default)
			)
			(layer "F.Fab")
		)
		(fp_line
			(start 0.12065 -0.3048)
			(end 0.67945 -0.3048)
			(stroke
				(width 0.1)
				(type default)
			)
			(layer "F.Fab")
		)
		(fp_line
			(start 0.120396 0.3048)
			(end 0.120396 0.2794)
			(stroke
				(width 0.1)
				(type default)
			)
			(layer "F.Fab")
		)
		(fp_line
			(start 0.120396 0.2794)
			(end -0.12065 0.2794)
			(stroke
				(width 0.1)
				(type default)
			)
			(layer "F.Fab")
		)
		(fp_line
			(start -0.12065 0.3048)
			(end -0.67945 0.3048)
			(stroke
				(width 0.1)
				(type default)
			)
			(layer "F.Fab")
		)
		(fp_line
			(start -0.12065 0.2794)
			(end -0.12065 0.3048)
			(stroke
				(width 0.1)
				(type default)
			)
			(layer "F.Fab")
		)
		(fp_line
			(start -0.12065 -0.2794)
			(end 0.12065 -0.2794)
			(stroke
				(width 0.1)
				(type default)
			)
			(layer "F.Fab")
		)
		(fp_line
			(start -0.12065 -0.305054)
			(end -0.12065 -0.2794)
			(stroke
				(width 0.1)
				(type default)
			)
			(layer "F.Fab")
		)
		(fp_line
			(start -0.67945 0.3048)
			(end -0.67945 -0.305054)
			(stroke
				(width 0.1)
				(type default)
			)
			(layer "F.Fab")
		)
		(fp_line
			(start -0.67945 -0.305054)
			(end -0.12065 -0.305054)
			(stroke
				(width 0.1)
				(type default)
			)
			(layer "F.Fab")
		)
		(pad "1" smd circle
			(at -0.40005 0 180)
			(size 0 0)
			(layers "F.Cu" "F.Mask" "F.Paste")
			(net "SMB_LTC4282_TEMP_SCL")
		)
		(pad "2" smd circle
			(at 0.40005 0 180)
			(size 0 0)
			(layers "F.Cu" "F.Mask" "F.Paste")
			(net "SMB_BIC_I2C6_MUX_PEX_ADC_R_SCL")
		)
	)
	(footprint ""
		(layer "F.Cu")
		(at 457.190602 -244.99824 180)
		(property "Reference" "C4431"
			(at 0 0 180)
			(layer "F.SilkS")
			(hide yes)
			(effects
				(font
					(size 1.27 1.27)
				)
			)
		)
		(property "Value" ""
			(at 0 0 180)
			(layer "F.Fab")
			(effects
				(font
					(size 1.27 1.27)
				)
			)
		)
		(duplicate_pad_numbers_are_jumpers no)
		(fp_line
			(start 1.524 0.762)
			(end -1.524 0.762)
			(stroke
				(width 0.1524)
				(type default)
			)
			(layer "F.SilkS")
		)
		(fp_line
			(start 1.524 -0.762)
			(end 1.524 0.762)
			(stroke
				(width 0.1524)
				(type default)
			)
			(layer "F.SilkS")
		)
		(fp_line
			(start -1.524 0.762)
			(end -1.524 -0.762)
			(stroke
				(width 0.1524)
				(type default)
			)
			(layer "F.SilkS")
		)
		(fp_line
			(start -1.524 -0.762)
			(end 1.524 -0.762)
			(stroke
				(width 0.1524)
				(type default)
			)
			(layer "F.SilkS")
		)
		(fp_line
			(start 1.1049 0.724916)
			(end 1.1049 -0.724916)
			(stroke
				(width 0.1)
				(type default)
			)
			(layer "F.Fab")
		)
		(fp_line
			(start 1.1049 -0.724916)
			(end -1.1049 -0.724916)
			(stroke
				(width 0.1)
				(type default)
			)
			(layer "F.Fab")
		)
		(fp_line
			(start -1.1049 0.724916)
			(end 1.1049 0.724916)
			(stroke
				(width 0.1)
				(type default)
			)
			(layer "F.Fab")
		)
		(fp_line
			(start -1.1049 -0.724916)
			(end -1.1049 0.724916)
			(stroke
				(width 0.1)
				(type default)
			)
			(layer "F.Fab")
		)
		(pad "1" smd rect
			(at -0.889 0)
			(size 1.016 1.27)
			(layers "F.Cu" "F.Mask" "F.Paste")
			(net "P1V8_PLL0_PEX3")
		)
		(pad "2" smd rect
			(at 0.889 0)
			(size 1.016 1.27)
			(layers "F.Cu" "F.Mask" "F.Paste")
			(net "GND")
		)
	)
	(footprint ""
		(layer "F.Cu")
		(at 214.757 -193.548)
		(property "Reference" "U122"
			(at -1.594866 2.187702 0)
			(unlocked yes)
			(layer "F.SilkS")
			(effects
				(font
					(size 0.7874 0.5842)
					(thickness 0.1524)
				)
				(justify left)
			)
		)
		(property "Value" ""
			(at 0 0 0)
			(layer "F.Fab")
			(effects
				(font
					(size 1.27 1.27)
				)
			)
		)
		(duplicate_pad_numbers_are_jumpers no)
		(fp_line
			(start -1.3208 -1.525016)
			(end -0.508 -1.525016)
			(stroke
				(width 0.1524)
				(type default)
			)
			(layer "F.SilkS")
		)
		(fp_line
			(start -1.3208 1.525016)
			(end -1.3208 -1.525016)
			(stroke
				(width 0.1524)
				(type default)
			)
			(layer "F.SilkS")
		)
		(fp_line
			(start -0.508 -1.525016)
			(end 0 -0.999998)
			(stroke
				(width 0.1524)
				(type default)
			)
			(layer "F.SilkS")
		)
		(fp_line
			(start 0 -0.999998)
			(end 0.508 -1.525016)
			(stroke
				(width 0.1524)
				(type default)
			)
			(layer "F.SilkS")
		)
		(fp_line
			(start 0.508 -1.525016)
			(end 1.3208 -1.525016)
			(stroke
				(width 0.1524)
				(type default)
			)
			(layer "F.SilkS")
		)
		(fp_line
			(start 1.3208 -1.525016)
			(end 1.3208 1.525016)
			(stroke
				(width 0.1524)
				(type default)
			)
			(layer "F.SilkS")
		)
		(fp_line
			(start 1.3208 1.525016)
			(end -1.3208 1.525016)
			(stroke
				(width 0.1524)
				(type default)
			)
			(layer "F.SilkS")
		)
		(fp_poly
			(pts
				(xy -2.850134 -1.390396) (xy -3.658362 -1.65989) (xy -3.119374 -2.198624)
			)
			(stroke
				(width 0)
				(type default)
			)
			(fill yes)
			(layer "F.SilkS")
		)
		(fp_line
			(start -3.037078 -1.20777)
			(end -1.524 -1.20777)
			(stroke
				(width 0.1)
				(type default)
			)
			(layer "F.Fab")
		)
		(fp_line
			(start -3.037078 1.203706)
			(end -3.037078 -1.20777)
			(stroke
				(width 0.1)
				(type default)
			)
			(layer "F.Fab")
		)
		(fp_line
			(start -1.5494 1.203706)
			(end -3.037078 1.203706)
			(stroke
				(width 0.1)
				(type default)
			)
			(layer "F.Fab")
		)
		(fp_line
			(start -1.5494 1.5494)
			(end -1.5494 1.203706)
			(stroke
				(width 0.1)
				(type default)
			)
			(layer "F.Fab")
		)
		(fp_line
			(start -1.524 -1.524)
			(end 1.524 -1.524)
			(stroke
				(width 0.1)
				(type default)
			)
			(layer "F.Fab")
		)
		(fp_line
			(start -1.524 -1.20777)
			(end -1.524 -1.524)
			(stroke
				(width 0.1)
				(type default)
			)
			(layer "F.Fab")
		)
		(fp_line
			(start 1.524 -1.524)
			(end 1.524 -1.20777)
			(stroke
				(width 0.1)
				(type default)
			)
			(layer "F.Fab")
		)
		(fp_line
			(start 1.524 -1.20777)
			(end 3.0353 -1.20777)
			(stroke
				(width 0.1)
				(type default)
			)
			(layer "F.Fab")
		)
		(fp_line
			(start 1.524 1.208786)
			(end 1.524 1.5494)
			(stroke
				(width 0.1)
				(type default)
			)
			(layer "F.Fab")
		)
		(fp_line
			(start 1.524 1.5494)
			(end -1.5494 1.5494)
			(stroke
				(width 0.1)
				(type default)
			)
			(layer "F.Fab")
		)
		(fp_line
			(start 3.0353 -1.20777)
			(end 3.0353 1.208786)
			(stroke
				(width 0.1)
				(type default)
			)
			(layer "F.Fab")
		)
		(fp_line
			(start 3.0353 1.208786)
			(end 1.524 1.208786)
			(stroke
				(width 0.1)
				(type default)
			)
			(layer "F.Fab")
		)
		(fp_poly
			(pts
				(xy -3.175 -1.016) (xy -3.937 -0.635) (xy -3.937 -1.397)
			)
			(stroke
				(width 0)
				(type default)
			)
			(fill yes)
			(layer "F.Fab")
		)
		(pad "1" smd rect
			(at -2.234946 -0.975106 270)
			(size 0.3556 1.4986)
			(layers "F.Cu" "F.Mask" "F.Paste")
			(net "P1V2_AUX")
		)
		(pad "2" smd rect
			(at -2.234946 -0.32512 270)
			(size 0.3556 1.4986)
			(layers "F.Cu" "F.Mask" "F.Paste")
			(net "SMB_NIC7_R_SDA")
		)
		(pad "3" smd rect
			(at -2.234946 0.32512 270)
			(size 0.3556 1.4986)
			(layers "F.Cu" "F.Mask" "F.Paste")
			(net "SMB_NIC7_R_SCL")
		)
		(pad "4" smd rect
			(at -2.234946 0.975106 270)
			(size 0.3556 1.4986)
			(layers "F.Cu" "F.Mask" "F.Paste")
			(net "GND")
		)
		(pad "5" smd rect
			(at 2.234946 0.975106 270)
			(size 0.3556 1.4986)
			(layers "F.Cu" "F.Mask" "F.Paste")
			(net "SMB_NIC7_LS_EN")
		)
		(pad "6" smd rect
			(at 2.234946 0.32512 270)
			(size 0.3556 1.4986)
			(layers "F.Cu" "F.Mask" "F.Paste")
			(net "SMB_NIC7_LS_R_SCL")
		)
		(pad "7" smd rect
			(at 2.234946 -0.32512 270)
			(size 0.3556 1.4986)
			(layers "F.Cu" "F.Mask" "F.Paste")
			(net "SMB_NIC7_LS_R_SDA")
		)
		(pad "8" smd rect
			(at 2.234946 -0.975106 270)
			(size 0.3556 1.4986)
			(layers "F.Cu" "F.Mask" "F.Paste")
			(net "P3V3_NIC7")
		)
	)
	(footprint ""
		(layer "F.Cu")
		(at 457.211684 -365.543084 90)
		(property "Reference" "R6692"
			(at 0 0 90)
			(layer "F.SilkS")
			(hide yes)
			(effects
				(font
					(size 1.27 1.27)
				)
			)
		)
		(property "Value" ""
			(at 0 0 90)
			(layer "F.Fab")
			(effects
				(font
					(size 1.27 1.27)
				)
			)
		)
		(duplicate_pad_numbers_are_jumpers no)
		(fp_line
			(start 0.7874 -0.4064)
			(end 0.7874 0.4064)
			(stroke
				(width 0.1524)
				(type default)
			)
			(layer "F.SilkS")
		)
		(fp_line
			(start -0.7874 -0.4064)
			(end 0.7874 -0.4064)
			(stroke
				(width 0.1524)
				(type default)
			)
			(layer "F.SilkS")
		)
		(fp_line
			(start 0.7874 0.4064)
			(end -0.7874 0.4064)
			(stroke
				(width 0.1524)
				(type default)
			)
			(layer "F.SilkS")
		)
		(fp_line
			(start -0.7874 0.4064)
			(end -0.7874 -0.4064)
			(stroke
				(width 0.1524)
				(type default)
			)
			(layer "F.SilkS")
		)
		(fp_line
			(start -0.12065 -0.305054)
			(end -0.12065 -0.2794)
			(stroke
				(width 0.1)
				(type default)
			)
			(layer "F.Fab")
		)
		(fp_line
			(start -0.67945 -0.305054)
			(end -0.12065 -0.305054)
			(stroke
				(width 0.1)
				(type default)
			)
			(layer "F.Fab")
		)
		(fp_line
			(start 0.67945 -0.3048)
			(end 0.67945 0.3048)
			(stroke
				(width 0.1)
				(type default)
			)
			(layer "F.Fab")
		)
		(fp_line
			(start 0.12065 -0.3048)
			(end 0.67945 -0.3048)
			(stroke
				(width 0.1)
				(type default)
			)
			(layer "F.Fab")
		)
		(fp_line
			(start 0.12065 -0.2794)
			(end 0.12065 -0.3048)
			(stroke
				(width 0.1)
				(type default)
			)
			(layer "F.Fab")
		)
		(fp_line
			(start -0.12065 -0.2794)
			(end 0.12065 -0.2794)
			(stroke
				(width 0.1)
				(type default)
			)
			(layer "F.Fab")
		)
		(fp_line
			(start 0.120396 0.2794)
			(end -0.12065 0.2794)
			(stroke
				(width 0.1)
				(type default)
			)
			(layer "F.Fab")
		)
		(fp_line
			(start -0.12065 0.2794)
			(end -0.12065 0.3048)
			(stroke
				(width 0.1)
				(type default)
			)
			(layer "F.Fab")
		)
		(fp_line
			(start 0.67945 0.3048)
			(end 0.120396 0.3048)
			(stroke
				(width 0.1)
				(type default)
			)
			(layer "F.Fab")
		)
		(fp_line
			(start 0.120396 0.3048)
			(end 0.120396 0.2794)
			(stroke
				(width 0.1)
				(type default)
			)
			(layer "F.Fab")
		)
		(fp_line
			(start -0.12065 0.3048)
			(end -0.67945 0.3048)
			(stroke
				(width 0.1)
				(type default)
			)
			(layer "F.Fab")
		)
		(fp_line
			(start -0.67945 0.3048)
			(end -0.67945 -0.305054)
			(stroke
				(width 0.1)
				(type default)
			)
			(layer "F.Fab")
		)
		(pad "1" smd circle
			(at -0.40005 0 90)
			(size 0 0)
			(layers "F.Cu" "F.Mask" "F.Paste")
			(net "GPU_3V3IO_RSVD4_ISO_R")
		)
		(pad "2" smd circle
			(at 0.40005 0 90)
			(size 0 0)
			(layers "F.Cu" "F.Mask" "F.Paste")
			(net "GPU_3V3IO_RSVD4_ISO")
		)
	)
	(footprint ""
		(layer "F.Cu")
		(at 171.255182 -53.468524 90)
		(property "Reference" "PC511"
			(at 0 0 90)
			(layer "F.SilkS")
			(hide yes)
			(effects
				(font
					(size 1.27 1.27)
				)
			)
		)
		(property "Value" ""
			(at 0 0 90)
			(layer "F.Fab")
			(effects
				(font
					(size 1.27 1.27)
				)
			)
		)
		(duplicate_pad_numbers_are_jumpers no)
		(fp_line
			(start 1.524 -0.762)
			(end 1.524 0.762)
			(stroke
				(width 0.1524)
				(type default)
			)
			(layer "F.SilkS")
		)
		(fp_line
			(start -1.524 -0.762)
			(end 1.524 -0.762)
			(stroke
				(width 0.1524)
				(type default)
			)
			(layer "F.SilkS")
		)
		(fp_line
			(start 1.524 0.762)
			(end -1.524 0.762)
			(stroke
				(width 0.1524)
				(type default)
			)
			(layer "F.SilkS")
		)
		(fp_line
			(start -1.524 0.762)
			(end -1.524 -0.762)
			(stroke
				(width 0.1524)
				(type default)
			)
			(layer "F.SilkS")
		)
		(fp_line
			(start 1.1049 -0.724916)
			(end -1.1049 -0.724916)
			(stroke
				(width 0.1)
				(type default)
			)
			(layer "F.Fab")
		)
		(fp_line
			(start -1.1049 -0.724916)
			(end -1.1049 0.724916)
			(stroke
				(width 0.1)
				(type default)
			)
			(layer "F.Fab")
		)
		(fp_line
			(start 1.1049 0.724916)
			(end 1.1049 -0.724916)
			(stroke
				(width 0.1)
				(type default)
			)
			(layer "F.Fab")
		)
		(fp_line
			(start -1.1049 0.724916)
			(end 1.1049 0.724916)
			(stroke
				(width 0.1)
				(type default)
			)
			(layer "F.Fab")
		)
		(pad "1" smd rect
			(at -0.889 0 270)
			(size 1.016 1.27)
			(layers "F.Cu" "F.Mask" "F.Paste")
			(net "GND")
		)
		(pad "2" smd rect
			(at 0.889 0 270)
			(size 1.016 1.27)
			(layers "F.Cu" "F.Mask" "F.Paste")
			(net "P3V3_AUX")
		)
	)
	(footprint ""
		(layer "F.Cu")
		(at 399.639282 -177.428398 -90)
		(property "Reference" "Q7"
			(at 0.542798 1.721612 90)
			(unlocked yes)
			(layer "F.SilkS")
			(effects
				(font
					(size 0.7874 0.5842)
					(thickness 0.1524)
				)
				(justify left)
			)
		)
		(property "Value" ""
			(at 0 0 270)
			(layer "F.Fab")
			(effects
				(font
					(size 1.27 1.27)
				)
			)
		)
		(duplicate_pad_numbers_are_jumpers no)
		(fp_line
			(start -1.38176 1.100074)
			(end 1.38176 1.100074)
			(stroke
				(width 0.1524)
				(type default)
			)
			(layer "F.SilkS")
		)
		(fp_line
			(start 1.38176 1.100074)
			(end 1.38176 -1.100074)
			(stroke
				(width 0.1524)
				(type default)
			)
			(layer "F.SilkS")
		)
		(fp_line
			(start 0 -0.508)
			(end -0.592074 -1.100074)
			(stroke
				(width 0.1524)
				(type default)
			)
			(layer "F.SilkS")
		)
		(fp_line
			(start -1.38176 -1.100074)
			(end -1.38176 1.100074)
			(stroke
				(width 0.1524)
				(type default)
			)
			(layer "F.SilkS")
		)
		(fp_line
			(start -0.592074 -1.100074)
			(end -1.38176 -1.100074)
			(stroke
				(width 0.1524)
				(type default)
			)
			(layer "F.SilkS")
		)
		(fp_line
			(start 0.592074 -1.100074)
			(end 0 -0.508)
			(stroke
				(width 0.1524)
				(type default)
			)
			(layer "F.SilkS")
		)
		(fp_line
			(start 1.38176 -1.100074)
			(end 0.592074 -1.100074)
			(stroke
				(width 0.1524)
				(type default)
			)
			(layer "F.SilkS")
		)
		(fp_poly
			(pts
				(xy -0.68453 -1.603756) (xy -0.904748 -1.163066) (xy -1.124966 -1.603756)
			)
			(stroke
				(width 0)
				(type default)
			)
			(fill yes)
			(layer "F.SilkS")
		)
		(fp_line
			(start -0.674878 1.100074)
			(end 0.674878 1.100074)
			(stroke
				(width 0.1)
				(type default)
			)
			(layer "F.Fab")
		)
		(fp_line
			(start 0.674878 1.100074)
			(end 0.674878 -1.100074)
			(stroke
				(width 0.1)
				(type default)
			)
			(layer "F.Fab")
		)
		(fp_line
			(start -0.674878 -1.100074)
			(end -0.674878 1.100074)
			(stroke
				(width 0.1)
				(type default)
			)
			(layer "F.Fab")
		)
		(fp_line
			(start 0.674878 -1.100074)
			(end -0.674878 -1.100074)
			(stroke
				(width 0.1)
				(type default)
			)
			(layer "F.Fab")
		)
		(fp_poly
			(pts
				(xy -1.9431 -0.870204) (xy -1.50241 -0.649986) (xy -1.9431 -0.429768)
			)
			(stroke
				(width 0)
				(type default)
			)
			(fill yes)
			(layer "F.Fab")
		)
		(pad "1" smd rect
			(at -0.94996 -0.649986 180)
			(size 0.4318 0.6096)
			(layers "F.Cu" "F.Mask" "F.Paste")
			(net "GND")
		)
		(pad "2" smd rect
			(at -0.94996 0 180)
			(size 0.4318 0.6096)
			(layers "F.Cu" "F.Mask" "F.Paste")
			(net "HP_NIC6_HSC_PWRGD_N")
		)
		(pad "3" smd rect
			(at -0.94996 0.649986 180)
			(size 0.4318 0.6096)
			(layers "F.Cu" "F.Mask" "F.Paste")
			(net "HP_NIC6_HSC_PWRGD_N")
		)
		(pad "4" smd rect
			(at 0.94996 0.649986 180)
			(size 0.4318 0.6096)
			(layers "F.Cu" "F.Mask" "F.Paste")
			(net "GND")
		)
		(pad "5" smd rect
			(at 0.94996 0 180)
			(size 0.4318 0.6096)
			(layers "F.Cu" "F.Mask" "F.Paste")
			(net "PWRGD_P12V_NIC6_R")
		)
		(pad "6" smd rect
			(at 0.94996 -0.649986 180)
			(size 0.4318 0.6096)
			(layers "F.Cu" "F.Mask" "F.Paste")
			(net "HP_NIC6_PWRGD_R")
		)
	)
	(footprint ""
		(layer "F.Cu")
		(at 220.36786 -55.083456)
		(property "Reference" "PC384"
			(at 0 0 0)
			(layer "F.SilkS")
			(hide yes)
			(effects
				(font
					(size 1.27 1.27)
				)
			)
		)
		(property "Value" ""
			(at 0 0 0)
			(layer "F.Fab")
			(effects
				(font
					(size 1.27 1.27)
				)
			)
		)
		(duplicate_pad_numbers_are_jumpers no)
		(fp_line
			(start -0.7874 -0.4064)
			(end 0.7874 -0.4064)
			(stroke
				(width 0.1524)
				(type default)
			)
			(layer "F.SilkS")
		)
		(fp_line
			(start -0.7874 0.4064)
			(end -0.7874 -0.4064)
			(stroke
				(width 0.1524)
				(type default)
			)
			(layer "F.SilkS")
		)
		(fp_line
			(start 0.7874 -0.4064)
			(end 0.7874 0.4064)
			(stroke
				(width 0.1524)
				(type default)
			)
			(layer "F.SilkS")
		)
		(fp_line
			(start 0.7874 0.4064)
			(end -0.7874 0.4064)
			(stroke
				(width 0.1524)
				(type default)
			)
			(layer "F.SilkS")
		)
		(fp_line
			(start -0.67945 -0.305054)
			(end -0.12065 -0.305054)
			(stroke
				(width 0.1)
				(type default)
			)
			(layer "F.Fab")
		)
		(fp_line
			(start -0.67945 0.3048)
			(end -0.67945 -0.305054)
			(stroke
				(width 0.1)
				(type default)
			)
			(layer "F.Fab")
		)
		(fp_line
			(start -0.12065 -0.305054)
			(end -0.12065 -0.2794)
			(stroke
				(width 0.1)
				(type default)
			)
			(layer "F.Fab")
		)
		(fp_line
			(start -0.12065 -0.2794)
			(end 0.12065 -0.2794)
			(stroke
				(width 0.1)
				(type default)
			)
			(layer "F.Fab")
		)
		(fp_line
			(start -0.12065 0.2794)
			(end -0.12065 0.3048)
			(stroke
				(width 0.1)
				(type default)
			)
			(layer "F.Fab")
		)
		(fp_line
			(start -0.12065 0.3048)
			(end -0.67945 0.3048)
			(stroke
				(width 0.1)
				(type default)
			)
			(layer "F.Fab")
		)
		(fp_line
			(start 0.120396 0.2794)
			(end -0.12065 0.2794)
			(stroke
				(width 0.1)
				(type default)
			)
			(layer "F.Fab")
		)
		(fp_line
			(start 0.120396 0.3048)
			(end 0.120396 0.2794)
			(stroke
				(width 0.1)
				(type default)
			)
			(layer "F.Fab")
		)
		(fp_line
			(start 0.12065 -0.3048)
			(end 0.67945 -0.3048)
			(stroke
				(width 0.1)
				(type default)
			)
			(layer "F.Fab")
		)
		(fp_line
			(start 0.12065 -0.2794)
			(end 0.12065 -0.3048)
			(stroke
				(width 0.1)
				(type default)
			)
			(layer "F.Fab")
		)
		(fp_line
			(start 0.67945 -0.3048)
			(end 0.67945 0.3048)
			(stroke
				(width 0.1)
				(type default)
			)
			(layer "F.Fab")
		)
		(fp_line
			(start 0.67945 0.3048)
			(end 0.120396 0.3048)
			(stroke
				(width 0.1)
				(type default)
			)
			(layer "F.Fab")
		)
		(pad "1" smd circle
			(at -0.40005 0)
			(size 0 0)
			(layers "F.Cu" "F.Mask" "F.Paste")
			(net "P5V_AUX")
		)
		(pad "2" smd circle
			(at 0.40005 0)
			(size 0 0)
			(layers "F.Cu" "F.Mask" "F.Paste")
			(net "GND")
		)
	)
	(footprint ""
		(layer "F.Cu")
		(at 336.467704 -54.067456)
		(property "Reference" "PR237"
			(at 0 0 0)
			(layer "F.SilkS")
			(hide yes)
			(effects
				(font
					(size 1.27 1.27)
				)
			)
		)
		(property "Value" ""
			(at 0 0 0)
			(layer "F.Fab")
			(effects
				(font
					(size 1.27 1.27)
				)
			)
		)
		(duplicate_pad_numbers_are_jumpers no)
		(fp_line
			(start -0.7874 -0.4064)
			(end 0.7874 -0.4064)
			(stroke
				(width 0.1524)
				(type default)
			)
			(layer "F.SilkS")
		)
		(fp_line
			(start -0.7874 0.4064)
			(end -0.7874 -0.4064)
			(stroke
				(width 0.1524)
				(type default)
			)
			(layer "F.SilkS")
		)
		(fp_line
			(start 0.7874 -0.4064)
			(end 0.7874 0.4064)
			(stroke
				(width 0.1524)
				(type default)
			)
			(layer "F.SilkS")
		)
		(fp_line
			(start 0.7874 0.4064)
			(end -0.7874 0.4064)
			(stroke
				(width 0.1524)
				(type default)
			)
			(layer "F.SilkS")
		)
		(fp_line
			(start -0.67945 -0.305054)
			(end -0.12065 -0.305054)
			(stroke
				(width 0.1)
				(type default)
			)
			(layer "F.Fab")
		)
		(fp_line
			(start -0.67945 0.3048)
			(end -0.67945 -0.305054)
			(stroke
				(width 0.1)
				(type default)
			)
			(layer "F.Fab")
		)
		(fp_line
			(start -0.12065 -0.305054)
			(end -0.12065 -0.2794)
			(stroke
				(width 0.1)
				(type default)
			)
			(layer "F.Fab")
		)
		(fp_line
			(start -0.12065 -0.2794)
			(end 0.12065 -0.2794)
			(stroke
				(width 0.1)
				(type default)
			)
			(layer "F.Fab")
		)
		(fp_line
			(start -0.12065 0.2794)
			(end -0.12065 0.3048)
			(stroke
				(width 0.1)
				(type default)
			)
			(layer "F.Fab")
		)
		(fp_line
			(start -0.12065 0.3048)
			(end -0.67945 0.3048)
			(stroke
				(width 0.1)
				(type default)
			)
			(layer "F.Fab")
		)
		(fp_line
			(start 0.120396 0.2794)
			(end -0.12065 0.2794)
			(stroke
				(width 0.1)
				(type default)
			)
			(layer "F.Fab")
		)
		(fp_line
			(start 0.120396 0.3048)
			(end 0.120396 0.2794)
			(stroke
				(width 0.1)
				(type default)
			)
			(layer "F.Fab")
		)
		(fp_line
			(start 0.12065 -0.3048)
			(end 0.67945 -0.3048)
			(stroke
				(width 0.1)
				(type default)
			)
			(layer "F.Fab")
		)
		(fp_line
			(start 0.12065 -0.2794)
			(end 0.12065 -0.3048)
			(stroke
				(width 0.1)
				(type default)
			)
			(layer "F.Fab")
		)
		(fp_line
			(start 0.67945 -0.3048)
			(end 0.67945 0.3048)
			(stroke
				(width 0.1)
				(type default)
			)
			(layer "F.Fab")
		)
		(fp_line
			(start 0.67945 0.3048)
			(end 0.120396 0.3048)
			(stroke
				(width 0.1)
				(type default)
			)
			(layer "F.Fab")
		)
		(pad "1" smd circle
			(at -0.40005 0)
			(size 0 0)
			(layers "F.Cu" "F.Mask" "F.Paste")
			(net "P12V_SSD11_OCP")
		)
		(pad "2" smd circle
			(at 0.40005 0)
			(size 0 0)
			(layers "F.Cu" "F.Mask" "F.Paste")
			(net "GND")
		)
	)
	(footprint ""
		(layer "F.Cu")
		(at 240.306606 -80.451706 180)
		(property "Reference" "R1002"
			(at 0 0 180)
			(layer "F.SilkS")
			(hide yes)
			(effects
				(font
					(size 1.27 1.27)
				)
			)
		)
		(property "Value" ""
			(at 0 0 180)
			(layer "F.Fab")
			(effects
				(font
					(size 1.27 1.27)
				)
			)
		)
		(duplicate_pad_numbers_are_jumpers no)
		(fp_line
			(start 0.7874 0.4064)
			(end -0.7874 0.4064)
			(stroke
				(width 0.1524)
				(type default)
			)
			(layer "F.SilkS")
		)
		(fp_line
			(start 0.7874 -0.4064)
			(end 0.7874 0.4064)
			(stroke
				(width 0.1524)
				(type default)
			)
			(layer "F.SilkS")
		)
		(fp_line
			(start -0.7874 0.4064)
			(end -0.7874 -0.4064)
			(stroke
				(width 0.1524)
				(type default)
			)
			(layer "F.SilkS")
		)
		(fp_line
			(start -0.7874 -0.4064)
			(end 0.7874 -0.4064)
			(stroke
				(width 0.1524)
				(type default)
			)
			(layer "F.SilkS")
		)
		(fp_line
			(start 0.67945 0.3048)
			(end 0.120396 0.3048)
			(stroke
				(width 0.1)
				(type default)
			)
			(layer "F.Fab")
		)
		(fp_line
			(start 0.67945 -0.3048)
			(end 0.67945 0.3048)
			(stroke
				(width 0.1)
				(type default)
			)
			(layer "F.Fab")
		)
		(fp_line
			(start 0.12065 -0.2794)
			(end 0.12065 -0.3048)
			(stroke
				(width 0.1)
				(type default)
			)
			(layer "F.Fab")
		)
		(fp_line
			(start 0.12065 -0.3048)
			(end 0.67945 -0.3048)
			(stroke
				(width 0.1)
				(type default)
			)
			(layer "F.Fab")
		)
		(fp_line
			(start 0.120396 0.3048)
			(end 0.120396 0.2794)
			(stroke
				(width 0.1)
				(type default)
			)
			(layer "F.Fab")
		)
		(fp_line
			(start 0.120396 0.2794)
			(end -0.12065 0.2794)
			(stroke
				(width 0.1)
				(type default)
			)
			(layer "F.Fab")
		)
		(fp_line
			(start -0.12065 0.3048)
			(end -0.67945 0.3048)
			(stroke
				(width 0.1)
				(type default)
			)
			(layer "F.Fab")
		)
		(fp_line
			(start -0.12065 0.2794)
			(end -0.12065 0.3048)
			(stroke
				(width 0.1)
				(type default)
			)
			(layer "F.Fab")
		)
		(fp_line
			(start -0.12065 -0.2794)
			(end 0.12065 -0.2794)
			(stroke
				(width 0.1)
				(type default)
			)
			(layer "F.Fab")
		)
		(fp_line
			(start -0.12065 -0.305054)
			(end -0.12065 -0.2794)
			(stroke
				(width 0.1)
				(type default)
			)
			(layer "F.Fab")
		)
		(fp_line
			(start -0.67945 0.3048)
			(end -0.67945 -0.305054)
			(stroke
				(width 0.1)
				(type default)
			)
			(layer "F.Fab")
		)
		(fp_line
			(start -0.67945 -0.305054)
			(end -0.12065 -0.305054)
			(stroke
				(width 0.1)
				(type default)
			)
			(layer "F.Fab")
		)
		(pad "1" smd circle
			(at -0.40005 0 180)
			(size 0 0)
			(layers "F.Cu" "F.Mask" "F.Paste")
			(net "PEX_USB2_SEL_CONN")
		)
		(pad "2" smd circle
			(at 0.40005 0 180)
			(size 0 0)
			(layers "F.Cu" "F.Mask" "F.Paste")
			(net "P3V3_AUX")
		)
	)
	(footprint ""
		(layer "F.Cu")
		(at 363.474 -205.867)
		(property "Reference" "R4605"
			(at 0 0 0)
			(layer "F.SilkS")
			(hide yes)
			(effects
				(font
					(size 1.27 1.27)
				)
			)
		)
		(property "Value" ""
			(at 0 0 0)
			(layer "F.Fab")
			(effects
				(font
					(size 1.27 1.27)
				)
			)
		)
		(duplicate_pad_numbers_are_jumpers no)
		(fp_line
			(start -0.7874 -0.4064)
			(end 0.7874 -0.4064)
			(stroke
				(width 0.1524)
				(type default)
			)
			(layer "F.SilkS")
		)
		(fp_line
			(start -0.7874 0.4064)
			(end -0.7874 -0.4064)
			(stroke
				(width 0.1524)
				(type default)
			)
			(layer "F.SilkS")
		)
		(fp_line
			(start 0.7874 -0.4064)
			(end 0.7874 0.4064)
			(stroke
				(width 0.1524)
				(type default)
			)
			(layer "F.SilkS")
		)
		(fp_line
			(start 0.7874 0.4064)
			(end -0.7874 0.4064)
			(stroke
				(width 0.1524)
				(type default)
			)
			(layer "F.SilkS")
		)
		(fp_line
			(start -0.67945 -0.305054)
			(end -0.12065 -0.305054)
			(stroke
				(width 0.1)
				(type default)
			)
			(layer "F.Fab")
		)
		(fp_line
			(start -0.67945 0.3048)
			(end -0.67945 -0.305054)
			(stroke
				(width 0.1)
				(type default)
			)
			(layer "F.Fab")
		)
		(fp_line
			(start -0.12065 -0.305054)
			(end -0.12065 -0.2794)
			(stroke
				(width 0.1)
				(type default)
			)
			(layer "F.Fab")
		)
		(fp_line
			(start -0.12065 -0.2794)
			(end 0.12065 -0.2794)
			(stroke
				(width 0.1)
				(type default)
			)
			(layer "F.Fab")
		)
		(fp_line
			(start -0.12065 0.2794)
			(end -0.12065 0.3048)
			(stroke
				(width 0.1)
				(type default)
			)
			(layer "F.Fab")
		)
		(fp_line
			(start -0.12065 0.3048)
			(end -0.67945 0.3048)
			(stroke
				(width 0.1)
				(type default)
			)
			(layer "F.Fab")
		)
		(fp_line
			(start 0.120396 0.2794)
			(end -0.12065 0.2794)
			(stroke
				(width 0.1)
				(type default)
			)
			(layer "F.Fab")
		)
		(fp_line
			(start 0.120396 0.3048)
			(end 0.120396 0.2794)
			(stroke
				(width 0.1)
				(type default)
			)
			(layer "F.Fab")
		)
		(fp_line
			(start 0.12065 -0.3048)
			(end 0.67945 -0.3048)
			(stroke
				(width 0.1)
				(type default)
			)
			(layer "F.Fab")
		)
		(fp_line
			(start 0.12065 -0.2794)
			(end 0.12065 -0.3048)
			(stroke
				(width 0.1)
				(type default)
			)
			(layer "F.Fab")
		)
		(fp_line
			(start 0.67945 -0.3048)
			(end 0.67945 0.3048)
			(stroke
				(width 0.1)
				(type default)
			)
			(layer "F.Fab")
		)
		(fp_line
			(start 0.67945 0.3048)
			(end 0.120396 0.3048)
			(stroke
				(width 0.1)
				(type default)
			)
			(layer "F.Fab")
		)
		(pad "1" smd circle
			(at -0.40005 0)
			(size 0 0)
			(layers "F.Cu" "F.Mask" "F.Paste")
			(net "P3V3_AUX")
		)
		(pad "2" smd circle
			(at 0.40005 0)
			(size 0 0)
			(layers "F.Cu" "F.Mask" "F.Paste")
			(net "RST_PEX_SSD1_PERST_R_N")
		)
	)
	(footprint ""
		(layer "F.Cu")
		(at 368.875564 -69.47916 180)
		(property "Reference" "PU115"
			(at -1.813306 4.13004 90)
			(unlocked yes)
			(layer "F.SilkS")
			(effects
				(font
					(size 0.7874 0.5842)
					(thickness 0.1524)
				)
			)
		)
		(property "Value" ""
			(at 0 0 180)
			(layer "F.Fab")
			(effects
				(font
					(size 1.27 1.27)
				)
			)
		)
		(duplicate_pad_numbers_are_jumpers no)
		(fp_line
			(start 1.239774 1.495298)
			(end -1.239774 1.495298)
			(stroke
				(width 0.1524)
				(type default)
			)
			(layer "F.SilkS")
		)
		(fp_line
			(start 1.239774 -1.495298)
			(end 1.239774 1.495298)
			(stroke
				(width 0.1524)
				(type default)
			)
			(layer "F.SilkS")
		)
		(fp_line
			(start -1.239774 1.495298)
			(end -1.239774 -1.495298)
			(stroke
				(width 0.1524)
				(type default)
			)
			(layer "F.SilkS")
		)
		(fp_line
			(start -1.239774 -1.495298)
			(end 1.239774 -1.495298)
			(stroke
				(width 0.1524)
				(type default)
			)
			(layer "F.SilkS")
		)
		(fp_poly
			(pts
				(xy -1.746758 -2.302256) (xy -2.465324 -1.58369) (xy -1.387602 -1.224534)
			)
			(stroke
				(width 0)
				(type default)
			)
			(fill yes)
			(layer "F.SilkS")
		)
		(fp_line
			(start 0.8001 1.050036)
			(end -0.8001 1.050036)
			(stroke
				(width 0.1)
				(type default)
			)
			(layer "F.Fab")
		)
		(fp_line
			(start 0.8001 -1.050036)
			(end 0.8001 1.050036)
			(stroke
				(width 0.1)
				(type default)
			)
			(layer "F.Fab")
		)
		(fp_line
			(start -0.8001 1.050036)
			(end -0.8001 -1.050036)
			(stroke
				(width 0.1)
				(type default)
			)
			(layer "F.Fab")
		)
		(fp_line
			(start -0.8001 -1.050036)
			(end 0.8001 -1.050036)
			(stroke
				(width 0.1)
				(type default)
			)
			(layer "F.Fab")
		)
		(fp_poly
			(pts
				(xy -2.458974 -0.508) (xy -2.458974 0.508) (xy -1.442974 0)
			)
			(stroke
				(width 0)
				(type default)
			)
			(fill yes)
			(layer "F.Fab")
		)
		(pad "1_2" smd circle
			(at -0.374904 0 270)
			(size 0 0)
			(layers "F.Cu" "F.Mask" "F.Paste")
			(net "P12V_AUX")
		)
		(pad "3" smd rect
			(at -0.499872 0.999998 180)
			(size 0.254 0.7112)
			(layers "F.Cu" "F.Mask" "F.Paste")
			(net "GND")
		)
		(pad "4" smd rect
			(at 0 0.999998 180)
			(size 0.254 0.7112)
			(layers "F.Cu" "F.Mask" "F.Paste")
			(net "P12V_SSD12_CO_ILIMIT")
		)
		(pad "5" smd rect
			(at 0.499872 0.999998 180)
			(size 0.254 0.7112)
			(layers "F.Cu" "F.Mask" "F.Paste")
			(net "P12V_SSD12_CO_MODE")
		)
		(pad "6_7" smd circle
			(at 0.374904 0 90)
			(size 0 0)
			(layers "F.Cu" "F.Mask" "F.Paste")
			(net "P12V_SSD12_R")
		)
		(pad "8" smd rect
			(at 0.499872 -0.999998 180)
			(size 0.254 0.7112)
			(layers "F.Cu" "F.Mask" "F.Paste")
			(net "P12V_SSD12_CO_GATE")
		)
		(pad "9" smd rect
			(at 0 -0.999998 180)
			(size 0.254 0.7112)
			(layers "F.Cu" "F.Mask" "F.Paste")
			(net "P12V_SSD12_CO_EN")
		)
		(pad "10" smd rect
			(at -0.499872 -0.999998 180)
			(size 0.254 0.7112)
			(layers "F.Cu" "F.Mask" "F.Paste")
			(net "P12V_SSD12_CO_DV_DT")
		)
	)
	(footprint ""
		(layer "F.Cu")
		(at 226.029266 -104.328722 90)
		(property "Reference" "PC340"
			(at 0 0 90)
			(layer "F.SilkS")
			(hide yes)
			(effects
				(font
					(size 1.27 1.27)
				)
			)
		)
		(property "Value" ""
			(at 0 0 90)
			(layer "F.Fab")
			(effects
				(font
					(size 1.27 1.27)
				)
			)
		)
		(duplicate_pad_numbers_are_jumpers no)
		(fp_line
			(start 0.7874 -0.4064)
			(end 0.7874 0.4064)
			(stroke
				(width 0.1524)
				(type default)
			)
			(layer "F.SilkS")
		)
		(fp_line
			(start -0.7874 -0.4064)
			(end 0.7874 -0.4064)
			(stroke
				(width 0.1524)
				(type default)
			)
			(layer "F.SilkS")
		)
		(fp_line
			(start 0.7874 0.4064)
			(end -0.7874 0.4064)
			(stroke
				(width 0.1524)
				(type default)
			)
			(layer "F.SilkS")
		)
		(fp_line
			(start -0.7874 0.4064)
			(end -0.7874 -0.4064)
			(stroke
				(width 0.1524)
				(type default)
			)
			(layer "F.SilkS")
		)
		(fp_line
			(start -0.12065 -0.305054)
			(end -0.12065 -0.2794)
			(stroke
				(width 0.1)
				(type default)
			)
			(layer "F.Fab")
		)
		(fp_line
			(start -0.67945 -0.305054)
			(end -0.12065 -0.305054)
			(stroke
				(width 0.1)
				(type default)
			)
			(layer "F.Fab")
		)
		(fp_line
			(start 0.67945 -0.3048)
			(end 0.67945 0.3048)
			(stroke
				(width 0.1)
				(type default)
			)
			(layer "F.Fab")
		)
		(fp_line
			(start 0.12065 -0.3048)
			(end 0.67945 -0.3048)
			(stroke
				(width 0.1)
				(type default)
			)
			(layer "F.Fab")
		)
		(fp_line
			(start 0.12065 -0.2794)
			(end 0.12065 -0.3048)
			(stroke
				(width 0.1)
				(type default)
			)
			(layer "F.Fab")
		)
		(fp_line
			(start -0.12065 -0.2794)
			(end 0.12065 -0.2794)
			(stroke
				(width 0.1)
				(type default)
			)
			(layer "F.Fab")
		)
		(fp_line
			(start 0.120396 0.2794)
			(end -0.12065 0.2794)
			(stroke
				(width 0.1)
				(type default)
			)
			(layer "F.Fab")
		)
		(fp_line
			(start -0.12065 0.2794)
			(end -0.12065 0.3048)
			(stroke
				(width 0.1)
				(type default)
			)
			(layer "F.Fab")
		)
		(fp_line
			(start 0.67945 0.3048)
			(end 0.120396 0.3048)
			(stroke
				(width 0.1)
				(type default)
			)
			(layer "F.Fab")
		)
		(fp_line
			(start 0.120396 0.3048)
			(end 0.120396 0.2794)
			(stroke
				(width 0.1)
				(type default)
			)
			(layer "F.Fab")
		)
		(fp_line
			(start -0.12065 0.3048)
			(end -0.67945 0.3048)
			(stroke
				(width 0.1)
				(type default)
			)
			(layer "F.Fab")
		)
		(fp_line
			(start -0.67945 0.3048)
			(end -0.67945 -0.305054)
			(stroke
				(width 0.1)
				(type default)
			)
			(layer "F.Fab")
		)
		(pad "1" smd circle
			(at -0.40005 0 90)
			(size 0 0)
			(layers "F.Cu" "F.Mask" "F.Paste")
			(net "P12V_AUX")
		)
		(pad "2" smd circle
			(at 0.40005 0 90)
			(size 0 0)
			(layers "F.Cu" "F.Mask" "F.Paste")
			(net "GND")
		)
	)
	(footprint ""
		(layer "F.Cu")
		(at 144.53108 -188.752988)
		(property "Reference" "R6666"
			(at 0 0 0)
			(layer "F.SilkS")
			(hide yes)
			(effects
				(font
					(size 1.27 1.27)
				)
			)
		)
		(property "Value" ""
			(at 0 0 0)
			(layer "F.Fab")
			(effects
				(font
					(size 1.27 1.27)
				)
			)
		)
		(duplicate_pad_numbers_are_jumpers no)
		(fp_line
			(start -0.7874 -0.4064)
			(end 0.7874 -0.4064)
			(stroke
				(width 0.1524)
				(type default)
			)
			(layer "F.SilkS")
		)
		(fp_line
			(start -0.7874 0.4064)
			(end -0.7874 -0.4064)
			(stroke
				(width 0.1524)
				(type default)
			)
			(layer "F.SilkS")
		)
		(fp_line
			(start 0.7874 -0.4064)
			(end 0.7874 0.4064)
			(stroke
				(width 0.1524)
				(type default)
			)
			(layer "F.SilkS")
		)
		(fp_line
			(start 0.7874 0.4064)
			(end -0.7874 0.4064)
			(stroke
				(width 0.1524)
				(type default)
			)
			(layer "F.SilkS")
		)
		(fp_line
			(start -0.67945 -0.305054)
			(end -0.12065 -0.305054)
			(stroke
				(width 0.1)
				(type default)
			)
			(layer "F.Fab")
		)
		(fp_line
			(start -0.67945 0.3048)
			(end -0.67945 -0.305054)
			(stroke
				(width 0.1)
				(type default)
			)
			(layer "F.Fab")
		)
		(fp_line
			(start -0.12065 -0.305054)
			(end -0.12065 -0.2794)
			(stroke
				(width 0.1)
				(type default)
			)
			(layer "F.Fab")
		)
		(fp_line
			(start -0.12065 -0.2794)
			(end 0.12065 -0.2794)
			(stroke
				(width 0.1)
				(type default)
			)
			(layer "F.Fab")
		)
		(fp_line
			(start -0.12065 0.2794)
			(end -0.12065 0.3048)
			(stroke
				(width 0.1)
				(type default)
			)
			(layer "F.Fab")
		)
		(fp_line
			(start -0.12065 0.3048)
			(end -0.67945 0.3048)
			(stroke
				(width 0.1)
				(type default)
			)
			(layer "F.Fab")
		)
		(fp_line
			(start 0.120396 0.2794)
			(end -0.12065 0.2794)
			(stroke
				(width 0.1)
				(type default)
			)
			(layer "F.Fab")
		)
		(fp_line
			(start 0.120396 0.3048)
			(end 0.120396 0.2794)
			(stroke
				(width 0.1)
				(type default)
			)
			(layer "F.Fab")
		)
		(fp_line
			(start 0.12065 -0.3048)
			(end 0.67945 -0.3048)
			(stroke
				(width 0.1)
				(type default)
			)
			(layer "F.Fab")
		)
		(fp_line
			(start 0.12065 -0.2794)
			(end 0.12065 -0.3048)
			(stroke
				(width 0.1)
				(type default)
			)
			(layer "F.Fab")
		)
		(fp_line
			(start 0.67945 -0.3048)
			(end 0.67945 0.3048)
			(stroke
				(width 0.1)
				(type default)
			)
			(layer "F.Fab")
		)
		(fp_line
			(start 0.67945 0.3048)
			(end 0.120396 0.3048)
			(stroke
				(width 0.1)
				(type default)
			)
			(layer "F.Fab")
		)
		(pad "1" smd circle
			(at -0.40005 0)
			(size 0 0)
			(layers "F.Cu" "F.Mask" "F.Paste")
			(net "NIC5_CLK_EN_BUF_N")
		)
		(pad "2" smd circle
			(at 0.40005 0)
			(size 0 0)
			(layers "F.Cu" "F.Mask" "F.Paste")
			(net "NIC5_CLK_EN_BUF_R_N")
		)
	)
	(footprint ""
		(layer "F.Cu")
		(at 268.53515 -83.351624 180)
		(property "Reference" "R1072"
			(at 0 0 180)
			(layer "F.SilkS")
			(hide yes)
			(effects
				(font
					(size 1.27 1.27)
				)
			)
		)
		(property "Value" ""
			(at 0 0 180)
			(layer "F.Fab")
			(effects
				(font
					(size 1.27 1.27)
				)
			)
		)
		(duplicate_pad_numbers_are_jumpers no)
		(fp_line
			(start -0.7874 -0.4064)
			(end 0.7874 -0.4064)
			(stroke
				(width 0.1524)
				(type default)
			)
			(layer "F.SilkS")
		)
		(fp_line
			(start 0.67945 0.3048)
			(end 0.120396 0.3048)
			(stroke
				(width 0.1)
				(type default)
			)
			(layer "F.Fab")
		)
		(fp_line
			(start 0.67945 -0.3048)
			(end 0.67945 0.3048)
			(stroke
				(width 0.1)
				(type default)
			)
			(layer "F.Fab")
		)
		(fp_line
			(start 0.12065 -0.2794)
			(end 0.12065 -0.3048)
			(stroke
				(width 0.1)
				(type default)
			)
			(layer "F.Fab")
		)
		(fp_line
			(start 0.12065 -0.3048)
			(end 0.67945 -0.3048)
			(stroke
				(width 0.1)
				(type default)
			)
			(layer "F.Fab")
		)
		(fp_line
			(start 0.120396 0.3048)
			(end 0.120396 0.2794)
			(stroke
				(width 0.1)
				(type default)
			)
			(layer "F.Fab")
		)
		(fp_line
			(start 0.120396 0.2794)
			(end -0.12065 0.2794)
			(stroke
				(width 0.1)
				(type default)
			)
			(layer "F.Fab")
		)
		(fp_line
			(start -0.12065 0.3048)
			(end -0.67945 0.3048)
			(stroke
				(width 0.1)
				(type default)
			)
			(layer "F.Fab")
		)
		(fp_line
			(start -0.12065 0.2794)
			(end -0.12065 0.3048)
			(stroke
				(width 0.1)
				(type default)
			)
			(layer "F.Fab")
		)
		(fp_line
			(start -0.12065 -0.2794)
			(end 0.12065 -0.2794)
			(stroke
				(width 0.1)
				(type default)
			)
			(layer "F.Fab")
		)
		(fp_line
			(start -0.12065 -0.305054)
			(end -0.12065 -0.2794)
			(stroke
				(width 0.1)
				(type default)
			)
			(layer "F.Fab")
		)
		(fp_line
			(start -0.67945 0.3048)
			(end -0.67945 -0.305054)
			(stroke
				(width 0.1)
				(type default)
			)
			(layer "F.Fab")
		)
		(fp_line
			(start -0.67945 -0.305054)
			(end -0.12065 -0.305054)
			(stroke
				(width 0.1)
				(type default)
			)
			(layer "F.Fab")
		)
		(pad "1" smd circle
			(at -0.40005 0 180)
			(size 0 0)
			(layers "F.Cu" "F.Mask" "F.Paste")
			(net "CLK_100M_CK440Q_0_DB2000QL_R_DN")
		)
		(pad "2" smd circle
			(at 0.40005 0 180)
			(size 0 0)
			(layers "F.Cu" "F.Mask" "F.Paste")
			(net "CLK_100M_CK440Q_0_DB2000QL_DN")
		)
	)
	(footprint ""
		(layer "F.Cu")
		(at 417.92271 -22.867366 90)
		(property "Reference" "C3976"
			(at 0 0 90)
			(layer "F.SilkS")
			(hide yes)
			(effects
				(font
					(size 1.27 1.27)
				)
			)
		)
		(property "Value" ""
			(at 0 0 90)
			(layer "F.Fab")
			(effects
				(font
					(size 1.27 1.27)
				)
			)
		)
		(duplicate_pad_numbers_are_jumpers no)
		(fp_line
			(start 0.7874 -0.4064)
			(end 0.7874 0.4064)
			(stroke
				(width 0.1524)
				(type default)
			)
			(layer "F.SilkS")
		)
		(fp_line
			(start -0.7874 -0.4064)
			(end 0.7874 -0.4064)
			(stroke
				(width 0.1524)
				(type default)
			)
			(layer "F.SilkS")
		)
		(fp_line
			(start 0.7874 0.4064)
			(end -0.7874 0.4064)
			(stroke
				(width 0.1524)
				(type default)
			)
			(layer "F.SilkS")
		)
		(fp_line
			(start -0.7874 0.4064)
			(end -0.7874 -0.4064)
			(stroke
				(width 0.1524)
				(type default)
			)
			(layer "F.SilkS")
		)
		(fp_line
			(start -0.12065 -0.305054)
			(end -0.12065 -0.2794)
			(stroke
				(width 0.1)
				(type default)
			)
			(layer "F.Fab")
		)
		(fp_line
			(start -0.67945 -0.305054)
			(end -0.12065 -0.305054)
			(stroke
				(width 0.1)
				(type default)
			)
			(layer "F.Fab")
		)
		(fp_line
			(start 0.67945 -0.3048)
			(end 0.67945 0.3048)
			(stroke
				(width 0.1)
				(type default)
			)
			(layer "F.Fab")
		)
		(fp_line
			(start 0.12065 -0.3048)
			(end 0.67945 -0.3048)
			(stroke
				(width 0.1)
				(type default)
			)
			(layer "F.Fab")
		)
		(fp_line
			(start 0.12065 -0.2794)
			(end 0.12065 -0.3048)
			(stroke
				(width 0.1)
				(type default)
			)
			(layer "F.Fab")
		)
		(fp_line
			(start -0.12065 -0.2794)
			(end 0.12065 -0.2794)
			(stroke
				(width 0.1)
				(type default)
			)
			(layer "F.Fab")
		)
		(fp_line
			(start 0.120396 0.2794)
			(end -0.12065 0.2794)
			(stroke
				(width 0.1)
				(type default)
			)
			(layer "F.Fab")
		)
		(fp_line
			(start -0.12065 0.2794)
			(end -0.12065 0.3048)
			(stroke
				(width 0.1)
				(type default)
			)
			(layer "F.Fab")
		)
		(fp_line
			(start 0.67945 0.3048)
			(end 0.120396 0.3048)
			(stroke
				(width 0.1)
				(type default)
			)
			(layer "F.Fab")
		)
		(fp_line
			(start 0.120396 0.3048)
			(end 0.120396 0.2794)
			(stroke
				(width 0.1)
				(type default)
			)
			(layer "F.Fab")
		)
		(fp_line
			(start -0.12065 0.3048)
			(end -0.67945 0.3048)
			(stroke
				(width 0.1)
				(type default)
			)
			(layer "F.Fab")
		)
		(fp_line
			(start -0.67945 0.3048)
			(end -0.67945 -0.305054)
			(stroke
				(width 0.1)
				(type default)
			)
			(layer "F.Fab")
		)
		(pad "1" smd circle
			(at -0.40005 0 90)
			(size 0 0)
			(layers "F.Cu" "F.Mask" "F.Paste")
			(net "P12V_SSD14")
		)
		(pad "2" smd circle
			(at 0.40005 0 90)
			(size 0 0)
			(layers "F.Cu" "F.Mask" "F.Paste")
			(net "GND")
		)
	)
	(footprint ""
		(layer "F.Cu")
		(at 369.071144 -145.189956 180)
		(property "Reference" "R756"
			(at 0 0 180)
			(layer "F.SilkS")
			(hide yes)
			(effects
				(font
					(size 1.27 1.27)
				)
			)
		)
		(property "Value" ""
			(at 0 0 180)
			(layer "F.Fab")
			(effects
				(font
					(size 1.27 1.27)
				)
			)
		)
		(duplicate_pad_numbers_are_jumpers no)
		(fp_line
			(start 0.7874 0.4064)
			(end -0.7874 0.4064)
			(stroke
				(width 0.1524)
				(type default)
			)
			(layer "F.SilkS")
		)
		(fp_line
			(start 0.7874 -0.4064)
			(end 0.7874 0.4064)
			(stroke
				(width 0.1524)
				(type default)
			)
			(layer "F.SilkS")
		)
		(fp_line
			(start -0.7874 0.4064)
			(end -0.7874 -0.4064)
			(stroke
				(width 0.1524)
				(type default)
			)
			(layer "F.SilkS")
		)
		(fp_line
			(start -0.7874 -0.4064)
			(end 0.7874 -0.4064)
			(stroke
				(width 0.1524)
				(type default)
			)
			(layer "F.SilkS")
		)
		(fp_line
			(start 0.67945 0.3048)
			(end 0.120396 0.3048)
			(stroke
				(width 0.1)
				(type default)
			)
			(layer "F.Fab")
		)
		(fp_line
			(start 0.67945 -0.3048)
			(end 0.67945 0.3048)
			(stroke
				(width 0.1)
				(type default)
			)
			(layer "F.Fab")
		)
		(fp_line
			(start 0.12065 -0.2794)
			(end 0.12065 -0.3048)
			(stroke
				(width 0.1)
				(type default)
			)
			(layer "F.Fab")
		)
		(fp_line
			(start 0.12065 -0.3048)
			(end 0.67945 -0.3048)
			(stroke
				(width 0.1)
				(type default)
			)
			(layer "F.Fab")
		)
		(fp_line
			(start 0.120396 0.3048)
			(end 0.120396 0.2794)
			(stroke
				(width 0.1)
				(type default)
			)
			(layer "F.Fab")
		)
		(fp_line
			(start 0.120396 0.2794)
			(end -0.12065 0.2794)
			(stroke
				(width 0.1)
				(type default)
			)
			(layer "F.Fab")
		)
		(fp_line
			(start -0.12065 0.3048)
			(end -0.67945 0.3048)
			(stroke
				(width 0.1)
				(type default)
			)
			(layer "F.Fab")
		)
		(fp_line
			(start -0.12065 0.2794)
			(end -0.12065 0.3048)
			(stroke
				(width 0.1)
				(type default)
			)
			(layer "F.Fab")
		)
		(fp_line
			(start -0.12065 -0.2794)
			(end 0.12065 -0.2794)
			(stroke
				(width 0.1)
				(type default)
			)
			(layer "F.Fab")
		)
		(fp_line
			(start -0.12065 -0.305054)
			(end -0.12065 -0.2794)
			(stroke
				(width 0.1)
				(type default)
			)
			(layer "F.Fab")
		)
		(fp_line
			(start -0.67945 0.3048)
			(end -0.67945 -0.305054)
			(stroke
				(width 0.1)
				(type default)
			)
			(layer "F.Fab")
		)
		(fp_line
			(start -0.67945 -0.305054)
			(end -0.12065 -0.305054)
			(stroke
				(width 0.1)
				(type default)
			)
			(layer "F.Fab")
		)
		(pad "1" smd circle
			(at -0.40005 0 180)
			(size 0 0)
			(layers "F.Cu" "F.Mask" "F.Paste")
			(net "P12V_NIC6")
		)
		(pad "2" smd circle
			(at 0.40005 0 180)
			(size 0 0)
			(layers "F.Cu" "F.Mask" "F.Paste")
			(net "P12V_NIC6_VIN_N")
		)
	)
	(footprint ""
		(layer "F.Cu")
		(at 239.754918 -315.821314 180)
		(property "Reference" "PC245"
			(at 0 0 180)
			(layer "F.SilkS")
			(hide yes)
			(effects
				(font
					(size 1.27 1.27)
				)
			)
		)
		(property "Value" ""
			(at 0 0 180)
			(layer "F.Fab")
			(effects
				(font
					(size 1.27 1.27)
				)
			)
		)
		(duplicate_pad_numbers_are_jumpers no)
		(fp_line
			(start 1.524 0.762)
			(end -1.524 0.762)
			(stroke
				(width 0.1524)
				(type default)
			)
			(layer "F.SilkS")
		)
		(fp_line
			(start 1.524 -0.762)
			(end 1.524 0.762)
			(stroke
				(width 0.1524)
				(type default)
			)
			(layer "F.SilkS")
		)
		(fp_line
			(start -1.524 0.762)
			(end -1.524 -0.762)
			(stroke
				(width 0.1524)
				(type default)
			)
			(layer "F.SilkS")
		)
		(fp_line
			(start -1.524 -0.762)
			(end 1.524 -0.762)
			(stroke
				(width 0.1524)
				(type default)
			)
			(layer "F.SilkS")
		)
		(fp_line
			(start 1.1049 0.724916)
			(end 1.1049 -0.724916)
			(stroke
				(width 0.1)
				(type default)
			)
			(layer "F.Fab")
		)
		(fp_line
			(start 1.1049 -0.724916)
			(end -1.1049 -0.724916)
			(stroke
				(width 0.1)
				(type default)
			)
			(layer "F.Fab")
		)
		(fp_line
			(start -1.1049 0.724916)
			(end 1.1049 0.724916)
			(stroke
				(width 0.1)
				(type default)
			)
			(layer "F.Fab")
		)
		(fp_line
			(start -1.1049 -0.724916)
			(end -1.1049 0.724916)
			(stroke
				(width 0.1)
				(type default)
			)
			(layer "F.Fab")
		)
		(pad "1" smd rect
			(at -0.889 0)
			(size 1.016 1.27)
			(layers "F.Cu" "F.Mask" "F.Paste")
			(net "SW_P12V_P1V25_PEX2_FLT")
		)
		(pad "2" smd rect
			(at 0.889 0)
			(size 1.016 1.27)
			(layers "F.Cu" "F.Mask" "F.Paste")
			(net "GND")
		)
	)
	(footprint ""
		(layer "F.Cu")
		(at 171.979844 -142.9512 180)
		(property "Reference" "R111"
			(at 0 0 180)
			(layer "F.SilkS")
			(hide yes)
			(effects
				(font
					(size 1.27 1.27)
				)
			)
		)
		(property "Value" ""
			(at 0 0 180)
			(layer "F.Fab")
			(effects
				(font
					(size 1.27 1.27)
				)
			)
		)
		(duplicate_pad_numbers_are_jumpers no)
		(fp_line
			(start 0.7874 0.4064)
			(end -0.7874 0.4064)
			(stroke
				(width 0.1524)
				(type default)
			)
			(layer "F.SilkS")
		)
		(fp_line
			(start 0.7874 -0.4064)
			(end 0.7874 0.4064)
			(stroke
				(width 0.1524)
				(type default)
			)
			(layer "F.SilkS")
		)
		(fp_line
			(start -0.7874 0.4064)
			(end -0.7874 -0.4064)
			(stroke
				(width 0.1524)
				(type default)
			)
			(layer "F.SilkS")
		)
		(fp_line
			(start -0.7874 -0.4064)
			(end 0.7874 -0.4064)
			(stroke
				(width 0.1524)
				(type default)
			)
			(layer "F.SilkS")
		)
		(fp_line
			(start 0.67945 0.3048)
			(end 0.120396 0.3048)
			(stroke
				(width 0.1)
				(type default)
			)
			(layer "F.Fab")
		)
		(fp_line
			(start 0.67945 -0.3048)
			(end 0.67945 0.3048)
			(stroke
				(width 0.1)
				(type default)
			)
			(layer "F.Fab")
		)
		(fp_line
			(start 0.12065 -0.2794)
			(end 0.12065 -0.3048)
			(stroke
				(width 0.1)
				(type default)
			)
			(layer "F.Fab")
		)
		(fp_line
			(start 0.12065 -0.3048)
			(end 0.67945 -0.3048)
			(stroke
				(width 0.1)
				(type default)
			)
			(layer "F.Fab")
		)
		(fp_line
			(start 0.120396 0.3048)
			(end 0.120396 0.2794)
			(stroke
				(width 0.1)
				(type default)
			)
			(layer "F.Fab")
		)
		(fp_line
			(start 0.120396 0.2794)
			(end -0.12065 0.2794)
			(stroke
				(width 0.1)
				(type default)
			)
			(layer "F.Fab")
		)
		(fp_line
			(start -0.12065 0.3048)
			(end -0.67945 0.3048)
			(stroke
				(width 0.1)
				(type default)
			)
			(layer "F.Fab")
		)
		(fp_line
			(start -0.12065 0.2794)
			(end -0.12065 0.3048)
			(stroke
				(width 0.1)
				(type default)
			)
			(layer "F.Fab")
		)
		(fp_line
			(start -0.12065 -0.2794)
			(end 0.12065 -0.2794)
			(stroke
				(width 0.1)
				(type default)
			)
			(layer "F.Fab")
		)
		(fp_line
			(start -0.12065 -0.305054)
			(end -0.12065 -0.2794)
			(stroke
				(width 0.1)
				(type default)
			)
			(layer "F.Fab")
		)
		(fp_line
			(start -0.67945 0.3048)
			(end -0.67945 -0.305054)
			(stroke
				(width 0.1)
				(type default)
			)
			(layer "F.Fab")
		)
		(fp_line
			(start -0.67945 -0.305054)
			(end -0.12065 -0.305054)
			(stroke
				(width 0.1)
				(type default)
			)
			(layer "F.Fab")
		)
		(pad "1" smd circle
			(at -0.40005 0 180)
			(size 0 0)
			(layers "F.Cu" "F.Mask" "F.Paste")
			(net "P3V3_NIC2")
		)
		(pad "2" smd circle
			(at 0.40005 0 180)
			(size 0 0)
			(layers "F.Cu" "F.Mask" "F.Paste")
			(net "SMB_NIC2_R_SCL")
		)
	)
	(footprint ""
		(layer "F.Cu")
		(at 190.946024 -46.4439 180)
		(property "Reference" "U61"
			(at -0.163576 -2.45237 0)
			(unlocked yes)
			(layer "F.SilkS")
			(effects
				(font
					(size 0.7874 0.5842)
					(thickness 0.1524)
				)
			)
		)
		(property "Value" ""
			(at 0 0 180)
			(layer "F.Fab")
			(effects
				(font
					(size 1.27 1.27)
				)
			)
		)
		(duplicate_pad_numbers_are_jumpers no)
		(fp_line
			(start 1.500124 1.500124)
			(end 1.004062 1.500124)
			(stroke
				(width 0.1524)
				(type default)
			)
			(layer "F.SilkS")
		)
		(fp_line
			(start 1.500124 1.004062)
			(end 1.500124 1.500124)
			(stroke
				(width 0.1524)
				(type default)
			)
			(layer "F.SilkS")
		)
		(fp_line
			(start 1.500124 -1.500124)
			(end 1.500124 -1.004062)
			(stroke
				(width 0.1524)
				(type default)
			)
			(layer "F.SilkS")
		)
		(fp_line
			(start 1.004062 -1.500124)
			(end 1.500124 -1.500124)
			(stroke
				(width 0.1524)
				(type default)
			)
			(layer "F.SilkS")
		)
		(fp_line
			(start -1.004062 1.500124)
			(end -1.500124 1.500124)
			(stroke
				(width 0.1524)
				(type default)
			)
			(layer "F.SilkS")
		)
		(fp_line
			(start -1.500124 1.500124)
			(end -1.500124 1.004062)
			(stroke
				(width 0.1524)
				(type default)
			)
			(layer "F.SilkS")
		)
		(fp_line
			(start -1.500124 -1.004062)
			(end -1.500124 -1.500124)
			(stroke
				(width 0.1524)
				(type default)
			)
			(layer "F.SilkS")
		)
		(fp_line
			(start -1.500124 -1.500124)
			(end -1.004062 -1.500124)
			(stroke
				(width 0.1524)
				(type default)
			)
			(layer "F.SilkS")
		)
		(fp_poly
			(pts
				(xy -1.827022 -2.276602) (xy -2.545334 -1.55829) (xy -1.467612 -1.199134)
			)
			(stroke
				(width 0)
				(type default)
			)
			(fill yes)
			(layer "F.SilkS")
		)
		(fp_line
			(start 1.500124 1.500124)
			(end -1.500124 1.500124)
			(stroke
				(width 0.1)
				(type default)
			)
			(layer "F.Fab")
		)
		(fp_line
			(start 1.500124 -1.500124)
			(end 1.500124 1.500124)
			(stroke
				(width 0.1)
				(type default)
			)
			(layer "F.Fab")
		)
		(fp_line
			(start -1.500124 1.500124)
			(end -1.500124 -1.500124)
			(stroke
				(width 0.1)
				(type default)
			)
			(layer "F.Fab")
		)
		(fp_line
			(start -1.500124 -1.500124)
			(end 1.500124 -1.500124)
			(stroke
				(width 0.1)
				(type default)
			)
			(layer "F.Fab")
		)
		(fp_poly
			(pts
				(xy -2.847848 -1.258062) (xy -2.847848 -0.242062) (xy -1.831848 -0.750062)
			)
			(stroke
				(width 0)
				(type default)
			)
			(fill yes)
			(layer "F.Fab")
		)
		(pad "1" smd rect
			(at -1.400048 -0.750062 90)
			(size 0.2286 0.6096)
			(layers "F.Cu" "F.Mask" "F.Paste")
			(net "SSD6_ADC_A1")
		)
		(pad "2" smd rect
			(at -1.400048 -0.249936 90)
			(size 0.2286 0.6096)
			(layers "F.Cu" "F.Mask" "F.Paste")
			(net "SSD6_ADC_A0")
		)
		(pad "3" smd rect
			(at -1.400048 0.249936 90)
			(size 0.2286 0.6096)
			(layers "F.Cu" "F.Mask" "F.Paste")
			(net "SSD6_ADC_ALERT_N")
		)
		(pad "4" smd rect
			(at -1.400048 0.750062 90)
			(size 0.2286 0.6096)
			(layers "F.Cu" "F.Mask" "F.Paste")
			(net "SMB_SSD6_ADC_SDA")
		)
		(pad "5" smd rect
			(at -0.750062 1.400048 180)
			(size 0.2286 0.6096)
			(layers "F.Cu" "F.Mask" "F.Paste")
			(net "SMB_SSD6_ADC_SCL")
		)
		(pad "6" smd rect
			(at -0.249936 1.400048 180)
			(size 0.2286 0.6096)
			(layers "F.Cu" "F.Mask" "F.Paste")
			(net "Net_8726")
		)
		(pad "7" smd rect
			(at 0.249936 1.400048 180)
			(size 0.2286 0.6096)
			(layers "F.Cu" "F.Mask" "F.Paste")
			(net "Net_8725")
		)
		(pad "8" smd rect
			(at 0.750062 1.400048 180)
			(size 0.2286 0.6096)
			(layers "F.Cu" "F.Mask" "F.Paste")
			(net "Net_8724")
		)
		(pad "9" smd rect
			(at 1.400048 0.750062 90)
			(size 0.2286 0.6096)
			(layers "F.Cu" "F.Mask" "F.Paste")
			(net "P3V3_AUX")
		)
		(pad "10" smd rect
			(at 1.400048 0.249936 90)
			(size 0.2286 0.6096)
			(layers "F.Cu" "F.Mask" "F.Paste")
			(net "GND")
		)
		(pad "11" smd rect
			(at 1.400048 -0.249936 90)
			(size 0.2286 0.6096)
			(layers "F.Cu" "F.Mask" "F.Paste")
			(net "P12V_SSD6_R")
		)
		(pad "12" smd rect
			(at 1.400048 -0.750062 90)
			(size 0.2286 0.6096)
			(layers "F.Cu" "F.Mask" "F.Paste")
			(net "P12V_SSD6_VIN_N")
		)
		(pad "13" smd rect
			(at 0.750062 -1.400048 180)
			(size 0.2286 0.6096)
			(layers "F.Cu" "F.Mask" "F.Paste")
			(net "P12V_SSD6_VIN_P")
		)
		(pad "14" smd rect
			(at 0.249936 -1.400048 180)
			(size 0.2286 0.6096)
			(layers "F.Cu" "F.Mask" "F.Paste")
			(net "Net_8723")
		)
		(pad "15" smd rect
			(at -0.249936 -1.400048 180)
			(size 0.2286 0.6096)
			(layers "F.Cu" "F.Mask" "F.Paste")
			(net "Net_8722")
		)
		(pad "16" smd rect
			(at -0.750062 -1.400048 180)
			(size 0.2286 0.6096)
			(layers "F.Cu" "F.Mask" "F.Paste")
			(net "Net_8721")
		)
		(pad "TH" smd rect
			(at 0 0 180)
			(size 1.7018 1.7018)
			(layers "F.Cu" "F.Mask" "F.Paste")
			(net "GND")
		)
		(zone
			(layer "F.Cu")
			(hatch none 0.5)
			(connect_pads
				(clearance 0)
			)
			(min_thickness 0.25)
			(keepout
				(tracks not_allowed)
				(vias allowed)
				(pads allowed)
				(copperpour not_allowed)
				(footprints allowed)
			)
			(placement
				(enabled no)
				(sheetname "")
			)
			(fill
				(thermal_gap 0.5)
				(thermal_bridge_width 0.5)
				(island_removal_mode 0)
			)
			(polygon
				(pts
					(xy 191.990472 -46.4185) (xy 191.990472 -45.399452) (xy 189.901576 -45.399452) (xy 189.901576 -47.488348)
					(xy 191.990472 -47.488348) (xy 191.990472 -46.4439) (xy 191.847724 -46.4439) (xy 191.847724 -47.3456)
					(xy 190.044324 -47.3456) (xy 190.044324 -45.5422) (xy 191.847724 -45.5422) (xy 191.847724 -46.4185)
				)
			)
		)
	)
	(footprint ""
		(layer "F.Cu")
		(at 115.64239 -257.13055 180)
		(property "Reference" "PC56"
			(at 0 0 180)
			(layer "F.SilkS")
			(hide yes)
			(effects
				(font
					(size 1.27 1.27)
				)
			)
		)
		(property "Value" ""
			(at 0 0 180)
			(layer "F.Fab")
			(effects
				(font
					(size 1.27 1.27)
				)
			)
		)
		(duplicate_pad_numbers_are_jumpers no)
		(fp_line
			(start 0.7874 0.4064)
			(end -0.7874 0.4064)
			(stroke
				(width 0.1524)
				(type default)
			)
			(layer "F.SilkS")
		)
		(fp_line
			(start 0.7874 -0.4064)
			(end 0.7874 0.4064)
			(stroke
				(width 0.1524)
				(type default)
			)
			(layer "F.SilkS")
		)
		(fp_line
			(start -0.7874 0.4064)
			(end -0.7874 -0.4064)
			(stroke
				(width 0.1524)
				(type default)
			)
			(layer "F.SilkS")
		)
		(fp_line
			(start -0.7874 -0.4064)
			(end 0.7874 -0.4064)
			(stroke
				(width 0.1524)
				(type default)
			)
			(layer "F.SilkS")
		)
		(fp_line
			(start 0.67945 0.3048)
			(end 0.120396 0.3048)
			(stroke
				(width 0.1)
				(type default)
			)
			(layer "F.Fab")
		)
		(fp_line
			(start 0.67945 -0.3048)
			(end 0.67945 0.3048)
			(stroke
				(width 0.1)
				(type default)
			)
			(layer "F.Fab")
		)
		(fp_line
			(start 0.12065 -0.2794)
			(end 0.12065 -0.3048)
			(stroke
				(width 0.1)
				(type default)
			)
			(layer "F.Fab")
		)
		(fp_line
			(start 0.12065 -0.3048)
			(end 0.67945 -0.3048)
			(stroke
				(width 0.1)
				(type default)
			)
			(layer "F.Fab")
		)
		(fp_line
			(start 0.120396 0.3048)
			(end 0.120396 0.2794)
			(stroke
				(width 0.1)
				(type default)
			)
			(layer "F.Fab")
		)
		(fp_line
			(start 0.120396 0.2794)
			(end -0.12065 0.2794)
			(stroke
				(width 0.1)
				(type default)
			)
			(layer "F.Fab")
		)
		(fp_line
			(start -0.12065 0.3048)
			(end -0.67945 0.3048)
			(stroke
				(width 0.1)
				(type default)
			)
			(layer "F.Fab")
		)
		(fp_line
			(start -0.12065 0.2794)
			(end -0.12065 0.3048)
			(stroke
				(width 0.1)
				(type default)
			)
			(layer "F.Fab")
		)
		(fp_line
			(start -0.12065 -0.2794)
			(end 0.12065 -0.2794)
			(stroke
				(width 0.1)
				(type default)
			)
			(layer "F.Fab")
		)
		(fp_line
			(start -0.12065 -0.305054)
			(end -0.12065 -0.2794)
			(stroke
				(width 0.1)
				(type default)
			)
			(layer "F.Fab")
		)
		(fp_line
			(start -0.67945 0.3048)
			(end -0.67945 -0.305054)
			(stroke
				(width 0.1)
				(type default)
			)
			(layer "F.Fab")
		)
		(fp_line
			(start -0.67945 -0.305054)
			(end -0.12065 -0.305054)
			(stroke
				(width 0.1)
				(type default)
			)
			(layer "F.Fab")
		)
		(pad "1" smd circle
			(at -0.40005 0 180)
			(size 0 0)
			(layers "F.Cu" "F.Mask" "F.Paste")
			(net "P0V8_PEX0_VINSEN")
		)
		(pad "2" smd circle
			(at 0.40005 0 180)
			(size 0 0)
			(layers "F.Cu" "F.Mask" "F.Paste")
			(net "GND")
		)
	)
	(footprint ""
		(layer "F.Cu")
		(at 428.319438 -154.304746 180)
		(property "Reference" "C636"
			(at 0 0 180)
			(layer "F.SilkS")
			(hide yes)
			(effects
				(font
					(size 1.27 1.27)
				)
			)
		)
		(property "Value" ""
			(at 0 0 180)
			(layer "F.Fab")
			(effects
				(font
					(size 1.27 1.27)
				)
			)
		)
		(duplicate_pad_numbers_are_jumpers no)
		(fp_line
			(start 0.299974 0.150114)
			(end -0.299974 0.150114)
			(stroke
				(width 0.1)
				(type default)
			)
			(layer "F.Fab")
		)
		(fp_line
			(start 0.299974 -0.150114)
			(end 0.299974 0.150114)
			(stroke
				(width 0.1)
				(type default)
			)
			(layer "F.Fab")
		)
		(fp_line
			(start -0.299974 0.150114)
			(end -0.299974 -0.150114)
			(stroke
				(width 0.1)
				(type default)
			)
			(layer "F.Fab")
		)
		(fp_line
			(start -0.299974 -0.150114)
			(end 0.299974 -0.150114)
			(stroke
				(width 0.1)
				(type default)
			)
			(layer "F.Fab")
		)
		(pad "1" smd rect
			(at -0.2667 0 180)
			(size 0.3048 0.381)
			(layers "F.Cu" "F.Mask" "F.Paste")
			(net "P5E_PEX3_STN0_TX_DN<14>")
		)
		(pad "2" smd rect
			(at 0.2667 0 180)
			(size 0.3048 0.381)
			(layers "F.Cu" "F.Mask" "F.Paste")
			(net "P5E_PEX3_STN0_TX_C_DN<14>")
		)
	)
	(footprint ""
		(layer "F.Cu")
		(at 268.838426 -119.198898)
		(property "Reference" "C469"
			(at 0 0 0)
			(layer "F.SilkS")
			(hide yes)
			(effects
				(font
					(size 1.27 1.27)
				)
			)
		)
		(property "Value" ""
			(at 0 0 0)
			(layer "F.Fab")
			(effects
				(font
					(size 1.27 1.27)
				)
			)
		)
		(duplicate_pad_numbers_are_jumpers no)
		(fp_line
			(start -0.299974 -0.150114)
			(end 0.299974 -0.150114)
			(stroke
				(width 0.1)
				(type default)
			)
			(layer "F.Fab")
		)
		(fp_line
			(start -0.299974 0.150114)
			(end -0.299974 -0.150114)
			(stroke
				(width 0.1)
				(type default)
			)
			(layer "F.Fab")
		)
		(fp_line
			(start 0.299974 -0.150114)
			(end 0.299974 0.150114)
			(stroke
				(width 0.1)
				(type default)
			)
			(layer "F.Fab")
		)
		(fp_line
			(start 0.299974 0.150114)
			(end -0.299974 0.150114)
			(stroke
				(width 0.1)
				(type default)
			)
			(layer "F.Fab")
		)
		(pad "1" smd rect
			(at -0.2667 0)
			(size 0.3048 0.381)
			(layers "F.Cu" "F.Mask" "F.Paste")
			(net "P5E_PEX2_STN1_TX_DP<24>")
		)
		(pad "2" smd rect
			(at 0.2667 0)
			(size 0.3048 0.381)
			(layers "F.Cu" "F.Mask" "F.Paste")
			(net "P5E_PEX2_STN1_TX_C_DP<24>")
		)
	)
	(footprint ""
		(layer "F.Cu")
		(at 344.612976 -88.16975 180)
		(property "Reference" "R1181"
			(at 0 0 180)
			(layer "F.SilkS")
			(hide yes)
			(effects
				(font
					(size 1.27 1.27)
				)
			)
		)
		(property "Value" ""
			(at 0 0 180)
			(layer "F.Fab")
			(effects
				(font
					(size 1.27 1.27)
				)
			)
		)
		(duplicate_pad_numbers_are_jumpers no)
		(fp_line
			(start 0.7874 0.4064)
			(end -0.7874 0.4064)
			(stroke
				(width 0.1524)
				(type default)
			)
			(layer "F.SilkS")
		)
		(fp_line
			(start 0.67945 0.3048)
			(end 0.120396 0.3048)
			(stroke
				(width 0.1)
				(type default)
			)
			(layer "F.Fab")
		)
		(fp_line
			(start 0.67945 -0.3048)
			(end 0.67945 0.3048)
			(stroke
				(width 0.1)
				(type default)
			)
			(layer "F.Fab")
		)
		(fp_line
			(start 0.12065 -0.2794)
			(end 0.12065 -0.3048)
			(stroke
				(width 0.1)
				(type default)
			)
			(layer "F.Fab")
		)
		(fp_line
			(start 0.12065 -0.3048)
			(end 0.67945 -0.3048)
			(stroke
				(width 0.1)
				(type default)
			)
			(layer "F.Fab")
		)
		(fp_line
			(start 0.120396 0.3048)
			(end 0.120396 0.2794)
			(stroke
				(width 0.1)
				(type default)
			)
			(layer "F.Fab")
		)
		(fp_line
			(start 0.120396 0.2794)
			(end -0.12065 0.2794)
			(stroke
				(width 0.1)
				(type default)
			)
			(layer "F.Fab")
		)
		(fp_line
			(start -0.12065 0.3048)
			(end -0.67945 0.3048)
			(stroke
				(width 0.1)
				(type default)
			)
			(layer "F.Fab")
		)
		(fp_line
			(start -0.12065 0.2794)
			(end -0.12065 0.3048)
			(stroke
				(width 0.1)
				(type default)
			)
			(layer "F.Fab")
		)
		(fp_line
			(start -0.12065 -0.2794)
			(end 0.12065 -0.2794)
			(stroke
				(width 0.1)
				(type default)
			)
			(layer "F.Fab")
		)
		(fp_line
			(start -0.12065 -0.305054)
			(end -0.12065 -0.2794)
			(stroke
				(width 0.1)
				(type default)
			)
			(layer "F.Fab")
		)
		(fp_line
			(start -0.67945 0.3048)
			(end -0.67945 -0.305054)
			(stroke
				(width 0.1)
				(type default)
			)
			(layer "F.Fab")
		)
		(fp_line
			(start -0.67945 -0.305054)
			(end -0.12065 -0.305054)
			(stroke
				(width 0.1)
				(type default)
			)
			(layer "F.Fab")
		)
		(pad "1" smd circle
			(at -0.40005 0 180)
			(size 0 0)
			(layers "F.Cu" "F.Mask" "F.Paste")
			(net "CLK_100M_DB800ZL_SSD13_R_DN")
		)
		(pad "2" smd circle
			(at 0.40005 0 180)
			(size 0 0)
			(layers "F.Cu" "F.Mask" "F.Paste")
			(net "CLK_100M_DB800ZL_SSD13_DN")
		)
	)
	(footprint ""
		(layer "F.Cu")
		(at 230.938832 -155.960826 -90)
		(property "Reference" "R1207"
			(at 0 0 270)
			(layer "F.SilkS")
			(hide yes)
			(effects
				(font
					(size 1.27 1.27)
				)
			)
		)
		(property "Value" ""
			(at 0 0 270)
			(layer "F.Fab")
			(effects
				(font
					(size 1.27 1.27)
				)
			)
		)
		(duplicate_pad_numbers_are_jumpers no)
		(fp_line
			(start 0.7874 0.4064)
			(end -0.7874 0.4064)
			(stroke
				(width 0.1524)
				(type default)
			)
			(layer "F.SilkS")
		)
		(fp_line
			(start -0.67945 0.3048)
			(end -0.67945 -0.305054)
			(stroke
				(width 0.1)
				(type default)
			)
			(layer "F.Fab")
		)
		(fp_line
			(start -0.12065 0.3048)
			(end -0.67945 0.3048)
			(stroke
				(width 0.1)
				(type default)
			)
			(layer "F.Fab")
		)
		(fp_line
			(start 0.120396 0.3048)
			(end 0.120396 0.2794)
			(stroke
				(width 0.1)
				(type default)
			)
			(layer "F.Fab")
		)
		(fp_line
			(start 0.67945 0.3048)
			(end 0.120396 0.3048)
			(stroke
				(width 0.1)
				(type default)
			)
			(layer "F.Fab")
		)
		(fp_line
			(start -0.12065 0.2794)
			(end -0.12065 0.3048)
			(stroke
				(width 0.1)
				(type default)
			)
			(layer "F.Fab")
		)
		(fp_line
			(start 0.120396 0.2794)
			(end -0.12065 0.2794)
			(stroke
				(width 0.1)
				(type default)
			)
			(layer "F.Fab")
		)
		(fp_line
			(start -0.12065 -0.2794)
			(end 0.12065 -0.2794)
			(stroke
				(width 0.1)
				(type default)
			)
			(layer "F.Fab")
		)
		(fp_line
			(start 0.12065 -0.2794)
			(end 0.12065 -0.3048)
			(stroke
				(width 0.1)
				(type default)
			)
			(layer "F.Fab")
		)
		(fp_line
			(start 0.12065 -0.3048)
			(end 0.67945 -0.3048)
			(stroke
				(width 0.1)
				(type default)
			)
			(layer "F.Fab")
		)
		(fp_line
			(start 0.67945 -0.3048)
			(end 0.67945 0.3048)
			(stroke
				(width 0.1)
				(type default)
			)
			(layer "F.Fab")
		)
		(fp_line
			(start -0.67945 -0.305054)
			(end -0.12065 -0.305054)
			(stroke
				(width 0.1)
				(type default)
			)
			(layer "F.Fab")
		)
		(fp_line
			(start -0.12065 -0.305054)
			(end -0.12065 -0.2794)
			(stroke
				(width 0.1)
				(type default)
			)
			(layer "F.Fab")
		)
		(pad "1" smd circle
			(at -0.40005 0 270)
			(size 0 0)
			(layers "F.Cu" "F.Mask" "F.Paste")
			(net "CLK_100M_PEX1_REF_R_DP")
		)
		(pad "2" smd circle
			(at 0.40005 0 270)
			(size 0 0)
			(layers "F.Cu" "F.Mask" "F.Paste")
			(net "CLK_100M_PEX1_REF_DP")
		)
	)
	(footprint ""
		(layer "F.Cu")
		(at 8.45058 -72.459088)
		(property "Reference" "R5655"
			(at 0 0 0)
			(layer "F.SilkS")
			(hide yes)
			(effects
				(font
					(size 1.27 1.27)
				)
			)
		)
		(property "Value" ""
			(at 0 0 0)
			(layer "F.Fab")
			(effects
				(font
					(size 1.27 1.27)
				)
			)
		)
		(duplicate_pad_numbers_are_jumpers no)
		(fp_line
			(start -0.7874 -0.4064)
			(end 0.7874 -0.4064)
			(stroke
				(width 0.1524)
				(type default)
			)
			(layer "F.SilkS")
		)
		(fp_line
			(start -0.7874 0.4064)
			(end -0.7874 -0.4064)
			(stroke
				(width 0.1524)
				(type default)
			)
			(layer "F.SilkS")
		)
		(fp_line
			(start 0.7874 -0.4064)
			(end 0.7874 0.4064)
			(stroke
				(width 0.1524)
				(type default)
			)
			(layer "F.SilkS")
		)
		(fp_line
			(start 0.7874 0.4064)
			(end -0.7874 0.4064)
			(stroke
				(width 0.1524)
				(type default)
			)
			(layer "F.SilkS")
		)
		(fp_line
			(start -0.67945 -0.305054)
			(end -0.12065 -0.305054)
			(stroke
				(width 0.1)
				(type default)
			)
			(layer "F.Fab")
		)
		(fp_line
			(start -0.67945 0.3048)
			(end -0.67945 -0.305054)
			(stroke
				(width 0.1)
				(type default)
			)
			(layer "F.Fab")
		)
		(fp_line
			(start -0.12065 -0.305054)
			(end -0.12065 -0.2794)
			(stroke
				(width 0.1)
				(type default)
			)
			(layer "F.Fab")
		)
		(fp_line
			(start -0.12065 -0.2794)
			(end 0.12065 -0.2794)
			(stroke
				(width 0.1)
				(type default)
			)
			(layer "F.Fab")
		)
		(fp_line
			(start -0.12065 0.2794)
			(end -0.12065 0.3048)
			(stroke
				(width 0.1)
				(type default)
			)
			(layer "F.Fab")
		)
		(fp_line
			(start -0.12065 0.3048)
			(end -0.67945 0.3048)
			(stroke
				(width 0.1)
				(type default)
			)
			(layer "F.Fab")
		)
		(fp_line
			(start 0.120396 0.2794)
			(end -0.12065 0.2794)
			(stroke
				(width 0.1)
				(type default)
			)
			(layer "F.Fab")
		)
		(fp_line
			(start 0.120396 0.3048)
			(end 0.120396 0.2794)
			(stroke
				(width 0.1)
				(type default)
			)
			(layer "F.Fab")
		)
		(fp_line
			(start 0.12065 -0.3048)
			(end 0.67945 -0.3048)
			(stroke
				(width 0.1)
				(type default)
			)
			(layer "F.Fab")
		)
		(fp_line
			(start 0.12065 -0.2794)
			(end 0.12065 -0.3048)
			(stroke
				(width 0.1)
				(type default)
			)
			(layer "F.Fab")
		)
		(fp_line
			(start 0.67945 -0.3048)
			(end 0.67945 0.3048)
			(stroke
				(width 0.1)
				(type default)
			)
			(layer "F.Fab")
		)
		(fp_line
			(start 0.67945 0.3048)
			(end 0.120396 0.3048)
			(stroke
				(width 0.1)
				(type default)
			)
			(layer "F.Fab")
		)
		(pad "1" smd circle
			(at -0.40005 0)
			(size 0 0)
			(layers "F.Cu" "F.Mask" "F.Paste")
			(net "RST_SMB_SSD0_ISO_N")
		)
		(pad "2" smd circle
			(at 0.40005 0)
			(size 0 0)
			(layers "F.Cu" "F.Mask" "F.Paste")
			(net "GND")
		)
	)
	(footprint ""
		(layer "F.Cu")
		(at 192.374012 -26.31186 -90)
		(property "Reference" "U404"
			(at -0.20574 -2.394458 90)
			(unlocked yes)
			(layer "F.SilkS")
			(effects
				(font
					(size 0.7874 0.5842)
					(thickness 0.1524)
				)
			)
		)
		(property "Value" ""
			(at 0 0 270)
			(layer "F.Fab")
			(effects
				(font
					(size 1.27 1.27)
				)
			)
		)
		(duplicate_pad_numbers_are_jumpers no)
		(fp_line
			(start -1.949958 1.610106)
			(end -1.949958 -1.610106)
			(stroke
				(width 0.1524)
				(type default)
			)
			(layer "F.SilkS")
		)
		(fp_line
			(start 1.949958 1.610106)
			(end -1.949958 1.610106)
			(stroke
				(width 0.1524)
				(type default)
			)
			(layer "F.SilkS")
		)
		(fp_line
			(start 1.949958 -1.560068)
			(end 1.949958 1.610106)
			(stroke
				(width 0.1524)
				(type default)
			)
			(layer "F.SilkS")
		)
		(fp_line
			(start -1.949958 -1.610106)
			(end 1.949958 -1.610106)
			(stroke
				(width 0.1524)
				(type default)
			)
			(layer "F.SilkS")
		)
		(fp_line
			(start -0.750062 1.560068)
			(end -0.750062 -1.560068)
			(stroke
				(width 0.1)
				(type default)
			)
			(layer "F.Fab")
		)
		(fp_line
			(start 0.750062 1.560068)
			(end -0.750062 1.560068)
			(stroke
				(width 0.1)
				(type default)
			)
			(layer "F.Fab")
		)
		(fp_line
			(start -0.750062 -1.560068)
			(end 0.750062 -1.560068)
			(stroke
				(width 0.1)
				(type default)
			)
			(layer "F.Fab")
		)
		(fp_line
			(start 0.750062 -1.560068)
			(end 0.750062 1.560068)
			(stroke
				(width 0.1)
				(type default)
			)
			(layer "F.Fab")
		)
		(pad "D" smd rect
			(at 1.100074 0 180)
			(size 1.016 1.4224)
			(layers "F.Cu" "F.Mask" "F.Paste")
			(net "SSD6_LED_ISO_N")
		)
		(pad "G" smd rect
			(at -1.100074 -0.94996 180)
			(size 1.016 1.4224)
			(layers "F.Cu" "F.Mask" "F.Paste")
			(net "SSD6_LED_R")
		)
		(pad "S" smd rect
			(at -1.100074 0.94996 180)
			(size 1.016 1.4224)
			(layers "F.Cu" "F.Mask" "F.Paste")
			(net "GND")
		)
	)
	(footprint ""
		(layer "F.Cu")
		(at 349.899986 -194.360038)
		(property "Reference" "H68"
			(at -4.485894 -5.045456 0)
			(unlocked yes)
			(layer "F.SilkS")
			(effects
				(font
					(size 0.7874 0.5842)
					(thickness 0.1524)
				)
				(justify left)
			)
		)
		(property "Value" ""
			(at 0 0 0)
			(layer "F.Fab")
			(effects
				(font
					(size 1.27 1.27)
				)
			)
		)
		(duplicate_pad_numbers_are_jumpers no)
		(pad "1" thru_hole circle
			(at 0 0)
			(size 10.0076 10.0076)
			(drill 5.6134)
			(layers "*.Cu" "*.Mask")
			(remove_unused_layers no)
			(net "GND")
			(clearance -1.9431)
		)
	)
	(footprint ""
		(layer "F.Cu")
		(at 270.960342 -97.1804 180)
		(property "Reference" "R212"
			(at 0 0 180)
			(layer "F.SilkS")
			(hide yes)
			(effects
				(font
					(size 1.27 1.27)
				)
			)
		)
		(property "Value" ""
			(at 0 0 180)
			(layer "F.Fab")
			(effects
				(font
					(size 1.27 1.27)
				)
			)
		)
		(duplicate_pad_numbers_are_jumpers no)
		(fp_line
			(start 0.7874 0.4064)
			(end -0.7874 0.4064)
			(stroke
				(width 0.1524)
				(type default)
			)
			(layer "F.SilkS")
		)
		(fp_line
			(start 0.7874 -0.4064)
			(end 0.7874 0.4064)
			(stroke
				(width 0.1524)
				(type default)
			)
			(layer "F.SilkS")
		)
		(fp_line
			(start -0.7874 0.4064)
			(end -0.7874 -0.4064)
			(stroke
				(width 0.1524)
				(type default)
			)
			(layer "F.SilkS")
		)
		(fp_line
			(start -0.7874 -0.4064)
			(end 0.7874 -0.4064)
			(stroke
				(width 0.1524)
				(type default)
			)
			(layer "F.SilkS")
		)
		(fp_line
			(start 0.67945 0.3048)
			(end 0.120396 0.3048)
			(stroke
				(width 0.1)
				(type default)
			)
			(layer "F.Fab")
		)
		(fp_line
			(start 0.67945 -0.3048)
			(end 0.67945 0.3048)
			(stroke
				(width 0.1)
				(type default)
			)
			(layer "F.Fab")
		)
		(fp_line
			(start 0.12065 -0.2794)
			(end 0.12065 -0.3048)
			(stroke
				(width 0.1)
				(type default)
			)
			(layer "F.Fab")
		)
		(fp_line
			(start 0.12065 -0.3048)
			(end 0.67945 -0.3048)
			(stroke
				(width 0.1)
				(type default)
			)
			(layer "F.Fab")
		)
		(fp_line
			(start 0.120396 0.3048)
			(end 0.120396 0.2794)
			(stroke
				(width 0.1)
				(type default)
			)
			(layer "F.Fab")
		)
		(fp_line
			(start 0.120396 0.2794)
			(end -0.12065 0.2794)
			(stroke
				(width 0.1)
				(type default)
			)
			(layer "F.Fab")
		)
		(fp_line
			(start -0.12065 0.3048)
			(end -0.67945 0.3048)
			(stroke
				(width 0.1)
				(type default)
			)
			(layer "F.Fab")
		)
		(fp_line
			(start -0.12065 0.2794)
			(end -0.12065 0.3048)
			(stroke
				(width 0.1)
				(type default)
			)
			(layer "F.Fab")
		)
		(fp_line
			(start -0.12065 -0.2794)
			(end 0.12065 -0.2794)
			(stroke
				(width 0.1)
				(type default)
			)
			(layer "F.Fab")
		)
		(fp_line
			(start -0.12065 -0.305054)
			(end -0.12065 -0.2794)
			(stroke
				(width 0.1)
				(type default)
			)
			(layer "F.Fab")
		)
		(fp_line
			(start -0.67945 0.3048)
			(end -0.67945 -0.305054)
			(stroke
				(width 0.1)
				(type default)
			)
			(layer "F.Fab")
		)
		(fp_line
			(start -0.67945 -0.305054)
			(end -0.12065 -0.305054)
			(stroke
				(width 0.1)
				(type default)
			)
			(layer "F.Fab")
		)
		(pad "1" smd circle
			(at -0.40005 0 180)
			(size 0 0)
			(layers "F.Cu" "F.Mask" "F.Paste")
			(net "PRSNTB3_NIC4_N")
		)
		(pad "2" smd circle
			(at 0.40005 0 180)
			(size 0 0)
			(layers "F.Cu" "F.Mask" "F.Paste")
			(net "P3V3_AUX")
		)
	)
	(footprint ""
		(layer "F.Cu")
		(at 89.649808 -270.89989)
		(property "Reference" "H96"
			(at -2.967482 -9.050528 0)
			(unlocked yes)
			(layer "F.SilkS")
			(effects
				(font
					(size 0.7874 0.5842)
					(thickness 0.1524)
				)
				(justify left)
			)
		)
		(property "Value" ""
			(at 0 0 0)
			(layer "F.Fab")
			(effects
				(font
					(size 1.27 1.27)
				)
			)
		)
		(duplicate_pad_numbers_are_jumpers no)
		(fp_arc
			(start -5.469382 -5.83819)
			(mid 3.181563 -7.340126)
			(end 7.999984 0)
			(stroke
				(width 0.1524)
				(type default)
			)
			(layer "F.SilkS")
		)
		(fp_arc
			(start 7.999984 0)
			(mid -0.337504 7.99289)
			(end -7.971536 -0.67437)
			(stroke
				(width 0.1524)
				(type default)
			)
			(layer "F.SilkS")
		)
		(fp_arc
			(start -5.443474 -5.862574)
			(mid 3.197823 -7.333049)
			(end 7.999984 0)
			(stroke
				(width 0.1524)
				(type default)
			)
			(layer "B.SilkS")
		)
		(fp_arc
			(start 7.999984 0)
			(mid -0.300418 7.994298)
			(end -7.977378 -0.600456)
			(stroke
				(width 0.1524)
				(type default)
			)
			(layer "B.SilkS")
		)
		(fp_circle
			(center 0 0)
			(end 7.999984 0)
			(stroke
				(width 0.1)
				(type default)
			)
			(fill no)
			(layer "B.Fab")
		)
		(fp_circle
			(center 0 0)
			(end 7.999984 0)
			(stroke
				(width 0.1)
				(type default)
			)
			(fill no)
			(layer "F.Fab")
		)
		(pad "" np_thru_hole circle
			(at 0 0)
			(size 4.5212 4.5212)
			(drill 4.5212)
			(layers "*.Cu" "*.Mask")
			(clearance 0.381)
			(thermal_gap 0.381)
		)
		(pad "2" thru_hole circle
			(at 3.6322 0)
			(size 0.762 0.762)
			(drill 0.5588)
			(layers "*.Cu" "*.Mask")
			(remove_unused_layers no)
			(net "GND")
			(clearance 0.1524)
			(thermal_gap 0.1524)
		)
		(pad "3" thru_hole circle
			(at 2.568448 -2.568448)
			(size 0.762 0.762)
			(drill 0.5588)
			(layers "*.Cu" "*.Mask")
			(remove_unused_layers no)
			(net "GND")
			(clearance 0.1524)
			(thermal_gap 0.1524)
		)
		(pad "4" thru_hole circle
			(at 0 -3.6322)
			(size 0.762 0.762)
			(drill 0.5588)
			(layers "*.Cu" "*.Mask")
			(remove_unused_layers no)
			(net "GND")
			(clearance 0.1524)
			(thermal_gap 0.1524)
		)
		(pad "5" thru_hole circle
			(at -2.568448 -2.568448)
			(size 0.762 0.762)
			(drill 0.5588)
			(layers "*.Cu" "*.Mask")
			(remove_unused_layers no)
			(net "GND")
			(clearance 0.1524)
			(thermal_gap 0.1524)
		)
		(pad "6" thru_hole circle
			(at -3.6322 0)
			(size 0.762 0.762)
			(drill 0.5588)
			(layers "*.Cu" "*.Mask")
			(remove_unused_layers no)
			(net "GND")
			(clearance 0.1524)
			(thermal_gap 0.1524)
		)
		(pad "7" thru_hole circle
			(at -2.568448 2.568448)
			(size 0.762 0.762)
			(drill 0.5588)
			(layers "*.Cu" "*.Mask")
			(remove_unused_layers no)
			(net "GND")
			(clearance 0.1524)
			(thermal_gap 0.1524)
		)
		(pad "8" thru_hole circle
			(at 0 3.6322)
			(size 0.762 0.762)
			(drill 0.5588)
			(layers "*.Cu" "*.Mask")
			(remove_unused_layers no)
			(net "GND")
			(clearance 0.1524)
			(thermal_gap 0.1524)
		)
		(pad "9" thru_hole circle
			(at 2.568448 2.568448)
			(size 0.762 0.762)
			(drill 0.5588)
			(layers "*.Cu" "*.Mask")
			(remove_unused_layers no)
			(net "GND")
			(clearance 0.1524)
			(thermal_gap 0.1524)
		)
		(zone
			(layer "F.Cu")
			(hatch none 0.5)
			(connect_pads
				(clearance 0)
			)
			(min_thickness 0.25)
			(keepout
				(tracks not_allowed)
				(vias allowed)
				(pads allowed)
				(copperpour not_allowed)
				(footprints allowed)
			)
			(placement
				(enabled no)
				(sheetname "")
			)
			(fill
				(thermal_gap 0.5)
				(thermal_bridge_width 0.5)
				(island_removal_mode 0)
			)
			(polygon
				(pts
					(arc
						(start 89.649808 -262.899906)
						(mid 81.649824 -270.89989)
						(end 89.649808 -278.899874)
					)
					(arc
						(start 89.649808 -275.64969)
						(mid 84.900008 -270.89989)
						(end 89.649808 -266.15009)
					)
				)
			)
		)
		(zone
			(layer "F.Cu")
			(hatch none 0.5)
			(connect_pads
				(clearance 0)
			)
			(min_thickness 0.25)
			(keepout
				(tracks not_allowed)
				(vias allowed)
				(pads allowed)
				(copperpour not_allowed)
				(footprints allowed)
			)
			(placement
				(enabled no)
				(sheetname "")
			)
			(fill
				(thermal_gap 0.5)
				(thermal_bridge_width 0.5)
				(island_removal_mode 0)
			)
			(polygon
				(pts
					(arc
						(start 89.649808 -262.899906)
						(mid 97.649792 -270.89989)
						(end 89.649808 -278.899874)
					)
					(arc
						(start 89.649808 -275.64969)
						(mid 94.399608 -270.89989)
						(end 89.649808 -266.15009)
					)
				)
			)
		)
		(zone
			(layers "F.Cu" "B.Cu" "In1.Cu" "In2.Cu" "In3.Cu" "In4.Cu" "In5.Cu" "In6.Cu"
				"In7.Cu" "In8.Cu" "In9.Cu" "In10.Cu" "In11.Cu" "In12.Cu" "In13.Cu" "In14.Cu"
				"In15.Cu" "In16.Cu"
			)
			(hatch none 0.5)
			(connect_pads
				(clearance 0)
			)
			(min_thickness 0.25)
			(keepout
				(tracks not_allowed)
				(vias allowed)
				(pads allowed)
				(copperpour not_allowed)
				(footprints allowed)
			)
			(placement
				(enabled no)
				(sheetname "")
			)
			(fill
				(thermal_gap 0.5)
				(thermal_bridge_width 0.5)
				(island_removal_mode 0)
			)
			(polygon
				(pts
					(arc
						(start 92.415868 -270.89989)
						(mid 86.883748 -270.89989)
						(end 92.415868 -270.89989)
					)
				)
			)
		)
		(zone
			(layer "B.Cu")
			(hatch none 0.5)
			(connect_pads
				(clearance 0)
			)
			(min_thickness 0.25)
			(keepout
				(tracks not_allowed)
				(vias allowed)
				(pads allowed)
				(copperpour not_allowed)
				(footprints allowed)
			)
			(placement
				(enabled no)
				(sheetname "")
			)
			(fill
				(thermal_gap 0.5)
				(thermal_bridge_width 0.5)
				(island_removal_mode 0)
			)
			(polygon
				(pts
					(arc
						(start 89.649808 -265.89609)
						(mid 84.646008 -270.89989)
						(end 89.649808 -275.90369)
					)
					(arc
						(start 89.649808 -275.42109)
						(mid 85.128608 -270.89989)
						(end 89.649808 -266.37869)
					)
				)
			)
		)
		(zone
			(layer "B.Cu")
			(hatch none 0.5)
			(connect_pads
				(clearance 0)
			)
			(min_thickness 0.25)
			(keepout
				(tracks not_allowed)
				(vias allowed)
				(pads allowed)
				(copperpour not_allowed)
				(footprints allowed)
			)
			(placement
				(enabled no)
				(sheetname "")
			)
			(fill
				(thermal_gap 0.5)
				(thermal_bridge_width 0.5)
				(island_removal_mode 0)
			)
			(polygon
				(pts
					(arc
						(start 89.649808 -265.89609)
						(mid 94.653608 -270.89989)
						(end 89.649808 -275.90369)
					)
					(arc
						(start 89.649808 -275.42109)
						(mid 94.171008 -270.89989)
						(end 89.649808 -266.37869)
					)
				)
			)
		)
	)
	(footprint ""
		(layer "F.Cu")
		(at 255.01346 -195.573396 90)
		(property "Reference" "R5066"
			(at 0 0 90)
			(layer "F.SilkS")
			(hide yes)
			(effects
				(font
					(size 1.27 1.27)
				)
			)
		)
		(property "Value" ""
			(at 0 0 90)
			(layer "F.Fab")
			(effects
				(font
					(size 1.27 1.27)
				)
			)
		)
		(duplicate_pad_numbers_are_jumpers no)
		(fp_line
			(start 0.7874 -0.4064)
			(end 0.7874 0.4064)
			(stroke
				(width 0.1524)
				(type default)
			)
			(layer "F.SilkS")
		)
		(fp_line
			(start -0.7874 -0.4064)
			(end 0.7874 -0.4064)
			(stroke
				(width 0.1524)
				(type default)
			)
			(layer "F.SilkS")
		)
		(fp_line
			(start 0.7874 0.4064)
			(end -0.7874 0.4064)
			(stroke
				(width 0.1524)
				(type default)
			)
			(layer "F.SilkS")
		)
		(fp_line
			(start -0.7874 0.4064)
			(end -0.7874 -0.4064)
			(stroke
				(width 0.1524)
				(type default)
			)
			(layer "F.SilkS")
		)
		(fp_line
			(start -0.12065 -0.305054)
			(end -0.12065 -0.2794)
			(stroke
				(width 0.1)
				(type default)
			)
			(layer "F.Fab")
		)
		(fp_line
			(start -0.67945 -0.305054)
			(end -0.12065 -0.305054)
			(stroke
				(width 0.1)
				(type default)
			)
			(layer "F.Fab")
		)
		(fp_line
			(start 0.67945 -0.3048)
			(end 0.67945 0.3048)
			(stroke
				(width 0.1)
				(type default)
			)
			(layer "F.Fab")
		)
		(fp_line
			(start 0.12065 -0.3048)
			(end 0.67945 -0.3048)
			(stroke
				(width 0.1)
				(type default)
			)
			(layer "F.Fab")
		)
		(fp_line
			(start 0.12065 -0.2794)
			(end 0.12065 -0.3048)
			(stroke
				(width 0.1)
				(type default)
			)
			(layer "F.Fab")
		)
		(fp_line
			(start -0.12065 -0.2794)
			(end 0.12065 -0.2794)
			(stroke
				(width 0.1)
				(type default)
			)
			(layer "F.Fab")
		)
		(fp_line
			(start 0.120396 0.2794)
			(end -0.12065 0.2794)
			(stroke
				(width 0.1)
				(type default)
			)
			(layer "F.Fab")
		)
		(fp_line
			(start -0.12065 0.2794)
			(end -0.12065 0.3048)
			(stroke
				(width 0.1)
				(type default)
			)
			(layer "F.Fab")
		)
		(fp_line
			(start 0.67945 0.3048)
			(end 0.120396 0.3048)
			(stroke
				(width 0.1)
				(type default)
			)
			(layer "F.Fab")
		)
		(fp_line
			(start 0.120396 0.3048)
			(end 0.120396 0.2794)
			(stroke
				(width 0.1)
				(type default)
			)
			(layer "F.Fab")
		)
		(fp_line
			(start -0.12065 0.3048)
			(end -0.67945 0.3048)
			(stroke
				(width 0.1)
				(type default)
			)
			(layer "F.Fab")
		)
		(fp_line
			(start -0.67945 0.3048)
			(end -0.67945 -0.305054)
			(stroke
				(width 0.1)
				(type default)
			)
			(layer "F.Fab")
		)
		(pad "1" smd circle
			(at -0.40005 0 90)
			(size 0 0)
			(layers "F.Cu" "F.Mask" "F.Paste")
			(net "P3V3_AUX")
		)
		(pad "2" smd circle
			(at 0.40005 0 90)
			(size 0 0)
			(layers "F.Cu" "F.Mask" "F.Paste")
			(net "JTAG_BIC_TMS_R")
		)
	)
	(footprint ""
		(layer "F.Cu")
		(at 440.292744 -118.446804)
		(property "Reference" "PC913"
			(at 0 0 0)
			(layer "F.SilkS")
			(hide yes)
			(effects
				(font
					(size 1.27 1.27)
				)
			)
		)
		(property "Value" ""
			(at 0 0 0)
			(layer "F.Fab")
			(effects
				(font
					(size 1.27 1.27)
				)
			)
		)
		(duplicate_pad_numbers_are_jumpers no)
		(fp_line
			(start -1.524 -0.762)
			(end 1.524 -0.762)
			(stroke
				(width 0.1524)
				(type default)
			)
			(layer "F.SilkS")
		)
		(fp_line
			(start -1.524 0.762)
			(end -1.524 -0.762)
			(stroke
				(width 0.1524)
				(type default)
			)
			(layer "F.SilkS")
		)
		(fp_line
			(start 1.524 -0.762)
			(end 1.524 0.762)
			(stroke
				(width 0.1524)
				(type default)
			)
			(layer "F.SilkS")
		)
		(fp_line
			(start 1.524 0.762)
			(end -1.524 0.762)
			(stroke
				(width 0.1524)
				(type default)
			)
			(layer "F.SilkS")
		)
		(fp_line
			(start -1.1049 -0.724916)
			(end -1.1049 0.724916)
			(stroke
				(width 0.1)
				(type default)
			)
			(layer "F.Fab")
		)
		(fp_line
			(start -1.1049 0.724916)
			(end 1.1049 0.724916)
			(stroke
				(width 0.1)
				(type default)
			)
			(layer "F.Fab")
		)
		(fp_line
			(start 1.1049 -0.724916)
			(end -1.1049 -0.724916)
			(stroke
				(width 0.1)
				(type default)
			)
			(layer "F.Fab")
		)
		(fp_line
			(start 1.1049 0.724916)
			(end 1.1049 -0.724916)
			(stroke
				(width 0.1)
				(type default)
			)
			(layer "F.Fab")
		)
		(pad "1" smd rect
			(at -0.889 0 180)
			(size 1.016 1.27)
			(layers "F.Cu" "F.Mask" "F.Paste")
			(net "P3V3_NIC7")
		)
		(pad "2" smd rect
			(at 0.889 0 180)
			(size 1.016 1.27)
			(layers "F.Cu" "F.Mask" "F.Paste")
			(net "GND")
		)
	)
	(footprint ""
		(layer "F.Cu")
		(at 253.713488 -254.753364 -90)
		(property "Reference" "R6155"
			(at 0 0 270)
			(layer "F.SilkS")
			(hide yes)
			(effects
				(font
					(size 1.27 1.27)
				)
			)
		)
		(property "Value" ""
			(at 0 0 270)
			(layer "F.Fab")
			(effects
				(font
					(size 1.27 1.27)
				)
			)
		)
		(duplicate_pad_numbers_are_jumpers no)
		(fp_line
			(start -0.7874 0.4064)
			(end -0.7874 -0.4064)
			(stroke
				(width 0.1524)
				(type default)
			)
			(layer "F.SilkS")
		)
		(fp_line
			(start 0.7874 0.4064)
			(end -0.7874 0.4064)
			(stroke
				(width 0.1524)
				(type default)
			)
			(layer "F.SilkS")
		)
		(fp_line
			(start -0.7874 -0.4064)
			(end 0.7874 -0.4064)
			(stroke
				(width 0.1524)
				(type default)
			)
			(layer "F.SilkS")
		)
		(fp_line
			(start 0.7874 -0.4064)
			(end 0.7874 0.4064)
			(stroke
				(width 0.1524)
				(type default)
			)
			(layer "F.SilkS")
		)
		(fp_line
			(start -0.67945 0.3048)
			(end -0.67945 -0.305054)
			(stroke
				(width 0.1)
				(type default)
			)
			(layer "F.Fab")
		)
		(fp_line
			(start -0.12065 0.3048)
			(end -0.67945 0.3048)
			(stroke
				(width 0.1)
				(type default)
			)
			(layer "F.Fab")
		)
		(fp_line
			(start 0.120396 0.3048)
			(end 0.120396 0.2794)
			(stroke
				(width 0.1)
				(type default)
			)
			(layer "F.Fab")
		)
		(fp_line
			(start 0.67945 0.3048)
			(end 0.120396 0.3048)
			(stroke
				(width 0.1)
				(type default)
			)
			(layer "F.Fab")
		)
		(fp_line
			(start -0.12065 0.2794)
			(end -0.12065 0.3048)
			(stroke
				(width 0.1)
				(type default)
			)
			(layer "F.Fab")
		)
		(fp_line
			(start 0.120396 0.2794)
			(end -0.12065 0.2794)
			(stroke
				(width 0.1)
				(type default)
			)
			(layer "F.Fab")
		)
		(fp_line
			(start -0.12065 -0.2794)
			(end 0.12065 -0.2794)
			(stroke
				(width 0.1)
				(type default)
			)
			(layer "F.Fab")
		)
		(fp_line
			(start 0.12065 -0.2794)
			(end 0.12065 -0.3048)
			(stroke
				(width 0.1)
				(type default)
			)
			(layer "F.Fab")
		)
		(fp_line
			(start 0.12065 -0.3048)
			(end 0.67945 -0.3048)
			(stroke
				(width 0.1)
				(type default)
			)
			(layer "F.Fab")
		)
		(fp_line
			(start 0.67945 -0.3048)
			(end 0.67945 0.3048)
			(stroke
				(width 0.1)
				(type default)
			)
			(layer "F.Fab")
		)
		(fp_line
			(start -0.67945 -0.305054)
			(end -0.12065 -0.305054)
			(stroke
				(width 0.1)
				(type default)
			)
			(layer "F.Fab")
		)
		(fp_line
			(start -0.12065 -0.305054)
			(end -0.12065 -0.2794)
			(stroke
				(width 0.1)
				(type default)
			)
			(layer "F.Fab")
		)
		(pad "1" smd circle
			(at -0.40005 0 270)
			(size 0 0)
			(layers "F.Cu" "F.Mask" "F.Paste")
			(net "PEX2_SYS_ERR_R_N")
		)
		(pad "2" smd circle
			(at 0.40005 0 270)
			(size 0 0)
			(layers "F.Cu" "F.Mask" "F.Paste")
			(net "P1V8_PEX")
		)
	)
	(footprint ""
		(layer "F.Cu")
		(at 260.205474 -258.511548 -90)
		(property "Reference" "C3422"
			(at 0 0 270)
			(layer "F.SilkS")
			(hide yes)
			(effects
				(font
					(size 1.27 1.27)
				)
			)
		)
		(property "Value" ""
			(at 0 0 270)
			(layer "F.Fab")
			(effects
				(font
					(size 1.27 1.27)
				)
			)
		)
		(duplicate_pad_numbers_are_jumpers no)
		(fp_line
			(start -1.2954 0.5842)
			(end -1.2954 -0.5842)
			(stroke
				(width 0.1524)
				(type default)
			)
			(layer "F.SilkS")
		)
		(fp_line
			(start 1.2954 0.5842)
			(end -1.2954 0.5842)
			(stroke
				(width 0.1524)
				(type default)
			)
			(layer "F.SilkS")
		)
		(fp_line
			(start -1.2954 -0.5842)
			(end 1.2954 -0.5842)
			(stroke
				(width 0.1524)
				(type default)
			)
			(layer "F.SilkS")
		)
		(fp_line
			(start 1.2954 -0.5842)
			(end 1.2954 0.5842)
			(stroke
				(width 0.1524)
				(type default)
			)
			(layer "F.SilkS")
		)
		(fp_line
			(start -0.8636 0.4572)
			(end -0.8636 0.4064)
			(stroke
				(width 0.1)
				(type default)
			)
			(layer "F.Fab")
		)
		(fp_line
			(start 0.8636 0.4572)
			(end -0.8636 0.4572)
			(stroke
				(width 0.1)
				(type default)
			)
			(layer "F.Fab")
		)
		(fp_line
			(start -1.1938 0.4064)
			(end -1.1938 -0.4064)
			(stroke
				(width 0.1)
				(type default)
			)
			(layer "F.Fab")
		)
		(fp_line
			(start -0.8636 0.4064)
			(end -1.1938 0.4064)
			(stroke
				(width 0.1)
				(type default)
			)
			(layer "F.Fab")
		)
		(fp_line
			(start 0.8636 0.4064)
			(end 0.8636 0.4572)
			(stroke
				(width 0.1)
				(type default)
			)
			(layer "F.Fab")
		)
		(fp_line
			(start 1.1938 0.4064)
			(end 0.8636 0.4064)
			(stroke
				(width 0.1)
				(type default)
			)
			(layer "F.Fab")
		)
		(fp_line
			(start -1.1938 -0.4064)
			(end -0.8636 -0.4064)
			(stroke
				(width 0.1)
				(type default)
			)
			(layer "F.Fab")
		)
		(fp_line
			(start -0.8636 -0.4064)
			(end -0.8636 -0.4572)
			(stroke
				(width 0.1)
				(type default)
			)
			(layer "F.Fab")
		)
		(fp_line
			(start 0.8636 -0.4064)
			(end 1.1938 -0.4064)
			(stroke
				(width 0.1)
				(type default)
			)
			(layer "F.Fab")
		)
		(fp_line
			(start 1.1938 -0.4064)
			(end 1.1938 0.4064)
			(stroke
				(width 0.1)
				(type default)
			)
			(layer "F.Fab")
		)
		(fp_line
			(start -0.8636 -0.4572)
			(end 0.8636 -0.4572)
			(stroke
				(width 0.1)
				(type default)
			)
			(layer "F.Fab")
		)
		(fp_line
			(start 0.8636 -0.4572)
			(end 0.8636 -0.4064)
			(stroke
				(width 0.1)
				(type default)
			)
			(layer "F.Fab")
		)
		(pad "1" smd rect
			(at -0.7366 0 180)
			(size 0.7112 0.8128)
			(layers "F.Cu" "F.Mask" "F.Paste")
			(net "P1V8_VDDA_PEX2_R")
		)
		(pad "2" smd rect
			(at 0.7366 0 180)
			(size 0.7112 0.8128)
			(layers "F.Cu" "F.Mask" "F.Paste")
			(net "GND")
		)
	)
	(footprint ""
		(layer "F.Cu")
		(at 104.385872 -272.15846 -90)
		(property "Reference" "PL5"
			(at 4.844034 0.527304 0)
			(unlocked yes)
			(layer "F.SilkS")
			(effects
				(font
					(size 0.7874 0.5842)
					(thickness 0.1524)
				)
			)
		)
		(property "Value" ""
			(at 0 0 270)
			(layer "F.Fab")
			(effects
				(font
					(size 1.27 1.27)
				)
			)
		)
		(duplicate_pad_numbers_are_jumpers no)
		(fp_line
			(start -2.249932 2.249932)
			(end -2.249932 1.3843)
			(stroke
				(width 0.1524)
				(type default)
			)
			(layer "F.SilkS")
		)
		(fp_line
			(start 2.249932 2.249932)
			(end -2.249932 2.249932)
			(stroke
				(width 0.1524)
				(type default)
			)
			(layer "F.SilkS")
		)
		(fp_line
			(start 2.249932 1.3843)
			(end 2.249932 2.249932)
			(stroke
				(width 0.1524)
				(type default)
			)
			(layer "F.SilkS")
		)
		(fp_line
			(start -2.249932 -1.3843)
			(end -2.249932 -2.249932)
			(stroke
				(width 0.1524)
				(type default)
			)
			(layer "F.SilkS")
		)
		(fp_line
			(start -2.249932 -2.249932)
			(end 2.249932 -2.249932)
			(stroke
				(width 0.1524)
				(type default)
			)
			(layer "F.SilkS")
		)
		(fp_line
			(start 2.249932 -2.249932)
			(end 2.249932 -1.3843)
			(stroke
				(width 0.1524)
				(type default)
			)
			(layer "F.SilkS")
		)
		(fp_line
			(start -2.249932 2.249932)
			(end -2.249932 -2.249932)
			(stroke
				(width 0.1)
				(type default)
			)
			(layer "F.Fab")
		)
		(fp_line
			(start 2.249932 2.249932)
			(end -2.249932 2.249932)
			(stroke
				(width 0.1)
				(type default)
			)
			(layer "F.Fab")
		)
		(fp_line
			(start -2.249932 -2.249932)
			(end 2.249932 -2.249932)
			(stroke
				(width 0.1)
				(type default)
			)
			(layer "F.Fab")
		)
		(fp_line
			(start 2.249932 -2.249932)
			(end 2.249932 2.249932)
			(stroke
				(width 0.1)
				(type default)
			)
			(layer "F.Fab")
		)
		(pad "1" smd rect
			(at -1.82499 0 270)
			(size 1.0668 2.5146)
			(layers "F.Cu" "F.Mask" "F.Paste")
			(net "SW_P12V_P0V8_PEX0_FLT")
		)
		(pad "2" smd rect
			(at 1.82499 0 270)
			(size 1.0668 2.5146)
			(layers "F.Cu" "F.Mask" "F.Paste")
			(net "P12V_AUX")
		)
	)
	(footprint ""
		(layer "F.Cu")
		(at 363.474 -209.931)
		(property "Reference" "R4604"
			(at 0 0 0)
			(layer "F.SilkS")
			(hide yes)
			(effects
				(font
					(size 1.27 1.27)
				)
			)
		)
		(property "Value" ""
			(at 0 0 0)
			(layer "F.Fab")
			(effects
				(font
					(size 1.27 1.27)
				)
			)
		)
		(duplicate_pad_numbers_are_jumpers no)
		(fp_line
			(start -0.7874 -0.4064)
			(end 0.7874 -0.4064)
			(stroke
				(width 0.1524)
				(type default)
			)
			(layer "F.SilkS")
		)
		(fp_line
			(start -0.7874 0.4064)
			(end -0.7874 -0.4064)
			(stroke
				(width 0.1524)
				(type default)
			)
			(layer "F.SilkS")
		)
		(fp_line
			(start 0.7874 -0.4064)
			(end 0.7874 0.4064)
			(stroke
				(width 0.1524)
				(type default)
			)
			(layer "F.SilkS")
		)
		(fp_line
			(start 0.7874 0.4064)
			(end -0.7874 0.4064)
			(stroke
				(width 0.1524)
				(type default)
			)
			(layer "F.SilkS")
		)
		(fp_line
			(start -0.67945 -0.305054)
			(end -0.12065 -0.305054)
			(stroke
				(width 0.1)
				(type default)
			)
			(layer "F.Fab")
		)
		(fp_line
			(start -0.67945 0.3048)
			(end -0.67945 -0.305054)
			(stroke
				(width 0.1)
				(type default)
			)
			(layer "F.Fab")
		)
		(fp_line
			(start -0.12065 -0.305054)
			(end -0.12065 -0.2794)
			(stroke
				(width 0.1)
				(type default)
			)
			(layer "F.Fab")
		)
		(fp_line
			(start -0.12065 -0.2794)
			(end 0.12065 -0.2794)
			(stroke
				(width 0.1)
				(type default)
			)
			(layer "F.Fab")
		)
		(fp_line
			(start -0.12065 0.2794)
			(end -0.12065 0.3048)
			(stroke
				(width 0.1)
				(type default)
			)
			(layer "F.Fab")
		)
		(fp_line
			(start -0.12065 0.3048)
			(end -0.67945 0.3048)
			(stroke
				(width 0.1)
				(type default)
			)
			(layer "F.Fab")
		)
		(fp_line
			(start 0.120396 0.2794)
			(end -0.12065 0.2794)
			(stroke
				(width 0.1)
				(type default)
			)
			(layer "F.Fab")
		)
		(fp_line
			(start 0.120396 0.3048)
			(end 0.120396 0.2794)
			(stroke
				(width 0.1)
				(type default)
			)
			(layer "F.Fab")
		)
		(fp_line
			(start 0.12065 -0.3048)
			(end 0.67945 -0.3048)
			(stroke
				(width 0.1)
				(type default)
			)
			(layer "F.Fab")
		)
		(fp_line
			(start 0.12065 -0.2794)
			(end 0.12065 -0.3048)
			(stroke
				(width 0.1)
				(type default)
			)
			(layer "F.Fab")
		)
		(fp_line
			(start 0.67945 -0.3048)
			(end 0.67945 0.3048)
			(stroke
				(width 0.1)
				(type default)
			)
			(layer "F.Fab")
		)
		(fp_line
			(start 0.67945 0.3048)
			(end 0.120396 0.3048)
			(stroke
				(width 0.1)
				(type default)
			)
			(layer "F.Fab")
		)
		(pad "1" smd circle
			(at -0.40005 0)
			(size 0 0)
			(layers "F.Cu" "F.Mask" "F.Paste")
			(net "P3V3_AUX")
		)
		(pad "2" smd circle
			(at 0.40005 0)
			(size 0 0)
			(layers "F.Cu" "F.Mask" "F.Paste")
			(net "RST_PEX_SSD0_PERST_R_N")
		)
	)
	(footprint ""
		(layer "F.Cu")
		(at 140.074142 -179.961286 180)
		(property "Reference" "R1105"
			(at 0 0 180)
			(layer "F.SilkS")
			(hide yes)
			(effects
				(font
					(size 1.27 1.27)
				)
			)
		)
		(property "Value" ""
			(at 0 0 180)
			(layer "F.Fab")
			(effects
				(font
					(size 1.27 1.27)
				)
			)
		)
		(duplicate_pad_numbers_are_jumpers no)
		(fp_line
			(start -0.7874 -0.4064)
			(end 0.7874 -0.4064)
			(stroke
				(width 0.1524)
				(type default)
			)
			(layer "F.SilkS")
		)
		(fp_line
			(start 0.67945 0.3048)
			(end 0.120396 0.3048)
			(stroke
				(width 0.1)
				(type default)
			)
			(layer "F.Fab")
		)
		(fp_line
			(start 0.67945 -0.3048)
			(end 0.67945 0.3048)
			(stroke
				(width 0.1)
				(type default)
			)
			(layer "F.Fab")
		)
		(fp_line
			(start 0.12065 -0.2794)
			(end 0.12065 -0.3048)
			(stroke
				(width 0.1)
				(type default)
			)
			(layer "F.Fab")
		)
		(fp_line
			(start 0.12065 -0.3048)
			(end 0.67945 -0.3048)
			(stroke
				(width 0.1)
				(type default)
			)
			(layer "F.Fab")
		)
		(fp_line
			(start 0.120396 0.3048)
			(end 0.120396 0.2794)
			(stroke
				(width 0.1)
				(type default)
			)
			(layer "F.Fab")
		)
		(fp_line
			(start 0.120396 0.2794)
			(end -0.12065 0.2794)
			(stroke
				(width 0.1)
				(type default)
			)
			(layer "F.Fab")
		)
		(fp_line
			(start -0.12065 0.3048)
			(end -0.67945 0.3048)
			(stroke
				(width 0.1)
				(type default)
			)
			(layer "F.Fab")
		)
		(fp_line
			(start -0.12065 0.2794)
			(end -0.12065 0.3048)
			(stroke
				(width 0.1)
				(type default)
			)
			(layer "F.Fab")
		)
		(fp_line
			(start -0.12065 -0.2794)
			(end 0.12065 -0.2794)
			(stroke
				(width 0.1)
				(type default)
			)
			(layer "F.Fab")
		)
		(fp_line
			(start -0.12065 -0.305054)
			(end -0.12065 -0.2794)
			(stroke
				(width 0.1)
				(type default)
			)
			(layer "F.Fab")
		)
		(fp_line
			(start -0.67945 0.3048)
			(end -0.67945 -0.305054)
			(stroke
				(width 0.1)
				(type default)
			)
			(layer "F.Fab")
		)
		(fp_line
			(start -0.67945 -0.305054)
			(end -0.12065 -0.305054)
			(stroke
				(width 0.1)
				(type default)
			)
			(layer "F.Fab")
		)
		(pad "1" smd circle
			(at -0.40005 0 180)
			(size 0 0)
			(layers "F.Cu" "F.Mask" "F.Paste")
			(net "CLK_100M_DB2000QL_NIC5_R_DP")
		)
		(pad "2" smd circle
			(at 0.40005 0 180)
			(size 0 0)
			(layers "F.Cu" "F.Mask" "F.Paste")
			(net "CLK_100M_DB2000QL_NIC5_DP")
		)
	)
	(footprint ""
		(layer "F.Cu")
		(at 321.21221 -300.64202 -90)
		(property "Reference" "R3976"
			(at 0 0 270)
			(layer "F.SilkS")
			(hide yes)
			(effects
				(font
					(size 1.27 1.27)
				)
			)
		)
		(property "Value" ""
			(at 0 0 270)
			(layer "F.Fab")
			(effects
				(font
					(size 1.27 1.27)
				)
			)
		)
		(duplicate_pad_numbers_are_jumpers no)
		(fp_line
			(start -0.7874 0.4064)
			(end -0.7874 -0.4064)
			(stroke
				(width 0.1524)
				(type default)
			)
			(layer "F.SilkS")
		)
		(fp_line
			(start 0.7874 0.4064)
			(end -0.7874 0.4064)
			(stroke
				(width 0.1524)
				(type default)
			)
			(layer "F.SilkS")
		)
		(fp_line
			(start -0.7874 -0.4064)
			(end 0.7874 -0.4064)
			(stroke
				(width 0.1524)
				(type default)
			)
			(layer "F.SilkS")
		)
		(fp_line
			(start 0.7874 -0.4064)
			(end 0.7874 0.4064)
			(stroke
				(width 0.1524)
				(type default)
			)
			(layer "F.SilkS")
		)
		(fp_line
			(start -0.67945 0.3048)
			(end -0.67945 -0.305054)
			(stroke
				(width 0.1)
				(type default)
			)
			(layer "F.Fab")
		)
		(fp_line
			(start -0.12065 0.3048)
			(end -0.67945 0.3048)
			(stroke
				(width 0.1)
				(type default)
			)
			(layer "F.Fab")
		)
		(fp_line
			(start 0.120396 0.3048)
			(end 0.120396 0.2794)
			(stroke
				(width 0.1)
				(type default)
			)
			(layer "F.Fab")
		)
		(fp_line
			(start 0.67945 0.3048)
			(end 0.120396 0.3048)
			(stroke
				(width 0.1)
				(type default)
			)
			(layer "F.Fab")
		)
		(fp_line
			(start -0.12065 0.2794)
			(end -0.12065 0.3048)
			(stroke
				(width 0.1)
				(type default)
			)
			(layer "F.Fab")
		)
		(fp_line
			(start 0.120396 0.2794)
			(end -0.12065 0.2794)
			(stroke
				(width 0.1)
				(type default)
			)
			(layer "F.Fab")
		)
		(fp_line
			(start -0.12065 -0.2794)
			(end 0.12065 -0.2794)
			(stroke
				(width 0.1)
				(type default)
			)
			(layer "F.Fab")
		)
		(fp_line
			(start 0.12065 -0.2794)
			(end 0.12065 -0.3048)
			(stroke
				(width 0.1)
				(type default)
			)
			(layer "F.Fab")
		)
		(fp_line
			(start 0.12065 -0.3048)
			(end 0.67945 -0.3048)
			(stroke
				(width 0.1)
				(type default)
			)
			(layer "F.Fab")
		)
		(fp_line
			(start 0.67945 -0.3048)
			(end 0.67945 0.3048)
			(stroke
				(width 0.1)
				(type default)
			)
			(layer "F.Fab")
		)
		(fp_line
			(start -0.67945 -0.305054)
			(end -0.12065 -0.305054)
			(stroke
				(width 0.1)
				(type default)
			)
			(layer "F.Fab")
		)
		(fp_line
			(start -0.12065 -0.305054)
			(end -0.12065 -0.2794)
			(stroke
				(width 0.1)
				(type default)
			)
			(layer "F.Fab")
		)
		(pad "1" smd circle
			(at -0.40005 0 270)
			(size 0 0)
			(layers "F.Cu" "F.Mask" "F.Paste")
			(net "I2C0_PEX2_SHPC_SDA")
		)
		(pad "2" smd circle
			(at 0.40005 0 270)
			(size 0 0)
			(layers "F.Cu" "F.Mask" "F.Paste")
			(net "I2C_PEX2_HOST_SDA")
		)
	)
	(footprint ""
		(layer "F.Cu")
		(at 382.410462 -63.652146 180)
		(property "Reference" "R6017"
			(at 0 0 180)
			(layer "F.SilkS")
			(hide yes)
			(effects
				(font
					(size 1.27 1.27)
				)
			)
		)
		(property "Value" ""
			(at 0 0 180)
			(layer "F.Fab")
			(effects
				(font
					(size 1.27 1.27)
				)
			)
		)
		(duplicate_pad_numbers_are_jumpers no)
		(fp_line
			(start 0.7874 0.4064)
			(end -0.7874 0.4064)
			(stroke
				(width 0.1524)
				(type default)
			)
			(layer "F.SilkS")
		)
		(fp_line
			(start 0.7874 -0.4064)
			(end 0.7874 0.4064)
			(stroke
				(width 0.1524)
				(type default)
			)
			(layer "F.SilkS")
		)
		(fp_line
			(start -0.7874 0.4064)
			(end -0.7874 -0.4064)
			(stroke
				(width 0.1524)
				(type default)
			)
			(layer "F.SilkS")
		)
		(fp_line
			(start -0.7874 -0.4064)
			(end 0.7874 -0.4064)
			(stroke
				(width 0.1524)
				(type default)
			)
			(layer "F.SilkS")
		)
		(fp_line
			(start 0.67945 0.3048)
			(end 0.120396 0.3048)
			(stroke
				(width 0.1)
				(type default)
			)
			(layer "F.Fab")
		)
		(fp_line
			(start 0.67945 -0.3048)
			(end 0.67945 0.3048)
			(stroke
				(width 0.1)
				(type default)
			)
			(layer "F.Fab")
		)
		(fp_line
			(start 0.12065 -0.2794)
			(end 0.12065 -0.3048)
			(stroke
				(width 0.1)
				(type default)
			)
			(layer "F.Fab")
		)
		(fp_line
			(start 0.12065 -0.3048)
			(end 0.67945 -0.3048)
			(stroke
				(width 0.1)
				(type default)
			)
			(layer "F.Fab")
		)
		(fp_line
			(start 0.120396 0.3048)
			(end 0.120396 0.2794)
			(stroke
				(width 0.1)
				(type default)
			)
			(layer "F.Fab")
		)
		(fp_line
			(start 0.120396 0.2794)
			(end -0.12065 0.2794)
			(stroke
				(width 0.1)
				(type default)
			)
			(layer "F.Fab")
		)
		(fp_line
			(start -0.12065 0.3048)
			(end -0.67945 0.3048)
			(stroke
				(width 0.1)
				(type default)
			)
			(layer "F.Fab")
		)
		(fp_line
			(start -0.12065 0.2794)
			(end -0.12065 0.3048)
			(stroke
				(width 0.1)
				(type default)
			)
			(layer "F.Fab")
		)
		(fp_line
			(start -0.12065 -0.2794)
			(end 0.12065 -0.2794)
			(stroke
				(width 0.1)
				(type default)
			)
			(layer "F.Fab")
		)
		(fp_line
			(start -0.12065 -0.305054)
			(end -0.12065 -0.2794)
			(stroke
				(width 0.1)
				(type default)
			)
			(layer "F.Fab")
		)
		(fp_line
			(start -0.67945 0.3048)
			(end -0.67945 -0.305054)
			(stroke
				(width 0.1)
				(type default)
			)
			(layer "F.Fab")
		)
		(fp_line
			(start -0.67945 -0.305054)
			(end -0.12065 -0.305054)
			(stroke
				(width 0.1)
				(type default)
			)
			(layer "F.Fab")
		)
		(pad "1" smd circle
			(at -0.40005 0 180)
			(size 0 0)
			(layers "F.Cu" "F.Mask" "F.Paste")
			(net "P5V_AUX")
		)
		(pad "2" smd circle
			(at 0.40005 0 180)
			(size 0 0)
			(layers "F.Cu" "F.Mask" "F.Paste")
			(net "P12V_SSD13_PG_G2")
		)
	)
	(footprint ""
		(layer "F.Cu")
		(at 139.817348 -343.952322 90)
		(property "Reference" "C2263"
			(at 0 0 90)
			(layer "F.SilkS")
			(hide yes)
			(effects
				(font
					(size 1.27 1.27)
				)
			)
		)
		(property "Value" ""
			(at 0 0 90)
			(layer "F.Fab")
			(effects
				(font
					(size 1.27 1.27)
				)
			)
		)
		(duplicate_pad_numbers_are_jumpers no)
		(fp_line
			(start 0.299974 -0.150114)
			(end 0.299974 0.150114)
			(stroke
				(width 0.1)
				(type default)
			)
			(layer "F.Fab")
		)
		(fp_line
			(start -0.299974 -0.150114)
			(end 0.299974 -0.150114)
			(stroke
				(width 0.1)
				(type default)
			)
			(layer "F.Fab")
		)
		(fp_line
			(start 0.299974 0.150114)
			(end -0.299974 0.150114)
			(stroke
				(width 0.1)
				(type default)
			)
			(layer "F.Fab")
		)
		(fp_line
			(start -0.299974 0.150114)
			(end -0.299974 -0.150114)
			(stroke
				(width 0.1)
				(type default)
			)
			(layer "F.Fab")
		)
		(pad "1" smd rect
			(at -0.2667 0 90)
			(size 0.3048 0.381)
			(layers "F.Cu" "F.Mask" "F.Paste")
			(net "P5E_PEX1_STN5_TX_DP<85>")
		)
		(pad "2" smd rect
			(at 0.2667 0 90)
			(size 0.3048 0.381)
			(layers "F.Cu" "F.Mask" "F.Paste")
			(net "P5E_PEX1_STN5_TX_C_DP<85>")
		)
	)
	(footprint ""
		(layer "F.Cu")
		(at 38.782752 -141.87297)
		(property "Reference" "R32"
			(at 0 0 0)
			(layer "F.SilkS")
			(hide yes)
			(effects
				(font
					(size 1.27 1.27)
				)
			)
		)
		(property "Value" ""
			(at 0 0 0)
			(layer "F.Fab")
			(effects
				(font
					(size 1.27 1.27)
				)
			)
		)
		(duplicate_pad_numbers_are_jumpers no)
		(fp_line
			(start -0.7874 -0.4064)
			(end 0.7874 -0.4064)
			(stroke
				(width 0.1524)
				(type default)
			)
			(layer "F.SilkS")
		)
		(fp_line
			(start -0.7874 0.4064)
			(end -0.7874 -0.4064)
			(stroke
				(width 0.1524)
				(type default)
			)
			(layer "F.SilkS")
		)
		(fp_line
			(start 0.7874 -0.4064)
			(end 0.7874 0.4064)
			(stroke
				(width 0.1524)
				(type default)
			)
			(layer "F.SilkS")
		)
		(fp_line
			(start 0.7874 0.4064)
			(end -0.7874 0.4064)
			(stroke
				(width 0.1524)
				(type default)
			)
			(layer "F.SilkS")
		)
		(fp_line
			(start -0.67945 -0.305054)
			(end -0.12065 -0.305054)
			(stroke
				(width 0.1)
				(type default)
			)
			(layer "F.Fab")
		)
		(fp_line
			(start -0.67945 0.3048)
			(end -0.67945 -0.305054)
			(stroke
				(width 0.1)
				(type default)
			)
			(layer "F.Fab")
		)
		(fp_line
			(start -0.12065 -0.305054)
			(end -0.12065 -0.2794)
			(stroke
				(width 0.1)
				(type default)
			)
			(layer "F.Fab")
		)
		(fp_line
			(start -0.12065 -0.2794)
			(end 0.12065 -0.2794)
			(stroke
				(width 0.1)
				(type default)
			)
			(layer "F.Fab")
		)
		(fp_line
			(start -0.12065 0.2794)
			(end -0.12065 0.3048)
			(stroke
				(width 0.1)
				(type default)
			)
			(layer "F.Fab")
		)
		(fp_line
			(start -0.12065 0.3048)
			(end -0.67945 0.3048)
			(stroke
				(width 0.1)
				(type default)
			)
			(layer "F.Fab")
		)
		(fp_line
			(start 0.120396 0.2794)
			(end -0.12065 0.2794)
			(stroke
				(width 0.1)
				(type default)
			)
			(layer "F.Fab")
		)
		(fp_line
			(start 0.120396 0.3048)
			(end 0.120396 0.2794)
			(stroke
				(width 0.1)
				(type default)
			)
			(layer "F.Fab")
		)
		(fp_line
			(start 0.12065 -0.3048)
			(end 0.67945 -0.3048)
			(stroke
				(width 0.1)
				(type default)
			)
			(layer "F.Fab")
		)
		(fp_line
			(start 0.12065 -0.2794)
			(end 0.12065 -0.3048)
			(stroke
				(width 0.1)
				(type default)
			)
			(layer "F.Fab")
		)
		(fp_line
			(start 0.67945 -0.3048)
			(end 0.67945 0.3048)
			(stroke
				(width 0.1)
				(type default)
			)
			(layer "F.Fab")
		)
		(fp_line
			(start 0.67945 0.3048)
			(end 0.120396 0.3048)
			(stroke
				(width 0.1)
				(type default)
			)
			(layer "F.Fab")
		)
		(pad "1" smd circle
			(at -0.40005 0)
			(size 0 0)
			(layers "F.Cu" "F.Mask" "F.Paste")
			(net "NIC0_BIF1_N")
		)
		(pad "2" smd circle
			(at 0.40005 0)
			(size 0 0)
			(layers "F.Cu" "F.Mask" "F.Paste")
			(net "GND")
		)
	)
	(footprint ""
		(layer "F.Cu")
		(at 240.121948 -83.951318)
		(property "Reference" "R6723"
			(at 0 0 0)
			(layer "F.SilkS")
			(hide yes)
			(effects
				(font
					(size 1.27 1.27)
				)
			)
		)
		(property "Value" ""
			(at 0 0 0)
			(layer "F.Fab")
			(effects
				(font
					(size 1.27 1.27)
				)
			)
		)
		(duplicate_pad_numbers_are_jumpers no)
		(fp_line
			(start -0.7874 -0.4064)
			(end 0.7874 -0.4064)
			(stroke
				(width 0.1524)
				(type default)
			)
			(layer "F.SilkS")
		)
		(fp_line
			(start -0.7874 0.4064)
			(end -0.7874 -0.4064)
			(stroke
				(width 0.1524)
				(type default)
			)
			(layer "F.SilkS")
		)
		(fp_line
			(start 0.7874 -0.4064)
			(end 0.7874 0.4064)
			(stroke
				(width 0.1524)
				(type default)
			)
			(layer "F.SilkS")
		)
		(fp_line
			(start 0.7874 0.4064)
			(end 0.007366 0.4064)
			(stroke
				(width 0.1524)
				(type default)
			)
			(layer "F.SilkS")
		)
		(fp_line
			(start -0.67945 -0.305054)
			(end -0.12065 -0.305054)
			(stroke
				(width 0.1)
				(type default)
			)
			(layer "F.Fab")
		)
		(fp_line
			(start -0.67945 0.3048)
			(end -0.67945 -0.305054)
			(stroke
				(width 0.1)
				(type default)
			)
			(layer "F.Fab")
		)
		(fp_line
			(start -0.12065 -0.305054)
			(end -0.12065 -0.2794)
			(stroke
				(width 0.1)
				(type default)
			)
			(layer "F.Fab")
		)
		(fp_line
			(start -0.12065 -0.2794)
			(end 0.12065 -0.2794)
			(stroke
				(width 0.1)
				(type default)
			)
			(layer "F.Fab")
		)
		(fp_line
			(start -0.12065 0.2794)
			(end -0.12065 0.3048)
			(stroke
				(width 0.1)
				(type default)
			)
			(layer "F.Fab")
		)
		(fp_line
			(start -0.12065 0.3048)
			(end -0.67945 0.3048)
			(stroke
				(width 0.1)
				(type default)
			)
			(layer "F.Fab")
		)
		(fp_line
			(start 0.120396 0.2794)
			(end -0.12065 0.2794)
			(stroke
				(width 0.1)
				(type default)
			)
			(layer "F.Fab")
		)
		(fp_line
			(start 0.120396 0.3048)
			(end 0.120396 0.2794)
			(stroke
				(width 0.1)
				(type default)
			)
			(layer "F.Fab")
		)
		(fp_line
			(start 0.12065 -0.3048)
			(end 0.67945 -0.3048)
			(stroke
				(width 0.1)
				(type default)
			)
			(layer "F.Fab")
		)
		(fp_line
			(start 0.12065 -0.2794)
			(end 0.12065 -0.3048)
			(stroke
				(width 0.1)
				(type default)
			)
			(layer "F.Fab")
		)
		(fp_line
			(start 0.67945 -0.3048)
			(end 0.67945 0.3048)
			(stroke
				(width 0.1)
				(type default)
			)
			(layer "F.Fab")
		)
		(fp_line
			(start 0.67945 0.3048)
			(end 0.120396 0.3048)
			(stroke
				(width 0.1)
				(type default)
			)
			(layer "F.Fab")
		)
		(pad "1" smd rect
			(at -0.40005 0 180)
			(size 0.4572 0.508)
			(layers "F.Cu" "F.Mask" "F.Paste")
			(net "USB2_CP2108_CLI_DP")
		)
		(pad "2" smd rect
			(at 0.40005 0 180)
			(size 0.4572 0.508)
			(layers "F.Cu" "F.Mask" "F.Paste")
			(net "GND")
		)
	)
	(footprint ""
		(layer "F.Cu")
		(at 149.211538 -258.234434)
		(property "Reference" "L109"
			(at 0 0 0)
			(layer "F.SilkS")
			(hide yes)
			(effects
				(font
					(size 1.27 1.27)
				)
			)
		)
		(property "Value" ""
			(at 0 0 0)
			(layer "F.Fab")
			(effects
				(font
					(size 1.27 1.27)
				)
			)
		)
		(duplicate_pad_numbers_are_jumpers no)
		(fp_line
			(start -1.63576 -0.8128)
			(end -1.63576 0.8128)
			(stroke
				(width 0.1524)
				(type default)
			)
			(layer "F.SilkS")
		)
		(fp_line
			(start -1.63576 -0.8128)
			(end 1.63576 -0.8128)
			(stroke
				(width 0.1524)
				(type default)
			)
			(layer "F.SilkS")
		)
		(fp_line
			(start 1.63576 -0.8128)
			(end 1.63576 0.8128)
			(stroke
				(width 0.1524)
				(type default)
			)
			(layer "F.SilkS")
		)
		(fp_line
			(start 1.63576 0.8128)
			(end -1.63576 0.8128)
			(stroke
				(width 0.1524)
				(type default)
			)
			(layer "F.SilkS")
		)
		(fp_line
			(start -1.56083 -0.738632)
			(end -1.56083 0.7366)
			(stroke
				(width 0.1)
				(type default)
			)
			(layer "F.Fab")
		)
		(fp_line
			(start -1.56083 0.7366)
			(end -1.524 0.7366)
			(stroke
				(width 0.1)
				(type default)
			)
			(layer "F.Fab")
		)
		(fp_line
			(start -1.524 0.7366)
			(end 1.524 0.7366)
			(stroke
				(width 0.1)
				(type default)
			)
			(layer "F.Fab")
		)
		(fp_line
			(start 1.524 0.7366)
			(end 1.560576 0.7366)
			(stroke
				(width 0.1)
				(type default)
			)
			(layer "F.Fab")
		)
		(fp_line
			(start 1.560576 -0.738632)
			(end -1.56083 -0.738632)
			(stroke
				(width 0.1)
				(type default)
			)
			(layer "F.Fab")
		)
		(fp_line
			(start 1.560576 0.7366)
			(end 1.560576 -0.738632)
			(stroke
				(width 0.1)
				(type default)
			)
			(layer "F.Fab")
		)
		(pad "1" smd rect
			(at -0.94996 0 180)
			(size 1.1176 1.3716)
			(layers "F.Cu" "F.Mask" "F.Paste")
			(net "P1V8_PLL0_PEX1")
		)
		(pad "2" smd rect
			(at 0.94996 0 180)
			(size 1.1176 1.3716)
			(layers "F.Cu" "F.Mask" "F.Paste")
			(net "PCEPLL5_VDDA18_PEX1")
		)
	)
	(footprint ""
		(layer "F.Cu")
		(at 365.506 -199.771 180)
		(property "Reference" "R4687"
			(at 0 0 180)
			(layer "F.SilkS")
			(hide yes)
			(effects
				(font
					(size 1.27 1.27)
				)
			)
		)
		(property "Value" ""
			(at 0 0 180)
			(layer "F.Fab")
			(effects
				(font
					(size 1.27 1.27)
				)
			)
		)
		(duplicate_pad_numbers_are_jumpers no)
		(fp_line
			(start 0.7874 0.4064)
			(end -0.7874 0.4064)
			(stroke
				(width 0.1524)
				(type default)
			)
			(layer "F.SilkS")
		)
		(fp_line
			(start 0.7874 -0.4064)
			(end 0.7874 0.4064)
			(stroke
				(width 0.1524)
				(type default)
			)
			(layer "F.SilkS")
		)
		(fp_line
			(start -0.7874 0.4064)
			(end -0.7874 -0.4064)
			(stroke
				(width 0.1524)
				(type default)
			)
			(layer "F.SilkS")
		)
		(fp_line
			(start -0.7874 -0.4064)
			(end 0.7874 -0.4064)
			(stroke
				(width 0.1524)
				(type default)
			)
			(layer "F.SilkS")
		)
		(fp_line
			(start 0.67945 0.3048)
			(end 0.120396 0.3048)
			(stroke
				(width 0.1)
				(type default)
			)
			(layer "F.Fab")
		)
		(fp_line
			(start 0.67945 -0.3048)
			(end 0.67945 0.3048)
			(stroke
				(width 0.1)
				(type default)
			)
			(layer "F.Fab")
		)
		(fp_line
			(start 0.12065 -0.2794)
			(end 0.12065 -0.3048)
			(stroke
				(width 0.1)
				(type default)
			)
			(layer "F.Fab")
		)
		(fp_line
			(start 0.12065 -0.3048)
			(end 0.67945 -0.3048)
			(stroke
				(width 0.1)
				(type default)
			)
			(layer "F.Fab")
		)
		(fp_line
			(start 0.120396 0.3048)
			(end 0.120396 0.2794)
			(stroke
				(width 0.1)
				(type default)
			)
			(layer "F.Fab")
		)
		(fp_line
			(start 0.120396 0.2794)
			(end -0.12065 0.2794)
			(stroke
				(width 0.1)
				(type default)
			)
			(layer "F.Fab")
		)
		(fp_line
			(start -0.12065 0.3048)
			(end -0.67945 0.3048)
			(stroke
				(width 0.1)
				(type default)
			)
			(layer "F.Fab")
		)
		(fp_line
			(start -0.12065 0.2794)
			(end -0.12065 0.3048)
			(stroke
				(width 0.1)
				(type default)
			)
			(layer "F.Fab")
		)
		(fp_line
			(start -0.12065 -0.2794)
			(end 0.12065 -0.2794)
			(stroke
				(width 0.1)
				(type default)
			)
			(layer "F.Fab")
		)
		(fp_line
			(start -0.12065 -0.305054)
			(end -0.12065 -0.2794)
			(stroke
				(width 0.1)
				(type default)
			)
			(layer "F.Fab")
		)
		(fp_line
			(start -0.67945 0.3048)
			(end -0.67945 -0.305054)
			(stroke
				(width 0.1)
				(type default)
			)
			(layer "F.Fab")
		)
		(fp_line
			(start -0.67945 -0.305054)
			(end -0.12065 -0.305054)
			(stroke
				(width 0.1)
				(type default)
			)
			(layer "F.Fab")
		)
		(pad "1" smd circle
			(at -0.40005 0 180)
			(size 0 0)
			(layers "F.Cu" "F.Mask" "F.Paste")
			(net "SSD4_PEX_PWR_EN")
		)
		(pad "2" smd circle
			(at 0.40005 0 180)
			(size 0 0)
			(layers "F.Cu" "F.Mask" "F.Paste")
			(net "SSD4_PEX_PWR_EN_R")
		)
	)
	(footprint ""
		(layer "F.Cu")
		(at 38.566344 -250.070874 -90)
		(property "Reference" "R1127"
			(at 0 0 270)
			(layer "F.SilkS")
			(hide yes)
			(effects
				(font
					(size 1.27 1.27)
				)
			)
		)
		(property "Value" ""
			(at 0 0 270)
			(layer "F.Fab")
			(effects
				(font
					(size 1.27 1.27)
				)
			)
		)
		(duplicate_pad_numbers_are_jumpers no)
		(fp_line
			(start -0.7874 0.4064)
			(end -0.7874 -0.4064)
			(stroke
				(width 0.1524)
				(type default)
			)
			(layer "F.SilkS")
		)
		(fp_line
			(start 0.7874 0.4064)
			(end -0.7874 0.4064)
			(stroke
				(width 0.1524)
				(type default)
			)
			(layer "F.SilkS")
		)
		(fp_line
			(start -0.7874 -0.4064)
			(end 0.7874 -0.4064)
			(stroke
				(width 0.1524)
				(type default)
			)
			(layer "F.SilkS")
		)
		(fp_line
			(start 0.7874 -0.4064)
			(end 0.7874 0.4064)
			(stroke
				(width 0.1524)
				(type default)
			)
			(layer "F.SilkS")
		)
		(fp_line
			(start -0.67945 0.3048)
			(end -0.67945 -0.305054)
			(stroke
				(width 0.1)
				(type default)
			)
			(layer "F.Fab")
		)
		(fp_line
			(start -0.12065 0.3048)
			(end -0.67945 0.3048)
			(stroke
				(width 0.1)
				(type default)
			)
			(layer "F.Fab")
		)
		(fp_line
			(start 0.120396 0.3048)
			(end 0.120396 0.2794)
			(stroke
				(width 0.1)
				(type default)
			)
			(layer "F.Fab")
		)
		(fp_line
			(start 0.67945 0.3048)
			(end 0.120396 0.3048)
			(stroke
				(width 0.1)
				(type default)
			)
			(layer "F.Fab")
		)
		(fp_line
			(start -0.12065 0.2794)
			(end -0.12065 0.3048)
			(stroke
				(width 0.1)
				(type default)
			)
			(layer "F.Fab")
		)
		(fp_line
			(start 0.120396 0.2794)
			(end -0.12065 0.2794)
			(stroke
				(width 0.1)
				(type default)
			)
			(layer "F.Fab")
		)
		(fp_line
			(start -0.12065 -0.2794)
			(end 0.12065 -0.2794)
			(stroke
				(width 0.1)
				(type default)
			)
			(layer "F.Fab")
		)
		(fp_line
			(start 0.12065 -0.2794)
			(end 0.12065 -0.3048)
			(stroke
				(width 0.1)
				(type default)
			)
			(layer "F.Fab")
		)
		(fp_line
			(start 0.12065 -0.3048)
			(end 0.67945 -0.3048)
			(stroke
				(width 0.1)
				(type default)
			)
			(layer "F.Fab")
		)
		(fp_line
			(start 0.67945 -0.3048)
			(end 0.67945 0.3048)
			(stroke
				(width 0.1)
				(type default)
			)
			(layer "F.Fab")
		)
		(fp_line
			(start -0.67945 -0.305054)
			(end -0.12065 -0.305054)
			(stroke
				(width 0.1)
				(type default)
			)
			(layer "F.Fab")
		)
		(fp_line
			(start -0.12065 -0.305054)
			(end -0.12065 -0.2794)
			(stroke
				(width 0.1)
				(type default)
			)
			(layer "F.Fab")
		)
		(pad "1" smd circle
			(at -0.40005 0 270)
			(size 0 0)
			(layers "F.Cu" "F.Mask" "F.Paste")
			(net "PEX0_DBG_MODE4")
		)
		(pad "2" smd circle
			(at 0.40005 0 270)
			(size 0 0)
			(layers "F.Cu" "F.Mask" "F.Paste")
			(net "P1V8_PEX")
		)
	)
	(footprint ""
		(layer "F.Cu")
		(at 136.773158 -22.867366 90)
		(property "Reference" "C3900"
			(at 0 0 90)
			(layer "F.SilkS")
			(hide yes)
			(effects
				(font
					(size 1.27 1.27)
				)
			)
		)
		(property "Value" ""
			(at 0 0 90)
			(layer "F.Fab")
			(effects
				(font
					(size 1.27 1.27)
				)
			)
		)
		(duplicate_pad_numbers_are_jumpers no)
		(fp_line
			(start 0.7874 -0.4064)
			(end 0.7874 0.4064)
			(stroke
				(width 0.1524)
				(type default)
			)
			(layer "F.SilkS")
		)
		(fp_line
			(start -0.7874 -0.4064)
			(end 0.7874 -0.4064)
			(stroke
				(width 0.1524)
				(type default)
			)
			(layer "F.SilkS")
		)
		(fp_line
			(start 0.7874 0.4064)
			(end -0.7874 0.4064)
			(stroke
				(width 0.1524)
				(type default)
			)
			(layer "F.SilkS")
		)
		(fp_line
			(start -0.7874 0.4064)
			(end -0.7874 -0.4064)
			(stroke
				(width 0.1524)
				(type default)
			)
			(layer "F.SilkS")
		)
		(fp_line
			(start -0.12065 -0.305054)
			(end -0.12065 -0.2794)
			(stroke
				(width 0.1)
				(type default)
			)
			(layer "F.Fab")
		)
		(fp_line
			(start -0.67945 -0.305054)
			(end -0.12065 -0.305054)
			(stroke
				(width 0.1)
				(type default)
			)
			(layer "F.Fab")
		)
		(fp_line
			(start 0.67945 -0.3048)
			(end 0.67945 0.3048)
			(stroke
				(width 0.1)
				(type default)
			)
			(layer "F.Fab")
		)
		(fp_line
			(start 0.12065 -0.3048)
			(end 0.67945 -0.3048)
			(stroke
				(width 0.1)
				(type default)
			)
			(layer "F.Fab")
		)
		(fp_line
			(start 0.12065 -0.2794)
			(end 0.12065 -0.3048)
			(stroke
				(width 0.1)
				(type default)
			)
			(layer "F.Fab")
		)
		(fp_line
			(start -0.12065 -0.2794)
			(end 0.12065 -0.2794)
			(stroke
				(width 0.1)
				(type default)
			)
			(layer "F.Fab")
		)
		(fp_line
			(start 0.120396 0.2794)
			(end -0.12065 0.2794)
			(stroke
				(width 0.1)
				(type default)
			)
			(layer "F.Fab")
		)
		(fp_line
			(start -0.12065 0.2794)
			(end -0.12065 0.3048)
			(stroke
				(width 0.1)
				(type default)
			)
			(layer "F.Fab")
		)
		(fp_line
			(start 0.67945 0.3048)
			(end 0.120396 0.3048)
			(stroke
				(width 0.1)
				(type default)
			)
			(layer "F.Fab")
		)
		(fp_line
			(start 0.120396 0.3048)
			(end 0.120396 0.2794)
			(stroke
				(width 0.1)
				(type default)
			)
			(layer "F.Fab")
		)
		(fp_line
			(start -0.12065 0.3048)
			(end -0.67945 0.3048)
			(stroke
				(width 0.1)
				(type default)
			)
			(layer "F.Fab")
		)
		(fp_line
			(start -0.67945 0.3048)
			(end -0.67945 -0.305054)
			(stroke
				(width 0.1)
				(type default)
			)
			(layer "F.Fab")
		)
		(pad "1" smd circle
			(at -0.40005 0 90)
			(size 0 0)
			(layers "F.Cu" "F.Mask" "F.Paste")
			(net "P12V_SSD4")
		)
		(pad "2" smd circle
			(at 0.40005 0 90)
			(size 0 0)
			(layers "F.Cu" "F.Mask" "F.Paste")
			(net "GND")
		)
	)
	(footprint ""
		(layer "F.Cu")
		(at 148.073364 -382.453896)
		(property "Reference" "R6770"
			(at 0 0 0)
			(layer "F.SilkS")
			(hide yes)
			(effects
				(font
					(size 1.27 1.27)
				)
			)
		)
		(property "Value" ""
			(at 0 0 0)
			(layer "F.Fab")
			(effects
				(font
					(size 1.27 1.27)
				)
			)
		)
		(duplicate_pad_numbers_are_jumpers no)
		(fp_line
			(start -0.7874 -0.4064)
			(end 0.7874 -0.4064)
			(stroke
				(width 0.1524)
				(type default)
			)
			(layer "F.SilkS")
		)
		(fp_line
			(start -0.7874 0.4064)
			(end -0.7874 -0.4064)
			(stroke
				(width 0.1524)
				(type default)
			)
			(layer "F.SilkS")
		)
		(fp_line
			(start 0.7874 -0.4064)
			(end 0.7874 0.4064)
			(stroke
				(width 0.1524)
				(type default)
			)
			(layer "F.SilkS")
		)
		(fp_line
			(start 0.7874 0.4064)
			(end -0.7874 0.4064)
			(stroke
				(width 0.1524)
				(type default)
			)
			(layer "F.SilkS")
		)
		(fp_line
			(start -0.67945 -0.305054)
			(end -0.12065 -0.305054)
			(stroke
				(width 0.1)
				(type default)
			)
			(layer "F.Fab")
		)
		(fp_line
			(start -0.67945 0.3048)
			(end -0.67945 -0.305054)
			(stroke
				(width 0.1)
				(type default)
			)
			(layer "F.Fab")
		)
		(fp_line
			(start -0.12065 -0.305054)
			(end -0.12065 -0.2794)
			(stroke
				(width 0.1)
				(type default)
			)
			(layer "F.Fab")
		)
		(fp_line
			(start -0.12065 -0.2794)
			(end 0.12065 -0.2794)
			(stroke
				(width 0.1)
				(type default)
			)
			(layer "F.Fab")
		)
		(fp_line
			(start -0.12065 0.2794)
			(end -0.12065 0.3048)
			(stroke
				(width 0.1)
				(type default)
			)
			(layer "F.Fab")
		)
		(fp_line
			(start -0.12065 0.3048)
			(end -0.67945 0.3048)
			(stroke
				(width 0.1)
				(type default)
			)
			(layer "F.Fab")
		)
		(fp_line
			(start 0.120396 0.2794)
			(end -0.12065 0.2794)
			(stroke
				(width 0.1)
				(type default)
			)
			(layer "F.Fab")
		)
		(fp_line
			(start 0.120396 0.3048)
			(end 0.120396 0.2794)
			(stroke
				(width 0.1)
				(type default)
			)
			(layer "F.Fab")
		)
		(fp_line
			(start 0.12065 -0.3048)
			(end 0.67945 -0.3048)
			(stroke
				(width 0.1)
				(type default)
			)
			(layer "F.Fab")
		)
		(fp_line
			(start 0.12065 -0.2794)
			(end 0.12065 -0.3048)
			(stroke
				(width 0.1)
				(type default)
			)
			(layer "F.Fab")
		)
		(fp_line
			(start 0.67945 -0.3048)
			(end 0.67945 0.3048)
			(stroke
				(width 0.1)
				(type default)
			)
			(layer "F.Fab")
		)
		(fp_line
			(start 0.67945 0.3048)
			(end 0.120396 0.3048)
			(stroke
				(width 0.1)
				(type default)
			)
			(layer "F.Fab")
		)
		(pad "1" smd circle
			(at -0.40005 0)
			(size 0 0)
			(layers "F.Cu" "F.Mask" "F.Paste")
			(net "PRSNT_SWB_B3_N")
		)
		(pad "2" smd circle
			(at 0.40005 0)
			(size 0 0)
			(layers "F.Cu" "F.Mask" "F.Paste")
			(net "GND")
		)
	)
	(footprint ""
		(layer "F.Cu")
		(at 9.218422 -251.312426 -90)
		(property "Reference" "C4227"
			(at 0 0 270)
			(layer "F.SilkS")
			(hide yes)
			(effects
				(font
					(size 1.27 1.27)
				)
			)
		)
		(property "Value" ""
			(at 0 0 270)
			(layer "F.Fab")
			(effects
				(font
					(size 1.27 1.27)
				)
			)
		)
		(duplicate_pad_numbers_are_jumpers no)
		(fp_line
			(start -1.2954 0.5842)
			(end -1.2954 -0.5842)
			(stroke
				(width 0.1524)
				(type default)
			)
			(layer "F.SilkS")
		)
		(fp_line
			(start 1.2954 0.5842)
			(end -1.2954 0.5842)
			(stroke
				(width 0.1524)
				(type default)
			)
			(layer "F.SilkS")
		)
		(fp_line
			(start -1.2954 -0.5842)
			(end 1.2954 -0.5842)
			(stroke
				(width 0.1524)
				(type default)
			)
			(layer "F.SilkS")
		)
		(fp_line
			(start 1.2954 -0.5842)
			(end 1.2954 0.5842)
			(stroke
				(width 0.1524)
				(type default)
			)
			(layer "F.SilkS")
		)
		(fp_line
			(start -0.8636 0.4572)
			(end -0.8636 0.4064)
			(stroke
				(width 0.1)
				(type default)
			)
			(layer "F.Fab")
		)
		(fp_line
			(start 0.8636 0.4572)
			(end -0.8636 0.4572)
			(stroke
				(width 0.1)
				(type default)
			)
			(layer "F.Fab")
		)
		(fp_line
			(start -1.1938 0.4064)
			(end -1.1938 -0.4064)
			(stroke
				(width 0.1)
				(type default)
			)
			(layer "F.Fab")
		)
		(fp_line
			(start -0.8636 0.4064)
			(end -1.1938 0.4064)
			(stroke
				(width 0.1)
				(type default)
			)
			(layer "F.Fab")
		)
		(fp_line
			(start 0.8636 0.4064)
			(end 0.8636 0.4572)
			(stroke
				(width 0.1)
				(type default)
			)
			(layer "F.Fab")
		)
		(fp_line
			(start 1.1938 0.4064)
			(end 0.8636 0.4064)
			(stroke
				(width 0.1)
				(type default)
			)
			(layer "F.Fab")
		)
		(fp_line
			(start -1.1938 -0.4064)
			(end -0.8636 -0.4064)
			(stroke
				(width 0.1)
				(type default)
			)
			(layer "F.Fab")
		)
		(fp_line
			(start -0.8636 -0.4064)
			(end -0.8636 -0.4572)
			(stroke
				(width 0.1)
				(type default)
			)
			(layer "F.Fab")
		)
		(fp_line
			(start 0.8636 -0.4064)
			(end 1.1938 -0.4064)
			(stroke
				(width 0.1)
				(type default)
			)
			(layer "F.Fab")
		)
		(fp_line
			(start 1.1938 -0.4064)
			(end 1.1938 0.4064)
			(stroke
				(width 0.1)
				(type default)
			)
			(layer "F.Fab")
		)
		(fp_line
			(start -0.8636 -0.4572)
			(end 0.8636 -0.4572)
			(stroke
				(width 0.1)
				(type default)
			)
			(layer "F.Fab")
		)
		(fp_line
			(start 0.8636 -0.4572)
			(end 0.8636 -0.4064)
			(stroke
				(width 0.1)
				(type default)
			)
			(layer "F.Fab")
		)
		(pad "1" smd rect
			(at -0.7366 0 180)
			(size 0.7112 0.8128)
			(layers "F.Cu" "F.Mask" "F.Paste")
			(net "P1V25_SERDES_VDDPLL_PEX0_C1")
		)
		(pad "2" smd rect
			(at 0.7366 0 180)
			(size 0.7112 0.8128)
			(layers "F.Cu" "F.Mask" "F.Paste")
			(net "GND")
		)
	)
	(footprint ""
		(layer "F.Cu")
		(at 374.674384 -250.070874 -90)
		(property "Reference" "R1407"
			(at 0 0 270)
			(layer "F.SilkS")
			(hide yes)
			(effects
				(font
					(size 1.27 1.27)
				)
			)
		)
		(property "Value" ""
			(at 0 0 270)
			(layer "F.Fab")
			(effects
				(font
					(size 1.27 1.27)
				)
			)
		)
		(duplicate_pad_numbers_are_jumpers no)
		(fp_line
			(start -0.7874 0.4064)
			(end -0.7874 -0.4064)
			(stroke
				(width 0.1524)
				(type default)
			)
			(layer "F.SilkS")
		)
		(fp_line
			(start 0.7874 0.4064)
			(end -0.7874 0.4064)
			(stroke
				(width 0.1524)
				(type default)
			)
			(layer "F.SilkS")
		)
		(fp_line
			(start -0.7874 -0.4064)
			(end 0.7874 -0.4064)
			(stroke
				(width 0.1524)
				(type default)
			)
			(layer "F.SilkS")
		)
		(fp_line
			(start 0.7874 -0.4064)
			(end 0.7874 0.4064)
			(stroke
				(width 0.1524)
				(type default)
			)
			(layer "F.SilkS")
		)
		(fp_line
			(start -0.67945 0.3048)
			(end -0.67945 -0.305054)
			(stroke
				(width 0.1)
				(type default)
			)
			(layer "F.Fab")
		)
		(fp_line
			(start -0.12065 0.3048)
			(end -0.67945 0.3048)
			(stroke
				(width 0.1)
				(type default)
			)
			(layer "F.Fab")
		)
		(fp_line
			(start 0.120396 0.3048)
			(end 0.120396 0.2794)
			(stroke
				(width 0.1)
				(type default)
			)
			(layer "F.Fab")
		)
		(fp_line
			(start 0.67945 0.3048)
			(end 0.120396 0.3048)
			(stroke
				(width 0.1)
				(type default)
			)
			(layer "F.Fab")
		)
		(fp_line
			(start -0.12065 0.2794)
			(end -0.12065 0.3048)
			(stroke
				(width 0.1)
				(type default)
			)
			(layer "F.Fab")
		)
		(fp_line
			(start 0.120396 0.2794)
			(end -0.12065 0.2794)
			(stroke
				(width 0.1)
				(type default)
			)
			(layer "F.Fab")
		)
		(fp_line
			(start -0.12065 -0.2794)
			(end 0.12065 -0.2794)
			(stroke
				(width 0.1)
				(type default)
			)
			(layer "F.Fab")
		)
		(fp_line
			(start 0.12065 -0.2794)
			(end 0.12065 -0.3048)
			(stroke
				(width 0.1)
				(type default)
			)
			(layer "F.Fab")
		)
		(fp_line
			(start 0.12065 -0.3048)
			(end 0.67945 -0.3048)
			(stroke
				(width 0.1)
				(type default)
			)
			(layer "F.Fab")
		)
		(fp_line
			(start 0.67945 -0.3048)
			(end 0.67945 0.3048)
			(stroke
				(width 0.1)
				(type default)
			)
			(layer "F.Fab")
		)
		(fp_line
			(start -0.67945 -0.305054)
			(end -0.12065 -0.305054)
			(stroke
				(width 0.1)
				(type default)
			)
			(layer "F.Fab")
		)
		(fp_line
			(start -0.12065 -0.305054)
			(end -0.12065 -0.2794)
			(stroke
				(width 0.1)
				(type default)
			)
			(layer "F.Fab")
		)
		(pad "1" smd circle
			(at -0.40005 0 270)
			(size 0 0)
			(layers "F.Cu" "F.Mask" "F.Paste")
			(net "PEX3_MODE_SEL2")
		)
		(pad "2" smd circle
			(at 0.40005 0 270)
			(size 0 0)
			(layers "F.Cu" "F.Mask" "F.Paste")
			(net "P1V8_PEX")
		)
	)
	(footprint ""
		(layer "F.Cu")
		(at 17.354042 -269.446248)
		(property "Reference" "C4239"
			(at 0 0 0)
			(layer "F.SilkS")
			(hide yes)
			(effects
				(font
					(size 1.27 1.27)
				)
			)
		)
		(property "Value" ""
			(at 0 0 0)
			(layer "F.Fab")
			(effects
				(font
					(size 1.27 1.27)
				)
			)
		)
		(duplicate_pad_numbers_are_jumpers no)
		(fp_line
			(start -0.299974 -0.150114)
			(end 0.299974 -0.150114)
			(stroke
				(width 0.1)
				(type default)
			)
			(layer "F.Fab")
		)
		(fp_line
			(start -0.299974 0.150114)
			(end -0.299974 -0.150114)
			(stroke
				(width 0.1)
				(type default)
			)
			(layer "F.Fab")
		)
		(fp_line
			(start 0.299974 -0.150114)
			(end 0.299974 0.150114)
			(stroke
				(width 0.1)
				(type default)
			)
			(layer "F.Fab")
		)
		(fp_line
			(start 0.299974 0.150114)
			(end -0.299974 0.150114)
			(stroke
				(width 0.1)
				(type default)
			)
			(layer "F.Fab")
		)
		(pad "1" smd rect
			(at -0.2667 0)
			(size 0.3048 0.381)
			(layers "F.Cu" "F.Mask" "F.Paste")
			(net "P1V25_SERDES_VDDPLL_PEX0")
		)
		(pad "2" smd rect
			(at 0.2667 0)
			(size 0.3048 0.381)
			(layers "F.Cu" "F.Mask" "F.Paste")
			(net "GND")
		)
	)
	(footprint ""
		(layer "F.Cu")
		(at 206.623158 -84.675472)
		(property "Reference" "R4302"
			(at 0 0 0)
			(layer "F.SilkS")
			(hide yes)
			(effects
				(font
					(size 1.27 1.27)
				)
			)
		)
		(property "Value" ""
			(at 0 0 0)
			(layer "F.Fab")
			(effects
				(font
					(size 1.27 1.27)
				)
			)
		)
		(duplicate_pad_numbers_are_jumpers no)
		(fp_line
			(start -0.7874 -0.4064)
			(end 0.7874 -0.4064)
			(stroke
				(width 0.1524)
				(type default)
			)
			(layer "F.SilkS")
		)
		(fp_line
			(start -0.7874 0.4064)
			(end -0.7874 -0.4064)
			(stroke
				(width 0.1524)
				(type default)
			)
			(layer "F.SilkS")
		)
		(fp_line
			(start 0.7874 -0.4064)
			(end 0.7874 0.4064)
			(stroke
				(width 0.1524)
				(type default)
			)
			(layer "F.SilkS")
		)
		(fp_line
			(start 0.7874 0.4064)
			(end -0.7874 0.4064)
			(stroke
				(width 0.1524)
				(type default)
			)
			(layer "F.SilkS")
		)
		(fp_line
			(start -0.67945 -0.305054)
			(end -0.12065 -0.305054)
			(stroke
				(width 0.1)
				(type default)
			)
			(layer "F.Fab")
		)
		(fp_line
			(start -0.67945 0.3048)
			(end -0.67945 -0.305054)
			(stroke
				(width 0.1)
				(type default)
			)
			(layer "F.Fab")
		)
		(fp_line
			(start -0.12065 -0.305054)
			(end -0.12065 -0.2794)
			(stroke
				(width 0.1)
				(type default)
			)
			(layer "F.Fab")
		)
		(fp_line
			(start -0.12065 -0.2794)
			(end 0.12065 -0.2794)
			(stroke
				(width 0.1)
				(type default)
			)
			(layer "F.Fab")
		)
		(fp_line
			(start -0.12065 0.2794)
			(end -0.12065 0.3048)
			(stroke
				(width 0.1)
				(type default)
			)
			(layer "F.Fab")
		)
		(fp_line
			(start -0.12065 0.3048)
			(end -0.67945 0.3048)
			(stroke
				(width 0.1)
				(type default)
			)
			(layer "F.Fab")
		)
		(fp_line
			(start 0.120396 0.2794)
			(end -0.12065 0.2794)
			(stroke
				(width 0.1)
				(type default)
			)
			(layer "F.Fab")
		)
		(fp_line
			(start 0.120396 0.3048)
			(end 0.120396 0.2794)
			(stroke
				(width 0.1)
				(type default)
			)
			(layer "F.Fab")
		)
		(fp_line
			(start 0.12065 -0.3048)
			(end 0.67945 -0.3048)
			(stroke
				(width 0.1)
				(type default)
			)
			(layer "F.Fab")
		)
		(fp_line
			(start 0.12065 -0.2794)
			(end 0.12065 -0.3048)
			(stroke
				(width 0.1)
				(type default)
			)
			(layer "F.Fab")
		)
		(fp_line
			(start 0.67945 -0.3048)
			(end 0.67945 0.3048)
			(stroke
				(width 0.1)
				(type default)
			)
			(layer "F.Fab")
		)
		(fp_line
			(start 0.67945 0.3048)
			(end 0.120396 0.3048)
			(stroke
				(width 0.1)
				(type default)
			)
			(layer "F.Fab")
		)
		(pad "1" smd circle
			(at -0.40005 0)
			(size 0 0)
			(layers "F.Cu" "F.Mask" "F.Paste")
			(net "SSD0_LED_R")
		)
		(pad "2" smd circle
			(at 0.40005 0)
			(size 0 0)
			(layers "F.Cu" "F.Mask" "F.Paste")
			(net "SSD0_LED")
		)
	)
	(footprint ""
		(layer "F.Cu")
		(at 124.279152 -59.577986 -90)
		(property "Reference" "R887"
			(at 0 0 270)
			(layer "F.SilkS")
			(hide yes)
			(effects
				(font
					(size 1.27 1.27)
				)
			)
		)
		(property "Value" ""
			(at 0 0 270)
			(layer "F.Fab")
			(effects
				(font
					(size 1.27 1.27)
				)
			)
		)
		(duplicate_pad_numbers_are_jumpers no)
		(fp_line
			(start -0.7874 0.4064)
			(end -0.7874 -0.4064)
			(stroke
				(width 0.1524)
				(type default)
			)
			(layer "F.SilkS")
		)
		(fp_line
			(start 0.7874 0.4064)
			(end -0.7874 0.4064)
			(stroke
				(width 0.1524)
				(type default)
			)
			(layer "F.SilkS")
		)
		(fp_line
			(start -0.7874 -0.4064)
			(end 0.7874 -0.4064)
			(stroke
				(width 0.1524)
				(type default)
			)
			(layer "F.SilkS")
		)
		(fp_line
			(start 0.7874 -0.4064)
			(end 0.7874 0.4064)
			(stroke
				(width 0.1524)
				(type default)
			)
			(layer "F.SilkS")
		)
		(fp_line
			(start -0.67945 0.3048)
			(end -0.67945 -0.305054)
			(stroke
				(width 0.1)
				(type default)
			)
			(layer "F.Fab")
		)
		(fp_line
			(start -0.12065 0.3048)
			(end -0.67945 0.3048)
			(stroke
				(width 0.1)
				(type default)
			)
			(layer "F.Fab")
		)
		(fp_line
			(start 0.120396 0.3048)
			(end 0.120396 0.2794)
			(stroke
				(width 0.1)
				(type default)
			)
			(layer "F.Fab")
		)
		(fp_line
			(start 0.67945 0.3048)
			(end 0.120396 0.3048)
			(stroke
				(width 0.1)
				(type default)
			)
			(layer "F.Fab")
		)
		(fp_line
			(start -0.12065 0.2794)
			(end -0.12065 0.3048)
			(stroke
				(width 0.1)
				(type default)
			)
			(layer "F.Fab")
		)
		(fp_line
			(start 0.120396 0.2794)
			(end -0.12065 0.2794)
			(stroke
				(width 0.1)
				(type default)
			)
			(layer "F.Fab")
		)
		(fp_line
			(start -0.12065 -0.2794)
			(end 0.12065 -0.2794)
			(stroke
				(width 0.1)
				(type default)
			)
			(layer "F.Fab")
		)
		(fp_line
			(start 0.12065 -0.2794)
			(end 0.12065 -0.3048)
			(stroke
				(width 0.1)
				(type default)
			)
			(layer "F.Fab")
		)
		(fp_line
			(start 0.12065 -0.3048)
			(end 0.67945 -0.3048)
			(stroke
				(width 0.1)
				(type default)
			)
			(layer "F.Fab")
		)
		(fp_line
			(start 0.67945 -0.3048)
			(end 0.67945 0.3048)
			(stroke
				(width 0.1)
				(type default)
			)
			(layer "F.Fab")
		)
		(fp_line
			(start -0.67945 -0.305054)
			(end -0.12065 -0.305054)
			(stroke
				(width 0.1)
				(type default)
			)
			(layer "F.Fab")
		)
		(fp_line
			(start -0.12065 -0.305054)
			(end -0.12065 -0.2794)
			(stroke
				(width 0.1)
				(type default)
			)
			(layer "F.Fab")
		)
		(pad "1" smd circle
			(at -0.40005 0 270)
			(size 0 0)
			(layers "F.Cu" "F.Mask" "F.Paste")
			(net "P3V3_SSD4")
		)
		(pad "2" smd circle
			(at 0.40005 0 270)
			(size 0 0)
			(layers "F.Cu" "F.Mask" "F.Paste")
			(net "PWRGD_P3V3_SSD4")
		)
	)
	(footprint ""
		(layer "F.Cu")
		(at 381.254 -205.486)
		(property "Reference" "R4631"
			(at 0 0 0)
			(layer "F.SilkS")
			(hide yes)
			(effects
				(font
					(size 1.27 1.27)
				)
			)
		)
		(property "Value" ""
			(at 0 0 0)
			(layer "F.Fab")
			(effects
				(font
					(size 1.27 1.27)
				)
			)
		)
		(duplicate_pad_numbers_are_jumpers no)
		(fp_line
			(start -0.7874 -0.4064)
			(end 0.7874 -0.4064)
			(stroke
				(width 0.1524)
				(type default)
			)
			(layer "F.SilkS")
		)
		(fp_line
			(start -0.7874 0.4064)
			(end -0.7874 -0.4064)
			(stroke
				(width 0.1524)
				(type default)
			)
			(layer "F.SilkS")
		)
		(fp_line
			(start 0.7874 -0.4064)
			(end 0.7874 0.4064)
			(stroke
				(width 0.1524)
				(type default)
			)
			(layer "F.SilkS")
		)
		(fp_line
			(start 0.7874 0.4064)
			(end -0.7874 0.4064)
			(stroke
				(width 0.1524)
				(type default)
			)
			(layer "F.SilkS")
		)
		(fp_line
			(start -0.67945 -0.305054)
			(end -0.12065 -0.305054)
			(stroke
				(width 0.1)
				(type default)
			)
			(layer "F.Fab")
		)
		(fp_line
			(start -0.67945 0.3048)
			(end -0.67945 -0.305054)
			(stroke
				(width 0.1)
				(type default)
			)
			(layer "F.Fab")
		)
		(fp_line
			(start -0.12065 -0.305054)
			(end -0.12065 -0.2794)
			(stroke
				(width 0.1)
				(type default)
			)
			(layer "F.Fab")
		)
		(fp_line
			(start -0.12065 -0.2794)
			(end 0.12065 -0.2794)
			(stroke
				(width 0.1)
				(type default)
			)
			(layer "F.Fab")
		)
		(fp_line
			(start -0.12065 0.2794)
			(end -0.12065 0.3048)
			(stroke
				(width 0.1)
				(type default)
			)
			(layer "F.Fab")
		)
		(fp_line
			(start -0.12065 0.3048)
			(end -0.67945 0.3048)
			(stroke
				(width 0.1)
				(type default)
			)
			(layer "F.Fab")
		)
		(fp_line
			(start 0.120396 0.2794)
			(end -0.12065 0.2794)
			(stroke
				(width 0.1)
				(type default)
			)
			(layer "F.Fab")
		)
		(fp_line
			(start 0.120396 0.3048)
			(end 0.120396 0.2794)
			(stroke
				(width 0.1)
				(type default)
			)
			(layer "F.Fab")
		)
		(fp_line
			(start 0.12065 -0.3048)
			(end 0.67945 -0.3048)
			(stroke
				(width 0.1)
				(type default)
			)
			(layer "F.Fab")
		)
		(fp_line
			(start 0.12065 -0.2794)
			(end 0.12065 -0.3048)
			(stroke
				(width 0.1)
				(type default)
			)
			(layer "F.Fab")
		)
		(fp_line
			(start 0.67945 -0.3048)
			(end 0.67945 0.3048)
			(stroke
				(width 0.1)
				(type default)
			)
			(layer "F.Fab")
		)
		(fp_line
			(start 0.67945 0.3048)
			(end 0.120396 0.3048)
			(stroke
				(width 0.1)
				(type default)
			)
			(layer "F.Fab")
		)
		(pad "1" smd circle
			(at -0.40005 0)
			(size 0 0)
			(layers "F.Cu" "F.Mask" "F.Paste")
			(net "PRSNT_NIC0_FPGA_PCA9555_N")
		)
		(pad "2" smd circle
			(at 0.40005 0)
			(size 0 0)
			(layers "F.Cu" "F.Mask" "F.Paste")
			(net "PRSNT_NIC0_FPGA_R_N")
		)
	)
	(footprint ""
		(layer "F.Cu")
		(at 15.542768 -162.003994 -90)
		(property "Reference" "C839"
			(at 0 0 270)
			(layer "F.SilkS")
			(hide yes)
			(effects
				(font
					(size 1.27 1.27)
				)
			)
		)
		(property "Value" ""
			(at 0 0 270)
			(layer "F.Fab")
			(effects
				(font
					(size 1.27 1.27)
				)
			)
		)
		(duplicate_pad_numbers_are_jumpers no)
		(fp_line
			(start -0.7874 0.4064)
			(end -0.7874 -0.4064)
			(stroke
				(width 0.1524)
				(type default)
			)
			(layer "F.SilkS")
		)
		(fp_line
			(start 0.7874 0.4064)
			(end -0.7874 0.4064)
			(stroke
				(width 0.1524)
				(type default)
			)
			(layer "F.SilkS")
		)
		(fp_line
			(start -0.7874 -0.4064)
			(end 0.7874 -0.4064)
			(stroke
				(width 0.1524)
				(type default)
			)
			(layer "F.SilkS")
		)
		(fp_line
			(start 0.7874 -0.4064)
			(end 0.7874 0.4064)
			(stroke
				(width 0.1524)
				(type default)
			)
			(layer "F.SilkS")
		)
		(fp_line
			(start -0.67945 0.3048)
			(end -0.67945 -0.305054)
			(stroke
				(width 0.1)
				(type default)
			)
			(layer "F.Fab")
		)
		(fp_line
			(start -0.12065 0.3048)
			(end -0.67945 0.3048)
			(stroke
				(width 0.1)
				(type default)
			)
			(layer "F.Fab")
		)
		(fp_line
			(start 0.120396 0.3048)
			(end 0.120396 0.2794)
			(stroke
				(width 0.1)
				(type default)
			)
			(layer "F.Fab")
		)
		(fp_line
			(start 0.67945 0.3048)
			(end 0.120396 0.3048)
			(stroke
				(width 0.1)
				(type default)
			)
			(layer "F.Fab")
		)
		(fp_line
			(start -0.12065 0.2794)
			(end -0.12065 0.3048)
			(stroke
				(width 0.1)
				(type default)
			)
			(layer "F.Fab")
		)
		(fp_line
			(start 0.120396 0.2794)
			(end -0.12065 0.2794)
			(stroke
				(width 0.1)
				(type default)
			)
			(layer "F.Fab")
		)
		(fp_line
			(start -0.12065 -0.2794)
			(end 0.12065 -0.2794)
			(stroke
				(width 0.1)
				(type default)
			)
			(layer "F.Fab")
		)
		(fp_line
			(start 0.12065 -0.2794)
			(end 0.12065 -0.3048)
			(stroke
				(width 0.1)
				(type default)
			)
			(layer "F.Fab")
		)
		(fp_line
			(start 0.12065 -0.3048)
			(end 0.67945 -0.3048)
			(stroke
				(width 0.1)
				(type default)
			)
			(layer "F.Fab")
		)
		(fp_line
			(start 0.67945 -0.3048)
			(end 0.67945 0.3048)
			(stroke
				(width 0.1)
				(type default)
			)
			(layer "F.Fab")
		)
		(fp_line
			(start -0.67945 -0.305054)
			(end -0.12065 -0.305054)
			(stroke
				(width 0.1)
				(type default)
			)
			(layer "F.Fab")
		)
		(fp_line
			(start -0.12065 -0.305054)
			(end -0.12065 -0.2794)
			(stroke
				(width 0.1)
				(type default)
			)
			(layer "F.Fab")
		)
		(pad "1" smd circle
			(at -0.40005 0 270)
			(size 0 0)
			(layers "F.Cu" "F.Mask" "F.Paste")
			(net "GND")
		)
		(pad "2" smd circle
			(at 0.40005 0 270)
			(size 0 0)
			(layers "F.Cu" "F.Mask" "F.Paste")
			(net "P12V_NIC0_CO_EN")
		)
	)
	(footprint ""
		(layer "F.Cu")
		(at 228.79304 -91.025726)
		(property "Reference" "R1014"
			(at 0 0 0)
			(layer "F.SilkS")
			(hide yes)
			(effects
				(font
					(size 1.27 1.27)
				)
			)
		)
		(property "Value" ""
			(at 0 0 0)
			(layer "F.Fab")
			(effects
				(font
					(size 1.27 1.27)
				)
			)
		)
		(duplicate_pad_numbers_are_jumpers no)
		(fp_line
			(start -0.7874 -0.4064)
			(end 0.7874 -0.4064)
			(stroke
				(width 0.1524)
				(type default)
			)
			(layer "F.SilkS")
		)
		(fp_line
			(start -0.7874 0.4064)
			(end -0.7874 -0.4064)
			(stroke
				(width 0.1524)
				(type default)
			)
			(layer "F.SilkS")
		)
		(fp_line
			(start 0.7874 -0.4064)
			(end 0.7874 0.4064)
			(stroke
				(width 0.1524)
				(type default)
			)
			(layer "F.SilkS")
		)
		(fp_line
			(start 0.7874 0.4064)
			(end -0.7874 0.4064)
			(stroke
				(width 0.1524)
				(type default)
			)
			(layer "F.SilkS")
		)
		(fp_line
			(start -0.67945 -0.305054)
			(end -0.12065 -0.305054)
			(stroke
				(width 0.1)
				(type default)
			)
			(layer "F.Fab")
		)
		(fp_line
			(start -0.67945 0.3048)
			(end -0.67945 -0.305054)
			(stroke
				(width 0.1)
				(type default)
			)
			(layer "F.Fab")
		)
		(fp_line
			(start -0.12065 -0.305054)
			(end -0.12065 -0.2794)
			(stroke
				(width 0.1)
				(type default)
			)
			(layer "F.Fab")
		)
		(fp_line
			(start -0.12065 -0.2794)
			(end 0.12065 -0.2794)
			(stroke
				(width 0.1)
				(type default)
			)
			(layer "F.Fab")
		)
		(fp_line
			(start -0.12065 0.2794)
			(end -0.12065 0.3048)
			(stroke
				(width 0.1)
				(type default)
			)
			(layer "F.Fab")
		)
		(fp_line
			(start -0.12065 0.3048)
			(end -0.67945 0.3048)
			(stroke
				(width 0.1)
				(type default)
			)
			(layer "F.Fab")
		)
		(fp_line
			(start 0.120396 0.2794)
			(end -0.12065 0.2794)
			(stroke
				(width 0.1)
				(type default)
			)
			(layer "F.Fab")
		)
		(fp_line
			(start 0.120396 0.3048)
			(end 0.120396 0.2794)
			(stroke
				(width 0.1)
				(type default)
			)
			(layer "F.Fab")
		)
		(fp_line
			(start 0.12065 -0.3048)
			(end 0.67945 -0.3048)
			(stroke
				(width 0.1)
				(type default)
			)
			(layer "F.Fab")
		)
		(fp_line
			(start 0.12065 -0.2794)
			(end 0.12065 -0.3048)
			(stroke
				(width 0.1)
				(type default)
			)
			(layer "F.Fab")
		)
		(fp_line
			(start 0.67945 -0.3048)
			(end 0.67945 0.3048)
			(stroke
				(width 0.1)
				(type default)
			)
			(layer "F.Fab")
		)
		(fp_line
			(start 0.67945 0.3048)
			(end 0.120396 0.3048)
			(stroke
				(width 0.1)
				(type default)
			)
			(layer "F.Fab")
		)
		(pad "1" smd circle
			(at -0.40005 0)
			(size 0 0)
			(layers "F.Cu" "F.Mask" "F.Paste")
			(net "P3V3_AUX")
		)
		(pad "2" smd circle
			(at 0.40005 0)
			(size 0 0)
			(layers "F.Cu" "F.Mask" "F.Paste")
			(net "PEX_USB_HUB_OVCUR2")
		)
	)
	(footprint ""
		(layer "F.Cu")
		(at 258.54533 -209.799174)
		(property "Reference" "C2811"
			(at 0 0 0)
			(layer "F.SilkS")
			(hide yes)
			(effects
				(font
					(size 1.27 1.27)
				)
			)
		)
		(property "Value" ""
			(at 0 0 0)
			(layer "F.Fab")
			(effects
				(font
					(size 1.27 1.27)
				)
			)
		)
		(duplicate_pad_numbers_are_jumpers no)
		(fp_line
			(start -0.7874 -0.4064)
			(end 0.7874 -0.4064)
			(stroke
				(width 0.1524)
				(type default)
			)
			(layer "F.SilkS")
		)
		(fp_line
			(start -0.7874 0.4064)
			(end -0.7874 -0.4064)
			(stroke
				(width 0.1524)
				(type default)
			)
			(layer "F.SilkS")
		)
		(fp_line
			(start 0.7874 -0.4064)
			(end 0.7874 0.4064)
			(stroke
				(width 0.1524)
				(type default)
			)
			(layer "F.SilkS")
		)
		(fp_line
			(start 0.7874 0.4064)
			(end -0.7874 0.4064)
			(stroke
				(width 0.1524)
				(type default)
			)
			(layer "F.SilkS")
		)
		(fp_line
			(start -0.67945 -0.305054)
			(end -0.12065 -0.305054)
			(stroke
				(width 0.1)
				(type default)
			)
			(layer "F.Fab")
		)
		(fp_line
			(start -0.67945 0.3048)
			(end -0.67945 -0.305054)
			(stroke
				(width 0.1)
				(type default)
			)
			(layer "F.Fab")
		)
		(fp_line
			(start -0.12065 -0.305054)
			(end -0.12065 -0.2794)
			(stroke
				(width 0.1)
				(type default)
			)
			(layer "F.Fab")
		)
		(fp_line
			(start -0.12065 -0.2794)
			(end 0.12065 -0.2794)
			(stroke
				(width 0.1)
				(type default)
			)
			(layer "F.Fab")
		)
		(fp_line
			(start -0.12065 0.2794)
			(end -0.12065 0.3048)
			(stroke
				(width 0.1)
				(type default)
			)
			(layer "F.Fab")
		)
		(fp_line
			(start -0.12065 0.3048)
			(end -0.67945 0.3048)
			(stroke
				(width 0.1)
				(type default)
			)
			(layer "F.Fab")
		)
		(fp_line
			(start 0.120396 0.2794)
			(end -0.12065 0.2794)
			(stroke
				(width 0.1)
				(type default)
			)
			(layer "F.Fab")
		)
		(fp_line
			(start 0.120396 0.3048)
			(end 0.120396 0.2794)
			(stroke
				(width 0.1)
				(type default)
			)
			(layer "F.Fab")
		)
		(fp_line
			(start 0.12065 -0.3048)
			(end 0.67945 -0.3048)
			(stroke
				(width 0.1)
				(type default)
			)
			(layer "F.Fab")
		)
		(fp_line
			(start 0.12065 -0.2794)
			(end 0.12065 -0.3048)
			(stroke
				(width 0.1)
				(type default)
			)
			(layer "F.Fab")
		)
		(fp_line
			(start 0.67945 -0.3048)
			(end 0.67945 0.3048)
			(stroke
				(width 0.1)
				(type default)
			)
			(layer "F.Fab")
		)
		(fp_line
			(start 0.67945 0.3048)
			(end 0.120396 0.3048)
			(stroke
				(width 0.1)
				(type default)
			)
			(layer "F.Fab")
		)
		(pad "1" smd circle
			(at -0.40005 0)
			(size 0 0)
			(layers "F.Cu" "F.Mask" "F.Paste")
			(net "GND")
		)
		(pad "2" smd circle
			(at 0.40005 0)
			(size 0 0)
			(layers "F.Cu" "F.Mask" "F.Paste")
			(net "P3V3_AUX_JTAG")
		)
	)
	(footprint ""
		(layer "F.Cu")
		(at 31.742888 -356.244906 90)
		(property "Reference" "C2164"
			(at 0 0 90)
			(layer "F.SilkS")
			(hide yes)
			(effects
				(font
					(size 1.27 1.27)
				)
			)
		)
		(property "Value" ""
			(at 0 0 90)
			(layer "F.Fab")
			(effects
				(font
					(size 1.27 1.27)
				)
			)
		)
		(duplicate_pad_numbers_are_jumpers no)
		(fp_line
			(start 0.299974 -0.150114)
			(end 0.299974 0.150114)
			(stroke
				(width 0.1)
				(type default)
			)
			(layer "F.Fab")
		)
		(fp_line
			(start -0.299974 -0.150114)
			(end 0.299974 -0.150114)
			(stroke
				(width 0.1)
				(type default)
			)
			(layer "F.Fab")
		)
		(fp_line
			(start 0.299974 0.150114)
			(end -0.299974 0.150114)
			(stroke
				(width 0.1)
				(type default)
			)
			(layer "F.Fab")
		)
		(fp_line
			(start -0.299974 0.150114)
			(end -0.299974 -0.150114)
			(stroke
				(width 0.1)
				(type default)
			)
			(layer "F.Fab")
		)
		(pad "1" smd rect
			(at -0.2667 0 90)
			(size 0.3048 0.381)
			(layers "F.Cu" "F.Mask" "F.Paste")
			(net "P5E_PEX0_STN4_TX_DP<73>")
		)
		(pad "2" smd rect
			(at 0.2667 0 90)
			(size 0.3048 0.381)
			(layers "F.Cu" "F.Mask" "F.Paste")
			(net "P5E_PEX0_STN4_TX_C_DP<73>")
		)
	)
	(footprint ""
		(layer "F.Cu")
		(at 338.263484 -356.244906 90)
		(property "Reference" "C576"
			(at 0 0 90)
			(layer "F.SilkS")
			(hide yes)
			(effects
				(font
					(size 1.27 1.27)
				)
			)
		)
		(property "Value" ""
			(at 0 0 90)
			(layer "F.Fab")
			(effects
				(font
					(size 1.27 1.27)
				)
			)
		)
		(duplicate_pad_numbers_are_jumpers no)
		(fp_line
			(start 0.299974 -0.150114)
			(end 0.299974 0.150114)
			(stroke
				(width 0.1)
				(type default)
			)
			(layer "F.Fab")
		)
		(fp_line
			(start -0.299974 -0.150114)
			(end 0.299974 -0.150114)
			(stroke
				(width 0.1)
				(type default)
			)
			(layer "F.Fab")
		)
		(fp_line
			(start 0.299974 0.150114)
			(end -0.299974 0.150114)
			(stroke
				(width 0.1)
				(type default)
			)
			(layer "F.Fab")
		)
		(fp_line
			(start -0.299974 0.150114)
			(end -0.299974 -0.150114)
			(stroke
				(width 0.1)
				(type default)
			)
			(layer "F.Fab")
		)
		(pad "1" smd rect
			(at -0.2667 0 90)
			(size 0.3048 0.381)
			(layers "F.Cu" "F.Mask" "F.Paste")
			(net "P5E_PEX2_STN6_TX_DN<99>")
		)
		(pad "2" smd rect
			(at 0.2667 0 90)
			(size 0.3048 0.381)
			(layers "F.Cu" "F.Mask" "F.Paste")
			(net "P5E_PEX2_STN6_TX_C_DN<99>")
		)
	)
	(footprint ""
		(layer "F.Cu")
		(at 146.255486 -390.398254 90)
		(property "Reference" "R1847"
			(at 0 0 90)
			(layer "F.SilkS")
			(hide yes)
			(effects
				(font
					(size 1.27 1.27)
				)
			)
		)
		(property "Value" ""
			(at 0 0 90)
			(layer "F.Fab")
			(effects
				(font
					(size 1.27 1.27)
				)
			)
		)
		(duplicate_pad_numbers_are_jumpers no)
		(fp_line
			(start 0.7874 -0.4064)
			(end 0.7874 0.4064)
			(stroke
				(width 0.1524)
				(type default)
			)
			(layer "F.SilkS")
		)
		(fp_line
			(start -0.7874 -0.4064)
			(end 0.7874 -0.4064)
			(stroke
				(width 0.1524)
				(type default)
			)
			(layer "F.SilkS")
		)
		(fp_line
			(start 0.7874 0.4064)
			(end -0.7874 0.4064)
			(stroke
				(width 0.1524)
				(type default)
			)
			(layer "F.SilkS")
		)
		(fp_line
			(start -0.7874 0.4064)
			(end -0.7874 -0.4064)
			(stroke
				(width 0.1524)
				(type default)
			)
			(layer "F.SilkS")
		)
		(fp_line
			(start -0.12065 -0.305054)
			(end -0.12065 -0.2794)
			(stroke
				(width 0.1)
				(type default)
			)
			(layer "F.Fab")
		)
		(fp_line
			(start -0.67945 -0.305054)
			(end -0.12065 -0.305054)
			(stroke
				(width 0.1)
				(type default)
			)
			(layer "F.Fab")
		)
		(fp_line
			(start 0.67945 -0.3048)
			(end 0.67945 0.3048)
			(stroke
				(width 0.1)
				(type default)
			)
			(layer "F.Fab")
		)
		(fp_line
			(start 0.12065 -0.3048)
			(end 0.67945 -0.3048)
			(stroke
				(width 0.1)
				(type default)
			)
			(layer "F.Fab")
		)
		(fp_line
			(start 0.12065 -0.2794)
			(end 0.12065 -0.3048)
			(stroke
				(width 0.1)
				(type default)
			)
			(layer "F.Fab")
		)
		(fp_line
			(start -0.12065 -0.2794)
			(end 0.12065 -0.2794)
			(stroke
				(width 0.1)
				(type default)
			)
			(layer "F.Fab")
		)
		(fp_line
			(start 0.120396 0.2794)
			(end -0.12065 0.2794)
			(stroke
				(width 0.1)
				(type default)
			)
			(layer "F.Fab")
		)
		(fp_line
			(start -0.12065 0.2794)
			(end -0.12065 0.3048)
			(stroke
				(width 0.1)
				(type default)
			)
			(layer "F.Fab")
		)
		(fp_line
			(start 0.67945 0.3048)
			(end 0.120396 0.3048)
			(stroke
				(width 0.1)
				(type default)
			)
			(layer "F.Fab")
		)
		(fp_line
			(start 0.120396 0.3048)
			(end 0.120396 0.2794)
			(stroke
				(width 0.1)
				(type default)
			)
			(layer "F.Fab")
		)
		(fp_line
			(start -0.12065 0.3048)
			(end -0.67945 0.3048)
			(stroke
				(width 0.1)
				(type default)
			)
			(layer "F.Fab")
		)
		(fp_line
			(start -0.67945 0.3048)
			(end -0.67945 -0.305054)
			(stroke
				(width 0.1)
				(type default)
			)
			(layer "F.Fab")
		)
		(pad "1" smd circle
			(at -0.40005 0 90)
			(size 0 0)
			(layers "F.Cu" "F.Mask" "F.Paste")
			(net "GPU_FPGA_BOOT_EN_R")
		)
		(pad "2" smd circle
			(at 0.40005 0 90)
			(size 0 0)
			(layers "F.Cu" "F.Mask" "F.Paste")
			(net "GPU_FPGA_BOOT_EN")
		)
	)
	(footprint ""
		(layer "F.Cu")
		(at 251.56287 -79.379318 -90)
		(property "Reference" "C2636"
			(at 0 0 270)
			(layer "F.SilkS")
			(hide yes)
			(effects
				(font
					(size 1.27 1.27)
				)
			)
		)
		(property "Value" ""
			(at 0 0 270)
			(layer "F.Fab")
			(effects
				(font
					(size 1.27 1.27)
				)
			)
		)
		(duplicate_pad_numbers_are_jumpers no)
		(fp_line
			(start -0.7874 0.4064)
			(end -0.7874 -0.4064)
			(stroke
				(width 0.1524)
				(type default)
			)
			(layer "F.SilkS")
		)
		(fp_line
			(start 0.7874 0.4064)
			(end -0.7874 0.4064)
			(stroke
				(width 0.1524)
				(type default)
			)
			(layer "F.SilkS")
		)
		(fp_line
			(start -0.7874 -0.4064)
			(end 0.7874 -0.4064)
			(stroke
				(width 0.1524)
				(type default)
			)
			(layer "F.SilkS")
		)
		(fp_line
			(start 0.7874 -0.4064)
			(end 0.7874 0.4064)
			(stroke
				(width 0.1524)
				(type default)
			)
			(layer "F.SilkS")
		)
		(fp_line
			(start -0.67945 0.3048)
			(end -0.67945 -0.305054)
			(stroke
				(width 0.1)
				(type default)
			)
			(layer "F.Fab")
		)
		(fp_line
			(start -0.12065 0.3048)
			(end -0.67945 0.3048)
			(stroke
				(width 0.1)
				(type default)
			)
			(layer "F.Fab")
		)
		(fp_line
			(start 0.120396 0.3048)
			(end 0.120396 0.2794)
			(stroke
				(width 0.1)
				(type default)
			)
			(layer "F.Fab")
		)
		(fp_line
			(start 0.67945 0.3048)
			(end 0.120396 0.3048)
			(stroke
				(width 0.1)
				(type default)
			)
			(layer "F.Fab")
		)
		(fp_line
			(start -0.12065 0.2794)
			(end -0.12065 0.3048)
			(stroke
				(width 0.1)
				(type default)
			)
			(layer "F.Fab")
		)
		(fp_line
			(start 0.120396 0.2794)
			(end -0.12065 0.2794)
			(stroke
				(width 0.1)
				(type default)
			)
			(layer "F.Fab")
		)
		(fp_line
			(start -0.12065 -0.2794)
			(end 0.12065 -0.2794)
			(stroke
				(width 0.1)
				(type default)
			)
			(layer "F.Fab")
		)
		(fp_line
			(start 0.12065 -0.2794)
			(end 0.12065 -0.3048)
			(stroke
				(width 0.1)
				(type default)
			)
			(layer "F.Fab")
		)
		(fp_line
			(start 0.12065 -0.3048)
			(end 0.67945 -0.3048)
			(stroke
				(width 0.1)
				(type default)
			)
			(layer "F.Fab")
		)
		(fp_line
			(start 0.67945 -0.3048)
			(end 0.67945 0.3048)
			(stroke
				(width 0.1)
				(type default)
			)
			(layer "F.Fab")
		)
		(fp_line
			(start -0.67945 -0.305054)
			(end -0.12065 -0.305054)
			(stroke
				(width 0.1)
				(type default)
			)
			(layer "F.Fab")
		)
		(fp_line
			(start -0.12065 -0.305054)
			(end -0.12065 -0.2794)
			(stroke
				(width 0.1)
				(type default)
			)
			(layer "F.Fab")
		)
		(pad "1" smd circle
			(at -0.40005 0 270)
			(size 0 0)
			(layers "F.Cu" "F.Mask" "F.Paste")
			(net "XTAL_CK440_25M_R_XIN")
		)
		(pad "2" smd circle
			(at 0.40005 0 270)
			(size 0 0)
			(layers "F.Cu" "F.Mask" "F.Paste")
			(net "GND")
		)
	)
	(footprint ""
		(layer "F.Cu")
		(at 289.14725 -36.686998 90)
		(property "Reference" "C3676"
			(at 0 0 90)
			(layer "F.SilkS")
			(hide yes)
			(effects
				(font
					(size 1.27 1.27)
				)
			)
		)
		(property "Value" ""
			(at 0 0 90)
			(layer "F.Fab")
			(effects
				(font
					(size 1.27 1.27)
				)
			)
		)
		(duplicate_pad_numbers_are_jumpers no)
		(fp_line
			(start 0.7874 -0.4064)
			(end 0.7874 0.4064)
			(stroke
				(width 0.1524)
				(type default)
			)
			(layer "F.SilkS")
		)
		(fp_line
			(start -0.7874 -0.4064)
			(end 0.7874 -0.4064)
			(stroke
				(width 0.1524)
				(type default)
			)
			(layer "F.SilkS")
		)
		(fp_line
			(start 0.7874 0.4064)
			(end -0.7874 0.4064)
			(stroke
				(width 0.1524)
				(type default)
			)
			(layer "F.SilkS")
		)
		(fp_line
			(start -0.7874 0.4064)
			(end -0.7874 -0.4064)
			(stroke
				(width 0.1524)
				(type default)
			)
			(layer "F.SilkS")
		)
		(fp_line
			(start -0.12065 -0.305054)
			(end -0.12065 -0.2794)
			(stroke
				(width 0.1)
				(type default)
			)
			(layer "F.Fab")
		)
		(fp_line
			(start -0.67945 -0.305054)
			(end -0.12065 -0.305054)
			(stroke
				(width 0.1)
				(type default)
			)
			(layer "F.Fab")
		)
		(fp_line
			(start 0.67945 -0.3048)
			(end 0.67945 0.3048)
			(stroke
				(width 0.1)
				(type default)
			)
			(layer "F.Fab")
		)
		(fp_line
			(start 0.12065 -0.3048)
			(end 0.67945 -0.3048)
			(stroke
				(width 0.1)
				(type default)
			)
			(layer "F.Fab")
		)
		(fp_line
			(start 0.12065 -0.2794)
			(end 0.12065 -0.3048)
			(stroke
				(width 0.1)
				(type default)
			)
			(layer "F.Fab")
		)
		(fp_line
			(start -0.12065 -0.2794)
			(end 0.12065 -0.2794)
			(stroke
				(width 0.1)
				(type default)
			)
			(layer "F.Fab")
		)
		(fp_line
			(start 0.120396 0.2794)
			(end -0.12065 0.2794)
			(stroke
				(width 0.1)
				(type default)
			)
			(layer "F.Fab")
		)
		(fp_line
			(start -0.12065 0.2794)
			(end -0.12065 0.3048)
			(stroke
				(width 0.1)
				(type default)
			)
			(layer "F.Fab")
		)
		(fp_line
			(start 0.67945 0.3048)
			(end 0.120396 0.3048)
			(stroke
				(width 0.1)
				(type default)
			)
			(layer "F.Fab")
		)
		(fp_line
			(start 0.120396 0.3048)
			(end 0.120396 0.2794)
			(stroke
				(width 0.1)
				(type default)
			)
			(layer "F.Fab")
		)
		(fp_line
			(start -0.12065 0.3048)
			(end -0.67945 0.3048)
			(stroke
				(width 0.1)
				(type default)
			)
			(layer "F.Fab")
		)
		(fp_line
			(start -0.67945 0.3048)
			(end -0.67945 -0.305054)
			(stroke
				(width 0.1)
				(type default)
			)
			(layer "F.Fab")
		)
		(pad "1" smd circle
			(at -0.40005 0 90)
			(size 0 0)
			(layers "F.Cu" "F.Mask" "F.Paste")
			(net "P3V3_AUX")
		)
		(pad "2" smd circle
			(at 0.40005 0 90)
			(size 0 0)
			(layers "F.Cu" "F.Mask" "F.Paste")
			(net "GND")
		)
	)
	(footprint ""
		(layer "F.Cu")
		(at 451.362318 -22.955504 -90)
		(property "Reference" "C2735"
			(at 0 0 270)
			(layer "F.SilkS")
			(hide yes)
			(effects
				(font
					(size 1.27 1.27)
				)
			)
		)
		(property "Value" ""
			(at 0 0 270)
			(layer "F.Fab")
			(effects
				(font
					(size 1.27 1.27)
				)
			)
		)
		(duplicate_pad_numbers_are_jumpers no)
		(fp_line
			(start -0.7874 0.4064)
			(end -0.7874 -0.4064)
			(stroke
				(width 0.1524)
				(type default)
			)
			(layer "F.SilkS")
		)
		(fp_line
			(start 0.7874 0.4064)
			(end -0.7874 0.4064)
			(stroke
				(width 0.1524)
				(type default)
			)
			(layer "F.SilkS")
		)
		(fp_line
			(start -0.7874 -0.4064)
			(end 0.7874 -0.4064)
			(stroke
				(width 0.1524)
				(type default)
			)
			(layer "F.SilkS")
		)
		(fp_line
			(start 0.7874 -0.4064)
			(end 0.7874 0.4064)
			(stroke
				(width 0.1524)
				(type default)
			)
			(layer "F.SilkS")
		)
		(fp_line
			(start -0.67945 0.3048)
			(end -0.67945 -0.305054)
			(stroke
				(width 0.1)
				(type default)
			)
			(layer "F.Fab")
		)
		(fp_line
			(start -0.12065 0.3048)
			(end -0.67945 0.3048)
			(stroke
				(width 0.1)
				(type default)
			)
			(layer "F.Fab")
		)
		(fp_line
			(start 0.120396 0.3048)
			(end 0.120396 0.2794)
			(stroke
				(width 0.1)
				(type default)
			)
			(layer "F.Fab")
		)
		(fp_line
			(start 0.67945 0.3048)
			(end 0.120396 0.3048)
			(stroke
				(width 0.1)
				(type default)
			)
			(layer "F.Fab")
		)
		(fp_line
			(start -0.12065 0.2794)
			(end -0.12065 0.3048)
			(stroke
				(width 0.1)
				(type default)
			)
			(layer "F.Fab")
		)
		(fp_line
			(start 0.120396 0.2794)
			(end -0.12065 0.2794)
			(stroke
				(width 0.1)
				(type default)
			)
			(layer "F.Fab")
		)
		(fp_line
			(start -0.12065 -0.2794)
			(end 0.12065 -0.2794)
			(stroke
				(width 0.1)
				(type default)
			)
			(layer "F.Fab")
		)
		(fp_line
			(start 0.12065 -0.2794)
			(end 0.12065 -0.3048)
			(stroke
				(width 0.1)
				(type default)
			)
			(layer "F.Fab")
		)
		(fp_line
			(start 0.12065 -0.3048)
			(end 0.67945 -0.3048)
			(stroke
				(width 0.1)
				(type default)
			)
			(layer "F.Fab")
		)
		(fp_line
			(start 0.67945 -0.3048)
			(end 0.67945 0.3048)
			(stroke
				(width 0.1)
				(type default)
			)
			(layer "F.Fab")
		)
		(fp_line
			(start -0.67945 -0.305054)
			(end -0.12065 -0.305054)
			(stroke
				(width 0.1)
				(type default)
			)
			(layer "F.Fab")
		)
		(fp_line
			(start -0.12065 -0.305054)
			(end -0.12065 -0.2794)
			(stroke
				(width 0.1)
				(type default)
			)
			(layer "F.Fab")
		)
		(pad "1" smd circle
			(at -0.40005 0 270)
			(size 0 0)
			(layers "F.Cu" "F.Mask" "F.Paste")
			(net "GND")
		)
		(pad "2" smd circle
			(at 0.40005 0 270)
			(size 0 0)
			(layers "F.Cu" "F.Mask" "F.Paste")
			(net "P3V3_AUX")
		)
	)
	(footprint ""
		(layer "F.Cu")
		(at 376.936 -186.817)
		(property "Reference" "R4603"
			(at 0 0 0)
			(layer "F.SilkS")
			(hide yes)
			(effects
				(font
					(size 1.27 1.27)
				)
			)
		)
		(property "Value" ""
			(at 0 0 0)
			(layer "F.Fab")
			(effects
				(font
					(size 1.27 1.27)
				)
			)
		)
		(duplicate_pad_numbers_are_jumpers no)
		(fp_line
			(start -0.7874 -0.4064)
			(end 0.7874 -0.4064)
			(stroke
				(width 0.1524)
				(type default)
			)
			(layer "F.SilkS")
		)
		(fp_line
			(start -0.7874 0.4064)
			(end -0.7874 -0.4064)
			(stroke
				(width 0.1524)
				(type default)
			)
			(layer "F.SilkS")
		)
		(fp_line
			(start 0.7874 -0.4064)
			(end 0.7874 0.4064)
			(stroke
				(width 0.1524)
				(type default)
			)
			(layer "F.SilkS")
		)
		(fp_line
			(start 0.7874 0.4064)
			(end -0.7874 0.4064)
			(stroke
				(width 0.1524)
				(type default)
			)
			(layer "F.SilkS")
		)
		(fp_line
			(start -0.67945 -0.305054)
			(end -0.12065 -0.305054)
			(stroke
				(width 0.1)
				(type default)
			)
			(layer "F.Fab")
		)
		(fp_line
			(start -0.67945 0.3048)
			(end -0.67945 -0.305054)
			(stroke
				(width 0.1)
				(type default)
			)
			(layer "F.Fab")
		)
		(fp_line
			(start -0.12065 -0.305054)
			(end -0.12065 -0.2794)
			(stroke
				(width 0.1)
				(type default)
			)
			(layer "F.Fab")
		)
		(fp_line
			(start -0.12065 -0.2794)
			(end 0.12065 -0.2794)
			(stroke
				(width 0.1)
				(type default)
			)
			(layer "F.Fab")
		)
		(fp_line
			(start -0.12065 0.2794)
			(end -0.12065 0.3048)
			(stroke
				(width 0.1)
				(type default)
			)
			(layer "F.Fab")
		)
		(fp_line
			(start -0.12065 0.3048)
			(end -0.67945 0.3048)
			(stroke
				(width 0.1)
				(type default)
			)
			(layer "F.Fab")
		)
		(fp_line
			(start 0.120396 0.2794)
			(end -0.12065 0.2794)
			(stroke
				(width 0.1)
				(type default)
			)
			(layer "F.Fab")
		)
		(fp_line
			(start 0.120396 0.3048)
			(end 0.120396 0.2794)
			(stroke
				(width 0.1)
				(type default)
			)
			(layer "F.Fab")
		)
		(fp_line
			(start 0.12065 -0.3048)
			(end 0.67945 -0.3048)
			(stroke
				(width 0.1)
				(type default)
			)
			(layer "F.Fab")
		)
		(fp_line
			(start 0.12065 -0.2794)
			(end 0.12065 -0.3048)
			(stroke
				(width 0.1)
				(type default)
			)
			(layer "F.Fab")
		)
		(fp_line
			(start 0.67945 -0.3048)
			(end 0.67945 0.3048)
			(stroke
				(width 0.1)
				(type default)
			)
			(layer "F.Fab")
		)
		(fp_line
			(start 0.67945 0.3048)
			(end 0.120396 0.3048)
			(stroke
				(width 0.1)
				(type default)
			)
			(layer "F.Fab")
		)
		(pad "1" smd circle
			(at -0.40005 0)
			(size 0 0)
			(layers "F.Cu" "F.Mask" "F.Paste")
			(net "P3V3_AUX")
		)
		(pad "2" smd circle
			(at 0.40005 0)
			(size 0 0)
			(layers "F.Cu" "F.Mask" "F.Paste")
			(net "NIC1_PEX_PWR_EN_R")
		)
	)
	(footprint ""
		(layer "F.Cu")
		(at 232.936542 -451.107556 180)
		(property "Reference" "X68"
			(at -0.1778 -1.92913 180)
			(unlocked yes)
			(layer "F.SilkS")
			(effects
				(font
					(size 0.7874 0.5842)
					(thickness 0.1524)
				)
				(justify left)
			)
		)
		(property "Value" ""
			(at 0 0 180)
			(layer "F.Fab")
			(effects
				(font
					(size 1.27 1.27)
				)
			)
		)
		(property "Device Type" "TP_TDR_4P_FTS_MPKT4_H025P0200_IO_TP15_TP_TDR_4P_DIP"
			(at 1.30175 1.27 270)
			(unlocked yes)
			(layer "F.Fab")
			(hide yes)
			(effects
				(font
					(size 0.635 0.4064)
					(thickness 0.1524)
				)
			)
		)
		(property "User Part Number" "TP15"
			(at 1.30175 1.27 270)
			(unlocked yes)
			(layer "Cmts.User")
			(hide yes)
			(effects
				(font
					(size 0.635 0.4064)
					(thickness 0.1524)
				)
			)
		)
		(duplicate_pad_numbers_are_jumpers no)
		(fp_line
			(start 2.54 3.81)
			(end 2.54 3.6703)
			(stroke
				(width 0.1524)
				(type default)
			)
			(layer "F.SilkS")
		)
		(fp_line
			(start 2.54 1.4097)
			(end 2.54 1.1303)
			(stroke
				(width 0.1524)
				(type default)
			)
			(layer "F.SilkS")
		)
		(fp_line
			(start 2.54 -1.1303)
			(end 2.54 -1.27)
			(stroke
				(width 0.1524)
				(type default)
			)
			(layer "F.SilkS")
		)
		(fp_line
			(start 2.54 -1.27)
			(end 0 -1.27)
			(stroke
				(width 0.1524)
				(type default)
			)
			(layer "F.SilkS")
		)
		(fp_line
			(start 0 3.81)
			(end 2.54 3.81)
			(stroke
				(width 0.1524)
				(type default)
			)
			(layer "F.SilkS")
		)
		(fp_line
			(start 0 3.175)
			(end 0 3.81)
			(stroke
				(width 0.1524)
				(type default)
			)
			(layer "F.SilkS")
		)
		(fp_line
			(start 0 0.635)
			(end 0 1.905)
			(stroke
				(width 0.1524)
				(type default)
			)
			(layer "F.SilkS")
		)
		(fp_line
			(start 0 -1.27)
			(end 0 -0.635)
			(stroke
				(width 0.1524)
				(type default)
			)
			(layer "F.SilkS")
		)
		(fp_poly
			(pts
				(xy -0.761746 0) (xy -2.285746 -0.762) (xy -2.285746 0.762)
			)
			(stroke
				(width 0)
				(type default)
			)
			(fill yes)
			(layer "F.SilkS")
		)
		(fp_line
			(start 2.54 3.81)
			(end 2.54 -1.27)
			(stroke
				(width 0.1)
				(type default)
			)
			(layer "F.Fab")
		)
		(fp_line
			(start 2.54 -1.27)
			(end 0 -1.27)
			(stroke
				(width 0.1)
				(type default)
			)
			(layer "F.Fab")
		)
		(fp_line
			(start 0 3.81)
			(end 2.54 3.81)
			(stroke
				(width 0.1)
				(type default)
			)
			(layer "F.Fab")
		)
		(fp_line
			(start 0 -1.27)
			(end 0 3.81)
			(stroke
				(width 0.1)
				(type default)
			)
			(layer "F.Fab")
		)
		(fp_poly
			(pts
				(xy -0.761746 0) (xy -2.285746 -0.762) (xy -2.285746 0.762)
			)
			(stroke
				(width 0)
				(type default)
			)
			(fill yes)
			(layer "F.Fab")
		)
		(pad "1" thru_hole circle
			(at 0 0 180)
			(size 1.0033 1.0033)
			(drill 0.249936)
			(layers "*.Cu" "*.Mask")
			(remove_unused_layers no)
			(net "TDR_DIFF_100_IN1_DIP")
			(clearance 0.10795)
			(thermal_gap 0.10795)
			(padstack
				(mode front_inner_back)
				(layer "Inner"
					(shape circle)
					(size 0.8001 0.8001)
					(clearance 0.1524)
				)
				(layer "B.Cu"
					(shape circle)
					(size 1.0033 1.0033)
					(clearance 0.10795)
				)
			)
		)
		(pad "2" thru_hole circle
			(at 2.54 0 180)
			(size 1.9939 1.9939)
			(drill 0.249936)
			(layers "*.Cu" "*.Mask")
			(remove_unused_layers no)
			(net "COUPON_GND1")
			(clearance 0.10795)
			(thermal_gap 0.10795)
			(padstack
				(mode front_inner_back)
				(layer "Inner"
					(shape circle)
					(size 0.8001 0.8001)
					(clearance 0.1524)
				)
				(layer "B.Cu"
					(shape circle)
					(size 1.9939 1.9939)
					(clearance 0.10795)
				)
			)
		)
		(pad "3" thru_hole circle
			(at 2.54 2.54 180)
			(size 1.9939 1.9939)
			(drill 0.249936)
			(layers "*.Cu" "*.Mask")
			(remove_unused_layers no)
			(net "COUPON_GND1")
			(clearance 0.10795)
			(thermal_gap 0.10795)
			(padstack
				(mode front_inner_back)
				(layer "Inner"
					(shape circle)
					(size 0.8001 0.8001)
					(clearance 0.1524)
				)
				(layer "B.Cu"
					(shape circle)
					(size 1.9939 1.9939)
					(clearance 0.10795)
				)
			)
		)
		(pad "4" thru_hole circle
			(at 0 2.54 180)
			(size 1.0033 1.0033)
			(drill 0.249936)
			(layers "*.Cu" "*.Mask")
			(remove_unused_layers no)
			(net "TDR_DIFF_100_IN1_DIN")
			(clearance 0.10795)
			(thermal_gap 0.10795)
			(padstack
				(mode front_inner_back)
				(layer "Inner"
					(shape circle)
					(size 0.8001 0.8001)
					(clearance 0.1524)
				)
				(layer "B.Cu"
					(shape circle)
					(size 1.0033 1.0033)
					(clearance 0.10795)
				)
			)
		)
	)
	(footprint ""
		(layer "F.Cu")
		(at 80.53959 -158.219648)
		(property "Reference" "R59"
			(at 0 0 0)
			(layer "F.SilkS")
			(hide yes)
			(effects
				(font
					(size 1.27 1.27)
				)
			)
		)
		(property "Value" ""
			(at 0 0 0)
			(layer "F.Fab")
			(effects
				(font
					(size 1.27 1.27)
				)
			)
		)
		(duplicate_pad_numbers_are_jumpers no)
		(fp_line
			(start -0.7874 -0.4064)
			(end 0.7874 -0.4064)
			(stroke
				(width 0.1524)
				(type default)
			)
			(layer "F.SilkS")
		)
		(fp_line
			(start -0.7874 0.4064)
			(end -0.7874 -0.4064)
			(stroke
				(width 0.1524)
				(type default)
			)
			(layer "F.SilkS")
		)
		(fp_line
			(start 0.7874 -0.4064)
			(end 0.7874 0.4064)
			(stroke
				(width 0.1524)
				(type default)
			)
			(layer "F.SilkS")
		)
		(fp_line
			(start 0.7874 0.4064)
			(end -0.7874 0.4064)
			(stroke
				(width 0.1524)
				(type default)
			)
			(layer "F.SilkS")
		)
		(fp_line
			(start -0.67945 -0.305054)
			(end -0.12065 -0.305054)
			(stroke
				(width 0.1)
				(type default)
			)
			(layer "F.Fab")
		)
		(fp_line
			(start -0.67945 0.3048)
			(end -0.67945 -0.305054)
			(stroke
				(width 0.1)
				(type default)
			)
			(layer "F.Fab")
		)
		(fp_line
			(start -0.12065 -0.305054)
			(end -0.12065 -0.2794)
			(stroke
				(width 0.1)
				(type default)
			)
			(layer "F.Fab")
		)
		(fp_line
			(start -0.12065 -0.2794)
			(end 0.12065 -0.2794)
			(stroke
				(width 0.1)
				(type default)
			)
			(layer "F.Fab")
		)
		(fp_line
			(start -0.12065 0.2794)
			(end -0.12065 0.3048)
			(stroke
				(width 0.1)
				(type default)
			)
			(layer "F.Fab")
		)
		(fp_line
			(start -0.12065 0.3048)
			(end -0.67945 0.3048)
			(stroke
				(width 0.1)
				(type default)
			)
			(layer "F.Fab")
		)
		(fp_line
			(start 0.120396 0.2794)
			(end -0.12065 0.2794)
			(stroke
				(width 0.1)
				(type default)
			)
			(layer "F.Fab")
		)
		(fp_line
			(start 0.120396 0.3048)
			(end 0.120396 0.2794)
			(stroke
				(width 0.1)
				(type default)
			)
			(layer "F.Fab")
		)
		(fp_line
			(start 0.12065 -0.3048)
			(end 0.67945 -0.3048)
			(stroke
				(width 0.1)
				(type default)
			)
			(layer "F.Fab")
		)
		(fp_line
			(start 0.12065 -0.2794)
			(end 0.12065 -0.3048)
			(stroke
				(width 0.1)
				(type default)
			)
			(layer "F.Fab")
		)
		(fp_line
			(start 0.67945 -0.3048)
			(end 0.67945 0.3048)
			(stroke
				(width 0.1)
				(type default)
			)
			(layer "F.Fab")
		)
		(fp_line
			(start 0.67945 0.3048)
			(end 0.120396 0.3048)
			(stroke
				(width 0.1)
				(type default)
			)
			(layer "F.Fab")
		)
		(pad "1" smd circle
			(at -0.40005 0)
			(size 0 0)
			(layers "F.Cu" "F.Mask" "F.Paste")
			(net "PRSNTB3_NIC1_N")
		)
		(pad "2" smd circle
			(at 0.40005 0)
			(size 0 0)
			(layers "F.Cu" "F.Mask" "F.Paste")
			(net "P3V3_AUX")
		)
	)
	(footprint ""
		(layer "F.Cu")
		(at 242.91671 -162.003994 90)
		(property "Reference" "PC811"
			(at 0 0 90)
			(layer "F.SilkS")
			(hide yes)
			(effects
				(font
					(size 1.27 1.27)
				)
			)
		)
		(property "Value" ""
			(at 0 0 90)
			(layer "F.Fab")
			(effects
				(font
					(size 1.27 1.27)
				)
			)
		)
		(duplicate_pad_numbers_are_jumpers no)
		(fp_line
			(start 0.7874 -0.4064)
			(end 0.7874 0.4064)
			(stroke
				(width 0.1524)
				(type default)
			)
			(layer "F.SilkS")
		)
		(fp_line
			(start -0.7874 -0.4064)
			(end 0.7874 -0.4064)
			(stroke
				(width 0.1524)
				(type default)
			)
			(layer "F.SilkS")
		)
		(fp_line
			(start 0.7874 0.4064)
			(end -0.7874 0.4064)
			(stroke
				(width 0.1524)
				(type default)
			)
			(layer "F.SilkS")
		)
		(fp_line
			(start -0.7874 0.4064)
			(end -0.7874 -0.4064)
			(stroke
				(width 0.1524)
				(type default)
			)
			(layer "F.SilkS")
		)
		(fp_line
			(start -0.12065 -0.305054)
			(end -0.12065 -0.2794)
			(stroke
				(width 0.1)
				(type default)
			)
			(layer "F.Fab")
		)
		(fp_line
			(start -0.67945 -0.305054)
			(end -0.12065 -0.305054)
			(stroke
				(width 0.1)
				(type default)
			)
			(layer "F.Fab")
		)
		(fp_line
			(start 0.67945 -0.3048)
			(end 0.67945 0.3048)
			(stroke
				(width 0.1)
				(type default)
			)
			(layer "F.Fab")
		)
		(fp_line
			(start 0.12065 -0.3048)
			(end 0.67945 -0.3048)
			(stroke
				(width 0.1)
				(type default)
			)
			(layer "F.Fab")
		)
		(fp_line
			(start 0.12065 -0.2794)
			(end 0.12065 -0.3048)
			(stroke
				(width 0.1)
				(type default)
			)
			(layer "F.Fab")
		)
		(fp_line
			(start -0.12065 -0.2794)
			(end 0.12065 -0.2794)
			(stroke
				(width 0.1)
				(type default)
			)
			(layer "F.Fab")
		)
		(fp_line
			(start 0.120396 0.2794)
			(end -0.12065 0.2794)
			(stroke
				(width 0.1)
				(type default)
			)
			(layer "F.Fab")
		)
		(fp_line
			(start -0.12065 0.2794)
			(end -0.12065 0.3048)
			(stroke
				(width 0.1)
				(type default)
			)
			(layer "F.Fab")
		)
		(fp_line
			(start 0.67945 0.3048)
			(end 0.120396 0.3048)
			(stroke
				(width 0.1)
				(type default)
			)
			(layer "F.Fab")
		)
		(fp_line
			(start 0.120396 0.3048)
			(end 0.120396 0.2794)
			(stroke
				(width 0.1)
				(type default)
			)
			(layer "F.Fab")
		)
		(fp_line
			(start -0.12065 0.3048)
			(end -0.67945 0.3048)
			(stroke
				(width 0.1)
				(type default)
			)
			(layer "F.Fab")
		)
		(fp_line
			(start -0.67945 0.3048)
			(end -0.67945 -0.305054)
			(stroke
				(width 0.1)
				(type default)
			)
			(layer "F.Fab")
		)
		(pad "1" smd circle
			(at -0.40005 0 90)
			(size 0 0)
			(layers "F.Cu" "F.Mask" "F.Paste")
			(net "P12V_NIC4_CO_SS")
		)
		(pad "2" smd circle
			(at 0.40005 0 90)
			(size 0 0)
			(layers "F.Cu" "F.Mask" "F.Paste")
			(net "GND")
		)
	)
	(footprint ""
		(layer "F.Cu")
		(at 453.29602 -371.5258)
		(property "Reference" "R6688"
			(at 0 0 0)
			(layer "F.SilkS")
			(hide yes)
			(effects
				(font
					(size 1.27 1.27)
				)
			)
		)
		(property "Value" ""
			(at 0 0 0)
			(layer "F.Fab")
			(effects
				(font
					(size 1.27 1.27)
				)
			)
		)
		(duplicate_pad_numbers_are_jumpers no)
		(fp_line
			(start -0.7874 -0.4064)
			(end 0.7874 -0.4064)
			(stroke
				(width 0.1524)
				(type default)
			)
			(layer "F.SilkS")
		)
		(fp_line
			(start -0.7874 0.4064)
			(end -0.7874 -0.4064)
			(stroke
				(width 0.1524)
				(type default)
			)
			(layer "F.SilkS")
		)
		(fp_line
			(start 0.7874 -0.4064)
			(end 0.7874 0.4064)
			(stroke
				(width 0.1524)
				(type default)
			)
			(layer "F.SilkS")
		)
		(fp_line
			(start 0.7874 0.4064)
			(end -0.7874 0.4064)
			(stroke
				(width 0.1524)
				(type default)
			)
			(layer "F.SilkS")
		)
		(fp_line
			(start -0.67945 -0.305054)
			(end -0.12065 -0.305054)
			(stroke
				(width 0.1)
				(type default)
			)
			(layer "F.Fab")
		)
		(fp_line
			(start -0.67945 0.3048)
			(end -0.67945 -0.305054)
			(stroke
				(width 0.1)
				(type default)
			)
			(layer "F.Fab")
		)
		(fp_line
			(start -0.12065 -0.305054)
			(end -0.12065 -0.2794)
			(stroke
				(width 0.1)
				(type default)
			)
			(layer "F.Fab")
		)
		(fp_line
			(start -0.12065 -0.2794)
			(end 0.12065 -0.2794)
			(stroke
				(width 0.1)
				(type default)
			)
			(layer "F.Fab")
		)
		(fp_line
			(start -0.12065 0.2794)
			(end -0.12065 0.3048)
			(stroke
				(width 0.1)
				(type default)
			)
			(layer "F.Fab")
		)
		(fp_line
			(start -0.12065 0.3048)
			(end -0.67945 0.3048)
			(stroke
				(width 0.1)
				(type default)
			)
			(layer "F.Fab")
		)
		(fp_line
			(start 0.120396 0.2794)
			(end -0.12065 0.2794)
			(stroke
				(width 0.1)
				(type default)
			)
			(layer "F.Fab")
		)
		(fp_line
			(start 0.120396 0.3048)
			(end 0.120396 0.2794)
			(stroke
				(width 0.1)
				(type default)
			)
			(layer "F.Fab")
		)
		(fp_line
			(start 0.12065 -0.3048)
			(end 0.67945 -0.3048)
			(stroke
				(width 0.1)
				(type default)
			)
			(layer "F.Fab")
		)
		(fp_line
			(start 0.12065 -0.2794)
			(end 0.12065 -0.3048)
			(stroke
				(width 0.1)
				(type default)
			)
			(layer "F.Fab")
		)
		(fp_line
			(start 0.67945 -0.3048)
			(end 0.67945 0.3048)
			(stroke
				(width 0.1)
				(type default)
			)
			(layer "F.Fab")
		)
		(fp_line
			(start 0.67945 0.3048)
			(end 0.120396 0.3048)
			(stroke
				(width 0.1)
				(type default)
			)
			(layer "F.Fab")
		)
		(pad "1" smd circle
			(at -0.40005 0)
			(size 0 0)
			(layers "F.Cu" "F.Mask" "F.Paste")
			(net "GPU_3V3IO_RSVD3_ISO")
		)
		(pad "2" smd circle
			(at 0.40005 0)
			(size 0 0)
			(layers "F.Cu" "F.Mask" "F.Paste")
			(net "GPU_3V3IO_RSVD3")
		)
	)
	(footprint ""
		(layer "F.Cu")
		(at 325.03237 -87.414354 -90)
		(property "Reference" "R6385"
			(at 0 0 270)
			(layer "F.SilkS")
			(hide yes)
			(effects
				(font
					(size 1.27 1.27)
				)
			)
		)
		(property "Value" ""
			(at 0 0 270)
			(layer "F.Fab")
			(effects
				(font
					(size 1.27 1.27)
				)
			)
		)
		(duplicate_pad_numbers_are_jumpers no)
		(fp_line
			(start -0.7874 0.4064)
			(end -0.7874 -0.4064)
			(stroke
				(width 0.1524)
				(type default)
			)
			(layer "F.SilkS")
		)
		(fp_line
			(start 0.7874 0.4064)
			(end -0.7874 0.4064)
			(stroke
				(width 0.1524)
				(type default)
			)
			(layer "F.SilkS")
		)
		(fp_line
			(start -0.7874 -0.4064)
			(end 0.7874 -0.4064)
			(stroke
				(width 0.1524)
				(type default)
			)
			(layer "F.SilkS")
		)
		(fp_line
			(start 0.7874 -0.4064)
			(end 0.7874 0.4064)
			(stroke
				(width 0.1524)
				(type default)
			)
			(layer "F.SilkS")
		)
		(fp_line
			(start -0.67945 0.3048)
			(end -0.67945 -0.305054)
			(stroke
				(width 0.1)
				(type default)
			)
			(layer "F.Fab")
		)
		(fp_line
			(start -0.12065 0.3048)
			(end -0.67945 0.3048)
			(stroke
				(width 0.1)
				(type default)
			)
			(layer "F.Fab")
		)
		(fp_line
			(start 0.120396 0.3048)
			(end 0.120396 0.2794)
			(stroke
				(width 0.1)
				(type default)
			)
			(layer "F.Fab")
		)
		(fp_line
			(start 0.67945 0.3048)
			(end 0.120396 0.3048)
			(stroke
				(width 0.1)
				(type default)
			)
			(layer "F.Fab")
		)
		(fp_line
			(start -0.12065 0.2794)
			(end -0.12065 0.3048)
			(stroke
				(width 0.1)
				(type default)
			)
			(layer "F.Fab")
		)
		(fp_line
			(start 0.120396 0.2794)
			(end -0.12065 0.2794)
			(stroke
				(width 0.1)
				(type default)
			)
			(layer "F.Fab")
		)
		(fp_line
			(start -0.12065 -0.2794)
			(end 0.12065 -0.2794)
			(stroke
				(width 0.1)
				(type default)
			)
			(layer "F.Fab")
		)
		(fp_line
			(start 0.12065 -0.2794)
			(end 0.12065 -0.3048)
			(stroke
				(width 0.1)
				(type default)
			)
			(layer "F.Fab")
		)
		(fp_line
			(start 0.12065 -0.3048)
			(end 0.67945 -0.3048)
			(stroke
				(width 0.1)
				(type default)
			)
			(layer "F.Fab")
		)
		(fp_line
			(start 0.67945 -0.3048)
			(end 0.67945 0.3048)
			(stroke
				(width 0.1)
				(type default)
			)
			(layer "F.Fab")
		)
		(fp_line
			(start -0.67945 -0.305054)
			(end -0.12065 -0.305054)
			(stroke
				(width 0.1)
				(type default)
			)
			(layer "F.Fab")
		)
		(fp_line
			(start -0.12065 -0.305054)
			(end -0.12065 -0.2794)
			(stroke
				(width 0.1)
				(type default)
			)
			(layer "F.Fab")
		)
		(pad "1" smd circle
			(at -0.40005 0 270)
			(size 0 0)
			(layers "F.Cu" "F.Mask" "F.Paste")
			(net "SMB_BMC_9FGL0451E_S3_SDA")
		)
		(pad "2" smd circle
			(at 0.40005 0 270)
			(size 0 0)
			(layers "F.Cu" "F.Mask" "F.Paste")
			(net "SMB_ISO_CB_SDA")
		)
	)
	(footprint ""
		(layer "F.Cu")
		(at 215.464136 -181.613556 -90)
		(property "Reference" "C3625"
			(at 0 0 270)
			(layer "F.SilkS")
			(hide yes)
			(effects
				(font
					(size 1.27 1.27)
				)
			)
		)
		(property "Value" ""
			(at 0 0 270)
			(layer "F.Fab")
			(effects
				(font
					(size 1.27 1.27)
				)
			)
		)
		(duplicate_pad_numbers_are_jumpers no)
		(fp_line
			(start -0.7874 0.4064)
			(end -0.7874 -0.4064)
			(stroke
				(width 0.1524)
				(type default)
			)
			(layer "F.SilkS")
		)
		(fp_line
			(start 0.7874 0.4064)
			(end -0.7874 0.4064)
			(stroke
				(width 0.1524)
				(type default)
			)
			(layer "F.SilkS")
		)
		(fp_line
			(start -0.7874 -0.4064)
			(end 0.7874 -0.4064)
			(stroke
				(width 0.1524)
				(type default)
			)
			(layer "F.SilkS")
		)
		(fp_line
			(start 0.7874 -0.4064)
			(end 0.7874 0.4064)
			(stroke
				(width 0.1524)
				(type default)
			)
			(layer "F.SilkS")
		)
		(fp_line
			(start -0.67945 0.3048)
			(end -0.67945 -0.305054)
			(stroke
				(width 0.1)
				(type default)
			)
			(layer "F.Fab")
		)
		(fp_line
			(start -0.12065 0.3048)
			(end -0.67945 0.3048)
			(stroke
				(width 0.1)
				(type default)
			)
			(layer "F.Fab")
		)
		(fp_line
			(start 0.120396 0.3048)
			(end 0.120396 0.2794)
			(stroke
				(width 0.1)
				(type default)
			)
			(layer "F.Fab")
		)
		(fp_line
			(start 0.67945 0.3048)
			(end 0.120396 0.3048)
			(stroke
				(width 0.1)
				(type default)
			)
			(layer "F.Fab")
		)
		(fp_line
			(start -0.12065 0.2794)
			(end -0.12065 0.3048)
			(stroke
				(width 0.1)
				(type default)
			)
			(layer "F.Fab")
		)
		(fp_line
			(start 0.120396 0.2794)
			(end -0.12065 0.2794)
			(stroke
				(width 0.1)
				(type default)
			)
			(layer "F.Fab")
		)
		(fp_line
			(start -0.12065 -0.2794)
			(end 0.12065 -0.2794)
			(stroke
				(width 0.1)
				(type default)
			)
			(layer "F.Fab")
		)
		(fp_line
			(start 0.12065 -0.2794)
			(end 0.12065 -0.3048)
			(stroke
				(width 0.1)
				(type default)
			)
			(layer "F.Fab")
		)
		(fp_line
			(start 0.12065 -0.3048)
			(end 0.67945 -0.3048)
			(stroke
				(width 0.1)
				(type default)
			)
			(layer "F.Fab")
		)
		(fp_line
			(start 0.67945 -0.3048)
			(end 0.67945 0.3048)
			(stroke
				(width 0.1)
				(type default)
			)
			(layer "F.Fab")
		)
		(fp_line
			(start -0.67945 -0.305054)
			(end -0.12065 -0.305054)
			(stroke
				(width 0.1)
				(type default)
			)
			(layer "F.Fab")
		)
		(fp_line
			(start -0.12065 -0.305054)
			(end -0.12065 -0.2794)
			(stroke
				(width 0.1)
				(type default)
			)
			(layer "F.Fab")
		)
		(pad "1" smd circle
			(at -0.40005 0 270)
			(size 0 0)
			(layers "F.Cu" "F.Mask" "F.Paste")
			(net "P3V3_AUX")
		)
		(pad "2" smd circle
			(at 0.40005 0 270)
			(size 0 0)
			(layers "F.Cu" "F.Mask" "F.Paste")
			(net "GND")
		)
	)
	(footprint ""
		(layer "F.Cu")
		(at 433.00904 -27.04973 180)
		(property "Reference" "C2778"
			(at 0 0 180)
			(layer "F.SilkS")
			(hide yes)
			(effects
				(font
					(size 1.27 1.27)
				)
			)
		)
		(property "Value" ""
			(at 0 0 180)
			(layer "F.Fab")
			(effects
				(font
					(size 1.27 1.27)
				)
			)
		)
		(duplicate_pad_numbers_are_jumpers no)
		(fp_line
			(start 0.7874 0.4064)
			(end -0.7874 0.4064)
			(stroke
				(width 0.1524)
				(type default)
			)
			(layer "F.SilkS")
		)
		(fp_line
			(start 0.7874 -0.4064)
			(end 0.7874 0.4064)
			(stroke
				(width 0.1524)
				(type default)
			)
			(layer "F.SilkS")
		)
		(fp_line
			(start -0.7874 0.4064)
			(end -0.7874 -0.4064)
			(stroke
				(width 0.1524)
				(type default)
			)
			(layer "F.SilkS")
		)
		(fp_line
			(start -0.7874 -0.4064)
			(end 0.7874 -0.4064)
			(stroke
				(width 0.1524)
				(type default)
			)
			(layer "F.SilkS")
		)
		(fp_line
			(start 0.67945 0.3048)
			(end 0.120396 0.3048)
			(stroke
				(width 0.1)
				(type default)
			)
			(layer "F.Fab")
		)
		(fp_line
			(start 0.67945 -0.3048)
			(end 0.67945 0.3048)
			(stroke
				(width 0.1)
				(type default)
			)
			(layer "F.Fab")
		)
		(fp_line
			(start 0.12065 -0.2794)
			(end 0.12065 -0.3048)
			(stroke
				(width 0.1)
				(type default)
			)
			(layer "F.Fab")
		)
		(fp_line
			(start 0.12065 -0.3048)
			(end 0.67945 -0.3048)
			(stroke
				(width 0.1)
				(type default)
			)
			(layer "F.Fab")
		)
		(fp_line
			(start 0.120396 0.3048)
			(end 0.120396 0.2794)
			(stroke
				(width 0.1)
				(type default)
			)
			(layer "F.Fab")
		)
		(fp_line
			(start 0.120396 0.2794)
			(end -0.12065 0.2794)
			(stroke
				(width 0.1)
				(type default)
			)
			(layer "F.Fab")
		)
		(fp_line
			(start -0.12065 0.3048)
			(end -0.67945 0.3048)
			(stroke
				(width 0.1)
				(type default)
			)
			(layer "F.Fab")
		)
		(fp_line
			(start -0.12065 0.2794)
			(end -0.12065 0.3048)
			(stroke
				(width 0.1)
				(type default)
			)
			(layer "F.Fab")
		)
		(fp_line
			(start -0.12065 -0.2794)
			(end 0.12065 -0.2794)
			(stroke
				(width 0.1)
				(type default)
			)
			(layer "F.Fab")
		)
		(fp_line
			(start -0.12065 -0.305054)
			(end -0.12065 -0.2794)
			(stroke
				(width 0.1)
				(type default)
			)
			(layer "F.Fab")
		)
		(fp_line
			(start -0.67945 0.3048)
			(end -0.67945 -0.305054)
			(stroke
				(width 0.1)
				(type default)
			)
			(layer "F.Fab")
		)
		(fp_line
			(start -0.67945 -0.305054)
			(end -0.12065 -0.305054)
			(stroke
				(width 0.1)
				(type default)
			)
			(layer "F.Fab")
		)
		(pad "1" smd circle
			(at -0.40005 0 180)
			(size 0 0)
			(layers "F.Cu" "F.Mask" "F.Paste")
			(net "PRSNT_SSD15_R_N")
		)
		(pad "2" smd circle
			(at 0.40005 0 180)
			(size 0 0)
			(layers "F.Cu" "F.Mask" "F.Paste")
			(net "GND")
		)
	)
	(footprint ""
		(layer "F.Cu")
		(at 400.543776 -49.95291 180)
		(property "Reference" "R654"
			(at 0 0 180)
			(layer "F.SilkS")
			(hide yes)
			(effects
				(font
					(size 1.27 1.27)
				)
			)
		)
		(property "Value" ""
			(at 0 0 180)
			(layer "F.Fab")
			(effects
				(font
					(size 1.27 1.27)
				)
			)
		)
		(duplicate_pad_numbers_are_jumpers no)
		(fp_line
			(start 0.7874 0.4064)
			(end -0.7874 0.4064)
			(stroke
				(width 0.1524)
				(type default)
			)
			(layer "F.SilkS")
		)
		(fp_line
			(start 0.7874 -0.4064)
			(end 0.7874 0.4064)
			(stroke
				(width 0.1524)
				(type default)
			)
			(layer "F.SilkS")
		)
		(fp_line
			(start -0.7874 0.4064)
			(end -0.7874 -0.4064)
			(stroke
				(width 0.1524)
				(type default)
			)
			(layer "F.SilkS")
		)
		(fp_line
			(start -0.7874 -0.4064)
			(end 0.7874 -0.4064)
			(stroke
				(width 0.1524)
				(type default)
			)
			(layer "F.SilkS")
		)
		(fp_line
			(start 0.67945 0.3048)
			(end 0.120396 0.3048)
			(stroke
				(width 0.1)
				(type default)
			)
			(layer "F.Fab")
		)
		(fp_line
			(start 0.67945 -0.3048)
			(end 0.67945 0.3048)
			(stroke
				(width 0.1)
				(type default)
			)
			(layer "F.Fab")
		)
		(fp_line
			(start 0.12065 -0.2794)
			(end 0.12065 -0.3048)
			(stroke
				(width 0.1)
				(type default)
			)
			(layer "F.Fab")
		)
		(fp_line
			(start 0.12065 -0.3048)
			(end 0.67945 -0.3048)
			(stroke
				(width 0.1)
				(type default)
			)
			(layer "F.Fab")
		)
		(fp_line
			(start 0.120396 0.3048)
			(end 0.120396 0.2794)
			(stroke
				(width 0.1)
				(type default)
			)
			(layer "F.Fab")
		)
		(fp_line
			(start 0.120396 0.2794)
			(end -0.12065 0.2794)
			(stroke
				(width 0.1)
				(type default)
			)
			(layer "F.Fab")
		)
		(fp_line
			(start -0.12065 0.3048)
			(end -0.67945 0.3048)
			(stroke
				(width 0.1)
				(type default)
			)
			(layer "F.Fab")
		)
		(fp_line
			(start -0.12065 0.2794)
			(end -0.12065 0.3048)
			(stroke
				(width 0.1)
				(type default)
			)
			(layer "F.Fab")
		)
		(fp_line
			(start -0.12065 -0.2794)
			(end 0.12065 -0.2794)
			(stroke
				(width 0.1)
				(type default)
			)
			(layer "F.Fab")
		)
		(fp_line
			(start -0.12065 -0.305054)
			(end -0.12065 -0.2794)
			(stroke
				(width 0.1)
				(type default)
			)
			(layer "F.Fab")
		)
		(fp_line
			(start -0.67945 0.3048)
			(end -0.67945 -0.305054)
			(stroke
				(width 0.1)
				(type default)
			)
			(layer "F.Fab")
		)
		(fp_line
			(start -0.67945 -0.305054)
			(end -0.12065 -0.305054)
			(stroke
				(width 0.1)
				(type default)
			)
			(layer "F.Fab")
		)
		(pad "1" smd circle
			(at -0.40005 0 180)
			(size 0 0)
			(layers "F.Cu" "F.Mask" "F.Paste")
			(net "SMB_BIC_I2C6_MUX_SSD_8_15_ADC_R_SCL")
		)
		(pad "2" smd circle
			(at 0.40005 0 180)
			(size 0 0)
			(layers "F.Cu" "F.Mask" "F.Paste")
			(net "SMB_SSD13_ADC_SCL")
		)
	)
	(footprint ""
		(layer "F.Cu")
		(at 387.580632 -121.005346)
		(property "Reference" "C678"
			(at 0 0 0)
			(layer "F.SilkS")
			(hide yes)
			(effects
				(font
					(size 1.27 1.27)
				)
			)
		)
		(property "Value" ""
			(at 0 0 0)
			(layer "F.Fab")
			(effects
				(font
					(size 1.27 1.27)
				)
			)
		)
		(duplicate_pad_numbers_are_jumpers no)
		(fp_line
			(start -0.299974 -0.150114)
			(end 0.299974 -0.150114)
			(stroke
				(width 0.1)
				(type default)
			)
			(layer "F.Fab")
		)
		(fp_line
			(start -0.299974 0.150114)
			(end -0.299974 -0.150114)
			(stroke
				(width 0.1)
				(type default)
			)
			(layer "F.Fab")
		)
		(fp_line
			(start 0.299974 -0.150114)
			(end 0.299974 0.150114)
			(stroke
				(width 0.1)
				(type default)
			)
			(layer "F.Fab")
		)
		(fp_line
			(start 0.299974 0.150114)
			(end -0.299974 0.150114)
			(stroke
				(width 0.1)
				(type default)
			)
			(layer "F.Fab")
		)
		(pad "1" smd rect
			(at -0.2667 0)
			(size 0.3048 0.381)
			(layers "F.Cu" "F.Mask" "F.Paste")
			(net "P5E_PEX3_STN1_TX_DN<25>")
		)
		(pad "2" smd rect
			(at 0.2667 0)
			(size 0.3048 0.381)
			(layers "F.Cu" "F.Mask" "F.Paste")
			(net "P5E_PEX3_STN1_TX_C_DN<25>")
		)
	)
	(footprint ""
		(layer "F.Cu")
		(at 133.599428 -350.098614 90)
		(property "Reference" "C2253"
			(at 0 0 90)
			(layer "F.SilkS")
			(hide yes)
			(effects
				(font
					(size 1.27 1.27)
				)
			)
		)
		(property "Value" ""
			(at 0 0 90)
			(layer "F.Fab")
			(effects
				(font
					(size 1.27 1.27)
				)
			)
		)
		(duplicate_pad_numbers_are_jumpers no)
		(fp_line
			(start 0.299974 -0.150114)
			(end 0.299974 0.150114)
			(stroke
				(width 0.1)
				(type default)
			)
			(layer "F.Fab")
		)
		(fp_line
			(start -0.299974 -0.150114)
			(end 0.299974 -0.150114)
			(stroke
				(width 0.1)
				(type default)
			)
			(layer "F.Fab")
		)
		(fp_line
			(start 0.299974 0.150114)
			(end -0.299974 0.150114)
			(stroke
				(width 0.1)
				(type default)
			)
			(layer "F.Fab")
		)
		(fp_line
			(start -0.299974 0.150114)
			(end -0.299974 -0.150114)
			(stroke
				(width 0.1)
				(type default)
			)
			(layer "F.Fab")
		)
		(pad "1" smd rect
			(at -0.2667 0 90)
			(size 0.3048 0.381)
			(layers "F.Cu" "F.Mask" "F.Paste")
			(net "P5E_PEX1_STN5_TX_DP<90>")
		)
		(pad "2" smd rect
			(at 0.2667 0 90)
			(size 0.3048 0.381)
			(layers "F.Cu" "F.Mask" "F.Paste")
			(net "P5E_PEX1_STN5_TX_C_DP<90>")
		)
	)
	(footprint ""
		(layer "F.Cu")
		(at 262.281924 -292.991032 180)
		(property "Reference" "C3380"
			(at 0 0 180)
			(layer "F.SilkS")
			(hide yes)
			(effects
				(font
					(size 1.27 1.27)
				)
			)
		)
		(property "Value" ""
			(at 0 0 180)
			(layer "F.Fab")
			(effects
				(font
					(size 1.27 1.27)
				)
			)
		)
		(duplicate_pad_numbers_are_jumpers no)
		(fp_line
			(start 1.2954 0.5842)
			(end -1.2954 0.5842)
			(stroke
				(width 0.1524)
				(type default)
			)
			(layer "F.SilkS")
		)
		(fp_line
			(start 1.2954 -0.5842)
			(end 1.2954 0.5842)
			(stroke
				(width 0.1524)
				(type default)
			)
			(layer "F.SilkS")
		)
		(fp_line
			(start -1.2954 0.5842)
			(end -1.2954 -0.5842)
			(stroke
				(width 0.1524)
				(type default)
			)
			(layer "F.SilkS")
		)
		(fp_line
			(start -1.2954 -0.5842)
			(end 1.2954 -0.5842)
			(stroke
				(width 0.1524)
				(type default)
			)
			(layer "F.SilkS")
		)
		(fp_line
			(start 1.1938 0.4064)
			(end 0.8636 0.4064)
			(stroke
				(width 0.1)
				(type default)
			)
			(layer "F.Fab")
		)
		(fp_line
			(start 1.1938 -0.4064)
			(end 1.1938 0.4064)
			(stroke
				(width 0.1)
				(type default)
			)
			(layer "F.Fab")
		)
		(fp_line
			(start 0.8636 0.4572)
			(end -0.8636 0.4572)
			(stroke
				(width 0.1)
				(type default)
			)
			(layer "F.Fab")
		)
		(fp_line
			(start 0.8636 0.4064)
			(end 0.8636 0.4572)
			(stroke
				(width 0.1)
				(type default)
			)
			(layer "F.Fab")
		)
		(fp_line
			(start 0.8636 -0.4064)
			(end 1.1938 -0.4064)
			(stroke
				(width 0.1)
				(type default)
			)
			(layer "F.Fab")
		)
		(fp_line
			(start 0.8636 -0.4572)
			(end 0.8636 -0.4064)
			(stroke
				(width 0.1)
				(type default)
			)
			(layer "F.Fab")
		)
		(fp_line
			(start -0.8636 0.4572)
			(end -0.8636 0.4064)
			(stroke
				(width 0.1)
				(type default)
			)
			(layer "F.Fab")
		)
		(fp_line
			(start -0.8636 0.4064)
			(end -1.1938 0.4064)
			(stroke
				(width 0.1)
				(type default)
			)
			(layer "F.Fab")
		)
		(fp_line
			(start -0.8636 -0.4064)
			(end -0.8636 -0.4572)
			(stroke
				(width 0.1)
				(type default)
			)
			(layer "F.Fab")
		)
		(fp_line
			(start -0.8636 -0.4572)
			(end 0.8636 -0.4572)
			(stroke
				(width 0.1)
				(type default)
			)
			(layer "F.Fab")
		)
		(fp_line
			(start -1.1938 0.4064)
			(end -1.1938 -0.4064)
			(stroke
				(width 0.1)
				(type default)
			)
			(layer "F.Fab")
		)
		(fp_line
			(start -1.1938 -0.4064)
			(end -0.8636 -0.4064)
			(stroke
				(width 0.1)
				(type default)
			)
			(layer "F.Fab")
		)
		(pad "1" smd rect
			(at -0.7366 0 90)
			(size 0.7112 0.8128)
			(layers "F.Cu" "F.Mask" "F.Paste")
			(net "PCEPLL2_VDDA18_PEX2_R")
		)
		(pad "2" smd rect
			(at 0.7366 0 90)
			(size 0.7112 0.8128)
			(layers "F.Cu" "F.Mask" "F.Paste")
			(net "GND")
		)
	)
	(footprint ""
		(layer "F.Cu")
		(at 89.933018 -311.946544 135)
		(property "Reference" "R1235"
			(at 0 0 135)
			(layer "F.SilkS")
			(hide yes)
			(effects
				(font
					(size 1.27 1.27)
				)
			)
		)
		(property "Value" ""
			(at 0 0 135)
			(layer "F.Fab")
			(effects
				(font
					(size 1.27 1.27)
				)
			)
		)
		(duplicate_pad_numbers_are_jumpers no)
		(fp_line
			(start 0.787389 -0.406267)
			(end 0.787389 0.406267)
			(stroke
				(width 0.1524)
				(type default)
			)
			(layer "F.SilkS")
		)
		(fp_line
			(start 0.787389 0.406267)
			(end -0.787389 0.406267)
			(stroke
				(width 0.1524)
				(type default)
			)
			(layer "F.SilkS")
		)
		(fp_line
			(start -0.787389 -0.406267)
			(end 0.787389 -0.406267)
			(stroke
				(width 0.1524)
				(type default)
			)
			(layer "F.SilkS")
		)
		(fp_line
			(start -0.787389 0.406267)
			(end -0.787389 -0.406267)
			(stroke
				(width 0.1524)
				(type default)
			)
			(layer "F.SilkS")
		)
		(fp_line
			(start 0.679446 -0.30479)
			(end 0.679446 0.30479)
			(stroke
				(width 0.1)
				(type default)
			)
			(layer "F.Fab")
		)
		(fp_line
			(start 0.120515 -0.30479)
			(end 0.679446 -0.30479)
			(stroke
				(width 0.1)
				(type default)
			)
			(layer "F.Fab")
		)
		(fp_line
			(start 0.120695 -0.279466)
			(end 0.120515 -0.30479)
			(stroke
				(width 0.1)
				(type default)
			)
			(layer "F.Fab")
		)
		(fp_line
			(start 0.679446 0.30479)
			(end 0.120515 0.30479)
			(stroke
				(width 0.1)
				(type default)
			)
			(layer "F.Fab")
		)
		(fp_line
			(start -0.120695 -0.304969)
			(end -0.120695 -0.279466)
			(stroke
				(width 0.1)
				(type default)
			)
			(layer "F.Fab")
		)
		(fp_line
			(start -0.120695 -0.279466)
			(end 0.120695 -0.279466)
			(stroke
				(width 0.1)
				(type default)
			)
			(layer "F.Fab")
		)
		(fp_line
			(start 0.120335 0.279466)
			(end -0.120695 0.279466)
			(stroke
				(width 0.1)
				(type default)
			)
			(layer "F.Fab")
		)
		(fp_line
			(start 0.120515 0.30479)
			(end 0.120335 0.279466)
			(stroke
				(width 0.1)
				(type default)
			)
			(layer "F.Fab")
		)
		(fp_line
			(start -0.679446 -0.305149)
			(end -0.120695 -0.304969)
			(stroke
				(width 0.1)
				(type default)
			)
			(layer "F.Fab")
		)
		(fp_line
			(start -0.120695 0.279466)
			(end -0.120515 0.30479)
			(stroke
				(width 0.1)
				(type default)
			)
			(layer "F.Fab")
		)
		(fp_line
			(start -0.120515 0.30479)
			(end -0.679446 0.30479)
			(stroke
				(width 0.1)
				(type default)
			)
			(layer "F.Fab")
		)
		(fp_line
			(start -0.679446 0.30479)
			(end -0.679446 -0.305149)
			(stroke
				(width 0.1)
				(type default)
			)
			(layer "F.Fab")
		)
		(pad "1" smd circle
			(at -0.40005 0 135)
			(size 0 0)
			(layers "F.Cu" "F.Mask" "F.Paste")
			(net "PEX0_SPARE5")
		)
		(pad "2" smd circle
			(at 0.40005 0 135)
			(size 0 0)
			(layers "F.Cu" "F.Mask" "F.Paste")
			(net "P1V8_PEX")
		)
	)
	(footprint ""
		(layer "F.Cu")
		(at 410.791914 -161.881566 90)
		(property "Reference" "Q122"
			(at 0.018034 -1.901444 90)
			(unlocked yes)
			(layer "F.SilkS")
			(effects
				(font
					(size 0.7874 0.5842)
					(thickness 0.1524)
				)
			)
		)
		(property "Value" ""
			(at 0 0 90)
			(layer "F.Fab")
			(effects
				(font
					(size 1.27 1.27)
				)
			)
		)
		(duplicate_pad_numbers_are_jumpers no)
		(fp_line
			(start 1.376172 -1.199896)
			(end 1.376172 1.199896)
			(stroke
				(width 0.1524)
				(type default)
			)
			(layer "F.SilkS")
		)
		(fp_line
			(start 0.508 -1.199896)
			(end 1.376172 -1.199896)
			(stroke
				(width 0.1524)
				(type default)
			)
			(layer "F.SilkS")
		)
		(fp_line
			(start -0.508 -1.199896)
			(end 0 -0.762)
			(stroke
				(width 0.1524)
				(type default)
			)
			(layer "F.SilkS")
		)
		(fp_line
			(start -1.376172 -1.199896)
			(end -0.508 -1.199896)
			(stroke
				(width 0.1524)
				(type default)
			)
			(layer "F.SilkS")
		)
		(fp_line
			(start 0 -0.762)
			(end 0.508 -1.199896)
			(stroke
				(width 0.1524)
				(type default)
			)
			(layer "F.SilkS")
		)
		(fp_line
			(start 1.376172 1.199896)
			(end -1.376172 1.199896)
			(stroke
				(width 0.1524)
				(type default)
			)
			(layer "F.SilkS")
		)
		(fp_line
			(start -1.376172 1.199896)
			(end -1.376172 -1.199896)
			(stroke
				(width 0.1524)
				(type default)
			)
			(layer "F.SilkS")
		)
		(fp_poly
			(pts
				(xy -1.531874 -1.143762) (xy -1.801368 -1.95199) (xy -2.340102 -1.413256)
			)
			(stroke
				(width 0)
				(type default)
			)
			(fill yes)
			(layer "F.SilkS")
		)
		(fp_line
			(start 0.674878 -1.100074)
			(end 0.674878 1.100074)
			(stroke
				(width 0.1)
				(type default)
			)
			(layer "F.Fab")
		)
		(fp_line
			(start -0.674878 -1.100074)
			(end 0.674878 -1.100074)
			(stroke
				(width 0.1)
				(type default)
			)
			(layer "F.Fab")
		)
		(fp_line
			(start 0.674878 1.100074)
			(end -0.674878 1.100074)
			(stroke
				(width 0.1)
				(type default)
			)
			(layer "F.Fab")
		)
		(fp_line
			(start -0.674878 1.100074)
			(end -0.674878 -1.100074)
			(stroke
				(width 0.1)
				(type default)
			)
			(layer "F.Fab")
		)
		(fp_poly
			(pts
				(xy -1.4605 -0.7493) (xy -2.2225 -1.1303) (xy -2.2225 -0.3683)
			)
			(stroke
				(width 0)
				(type default)
			)
			(fill yes)
			(layer "F.Fab")
		)
		(pad "1" smd rect
			(at -0.899922 -0.750062)
			(size 0.6096 0.6096)
			(layers "F.Cu" "F.Mask" "F.Paste")
			(net "GND")
		)
		(pad "2" smd rect
			(at -0.899922 0)
			(size 0.4064 0.6096)
			(layers "F.Cu" "F.Mask" "F.Paste")
			(net "FM_SYS_THROTTLE_NIC6")
		)
		(pad "3" smd rect
			(at -0.899922 0.750062)
			(size 0.6096 0.6096)
			(layers "F.Cu" "F.Mask" "F.Paste")
			(net "NIC7_PWRBRK_N")
		)
		(pad "4" smd rect
			(at 0.899922 0.750062)
			(size 0.6096 0.6096)
			(layers "F.Cu" "F.Mask" "F.Paste")
			(net "GND")
		)
		(pad "5" smd rect
			(at 0.899922 0)
			(size 0.4064 0.6096)
			(layers "F.Cu" "F.Mask" "F.Paste")
			(net "FM_SYS_THROTTLE_NIC7")
		)
		(pad "6" smd rect
			(at 0.899922 -0.750062)
			(size 0.6096 0.6096)
			(layers "F.Cu" "F.Mask" "F.Paste")
			(net "NIC6_PWRBRK_N")
		)
	)
	(footprint ""
		(layer "F.Cu")
		(at 117.706902 -285.088584 90)
		(property "Reference" "PC57"
			(at 0 0 90)
			(layer "F.SilkS")
			(hide yes)
			(effects
				(font
					(size 1.27 1.27)
				)
			)
		)
		(property "Value" ""
			(at 0 0 90)
			(layer "F.Fab")
			(effects
				(font
					(size 1.27 1.27)
				)
			)
		)
		(duplicate_pad_numbers_are_jumpers no)
		(fp_line
			(start 0.7874 -0.4064)
			(end 0.7874 0.4064)
			(stroke
				(width 0.1524)
				(type default)
			)
			(layer "F.SilkS")
		)
		(fp_line
			(start -0.7874 -0.4064)
			(end 0.7874 -0.4064)
			(stroke
				(width 0.1524)
				(type default)
			)
			(layer "F.SilkS")
		)
		(fp_line
			(start 0.7874 0.4064)
			(end -0.7874 0.4064)
			(stroke
				(width 0.1524)
				(type default)
			)
			(layer "F.SilkS")
		)
		(fp_line
			(start -0.7874 0.4064)
			(end -0.7874 -0.4064)
			(stroke
				(width 0.1524)
				(type default)
			)
			(layer "F.SilkS")
		)
		(fp_line
			(start -0.12065 -0.305054)
			(end -0.12065 -0.2794)
			(stroke
				(width 0.1)
				(type default)
			)
			(layer "F.Fab")
		)
		(fp_line
			(start -0.67945 -0.305054)
			(end -0.12065 -0.305054)
			(stroke
				(width 0.1)
				(type default)
			)
			(layer "F.Fab")
		)
		(fp_line
			(start 0.67945 -0.3048)
			(end 0.67945 0.3048)
			(stroke
				(width 0.1)
				(type default)
			)
			(layer "F.Fab")
		)
		(fp_line
			(start 0.12065 -0.3048)
			(end 0.67945 -0.3048)
			(stroke
				(width 0.1)
				(type default)
			)
			(layer "F.Fab")
		)
		(fp_line
			(start 0.12065 -0.2794)
			(end 0.12065 -0.3048)
			(stroke
				(width 0.1)
				(type default)
			)
			(layer "F.Fab")
		)
		(fp_line
			(start -0.12065 -0.2794)
			(end 0.12065 -0.2794)
			(stroke
				(width 0.1)
				(type default)
			)
			(layer "F.Fab")
		)
		(fp_line
			(start 0.120396 0.2794)
			(end -0.12065 0.2794)
			(stroke
				(width 0.1)
				(type default)
			)
			(layer "F.Fab")
		)
		(fp_line
			(start -0.12065 0.2794)
			(end -0.12065 0.3048)
			(stroke
				(width 0.1)
				(type default)
			)
			(layer "F.Fab")
		)
		(fp_line
			(start 0.67945 0.3048)
			(end 0.120396 0.3048)
			(stroke
				(width 0.1)
				(type default)
			)
			(layer "F.Fab")
		)
		(fp_line
			(start 0.120396 0.3048)
			(end 0.120396 0.2794)
			(stroke
				(width 0.1)
				(type default)
			)
			(layer "F.Fab")
		)
		(fp_line
			(start -0.12065 0.3048)
			(end -0.67945 0.3048)
			(stroke
				(width 0.1)
				(type default)
			)
			(layer "F.Fab")
		)
		(fp_line
			(start -0.67945 0.3048)
			(end -0.67945 -0.305054)
			(stroke
				(width 0.1)
				(type default)
			)
			(layer "F.Fab")
		)
		(pad "1" smd circle
			(at -0.40005 0 90)
			(size 0 0)
			(layers "F.Cu" "F.Mask" "F.Paste")
			(net "P0V8_PEX0_PVCC")
		)
		(pad "2" smd circle
			(at 0.40005 0 90)
			(size 0 0)
			(layers "F.Cu" "F.Mask" "F.Paste")
			(net "GND")
		)
	)
	(footprint ""
		(layer "F.Cu")
		(at 357.19131 -252.416564 90)
		(property "Reference" "R836"
			(at 0 0 90)
			(layer "F.SilkS")
			(hide yes)
			(effects
				(font
					(size 1.27 1.27)
				)
			)
		)
		(property "Value" ""
			(at 0 0 90)
			(layer "F.Fab")
			(effects
				(font
					(size 1.27 1.27)
				)
			)
		)
		(duplicate_pad_numbers_are_jumpers no)
		(fp_line
			(start 0.7874 -0.4064)
			(end 0.7874 0.4064)
			(stroke
				(width 0.1524)
				(type default)
			)
			(layer "F.SilkS")
		)
		(fp_line
			(start -0.7874 -0.4064)
			(end 0.7874 -0.4064)
			(stroke
				(width 0.1524)
				(type default)
			)
			(layer "F.SilkS")
		)
		(fp_line
			(start 0.7874 0.4064)
			(end -0.7874 0.4064)
			(stroke
				(width 0.1524)
				(type default)
			)
			(layer "F.SilkS")
		)
		(fp_line
			(start -0.7874 0.4064)
			(end -0.7874 -0.4064)
			(stroke
				(width 0.1524)
				(type default)
			)
			(layer "F.SilkS")
		)
		(fp_line
			(start -0.12065 -0.305054)
			(end -0.12065 -0.2794)
			(stroke
				(width 0.1)
				(type default)
			)
			(layer "F.Fab")
		)
		(fp_line
			(start -0.67945 -0.305054)
			(end -0.12065 -0.305054)
			(stroke
				(width 0.1)
				(type default)
			)
			(layer "F.Fab")
		)
		(fp_line
			(start 0.67945 -0.3048)
			(end 0.67945 0.3048)
			(stroke
				(width 0.1)
				(type default)
			)
			(layer "F.Fab")
		)
		(fp_line
			(start 0.12065 -0.3048)
			(end 0.67945 -0.3048)
			(stroke
				(width 0.1)
				(type default)
			)
			(layer "F.Fab")
		)
		(fp_line
			(start 0.12065 -0.2794)
			(end 0.12065 -0.3048)
			(stroke
				(width 0.1)
				(type default)
			)
			(layer "F.Fab")
		)
		(fp_line
			(start -0.12065 -0.2794)
			(end 0.12065 -0.2794)
			(stroke
				(width 0.1)
				(type default)
			)
			(layer "F.Fab")
		)
		(fp_line
			(start 0.120396 0.2794)
			(end -0.12065 0.2794)
			(stroke
				(width 0.1)
				(type default)
			)
			(layer "F.Fab")
		)
		(fp_line
			(start -0.12065 0.2794)
			(end -0.12065 0.3048)
			(stroke
				(width 0.1)
				(type default)
			)
			(layer "F.Fab")
		)
		(fp_line
			(start 0.67945 0.3048)
			(end 0.120396 0.3048)
			(stroke
				(width 0.1)
				(type default)
			)
			(layer "F.Fab")
		)
		(fp_line
			(start 0.120396 0.3048)
			(end 0.120396 0.2794)
			(stroke
				(width 0.1)
				(type default)
			)
			(layer "F.Fab")
		)
		(fp_line
			(start -0.12065 0.3048)
			(end -0.67945 0.3048)
			(stroke
				(width 0.1)
				(type default)
			)
			(layer "F.Fab")
		)
		(fp_line
			(start -0.67945 0.3048)
			(end -0.67945 -0.305054)
			(stroke
				(width 0.1)
				(type default)
			)
			(layer "F.Fab")
		)
		(pad "1" smd circle
			(at -0.40005 0 90)
			(size 0 0)
			(layers "F.Cu" "F.Mask" "F.Paste")
			(net "SMB_BIC_I2C6_MUX_VR_R_SCL")
		)
		(pad "2" smd circle
			(at 0.40005 0 90)
			(size 0 0)
			(layers "F.Cu" "F.Mask" "F.Paste")
			(net "SMB_VR_P0V8_PEX2_SCL")
		)
	)
	(footprint ""
		(layer "F.Cu")
		(at 446.038478 -44.341542 90)
		(property "Reference" "C408"
			(at 0 0 90)
			(layer "F.SilkS")
			(hide yes)
			(effects
				(font
					(size 1.27 1.27)
				)
			)
		)
		(property "Value" ""
			(at 0 0 90)
			(layer "F.Fab")
			(effects
				(font
					(size 1.27 1.27)
				)
			)
		)
		(duplicate_pad_numbers_are_jumpers no)
		(fp_line
			(start 0.7874 -0.4064)
			(end 0.7874 0.4064)
			(stroke
				(width 0.1524)
				(type default)
			)
			(layer "F.SilkS")
		)
		(fp_line
			(start -0.7874 -0.4064)
			(end 0.7874 -0.4064)
			(stroke
				(width 0.1524)
				(type default)
			)
			(layer "F.SilkS")
		)
		(fp_line
			(start 0.7874 0.4064)
			(end -0.7874 0.4064)
			(stroke
				(width 0.1524)
				(type default)
			)
			(layer "F.SilkS")
		)
		(fp_line
			(start -0.7874 0.4064)
			(end -0.7874 -0.4064)
			(stroke
				(width 0.1524)
				(type default)
			)
			(layer "F.SilkS")
		)
		(fp_line
			(start -0.12065 -0.305054)
			(end -0.12065 -0.2794)
			(stroke
				(width 0.1)
				(type default)
			)
			(layer "F.Fab")
		)
		(fp_line
			(start -0.67945 -0.305054)
			(end -0.12065 -0.305054)
			(stroke
				(width 0.1)
				(type default)
			)
			(layer "F.Fab")
		)
		(fp_line
			(start 0.67945 -0.3048)
			(end 0.67945 0.3048)
			(stroke
				(width 0.1)
				(type default)
			)
			(layer "F.Fab")
		)
		(fp_line
			(start 0.12065 -0.3048)
			(end 0.67945 -0.3048)
			(stroke
				(width 0.1)
				(type default)
			)
			(layer "F.Fab")
		)
		(fp_line
			(start 0.12065 -0.2794)
			(end 0.12065 -0.3048)
			(stroke
				(width 0.1)
				(type default)
			)
			(layer "F.Fab")
		)
		(fp_line
			(start -0.12065 -0.2794)
			(end 0.12065 -0.2794)
			(stroke
				(width 0.1)
				(type default)
			)
			(layer "F.Fab")
		)
		(fp_line
			(start 0.120396 0.2794)
			(end -0.12065 0.2794)
			(stroke
				(width 0.1)
				(type default)
			)
			(layer "F.Fab")
		)
		(fp_line
			(start -0.12065 0.2794)
			(end -0.12065 0.3048)
			(stroke
				(width 0.1)
				(type default)
			)
			(layer "F.Fab")
		)
		(fp_line
			(start 0.67945 0.3048)
			(end 0.120396 0.3048)
			(stroke
				(width 0.1)
				(type default)
			)
			(layer "F.Fab")
		)
		(fp_line
			(start 0.120396 0.3048)
			(end 0.120396 0.2794)
			(stroke
				(width 0.1)
				(type default)
			)
			(layer "F.Fab")
		)
		(fp_line
			(start -0.12065 0.3048)
			(end -0.67945 0.3048)
			(stroke
				(width 0.1)
				(type default)
			)
			(layer "F.Fab")
		)
		(fp_line
			(start -0.67945 0.3048)
			(end -0.67945 -0.305054)
			(stroke
				(width 0.1)
				(type default)
			)
			(layer "F.Fab")
		)
		(pad "1" smd circle
			(at -0.40005 0 90)
			(size 0 0)
			(layers "F.Cu" "F.Mask" "F.Paste")
			(net "P12V_SSD15_VIN_P")
		)
		(pad "2" smd circle
			(at 0.40005 0 90)
			(size 0 0)
			(layers "F.Cu" "F.Mask" "F.Paste")
			(net "P12V_SSD15_VIN_N")
		)
	)
	(footprint ""
		(layer "F.Cu")
		(at 360.683556 -160.327848 180)
		(property "Reference" "PR7051"
			(at 0 0 180)
			(layer "F.SilkS")
			(hide yes)
			(effects
				(font
					(size 1.27 1.27)
				)
			)
		)
		(property "Value" ""
			(at 0 0 180)
			(layer "F.Fab")
			(effects
				(font
					(size 1.27 1.27)
				)
			)
		)
		(duplicate_pad_numbers_are_jumpers no)
		(fp_line
			(start 0.7874 0.4064)
			(end -0.7874 0.4064)
			(stroke
				(width 0.1524)
				(type default)
			)
			(layer "F.SilkS")
		)
		(fp_line
			(start 0.7874 -0.4064)
			(end 0.7874 0.4064)
			(stroke
				(width 0.1524)
				(type default)
			)
			(layer "F.SilkS")
		)
		(fp_line
			(start -0.7874 0.4064)
			(end -0.7874 -0.4064)
			(stroke
				(width 0.1524)
				(type default)
			)
			(layer "F.SilkS")
		)
		(fp_line
			(start -0.7874 -0.4064)
			(end 0.7874 -0.4064)
			(stroke
				(width 0.1524)
				(type default)
			)
			(layer "F.SilkS")
		)
		(fp_line
			(start 0.67945 0.3048)
			(end 0.120396 0.3048)
			(stroke
				(width 0.1)
				(type default)
			)
			(layer "F.Fab")
		)
		(fp_line
			(start 0.67945 -0.3048)
			(end 0.67945 0.3048)
			(stroke
				(width 0.1)
				(type default)
			)
			(layer "F.Fab")
		)
		(fp_line
			(start 0.12065 -0.2794)
			(end 0.12065 -0.3048)
			(stroke
				(width 0.1)
				(type default)
			)
			(layer "F.Fab")
		)
		(fp_line
			(start 0.12065 -0.3048)
			(end 0.67945 -0.3048)
			(stroke
				(width 0.1)
				(type default)
			)
			(layer "F.Fab")
		)
		(fp_line
			(start 0.120396 0.3048)
			(end 0.120396 0.2794)
			(stroke
				(width 0.1)
				(type default)
			)
			(layer "F.Fab")
		)
		(fp_line
			(start 0.120396 0.2794)
			(end -0.12065 0.2794)
			(stroke
				(width 0.1)
				(type default)
			)
			(layer "F.Fab")
		)
		(fp_line
			(start -0.12065 0.3048)
			(end -0.67945 0.3048)
			(stroke
				(width 0.1)
				(type default)
			)
			(layer "F.Fab")
		)
		(fp_line
			(start -0.12065 0.2794)
			(end -0.12065 0.3048)
			(stroke
				(width 0.1)
				(type default)
			)
			(layer "F.Fab")
		)
		(fp_line
			(start -0.12065 -0.2794)
			(end 0.12065 -0.2794)
			(stroke
				(width 0.1)
				(type default)
			)
			(layer "F.Fab")
		)
		(fp_line
			(start -0.12065 -0.305054)
			(end -0.12065 -0.2794)
			(stroke
				(width 0.1)
				(type default)
			)
			(layer "F.Fab")
		)
		(fp_line
			(start -0.67945 0.3048)
			(end -0.67945 -0.305054)
			(stroke
				(width 0.1)
				(type default)
			)
			(layer "F.Fab")
		)
		(fp_line
			(start -0.67945 -0.305054)
			(end -0.12065 -0.305054)
			(stroke
				(width 0.1)
				(type default)
			)
			(layer "F.Fab")
		)
		(pad "1" smd circle
			(at -0.40005 0 180)
			(size 0 0)
			(layers "F.Cu" "F.Mask" "F.Paste")
			(net "P12V_NIC6_CO_ISET")
		)
		(pad "2" smd circle
			(at 0.40005 0 180)
			(size 0 0)
			(layers "F.Cu" "F.Mask" "F.Paste")
			(net "P12V_NIC6_CO_ISET_R")
		)
	)
	(footprint ""
		(layer "F.Cu")
		(at 89.023444 -96.811592 -90)
		(property "Reference" "R694"
			(at 0 0 270)
			(layer "F.SilkS")
			(hide yes)
			(effects
				(font
					(size 1.27 1.27)
				)
			)
		)
		(property "Value" ""
			(at 0 0 270)
			(layer "F.Fab")
			(effects
				(font
					(size 1.27 1.27)
				)
			)
		)
		(duplicate_pad_numbers_are_jumpers no)
		(fp_line
			(start -0.7874 0.4064)
			(end -0.7874 -0.4064)
			(stroke
				(width 0.1524)
				(type default)
			)
			(layer "F.SilkS")
		)
		(fp_line
			(start 0.7874 0.4064)
			(end -0.7874 0.4064)
			(stroke
				(width 0.1524)
				(type default)
			)
			(layer "F.SilkS")
		)
		(fp_line
			(start -0.7874 -0.4064)
			(end 0.7874 -0.4064)
			(stroke
				(width 0.1524)
				(type default)
			)
			(layer "F.SilkS")
		)
		(fp_line
			(start 0.7874 -0.4064)
			(end 0.7874 0.4064)
			(stroke
				(width 0.1524)
				(type default)
			)
			(layer "F.SilkS")
		)
		(fp_line
			(start -0.67945 0.3048)
			(end -0.67945 -0.305054)
			(stroke
				(width 0.1)
				(type default)
			)
			(layer "F.Fab")
		)
		(fp_line
			(start -0.12065 0.3048)
			(end -0.67945 0.3048)
			(stroke
				(width 0.1)
				(type default)
			)
			(layer "F.Fab")
		)
		(fp_line
			(start 0.120396 0.3048)
			(end 0.120396 0.2794)
			(stroke
				(width 0.1)
				(type default)
			)
			(layer "F.Fab")
		)
		(fp_line
			(start 0.67945 0.3048)
			(end 0.120396 0.3048)
			(stroke
				(width 0.1)
				(type default)
			)
			(layer "F.Fab")
		)
		(fp_line
			(start -0.12065 0.2794)
			(end -0.12065 0.3048)
			(stroke
				(width 0.1)
				(type default)
			)
			(layer "F.Fab")
		)
		(fp_line
			(start 0.120396 0.2794)
			(end -0.12065 0.2794)
			(stroke
				(width 0.1)
				(type default)
			)
			(layer "F.Fab")
		)
		(fp_line
			(start -0.12065 -0.2794)
			(end 0.12065 -0.2794)
			(stroke
				(width 0.1)
				(type default)
			)
			(layer "F.Fab")
		)
		(fp_line
			(start 0.12065 -0.2794)
			(end 0.12065 -0.3048)
			(stroke
				(width 0.1)
				(type default)
			)
			(layer "F.Fab")
		)
		(fp_line
			(start 0.12065 -0.3048)
			(end 0.67945 -0.3048)
			(stroke
				(width 0.1)
				(type default)
			)
			(layer "F.Fab")
		)
		(fp_line
			(start 0.67945 -0.3048)
			(end 0.67945 0.3048)
			(stroke
				(width 0.1)
				(type default)
			)
			(layer "F.Fab")
		)
		(fp_line
			(start -0.67945 -0.305054)
			(end -0.12065 -0.305054)
			(stroke
				(width 0.1)
				(type default)
			)
			(layer "F.Fab")
		)
		(fp_line
			(start -0.12065 -0.305054)
			(end -0.12065 -0.2794)
			(stroke
				(width 0.1)
				(type default)
			)
			(layer "F.Fab")
		)
		(pad "1" smd circle
			(at -0.40005 0 270)
			(size 0 0)
			(layers "F.Cu" "F.Mask" "F.Paste")
			(net "NIC1_ADC_A0")
		)
		(pad "2" smd circle
			(at 0.40005 0 270)
			(size 0 0)
			(layers "F.Cu" "F.Mask" "F.Paste")
			(net "P3V3_AUX")
		)
	)
	(footprint ""
		(layer "F.Cu")
		(at 213.990936 -188.652404 90)
		(property "Reference" "R5302"
			(at 0 0 90)
			(layer "F.SilkS")
			(hide yes)
			(effects
				(font
					(size 1.27 1.27)
				)
			)
		)
		(property "Value" ""
			(at 0 0 90)
			(layer "F.Fab")
			(effects
				(font
					(size 1.27 1.27)
				)
			)
		)
		(duplicate_pad_numbers_are_jumpers no)
		(fp_line
			(start 0.7874 -0.4064)
			(end 0.7874 0.4064)
			(stroke
				(width 0.1524)
				(type default)
			)
			(layer "F.SilkS")
		)
		(fp_line
			(start -0.7874 -0.4064)
			(end 0.7874 -0.4064)
			(stroke
				(width 0.1524)
				(type default)
			)
			(layer "F.SilkS")
		)
		(fp_line
			(start 0.7874 0.4064)
			(end -0.7874 0.4064)
			(stroke
				(width 0.1524)
				(type default)
			)
			(layer "F.SilkS")
		)
		(fp_line
			(start -0.7874 0.4064)
			(end -0.7874 -0.4064)
			(stroke
				(width 0.1524)
				(type default)
			)
			(layer "F.SilkS")
		)
		(fp_line
			(start -0.12065 -0.305054)
			(end -0.12065 -0.2794)
			(stroke
				(width 0.1)
				(type default)
			)
			(layer "F.Fab")
		)
		(fp_line
			(start -0.67945 -0.305054)
			(end -0.12065 -0.305054)
			(stroke
				(width 0.1)
				(type default)
			)
			(layer "F.Fab")
		)
		(fp_line
			(start 0.67945 -0.3048)
			(end 0.67945 0.3048)
			(stroke
				(width 0.1)
				(type default)
			)
			(layer "F.Fab")
		)
		(fp_line
			(start 0.12065 -0.3048)
			(end 0.67945 -0.3048)
			(stroke
				(width 0.1)
				(type default)
			)
			(layer "F.Fab")
		)
		(fp_line
			(start 0.12065 -0.2794)
			(end 0.12065 -0.3048)
			(stroke
				(width 0.1)
				(type default)
			)
			(layer "F.Fab")
		)
		(fp_line
			(start -0.12065 -0.2794)
			(end 0.12065 -0.2794)
			(stroke
				(width 0.1)
				(type default)
			)
			(layer "F.Fab")
		)
		(fp_line
			(start 0.120396 0.2794)
			(end -0.12065 0.2794)
			(stroke
				(width 0.1)
				(type default)
			)
			(layer "F.Fab")
		)
		(fp_line
			(start -0.12065 0.2794)
			(end -0.12065 0.3048)
			(stroke
				(width 0.1)
				(type default)
			)
			(layer "F.Fab")
		)
		(fp_line
			(start 0.67945 0.3048)
			(end 0.120396 0.3048)
			(stroke
				(width 0.1)
				(type default)
			)
			(layer "F.Fab")
		)
		(fp_line
			(start 0.120396 0.3048)
			(end 0.120396 0.2794)
			(stroke
				(width 0.1)
				(type default)
			)
			(layer "F.Fab")
		)
		(fp_line
			(start -0.12065 0.3048)
			(end -0.67945 0.3048)
			(stroke
				(width 0.1)
				(type default)
			)
			(layer "F.Fab")
		)
		(fp_line
			(start -0.67945 0.3048)
			(end -0.67945 -0.305054)
			(stroke
				(width 0.1)
				(type default)
			)
			(layer "F.Fab")
		)
		(pad "1" smd circle
			(at -0.40005 0 90)
			(size 0 0)
			(layers "F.Cu" "F.Mask" "F.Paste")
			(net "BIC_SEL_FLASH_SW1_R")
		)
		(pad "2" smd circle
			(at 0.40005 0 90)
			(size 0 0)
			(layers "F.Cu" "F.Mask" "F.Paste")
			(net "P3V3_AUX")
		)
	)
	(footprint ""
		(layer "F.Cu")
		(at 78.267052 -57.332626)
		(property "Reference" "R6839"
			(at 0 0 0)
			(layer "F.SilkS")
			(hide yes)
			(effects
				(font
					(size 1.27 1.27)
				)
			)
		)
		(property "Value" ""
			(at 0 0 0)
			(layer "F.Fab")
			(effects
				(font
					(size 1.27 1.27)
				)
			)
		)
		(duplicate_pad_numbers_are_jumpers no)
		(fp_line
			(start -0.7874 -0.4064)
			(end 0.7874 -0.4064)
			(stroke
				(width 0.1524)
				(type default)
			)
			(layer "F.SilkS")
		)
		(fp_line
			(start -0.7874 0.4064)
			(end -0.7874 -0.4064)
			(stroke
				(width 0.1524)
				(type default)
			)
			(layer "F.SilkS")
		)
		(fp_line
			(start 0.7874 -0.4064)
			(end 0.7874 0.4064)
			(stroke
				(width 0.1524)
				(type default)
			)
			(layer "F.SilkS")
		)
		(fp_line
			(start 0.7874 0.4064)
			(end -0.7874 0.4064)
			(stroke
				(width 0.1524)
				(type default)
			)
			(layer "F.SilkS")
		)
		(fp_line
			(start -0.67945 -0.305054)
			(end -0.12065 -0.305054)
			(stroke
				(width 0.1)
				(type default)
			)
			(layer "F.Fab")
		)
		(fp_line
			(start -0.67945 0.3048)
			(end -0.67945 -0.305054)
			(stroke
				(width 0.1)
				(type default)
			)
			(layer "F.Fab")
		)
		(fp_line
			(start -0.12065 -0.305054)
			(end -0.12065 -0.2794)
			(stroke
				(width 0.1)
				(type default)
			)
			(layer "F.Fab")
		)
		(fp_line
			(start -0.12065 -0.2794)
			(end 0.12065 -0.2794)
			(stroke
				(width 0.1)
				(type default)
			)
			(layer "F.Fab")
		)
		(fp_line
			(start -0.12065 0.2794)
			(end -0.12065 0.3048)
			(stroke
				(width 0.1)
				(type default)
			)
			(layer "F.Fab")
		)
		(fp_line
			(start -0.12065 0.3048)
			(end -0.67945 0.3048)
			(stroke
				(width 0.1)
				(type default)
			)
			(layer "F.Fab")
		)
		(fp_line
			(start 0.120396 0.2794)
			(end -0.12065 0.2794)
			(stroke
				(width 0.1)
				(type default)
			)
			(layer "F.Fab")
		)
		(fp_line
			(start 0.120396 0.3048)
			(end 0.120396 0.2794)
			(stroke
				(width 0.1)
				(type default)
			)
			(layer "F.Fab")
		)
		(fp_line
			(start 0.12065 -0.3048)
			(end 0.67945 -0.3048)
			(stroke
				(width 0.1)
				(type default)
			)
			(layer "F.Fab")
		)
		(fp_line
			(start 0.12065 -0.2794)
			(end 0.12065 -0.3048)
			(stroke
				(width 0.1)
				(type default)
			)
			(layer "F.Fab")
		)
		(fp_line
			(start 0.67945 -0.3048)
			(end 0.67945 0.3048)
			(stroke
				(width 0.1)
				(type default)
			)
			(layer "F.Fab")
		)
		(fp_line
			(start 0.67945 0.3048)
			(end 0.120396 0.3048)
			(stroke
				(width 0.1)
				(type default)
			)
			(layer "F.Fab")
		)
		(pad "1" smd circle
			(at -0.40005 0)
			(size 0 0)
			(layers "F.Cu" "F.Mask" "F.Paste")
			(net "SSD2_PWR_EN_R")
		)
		(pad "2" smd circle
			(at 0.40005 0)
			(size 0 0)
			(layers "F.Cu" "F.Mask" "F.Paste")
			(net "GND")
		)
	)
	(footprint ""
		(layer "F.Cu")
		(at 295.767252 -171.675806)
		(property "Reference" "R253"
			(at 0 0 0)
			(layer "F.SilkS")
			(hide yes)
			(effects
				(font
					(size 1.27 1.27)
				)
			)
		)
		(property "Value" ""
			(at 0 0 0)
			(layer "F.Fab")
			(effects
				(font
					(size 1.27 1.27)
				)
			)
		)
		(duplicate_pad_numbers_are_jumpers no)
		(fp_line
			(start -0.7874 -0.4064)
			(end 0.7874 -0.4064)
			(stroke
				(width 0.1524)
				(type default)
			)
			(layer "F.SilkS")
		)
		(fp_line
			(start -0.7874 0.4064)
			(end -0.7874 -0.4064)
			(stroke
				(width 0.1524)
				(type default)
			)
			(layer "F.SilkS")
		)
		(fp_line
			(start 0.7874 -0.4064)
			(end 0.7874 0.4064)
			(stroke
				(width 0.1524)
				(type default)
			)
			(layer "F.SilkS")
		)
		(fp_line
			(start 0.7874 0.4064)
			(end -0.7874 0.4064)
			(stroke
				(width 0.1524)
				(type default)
			)
			(layer "F.SilkS")
		)
		(fp_line
			(start -0.67945 -0.305054)
			(end -0.12065 -0.305054)
			(stroke
				(width 0.1)
				(type default)
			)
			(layer "F.Fab")
		)
		(fp_line
			(start -0.67945 0.3048)
			(end -0.67945 -0.305054)
			(stroke
				(width 0.1)
				(type default)
			)
			(layer "F.Fab")
		)
		(fp_line
			(start -0.12065 -0.305054)
			(end -0.12065 -0.2794)
			(stroke
				(width 0.1)
				(type default)
			)
			(layer "F.Fab")
		)
		(fp_line
			(start -0.12065 -0.2794)
			(end 0.12065 -0.2794)
			(stroke
				(width 0.1)
				(type default)
			)
			(layer "F.Fab")
		)
		(fp_line
			(start -0.12065 0.2794)
			(end -0.12065 0.3048)
			(stroke
				(width 0.1)
				(type default)
			)
			(layer "F.Fab")
		)
		(fp_line
			(start -0.12065 0.3048)
			(end -0.67945 0.3048)
			(stroke
				(width 0.1)
				(type default)
			)
			(layer "F.Fab")
		)
		(fp_line
			(start 0.120396 0.2794)
			(end -0.12065 0.2794)
			(stroke
				(width 0.1)
				(type default)
			)
			(layer "F.Fab")
		)
		(fp_line
			(start 0.120396 0.3048)
			(end 0.120396 0.2794)
			(stroke
				(width 0.1)
				(type default)
			)
			(layer "F.Fab")
		)
		(fp_line
			(start 0.12065 -0.3048)
			(end 0.67945 -0.3048)
			(stroke
				(width 0.1)
				(type default)
			)
			(layer "F.Fab")
		)
		(fp_line
			(start 0.12065 -0.2794)
			(end 0.12065 -0.3048)
			(stroke
				(width 0.1)
				(type default)
			)
			(layer "F.Fab")
		)
		(fp_line
			(start 0.67945 -0.3048)
			(end 0.67945 0.3048)
			(stroke
				(width 0.1)
				(type default)
			)
			(layer "F.Fab")
		)
		(fp_line
			(start 0.67945 0.3048)
			(end 0.120396 0.3048)
			(stroke
				(width 0.1)
				(type default)
			)
			(layer "F.Fab")
		)
		(pad "1" smd circle
			(at -0.40005 0)
			(size 0 0)
			(layers "F.Cu" "F.Mask" "F.Paste")
			(net "P3V3_NIC4")
		)
		(pad "2" smd circle
			(at 0.40005 0)
			(size 0 0)
			(layers "F.Cu" "F.Mask" "F.Paste")
			(net "HP_NIC4_PWRGD")
		)
	)
	(footprint ""
		(layer "F.Cu")
		(at 216.920572 -70.307454 90)
		(property "Reference" "PC849"
			(at 0 0 90)
			(layer "F.SilkS")
			(hide yes)
			(effects
				(font
					(size 1.27 1.27)
				)
			)
		)
		(property "Value" ""
			(at 0 0 90)
			(layer "F.Fab")
			(effects
				(font
					(size 1.27 1.27)
				)
			)
		)
		(duplicate_pad_numbers_are_jumpers no)
		(fp_line
			(start 0.7874 -0.4064)
			(end 0.7874 0.4064)
			(stroke
				(width 0.1524)
				(type default)
			)
			(layer "F.SilkS")
		)
		(fp_line
			(start -0.7874 -0.4064)
			(end 0.7874 -0.4064)
			(stroke
				(width 0.1524)
				(type default)
			)
			(layer "F.SilkS")
		)
		(fp_line
			(start 0.7874 0.4064)
			(end -0.7874 0.4064)
			(stroke
				(width 0.1524)
				(type default)
			)
			(layer "F.SilkS")
		)
		(fp_line
			(start -0.7874 0.4064)
			(end -0.7874 -0.4064)
			(stroke
				(width 0.1524)
				(type default)
			)
			(layer "F.SilkS")
		)
		(fp_line
			(start -0.12065 -0.305054)
			(end -0.12065 -0.2794)
			(stroke
				(width 0.1)
				(type default)
			)
			(layer "F.Fab")
		)
		(fp_line
			(start -0.67945 -0.305054)
			(end -0.12065 -0.305054)
			(stroke
				(width 0.1)
				(type default)
			)
			(layer "F.Fab")
		)
		(fp_line
			(start 0.67945 -0.3048)
			(end 0.67945 0.3048)
			(stroke
				(width 0.1)
				(type default)
			)
			(layer "F.Fab")
		)
		(fp_line
			(start 0.12065 -0.3048)
			(end 0.67945 -0.3048)
			(stroke
				(width 0.1)
				(type default)
			)
			(layer "F.Fab")
		)
		(fp_line
			(start 0.12065 -0.2794)
			(end 0.12065 -0.3048)
			(stroke
				(width 0.1)
				(type default)
			)
			(layer "F.Fab")
		)
		(fp_line
			(start -0.12065 -0.2794)
			(end 0.12065 -0.2794)
			(stroke
				(width 0.1)
				(type default)
			)
			(layer "F.Fab")
		)
		(fp_line
			(start 0.120396 0.2794)
			(end -0.12065 0.2794)
			(stroke
				(width 0.1)
				(type default)
			)
			(layer "F.Fab")
		)
		(fp_line
			(start -0.12065 0.2794)
			(end -0.12065 0.3048)
			(stroke
				(width 0.1)
				(type default)
			)
			(layer "F.Fab")
		)
		(fp_line
			(start 0.67945 0.3048)
			(end 0.120396 0.3048)
			(stroke
				(width 0.1)
				(type default)
			)
			(layer "F.Fab")
		)
		(fp_line
			(start 0.120396 0.3048)
			(end 0.120396 0.2794)
			(stroke
				(width 0.1)
				(type default)
			)
			(layer "F.Fab")
		)
		(fp_line
			(start -0.12065 0.3048)
			(end -0.67945 0.3048)
			(stroke
				(width 0.1)
				(type default)
			)
			(layer "F.Fab")
		)
		(fp_line
			(start -0.67945 0.3048)
			(end -0.67945 -0.305054)
			(stroke
				(width 0.1)
				(type default)
			)
			(layer "F.Fab")
		)
		(pad "1" smd circle
			(at -0.40005 0 90)
			(size 0 0)
			(layers "F.Cu" "F.Mask" "F.Paste")
			(net "P12V_AUX")
		)
		(pad "2" smd circle
			(at 0.40005 0 90)
			(size 0 0)
			(layers "F.Cu" "F.Mask" "F.Paste")
			(net "GND")
		)
	)
	(footprint ""
		(layer "F.Cu")
		(at 387.580632 -111.003334)
		(property "Reference" "C685"
			(at 0 0 0)
			(layer "F.SilkS")
			(hide yes)
			(effects
				(font
					(size 1.27 1.27)
				)
			)
		)
		(property "Value" ""
			(at 0 0 0)
			(layer "F.Fab")
			(effects
				(font
					(size 1.27 1.27)
				)
			)
		)
		(duplicate_pad_numbers_are_jumpers no)
		(fp_line
			(start -0.299974 -0.150114)
			(end 0.299974 -0.150114)
			(stroke
				(width 0.1)
				(type default)
			)
			(layer "F.Fab")
		)
		(fp_line
			(start -0.299974 0.150114)
			(end -0.299974 -0.150114)
			(stroke
				(width 0.1)
				(type default)
			)
			(layer "F.Fab")
		)
		(fp_line
			(start 0.299974 -0.150114)
			(end 0.299974 0.150114)
			(stroke
				(width 0.1)
				(type default)
			)
			(layer "F.Fab")
		)
		(fp_line
			(start 0.299974 0.150114)
			(end -0.299974 0.150114)
			(stroke
				(width 0.1)
				(type default)
			)
			(layer "F.Fab")
		)
		(pad "1" smd rect
			(at -0.2667 0)
			(size 0.3048 0.381)
			(layers "F.Cu" "F.Mask" "F.Paste")
			(net "P5E_PEX3_STN1_TX_DN<22>")
		)
		(pad "2" smd rect
			(at 0.2667 0)
			(size 0.3048 0.381)
			(layers "F.Cu" "F.Mask" "F.Paste")
			(net "P5E_PEX3_STN1_TX_C_DN<22>")
		)
	)
	(footprint ""
		(layer "F.Cu")
		(at 319.696084 -390.990836 180)
		(property "Reference" "R1849"
			(at 0 0 180)
			(layer "F.SilkS")
			(hide yes)
			(effects
				(font
					(size 1.27 1.27)
				)
			)
		)
		(property "Value" ""
			(at 0 0 180)
			(layer "F.Fab")
			(effects
				(font
					(size 1.27 1.27)
				)
			)
		)
		(duplicate_pad_numbers_are_jumpers no)
		(fp_line
			(start 0.7874 0.4064)
			(end -0.7874 0.4064)
			(stroke
				(width 0.1524)
				(type default)
			)
			(layer "F.SilkS")
		)
		(fp_line
			(start 0.7874 -0.4064)
			(end 0.7874 0.4064)
			(stroke
				(width 0.1524)
				(type default)
			)
			(layer "F.SilkS")
		)
		(fp_line
			(start -0.7874 0.4064)
			(end -0.7874 -0.4064)
			(stroke
				(width 0.1524)
				(type default)
			)
			(layer "F.SilkS")
		)
		(fp_line
			(start -0.7874 -0.4064)
			(end 0.7874 -0.4064)
			(stroke
				(width 0.1524)
				(type default)
			)
			(layer "F.SilkS")
		)
		(fp_line
			(start 0.67945 0.3048)
			(end 0.120396 0.3048)
			(stroke
				(width 0.1)
				(type default)
			)
			(layer "F.Fab")
		)
		(fp_line
			(start 0.67945 -0.3048)
			(end 0.67945 0.3048)
			(stroke
				(width 0.1)
				(type default)
			)
			(layer "F.Fab")
		)
		(fp_line
			(start 0.12065 -0.2794)
			(end 0.12065 -0.3048)
			(stroke
				(width 0.1)
				(type default)
			)
			(layer "F.Fab")
		)
		(fp_line
			(start 0.12065 -0.3048)
			(end 0.67945 -0.3048)
			(stroke
				(width 0.1)
				(type default)
			)
			(layer "F.Fab")
		)
		(fp_line
			(start 0.120396 0.3048)
			(end 0.120396 0.2794)
			(stroke
				(width 0.1)
				(type default)
			)
			(layer "F.Fab")
		)
		(fp_line
			(start 0.120396 0.2794)
			(end -0.12065 0.2794)
			(stroke
				(width 0.1)
				(type default)
			)
			(layer "F.Fab")
		)
		(fp_line
			(start -0.12065 0.3048)
			(end -0.67945 0.3048)
			(stroke
				(width 0.1)
				(type default)
			)
			(layer "F.Fab")
		)
		(fp_line
			(start -0.12065 0.2794)
			(end -0.12065 0.3048)
			(stroke
				(width 0.1)
				(type default)
			)
			(layer "F.Fab")
		)
		(fp_line
			(start -0.12065 -0.2794)
			(end 0.12065 -0.2794)
			(stroke
				(width 0.1)
				(type default)
			)
			(layer "F.Fab")
		)
		(fp_line
			(start -0.12065 -0.305054)
			(end -0.12065 -0.2794)
			(stroke
				(width 0.1)
				(type default)
			)
			(layer "F.Fab")
		)
		(fp_line
			(start -0.67945 0.3048)
			(end -0.67945 -0.305054)
			(stroke
				(width 0.1)
				(type default)
			)
			(layer "F.Fab")
		)
		(fp_line
			(start -0.67945 -0.305054)
			(end -0.12065 -0.305054)
			(stroke
				(width 0.1)
				(type default)
			)
			(layer "F.Fab")
		)
		(pad "1" smd circle
			(at -0.40005 0 180)
			(size 0 0)
			(layers "F.Cu" "F.Mask" "F.Paste")
			(net "GPU_3V3IO_RSVD3_FFU_R")
		)
		(pad "2" smd circle
			(at 0.40005 0 180)
			(size 0 0)
			(layers "F.Cu" "F.Mask" "F.Paste")
			(net "GPU_3V3IO_RSVD3_FFU")
		)
	)
	(footprint ""
		(layer "F.Cu")
		(at 200.990962 -55.663846 90)
		(property "Reference" "PU61"
			(at -1.597406 2.829052 90)
			(unlocked yes)
			(layer "F.SilkS")
			(effects
				(font
					(size 0.7874 0.5842)
					(thickness 0.1524)
				)
				(justify left)
			)
		)
		(property "Value" ""
			(at 0 0 90)
			(layer "F.Fab")
			(effects
				(font
					(size 1.27 1.27)
				)
			)
		)
		(duplicate_pad_numbers_are_jumpers no)
		(fp_line
			(start 1.943608 -1.549908)
			(end 1.943608 1.549908)
			(stroke
				(width 0.1524)
				(type default)
			)
			(layer "F.SilkS")
		)
		(fp_line
			(start -1.943608 -1.549908)
			(end 1.943608 -1.549908)
			(stroke
				(width 0.1524)
				(type default)
			)
			(layer "F.SilkS")
		)
		(fp_line
			(start 1.943608 1.549908)
			(end -1.943608 1.549908)
			(stroke
				(width 0.1524)
				(type default)
			)
			(layer "F.SilkS")
		)
		(fp_line
			(start -1.943608 1.549908)
			(end -1.943608 -1.549908)
			(stroke
				(width 0.1524)
				(type default)
			)
			(layer "F.SilkS")
		)
		(fp_poly
			(pts
				(xy -2.019808 -1.549908) (xy -1.257808 -1.549908) (xy -1.257808 -1.880108) (xy -2.019808 -1.880108)
			)
			(stroke
				(width 0)
				(type default)
			)
			(fill yes)
			(layer "F.SilkS")
		)
		(fp_line
			(start 1.549908 -1.549908)
			(end 1.549908 1.549908)
			(stroke
				(width 0.1)
				(type default)
			)
			(layer "F.Fab")
		)
		(fp_line
			(start -1.549908 -1.549908)
			(end 1.549908 -1.549908)
			(stroke
				(width 0.1)
				(type default)
			)
			(layer "F.Fab")
		)
		(fp_line
			(start 1.549908 1.549908)
			(end -1.549908 1.549908)
			(stroke
				(width 0.1)
				(type default)
			)
			(layer "F.Fab")
		)
		(fp_line
			(start -1.549908 1.549908)
			(end -1.549908 -1.549908)
			(stroke
				(width 0.1)
				(type default)
			)
			(layer "F.Fab")
		)
		(fp_poly
			(pts
				(xy -2.019808 -1.549908) (xy -1.257808 -1.549908) (xy -1.257808 -1.880108) (xy -2.019808 -1.880108)
			)
			(stroke
				(width 0)
				(type default)
			)
			(fill yes)
			(layer "F.Fab")
		)
		(pad "1" smd rect
			(at -1.500124 -1.249934)
			(size 0.2794 0.6096)
			(layers "F.Cu" "F.Mask" "F.Paste")
			(net "P3V3_SSD7")
		)
		(pad "2" smd rect
			(at -1.500124 -0.750062)
			(size 0.2794 0.6096)
			(layers "F.Cu" "F.Mask" "F.Paste")
			(net "P3V3_SSD7")
		)
		(pad "3" smd rect
			(at -1.500124 -0.249936)
			(size 0.2794 0.6096)
			(layers "F.Cu" "F.Mask" "F.Paste")
			(net "P3V3_SSD7")
		)
		(pad "4" smd rect
			(at -1.500124 0.249936)
			(size 0.2794 0.6096)
			(layers "F.Cu" "F.Mask" "F.Paste")
			(net "P3V3_SSD7")
		)
		(pad "5" smd rect
			(at -1.500124 0.750062)
			(size 0.2794 0.6096)
			(layers "F.Cu" "F.Mask" "F.Paste")
			(net "P3V3_SSD7")
		)
		(pad "6" smd rect
			(at -1.500124 1.249934)
			(size 0.2794 0.6096)
			(layers "F.Cu" "F.Mask" "F.Paste")
			(net "GND")
		)
		(pad "7" smd rect
			(at 1.500124 1.249934)
			(size 0.2794 0.6096)
			(layers "F.Cu" "F.Mask" "F.Paste")
			(net "P3V3_SSD7_SS")
		)
		(pad "8" smd rect
			(at 1.500124 0.750062)
			(size 0.2794 0.6096)
			(layers "F.Cu" "F.Mask" "F.Paste")
			(net "PWRGD_P3V3_SSD7")
		)
		(pad "9" smd rect
			(at 1.500124 0.249936)
			(size 0.2794 0.6096)
			(layers "F.Cu" "F.Mask" "F.Paste")
			(net "P3V3_SSD7_OCP")
		)
		(pad "10" smd rect
			(at 1.500124 -0.249936)
			(size 0.2794 0.6096)
			(layers "F.Cu" "F.Mask" "F.Paste")
			(net "P5V_AUX")
		)
		(pad "11" smd rect
			(at 1.500124 -0.750062)
			(size 0.2794 0.6096)
			(layers "F.Cu" "F.Mask" "F.Paste")
			(net "SSD7_AUX_P3V3_EN_R")
		)
		(pad "12" smd rect
			(at 1.500124 -1.249934)
			(size 0.2794 0.6096)
			(layers "F.Cu" "F.Mask" "F.Paste")
			(net "P3V3_AUX")
		)
		(pad "13" smd rect
			(at 0 0 90)
			(size 1.9812 2.7178)
			(layers "F.Cu" "F.Mask" "F.Paste")
			(net "P3V3_AUX")
		)
		(zone
			(layer "F.Cu")
			(hatch none 0.5)
			(connect_pads
				(clearance 0)
			)
			(min_thickness 0.25)
			(keepout
				(tracks not_allowed)
				(vias allowed)
				(pads allowed)
				(copperpour not_allowed)
				(footprints allowed)
			)
			(placement
				(enabled no)
				(sheetname "")
			)
			(fill
				(thermal_gap 0.5)
				(thermal_bridge_width 0.5)
				(island_removal_mode 0)
			)
			(polygon
				(pts
					(xy 199.441562 -56.806846) (xy 199.568562 -56.806846) (xy 202.540362 -56.806846) (xy 202.54087 -56.806846)
					(xy 202.54087 -54.520846) (xy 202.540362 -54.520846) (xy 202.413362 -54.520846) (xy 200.990962 -54.520846)
					(xy 200.990962 -54.622446) (xy 202.413362 -54.622446) (xy 202.413362 -56.705246) (xy 199.568562 -56.705246)
					(xy 199.568562 -54.622446) (xy 200.965562 -54.622446) (xy 200.965562 -54.520846) (xy 199.568562 -54.520846)
					(xy 199.441562 -54.520846) (xy 199.441054 -54.520846) (xy 199.441054 -56.806846)
				)
			)
		)
	)
	(footprint ""
		(layer "F.Cu")
		(at 36.638484 -105.609898)
		(property "Reference" "C58"
			(at 0 0 0)
			(layer "F.SilkS")
			(hide yes)
			(effects
				(font
					(size 1.27 1.27)
				)
			)
		)
		(property "Value" ""
			(at 0 0 0)
			(layer "F.Fab")
			(effects
				(font
					(size 1.27 1.27)
				)
			)
		)
		(duplicate_pad_numbers_are_jumpers no)
		(fp_line
			(start -0.299974 -0.150114)
			(end 0.299974 -0.150114)
			(stroke
				(width 0.1)
				(type default)
			)
			(layer "F.Fab")
		)
		(fp_line
			(start -0.299974 0.150114)
			(end -0.299974 -0.150114)
			(stroke
				(width 0.1)
				(type default)
			)
			(layer "F.Fab")
		)
		(fp_line
			(start 0.299974 -0.150114)
			(end 0.299974 0.150114)
			(stroke
				(width 0.1)
				(type default)
			)
			(layer "F.Fab")
		)
		(fp_line
			(start 0.299974 0.150114)
			(end -0.299974 0.150114)
			(stroke
				(width 0.1)
				(type default)
			)
			(layer "F.Fab")
		)
		(pad "1" smd rect
			(at -0.2667 0)
			(size 0.3048 0.381)
			(layers "F.Cu" "F.Mask" "F.Paste")
			(net "P5E_PEX0_STN1_TX_DP<19>")
		)
		(pad "2" smd rect
			(at 0.2667 0)
			(size 0.3048 0.381)
			(layers "F.Cu" "F.Mask" "F.Paste")
			(net "P5E_PEX0_STN1_TX_C_DP<19>")
		)
	)
	(footprint ""
		(layer "F.Cu")
		(at 257.171698 -350.722438)
		(property "Reference" "R6653"
			(at 0 0 0)
			(layer "F.SilkS")
			(hide yes)
			(effects
				(font
					(size 1.27 1.27)
				)
			)
		)
		(property "Value" ""
			(at 0 0 0)
			(layer "F.Fab")
			(effects
				(font
					(size 1.27 1.27)
				)
			)
		)
		(duplicate_pad_numbers_are_jumpers no)
		(fp_line
			(start -0.7874 -0.4064)
			(end 0.7874 -0.4064)
			(stroke
				(width 0.1524)
				(type default)
			)
			(layer "F.SilkS")
		)
		(fp_line
			(start -0.7874 0.4064)
			(end -0.7874 -0.4064)
			(stroke
				(width 0.1524)
				(type default)
			)
			(layer "F.SilkS")
		)
		(fp_line
			(start 0.7874 -0.4064)
			(end 0.7874 0.4064)
			(stroke
				(width 0.1524)
				(type default)
			)
			(layer "F.SilkS")
		)
		(fp_line
			(start 0.7874 0.4064)
			(end -0.7874 0.4064)
			(stroke
				(width 0.1524)
				(type default)
			)
			(layer "F.SilkS")
		)
		(fp_line
			(start -0.67945 -0.305054)
			(end -0.12065 -0.305054)
			(stroke
				(width 0.1)
				(type default)
			)
			(layer "F.Fab")
		)
		(fp_line
			(start -0.67945 0.3048)
			(end -0.67945 -0.305054)
			(stroke
				(width 0.1)
				(type default)
			)
			(layer "F.Fab")
		)
		(fp_line
			(start -0.12065 -0.305054)
			(end -0.12065 -0.2794)
			(stroke
				(width 0.1)
				(type default)
			)
			(layer "F.Fab")
		)
		(fp_line
			(start -0.12065 -0.2794)
			(end 0.12065 -0.2794)
			(stroke
				(width 0.1)
				(type default)
			)
			(layer "F.Fab")
		)
		(fp_line
			(start -0.12065 0.2794)
			(end -0.12065 0.3048)
			(stroke
				(width 0.1)
				(type default)
			)
			(layer "F.Fab")
		)
		(fp_line
			(start -0.12065 0.3048)
			(end -0.67945 0.3048)
			(stroke
				(width 0.1)
				(type default)
			)
			(layer "F.Fab")
		)
		(fp_line
			(start 0.120396 0.2794)
			(end -0.12065 0.2794)
			(stroke
				(width 0.1)
				(type default)
			)
			(layer "F.Fab")
		)
		(fp_line
			(start 0.120396 0.3048)
			(end 0.120396 0.2794)
			(stroke
				(width 0.1)
				(type default)
			)
			(layer "F.Fab")
		)
		(fp_line
			(start 0.12065 -0.3048)
			(end 0.67945 -0.3048)
			(stroke
				(width 0.1)
				(type default)
			)
			(layer "F.Fab")
		)
		(fp_line
			(start 0.12065 -0.2794)
			(end 0.12065 -0.3048)
			(stroke
				(width 0.1)
				(type default)
			)
			(layer "F.Fab")
		)
		(fp_line
			(start 0.67945 -0.3048)
			(end 0.67945 0.3048)
			(stroke
				(width 0.1)
				(type default)
			)
			(layer "F.Fab")
		)
		(fp_line
			(start 0.67945 0.3048)
			(end 0.120396 0.3048)
			(stroke
				(width 0.1)
				(type default)
			)
			(layer "F.Fab")
		)
		(pad "1" smd circle
			(at -0.40005 0)
			(size 0 0)
			(layers "F.Cu" "F.Mask" "F.Paste")
			(net "P3V3_AUX")
		)
		(pad "2" smd circle
			(at 0.40005 0)
			(size 0 0)
			(layers "F.Cu" "F.Mask" "F.Paste")
			(net "A_HSC_LOW_GATE")
		)
	)
	(footprint ""
		(layer "F.Cu")
		(at 451.467982 -114.833654 90)
		(property "Reference" "PR7054"
			(at 0 0 90)
			(layer "F.SilkS")
			(hide yes)
			(effects
				(font
					(size 1.27 1.27)
				)
			)
		)
		(property "Value" ""
			(at 0 0 90)
			(layer "F.Fab")
			(effects
				(font
					(size 1.27 1.27)
				)
			)
		)
		(duplicate_pad_numbers_are_jumpers no)
		(fp_line
			(start 1.2954 -0.5842)
			(end 1.2954 0.5842)
			(stroke
				(width 0.1524)
				(type default)
			)
			(layer "F.SilkS")
		)
		(fp_line
			(start -1.2954 -0.5842)
			(end 1.2954 -0.5842)
			(stroke
				(width 0.1524)
				(type default)
			)
			(layer "F.SilkS")
		)
		(fp_line
			(start 1.2954 0.5842)
			(end -1.2954 0.5842)
			(stroke
				(width 0.1524)
				(type default)
			)
			(layer "F.SilkS")
		)
		(fp_line
			(start -1.2954 0.5842)
			(end -1.2954 -0.5842)
			(stroke
				(width 0.1524)
				(type default)
			)
			(layer "F.SilkS")
		)
		(fp_line
			(start 0.8636 -0.4572)
			(end 0.8636 -0.406654)
			(stroke
				(width 0.1)
				(type default)
			)
			(layer "F.Fab")
		)
		(fp_line
			(start -0.8636 -0.4572)
			(end 0.8636 -0.4572)
			(stroke
				(width 0.1)
				(type default)
			)
			(layer "F.Fab")
		)
		(fp_line
			(start 1.1938 -0.406654)
			(end 1.1938 0.4064)
			(stroke
				(width 0.1)
				(type default)
			)
			(layer "F.Fab")
		)
		(fp_line
			(start 0.8636 -0.406654)
			(end 1.1938 -0.406654)
			(stroke
				(width 0.1)
				(type default)
			)
			(layer "F.Fab")
		)
		(fp_line
			(start -0.8636 -0.406654)
			(end -0.8636 -0.4572)
			(stroke
				(width 0.1)
				(type default)
			)
			(layer "F.Fab")
		)
		(fp_line
			(start -1.1938 -0.406654)
			(end -0.8636 -0.406654)
			(stroke
				(width 0.1)
				(type default)
			)
			(layer "F.Fab")
		)
		(fp_line
			(start 1.1938 0.4064)
			(end 0.8636 0.4064)
			(stroke
				(width 0.1)
				(type default)
			)
			(layer "F.Fab")
		)
		(fp_line
			(start 0.8636 0.4064)
			(end 0.8636 0.4572)
			(stroke
				(width 0.1)
				(type default)
			)
			(layer "F.Fab")
		)
		(fp_line
			(start -0.8636 0.4064)
			(end -1.1938 0.4064)
			(stroke
				(width 0.1)
				(type default)
			)
			(layer "F.Fab")
		)
		(fp_line
			(start -1.1938 0.4064)
			(end -1.1938 -0.406654)
			(stroke
				(width 0.1)
				(type default)
			)
			(layer "F.Fab")
		)
		(fp_line
			(start -0.8636 0.4318)
			(end -0.8636 0.4064)
			(stroke
				(width 0.1)
				(type default)
			)
			(layer "F.Fab")
		)
		(fp_line
			(start 0.8636 0.4572)
			(end -0.8636 0.4572)
			(stroke
				(width 0.1)
				(type default)
			)
			(layer "F.Fab")
		)
		(fp_line
			(start -0.8636 0.4572)
			(end -0.8636 0.4318)
			(stroke
				(width 0.1)
				(type default)
			)
			(layer "F.Fab")
		)
		(pad "1" smd rect
			(at -0.7366 0)
			(size 0.7112 0.8128)
			(layers "F.Cu" "F.Mask" "F.Paste")
			(net "P12V_NIC7_CO_AVIN_PD")
		)
		(pad "2" smd rect
			(at 0.7366 0)
			(size 0.7112 0.8128)
			(layers "F.Cu" "F.Mask" "F.Paste")
			(net "P12V_AUX")
		)
	)
	(footprint ""
		(layer "F.Cu")
		(at 336.931 -236.855 90)
		(property "Reference" "R1793"
			(at 0 0 90)
			(layer "F.SilkS")
			(hide yes)
			(effects
				(font
					(size 1.27 1.27)
				)
			)
		)
		(property "Value" ""
			(at 0 0 90)
			(layer "F.Fab")
			(effects
				(font
					(size 1.27 1.27)
				)
			)
		)
		(duplicate_pad_numbers_are_jumpers no)
		(fp_line
			(start 0.7874 -0.4064)
			(end 0.7874 0.4064)
			(stroke
				(width 0.1524)
				(type default)
			)
			(layer "F.SilkS")
		)
		(fp_line
			(start -0.7874 -0.4064)
			(end 0.7874 -0.4064)
			(stroke
				(width 0.1524)
				(type default)
			)
			(layer "F.SilkS")
		)
		(fp_line
			(start 0.7874 0.4064)
			(end -0.7874 0.4064)
			(stroke
				(width 0.1524)
				(type default)
			)
			(layer "F.SilkS")
		)
		(fp_line
			(start -0.7874 0.4064)
			(end -0.7874 -0.4064)
			(stroke
				(width 0.1524)
				(type default)
			)
			(layer "F.SilkS")
		)
		(fp_line
			(start -0.12065 -0.305054)
			(end -0.12065 -0.2794)
			(stroke
				(width 0.1)
				(type default)
			)
			(layer "F.Fab")
		)
		(fp_line
			(start -0.67945 -0.305054)
			(end -0.12065 -0.305054)
			(stroke
				(width 0.1)
				(type default)
			)
			(layer "F.Fab")
		)
		(fp_line
			(start 0.67945 -0.3048)
			(end 0.67945 0.3048)
			(stroke
				(width 0.1)
				(type default)
			)
			(layer "F.Fab")
		)
		(fp_line
			(start 0.12065 -0.3048)
			(end 0.67945 -0.3048)
			(stroke
				(width 0.1)
				(type default)
			)
			(layer "F.Fab")
		)
		(fp_line
			(start 0.12065 -0.2794)
			(end 0.12065 -0.3048)
			(stroke
				(width 0.1)
				(type default)
			)
			(layer "F.Fab")
		)
		(fp_line
			(start -0.12065 -0.2794)
			(end 0.12065 -0.2794)
			(stroke
				(width 0.1)
				(type default)
			)
			(layer "F.Fab")
		)
		(fp_line
			(start 0.120396 0.2794)
			(end -0.12065 0.2794)
			(stroke
				(width 0.1)
				(type default)
			)
			(layer "F.Fab")
		)
		(fp_line
			(start -0.12065 0.2794)
			(end -0.12065 0.3048)
			(stroke
				(width 0.1)
				(type default)
			)
			(layer "F.Fab")
		)
		(fp_line
			(start 0.67945 0.3048)
			(end 0.120396 0.3048)
			(stroke
				(width 0.1)
				(type default)
			)
			(layer "F.Fab")
		)
		(fp_line
			(start 0.120396 0.3048)
			(end 0.120396 0.2794)
			(stroke
				(width 0.1)
				(type default)
			)
			(layer "F.Fab")
		)
		(fp_line
			(start -0.12065 0.3048)
			(end -0.67945 0.3048)
			(stroke
				(width 0.1)
				(type default)
			)
			(layer "F.Fab")
		)
		(fp_line
			(start -0.67945 0.3048)
			(end -0.67945 -0.305054)
			(stroke
				(width 0.1)
				(type default)
			)
			(layer "F.Fab")
		)
		(pad "1" smd circle
			(at -0.40005 0 90)
			(size 0 0)
			(layers "F.Cu" "F.Mask" "F.Paste")
			(net "P3V3_AUX")
		)
		(pad "2" smd circle
			(at 0.40005 0 90)
			(size 0 0)
			(layers "F.Cu" "F.Mask" "F.Paste")
			(net "MB_SWB_PWR_EN_ISO_R")
		)
	)
	(footprint ""
		(layer "F.Cu")
		(at 452.567802 -51.019456)
		(property "Reference" "PC447"
			(at 0 0 0)
			(layer "F.SilkS")
			(hide yes)
			(effects
				(font
					(size 1.27 1.27)
				)
			)
		)
		(property "Value" ""
			(at 0 0 0)
			(layer "F.Fab")
			(effects
				(font
					(size 1.27 1.27)
				)
			)
		)
		(duplicate_pad_numbers_are_jumpers no)
		(fp_line
			(start -0.7874 -0.4064)
			(end 0.7874 -0.4064)
			(stroke
				(width 0.1524)
				(type default)
			)
			(layer "F.SilkS")
		)
		(fp_line
			(start -0.7874 0.4064)
			(end -0.7874 -0.4064)
			(stroke
				(width 0.1524)
				(type default)
			)
			(layer "F.SilkS")
		)
		(fp_line
			(start 0.7874 -0.4064)
			(end 0.7874 0.4064)
			(stroke
				(width 0.1524)
				(type default)
			)
			(layer "F.SilkS")
		)
		(fp_line
			(start 0.7874 0.4064)
			(end -0.7874 0.4064)
			(stroke
				(width 0.1524)
				(type default)
			)
			(layer "F.SilkS")
		)
		(fp_line
			(start -0.67945 -0.305054)
			(end -0.12065 -0.305054)
			(stroke
				(width 0.1)
				(type default)
			)
			(layer "F.Fab")
		)
		(fp_line
			(start -0.67945 0.3048)
			(end -0.67945 -0.305054)
			(stroke
				(width 0.1)
				(type default)
			)
			(layer "F.Fab")
		)
		(fp_line
			(start -0.12065 -0.305054)
			(end -0.12065 -0.2794)
			(stroke
				(width 0.1)
				(type default)
			)
			(layer "F.Fab")
		)
		(fp_line
			(start -0.12065 -0.2794)
			(end 0.12065 -0.2794)
			(stroke
				(width 0.1)
				(type default)
			)
			(layer "F.Fab")
		)
		(fp_line
			(start -0.12065 0.2794)
			(end -0.12065 0.3048)
			(stroke
				(width 0.1)
				(type default)
			)
			(layer "F.Fab")
		)
		(fp_line
			(start -0.12065 0.3048)
			(end -0.67945 0.3048)
			(stroke
				(width 0.1)
				(type default)
			)
			(layer "F.Fab")
		)
		(fp_line
			(start 0.120396 0.2794)
			(end -0.12065 0.2794)
			(stroke
				(width 0.1)
				(type default)
			)
			(layer "F.Fab")
		)
		(fp_line
			(start 0.120396 0.3048)
			(end 0.120396 0.2794)
			(stroke
				(width 0.1)
				(type default)
			)
			(layer "F.Fab")
		)
		(fp_line
			(start 0.12065 -0.3048)
			(end 0.67945 -0.3048)
			(stroke
				(width 0.1)
				(type default)
			)
			(layer "F.Fab")
		)
		(fp_line
			(start 0.12065 -0.2794)
			(end 0.12065 -0.3048)
			(stroke
				(width 0.1)
				(type default)
			)
			(layer "F.Fab")
		)
		(fp_line
			(start 0.67945 -0.3048)
			(end 0.67945 0.3048)
			(stroke
				(width 0.1)
				(type default)
			)
			(layer "F.Fab")
		)
		(fp_line
			(start 0.67945 0.3048)
			(end 0.120396 0.3048)
			(stroke
				(width 0.1)
				(type default)
			)
			(layer "F.Fab")
		)
		(pad "1" smd circle
			(at -0.40005 0)
			(size 0 0)
			(layers "F.Cu" "F.Mask" "F.Paste")
			(net "P12V_SSD15_SS")
		)
		(pad "2" smd circle
			(at 0.40005 0)
			(size 0 0)
			(layers "F.Cu" "F.Mask" "F.Paste")
			(net "GND")
		)
	)
	(footprint ""
		(layer "F.Cu")
		(at 454.125838 -315.944758 180)
		(property "Reference" "PC263"
			(at 0 0 180)
			(layer "F.SilkS")
			(hide yes)
			(effects
				(font
					(size 1.27 1.27)
				)
			)
		)
		(property "Value" ""
			(at 0 0 180)
			(layer "F.Fab")
			(effects
				(font
					(size 1.27 1.27)
				)
			)
		)
		(duplicate_pad_numbers_are_jumpers no)
		(fp_line
			(start 1.524 0.762)
			(end -1.524 0.762)
			(stroke
				(width 0.1524)
				(type default)
			)
			(layer "F.SilkS")
		)
		(fp_line
			(start 1.524 -0.762)
			(end 1.524 0.762)
			(stroke
				(width 0.1524)
				(type default)
			)
			(layer "F.SilkS")
		)
		(fp_line
			(start -1.524 0.762)
			(end -1.524 -0.762)
			(stroke
				(width 0.1524)
				(type default)
			)
			(layer "F.SilkS")
		)
		(fp_line
			(start -1.524 -0.762)
			(end 1.524 -0.762)
			(stroke
				(width 0.1524)
				(type default)
			)
			(layer "F.SilkS")
		)
		(fp_line
			(start 1.1049 0.724916)
			(end 1.1049 -0.724916)
			(stroke
				(width 0.1)
				(type default)
			)
			(layer "F.Fab")
		)
		(fp_line
			(start 1.1049 -0.724916)
			(end -1.1049 -0.724916)
			(stroke
				(width 0.1)
				(type default)
			)
			(layer "F.Fab")
		)
		(fp_line
			(start -1.1049 0.724916)
			(end 1.1049 0.724916)
			(stroke
				(width 0.1)
				(type default)
			)
			(layer "F.Fab")
		)
		(fp_line
			(start -1.1049 -0.724916)
			(end -1.1049 0.724916)
			(stroke
				(width 0.1)
				(type default)
			)
			(layer "F.Fab")
		)
		(pad "1" smd rect
			(at -0.889 0)
			(size 1.016 1.27)
			(layers "F.Cu" "F.Mask" "F.Paste")
			(net "SW_P12V_P1V25_PEX3_FLT")
		)
		(pad "2" smd rect
			(at 0.889 0)
			(size 1.016 1.27)
			(layers "F.Cu" "F.Mask" "F.Paste")
			(net "GND")
		)
	)
	(footprint ""
		(layer "F.Cu")
		(at 220.34373 -44.87291)
		(property "Reference" "R584"
			(at 0 0 0)
			(layer "F.SilkS")
			(hide yes)
			(effects
				(font
					(size 1.27 1.27)
				)
			)
		)
		(property "Value" ""
			(at 0 0 0)
			(layer "F.Fab")
			(effects
				(font
					(size 1.27 1.27)
				)
			)
		)
		(duplicate_pad_numbers_are_jumpers no)
		(fp_line
			(start -0.7874 -0.4064)
			(end 0.7874 -0.4064)
			(stroke
				(width 0.1524)
				(type default)
			)
			(layer "F.SilkS")
		)
		(fp_line
			(start -0.7874 0.4064)
			(end -0.7874 -0.4064)
			(stroke
				(width 0.1524)
				(type default)
			)
			(layer "F.SilkS")
		)
		(fp_line
			(start 0.7874 -0.4064)
			(end 0.7874 0.4064)
			(stroke
				(width 0.1524)
				(type default)
			)
			(layer "F.SilkS")
		)
		(fp_line
			(start 0.7874 0.4064)
			(end -0.7874 0.4064)
			(stroke
				(width 0.1524)
				(type default)
			)
			(layer "F.SilkS")
		)
		(fp_line
			(start -0.67945 -0.305054)
			(end -0.12065 -0.305054)
			(stroke
				(width 0.1)
				(type default)
			)
			(layer "F.Fab")
		)
		(fp_line
			(start -0.67945 0.3048)
			(end -0.67945 -0.305054)
			(stroke
				(width 0.1)
				(type default)
			)
			(layer "F.Fab")
		)
		(fp_line
			(start -0.12065 -0.305054)
			(end -0.12065 -0.2794)
			(stroke
				(width 0.1)
				(type default)
			)
			(layer "F.Fab")
		)
		(fp_line
			(start -0.12065 -0.2794)
			(end 0.12065 -0.2794)
			(stroke
				(width 0.1)
				(type default)
			)
			(layer "F.Fab")
		)
		(fp_line
			(start -0.12065 0.2794)
			(end -0.12065 0.3048)
			(stroke
				(width 0.1)
				(type default)
			)
			(layer "F.Fab")
		)
		(fp_line
			(start -0.12065 0.3048)
			(end -0.67945 0.3048)
			(stroke
				(width 0.1)
				(type default)
			)
			(layer "F.Fab")
		)
		(fp_line
			(start 0.120396 0.2794)
			(end -0.12065 0.2794)
			(stroke
				(width 0.1)
				(type default)
			)
			(layer "F.Fab")
		)
		(fp_line
			(start 0.120396 0.3048)
			(end 0.120396 0.2794)
			(stroke
				(width 0.1)
				(type default)
			)
			(layer "F.Fab")
		)
		(fp_line
			(start 0.12065 -0.3048)
			(end 0.67945 -0.3048)
			(stroke
				(width 0.1)
				(type default)
			)
			(layer "F.Fab")
		)
		(fp_line
			(start 0.12065 -0.2794)
			(end 0.12065 -0.3048)
			(stroke
				(width 0.1)
				(type default)
			)
			(layer "F.Fab")
		)
		(fp_line
			(start 0.67945 -0.3048)
			(end 0.67945 0.3048)
			(stroke
				(width 0.1)
				(type default)
			)
			(layer "F.Fab")
		)
		(fp_line
			(start 0.67945 0.3048)
			(end 0.120396 0.3048)
			(stroke
				(width 0.1)
				(type default)
			)
			(layer "F.Fab")
		)
		(pad "1" smd circle
			(at -0.40005 0)
			(size 0 0)
			(layers "F.Cu" "F.Mask" "F.Paste")
			(net "SSD7_ADC_A0")
		)
		(pad "2" smd circle
			(at 0.40005 0)
			(size 0 0)
			(layers "F.Cu" "F.Mask" "F.Paste")
			(net "P3V3_AUX")
		)
	)
	(footprint ""
		(layer "F.Cu")
		(at 134.513828 -350.098614 90)
		(property "Reference" "C2254"
			(at 0 0 90)
			(layer "F.SilkS")
			(hide yes)
			(effects
				(font
					(size 1.27 1.27)
				)
			)
		)
		(property "Value" ""
			(at 0 0 90)
			(layer "F.Fab")
			(effects
				(font
					(size 1.27 1.27)
				)
			)
		)
		(duplicate_pad_numbers_are_jumpers no)
		(fp_line
			(start 0.299974 -0.150114)
			(end 0.299974 0.150114)
			(stroke
				(width 0.1)
				(type default)
			)
			(layer "F.Fab")
		)
		(fp_line
			(start -0.299974 -0.150114)
			(end 0.299974 -0.150114)
			(stroke
				(width 0.1)
				(type default)
			)
			(layer "F.Fab")
		)
		(fp_line
			(start 0.299974 0.150114)
			(end -0.299974 0.150114)
			(stroke
				(width 0.1)
				(type default)
			)
			(layer "F.Fab")
		)
		(fp_line
			(start -0.299974 0.150114)
			(end -0.299974 -0.150114)
			(stroke
				(width 0.1)
				(type default)
			)
			(layer "F.Fab")
		)
		(pad "1" smd rect
			(at -0.2667 0 90)
			(size 0.3048 0.381)
			(layers "F.Cu" "F.Mask" "F.Paste")
			(net "P5E_PEX1_STN5_TX_DN<90>")
		)
		(pad "2" smd rect
			(at 0.2667 0 90)
			(size 0.3048 0.381)
			(layers "F.Cu" "F.Mask" "F.Paste")
			(net "P5E_PEX1_STN5_TX_C_DN<90>")
		)
	)
	(footprint ""
		(layer "F.Cu")
		(at 96.638618 -22.867366 90)
		(property "Reference" "C3897"
			(at 0 0 90)
			(layer "F.SilkS")
			(hide yes)
			(effects
				(font
					(size 1.27 1.27)
				)
			)
		)
		(property "Value" ""
			(at 0 0 90)
			(layer "F.Fab")
			(effects
				(font
					(size 1.27 1.27)
				)
			)
		)
		(duplicate_pad_numbers_are_jumpers no)
		(fp_line
			(start 0.7874 -0.4064)
			(end 0.7874 0.4064)
			(stroke
				(width 0.1524)
				(type default)
			)
			(layer "F.SilkS")
		)
		(fp_line
			(start -0.7874 -0.4064)
			(end 0.7874 -0.4064)
			(stroke
				(width 0.1524)
				(type default)
			)
			(layer "F.SilkS")
		)
		(fp_line
			(start 0.7874 0.4064)
			(end -0.7874 0.4064)
			(stroke
				(width 0.1524)
				(type default)
			)
			(layer "F.SilkS")
		)
		(fp_line
			(start -0.7874 0.4064)
			(end -0.7874 -0.4064)
			(stroke
				(width 0.1524)
				(type default)
			)
			(layer "F.SilkS")
		)
		(fp_line
			(start -0.12065 -0.305054)
			(end -0.12065 -0.2794)
			(stroke
				(width 0.1)
				(type default)
			)
			(layer "F.Fab")
		)
		(fp_line
			(start -0.67945 -0.305054)
			(end -0.12065 -0.305054)
			(stroke
				(width 0.1)
				(type default)
			)
			(layer "F.Fab")
		)
		(fp_line
			(start 0.67945 -0.3048)
			(end 0.67945 0.3048)
			(stroke
				(width 0.1)
				(type default)
			)
			(layer "F.Fab")
		)
		(fp_line
			(start 0.12065 -0.3048)
			(end 0.67945 -0.3048)
			(stroke
				(width 0.1)
				(type default)
			)
			(layer "F.Fab")
		)
		(fp_line
			(start 0.12065 -0.2794)
			(end 0.12065 -0.3048)
			(stroke
				(width 0.1)
				(type default)
			)
			(layer "F.Fab")
		)
		(fp_line
			(start -0.12065 -0.2794)
			(end 0.12065 -0.2794)
			(stroke
				(width 0.1)
				(type default)
			)
			(layer "F.Fab")
		)
		(fp_line
			(start 0.120396 0.2794)
			(end -0.12065 0.2794)
			(stroke
				(width 0.1)
				(type default)
			)
			(layer "F.Fab")
		)
		(fp_line
			(start -0.12065 0.2794)
			(end -0.12065 0.3048)
			(stroke
				(width 0.1)
				(type default)
			)
			(layer "F.Fab")
		)
		(fp_line
			(start 0.67945 0.3048)
			(end 0.120396 0.3048)
			(stroke
				(width 0.1)
				(type default)
			)
			(layer "F.Fab")
		)
		(fp_line
			(start 0.120396 0.3048)
			(end 0.120396 0.2794)
			(stroke
				(width 0.1)
				(type default)
			)
			(layer "F.Fab")
		)
		(fp_line
			(start -0.12065 0.3048)
			(end -0.67945 0.3048)
			(stroke
				(width 0.1)
				(type default)
			)
			(layer "F.Fab")
		)
		(fp_line
			(start -0.67945 0.3048)
			(end -0.67945 -0.305054)
			(stroke
				(width 0.1)
				(type default)
			)
			(layer "F.Fab")
		)
		(pad "1" smd circle
			(at -0.40005 0 90)
			(size 0 0)
			(layers "F.Cu" "F.Mask" "F.Paste")
			(net "P12V_SSD3")
		)
		(pad "2" smd circle
			(at 0.40005 0 90)
			(size 0 0)
			(layers "F.Cu" "F.Mask" "F.Paste")
			(net "GND")
		)
	)
	(footprint ""
		(layer "F.Cu")
		(at 98.048318 -393.1158 180)
		(property "Reference" "R5457"
			(at 0 0 180)
			(layer "F.SilkS")
			(hide yes)
			(effects
				(font
					(size 1.27 1.27)
				)
			)
		)
		(property "Value" ""
			(at 0 0 180)
			(layer "F.Fab")
			(effects
				(font
					(size 1.27 1.27)
				)
			)
		)
		(duplicate_pad_numbers_are_jumpers no)
		(fp_line
			(start 0.7874 0.4064)
			(end -0.7874 0.4064)
			(stroke
				(width 0.1524)
				(type default)
			)
			(layer "F.SilkS")
		)
		(fp_line
			(start 0.7874 -0.4064)
			(end 0.7874 0.4064)
			(stroke
				(width 0.1524)
				(type default)
			)
			(layer "F.SilkS")
		)
		(fp_line
			(start -0.7874 0.4064)
			(end -0.7874 -0.4064)
			(stroke
				(width 0.1524)
				(type default)
			)
			(layer "F.SilkS")
		)
		(fp_line
			(start -0.7874 -0.4064)
			(end 0.7874 -0.4064)
			(stroke
				(width 0.1524)
				(type default)
			)
			(layer "F.SilkS")
		)
		(fp_line
			(start 0.67945 0.3048)
			(end 0.120396 0.3048)
			(stroke
				(width 0.1)
				(type default)
			)
			(layer "F.Fab")
		)
		(fp_line
			(start 0.67945 -0.3048)
			(end 0.67945 0.3048)
			(stroke
				(width 0.1)
				(type default)
			)
			(layer "F.Fab")
		)
		(fp_line
			(start 0.12065 -0.2794)
			(end 0.12065 -0.3048)
			(stroke
				(width 0.1)
				(type default)
			)
			(layer "F.Fab")
		)
		(fp_line
			(start 0.12065 -0.3048)
			(end 0.67945 -0.3048)
			(stroke
				(width 0.1)
				(type default)
			)
			(layer "F.Fab")
		)
		(fp_line
			(start 0.120396 0.3048)
			(end 0.120396 0.2794)
			(stroke
				(width 0.1)
				(type default)
			)
			(layer "F.Fab")
		)
		(fp_line
			(start 0.120396 0.2794)
			(end -0.12065 0.2794)
			(stroke
				(width 0.1)
				(type default)
			)
			(layer "F.Fab")
		)
		(fp_line
			(start -0.12065 0.3048)
			(end -0.67945 0.3048)
			(stroke
				(width 0.1)
				(type default)
			)
			(layer "F.Fab")
		)
		(fp_line
			(start -0.12065 0.2794)
			(end -0.12065 0.3048)
			(stroke
				(width 0.1)
				(type default)
			)
			(layer "F.Fab")
		)
		(fp_line
			(start -0.12065 -0.2794)
			(end 0.12065 -0.2794)
			(stroke
				(width 0.1)
				(type default)
			)
			(layer "F.Fab")
		)
		(fp_line
			(start -0.12065 -0.305054)
			(end -0.12065 -0.2794)
			(stroke
				(width 0.1)
				(type default)
			)
			(layer "F.Fab")
		)
		(fp_line
			(start -0.67945 0.3048)
			(end -0.67945 -0.305054)
			(stroke
				(width 0.1)
				(type default)
			)
			(layer "F.Fab")
		)
		(fp_line
			(start -0.67945 -0.305054)
			(end -0.12065 -0.305054)
			(stroke
				(width 0.1)
				(type default)
			)
			(layer "F.Fab")
		)
		(pad "1" smd circle
			(at -0.40005 0 180)
			(size 0 0)
			(layers "F.Cu" "F.Mask" "F.Paste")
			(net "BIC_USB_HUB_PGANG")
		)
		(pad "2" smd circle
			(at 0.40005 0 180)
			(size 0 0)
			(layers "F.Cu" "F.Mask" "F.Paste")
			(net "GND")
		)
	)
	(footprint ""
		(layer "F.Cu")
		(at 428.319438 -119.584724 180)
		(property "Reference" "C664"
			(at 0 0 180)
			(layer "F.SilkS")
			(hide yes)
			(effects
				(font
					(size 1.27 1.27)
				)
			)
		)
		(property "Value" ""
			(at 0 0 180)
			(layer "F.Fab")
			(effects
				(font
					(size 1.27 1.27)
				)
			)
		)
		(duplicate_pad_numbers_are_jumpers no)
		(fp_line
			(start 0.299974 0.150114)
			(end -0.299974 0.150114)
			(stroke
				(width 0.1)
				(type default)
			)
			(layer "F.Fab")
		)
		(fp_line
			(start 0.299974 -0.150114)
			(end 0.299974 0.150114)
			(stroke
				(width 0.1)
				(type default)
			)
			(layer "F.Fab")
		)
		(fp_line
			(start -0.299974 0.150114)
			(end -0.299974 -0.150114)
			(stroke
				(width 0.1)
				(type default)
			)
			(layer "F.Fab")
		)
		(fp_line
			(start -0.299974 -0.150114)
			(end 0.299974 -0.150114)
			(stroke
				(width 0.1)
				(type default)
			)
			(layer "F.Fab")
		)
		(pad "1" smd rect
			(at -0.2667 0 180)
			(size 0.3048 0.381)
			(layers "F.Cu" "F.Mask" "F.Paste")
			(net "P5E_PEX3_STN0_TX_DP<0>")
		)
		(pad "2" smd rect
			(at 0.2667 0 180)
			(size 0.3048 0.381)
			(layers "F.Cu" "F.Mask" "F.Paste")
			(net "P5E_PEX3_STN0_TX_C_DP<0>")
		)
	)
	(footprint ""
		(layer "F.Cu")
		(at 160.026604 -25.432004 -90)
		(property "Reference" "C970"
			(at 0 0 270)
			(layer "F.SilkS")
			(hide yes)
			(effects
				(font
					(size 1.27 1.27)
				)
			)
		)
		(property "Value" ""
			(at 0 0 270)
			(layer "F.Fab")
			(effects
				(font
					(size 1.27 1.27)
				)
			)
		)
		(duplicate_pad_numbers_are_jumpers no)
		(fp_line
			(start -0.7874 0.4064)
			(end -0.7874 -0.4064)
			(stroke
				(width 0.1524)
				(type default)
			)
			(layer "F.SilkS")
		)
		(fp_line
			(start 0.7874 0.4064)
			(end -0.7874 0.4064)
			(stroke
				(width 0.1524)
				(type default)
			)
			(layer "F.SilkS")
		)
		(fp_line
			(start -0.7874 -0.4064)
			(end 0.7874 -0.4064)
			(stroke
				(width 0.1524)
				(type default)
			)
			(layer "F.SilkS")
		)
		(fp_line
			(start 0.7874 -0.4064)
			(end 0.7874 0.4064)
			(stroke
				(width 0.1524)
				(type default)
			)
			(layer "F.SilkS")
		)
		(fp_line
			(start -0.67945 0.3048)
			(end -0.67945 -0.305054)
			(stroke
				(width 0.1)
				(type default)
			)
			(layer "F.Fab")
		)
		(fp_line
			(start -0.12065 0.3048)
			(end -0.67945 0.3048)
			(stroke
				(width 0.1)
				(type default)
			)
			(layer "F.Fab")
		)
		(fp_line
			(start 0.120396 0.3048)
			(end 0.120396 0.2794)
			(stroke
				(width 0.1)
				(type default)
			)
			(layer "F.Fab")
		)
		(fp_line
			(start 0.67945 0.3048)
			(end 0.120396 0.3048)
			(stroke
				(width 0.1)
				(type default)
			)
			(layer "F.Fab")
		)
		(fp_line
			(start -0.12065 0.2794)
			(end -0.12065 0.3048)
			(stroke
				(width 0.1)
				(type default)
			)
			(layer "F.Fab")
		)
		(fp_line
			(start 0.120396 0.2794)
			(end -0.12065 0.2794)
			(stroke
				(width 0.1)
				(type default)
			)
			(layer "F.Fab")
		)
		(fp_line
			(start -0.12065 -0.2794)
			(end 0.12065 -0.2794)
			(stroke
				(width 0.1)
				(type default)
			)
			(layer "F.Fab")
		)
		(fp_line
			(start 0.12065 -0.2794)
			(end 0.12065 -0.3048)
			(stroke
				(width 0.1)
				(type default)
			)
			(layer "F.Fab")
		)
		(fp_line
			(start 0.12065 -0.3048)
			(end 0.67945 -0.3048)
			(stroke
				(width 0.1)
				(type default)
			)
			(layer "F.Fab")
		)
		(fp_line
			(start 0.67945 -0.3048)
			(end 0.67945 0.3048)
			(stroke
				(width 0.1)
				(type default)
			)
			(layer "F.Fab")
		)
		(fp_line
			(start -0.67945 -0.305054)
			(end -0.12065 -0.305054)
			(stroke
				(width 0.1)
				(type default)
			)
			(layer "F.Fab")
		)
		(fp_line
			(start -0.12065 -0.305054)
			(end -0.12065 -0.2794)
			(stroke
				(width 0.1)
				(type default)
			)
			(layer "F.Fab")
		)
		(pad "1" smd circle
			(at -0.40005 0 270)
			(size 0 0)
			(layers "F.Cu" "F.Mask" "F.Paste")
			(net "GND")
		)
		(pad "2" smd circle
			(at 0.40005 0 270)
			(size 0 0)
			(layers "F.Cu" "F.Mask" "F.Paste")
			(net "P3V3_SSD5")
		)
	)
	(footprint ""
		(layer "F.Cu")
		(at 332.416404 -100.178108 90)
		(property "Reference" "PC318"
			(at 0 0 90)
			(layer "F.SilkS")
			(hide yes)
			(effects
				(font
					(size 1.27 1.27)
				)
			)
		)
		(property "Value" ""
			(at 0 0 90)
			(layer "F.Fab")
			(effects
				(font
					(size 1.27 1.27)
				)
			)
		)
		(duplicate_pad_numbers_are_jumpers no)
		(fp_line
			(start 0.7874 -0.4064)
			(end 0.7874 0.4064)
			(stroke
				(width 0.1524)
				(type default)
			)
			(layer "F.SilkS")
		)
		(fp_line
			(start -0.7874 -0.4064)
			(end 0.7874 -0.4064)
			(stroke
				(width 0.1524)
				(type default)
			)
			(layer "F.SilkS")
		)
		(fp_line
			(start 0.7874 0.4064)
			(end -0.7874 0.4064)
			(stroke
				(width 0.1524)
				(type default)
			)
			(layer "F.SilkS")
		)
		(fp_line
			(start -0.7874 0.4064)
			(end -0.7874 -0.4064)
			(stroke
				(width 0.1524)
				(type default)
			)
			(layer "F.SilkS")
		)
		(fp_line
			(start -0.12065 -0.305054)
			(end -0.12065 -0.2794)
			(stroke
				(width 0.1)
				(type default)
			)
			(layer "F.Fab")
		)
		(fp_line
			(start -0.67945 -0.305054)
			(end -0.12065 -0.305054)
			(stroke
				(width 0.1)
				(type default)
			)
			(layer "F.Fab")
		)
		(fp_line
			(start 0.67945 -0.3048)
			(end 0.67945 0.3048)
			(stroke
				(width 0.1)
				(type default)
			)
			(layer "F.Fab")
		)
		(fp_line
			(start 0.12065 -0.3048)
			(end 0.67945 -0.3048)
			(stroke
				(width 0.1)
				(type default)
			)
			(layer "F.Fab")
		)
		(fp_line
			(start 0.12065 -0.2794)
			(end 0.12065 -0.3048)
			(stroke
				(width 0.1)
				(type default)
			)
			(layer "F.Fab")
		)
		(fp_line
			(start -0.12065 -0.2794)
			(end 0.12065 -0.2794)
			(stroke
				(width 0.1)
				(type default)
			)
			(layer "F.Fab")
		)
		(fp_line
			(start 0.120396 0.2794)
			(end -0.12065 0.2794)
			(stroke
				(width 0.1)
				(type default)
			)
			(layer "F.Fab")
		)
		(fp_line
			(start -0.12065 0.2794)
			(end -0.12065 0.3048)
			(stroke
				(width 0.1)
				(type default)
			)
			(layer "F.Fab")
		)
		(fp_line
			(start 0.67945 0.3048)
			(end 0.120396 0.3048)
			(stroke
				(width 0.1)
				(type default)
			)
			(layer "F.Fab")
		)
		(fp_line
			(start 0.120396 0.3048)
			(end 0.120396 0.2794)
			(stroke
				(width 0.1)
				(type default)
			)
			(layer "F.Fab")
		)
		(fp_line
			(start -0.12065 0.3048)
			(end -0.67945 0.3048)
			(stroke
				(width 0.1)
				(type default)
			)
			(layer "F.Fab")
		)
		(fp_line
			(start -0.67945 0.3048)
			(end -0.67945 -0.305054)
			(stroke
				(width 0.1)
				(type default)
			)
			(layer "F.Fab")
		)
		(pad "1" smd circle
			(at -0.40005 0 90)
			(size 0 0)
			(layers "F.Cu" "F.Mask" "F.Paste")
			(net "P12V_AUX")
		)
		(pad "2" smd circle
			(at 0.40005 0 90)
			(size 0 0)
			(layers "F.Cu" "F.Mask" "F.Paste")
			(net "GND")
		)
	)
	(footprint ""
		(layer "F.Cu")
		(at 127.185166 -118.343426 -90)
		(property "Reference" "R5956"
			(at 0 0 270)
			(layer "F.SilkS")
			(hide yes)
			(effects
				(font
					(size 1.27 1.27)
				)
			)
		)
		(property "Value" ""
			(at 0 0 270)
			(layer "F.Fab")
			(effects
				(font
					(size 1.27 1.27)
				)
			)
		)
		(duplicate_pad_numbers_are_jumpers no)
		(fp_line
			(start -0.7874 0.4064)
			(end -0.7874 -0.4064)
			(stroke
				(width 0.1524)
				(type default)
			)
			(layer "F.SilkS")
		)
		(fp_line
			(start 0.7874 0.4064)
			(end -0.7874 0.4064)
			(stroke
				(width 0.1524)
				(type default)
			)
			(layer "F.SilkS")
		)
		(fp_line
			(start -0.7874 -0.4064)
			(end 0.7874 -0.4064)
			(stroke
				(width 0.1524)
				(type default)
			)
			(layer "F.SilkS")
		)
		(fp_line
			(start 0.7874 -0.4064)
			(end 0.7874 0.4064)
			(stroke
				(width 0.1524)
				(type default)
			)
			(layer "F.SilkS")
		)
		(fp_line
			(start -0.67945 0.3048)
			(end -0.67945 -0.305054)
			(stroke
				(width 0.1)
				(type default)
			)
			(layer "F.Fab")
		)
		(fp_line
			(start -0.12065 0.3048)
			(end -0.67945 0.3048)
			(stroke
				(width 0.1)
				(type default)
			)
			(layer "F.Fab")
		)
		(fp_line
			(start 0.120396 0.3048)
			(end 0.120396 0.2794)
			(stroke
				(width 0.1)
				(type default)
			)
			(layer "F.Fab")
		)
		(fp_line
			(start 0.67945 0.3048)
			(end 0.120396 0.3048)
			(stroke
				(width 0.1)
				(type default)
			)
			(layer "F.Fab")
		)
		(fp_line
			(start -0.12065 0.2794)
			(end -0.12065 0.3048)
			(stroke
				(width 0.1)
				(type default)
			)
			(layer "F.Fab")
		)
		(fp_line
			(start 0.120396 0.2794)
			(end -0.12065 0.2794)
			(stroke
				(width 0.1)
				(type default)
			)
			(layer "F.Fab")
		)
		(fp_line
			(start -0.12065 -0.2794)
			(end 0.12065 -0.2794)
			(stroke
				(width 0.1)
				(type default)
			)
			(layer "F.Fab")
		)
		(fp_line
			(start 0.12065 -0.2794)
			(end 0.12065 -0.3048)
			(stroke
				(width 0.1)
				(type default)
			)
			(layer "F.Fab")
		)
		(fp_line
			(start 0.12065 -0.3048)
			(end 0.67945 -0.3048)
			(stroke
				(width 0.1)
				(type default)
			)
			(layer "F.Fab")
		)
		(fp_line
			(start 0.67945 -0.3048)
			(end 0.67945 0.3048)
			(stroke
				(width 0.1)
				(type default)
			)
			(layer "F.Fab")
		)
		(fp_line
			(start -0.67945 -0.305054)
			(end -0.12065 -0.305054)
			(stroke
				(width 0.1)
				(type default)
			)
			(layer "F.Fab")
		)
		(fp_line
			(start -0.12065 -0.305054)
			(end -0.12065 -0.2794)
			(stroke
				(width 0.1)
				(type default)
			)
			(layer "F.Fab")
		)
		(pad "1" smd circle
			(at -0.40005 0 270)
			(size 0 0)
			(layers "F.Cu" "F.Mask" "F.Paste")
			(net "P3V3_AUX")
		)
		(pad "2" smd circle
			(at 0.40005 0 270)
			(size 0 0)
			(layers "F.Cu" "F.Mask" "F.Paste")
			(net "PWRGD_P3V3_NIC2_D")
		)
	)
	(footprint ""
		(layer "F.Cu")
		(at 141.71168 -71.458074 -90)
		(property "Reference" "PD105"
			(at 4.249674 -2.76479 90)
			(unlocked yes)
			(layer "F.SilkS")
			(effects
				(font
					(size 0.7874 0.5842)
					(thickness 0.1524)
				)
				(justify left)
			)
		)
		(property "Value" ""
			(at 0 0 270)
			(layer "F.Fab")
			(effects
				(font
					(size 1.27 1.27)
				)
			)
		)
		(duplicate_pad_numbers_are_jumpers no)
		(fp_line
			(start -3.656584 1.970024)
			(end 4.240784 1.970024)
			(stroke
				(width 0.1524)
				(type default)
			)
			(layer "F.SilkS")
		)
		(fp_line
			(start 4.240784 1.970024)
			(end 4.240784 -1.970024)
			(stroke
				(width 0.1524)
				(type default)
			)
			(layer "F.SilkS")
		)
		(fp_line
			(start -3.656584 -1.970024)
			(end -3.656584 1.970024)
			(stroke
				(width 0.1524)
				(type default)
			)
			(layer "F.SilkS")
		)
		(fp_line
			(start 4.240784 -1.970024)
			(end -3.656584 -1.970024)
			(stroke
				(width 0.1524)
				(type default)
			)
			(layer "F.SilkS")
		)
		(fp_poly
			(pts
				(xy 3.580384 1.970024) (xy 3.580384 -1.970024) (xy 4.240784 -1.970024) (xy 4.240784 1.970024)
			)
			(stroke
				(width 0)
				(type default)
			)
			(fill yes)
			(layer "F.SilkS")
		)
		(fp_line
			(start -2.3749 1.970024)
			(end 2.3749 1.970024)
			(stroke
				(width 0.1)
				(type default)
			)
			(layer "F.Fab")
		)
		(fp_line
			(start 2.3749 1.970024)
			(end 2.3749 -1.970024)
			(stroke
				(width 0.1)
				(type default)
			)
			(layer "F.Fab")
		)
		(fp_line
			(start -2.3749 -1.970024)
			(end -2.3749 1.970024)
			(stroke
				(width 0.1)
				(type default)
			)
			(layer "F.Fab")
		)
		(fp_line
			(start 2.3749 -1.970024)
			(end -2.3749 -1.970024)
			(stroke
				(width 0.1)
				(type default)
			)
			(layer "F.Fab")
		)
		(fp_text user "+"
			(at -4.9784 -0.23495 270)
			(unlocked yes)
			(layer "F.Fab")
			(effects
				(font
					(size 1.905 1.4224)
					(thickness 0.1524)
				)
				(justify left)
			)
		)
		(fp_text user "-"
			(at 4.1656 -0.23495 270)
			(unlocked yes)
			(layer "F.Fab")
			(effects
				(font
					(size 1.905 1.4224)
					(thickness 0.1524)
				)
				(justify left)
			)
		)
		(pad "A" smd rect
			(at -2.450084 0 270)
			(size 2.159 2.2606)
			(layers "F.Cu" "F.Mask" "F.Paste")
			(net "GND")
		)
		(pad "C" smd rect
			(at 2.450084 0 270)
			(size 2.159 2.2606)
			(layers "F.Cu" "F.Mask" "F.Paste")
			(net "P12V_AUX")
		)
	)
	(footprint ""
		(layer "F.Cu")
		(at 264.611358 -280.443432 -90)
		(property "Reference" "R4586"
			(at 0 0 270)
			(layer "F.SilkS")
			(hide yes)
			(effects
				(font
					(size 1.27 1.27)
				)
			)
		)
		(property "Value" ""
			(at 0 0 270)
			(layer "F.Fab")
			(effects
				(font
					(size 1.27 1.27)
				)
			)
		)
		(duplicate_pad_numbers_are_jumpers no)
		(fp_line
			(start -0.7874 0.4064)
			(end -0.7874 -0.4064)
			(stroke
				(width 0.1524)
				(type default)
			)
			(layer "F.SilkS")
		)
		(fp_line
			(start 0.7874 0.4064)
			(end -0.7874 0.4064)
			(stroke
				(width 0.1524)
				(type default)
			)
			(layer "F.SilkS")
		)
		(fp_line
			(start -0.7874 -0.4064)
			(end 0.7874 -0.4064)
			(stroke
				(width 0.1524)
				(type default)
			)
			(layer "F.SilkS")
		)
		(fp_line
			(start 0.7874 -0.4064)
			(end 0.7874 0.4064)
			(stroke
				(width 0.1524)
				(type default)
			)
			(layer "F.SilkS")
		)
		(fp_line
			(start -0.67945 0.3048)
			(end -0.67945 -0.305054)
			(stroke
				(width 0.1)
				(type default)
			)
			(layer "F.Fab")
		)
		(fp_line
			(start -0.12065 0.3048)
			(end -0.67945 0.3048)
			(stroke
				(width 0.1)
				(type default)
			)
			(layer "F.Fab")
		)
		(fp_line
			(start 0.120396 0.3048)
			(end 0.120396 0.2794)
			(stroke
				(width 0.1)
				(type default)
			)
			(layer "F.Fab")
		)
		(fp_line
			(start 0.67945 0.3048)
			(end 0.120396 0.3048)
			(stroke
				(width 0.1)
				(type default)
			)
			(layer "F.Fab")
		)
		(fp_line
			(start -0.12065 0.2794)
			(end -0.12065 0.3048)
			(stroke
				(width 0.1)
				(type default)
			)
			(layer "F.Fab")
		)
		(fp_line
			(start 0.120396 0.2794)
			(end -0.12065 0.2794)
			(stroke
				(width 0.1)
				(type default)
			)
			(layer "F.Fab")
		)
		(fp_line
			(start -0.12065 -0.2794)
			(end 0.12065 -0.2794)
			(stroke
				(width 0.1)
				(type default)
			)
			(layer "F.Fab")
		)
		(fp_line
			(start 0.12065 -0.2794)
			(end 0.12065 -0.3048)
			(stroke
				(width 0.1)
				(type default)
			)
			(layer "F.Fab")
		)
		(fp_line
			(start 0.12065 -0.3048)
			(end 0.67945 -0.3048)
			(stroke
				(width 0.1)
				(type default)
			)
			(layer "F.Fab")
		)
		(fp_line
			(start 0.67945 -0.3048)
			(end 0.67945 0.3048)
			(stroke
				(width 0.1)
				(type default)
			)
			(layer "F.Fab")
		)
		(fp_line
			(start -0.67945 -0.305054)
			(end -0.12065 -0.305054)
			(stroke
				(width 0.1)
				(type default)
			)
			(layer "F.Fab")
		)
		(fp_line
			(start -0.12065 -0.305054)
			(end -0.12065 -0.2794)
			(stroke
				(width 0.1)
				(type default)
			)
			(layer "F.Fab")
		)
		(pad "1" smd circle
			(at -0.40005 0 270)
			(size 0 0)
			(layers "F.Cu" "F.Mask" "F.Paste")
			(net "SYSPLL_VDDA18_PEX2")
		)
		(pad "2" smd circle
			(at 0.40005 0 270)
			(size 0 0)
			(layers "F.Cu" "F.Mask" "F.Paste")
			(net "SYSPLL_VDDA18_PEX2_R")
		)
	)
	(footprint ""
		(layer "F.Cu")
		(at 43.792394 -32.739584 180)
		(property "Reference" "C75"
			(at 0 0 180)
			(layer "F.SilkS")
			(hide yes)
			(effects
				(font
					(size 1.27 1.27)
				)
			)
		)
		(property "Value" ""
			(at 0 0 180)
			(layer "F.Fab")
			(effects
				(font
					(size 1.27 1.27)
				)
			)
		)
		(duplicate_pad_numbers_are_jumpers no)
		(fp_line
			(start 0.299974 0.150114)
			(end -0.299974 0.150114)
			(stroke
				(width 0.1)
				(type default)
			)
			(layer "F.Fab")
		)
		(fp_line
			(start 0.299974 -0.150114)
			(end 0.299974 0.150114)
			(stroke
				(width 0.1)
				(type default)
			)
			(layer "F.Fab")
		)
		(fp_line
			(start -0.299974 0.150114)
			(end -0.299974 -0.150114)
			(stroke
				(width 0.1)
				(type default)
			)
			(layer "F.Fab")
		)
		(fp_line
			(start -0.299974 -0.150114)
			(end 0.299974 -0.150114)
			(stroke
				(width 0.1)
				(type default)
			)
			(layer "F.Fab")
		)
		(pad "1" smd rect
			(at -0.2667 0 180)
			(size 0.3048 0.381)
			(layers "F.Cu" "F.Mask" "F.Paste")
			(net "P5E_PEX0_STN2_TX_DP<42>")
		)
		(pad "2" smd rect
			(at 0.2667 0 180)
			(size 0.3048 0.381)
			(layers "F.Cu" "F.Mask" "F.Paste")
			(net "P5E_PEX0_STN2_TX_C_DP<42>")
		)
	)
	(footprint ""
		(layer "F.Cu")
		(at 99.023678 -106.413808 180)
		(property "Reference" "PD79"
			(at 4.230878 2.093722 0)
			(unlocked yes)
			(layer "F.SilkS")
			(effects
				(font
					(size 0.7874 0.5842)
					(thickness 0.1524)
				)
				(justify left)
			)
		)
		(property "Value" ""
			(at 0 0 180)
			(layer "F.Fab")
			(effects
				(font
					(size 1.27 1.27)
				)
			)
		)
		(duplicate_pad_numbers_are_jumpers no)
		(fp_line
			(start 4.107942 1.459992)
			(end -3.400044 1.459992)
			(stroke
				(width 0.1524)
				(type default)
			)
			(layer "F.SilkS")
		)
		(fp_line
			(start 4.107942 -1.459992)
			(end 4.107942 1.459992)
			(stroke
				(width 0.1524)
				(type default)
			)
			(layer "F.SilkS")
		)
		(fp_line
			(start -3.400044 1.459992)
			(end -3.400044 -1.459992)
			(stroke
				(width 0.1524)
				(type default)
			)
			(layer "F.SilkS")
		)
		(fp_line
			(start -3.400044 -1.459992)
			(end 4.107942 -1.459992)
			(stroke
				(width 0.1524)
				(type default)
			)
			(layer "F.SilkS")
		)
		(fp_rect
			(start 4.107942 -1.459992)
			(end 3.308096 1.459992)
			(stroke
				(width 0)
				(type default)
			)
			(fill yes)
			(layer "F.SilkS")
		)
		(fp_line
			(start 2.29997 1.459992)
			(end -2.29997 1.459992)
			(stroke
				(width 0.1)
				(type default)
			)
			(layer "F.Fab")
		)
		(fp_line
			(start 2.29997 -1.459992)
			(end 2.29997 1.459992)
			(stroke
				(width 0.1)
				(type default)
			)
			(layer "F.Fab")
		)
		(fp_line
			(start -2.29997 1.459992)
			(end -2.29997 -1.459992)
			(stroke
				(width 0.1)
				(type default)
			)
			(layer "F.Fab")
		)
		(fp_line
			(start -2.29997 -1.459992)
			(end 2.29997 -1.459992)
			(stroke
				(width 0.1)
				(type default)
			)
			(layer "F.Fab")
		)
		(fp_text user "-"
			(at 4.38531 -1.64592 0)
			(unlocked yes)
			(layer "F.SilkS")
			(effects
				(font
					(size 1.905 1.4224)
					(thickness 0.1524)
				)
				(justify left)
			)
		)
		(fp_text user "+"
			(at -4.586986 0.916432 180)
			(unlocked yes)
			(layer "F.SilkS")
			(effects
				(font
					(size 1.905 1.4224)
					(thickness 0.1524)
				)
				(justify left)
			)
		)
		(fp_text user "-"
			(at 5.4102 0.29845 0)
			(unlocked yes)
			(layer "F.Fab")
			(effects
				(font
					(size 1.905 1.4224)
					(thickness 0.1524)
				)
				(justify left)
			)
		)
		(fp_text user "+"
			(at -4.7752 -0.12065 180)
			(unlocked yes)
			(layer "F.Fab")
			(effects
				(font
					(size 1.905 1.4224)
					(thickness 0.1524)
				)
				(justify left)
			)
		)
		(pad "A" smd rect
			(at -1.999996 0 270)
			(size 1.7018 2.5146)
			(layers "F.Cu" "F.Mask" "F.Paste")
			(net "GND")
		)
		(pad "C" smd rect
			(at 1.999996 0 270)
			(size 1.7018 2.5146)
			(layers "F.Cu" "F.Mask" "F.Paste")
			(net "P12V_NIC1_R")
		)
	)
	(footprint ""
		(layer "F.Cu")
		(at 204.849476 -377.025916)
		(property "Reference" "R6252"
			(at 0 0 0)
			(layer "F.SilkS")
			(hide yes)
			(effects
				(font
					(size 1.27 1.27)
				)
			)
		)
		(property "Value" ""
			(at 0 0 0)
			(layer "F.Fab")
			(effects
				(font
					(size 1.27 1.27)
				)
			)
		)
		(duplicate_pad_numbers_are_jumpers no)
		(fp_line
			(start -0.7874 -0.4064)
			(end 0.7874 -0.4064)
			(stroke
				(width 0.1524)
				(type default)
			)
			(layer "F.SilkS")
		)
		(fp_line
			(start -0.7874 0.4064)
			(end -0.7874 -0.4064)
			(stroke
				(width 0.1524)
				(type default)
			)
			(layer "F.SilkS")
		)
		(fp_line
			(start 0.7874 -0.4064)
			(end 0.7874 0.4064)
			(stroke
				(width 0.1524)
				(type default)
			)
			(layer "F.SilkS")
		)
		(fp_line
			(start 0.7874 0.4064)
			(end -0.7874 0.4064)
			(stroke
				(width 0.1524)
				(type default)
			)
			(layer "F.SilkS")
		)
		(fp_line
			(start -0.67945 -0.305054)
			(end -0.12065 -0.305054)
			(stroke
				(width 0.1)
				(type default)
			)
			(layer "F.Fab")
		)
		(fp_line
			(start -0.67945 0.3048)
			(end -0.67945 -0.305054)
			(stroke
				(width 0.1)
				(type default)
			)
			(layer "F.Fab")
		)
		(fp_line
			(start -0.12065 -0.305054)
			(end -0.12065 -0.2794)
			(stroke
				(width 0.1)
				(type default)
			)
			(layer "F.Fab")
		)
		(fp_line
			(start -0.12065 -0.2794)
			(end 0.12065 -0.2794)
			(stroke
				(width 0.1)
				(type default)
			)
			(layer "F.Fab")
		)
		(fp_line
			(start -0.12065 0.2794)
			(end -0.12065 0.3048)
			(stroke
				(width 0.1)
				(type default)
			)
			(layer "F.Fab")
		)
		(fp_line
			(start -0.12065 0.3048)
			(end -0.67945 0.3048)
			(stroke
				(width 0.1)
				(type default)
			)
			(layer "F.Fab")
		)
		(fp_line
			(start 0.120396 0.2794)
			(end -0.12065 0.2794)
			(stroke
				(width 0.1)
				(type default)
			)
			(layer "F.Fab")
		)
		(fp_line
			(start 0.120396 0.3048)
			(end 0.120396 0.2794)
			(stroke
				(width 0.1)
				(type default)
			)
			(layer "F.Fab")
		)
		(fp_line
			(start 0.12065 -0.3048)
			(end 0.67945 -0.3048)
			(stroke
				(width 0.1)
				(type default)
			)
			(layer "F.Fab")
		)
		(fp_line
			(start 0.12065 -0.2794)
			(end 0.12065 -0.3048)
			(stroke
				(width 0.1)
				(type default)
			)
			(layer "F.Fab")
		)
		(fp_line
			(start 0.67945 -0.3048)
			(end 0.67945 0.3048)
			(stroke
				(width 0.1)
				(type default)
			)
			(layer "F.Fab")
		)
		(fp_line
			(start 0.67945 0.3048)
			(end 0.120396 0.3048)
			(stroke
				(width 0.1)
				(type default)
			)
			(layer "F.Fab")
		)
		(pad "1" smd circle
			(at -0.40005 0)
			(size 0 0)
			(layers "F.Cu" "F.Mask" "F.Paste")
			(net "MB_HSC_ISO_D1_EN")
		)
		(pad "2" smd circle
			(at 0.40005 0)
			(size 0 0)
			(layers "F.Cu" "F.Mask" "F.Paste")
			(net "P12V_STBY")
		)
	)
	(footprint ""
		(layer "F.Cu")
		(at 358.013 -225.552)
		(property "Reference" "R3631"
			(at 0 0 0)
			(layer "F.SilkS")
			(hide yes)
			(effects
				(font
					(size 1.27 1.27)
				)
			)
		)
		(property "Value" ""
			(at 0 0 0)
			(layer "F.Fab")
			(effects
				(font
					(size 1.27 1.27)
				)
			)
		)
		(duplicate_pad_numbers_are_jumpers no)
		(fp_line
			(start -0.7874 -0.4064)
			(end 0.7874 -0.4064)
			(stroke
				(width 0.1524)
				(type default)
			)
			(layer "F.SilkS")
		)
		(fp_line
			(start -0.7874 0.4064)
			(end -0.7874 -0.4064)
			(stroke
				(width 0.1524)
				(type default)
			)
			(layer "F.SilkS")
		)
		(fp_line
			(start 0.7874 -0.4064)
			(end 0.7874 0.4064)
			(stroke
				(width 0.1524)
				(type default)
			)
			(layer "F.SilkS")
		)
		(fp_line
			(start 0.7874 0.4064)
			(end -0.7874 0.4064)
			(stroke
				(width 0.1524)
				(type default)
			)
			(layer "F.SilkS")
		)
		(fp_line
			(start -0.67945 -0.305054)
			(end -0.12065 -0.305054)
			(stroke
				(width 0.1)
				(type default)
			)
			(layer "F.Fab")
		)
		(fp_line
			(start -0.67945 0.3048)
			(end -0.67945 -0.305054)
			(stroke
				(width 0.1)
				(type default)
			)
			(layer "F.Fab")
		)
		(fp_line
			(start -0.12065 -0.305054)
			(end -0.12065 -0.2794)
			(stroke
				(width 0.1)
				(type default)
			)
			(layer "F.Fab")
		)
		(fp_line
			(start -0.12065 -0.2794)
			(end 0.12065 -0.2794)
			(stroke
				(width 0.1)
				(type default)
			)
			(layer "F.Fab")
		)
		(fp_line
			(start -0.12065 0.2794)
			(end -0.12065 0.3048)
			(stroke
				(width 0.1)
				(type default)
			)
			(layer "F.Fab")
		)
		(fp_line
			(start -0.12065 0.3048)
			(end -0.67945 0.3048)
			(stroke
				(width 0.1)
				(type default)
			)
			(layer "F.Fab")
		)
		(fp_line
			(start 0.120396 0.2794)
			(end -0.12065 0.2794)
			(stroke
				(width 0.1)
				(type default)
			)
			(layer "F.Fab")
		)
		(fp_line
			(start 0.120396 0.3048)
			(end 0.120396 0.2794)
			(stroke
				(width 0.1)
				(type default)
			)
			(layer "F.Fab")
		)
		(fp_line
			(start 0.12065 -0.3048)
			(end 0.67945 -0.3048)
			(stroke
				(width 0.1)
				(type default)
			)
			(layer "F.Fab")
		)
		(fp_line
			(start 0.12065 -0.2794)
			(end 0.12065 -0.3048)
			(stroke
				(width 0.1)
				(type default)
			)
			(layer "F.Fab")
		)
		(fp_line
			(start 0.67945 -0.3048)
			(end 0.67945 0.3048)
			(stroke
				(width 0.1)
				(type default)
			)
			(layer "F.Fab")
		)
		(fp_line
			(start 0.67945 0.3048)
			(end 0.120396 0.3048)
			(stroke
				(width 0.1)
				(type default)
			)
			(layer "F.Fab")
		)
		(pad "1" smd circle
			(at -0.40005 0)
			(size 0 0)
			(layers "F.Cu" "F.Mask" "F.Paste")
			(net "RST_NIC3_PERST_N")
		)
		(pad "2" smd circle
			(at 0.40005 0)
			(size 0 0)
			(layers "F.Cu" "F.Mask" "F.Paste")
			(net "RST_NIC3_PERST_R_N")
		)
	)
	(footprint ""
		(layer "F.Cu")
		(at 334.493362 -93.152214 -90)
		(property "Reference" "R3508"
			(at 0 0 270)
			(layer "F.SilkS")
			(hide yes)
			(effects
				(font
					(size 1.27 1.27)
				)
			)
		)
		(property "Value" ""
			(at 0 0 270)
			(layer "F.Fab")
			(effects
				(font
					(size 1.27 1.27)
				)
			)
		)
		(duplicate_pad_numbers_are_jumpers no)
		(fp_line
			(start -0.7874 0.4064)
			(end -0.7874 -0.4064)
			(stroke
				(width 0.1524)
				(type default)
			)
			(layer "F.SilkS")
		)
		(fp_line
			(start 0.7874 0.4064)
			(end -0.7874 0.4064)
			(stroke
				(width 0.1524)
				(type default)
			)
			(layer "F.SilkS")
		)
		(fp_line
			(start -0.7874 -0.4064)
			(end 0.7874 -0.4064)
			(stroke
				(width 0.1524)
				(type default)
			)
			(layer "F.SilkS")
		)
		(fp_line
			(start 0.7874 -0.4064)
			(end 0.7874 0.4064)
			(stroke
				(width 0.1524)
				(type default)
			)
			(layer "F.SilkS")
		)
		(fp_line
			(start -0.67945 0.3048)
			(end -0.67945 -0.305054)
			(stroke
				(width 0.1)
				(type default)
			)
			(layer "F.Fab")
		)
		(fp_line
			(start -0.12065 0.3048)
			(end -0.67945 0.3048)
			(stroke
				(width 0.1)
				(type default)
			)
			(layer "F.Fab")
		)
		(fp_line
			(start 0.120396 0.3048)
			(end 0.120396 0.2794)
			(stroke
				(width 0.1)
				(type default)
			)
			(layer "F.Fab")
		)
		(fp_line
			(start 0.67945 0.3048)
			(end 0.120396 0.3048)
			(stroke
				(width 0.1)
				(type default)
			)
			(layer "F.Fab")
		)
		(fp_line
			(start -0.12065 0.2794)
			(end -0.12065 0.3048)
			(stroke
				(width 0.1)
				(type default)
			)
			(layer "F.Fab")
		)
		(fp_line
			(start 0.120396 0.2794)
			(end -0.12065 0.2794)
			(stroke
				(width 0.1)
				(type default)
			)
			(layer "F.Fab")
		)
		(fp_line
			(start -0.12065 -0.2794)
			(end 0.12065 -0.2794)
			(stroke
				(width 0.1)
				(type default)
			)
			(layer "F.Fab")
		)
		(fp_line
			(start 0.12065 -0.2794)
			(end 0.12065 -0.3048)
			(stroke
				(width 0.1)
				(type default)
			)
			(layer "F.Fab")
		)
		(fp_line
			(start 0.12065 -0.3048)
			(end 0.67945 -0.3048)
			(stroke
				(width 0.1)
				(type default)
			)
			(layer "F.Fab")
		)
		(fp_line
			(start 0.67945 -0.3048)
			(end 0.67945 0.3048)
			(stroke
				(width 0.1)
				(type default)
			)
			(layer "F.Fab")
		)
		(fp_line
			(start -0.67945 -0.305054)
			(end -0.12065 -0.305054)
			(stroke
				(width 0.1)
				(type default)
			)
			(layer "F.Fab")
		)
		(fp_line
			(start -0.12065 -0.305054)
			(end -0.12065 -0.2794)
			(stroke
				(width 0.1)
				(type default)
			)
			(layer "F.Fab")
		)
		(pad "1" smd circle
			(at -0.40005 0 270)
			(size 0 0)
			(layers "F.Cu" "F.Mask" "F.Paste")
			(net "P3V3")
		)
		(pad "2" smd circle
			(at 0.40005 0 270)
			(size 0 0)
			(layers "F.Cu" "F.Mask" "F.Paste")
			(net "PU_9ZXL0851_8_15_HBW")
		)
	)
	(footprint ""
		(layer "F.Cu")
		(at 263.789414 -63.56223)
		(property "Reference" "Q205"
			(at 0.150368 -2.585212 0)
			(unlocked yes)
			(layer "F.SilkS")
			(effects
				(font
					(size 0.7874 0.5842)
					(thickness 0.1524)
				)
			)
		)
		(property "Value" ""
			(at 0 0 0)
			(layer "F.Fab")
			(effects
				(font
					(size 1.27 1.27)
				)
			)
		)
		(duplicate_pad_numbers_are_jumpers no)
		(fp_line
			(start -1.376172 -1.199896)
			(end -0.508 -1.199896)
			(stroke
				(width 0.1524)
				(type default)
			)
			(layer "F.SilkS")
		)
		(fp_line
			(start -1.376172 1.199896)
			(end -1.376172 -1.199896)
			(stroke
				(width 0.1524)
				(type default)
			)
			(layer "F.SilkS")
		)
		(fp_line
			(start -0.508 -1.199896)
			(end 0 -0.762)
			(stroke
				(width 0.1524)
				(type default)
			)
			(layer "F.SilkS")
		)
		(fp_line
			(start 0 -0.762)
			(end 0.508 -1.199896)
			(stroke
				(width 0.1524)
				(type default)
			)
			(layer "F.SilkS")
		)
		(fp_line
			(start 0.508 -1.199896)
			(end 1.376172 -1.199896)
			(stroke
				(width 0.1524)
				(type default)
			)
			(layer "F.SilkS")
		)
		(fp_line
			(start 1.376172 -1.199896)
			(end 1.376172 1.199896)
			(stroke
				(width 0.1524)
				(type default)
			)
			(layer "F.SilkS")
		)
		(fp_line
			(start 1.376172 1.199896)
			(end -1.376172 1.199896)
			(stroke
				(width 0.1524)
				(type default)
			)
			(layer "F.SilkS")
		)
		(fp_poly
			(pts
				(xy -1.606042 -1.021334) (xy -1.875536 -1.829562) (xy -2.41427 -1.290574)
			)
			(stroke
				(width 0)
				(type default)
			)
			(fill yes)
			(layer "F.SilkS")
		)
		(fp_line
			(start -0.674878 -1.100074)
			(end 0.674878 -1.100074)
			(stroke
				(width 0.1)
				(type default)
			)
			(layer "F.Fab")
		)
		(fp_line
			(start -0.674878 1.100074)
			(end -0.674878 -1.100074)
			(stroke
				(width 0.1)
				(type default)
			)
			(layer "F.Fab")
		)
		(fp_line
			(start 0.674878 -1.100074)
			(end 0.674878 1.100074)
			(stroke
				(width 0.1)
				(type default)
			)
			(layer "F.Fab")
		)
		(fp_line
			(start 0.674878 1.100074)
			(end -0.674878 1.100074)
			(stroke
				(width 0.1)
				(type default)
			)
			(layer "F.Fab")
		)
		(fp_poly
			(pts
				(xy -1.4605 -0.7493) (xy -2.2225 -1.1303) (xy -2.2225 -0.3683)
			)
			(stroke
				(width 0)
				(type default)
			)
			(fill yes)
			(layer "F.Fab")
		)
		(pad "1" smd rect
			(at -0.899922 -0.750062 270)
			(size 0.6096 0.6096)
			(layers "F.Cu" "F.Mask" "F.Paste")
			(net "GND")
		)
		(pad "2" smd rect
			(at -0.899922 0 270)
			(size 0.4064 0.6096)
			(layers "F.Cu" "F.Mask" "F.Paste")
			(net "P12V_SSD9_PG_G1")
		)
		(pad "3" smd rect
			(at -0.899922 0.750062 270)
			(size 0.6096 0.6096)
			(layers "F.Cu" "F.Mask" "F.Paste")
			(net "PWRGD_P12V_SSD9_D")
		)
		(pad "4" smd rect
			(at 0.899922 0.750062 270)
			(size 0.6096 0.6096)
			(layers "F.Cu" "F.Mask" "F.Paste")
			(net "GND")
		)
		(pad "5" smd rect
			(at 0.899922 0 270)
			(size 0.4064 0.6096)
			(layers "F.Cu" "F.Mask" "F.Paste")
			(net "P12V_SSD9_PG_G2")
		)
		(pad "6" smd rect
			(at 0.899922 -0.750062 270)
			(size 0.6096 0.6096)
			(layers "F.Cu" "F.Mask" "F.Paste")
			(net "P12V_SSD9_PG_G2")
		)
	)
	(footprint ""
		(layer "F.Cu")
		(at 231.3686 -231.394 90)
		(property "Reference" "R4525"
			(at 0 0 90)
			(layer "F.SilkS")
			(hide yes)
			(effects
				(font
					(size 1.27 1.27)
				)
			)
		)
		(property "Value" ""
			(at 0 0 90)
			(layer "F.Fab")
			(effects
				(font
					(size 1.27 1.27)
				)
			)
		)
		(duplicate_pad_numbers_are_jumpers no)
		(fp_line
			(start 0.7874 -0.4064)
			(end 0.7874 0.4064)
			(stroke
				(width 0.1524)
				(type default)
			)
			(layer "F.SilkS")
		)
		(fp_line
			(start -0.7874 -0.4064)
			(end 0.7874 -0.4064)
			(stroke
				(width 0.1524)
				(type default)
			)
			(layer "F.SilkS")
		)
		(fp_line
			(start 0.7874 0.4064)
			(end -0.7874 0.4064)
			(stroke
				(width 0.1524)
				(type default)
			)
			(layer "F.SilkS")
		)
		(fp_line
			(start -0.7874 0.4064)
			(end -0.7874 -0.4064)
			(stroke
				(width 0.1524)
				(type default)
			)
			(layer "F.SilkS")
		)
		(fp_line
			(start -0.12065 -0.305054)
			(end -0.12065 -0.2794)
			(stroke
				(width 0.1)
				(type default)
			)
			(layer "F.Fab")
		)
		(fp_line
			(start -0.67945 -0.305054)
			(end -0.12065 -0.305054)
			(stroke
				(width 0.1)
				(type default)
			)
			(layer "F.Fab")
		)
		(fp_line
			(start 0.67945 -0.3048)
			(end 0.67945 0.3048)
			(stroke
				(width 0.1)
				(type default)
			)
			(layer "F.Fab")
		)
		(fp_line
			(start 0.12065 -0.3048)
			(end 0.67945 -0.3048)
			(stroke
				(width 0.1)
				(type default)
			)
			(layer "F.Fab")
		)
		(fp_line
			(start 0.12065 -0.2794)
			(end 0.12065 -0.3048)
			(stroke
				(width 0.1)
				(type default)
			)
			(layer "F.Fab")
		)
		(fp_line
			(start -0.12065 -0.2794)
			(end 0.12065 -0.2794)
			(stroke
				(width 0.1)
				(type default)
			)
			(layer "F.Fab")
		)
		(fp_line
			(start 0.120396 0.2794)
			(end -0.12065 0.2794)
			(stroke
				(width 0.1)
				(type default)
			)
			(layer "F.Fab")
		)
		(fp_line
			(start -0.12065 0.2794)
			(end -0.12065 0.3048)
			(stroke
				(width 0.1)
				(type default)
			)
			(layer "F.Fab")
		)
		(fp_line
			(start 0.67945 0.3048)
			(end 0.120396 0.3048)
			(stroke
				(width 0.1)
				(type default)
			)
			(layer "F.Fab")
		)
		(fp_line
			(start 0.120396 0.3048)
			(end 0.120396 0.2794)
			(stroke
				(width 0.1)
				(type default)
			)
			(layer "F.Fab")
		)
		(fp_line
			(start -0.12065 0.3048)
			(end -0.67945 0.3048)
			(stroke
				(width 0.1)
				(type default)
			)
			(layer "F.Fab")
		)
		(fp_line
			(start -0.67945 0.3048)
			(end -0.67945 -0.305054)
			(stroke
				(width 0.1)
				(type default)
			)
			(layer "F.Fab")
		)
		(pad "1" smd circle
			(at -0.40005 0 90)
			(size 0 0)
			(layers "F.Cu" "F.Mask" "F.Paste")
			(net "SSD11_PWRDIS_BIC")
		)
		(pad "2" smd circle
			(at 0.40005 0 90)
			(size 0 0)
			(layers "F.Cu" "F.Mask" "F.Paste")
			(net "SSD11_PWRDIS_BIC_R")
		)
	)
	(footprint ""
		(layer "F.Cu")
		(at 262.726678 -53.697124 -90)
		(property "Reference" "PC580"
			(at 0 0 270)
			(layer "F.SilkS")
			(hide yes)
			(effects
				(font
					(size 1.27 1.27)
				)
			)
		)
		(property "Value" ""
			(at 0 0 270)
			(layer "F.Fab")
			(effects
				(font
					(size 1.27 1.27)
				)
			)
		)
		(duplicate_pad_numbers_are_jumpers no)
		(fp_line
			(start -0.7874 0.4064)
			(end -0.7874 -0.4064)
			(stroke
				(width 0.1524)
				(type default)
			)
			(layer "F.SilkS")
		)
		(fp_line
			(start 0.7874 0.4064)
			(end -0.7874 0.4064)
			(stroke
				(width 0.1524)
				(type default)
			)
			(layer "F.SilkS")
		)
		(fp_line
			(start -0.7874 -0.4064)
			(end 0.7874 -0.4064)
			(stroke
				(width 0.1524)
				(type default)
			)
			(layer "F.SilkS")
		)
		(fp_line
			(start 0.7874 -0.4064)
			(end 0.7874 0.4064)
			(stroke
				(width 0.1524)
				(type default)
			)
			(layer "F.SilkS")
		)
		(fp_line
			(start -0.67945 0.3048)
			(end -0.67945 -0.305054)
			(stroke
				(width 0.1)
				(type default)
			)
			(layer "F.Fab")
		)
		(fp_line
			(start -0.12065 0.3048)
			(end -0.67945 0.3048)
			(stroke
				(width 0.1)
				(type default)
			)
			(layer "F.Fab")
		)
		(fp_line
			(start 0.120396 0.3048)
			(end 0.120396 0.2794)
			(stroke
				(width 0.1)
				(type default)
			)
			(layer "F.Fab")
		)
		(fp_line
			(start 0.67945 0.3048)
			(end 0.120396 0.3048)
			(stroke
				(width 0.1)
				(type default)
			)
			(layer "F.Fab")
		)
		(fp_line
			(start -0.12065 0.2794)
			(end -0.12065 0.3048)
			(stroke
				(width 0.1)
				(type default)
			)
			(layer "F.Fab")
		)
		(fp_line
			(start 0.120396 0.2794)
			(end -0.12065 0.2794)
			(stroke
				(width 0.1)
				(type default)
			)
			(layer "F.Fab")
		)
		(fp_line
			(start -0.12065 -0.2794)
			(end 0.12065 -0.2794)
			(stroke
				(width 0.1)
				(type default)
			)
			(layer "F.Fab")
		)
		(fp_line
			(start 0.12065 -0.2794)
			(end 0.12065 -0.3048)
			(stroke
				(width 0.1)
				(type default)
			)
			(layer "F.Fab")
		)
		(fp_line
			(start 0.12065 -0.3048)
			(end 0.67945 -0.3048)
			(stroke
				(width 0.1)
				(type default)
			)
			(layer "F.Fab")
		)
		(fp_line
			(start 0.67945 -0.3048)
			(end 0.67945 0.3048)
			(stroke
				(width 0.1)
				(type default)
			)
			(layer "F.Fab")
		)
		(fp_line
			(start -0.67945 -0.305054)
			(end -0.12065 -0.305054)
			(stroke
				(width 0.1)
				(type default)
			)
			(layer "F.Fab")
		)
		(fp_line
			(start -0.12065 -0.305054)
			(end -0.12065 -0.2794)
			(stroke
				(width 0.1)
				(type default)
			)
			(layer "F.Fab")
		)
		(pad "1" smd circle
			(at -0.40005 0 270)
			(size 0 0)
			(layers "F.Cu" "F.Mask" "F.Paste")
			(net "P3V3_AUX")
		)
		(pad "2" smd circle
			(at 0.40005 0 270)
			(size 0 0)
			(layers "F.Cu" "F.Mask" "F.Paste")
			(net "GND")
		)
	)
	(footprint ""
		(layer "F.Cu")
		(at 193.453766 -83.932268 90)
		(property "Reference" "C412"
			(at 0 0 90)
			(layer "F.SilkS")
			(hide yes)
			(effects
				(font
					(size 1.27 1.27)
				)
			)
		)
		(property "Value" ""
			(at 0 0 90)
			(layer "F.Fab")
			(effects
				(font
					(size 1.27 1.27)
				)
			)
		)
		(duplicate_pad_numbers_are_jumpers no)
		(fp_line
			(start 0.7874 -0.4064)
			(end 0.7874 0.4064)
			(stroke
				(width 0.1524)
				(type default)
			)
			(layer "F.SilkS")
		)
		(fp_line
			(start -0.7874 -0.4064)
			(end 0.7874 -0.4064)
			(stroke
				(width 0.1524)
				(type default)
			)
			(layer "F.SilkS")
		)
		(fp_line
			(start 0.7874 0.4064)
			(end -0.7874 0.4064)
			(stroke
				(width 0.1524)
				(type default)
			)
			(layer "F.SilkS")
		)
		(fp_line
			(start -0.7874 0.4064)
			(end -0.7874 -0.4064)
			(stroke
				(width 0.1524)
				(type default)
			)
			(layer "F.SilkS")
		)
		(fp_line
			(start -0.12065 -0.305054)
			(end -0.12065 -0.2794)
			(stroke
				(width 0.1)
				(type default)
			)
			(layer "F.Fab")
		)
		(fp_line
			(start -0.67945 -0.305054)
			(end -0.12065 -0.305054)
			(stroke
				(width 0.1)
				(type default)
			)
			(layer "F.Fab")
		)
		(fp_line
			(start 0.67945 -0.3048)
			(end 0.67945 0.3048)
			(stroke
				(width 0.1)
				(type default)
			)
			(layer "F.Fab")
		)
		(fp_line
			(start 0.12065 -0.3048)
			(end 0.67945 -0.3048)
			(stroke
				(width 0.1)
				(type default)
			)
			(layer "F.Fab")
		)
		(fp_line
			(start 0.12065 -0.2794)
			(end 0.12065 -0.3048)
			(stroke
				(width 0.1)
				(type default)
			)
			(layer "F.Fab")
		)
		(fp_line
			(start -0.12065 -0.2794)
			(end 0.12065 -0.2794)
			(stroke
				(width 0.1)
				(type default)
			)
			(layer "F.Fab")
		)
		(fp_line
			(start 0.120396 0.2794)
			(end -0.12065 0.2794)
			(stroke
				(width 0.1)
				(type default)
			)
			(layer "F.Fab")
		)
		(fp_line
			(start -0.12065 0.2794)
			(end -0.12065 0.3048)
			(stroke
				(width 0.1)
				(type default)
			)
			(layer "F.Fab")
		)
		(fp_line
			(start 0.67945 0.3048)
			(end 0.120396 0.3048)
			(stroke
				(width 0.1)
				(type default)
			)
			(layer "F.Fab")
		)
		(fp_line
			(start 0.120396 0.3048)
			(end 0.120396 0.2794)
			(stroke
				(width 0.1)
				(type default)
			)
			(layer "F.Fab")
		)
		(fp_line
			(start -0.12065 0.3048)
			(end -0.67945 0.3048)
			(stroke
				(width 0.1)
				(type default)
			)
			(layer "F.Fab")
		)
		(fp_line
			(start -0.67945 0.3048)
			(end -0.67945 -0.305054)
			(stroke
				(width 0.1)
				(type default)
			)
			(layer "F.Fab")
		)
		(pad "1" smd circle
			(at -0.40005 0 90)
			(size 0 0)
			(layers "F.Cu" "F.Mask" "F.Paste")
			(net "P3V3_AUX")
		)
		(pad "2" smd circle
			(at 0.40005 0 90)
			(size 0 0)
			(layers "F.Cu" "F.Mask" "F.Paste")
			(net "GND")
		)
	)
	(footprint ""
		(layer "F.Cu")
		(at 140.761974 -187.593732)
		(property "Reference" "C4496"
			(at 0 0 0)
			(layer "F.SilkS")
			(hide yes)
			(effects
				(font
					(size 1.27 1.27)
				)
			)
		)
		(property "Value" ""
			(at 0 0 0)
			(layer "F.Fab")
			(effects
				(font
					(size 1.27 1.27)
				)
			)
		)
		(duplicate_pad_numbers_are_jumpers no)
		(fp_line
			(start -0.7874 -0.4064)
			(end 0.7874 -0.4064)
			(stroke
				(width 0.1524)
				(type default)
			)
			(layer "F.SilkS")
		)
		(fp_line
			(start -0.7874 0.4064)
			(end -0.7874 -0.4064)
			(stroke
				(width 0.1524)
				(type default)
			)
			(layer "F.SilkS")
		)
		(fp_line
			(start 0.7874 -0.4064)
			(end 0.7874 0.4064)
			(stroke
				(width 0.1524)
				(type default)
			)
			(layer "F.SilkS")
		)
		(fp_line
			(start 0.7874 0.4064)
			(end -0.7874 0.4064)
			(stroke
				(width 0.1524)
				(type default)
			)
			(layer "F.SilkS")
		)
		(fp_line
			(start -0.67945 -0.305054)
			(end -0.12065 -0.305054)
			(stroke
				(width 0.1)
				(type default)
			)
			(layer "F.Fab")
		)
		(fp_line
			(start -0.67945 0.3048)
			(end -0.67945 -0.305054)
			(stroke
				(width 0.1)
				(type default)
			)
			(layer "F.Fab")
		)
		(fp_line
			(start -0.12065 -0.305054)
			(end -0.12065 -0.2794)
			(stroke
				(width 0.1)
				(type default)
			)
			(layer "F.Fab")
		)
		(fp_line
			(start -0.12065 -0.2794)
			(end 0.12065 -0.2794)
			(stroke
				(width 0.1)
				(type default)
			)
			(layer "F.Fab")
		)
		(fp_line
			(start -0.12065 0.2794)
			(end -0.12065 0.3048)
			(stroke
				(width 0.1)
				(type default)
			)
			(layer "F.Fab")
		)
		(fp_line
			(start -0.12065 0.3048)
			(end -0.67945 0.3048)
			(stroke
				(width 0.1)
				(type default)
			)
			(layer "F.Fab")
		)
		(fp_line
			(start 0.120396 0.2794)
			(end -0.12065 0.2794)
			(stroke
				(width 0.1)
				(type default)
			)
			(layer "F.Fab")
		)
		(fp_line
			(start 0.120396 0.3048)
			(end 0.120396 0.2794)
			(stroke
				(width 0.1)
				(type default)
			)
			(layer "F.Fab")
		)
		(fp_line
			(start 0.12065 -0.3048)
			(end 0.67945 -0.3048)
			(stroke
				(width 0.1)
				(type default)
			)
			(layer "F.Fab")
		)
		(fp_line
			(start 0.12065 -0.2794)
			(end 0.12065 -0.3048)
			(stroke
				(width 0.1)
				(type default)
			)
			(layer "F.Fab")
		)
		(fp_line
			(start 0.67945 -0.3048)
			(end 0.67945 0.3048)
			(stroke
				(width 0.1)
				(type default)
			)
			(layer "F.Fab")
		)
		(fp_line
			(start 0.67945 0.3048)
			(end 0.120396 0.3048)
			(stroke
				(width 0.1)
				(type default)
			)
			(layer "F.Fab")
		)
		(pad "1" smd circle
			(at -0.40005 0)
			(size 0 0)
			(layers "F.Cu" "F.Mask" "F.Paste")
			(net "NIC5_CLK_EN_R_N")
		)
		(pad "2" smd circle
			(at 0.40005 0)
			(size 0 0)
			(layers "F.Cu" "F.Mask" "F.Paste")
			(net "GND")
		)
	)
	(footprint ""
		(layer "F.Cu")
		(at 26.267918 -54.067456)
		(property "Reference" "PR209"
			(at 0 0 0)
			(layer "F.SilkS")
			(hide yes)
			(effects
				(font
					(size 1.27 1.27)
				)
			)
		)
		(property "Value" ""
			(at 0 0 0)
			(layer "F.Fab")
			(effects
				(font
					(size 1.27 1.27)
				)
			)
		)
		(duplicate_pad_numbers_are_jumpers no)
		(fp_line
			(start -0.7874 -0.4064)
			(end 0.7874 -0.4064)
			(stroke
				(width 0.1524)
				(type default)
			)
			(layer "F.SilkS")
		)
		(fp_line
			(start -0.7874 0.4064)
			(end -0.7874 -0.4064)
			(stroke
				(width 0.1524)
				(type default)
			)
			(layer "F.SilkS")
		)
		(fp_line
			(start 0.7874 -0.4064)
			(end 0.7874 0.4064)
			(stroke
				(width 0.1524)
				(type default)
			)
			(layer "F.SilkS")
		)
		(fp_line
			(start 0.7874 0.4064)
			(end -0.7874 0.4064)
			(stroke
				(width 0.1524)
				(type default)
			)
			(layer "F.SilkS")
		)
		(fp_line
			(start -0.67945 -0.305054)
			(end -0.12065 -0.305054)
			(stroke
				(width 0.1)
				(type default)
			)
			(layer "F.Fab")
		)
		(fp_line
			(start -0.67945 0.3048)
			(end -0.67945 -0.305054)
			(stroke
				(width 0.1)
				(type default)
			)
			(layer "F.Fab")
		)
		(fp_line
			(start -0.12065 -0.305054)
			(end -0.12065 -0.2794)
			(stroke
				(width 0.1)
				(type default)
			)
			(layer "F.Fab")
		)
		(fp_line
			(start -0.12065 -0.2794)
			(end 0.12065 -0.2794)
			(stroke
				(width 0.1)
				(type default)
			)
			(layer "F.Fab")
		)
		(fp_line
			(start -0.12065 0.2794)
			(end -0.12065 0.3048)
			(stroke
				(width 0.1)
				(type default)
			)
			(layer "F.Fab")
		)
		(fp_line
			(start -0.12065 0.3048)
			(end -0.67945 0.3048)
			(stroke
				(width 0.1)
				(type default)
			)
			(layer "F.Fab")
		)
		(fp_line
			(start 0.120396 0.2794)
			(end -0.12065 0.2794)
			(stroke
				(width 0.1)
				(type default)
			)
			(layer "F.Fab")
		)
		(fp_line
			(start 0.120396 0.3048)
			(end 0.120396 0.2794)
			(stroke
				(width 0.1)
				(type default)
			)
			(layer "F.Fab")
		)
		(fp_line
			(start 0.12065 -0.3048)
			(end 0.67945 -0.3048)
			(stroke
				(width 0.1)
				(type default)
			)
			(layer "F.Fab")
		)
		(fp_line
			(start 0.12065 -0.2794)
			(end 0.12065 -0.3048)
			(stroke
				(width 0.1)
				(type default)
			)
			(layer "F.Fab")
		)
		(fp_line
			(start 0.67945 -0.3048)
			(end 0.67945 0.3048)
			(stroke
				(width 0.1)
				(type default)
			)
			(layer "F.Fab")
		)
		(fp_line
			(start 0.67945 0.3048)
			(end 0.120396 0.3048)
			(stroke
				(width 0.1)
				(type default)
			)
			(layer "F.Fab")
		)
		(pad "1" smd circle
			(at -0.40005 0)
			(size 0 0)
			(layers "F.Cu" "F.Mask" "F.Paste")
			(net "P12V_SSD0_OCP")
		)
		(pad "2" smd circle
			(at 0.40005 0)
			(size 0 0)
			(layers "F.Cu" "F.Mask" "F.Paste")
			(net "GND")
		)
	)
	(footprint ""
		(layer "F.Cu")
		(at 352.920554 -83.787234)
		(property "Reference" "R1625"
			(at 0 0 0)
			(layer "F.SilkS")
			(hide yes)
			(effects
				(font
					(size 1.27 1.27)
				)
			)
		)
		(property "Value" ""
			(at 0 0 0)
			(layer "F.Fab")
			(effects
				(font
					(size 1.27 1.27)
				)
			)
		)
		(duplicate_pad_numbers_are_jumpers no)
		(fp_line
			(start -0.7874 -0.4064)
			(end 0.7874 -0.4064)
			(stroke
				(width 0.1524)
				(type default)
			)
			(layer "F.SilkS")
		)
		(fp_line
			(start -0.7874 0.4064)
			(end -0.7874 -0.4064)
			(stroke
				(width 0.1524)
				(type default)
			)
			(layer "F.SilkS")
		)
		(fp_line
			(start 0.7874 -0.4064)
			(end 0.7874 0.4064)
			(stroke
				(width 0.1524)
				(type default)
			)
			(layer "F.SilkS")
		)
		(fp_line
			(start 0.7874 0.4064)
			(end -0.7874 0.4064)
			(stroke
				(width 0.1524)
				(type default)
			)
			(layer "F.SilkS")
		)
		(fp_line
			(start -0.67945 -0.305054)
			(end -0.12065 -0.305054)
			(stroke
				(width 0.1)
				(type default)
			)
			(layer "F.Fab")
		)
		(fp_line
			(start -0.67945 0.3048)
			(end -0.67945 -0.305054)
			(stroke
				(width 0.1)
				(type default)
			)
			(layer "F.Fab")
		)
		(fp_line
			(start -0.12065 -0.305054)
			(end -0.12065 -0.2794)
			(stroke
				(width 0.1)
				(type default)
			)
			(layer "F.Fab")
		)
		(fp_line
			(start -0.12065 -0.2794)
			(end 0.12065 -0.2794)
			(stroke
				(width 0.1)
				(type default)
			)
			(layer "F.Fab")
		)
		(fp_line
			(start -0.12065 0.2794)
			(end -0.12065 0.3048)
			(stroke
				(width 0.1)
				(type default)
			)
			(layer "F.Fab")
		)
		(fp_line
			(start -0.12065 0.3048)
			(end -0.67945 0.3048)
			(stroke
				(width 0.1)
				(type default)
			)
			(layer "F.Fab")
		)
		(fp_line
			(start 0.120396 0.2794)
			(end -0.12065 0.2794)
			(stroke
				(width 0.1)
				(type default)
			)
			(layer "F.Fab")
		)
		(fp_line
			(start 0.120396 0.3048)
			(end 0.120396 0.2794)
			(stroke
				(width 0.1)
				(type default)
			)
			(layer "F.Fab")
		)
		(fp_line
			(start 0.12065 -0.3048)
			(end 0.67945 -0.3048)
			(stroke
				(width 0.1)
				(type default)
			)
			(layer "F.Fab")
		)
		(fp_line
			(start 0.12065 -0.2794)
			(end 0.12065 -0.3048)
			(stroke
				(width 0.1)
				(type default)
			)
			(layer "F.Fab")
		)
		(fp_line
			(start 0.67945 -0.3048)
			(end 0.67945 0.3048)
			(stroke
				(width 0.1)
				(type default)
			)
			(layer "F.Fab")
		)
		(fp_line
			(start 0.67945 0.3048)
			(end 0.120396 0.3048)
			(stroke
				(width 0.1)
				(type default)
			)
			(layer "F.Fab")
		)
		(pad "1" smd circle
			(at -0.40005 0)
			(size 0 0)
			(layers "F.Cu" "F.Mask" "F.Paste")
			(net "SMB_BIC_I2C9_MUX1_SSD10_R_SCL")
		)
		(pad "2" smd circle
			(at 0.40005 0)
			(size 0 0)
			(layers "F.Cu" "F.Mask" "F.Paste")
			(net "SMB_BIC_I2C9_MUX1_SSD10_SCL")
		)
	)
	(footprint ""
		(layer "F.Cu")
		(at 324.15861 -111.227108 90)
		(property "Reference" "PC323"
			(at 0 0 90)
			(layer "F.SilkS")
			(hide yes)
			(effects
				(font
					(size 1.27 1.27)
				)
			)
		)
		(property "Value" ""
			(at 0 0 90)
			(layer "F.Fab")
			(effects
				(font
					(size 1.27 1.27)
				)
			)
		)
		(duplicate_pad_numbers_are_jumpers no)
		(fp_line
			(start 1.524 -0.762)
			(end 1.524 0.762)
			(stroke
				(width 0.1524)
				(type default)
			)
			(layer "F.SilkS")
		)
		(fp_line
			(start -1.524 -0.762)
			(end 1.524 -0.762)
			(stroke
				(width 0.1524)
				(type default)
			)
			(layer "F.SilkS")
		)
		(fp_line
			(start 1.524 0.762)
			(end -1.524 0.762)
			(stroke
				(width 0.1524)
				(type default)
			)
			(layer "F.SilkS")
		)
		(fp_line
			(start -1.524 0.762)
			(end -1.524 -0.762)
			(stroke
				(width 0.1524)
				(type default)
			)
			(layer "F.SilkS")
		)
		(fp_line
			(start 1.1049 -0.724916)
			(end -1.1049 -0.724916)
			(stroke
				(width 0.1)
				(type default)
			)
			(layer "F.Fab")
		)
		(fp_line
			(start -1.1049 -0.724916)
			(end -1.1049 0.724916)
			(stroke
				(width 0.1)
				(type default)
			)
			(layer "F.Fab")
		)
		(fp_line
			(start 1.1049 0.724916)
			(end 1.1049 -0.724916)
			(stroke
				(width 0.1)
				(type default)
			)
			(layer "F.Fab")
		)
		(fp_line
			(start -1.1049 0.724916)
			(end 1.1049 0.724916)
			(stroke
				(width 0.1)
				(type default)
			)
			(layer "F.Fab")
		)
		(pad "1" smd rect
			(at -0.889 0 270)
			(size 1.016 1.27)
			(layers "F.Cu" "F.Mask" "F.Paste")
			(net "P12V_NIC5_R")
		)
		(pad "2" smd rect
			(at 0.889 0 270)
			(size 1.016 1.27)
			(layers "F.Cu" "F.Mask" "F.Paste")
			(net "GND")
		)
	)
	(footprint ""
		(layer "F.Cu")
		(at 476.681038 -554.52518 180)
		(property "Reference" "J55_12"
			(at -2.8448 -1.402334 0)
			(unlocked yes)
			(layer "B.SilkS")
			(effects
				(font
					(size 0.7874 0.5842)
					(thickness 0.1524)
				)
				(justify mirror)
			)
		)
		(property "Value" ""
			(at 0 0 180)
			(layer "F.Fab")
			(effects
				(font
					(size 1.27 1.27)
				)
			)
		)
		(duplicate_pad_numbers_are_jumpers no)
		(pad "1" thru_hole circle
			(at 0 0 180)
			(size 0.4572 0.4572)
			(drill 0.2032)
			(layers "*.Cu" "*.Mask")
			(remove_unused_layers no)
			(net "Net_2678")
			(clearance 0.127)
			(thermal_gap 0.127)
			(padstack
				(mode front_inner_back)
				(layer "Inner"
					(shape circle)
					(size 0.4572 0.4572)
					(clearance 0.127)
				)
				(layer "B.Cu"
					(shape circle)
					(size 0.508 0.508)
					(clearance 0.1016)
				)
			)
		)
	)
	(footprint ""
		(layer "F.Cu")
		(at 366.566196 -285.088584 90)
		(property "Reference" "PC187"
			(at 0 0 90)
			(layer "F.SilkS")
			(hide yes)
			(effects
				(font
					(size 1.27 1.27)
				)
			)
		)
		(property "Value" ""
			(at 0 0 90)
			(layer "F.Fab")
			(effects
				(font
					(size 1.27 1.27)
				)
			)
		)
		(duplicate_pad_numbers_are_jumpers no)
		(fp_line
			(start 0.7874 -0.4064)
			(end 0.7874 0.4064)
			(stroke
				(width 0.1524)
				(type default)
			)
			(layer "F.SilkS")
		)
		(fp_line
			(start -0.7874 -0.4064)
			(end 0.7874 -0.4064)
			(stroke
				(width 0.1524)
				(type default)
			)
			(layer "F.SilkS")
		)
		(fp_line
			(start 0.7874 0.4064)
			(end -0.7874 0.4064)
			(stroke
				(width 0.1524)
				(type default)
			)
			(layer "F.SilkS")
		)
		(fp_line
			(start -0.7874 0.4064)
			(end -0.7874 -0.4064)
			(stroke
				(width 0.1524)
				(type default)
			)
			(layer "F.SilkS")
		)
		(fp_line
			(start -0.12065 -0.305054)
			(end -0.12065 -0.2794)
			(stroke
				(width 0.1)
				(type default)
			)
			(layer "F.Fab")
		)
		(fp_line
			(start -0.67945 -0.305054)
			(end -0.12065 -0.305054)
			(stroke
				(width 0.1)
				(type default)
			)
			(layer "F.Fab")
		)
		(fp_line
			(start 0.67945 -0.3048)
			(end 0.67945 0.3048)
			(stroke
				(width 0.1)
				(type default)
			)
			(layer "F.Fab")
		)
		(fp_line
			(start 0.12065 -0.3048)
			(end 0.67945 -0.3048)
			(stroke
				(width 0.1)
				(type default)
			)
			(layer "F.Fab")
		)
		(fp_line
			(start 0.12065 -0.2794)
			(end 0.12065 -0.3048)
			(stroke
				(width 0.1)
				(type default)
			)
			(layer "F.Fab")
		)
		(fp_line
			(start -0.12065 -0.2794)
			(end 0.12065 -0.2794)
			(stroke
				(width 0.1)
				(type default)
			)
			(layer "F.Fab")
		)
		(fp_line
			(start 0.120396 0.2794)
			(end -0.12065 0.2794)
			(stroke
				(width 0.1)
				(type default)
			)
			(layer "F.Fab")
		)
		(fp_line
			(start -0.12065 0.2794)
			(end -0.12065 0.3048)
			(stroke
				(width 0.1)
				(type default)
			)
			(layer "F.Fab")
		)
		(fp_line
			(start 0.67945 0.3048)
			(end 0.120396 0.3048)
			(stroke
				(width 0.1)
				(type default)
			)
			(layer "F.Fab")
		)
		(fp_line
			(start 0.120396 0.3048)
			(end 0.120396 0.2794)
			(stroke
				(width 0.1)
				(type default)
			)
			(layer "F.Fab")
		)
		(fp_line
			(start -0.12065 0.3048)
			(end -0.67945 0.3048)
			(stroke
				(width 0.1)
				(type default)
			)
			(layer "F.Fab")
		)
		(fp_line
			(start -0.67945 0.3048)
			(end -0.67945 -0.305054)
			(stroke
				(width 0.1)
				(type default)
			)
			(layer "F.Fab")
		)
		(pad "1" smd circle
			(at -0.40005 0 90)
			(size 0 0)
			(layers "F.Cu" "F.Mask" "F.Paste")
			(net "P0V8_PEX3_PVCC")
		)
		(pad "2" smd circle
			(at 0.40005 0 90)
			(size 0 0)
			(layers "F.Cu" "F.Mask" "F.Paste")
			(net "GND")
		)
	)
	(footprint ""
		(layer "F.Cu")
		(at 90.4113 -107.29976)
		(property "Reference" "R693"
			(at 0 0 0)
			(layer "F.SilkS")
			(hide yes)
			(effects
				(font
					(size 1.27 1.27)
				)
			)
		)
		(property "Value" ""
			(at 0 0 0)
			(layer "F.Fab")
			(effects
				(font
					(size 1.27 1.27)
				)
			)
		)
		(duplicate_pad_numbers_are_jumpers no)
		(fp_line
			(start -3.937508 -1.8796)
			(end -3.937508 1.8796)
			(stroke
				(width 0.1524)
				(type default)
			)
			(layer "F.SilkS")
		)
		(fp_line
			(start -3.937508 1.8796)
			(end 3.937508 1.8796)
			(stroke
				(width 0.1524)
				(type default)
			)
			(layer "F.SilkS")
		)
		(fp_line
			(start 3.937508 -1.8796)
			(end -3.937508 -1.8796)
			(stroke
				(width 0.1524)
				(type default)
			)
			(layer "F.SilkS")
		)
		(fp_line
			(start 3.937508 1.8796)
			(end 3.937508 -1.8796)
			(stroke
				(width 0.1524)
				(type default)
			)
			(layer "F.SilkS")
		)
		(fp_line
			(start -3.275076 -1.674876)
			(end -3.275076 1.674876)
			(stroke
				(width 0.1)
				(type default)
			)
			(layer "F.Fab")
		)
		(fp_line
			(start -3.275076 1.674876)
			(end 3.275076 1.674876)
			(stroke
				(width 0.1)
				(type default)
			)
			(layer "F.Fab")
		)
		(fp_line
			(start 3.275076 -1.674876)
			(end -3.275076 -1.674876)
			(stroke
				(width 0.1)
				(type default)
			)
			(layer "F.Fab")
		)
		(fp_line
			(start 3.275076 1.674876)
			(end 3.275076 -1.674876)
			(stroke
				(width 0.1)
				(type default)
			)
			(layer "F.Fab")
		)
		(pad "1" smd rect
			(at -2.350008 0)
			(size 2.921 3.5052)
			(layers "F.Cu" "F.Mask" "F.Paste")
			(net "P12V_NIC1")
		)
		(pad "2" smd rect
			(at 2.350008 0)
			(size 2.921 3.5052)
			(layers "F.Cu" "F.Mask" "F.Paste")
			(net "P12V_NIC1_R")
		)
	)
	(footprint ""
		(layer "F.Cu")
		(at 359.156 -191.262 180)
		(property "Reference" "R4639"
			(at 0 0 180)
			(layer "F.SilkS")
			(hide yes)
			(effects
				(font
					(size 1.27 1.27)
				)
			)
		)
		(property "Value" ""
			(at 0 0 180)
			(layer "F.Fab")
			(effects
				(font
					(size 1.27 1.27)
				)
			)
		)
		(duplicate_pad_numbers_are_jumpers no)
		(fp_line
			(start 0.7874 0.4064)
			(end -0.7874 0.4064)
			(stroke
				(width 0.1524)
				(type default)
			)
			(layer "F.SilkS")
		)
		(fp_line
			(start 0.7874 -0.4064)
			(end 0.7874 0.4064)
			(stroke
				(width 0.1524)
				(type default)
			)
			(layer "F.SilkS")
		)
		(fp_line
			(start -0.7874 0.4064)
			(end -0.7874 -0.4064)
			(stroke
				(width 0.1524)
				(type default)
			)
			(layer "F.SilkS")
		)
		(fp_line
			(start -0.7874 -0.4064)
			(end 0.7874 -0.4064)
			(stroke
				(width 0.1524)
				(type default)
			)
			(layer "F.SilkS")
		)
		(fp_line
			(start 0.67945 0.3048)
			(end 0.120396 0.3048)
			(stroke
				(width 0.1)
				(type default)
			)
			(layer "F.Fab")
		)
		(fp_line
			(start 0.67945 -0.3048)
			(end 0.67945 0.3048)
			(stroke
				(width 0.1)
				(type default)
			)
			(layer "F.Fab")
		)
		(fp_line
			(start 0.12065 -0.2794)
			(end 0.12065 -0.3048)
			(stroke
				(width 0.1)
				(type default)
			)
			(layer "F.Fab")
		)
		(fp_line
			(start 0.12065 -0.3048)
			(end 0.67945 -0.3048)
			(stroke
				(width 0.1)
				(type default)
			)
			(layer "F.Fab")
		)
		(fp_line
			(start 0.120396 0.3048)
			(end 0.120396 0.2794)
			(stroke
				(width 0.1)
				(type default)
			)
			(layer "F.Fab")
		)
		(fp_line
			(start 0.120396 0.2794)
			(end -0.12065 0.2794)
			(stroke
				(width 0.1)
				(type default)
			)
			(layer "F.Fab")
		)
		(fp_line
			(start -0.12065 0.3048)
			(end -0.67945 0.3048)
			(stroke
				(width 0.1)
				(type default)
			)
			(layer "F.Fab")
		)
		(fp_line
			(start -0.12065 0.2794)
			(end -0.12065 0.3048)
			(stroke
				(width 0.1)
				(type default)
			)
			(layer "F.Fab")
		)
		(fp_line
			(start -0.12065 -0.2794)
			(end 0.12065 -0.2794)
			(stroke
				(width 0.1)
				(type default)
			)
			(layer "F.Fab")
		)
		(fp_line
			(start -0.12065 -0.305054)
			(end -0.12065 -0.2794)
			(stroke
				(width 0.1)
				(type default)
			)
			(layer "F.Fab")
		)
		(fp_line
			(start -0.67945 0.3048)
			(end -0.67945 -0.305054)
			(stroke
				(width 0.1)
				(type default)
			)
			(layer "F.Fab")
		)
		(fp_line
			(start -0.67945 -0.305054)
			(end -0.12065 -0.305054)
			(stroke
				(width 0.1)
				(type default)
			)
			(layer "F.Fab")
		)
		(pad "1" smd circle
			(at -0.40005 0 180)
			(size 0 0)
			(layers "F.Cu" "F.Mask" "F.Paste")
			(net "PCA9555_1_PEX0_A2")
		)
		(pad "2" smd circle
			(at 0.40005 0 180)
			(size 0 0)
			(layers "F.Cu" "F.Mask" "F.Paste")
			(net "P3V3_AUX")
		)
	)
	(footprint ""
		(layer "F.Cu")
		(at 148.809202 -26.03373)
		(property "Reference" "R4062"
			(at 0 0 0)
			(layer "F.SilkS")
			(hide yes)
			(effects
				(font
					(size 1.27 1.27)
				)
			)
		)
		(property "Value" ""
			(at 0 0 0)
			(layer "F.Fab")
			(effects
				(font
					(size 1.27 1.27)
				)
			)
		)
		(duplicate_pad_numbers_are_jumpers no)
		(fp_line
			(start -0.7874 -0.4064)
			(end 0.7874 -0.4064)
			(stroke
				(width 0.1524)
				(type default)
			)
			(layer "F.SilkS")
		)
		(fp_line
			(start -0.7874 0.4064)
			(end -0.7874 -0.4064)
			(stroke
				(width 0.1524)
				(type default)
			)
			(layer "F.SilkS")
		)
		(fp_line
			(start 0.7874 -0.4064)
			(end 0.7874 0.4064)
			(stroke
				(width 0.1524)
				(type default)
			)
			(layer "F.SilkS")
		)
		(fp_line
			(start 0.7874 0.4064)
			(end -0.7874 0.4064)
			(stroke
				(width 0.1524)
				(type default)
			)
			(layer "F.SilkS")
		)
		(fp_line
			(start -0.67945 -0.305054)
			(end -0.12065 -0.305054)
			(stroke
				(width 0.1)
				(type default)
			)
			(layer "F.Fab")
		)
		(fp_line
			(start -0.67945 0.3048)
			(end -0.67945 -0.305054)
			(stroke
				(width 0.1)
				(type default)
			)
			(layer "F.Fab")
		)
		(fp_line
			(start -0.12065 -0.305054)
			(end -0.12065 -0.2794)
			(stroke
				(width 0.1)
				(type default)
			)
			(layer "F.Fab")
		)
		(fp_line
			(start -0.12065 -0.2794)
			(end 0.12065 -0.2794)
			(stroke
				(width 0.1)
				(type default)
			)
			(layer "F.Fab")
		)
		(fp_line
			(start -0.12065 0.2794)
			(end -0.12065 0.3048)
			(stroke
				(width 0.1)
				(type default)
			)
			(layer "F.Fab")
		)
		(fp_line
			(start -0.12065 0.3048)
			(end -0.67945 0.3048)
			(stroke
				(width 0.1)
				(type default)
			)
			(layer "F.Fab")
		)
		(fp_line
			(start 0.120396 0.2794)
			(end -0.12065 0.2794)
			(stroke
				(width 0.1)
				(type default)
			)
			(layer "F.Fab")
		)
		(fp_line
			(start 0.120396 0.3048)
			(end 0.120396 0.2794)
			(stroke
				(width 0.1)
				(type default)
			)
			(layer "F.Fab")
		)
		(fp_line
			(start 0.12065 -0.3048)
			(end 0.67945 -0.3048)
			(stroke
				(width 0.1)
				(type default)
			)
			(layer "F.Fab")
		)
		(fp_line
			(start 0.12065 -0.2794)
			(end 0.12065 -0.3048)
			(stroke
				(width 0.1)
				(type default)
			)
			(layer "F.Fab")
		)
		(fp_line
			(start 0.67945 -0.3048)
			(end 0.67945 0.3048)
			(stroke
				(width 0.1)
				(type default)
			)
			(layer "F.Fab")
		)
		(fp_line
			(start 0.67945 0.3048)
			(end 0.120396 0.3048)
			(stroke
				(width 0.1)
				(type default)
			)
			(layer "F.Fab")
		)
		(pad "1" smd circle
			(at -0.40005 0)
			(size 0 0)
			(layers "F.Cu" "F.Mask" "F.Paste")
			(net "P3V3_AUX")
		)
		(pad "2" smd circle
			(at 0.40005 0)
			(size 0 0)
			(layers "F.Cu" "F.Mask" "F.Paste")
			(net "PRSNT_SSD5_R_N")
		)
	)
	(footprint ""
		(layer "F.Cu")
		(at 359.508044 -86.490048)
		(property "Reference" "U125"
			(at -2.1844 -4.587748 0)
			(unlocked yes)
			(layer "F.SilkS")
			(effects
				(font
					(size 0.7874 0.5842)
					(thickness 0.1524)
				)
				(justify left)
			)
		)
		(property "Value" ""
			(at 0 0 0)
			(layer "F.Fab")
			(effects
				(font
					(size 1.27 1.27)
				)
			)
		)
		(duplicate_pad_numbers_are_jumpers no)
		(fp_line
			(start -1.8542 -3.949954)
			(end -1.8542 3.949954)
			(stroke
				(width 0.1524)
				(type default)
			)
			(layer "F.SilkS")
		)
		(fp_line
			(start -1.8542 3.949954)
			(end 1.8542 3.949954)
			(stroke
				(width 0.1524)
				(type default)
			)
			(layer "F.SilkS")
		)
		(fp_line
			(start -1.282954 -3.949954)
			(end -1.8542 -3.949954)
			(stroke
				(width 0.1524)
				(type default)
			)
			(layer "F.SilkS")
		)
		(fp_line
			(start 0 -2.667)
			(end -1.282954 -3.949954)
			(stroke
				(width 0.1524)
				(type default)
			)
			(layer "F.SilkS")
		)
		(fp_line
			(start 1.282954 -3.949954)
			(end 0 -2.667)
			(stroke
				(width 0.1524)
				(type default)
			)
			(layer "F.SilkS")
		)
		(fp_line
			(start 1.8542 -3.949954)
			(end 1.282954 -3.949954)
			(stroke
				(width 0.1524)
				(type default)
			)
			(layer "F.SilkS")
		)
		(fp_line
			(start 1.8542 3.949954)
			(end 1.8542 -3.949954)
			(stroke
				(width 0.1524)
				(type default)
			)
			(layer "F.SilkS")
		)
		(fp_poly
			(pts
				(xy -4.8006 -4.08305) (xy -4.8006 -3.06705) (xy -3.7846 -3.57505)
			)
			(stroke
				(width 0)
				(type default)
			)
			(fill yes)
			(layer "F.SilkS")
		)
		(fp_line
			(start -2.249932 -3.949954)
			(end -2.249932 3.949954)
			(stroke
				(width 0.1)
				(type default)
			)
			(layer "F.Fab")
		)
		(fp_line
			(start -2.249932 3.949954)
			(end 2.249932 3.949954)
			(stroke
				(width 0.1)
				(type default)
			)
			(layer "F.Fab")
		)
		(fp_line
			(start 2.249932 -3.949954)
			(end -2.249932 -3.949954)
			(stroke
				(width 0.1)
				(type default)
			)
			(layer "F.Fab")
		)
		(fp_line
			(start 2.249932 3.949954)
			(end 2.249932 -3.949954)
			(stroke
				(width 0.1)
				(type default)
			)
			(layer "F.Fab")
		)
		(fp_poly
			(pts
				(xy -4.8006 -4.08305) (xy -4.8006 -3.06705) (xy -3.7846 -3.57505)
			)
			(stroke
				(width 0)
				(type default)
			)
			(fill yes)
			(layer "F.Fab")
		)
		(pad "1" smd rect
			(at -2.800096 -3.57505 270)
			(size 0.3048 1.6002)
			(layers "F.Cu" "F.Mask" "F.Paste")
			(net "BIC_I2C9_SSD_MUX1_A0")
		)
		(pad "2" smd rect
			(at -2.800096 -2.925064 270)
			(size 0.3048 1.6002)
			(layers "F.Cu" "F.Mask" "F.Paste")
			(net "BIC_I2C9_SSD_MUX1_A1")
		)
		(pad "3" smd rect
			(at -2.800096 -2.275078 270)
			(size 0.3048 1.6002)
			(layers "F.Cu" "F.Mask" "F.Paste")
			(net "RST_BIC_I2C9_SSD_MUX1_R_N")
		)
		(pad "4" smd rect
			(at -2.800096 -1.625092 270)
			(size 0.3048 1.6002)
			(layers "F.Cu" "F.Mask" "F.Paste")
			(net "SMB_BIC_I2C9_MUX1_SSD8_SDA")
		)
		(pad "5" smd rect
			(at -2.800096 -0.975106 270)
			(size 0.3048 1.6002)
			(layers "F.Cu" "F.Mask" "F.Paste")
			(net "SMB_BIC_I2C9_MUX1_SSD8_SCL")
		)
		(pad "6" smd rect
			(at -2.800096 -0.32512 270)
			(size 0.3048 1.6002)
			(layers "F.Cu" "F.Mask" "F.Paste")
			(net "SMB_BIC_I2C9_MUX1_SSD9_SDA")
		)
		(pad "7" smd rect
			(at -2.800096 0.32512 270)
			(size 0.3048 1.6002)
			(layers "F.Cu" "F.Mask" "F.Paste")
			(net "SMB_BIC_I2C9_MUX1_SSD9_SCL")
		)
		(pad "8" smd rect
			(at -2.800096 0.975106 270)
			(size 0.3048 1.6002)
			(layers "F.Cu" "F.Mask" "F.Paste")
			(net "SMB_BIC_I2C9_MUX1_SSD10_SDA")
		)
		(pad "9" smd rect
			(at -2.800096 1.625092 270)
			(size 0.3048 1.6002)
			(layers "F.Cu" "F.Mask" "F.Paste")
			(net "SMB_BIC_I2C9_MUX1_SSD10_SCL")
		)
		(pad "10" smd rect
			(at -2.800096 2.275078 270)
			(size 0.3048 1.6002)
			(layers "F.Cu" "F.Mask" "F.Paste")
			(net "SMB_BIC_I2C9_MUX1_SSD11_SDA")
		)
		(pad "11" smd rect
			(at -2.800096 2.925064 270)
			(size 0.3048 1.6002)
			(layers "F.Cu" "F.Mask" "F.Paste")
			(net "SMB_BIC_I2C9_MUX1_SSD11_SCL")
		)
		(pad "12" smd rect
			(at -2.800096 3.57505 270)
			(size 0.3048 1.6002)
			(layers "F.Cu" "F.Mask" "F.Paste")
			(net "GND")
		)
		(pad "13" smd rect
			(at 2.800096 3.57505 270)
			(size 0.3048 1.6002)
			(layers "F.Cu" "F.Mask" "F.Paste")
			(net "SMB_BIC_I2C9_MUX1_SSD12_SDA")
		)
		(pad "14" smd rect
			(at 2.800096 2.925064 270)
			(size 0.3048 1.6002)
			(layers "F.Cu" "F.Mask" "F.Paste")
			(net "SMB_BIC_I2C9_MUX1_SSD12_SCL")
		)
		(pad "15" smd rect
			(at 2.800096 2.275078 270)
			(size 0.3048 1.6002)
			(layers "F.Cu" "F.Mask" "F.Paste")
			(net "SMB_BIC_I2C9_MUX1_SSD13_SDA")
		)
		(pad "16" smd rect
			(at 2.800096 1.625092 270)
			(size 0.3048 1.6002)
			(layers "F.Cu" "F.Mask" "F.Paste")
			(net "SMB_BIC_I2C9_MUX1_SSD13_SCL")
		)
		(pad "17" smd rect
			(at 2.800096 0.975106 270)
			(size 0.3048 1.6002)
			(layers "F.Cu" "F.Mask" "F.Paste")
			(net "SMB_BIC_I2C9_MUX1_SSD14_SDA")
		)
		(pad "18" smd rect
			(at 2.800096 0.32512 270)
			(size 0.3048 1.6002)
			(layers "F.Cu" "F.Mask" "F.Paste")
			(net "SMB_BIC_I2C9_MUX1_SSD14_SCL")
		)
		(pad "19" smd rect
			(at 2.800096 -0.32512 270)
			(size 0.3048 1.6002)
			(layers "F.Cu" "F.Mask" "F.Paste")
			(net "SMB_BIC_I2C9_MUX1_SSD15_SDA")
		)
		(pad "20" smd rect
			(at 2.800096 -0.975106 270)
			(size 0.3048 1.6002)
			(layers "F.Cu" "F.Mask" "F.Paste")
			(net "SMB_BIC_I2C9_MUX1_SSD15_SCL")
		)
		(pad "21" smd rect
			(at 2.800096 -1.625092 270)
			(size 0.3048 1.6002)
			(layers "F.Cu" "F.Mask" "F.Paste")
			(net "BIC_I2C9_SSD_MUX1_A2")
		)
		(pad "22" smd rect
			(at 2.800096 -2.275078 270)
			(size 0.3048 1.6002)
			(layers "F.Cu" "F.Mask" "F.Paste")
			(net "SMB_BIC_I2C9_SSD_MUX1_SCL")
		)
		(pad "23" smd rect
			(at 2.800096 -2.925064 270)
			(size 0.3048 1.6002)
			(layers "F.Cu" "F.Mask" "F.Paste")
			(net "SMB_BIC_I2C9_SSD_MUX1_SDA")
		)
		(pad "24" smd rect
			(at 2.800096 -3.57505 270)
			(size 0.3048 1.6002)
			(layers "F.Cu" "F.Mask" "F.Paste")
			(net "P3V3_AUX")
		)
	)
	(footprint ""
		(layer "F.Cu")
		(at 185.89244 -29.139642 180)
		(property "Reference" "C298"
			(at 0 0 180)
			(layer "F.SilkS")
			(hide yes)
			(effects
				(font
					(size 1.27 1.27)
				)
			)
		)
		(property "Value" ""
			(at 0 0 180)
			(layer "F.Fab")
			(effects
				(font
					(size 1.27 1.27)
				)
			)
		)
		(duplicate_pad_numbers_are_jumpers no)
		(fp_line
			(start 0.299974 0.150114)
			(end -0.299974 0.150114)
			(stroke
				(width 0.1)
				(type default)
			)
			(layer "F.Fab")
		)
		(fp_line
			(start 0.299974 -0.150114)
			(end 0.299974 0.150114)
			(stroke
				(width 0.1)
				(type default)
			)
			(layer "F.Fab")
		)
		(fp_line
			(start -0.299974 0.150114)
			(end -0.299974 -0.150114)
			(stroke
				(width 0.1)
				(type default)
			)
			(layer "F.Fab")
		)
		(fp_line
			(start -0.299974 -0.150114)
			(end 0.299974 -0.150114)
			(stroke
				(width 0.1)
				(type default)
			)
			(layer "F.Fab")
		)
		(pad "1" smd rect
			(at -0.2667 0 180)
			(size 0.3048 0.381)
			(layers "F.Cu" "F.Mask" "F.Paste")
			(net "P5E_PEX1_STN2_TX_DP<36>")
		)
		(pad "2" smd rect
			(at 0.2667 0 180)
			(size 0.3048 0.381)
			(layers "F.Cu" "F.Mask" "F.Paste")
			(net "P5E_PEX1_STN2_TX_C_DP<36>")
		)
	)
	(footprint ""
		(layer "F.Cu")
		(at 421.705532 -350.098614 90)
		(property "Reference" "C2451"
			(at 0 0 90)
			(layer "F.SilkS")
			(hide yes)
			(effects
				(font
					(size 1.27 1.27)
				)
			)
		)
		(property "Value" ""
			(at 0 0 90)
			(layer "F.Fab")
			(effects
				(font
					(size 1.27 1.27)
				)
			)
		)
		(duplicate_pad_numbers_are_jumpers no)
		(fp_line
			(start 0.299974 -0.150114)
			(end 0.299974 0.150114)
			(stroke
				(width 0.1)
				(type default)
			)
			(layer "F.Fab")
		)
		(fp_line
			(start -0.299974 -0.150114)
			(end 0.299974 -0.150114)
			(stroke
				(width 0.1)
				(type default)
			)
			(layer "F.Fab")
		)
		(fp_line
			(start 0.299974 0.150114)
			(end -0.299974 0.150114)
			(stroke
				(width 0.1)
				(type default)
			)
			(layer "F.Fab")
		)
		(fp_line
			(start -0.299974 0.150114)
			(end -0.299974 -0.150114)
			(stroke
				(width 0.1)
				(type default)
			)
			(layer "F.Fab")
		)
		(pad "1" smd rect
			(at -0.2667 0 90)
			(size 0.3048 0.381)
			(layers "F.Cu" "F.Mask" "F.Paste")
			(net "P5E_PEX3_STN4_TX_DP<73>")
		)
		(pad "2" smd rect
			(at 0.2667 0 90)
			(size 0.3048 0.381)
			(layers "F.Cu" "F.Mask" "F.Paste")
			(net "P5E_PEX3_STN4_TX_C_DP<73>")
		)
	)
	(footprint ""
		(layer "F.Cu")
		(at 37.550344 -252.356874 -90)
		(property "Reference" "R1216"
			(at 0 0 270)
			(layer "F.SilkS")
			(hide yes)
			(effects
				(font
					(size 1.27 1.27)
				)
			)
		)
		(property "Value" ""
			(at 0 0 270)
			(layer "F.Fab")
			(effects
				(font
					(size 1.27 1.27)
				)
			)
		)
		(duplicate_pad_numbers_are_jumpers no)
		(fp_line
			(start -0.7874 0.4064)
			(end -0.7874 -0.4064)
			(stroke
				(width 0.1524)
				(type default)
			)
			(layer "F.SilkS")
		)
		(fp_line
			(start 0.7874 0.4064)
			(end -0.7874 0.4064)
			(stroke
				(width 0.1524)
				(type default)
			)
			(layer "F.SilkS")
		)
		(fp_line
			(start -0.7874 -0.4064)
			(end 0.7874 -0.4064)
			(stroke
				(width 0.1524)
				(type default)
			)
			(layer "F.SilkS")
		)
		(fp_line
			(start 0.7874 -0.4064)
			(end 0.7874 0.4064)
			(stroke
				(width 0.1524)
				(type default)
			)
			(layer "F.SilkS")
		)
		(fp_line
			(start -0.67945 0.3048)
			(end -0.67945 -0.305054)
			(stroke
				(width 0.1)
				(type default)
			)
			(layer "F.Fab")
		)
		(fp_line
			(start -0.12065 0.3048)
			(end -0.67945 0.3048)
			(stroke
				(width 0.1)
				(type default)
			)
			(layer "F.Fab")
		)
		(fp_line
			(start 0.120396 0.3048)
			(end 0.120396 0.2794)
			(stroke
				(width 0.1)
				(type default)
			)
			(layer "F.Fab")
		)
		(fp_line
			(start 0.67945 0.3048)
			(end 0.120396 0.3048)
			(stroke
				(width 0.1)
				(type default)
			)
			(layer "F.Fab")
		)
		(fp_line
			(start -0.12065 0.2794)
			(end -0.12065 0.3048)
			(stroke
				(width 0.1)
				(type default)
			)
			(layer "F.Fab")
		)
		(fp_line
			(start 0.120396 0.2794)
			(end -0.12065 0.2794)
			(stroke
				(width 0.1)
				(type default)
			)
			(layer "F.Fab")
		)
		(fp_line
			(start -0.12065 -0.2794)
			(end 0.12065 -0.2794)
			(stroke
				(width 0.1)
				(type default)
			)
			(layer "F.Fab")
		)
		(fp_line
			(start 0.12065 -0.2794)
			(end 0.12065 -0.3048)
			(stroke
				(width 0.1)
				(type default)
			)
			(layer "F.Fab")
		)
		(fp_line
			(start 0.12065 -0.3048)
			(end 0.67945 -0.3048)
			(stroke
				(width 0.1)
				(type default)
			)
			(layer "F.Fab")
		)
		(fp_line
			(start 0.67945 -0.3048)
			(end 0.67945 0.3048)
			(stroke
				(width 0.1)
				(type default)
			)
			(layer "F.Fab")
		)
		(fp_line
			(start -0.67945 -0.305054)
			(end -0.12065 -0.305054)
			(stroke
				(width 0.1)
				(type default)
			)
			(layer "F.Fab")
		)
		(fp_line
			(start -0.12065 -0.305054)
			(end -0.12065 -0.2794)
			(stroke
				(width 0.1)
				(type default)
			)
			(layer "F.Fab")
		)
		(pad "1" smd circle
			(at -0.40005 0 270)
			(size 0 0)
			(layers "F.Cu" "F.Mask" "F.Paste")
			(net "GND")
		)
		(pad "2" smd circle
			(at 0.40005 0 270)
			(size 0 0)
			(layers "F.Cu" "F.Mask" "F.Paste")
			(net "PEX0_MODE_SEL10")
		)
	)
	(footprint ""
		(layer "F.Cu")
		(at 211.939886 -70.52437 90)
		(property "Reference" "PC395"
			(at 0 0 90)
			(layer "F.SilkS")
			(hide yes)
			(effects
				(font
					(size 1.27 1.27)
				)
			)
		)
		(property "Value" ""
			(at 0 0 90)
			(layer "F.Fab")
			(effects
				(font
					(size 1.27 1.27)
				)
			)
		)
		(duplicate_pad_numbers_are_jumpers no)
		(fp_line
			(start 1.524 -0.762)
			(end 1.524 0.762)
			(stroke
				(width 0.1524)
				(type default)
			)
			(layer "F.SilkS")
		)
		(fp_line
			(start -1.524 -0.762)
			(end 1.524 -0.762)
			(stroke
				(width 0.1524)
				(type default)
			)
			(layer "F.SilkS")
		)
		(fp_line
			(start 1.524 0.762)
			(end -1.524 0.762)
			(stroke
				(width 0.1524)
				(type default)
			)
			(layer "F.SilkS")
		)
		(fp_line
			(start -1.524 0.762)
			(end -1.524 -0.762)
			(stroke
				(width 0.1524)
				(type default)
			)
			(layer "F.SilkS")
		)
		(fp_line
			(start 1.1049 -0.724916)
			(end -1.1049 -0.724916)
			(stroke
				(width 0.1)
				(type default)
			)
			(layer "F.Fab")
		)
		(fp_line
			(start -1.1049 -0.724916)
			(end -1.1049 0.724916)
			(stroke
				(width 0.1)
				(type default)
			)
			(layer "F.Fab")
		)
		(fp_line
			(start 1.1049 0.724916)
			(end 1.1049 -0.724916)
			(stroke
				(width 0.1)
				(type default)
			)
			(layer "F.Fab")
		)
		(fp_line
			(start -1.1049 0.724916)
			(end 1.1049 0.724916)
			(stroke
				(width 0.1)
				(type default)
			)
			(layer "F.Fab")
		)
		(pad "1" smd rect
			(at -0.889 0 270)
			(size 1.016 1.27)
			(layers "F.Cu" "F.Mask" "F.Paste")
			(net "P12V_SSD7_R")
		)
		(pad "2" smd rect
			(at 0.889 0 270)
			(size 1.016 1.27)
			(layers "F.Cu" "F.Mask" "F.Paste")
			(net "GND")
		)
	)
	(footprint ""
		(layer "F.Cu")
		(at 338.074 -158.75 180)
		(property "Reference" "R4813"
			(at 0 0 180)
			(layer "F.SilkS")
			(hide yes)
			(effects
				(font
					(size 1.27 1.27)
				)
			)
		)
		(property "Value" ""
			(at 0 0 180)
			(layer "F.Fab")
			(effects
				(font
					(size 1.27 1.27)
				)
			)
		)
		(duplicate_pad_numbers_are_jumpers no)
		(fp_line
			(start 0.7874 0.4064)
			(end -0.7874 0.4064)
			(stroke
				(width 0.1524)
				(type default)
			)
			(layer "F.SilkS")
		)
		(fp_line
			(start 0.7874 -0.4064)
			(end 0.7874 0.4064)
			(stroke
				(width 0.1524)
				(type default)
			)
			(layer "F.SilkS")
		)
		(fp_line
			(start -0.7874 0.4064)
			(end -0.7874 -0.4064)
			(stroke
				(width 0.1524)
				(type default)
			)
			(layer "F.SilkS")
		)
		(fp_line
			(start -0.7874 -0.4064)
			(end 0.7874 -0.4064)
			(stroke
				(width 0.1524)
				(type default)
			)
			(layer "F.SilkS")
		)
		(fp_line
			(start 0.67945 0.3048)
			(end 0.120396 0.3048)
			(stroke
				(width 0.1)
				(type default)
			)
			(layer "F.Fab")
		)
		(fp_line
			(start 0.67945 -0.3048)
			(end 0.67945 0.3048)
			(stroke
				(width 0.1)
				(type default)
			)
			(layer "F.Fab")
		)
		(fp_line
			(start 0.12065 -0.2794)
			(end 0.12065 -0.3048)
			(stroke
				(width 0.1)
				(type default)
			)
			(layer "F.Fab")
		)
		(fp_line
			(start 0.12065 -0.3048)
			(end 0.67945 -0.3048)
			(stroke
				(width 0.1)
				(type default)
			)
			(layer "F.Fab")
		)
		(fp_line
			(start 0.120396 0.3048)
			(end 0.120396 0.2794)
			(stroke
				(width 0.1)
				(type default)
			)
			(layer "F.Fab")
		)
		(fp_line
			(start 0.120396 0.2794)
			(end -0.12065 0.2794)
			(stroke
				(width 0.1)
				(type default)
			)
			(layer "F.Fab")
		)
		(fp_line
			(start -0.12065 0.3048)
			(end -0.67945 0.3048)
			(stroke
				(width 0.1)
				(type default)
			)
			(layer "F.Fab")
		)
		(fp_line
			(start -0.12065 0.2794)
			(end -0.12065 0.3048)
			(stroke
				(width 0.1)
				(type default)
			)
			(layer "F.Fab")
		)
		(fp_line
			(start -0.12065 -0.2794)
			(end 0.12065 -0.2794)
			(stroke
				(width 0.1)
				(type default)
			)
			(layer "F.Fab")
		)
		(fp_line
			(start -0.12065 -0.305054)
			(end -0.12065 -0.2794)
			(stroke
				(width 0.1)
				(type default)
			)
			(layer "F.Fab")
		)
		(fp_line
			(start -0.67945 0.3048)
			(end -0.67945 -0.305054)
			(stroke
				(width 0.1)
				(type default)
			)
			(layer "F.Fab")
		)
		(fp_line
			(start -0.67945 -0.305054)
			(end -0.12065 -0.305054)
			(stroke
				(width 0.1)
				(type default)
			)
			(layer "F.Fab")
		)
		(pad "1" smd circle
			(at -0.40005 0 180)
			(size 0 0)
			(layers "F.Cu" "F.Mask" "F.Paste")
			(net "SSD12_PEX_PWR_EN")
		)
		(pad "2" smd circle
			(at 0.40005 0 180)
			(size 0 0)
			(layers "F.Cu" "F.Mask" "F.Paste")
			(net "SSD12_PEX_PWR_EN_R")
		)
	)
	(footprint ""
		(layer "F.Cu")
		(at 214.534496 -30.03169 180)
		(property "Reference" "C305"
			(at 0 0 180)
			(layer "F.SilkS")
			(hide yes)
			(effects
				(font
					(size 1.27 1.27)
				)
			)
		)
		(property "Value" ""
			(at 0 0 180)
			(layer "F.Fab")
			(effects
				(font
					(size 1.27 1.27)
				)
			)
		)
		(duplicate_pad_numbers_are_jumpers no)
		(fp_line
			(start 0.299974 0.150114)
			(end -0.299974 0.150114)
			(stroke
				(width 0.1)
				(type default)
			)
			(layer "F.Fab")
		)
		(fp_line
			(start 0.299974 -0.150114)
			(end 0.299974 0.150114)
			(stroke
				(width 0.1)
				(type default)
			)
			(layer "F.Fab")
		)
		(fp_line
			(start -0.299974 0.150114)
			(end -0.299974 -0.150114)
			(stroke
				(width 0.1)
				(type default)
			)
			(layer "F.Fab")
		)
		(fp_line
			(start -0.299974 -0.150114)
			(end 0.299974 -0.150114)
			(stroke
				(width 0.1)
				(type default)
			)
			(layer "F.Fab")
		)
		(pad "1" smd rect
			(at -0.2667 0 180)
			(size 0.3048 0.381)
			(layers "F.Cu" "F.Mask" "F.Paste")
			(net "P5E_PEX1_STN2_TX_DN<33>")
		)
		(pad "2" smd rect
			(at 0.2667 0 180)
			(size 0.3048 0.381)
			(layers "F.Cu" "F.Mask" "F.Paste")
			(net "P5E_PEX1_STN2_TX_C_DN<33>")
		)
	)
	(footprint ""
		(layer "F.Cu")
		(at 101.439726 -222.064072 -90)
		(property "Reference" "PR186"
			(at 0 0 270)
			(layer "F.SilkS")
			(hide yes)
			(effects
				(font
					(size 1.27 1.27)
				)
			)
		)
		(property "Value" ""
			(at 0 0 270)
			(layer "F.Fab")
			(effects
				(font
					(size 1.27 1.27)
				)
			)
		)
		(duplicate_pad_numbers_are_jumpers no)
		(fp_line
			(start -0.7874 0.4064)
			(end -0.7874 -0.4064)
			(stroke
				(width 0.1524)
				(type default)
			)
			(layer "F.SilkS")
		)
		(fp_line
			(start 0.7874 0.4064)
			(end -0.7874 0.4064)
			(stroke
				(width 0.1524)
				(type default)
			)
			(layer "F.SilkS")
		)
		(fp_line
			(start -0.7874 -0.4064)
			(end 0.7874 -0.4064)
			(stroke
				(width 0.1524)
				(type default)
			)
			(layer "F.SilkS")
		)
		(fp_line
			(start 0.7874 -0.4064)
			(end 0.7874 0.4064)
			(stroke
				(width 0.1524)
				(type default)
			)
			(layer "F.SilkS")
		)
		(fp_line
			(start -0.67945 0.3048)
			(end -0.67945 -0.305054)
			(stroke
				(width 0.1)
				(type default)
			)
			(layer "F.Fab")
		)
		(fp_line
			(start -0.12065 0.3048)
			(end -0.67945 0.3048)
			(stroke
				(width 0.1)
				(type default)
			)
			(layer "F.Fab")
		)
		(fp_line
			(start 0.120396 0.3048)
			(end 0.120396 0.2794)
			(stroke
				(width 0.1)
				(type default)
			)
			(layer "F.Fab")
		)
		(fp_line
			(start 0.67945 0.3048)
			(end 0.120396 0.3048)
			(stroke
				(width 0.1)
				(type default)
			)
			(layer "F.Fab")
		)
		(fp_line
			(start -0.12065 0.2794)
			(end -0.12065 0.3048)
			(stroke
				(width 0.1)
				(type default)
			)
			(layer "F.Fab")
		)
		(fp_line
			(start 0.120396 0.2794)
			(end -0.12065 0.2794)
			(stroke
				(width 0.1)
				(type default)
			)
			(layer "F.Fab")
		)
		(fp_line
			(start -0.12065 -0.2794)
			(end 0.12065 -0.2794)
			(stroke
				(width 0.1)
				(type default)
			)
			(layer "F.Fab")
		)
		(fp_line
			(start 0.12065 -0.2794)
			(end 0.12065 -0.3048)
			(stroke
				(width 0.1)
				(type default)
			)
			(layer "F.Fab")
		)
		(fp_line
			(start 0.12065 -0.3048)
			(end 0.67945 -0.3048)
			(stroke
				(width 0.1)
				(type default)
			)
			(layer "F.Fab")
		)
		(fp_line
			(start 0.67945 -0.3048)
			(end 0.67945 0.3048)
			(stroke
				(width 0.1)
				(type default)
			)
			(layer "F.Fab")
		)
		(fp_line
			(start -0.67945 -0.305054)
			(end -0.12065 -0.305054)
			(stroke
				(width 0.1)
				(type default)
			)
			(layer "F.Fab")
		)
		(fp_line
			(start -0.12065 -0.305054)
			(end -0.12065 -0.2794)
			(stroke
				(width 0.1)
				(type default)
			)
			(layer "F.Fab")
		)
		(pad "1" smd circle
			(at -0.40005 0 270)
			(size 0 0)
			(layers "F.Cu" "F.Mask" "F.Paste")
			(net "SH_P1V8_PEX_FB")
		)
		(pad "2" smd circle
			(at 0.40005 0 270)
			(size 0 0)
			(layers "F.Cu" "F.Mask" "F.Paste")
			(net "P1V8_PEX_FB")
		)
	)
	(footprint ""
		(layer "F.Cu")
		(at 14.708886 -251.123704 -90)
		(property "Reference" "C4244"
			(at 0 0 270)
			(layer "F.SilkS")
			(hide yes)
			(effects
				(font
					(size 1.27 1.27)
				)
			)
		)
		(property "Value" ""
			(at 0 0 270)
			(layer "F.Fab")
			(effects
				(font
					(size 1.27 1.27)
				)
			)
		)
		(duplicate_pad_numbers_are_jumpers no)
		(fp_line
			(start -1.524 0.762)
			(end -1.524 -0.762)
			(stroke
				(width 0.1524)
				(type default)
			)
			(layer "F.SilkS")
		)
		(fp_line
			(start 1.524 0.762)
			(end -1.524 0.762)
			(stroke
				(width 0.1524)
				(type default)
			)
			(layer "F.SilkS")
		)
		(fp_line
			(start -1.524 -0.762)
			(end 1.524 -0.762)
			(stroke
				(width 0.1524)
				(type default)
			)
			(layer "F.SilkS")
		)
		(fp_line
			(start 1.524 -0.762)
			(end 1.524 0.762)
			(stroke
				(width 0.1524)
				(type default)
			)
			(layer "F.SilkS")
		)
		(fp_line
			(start -1.1049 0.724916)
			(end 1.1049 0.724916)
			(stroke
				(width 0.1)
				(type default)
			)
			(layer "F.Fab")
		)
		(fp_line
			(start 1.1049 0.724916)
			(end 1.1049 -0.724916)
			(stroke
				(width 0.1)
				(type default)
			)
			(layer "F.Fab")
		)
		(fp_line
			(start -1.1049 -0.724916)
			(end -1.1049 0.724916)
			(stroke
				(width 0.1)
				(type default)
			)
			(layer "F.Fab")
		)
		(fp_line
			(start 1.1049 -0.724916)
			(end -1.1049 -0.724916)
			(stroke
				(width 0.1)
				(type default)
			)
			(layer "F.Fab")
		)
		(pad "1" smd rect
			(at -0.889 0 90)
			(size 1.016 1.27)
			(layers "F.Cu" "F.Mask" "F.Paste")
			(net "P1V25_SERDES_VDDPLL_PEX0_C10")
		)
		(pad "2" smd rect
			(at 0.889 0 90)
			(size 1.016 1.27)
			(layers "F.Cu" "F.Mask" "F.Paste")
			(net "GND")
		)
		(zone
			(layer "F.Cu")
			(hatch none 0.5)
			(connect_pads
				(clearance 0)
			)
			(min_thickness 0.25)
			(keepout
				(tracks not_allowed)
				(vias allowed)
				(pads allowed)
				(copperpour not_allowed)
				(footprints allowed)
			)
			(placement
				(enabled no)
				(sheetname "")
			)
			(fill
				(thermal_gap 0.5)
				(thermal_bridge_width 0.5)
				(island_removal_mode 0)
			)
			(polygon
				(pts
					(xy 15.433802 -251.453904) (xy 13.98397 -251.453904) (xy 13.98397 -250.793504) (xy 15.433802 -250.793504)
				)
			)
		)
	)
	(footprint ""
		(layer "F.Cu")
		(at 327.533 -220.218 180)
		(property "Reference" "R4162"
			(at 0 0 180)
			(layer "F.SilkS")
			(hide yes)
			(effects
				(font
					(size 1.27 1.27)
				)
			)
		)
		(property "Value" ""
			(at 0 0 180)
			(layer "F.Fab")
			(effects
				(font
					(size 1.27 1.27)
				)
			)
		)
		(duplicate_pad_numbers_are_jumpers no)
		(fp_line
			(start 0.7874 0.4064)
			(end -0.7874 0.4064)
			(stroke
				(width 0.1524)
				(type default)
			)
			(layer "F.SilkS")
		)
		(fp_line
			(start 0.7874 -0.4064)
			(end 0.7874 0.4064)
			(stroke
				(width 0.1524)
				(type default)
			)
			(layer "F.SilkS")
		)
		(fp_line
			(start -0.7874 0.4064)
			(end -0.7874 -0.4064)
			(stroke
				(width 0.1524)
				(type default)
			)
			(layer "F.SilkS")
		)
		(fp_line
			(start -0.7874 -0.4064)
			(end 0.7874 -0.4064)
			(stroke
				(width 0.1524)
				(type default)
			)
			(layer "F.SilkS")
		)
		(fp_line
			(start 0.67945 0.3048)
			(end 0.120396 0.3048)
			(stroke
				(width 0.1)
				(type default)
			)
			(layer "F.Fab")
		)
		(fp_line
			(start 0.67945 -0.3048)
			(end 0.67945 0.3048)
			(stroke
				(width 0.1)
				(type default)
			)
			(layer "F.Fab")
		)
		(fp_line
			(start 0.12065 -0.2794)
			(end 0.12065 -0.3048)
			(stroke
				(width 0.1)
				(type default)
			)
			(layer "F.Fab")
		)
		(fp_line
			(start 0.12065 -0.3048)
			(end 0.67945 -0.3048)
			(stroke
				(width 0.1)
				(type default)
			)
			(layer "F.Fab")
		)
		(fp_line
			(start 0.120396 0.3048)
			(end 0.120396 0.2794)
			(stroke
				(width 0.1)
				(type default)
			)
			(layer "F.Fab")
		)
		(fp_line
			(start 0.120396 0.2794)
			(end -0.12065 0.2794)
			(stroke
				(width 0.1)
				(type default)
			)
			(layer "F.Fab")
		)
		(fp_line
			(start -0.12065 0.3048)
			(end -0.67945 0.3048)
			(stroke
				(width 0.1)
				(type default)
			)
			(layer "F.Fab")
		)
		(fp_line
			(start -0.12065 0.2794)
			(end -0.12065 0.3048)
			(stroke
				(width 0.1)
				(type default)
			)
			(layer "F.Fab")
		)
		(fp_line
			(start -0.12065 -0.2794)
			(end 0.12065 -0.2794)
			(stroke
				(width 0.1)
				(type default)
			)
			(layer "F.Fab")
		)
		(fp_line
			(start -0.12065 -0.305054)
			(end -0.12065 -0.2794)
			(stroke
				(width 0.1)
				(type default)
			)
			(layer "F.Fab")
		)
		(fp_line
			(start -0.67945 0.3048)
			(end -0.67945 -0.305054)
			(stroke
				(width 0.1)
				(type default)
			)
			(layer "F.Fab")
		)
		(fp_line
			(start -0.67945 -0.305054)
			(end -0.12065 -0.305054)
			(stroke
				(width 0.1)
				(type default)
			)
			(layer "F.Fab")
		)
		(pad "1" smd circle
			(at -0.40005 0 180)
			(size 0 0)
			(layers "F.Cu" "F.Mask" "F.Paste")
			(net "PRSNT_SSD15_FPGA_N")
		)
		(pad "2" smd circle
			(at 0.40005 0 180)
			(size 0 0)
			(layers "F.Cu" "F.Mask" "F.Paste")
			(net "PRSNT_SSD15_FPGA_R_N")
		)
	)
	(footprint ""
		(layer "F.Cu")
		(at 50.481992 -38.041072 180)
		(property "Reference" "R5884"
			(at 0 0 180)
			(layer "F.SilkS")
			(hide yes)
			(effects
				(font
					(size 1.27 1.27)
				)
			)
		)
		(property "Value" ""
			(at 0 0 180)
			(layer "F.Fab")
			(effects
				(font
					(size 1.27 1.27)
				)
			)
		)
		(duplicate_pad_numbers_are_jumpers no)
		(fp_line
			(start 0.7874 0.4064)
			(end -0.7874 0.4064)
			(stroke
				(width 0.1524)
				(type default)
			)
			(layer "F.SilkS")
		)
		(fp_line
			(start 0.7874 -0.4064)
			(end 0.7874 0.4064)
			(stroke
				(width 0.1524)
				(type default)
			)
			(layer "F.SilkS")
		)
		(fp_line
			(start -0.7874 0.4064)
			(end -0.7874 -0.4064)
			(stroke
				(width 0.1524)
				(type default)
			)
			(layer "F.SilkS")
		)
		(fp_line
			(start -0.7874 -0.4064)
			(end 0.7874 -0.4064)
			(stroke
				(width 0.1524)
				(type default)
			)
			(layer "F.SilkS")
		)
		(fp_line
			(start 0.67945 0.3048)
			(end 0.120396 0.3048)
			(stroke
				(width 0.1)
				(type default)
			)
			(layer "F.Fab")
		)
		(fp_line
			(start 0.67945 -0.3048)
			(end 0.67945 0.3048)
			(stroke
				(width 0.1)
				(type default)
			)
			(layer "F.Fab")
		)
		(fp_line
			(start 0.12065 -0.2794)
			(end 0.12065 -0.3048)
			(stroke
				(width 0.1)
				(type default)
			)
			(layer "F.Fab")
		)
		(fp_line
			(start 0.12065 -0.3048)
			(end 0.67945 -0.3048)
			(stroke
				(width 0.1)
				(type default)
			)
			(layer "F.Fab")
		)
		(fp_line
			(start 0.120396 0.3048)
			(end 0.120396 0.2794)
			(stroke
				(width 0.1)
				(type default)
			)
			(layer "F.Fab")
		)
		(fp_line
			(start 0.120396 0.2794)
			(end -0.12065 0.2794)
			(stroke
				(width 0.1)
				(type default)
			)
			(layer "F.Fab")
		)
		(fp_line
			(start -0.12065 0.3048)
			(end -0.67945 0.3048)
			(stroke
				(width 0.1)
				(type default)
			)
			(layer "F.Fab")
		)
		(fp_line
			(start -0.12065 0.2794)
			(end -0.12065 0.3048)
			(stroke
				(width 0.1)
				(type default)
			)
			(layer "F.Fab")
		)
		(fp_line
			(start -0.12065 -0.2794)
			(end 0.12065 -0.2794)
			(stroke
				(width 0.1)
				(type default)
			)
			(layer "F.Fab")
		)
		(fp_line
			(start -0.12065 -0.305054)
			(end -0.12065 -0.2794)
			(stroke
				(width 0.1)
				(type default)
			)
			(layer "F.Fab")
		)
		(fp_line
			(start -0.67945 0.3048)
			(end -0.67945 -0.305054)
			(stroke
				(width 0.1)
				(type default)
			)
			(layer "F.Fab")
		)
		(fp_line
			(start -0.67945 -0.305054)
			(end -0.12065 -0.305054)
			(stroke
				(width 0.1)
				(type default)
			)
			(layer "F.Fab")
		)
		(pad "1" smd circle
			(at -0.40005 0 180)
			(size 0 0)
			(layers "F.Cu" "F.Mask" "F.Paste")
			(net "P5V_AUX")
		)
		(pad "2" smd circle
			(at 0.40005 0 180)
			(size 0 0)
			(layers "F.Cu" "F.Mask" "F.Paste")
			(net "P3V3_SSD2_PG_G2")
		)
	)
	(footprint ""
		(layer "F.Cu")
		(at 276.726396 -414.88995 -90)
		(property "Reference" "R1817"
			(at 0 0 270)
			(layer "F.SilkS")
			(hide yes)
			(effects
				(font
					(size 1.27 1.27)
				)
			)
		)
		(property "Value" ""
			(at 0 0 270)
			(layer "F.Fab")
			(effects
				(font
					(size 1.27 1.27)
				)
			)
		)
		(duplicate_pad_numbers_are_jumpers no)
		(fp_line
			(start -0.7874 0.4064)
			(end -0.7874 -0.4064)
			(stroke
				(width 0.1524)
				(type default)
			)
			(layer "F.SilkS")
		)
		(fp_line
			(start 0.7874 0.4064)
			(end -0.7874 0.4064)
			(stroke
				(width 0.1524)
				(type default)
			)
			(layer "F.SilkS")
		)
		(fp_line
			(start -0.7874 -0.4064)
			(end 0.7874 -0.4064)
			(stroke
				(width 0.1524)
				(type default)
			)
			(layer "F.SilkS")
		)
		(fp_line
			(start 0.7874 -0.4064)
			(end 0.7874 0.4064)
			(stroke
				(width 0.1524)
				(type default)
			)
			(layer "F.SilkS")
		)
		(fp_line
			(start -0.67945 0.3048)
			(end -0.67945 -0.305054)
			(stroke
				(width 0.1)
				(type default)
			)
			(layer "F.Fab")
		)
		(fp_line
			(start -0.12065 0.3048)
			(end -0.67945 0.3048)
			(stroke
				(width 0.1)
				(type default)
			)
			(layer "F.Fab")
		)
		(fp_line
			(start 0.120396 0.3048)
			(end 0.120396 0.2794)
			(stroke
				(width 0.1)
				(type default)
			)
			(layer "F.Fab")
		)
		(fp_line
			(start 0.67945 0.3048)
			(end 0.120396 0.3048)
			(stroke
				(width 0.1)
				(type default)
			)
			(layer "F.Fab")
		)
		(fp_line
			(start -0.12065 0.2794)
			(end -0.12065 0.3048)
			(stroke
				(width 0.1)
				(type default)
			)
			(layer "F.Fab")
		)
		(fp_line
			(start 0.120396 0.2794)
			(end -0.12065 0.2794)
			(stroke
				(width 0.1)
				(type default)
			)
			(layer "F.Fab")
		)
		(fp_line
			(start -0.12065 -0.2794)
			(end 0.12065 -0.2794)
			(stroke
				(width 0.1)
				(type default)
			)
			(layer "F.Fab")
		)
		(fp_line
			(start 0.12065 -0.2794)
			(end 0.12065 -0.3048)
			(stroke
				(width 0.1)
				(type default)
			)
			(layer "F.Fab")
		)
		(fp_line
			(start 0.12065 -0.3048)
			(end 0.67945 -0.3048)
			(stroke
				(width 0.1)
				(type default)
			)
			(layer "F.Fab")
		)
		(fp_line
			(start 0.67945 -0.3048)
			(end 0.67945 0.3048)
			(stroke
				(width 0.1)
				(type default)
			)
			(layer "F.Fab")
		)
		(fp_line
			(start -0.67945 -0.305054)
			(end -0.12065 -0.305054)
			(stroke
				(width 0.1)
				(type default)
			)
			(layer "F.Fab")
		)
		(fp_line
			(start -0.12065 -0.305054)
			(end -0.12065 -0.2794)
			(stroke
				(width 0.1)
				(type default)
			)
			(layer "F.Fab")
		)
		(pad "1" smd circle
			(at -0.40005 0 270)
			(size 0 0)
			(layers "F.Cu" "F.Mask" "F.Paste")
			(net "RST_MB_BMC_N")
		)
		(pad "2" smd circle
			(at 0.40005 0 270)
			(size 0 0)
			(layers "F.Cu" "F.Mask" "F.Paste")
			(net "RST_MB_BMC_R_N")
		)
	)
	(footprint ""
		(layer "F.Cu")
		(at 167.711628 -71.458074 -90)
		(property "Reference" "PD101"
			(at 4.198874 -2.825242 90)
			(unlocked yes)
			(layer "F.SilkS")
			(effects
				(font
					(size 0.7874 0.5842)
					(thickness 0.1524)
				)
				(justify left)
			)
		)
		(property "Value" ""
			(at 0 0 270)
			(layer "F.Fab")
			(effects
				(font
					(size 1.27 1.27)
				)
			)
		)
		(duplicate_pad_numbers_are_jumpers no)
		(fp_line
			(start -3.656584 1.970024)
			(end 4.240784 1.970024)
			(stroke
				(width 0.1524)
				(type default)
			)
			(layer "F.SilkS")
		)
		(fp_line
			(start 4.240784 1.970024)
			(end 4.240784 -1.970024)
			(stroke
				(width 0.1524)
				(type default)
			)
			(layer "F.SilkS")
		)
		(fp_line
			(start -3.656584 -1.970024)
			(end -3.656584 1.970024)
			(stroke
				(width 0.1524)
				(type default)
			)
			(layer "F.SilkS")
		)
		(fp_line
			(start 4.240784 -1.970024)
			(end -3.656584 -1.970024)
			(stroke
				(width 0.1524)
				(type default)
			)
			(layer "F.SilkS")
		)
		(fp_poly
			(pts
				(xy 3.580384 1.970024) (xy 3.580384 -1.970024) (xy 4.240784 -1.970024) (xy 4.240784 1.970024)
			)
			(stroke
				(width 0)
				(type default)
			)
			(fill yes)
			(layer "F.SilkS")
		)
		(fp_line
			(start -2.3749 1.970024)
			(end 2.3749 1.970024)
			(stroke
				(width 0.1)
				(type default)
			)
			(layer "F.Fab")
		)
		(fp_line
			(start 2.3749 1.970024)
			(end 2.3749 -1.970024)
			(stroke
				(width 0.1)
				(type default)
			)
			(layer "F.Fab")
		)
		(fp_line
			(start -2.3749 -1.970024)
			(end -2.3749 1.970024)
			(stroke
				(width 0.1)
				(type default)
			)
			(layer "F.Fab")
		)
		(fp_line
			(start 2.3749 -1.970024)
			(end -2.3749 -1.970024)
			(stroke
				(width 0.1)
				(type default)
			)
			(layer "F.Fab")
		)
		(fp_text user "+"
			(at -4.9784 -0.23495 270)
			(unlocked yes)
			(layer "F.Fab")
			(effects
				(font
					(size 1.905 1.4224)
					(thickness 0.1524)
				)
				(justify left)
			)
		)
		(fp_text user "-"
			(at 4.1656 -0.23495 270)
			(unlocked yes)
			(layer "F.Fab")
			(effects
				(font
					(size 1.905 1.4224)
					(thickness 0.1524)
				)
				(justify left)
			)
		)
		(pad "A" smd rect
			(at -2.450084 0 270)
			(size 2.159 2.2606)
			(layers "F.Cu" "F.Mask" "F.Paste")
			(net "GND")
		)
		(pad "C" smd rect
			(at 2.450084 0 270)
			(size 2.159 2.2606)
			(layers "F.Cu" "F.Mask" "F.Paste")
			(net "P12V_AUX")
		)
	)
	(footprint ""
		(layer "F.Cu")
		(at 396.209266 -80.356202 180)
		(property "Reference" "R1754"
			(at 0 0 180)
			(layer "F.SilkS")
			(hide yes)
			(effects
				(font
					(size 1.27 1.27)
				)
			)
		)
		(property "Value" ""
			(at 0 0 180)
			(layer "F.Fab")
			(effects
				(font
					(size 1.27 1.27)
				)
			)
		)
		(duplicate_pad_numbers_are_jumpers no)
		(fp_line
			(start 0.7874 0.4064)
			(end -0.7874 0.4064)
			(stroke
				(width 0.1524)
				(type default)
			)
			(layer "F.SilkS")
		)
		(fp_line
			(start 0.7874 -0.4064)
			(end 0.7874 0.4064)
			(stroke
				(width 0.1524)
				(type default)
			)
			(layer "F.SilkS")
		)
		(fp_line
			(start -0.7874 0.4064)
			(end -0.7874 -0.4064)
			(stroke
				(width 0.1524)
				(type default)
			)
			(layer "F.SilkS")
		)
		(fp_line
			(start -0.7874 -0.4064)
			(end 0.7874 -0.4064)
			(stroke
				(width 0.1524)
				(type default)
			)
			(layer "F.SilkS")
		)
		(fp_line
			(start 0.67945 0.3048)
			(end 0.120396 0.3048)
			(stroke
				(width 0.1)
				(type default)
			)
			(layer "F.Fab")
		)
		(fp_line
			(start 0.67945 -0.3048)
			(end 0.67945 0.3048)
			(stroke
				(width 0.1)
				(type default)
			)
			(layer "F.Fab")
		)
		(fp_line
			(start 0.12065 -0.2794)
			(end 0.12065 -0.3048)
			(stroke
				(width 0.1)
				(type default)
			)
			(layer "F.Fab")
		)
		(fp_line
			(start 0.12065 -0.3048)
			(end 0.67945 -0.3048)
			(stroke
				(width 0.1)
				(type default)
			)
			(layer "F.Fab")
		)
		(fp_line
			(start 0.120396 0.3048)
			(end 0.120396 0.2794)
			(stroke
				(width 0.1)
				(type default)
			)
			(layer "F.Fab")
		)
		(fp_line
			(start 0.120396 0.2794)
			(end -0.12065 0.2794)
			(stroke
				(width 0.1)
				(type default)
			)
			(layer "F.Fab")
		)
		(fp_line
			(start -0.12065 0.3048)
			(end -0.67945 0.3048)
			(stroke
				(width 0.1)
				(type default)
			)
			(layer "F.Fab")
		)
		(fp_line
			(start -0.12065 0.2794)
			(end -0.12065 0.3048)
			(stroke
				(width 0.1)
				(type default)
			)
			(layer "F.Fab")
		)
		(fp_line
			(start -0.12065 -0.2794)
			(end 0.12065 -0.2794)
			(stroke
				(width 0.1)
				(type default)
			)
			(layer "F.Fab")
		)
		(fp_line
			(start -0.12065 -0.305054)
			(end -0.12065 -0.2794)
			(stroke
				(width 0.1)
				(type default)
			)
			(layer "F.Fab")
		)
		(fp_line
			(start -0.67945 0.3048)
			(end -0.67945 -0.305054)
			(stroke
				(width 0.1)
				(type default)
			)
			(layer "F.Fab")
		)
		(fp_line
			(start -0.67945 -0.305054)
			(end -0.12065 -0.305054)
			(stroke
				(width 0.1)
				(type default)
			)
			(layer "F.Fab")
		)
		(pad "1" smd circle
			(at -0.40005 0 180)
			(size 0 0)
			(layers "F.Cu" "F.Mask" "F.Paste")
			(net "P3V3_AUX")
		)
		(pad "2" smd circle
			(at 0.40005 0 180)
			(size 0 0)
			(layers "F.Cu" "F.Mask" "F.Paste")
			(net "SMB_BIC_I2C6_MUX_SSD_8_15_ADC_R_SDA")
		)
	)
	(footprint ""
		(layer "F.Cu")
		(at 74.697082 -350.098614 90)
		(property "Reference" "C116"
			(at 0 0 90)
			(layer "F.SilkS")
			(hide yes)
			(effects
				(font
					(size 1.27 1.27)
				)
			)
		)
		(property "Value" ""
			(at 0 0 90)
			(layer "F.Fab")
			(effects
				(font
					(size 1.27 1.27)
				)
			)
		)
		(duplicate_pad_numbers_are_jumpers no)
		(fp_line
			(start 0.299974 -0.150114)
			(end 0.299974 0.150114)
			(stroke
				(width 0.1)
				(type default)
			)
			(layer "F.Fab")
		)
		(fp_line
			(start -0.299974 -0.150114)
			(end 0.299974 -0.150114)
			(stroke
				(width 0.1)
				(type default)
			)
			(layer "F.Fab")
		)
		(fp_line
			(start 0.299974 0.150114)
			(end -0.299974 0.150114)
			(stroke
				(width 0.1)
				(type default)
			)
			(layer "F.Fab")
		)
		(fp_line
			(start -0.299974 0.150114)
			(end -0.299974 -0.150114)
			(stroke
				(width 0.1)
				(type default)
			)
			(layer "F.Fab")
		)
		(pad "1" smd rect
			(at -0.2667 0 90)
			(size 0.3048 0.381)
			(layers "F.Cu" "F.Mask" "F.Paste")
			(net "P5E_PEX0_STN5_TX_DN<86>")
		)
		(pad "2" smd rect
			(at 0.2667 0 90)
			(size 0.3048 0.381)
			(layers "F.Cu" "F.Mask" "F.Paste")
			(net "P5E_PEX0_STN5_TX_C_DN<86>")
		)
	)
	(footprint ""
		(layer "F.Cu")
		(at 357.746808 -152.859994 180)
		(property "Reference" "PR7047"
			(at 0 0 180)
			(layer "F.SilkS")
			(hide yes)
			(effects
				(font
					(size 1.27 1.27)
				)
			)
		)
		(property "Value" ""
			(at 0 0 180)
			(layer "F.Fab")
			(effects
				(font
					(size 1.27 1.27)
				)
			)
		)
		(duplicate_pad_numbers_are_jumpers no)
		(fp_line
			(start 1.2954 0.5842)
			(end -1.2954 0.5842)
			(stroke
				(width 0.1524)
				(type default)
			)
			(layer "F.SilkS")
		)
		(fp_line
			(start 1.2954 -0.5842)
			(end 1.2954 0.5842)
			(stroke
				(width 0.1524)
				(type default)
			)
			(layer "F.SilkS")
		)
		(fp_line
			(start -1.2954 0.5842)
			(end -1.2954 -0.5842)
			(stroke
				(width 0.1524)
				(type default)
			)
			(layer "F.SilkS")
		)
		(fp_line
			(start -1.2954 -0.5842)
			(end 1.2954 -0.5842)
			(stroke
				(width 0.1524)
				(type default)
			)
			(layer "F.SilkS")
		)
		(fp_line
			(start 1.1938 0.4064)
			(end 0.8636 0.4064)
			(stroke
				(width 0.1)
				(type default)
			)
			(layer "F.Fab")
		)
		(fp_line
			(start 1.1938 -0.406654)
			(end 1.1938 0.4064)
			(stroke
				(width 0.1)
				(type default)
			)
			(layer "F.Fab")
		)
		(fp_line
			(start 0.8636 0.4572)
			(end -0.8636 0.4572)
			(stroke
				(width 0.1)
				(type default)
			)
			(layer "F.Fab")
		)
		(fp_line
			(start 0.8636 0.4064)
			(end 0.8636 0.4572)
			(stroke
				(width 0.1)
				(type default)
			)
			(layer "F.Fab")
		)
		(fp_line
			(start 0.8636 -0.406654)
			(end 1.1938 -0.406654)
			(stroke
				(width 0.1)
				(type default)
			)
			(layer "F.Fab")
		)
		(fp_line
			(start 0.8636 -0.4572)
			(end 0.8636 -0.406654)
			(stroke
				(width 0.1)
				(type default)
			)
			(layer "F.Fab")
		)
		(fp_line
			(start -0.8636 0.4572)
			(end -0.8636 0.4318)
			(stroke
				(width 0.1)
				(type default)
			)
			(layer "F.Fab")
		)
		(fp_line
			(start -0.8636 0.4318)
			(end -0.8636 0.4064)
			(stroke
				(width 0.1)
				(type default)
			)
			(layer "F.Fab")
		)
		(fp_line
			(start -0.8636 0.4064)
			(end -1.1938 0.4064)
			(stroke
				(width 0.1)
				(type default)
			)
			(layer "F.Fab")
		)
		(fp_line
			(start -0.8636 -0.406654)
			(end -0.8636 -0.4572)
			(stroke
				(width 0.1)
				(type default)
			)
			(layer "F.Fab")
		)
		(fp_line
			(start -0.8636 -0.4572)
			(end 0.8636 -0.4572)
			(stroke
				(width 0.1)
				(type default)
			)
			(layer "F.Fab")
		)
		(fp_line
			(start -1.1938 0.4064)
			(end -1.1938 -0.406654)
			(stroke
				(width 0.1)
				(type default)
			)
			(layer "F.Fab")
		)
		(fp_line
			(start -1.1938 -0.406654)
			(end -0.8636 -0.406654)
			(stroke
				(width 0.1)
				(type default)
			)
			(layer "F.Fab")
		)
		(pad "1" smd rect
			(at -0.7366 0 90)
			(size 0.7112 0.8128)
			(layers "F.Cu" "F.Mask" "F.Paste")
			(net "P12V_NIC6_CO_AVIN_PD")
		)
		(pad "2" smd rect
			(at 0.7366 0 90)
			(size 0.7112 0.8128)
			(layers "F.Cu" "F.Mask" "F.Paste")
			(net "P12V_AUX")
		)
	)
	(footprint ""
		(layer "F.Cu")
		(at 215.075516 -117.191028)
		(property "Reference" "PC494"
			(at 0 0 0)
			(layer "F.SilkS")
			(hide yes)
			(effects
				(font
					(size 1.27 1.27)
				)
			)
		)
		(property "Value" ""
			(at 0 0 0)
			(layer "F.Fab")
			(effects
				(font
					(size 1.27 1.27)
				)
			)
		)
		(duplicate_pad_numbers_are_jumpers no)
		(fp_line
			(start -0.7874 -0.4064)
			(end 0.7874 -0.4064)
			(stroke
				(width 0.1524)
				(type default)
			)
			(layer "F.SilkS")
		)
		(fp_line
			(start -0.7874 0.4064)
			(end -0.7874 -0.4064)
			(stroke
				(width 0.1524)
				(type default)
			)
			(layer "F.SilkS")
		)
		(fp_line
			(start 0.7874 -0.4064)
			(end 0.7874 0.4064)
			(stroke
				(width 0.1524)
				(type default)
			)
			(layer "F.SilkS")
		)
		(fp_line
			(start 0.7874 0.4064)
			(end -0.7874 0.4064)
			(stroke
				(width 0.1524)
				(type default)
			)
			(layer "F.SilkS")
		)
		(fp_line
			(start -0.67945 -0.305054)
			(end -0.12065 -0.305054)
			(stroke
				(width 0.1)
				(type default)
			)
			(layer "F.Fab")
		)
		(fp_line
			(start -0.67945 0.3048)
			(end -0.67945 -0.305054)
			(stroke
				(width 0.1)
				(type default)
			)
			(layer "F.Fab")
		)
		(fp_line
			(start -0.12065 -0.305054)
			(end -0.12065 -0.2794)
			(stroke
				(width 0.1)
				(type default)
			)
			(layer "F.Fab")
		)
		(fp_line
			(start -0.12065 -0.2794)
			(end 0.12065 -0.2794)
			(stroke
				(width 0.1)
				(type default)
			)
			(layer "F.Fab")
		)
		(fp_line
			(start -0.12065 0.2794)
			(end -0.12065 0.3048)
			(stroke
				(width 0.1)
				(type default)
			)
			(layer "F.Fab")
		)
		(fp_line
			(start -0.12065 0.3048)
			(end -0.67945 0.3048)
			(stroke
				(width 0.1)
				(type default)
			)
			(layer "F.Fab")
		)
		(fp_line
			(start 0.120396 0.2794)
			(end -0.12065 0.2794)
			(stroke
				(width 0.1)
				(type default)
			)
			(layer "F.Fab")
		)
		(fp_line
			(start 0.120396 0.3048)
			(end 0.120396 0.2794)
			(stroke
				(width 0.1)
				(type default)
			)
			(layer "F.Fab")
		)
		(fp_line
			(start 0.12065 -0.3048)
			(end 0.67945 -0.3048)
			(stroke
				(width 0.1)
				(type default)
			)
			(layer "F.Fab")
		)
		(fp_line
			(start 0.12065 -0.2794)
			(end 0.12065 -0.3048)
			(stroke
				(width 0.1)
				(type default)
			)
			(layer "F.Fab")
		)
		(fp_line
			(start 0.67945 -0.3048)
			(end 0.67945 0.3048)
			(stroke
				(width 0.1)
				(type default)
			)
			(layer "F.Fab")
		)
		(fp_line
			(start 0.67945 0.3048)
			(end 0.120396 0.3048)
			(stroke
				(width 0.1)
				(type default)
			)
			(layer "F.Fab")
		)
		(pad "1" smd circle
			(at -0.40005 0)
			(size 0 0)
			(layers "F.Cu" "F.Mask" "F.Paste")
			(net "P3V3_NIC3_SS")
		)
		(pad "2" smd circle
			(at 0.40005 0)
			(size 0 0)
			(layers "F.Cu" "F.Mask" "F.Paste")
			(net "GND")
		)
	)
	(footprint ""
		(layer "F.Cu")
		(at 197.972172 -32.848042 90)
		(property "Reference" "PC932"
			(at 0 0 90)
			(layer "F.SilkS")
			(hide yes)
			(effects
				(font
					(size 1.27 1.27)
				)
			)
		)
		(property "Value" ""
			(at 0 0 90)
			(layer "F.Fab")
			(effects
				(font
					(size 1.27 1.27)
				)
			)
		)
		(duplicate_pad_numbers_are_jumpers no)
		(fp_line
			(start 0.7874 -0.4064)
			(end 0.7874 0.4064)
			(stroke
				(width 0.1524)
				(type default)
			)
			(layer "F.SilkS")
		)
		(fp_line
			(start -0.7874 -0.4064)
			(end 0.7874 -0.4064)
			(stroke
				(width 0.1524)
				(type default)
			)
			(layer "F.SilkS")
		)
		(fp_line
			(start 0.7874 0.4064)
			(end -0.7874 0.4064)
			(stroke
				(width 0.1524)
				(type default)
			)
			(layer "F.SilkS")
		)
		(fp_line
			(start -0.7874 0.4064)
			(end -0.7874 -0.4064)
			(stroke
				(width 0.1524)
				(type default)
			)
			(layer "F.SilkS")
		)
		(fp_line
			(start -0.12065 -0.305054)
			(end -0.12065 -0.2794)
			(stroke
				(width 0.1)
				(type default)
			)
			(layer "F.Fab")
		)
		(fp_line
			(start -0.67945 -0.305054)
			(end -0.12065 -0.305054)
			(stroke
				(width 0.1)
				(type default)
			)
			(layer "F.Fab")
		)
		(fp_line
			(start 0.67945 -0.3048)
			(end 0.67945 0.3048)
			(stroke
				(width 0.1)
				(type default)
			)
			(layer "F.Fab")
		)
		(fp_line
			(start 0.12065 -0.3048)
			(end 0.67945 -0.3048)
			(stroke
				(width 0.1)
				(type default)
			)
			(layer "F.Fab")
		)
		(fp_line
			(start 0.12065 -0.2794)
			(end 0.12065 -0.3048)
			(stroke
				(width 0.1)
				(type default)
			)
			(layer "F.Fab")
		)
		(fp_line
			(start -0.12065 -0.2794)
			(end 0.12065 -0.2794)
			(stroke
				(width 0.1)
				(type default)
			)
			(layer "F.Fab")
		)
		(fp_line
			(start 0.120396 0.2794)
			(end -0.12065 0.2794)
			(stroke
				(width 0.1)
				(type default)
			)
			(layer "F.Fab")
		)
		(fp_line
			(start -0.12065 0.2794)
			(end -0.12065 0.3048)
			(stroke
				(width 0.1)
				(type default)
			)
			(layer "F.Fab")
		)
		(fp_line
			(start 0.67945 0.3048)
			(end 0.120396 0.3048)
			(stroke
				(width 0.1)
				(type default)
			)
			(layer "F.Fab")
		)
		(fp_line
			(start 0.120396 0.3048)
			(end 0.120396 0.2794)
			(stroke
				(width 0.1)
				(type default)
			)
			(layer "F.Fab")
		)
		(fp_line
			(start -0.12065 0.3048)
			(end -0.67945 0.3048)
			(stroke
				(width 0.1)
				(type default)
			)
			(layer "F.Fab")
		)
		(fp_line
			(start -0.67945 0.3048)
			(end -0.67945 -0.305054)
			(stroke
				(width 0.1)
				(type default)
			)
			(layer "F.Fab")
		)
		(pad "1" smd circle
			(at -0.40005 0 90)
			(size 0 0)
			(layers "F.Cu" "F.Mask" "F.Paste")
			(net "P3V3_SSD7_CO_GATE")
		)
		(pad "2" smd circle
			(at 0.40005 0 90)
			(size 0 0)
			(layers "F.Cu" "F.Mask" "F.Paste")
			(net "GND")
		)
	)
	(footprint ""
		(layer "F.Cu")
		(at 140.074142 -181.993286 180)
		(property "Reference" "R1107"
			(at 0 0 180)
			(layer "F.SilkS")
			(hide yes)
			(effects
				(font
					(size 1.27 1.27)
				)
			)
		)
		(property "Value" ""
			(at 0 0 180)
			(layer "F.Fab")
			(effects
				(font
					(size 1.27 1.27)
				)
			)
		)
		(duplicate_pad_numbers_are_jumpers no)
		(fp_line
			(start -0.7874 -0.4064)
			(end 0.7874 -0.4064)
			(stroke
				(width 0.1524)
				(type default)
			)
			(layer "F.SilkS")
		)
		(fp_line
			(start 0.67945 0.3048)
			(end 0.120396 0.3048)
			(stroke
				(width 0.1)
				(type default)
			)
			(layer "F.Fab")
		)
		(fp_line
			(start 0.67945 -0.3048)
			(end 0.67945 0.3048)
			(stroke
				(width 0.1)
				(type default)
			)
			(layer "F.Fab")
		)
		(fp_line
			(start 0.12065 -0.2794)
			(end 0.12065 -0.3048)
			(stroke
				(width 0.1)
				(type default)
			)
			(layer "F.Fab")
		)
		(fp_line
			(start 0.12065 -0.3048)
			(end 0.67945 -0.3048)
			(stroke
				(width 0.1)
				(type default)
			)
			(layer "F.Fab")
		)
		(fp_line
			(start 0.120396 0.3048)
			(end 0.120396 0.2794)
			(stroke
				(width 0.1)
				(type default)
			)
			(layer "F.Fab")
		)
		(fp_line
			(start 0.120396 0.2794)
			(end -0.12065 0.2794)
			(stroke
				(width 0.1)
				(type default)
			)
			(layer "F.Fab")
		)
		(fp_line
			(start -0.12065 0.3048)
			(end -0.67945 0.3048)
			(stroke
				(width 0.1)
				(type default)
			)
			(layer "F.Fab")
		)
		(fp_line
			(start -0.12065 0.2794)
			(end -0.12065 0.3048)
			(stroke
				(width 0.1)
				(type default)
			)
			(layer "F.Fab")
		)
		(fp_line
			(start -0.12065 -0.2794)
			(end 0.12065 -0.2794)
			(stroke
				(width 0.1)
				(type default)
			)
			(layer "F.Fab")
		)
		(fp_line
			(start -0.12065 -0.305054)
			(end -0.12065 -0.2794)
			(stroke
				(width 0.1)
				(type default)
			)
			(layer "F.Fab")
		)
		(fp_line
			(start -0.67945 0.3048)
			(end -0.67945 -0.305054)
			(stroke
				(width 0.1)
				(type default)
			)
			(layer "F.Fab")
		)
		(fp_line
			(start -0.67945 -0.305054)
			(end -0.12065 -0.305054)
			(stroke
				(width 0.1)
				(type default)
			)
			(layer "F.Fab")
		)
		(pad "1" smd circle
			(at -0.40005 0 180)
			(size 0 0)
			(layers "F.Cu" "F.Mask" "F.Paste")
			(net "CLK_100M_DB2000QL_NIC6_R_DP")
		)
		(pad "2" smd circle
			(at 0.40005 0 180)
			(size 0 0)
			(layers "F.Cu" "F.Mask" "F.Paste")
			(net "CLK_100M_DB2000QL_NIC6_DP")
		)
	)
	(footprint ""
		(layer "F.Cu")
		(at 435.055772 -350.098614 90)
		(property "Reference" "C2464"
			(at 0 0 90)
			(layer "F.SilkS")
			(hide yes)
			(effects
				(font
					(size 1.27 1.27)
				)
			)
		)
		(property "Value" ""
			(at 0 0 90)
			(layer "F.Fab")
			(effects
				(font
					(size 1.27 1.27)
				)
			)
		)
		(duplicate_pad_numbers_are_jumpers no)
		(fp_line
			(start 0.299974 -0.150114)
			(end 0.299974 0.150114)
			(stroke
				(width 0.1)
				(type default)
			)
			(layer "F.Fab")
		)
		(fp_line
			(start -0.299974 -0.150114)
			(end 0.299974 -0.150114)
			(stroke
				(width 0.1)
				(type default)
			)
			(layer "F.Fab")
		)
		(fp_line
			(start 0.299974 0.150114)
			(end -0.299974 0.150114)
			(stroke
				(width 0.1)
				(type default)
			)
			(layer "F.Fab")
		)
		(fp_line
			(start -0.299974 0.150114)
			(end -0.299974 -0.150114)
			(stroke
				(width 0.1)
				(type default)
			)
			(layer "F.Fab")
		)
		(pad "1" smd rect
			(at -0.2667 0 90)
			(size 0.3048 0.381)
			(layers "F.Cu" "F.Mask" "F.Paste")
			(net "P5E_PEX3_STN4_TX_DN<67>")
		)
		(pad "2" smd rect
			(at 0.2667 0 90)
			(size 0.3048 0.381)
			(layers "F.Cu" "F.Mask" "F.Paste")
			(net "P5E_PEX3_STN4_TX_C_DN<67>")
		)
	)
	(footprint ""
		(layer "F.Cu")
		(at 361.89031 -258.131564 180)
		(property "Reference" "R839"
			(at 0 0 180)
			(layer "F.SilkS")
			(hide yes)
			(effects
				(font
					(size 1.27 1.27)
				)
			)
		)
		(property "Value" ""
			(at 0 0 180)
			(layer "F.Fab")
			(effects
				(font
					(size 1.27 1.27)
				)
			)
		)
		(duplicate_pad_numbers_are_jumpers no)
		(fp_line
			(start 0.7874 0.4064)
			(end -0.7874 0.4064)
			(stroke
				(width 0.1524)
				(type default)
			)
			(layer "F.SilkS")
		)
		(fp_line
			(start 0.7874 -0.4064)
			(end 0.7874 0.4064)
			(stroke
				(width 0.1524)
				(type default)
			)
			(layer "F.SilkS")
		)
		(fp_line
			(start -0.7874 0.4064)
			(end -0.7874 -0.4064)
			(stroke
				(width 0.1524)
				(type default)
			)
			(layer "F.SilkS")
		)
		(fp_line
			(start -0.7874 -0.4064)
			(end 0.7874 -0.4064)
			(stroke
				(width 0.1524)
				(type default)
			)
			(layer "F.SilkS")
		)
		(fp_line
			(start 0.67945 0.3048)
			(end 0.120396 0.3048)
			(stroke
				(width 0.1)
				(type default)
			)
			(layer "F.Fab")
		)
		(fp_line
			(start 0.67945 -0.3048)
			(end 0.67945 0.3048)
			(stroke
				(width 0.1)
				(type default)
			)
			(layer "F.Fab")
		)
		(fp_line
			(start 0.12065 -0.2794)
			(end 0.12065 -0.3048)
			(stroke
				(width 0.1)
				(type default)
			)
			(layer "F.Fab")
		)
		(fp_line
			(start 0.12065 -0.3048)
			(end 0.67945 -0.3048)
			(stroke
				(width 0.1)
				(type default)
			)
			(layer "F.Fab")
		)
		(fp_line
			(start 0.120396 0.3048)
			(end 0.120396 0.2794)
			(stroke
				(width 0.1)
				(type default)
			)
			(layer "F.Fab")
		)
		(fp_line
			(start 0.120396 0.2794)
			(end -0.12065 0.2794)
			(stroke
				(width 0.1)
				(type default)
			)
			(layer "F.Fab")
		)
		(fp_line
			(start -0.12065 0.3048)
			(end -0.67945 0.3048)
			(stroke
				(width 0.1)
				(type default)
			)
			(layer "F.Fab")
		)
		(fp_line
			(start -0.12065 0.2794)
			(end -0.12065 0.3048)
			(stroke
				(width 0.1)
				(type default)
			)
			(layer "F.Fab")
		)
		(fp_line
			(start -0.12065 -0.2794)
			(end 0.12065 -0.2794)
			(stroke
				(width 0.1)
				(type default)
			)
			(layer "F.Fab")
		)
		(fp_line
			(start -0.12065 -0.305054)
			(end -0.12065 -0.2794)
			(stroke
				(width 0.1)
				(type default)
			)
			(layer "F.Fab")
		)
		(fp_line
			(start -0.67945 0.3048)
			(end -0.67945 -0.305054)
			(stroke
				(width 0.1)
				(type default)
			)
			(layer "F.Fab")
		)
		(fp_line
			(start -0.67945 -0.305054)
			(end -0.12065 -0.305054)
			(stroke
				(width 0.1)
				(type default)
			)
			(layer "F.Fab")
		)
		(pad "1" smd circle
			(at -0.40005 0 180)
			(size 0 0)
			(layers "F.Cu" "F.Mask" "F.Paste")
			(net "P3V3_AUX")
		)
		(pad "2" smd circle
			(at 0.40005 0 180)
			(size 0 0)
			(layers "F.Cu" "F.Mask" "F.Paste")
			(net "P0V8_PEX3_BVRRDY")
		)
	)
	(footprint ""
		(layer "F.Cu")
		(at 448.343274 -258.331208 -90)
		(property "Reference" "R6551"
			(at 0 0 270)
			(layer "F.SilkS")
			(hide yes)
			(effects
				(font
					(size 1.27 1.27)
				)
			)
		)
		(property "Value" ""
			(at 0 0 270)
			(layer "F.Fab")
			(effects
				(font
					(size 1.27 1.27)
				)
			)
		)
		(duplicate_pad_numbers_are_jumpers no)
		(fp_line
			(start -0.7874 0.4064)
			(end -0.7874 -0.4064)
			(stroke
				(width 0.1524)
				(type default)
			)
			(layer "F.SilkS")
		)
		(fp_line
			(start 0.7874 0.4064)
			(end -0.7874 0.4064)
			(stroke
				(width 0.1524)
				(type default)
			)
			(layer "F.SilkS")
		)
		(fp_line
			(start -0.7874 -0.4064)
			(end 0.7874 -0.4064)
			(stroke
				(width 0.1524)
				(type default)
			)
			(layer "F.SilkS")
		)
		(fp_line
			(start 0.7874 -0.4064)
			(end 0.7874 0.4064)
			(stroke
				(width 0.1524)
				(type default)
			)
			(layer "F.SilkS")
		)
		(fp_line
			(start -0.67945 0.3048)
			(end -0.67945 -0.305054)
			(stroke
				(width 0.1)
				(type default)
			)
			(layer "F.Fab")
		)
		(fp_line
			(start -0.12065 0.3048)
			(end -0.67945 0.3048)
			(stroke
				(width 0.1)
				(type default)
			)
			(layer "F.Fab")
		)
		(fp_line
			(start 0.120396 0.3048)
			(end 0.120396 0.2794)
			(stroke
				(width 0.1)
				(type default)
			)
			(layer "F.Fab")
		)
		(fp_line
			(start 0.67945 0.3048)
			(end 0.120396 0.3048)
			(stroke
				(width 0.1)
				(type default)
			)
			(layer "F.Fab")
		)
		(fp_line
			(start -0.12065 0.2794)
			(end -0.12065 0.3048)
			(stroke
				(width 0.1)
				(type default)
			)
			(layer "F.Fab")
		)
		(fp_line
			(start 0.120396 0.2794)
			(end -0.12065 0.2794)
			(stroke
				(width 0.1)
				(type default)
			)
			(layer "F.Fab")
		)
		(fp_line
			(start -0.12065 -0.2794)
			(end 0.12065 -0.2794)
			(stroke
				(width 0.1)
				(type default)
			)
			(layer "F.Fab")
		)
		(fp_line
			(start 0.12065 -0.2794)
			(end 0.12065 -0.3048)
			(stroke
				(width 0.1)
				(type default)
			)
			(layer "F.Fab")
		)
		(fp_line
			(start 0.12065 -0.3048)
			(end 0.67945 -0.3048)
			(stroke
				(width 0.1)
				(type default)
			)
			(layer "F.Fab")
		)
		(fp_line
			(start 0.67945 -0.3048)
			(end 0.67945 0.3048)
			(stroke
				(width 0.1)
				(type default)
			)
			(layer "F.Fab")
		)
		(fp_line
			(start -0.67945 -0.305054)
			(end -0.12065 -0.305054)
			(stroke
				(width 0.1)
				(type default)
			)
			(layer "F.Fab")
		)
		(fp_line
			(start -0.12065 -0.305054)
			(end -0.12065 -0.2794)
			(stroke
				(width 0.1)
				(type default)
			)
			(layer "F.Fab")
		)
		(pad "1" smd circle
			(at -0.40005 0 270)
			(size 0 0)
			(layers "F.Cu" "F.Mask" "F.Paste")
			(net "P1V25_SERDES_VDDPLL_PEX3")
		)
		(pad "2" smd circle
			(at 0.40005 0 270)
			(size 0 0)
			(layers "F.Cu" "F.Mask" "F.Paste")
			(net "P1V25_SERDES_VDDPLL_PEX3_C0")
		)
	)
	(footprint ""
		(layer "F.Cu")
		(at 51.311048 -350.098614 90)
		(property "Reference" "C162"
			(at 0 0 90)
			(layer "F.SilkS")
			(hide yes)
			(effects
				(font
					(size 1.27 1.27)
				)
			)
		)
		(property "Value" ""
			(at 0 0 90)
			(layer "F.Fab")
			(effects
				(font
					(size 1.27 1.27)
				)
			)
		)
		(duplicate_pad_numbers_are_jumpers no)
		(fp_line
			(start 0.299974 -0.150114)
			(end 0.299974 0.150114)
			(stroke
				(width 0.1)
				(type default)
			)
			(layer "F.Fab")
		)
		(fp_line
			(start -0.299974 -0.150114)
			(end 0.299974 -0.150114)
			(stroke
				(width 0.1)
				(type default)
			)
			(layer "F.Fab")
		)
		(fp_line
			(start 0.299974 0.150114)
			(end -0.299974 0.150114)
			(stroke
				(width 0.1)
				(type default)
			)
			(layer "F.Fab")
		)
		(fp_line
			(start -0.299974 0.150114)
			(end -0.299974 -0.150114)
			(stroke
				(width 0.1)
				(type default)
			)
			(layer "F.Fab")
		)
		(pad "1" smd rect
			(at -0.2667 0 90)
			(size 0.3048 0.381)
			(layers "F.Cu" "F.Mask" "F.Paste")
			(net "P5E_PEX0_STN7_TX_DN<127>")
		)
		(pad "2" smd rect
			(at 0.2667 0 90)
			(size 0.3048 0.381)
			(layers "F.Cu" "F.Mask" "F.Paste")
			(net "P5E_PEX0_STN7_TX_C_DN<127>")
		)
	)
	(footprint ""
		(layer "F.Cu")
		(at 308.31536 -42.853102 180)
		(property "Reference" "R5900"
			(at 0 0 180)
			(layer "F.SilkS")
			(hide yes)
			(effects
				(font
					(size 1.27 1.27)
				)
			)
		)
		(property "Value" ""
			(at 0 0 180)
			(layer "F.Fab")
			(effects
				(font
					(size 1.27 1.27)
				)
			)
		)
		(duplicate_pad_numbers_are_jumpers no)
		(fp_line
			(start 0.7874 0.4064)
			(end -0.7874 0.4064)
			(stroke
				(width 0.1524)
				(type default)
			)
			(layer "F.SilkS")
		)
		(fp_line
			(start 0.7874 -0.4064)
			(end 0.7874 0.4064)
			(stroke
				(width 0.1524)
				(type default)
			)
			(layer "F.SilkS")
		)
		(fp_line
			(start -0.7874 0.4064)
			(end -0.7874 -0.4064)
			(stroke
				(width 0.1524)
				(type default)
			)
			(layer "F.SilkS")
		)
		(fp_line
			(start -0.7874 -0.4064)
			(end 0.7874 -0.4064)
			(stroke
				(width 0.1524)
				(type default)
			)
			(layer "F.SilkS")
		)
		(fp_line
			(start 0.67945 0.3048)
			(end 0.120396 0.3048)
			(stroke
				(width 0.1)
				(type default)
			)
			(layer "F.Fab")
		)
		(fp_line
			(start 0.67945 -0.3048)
			(end 0.67945 0.3048)
			(stroke
				(width 0.1)
				(type default)
			)
			(layer "F.Fab")
		)
		(fp_line
			(start 0.12065 -0.2794)
			(end 0.12065 -0.3048)
			(stroke
				(width 0.1)
				(type default)
			)
			(layer "F.Fab")
		)
		(fp_line
			(start 0.12065 -0.3048)
			(end 0.67945 -0.3048)
			(stroke
				(width 0.1)
				(type default)
			)
			(layer "F.Fab")
		)
		(fp_line
			(start 0.120396 0.3048)
			(end 0.120396 0.2794)
			(stroke
				(width 0.1)
				(type default)
			)
			(layer "F.Fab")
		)
		(fp_line
			(start 0.120396 0.2794)
			(end -0.12065 0.2794)
			(stroke
				(width 0.1)
				(type default)
			)
			(layer "F.Fab")
		)
		(fp_line
			(start -0.12065 0.3048)
			(end -0.67945 0.3048)
			(stroke
				(width 0.1)
				(type default)
			)
			(layer "F.Fab")
		)
		(fp_line
			(start -0.12065 0.2794)
			(end -0.12065 0.3048)
			(stroke
				(width 0.1)
				(type default)
			)
			(layer "F.Fab")
		)
		(fp_line
			(start -0.12065 -0.2794)
			(end 0.12065 -0.2794)
			(stroke
				(width 0.1)
				(type default)
			)
			(layer "F.Fab")
		)
		(fp_line
			(start -0.12065 -0.305054)
			(end -0.12065 -0.2794)
			(stroke
				(width 0.1)
				(type default)
			)
			(layer "F.Fab")
		)
		(fp_line
			(start -0.67945 0.3048)
			(end -0.67945 -0.305054)
			(stroke
				(width 0.1)
				(type default)
			)
			(layer "F.Fab")
		)
		(fp_line
			(start -0.67945 -0.305054)
			(end -0.12065 -0.305054)
			(stroke
				(width 0.1)
				(type default)
			)
			(layer "F.Fab")
		)
		(pad "1" smd circle
			(at -0.40005 0 180)
			(size 0 0)
			(layers "F.Cu" "F.Mask" "F.Paste")
			(net "SSD10_ADC_A1")
		)
		(pad "2" smd circle
			(at 0.40005 0 180)
			(size 0 0)
			(layers "F.Cu" "F.Mask" "F.Paste")
			(net "SMB_SSD10_ADC_SDA")
		)
	)
	(footprint ""
		(layer "F.Cu")
		(at 298.57319 -213.523068 -90)
		(property "Reference" "R3399"
			(at 0 0 270)
			(layer "F.SilkS")
			(hide yes)
			(effects
				(font
					(size 1.27 1.27)
				)
			)
		)
		(property "Value" ""
			(at 0 0 270)
			(layer "F.Fab")
			(effects
				(font
					(size 1.27 1.27)
				)
			)
		)
		(duplicate_pad_numbers_are_jumpers no)
		(fp_line
			(start -0.7874 0.4064)
			(end -0.7874 -0.4064)
			(stroke
				(width 0.1524)
				(type default)
			)
			(layer "F.SilkS")
		)
		(fp_line
			(start 0.7874 0.4064)
			(end -0.7874 0.4064)
			(stroke
				(width 0.1524)
				(type default)
			)
			(layer "F.SilkS")
		)
		(fp_line
			(start -0.7874 -0.4064)
			(end 0.7874 -0.4064)
			(stroke
				(width 0.1524)
				(type default)
			)
			(layer "F.SilkS")
		)
		(fp_line
			(start 0.7874 -0.4064)
			(end 0.7874 0.4064)
			(stroke
				(width 0.1524)
				(type default)
			)
			(layer "F.SilkS")
		)
		(fp_line
			(start -0.67945 0.3048)
			(end -0.67945 -0.305054)
			(stroke
				(width 0.1)
				(type default)
			)
			(layer "F.Fab")
		)
		(fp_line
			(start -0.12065 0.3048)
			(end -0.67945 0.3048)
			(stroke
				(width 0.1)
				(type default)
			)
			(layer "F.Fab")
		)
		(fp_line
			(start 0.120396 0.3048)
			(end 0.120396 0.2794)
			(stroke
				(width 0.1)
				(type default)
			)
			(layer "F.Fab")
		)
		(fp_line
			(start 0.67945 0.3048)
			(end 0.120396 0.3048)
			(stroke
				(width 0.1)
				(type default)
			)
			(layer "F.Fab")
		)
		(fp_line
			(start -0.12065 0.2794)
			(end -0.12065 0.3048)
			(stroke
				(width 0.1)
				(type default)
			)
			(layer "F.Fab")
		)
		(fp_line
			(start 0.120396 0.2794)
			(end -0.12065 0.2794)
			(stroke
				(width 0.1)
				(type default)
			)
			(layer "F.Fab")
		)
		(fp_line
			(start -0.12065 -0.2794)
			(end 0.12065 -0.2794)
			(stroke
				(width 0.1)
				(type default)
			)
			(layer "F.Fab")
		)
		(fp_line
			(start 0.12065 -0.2794)
			(end 0.12065 -0.3048)
			(stroke
				(width 0.1)
				(type default)
			)
			(layer "F.Fab")
		)
		(fp_line
			(start 0.12065 -0.3048)
			(end 0.67945 -0.3048)
			(stroke
				(width 0.1)
				(type default)
			)
			(layer "F.Fab")
		)
		(fp_line
			(start 0.67945 -0.3048)
			(end 0.67945 0.3048)
			(stroke
				(width 0.1)
				(type default)
			)
			(layer "F.Fab")
		)
		(fp_line
			(start -0.67945 -0.305054)
			(end -0.12065 -0.305054)
			(stroke
				(width 0.1)
				(type default)
			)
			(layer "F.Fab")
		)
		(fp_line
			(start -0.12065 -0.305054)
			(end -0.12065 -0.2794)
			(stroke
				(width 0.1)
				(type default)
			)
			(layer "F.Fab")
		)
		(pad "1" smd circle
			(at -0.40005 0 270)
			(size 0 0)
			(layers "F.Cu" "F.Mask" "F.Paste")
			(net "SPI_BIC1_CLK_LS23_R2")
		)
		(pad "2" smd circle
			(at 0.40005 0 270)
			(size 0 0)
			(layers "F.Cu" "F.Mask" "F.Paste")
			(net "SPI_BIC1_CLK_LS23_R")
		)
	)
	(footprint ""
		(layer "F.Cu")
		(at 227.375466 -104.557322 -90)
		(property "Reference" "PC341"
			(at 0 0 270)
			(layer "F.SilkS")
			(hide yes)
			(effects
				(font
					(size 1.27 1.27)
				)
			)
		)
		(property "Value" ""
			(at 0 0 270)
			(layer "F.Fab")
			(effects
				(font
					(size 1.27 1.27)
				)
			)
		)
		(duplicate_pad_numbers_are_jumpers no)
		(fp_line
			(start -1.524 0.762)
			(end -1.524 -0.762)
			(stroke
				(width 0.1524)
				(type default)
			)
			(layer "F.SilkS")
		)
		(fp_line
			(start 1.524 0.762)
			(end -1.524 0.762)
			(stroke
				(width 0.1524)
				(type default)
			)
			(layer "F.SilkS")
		)
		(fp_line
			(start -1.524 -0.762)
			(end 1.524 -0.762)
			(stroke
				(width 0.1524)
				(type default)
			)
			(layer "F.SilkS")
		)
		(fp_line
			(start 1.524 -0.762)
			(end 1.524 0.762)
			(stroke
				(width 0.1524)
				(type default)
			)
			(layer "F.SilkS")
		)
		(fp_line
			(start -1.1049 0.724916)
			(end 1.1049 0.724916)
			(stroke
				(width 0.1)
				(type default)
			)
			(layer "F.Fab")
		)
		(fp_line
			(start 1.1049 0.724916)
			(end 1.1049 -0.724916)
			(stroke
				(width 0.1)
				(type default)
			)
			(layer "F.Fab")
		)
		(fp_line
			(start -1.1049 -0.724916)
			(end -1.1049 0.724916)
			(stroke
				(width 0.1)
				(type default)
			)
			(layer "F.Fab")
		)
		(fp_line
			(start 1.1049 -0.724916)
			(end -1.1049 -0.724916)
			(stroke
				(width 0.1)
				(type default)
			)
			(layer "F.Fab")
		)
		(pad "1" smd rect
			(at -0.889 0 90)
			(size 1.016 1.27)
			(layers "F.Cu" "F.Mask" "F.Paste")
			(net "GND")
		)
		(pad "2" smd rect
			(at 0.889 0 90)
			(size 1.016 1.27)
			(layers "F.Cu" "F.Mask" "F.Paste")
			(net "P12V_AUX")
		)
	)
	(footprint ""
		(layer "F.Cu")
		(at 259.130038 -290.805108 -90)
		(property "Reference" "C3381"
			(at 0 0 270)
			(layer "F.SilkS")
			(hide yes)
			(effects
				(font
					(size 1.27 1.27)
				)
			)
		)
		(property "Value" ""
			(at 0 0 270)
			(layer "F.Fab")
			(effects
				(font
					(size 1.27 1.27)
				)
			)
		)
		(duplicate_pad_numbers_are_jumpers no)
		(fp_line
			(start -1.2954 0.5842)
			(end -1.2954 -0.5842)
			(stroke
				(width 0.1524)
				(type default)
			)
			(layer "F.SilkS")
		)
		(fp_line
			(start 1.2954 0.5842)
			(end -1.2954 0.5842)
			(stroke
				(width 0.1524)
				(type default)
			)
			(layer "F.SilkS")
		)
		(fp_line
			(start -1.2954 -0.5842)
			(end 1.2954 -0.5842)
			(stroke
				(width 0.1524)
				(type default)
			)
			(layer "F.SilkS")
		)
		(fp_line
			(start 1.2954 -0.5842)
			(end 1.2954 0.5842)
			(stroke
				(width 0.1524)
				(type default)
			)
			(layer "F.SilkS")
		)
		(fp_line
			(start -0.8636 0.4572)
			(end -0.8636 0.4064)
			(stroke
				(width 0.1)
				(type default)
			)
			(layer "F.Fab")
		)
		(fp_line
			(start 0.8636 0.4572)
			(end -0.8636 0.4572)
			(stroke
				(width 0.1)
				(type default)
			)
			(layer "F.Fab")
		)
		(fp_line
			(start -1.1938 0.4064)
			(end -1.1938 -0.4064)
			(stroke
				(width 0.1)
				(type default)
			)
			(layer "F.Fab")
		)
		(fp_line
			(start -0.8636 0.4064)
			(end -1.1938 0.4064)
			(stroke
				(width 0.1)
				(type default)
			)
			(layer "F.Fab")
		)
		(fp_line
			(start 0.8636 0.4064)
			(end 0.8636 0.4572)
			(stroke
				(width 0.1)
				(type default)
			)
			(layer "F.Fab")
		)
		(fp_line
			(start 1.1938 0.4064)
			(end 0.8636 0.4064)
			(stroke
				(width 0.1)
				(type default)
			)
			(layer "F.Fab")
		)
		(fp_line
			(start -1.1938 -0.4064)
			(end -0.8636 -0.4064)
			(stroke
				(width 0.1)
				(type default)
			)
			(layer "F.Fab")
		)
		(fp_line
			(start -0.8636 -0.4064)
			(end -0.8636 -0.4572)
			(stroke
				(width 0.1)
				(type default)
			)
			(layer "F.Fab")
		)
		(fp_line
			(start 0.8636 -0.4064)
			(end 1.1938 -0.4064)
			(stroke
				(width 0.1)
				(type default)
			)
			(layer "F.Fab")
		)
		(fp_line
			(start 1.1938 -0.4064)
			(end 1.1938 0.4064)
			(stroke
				(width 0.1)
				(type default)
			)
			(layer "F.Fab")
		)
		(fp_line
			(start -0.8636 -0.4572)
			(end 0.8636 -0.4572)
			(stroke
				(width 0.1)
				(type default)
			)
			(layer "F.Fab")
		)
		(fp_line
			(start 0.8636 -0.4572)
			(end 0.8636 -0.4064)
			(stroke
				(width 0.1)
				(type default)
			)
			(layer "F.Fab")
		)
		(pad "1" smd rect
			(at -0.7366 0 180)
			(size 0.7112 0.8128)
			(layers "F.Cu" "F.Mask" "F.Paste")
			(net "P1V8_PLL0_PEX2")
		)
		(pad "2" smd rect
			(at 0.7366 0 180)
			(size 0.7112 0.8128)
			(layers "F.Cu" "F.Mask" "F.Paste")
			(net "GND")
		)
	)
	(footprint ""
		(layer "F.Cu")
		(at 21.917914 -413.969708 90)
		(property "Reference" "R5592"
			(at 0 0 90)
			(layer "F.SilkS")
			(hide yes)
			(effects
				(font
					(size 1.27 1.27)
				)
			)
		)
		(property "Value" ""
			(at 0 0 90)
			(layer "F.Fab")
			(effects
				(font
					(size 1.27 1.27)
				)
			)
		)
		(duplicate_pad_numbers_are_jumpers no)
		(fp_line
			(start 0.7874 -0.4064)
			(end 0.7874 0.4064)
			(stroke
				(width 0.1524)
				(type default)
			)
			(layer "F.SilkS")
		)
		(fp_line
			(start -0.7874 -0.4064)
			(end 0.7874 -0.4064)
			(stroke
				(width 0.1524)
				(type default)
			)
			(layer "F.SilkS")
		)
		(fp_line
			(start 0.7874 0.4064)
			(end -0.7874 0.4064)
			(stroke
				(width 0.1524)
				(type default)
			)
			(layer "F.SilkS")
		)
		(fp_line
			(start -0.7874 0.4064)
			(end -0.7874 -0.4064)
			(stroke
				(width 0.1524)
				(type default)
			)
			(layer "F.SilkS")
		)
		(fp_line
			(start -0.12065 -0.305054)
			(end -0.12065 -0.2794)
			(stroke
				(width 0.1)
				(type default)
			)
			(layer "F.Fab")
		)
		(fp_line
			(start -0.67945 -0.305054)
			(end -0.12065 -0.305054)
			(stroke
				(width 0.1)
				(type default)
			)
			(layer "F.Fab")
		)
		(fp_line
			(start 0.67945 -0.3048)
			(end 0.67945 0.3048)
			(stroke
				(width 0.1)
				(type default)
			)
			(layer "F.Fab")
		)
		(fp_line
			(start 0.12065 -0.3048)
			(end 0.67945 -0.3048)
			(stroke
				(width 0.1)
				(type default)
			)
			(layer "F.Fab")
		)
		(fp_line
			(start 0.12065 -0.2794)
			(end 0.12065 -0.3048)
			(stroke
				(width 0.1)
				(type default)
			)
			(layer "F.Fab")
		)
		(fp_line
			(start -0.12065 -0.2794)
			(end 0.12065 -0.2794)
			(stroke
				(width 0.1)
				(type default)
			)
			(layer "F.Fab")
		)
		(fp_line
			(start 0.120396 0.2794)
			(end -0.12065 0.2794)
			(stroke
				(width 0.1)
				(type default)
			)
			(layer "F.Fab")
		)
		(fp_line
			(start -0.12065 0.2794)
			(end -0.12065 0.3048)
			(stroke
				(width 0.1)
				(type default)
			)
			(layer "F.Fab")
		)
		(fp_line
			(start 0.67945 0.3048)
			(end 0.120396 0.3048)
			(stroke
				(width 0.1)
				(type default)
			)
			(layer "F.Fab")
		)
		(fp_line
			(start 0.120396 0.3048)
			(end 0.120396 0.2794)
			(stroke
				(width 0.1)
				(type default)
			)
			(layer "F.Fab")
		)
		(fp_line
			(start -0.12065 0.3048)
			(end -0.67945 0.3048)
			(stroke
				(width 0.1)
				(type default)
			)
			(layer "F.Fab")
		)
		(fp_line
			(start -0.67945 0.3048)
			(end -0.67945 -0.305054)
			(stroke
				(width 0.1)
				(type default)
			)
			(layer "F.Fab")
		)
		(pad "1" smd circle
			(at -0.40005 0 90)
			(size 0 0)
			(layers "F.Cu" "F.Mask" "F.Paste")
			(net "LM75_0_A2")
		)
		(pad "2" smd circle
			(at 0.40005 0 90)
			(size 0 0)
			(layers "F.Cu" "F.Mask" "F.Paste")
			(net "GND")
		)
	)
	(footprint ""
		(layer "F.Cu")
		(at 121.756424 -61.487812 180)
		(property "Reference" "R5972"
			(at 0 0 180)
			(layer "F.SilkS")
			(hide yes)
			(effects
				(font
					(size 1.27 1.27)
				)
			)
		)
		(property "Value" ""
			(at 0 0 180)
			(layer "F.Fab")
			(effects
				(font
					(size 1.27 1.27)
				)
			)
		)
		(duplicate_pad_numbers_are_jumpers no)
		(fp_line
			(start 0.7874 0.4064)
			(end -0.7874 0.4064)
			(stroke
				(width 0.1524)
				(type default)
			)
			(layer "F.SilkS")
		)
		(fp_line
			(start 0.7874 -0.4064)
			(end 0.7874 0.4064)
			(stroke
				(width 0.1524)
				(type default)
			)
			(layer "F.SilkS")
		)
		(fp_line
			(start -0.7874 0.4064)
			(end -0.7874 -0.4064)
			(stroke
				(width 0.1524)
				(type default)
			)
			(layer "F.SilkS")
		)
		(fp_line
			(start -0.7874 -0.4064)
			(end 0.7874 -0.4064)
			(stroke
				(width 0.1524)
				(type default)
			)
			(layer "F.SilkS")
		)
		(fp_line
			(start 0.67945 0.3048)
			(end 0.120396 0.3048)
			(stroke
				(width 0.1)
				(type default)
			)
			(layer "F.Fab")
		)
		(fp_line
			(start 0.67945 -0.3048)
			(end 0.67945 0.3048)
			(stroke
				(width 0.1)
				(type default)
			)
			(layer "F.Fab")
		)
		(fp_line
			(start 0.12065 -0.2794)
			(end 0.12065 -0.3048)
			(stroke
				(width 0.1)
				(type default)
			)
			(layer "F.Fab")
		)
		(fp_line
			(start 0.12065 -0.3048)
			(end 0.67945 -0.3048)
			(stroke
				(width 0.1)
				(type default)
			)
			(layer "F.Fab")
		)
		(fp_line
			(start 0.120396 0.3048)
			(end 0.120396 0.2794)
			(stroke
				(width 0.1)
				(type default)
			)
			(layer "F.Fab")
		)
		(fp_line
			(start 0.120396 0.2794)
			(end -0.12065 0.2794)
			(stroke
				(width 0.1)
				(type default)
			)
			(layer "F.Fab")
		)
		(fp_line
			(start -0.12065 0.3048)
			(end -0.67945 0.3048)
			(stroke
				(width 0.1)
				(type default)
			)
			(layer "F.Fab")
		)
		(fp_line
			(start -0.12065 0.2794)
			(end -0.12065 0.3048)
			(stroke
				(width 0.1)
				(type default)
			)
			(layer "F.Fab")
		)
		(fp_line
			(start -0.12065 -0.2794)
			(end 0.12065 -0.2794)
			(stroke
				(width 0.1)
				(type default)
			)
			(layer "F.Fab")
		)
		(fp_line
			(start -0.12065 -0.305054)
			(end -0.12065 -0.2794)
			(stroke
				(width 0.1)
				(type default)
			)
			(layer "F.Fab")
		)
		(fp_line
			(start -0.67945 0.3048)
			(end -0.67945 -0.305054)
			(stroke
				(width 0.1)
				(type default)
			)
			(layer "F.Fab")
		)
		(fp_line
			(start -0.67945 -0.305054)
			(end -0.12065 -0.305054)
			(stroke
				(width 0.1)
				(type default)
			)
			(layer "F.Fab")
		)
		(pad "1" smd circle
			(at -0.40005 0 180)
			(size 0 0)
			(layers "F.Cu" "F.Mask" "F.Paste")
			(net "P3V3_AUX")
		)
		(pad "2" smd circle
			(at 0.40005 0 180)
			(size 0 0)
			(layers "F.Cu" "F.Mask" "F.Paste")
			(net "PWRGD_P12V_SSD4_D")
		)
	)
	(footprint ""
		(layer "F.Cu")
		(at 314.861448 -144.396714 180)
		(property "Reference" "C436"
			(at 0 0 180)
			(layer "F.SilkS")
			(hide yes)
			(effects
				(font
					(size 1.27 1.27)
				)
			)
		)
		(property "Value" ""
			(at 0 0 180)
			(layer "F.Fab")
			(effects
				(font
					(size 1.27 1.27)
				)
			)
		)
		(duplicate_pad_numbers_are_jumpers no)
		(fp_line
			(start 0.299974 0.150114)
			(end -0.299974 0.150114)
			(stroke
				(width 0.1)
				(type default)
			)
			(layer "F.Fab")
		)
		(fp_line
			(start 0.299974 -0.150114)
			(end 0.299974 0.150114)
			(stroke
				(width 0.1)
				(type default)
			)
			(layer "F.Fab")
		)
		(fp_line
			(start -0.299974 0.150114)
			(end -0.299974 -0.150114)
			(stroke
				(width 0.1)
				(type default)
			)
			(layer "F.Fab")
		)
		(fp_line
			(start -0.299974 -0.150114)
			(end 0.299974 -0.150114)
			(stroke
				(width 0.1)
				(type default)
			)
			(layer "F.Fab")
		)
		(pad "1" smd rect
			(at -0.2667 0 180)
			(size 0.3048 0.381)
			(layers "F.Cu" "F.Mask" "F.Paste")
			(net "P5E_PEX2_STN0_TX_DN<9>")
		)
		(pad "2" smd rect
			(at 0.2667 0 180)
			(size 0.3048 0.381)
			(layers "F.Cu" "F.Mask" "F.Paste")
			(net "P5E_PEX2_STN0_TX_C_DN<9>")
		)
	)
	(footprint ""
		(layer "F.Cu")
		(at 151.209248 -453.294496)
		(property "Reference" "X21"
			(at -0.1778 -1.92913 0)
			(unlocked yes)
			(layer "F.SilkS")
			(effects
				(font
					(size 0.7874 0.5842)
					(thickness 0.1524)
				)
				(justify left)
			)
		)
		(property "Value" ""
			(at 0 0 0)
			(layer "F.Fab")
			(effects
				(font
					(size 1.27 1.27)
				)
			)
		)
		(property "Device Type" "TP_TDR_4P_FTS_MPKT4_H025P0200_IO_TP15_TP_TDR_4P_DIP"
			(at 1.30175 1.27 90)
			(unlocked yes)
			(layer "F.Fab")
			(hide yes)
			(effects
				(font
					(size 0.635 0.4064)
					(thickness 0.1524)
				)
			)
		)
		(property "User Part Number" "TP15"
			(at 1.30175 1.27 90)
			(unlocked yes)
			(layer "Cmts.User")
			(hide yes)
			(effects
				(font
					(size 0.635 0.4064)
					(thickness 0.1524)
				)
			)
		)
		(duplicate_pad_numbers_are_jumpers no)
		(fp_line
			(start 0 -1.27)
			(end 0 -0.635)
			(stroke
				(width 0.1524)
				(type default)
			)
			(layer "F.SilkS")
		)
		(fp_line
			(start 0 0.635)
			(end 0 1.905)
			(stroke
				(width 0.1524)
				(type default)
			)
			(layer "F.SilkS")
		)
		(fp_line
			(start 0 3.175)
			(end 0 3.81)
			(stroke
				(width 0.1524)
				(type default)
			)
			(layer "F.SilkS")
		)
		(fp_line
			(start 0 3.81)
			(end 2.54 3.81)
			(stroke
				(width 0.1524)
				(type default)
			)
			(layer "F.SilkS")
		)
		(fp_line
			(start 2.54 -1.27)
			(end 0 -1.27)
			(stroke
				(width 0.1524)
				(type default)
			)
			(layer "F.SilkS")
		)
		(fp_line
			(start 2.54 -1.1303)
			(end 2.54 -1.27)
			(stroke
				(width 0.1524)
				(type default)
			)
			(layer "F.SilkS")
		)
		(fp_line
			(start 2.54 1.4097)
			(end 2.54 1.1303)
			(stroke
				(width 0.1524)
				(type default)
			)
			(layer "F.SilkS")
		)
		(fp_line
			(start 2.54 3.81)
			(end 2.54 3.6703)
			(stroke
				(width 0.1524)
				(type default)
			)
			(layer "F.SilkS")
		)
		(fp_poly
			(pts
				(xy -0.761746 0) (xy -2.285746 -0.762) (xy -2.285746 0.762)
			)
			(stroke
				(width 0)
				(type default)
			)
			(fill yes)
			(layer "F.SilkS")
		)
		(fp_line
			(start 0 -1.27)
			(end 0 3.81)
			(stroke
				(width 0.1)
				(type default)
			)
			(layer "F.Fab")
		)
		(fp_line
			(start 0 3.81)
			(end 2.54 3.81)
			(stroke
				(width 0.1)
				(type default)
			)
			(layer "F.Fab")
		)
		(fp_line
			(start 2.54 -1.27)
			(end 0 -1.27)
			(stroke
				(width 0.1)
				(type default)
			)
			(layer "F.Fab")
		)
		(fp_line
			(start 2.54 3.81)
			(end 2.54 -1.27)
			(stroke
				(width 0.1)
				(type default)
			)
			(layer "F.Fab")
		)
		(fp_poly
			(pts
				(xy -0.761746 0) (xy -2.285746 -0.762) (xy -2.285746 0.762)
			)
			(stroke
				(width 0)
				(type default)
			)
			(fill yes)
			(layer "F.Fab")
		)
		(pad "1" thru_hole circle
			(at 0 0)
			(size 1.0033 1.0033)
			(drill 0.249936)
			(layers "*.Cu" "*.Mask")
			(remove_unused_layers no)
			(net "TDR_DIFF_85_IN3_DIN")
			(clearance 0.10795)
			(thermal_gap 0.10795)
			(padstack
				(mode front_inner_back)
				(layer "Inner"
					(shape circle)
					(size 0.8001 0.8001)
					(clearance 0.1524)
				)
				(layer "B.Cu"
					(shape circle)
					(size 1.0033 1.0033)
					(clearance 0.10795)
				)
			)
		)
		(pad "2" thru_hole circle
			(at 2.54 0)
			(size 1.9939 1.9939)
			(drill 0.249936)
			(layers "*.Cu" "*.Mask")
			(remove_unused_layers no)
			(net "COUPON_GND1")
			(clearance 0.10795)
			(thermal_gap 0.10795)
			(padstack
				(mode front_inner_back)
				(layer "Inner"
					(shape circle)
					(size 0.8001 0.8001)
					(clearance 0.1524)
				)
				(layer "B.Cu"
					(shape circle)
					(size 1.9939 1.9939)
					(clearance 0.10795)
				)
			)
		)
		(pad "3" thru_hole circle
			(at 2.54 2.54)
			(size 1.9939 1.9939)
			(drill 0.249936)
			(layers "*.Cu" "*.Mask")
			(remove_unused_layers no)
			(net "COUPON_GND1")
			(clearance 0.10795)
			(thermal_gap 0.10795)
			(padstack
				(mode front_inner_back)
				(layer "Inner"
					(shape circle)
					(size 0.8001 0.8001)
					(clearance 0.1524)
				)
				(layer "B.Cu"
					(shape circle)
					(size 1.9939 1.9939)
					(clearance 0.10795)
				)
			)
		)
		(pad "4" thru_hole circle
			(at 0 2.54)
			(size 1.0033 1.0033)
			(drill 0.249936)
			(layers "*.Cu" "*.Mask")
			(remove_unused_layers no)
			(net "TDR_DIFF_85_IN3_DIP")
			(clearance 0.10795)
			(thermal_gap 0.10795)
			(padstack
				(mode front_inner_back)
				(layer "Inner"
					(shape circle)
					(size 0.8001 0.8001)
					(clearance 0.1524)
				)
				(layer "B.Cu"
					(shape circle)
					(size 1.0033 1.0033)
					(clearance 0.10795)
				)
			)
		)
	)
	(footprint ""
		(layer "F.Cu")
		(at 256.542286 -252.356874 -90)
		(property "Reference" "R1365"
			(at 0 0 270)
			(layer "F.SilkS")
			(hide yes)
			(effects
				(font
					(size 1.27 1.27)
				)
			)
		)
		(property "Value" ""
			(at 0 0 270)
			(layer "F.Fab")
			(effects
				(font
					(size 1.27 1.27)
				)
			)
		)
		(duplicate_pad_numbers_are_jumpers no)
		(fp_line
			(start -0.7874 0.4064)
			(end -0.7874 -0.4064)
			(stroke
				(width 0.1524)
				(type default)
			)
			(layer "F.SilkS")
		)
		(fp_line
			(start 0.7874 0.4064)
			(end -0.7874 0.4064)
			(stroke
				(width 0.1524)
				(type default)
			)
			(layer "F.SilkS")
		)
		(fp_line
			(start -0.7874 -0.4064)
			(end 0.7874 -0.4064)
			(stroke
				(width 0.1524)
				(type default)
			)
			(layer "F.SilkS")
		)
		(fp_line
			(start 0.7874 -0.4064)
			(end 0.7874 0.4064)
			(stroke
				(width 0.1524)
				(type default)
			)
			(layer "F.SilkS")
		)
		(fp_line
			(start -0.67945 0.3048)
			(end -0.67945 -0.305054)
			(stroke
				(width 0.1)
				(type default)
			)
			(layer "F.Fab")
		)
		(fp_line
			(start -0.12065 0.3048)
			(end -0.67945 0.3048)
			(stroke
				(width 0.1)
				(type default)
			)
			(layer "F.Fab")
		)
		(fp_line
			(start 0.120396 0.3048)
			(end 0.120396 0.2794)
			(stroke
				(width 0.1)
				(type default)
			)
			(layer "F.Fab")
		)
		(fp_line
			(start 0.67945 0.3048)
			(end 0.120396 0.3048)
			(stroke
				(width 0.1)
				(type default)
			)
			(layer "F.Fab")
		)
		(fp_line
			(start -0.12065 0.2794)
			(end -0.12065 0.3048)
			(stroke
				(width 0.1)
				(type default)
			)
			(layer "F.Fab")
		)
		(fp_line
			(start 0.120396 0.2794)
			(end -0.12065 0.2794)
			(stroke
				(width 0.1)
				(type default)
			)
			(layer "F.Fab")
		)
		(fp_line
			(start -0.12065 -0.2794)
			(end 0.12065 -0.2794)
			(stroke
				(width 0.1)
				(type default)
			)
			(layer "F.Fab")
		)
		(fp_line
			(start 0.12065 -0.2794)
			(end 0.12065 -0.3048)
			(stroke
				(width 0.1)
				(type default)
			)
			(layer "F.Fab")
		)
		(fp_line
			(start 0.12065 -0.3048)
			(end 0.67945 -0.3048)
			(stroke
				(width 0.1)
				(type default)
			)
			(layer "F.Fab")
		)
		(fp_line
			(start 0.67945 -0.3048)
			(end 0.67945 0.3048)
			(stroke
				(width 0.1)
				(type default)
			)
			(layer "F.Fab")
		)
		(fp_line
			(start -0.67945 -0.305054)
			(end -0.12065 -0.305054)
			(stroke
				(width 0.1)
				(type default)
			)
			(layer "F.Fab")
		)
		(fp_line
			(start -0.12065 -0.305054)
			(end -0.12065 -0.2794)
			(stroke
				(width 0.1)
				(type default)
			)
			(layer "F.Fab")
		)
		(pad "1" smd circle
			(at -0.40005 0 270)
			(size 0 0)
			(layers "F.Cu" "F.Mask" "F.Paste")
			(net "GND")
		)
		(pad "2" smd circle
			(at 0.40005 0 270)
			(size 0 0)
			(layers "F.Cu" "F.Mask" "F.Paste")
			(net "PEX2_MODE_SEL9")
		)
	)
	(footprint ""
		(layer "F.Cu")
		(at 127.381508 -343.952322 90)
		(property "Reference" "C370"
			(at 0 0 90)
			(layer "F.SilkS")
			(hide yes)
			(effects
				(font
					(size 1.27 1.27)
				)
			)
		)
		(property "Value" ""
			(at 0 0 90)
			(layer "F.Fab")
			(effects
				(font
					(size 1.27 1.27)
				)
			)
		)
		(duplicate_pad_numbers_are_jumpers no)
		(fp_line
			(start 0.299974 -0.150114)
			(end 0.299974 0.150114)
			(stroke
				(width 0.1)
				(type default)
			)
			(layer "F.Fab")
		)
		(fp_line
			(start -0.299974 -0.150114)
			(end 0.299974 -0.150114)
			(stroke
				(width 0.1)
				(type default)
			)
			(layer "F.Fab")
		)
		(fp_line
			(start 0.299974 0.150114)
			(end -0.299974 0.150114)
			(stroke
				(width 0.1)
				(type default)
			)
			(layer "F.Fab")
		)
		(fp_line
			(start -0.299974 0.150114)
			(end -0.299974 -0.150114)
			(stroke
				(width 0.1)
				(type default)
			)
			(layer "F.Fab")
		)
		(pad "1" smd rect
			(at -0.2667 0 90)
			(size 0.3048 0.381)
			(layers "F.Cu" "F.Mask" "F.Paste")
			(net "P5E_PEX1_STN6_TX_DP<96>")
		)
		(pad "2" smd rect
			(at 0.2667 0 90)
			(size 0.3048 0.381)
			(layers "F.Cu" "F.Mask" "F.Paste")
			(net "P5E_PEX1_STN6_TX_C_DP<96>")
		)
	)
	(footprint ""
		(layer "F.Cu")
		(at 166.374064 -26.31186 -90)
		(property "Reference" "U403"
			(at -0.10414 -2.334006 90)
			(unlocked yes)
			(layer "F.SilkS")
			(effects
				(font
					(size 0.7874 0.5842)
					(thickness 0.1524)
				)
			)
		)
		(property "Value" ""
			(at 0 0 270)
			(layer "F.Fab")
			(effects
				(font
					(size 1.27 1.27)
				)
			)
		)
		(duplicate_pad_numbers_are_jumpers no)
		(fp_line
			(start -1.949958 1.610106)
			(end -1.949958 -1.610106)
			(stroke
				(width 0.1524)
				(type default)
			)
			(layer "F.SilkS")
		)
		(fp_line
			(start 1.949958 1.610106)
			(end -1.949958 1.610106)
			(stroke
				(width 0.1524)
				(type default)
			)
			(layer "F.SilkS")
		)
		(fp_line
			(start 1.949958 -1.560068)
			(end 1.949958 1.610106)
			(stroke
				(width 0.1524)
				(type default)
			)
			(layer "F.SilkS")
		)
		(fp_line
			(start -1.949958 -1.610106)
			(end 1.949958 -1.610106)
			(stroke
				(width 0.1524)
				(type default)
			)
			(layer "F.SilkS")
		)
		(fp_line
			(start -0.750062 1.560068)
			(end -0.750062 -1.560068)
			(stroke
				(width 0.1)
				(type default)
			)
			(layer "F.Fab")
		)
		(fp_line
			(start 0.750062 1.560068)
			(end -0.750062 1.560068)
			(stroke
				(width 0.1)
				(type default)
			)
			(layer "F.Fab")
		)
		(fp_line
			(start -0.750062 -1.560068)
			(end 0.750062 -1.560068)
			(stroke
				(width 0.1)
				(type default)
			)
			(layer "F.Fab")
		)
		(fp_line
			(start 0.750062 -1.560068)
			(end 0.750062 1.560068)
			(stroke
				(width 0.1)
				(type default)
			)
			(layer "F.Fab")
		)
		(pad "D" smd rect
			(at 1.100074 0 180)
			(size 1.016 1.4224)
			(layers "F.Cu" "F.Mask" "F.Paste")
			(net "SSD5_LED_ISO_N")
		)
		(pad "G" smd rect
			(at -1.100074 -0.94996 180)
			(size 1.016 1.4224)
			(layers "F.Cu" "F.Mask" "F.Paste")
			(net "SSD5_LED_R")
		)
		(pad "S" smd rect
			(at -1.100074 0.94996 180)
			(size 1.016 1.4224)
			(layers "F.Cu" "F.Mask" "F.Paste")
			(net "GND")
		)
	)
	(footprint ""
		(layer "F.Cu")
		(at 162.546538 -58.323734)
		(property "Reference" "PC379"
			(at 0 0 0)
			(layer "F.SilkS")
			(hide yes)
			(effects
				(font
					(size 1.27 1.27)
				)
			)
		)
		(property "Value" ""
			(at 0 0 0)
			(layer "F.Fab")
			(effects
				(font
					(size 1.27 1.27)
				)
			)
		)
		(duplicate_pad_numbers_are_jumpers no)
		(fp_line
			(start -1.524 -0.762)
			(end 1.524 -0.762)
			(stroke
				(width 0.1524)
				(type default)
			)
			(layer "F.SilkS")
		)
		(fp_line
			(start -1.524 0.762)
			(end -1.524 -0.762)
			(stroke
				(width 0.1524)
				(type default)
			)
			(layer "F.SilkS")
		)
		(fp_line
			(start 1.524 -0.762)
			(end 1.524 0.762)
			(stroke
				(width 0.1524)
				(type default)
			)
			(layer "F.SilkS")
		)
		(fp_line
			(start 1.524 0.762)
			(end -1.524 0.762)
			(stroke
				(width 0.1524)
				(type default)
			)
			(layer "F.SilkS")
		)
		(fp_line
			(start -1.1049 -0.724916)
			(end -1.1049 0.724916)
			(stroke
				(width 0.1)
				(type default)
			)
			(layer "F.Fab")
		)
		(fp_line
			(start -1.1049 0.724916)
			(end 1.1049 0.724916)
			(stroke
				(width 0.1)
				(type default)
			)
			(layer "F.Fab")
		)
		(fp_line
			(start 1.1049 -0.724916)
			(end -1.1049 -0.724916)
			(stroke
				(width 0.1)
				(type default)
			)
			(layer "F.Fab")
		)
		(fp_line
			(start 1.1049 0.724916)
			(end 1.1049 -0.724916)
			(stroke
				(width 0.1)
				(type default)
			)
			(layer "F.Fab")
		)
		(pad "1" smd rect
			(at -0.889 0 180)
			(size 1.016 1.27)
			(layers "F.Cu" "F.Mask" "F.Paste")
			(net "GND")
		)
		(pad "2" smd rect
			(at 0.889 0 180)
			(size 1.016 1.27)
			(layers "F.Cu" "F.Mask" "F.Paste")
			(net "P12V_AUX")
		)
	)
	(footprint ""
		(layer "F.Cu")
		(at 386.890768 8.142732 180)
		(property "Reference" "DE14T_1"
			(at 2.715768 3.061462 0)
			(unlocked yes)
			(layer "F.SilkS")
			(effects
				(font
					(size 0.7874 0.5842)
					(thickness 0.1524)
				)
				(justify left)
			)
		)
		(property "Value" ""
			(at 0 0 180)
			(layer "F.Fab")
			(effects
				(font
					(size 1.27 1.27)
				)
			)
		)
		(duplicate_pad_numbers_are_jumpers no)
		(fp_line
			(start 1.2192 2.1082)
			(end -1.2192 2.1082)
			(stroke
				(width 0.1524)
				(type default)
			)
			(layer "F.SilkS")
		)
		(fp_line
			(start 1.2192 -2.1082)
			(end 1.2192 2.1082)
			(stroke
				(width 0.1524)
				(type default)
			)
			(layer "F.SilkS")
		)
		(fp_line
			(start -1.2192 2.1082)
			(end -1.2192 -2.1082)
			(stroke
				(width 0.1524)
				(type default)
			)
			(layer "F.SilkS")
		)
		(fp_line
			(start -1.2192 -2.1082)
			(end 1.2192 -2.1082)
			(stroke
				(width 0.1524)
				(type default)
			)
			(layer "F.SilkS")
		)
		(pad "" np_thru_hole circle
			(at -2.8829 -1.27 90)
			(size 1.0414 1.0414)
			(drill 1.0414)
			(layers "*.Cu" "*.Mask")
			(clearance 0.381)
			(thermal_gap 0.381)
		)
		(pad "" np_thru_hole circle
			(at -2.8829 1.27 90)
			(size 1.0414 1.0414)
			(drill 1.0414)
			(layers "*.Cu" "*.Mask")
			(clearance 0.381)
			(thermal_gap 0.381)
		)
		(pad "" np_thru_hole circle
			(at 3.4671 -1.27 90)
			(size 1.0414 1.0414)
			(drill 1.0414)
			(layers "*.Cu" "*.Mask")
			(clearance 0.381)
			(thermal_gap 0.381)
		)
		(pad "" np_thru_hole circle
			(at 3.4671 1.27 90)
			(size 1.0414 1.0414)
			(drill 1.0414)
			(layers "*.Cu" "*.Mask")
			(clearance 0.381)
			(thermal_gap 0.381)
		)
		(pad "1" smd rect
			(at 0.8255 -0.249936 90)
			(size 0.3048 0.508)
			(layers "F.Cu" "F.Mask" "F.Paste")
			(net "85_10INCH_IN2_DP")
		)
		(pad "2" smd rect
			(at 0.8255 0.249936 90)
			(size 0.3048 0.508)
			(layers "F.Cu" "F.Mask" "F.Paste")
			(net "85_10INCH_IN2_DN")
		)
		(pad "3" smd circle
			(at 0 0 180)
			(size 0 0)
			(layers "F.Cu" "F.Mask" "F.Paste")
			(net "COUPON_GND2")
		)
		(zone
			(layer "F.Cu")
			(hatch none 0.5)
			(connect_pads
				(clearance 0)
			)
			(min_thickness 0.25)
			(keepout
				(tracks not_allowed)
				(vias allowed)
				(pads allowed)
				(copperpour not_allowed)
				(footprints allowed)
			)
			(placement
				(enabled no)
				(sheetname "")
			)
			(fill
				(thermal_gap 0.5)
				(thermal_bridge_width 0.5)
				(island_removal_mode 0)
			)
			(polygon
				(pts
					(xy 385.773168 8.691372) (xy 385.773168 8.595868) (xy 386.370068 8.595868) (xy 386.370068 8.189468)
					(xy 385.773168 8.189468) (xy 385.773168 8.095996) (xy 386.370068 8.095996) (xy 386.370068 7.689596)
					(xy 385.773168 7.689596) (xy 385.773168 7.594092) (xy 386.471668 7.594092) (xy 386.471668 8.691372)
				)
			)
		)
		(zone
			(layers "F.Cu" "B.Cu" "In1.Cu" "In2.Cu" "In3.Cu" "In4.Cu" "In5.Cu" "In6.Cu"
				"In7.Cu" "In8.Cu" "In9.Cu" "In10.Cu" "In11.Cu" "In12.Cu" "In13.Cu" "In14.Cu"
				"In15.Cu" "In16.Cu"
			)
			(hatch none 0.5)
			(connect_pads
				(clearance 0)
			)
			(min_thickness 0.25)
			(keepout
				(tracks not_allowed)
				(vias allowed)
				(pads allowed)
				(copperpour not_allowed)
				(footprints allowed)
			)
			(placement
				(enabled no)
				(sheetname "")
			)
			(fill
				(thermal_gap 0.5)
				(thermal_bridge_width 0.5)
				(island_removal_mode 0)
			)
			(polygon
				(pts
					(arc
						(start 384.350768 6.872732)
						(mid 382.496568 6.872732)
						(end 384.350768 6.872732)
					)
				)
			)
		)
		(zone
			(layers "F.Cu" "B.Cu" "In1.Cu" "In2.Cu" "In3.Cu" "In4.Cu" "In5.Cu" "In6.Cu"
				"In7.Cu" "In8.Cu" "In9.Cu" "In10.Cu" "In11.Cu" "In12.Cu" "In13.Cu" "In14.Cu"
				"In15.Cu" "In16.Cu"
			)
			(hatch none 0.5)
			(connect_pads
				(clearance 0)
			)
			(min_thickness 0.25)
			(keepout
				(tracks not_allowed)
				(vias allowed)
				(pads allowed)
				(copperpour not_allowed)
				(footprints allowed)
			)
			(placement
				(enabled no)
				(sheetname "")
			)
			(fill
				(thermal_gap 0.5)
				(thermal_bridge_width 0.5)
				(island_removal_mode 0)
			)
			(polygon
				(pts
					(arc
						(start 384.350768 9.412732)
						(mid 382.496568 9.412732)
						(end 384.350768 9.412732)
					)
				)
			)
		)
		(zone
			(layers "F.Cu" "B.Cu" "In1.Cu" "In2.Cu" "In3.Cu" "In4.Cu" "In5.Cu" "In6.Cu"
				"In7.Cu" "In8.Cu" "In9.Cu" "In10.Cu" "In11.Cu" "In12.Cu" "In13.Cu" "In14.Cu"
				"In15.Cu" "In16.Cu"
			)
			(hatch none 0.5)
			(connect_pads
				(clearance 0)
			)
			(min_thickness 0.25)
			(keepout
				(tracks not_allowed)
				(vias allowed)
				(pads allowed)
				(copperpour not_allowed)
				(footprints allowed)
			)
			(placement
				(enabled no)
				(sheetname "")
			)
			(fill
				(thermal_gap 0.5)
				(thermal_bridge_width 0.5)
				(island_removal_mode 0)
			)
			(polygon
				(pts
					(arc
						(start 390.700768 6.872732)
						(mid 388.846568 6.872732)
						(end 390.700768 6.872732)
					)
				)
			)
		)
		(zone
			(layers "F.Cu" "B.Cu" "In1.Cu" "In2.Cu" "In3.Cu" "In4.Cu" "In5.Cu" "In6.Cu"
				"In7.Cu" "In8.Cu" "In9.Cu" "In10.Cu" "In11.Cu" "In12.Cu" "In13.Cu" "In14.Cu"
				"In15.Cu" "In16.Cu"
			)
			(hatch none 0.5)
			(connect_pads
				(clearance 0)
			)
			(min_thickness 0.25)
			(keepout
				(tracks not_allowed)
				(vias allowed)
				(pads allowed)
				(copperpour not_allowed)
				(footprints allowed)
			)
			(placement
				(enabled no)
				(sheetname "")
			)
			(fill
				(thermal_gap 0.5)
				(thermal_bridge_width 0.5)
				(island_removal_mode 0)
			)
			(polygon
				(pts
					(arc
						(start 390.700768 9.412732)
						(mid 388.846568 9.412732)
						(end 390.700768 9.412732)
					)
				)
			)
		)
	)
	(footprint ""
		(layer "F.Cu")
		(at 181.728872 -343.952322 90)
		(property "Reference" "C384"
			(at 0 0 90)
			(layer "F.SilkS")
			(hide yes)
			(effects
				(font
					(size 1.27 1.27)
				)
			)
		)
		(property "Value" ""
			(at 0 0 90)
			(layer "F.Fab")
			(effects
				(font
					(size 1.27 1.27)
				)
			)
		)
		(duplicate_pad_numbers_are_jumpers no)
		(fp_line
			(start 0.299974 -0.150114)
			(end 0.299974 0.150114)
			(stroke
				(width 0.1)
				(type default)
			)
			(layer "F.Fab")
		)
		(fp_line
			(start -0.299974 -0.150114)
			(end 0.299974 -0.150114)
			(stroke
				(width 0.1)
				(type default)
			)
			(layer "F.Fab")
		)
		(fp_line
			(start 0.299974 0.150114)
			(end -0.299974 0.150114)
			(stroke
				(width 0.1)
				(type default)
			)
			(layer "F.Fab")
		)
		(fp_line
			(start -0.299974 0.150114)
			(end -0.299974 -0.150114)
			(stroke
				(width 0.1)
				(type default)
			)
			(layer "F.Fab")
		)
		(pad "1" smd rect
			(at -0.2667 0 90)
			(size 0.3048 0.381)
			(layers "F.Cu" "F.Mask" "F.Paste")
			(net "P5E_PEX1_STN7_TX_DP<121>")
		)
		(pad "2" smd rect
			(at 0.2667 0 90)
			(size 0.3048 0.381)
			(layers "F.Cu" "F.Mask" "F.Paste")
			(net "P5E_PEX1_STN7_TX_C_DP<121>")
		)
	)
	(footprint ""
		(layer "F.Cu")
		(at 116.985796 -318.514984 90)
		(property "Reference" "R6460"
			(at 0 0 90)
			(layer "F.SilkS")
			(hide yes)
			(effects
				(font
					(size 1.27 1.27)
				)
			)
		)
		(property "Value" ""
			(at 0 0 90)
			(layer "F.Fab")
			(effects
				(font
					(size 1.27 1.27)
				)
			)
		)
		(duplicate_pad_numbers_are_jumpers no)
		(fp_line
			(start 0.7874 -0.4064)
			(end 0.7874 0.4064)
			(stroke
				(width 0.1524)
				(type default)
			)
			(layer "F.SilkS")
		)
		(fp_line
			(start -0.7874 -0.4064)
			(end 0.7874 -0.4064)
			(stroke
				(width 0.1524)
				(type default)
			)
			(layer "F.SilkS")
		)
		(fp_line
			(start 0.7874 0.4064)
			(end -0.7874 0.4064)
			(stroke
				(width 0.1524)
				(type default)
			)
			(layer "F.SilkS")
		)
		(fp_line
			(start -0.7874 0.4064)
			(end -0.7874 -0.4064)
			(stroke
				(width 0.1524)
				(type default)
			)
			(layer "F.SilkS")
		)
		(fp_line
			(start -0.12065 -0.305054)
			(end -0.12065 -0.2794)
			(stroke
				(width 0.1)
				(type default)
			)
			(layer "F.Fab")
		)
		(fp_line
			(start -0.67945 -0.305054)
			(end -0.12065 -0.305054)
			(stroke
				(width 0.1)
				(type default)
			)
			(layer "F.Fab")
		)
		(fp_line
			(start 0.67945 -0.3048)
			(end 0.67945 0.3048)
			(stroke
				(width 0.1)
				(type default)
			)
			(layer "F.Fab")
		)
		(fp_line
			(start 0.12065 -0.3048)
			(end 0.67945 -0.3048)
			(stroke
				(width 0.1)
				(type default)
			)
			(layer "F.Fab")
		)
		(fp_line
			(start 0.12065 -0.2794)
			(end 0.12065 -0.3048)
			(stroke
				(width 0.1)
				(type default)
			)
			(layer "F.Fab")
		)
		(fp_line
			(start -0.12065 -0.2794)
			(end 0.12065 -0.2794)
			(stroke
				(width 0.1)
				(type default)
			)
			(layer "F.Fab")
		)
		(fp_line
			(start 0.120396 0.2794)
			(end -0.12065 0.2794)
			(stroke
				(width 0.1)
				(type default)
			)
			(layer "F.Fab")
		)
		(fp_line
			(start -0.12065 0.2794)
			(end -0.12065 0.3048)
			(stroke
				(width 0.1)
				(type default)
			)
			(layer "F.Fab")
		)
		(fp_line
			(start 0.67945 0.3048)
			(end 0.120396 0.3048)
			(stroke
				(width 0.1)
				(type default)
			)
			(layer "F.Fab")
		)
		(fp_line
			(start 0.120396 0.3048)
			(end 0.120396 0.2794)
			(stroke
				(width 0.1)
				(type default)
			)
			(layer "F.Fab")
		)
		(fp_line
			(start -0.12065 0.3048)
			(end -0.67945 0.3048)
			(stroke
				(width 0.1)
				(type default)
			)
			(layer "F.Fab")
		)
		(fp_line
			(start -0.67945 0.3048)
			(end -0.67945 -0.305054)
			(stroke
				(width 0.1)
				(type default)
			)
			(layer "F.Fab")
		)
		(pad "1" smd circle
			(at -0.40005 0 90)
			(size 0 0)
			(layers "F.Cu" "F.Mask" "F.Paste")
			(net "P0V8_SERDES_VDDA_PEX0")
		)
		(pad "2" smd circle
			(at 0.40005 0 90)
			(size 0 0)
			(layers "F.Cu" "F.Mask" "F.Paste")
			(net "P0V8_SERDES_VDDA_PEX0_C11")
		)
	)
	(footprint ""
		(layer "F.Cu")
		(at 189.88786 -414.581086 -90)
		(property "Reference" "R6780"
			(at 0 0 270)
			(layer "F.SilkS")
			(hide yes)
			(effects
				(font
					(size 1.27 1.27)
				)
			)
		)
		(property "Value" ""
			(at 0 0 270)
			(layer "F.Fab")
			(effects
				(font
					(size 1.27 1.27)
				)
			)
		)
		(duplicate_pad_numbers_are_jumpers no)
		(fp_line
			(start -0.7874 0.4064)
			(end -0.7874 -0.4064)
			(stroke
				(width 0.1524)
				(type default)
			)
			(layer "F.SilkS")
		)
		(fp_line
			(start 0.7874 0.4064)
			(end -0.7874 0.4064)
			(stroke
				(width 0.1524)
				(type default)
			)
			(layer "F.SilkS")
		)
		(fp_line
			(start -0.7874 -0.4064)
			(end 0.7874 -0.4064)
			(stroke
				(width 0.1524)
				(type default)
			)
			(layer "F.SilkS")
		)
		(fp_line
			(start 0.7874 -0.4064)
			(end 0.7874 0.4064)
			(stroke
				(width 0.1524)
				(type default)
			)
			(layer "F.SilkS")
		)
		(fp_line
			(start -0.67945 0.3048)
			(end -0.67945 -0.305054)
			(stroke
				(width 0.1)
				(type default)
			)
			(layer "F.Fab")
		)
		(fp_line
			(start -0.12065 0.3048)
			(end -0.67945 0.3048)
			(stroke
				(width 0.1)
				(type default)
			)
			(layer "F.Fab")
		)
		(fp_line
			(start 0.120396 0.3048)
			(end 0.120396 0.2794)
			(stroke
				(width 0.1)
				(type default)
			)
			(layer "F.Fab")
		)
		(fp_line
			(start 0.67945 0.3048)
			(end 0.120396 0.3048)
			(stroke
				(width 0.1)
				(type default)
			)
			(layer "F.Fab")
		)
		(fp_line
			(start -0.12065 0.2794)
			(end -0.12065 0.3048)
			(stroke
				(width 0.1)
				(type default)
			)
			(layer "F.Fab")
		)
		(fp_line
			(start 0.120396 0.2794)
			(end -0.12065 0.2794)
			(stroke
				(width 0.1)
				(type default)
			)
			(layer "F.Fab")
		)
		(fp_line
			(start -0.12065 -0.2794)
			(end 0.12065 -0.2794)
			(stroke
				(width 0.1)
				(type default)
			)
			(layer "F.Fab")
		)
		(fp_line
			(start 0.12065 -0.2794)
			(end 0.12065 -0.3048)
			(stroke
				(width 0.1)
				(type default)
			)
			(layer "F.Fab")
		)
		(fp_line
			(start 0.12065 -0.3048)
			(end 0.67945 -0.3048)
			(stroke
				(width 0.1)
				(type default)
			)
			(layer "F.Fab")
		)
		(fp_line
			(start 0.67945 -0.3048)
			(end 0.67945 0.3048)
			(stroke
				(width 0.1)
				(type default)
			)
			(layer "F.Fab")
		)
		(fp_line
			(start -0.67945 -0.305054)
			(end -0.12065 -0.305054)
			(stroke
				(width 0.1)
				(type default)
			)
			(layer "F.Fab")
		)
		(fp_line
			(start -0.12065 -0.305054)
			(end -0.12065 -0.2794)
			(stroke
				(width 0.1)
				(type default)
			)
			(layer "F.Fab")
		)
		(pad "1" smd circle
			(at -0.40005 0 270)
			(size 0 0)
			(layers "F.Cu" "F.Mask" "F.Paste")
			(net "P12V_AUX_FP_TRIGGER")
		)
		(pad "2" smd circle
			(at 0.40005 0 270)
			(size 0 0)
			(layers "F.Cu" "F.Mask" "F.Paste")
			(net "GND")
		)
	)
	(footprint ""
		(layer "F.Cu")
		(at 74.845926 -46.4439 180)
		(property "Reference" "U55"
			(at 0.017526 -2.40157 0)
			(unlocked yes)
			(layer "F.SilkS")
			(effects
				(font
					(size 0.7874 0.5842)
					(thickness 0.1524)
				)
			)
		)
		(property "Value" ""
			(at 0 0 180)
			(layer "F.Fab")
			(effects
				(font
					(size 1.27 1.27)
				)
			)
		)
		(duplicate_pad_numbers_are_jumpers no)
		(fp_line
			(start 1.500124 1.500124)
			(end 1.004062 1.500124)
			(stroke
				(width 0.1524)
				(type default)
			)
			(layer "F.SilkS")
		)
		(fp_line
			(start 1.500124 1.004062)
			(end 1.500124 1.500124)
			(stroke
				(width 0.1524)
				(type default)
			)
			(layer "F.SilkS")
		)
		(fp_line
			(start 1.500124 -1.500124)
			(end 1.500124 -1.004062)
			(stroke
				(width 0.1524)
				(type default)
			)
			(layer "F.SilkS")
		)
		(fp_line
			(start 1.004062 -1.500124)
			(end 1.500124 -1.500124)
			(stroke
				(width 0.1524)
				(type default)
			)
			(layer "F.SilkS")
		)
		(fp_line
			(start -1.004062 1.500124)
			(end -1.500124 1.500124)
			(stroke
				(width 0.1524)
				(type default)
			)
			(layer "F.SilkS")
		)
		(fp_line
			(start -1.500124 1.500124)
			(end -1.500124 1.004062)
			(stroke
				(width 0.1524)
				(type default)
			)
			(layer "F.SilkS")
		)
		(fp_line
			(start -1.500124 -1.004062)
			(end -1.500124 -1.500124)
			(stroke
				(width 0.1524)
				(type default)
			)
			(layer "F.SilkS")
		)
		(fp_line
			(start -1.500124 -1.500124)
			(end -1.004062 -1.500124)
			(stroke
				(width 0.1524)
				(type default)
			)
			(layer "F.SilkS")
		)
		(fp_poly
			(pts
				(xy -1.852676 -2.264918) (xy -2.570988 -1.546352) (xy -1.49352 -1.187196)
			)
			(stroke
				(width 0)
				(type default)
			)
			(fill yes)
			(layer "F.SilkS")
		)
		(fp_line
			(start 1.500124 1.500124)
			(end -1.500124 1.500124)
			(stroke
				(width 0.1)
				(type default)
			)
			(layer "F.Fab")
		)
		(fp_line
			(start 1.500124 -1.500124)
			(end 1.500124 1.500124)
			(stroke
				(width 0.1)
				(type default)
			)
			(layer "F.Fab")
		)
		(fp_line
			(start -1.500124 1.500124)
			(end -1.500124 -1.500124)
			(stroke
				(width 0.1)
				(type default)
			)
			(layer "F.Fab")
		)
		(fp_line
			(start -1.500124 -1.500124)
			(end 1.500124 -1.500124)
			(stroke
				(width 0.1)
				(type default)
			)
			(layer "F.Fab")
		)
		(fp_poly
			(pts
				(xy -2.847848 -1.258062) (xy -2.847848 -0.242062) (xy -1.831848 -0.750062)
			)
			(stroke
				(width 0)
				(type default)
			)
			(fill yes)
			(layer "F.Fab")
		)
		(pad "1" smd rect
			(at -1.400048 -0.750062 90)
			(size 0.2286 0.6096)
			(layers "F.Cu" "F.Mask" "F.Paste")
			(net "SSD2_ADC_A1")
		)
		(pad "2" smd rect
			(at -1.400048 -0.249936 90)
			(size 0.2286 0.6096)
			(layers "F.Cu" "F.Mask" "F.Paste")
			(net "SSD2_ADC_A0")
		)
		(pad "3" smd rect
			(at -1.400048 0.249936 90)
			(size 0.2286 0.6096)
			(layers "F.Cu" "F.Mask" "F.Paste")
			(net "SSD2_ADC_ALERT_N")
		)
		(pad "4" smd rect
			(at -1.400048 0.750062 90)
			(size 0.2286 0.6096)
			(layers "F.Cu" "F.Mask" "F.Paste")
			(net "SMB_SSD2_ADC_SDA")
		)
		(pad "5" smd rect
			(at -0.750062 1.400048 180)
			(size 0.2286 0.6096)
			(layers "F.Cu" "F.Mask" "F.Paste")
			(net "SMB_SSD2_ADC_SCL")
		)
		(pad "6" smd rect
			(at -0.249936 1.400048 180)
			(size 0.2286 0.6096)
			(layers "F.Cu" "F.Mask" "F.Paste")
			(net "Net_4621")
		)
		(pad "7" smd rect
			(at 0.249936 1.400048 180)
			(size 0.2286 0.6096)
			(layers "F.Cu" "F.Mask" "F.Paste")
			(net "Net_4622")
		)
		(pad "8" smd rect
			(at 0.750062 1.400048 180)
			(size 0.2286 0.6096)
			(layers "F.Cu" "F.Mask" "F.Paste")
			(net "Net_4623")
		)
		(pad "9" smd rect
			(at 1.400048 0.750062 90)
			(size 0.2286 0.6096)
			(layers "F.Cu" "F.Mask" "F.Paste")
			(net "P3V3_AUX")
		)
		(pad "10" smd rect
			(at 1.400048 0.249936 90)
			(size 0.2286 0.6096)
			(layers "F.Cu" "F.Mask" "F.Paste")
			(net "GND")
		)
		(pad "11" smd rect
			(at 1.400048 -0.249936 90)
			(size 0.2286 0.6096)
			(layers "F.Cu" "F.Mask" "F.Paste")
			(net "P12V_SSD2_R")
		)
		(pad "12" smd rect
			(at 1.400048 -0.750062 90)
			(size 0.2286 0.6096)
			(layers "F.Cu" "F.Mask" "F.Paste")
			(net "P12V_SSD2_VIN_N")
		)
		(pad "13" smd rect
			(at 0.750062 -1.400048 180)
			(size 0.2286 0.6096)
			(layers "F.Cu" "F.Mask" "F.Paste")
			(net "P12V_SSD2_VIN_P")
		)
		(pad "14" smd rect
			(at 0.249936 -1.400048 180)
			(size 0.2286 0.6096)
			(layers "F.Cu" "F.Mask" "F.Paste")
			(net "Net_4624")
		)
		(pad "15" smd rect
			(at -0.249936 -1.400048 180)
			(size 0.2286 0.6096)
			(layers "F.Cu" "F.Mask" "F.Paste")
			(net "Net_4625")
		)
		(pad "16" smd rect
			(at -0.750062 -1.400048 180)
			(size 0.2286 0.6096)
			(layers "F.Cu" "F.Mask" "F.Paste")
			(net "Net_4626")
		)
		(pad "TH" smd rect
			(at 0 0 180)
			(size 1.7018 1.7018)
			(layers "F.Cu" "F.Mask" "F.Paste")
			(net "GND")
		)
		(zone
			(layer "F.Cu")
			(hatch none 0.5)
			(connect_pads
				(clearance 0)
			)
			(min_thickness 0.25)
			(keepout
				(tracks not_allowed)
				(vias allowed)
				(pads allowed)
				(copperpour not_allowed)
				(footprints allowed)
			)
			(placement
				(enabled no)
				(sheetname "")
			)
			(fill
				(thermal_gap 0.5)
				(thermal_bridge_width 0.5)
				(island_removal_mode 0)
			)
			(polygon
				(pts
					(xy 75.890374 -46.4185) (xy 75.890374 -45.399452) (xy 73.801478 -45.399452) (xy 73.801478 -47.488348)
					(xy 75.890374 -47.488348) (xy 75.890374 -46.4439) (xy 75.747626 -46.4439) (xy 75.747626 -47.3456)
					(xy 73.944226 -47.3456) (xy 73.944226 -45.5422) (xy 75.747626 -45.5422) (xy 75.747626 -46.4185)
				)
			)
		)
	)
	(footprint ""
		(layer "F.Cu")
		(at 148.270468 -392.75639 -90)
		(property "Reference" "C4064"
			(at 0 0 270)
			(layer "F.SilkS")
			(hide yes)
			(effects
				(font
					(size 1.27 1.27)
				)
			)
		)
		(property "Value" ""
			(at 0 0 270)
			(layer "F.Fab")
			(effects
				(font
					(size 1.27 1.27)
				)
			)
		)
		(duplicate_pad_numbers_are_jumpers no)
		(fp_line
			(start -0.7874 0.4064)
			(end -0.7874 -0.4064)
			(stroke
				(width 0.1524)
				(type default)
			)
			(layer "F.SilkS")
		)
		(fp_line
			(start 0.7874 0.4064)
			(end -0.7874 0.4064)
			(stroke
				(width 0.1524)
				(type default)
			)
			(layer "F.SilkS")
		)
		(fp_line
			(start -0.7874 -0.4064)
			(end 0.7874 -0.4064)
			(stroke
				(width 0.1524)
				(type default)
			)
			(layer "F.SilkS")
		)
		(fp_line
			(start 0.7874 -0.4064)
			(end 0.7874 0.4064)
			(stroke
				(width 0.1524)
				(type default)
			)
			(layer "F.SilkS")
		)
		(fp_line
			(start -0.67945 0.3048)
			(end -0.67945 -0.305054)
			(stroke
				(width 0.1)
				(type default)
			)
			(layer "F.Fab")
		)
		(fp_line
			(start -0.12065 0.3048)
			(end -0.67945 0.3048)
			(stroke
				(width 0.1)
				(type default)
			)
			(layer "F.Fab")
		)
		(fp_line
			(start 0.120396 0.3048)
			(end 0.120396 0.2794)
			(stroke
				(width 0.1)
				(type default)
			)
			(layer "F.Fab")
		)
		(fp_line
			(start 0.67945 0.3048)
			(end 0.120396 0.3048)
			(stroke
				(width 0.1)
				(type default)
			)
			(layer "F.Fab")
		)
		(fp_line
			(start -0.12065 0.2794)
			(end -0.12065 0.3048)
			(stroke
				(width 0.1)
				(type default)
			)
			(layer "F.Fab")
		)
		(fp_line
			(start 0.120396 0.2794)
			(end -0.12065 0.2794)
			(stroke
				(width 0.1)
				(type default)
			)
			(layer "F.Fab")
		)
		(fp_line
			(start -0.12065 -0.2794)
			(end 0.12065 -0.2794)
			(stroke
				(width 0.1)
				(type default)
			)
			(layer "F.Fab")
		)
		(fp_line
			(start 0.12065 -0.2794)
			(end 0.12065 -0.3048)
			(stroke
				(width 0.1)
				(type default)
			)
			(layer "F.Fab")
		)
		(fp_line
			(start 0.12065 -0.3048)
			(end 0.67945 -0.3048)
			(stroke
				(width 0.1)
				(type default)
			)
			(layer "F.Fab")
		)
		(fp_line
			(start 0.67945 -0.3048)
			(end 0.67945 0.3048)
			(stroke
				(width 0.1)
				(type default)
			)
			(layer "F.Fab")
		)
		(fp_line
			(start -0.67945 -0.305054)
			(end -0.12065 -0.305054)
			(stroke
				(width 0.1)
				(type default)
			)
			(layer "F.Fab")
		)
		(fp_line
			(start -0.12065 -0.305054)
			(end -0.12065 -0.2794)
			(stroke
				(width 0.1)
				(type default)
			)
			(layer "F.Fab")
		)
		(pad "1" smd circle
			(at -0.40005 0 270)
			(size 0 0)
			(layers "F.Cu" "F.Mask" "F.Paste")
			(net "GND")
		)
		(pad "2" smd circle
			(at 0.40005 0 270)
			(size 0 0)
			(layers "F.Cu" "F.Mask" "F.Paste")
			(net "GPU_BASE_STBY_EN")
		)
	)
	(footprint ""
		(layer "F.Cu")
		(at 165.75659 -17.419574 180)
		(property "Reference" "R1663"
			(at 0 0 180)
			(layer "F.SilkS")
			(hide yes)
			(effects
				(font
					(size 1.27 1.27)
				)
			)
		)
		(property "Value" ""
			(at 0 0 180)
			(layer "F.Fab")
			(effects
				(font
					(size 1.27 1.27)
				)
			)
		)
		(duplicate_pad_numbers_are_jumpers no)
		(fp_line
			(start 0.7874 0.4064)
			(end -0.7874 0.4064)
			(stroke
				(width 0.1524)
				(type default)
			)
			(layer "F.SilkS")
		)
		(fp_line
			(start 0.7874 -0.4064)
			(end 0.7874 0.4064)
			(stroke
				(width 0.1524)
				(type default)
			)
			(layer "F.SilkS")
		)
		(fp_line
			(start -0.7874 0.4064)
			(end -0.7874 -0.4064)
			(stroke
				(width 0.1524)
				(type default)
			)
			(layer "F.SilkS")
		)
		(fp_line
			(start -0.7874 -0.4064)
			(end 0.7874 -0.4064)
			(stroke
				(width 0.1524)
				(type default)
			)
			(layer "F.SilkS")
		)
		(fp_line
			(start 0.67945 0.3048)
			(end 0.120396 0.3048)
			(stroke
				(width 0.1)
				(type default)
			)
			(layer "F.Fab")
		)
		(fp_line
			(start 0.67945 -0.3048)
			(end 0.67945 0.3048)
			(stroke
				(width 0.1)
				(type default)
			)
			(layer "F.Fab")
		)
		(fp_line
			(start 0.12065 -0.2794)
			(end 0.12065 -0.3048)
			(stroke
				(width 0.1)
				(type default)
			)
			(layer "F.Fab")
		)
		(fp_line
			(start 0.12065 -0.3048)
			(end 0.67945 -0.3048)
			(stroke
				(width 0.1)
				(type default)
			)
			(layer "F.Fab")
		)
		(fp_line
			(start 0.120396 0.3048)
			(end 0.120396 0.2794)
			(stroke
				(width 0.1)
				(type default)
			)
			(layer "F.Fab")
		)
		(fp_line
			(start 0.120396 0.2794)
			(end -0.12065 0.2794)
			(stroke
				(width 0.1)
				(type default)
			)
			(layer "F.Fab")
		)
		(fp_line
			(start -0.12065 0.3048)
			(end -0.67945 0.3048)
			(stroke
				(width 0.1)
				(type default)
			)
			(layer "F.Fab")
		)
		(fp_line
			(start -0.12065 0.2794)
			(end -0.12065 0.3048)
			(stroke
				(width 0.1)
				(type default)
			)
			(layer "F.Fab")
		)
		(fp_line
			(start -0.12065 -0.2794)
			(end 0.12065 -0.2794)
			(stroke
				(width 0.1)
				(type default)
			)
			(layer "F.Fab")
		)
		(fp_line
			(start -0.12065 -0.305054)
			(end -0.12065 -0.2794)
			(stroke
				(width 0.1)
				(type default)
			)
			(layer "F.Fab")
		)
		(fp_line
			(start -0.67945 0.3048)
			(end -0.67945 -0.305054)
			(stroke
				(width 0.1)
				(type default)
			)
			(layer "F.Fab")
		)
		(fp_line
			(start -0.67945 -0.305054)
			(end -0.12065 -0.305054)
			(stroke
				(width 0.1)
				(type default)
			)
			(layer "F.Fab")
		)
		(pad "1" smd circle
			(at -0.40005 0 180)
			(size 0 0)
			(layers "F.Cu" "F.Mask" "F.Paste")
			(net "P3V3_SSD5")
		)
		(pad "2" smd circle
			(at 0.40005 0 180)
			(size 0 0)
			(layers "F.Cu" "F.Mask" "F.Paste")
			(net "SMB_ISO_SSD5_SCL")
		)
	)
	(footprint ""
		(layer "F.Cu")
		(at 344.061542 -303.698402 90)
		(property "Reference" "PC152"
			(at 0 0 90)
			(layer "F.SilkS")
			(hide yes)
			(effects
				(font
					(size 1.27 1.27)
				)
			)
		)
		(property "Value" ""
			(at 0 0 90)
			(layer "F.Fab")
			(effects
				(font
					(size 1.27 1.27)
				)
			)
		)
		(duplicate_pad_numbers_are_jumpers no)
		(fp_line
			(start -4.53898 -2.150618)
			(end -4.539742 2.152142)
			(stroke
				(width 0.1524)
				(type default)
			)
			(layer "F.SilkS")
		)
		(fp_line
			(start -4.69138 -2.150618)
			(end -4.692396 2.161032)
			(stroke
				(width 0.1524)
				(type default)
			)
			(layer "F.SilkS")
		)
		(fp_line
			(start -4.84378 -2.150618)
			(end -4.53898 -2.150618)
			(stroke
				(width 0.1524)
				(type default)
			)
			(layer "F.SilkS")
		)
		(fp_line
			(start -4.84378 -2.150618)
			(end -4.842256 2.163064)
			(stroke
				(width 0.1524)
				(type default)
			)
			(layer "F.SilkS")
		)
		(fp_line
			(start 4.53898 -2.15011)
			(end 4.53898 2.15011)
			(stroke
				(width 0.1524)
				(type default)
			)
			(layer "F.SilkS")
		)
		(fp_line
			(start -4.53898 -2.15011)
			(end 4.53898 -2.15011)
			(stroke
				(width 0.1524)
				(type default)
			)
			(layer "F.SilkS")
		)
		(fp_line
			(start 4.53898 2.15011)
			(end -4.53898 2.15011)
			(stroke
				(width 0.1524)
				(type default)
			)
			(layer "F.SilkS")
		)
		(fp_line
			(start -4.53898 2.15011)
			(end -4.53898 -2.15011)
			(stroke
				(width 0.1524)
				(type default)
			)
			(layer "F.SilkS")
		)
		(fp_line
			(start -4.83108 2.150364)
			(end -4.447794 2.149348)
			(stroke
				(width 0.1524)
				(type default)
			)
			(layer "F.SilkS")
		)
		(fp_line
			(start 3.64998 -2.15011)
			(end 3.64998 2.15011)
			(stroke
				(width 0.1)
				(type default)
			)
			(layer "F.Fab")
		)
		(fp_line
			(start -3.64998 -2.15011)
			(end 3.64998 -2.15011)
			(stroke
				(width 0.1)
				(type default)
			)
			(layer "F.Fab")
		)
		(fp_line
			(start 3.64998 2.15011)
			(end -3.64998 2.15011)
			(stroke
				(width 0.1)
				(type default)
			)
			(layer "F.Fab")
		)
		(fp_line
			(start -3.64998 2.15011)
			(end -3.64998 -2.15011)
			(stroke
				(width 0.1)
				(type default)
			)
			(layer "F.Fab")
		)
		(fp_text user "-"
			(at 3.525012 2.45491 90)
			(unlocked yes)
			(layer "F.SilkS")
			(effects
				(font
					(size 1.905 1.4224)
					(thickness 0.1524)
				)
				(justify left)
			)
		)
		(fp_text user "+"
			(at -4.823968 2.643378 90)
			(unlocked yes)
			(layer "F.SilkS")
			(effects
				(font
					(size 1.905 1.4224)
					(thickness 0.1524)
				)
				(justify left)
			)
		)
		(fp_text user "+"
			(at -6.214872 -0.337058 90)
			(unlocked yes)
			(layer "F.Fab")
			(effects
				(font
					(size 1.905 1.4224)
					(thickness 0.1524)
				)
				(justify left)
			)
		)
		(fp_text user "-"
			(at 4.313174 -0.094488 90)
			(unlocked yes)
			(layer "F.Fab")
			(effects
				(font
					(size 1.905 1.4224)
					(thickness 0.1524)
				)
				(justify left)
			)
		)
		(pad "1" smd rect
			(at -3.199892 0 90)
			(size 2.413 2.8194)
			(layers "F.Cu" "F.Mask" "F.Paste")
			(net "P0V8_PEX2")
		)
		(pad "2" smd rect
			(at 3.199892 0 90)
			(size 2.413 2.8194)
			(layers "F.Cu" "F.Mask" "F.Paste")
			(net "GND")
		)
	)
	(footprint ""
		(layer "F.Cu")
		(at 33.287716 -301.220632)
		(property "Reference" "C3024"
			(at 0 0 0)
			(layer "F.SilkS")
			(hide yes)
			(effects
				(font
					(size 1.27 1.27)
				)
			)
		)
		(property "Value" ""
			(at 0 0 0)
			(layer "F.Fab")
			(effects
				(font
					(size 1.27 1.27)
				)
			)
		)
		(duplicate_pad_numbers_are_jumpers no)
		(fp_line
			(start -1.2954 -0.5842)
			(end 1.2954 -0.5842)
			(stroke
				(width 0.1524)
				(type default)
			)
			(layer "F.SilkS")
		)
		(fp_line
			(start -1.2954 0.5842)
			(end -1.2954 -0.5842)
			(stroke
				(width 0.1524)
				(type default)
			)
			(layer "F.SilkS")
		)
		(fp_line
			(start 1.2954 -0.5842)
			(end 1.2954 0.5842)
			(stroke
				(width 0.1524)
				(type default)
			)
			(layer "F.SilkS")
		)
		(fp_line
			(start 1.2954 0.5842)
			(end -1.2954 0.5842)
			(stroke
				(width 0.1524)
				(type default)
			)
			(layer "F.SilkS")
		)
		(fp_line
			(start -1.1938 -0.4064)
			(end -0.8636 -0.4064)
			(stroke
				(width 0.1)
				(type default)
			)
			(layer "F.Fab")
		)
		(fp_line
			(start -1.1938 0.4064)
			(end -1.1938 -0.4064)
			(stroke
				(width 0.1)
				(type default)
			)
			(layer "F.Fab")
		)
		(fp_line
			(start -0.8636 -0.4572)
			(end 0.8636 -0.4572)
			(stroke
				(width 0.1)
				(type default)
			)
			(layer "F.Fab")
		)
		(fp_line
			(start -0.8636 -0.4064)
			(end -0.8636 -0.4572)
			(stroke
				(width 0.1)
				(type default)
			)
			(layer "F.Fab")
		)
		(fp_line
			(start -0.8636 0.4064)
			(end -1.1938 0.4064)
			(stroke
				(width 0.1)
				(type default)
			)
			(layer "F.Fab")
		)
		(fp_line
			(start -0.8636 0.4572)
			(end -0.8636 0.4064)
			(stroke
				(width 0.1)
				(type default)
			)
			(layer "F.Fab")
		)
		(fp_line
			(start 0.8636 -0.4572)
			(end 0.8636 -0.4064)
			(stroke
				(width 0.1)
				(type default)
			)
			(layer "F.Fab")
		)
		(fp_line
			(start 0.8636 -0.4064)
			(end 1.1938 -0.4064)
			(stroke
				(width 0.1)
				(type default)
			)
			(layer "F.Fab")
		)
		(fp_line
			(start 0.8636 0.4064)
			(end 0.8636 0.4572)
			(stroke
				(width 0.1)
				(type default)
			)
			(layer "F.Fab")
		)
		(fp_line
			(start 0.8636 0.4572)
			(end -0.8636 0.4572)
			(stroke
				(width 0.1)
				(type default)
			)
			(layer "F.Fab")
		)
		(fp_line
			(start 1.1938 -0.4064)
			(end 1.1938 0.4064)
			(stroke
				(width 0.1)
				(type default)
			)
			(layer "F.Fab")
		)
		(fp_line
			(start 1.1938 0.4064)
			(end 0.8636 0.4064)
			(stroke
				(width 0.1)
				(type default)
			)
			(layer "F.Fab")
		)
		(pad "1" smd rect
			(at -0.7366 0 270)
			(size 0.7112 0.8128)
			(layers "F.Cu" "F.Mask" "F.Paste")
			(net "PCEPLL1_VDDA18_PEX0")
		)
		(pad "2" smd rect
			(at 0.7366 0 270)
			(size 0.7112 0.8128)
			(layers "F.Cu" "F.Mask" "F.Paste")
			(net "GND")
		)
	)
	(footprint ""
		(layer "F.Cu")
		(at 187.032392 -356.22103 90)
		(property "Reference" "C376"
			(at 0 0 90)
			(layer "F.SilkS")
			(hide yes)
			(effects
				(font
					(size 1.27 1.27)
				)
			)
		)
		(property "Value" ""
			(at 0 0 90)
			(layer "F.Fab")
			(effects
				(font
					(size 1.27 1.27)
				)
			)
		)
		(duplicate_pad_numbers_are_jumpers no)
		(fp_line
			(start 0.299974 -0.150114)
			(end 0.299974 0.150114)
			(stroke
				(width 0.1)
				(type default)
			)
			(layer "F.Fab")
		)
		(fp_line
			(start -0.299974 -0.150114)
			(end 0.299974 -0.150114)
			(stroke
				(width 0.1)
				(type default)
			)
			(layer "F.Fab")
		)
		(fp_line
			(start 0.299974 0.150114)
			(end -0.299974 0.150114)
			(stroke
				(width 0.1)
				(type default)
			)
			(layer "F.Fab")
		)
		(fp_line
			(start -0.299974 0.150114)
			(end -0.299974 -0.150114)
			(stroke
				(width 0.1)
				(type default)
			)
			(layer "F.Fab")
		)
		(pad "1" smd rect
			(at -0.2667 0 90)
			(size 0.3048 0.381)
			(layers "F.Cu" "F.Mask" "F.Paste")
			(net "P5E_PEX1_STN7_TX_DP<125>")
		)
		(pad "2" smd rect
			(at 0.2667 0 90)
			(size 0.3048 0.381)
			(layers "F.Cu" "F.Mask" "F.Paste")
			(net "P5E_PEX1_STN7_TX_C_DP<125>")
		)
	)
	(footprint ""
		(layer "F.Cu")
		(at 310.443626 -49.95291 180)
		(property "Reference" "R5901"
			(at 0 0 180)
			(layer "F.SilkS")
			(hide yes)
			(effects
				(font
					(size 1.27 1.27)
				)
			)
		)
		(property "Value" ""
			(at 0 0 180)
			(layer "F.Fab")
			(effects
				(font
					(size 1.27 1.27)
				)
			)
		)
		(duplicate_pad_numbers_are_jumpers no)
		(fp_line
			(start 0.7874 0.4064)
			(end -0.7874 0.4064)
			(stroke
				(width 0.1524)
				(type default)
			)
			(layer "F.SilkS")
		)
		(fp_line
			(start 0.7874 -0.4064)
			(end 0.7874 0.4064)
			(stroke
				(width 0.1524)
				(type default)
			)
			(layer "F.SilkS")
		)
		(fp_line
			(start -0.7874 0.4064)
			(end -0.7874 -0.4064)
			(stroke
				(width 0.1524)
				(type default)
			)
			(layer "F.SilkS")
		)
		(fp_line
			(start -0.7874 -0.4064)
			(end 0.7874 -0.4064)
			(stroke
				(width 0.1524)
				(type default)
			)
			(layer "F.SilkS")
		)
		(fp_line
			(start 0.67945 0.3048)
			(end 0.120396 0.3048)
			(stroke
				(width 0.1)
				(type default)
			)
			(layer "F.Fab")
		)
		(fp_line
			(start 0.67945 -0.3048)
			(end 0.67945 0.3048)
			(stroke
				(width 0.1)
				(type default)
			)
			(layer "F.Fab")
		)
		(fp_line
			(start 0.12065 -0.2794)
			(end 0.12065 -0.3048)
			(stroke
				(width 0.1)
				(type default)
			)
			(layer "F.Fab")
		)
		(fp_line
			(start 0.12065 -0.3048)
			(end 0.67945 -0.3048)
			(stroke
				(width 0.1)
				(type default)
			)
			(layer "F.Fab")
		)
		(fp_line
			(start 0.120396 0.3048)
			(end 0.120396 0.2794)
			(stroke
				(width 0.1)
				(type default)
			)
			(layer "F.Fab")
		)
		(fp_line
			(start 0.120396 0.2794)
			(end -0.12065 0.2794)
			(stroke
				(width 0.1)
				(type default)
			)
			(layer "F.Fab")
		)
		(fp_line
			(start -0.12065 0.3048)
			(end -0.67945 0.3048)
			(stroke
				(width 0.1)
				(type default)
			)
			(layer "F.Fab")
		)
		(fp_line
			(start -0.12065 0.2794)
			(end -0.12065 0.3048)
			(stroke
				(width 0.1)
				(type default)
			)
			(layer "F.Fab")
		)
		(fp_line
			(start -0.12065 -0.2794)
			(end 0.12065 -0.2794)
			(stroke
				(width 0.1)
				(type default)
			)
			(layer "F.Fab")
		)
		(fp_line
			(start -0.12065 -0.305054)
			(end -0.12065 -0.2794)
			(stroke
				(width 0.1)
				(type default)
			)
			(layer "F.Fab")
		)
		(fp_line
			(start -0.67945 0.3048)
			(end -0.67945 -0.305054)
			(stroke
				(width 0.1)
				(type default)
			)
			(layer "F.Fab")
		)
		(fp_line
			(start -0.67945 -0.305054)
			(end -0.12065 -0.305054)
			(stroke
				(width 0.1)
				(type default)
			)
			(layer "F.Fab")
		)
		(pad "1" smd circle
			(at -0.40005 0 180)
			(size 0 0)
			(layers "F.Cu" "F.Mask" "F.Paste")
			(net "SSD10_ADC_A0")
		)
		(pad "2" smd circle
			(at 0.40005 0 180)
			(size 0 0)
			(layers "F.Cu" "F.Mask" "F.Paste")
			(net "SMB_SSD10_ADC_SDA")
		)
	)
	(footprint ""
		(layer "F.Cu")
		(at 326.187816 -45.704252 90)
		(property "Reference" "R626"
			(at 0 0 90)
			(layer "F.SilkS")
			(hide yes)
			(effects
				(font
					(size 1.27 1.27)
				)
			)
		)
		(property "Value" ""
			(at 0 0 90)
			(layer "F.Fab")
			(effects
				(font
					(size 1.27 1.27)
				)
			)
		)
		(duplicate_pad_numbers_are_jumpers no)
		(fp_line
			(start 3.937508 -1.8796)
			(end -3.937508 -1.8796)
			(stroke
				(width 0.1524)
				(type default)
			)
			(layer "F.SilkS")
		)
		(fp_line
			(start -3.937508 -1.8796)
			(end -3.937508 1.8796)
			(stroke
				(width 0.1524)
				(type default)
			)
			(layer "F.SilkS")
		)
		(fp_line
			(start 3.937508 1.8796)
			(end 3.937508 -1.8796)
			(stroke
				(width 0.1524)
				(type default)
			)
			(layer "F.SilkS")
		)
		(fp_line
			(start -3.937508 1.8796)
			(end 3.937508 1.8796)
			(stroke
				(width 0.1524)
				(type default)
			)
			(layer "F.SilkS")
		)
		(fp_line
			(start 3.275076 -1.674876)
			(end -3.275076 -1.674876)
			(stroke
				(width 0.1)
				(type default)
			)
			(layer "F.Fab")
		)
		(fp_line
			(start -3.275076 -1.674876)
			(end -3.275076 1.674876)
			(stroke
				(width 0.1)
				(type default)
			)
			(layer "F.Fab")
		)
		(fp_line
			(start 3.275076 1.674876)
			(end 3.275076 -1.674876)
			(stroke
				(width 0.1)
				(type default)
			)
			(layer "F.Fab")
		)
		(fp_line
			(start -3.275076 1.674876)
			(end 3.275076 1.674876)
			(stroke
				(width 0.1)
				(type default)
			)
			(layer "F.Fab")
		)
		(pad "1" smd rect
			(at -2.350008 0 90)
			(size 2.921 3.5052)
			(layers "F.Cu" "F.Mask" "F.Paste")
			(net "P12V_SSD11")
		)
		(pad "2" smd rect
			(at 2.350008 0 90)
			(size 2.921 3.5052)
			(layers "F.Cu" "F.Mask" "F.Paste")
			(net "P12V_SSD11_R")
		)
	)
	(footprint ""
		(layer "F.Cu")
		(at 339.344 -236.855 90)
		(property "Reference" "R1792"
			(at 0 0 90)
			(layer "F.SilkS")
			(hide yes)
			(effects
				(font
					(size 1.27 1.27)
				)
			)
		)
		(property "Value" ""
			(at 0 0 90)
			(layer "F.Fab")
			(effects
				(font
					(size 1.27 1.27)
				)
			)
		)
		(duplicate_pad_numbers_are_jumpers no)
		(fp_line
			(start 0.7874 -0.4064)
			(end 0.7874 0.4064)
			(stroke
				(width 0.1524)
				(type default)
			)
			(layer "F.SilkS")
		)
		(fp_line
			(start -0.7874 -0.4064)
			(end 0.7874 -0.4064)
			(stroke
				(width 0.1524)
				(type default)
			)
			(layer "F.SilkS")
		)
		(fp_line
			(start 0.7874 0.4064)
			(end -0.7874 0.4064)
			(stroke
				(width 0.1524)
				(type default)
			)
			(layer "F.SilkS")
		)
		(fp_line
			(start -0.7874 0.4064)
			(end -0.7874 -0.4064)
			(stroke
				(width 0.1524)
				(type default)
			)
			(layer "F.SilkS")
		)
		(fp_line
			(start -0.12065 -0.305054)
			(end -0.12065 -0.2794)
			(stroke
				(width 0.1)
				(type default)
			)
			(layer "F.Fab")
		)
		(fp_line
			(start -0.67945 -0.305054)
			(end -0.12065 -0.305054)
			(stroke
				(width 0.1)
				(type default)
			)
			(layer "F.Fab")
		)
		(fp_line
			(start 0.67945 -0.3048)
			(end 0.67945 0.3048)
			(stroke
				(width 0.1)
				(type default)
			)
			(layer "F.Fab")
		)
		(fp_line
			(start 0.12065 -0.3048)
			(end 0.67945 -0.3048)
			(stroke
				(width 0.1)
				(type default)
			)
			(layer "F.Fab")
		)
		(fp_line
			(start 0.12065 -0.2794)
			(end 0.12065 -0.3048)
			(stroke
				(width 0.1)
				(type default)
			)
			(layer "F.Fab")
		)
		(fp_line
			(start -0.12065 -0.2794)
			(end 0.12065 -0.2794)
			(stroke
				(width 0.1)
				(type default)
			)
			(layer "F.Fab")
		)
		(fp_line
			(start 0.120396 0.2794)
			(end -0.12065 0.2794)
			(stroke
				(width 0.1)
				(type default)
			)
			(layer "F.Fab")
		)
		(fp_line
			(start -0.12065 0.2794)
			(end -0.12065 0.3048)
			(stroke
				(width 0.1)
				(type default)
			)
			(layer "F.Fab")
		)
		(fp_line
			(start 0.67945 0.3048)
			(end 0.120396 0.3048)
			(stroke
				(width 0.1)
				(type default)
			)
			(layer "F.Fab")
		)
		(fp_line
			(start 0.120396 0.3048)
			(end 0.120396 0.2794)
			(stroke
				(width 0.1)
				(type default)
			)
			(layer "F.Fab")
		)
		(fp_line
			(start -0.12065 0.3048)
			(end -0.67945 0.3048)
			(stroke
				(width 0.1)
				(type default)
			)
			(layer "F.Fab")
		)
		(fp_line
			(start -0.67945 0.3048)
			(end -0.67945 -0.305054)
			(stroke
				(width 0.1)
				(type default)
			)
			(layer "F.Fab")
		)
		(pad "1" smd circle
			(at -0.40005 0 90)
			(size 0 0)
			(layers "F.Cu" "F.Mask" "F.Paste")
			(net "P3V3_AUX")
		)
		(pad "2" smd circle
			(at 0.40005 0 90)
			(size 0 0)
			(layers "F.Cu" "F.Mask" "F.Paste")
			(net "RST_MB_PERST_2_ISO_R_N")
		)
	)
	(footprint ""
		(layer "F.Cu")
		(at 355.913436 -139.376404)
		(property "Reference" "R858"
			(at 0 0 0)
			(layer "F.SilkS")
			(hide yes)
			(effects
				(font
					(size 1.27 1.27)
				)
			)
		)
		(property "Value" ""
			(at 0 0 0)
			(layer "F.Fab")
			(effects
				(font
					(size 1.27 1.27)
				)
			)
		)
		(duplicate_pad_numbers_are_jumpers no)
		(fp_line
			(start -0.7874 -0.4064)
			(end 0.7874 -0.4064)
			(stroke
				(width 0.1524)
				(type default)
			)
			(layer "F.SilkS")
		)
		(fp_line
			(start -0.7874 0.4064)
			(end -0.7874 -0.4064)
			(stroke
				(width 0.1524)
				(type default)
			)
			(layer "F.SilkS")
		)
		(fp_line
			(start 0.7874 -0.4064)
			(end 0.7874 0.4064)
			(stroke
				(width 0.1524)
				(type default)
			)
			(layer "F.SilkS")
		)
		(fp_line
			(start 0.7874 0.4064)
			(end -0.7874 0.4064)
			(stroke
				(width 0.1524)
				(type default)
			)
			(layer "F.SilkS")
		)
		(fp_line
			(start -0.67945 -0.305054)
			(end -0.12065 -0.305054)
			(stroke
				(width 0.1)
				(type default)
			)
			(layer "F.Fab")
		)
		(fp_line
			(start -0.67945 0.3048)
			(end -0.67945 -0.305054)
			(stroke
				(width 0.1)
				(type default)
			)
			(layer "F.Fab")
		)
		(fp_line
			(start -0.12065 -0.305054)
			(end -0.12065 -0.2794)
			(stroke
				(width 0.1)
				(type default)
			)
			(layer "F.Fab")
		)
		(fp_line
			(start -0.12065 -0.2794)
			(end 0.12065 -0.2794)
			(stroke
				(width 0.1)
				(type default)
			)
			(layer "F.Fab")
		)
		(fp_line
			(start -0.12065 0.2794)
			(end -0.12065 0.3048)
			(stroke
				(width 0.1)
				(type default)
			)
			(layer "F.Fab")
		)
		(fp_line
			(start -0.12065 0.3048)
			(end -0.67945 0.3048)
			(stroke
				(width 0.1)
				(type default)
			)
			(layer "F.Fab")
		)
		(fp_line
			(start 0.120396 0.2794)
			(end -0.12065 0.2794)
			(stroke
				(width 0.1)
				(type default)
			)
			(layer "F.Fab")
		)
		(fp_line
			(start 0.120396 0.3048)
			(end 0.120396 0.2794)
			(stroke
				(width 0.1)
				(type default)
			)
			(layer "F.Fab")
		)
		(fp_line
			(start 0.12065 -0.3048)
			(end 0.67945 -0.3048)
			(stroke
				(width 0.1)
				(type default)
			)
			(layer "F.Fab")
		)
		(fp_line
			(start 0.12065 -0.2794)
			(end 0.12065 -0.3048)
			(stroke
				(width 0.1)
				(type default)
			)
			(layer "F.Fab")
		)
		(fp_line
			(start 0.67945 -0.3048)
			(end 0.67945 0.3048)
			(stroke
				(width 0.1)
				(type default)
			)
			(layer "F.Fab")
		)
		(fp_line
			(start 0.67945 0.3048)
			(end 0.120396 0.3048)
			(stroke
				(width 0.1)
				(type default)
			)
			(layer "F.Fab")
		)
		(pad "1" smd circle
			(at -0.40005 0)
			(size 0 0)
			(layers "F.Cu" "F.Mask" "F.Paste")
			(net "P3V3_AUX")
		)
		(pad "2" smd circle
			(at 0.40005 0)
			(size 0 0)
			(layers "F.Cu" "F.Mask" "F.Paste")
			(net "PWRGD_P12V_NIC6")
		)
	)
	(footprint ""
		(layer "F.Cu")
		(at 340.561422 -196.51345)
		(property "Reference" "R4236"
			(at 0 0 0)
			(layer "F.SilkS")
			(hide yes)
			(effects
				(font
					(size 1.27 1.27)
				)
			)
		)
		(property "Value" ""
			(at 0 0 0)
			(layer "F.Fab")
			(effects
				(font
					(size 1.27 1.27)
				)
			)
		)
		(duplicate_pad_numbers_are_jumpers no)
		(fp_line
			(start -0.7874 -0.4064)
			(end 0.7874 -0.4064)
			(stroke
				(width 0.1524)
				(type default)
			)
			(layer "F.SilkS")
		)
		(fp_line
			(start -0.7874 0.4064)
			(end -0.7874 -0.4064)
			(stroke
				(width 0.1524)
				(type default)
			)
			(layer "F.SilkS")
		)
		(fp_line
			(start 0.7874 -0.4064)
			(end 0.7874 0.4064)
			(stroke
				(width 0.1524)
				(type default)
			)
			(layer "F.SilkS")
		)
		(fp_line
			(start 0.7874 0.4064)
			(end -0.7874 0.4064)
			(stroke
				(width 0.1524)
				(type default)
			)
			(layer "F.SilkS")
		)
		(fp_line
			(start -0.67945 -0.305054)
			(end -0.12065 -0.305054)
			(stroke
				(width 0.1)
				(type default)
			)
			(layer "F.Fab")
		)
		(fp_line
			(start -0.67945 0.3048)
			(end -0.67945 -0.305054)
			(stroke
				(width 0.1)
				(type default)
			)
			(layer "F.Fab")
		)
		(fp_line
			(start -0.12065 -0.305054)
			(end -0.12065 -0.2794)
			(stroke
				(width 0.1)
				(type default)
			)
			(layer "F.Fab")
		)
		(fp_line
			(start -0.12065 -0.2794)
			(end 0.12065 -0.2794)
			(stroke
				(width 0.1)
				(type default)
			)
			(layer "F.Fab")
		)
		(fp_line
			(start -0.12065 0.2794)
			(end -0.12065 0.3048)
			(stroke
				(width 0.1)
				(type default)
			)
			(layer "F.Fab")
		)
		(fp_line
			(start -0.12065 0.3048)
			(end -0.67945 0.3048)
			(stroke
				(width 0.1)
				(type default)
			)
			(layer "F.Fab")
		)
		(fp_line
			(start 0.120396 0.2794)
			(end -0.12065 0.2794)
			(stroke
				(width 0.1)
				(type default)
			)
			(layer "F.Fab")
		)
		(fp_line
			(start 0.120396 0.3048)
			(end 0.120396 0.2794)
			(stroke
				(width 0.1)
				(type default)
			)
			(layer "F.Fab")
		)
		(fp_line
			(start 0.12065 -0.3048)
			(end 0.67945 -0.3048)
			(stroke
				(width 0.1)
				(type default)
			)
			(layer "F.Fab")
		)
		(fp_line
			(start 0.12065 -0.2794)
			(end 0.12065 -0.3048)
			(stroke
				(width 0.1)
				(type default)
			)
			(layer "F.Fab")
		)
		(fp_line
			(start 0.67945 -0.3048)
			(end 0.67945 0.3048)
			(stroke
				(width 0.1)
				(type default)
			)
			(layer "F.Fab")
		)
		(fp_line
			(start 0.67945 0.3048)
			(end 0.120396 0.3048)
			(stroke
				(width 0.1)
				(type default)
			)
			(layer "F.Fab")
		)
		(pad "1" smd circle
			(at -0.40005 0)
			(size 0 0)
			(layers "F.Cu" "F.Mask" "F.Paste")
			(net "IOEXP_DBV2_A0")
		)
		(pad "2" smd circle
			(at 0.40005 0)
			(size 0 0)
			(layers "F.Cu" "F.Mask" "F.Paste")
			(net "P3V3_AUX")
		)
	)
	(footprint ""
		(layer "F.Cu")
		(at 126.63043 -144.067276 180)
		(property "Reference" "PC624"
			(at 0 0 180)
			(layer "F.SilkS")
			(hide yes)
			(effects
				(font
					(size 1.27 1.27)
				)
			)
		)
		(property "Value" ""
			(at 0 0 180)
			(layer "F.Fab")
			(effects
				(font
					(size 1.27 1.27)
				)
			)
		)
		(duplicate_pad_numbers_are_jumpers no)
		(fp_line
			(start 1.524 0.762)
			(end -1.524 0.762)
			(stroke
				(width 0.1524)
				(type default)
			)
			(layer "F.SilkS")
		)
		(fp_line
			(start 1.524 -0.762)
			(end 1.524 0.762)
			(stroke
				(width 0.1524)
				(type default)
			)
			(layer "F.SilkS")
		)
		(fp_line
			(start -1.524 0.762)
			(end -1.524 -0.762)
			(stroke
				(width 0.1524)
				(type default)
			)
			(layer "F.SilkS")
		)
		(fp_line
			(start -1.524 -0.762)
			(end 1.524 -0.762)
			(stroke
				(width 0.1524)
				(type default)
			)
			(layer "F.SilkS")
		)
		(fp_line
			(start 1.1049 0.724916)
			(end 1.1049 -0.724916)
			(stroke
				(width 0.1)
				(type default)
			)
			(layer "F.Fab")
		)
		(fp_line
			(start 1.1049 -0.724916)
			(end -1.1049 -0.724916)
			(stroke
				(width 0.1)
				(type default)
			)
			(layer "F.Fab")
		)
		(fp_line
			(start -1.1049 0.724916)
			(end 1.1049 0.724916)
			(stroke
				(width 0.1)
				(type default)
			)
			(layer "F.Fab")
		)
		(fp_line
			(start -1.1049 -0.724916)
			(end -1.1049 0.724916)
			(stroke
				(width 0.1)
				(type default)
			)
			(layer "F.Fab")
		)
		(pad "1" smd rect
			(at -0.889 0)
			(size 1.016 1.27)
			(layers "F.Cu" "F.Mask" "F.Paste")
			(net "P12V_NIC2_R")
		)
		(pad "2" smd rect
			(at 0.889 0)
			(size 1.016 1.27)
			(layers "F.Cu" "F.Mask" "F.Paste")
			(net "GND")
		)
	)
	(footprint ""
		(layer "F.Cu")
		(at 143.226282 -37.929566 90)
		(property "Reference" "R5555"
			(at 0 0 90)
			(layer "F.SilkS")
			(hide yes)
			(effects
				(font
					(size 1.27 1.27)
				)
			)
		)
		(property "Value" ""
			(at 0 0 90)
			(layer "F.Fab")
			(effects
				(font
					(size 1.27 1.27)
				)
			)
		)
		(duplicate_pad_numbers_are_jumpers no)
		(fp_line
			(start 0.7874 -0.4064)
			(end 0.7874 0.4064)
			(stroke
				(width 0.1524)
				(type default)
			)
			(layer "F.SilkS")
		)
		(fp_line
			(start -0.7874 -0.4064)
			(end 0.7874 -0.4064)
			(stroke
				(width 0.1524)
				(type default)
			)
			(layer "F.SilkS")
		)
		(fp_line
			(start 0.7874 0.4064)
			(end -0.7874 0.4064)
			(stroke
				(width 0.1524)
				(type default)
			)
			(layer "F.SilkS")
		)
		(fp_line
			(start -0.7874 0.4064)
			(end -0.7874 -0.4064)
			(stroke
				(width 0.1524)
				(type default)
			)
			(layer "F.SilkS")
		)
		(fp_line
			(start -0.12065 -0.305054)
			(end -0.12065 -0.2794)
			(stroke
				(width 0.1)
				(type default)
			)
			(layer "F.Fab")
		)
		(fp_line
			(start -0.67945 -0.305054)
			(end -0.12065 -0.305054)
			(stroke
				(width 0.1)
				(type default)
			)
			(layer "F.Fab")
		)
		(fp_line
			(start 0.67945 -0.3048)
			(end 0.67945 0.3048)
			(stroke
				(width 0.1)
				(type default)
			)
			(layer "F.Fab")
		)
		(fp_line
			(start 0.12065 -0.3048)
			(end 0.67945 -0.3048)
			(stroke
				(width 0.1)
				(type default)
			)
			(layer "F.Fab")
		)
		(fp_line
			(start 0.12065 -0.2794)
			(end 0.12065 -0.3048)
			(stroke
				(width 0.1)
				(type default)
			)
			(layer "F.Fab")
		)
		(fp_line
			(start -0.12065 -0.2794)
			(end 0.12065 -0.2794)
			(stroke
				(width 0.1)
				(type default)
			)
			(layer "F.Fab")
		)
		(fp_line
			(start 0.120396 0.2794)
			(end -0.12065 0.2794)
			(stroke
				(width 0.1)
				(type default)
			)
			(layer "F.Fab")
		)
		(fp_line
			(start -0.12065 0.2794)
			(end -0.12065 0.3048)
			(stroke
				(width 0.1)
				(type default)
			)
			(layer "F.Fab")
		)
		(fp_line
			(start 0.67945 0.3048)
			(end 0.120396 0.3048)
			(stroke
				(width 0.1)
				(type default)
			)
			(layer "F.Fab")
		)
		(fp_line
			(start 0.120396 0.3048)
			(end 0.120396 0.2794)
			(stroke
				(width 0.1)
				(type default)
			)
			(layer "F.Fab")
		)
		(fp_line
			(start -0.12065 0.3048)
			(end -0.67945 0.3048)
			(stroke
				(width 0.1)
				(type default)
			)
			(layer "F.Fab")
		)
		(fp_line
			(start -0.67945 0.3048)
			(end -0.67945 -0.305054)
			(stroke
				(width 0.1)
				(type default)
			)
			(layer "F.Fab")
		)
		(pad "1" smd circle
			(at -0.40005 0 90)
			(size 0 0)
			(layers "F.Cu" "F.Mask" "F.Paste")
			(net "SSD5_AUX_P3V3_EN_R")
		)
		(pad "2" smd circle
			(at 0.40005 0 90)
			(size 0 0)
			(layers "F.Cu" "F.Mask" "F.Paste")
			(net "SSD5_AUX_P3V3_EN")
		)
	)
	(footprint ""
		(layer "F.Cu")
		(at 278.87295 -22.867366 90)
		(property "Reference" "C3935"
			(at 0 0 90)
			(layer "F.SilkS")
			(hide yes)
			(effects
				(font
					(size 1.27 1.27)
				)
			)
		)
		(property "Value" ""
			(at 0 0 90)
			(layer "F.Fab")
			(effects
				(font
					(size 1.27 1.27)
				)
			)
		)
		(duplicate_pad_numbers_are_jumpers no)
		(fp_line
			(start 0.7874 -0.4064)
			(end 0.7874 0.4064)
			(stroke
				(width 0.1524)
				(type default)
			)
			(layer "F.SilkS")
		)
		(fp_line
			(start -0.7874 -0.4064)
			(end 0.7874 -0.4064)
			(stroke
				(width 0.1524)
				(type default)
			)
			(layer "F.SilkS")
		)
		(fp_line
			(start 0.7874 0.4064)
			(end -0.7874 0.4064)
			(stroke
				(width 0.1524)
				(type default)
			)
			(layer "F.SilkS")
		)
		(fp_line
			(start -0.7874 0.4064)
			(end -0.7874 -0.4064)
			(stroke
				(width 0.1524)
				(type default)
			)
			(layer "F.SilkS")
		)
		(fp_line
			(start -0.12065 -0.305054)
			(end -0.12065 -0.2794)
			(stroke
				(width 0.1)
				(type default)
			)
			(layer "F.Fab")
		)
		(fp_line
			(start -0.67945 -0.305054)
			(end -0.12065 -0.305054)
			(stroke
				(width 0.1)
				(type default)
			)
			(layer "F.Fab")
		)
		(fp_line
			(start 0.67945 -0.3048)
			(end 0.67945 0.3048)
			(stroke
				(width 0.1)
				(type default)
			)
			(layer "F.Fab")
		)
		(fp_line
			(start 0.12065 -0.3048)
			(end 0.67945 -0.3048)
			(stroke
				(width 0.1)
				(type default)
			)
			(layer "F.Fab")
		)
		(fp_line
			(start 0.12065 -0.2794)
			(end 0.12065 -0.3048)
			(stroke
				(width 0.1)
				(type default)
			)
			(layer "F.Fab")
		)
		(fp_line
			(start -0.12065 -0.2794)
			(end 0.12065 -0.2794)
			(stroke
				(width 0.1)
				(type default)
			)
			(layer "F.Fab")
		)
		(fp_line
			(start 0.120396 0.2794)
			(end -0.12065 0.2794)
			(stroke
				(width 0.1)
				(type default)
			)
			(layer "F.Fab")
		)
		(fp_line
			(start -0.12065 0.2794)
			(end -0.12065 0.3048)
			(stroke
				(width 0.1)
				(type default)
			)
			(layer "F.Fab")
		)
		(fp_line
			(start 0.67945 0.3048)
			(end 0.120396 0.3048)
			(stroke
				(width 0.1)
				(type default)
			)
			(layer "F.Fab")
		)
		(fp_line
			(start 0.120396 0.3048)
			(end 0.120396 0.2794)
			(stroke
				(width 0.1)
				(type default)
			)
			(layer "F.Fab")
		)
		(fp_line
			(start -0.12065 0.3048)
			(end -0.67945 0.3048)
			(stroke
				(width 0.1)
				(type default)
			)
			(layer "F.Fab")
		)
		(fp_line
			(start -0.67945 0.3048)
			(end -0.67945 -0.305054)
			(stroke
				(width 0.1)
				(type default)
			)
			(layer "F.Fab")
		)
		(pad "1" smd circle
			(at -0.40005 0 90)
			(size 0 0)
			(layers "F.Cu" "F.Mask" "F.Paste")
			(net "P12V_SSD9")
		)
		(pad "2" smd circle
			(at 0.40005 0 90)
			(size 0 0)
			(layers "F.Cu" "F.Mask" "F.Paste")
			(net "GND")
		)
	)
	(footprint ""
		(layer "F.Cu")
		(at 131.404868 -350.098614 90)
		(property "Reference" "C2272"
			(at 0 0 90)
			(layer "F.SilkS")
			(hide yes)
			(effects
				(font
					(size 1.27 1.27)
				)
			)
		)
		(property "Value" ""
			(at 0 0 90)
			(layer "F.Fab")
			(effects
				(font
					(size 1.27 1.27)
				)
			)
		)
		(duplicate_pad_numbers_are_jumpers no)
		(fp_line
			(start 0.299974 -0.150114)
			(end 0.299974 0.150114)
			(stroke
				(width 0.1)
				(type default)
			)
			(layer "F.Fab")
		)
		(fp_line
			(start -0.299974 -0.150114)
			(end 0.299974 -0.150114)
			(stroke
				(width 0.1)
				(type default)
			)
			(layer "F.Fab")
		)
		(fp_line
			(start 0.299974 0.150114)
			(end -0.299974 0.150114)
			(stroke
				(width 0.1)
				(type default)
			)
			(layer "F.Fab")
		)
		(fp_line
			(start -0.299974 0.150114)
			(end -0.299974 -0.150114)
			(stroke
				(width 0.1)
				(type default)
			)
			(layer "F.Fab")
		)
		(pad "1" smd rect
			(at -0.2667 0 90)
			(size 0.3048 0.381)
			(layers "F.Cu" "F.Mask" "F.Paste")
			(net "P5E_PEX1_STN5_TX_DN<81>")
		)
		(pad "2" smd rect
			(at 0.2667 0 90)
			(size 0.3048 0.381)
			(layers "F.Cu" "F.Mask" "F.Paste")
			(net "P5E_PEX1_STN5_TX_C_DN<81>")
		)
	)
	(footprint ""
		(layer "F.Cu")
		(at 420.73449 -30.94609 180)
		(property "Reference" "C718"
			(at 0 0 180)
			(layer "F.SilkS")
			(hide yes)
			(effects
				(font
					(size 1.27 1.27)
				)
			)
		)
		(property "Value" ""
			(at 0 0 180)
			(layer "F.Fab")
			(effects
				(font
					(size 1.27 1.27)
				)
			)
		)
		(duplicate_pad_numbers_are_jumpers no)
		(fp_line
			(start 0.299974 0.150114)
			(end -0.299974 0.150114)
			(stroke
				(width 0.1)
				(type default)
			)
			(layer "F.Fab")
		)
		(fp_line
			(start 0.299974 -0.150114)
			(end 0.299974 0.150114)
			(stroke
				(width 0.1)
				(type default)
			)
			(layer "F.Fab")
		)
		(fp_line
			(start -0.299974 0.150114)
			(end -0.299974 -0.150114)
			(stroke
				(width 0.1)
				(type default)
			)
			(layer "F.Fab")
		)
		(fp_line
			(start -0.299974 -0.150114)
			(end 0.299974 -0.150114)
			(stroke
				(width 0.1)
				(type default)
			)
			(layer "F.Fab")
		)
		(pad "1" smd rect
			(at -0.2667 0 180)
			(size 0.3048 0.381)
			(layers "F.Cu" "F.Mask" "F.Paste")
			(net "P5E_PEX3_STN2_TX_DP<37>")
		)
		(pad "2" smd rect
			(at 0.2667 0 180)
			(size 0.3048 0.381)
			(layers "F.Cu" "F.Mask" "F.Paste")
			(net "P5E_PEX3_STN2_TX_C_DP<37>")
		)
	)
	(footprint ""
		(layer "F.Cu")
		(at 30.979872 -310.28894 -135)
		(property "Reference" "R1111"
			(at 0 0 225)
			(layer "F.SilkS")
			(hide yes)
			(effects
				(font
					(size 1.27 1.27)
				)
			)
		)
		(property "Value" ""
			(at 0 0 225)
			(layer "F.Fab")
			(effects
				(font
					(size 1.27 1.27)
				)
			)
		)
		(duplicate_pad_numbers_are_jumpers no)
		(fp_line
			(start 0.787389 0.406267)
			(end -0.787389 0.406267)
			(stroke
				(width 0.1524)
				(type default)
			)
			(layer "F.SilkS")
		)
		(fp_line
			(start 0.787389 -0.406267)
			(end 0.787389 0.406267)
			(stroke
				(width 0.1524)
				(type default)
			)
			(layer "F.SilkS")
		)
		(fp_line
			(start -0.787389 0.406267)
			(end -0.787389 -0.406267)
			(stroke
				(width 0.1524)
				(type default)
			)
			(layer "F.SilkS")
		)
		(fp_line
			(start -0.787389 -0.406267)
			(end 0.787389 -0.406267)
			(stroke
				(width 0.1524)
				(type default)
			)
			(layer "F.SilkS")
		)
		(fp_line
			(start 0.679446 0.30479)
			(end 0.120515 0.30479)
			(stroke
				(width 0.1)
				(type default)
			)
			(layer "F.Fab")
		)
		(fp_line
			(start 0.120515 0.30479)
			(end 0.120335 0.279466)
			(stroke
				(width 0.1)
				(type default)
			)
			(layer "F.Fab")
		)
		(fp_line
			(start 0.120335 0.279466)
			(end -0.120695 0.279466)
			(stroke
				(width 0.1)
				(type default)
			)
			(layer "F.Fab")
		)
		(fp_line
			(start 0.679446 -0.30479)
			(end 0.679446 0.30479)
			(stroke
				(width 0.1)
				(type default)
			)
			(layer "F.Fab")
		)
		(fp_line
			(start -0.120515 0.30479)
			(end -0.679446 0.30479)
			(stroke
				(width 0.1)
				(type default)
			)
			(layer "F.Fab")
		)
		(fp_line
			(start -0.120695 0.279466)
			(end -0.120515 0.30479)
			(stroke
				(width 0.1)
				(type default)
			)
			(layer "F.Fab")
		)
		(fp_line
			(start 0.120695 -0.279466)
			(end 0.120515 -0.30479)
			(stroke
				(width 0.1)
				(type default)
			)
			(layer "F.Fab")
		)
		(fp_line
			(start 0.120515 -0.30479)
			(end 0.679446 -0.30479)
			(stroke
				(width 0.1)
				(type default)
			)
			(layer "F.Fab")
		)
		(fp_line
			(start -0.679446 0.30479)
			(end -0.679446 -0.305149)
			(stroke
				(width 0.1)
				(type default)
			)
			(layer "F.Fab")
		)
		(fp_line
			(start -0.120695 -0.279466)
			(end 0.120695 -0.279466)
			(stroke
				(width 0.1)
				(type default)
			)
			(layer "F.Fab")
		)
		(fp_line
			(start -0.120695 -0.304969)
			(end -0.120695 -0.279466)
			(stroke
				(width 0.1)
				(type default)
			)
			(layer "F.Fab")
		)
		(fp_line
			(start -0.679446 -0.305149)
			(end -0.120695 -0.304969)
			(stroke
				(width 0.1)
				(type default)
			)
			(layer "F.Fab")
		)
		(pad "1" smd circle
			(at -0.40005 0 225)
			(size 0 0)
			(layers "F.Cu" "F.Mask" "F.Paste")
			(net "PEX0_DBG_MODE0")
		)
		(pad "2" smd circle
			(at 0.40005 0 225)
			(size 0 0)
			(layers "F.Cu" "F.Mask" "F.Paste")
			(net "P1V8_PEX")
		)
	)
	(footprint ""
		(layer "F.Cu")
		(at 114.945668 -343.952322 90)
		(property "Reference" "C358"
			(at 0 0 90)
			(layer "F.SilkS")
			(hide yes)
			(effects
				(font
					(size 1.27 1.27)
				)
			)
		)
		(property "Value" ""
			(at 0 0 90)
			(layer "F.Fab")
			(effects
				(font
					(size 1.27 1.27)
				)
			)
		)
		(duplicate_pad_numbers_are_jumpers no)
		(fp_line
			(start 0.299974 -0.150114)
			(end 0.299974 0.150114)
			(stroke
				(width 0.1)
				(type default)
			)
			(layer "F.Fab")
		)
		(fp_line
			(start -0.299974 -0.150114)
			(end 0.299974 -0.150114)
			(stroke
				(width 0.1)
				(type default)
			)
			(layer "F.Fab")
		)
		(fp_line
			(start 0.299974 0.150114)
			(end -0.299974 0.150114)
			(stroke
				(width 0.1)
				(type default)
			)
			(layer "F.Fab")
		)
		(fp_line
			(start -0.299974 0.150114)
			(end -0.299974 -0.150114)
			(stroke
				(width 0.1)
				(type default)
			)
			(layer "F.Fab")
		)
		(pad "1" smd rect
			(at -0.2667 0 90)
			(size 0.3048 0.381)
			(layers "F.Cu" "F.Mask" "F.Paste")
			(net "P5E_PEX1_STN6_TX_DP<102>")
		)
		(pad "2" smd rect
			(at 0.2667 0 90)
			(size 0.3048 0.381)
			(layers "F.Cu" "F.Mask" "F.Paste")
			(net "P5E_PEX1_STN6_TX_C_DP<102>")
		)
	)
	(footprint ""
		(layer "F.Cu")
		(at 17.358868 -251.082556 -90)
		(property "Reference" "C4230"
			(at 0 0 270)
			(layer "F.SilkS")
			(hide yes)
			(effects
				(font
					(size 1.27 1.27)
				)
			)
		)
		(property "Value" ""
			(at 0 0 270)
			(layer "F.Fab")
			(effects
				(font
					(size 1.27 1.27)
				)
			)
		)
		(duplicate_pad_numbers_are_jumpers no)
		(fp_line
			(start -1.524 0.762)
			(end -1.524 -0.762)
			(stroke
				(width 0.1524)
				(type default)
			)
			(layer "F.SilkS")
		)
		(fp_line
			(start 1.524 0.762)
			(end -1.524 0.762)
			(stroke
				(width 0.1524)
				(type default)
			)
			(layer "F.SilkS")
		)
		(fp_line
			(start -1.524 -0.762)
			(end 1.524 -0.762)
			(stroke
				(width 0.1524)
				(type default)
			)
			(layer "F.SilkS")
		)
		(fp_line
			(start 1.524 -0.762)
			(end 1.524 0.762)
			(stroke
				(width 0.1524)
				(type default)
			)
			(layer "F.SilkS")
		)
		(fp_line
			(start -1.1049 0.724916)
			(end 1.1049 0.724916)
			(stroke
				(width 0.1)
				(type default)
			)
			(layer "F.Fab")
		)
		(fp_line
			(start 1.1049 0.724916)
			(end 1.1049 -0.724916)
			(stroke
				(width 0.1)
				(type default)
			)
			(layer "F.Fab")
		)
		(fp_line
			(start -1.1049 -0.724916)
			(end -1.1049 0.724916)
			(stroke
				(width 0.1)
				(type default)
			)
			(layer "F.Fab")
		)
		(fp_line
			(start 1.1049 -0.724916)
			(end -1.1049 -0.724916)
			(stroke
				(width 0.1)
				(type default)
			)
			(layer "F.Fab")
		)
		(pad "1" smd rect
			(at -0.889 0 90)
			(size 1.016 1.27)
			(layers "F.Cu" "F.Mask" "F.Paste")
			(net "P1V25_SERDES_VDDPLL_PEX0_C4")
		)
		(pad "2" smd rect
			(at 0.889 0 90)
			(size 1.016 1.27)
			(layers "F.Cu" "F.Mask" "F.Paste")
			(net "GND")
		)
		(zone
			(layer "F.Cu")
			(hatch none 0.5)
			(connect_pads
				(clearance 0)
			)
			(min_thickness 0.25)
			(keepout
				(tracks not_allowed)
				(vias allowed)
				(pads allowed)
				(copperpour not_allowed)
				(footprints allowed)
			)
			(placement
				(enabled no)
				(sheetname "")
			)
			(fill
				(thermal_gap 0.5)
				(thermal_bridge_width 0.5)
				(island_removal_mode 0)
			)
			(polygon
				(pts
					(xy 18.083784 -251.412756) (xy 16.633952 -251.412756) (xy 16.633952 -250.752356) (xy 18.083784 -250.752356)
				)
			)
		)
	)
	(footprint ""
		(layer "F.Cu")
		(at 122.077988 -350.098614 90)
		(property "Reference" "C349"
			(at 0 0 90)
			(layer "F.SilkS")
			(hide yes)
			(effects
				(font
					(size 1.27 1.27)
				)
			)
		)
		(property "Value" ""
			(at 0 0 90)
			(layer "F.Fab")
			(effects
				(font
					(size 1.27 1.27)
				)
			)
		)
		(duplicate_pad_numbers_are_jumpers no)
		(fp_line
			(start 0.299974 -0.150114)
			(end 0.299974 0.150114)
			(stroke
				(width 0.1)
				(type default)
			)
			(layer "F.Fab")
		)
		(fp_line
			(start -0.299974 -0.150114)
			(end 0.299974 -0.150114)
			(stroke
				(width 0.1)
				(type default)
			)
			(layer "F.Fab")
		)
		(fp_line
			(start 0.299974 0.150114)
			(end -0.299974 0.150114)
			(stroke
				(width 0.1)
				(type default)
			)
			(layer "F.Fab")
		)
		(fp_line
			(start -0.299974 0.150114)
			(end -0.299974 -0.150114)
			(stroke
				(width 0.1)
				(type default)
			)
			(layer "F.Fab")
		)
		(pad "1" smd rect
			(at -0.2667 0 90)
			(size 0.3048 0.381)
			(layers "F.Cu" "F.Mask" "F.Paste")
			(net "P5E_PEX1_STN6_TX_DN<107>")
		)
		(pad "2" smd rect
			(at 0.2667 0 90)
			(size 0.3048 0.381)
			(layers "F.Cu" "F.Mask" "F.Paste")
			(net "P5E_PEX1_STN6_TX_C_DN<107>")
		)
	)
	(footprint ""
		(layer "F.Cu")
		(at 415.057082 -197.155308 -90)
		(property "Reference" "R6428"
			(at 0 0 270)
			(layer "F.SilkS")
			(hide yes)
			(effects
				(font
					(size 1.27 1.27)
				)
			)
		)
		(property "Value" ""
			(at 0 0 270)
			(layer "F.Fab")
			(effects
				(font
					(size 1.27 1.27)
				)
			)
		)
		(duplicate_pad_numbers_are_jumpers no)
		(fp_line
			(start -0.7874 0.4064)
			(end -0.7874 -0.4064)
			(stroke
				(width 0.1524)
				(type default)
			)
			(layer "F.SilkS")
		)
		(fp_line
			(start 0.7874 0.4064)
			(end -0.7874 0.4064)
			(stroke
				(width 0.1524)
				(type default)
			)
			(layer "F.SilkS")
		)
		(fp_line
			(start -0.7874 -0.4064)
			(end 0.7874 -0.4064)
			(stroke
				(width 0.1524)
				(type default)
			)
			(layer "F.SilkS")
		)
		(fp_line
			(start 0.7874 -0.4064)
			(end 0.7874 0.4064)
			(stroke
				(width 0.1524)
				(type default)
			)
			(layer "F.SilkS")
		)
		(fp_line
			(start -0.67945 0.3048)
			(end -0.67945 -0.305054)
			(stroke
				(width 0.1)
				(type default)
			)
			(layer "F.Fab")
		)
		(fp_line
			(start -0.12065 0.3048)
			(end -0.67945 0.3048)
			(stroke
				(width 0.1)
				(type default)
			)
			(layer "F.Fab")
		)
		(fp_line
			(start 0.120396 0.3048)
			(end 0.120396 0.2794)
			(stroke
				(width 0.1)
				(type default)
			)
			(layer "F.Fab")
		)
		(fp_line
			(start 0.67945 0.3048)
			(end 0.120396 0.3048)
			(stroke
				(width 0.1)
				(type default)
			)
			(layer "F.Fab")
		)
		(fp_line
			(start -0.12065 0.2794)
			(end -0.12065 0.3048)
			(stroke
				(width 0.1)
				(type default)
			)
			(layer "F.Fab")
		)
		(fp_line
			(start 0.120396 0.2794)
			(end -0.12065 0.2794)
			(stroke
				(width 0.1)
				(type default)
			)
			(layer "F.Fab")
		)
		(fp_line
			(start -0.12065 -0.2794)
			(end 0.12065 -0.2794)
			(stroke
				(width 0.1)
				(type default)
			)
			(layer "F.Fab")
		)
		(fp_line
			(start 0.12065 -0.2794)
			(end 0.12065 -0.3048)
			(stroke
				(width 0.1)
				(type default)
			)
			(layer "F.Fab")
		)
		(fp_line
			(start 0.12065 -0.3048)
			(end 0.67945 -0.3048)
			(stroke
				(width 0.1)
				(type default)
			)
			(layer "F.Fab")
		)
		(fp_line
			(start 0.67945 -0.3048)
			(end 0.67945 0.3048)
			(stroke
				(width 0.1)
				(type default)
			)
			(layer "F.Fab")
		)
		(fp_line
			(start -0.67945 -0.305054)
			(end -0.12065 -0.305054)
			(stroke
				(width 0.1)
				(type default)
			)
			(layer "F.Fab")
		)
		(fp_line
			(start -0.12065 -0.305054)
			(end -0.12065 -0.2794)
			(stroke
				(width 0.1)
				(type default)
			)
			(layer "F.Fab")
		)
		(pad "1" smd circle
			(at -0.40005 0 270)
			(size 0 0)
			(layers "F.Cu" "F.Mask" "F.Paste")
			(net "FPGA_PEX0_MODE_SEL1_D_N")
		)
		(pad "2" smd circle
			(at 0.40005 0 270)
			(size 0 0)
			(layers "F.Cu" "F.Mask" "F.Paste")
			(net "P3V3_AUX")
		)
	)
	(footprint ""
		(layer "F.Cu")
		(at 197.366382 -404.113238 -90)
		(property "Reference" "C3990"
			(at 0 0 270)
			(layer "F.SilkS")
			(hide yes)
			(effects
				(font
					(size 1.27 1.27)
				)
			)
		)
		(property "Value" ""
			(at 0 0 270)
			(layer "F.Fab")
			(effects
				(font
					(size 1.27 1.27)
				)
			)
		)
		(duplicate_pad_numbers_are_jumpers no)
		(fp_line
			(start -0.7874 0.4064)
			(end -0.7874 -0.4064)
			(stroke
				(width 0.1524)
				(type default)
			)
			(layer "F.SilkS")
		)
		(fp_line
			(start 0.7874 0.4064)
			(end -0.7874 0.4064)
			(stroke
				(width 0.1524)
				(type default)
			)
			(layer "F.SilkS")
		)
		(fp_line
			(start -0.7874 -0.4064)
			(end 0.7874 -0.4064)
			(stroke
				(width 0.1524)
				(type default)
			)
			(layer "F.SilkS")
		)
		(fp_line
			(start 0.7874 -0.4064)
			(end 0.7874 0.4064)
			(stroke
				(width 0.1524)
				(type default)
			)
			(layer "F.SilkS")
		)
		(fp_line
			(start -0.67945 0.3048)
			(end -0.67945 -0.305054)
			(stroke
				(width 0.1)
				(type default)
			)
			(layer "F.Fab")
		)
		(fp_line
			(start -0.12065 0.3048)
			(end -0.67945 0.3048)
			(stroke
				(width 0.1)
				(type default)
			)
			(layer "F.Fab")
		)
		(fp_line
			(start 0.120396 0.3048)
			(end 0.120396 0.2794)
			(stroke
				(width 0.1)
				(type default)
			)
			(layer "F.Fab")
		)
		(fp_line
			(start 0.67945 0.3048)
			(end 0.120396 0.3048)
			(stroke
				(width 0.1)
				(type default)
			)
			(layer "F.Fab")
		)
		(fp_line
			(start -0.12065 0.2794)
			(end -0.12065 0.3048)
			(stroke
				(width 0.1)
				(type default)
			)
			(layer "F.Fab")
		)
		(fp_line
			(start 0.120396 0.2794)
			(end -0.12065 0.2794)
			(stroke
				(width 0.1)
				(type default)
			)
			(layer "F.Fab")
		)
		(fp_line
			(start -0.12065 -0.2794)
			(end 0.12065 -0.2794)
			(stroke
				(width 0.1)
				(type default)
			)
			(layer "F.Fab")
		)
		(fp_line
			(start 0.12065 -0.2794)
			(end 0.12065 -0.3048)
			(stroke
				(width 0.1)
				(type default)
			)
			(layer "F.Fab")
		)
		(fp_line
			(start 0.12065 -0.3048)
			(end 0.67945 -0.3048)
			(stroke
				(width 0.1)
				(type default)
			)
			(layer "F.Fab")
		)
		(fp_line
			(start 0.67945 -0.3048)
			(end 0.67945 0.3048)
			(stroke
				(width 0.1)
				(type default)
			)
			(layer "F.Fab")
		)
		(fp_line
			(start -0.67945 -0.305054)
			(end -0.12065 -0.305054)
			(stroke
				(width 0.1)
				(type default)
			)
			(layer "F.Fab")
		)
		(fp_line
			(start -0.12065 -0.305054)
			(end -0.12065 -0.2794)
			(stroke
				(width 0.1)
				(type default)
			)
			(layer "F.Fab")
		)
		(pad "1" smd circle
			(at -0.40005 0 270)
			(size 0 0)
			(layers "F.Cu" "F.Mask" "F.Paste")
			(net "GND")
		)
		(pad "2" smd circle
			(at 0.40005 0 270)
			(size 0 0)
			(layers "F.Cu" "F.Mask" "F.Paste")
			(net "HSC_P12V_EN")
		)
	)
	(footprint ""
		(layer "F.Cu")
		(at 142.368016 -55.083456)
		(property "Reference" "PC313"
			(at 0 0 0)
			(layer "F.SilkS")
			(hide yes)
			(effects
				(font
					(size 1.27 1.27)
				)
			)
		)
		(property "Value" ""
			(at 0 0 0)
			(layer "F.Fab")
			(effects
				(font
					(size 1.27 1.27)
				)
			)
		)
		(duplicate_pad_numbers_are_jumpers no)
		(fp_line
			(start -0.7874 -0.4064)
			(end 0.7874 -0.4064)
			(stroke
				(width 0.1524)
				(type default)
			)
			(layer "F.SilkS")
		)
		(fp_line
			(start -0.7874 0.4064)
			(end -0.7874 -0.4064)
			(stroke
				(width 0.1524)
				(type default)
			)
			(layer "F.SilkS")
		)
		(fp_line
			(start 0.7874 -0.4064)
			(end 0.7874 0.4064)
			(stroke
				(width 0.1524)
				(type default)
			)
			(layer "F.SilkS")
		)
		(fp_line
			(start 0.7874 0.4064)
			(end -0.7874 0.4064)
			(stroke
				(width 0.1524)
				(type default)
			)
			(layer "F.SilkS")
		)
		(fp_line
			(start -0.67945 -0.305054)
			(end -0.12065 -0.305054)
			(stroke
				(width 0.1)
				(type default)
			)
			(layer "F.Fab")
		)
		(fp_line
			(start -0.67945 0.3048)
			(end -0.67945 -0.305054)
			(stroke
				(width 0.1)
				(type default)
			)
			(layer "F.Fab")
		)
		(fp_line
			(start -0.12065 -0.305054)
			(end -0.12065 -0.2794)
			(stroke
				(width 0.1)
				(type default)
			)
			(layer "F.Fab")
		)
		(fp_line
			(start -0.12065 -0.2794)
			(end 0.12065 -0.2794)
			(stroke
				(width 0.1)
				(type default)
			)
			(layer "F.Fab")
		)
		(fp_line
			(start -0.12065 0.2794)
			(end -0.12065 0.3048)
			(stroke
				(width 0.1)
				(type default)
			)
			(layer "F.Fab")
		)
		(fp_line
			(start -0.12065 0.3048)
			(end -0.67945 0.3048)
			(stroke
				(width 0.1)
				(type default)
			)
			(layer "F.Fab")
		)
		(fp_line
			(start 0.120396 0.2794)
			(end -0.12065 0.2794)
			(stroke
				(width 0.1)
				(type default)
			)
			(layer "F.Fab")
		)
		(fp_line
			(start 0.120396 0.3048)
			(end 0.120396 0.2794)
			(stroke
				(width 0.1)
				(type default)
			)
			(layer "F.Fab")
		)
		(fp_line
			(start 0.12065 -0.3048)
			(end 0.67945 -0.3048)
			(stroke
				(width 0.1)
				(type default)
			)
			(layer "F.Fab")
		)
		(fp_line
			(start 0.12065 -0.2794)
			(end 0.12065 -0.3048)
			(stroke
				(width 0.1)
				(type default)
			)
			(layer "F.Fab")
		)
		(fp_line
			(start 0.67945 -0.3048)
			(end 0.67945 0.3048)
			(stroke
				(width 0.1)
				(type default)
			)
			(layer "F.Fab")
		)
		(fp_line
			(start 0.67945 0.3048)
			(end 0.120396 0.3048)
			(stroke
				(width 0.1)
				(type default)
			)
			(layer "F.Fab")
		)
		(pad "1" smd circle
			(at -0.40005 0)
			(size 0 0)
			(layers "F.Cu" "F.Mask" "F.Paste")
			(net "P5V_AUX")
		)
		(pad "2" smd circle
			(at 0.40005 0)
			(size 0 0)
			(layers "F.Cu" "F.Mask" "F.Paste")
			(net "GND")
		)
	)
	(footprint ""
		(layer "F.Cu")
		(at 261.997952 -215.194388 180)
		(property "Reference" "R6646"
			(at 0 0 180)
			(layer "F.SilkS")
			(hide yes)
			(effects
				(font
					(size 1.27 1.27)
				)
			)
		)
		(property "Value" ""
			(at 0 0 180)
			(layer "F.Fab")
			(effects
				(font
					(size 1.27 1.27)
				)
			)
		)
		(duplicate_pad_numbers_are_jumpers no)
		(fp_line
			(start 0.7874 0.4064)
			(end -0.7874 0.4064)
			(stroke
				(width 0.1524)
				(type default)
			)
			(layer "F.SilkS")
		)
		(fp_line
			(start 0.7874 -0.4064)
			(end 0.7874 0.4064)
			(stroke
				(width 0.1524)
				(type default)
			)
			(layer "F.SilkS")
		)
		(fp_line
			(start -0.7874 0.4064)
			(end -0.7874 -0.4064)
			(stroke
				(width 0.1524)
				(type default)
			)
			(layer "F.SilkS")
		)
		(fp_line
			(start -0.7874 -0.4064)
			(end 0.7874 -0.4064)
			(stroke
				(width 0.1524)
				(type default)
			)
			(layer "F.SilkS")
		)
		(fp_line
			(start 0.67945 0.3048)
			(end 0.120396 0.3048)
			(stroke
				(width 0.1)
				(type default)
			)
			(layer "F.Fab")
		)
		(fp_line
			(start 0.67945 -0.3048)
			(end 0.67945 0.3048)
			(stroke
				(width 0.1)
				(type default)
			)
			(layer "F.Fab")
		)
		(fp_line
			(start 0.12065 -0.2794)
			(end 0.12065 -0.3048)
			(stroke
				(width 0.1)
				(type default)
			)
			(layer "F.Fab")
		)
		(fp_line
			(start 0.12065 -0.3048)
			(end 0.67945 -0.3048)
			(stroke
				(width 0.1)
				(type default)
			)
			(layer "F.Fab")
		)
		(fp_line
			(start 0.120396 0.3048)
			(end 0.120396 0.2794)
			(stroke
				(width 0.1)
				(type default)
			)
			(layer "F.Fab")
		)
		(fp_line
			(start 0.120396 0.2794)
			(end -0.12065 0.2794)
			(stroke
				(width 0.1)
				(type default)
			)
			(layer "F.Fab")
		)
		(fp_line
			(start -0.12065 0.3048)
			(end -0.67945 0.3048)
			(stroke
				(width 0.1)
				(type default)
			)
			(layer "F.Fab")
		)
		(fp_line
			(start -0.12065 0.2794)
			(end -0.12065 0.3048)
			(stroke
				(width 0.1)
				(type default)
			)
			(layer "F.Fab")
		)
		(fp_line
			(start -0.12065 -0.2794)
			(end 0.12065 -0.2794)
			(stroke
				(width 0.1)
				(type default)
			)
			(layer "F.Fab")
		)
		(fp_line
			(start -0.12065 -0.305054)
			(end -0.12065 -0.2794)
			(stroke
				(width 0.1)
				(type default)
			)
			(layer "F.Fab")
		)
		(fp_line
			(start -0.67945 0.3048)
			(end -0.67945 -0.305054)
			(stroke
				(width 0.1)
				(type default)
			)
			(layer "F.Fab")
		)
		(fp_line
			(start -0.67945 -0.305054)
			(end -0.12065 -0.305054)
			(stroke
				(width 0.1)
				(type default)
			)
			(layer "F.Fab")
		)
		(pad "1" smd circle
			(at -0.40005 0 180)
			(size 0 0)
			(layers "F.Cu" "F.Mask" "F.Paste")
			(net "HSC_D_OC_BIC_N")
		)
		(pad "2" smd circle
			(at 0.40005 0 180)
			(size 0 0)
			(layers "F.Cu" "F.Mask" "F.Paste")
			(net "HSC_D_OC_BUF_R_N")
		)
	)
	(footprint ""
		(layer "F.Cu")
		(at 8.049768 -158.828994 180)
		(property "Reference" "R5830"
			(at 0 0 180)
			(layer "F.SilkS")
			(hide yes)
			(effects
				(font
					(size 1.27 1.27)
				)
			)
		)
		(property "Value" ""
			(at 0 0 180)
			(layer "F.Fab")
			(effects
				(font
					(size 1.27 1.27)
				)
			)
		)
		(duplicate_pad_numbers_are_jumpers no)
		(fp_line
			(start 0.7874 0.4064)
			(end -0.7874 0.4064)
			(stroke
				(width 0.1524)
				(type default)
			)
			(layer "F.SilkS")
		)
		(fp_line
			(start 0.7874 -0.4064)
			(end 0.7874 0.4064)
			(stroke
				(width 0.1524)
				(type default)
			)
			(layer "F.SilkS")
		)
		(fp_line
			(start -0.7874 0.4064)
			(end -0.7874 -0.4064)
			(stroke
				(width 0.1524)
				(type default)
			)
			(layer "F.SilkS")
		)
		(fp_line
			(start -0.7874 -0.4064)
			(end 0.7874 -0.4064)
			(stroke
				(width 0.1524)
				(type default)
			)
			(layer "F.SilkS")
		)
		(fp_line
			(start 0.67945 0.3048)
			(end 0.120396 0.3048)
			(stroke
				(width 0.1)
				(type default)
			)
			(layer "F.Fab")
		)
		(fp_line
			(start 0.67945 -0.3048)
			(end 0.67945 0.3048)
			(stroke
				(width 0.1)
				(type default)
			)
			(layer "F.Fab")
		)
		(fp_line
			(start 0.12065 -0.2794)
			(end 0.12065 -0.3048)
			(stroke
				(width 0.1)
				(type default)
			)
			(layer "F.Fab")
		)
		(fp_line
			(start 0.12065 -0.3048)
			(end 0.67945 -0.3048)
			(stroke
				(width 0.1)
				(type default)
			)
			(layer "F.Fab")
		)
		(fp_line
			(start 0.120396 0.3048)
			(end 0.120396 0.2794)
			(stroke
				(width 0.1)
				(type default)
			)
			(layer "F.Fab")
		)
		(fp_line
			(start 0.120396 0.2794)
			(end -0.12065 0.2794)
			(stroke
				(width 0.1)
				(type default)
			)
			(layer "F.Fab")
		)
		(fp_line
			(start -0.12065 0.3048)
			(end -0.67945 0.3048)
			(stroke
				(width 0.1)
				(type default)
			)
			(layer "F.Fab")
		)
		(fp_line
			(start -0.12065 0.2794)
			(end -0.12065 0.3048)
			(stroke
				(width 0.1)
				(type default)
			)
			(layer "F.Fab")
		)
		(fp_line
			(start -0.12065 -0.2794)
			(end 0.12065 -0.2794)
			(stroke
				(width 0.1)
				(type default)
			)
			(layer "F.Fab")
		)
		(fp_line
			(start -0.12065 -0.305054)
			(end -0.12065 -0.2794)
			(stroke
				(width 0.1)
				(type default)
			)
			(layer "F.Fab")
		)
		(fp_line
			(start -0.67945 0.3048)
			(end -0.67945 -0.305054)
			(stroke
				(width 0.1)
				(type default)
			)
			(layer "F.Fab")
		)
		(fp_line
			(start -0.67945 -0.305054)
			(end -0.12065 -0.305054)
			(stroke
				(width 0.1)
				(type default)
			)
			(layer "F.Fab")
		)
		(pad "1" smd circle
			(at -0.40005 0 180)
			(size 0 0)
			(layers "F.Cu" "F.Mask" "F.Paste")
			(net "PWRGD_P12V_NIC0_CO")
		)
		(pad "2" smd circle
			(at 0.40005 0 180)
			(size 0 0)
			(layers "F.Cu" "F.Mask" "F.Paste")
			(net "PWRGD_P12V_NIC0_R")
		)
	)
	(footprint ""
		(layer "F.Cu")
		(at 353.822 -165.608)
		(property "Reference" "R4776"
			(at 0 0 0)
			(layer "F.SilkS")
			(hide yes)
			(effects
				(font
					(size 1.27 1.27)
				)
			)
		)
		(property "Value" ""
			(at 0 0 0)
			(layer "F.Fab")
			(effects
				(font
					(size 1.27 1.27)
				)
			)
		)
		(duplicate_pad_numbers_are_jumpers no)
		(fp_line
			(start -0.7874 -0.4064)
			(end 0.7874 -0.4064)
			(stroke
				(width 0.1524)
				(type default)
			)
			(layer "F.SilkS")
		)
		(fp_line
			(start -0.7874 0.4064)
			(end -0.7874 -0.4064)
			(stroke
				(width 0.1524)
				(type default)
			)
			(layer "F.SilkS")
		)
		(fp_line
			(start 0.7874 -0.4064)
			(end 0.7874 0.4064)
			(stroke
				(width 0.1524)
				(type default)
			)
			(layer "F.SilkS")
		)
		(fp_line
			(start 0.7874 0.4064)
			(end -0.7874 0.4064)
			(stroke
				(width 0.1524)
				(type default)
			)
			(layer "F.SilkS")
		)
		(fp_line
			(start -0.67945 -0.305054)
			(end -0.12065 -0.305054)
			(stroke
				(width 0.1)
				(type default)
			)
			(layer "F.Fab")
		)
		(fp_line
			(start -0.67945 0.3048)
			(end -0.67945 -0.305054)
			(stroke
				(width 0.1)
				(type default)
			)
			(layer "F.Fab")
		)
		(fp_line
			(start -0.12065 -0.305054)
			(end -0.12065 -0.2794)
			(stroke
				(width 0.1)
				(type default)
			)
			(layer "F.Fab")
		)
		(fp_line
			(start -0.12065 -0.2794)
			(end 0.12065 -0.2794)
			(stroke
				(width 0.1)
				(type default)
			)
			(layer "F.Fab")
		)
		(fp_line
			(start -0.12065 0.2794)
			(end -0.12065 0.3048)
			(stroke
				(width 0.1)
				(type default)
			)
			(layer "F.Fab")
		)
		(fp_line
			(start -0.12065 0.3048)
			(end -0.67945 0.3048)
			(stroke
				(width 0.1)
				(type default)
			)
			(layer "F.Fab")
		)
		(fp_line
			(start 0.120396 0.2794)
			(end -0.12065 0.2794)
			(stroke
				(width 0.1)
				(type default)
			)
			(layer "F.Fab")
		)
		(fp_line
			(start 0.120396 0.3048)
			(end 0.120396 0.2794)
			(stroke
				(width 0.1)
				(type default)
			)
			(layer "F.Fab")
		)
		(fp_line
			(start 0.12065 -0.3048)
			(end 0.67945 -0.3048)
			(stroke
				(width 0.1)
				(type default)
			)
			(layer "F.Fab")
		)
		(fp_line
			(start 0.12065 -0.2794)
			(end 0.12065 -0.3048)
			(stroke
				(width 0.1)
				(type default)
			)
			(layer "F.Fab")
		)
		(fp_line
			(start 0.67945 -0.3048)
			(end 0.67945 0.3048)
			(stroke
				(width 0.1)
				(type default)
			)
			(layer "F.Fab")
		)
		(fp_line
			(start 0.67945 0.3048)
			(end 0.120396 0.3048)
			(stroke
				(width 0.1)
				(type default)
			)
			(layer "F.Fab")
		)
		(pad "1" smd circle
			(at -0.40005 0)
			(size 0 0)
			(layers "F.Cu" "F.Mask" "F.Paste")
			(net "PRSNT_NIC5_FPGA_PCA9555_N")
		)
		(pad "2" smd circle
			(at 0.40005 0)
			(size 0 0)
			(layers "F.Cu" "F.Mask" "F.Paste")
			(net "PRSNT_NIC5_FPGA_R_N")
		)
	)
	(footprint ""
		(layer "F.Cu")
		(at 55.357776 -27.006296 -90)
		(property "Reference" "PR6923"
			(at 0 0 270)
			(layer "F.SilkS")
			(hide yes)
			(effects
				(font
					(size 1.27 1.27)
				)
			)
		)
		(property "Value" ""
			(at 0 0 270)
			(layer "F.Fab")
			(effects
				(font
					(size 1.27 1.27)
				)
			)
		)
		(duplicate_pad_numbers_are_jumpers no)
		(fp_line
			(start -0.7874 0.4064)
			(end -0.7874 -0.4064)
			(stroke
				(width 0.1524)
				(type default)
			)
			(layer "F.SilkS")
		)
		(fp_line
			(start 0.7874 0.4064)
			(end -0.7874 0.4064)
			(stroke
				(width 0.1524)
				(type default)
			)
			(layer "F.SilkS")
		)
		(fp_line
			(start -0.7874 -0.4064)
			(end 0.7874 -0.4064)
			(stroke
				(width 0.1524)
				(type default)
			)
			(layer "F.SilkS")
		)
		(fp_line
			(start 0.7874 -0.4064)
			(end 0.7874 0.4064)
			(stroke
				(width 0.1524)
				(type default)
			)
			(layer "F.SilkS")
		)
		(fp_line
			(start -0.67945 0.3048)
			(end -0.67945 -0.305054)
			(stroke
				(width 0.1)
				(type default)
			)
			(layer "F.Fab")
		)
		(fp_line
			(start -0.12065 0.3048)
			(end -0.67945 0.3048)
			(stroke
				(width 0.1)
				(type default)
			)
			(layer "F.Fab")
		)
		(fp_line
			(start 0.120396 0.3048)
			(end 0.120396 0.2794)
			(stroke
				(width 0.1)
				(type default)
			)
			(layer "F.Fab")
		)
		(fp_line
			(start 0.67945 0.3048)
			(end 0.120396 0.3048)
			(stroke
				(width 0.1)
				(type default)
			)
			(layer "F.Fab")
		)
		(fp_line
			(start -0.12065 0.2794)
			(end -0.12065 0.3048)
			(stroke
				(width 0.1)
				(type default)
			)
			(layer "F.Fab")
		)
		(fp_line
			(start 0.120396 0.2794)
			(end -0.12065 0.2794)
			(stroke
				(width 0.1)
				(type default)
			)
			(layer "F.Fab")
		)
		(fp_line
			(start -0.12065 -0.2794)
			(end 0.12065 -0.2794)
			(stroke
				(width 0.1)
				(type default)
			)
			(layer "F.Fab")
		)
		(fp_line
			(start 0.12065 -0.2794)
			(end 0.12065 -0.3048)
			(stroke
				(width 0.1)
				(type default)
			)
			(layer "F.Fab")
		)
		(fp_line
			(start 0.12065 -0.3048)
			(end 0.67945 -0.3048)
			(stroke
				(width 0.1)
				(type default)
			)
			(layer "F.Fab")
		)
		(fp_line
			(start 0.67945 -0.3048)
			(end 0.67945 0.3048)
			(stroke
				(width 0.1)
				(type default)
			)
			(layer "F.Fab")
		)
		(fp_line
			(start -0.67945 -0.305054)
			(end -0.12065 -0.305054)
			(stroke
				(width 0.1)
				(type default)
			)
			(layer "F.Fab")
		)
		(fp_line
			(start -0.12065 -0.305054)
			(end -0.12065 -0.2794)
			(stroke
				(width 0.1)
				(type default)
			)
			(layer "F.Fab")
		)
		(pad "1" smd circle
			(at -0.40005 0 270)
			(size 0 0)
			(layers "F.Cu" "F.Mask" "F.Paste")
			(net "P3V3_SSD2_CO_MODE")
		)
		(pad "2" smd circle
			(at 0.40005 0 270)
			(size 0 0)
			(layers "F.Cu" "F.Mask" "F.Paste")
			(net "GND")
		)
	)
	(footprint ""
		(layer "F.Cu")
		(at 101.971094 -397.512286 -90)
		(property "Reference" "R5454"
			(at 0 0 270)
			(layer "F.SilkS")
			(hide yes)
			(effects
				(font
					(size 1.27 1.27)
				)
			)
		)
		(property "Value" ""
			(at 0 0 270)
			(layer "F.Fab")
			(effects
				(font
					(size 1.27 1.27)
				)
			)
		)
		(duplicate_pad_numbers_are_jumpers no)
		(fp_line
			(start -0.7874 0.4064)
			(end -0.7874 -0.4064)
			(stroke
				(width 0.1524)
				(type default)
			)
			(layer "F.SilkS")
		)
		(fp_line
			(start 0.7874 0.4064)
			(end -0.7874 0.4064)
			(stroke
				(width 0.1524)
				(type default)
			)
			(layer "F.SilkS")
		)
		(fp_line
			(start -0.7874 -0.4064)
			(end 0.7874 -0.4064)
			(stroke
				(width 0.1524)
				(type default)
			)
			(layer "F.SilkS")
		)
		(fp_line
			(start 0.7874 -0.4064)
			(end 0.7874 0.4064)
			(stroke
				(width 0.1524)
				(type default)
			)
			(layer "F.SilkS")
		)
		(fp_line
			(start -0.67945 0.3048)
			(end -0.67945 -0.305054)
			(stroke
				(width 0.1)
				(type default)
			)
			(layer "F.Fab")
		)
		(fp_line
			(start -0.12065 0.3048)
			(end -0.67945 0.3048)
			(stroke
				(width 0.1)
				(type default)
			)
			(layer "F.Fab")
		)
		(fp_line
			(start 0.120396 0.3048)
			(end 0.120396 0.2794)
			(stroke
				(width 0.1)
				(type default)
			)
			(layer "F.Fab")
		)
		(fp_line
			(start 0.67945 0.3048)
			(end 0.120396 0.3048)
			(stroke
				(width 0.1)
				(type default)
			)
			(layer "F.Fab")
		)
		(fp_line
			(start -0.12065 0.2794)
			(end -0.12065 0.3048)
			(stroke
				(width 0.1)
				(type default)
			)
			(layer "F.Fab")
		)
		(fp_line
			(start 0.120396 0.2794)
			(end -0.12065 0.2794)
			(stroke
				(width 0.1)
				(type default)
			)
			(layer "F.Fab")
		)
		(fp_line
			(start -0.12065 -0.2794)
			(end 0.12065 -0.2794)
			(stroke
				(width 0.1)
				(type default)
			)
			(layer "F.Fab")
		)
		(fp_line
			(start 0.12065 -0.2794)
			(end 0.12065 -0.3048)
			(stroke
				(width 0.1)
				(type default)
			)
			(layer "F.Fab")
		)
		(fp_line
			(start 0.12065 -0.3048)
			(end 0.67945 -0.3048)
			(stroke
				(width 0.1)
				(type default)
			)
			(layer "F.Fab")
		)
		(fp_line
			(start 0.67945 -0.3048)
			(end 0.67945 0.3048)
			(stroke
				(width 0.1)
				(type default)
			)
			(layer "F.Fab")
		)
		(fp_line
			(start -0.67945 -0.305054)
			(end -0.12065 -0.305054)
			(stroke
				(width 0.1)
				(type default)
			)
			(layer "F.Fab")
		)
		(fp_line
			(start -0.12065 -0.305054)
			(end -0.12065 -0.2794)
			(stroke
				(width 0.1)
				(type default)
			)
			(layer "F.Fab")
		)
		(pad "1" smd circle
			(at -0.40005 0 270)
			(size 0 0)
			(layers "F.Cu" "F.Mask" "F.Paste")
			(net "P3V3_AUX")
		)
		(pad "2" smd circle
			(at 0.40005 0 270)
			(size 0 0)
			(layers "F.Cu" "F.Mask" "F.Paste")
			(net "BIC_USB_HUB_OVCUR4")
		)
	)
	(footprint ""
		(layer "F.Cu")
		(at 170.956224 -32.848042 -90)
		(property "Reference" "R6066"
			(at 0 0 270)
			(layer "F.SilkS")
			(hide yes)
			(effects
				(font
					(size 1.27 1.27)
				)
			)
		)
		(property "Value" ""
			(at 0 0 270)
			(layer "F.Fab")
			(effects
				(font
					(size 1.27 1.27)
				)
			)
		)
		(duplicate_pad_numbers_are_jumpers no)
		(fp_line
			(start -0.7874 0.4064)
			(end -0.7874 -0.4064)
			(stroke
				(width 0.1524)
				(type default)
			)
			(layer "F.SilkS")
		)
		(fp_line
			(start 0.7874 0.4064)
			(end -0.7874 0.4064)
			(stroke
				(width 0.1524)
				(type default)
			)
			(layer "F.SilkS")
		)
		(fp_line
			(start -0.7874 -0.4064)
			(end 0.7874 -0.4064)
			(stroke
				(width 0.1524)
				(type default)
			)
			(layer "F.SilkS")
		)
		(fp_line
			(start 0.7874 -0.4064)
			(end 0.7874 0.4064)
			(stroke
				(width 0.1524)
				(type default)
			)
			(layer "F.SilkS")
		)
		(fp_line
			(start -0.67945 0.3048)
			(end -0.67945 -0.305054)
			(stroke
				(width 0.1)
				(type default)
			)
			(layer "F.Fab")
		)
		(fp_line
			(start -0.12065 0.3048)
			(end -0.67945 0.3048)
			(stroke
				(width 0.1)
				(type default)
			)
			(layer "F.Fab")
		)
		(fp_line
			(start 0.120396 0.3048)
			(end 0.120396 0.2794)
			(stroke
				(width 0.1)
				(type default)
			)
			(layer "F.Fab")
		)
		(fp_line
			(start 0.67945 0.3048)
			(end 0.120396 0.3048)
			(stroke
				(width 0.1)
				(type default)
			)
			(layer "F.Fab")
		)
		(fp_line
			(start -0.12065 0.2794)
			(end -0.12065 0.3048)
			(stroke
				(width 0.1)
				(type default)
			)
			(layer "F.Fab")
		)
		(fp_line
			(start 0.120396 0.2794)
			(end -0.12065 0.2794)
			(stroke
				(width 0.1)
				(type default)
			)
			(layer "F.Fab")
		)
		(fp_line
			(start -0.12065 -0.2794)
			(end 0.12065 -0.2794)
			(stroke
				(width 0.1)
				(type default)
			)
			(layer "F.Fab")
		)
		(fp_line
			(start 0.12065 -0.2794)
			(end 0.12065 -0.3048)
			(stroke
				(width 0.1)
				(type default)
			)
			(layer "F.Fab")
		)
		(fp_line
			(start 0.12065 -0.3048)
			(end 0.67945 -0.3048)
			(stroke
				(width 0.1)
				(type default)
			)
			(layer "F.Fab")
		)
		(fp_line
			(start 0.67945 -0.3048)
			(end 0.67945 0.3048)
			(stroke
				(width 0.1)
				(type default)
			)
			(layer "F.Fab")
		)
		(fp_line
			(start -0.67945 -0.305054)
			(end -0.12065 -0.305054)
			(stroke
				(width 0.1)
				(type default)
			)
			(layer "F.Fab")
		)
		(fp_line
			(start -0.12065 -0.305054)
			(end -0.12065 -0.2794)
			(stroke
				(width 0.1)
				(type default)
			)
			(layer "F.Fab")
		)
		(pad "1" smd circle
			(at -0.40005 0 270)
			(size 0 0)
			(layers "F.Cu" "F.Mask" "F.Paste")
			(net "SSD6_AUX_P3V3_EN_R")
		)
		(pad "2" smd circle
			(at 0.40005 0 270)
			(size 0 0)
			(layers "F.Cu" "F.Mask" "F.Paste")
			(net "P3V3_SSD6_CO_EN")
		)
	)
	(footprint ""
		(layer "F.Cu")
		(at 305.147218 -20.35556)
		(property "Reference" "C3948"
			(at 0 0 0)
			(layer "F.SilkS")
			(hide yes)
			(effects
				(font
					(size 1.27 1.27)
				)
			)
		)
		(property "Value" ""
			(at 0 0 0)
			(layer "F.Fab")
			(effects
				(font
					(size 1.27 1.27)
				)
			)
		)
		(duplicate_pad_numbers_are_jumpers no)
		(fp_line
			(start -0.7874 -0.4064)
			(end 0.7874 -0.4064)
			(stroke
				(width 0.1524)
				(type default)
			)
			(layer "F.SilkS")
		)
		(fp_line
			(start -0.7874 0.4064)
			(end -0.7874 -0.4064)
			(stroke
				(width 0.1524)
				(type default)
			)
			(layer "F.SilkS")
		)
		(fp_line
			(start 0.7874 -0.4064)
			(end 0.7874 0.4064)
			(stroke
				(width 0.1524)
				(type default)
			)
			(layer "F.SilkS")
		)
		(fp_line
			(start 0.7874 0.4064)
			(end -0.7874 0.4064)
			(stroke
				(width 0.1524)
				(type default)
			)
			(layer "F.SilkS")
		)
		(fp_line
			(start -0.67945 -0.305054)
			(end -0.12065 -0.305054)
			(stroke
				(width 0.1)
				(type default)
			)
			(layer "F.Fab")
		)
		(fp_line
			(start -0.67945 0.3048)
			(end -0.67945 -0.305054)
			(stroke
				(width 0.1)
				(type default)
			)
			(layer "F.Fab")
		)
		(fp_line
			(start -0.12065 -0.305054)
			(end -0.12065 -0.2794)
			(stroke
				(width 0.1)
				(type default)
			)
			(layer "F.Fab")
		)
		(fp_line
			(start -0.12065 -0.2794)
			(end 0.12065 -0.2794)
			(stroke
				(width 0.1)
				(type default)
			)
			(layer "F.Fab")
		)
		(fp_line
			(start -0.12065 0.2794)
			(end -0.12065 0.3048)
			(stroke
				(width 0.1)
				(type default)
			)
			(layer "F.Fab")
		)
		(fp_line
			(start -0.12065 0.3048)
			(end -0.67945 0.3048)
			(stroke
				(width 0.1)
				(type default)
			)
			(layer "F.Fab")
		)
		(fp_line
			(start 0.120396 0.2794)
			(end -0.12065 0.2794)
			(stroke
				(width 0.1)
				(type default)
			)
			(layer "F.Fab")
		)
		(fp_line
			(start 0.120396 0.3048)
			(end 0.120396 0.2794)
			(stroke
				(width 0.1)
				(type default)
			)
			(layer "F.Fab")
		)
		(fp_line
			(start 0.12065 -0.3048)
			(end 0.67945 -0.3048)
			(stroke
				(width 0.1)
				(type default)
			)
			(layer "F.Fab")
		)
		(fp_line
			(start 0.12065 -0.2794)
			(end 0.12065 -0.3048)
			(stroke
				(width 0.1)
				(type default)
			)
			(layer "F.Fab")
		)
		(fp_line
			(start 0.67945 -0.3048)
			(end 0.67945 0.3048)
			(stroke
				(width 0.1)
				(type default)
			)
			(layer "F.Fab")
		)
		(fp_line
			(start 0.67945 0.3048)
			(end 0.120396 0.3048)
			(stroke
				(width 0.1)
				(type default)
			)
			(layer "F.Fab")
		)
		(pad "1" smd circle
			(at -0.40005 0)
			(size 0 0)
			(layers "F.Cu" "F.Mask" "F.Paste")
			(net "P12V_SSD10")
		)
		(pad "2" smd circle
			(at 0.40005 0)
			(size 0 0)
			(layers "F.Cu" "F.Mask" "F.Paste")
			(net "GND")
		)
	)
	(footprint ""
		(layer "F.Cu")
		(at 310.443626 -48.93691 180)
		(property "Reference" "R622"
			(at 0 0 180)
			(layer "F.SilkS")
			(hide yes)
			(effects
				(font
					(size 1.27 1.27)
				)
			)
		)
		(property "Value" ""
			(at 0 0 180)
			(layer "F.Fab")
			(effects
				(font
					(size 1.27 1.27)
				)
			)
		)
		(duplicate_pad_numbers_are_jumpers no)
		(fp_line
			(start 0.7874 0.4064)
			(end -0.7874 0.4064)
			(stroke
				(width 0.1524)
				(type default)
			)
			(layer "F.SilkS")
		)
		(fp_line
			(start 0.7874 -0.4064)
			(end 0.7874 0.4064)
			(stroke
				(width 0.1524)
				(type default)
			)
			(layer "F.SilkS")
		)
		(fp_line
			(start -0.7874 0.4064)
			(end -0.7874 -0.4064)
			(stroke
				(width 0.1524)
				(type default)
			)
			(layer "F.SilkS")
		)
		(fp_line
			(start -0.7874 -0.4064)
			(end 0.7874 -0.4064)
			(stroke
				(width 0.1524)
				(type default)
			)
			(layer "F.SilkS")
		)
		(fp_line
			(start 0.67945 0.3048)
			(end 0.120396 0.3048)
			(stroke
				(width 0.1)
				(type default)
			)
			(layer "F.Fab")
		)
		(fp_line
			(start 0.67945 -0.3048)
			(end 0.67945 0.3048)
			(stroke
				(width 0.1)
				(type default)
			)
			(layer "F.Fab")
		)
		(fp_line
			(start 0.12065 -0.2794)
			(end 0.12065 -0.3048)
			(stroke
				(width 0.1)
				(type default)
			)
			(layer "F.Fab")
		)
		(fp_line
			(start 0.12065 -0.3048)
			(end 0.67945 -0.3048)
			(stroke
				(width 0.1)
				(type default)
			)
			(layer "F.Fab")
		)
		(fp_line
			(start 0.120396 0.3048)
			(end 0.120396 0.2794)
			(stroke
				(width 0.1)
				(type default)
			)
			(layer "F.Fab")
		)
		(fp_line
			(start 0.120396 0.2794)
			(end -0.12065 0.2794)
			(stroke
				(width 0.1)
				(type default)
			)
			(layer "F.Fab")
		)
		(fp_line
			(start -0.12065 0.3048)
			(end -0.67945 0.3048)
			(stroke
				(width 0.1)
				(type default)
			)
			(layer "F.Fab")
		)
		(fp_line
			(start -0.12065 0.2794)
			(end -0.12065 0.3048)
			(stroke
				(width 0.1)
				(type default)
			)
			(layer "F.Fab")
		)
		(fp_line
			(start -0.12065 -0.2794)
			(end 0.12065 -0.2794)
			(stroke
				(width 0.1)
				(type default)
			)
			(layer "F.Fab")
		)
		(fp_line
			(start -0.12065 -0.305054)
			(end -0.12065 -0.2794)
			(stroke
				(width 0.1)
				(type default)
			)
			(layer "F.Fab")
		)
		(fp_line
			(start -0.67945 0.3048)
			(end -0.67945 -0.305054)
			(stroke
				(width 0.1)
				(type default)
			)
			(layer "F.Fab")
		)
		(fp_line
			(start -0.67945 -0.305054)
			(end -0.12065 -0.305054)
			(stroke
				(width 0.1)
				(type default)
			)
			(layer "F.Fab")
		)
		(pad "1" smd circle
			(at -0.40005 0 180)
			(size 0 0)
			(layers "F.Cu" "F.Mask" "F.Paste")
			(net "SMB_BIC_I2C6_MUX_SSD_8_15_ADC_R_SDA")
		)
		(pad "2" smd circle
			(at 0.40005 0 180)
			(size 0 0)
			(layers "F.Cu" "F.Mask" "F.Paste")
			(net "SMB_SSD10_ADC_SDA")
		)
	)
	(footprint ""
		(layer "F.Cu")
		(at 208.377282 -112.112806)
		(property "Reference" "PC789"
			(at 0 0 0)
			(layer "F.SilkS")
			(hide yes)
			(effects
				(font
					(size 1.27 1.27)
				)
			)
		)
		(property "Value" ""
			(at 0 0 0)
			(layer "F.Fab")
			(effects
				(font
					(size 1.27 1.27)
				)
			)
		)
		(duplicate_pad_numbers_are_jumpers no)
		(fp_line
			(start -0.7874 -0.4064)
			(end 0.7874 -0.4064)
			(stroke
				(width 0.1524)
				(type default)
			)
			(layer "F.SilkS")
		)
		(fp_line
			(start -0.7874 0.4064)
			(end -0.7874 -0.4064)
			(stroke
				(width 0.1524)
				(type default)
			)
			(layer "F.SilkS")
		)
		(fp_line
			(start 0.7874 -0.4064)
			(end 0.7874 0.4064)
			(stroke
				(width 0.1524)
				(type default)
			)
			(layer "F.SilkS")
		)
		(fp_line
			(start 0.7874 0.4064)
			(end -0.7874 0.4064)
			(stroke
				(width 0.1524)
				(type default)
			)
			(layer "F.SilkS")
		)
		(fp_line
			(start -0.67945 -0.305054)
			(end -0.12065 -0.305054)
			(stroke
				(width 0.1)
				(type default)
			)
			(layer "F.Fab")
		)
		(fp_line
			(start -0.67945 0.3048)
			(end -0.67945 -0.305054)
			(stroke
				(width 0.1)
				(type default)
			)
			(layer "F.Fab")
		)
		(fp_line
			(start -0.12065 -0.305054)
			(end -0.12065 -0.2794)
			(stroke
				(width 0.1)
				(type default)
			)
			(layer "F.Fab")
		)
		(fp_line
			(start -0.12065 -0.2794)
			(end 0.12065 -0.2794)
			(stroke
				(width 0.1)
				(type default)
			)
			(layer "F.Fab")
		)
		(fp_line
			(start -0.12065 0.2794)
			(end -0.12065 0.3048)
			(stroke
				(width 0.1)
				(type default)
			)
			(layer "F.Fab")
		)
		(fp_line
			(start -0.12065 0.3048)
			(end -0.67945 0.3048)
			(stroke
				(width 0.1)
				(type default)
			)
			(layer "F.Fab")
		)
		(fp_line
			(start 0.120396 0.2794)
			(end -0.12065 0.2794)
			(stroke
				(width 0.1)
				(type default)
			)
			(layer "F.Fab")
		)
		(fp_line
			(start 0.120396 0.3048)
			(end 0.120396 0.2794)
			(stroke
				(width 0.1)
				(type default)
			)
			(layer "F.Fab")
		)
		(fp_line
			(start 0.12065 -0.3048)
			(end 0.67945 -0.3048)
			(stroke
				(width 0.1)
				(type default)
			)
			(layer "F.Fab")
		)
		(fp_line
			(start 0.12065 -0.2794)
			(end 0.12065 -0.3048)
			(stroke
				(width 0.1)
				(type default)
			)
			(layer "F.Fab")
		)
		(fp_line
			(start 0.67945 -0.3048)
			(end 0.67945 0.3048)
			(stroke
				(width 0.1)
				(type default)
			)
			(layer "F.Fab")
		)
		(fp_line
			(start 0.67945 0.3048)
			(end 0.120396 0.3048)
			(stroke
				(width 0.1)
				(type default)
			)
			(layer "F.Fab")
		)
		(pad "1" smd circle
			(at -0.40005 0)
			(size 0 0)
			(layers "F.Cu" "F.Mask" "F.Paste")
			(net "P3V3_AUX")
		)
		(pad "2" smd circle
			(at 0.40005 0)
			(size 0 0)
			(layers "F.Cu" "F.Mask" "F.Paste")
			(net "GND")
		)
	)
	(footprint ""
		(layer "F.Cu")
		(at 5.656326 -61.487812 180)
		(property "Reference" "R5836"
			(at 0 0 180)
			(layer "F.SilkS")
			(hide yes)
			(effects
				(font
					(size 1.27 1.27)
				)
			)
		)
		(property "Value" ""
			(at 0 0 180)
			(layer "F.Fab")
			(effects
				(font
					(size 1.27 1.27)
				)
			)
		)
		(duplicate_pad_numbers_are_jumpers no)
		(fp_line
			(start 0.7874 0.4064)
			(end -0.7874 0.4064)
			(stroke
				(width 0.1524)
				(type default)
			)
			(layer "F.SilkS")
		)
		(fp_line
			(start 0.7874 -0.4064)
			(end 0.7874 0.4064)
			(stroke
				(width 0.1524)
				(type default)
			)
			(layer "F.SilkS")
		)
		(fp_line
			(start -0.7874 0.4064)
			(end -0.7874 -0.4064)
			(stroke
				(width 0.1524)
				(type default)
			)
			(layer "F.SilkS")
		)
		(fp_line
			(start -0.7874 -0.4064)
			(end 0.7874 -0.4064)
			(stroke
				(width 0.1524)
				(type default)
			)
			(layer "F.SilkS")
		)
		(fp_line
			(start 0.67945 0.3048)
			(end 0.120396 0.3048)
			(stroke
				(width 0.1)
				(type default)
			)
			(layer "F.Fab")
		)
		(fp_line
			(start 0.67945 -0.3048)
			(end 0.67945 0.3048)
			(stroke
				(width 0.1)
				(type default)
			)
			(layer "F.Fab")
		)
		(fp_line
			(start 0.12065 -0.2794)
			(end 0.12065 -0.3048)
			(stroke
				(width 0.1)
				(type default)
			)
			(layer "F.Fab")
		)
		(fp_line
			(start 0.12065 -0.3048)
			(end 0.67945 -0.3048)
			(stroke
				(width 0.1)
				(type default)
			)
			(layer "F.Fab")
		)
		(fp_line
			(start 0.120396 0.3048)
			(end 0.120396 0.2794)
			(stroke
				(width 0.1)
				(type default)
			)
			(layer "F.Fab")
		)
		(fp_line
			(start 0.120396 0.2794)
			(end -0.12065 0.2794)
			(stroke
				(width 0.1)
				(type default)
			)
			(layer "F.Fab")
		)
		(fp_line
			(start -0.12065 0.3048)
			(end -0.67945 0.3048)
			(stroke
				(width 0.1)
				(type default)
			)
			(layer "F.Fab")
		)
		(fp_line
			(start -0.12065 0.2794)
			(end -0.12065 0.3048)
			(stroke
				(width 0.1)
				(type default)
			)
			(layer "F.Fab")
		)
		(fp_line
			(start -0.12065 -0.2794)
			(end 0.12065 -0.2794)
			(stroke
				(width 0.1)
				(type default)
			)
			(layer "F.Fab")
		)
		(fp_line
			(start -0.12065 -0.305054)
			(end -0.12065 -0.2794)
			(stroke
				(width 0.1)
				(type default)
			)
			(layer "F.Fab")
		)
		(fp_line
			(start -0.67945 0.3048)
			(end -0.67945 -0.305054)
			(stroke
				(width 0.1)
				(type default)
			)
			(layer "F.Fab")
		)
		(fp_line
			(start -0.67945 -0.305054)
			(end -0.12065 -0.305054)
			(stroke
				(width 0.1)
				(type default)
			)
			(layer "F.Fab")
		)
		(pad "1" smd circle
			(at -0.40005 0 180)
			(size 0 0)
			(layers "F.Cu" "F.Mask" "F.Paste")
			(net "P3V3_AUX")
		)
		(pad "2" smd circle
			(at 0.40005 0 180)
			(size 0 0)
			(layers "F.Cu" "F.Mask" "F.Paste")
			(net "PWRGD_P12V_SSD0_D")
		)
	)
	(footprint ""
		(layer "F.Cu")
		(at 63.47079 -137.848848 180)
		(property "Reference" "R57"
			(at 0 0 180)
			(layer "F.SilkS")
			(hide yes)
			(effects
				(font
					(size 1.27 1.27)
				)
			)
		)
		(property "Value" ""
			(at 0 0 180)
			(layer "F.Fab")
			(effects
				(font
					(size 1.27 1.27)
				)
			)
		)
		(duplicate_pad_numbers_are_jumpers no)
		(fp_line
			(start 0.7874 0.4064)
			(end -0.7874 0.4064)
			(stroke
				(width 0.1524)
				(type default)
			)
			(layer "F.SilkS")
		)
		(fp_line
			(start 0.7874 -0.4064)
			(end 0.7874 0.4064)
			(stroke
				(width 0.1524)
				(type default)
			)
			(layer "F.SilkS")
		)
		(fp_line
			(start -0.7874 0.4064)
			(end -0.7874 -0.4064)
			(stroke
				(width 0.1524)
				(type default)
			)
			(layer "F.SilkS")
		)
		(fp_line
			(start -0.7874 -0.4064)
			(end 0.7874 -0.4064)
			(stroke
				(width 0.1524)
				(type default)
			)
			(layer "F.SilkS")
		)
		(fp_line
			(start 0.67945 0.3048)
			(end 0.120396 0.3048)
			(stroke
				(width 0.1)
				(type default)
			)
			(layer "F.Fab")
		)
		(fp_line
			(start 0.67945 -0.3048)
			(end 0.67945 0.3048)
			(stroke
				(width 0.1)
				(type default)
			)
			(layer "F.Fab")
		)
		(fp_line
			(start 0.12065 -0.2794)
			(end 0.12065 -0.3048)
			(stroke
				(width 0.1)
				(type default)
			)
			(layer "F.Fab")
		)
		(fp_line
			(start 0.12065 -0.3048)
			(end 0.67945 -0.3048)
			(stroke
				(width 0.1)
				(type default)
			)
			(layer "F.Fab")
		)
		(fp_line
			(start 0.120396 0.3048)
			(end 0.120396 0.2794)
			(stroke
				(width 0.1)
				(type default)
			)
			(layer "F.Fab")
		)
		(fp_line
			(start 0.120396 0.2794)
			(end -0.12065 0.2794)
			(stroke
				(width 0.1)
				(type default)
			)
			(layer "F.Fab")
		)
		(fp_line
			(start -0.12065 0.3048)
			(end -0.67945 0.3048)
			(stroke
				(width 0.1)
				(type default)
			)
			(layer "F.Fab")
		)
		(fp_line
			(start -0.12065 0.2794)
			(end -0.12065 0.3048)
			(stroke
				(width 0.1)
				(type default)
			)
			(layer "F.Fab")
		)
		(fp_line
			(start -0.12065 -0.2794)
			(end 0.12065 -0.2794)
			(stroke
				(width 0.1)
				(type default)
			)
			(layer "F.Fab")
		)
		(fp_line
			(start -0.12065 -0.305054)
			(end -0.12065 -0.2794)
			(stroke
				(width 0.1)
				(type default)
			)
			(layer "F.Fab")
		)
		(fp_line
			(start -0.67945 0.3048)
			(end -0.67945 -0.305054)
			(stroke
				(width 0.1)
				(type default)
			)
			(layer "F.Fab")
		)
		(fp_line
			(start -0.67945 -0.305054)
			(end -0.12065 -0.305054)
			(stroke
				(width 0.1)
				(type default)
			)
			(layer "F.Fab")
		)
		(pad "1" smd circle
			(at -0.40005 0 180)
			(size 0 0)
			(layers "F.Cu" "F.Mask" "F.Paste")
			(net "PRSNTB1_NIC1_N")
		)
		(pad "2" smd circle
			(at 0.40005 0 180)
			(size 0 0)
			(layers "F.Cu" "F.Mask" "F.Paste")
			(net "P3V3_AUX")
		)
	)
	(footprint ""
		(layer "F.Cu")
		(at 105.7148 -202.4634 -90)
		(property "Reference" "R6631"
			(at 0 0 270)
			(layer "F.SilkS")
			(hide yes)
			(effects
				(font
					(size 1.27 1.27)
				)
			)
		)
		(property "Value" ""
			(at 0 0 270)
			(layer "F.Fab")
			(effects
				(font
					(size 1.27 1.27)
				)
			)
		)
		(duplicate_pad_numbers_are_jumpers no)
		(fp_line
			(start -0.7874 0.4064)
			(end -0.7874 -0.4064)
			(stroke
				(width 0.1524)
				(type default)
			)
			(layer "F.SilkS")
		)
		(fp_line
			(start 0.7874 0.4064)
			(end -0.7874 0.4064)
			(stroke
				(width 0.1524)
				(type default)
			)
			(layer "F.SilkS")
		)
		(fp_line
			(start -0.7874 -0.4064)
			(end 0.7874 -0.4064)
			(stroke
				(width 0.1524)
				(type default)
			)
			(layer "F.SilkS")
		)
		(fp_line
			(start 0.7874 -0.4064)
			(end 0.7874 0.4064)
			(stroke
				(width 0.1524)
				(type default)
			)
			(layer "F.SilkS")
		)
		(fp_line
			(start -0.67945 0.3048)
			(end -0.67945 -0.305054)
			(stroke
				(width 0.1)
				(type default)
			)
			(layer "F.Fab")
		)
		(fp_line
			(start -0.12065 0.3048)
			(end -0.67945 0.3048)
			(stroke
				(width 0.1)
				(type default)
			)
			(layer "F.Fab")
		)
		(fp_line
			(start 0.120396 0.3048)
			(end 0.120396 0.2794)
			(stroke
				(width 0.1)
				(type default)
			)
			(layer "F.Fab")
		)
		(fp_line
			(start 0.67945 0.3048)
			(end 0.120396 0.3048)
			(stroke
				(width 0.1)
				(type default)
			)
			(layer "F.Fab")
		)
		(fp_line
			(start -0.12065 0.2794)
			(end -0.12065 0.3048)
			(stroke
				(width 0.1)
				(type default)
			)
			(layer "F.Fab")
		)
		(fp_line
			(start 0.120396 0.2794)
			(end -0.12065 0.2794)
			(stroke
				(width 0.1)
				(type default)
			)
			(layer "F.Fab")
		)
		(fp_line
			(start -0.12065 -0.2794)
			(end 0.12065 -0.2794)
			(stroke
				(width 0.1)
				(type default)
			)
			(layer "F.Fab")
		)
		(fp_line
			(start 0.12065 -0.2794)
			(end 0.12065 -0.3048)
			(stroke
				(width 0.1)
				(type default)
			)
			(layer "F.Fab")
		)
		(fp_line
			(start 0.12065 -0.3048)
			(end 0.67945 -0.3048)
			(stroke
				(width 0.1)
				(type default)
			)
			(layer "F.Fab")
		)
		(fp_line
			(start 0.67945 -0.3048)
			(end 0.67945 0.3048)
			(stroke
				(width 0.1)
				(type default)
			)
			(layer "F.Fab")
		)
		(fp_line
			(start -0.67945 -0.305054)
			(end -0.12065 -0.305054)
			(stroke
				(width 0.1)
				(type default)
			)
			(layer "F.Fab")
		)
		(fp_line
			(start -0.12065 -0.305054)
			(end -0.12065 -0.2794)
			(stroke
				(width 0.1)
				(type default)
			)
			(layer "F.Fab")
		)
		(pad "1" smd circle
			(at -0.40005 0 270)
			(size 0 0)
			(layers "F.Cu" "F.Mask" "F.Paste")
			(net "UART_PEX0_CLI_BUF_R_TX")
		)
		(pad "2" smd circle
			(at 0.40005 0 270)
			(size 0 0)
			(layers "F.Cu" "F.Mask" "F.Paste")
			(net "UART_PEX0_CLI_CP2108_TX")
		)
	)
	(footprint ""
		(layer "F.Cu")
		(at 382.479042 -59.577986 -90)
		(property "Reference" "R897"
			(at 0 0 270)
			(layer "F.SilkS")
			(hide yes)
			(effects
				(font
					(size 1.27 1.27)
				)
			)
		)
		(property "Value" ""
			(at 0 0 270)
			(layer "F.Fab")
			(effects
				(font
					(size 1.27 1.27)
				)
			)
		)
		(duplicate_pad_numbers_are_jumpers no)
		(fp_line
			(start -0.7874 0.4064)
			(end -0.7874 -0.4064)
			(stroke
				(width 0.1524)
				(type default)
			)
			(layer "F.SilkS")
		)
		(fp_line
			(start 0.7874 0.4064)
			(end -0.7874 0.4064)
			(stroke
				(width 0.1524)
				(type default)
			)
			(layer "F.SilkS")
		)
		(fp_line
			(start -0.7874 -0.4064)
			(end 0.7874 -0.4064)
			(stroke
				(width 0.1524)
				(type default)
			)
			(layer "F.SilkS")
		)
		(fp_line
			(start 0.7874 -0.4064)
			(end 0.7874 0.4064)
			(stroke
				(width 0.1524)
				(type default)
			)
			(layer "F.SilkS")
		)
		(fp_line
			(start -0.67945 0.3048)
			(end -0.67945 -0.305054)
			(stroke
				(width 0.1)
				(type default)
			)
			(layer "F.Fab")
		)
		(fp_line
			(start -0.12065 0.3048)
			(end -0.67945 0.3048)
			(stroke
				(width 0.1)
				(type default)
			)
			(layer "F.Fab")
		)
		(fp_line
			(start 0.120396 0.3048)
			(end 0.120396 0.2794)
			(stroke
				(width 0.1)
				(type default)
			)
			(layer "F.Fab")
		)
		(fp_line
			(start 0.67945 0.3048)
			(end 0.120396 0.3048)
			(stroke
				(width 0.1)
				(type default)
			)
			(layer "F.Fab")
		)
		(fp_line
			(start -0.12065 0.2794)
			(end -0.12065 0.3048)
			(stroke
				(width 0.1)
				(type default)
			)
			(layer "F.Fab")
		)
		(fp_line
			(start 0.120396 0.2794)
			(end -0.12065 0.2794)
			(stroke
				(width 0.1)
				(type default)
			)
			(layer "F.Fab")
		)
		(fp_line
			(start -0.12065 -0.2794)
			(end 0.12065 -0.2794)
			(stroke
				(width 0.1)
				(type default)
			)
			(layer "F.Fab")
		)
		(fp_line
			(start 0.12065 -0.2794)
			(end 0.12065 -0.3048)
			(stroke
				(width 0.1)
				(type default)
			)
			(layer "F.Fab")
		)
		(fp_line
			(start 0.12065 -0.3048)
			(end 0.67945 -0.3048)
			(stroke
				(width 0.1)
				(type default)
			)
			(layer "F.Fab")
		)
		(fp_line
			(start 0.67945 -0.3048)
			(end 0.67945 0.3048)
			(stroke
				(width 0.1)
				(type default)
			)
			(layer "F.Fab")
		)
		(fp_line
			(start -0.67945 -0.305054)
			(end -0.12065 -0.305054)
			(stroke
				(width 0.1)
				(type default)
			)
			(layer "F.Fab")
		)
		(fp_line
			(start -0.12065 -0.305054)
			(end -0.12065 -0.2794)
			(stroke
				(width 0.1)
				(type default)
			)
			(layer "F.Fab")
		)
		(pad "1" smd circle
			(at -0.40005 0 270)
			(size 0 0)
			(layers "F.Cu" "F.Mask" "F.Paste")
			(net "P3V3_SSD13")
		)
		(pad "2" smd circle
			(at 0.40005 0 270)
			(size 0 0)
			(layers "F.Cu" "F.Mask" "F.Paste")
			(net "PWRGD_P3V3_SSD13")
		)
	)
	(footprint ""
		(layer "F.Cu")
		(at 358.013 -224.536 180)
		(property "Reference" "R3624"
			(at 0 0 180)
			(layer "F.SilkS")
			(hide yes)
			(effects
				(font
					(size 1.27 1.27)
				)
			)
		)
		(property "Value" ""
			(at 0 0 180)
			(layer "F.Fab")
			(effects
				(font
					(size 1.27 1.27)
				)
			)
		)
		(duplicate_pad_numbers_are_jumpers no)
		(fp_line
			(start 0.7874 0.4064)
			(end -0.7874 0.4064)
			(stroke
				(width 0.1524)
				(type default)
			)
			(layer "F.SilkS")
		)
		(fp_line
			(start 0.7874 -0.4064)
			(end 0.7874 0.4064)
			(stroke
				(width 0.1524)
				(type default)
			)
			(layer "F.SilkS")
		)
		(fp_line
			(start -0.7874 0.4064)
			(end -0.7874 -0.4064)
			(stroke
				(width 0.1524)
				(type default)
			)
			(layer "F.SilkS")
		)
		(fp_line
			(start -0.7874 -0.4064)
			(end 0.7874 -0.4064)
			(stroke
				(width 0.1524)
				(type default)
			)
			(layer "F.SilkS")
		)
		(fp_line
			(start 0.67945 0.3048)
			(end 0.120396 0.3048)
			(stroke
				(width 0.1)
				(type default)
			)
			(layer "F.Fab")
		)
		(fp_line
			(start 0.67945 -0.3048)
			(end 0.67945 0.3048)
			(stroke
				(width 0.1)
				(type default)
			)
			(layer "F.Fab")
		)
		(fp_line
			(start 0.12065 -0.2794)
			(end 0.12065 -0.3048)
			(stroke
				(width 0.1)
				(type default)
			)
			(layer "F.Fab")
		)
		(fp_line
			(start 0.12065 -0.3048)
			(end 0.67945 -0.3048)
			(stroke
				(width 0.1)
				(type default)
			)
			(layer "F.Fab")
		)
		(fp_line
			(start 0.120396 0.3048)
			(end 0.120396 0.2794)
			(stroke
				(width 0.1)
				(type default)
			)
			(layer "F.Fab")
		)
		(fp_line
			(start 0.120396 0.2794)
			(end -0.12065 0.2794)
			(stroke
				(width 0.1)
				(type default)
			)
			(layer "F.Fab")
		)
		(fp_line
			(start -0.12065 0.3048)
			(end -0.67945 0.3048)
			(stroke
				(width 0.1)
				(type default)
			)
			(layer "F.Fab")
		)
		(fp_line
			(start -0.12065 0.2794)
			(end -0.12065 0.3048)
			(stroke
				(width 0.1)
				(type default)
			)
			(layer "F.Fab")
		)
		(fp_line
			(start -0.12065 -0.2794)
			(end 0.12065 -0.2794)
			(stroke
				(width 0.1)
				(type default)
			)
			(layer "F.Fab")
		)
		(fp_line
			(start -0.12065 -0.305054)
			(end -0.12065 -0.2794)
			(stroke
				(width 0.1)
				(type default)
			)
			(layer "F.Fab")
		)
		(fp_line
			(start -0.67945 0.3048)
			(end -0.67945 -0.305054)
			(stroke
				(width 0.1)
				(type default)
			)
			(layer "F.Fab")
		)
		(fp_line
			(start -0.67945 -0.305054)
			(end -0.12065 -0.305054)
			(stroke
				(width 0.1)
				(type default)
			)
			(layer "F.Fab")
		)
		(pad "1" smd circle
			(at -0.40005 0 180)
			(size 0 0)
			(layers "F.Cu" "F.Mask" "F.Paste")
			(net "NIC2_CLK_EN_R_N")
		)
		(pad "2" smd circle
			(at 0.40005 0 180)
			(size 0 0)
			(layers "F.Cu" "F.Mask" "F.Paste")
			(net "NIC2_CLK_EN_N")
		)
	)
	(footprint ""
		(layer "F.Cu")
		(at 362.9914 -284.8991 180)
		(property "Reference" "PU15"
			(at -8.419592 -2.676398 90)
			(unlocked yes)
			(layer "F.SilkS")
			(effects
				(font
					(size 0.7874 0.5842)
					(thickness 0.1524)
				)
				(justify left)
			)
		)
		(property "Value" ""
			(at 0 0 180)
			(layer "F.Fab")
			(effects
				(font
					(size 1.27 1.27)
				)
			)
		)
		(duplicate_pad_numbers_are_jumpers no)
		(fp_line
			(start 2.500122 2.999994)
			(end 2.2987 2.999994)
			(stroke
				(width 0.1524)
				(type default)
			)
			(layer "F.SilkS")
		)
		(fp_line
			(start 2.500122 2.339594)
			(end 2.500122 2.999994)
			(stroke
				(width 0.1524)
				(type default)
			)
			(layer "F.SilkS")
		)
		(fp_line
			(start 2.500122 -2.999994)
			(end 2.500122 -2.44348)
			(stroke
				(width 0.1524)
				(type default)
			)
			(layer "F.SilkS")
		)
		(fp_line
			(start 2.31394 -2.999994)
			(end 2.500122 -2.999994)
			(stroke
				(width 0.1524)
				(type default)
			)
			(layer "F.SilkS")
		)
		(fp_line
			(start -2.2987 2.999994)
			(end -2.500122 2.999994)
			(stroke
				(width 0.1524)
				(type default)
			)
			(layer "F.SilkS")
		)
		(fp_line
			(start -2.500122 2.999994)
			(end -2.500122 2.339594)
			(stroke
				(width 0.1524)
				(type default)
			)
			(layer "F.SilkS")
		)
		(fp_line
			(start -2.500122 0.6604)
			(end -2.500122 0.229108)
			(stroke
				(width 0.1524)
				(type default)
			)
			(layer "F.SilkS")
		)
		(fp_line
			(start -2.500122 -2.529078)
			(end -2.500122 -2.999994)
			(stroke
				(width 0.1524)
				(type default)
			)
			(layer "F.SilkS")
		)
		(fp_line
			(start -2.500122 -2.999994)
			(end -2.24409 -2.999994)
			(stroke
				(width 0.1524)
				(type default)
			)
			(layer "F.SilkS")
		)
		(fp_poly
			(pts
				(xy -4.495292 -3.711702) (xy -5.213858 -2.99339) (xy -4.136136 -2.634234)
			)
			(stroke
				(width 0)
				(type default)
			)
			(fill yes)
			(layer "F.SilkS")
		)
		(fp_line
			(start 2.500122 2.999994)
			(end -2.500122 2.999994)
			(stroke
				(width 0.1)
				(type default)
			)
			(layer "F.Fab")
		)
		(fp_line
			(start 2.500122 -2.999994)
			(end 2.500122 2.999994)
			(stroke
				(width 0.1)
				(type default)
			)
			(layer "F.Fab")
		)
		(fp_line
			(start -2.500122 2.999994)
			(end -2.500122 -2.999994)
			(stroke
				(width 0.1)
				(type default)
			)
			(layer "F.Fab")
		)
		(fp_line
			(start -2.500122 -2.999994)
			(end 2.500122 -2.999994)
			(stroke
				(width 0.1)
				(type default)
			)
			(layer "F.Fab")
		)
		(fp_poly
			(pts
				(xy -4.218432 -2.783078) (xy -4.218432 -1.767078) (xy -3.202432 -2.275078)
			)
			(stroke
				(width 0)
				(type default)
			)
			(fill yes)
			(layer "F.Fab")
		)
		(pad "1" smd rect
			(at -2.400046 -2.275078 270)
			(size 0.2286 0.6096)
			(layers "F.Cu" "F.Mask" "F.Paste")
			(net "SW_P0V8_PEX3_VOS2")
		)
		(pad "2" smd rect
			(at -2.400046 -1.82499 270)
			(size 0.2286 0.6096)
			(layers "F.Cu" "F.Mask" "F.Paste")
			(net "GND")
		)
		(pad "3" smd rect
			(at -2.400046 -1.374902 270)
			(size 0.2286 0.6096)
			(layers "F.Cu" "F.Mask" "F.Paste")
			(net "P0V8_PEX3_VCC2")
		)
		(pad "4" smd rect
			(at -2.400046 -0.925068 270)
			(size 0.2286 0.6096)
			(layers "F.Cu" "F.Mask" "F.Paste")
			(net "P0V8_PEX3_PVCC")
		)
		(pad "5" smd rect
			(at -2.400046 -0.47498 270)
			(size 0.2286 0.6096)
			(layers "F.Cu" "F.Mask" "F.Paste")
			(net "GND")
		)
		(pad "6" smd rect
			(at -2.400046 -0.024892 270)
			(size 0.2286 0.6096)
			(layers "F.Cu" "F.Mask" "F.Paste")
			(net "NC_P0V8_PEX3_PH2_NC1")
		)
		(pad "7_9-20_24" smd circle
			(at 0 1.150112 270)
			(size 0 0)
			(layers "F.Cu" "F.Mask" "F.Paste")
			(net "GND")
		)
		(pad "10_19" smd rect
			(at 0 2.899918 270)
			(size 0.6096 4.318)
			(layers "F.Cu" "F.Mask" "F.Paste")
			(net "SW_P0V8_PEX3_PH2")
		)
		(pad "25_29" smd rect
			(at 1.549908 -1.279906 90)
			(size 2.0574 2.3114)
			(layers "F.Cu" "F.Mask" "F.Paste")
			(net "SW_P12V_P0V8_PEX3_FLT")
		)
		(pad "30" smd rect
			(at 2.05994 -2.899918 180)
			(size 0.2286 0.6096)
			(layers "F.Cu" "F.Mask" "F.Paste")
			(net "SW_P12V_P0V8_PEX3_FLT")
		)
		(pad "31" smd rect
			(at 1.610106 -2.899918 180)
			(size 0.2286 0.6096)
			(layers "F.Cu" "F.Mask" "F.Paste")
			(net "NC_P0V8_PEX3_PH2_NC3")
		)
		(pad "32" smd rect
			(at 1.160018 -2.899918 180)
			(size 0.2286 0.6096)
			(layers "F.Cu" "F.Mask" "F.Paste")
			(net "SW_P0V8_PEX3_PHASE2")
		)
		(pad "33" smd rect
			(at 0.70993 -2.899918 180)
			(size 0.2286 0.6096)
			(layers "F.Cu" "F.Mask" "F.Paste")
			(net "SW_P0V8_PEX3_BOOT2")
		)
		(pad "34" smd rect
			(at 0.260096 -2.899918 180)
			(size 0.2286 0.6096)
			(layers "F.Cu" "F.Mask" "F.Paste")
			(net "P0V8_PEX3_PWM2")
		)
		(pad "35" smd rect
			(at -0.189992 -2.899918 180)
			(size 0.2286 0.6096)
			(layers "F.Cu" "F.Mask" "F.Paste")
			(net "P0V8_PEX2_EN4")
		)
		(pad "36" smd rect
			(at -0.64008 -2.899918 180)
			(size 0.2286 0.6096)
			(layers "F.Cu" "F.Mask" "F.Paste")
			(net "P0V8_PEX3_TSEN")
		)
		(pad "37" smd rect
			(at -1.089914 -2.899918 180)
			(size 0.2286 0.6096)
			(layers "F.Cu" "F.Mask" "F.Paste")
			(net "P0V8_PEX3_LSET2")
		)
		(pad "38" smd rect
			(at -1.540002 -2.899918 180)
			(size 0.2286 0.6096)
			(layers "F.Cu" "F.Mask" "F.Paste")
			(net "P0V8_PEX3_ISEN2")
		)
		(pad "39" smd rect
			(at -1.99009 -2.899918 180)
			(size 0.2286 0.6096)
			(layers "F.Cu" "F.Mask" "F.Paste")
			(net "P0V8_PEX2_VREF")
		)
		(pad "40" smd rect
			(at -0.87503 -1.27508 180)
			(size 1.7526 1.9558)
			(layers "F.Cu" "F.Mask" "F.Paste")
			(net "GND")
		)
		(pad "41" smd rect
			(at -1.525016 0.249936 90)
			(size 0.3048 0.4572)
			(layers "F.Cu" "F.Mask" "F.Paste")
			(net "NC_P0V8_PEX3_PH2_NC2")
		)
		(zone
			(layer "F.Cu")
			(hatch none 0.5)
			(connect_pads
				(clearance 0)
			)
			(min_thickness 0.25)
			(keepout
				(tracks not_allowed)
				(vias allowed)
				(pads allowed)
				(copperpour not_allowed)
				(footprints allowed)
			)
			(placement
				(enabled no)
				(sheetname "")
			)
			(fill
				(thermal_gap 0.5)
				(thermal_bridge_width 0.5)
				(island_removal_mode 0)
			)
			(polygon
				(pts
					(xy 365.491522 -287.899094) (xy 365.491522 -287.149794) (xy 360.491278 -287.149794) (xy 360.491278 -287.899094)
					(xy 360.7816 -287.899094) (xy 360.7816 -287.443418) (xy 365.2012 -287.443418) (xy 365.2012 -287.899094)
				)
			)
		)
	)
	(footprint ""
		(layer "F.Cu")
		(at 233.425746 -115.936268 180)
		(property "Reference" "PU74"
			(at 3.656076 -1.433068 90)
			(unlocked yes)
			(layer "F.SilkS")
			(effects
				(font
					(size 0.7874 0.5842)
					(thickness 0.1524)
				)
				(justify left)
			)
		)
		(property "Value" ""
			(at 0 0 180)
			(layer "F.Fab")
			(effects
				(font
					(size 1.27 1.27)
				)
			)
		)
		(duplicate_pad_numbers_are_jumpers no)
		(fp_line
			(start 1.549908 2.549906)
			(end 1.549908 2.253996)
			(stroke
				(width 0.1524)
				(type default)
			)
			(layer "F.SilkS")
		)
		(fp_line
			(start 1.549908 -2.253996)
			(end 1.549908 -2.549906)
			(stroke
				(width 0.1524)
				(type default)
			)
			(layer "F.SilkS")
		)
		(fp_line
			(start 1.549908 -2.549906)
			(end 0.752094 -2.549906)
			(stroke
				(width 0.1524)
				(type default)
			)
			(layer "F.SilkS")
		)
		(fp_line
			(start 0.753872 2.549906)
			(end 1.549908 2.549906)
			(stroke
				(width 0.1524)
				(type default)
			)
			(layer "F.SilkS")
		)
		(fp_line
			(start 0.2413 -2.549906)
			(end -0.2413 -2.549906)
			(stroke
				(width 0.1524)
				(type default)
			)
			(layer "F.SilkS")
		)
		(fp_line
			(start -0.245872 2.549906)
			(end 0.245872 2.549906)
			(stroke
				(width 0.1524)
				(type default)
			)
			(layer "F.SilkS")
		)
		(fp_line
			(start -0.752094 -2.549906)
			(end -1.549908 -2.549906)
			(stroke
				(width 0.1524)
				(type default)
			)
			(layer "F.SilkS")
		)
		(fp_line
			(start -1.549908 2.549906)
			(end -0.753872 2.549906)
			(stroke
				(width 0.1524)
				(type default)
			)
			(layer "F.SilkS")
		)
		(fp_line
			(start -1.549908 2.253996)
			(end -1.549908 2.549906)
			(stroke
				(width 0.1524)
				(type default)
			)
			(layer "F.SilkS")
		)
		(fp_line
			(start -1.549908 -2.549906)
			(end -1.549908 -2.251964)
			(stroke
				(width 0.1524)
				(type default)
			)
			(layer "F.SilkS")
		)
		(fp_poly
			(pts
				(xy -1.891538 -1.999996) (xy -2.7432 -1.574292) (xy -2.7432 -2.4257)
			)
			(stroke
				(width 0)
				(type default)
			)
			(fill yes)
			(layer "F.SilkS")
		)
		(fp_line
			(start 1.549908 2.549906)
			(end 1.549908 -2.549906)
			(stroke
				(width 0.1)
				(type default)
			)
			(layer "F.Fab")
		)
		(fp_line
			(start 1.549908 -2.549906)
			(end -1.549908 -2.549906)
			(stroke
				(width 0.1)
				(type default)
			)
			(layer "F.Fab")
		)
		(fp_line
			(start -1.549908 2.549906)
			(end 1.549908 2.549906)
			(stroke
				(width 0.1)
				(type default)
			)
			(layer "F.Fab")
		)
		(fp_line
			(start -1.549908 -2.549906)
			(end -1.549908 2.549906)
			(stroke
				(width 0.1)
				(type default)
			)
			(layer "F.Fab")
		)
		(fp_poly
			(pts
				(xy -1.891538 -1.999996) (xy -2.7432 -1.574292) (xy -2.7432 -2.4257)
			)
			(stroke
				(width 0)
				(type default)
			)
			(fill yes)
			(layer "F.Fab")
		)
		(fp_text user "12"
			(at 2.71272 1.070864 90)
			(unlocked yes)
			(layer "F.SilkS")
			(effects
				(font
					(size 0.635 0.4064)
					(thickness 0.1524)
				)
			)
		)
		(fp_text user "20"
			(at 2.055368 -2.7686 90)
			(unlocked yes)
			(layer "F.SilkS")
			(effects
				(font
					(size 0.635 0.4064)
					(thickness 0.1524)
				)
			)
		)
		(fp_text user "11"
			(at 1.808734 3.022092 180)
			(unlocked yes)
			(layer "F.SilkS")
			(effects
				(font
					(size 0.635 0.4064)
					(thickness 0.1524)
				)
			)
		)
		(fp_text user "21_22"
			(at -0.745744 -3.513836 0)
			(unlocked yes)
			(layer "F.SilkS")
			(effects
				(font
					(size 0.635 0.4064)
					(thickness 0.1524)
				)
			)
		)
		(fp_text user "10"
			(at -1.4224 3.253232 180)
			(unlocked yes)
			(layer "F.SilkS")
			(effects
				(font
					(size 0.635 0.4064)
					(thickness 0.1524)
				)
			)
		)
		(fp_text user "9"
			(at -2.338832 2.5908 90)
			(unlocked yes)
			(layer "F.SilkS")
			(effects
				(font
					(size 0.635 0.4064)
					(thickness 0.1524)
				)
			)
		)
		(fp_text user "12"
			(at 2.207768 2.7178 90)
			(unlocked yes)
			(layer "F.Fab")
			(effects
				(font
					(size 0.635 0.4064)
					(thickness 0.1524)
				)
			)
		)
		(fp_text user "20"
			(at 2.055368 -2.7686 90)
			(unlocked yes)
			(layer "F.Fab")
			(effects
				(font
					(size 0.635 0.4064)
					(thickness 0.1524)
				)
			)
		)
		(fp_text user "11"
			(at 1.1938 3.329432 180)
			(unlocked yes)
			(layer "F.Fab")
			(effects
				(font
					(size 0.635 0.4064)
					(thickness 0.1524)
				)
			)
		)
		(fp_text user "21_22"
			(at -0.0762 -3.401568 180)
			(unlocked yes)
			(layer "F.Fab")
			(effects
				(font
					(size 0.635 0.4064)
					(thickness 0.1524)
				)
			)
		)
		(fp_text user "10"
			(at -1.4224 3.253232 180)
			(unlocked yes)
			(layer "F.Fab")
			(effects
				(font
					(size 0.635 0.4064)
					(thickness 0.1524)
				)
			)
		)
		(fp_text user "9"
			(at -2.338832 2.5908 90)
			(unlocked yes)
			(layer "F.Fab")
			(effects
				(font
					(size 0.635 0.4064)
					(thickness 0.1524)
				)
			)
		)
		(pad "1" smd circle
			(at -1.374902 -1.999996 90)
			(size 0 0)
			(layers "F.Cu" "F.Mask" "F.Paste")
			(net "P12V_NIC3_CO_EN")
		)
		(pad "2" smd rect
			(at -1.400048 -1.500124 90)
			(size 0.254 0.8128)
			(layers "F.Cu" "F.Mask" "F.Paste")
			(net "GND")
		)
		(pad "3" smd rect
			(at -1.400048 -0.999998 90)
			(size 0.254 0.8128)
			(layers "F.Cu" "F.Mask" "F.Paste")
			(net "GND")
		)
		(pad "4" smd rect
			(at -1.400048 -0.499872 90)
			(size 0.254 0.8128)
			(layers "F.Cu" "F.Mask" "F.Paste")
			(net "P12V_NIC3_CO_TIMER")
		)
		(pad "5" smd rect
			(at -1.400048 0 90)
			(size 0.254 0.8128)
			(layers "F.Cu" "F.Mask" "F.Paste")
			(net "P12V_NIC3_CO_ISET")
		)
		(pad "6" smd rect
			(at -1.400048 0.499872 90)
			(size 0.254 0.8128)
			(layers "F.Cu" "F.Mask" "F.Paste")
			(net "P12V_NIC3_CO_SS")
		)
		(pad "7" smd rect
			(at -1.400048 0.999998 90)
			(size 0.254 0.8128)
			(layers "F.Cu" "F.Mask" "F.Paste")
			(net "GND")
		)
		(pad "8" smd rect
			(at -1.400048 1.500124 90)
			(size 0.254 0.8128)
			(layers "F.Cu" "F.Mask" "F.Paste")
			(net "P12V_NIC3_CO_IMON_VR")
		)
		(pad "9" smd rect
			(at -1.400048 1.999996 90)
			(size 0.254 0.8128)
			(layers "F.Cu" "F.Mask" "F.Paste")
			(net "P12V_NIC3_CO_FLTB")
		)
		(pad "10" smd rect
			(at -0.499872 2.400046 180)
			(size 0.254 0.8128)
			(layers "F.Cu" "F.Mask" "F.Paste")
			(net "PWRGD_P12V_NIC3_CO")
		)
		(pad "11" smd rect
			(at 0.499872 2.400046 180)
			(size 0.254 0.8128)
			(layers "F.Cu" "F.Mask" "F.Paste")
			(net "P12V_NIC3_CO_OV_FB")
		)
		(pad "12" smd rect
			(at 1.400048 1.999996 90)
			(size 0.254 0.8128)
			(layers "F.Cu" "F.Mask" "F.Paste")
			(net "P12V_NIC3_CO_AVIN_PD")
		)
		(pad "13" smd rect
			(at 1.400048 1.500124 90)
			(size 0.254 0.8128)
			(layers "F.Cu" "F.Mask" "F.Paste")
			(net "P12V_NIC3_R")
		)
		(pad "14" smd rect
			(at 1.400048 0.999998 90)
			(size 0.254 0.8128)
			(layers "F.Cu" "F.Mask" "F.Paste")
			(net "P12V_NIC3_R")
		)
		(pad "15" smd rect
			(at 1.400048 0.499872 90)
			(size 0.254 0.8128)
			(layers "F.Cu" "F.Mask" "F.Paste")
			(net "P12V_NIC3_R")
		)
		(pad "16" smd rect
			(at 1.400048 0 90)
			(size 0.254 0.8128)
			(layers "F.Cu" "F.Mask" "F.Paste")
			(net "P12V_NIC3_R")
		)
		(pad "17" smd rect
			(at 1.400048 -0.499872 90)
			(size 0.254 0.8128)
			(layers "F.Cu" "F.Mask" "F.Paste")
			(net "P12V_NIC3_R")
		)
		(pad "18" smd rect
			(at 1.400048 -0.999998 90)
			(size 0.254 0.8128)
			(layers "F.Cu" "F.Mask" "F.Paste")
			(net "P12V_NIC3_R")
		)
		(pad "19" smd rect
			(at 1.400048 -1.500124 90)
			(size 0.254 0.8128)
			(layers "F.Cu" "F.Mask" "F.Paste")
			(net "P12V_NIC3_R")
		)
		(pad "20" smd rect
			(at 1.400048 -1.999996 90)
			(size 0.254 0.8128)
			(layers "F.Cu" "F.Mask" "F.Paste")
			(net "P12V_NIC3_R")
		)
		(pad "21_22" smd circle
			(at 0.499872 -2.337562 90)
			(size 0 0)
			(layers "F.Cu" "F.Mask" "F.Paste")
			(net "P12V_AUX")
		)
		(pad "23" smd rect
			(at 0 -1.100074 90)
			(size 0.254 1.27)
			(layers "F.Cu" "F.Mask" "F.Paste")
			(net "P12V_AUX")
		)
		(pad "24" smd rect
			(at 0 -0.199898 90)
			(size 0.254 1.27)
			(layers "F.Cu" "F.Mask" "F.Paste")
			(net "P12V_AUX")
		)
		(pad "25" smd rect
			(at 0 0.700024 90)
			(size 0.254 1.27)
			(layers "F.Cu" "F.Mask" "F.Paste")
			(net "P12V_AUX")
		)
		(pad "26" smd rect
			(at 0 1.599946 90)
			(size 0.254 1.27)
			(layers "F.Cu" "F.Mask" "F.Paste")
			(net "P12V_AUX")
		)
	)
	(footprint ""
		(layer "F.Cu")
		(at 409.269692 -350.098614 90)
		(property "Reference" "C2439"
			(at 0 0 90)
			(layer "F.SilkS")
			(hide yes)
			(effects
				(font
					(size 1.27 1.27)
				)
			)
		)
		(property "Value" ""
			(at 0 0 90)
			(layer "F.Fab")
			(effects
				(font
					(size 1.27 1.27)
				)
			)
		)
		(duplicate_pad_numbers_are_jumpers no)
		(fp_line
			(start 0.299974 -0.150114)
			(end 0.299974 0.150114)
			(stroke
				(width 0.1)
				(type default)
			)
			(layer "F.Fab")
		)
		(fp_line
			(start -0.299974 -0.150114)
			(end 0.299974 -0.150114)
			(stroke
				(width 0.1)
				(type default)
			)
			(layer "F.Fab")
		)
		(fp_line
			(start 0.299974 0.150114)
			(end -0.299974 0.150114)
			(stroke
				(width 0.1)
				(type default)
			)
			(layer "F.Fab")
		)
		(fp_line
			(start -0.299974 0.150114)
			(end -0.299974 -0.150114)
			(stroke
				(width 0.1)
				(type default)
			)
			(layer "F.Fab")
		)
		(pad "1" smd rect
			(at -0.2667 0 90)
			(size 0.3048 0.381)
			(layers "F.Cu" "F.Mask" "F.Paste")
			(net "P5E_PEX3_STN4_TX_DP<79>")
		)
		(pad "2" smd rect
			(at 0.2667 0 90)
			(size 0.3048 0.381)
			(layers "F.Cu" "F.Mask" "F.Paste")
			(net "P5E_PEX3_STN4_TX_C_DP<79>")
		)
	)
	(footprint ""
		(layer "F.Cu")
		(at 214.310976 -370.321586 180)
		(property "Reference" "PC15"
			(at 0 0 180)
			(layer "F.SilkS")
			(hide yes)
			(effects
				(font
					(size 1.27 1.27)
				)
			)
		)
		(property "Value" ""
			(at 0 0 180)
			(layer "F.Fab")
			(effects
				(font
					(size 1.27 1.27)
				)
			)
		)
		(duplicate_pad_numbers_are_jumpers no)
		(fp_line
			(start 0.7874 0.4064)
			(end -0.7874 0.4064)
			(stroke
				(width 0.1524)
				(type default)
			)
			(layer "F.SilkS")
		)
		(fp_line
			(start 0.7874 -0.4064)
			(end 0.7874 0.4064)
			(stroke
				(width 0.1524)
				(type default)
			)
			(layer "F.SilkS")
		)
		(fp_line
			(start -0.7874 0.4064)
			(end -0.7874 -0.4064)
			(stroke
				(width 0.1524)
				(type default)
			)
			(layer "F.SilkS")
		)
		(fp_line
			(start -0.7874 -0.4064)
			(end 0.7874 -0.4064)
			(stroke
				(width 0.1524)
				(type default)
			)
			(layer "F.SilkS")
		)
		(fp_line
			(start 0.67945 0.3048)
			(end 0.120396 0.3048)
			(stroke
				(width 0.1)
				(type default)
			)
			(layer "F.Fab")
		)
		(fp_line
			(start 0.67945 -0.3048)
			(end 0.67945 0.3048)
			(stroke
				(width 0.1)
				(type default)
			)
			(layer "F.Fab")
		)
		(fp_line
			(start 0.12065 -0.2794)
			(end 0.12065 -0.3048)
			(stroke
				(width 0.1)
				(type default)
			)
			(layer "F.Fab")
		)
		(fp_line
			(start 0.12065 -0.3048)
			(end 0.67945 -0.3048)
			(stroke
				(width 0.1)
				(type default)
			)
			(layer "F.Fab")
		)
		(fp_line
			(start 0.120396 0.3048)
			(end 0.120396 0.2794)
			(stroke
				(width 0.1)
				(type default)
			)
			(layer "F.Fab")
		)
		(fp_line
			(start 0.120396 0.2794)
			(end -0.12065 0.2794)
			(stroke
				(width 0.1)
				(type default)
			)
			(layer "F.Fab")
		)
		(fp_line
			(start -0.12065 0.3048)
			(end -0.67945 0.3048)
			(stroke
				(width 0.1)
				(type default)
			)
			(layer "F.Fab")
		)
		(fp_line
			(start -0.12065 0.2794)
			(end -0.12065 0.3048)
			(stroke
				(width 0.1)
				(type default)
			)
			(layer "F.Fab")
		)
		(fp_line
			(start -0.12065 -0.2794)
			(end 0.12065 -0.2794)
			(stroke
				(width 0.1)
				(type default)
			)
			(layer "F.Fab")
		)
		(fp_line
			(start -0.12065 -0.305054)
			(end -0.12065 -0.2794)
			(stroke
				(width 0.1)
				(type default)
			)
			(layer "F.Fab")
		)
		(fp_line
			(start -0.67945 0.3048)
			(end -0.67945 -0.305054)
			(stroke
				(width 0.1)
				(type default)
			)
			(layer "F.Fab")
		)
		(fp_line
			(start -0.67945 -0.305054)
			(end -0.12065 -0.305054)
			(stroke
				(width 0.1)
				(type default)
			)
			(layer "F.Fab")
		)
		(pad "1" smd circle
			(at -0.40005 0 180)
			(size 0 0)
			(layers "F.Cu" "F.Mask" "F.Paste")
			(net "HSC_SS")
		)
		(pad "2" smd circle
			(at 0.40005 0 180)
			(size 0 0)
			(layers "F.Cu" "F.Mask" "F.Paste")
			(net "AGND_HSC")
		)
	)
	(footprint ""
		(layer "F.Cu")
		(at 424.814492 -356.244906 90)
		(property "Reference" "C2455"
			(at 0 0 90)
			(layer "F.SilkS")
			(hide yes)
			(effects
				(font
					(size 1.27 1.27)
				)
			)
		)
		(property "Value" ""
			(at 0 0 90)
			(layer "F.Fab")
			(effects
				(font
					(size 1.27 1.27)
				)
			)
		)
		(duplicate_pad_numbers_are_jumpers no)
		(fp_line
			(start 0.299974 -0.150114)
			(end 0.299974 0.150114)
			(stroke
				(width 0.1)
				(type default)
			)
			(layer "F.Fab")
		)
		(fp_line
			(start -0.299974 -0.150114)
			(end 0.299974 -0.150114)
			(stroke
				(width 0.1)
				(type default)
			)
			(layer "F.Fab")
		)
		(fp_line
			(start 0.299974 0.150114)
			(end -0.299974 0.150114)
			(stroke
				(width 0.1)
				(type default)
			)
			(layer "F.Fab")
		)
		(fp_line
			(start -0.299974 0.150114)
			(end -0.299974 -0.150114)
			(stroke
				(width 0.1)
				(type default)
			)
			(layer "F.Fab")
		)
		(pad "1" smd rect
			(at -0.2667 0 90)
			(size 0.3048 0.381)
			(layers "F.Cu" "F.Mask" "F.Paste")
			(net "P5E_PEX3_STN4_TX_DP<71>")
		)
		(pad "2" smd rect
			(at 0.2667 0 90)
			(size 0.3048 0.381)
			(layers "F.Cu" "F.Mask" "F.Paste")
			(net "P5E_PEX3_STN4_TX_C_DP<71>")
		)
	)
	(footprint ""
		(layer "F.Cu")
		(at 193.065908 -360.074718)
		(property "Reference" "J58"
			(at -1.127252 -4.983988 0)
			(unlocked yes)
			(layer "F.SilkS")
			(effects
				(font
					(size 0.7874 0.5842)
					(thickness 0.1524)
				)
				(justify left)
			)
		)
		(property "Value" ""
			(at 0 0 0)
			(layer "F.Fab")
			(effects
				(font
					(size 1.27 1.27)
				)
			)
		)
		(duplicate_pad_numbers_are_jumpers no)
		(fp_line
			(start -1.27 -3.81)
			(end 1.27 -3.81)
			(stroke
				(width 0.1524)
				(type default)
			)
			(layer "F.SilkS")
		)
		(fp_line
			(start -1.27 -0.7747)
			(end -1.27 -3.81)
			(stroke
				(width 0.1524)
				(type default)
			)
			(layer "F.SilkS")
		)
		(fp_line
			(start -1.27 3.81)
			(end -1.27 0.7747)
			(stroke
				(width 0.1524)
				(type default)
			)
			(layer "F.SilkS")
		)
		(fp_line
			(start 1.27 -3.81)
			(end 1.27 -3.3147)
			(stroke
				(width 0.1524)
				(type default)
			)
			(layer "F.SilkS")
		)
		(fp_line
			(start 1.27 -1.7653)
			(end 1.27 1.7653)
			(stroke
				(width 0.1524)
				(type default)
			)
			(layer "F.SilkS")
		)
		(fp_line
			(start 1.27 3.3147)
			(end 1.27 3.81)
			(stroke
				(width 0.1524)
				(type default)
			)
			(layer "F.SilkS")
		)
		(fp_line
			(start 1.27 3.81)
			(end -1.27 3.81)
			(stroke
				(width 0.1524)
				(type default)
			)
			(layer "F.SilkS")
		)
		(fp_poly
			(pts
				(xy 4.3942 -3.048) (xy 4.3942 -2.032) (xy 3.3782 -2.54)
			)
			(stroke
				(width 0)
				(type default)
			)
			(fill yes)
			(layer "F.SilkS")
		)
		(fp_line
			(start -1.27 -3.81)
			(end -1.27 3.81)
			(stroke
				(width 0.1)
				(type default)
			)
			(layer "F.Fab")
		)
		(fp_line
			(start -1.27 3.81)
			(end 1.27 3.81)
			(stroke
				(width 0.1)
				(type default)
			)
			(layer "F.Fab")
		)
		(fp_line
			(start 1.27 -3.81)
			(end -1.27 -3.81)
			(stroke
				(width 0.1)
				(type default)
			)
			(layer "F.Fab")
		)
		(fp_line
			(start 1.27 3.81)
			(end 1.27 -3.81)
			(stroke
				(width 0.1)
				(type default)
			)
			(layer "F.Fab")
		)
		(fp_poly
			(pts
				(xy 4.3942 -3.048) (xy 4.3942 -2.032) (xy 3.3782 -2.54)
			)
			(stroke
				(width 0)
				(type default)
			)
			(fill yes)
			(layer "F.Fab")
		)
		(fp_text user "3"
			(at 3.720846 2.239518 0)
			(unlocked yes)
			(layer "F.SilkS")
			(effects
				(font
					(size 0.7874 0.5842)
					(thickness 0.1524)
				)
			)
		)
		(fp_text user "3"
			(at 3.921252 2.54 90)
			(unlocked yes)
			(layer "F.Fab")
			(effects
				(font
					(size 0.7874 0.5842)
					(thickness 0.1524)
				)
			)
		)
		(pad "1" smd rect
			(at 1.459992 -2.54 90)
			(size 1.27 3.429)
			(layers "F.Cu" "F.Mask" "F.Paste")
			(net "Net_616")
		)
		(pad "2" smd rect
			(at -1.459992 0 90)
			(size 1.27 3.429)
			(layers "F.Cu" "F.Mask" "F.Paste")
			(net "MB_HSC_ISO_D1_EN")
		)
		(pad "3" smd rect
			(at 1.459992 2.54 90)
			(size 1.27 3.429)
			(layers "F.Cu" "F.Mask" "F.Paste")
			(net "PD_MB_HSC_ISO_D1_EN")
		)
	)
	(footprint ""
		(layer "F.Cu")
		(at 136.54659 -58.323734)
		(property "Reference" "PC317"
			(at 0 0 0)
			(layer "F.SilkS")
			(hide yes)
			(effects
				(font
					(size 1.27 1.27)
				)
			)
		)
		(property "Value" ""
			(at 0 0 0)
			(layer "F.Fab")
			(effects
				(font
					(size 1.27 1.27)
				)
			)
		)
		(duplicate_pad_numbers_are_jumpers no)
		(fp_line
			(start -1.524 -0.762)
			(end 1.524 -0.762)
			(stroke
				(width 0.1524)
				(type default)
			)
			(layer "F.SilkS")
		)
		(fp_line
			(start -1.524 0.762)
			(end -1.524 -0.762)
			(stroke
				(width 0.1524)
				(type default)
			)
			(layer "F.SilkS")
		)
		(fp_line
			(start 1.524 -0.762)
			(end 1.524 0.762)
			(stroke
				(width 0.1524)
				(type default)
			)
			(layer "F.SilkS")
		)
		(fp_line
			(start 1.524 0.762)
			(end -1.524 0.762)
			(stroke
				(width 0.1524)
				(type default)
			)
			(layer "F.SilkS")
		)
		(fp_line
			(start -1.1049 -0.724916)
			(end -1.1049 0.724916)
			(stroke
				(width 0.1)
				(type default)
			)
			(layer "F.Fab")
		)
		(fp_line
			(start -1.1049 0.724916)
			(end 1.1049 0.724916)
			(stroke
				(width 0.1)
				(type default)
			)
			(layer "F.Fab")
		)
		(fp_line
			(start 1.1049 -0.724916)
			(end -1.1049 -0.724916)
			(stroke
				(width 0.1)
				(type default)
			)
			(layer "F.Fab")
		)
		(fp_line
			(start 1.1049 0.724916)
			(end 1.1049 -0.724916)
			(stroke
				(width 0.1)
				(type default)
			)
			(layer "F.Fab")
		)
		(pad "1" smd rect
			(at -0.889 0 180)
			(size 1.016 1.27)
			(layers "F.Cu" "F.Mask" "F.Paste")
			(net "GND")
		)
		(pad "2" smd rect
			(at 0.889 0 180)
			(size 1.016 1.27)
			(layers "F.Cu" "F.Mask" "F.Paste")
			(net "P12V_AUX")
		)
	)
	(footprint ""
		(layer "F.Cu")
		(at 262.312404 -342.4428 180)
		(property "Reference" "U436"
			(at -3.322066 -1.352296 0)
			(unlocked yes)
			(layer "F.SilkS")
			(effects
				(font
					(size 0.7874 0.5842)
					(thickness 0.1524)
				)
				(justify left)
			)
		)
		(property "Value" ""
			(at 0 0 180)
			(layer "F.Fab")
			(effects
				(font
					(size 1.27 1.27)
				)
			)
		)
		(duplicate_pad_numbers_are_jumpers no)
		(fp_line
			(start 2.046478 1.450086)
			(end 2.046478 -1.450086)
			(stroke
				(width 0.1524)
				(type default)
			)
			(layer "F.SilkS")
		)
		(fp_line
			(start 2.046478 -1.450086)
			(end 0.484886 -1.450086)
			(stroke
				(width 0.1524)
				(type default)
			)
			(layer "F.SilkS")
		)
		(fp_line
			(start 0.484886 -1.450086)
			(end 0 -0.762)
			(stroke
				(width 0.1524)
				(type default)
			)
			(layer "F.SilkS")
		)
		(fp_line
			(start 0 -0.762)
			(end -0.484886 -1.450086)
			(stroke
				(width 0.1524)
				(type default)
			)
			(layer "F.SilkS")
		)
		(fp_line
			(start -0.484886 -1.450086)
			(end -2.046478 -1.450086)
			(stroke
				(width 0.1524)
				(type default)
			)
			(layer "F.SilkS")
		)
		(fp_line
			(start -2.046478 1.450086)
			(end 2.046478 1.450086)
			(stroke
				(width 0.1524)
				(type default)
			)
			(layer "F.SilkS")
		)
		(fp_line
			(start -2.046478 -1.450086)
			(end -2.046478 1.450086)
			(stroke
				(width 0.1524)
				(type default)
			)
			(layer "F.SilkS")
		)
		(fp_poly
			(pts
				(xy -3.2512 -0.44196) (xy -3.2512 -1.45796) (xy -2.2352 -0.94996)
			)
			(stroke
				(width 0)
				(type default)
			)
			(fill yes)
			(layer "F.SilkS")
		)
		(fp_line
			(start 0.87503 1.450086)
			(end 0.87503 -1.450086)
			(stroke
				(width 0.1)
				(type default)
			)
			(layer "F.Fab")
		)
		(fp_line
			(start 0.87503 -1.450086)
			(end -0.87503 -1.450086)
			(stroke
				(width 0.1)
				(type default)
			)
			(layer "F.Fab")
		)
		(fp_line
			(start -0.87503 1.450086)
			(end 0.87503 1.450086)
			(stroke
				(width 0.1)
				(type default)
			)
			(layer "F.Fab")
		)
		(fp_line
			(start -0.87503 -1.450086)
			(end -0.87503 1.450086)
			(stroke
				(width 0.1)
				(type default)
			)
			(layer "F.Fab")
		)
		(fp_poly
			(pts
				(xy -3.2512 -0.44196) (xy -3.2512 -1.45796) (xy -2.2352 -0.94996)
			)
			(stroke
				(width 0)
				(type default)
			)
			(fill yes)
			(layer "F.Fab")
		)
		(pad "1" smd rect
			(at -1.309878 -0.94996 270)
			(size 0.635 1.2192)
			(layers "F.Cu" "F.Mask" "F.Paste")
			(net "A_HSC_LOW_GATE")
		)
		(pad "2" smd rect
			(at -1.309878 0 270)
			(size 0.635 1.2192)
			(layers "F.Cu" "F.Mask" "F.Paste")
			(net "GND")
		)
		(pad "3" smd rect
			(at -1.309878 0.94996 270)
			(size 0.635 1.2192)
			(layers "F.Cu" "F.Mask" "F.Paste")
			(net "A_HSC_LOW")
		)
		(pad "4" smd rect
			(at 1.309878 0.94996 270)
			(size 0.635 1.2192)
			(layers "F.Cu" "F.Mask" "F.Paste")
			(net "A_HSC_HIGH")
		)
		(pad "5" smd rect
			(at 1.309878 0 270)
			(size 0.635 1.2192)
			(layers "F.Cu" "F.Mask" "F.Paste")
			(net "HSC_OC_LT6700_VS")
		)
		(pad "6" smd rect
			(at 1.309878 -0.94996 270)
			(size 0.635 1.2192)
			(layers "F.Cu" "F.Mask" "F.Paste")
			(net "HSC_D_OC_R")
		)
	)
	(footprint ""
		(layer "F.Cu")
		(at 102.229412 -385.205224)
		(property "Reference" "R6294"
			(at 0 0 0)
			(layer "F.SilkS")
			(hide yes)
			(effects
				(font
					(size 1.27 1.27)
				)
			)
		)
		(property "Value" ""
			(at 0 0 0)
			(layer "F.Fab")
			(effects
				(font
					(size 1.27 1.27)
				)
			)
		)
		(duplicate_pad_numbers_are_jumpers no)
		(fp_line
			(start -0.7874 -0.4064)
			(end 0.7874 -0.4064)
			(stroke
				(width 0.1524)
				(type default)
			)
			(layer "F.SilkS")
		)
		(fp_line
			(start 0.7874 -0.4064)
			(end 0.7874 0.4064)
			(stroke
				(width 0.1524)
				(type default)
			)
			(layer "F.SilkS")
		)
		(fp_line
			(start 0.7874 0.4064)
			(end -0.7874 0.4064)
			(stroke
				(width 0.1524)
				(type default)
			)
			(layer "F.SilkS")
		)
		(fp_line
			(start -0.67945 -0.305054)
			(end -0.12065 -0.305054)
			(stroke
				(width 0.1)
				(type default)
			)
			(layer "F.Fab")
		)
		(fp_line
			(start -0.67945 0.3048)
			(end -0.67945 -0.305054)
			(stroke
				(width 0.1)
				(type default)
			)
			(layer "F.Fab")
		)
		(fp_line
			(start -0.12065 -0.305054)
			(end -0.12065 -0.2794)
			(stroke
				(width 0.1)
				(type default)
			)
			(layer "F.Fab")
		)
		(fp_line
			(start -0.12065 -0.2794)
			(end 0.12065 -0.2794)
			(stroke
				(width 0.1)
				(type default)
			)
			(layer "F.Fab")
		)
		(fp_line
			(start -0.12065 0.2794)
			(end -0.12065 0.3048)
			(stroke
				(width 0.1)
				(type default)
			)
			(layer "F.Fab")
		)
		(fp_line
			(start -0.12065 0.3048)
			(end -0.67945 0.3048)
			(stroke
				(width 0.1)
				(type default)
			)
			(layer "F.Fab")
		)
		(fp_line
			(start 0.120396 0.2794)
			(end -0.12065 0.2794)
			(stroke
				(width 0.1)
				(type default)
			)
			(layer "F.Fab")
		)
		(fp_line
			(start 0.120396 0.3048)
			(end 0.120396 0.2794)
			(stroke
				(width 0.1)
				(type default)
			)
			(layer "F.Fab")
		)
		(fp_line
			(start 0.12065 -0.3048)
			(end 0.67945 -0.3048)
			(stroke
				(width 0.1)
				(type default)
			)
			(layer "F.Fab")
		)
		(fp_line
			(start 0.12065 -0.2794)
			(end 0.12065 -0.3048)
			(stroke
				(width 0.1)
				(type default)
			)
			(layer "F.Fab")
		)
		(fp_line
			(start 0.67945 -0.3048)
			(end 0.67945 0.3048)
			(stroke
				(width 0.1)
				(type default)
			)
			(layer "F.Fab")
		)
		(fp_line
			(start 0.67945 0.3048)
			(end 0.120396 0.3048)
			(stroke
				(width 0.1)
				(type default)
			)
			(layer "F.Fab")
		)
		(pad "1" smd rect
			(at -0.40005 0 180)
			(size 0.4572 0.508)
			(layers "F.Cu" "F.Mask" "F.Paste")
			(net "USB2_MB_BMC_DP")
		)
		(pad "2" smd rect
			(at 0.40005 0 180)
			(size 0.4572 0.508)
			(layers "F.Cu" "F.Mask" "F.Paste")
			(net "GND")
		)
	)
	(footprint ""
		(layer "F.Cu")
		(at 128.48336 -160.327848 180)
		(property "Reference" "PR6895"
			(at 0 0 180)
			(layer "F.SilkS")
			(hide yes)
			(effects
				(font
					(size 1.27 1.27)
				)
			)
		)
		(property "Value" ""
			(at 0 0 180)
			(layer "F.Fab")
			(effects
				(font
					(size 1.27 1.27)
				)
			)
		)
		(duplicate_pad_numbers_are_jumpers no)
		(fp_line
			(start 0.7874 0.4064)
			(end -0.7874 0.4064)
			(stroke
				(width 0.1524)
				(type default)
			)
			(layer "F.SilkS")
		)
		(fp_line
			(start 0.7874 -0.4064)
			(end 0.7874 0.4064)
			(stroke
				(width 0.1524)
				(type default)
			)
			(layer "F.SilkS")
		)
		(fp_line
			(start -0.7874 0.4064)
			(end -0.7874 -0.4064)
			(stroke
				(width 0.1524)
				(type default)
			)
			(layer "F.SilkS")
		)
		(fp_line
			(start -0.7874 -0.4064)
			(end 0.7874 -0.4064)
			(stroke
				(width 0.1524)
				(type default)
			)
			(layer "F.SilkS")
		)
		(fp_line
			(start 0.67945 0.3048)
			(end 0.120396 0.3048)
			(stroke
				(width 0.1)
				(type default)
			)
			(layer "F.Fab")
		)
		(fp_line
			(start 0.67945 -0.3048)
			(end 0.67945 0.3048)
			(stroke
				(width 0.1)
				(type default)
			)
			(layer "F.Fab")
		)
		(fp_line
			(start 0.12065 -0.2794)
			(end 0.12065 -0.3048)
			(stroke
				(width 0.1)
				(type default)
			)
			(layer "F.Fab")
		)
		(fp_line
			(start 0.12065 -0.3048)
			(end 0.67945 -0.3048)
			(stroke
				(width 0.1)
				(type default)
			)
			(layer "F.Fab")
		)
		(fp_line
			(start 0.120396 0.3048)
			(end 0.120396 0.2794)
			(stroke
				(width 0.1)
				(type default)
			)
			(layer "F.Fab")
		)
		(fp_line
			(start 0.120396 0.2794)
			(end -0.12065 0.2794)
			(stroke
				(width 0.1)
				(type default)
			)
			(layer "F.Fab")
		)
		(fp_line
			(start -0.12065 0.3048)
			(end -0.67945 0.3048)
			(stroke
				(width 0.1)
				(type default)
			)
			(layer "F.Fab")
		)
		(fp_line
			(start -0.12065 0.2794)
			(end -0.12065 0.3048)
			(stroke
				(width 0.1)
				(type default)
			)
			(layer "F.Fab")
		)
		(fp_line
			(start -0.12065 -0.2794)
			(end 0.12065 -0.2794)
			(stroke
				(width 0.1)
				(type default)
			)
			(layer "F.Fab")
		)
		(fp_line
			(start -0.12065 -0.305054)
			(end -0.12065 -0.2794)
			(stroke
				(width 0.1)
				(type default)
			)
			(layer "F.Fab")
		)
		(fp_line
			(start -0.67945 0.3048)
			(end -0.67945 -0.305054)
			(stroke
				(width 0.1)
				(type default)
			)
			(layer "F.Fab")
		)
		(fp_line
			(start -0.67945 -0.305054)
			(end -0.12065 -0.305054)
			(stroke
				(width 0.1)
				(type default)
			)
			(layer "F.Fab")
		)
		(pad "1" smd circle
			(at -0.40005 0 180)
			(size 0 0)
			(layers "F.Cu" "F.Mask" "F.Paste")
			(net "P12V_NIC2_CO_ISET")
		)
		(pad "2" smd circle
			(at 0.40005 0 180)
			(size 0 0)
			(layers "F.Cu" "F.Mask" "F.Paste")
			(net "P12V_NIC2_CO_ISET_R")
		)
	)
	(footprint ""
		(layer "F.Cu")
		(at 172.473874 -27.006296 -90)
		(property "Reference" "PC934"
			(at 0 0 270)
			(layer "F.SilkS")
			(hide yes)
			(effects
				(font
					(size 1.27 1.27)
				)
			)
		)
		(property "Value" ""
			(at 0 0 270)
			(layer "F.Fab")
			(effects
				(font
					(size 1.27 1.27)
				)
			)
		)
		(duplicate_pad_numbers_are_jumpers no)
		(fp_line
			(start -0.7874 0.4064)
			(end -0.7874 -0.4064)
			(stroke
				(width 0.1524)
				(type default)
			)
			(layer "F.SilkS")
		)
		(fp_line
			(start 0.7874 0.4064)
			(end -0.7874 0.4064)
			(stroke
				(width 0.1524)
				(type default)
			)
			(layer "F.SilkS")
		)
		(fp_line
			(start -0.7874 -0.4064)
			(end 0.7874 -0.4064)
			(stroke
				(width 0.1524)
				(type default)
			)
			(layer "F.SilkS")
		)
		(fp_line
			(start 0.7874 -0.4064)
			(end 0.7874 0.4064)
			(stroke
				(width 0.1524)
				(type default)
			)
			(layer "F.SilkS")
		)
		(fp_line
			(start -0.67945 0.3048)
			(end -0.67945 -0.305054)
			(stroke
				(width 0.1)
				(type default)
			)
			(layer "F.Fab")
		)
		(fp_line
			(start -0.12065 0.3048)
			(end -0.67945 0.3048)
			(stroke
				(width 0.1)
				(type default)
			)
			(layer "F.Fab")
		)
		(fp_line
			(start 0.120396 0.3048)
			(end 0.120396 0.2794)
			(stroke
				(width 0.1)
				(type default)
			)
			(layer "F.Fab")
		)
		(fp_line
			(start 0.67945 0.3048)
			(end 0.120396 0.3048)
			(stroke
				(width 0.1)
				(type default)
			)
			(layer "F.Fab")
		)
		(fp_line
			(start -0.12065 0.2794)
			(end -0.12065 0.3048)
			(stroke
				(width 0.1)
				(type default)
			)
			(layer "F.Fab")
		)
		(fp_line
			(start 0.120396 0.2794)
			(end -0.12065 0.2794)
			(stroke
				(width 0.1)
				(type default)
			)
			(layer "F.Fab")
		)
		(fp_line
			(start -0.12065 -0.2794)
			(end 0.12065 -0.2794)
			(stroke
				(width 0.1)
				(type default)
			)
			(layer "F.Fab")
		)
		(fp_line
			(start 0.12065 -0.2794)
			(end 0.12065 -0.3048)
			(stroke
				(width 0.1)
				(type default)
			)
			(layer "F.Fab")
		)
		(fp_line
			(start 0.12065 -0.3048)
			(end 0.67945 -0.3048)
			(stroke
				(width 0.1)
				(type default)
			)
			(layer "F.Fab")
		)
		(fp_line
			(start 0.67945 -0.3048)
			(end 0.67945 0.3048)
			(stroke
				(width 0.1)
				(type default)
			)
			(layer "F.Fab")
		)
		(fp_line
			(start -0.67945 -0.305054)
			(end -0.12065 -0.305054)
			(stroke
				(width 0.1)
				(type default)
			)
			(layer "F.Fab")
		)
		(fp_line
			(start -0.12065 -0.305054)
			(end -0.12065 -0.2794)
			(stroke
				(width 0.1)
				(type default)
			)
			(layer "F.Fab")
		)
		(pad "1" smd circle
			(at -0.40005 0 270)
			(size 0 0)
			(layers "F.Cu" "F.Mask" "F.Paste")
			(net "P3V3_SSD6_CO_MODE")
		)
		(pad "2" smd circle
			(at 0.40005 0 270)
			(size 0 0)
			(layers "F.Cu" "F.Mask" "F.Paste")
			(net "GND")
		)
	)
	(footprint ""
		(layer "F.Cu")
		(at 398.41551 -42.853102 180)
		(property "Reference" "R5905"
			(at 0 0 180)
			(layer "F.SilkS")
			(hide yes)
			(effects
				(font
					(size 1.27 1.27)
				)
			)
		)
		(property "Value" ""
			(at 0 0 180)
			(layer "F.Fab")
			(effects
				(font
					(size 1.27 1.27)
				)
			)
		)
		(duplicate_pad_numbers_are_jumpers no)
		(fp_line
			(start 0.7874 0.4064)
			(end -0.7874 0.4064)
			(stroke
				(width 0.1524)
				(type default)
			)
			(layer "F.SilkS")
		)
		(fp_line
			(start 0.7874 -0.4064)
			(end 0.7874 0.4064)
			(stroke
				(width 0.1524)
				(type default)
			)
			(layer "F.SilkS")
		)
		(fp_line
			(start -0.7874 0.4064)
			(end -0.7874 -0.4064)
			(stroke
				(width 0.1524)
				(type default)
			)
			(layer "F.SilkS")
		)
		(fp_line
			(start -0.7874 -0.4064)
			(end 0.7874 -0.4064)
			(stroke
				(width 0.1524)
				(type default)
			)
			(layer "F.SilkS")
		)
		(fp_line
			(start 0.67945 0.3048)
			(end 0.120396 0.3048)
			(stroke
				(width 0.1)
				(type default)
			)
			(layer "F.Fab")
		)
		(fp_line
			(start 0.67945 -0.3048)
			(end 0.67945 0.3048)
			(stroke
				(width 0.1)
				(type default)
			)
			(layer "F.Fab")
		)
		(fp_line
			(start 0.12065 -0.2794)
			(end 0.12065 -0.3048)
			(stroke
				(width 0.1)
				(type default)
			)
			(layer "F.Fab")
		)
		(fp_line
			(start 0.12065 -0.3048)
			(end 0.67945 -0.3048)
			(stroke
				(width 0.1)
				(type default)
			)
			(layer "F.Fab")
		)
		(fp_line
			(start 0.120396 0.3048)
			(end 0.120396 0.2794)
			(stroke
				(width 0.1)
				(type default)
			)
			(layer "F.Fab")
		)
		(fp_line
			(start 0.120396 0.2794)
			(end -0.12065 0.2794)
			(stroke
				(width 0.1)
				(type default)
			)
			(layer "F.Fab")
		)
		(fp_line
			(start -0.12065 0.3048)
			(end -0.67945 0.3048)
			(stroke
				(width 0.1)
				(type default)
			)
			(layer "F.Fab")
		)
		(fp_line
			(start -0.12065 0.2794)
			(end -0.12065 0.3048)
			(stroke
				(width 0.1)
				(type default)
			)
			(layer "F.Fab")
		)
		(fp_line
			(start -0.12065 -0.2794)
			(end 0.12065 -0.2794)
			(stroke
				(width 0.1)
				(type default)
			)
			(layer "F.Fab")
		)
		(fp_line
			(start -0.12065 -0.305054)
			(end -0.12065 -0.2794)
			(stroke
				(width 0.1)
				(type default)
			)
			(layer "F.Fab")
		)
		(fp_line
			(start -0.67945 0.3048)
			(end -0.67945 -0.305054)
			(stroke
				(width 0.1)
				(type default)
			)
			(layer "F.Fab")
		)
		(fp_line
			(start -0.67945 -0.305054)
			(end -0.12065 -0.305054)
			(stroke
				(width 0.1)
				(type default)
			)
			(layer "F.Fab")
		)
		(pad "1" smd circle
			(at -0.40005 0 180)
			(size 0 0)
			(layers "F.Cu" "F.Mask" "F.Paste")
			(net "SSD13_ADC_A1")
		)
		(pad "2" smd circle
			(at 0.40005 0 180)
			(size 0 0)
			(layers "F.Cu" "F.Mask" "F.Paste")
			(net "SMB_SSD13_ADC_SCL")
		)
	)
	(footprint ""
		(layer "F.Cu")
		(at 94.809056 -95.041466 -90)
		(property "Reference" "PC326"
			(at 0 0 270)
			(layer "F.SilkS")
			(hide yes)
			(effects
				(font
					(size 1.27 1.27)
				)
			)
		)
		(property "Value" ""
			(at 0 0 270)
			(layer "F.Fab")
			(effects
				(font
					(size 1.27 1.27)
				)
			)
		)
		(duplicate_pad_numbers_are_jumpers no)
		(fp_line
			(start -0.7874 0.4064)
			(end -0.7874 -0.4064)
			(stroke
				(width 0.1524)
				(type default)
			)
			(layer "F.SilkS")
		)
		(fp_line
			(start 0.7874 0.4064)
			(end -0.7874 0.4064)
			(stroke
				(width 0.1524)
				(type default)
			)
			(layer "F.SilkS")
		)
		(fp_line
			(start -0.7874 -0.4064)
			(end 0.7874 -0.4064)
			(stroke
				(width 0.1524)
				(type default)
			)
			(layer "F.SilkS")
		)
		(fp_line
			(start 0.7874 -0.4064)
			(end 0.7874 0.4064)
			(stroke
				(width 0.1524)
				(type default)
			)
			(layer "F.SilkS")
		)
		(fp_line
			(start -0.6858 0.3048)
			(end -0.6858 -0.3048)
			(stroke
				(width 0.1)
				(type default)
			)
			(layer "F.Fab")
		)
		(fp_line
			(start -0.1016 0.3048)
			(end -0.6858 0.3048)
			(stroke
				(width 0.1)
				(type default)
			)
			(layer "F.Fab")
		)
		(fp_line
			(start 0.1016 0.3048)
			(end 0.1016 0.2794)
			(stroke
				(width 0.1)
				(type default)
			)
			(layer "F.Fab")
		)
		(fp_line
			(start 0.6858 0.3048)
			(end 0.1016 0.3048)
			(stroke
				(width 0.1)
				(type default)
			)
			(layer "F.Fab")
		)
		(fp_line
			(start -0.1016 0.2794)
			(end -0.1016 0.3048)
			(stroke
				(width 0.1)
				(type default)
			)
			(layer "F.Fab")
		)
		(fp_line
			(start 0.1016 0.2794)
			(end -0.1016 0.2794)
			(stroke
				(width 0.1)
				(type default)
			)
			(layer "F.Fab")
		)
		(fp_line
			(start -0.1016 -0.2794)
			(end 0.1016 -0.2794)
			(stroke
				(width 0.1)
				(type default)
			)
			(layer "F.Fab")
		)
		(fp_line
			(start 0.1016 -0.2794)
			(end 0.1016 -0.3048)
			(stroke
				(width 0.1)
				(type default)
			)
			(layer "F.Fab")
		)
		(fp_line
			(start -0.6858 -0.3048)
			(end -0.1016 -0.3048)
			(stroke
				(width 0.1)
				(type default)
			)
			(layer "F.Fab")
		)
		(fp_line
			(start -0.1016 -0.3048)
			(end -0.1016 -0.2794)
			(stroke
				(width 0.1)
				(type default)
			)
			(layer "F.Fab")
		)
		(fp_line
			(start 0.1016 -0.3048)
			(end 0.6858 -0.3048)
			(stroke
				(width 0.1)
				(type default)
			)
			(layer "F.Fab")
		)
		(fp_line
			(start 0.6858 -0.3048)
			(end 0.6858 0.3048)
			(stroke
				(width 0.1)
				(type default)
			)
			(layer "F.Fab")
		)
		(pad "1" smd rect
			(at -0.40005 0 90)
			(size 0.4572 0.508)
			(layers "F.Cu" "F.Mask" "F.Paste")
			(net "P12V_NIC1_SS")
		)
		(pad "2" smd rect
			(at 0.40005 0 90)
			(size 0.4572 0.508)
			(layers "F.Cu" "F.Mask" "F.Paste")
			(net "GND")
		)
	)
	(footprint ""
		(layer "F.Cu")
		(at 31.656274 -61.487812 180)
		(property "Reference" "R5837"
			(at 0 0 180)
			(layer "F.SilkS")
			(hide yes)
			(effects
				(font
					(size 1.27 1.27)
				)
			)
		)
		(property "Value" ""
			(at 0 0 180)
			(layer "F.Fab")
			(effects
				(font
					(size 1.27 1.27)
				)
			)
		)
		(duplicate_pad_numbers_are_jumpers no)
		(fp_line
			(start 0.7874 0.4064)
			(end -0.7874 0.4064)
			(stroke
				(width 0.1524)
				(type default)
			)
			(layer "F.SilkS")
		)
		(fp_line
			(start 0.7874 -0.4064)
			(end 0.7874 0.4064)
			(stroke
				(width 0.1524)
				(type default)
			)
			(layer "F.SilkS")
		)
		(fp_line
			(start -0.7874 0.4064)
			(end -0.7874 -0.4064)
			(stroke
				(width 0.1524)
				(type default)
			)
			(layer "F.SilkS")
		)
		(fp_line
			(start -0.7874 -0.4064)
			(end 0.7874 -0.4064)
			(stroke
				(width 0.1524)
				(type default)
			)
			(layer "F.SilkS")
		)
		(fp_line
			(start 0.67945 0.3048)
			(end 0.120396 0.3048)
			(stroke
				(width 0.1)
				(type default)
			)
			(layer "F.Fab")
		)
		(fp_line
			(start 0.67945 -0.3048)
			(end 0.67945 0.3048)
			(stroke
				(width 0.1)
				(type default)
			)
			(layer "F.Fab")
		)
		(fp_line
			(start 0.12065 -0.2794)
			(end 0.12065 -0.3048)
			(stroke
				(width 0.1)
				(type default)
			)
			(layer "F.Fab")
		)
		(fp_line
			(start 0.12065 -0.3048)
			(end 0.67945 -0.3048)
			(stroke
				(width 0.1)
				(type default)
			)
			(layer "F.Fab")
		)
		(fp_line
			(start 0.120396 0.3048)
			(end 0.120396 0.2794)
			(stroke
				(width 0.1)
				(type default)
			)
			(layer "F.Fab")
		)
		(fp_line
			(start 0.120396 0.2794)
			(end -0.12065 0.2794)
			(stroke
				(width 0.1)
				(type default)
			)
			(layer "F.Fab")
		)
		(fp_line
			(start -0.12065 0.3048)
			(end -0.67945 0.3048)
			(stroke
				(width 0.1)
				(type default)
			)
			(layer "F.Fab")
		)
		(fp_line
			(start -0.12065 0.2794)
			(end -0.12065 0.3048)
			(stroke
				(width 0.1)
				(type default)
			)
			(layer "F.Fab")
		)
		(fp_line
			(start -0.12065 -0.2794)
			(end 0.12065 -0.2794)
			(stroke
				(width 0.1)
				(type default)
			)
			(layer "F.Fab")
		)
		(fp_line
			(start -0.12065 -0.305054)
			(end -0.12065 -0.2794)
			(stroke
				(width 0.1)
				(type default)
			)
			(layer "F.Fab")
		)
		(fp_line
			(start -0.67945 0.3048)
			(end -0.67945 -0.305054)
			(stroke
				(width 0.1)
				(type default)
			)
			(layer "F.Fab")
		)
		(fp_line
			(start -0.67945 -0.305054)
			(end -0.12065 -0.305054)
			(stroke
				(width 0.1)
				(type default)
			)
			(layer "F.Fab")
		)
		(pad "1" smd circle
			(at -0.40005 0 180)
			(size 0 0)
			(layers "F.Cu" "F.Mask" "F.Paste")
			(net "P3V3_AUX")
		)
		(pad "2" smd circle
			(at 0.40005 0 180)
			(size 0 0)
			(layers "F.Cu" "F.Mask" "F.Paste")
			(net "PWRGD_P12V_SSD1_D")
		)
	)
	(footprint ""
		(layer "F.Cu")
		(at 426.884084 -29.222954 -90)
		(property "Reference" "PC969"
			(at 0 0 270)
			(layer "F.SilkS")
			(hide yes)
			(effects
				(font
					(size 1.27 1.27)
				)
			)
		)
		(property "Value" ""
			(at 0 0 270)
			(layer "F.Fab")
			(effects
				(font
					(size 1.27 1.27)
				)
			)
		)
		(duplicate_pad_numbers_are_jumpers no)
		(fp_line
			(start -0.7874 0.4064)
			(end -0.7874 -0.4064)
			(stroke
				(width 0.1524)
				(type default)
			)
			(layer "F.SilkS")
		)
		(fp_line
			(start 0.7874 0.4064)
			(end -0.7874 0.4064)
			(stroke
				(width 0.1524)
				(type default)
			)
			(layer "F.SilkS")
		)
		(fp_line
			(start -0.7874 -0.4064)
			(end 0.7874 -0.4064)
			(stroke
				(width 0.1524)
				(type default)
			)
			(layer "F.SilkS")
		)
		(fp_line
			(start 0.7874 -0.4064)
			(end 0.7874 0.4064)
			(stroke
				(width 0.1524)
				(type default)
			)
			(layer "F.SilkS")
		)
		(fp_line
			(start -0.67945 0.3048)
			(end -0.67945 -0.305054)
			(stroke
				(width 0.1)
				(type default)
			)
			(layer "F.Fab")
		)
		(fp_line
			(start -0.12065 0.3048)
			(end -0.67945 0.3048)
			(stroke
				(width 0.1)
				(type default)
			)
			(layer "F.Fab")
		)
		(fp_line
			(start 0.120396 0.3048)
			(end 0.120396 0.2794)
			(stroke
				(width 0.1)
				(type default)
			)
			(layer "F.Fab")
		)
		(fp_line
			(start 0.67945 0.3048)
			(end 0.120396 0.3048)
			(stroke
				(width 0.1)
				(type default)
			)
			(layer "F.Fab")
		)
		(fp_line
			(start -0.12065 0.2794)
			(end -0.12065 0.3048)
			(stroke
				(width 0.1)
				(type default)
			)
			(layer "F.Fab")
		)
		(fp_line
			(start 0.120396 0.2794)
			(end -0.12065 0.2794)
			(stroke
				(width 0.1)
				(type default)
			)
			(layer "F.Fab")
		)
		(fp_line
			(start -0.12065 -0.2794)
			(end 0.12065 -0.2794)
			(stroke
				(width 0.1)
				(type default)
			)
			(layer "F.Fab")
		)
		(fp_line
			(start 0.12065 -0.2794)
			(end 0.12065 -0.3048)
			(stroke
				(width 0.1)
				(type default)
			)
			(layer "F.Fab")
		)
		(fp_line
			(start 0.12065 -0.3048)
			(end 0.67945 -0.3048)
			(stroke
				(width 0.1)
				(type default)
			)
			(layer "F.Fab")
		)
		(fp_line
			(start 0.67945 -0.3048)
			(end 0.67945 0.3048)
			(stroke
				(width 0.1)
				(type default)
			)
			(layer "F.Fab")
		)
		(fp_line
			(start -0.67945 -0.305054)
			(end -0.12065 -0.305054)
			(stroke
				(width 0.1)
				(type default)
			)
			(layer "F.Fab")
		)
		(fp_line
			(start -0.12065 -0.305054)
			(end -0.12065 -0.2794)
			(stroke
				(width 0.1)
				(type default)
			)
			(layer "F.Fab")
		)
		(pad "1" smd circle
			(at -0.40005 0 270)
			(size 0 0)
			(layers "F.Cu" "F.Mask" "F.Paste")
			(net "P3V3_AUX")
		)
		(pad "2" smd circle
			(at 0.40005 0 270)
			(size 0 0)
			(layers "F.Cu" "F.Mask" "F.Paste")
			(net "GND")
		)
	)
	(footprint ""
		(layer "F.Cu")
		(at 230.682038 -38.041072 180)
		(property "Reference" "R6084"
			(at 0 0 180)
			(layer "F.SilkS")
			(hide yes)
			(effects
				(font
					(size 1.27 1.27)
				)
			)
		)
		(property "Value" ""
			(at 0 0 180)
			(layer "F.Fab")
			(effects
				(font
					(size 1.27 1.27)
				)
			)
		)
		(duplicate_pad_numbers_are_jumpers no)
		(fp_line
			(start 0.7874 0.4064)
			(end -0.7874 0.4064)
			(stroke
				(width 0.1524)
				(type default)
			)
			(layer "F.SilkS")
		)
		(fp_line
			(start 0.7874 -0.4064)
			(end 0.7874 0.4064)
			(stroke
				(width 0.1524)
				(type default)
			)
			(layer "F.SilkS")
		)
		(fp_line
			(start -0.7874 0.4064)
			(end -0.7874 -0.4064)
			(stroke
				(width 0.1524)
				(type default)
			)
			(layer "F.SilkS")
		)
		(fp_line
			(start -0.7874 -0.4064)
			(end 0.7874 -0.4064)
			(stroke
				(width 0.1524)
				(type default)
			)
			(layer "F.SilkS")
		)
		(fp_line
			(start 0.67945 0.3048)
			(end 0.120396 0.3048)
			(stroke
				(width 0.1)
				(type default)
			)
			(layer "F.Fab")
		)
		(fp_line
			(start 0.67945 -0.3048)
			(end 0.67945 0.3048)
			(stroke
				(width 0.1)
				(type default)
			)
			(layer "F.Fab")
		)
		(fp_line
			(start 0.12065 -0.2794)
			(end 0.12065 -0.3048)
			(stroke
				(width 0.1)
				(type default)
			)
			(layer "F.Fab")
		)
		(fp_line
			(start 0.12065 -0.3048)
			(end 0.67945 -0.3048)
			(stroke
				(width 0.1)
				(type default)
			)
			(layer "F.Fab")
		)
		(fp_line
			(start 0.120396 0.3048)
			(end 0.120396 0.2794)
			(stroke
				(width 0.1)
				(type default)
			)
			(layer "F.Fab")
		)
		(fp_line
			(start 0.120396 0.2794)
			(end -0.12065 0.2794)
			(stroke
				(width 0.1)
				(type default)
			)
			(layer "F.Fab")
		)
		(fp_line
			(start -0.12065 0.3048)
			(end -0.67945 0.3048)
			(stroke
				(width 0.1)
				(type default)
			)
			(layer "F.Fab")
		)
		(fp_line
			(start -0.12065 0.2794)
			(end -0.12065 0.3048)
			(stroke
				(width 0.1)
				(type default)
			)
			(layer "F.Fab")
		)
		(fp_line
			(start -0.12065 -0.2794)
			(end 0.12065 -0.2794)
			(stroke
				(width 0.1)
				(type default)
			)
			(layer "F.Fab")
		)
		(fp_line
			(start -0.12065 -0.305054)
			(end -0.12065 -0.2794)
			(stroke
				(width 0.1)
				(type default)
			)
			(layer "F.Fab")
		)
		(fp_line
			(start -0.67945 0.3048)
			(end -0.67945 -0.305054)
			(stroke
				(width 0.1)
				(type default)
			)
			(layer "F.Fab")
		)
		(fp_line
			(start -0.67945 -0.305054)
			(end -0.12065 -0.305054)
			(stroke
				(width 0.1)
				(type default)
			)
			(layer "F.Fab")
		)
		(pad "1" smd circle
			(at -0.40005 0 180)
			(size 0 0)
			(layers "F.Cu" "F.Mask" "F.Paste")
			(net "P5V_AUX")
		)
		(pad "2" smd circle
			(at 0.40005 0 180)
			(size 0 0)
			(layers "F.Cu" "F.Mask" "F.Paste")
			(net "P3V3_SSD8_PG_G2")
		)
	)
	(footprint ""
		(layer "F.Cu")
		(at 142.474442 -252.356874 -90)
		(property "Reference" "R1291"
			(at 0 0 270)
			(layer "F.SilkS")
			(hide yes)
			(effects
				(font
					(size 1.27 1.27)
				)
			)
		)
		(property "Value" ""
			(at 0 0 270)
			(layer "F.Fab")
			(effects
				(font
					(size 1.27 1.27)
				)
			)
		)
		(duplicate_pad_numbers_are_jumpers no)
		(fp_line
			(start -0.7874 0.4064)
			(end -0.7874 -0.4064)
			(stroke
				(width 0.1524)
				(type default)
			)
			(layer "F.SilkS")
		)
		(fp_line
			(start 0.7874 0.4064)
			(end -0.7874 0.4064)
			(stroke
				(width 0.1524)
				(type default)
			)
			(layer "F.SilkS")
		)
		(fp_line
			(start -0.7874 -0.4064)
			(end 0.7874 -0.4064)
			(stroke
				(width 0.1524)
				(type default)
			)
			(layer "F.SilkS")
		)
		(fp_line
			(start 0.7874 -0.4064)
			(end 0.7874 0.4064)
			(stroke
				(width 0.1524)
				(type default)
			)
			(layer "F.SilkS")
		)
		(fp_line
			(start -0.67945 0.3048)
			(end -0.67945 -0.305054)
			(stroke
				(width 0.1)
				(type default)
			)
			(layer "F.Fab")
		)
		(fp_line
			(start -0.12065 0.3048)
			(end -0.67945 0.3048)
			(stroke
				(width 0.1)
				(type default)
			)
			(layer "F.Fab")
		)
		(fp_line
			(start 0.120396 0.3048)
			(end 0.120396 0.2794)
			(stroke
				(width 0.1)
				(type default)
			)
			(layer "F.Fab")
		)
		(fp_line
			(start 0.67945 0.3048)
			(end 0.120396 0.3048)
			(stroke
				(width 0.1)
				(type default)
			)
			(layer "F.Fab")
		)
		(fp_line
			(start -0.12065 0.2794)
			(end -0.12065 0.3048)
			(stroke
				(width 0.1)
				(type default)
			)
			(layer "F.Fab")
		)
		(fp_line
			(start 0.120396 0.2794)
			(end -0.12065 0.2794)
			(stroke
				(width 0.1)
				(type default)
			)
			(layer "F.Fab")
		)
		(fp_line
			(start -0.12065 -0.2794)
			(end 0.12065 -0.2794)
			(stroke
				(width 0.1)
				(type default)
			)
			(layer "F.Fab")
		)
		(fp_line
			(start 0.12065 -0.2794)
			(end 0.12065 -0.3048)
			(stroke
				(width 0.1)
				(type default)
			)
			(layer "F.Fab")
		)
		(fp_line
			(start 0.12065 -0.3048)
			(end 0.67945 -0.3048)
			(stroke
				(width 0.1)
				(type default)
			)
			(layer "F.Fab")
		)
		(fp_line
			(start 0.67945 -0.3048)
			(end 0.67945 0.3048)
			(stroke
				(width 0.1)
				(type default)
			)
			(layer "F.Fab")
		)
		(fp_line
			(start -0.67945 -0.305054)
			(end -0.12065 -0.305054)
			(stroke
				(width 0.1)
				(type default)
			)
			(layer "F.Fab")
		)
		(fp_line
			(start -0.12065 -0.305054)
			(end -0.12065 -0.2794)
			(stroke
				(width 0.1)
				(type default)
			)
			(layer "F.Fab")
		)
		(pad "1" smd circle
			(at -0.40005 0 270)
			(size 0 0)
			(layers "F.Cu" "F.Mask" "F.Paste")
			(net "GND")
		)
		(pad "2" smd circle
			(at 0.40005 0 270)
			(size 0 0)
			(layers "F.Cu" "F.Mask" "F.Paste")
			(net "PEX1_MODE_SEL2")
		)
	)
	(footprint ""
		(layer "F.Cu")
		(at 218.483434 -49.94148)
		(property "Reference" "R5897"
			(at 0 0 0)
			(layer "F.SilkS")
			(hide yes)
			(effects
				(font
					(size 1.27 1.27)
				)
			)
		)
		(property "Value" ""
			(at 0 0 0)
			(layer "F.Fab")
			(effects
				(font
					(size 1.27 1.27)
				)
			)
		)
		(duplicate_pad_numbers_are_jumpers no)
		(fp_line
			(start -0.7874 -0.4064)
			(end 0.7874 -0.4064)
			(stroke
				(width 0.1524)
				(type default)
			)
			(layer "F.SilkS")
		)
		(fp_line
			(start -0.7874 0.4064)
			(end -0.7874 -0.4064)
			(stroke
				(width 0.1524)
				(type default)
			)
			(layer "F.SilkS")
		)
		(fp_line
			(start 0.7874 -0.4064)
			(end 0.7874 0.4064)
			(stroke
				(width 0.1524)
				(type default)
			)
			(layer "F.SilkS")
		)
		(fp_line
			(start 0.7874 0.4064)
			(end -0.7874 0.4064)
			(stroke
				(width 0.1524)
				(type default)
			)
			(layer "F.SilkS")
		)
		(fp_line
			(start -0.67945 -0.305054)
			(end -0.12065 -0.305054)
			(stroke
				(width 0.1)
				(type default)
			)
			(layer "F.Fab")
		)
		(fp_line
			(start -0.67945 0.3048)
			(end -0.67945 -0.305054)
			(stroke
				(width 0.1)
				(type default)
			)
			(layer "F.Fab")
		)
		(fp_line
			(start -0.12065 -0.305054)
			(end -0.12065 -0.2794)
			(stroke
				(width 0.1)
				(type default)
			)
			(layer "F.Fab")
		)
		(fp_line
			(start -0.12065 -0.2794)
			(end 0.12065 -0.2794)
			(stroke
				(width 0.1)
				(type default)
			)
			(layer "F.Fab")
		)
		(fp_line
			(start -0.12065 0.2794)
			(end -0.12065 0.3048)
			(stroke
				(width 0.1)
				(type default)
			)
			(layer "F.Fab")
		)
		(fp_line
			(start -0.12065 0.3048)
			(end -0.67945 0.3048)
			(stroke
				(width 0.1)
				(type default)
			)
			(layer "F.Fab")
		)
		(fp_line
			(start 0.120396 0.2794)
			(end -0.12065 0.2794)
			(stroke
				(width 0.1)
				(type default)
			)
			(layer "F.Fab")
		)
		(fp_line
			(start 0.120396 0.3048)
			(end 0.120396 0.2794)
			(stroke
				(width 0.1)
				(type default)
			)
			(layer "F.Fab")
		)
		(fp_line
			(start 0.12065 -0.3048)
			(end 0.67945 -0.3048)
			(stroke
				(width 0.1)
				(type default)
			)
			(layer "F.Fab")
		)
		(fp_line
			(start 0.12065 -0.2794)
			(end 0.12065 -0.3048)
			(stroke
				(width 0.1)
				(type default)
			)
			(layer "F.Fab")
		)
		(fp_line
			(start 0.67945 -0.3048)
			(end 0.67945 0.3048)
			(stroke
				(width 0.1)
				(type default)
			)
			(layer "F.Fab")
		)
		(fp_line
			(start 0.67945 0.3048)
			(end 0.120396 0.3048)
			(stroke
				(width 0.1)
				(type default)
			)
			(layer "F.Fab")
		)
		(pad "1" smd circle
			(at -0.40005 0)
			(size 0 0)
			(layers "F.Cu" "F.Mask" "F.Paste")
			(net "SSD7_ADC_A0")
		)
		(pad "2" smd circle
			(at 0.40005 0)
			(size 0 0)
			(layers "F.Cu" "F.Mask" "F.Paste")
			(net "SMB_SSD7_ADC_SCL")
		)
	)
	(footprint ""
		(layer "F.Cu")
		(at 429.455072 -53.468524 90)
		(property "Reference" "PC571"
			(at 0 0 90)
			(layer "F.SilkS")
			(hide yes)
			(effects
				(font
					(size 1.27 1.27)
				)
			)
		)
		(property "Value" ""
			(at 0 0 90)
			(layer "F.Fab")
			(effects
				(font
					(size 1.27 1.27)
				)
			)
		)
		(duplicate_pad_numbers_are_jumpers no)
		(fp_line
			(start 1.524 -0.762)
			(end 1.524 0.762)
			(stroke
				(width 0.1524)
				(type default)
			)
			(layer "F.SilkS")
		)
		(fp_line
			(start -1.524 -0.762)
			(end 1.524 -0.762)
			(stroke
				(width 0.1524)
				(type default)
			)
			(layer "F.SilkS")
		)
		(fp_line
			(start 1.524 0.762)
			(end -1.524 0.762)
			(stroke
				(width 0.1524)
				(type default)
			)
			(layer "F.SilkS")
		)
		(fp_line
			(start -1.524 0.762)
			(end -1.524 -0.762)
			(stroke
				(width 0.1524)
				(type default)
			)
			(layer "F.SilkS")
		)
		(fp_line
			(start 1.1049 -0.724916)
			(end -1.1049 -0.724916)
			(stroke
				(width 0.1)
				(type default)
			)
			(layer "F.Fab")
		)
		(fp_line
			(start -1.1049 -0.724916)
			(end -1.1049 0.724916)
			(stroke
				(width 0.1)
				(type default)
			)
			(layer "F.Fab")
		)
		(fp_line
			(start 1.1049 0.724916)
			(end 1.1049 -0.724916)
			(stroke
				(width 0.1)
				(type default)
			)
			(layer "F.Fab")
		)
		(fp_line
			(start -1.1049 0.724916)
			(end 1.1049 0.724916)
			(stroke
				(width 0.1)
				(type default)
			)
			(layer "F.Fab")
		)
		(pad "1" smd rect
			(at -0.889 0 270)
			(size 1.016 1.27)
			(layers "F.Cu" "F.Mask" "F.Paste")
			(net "GND")
		)
		(pad "2" smd rect
			(at 0.889 0 270)
			(size 1.016 1.27)
			(layers "F.Cu" "F.Mask" "F.Paste")
			(net "P3V3_AUX")
		)
	)
	(footprint ""
		(layer "F.Cu")
		(at 81.883504 -61.487812 180)
		(property "Reference" "R5849"
			(at 0 0 180)
			(layer "F.SilkS")
			(hide yes)
			(effects
				(font
					(size 1.27 1.27)
				)
			)
		)
		(property "Value" ""
			(at 0 0 180)
			(layer "F.Fab")
			(effects
				(font
					(size 1.27 1.27)
				)
			)
		)
		(duplicate_pad_numbers_are_jumpers no)
		(fp_line
			(start 0.7874 0.4064)
			(end -0.7874 0.4064)
			(stroke
				(width 0.1524)
				(type default)
			)
			(layer "F.SilkS")
		)
		(fp_line
			(start 0.7874 -0.4064)
			(end 0.7874 0.4064)
			(stroke
				(width 0.1524)
				(type default)
			)
			(layer "F.SilkS")
		)
		(fp_line
			(start -0.7874 0.4064)
			(end -0.7874 -0.4064)
			(stroke
				(width 0.1524)
				(type default)
			)
			(layer "F.SilkS")
		)
		(fp_line
			(start -0.7874 -0.4064)
			(end 0.7874 -0.4064)
			(stroke
				(width 0.1524)
				(type default)
			)
			(layer "F.SilkS")
		)
		(fp_line
			(start 0.67945 0.3048)
			(end 0.120396 0.3048)
			(stroke
				(width 0.1)
				(type default)
			)
			(layer "F.Fab")
		)
		(fp_line
			(start 0.67945 -0.3048)
			(end 0.67945 0.3048)
			(stroke
				(width 0.1)
				(type default)
			)
			(layer "F.Fab")
		)
		(fp_line
			(start 0.12065 -0.2794)
			(end 0.12065 -0.3048)
			(stroke
				(width 0.1)
				(type default)
			)
			(layer "F.Fab")
		)
		(fp_line
			(start 0.12065 -0.3048)
			(end 0.67945 -0.3048)
			(stroke
				(width 0.1)
				(type default)
			)
			(layer "F.Fab")
		)
		(fp_line
			(start 0.120396 0.3048)
			(end 0.120396 0.2794)
			(stroke
				(width 0.1)
				(type default)
			)
			(layer "F.Fab")
		)
		(fp_line
			(start 0.120396 0.2794)
			(end -0.12065 0.2794)
			(stroke
				(width 0.1)
				(type default)
			)
			(layer "F.Fab")
		)
		(fp_line
			(start -0.12065 0.3048)
			(end -0.67945 0.3048)
			(stroke
				(width 0.1)
				(type default)
			)
			(layer "F.Fab")
		)
		(fp_line
			(start -0.12065 0.2794)
			(end -0.12065 0.3048)
			(stroke
				(width 0.1)
				(type default)
			)
			(layer "F.Fab")
		)
		(fp_line
			(start -0.12065 -0.2794)
			(end 0.12065 -0.2794)
			(stroke
				(width 0.1)
				(type default)
			)
			(layer "F.Fab")
		)
		(fp_line
			(start -0.12065 -0.305054)
			(end -0.12065 -0.2794)
			(stroke
				(width 0.1)
				(type default)
			)
			(layer "F.Fab")
		)
		(fp_line
			(start -0.67945 0.3048)
			(end -0.67945 -0.305054)
			(stroke
				(width 0.1)
				(type default)
			)
			(layer "F.Fab")
		)
		(fp_line
			(start -0.67945 -0.305054)
			(end -0.12065 -0.305054)
			(stroke
				(width 0.1)
				(type default)
			)
			(layer "F.Fab")
		)
		(pad "1" smd circle
			(at -0.40005 0 180)
			(size 0 0)
			(layers "F.Cu" "F.Mask" "F.Paste")
			(net "PWRGD_P12V_SSD3_D")
		)
		(pad "2" smd circle
			(at 0.40005 0 180)
			(size 0 0)
			(layers "F.Cu" "F.Mask" "F.Paste")
			(net "PWRGD_P12V_SSD3_R")
		)
	)
	(footprint ""
		(layer "F.Cu")
		(at 410.809948 -165.670484 -90)
		(property "Reference" "R2470"
			(at 0 0 270)
			(layer "F.SilkS")
			(hide yes)
			(effects
				(font
					(size 1.27 1.27)
				)
			)
		)
		(property "Value" ""
			(at 0 0 270)
			(layer "F.Fab")
			(effects
				(font
					(size 1.27 1.27)
				)
			)
		)
		(duplicate_pad_numbers_are_jumpers no)
		(fp_line
			(start -0.7874 0.4064)
			(end -0.7874 -0.4064)
			(stroke
				(width 0.1524)
				(type default)
			)
			(layer "F.SilkS")
		)
		(fp_line
			(start 0.7874 0.4064)
			(end -0.7874 0.4064)
			(stroke
				(width 0.1524)
				(type default)
			)
			(layer "F.SilkS")
		)
		(fp_line
			(start -0.7874 -0.4064)
			(end 0.7874 -0.4064)
			(stroke
				(width 0.1524)
				(type default)
			)
			(layer "F.SilkS")
		)
		(fp_line
			(start 0.7874 -0.4064)
			(end 0.7874 0.4064)
			(stroke
				(width 0.1524)
				(type default)
			)
			(layer "F.SilkS")
		)
		(fp_line
			(start -0.67945 0.3048)
			(end -0.67945 -0.305054)
			(stroke
				(width 0.1)
				(type default)
			)
			(layer "F.Fab")
		)
		(fp_line
			(start -0.12065 0.3048)
			(end -0.67945 0.3048)
			(stroke
				(width 0.1)
				(type default)
			)
			(layer "F.Fab")
		)
		(fp_line
			(start 0.120396 0.3048)
			(end 0.120396 0.2794)
			(stroke
				(width 0.1)
				(type default)
			)
			(layer "F.Fab")
		)
		(fp_line
			(start 0.67945 0.3048)
			(end 0.120396 0.3048)
			(stroke
				(width 0.1)
				(type default)
			)
			(layer "F.Fab")
		)
		(fp_line
			(start -0.12065 0.2794)
			(end -0.12065 0.3048)
			(stroke
				(width 0.1)
				(type default)
			)
			(layer "F.Fab")
		)
		(fp_line
			(start 0.120396 0.2794)
			(end -0.12065 0.2794)
			(stroke
				(width 0.1)
				(type default)
			)
			(layer "F.Fab")
		)
		(fp_line
			(start -0.12065 -0.2794)
			(end 0.12065 -0.2794)
			(stroke
				(width 0.1)
				(type default)
			)
			(layer "F.Fab")
		)
		(fp_line
			(start 0.12065 -0.2794)
			(end 0.12065 -0.3048)
			(stroke
				(width 0.1)
				(type default)
			)
			(layer "F.Fab")
		)
		(fp_line
			(start 0.12065 -0.3048)
			(end 0.67945 -0.3048)
			(stroke
				(width 0.1)
				(type default)
			)
			(layer "F.Fab")
		)
		(fp_line
			(start 0.67945 -0.3048)
			(end 0.67945 0.3048)
			(stroke
				(width 0.1)
				(type default)
			)
			(layer "F.Fab")
		)
		(fp_line
			(start -0.67945 -0.305054)
			(end -0.12065 -0.305054)
			(stroke
				(width 0.1)
				(type default)
			)
			(layer "F.Fab")
		)
		(fp_line
			(start -0.12065 -0.305054)
			(end -0.12065 -0.2794)
			(stroke
				(width 0.1)
				(type default)
			)
			(layer "F.Fab")
		)
		(pad "1" smd circle
			(at -0.40005 0 270)
			(size 0 0)
			(layers "F.Cu" "F.Mask" "F.Paste")
			(net "NIC6_PWRBRK_R_N")
		)
		(pad "2" smd circle
			(at 0.40005 0 270)
			(size 0 0)
			(layers "F.Cu" "F.Mask" "F.Paste")
			(net "NIC6_PWRBRK_N")
		)
	)
	(footprint ""
		(layer "F.Cu")
		(at 60.11037 -63.652146 180)
		(property "Reference" "R5850"
			(at 0 0 180)
			(layer "F.SilkS")
			(hide yes)
			(effects
				(font
					(size 1.27 1.27)
				)
			)
		)
		(property "Value" ""
			(at 0 0 180)
			(layer "F.Fab")
			(effects
				(font
					(size 1.27 1.27)
				)
			)
		)
		(duplicate_pad_numbers_are_jumpers no)
		(fp_line
			(start 0.7874 0.4064)
			(end -0.7874 0.4064)
			(stroke
				(width 0.1524)
				(type default)
			)
			(layer "F.SilkS")
		)
		(fp_line
			(start 0.7874 -0.4064)
			(end 0.7874 0.4064)
			(stroke
				(width 0.1524)
				(type default)
			)
			(layer "F.SilkS")
		)
		(fp_line
			(start -0.7874 0.4064)
			(end -0.7874 -0.4064)
			(stroke
				(width 0.1524)
				(type default)
			)
			(layer "F.SilkS")
		)
		(fp_line
			(start -0.7874 -0.4064)
			(end 0.7874 -0.4064)
			(stroke
				(width 0.1524)
				(type default)
			)
			(layer "F.SilkS")
		)
		(fp_line
			(start 0.67945 0.3048)
			(end 0.120396 0.3048)
			(stroke
				(width 0.1)
				(type default)
			)
			(layer "F.Fab")
		)
		(fp_line
			(start 0.67945 -0.3048)
			(end 0.67945 0.3048)
			(stroke
				(width 0.1)
				(type default)
			)
			(layer "F.Fab")
		)
		(fp_line
			(start 0.12065 -0.2794)
			(end 0.12065 -0.3048)
			(stroke
				(width 0.1)
				(type default)
			)
			(layer "F.Fab")
		)
		(fp_line
			(start 0.12065 -0.3048)
			(end 0.67945 -0.3048)
			(stroke
				(width 0.1)
				(type default)
			)
			(layer "F.Fab")
		)
		(fp_line
			(start 0.120396 0.3048)
			(end 0.120396 0.2794)
			(stroke
				(width 0.1)
				(type default)
			)
			(layer "F.Fab")
		)
		(fp_line
			(start 0.120396 0.2794)
			(end -0.12065 0.2794)
			(stroke
				(width 0.1)
				(type default)
			)
			(layer "F.Fab")
		)
		(fp_line
			(start -0.12065 0.3048)
			(end -0.67945 0.3048)
			(stroke
				(width 0.1)
				(type default)
			)
			(layer "F.Fab")
		)
		(fp_line
			(start -0.12065 0.2794)
			(end -0.12065 0.3048)
			(stroke
				(width 0.1)
				(type default)
			)
			(layer "F.Fab")
		)
		(fp_line
			(start -0.12065 -0.2794)
			(end 0.12065 -0.2794)
			(stroke
				(width 0.1)
				(type default)
			)
			(layer "F.Fab")
		)
		(fp_line
			(start -0.12065 -0.305054)
			(end -0.12065 -0.2794)
			(stroke
				(width 0.1)
				(type default)
			)
			(layer "F.Fab")
		)
		(fp_line
			(start -0.67945 0.3048)
			(end -0.67945 -0.305054)
			(stroke
				(width 0.1)
				(type default)
			)
			(layer "F.Fab")
		)
		(fp_line
			(start -0.67945 -0.305054)
			(end -0.12065 -0.305054)
			(stroke
				(width 0.1)
				(type default)
			)
			(layer "F.Fab")
		)
		(pad "1" smd circle
			(at -0.40005 0 180)
			(size 0 0)
			(layers "F.Cu" "F.Mask" "F.Paste")
			(net "P5V_AUX")
		)
		(pad "2" smd circle
			(at 0.40005 0 180)
			(size 0 0)
			(layers "F.Cu" "F.Mask" "F.Paste")
			(net "P12V_SSD2_PG_G2")
		)
	)
	(footprint ""
		(layer "F.Cu")
		(at 428.319438 -129.880106 180)
		(property "Reference" "C657"
			(at 0 0 180)
			(layer "F.SilkS")
			(hide yes)
			(effects
				(font
					(size 1.27 1.27)
				)
			)
		)
		(property "Value" ""
			(at 0 0 180)
			(layer "F.Fab")
			(effects
				(font
					(size 1.27 1.27)
				)
			)
		)
		(duplicate_pad_numbers_are_jumpers no)
		(fp_line
			(start 0.299974 0.150114)
			(end -0.299974 0.150114)
			(stroke
				(width 0.1)
				(type default)
			)
			(layer "F.Fab")
		)
		(fp_line
			(start 0.299974 -0.150114)
			(end 0.299974 0.150114)
			(stroke
				(width 0.1)
				(type default)
			)
			(layer "F.Fab")
		)
		(fp_line
			(start -0.299974 0.150114)
			(end -0.299974 -0.150114)
			(stroke
				(width 0.1)
				(type default)
			)
			(layer "F.Fab")
		)
		(fp_line
			(start -0.299974 -0.150114)
			(end 0.299974 -0.150114)
			(stroke
				(width 0.1)
				(type default)
			)
			(layer "F.Fab")
		)
		(pad "1" smd rect
			(at -0.2667 0 180)
			(size 0.3048 0.381)
			(layers "F.Cu" "F.Mask" "F.Paste")
			(net "P5E_PEX3_STN0_TX_DN<4>")
		)
		(pad "2" smd rect
			(at 0.2667 0 180)
			(size 0.3048 0.381)
			(layers "F.Cu" "F.Mask" "F.Paste")
			(net "P5E_PEX3_STN0_TX_C_DN<4>")
		)
	)
	(footprint ""
		(layer "F.Cu")
		(at 370.327936 -35.876738)
		(property "Reference" "R6107"
			(at 0 0 0)
			(layer "F.SilkS")
			(hide yes)
			(effects
				(font
					(size 1.27 1.27)
				)
			)
		)
		(property "Value" ""
			(at 0 0 0)
			(layer "F.Fab")
			(effects
				(font
					(size 1.27 1.27)
				)
			)
		)
		(duplicate_pad_numbers_are_jumpers no)
		(fp_line
			(start -0.7874 -0.4064)
			(end 0.7874 -0.4064)
			(stroke
				(width 0.1524)
				(type default)
			)
			(layer "F.SilkS")
		)
		(fp_line
			(start -0.7874 0.4064)
			(end -0.7874 -0.4064)
			(stroke
				(width 0.1524)
				(type default)
			)
			(layer "F.SilkS")
		)
		(fp_line
			(start 0.7874 -0.4064)
			(end 0.7874 0.4064)
			(stroke
				(width 0.1524)
				(type default)
			)
			(layer "F.SilkS")
		)
		(fp_line
			(start 0.7874 0.4064)
			(end -0.7874 0.4064)
			(stroke
				(width 0.1524)
				(type default)
			)
			(layer "F.SilkS")
		)
		(fp_line
			(start -0.67945 -0.305054)
			(end -0.12065 -0.305054)
			(stroke
				(width 0.1)
				(type default)
			)
			(layer "F.Fab")
		)
		(fp_line
			(start -0.67945 0.3048)
			(end -0.67945 -0.305054)
			(stroke
				(width 0.1)
				(type default)
			)
			(layer "F.Fab")
		)
		(fp_line
			(start -0.12065 -0.305054)
			(end -0.12065 -0.2794)
			(stroke
				(width 0.1)
				(type default)
			)
			(layer "F.Fab")
		)
		(fp_line
			(start -0.12065 -0.2794)
			(end 0.12065 -0.2794)
			(stroke
				(width 0.1)
				(type default)
			)
			(layer "F.Fab")
		)
		(fp_line
			(start -0.12065 0.2794)
			(end -0.12065 0.3048)
			(stroke
				(width 0.1)
				(type default)
			)
			(layer "F.Fab")
		)
		(fp_line
			(start -0.12065 0.3048)
			(end -0.67945 0.3048)
			(stroke
				(width 0.1)
				(type default)
			)
			(layer "F.Fab")
		)
		(fp_line
			(start 0.120396 0.2794)
			(end -0.12065 0.2794)
			(stroke
				(width 0.1)
				(type default)
			)
			(layer "F.Fab")
		)
		(fp_line
			(start 0.120396 0.3048)
			(end 0.120396 0.2794)
			(stroke
				(width 0.1)
				(type default)
			)
			(layer "F.Fab")
		)
		(fp_line
			(start 0.12065 -0.3048)
			(end 0.67945 -0.3048)
			(stroke
				(width 0.1)
				(type default)
			)
			(layer "F.Fab")
		)
		(fp_line
			(start 0.12065 -0.2794)
			(end 0.12065 -0.3048)
			(stroke
				(width 0.1)
				(type default)
			)
			(layer "F.Fab")
		)
		(fp_line
			(start 0.67945 -0.3048)
			(end 0.67945 0.3048)
			(stroke
				(width 0.1)
				(type default)
			)
			(layer "F.Fab")
		)
		(fp_line
			(start 0.67945 0.3048)
			(end 0.120396 0.3048)
			(stroke
				(width 0.1)
				(type default)
			)
			(layer "F.Fab")
		)
		(pad "1" smd circle
			(at -0.40005 0)
			(size 0 0)
			(layers "F.Cu" "F.Mask" "F.Paste")
			(net "PWRGD_P3V3_SSD13_D")
		)
		(pad "2" smd circle
			(at 0.40005 0)
			(size 0 0)
			(layers "F.Cu" "F.Mask" "F.Paste")
			(net "PWRGD_P3V3_SSD13_R")
		)
	)
	(footprint ""
		(layer "F.Cu")
		(at 418.13988 -70.52437 90)
		(property "Reference" "PC431"
			(at 0 0 90)
			(layer "F.SilkS")
			(hide yes)
			(effects
				(font
					(size 1.27 1.27)
				)
			)
		)
		(property "Value" ""
			(at 0 0 90)
			(layer "F.Fab")
			(effects
				(font
					(size 1.27 1.27)
				)
			)
		)
		(duplicate_pad_numbers_are_jumpers no)
		(fp_line
			(start 1.524 -0.762)
			(end 1.524 0.762)
			(stroke
				(width 0.1524)
				(type default)
			)
			(layer "F.SilkS")
		)
		(fp_line
			(start -1.524 -0.762)
			(end 1.524 -0.762)
			(stroke
				(width 0.1524)
				(type default)
			)
			(layer "F.SilkS")
		)
		(fp_line
			(start 1.524 0.762)
			(end -1.524 0.762)
			(stroke
				(width 0.1524)
				(type default)
			)
			(layer "F.SilkS")
		)
		(fp_line
			(start -1.524 0.762)
			(end -1.524 -0.762)
			(stroke
				(width 0.1524)
				(type default)
			)
			(layer "F.SilkS")
		)
		(fp_line
			(start 1.1049 -0.724916)
			(end -1.1049 -0.724916)
			(stroke
				(width 0.1)
				(type default)
			)
			(layer "F.Fab")
		)
		(fp_line
			(start -1.1049 -0.724916)
			(end -1.1049 0.724916)
			(stroke
				(width 0.1)
				(type default)
			)
			(layer "F.Fab")
		)
		(fp_line
			(start 1.1049 0.724916)
			(end 1.1049 -0.724916)
			(stroke
				(width 0.1)
				(type default)
			)
			(layer "F.Fab")
		)
		(fp_line
			(start -1.1049 0.724916)
			(end 1.1049 0.724916)
			(stroke
				(width 0.1)
				(type default)
			)
			(layer "F.Fab")
		)
		(pad "1" smd rect
			(at -0.889 0 270)
			(size 1.016 1.27)
			(layers "F.Cu" "F.Mask" "F.Paste")
			(net "P12V_SSD14_R")
		)
		(pad "2" smd rect
			(at 0.889 0 270)
			(size 1.016 1.27)
			(layers "F.Cu" "F.Mask" "F.Paste")
			(net "GND")
		)
	)
	(footprint ""
		(layer "F.Cu")
		(at 140.259816 -214.982806 180)
		(property "Reference" "C2596"
			(at 0 0 180)
			(layer "F.SilkS")
			(hide yes)
			(effects
				(font
					(size 1.27 1.27)
				)
			)
		)
		(property "Value" ""
			(at 0 0 180)
			(layer "F.Fab")
			(effects
				(font
					(size 1.27 1.27)
				)
			)
		)
		(duplicate_pad_numbers_are_jumpers no)
		(fp_line
			(start 1.2954 0.5842)
			(end -1.2954 0.5842)
			(stroke
				(width 0.1524)
				(type default)
			)
			(layer "F.SilkS")
		)
		(fp_line
			(start 1.2954 -0.5842)
			(end 1.2954 0.5842)
			(stroke
				(width 0.1524)
				(type default)
			)
			(layer "F.SilkS")
		)
		(fp_line
			(start -1.2954 0.5842)
			(end -1.2954 -0.5842)
			(stroke
				(width 0.1524)
				(type default)
			)
			(layer "F.SilkS")
		)
		(fp_line
			(start -1.2954 -0.5842)
			(end 1.2954 -0.5842)
			(stroke
				(width 0.1524)
				(type default)
			)
			(layer "F.SilkS")
		)
		(fp_line
			(start 1.1938 0.4064)
			(end 0.8636 0.4064)
			(stroke
				(width 0.1)
				(type default)
			)
			(layer "F.Fab")
		)
		(fp_line
			(start 1.1938 -0.4064)
			(end 1.1938 0.4064)
			(stroke
				(width 0.1)
				(type default)
			)
			(layer "F.Fab")
		)
		(fp_line
			(start 0.8636 0.4572)
			(end -0.8636 0.4572)
			(stroke
				(width 0.1)
				(type default)
			)
			(layer "F.Fab")
		)
		(fp_line
			(start 0.8636 0.4064)
			(end 0.8636 0.4572)
			(stroke
				(width 0.1)
				(type default)
			)
			(layer "F.Fab")
		)
		(fp_line
			(start 0.8636 -0.4064)
			(end 1.1938 -0.4064)
			(stroke
				(width 0.1)
				(type default)
			)
			(layer "F.Fab")
		)
		(fp_line
			(start 0.8636 -0.4572)
			(end 0.8636 -0.4064)
			(stroke
				(width 0.1)
				(type default)
			)
			(layer "F.Fab")
		)
		(fp_line
			(start -0.8636 0.4572)
			(end -0.8636 0.4064)
			(stroke
				(width 0.1)
				(type default)
			)
			(layer "F.Fab")
		)
		(fp_line
			(start -0.8636 0.4064)
			(end -1.1938 0.4064)
			(stroke
				(width 0.1)
				(type default)
			)
			(layer "F.Fab")
		)
		(fp_line
			(start -0.8636 -0.4064)
			(end -0.8636 -0.4572)
			(stroke
				(width 0.1)
				(type default)
			)
			(layer "F.Fab")
		)
		(fp_line
			(start -0.8636 -0.4572)
			(end 0.8636 -0.4572)
			(stroke
				(width 0.1)
				(type default)
			)
			(layer "F.Fab")
		)
		(fp_line
			(start -1.1938 0.4064)
			(end -1.1938 -0.4064)
			(stroke
				(width 0.1)
				(type default)
			)
			(layer "F.Fab")
		)
		(fp_line
			(start -1.1938 -0.4064)
			(end -0.8636 -0.4064)
			(stroke
				(width 0.1)
				(type default)
			)
			(layer "F.Fab")
		)
		(pad "1" smd rect
			(at -0.7366 0 90)
			(size 0.7112 0.8128)
			(layers "F.Cu" "F.Mask" "F.Paste")
			(net "P1V8_CLI_VCORE")
		)
		(pad "2" smd rect
			(at 0.7366 0 90)
			(size 0.7112 0.8128)
			(layers "F.Cu" "F.Mask" "F.Paste")
			(net "GND")
		)
	)
	(footprint ""
		(layer "F.Cu")
		(at 270.799814 -151.279352 180)
		(property "Reference" "R220"
			(at 0 0 180)
			(layer "F.SilkS")
			(hide yes)
			(effects
				(font
					(size 1.27 1.27)
				)
			)
		)
		(property "Value" ""
			(at 0 0 180)
			(layer "F.Fab")
			(effects
				(font
					(size 1.27 1.27)
				)
			)
		)
		(duplicate_pad_numbers_are_jumpers no)
		(fp_line
			(start 0.7874 0.4064)
			(end -0.7874 0.4064)
			(stroke
				(width 0.1524)
				(type default)
			)
			(layer "F.SilkS")
		)
		(fp_line
			(start 0.7874 -0.4064)
			(end 0.7874 0.4064)
			(stroke
				(width 0.1524)
				(type default)
			)
			(layer "F.SilkS")
		)
		(fp_line
			(start -0.7874 0.4064)
			(end -0.7874 -0.4064)
			(stroke
				(width 0.1524)
				(type default)
			)
			(layer "F.SilkS")
		)
		(fp_line
			(start -0.7874 -0.4064)
			(end 0.7874 -0.4064)
			(stroke
				(width 0.1524)
				(type default)
			)
			(layer "F.SilkS")
		)
		(fp_line
			(start 0.67945 0.3048)
			(end 0.120396 0.3048)
			(stroke
				(width 0.1)
				(type default)
			)
			(layer "F.Fab")
		)
		(fp_line
			(start 0.67945 -0.3048)
			(end 0.67945 0.3048)
			(stroke
				(width 0.1)
				(type default)
			)
			(layer "F.Fab")
		)
		(fp_line
			(start 0.12065 -0.2794)
			(end 0.12065 -0.3048)
			(stroke
				(width 0.1)
				(type default)
			)
			(layer "F.Fab")
		)
		(fp_line
			(start 0.12065 -0.3048)
			(end 0.67945 -0.3048)
			(stroke
				(width 0.1)
				(type default)
			)
			(layer "F.Fab")
		)
		(fp_line
			(start 0.120396 0.3048)
			(end 0.120396 0.2794)
			(stroke
				(width 0.1)
				(type default)
			)
			(layer "F.Fab")
		)
		(fp_line
			(start 0.120396 0.2794)
			(end -0.12065 0.2794)
			(stroke
				(width 0.1)
				(type default)
			)
			(layer "F.Fab")
		)
		(fp_line
			(start -0.12065 0.3048)
			(end -0.67945 0.3048)
			(stroke
				(width 0.1)
				(type default)
			)
			(layer "F.Fab")
		)
		(fp_line
			(start -0.12065 0.2794)
			(end -0.12065 0.3048)
			(stroke
				(width 0.1)
				(type default)
			)
			(layer "F.Fab")
		)
		(fp_line
			(start -0.12065 -0.2794)
			(end 0.12065 -0.2794)
			(stroke
				(width 0.1)
				(type default)
			)
			(layer "F.Fab")
		)
		(fp_line
			(start -0.12065 -0.305054)
			(end -0.12065 -0.2794)
			(stroke
				(width 0.1)
				(type default)
			)
			(layer "F.Fab")
		)
		(fp_line
			(start -0.67945 0.3048)
			(end -0.67945 -0.305054)
			(stroke
				(width 0.1)
				(type default)
			)
			(layer "F.Fab")
		)
		(fp_line
			(start -0.67945 -0.305054)
			(end -0.12065 -0.305054)
			(stroke
				(width 0.1)
				(type default)
			)
			(layer "F.Fab")
		)
		(pad "1" smd circle
			(at -0.40005 0 180)
			(size 0 0)
			(layers "F.Cu" "F.Mask" "F.Paste")
			(net "NCSI_NIC4_RXD0")
		)
		(pad "2" smd circle
			(at 0.40005 0 180)
			(size 0 0)
			(layers "F.Cu" "F.Mask" "F.Paste")
			(net "GND")
		)
	)
	(footprint ""
		(layer "F.Cu")
		(at 46.44644 -58.323734)
		(property "Reference" "PC377"
			(at 0 0 0)
			(layer "F.SilkS")
			(hide yes)
			(effects
				(font
					(size 1.27 1.27)
				)
			)
		)
		(property "Value" ""
			(at 0 0 0)
			(layer "F.Fab")
			(effects
				(font
					(size 1.27 1.27)
				)
			)
		)
		(duplicate_pad_numbers_are_jumpers no)
		(fp_line
			(start -1.524 -0.762)
			(end 1.524 -0.762)
			(stroke
				(width 0.1524)
				(type default)
			)
			(layer "F.SilkS")
		)
		(fp_line
			(start -1.524 0.762)
			(end -1.524 -0.762)
			(stroke
				(width 0.1524)
				(type default)
			)
			(layer "F.SilkS")
		)
		(fp_line
			(start 1.524 -0.762)
			(end 1.524 0.762)
			(stroke
				(width 0.1524)
				(type default)
			)
			(layer "F.SilkS")
		)
		(fp_line
			(start 1.524 0.762)
			(end -1.524 0.762)
			(stroke
				(width 0.1524)
				(type default)
			)
			(layer "F.SilkS")
		)
		(fp_line
			(start -1.1049 -0.724916)
			(end -1.1049 0.724916)
			(stroke
				(width 0.1)
				(type default)
			)
			(layer "F.Fab")
		)
		(fp_line
			(start -1.1049 0.724916)
			(end 1.1049 0.724916)
			(stroke
				(width 0.1)
				(type default)
			)
			(layer "F.Fab")
		)
		(fp_line
			(start 1.1049 -0.724916)
			(end -1.1049 -0.724916)
			(stroke
				(width 0.1)
				(type default)
			)
			(layer "F.Fab")
		)
		(fp_line
			(start 1.1049 0.724916)
			(end 1.1049 -0.724916)
			(stroke
				(width 0.1)
				(type default)
			)
			(layer "F.Fab")
		)
		(pad "1" smd rect
			(at -0.889 0 180)
			(size 1.016 1.27)
			(layers "F.Cu" "F.Mask" "F.Paste")
			(net "GND")
		)
		(pad "2" smd rect
			(at 0.889 0 180)
			(size 1.016 1.27)
			(layers "F.Cu" "F.Mask" "F.Paste")
			(net "P12V_AUX")
		)
	)
	(footprint ""
		(layer "F.Cu")
		(at 20.901914 -413.969708 90)
		(property "Reference" "R5590"
			(at 0 0 90)
			(layer "F.SilkS")
			(hide yes)
			(effects
				(font
					(size 1.27 1.27)
				)
			)
		)
		(property "Value" ""
			(at 0 0 90)
			(layer "F.Fab")
			(effects
				(font
					(size 1.27 1.27)
				)
			)
		)
		(duplicate_pad_numbers_are_jumpers no)
		(fp_line
			(start 0.7874 -0.4064)
			(end 0.7874 0.4064)
			(stroke
				(width 0.1524)
				(type default)
			)
			(layer "F.SilkS")
		)
		(fp_line
			(start -0.7874 -0.4064)
			(end 0.7874 -0.4064)
			(stroke
				(width 0.1524)
				(type default)
			)
			(layer "F.SilkS")
		)
		(fp_line
			(start 0.7874 0.4064)
			(end -0.7874 0.4064)
			(stroke
				(width 0.1524)
				(type default)
			)
			(layer "F.SilkS")
		)
		(fp_line
			(start -0.7874 0.4064)
			(end -0.7874 -0.4064)
			(stroke
				(width 0.1524)
				(type default)
			)
			(layer "F.SilkS")
		)
		(fp_line
			(start -0.12065 -0.305054)
			(end -0.12065 -0.2794)
			(stroke
				(width 0.1)
				(type default)
			)
			(layer "F.Fab")
		)
		(fp_line
			(start -0.67945 -0.305054)
			(end -0.12065 -0.305054)
			(stroke
				(width 0.1)
				(type default)
			)
			(layer "F.Fab")
		)
		(fp_line
			(start 0.67945 -0.3048)
			(end 0.67945 0.3048)
			(stroke
				(width 0.1)
				(type default)
			)
			(layer "F.Fab")
		)
		(fp_line
			(start 0.12065 -0.3048)
			(end 0.67945 -0.3048)
			(stroke
				(width 0.1)
				(type default)
			)
			(layer "F.Fab")
		)
		(fp_line
			(start 0.12065 -0.2794)
			(end 0.12065 -0.3048)
			(stroke
				(width 0.1)
				(type default)
			)
			(layer "F.Fab")
		)
		(fp_line
			(start -0.12065 -0.2794)
			(end 0.12065 -0.2794)
			(stroke
				(width 0.1)
				(type default)
			)
			(layer "F.Fab")
		)
		(fp_line
			(start 0.120396 0.2794)
			(end -0.12065 0.2794)
			(stroke
				(width 0.1)
				(type default)
			)
			(layer "F.Fab")
		)
		(fp_line
			(start -0.12065 0.2794)
			(end -0.12065 0.3048)
			(stroke
				(width 0.1)
				(type default)
			)
			(layer "F.Fab")
		)
		(fp_line
			(start 0.67945 0.3048)
			(end 0.120396 0.3048)
			(stroke
				(width 0.1)
				(type default)
			)
			(layer "F.Fab")
		)
		(fp_line
			(start 0.120396 0.3048)
			(end 0.120396 0.2794)
			(stroke
				(width 0.1)
				(type default)
			)
			(layer "F.Fab")
		)
		(fp_line
			(start -0.12065 0.3048)
			(end -0.67945 0.3048)
			(stroke
				(width 0.1)
				(type default)
			)
			(layer "F.Fab")
		)
		(fp_line
			(start -0.67945 0.3048)
			(end -0.67945 -0.305054)
			(stroke
				(width 0.1)
				(type default)
			)
			(layer "F.Fab")
		)
		(pad "1" smd circle
			(at -0.40005 0 90)
			(size 0 0)
			(layers "F.Cu" "F.Mask" "F.Paste")
			(net "LM75_0_A2")
		)
		(pad "2" smd circle
			(at 0.40005 0 90)
			(size 0 0)
			(layers "F.Cu" "F.Mask" "F.Paste")
			(net "P3V3_AUX")
		)
	)
	(footprint ""
		(layer "F.Cu")
		(at 30.438344 -252.356874 -90)
		(property "Reference" "R1190"
			(at 0 0 270)
			(layer "F.SilkS")
			(hide yes)
			(effects
				(font
					(size 1.27 1.27)
				)
			)
		)
		(property "Value" ""
			(at 0 0 270)
			(layer "F.Fab")
			(effects
				(font
					(size 1.27 1.27)
				)
			)
		)
		(duplicate_pad_numbers_are_jumpers no)
		(fp_line
			(start -0.7874 0.4064)
			(end -0.7874 -0.4064)
			(stroke
				(width 0.1524)
				(type default)
			)
			(layer "F.SilkS")
		)
		(fp_line
			(start 0.7874 0.4064)
			(end -0.7874 0.4064)
			(stroke
				(width 0.1524)
				(type default)
			)
			(layer "F.SilkS")
		)
		(fp_line
			(start -0.7874 -0.4064)
			(end 0.7874 -0.4064)
			(stroke
				(width 0.1524)
				(type default)
			)
			(layer "F.SilkS")
		)
		(fp_line
			(start 0.7874 -0.4064)
			(end 0.7874 0.4064)
			(stroke
				(width 0.1524)
				(type default)
			)
			(layer "F.SilkS")
		)
		(fp_line
			(start -0.67945 0.3048)
			(end -0.67945 -0.305054)
			(stroke
				(width 0.1)
				(type default)
			)
			(layer "F.Fab")
		)
		(fp_line
			(start -0.12065 0.3048)
			(end -0.67945 0.3048)
			(stroke
				(width 0.1)
				(type default)
			)
			(layer "F.Fab")
		)
		(fp_line
			(start 0.120396 0.3048)
			(end 0.120396 0.2794)
			(stroke
				(width 0.1)
				(type default)
			)
			(layer "F.Fab")
		)
		(fp_line
			(start 0.67945 0.3048)
			(end 0.120396 0.3048)
			(stroke
				(width 0.1)
				(type default)
			)
			(layer "F.Fab")
		)
		(fp_line
			(start -0.12065 0.2794)
			(end -0.12065 0.3048)
			(stroke
				(width 0.1)
				(type default)
			)
			(layer "F.Fab")
		)
		(fp_line
			(start 0.120396 0.2794)
			(end -0.12065 0.2794)
			(stroke
				(width 0.1)
				(type default)
			)
			(layer "F.Fab")
		)
		(fp_line
			(start -0.12065 -0.2794)
			(end 0.12065 -0.2794)
			(stroke
				(width 0.1)
				(type default)
			)
			(layer "F.Fab")
		)
		(fp_line
			(start 0.12065 -0.2794)
			(end 0.12065 -0.3048)
			(stroke
				(width 0.1)
				(type default)
			)
			(layer "F.Fab")
		)
		(fp_line
			(start 0.12065 -0.3048)
			(end 0.67945 -0.3048)
			(stroke
				(width 0.1)
				(type default)
			)
			(layer "F.Fab")
		)
		(fp_line
			(start 0.67945 -0.3048)
			(end 0.67945 0.3048)
			(stroke
				(width 0.1)
				(type default)
			)
			(layer "F.Fab")
		)
		(fp_line
			(start -0.67945 -0.305054)
			(end -0.12065 -0.305054)
			(stroke
				(width 0.1)
				(type default)
			)
			(layer "F.Fab")
		)
		(fp_line
			(start -0.12065 -0.305054)
			(end -0.12065 -0.2794)
			(stroke
				(width 0.1)
				(type default)
			)
			(layer "F.Fab")
		)
		(pad "1" smd circle
			(at -0.40005 0 270)
			(size 0 0)
			(layers "F.Cu" "F.Mask" "F.Paste")
			(net "GND")
		)
		(pad "2" smd circle
			(at 0.40005 0 270)
			(size 0 0)
			(layers "F.Cu" "F.Mask" "F.Paste")
			(net "PEX0_MODE_SEL0")
		)
	)
	(footprint ""
		(layer "F.Cu")
		(at 187.032392 -343.952322 90)
		(property "Reference" "C378"
			(at 0 0 90)
			(layer "F.SilkS")
			(hide yes)
			(effects
				(font
					(size 1.27 1.27)
				)
			)
		)
		(property "Value" ""
			(at 0 0 90)
			(layer "F.Fab")
			(effects
				(font
					(size 1.27 1.27)
				)
			)
		)
		(duplicate_pad_numbers_are_jumpers no)
		(fp_line
			(start 0.299974 -0.150114)
			(end 0.299974 0.150114)
			(stroke
				(width 0.1)
				(type default)
			)
			(layer "F.Fab")
		)
		(fp_line
			(start -0.299974 -0.150114)
			(end 0.299974 -0.150114)
			(stroke
				(width 0.1)
				(type default)
			)
			(layer "F.Fab")
		)
		(fp_line
			(start 0.299974 0.150114)
			(end -0.299974 0.150114)
			(stroke
				(width 0.1)
				(type default)
			)
			(layer "F.Fab")
		)
		(fp_line
			(start -0.299974 0.150114)
			(end -0.299974 -0.150114)
			(stroke
				(width 0.1)
				(type default)
			)
			(layer "F.Fab")
		)
		(pad "1" smd rect
			(at -0.2667 0 90)
			(size 0.3048 0.381)
			(layers "F.Cu" "F.Mask" "F.Paste")
			(net "P5E_PEX1_STN7_TX_DP<124>")
		)
		(pad "2" smd rect
			(at 0.2667 0 90)
			(size 0.3048 0.381)
			(layers "F.Cu" "F.Mask" "F.Paste")
			(net "P5E_PEX1_STN7_TX_C_DP<124>")
		)
	)
	(footprint ""
		(layer "F.Cu")
		(at 316.908942 -27.04973 180)
		(property "Reference" "C2774"
			(at 0 0 180)
			(layer "F.SilkS")
			(hide yes)
			(effects
				(font
					(size 1.27 1.27)
				)
			)
		)
		(property "Value" ""
			(at 0 0 180)
			(layer "F.Fab")
			(effects
				(font
					(size 1.27 1.27)
				)
			)
		)
		(duplicate_pad_numbers_are_jumpers no)
		(fp_line
			(start 0.7874 0.4064)
			(end -0.7874 0.4064)
			(stroke
				(width 0.1524)
				(type default)
			)
			(layer "F.SilkS")
		)
		(fp_line
			(start 0.7874 -0.4064)
			(end 0.7874 0.4064)
			(stroke
				(width 0.1524)
				(type default)
			)
			(layer "F.SilkS")
		)
		(fp_line
			(start -0.7874 0.4064)
			(end -0.7874 -0.4064)
			(stroke
				(width 0.1524)
				(type default)
			)
			(layer "F.SilkS")
		)
		(fp_line
			(start -0.7874 -0.4064)
			(end 0.7874 -0.4064)
			(stroke
				(width 0.1524)
				(type default)
			)
			(layer "F.SilkS")
		)
		(fp_line
			(start 0.67945 0.3048)
			(end 0.120396 0.3048)
			(stroke
				(width 0.1)
				(type default)
			)
			(layer "F.Fab")
		)
		(fp_line
			(start 0.67945 -0.3048)
			(end 0.67945 0.3048)
			(stroke
				(width 0.1)
				(type default)
			)
			(layer "F.Fab")
		)
		(fp_line
			(start 0.12065 -0.2794)
			(end 0.12065 -0.3048)
			(stroke
				(width 0.1)
				(type default)
			)
			(layer "F.Fab")
		)
		(fp_line
			(start 0.12065 -0.3048)
			(end 0.67945 -0.3048)
			(stroke
				(width 0.1)
				(type default)
			)
			(layer "F.Fab")
		)
		(fp_line
			(start 0.120396 0.3048)
			(end 0.120396 0.2794)
			(stroke
				(width 0.1)
				(type default)
			)
			(layer "F.Fab")
		)
		(fp_line
			(start 0.120396 0.2794)
			(end -0.12065 0.2794)
			(stroke
				(width 0.1)
				(type default)
			)
			(layer "F.Fab")
		)
		(fp_line
			(start -0.12065 0.3048)
			(end -0.67945 0.3048)
			(stroke
				(width 0.1)
				(type default)
			)
			(layer "F.Fab")
		)
		(fp_line
			(start -0.12065 0.2794)
			(end -0.12065 0.3048)
			(stroke
				(width 0.1)
				(type default)
			)
			(layer "F.Fab")
		)
		(fp_line
			(start -0.12065 -0.2794)
			(end 0.12065 -0.2794)
			(stroke
				(width 0.1)
				(type default)
			)
			(layer "F.Fab")
		)
		(fp_line
			(start -0.12065 -0.305054)
			(end -0.12065 -0.2794)
			(stroke
				(width 0.1)
				(type default)
			)
			(layer "F.Fab")
		)
		(fp_line
			(start -0.67945 0.3048)
			(end -0.67945 -0.305054)
			(stroke
				(width 0.1)
				(type default)
			)
			(layer "F.Fab")
		)
		(fp_line
			(start -0.67945 -0.305054)
			(end -0.12065 -0.305054)
			(stroke
				(width 0.1)
				(type default)
			)
			(layer "F.Fab")
		)
		(pad "1" smd circle
			(at -0.40005 0 180)
			(size 0 0)
			(layers "F.Cu" "F.Mask" "F.Paste")
			(net "PRSNT_SSD11_R_N")
		)
		(pad "2" smd circle
			(at 0.40005 0 180)
			(size 0 0)
			(layers "F.Cu" "F.Mask" "F.Paste")
			(net "GND")
		)
	)
	(footprint ""
		(layer "F.Cu")
		(at 82.661506 -156.111194 180)
		(property "Reference" "C1"
			(at 0 0 180)
			(layer "F.SilkS")
			(hide yes)
			(effects
				(font
					(size 1.27 1.27)
				)
			)
		)
		(property "Value" ""
			(at 0 0 180)
			(layer "F.Fab")
			(effects
				(font
					(size 1.27 1.27)
				)
			)
		)
		(duplicate_pad_numbers_are_jumpers no)
		(fp_line
			(start 0.299974 0.150114)
			(end -0.299974 0.150114)
			(stroke
				(width 0.1)
				(type default)
			)
			(layer "F.Fab")
		)
		(fp_line
			(start 0.299974 -0.150114)
			(end 0.299974 0.150114)
			(stroke
				(width 0.1)
				(type default)
			)
			(layer "F.Fab")
		)
		(fp_line
			(start -0.299974 0.150114)
			(end -0.299974 -0.150114)
			(stroke
				(width 0.1)
				(type default)
			)
			(layer "F.Fab")
		)
		(fp_line
			(start -0.299974 -0.150114)
			(end 0.299974 -0.150114)
			(stroke
				(width 0.1)
				(type default)
			)
			(layer "F.Fab")
		)
		(pad "1" smd rect
			(at -0.2667 0 180)
			(size 0.3048 0.381)
			(layers "F.Cu" "F.Mask" "F.Paste")
			(net "P5E_PEX0_STN0_TX_DP<15>")
		)
		(pad "2" smd rect
			(at 0.2667 0 180)
			(size 0.3048 0.381)
			(layers "F.Cu" "F.Mask" "F.Paste")
			(net "P5E_PEX0_STN0_TX_C_DP<15>")
		)
	)
	(footprint ""
		(layer "F.Cu")
		(at 37.248084 -102.009702)
		(property "Reference" "C62"
			(at 0 0 0)
			(layer "F.SilkS")
			(hide yes)
			(effects
				(font
					(size 1.27 1.27)
				)
			)
		)
		(property "Value" ""
			(at 0 0 0)
			(layer "F.Fab")
			(effects
				(font
					(size 1.27 1.27)
				)
			)
		)
		(duplicate_pad_numbers_are_jumpers no)
		(fp_line
			(start -0.299974 -0.150114)
			(end 0.299974 -0.150114)
			(stroke
				(width 0.1)
				(type default)
			)
			(layer "F.Fab")
		)
		(fp_line
			(start -0.299974 0.150114)
			(end -0.299974 -0.150114)
			(stroke
				(width 0.1)
				(type default)
			)
			(layer "F.Fab")
		)
		(fp_line
			(start 0.299974 -0.150114)
			(end 0.299974 0.150114)
			(stroke
				(width 0.1)
				(type default)
			)
			(layer "F.Fab")
		)
		(fp_line
			(start 0.299974 0.150114)
			(end -0.299974 0.150114)
			(stroke
				(width 0.1)
				(type default)
			)
			(layer "F.Fab")
		)
		(pad "1" smd rect
			(at -0.2667 0)
			(size 0.3048 0.381)
			(layers "F.Cu" "F.Mask" "F.Paste")
			(net "P5E_PEX0_STN1_TX_DP<17>")
		)
		(pad "2" smd rect
			(at 0.2667 0)
			(size 0.3048 0.381)
			(layers "F.Cu" "F.Mask" "F.Paste")
			(net "P5E_PEX0_STN1_TX_C_DP<17>")
		)
	)
	(footprint ""
		(layer "F.Cu")
		(at 159.892492 -28.225242 180)
		(property "Reference" "C291"
			(at 0 0 180)
			(layer "F.SilkS")
			(hide yes)
			(effects
				(font
					(size 1.27 1.27)
				)
			)
		)
		(property "Value" ""
			(at 0 0 180)
			(layer "F.Fab")
			(effects
				(font
					(size 1.27 1.27)
				)
			)
		)
		(duplicate_pad_numbers_are_jumpers no)
		(fp_line
			(start 0.299974 0.150114)
			(end -0.299974 0.150114)
			(stroke
				(width 0.1)
				(type default)
			)
			(layer "F.Fab")
		)
		(fp_line
			(start 0.299974 -0.150114)
			(end 0.299974 0.150114)
			(stroke
				(width 0.1)
				(type default)
			)
			(layer "F.Fab")
		)
		(fp_line
			(start -0.299974 0.150114)
			(end -0.299974 -0.150114)
			(stroke
				(width 0.1)
				(type default)
			)
			(layer "F.Fab")
		)
		(fp_line
			(start -0.299974 -0.150114)
			(end 0.299974 -0.150114)
			(stroke
				(width 0.1)
				(type default)
			)
			(layer "F.Fab")
		)
		(pad "1" smd rect
			(at -0.2667 0 180)
			(size 0.3048 0.381)
			(layers "F.Cu" "F.Mask" "F.Paste")
			(net "P5E_PEX1_STN2_TX_DN<40>")
		)
		(pad "2" smd rect
			(at 0.2667 0 180)
			(size 0.3048 0.381)
			(layers "F.Cu" "F.Mask" "F.Paste")
			(net "P5E_PEX1_STN2_TX_C_DN<40>")
		)
	)
	(footprint ""
		(layer "F.Cu")
		(at 241.56416 -55.81142 90)
		(property "Reference" "PC554"
			(at 0 0 90)
			(layer "F.SilkS")
			(hide yes)
			(effects
				(font
					(size 1.27 1.27)
				)
			)
		)
		(property "Value" ""
			(at 0 0 90)
			(layer "F.Fab")
			(effects
				(font
					(size 1.27 1.27)
				)
			)
		)
		(duplicate_pad_numbers_are_jumpers no)
		(fp_line
			(start 0.7874 -0.4064)
			(end 0.7874 0.4064)
			(stroke
				(width 0.1524)
				(type default)
			)
			(layer "F.SilkS")
		)
		(fp_line
			(start -0.7874 -0.4064)
			(end 0.7874 -0.4064)
			(stroke
				(width 0.1524)
				(type default)
			)
			(layer "F.SilkS")
		)
		(fp_line
			(start 0.7874 0.4064)
			(end -0.7874 0.4064)
			(stroke
				(width 0.1524)
				(type default)
			)
			(layer "F.SilkS")
		)
		(fp_line
			(start -0.7874 0.4064)
			(end -0.7874 -0.4064)
			(stroke
				(width 0.1524)
				(type default)
			)
			(layer "F.SilkS")
		)
		(fp_line
			(start -0.12065 -0.305054)
			(end -0.12065 -0.2794)
			(stroke
				(width 0.1)
				(type default)
			)
			(layer "F.Fab")
		)
		(fp_line
			(start -0.67945 -0.305054)
			(end -0.12065 -0.305054)
			(stroke
				(width 0.1)
				(type default)
			)
			(layer "F.Fab")
		)
		(fp_line
			(start 0.67945 -0.3048)
			(end 0.67945 0.3048)
			(stroke
				(width 0.1)
				(type default)
			)
			(layer "F.Fab")
		)
		(fp_line
			(start 0.12065 -0.3048)
			(end 0.67945 -0.3048)
			(stroke
				(width 0.1)
				(type default)
			)
			(layer "F.Fab")
		)
		(fp_line
			(start 0.12065 -0.2794)
			(end 0.12065 -0.3048)
			(stroke
				(width 0.1)
				(type default)
			)
			(layer "F.Fab")
		)
		(fp_line
			(start -0.12065 -0.2794)
			(end 0.12065 -0.2794)
			(stroke
				(width 0.1)
				(type default)
			)
			(layer "F.Fab")
		)
		(fp_line
			(start 0.120396 0.2794)
			(end -0.12065 0.2794)
			(stroke
				(width 0.1)
				(type default)
			)
			(layer "F.Fab")
		)
		(fp_line
			(start -0.12065 0.2794)
			(end -0.12065 0.3048)
			(stroke
				(width 0.1)
				(type default)
			)
			(layer "F.Fab")
		)
		(fp_line
			(start 0.67945 0.3048)
			(end 0.120396 0.3048)
			(stroke
				(width 0.1)
				(type default)
			)
			(layer "F.Fab")
		)
		(fp_line
			(start 0.120396 0.3048)
			(end 0.120396 0.2794)
			(stroke
				(width 0.1)
				(type default)
			)
			(layer "F.Fab")
		)
		(fp_line
			(start -0.12065 0.3048)
			(end -0.67945 0.3048)
			(stroke
				(width 0.1)
				(type default)
			)
			(layer "F.Fab")
		)
		(fp_line
			(start -0.67945 0.3048)
			(end -0.67945 -0.305054)
			(stroke
				(width 0.1)
				(type default)
			)
			(layer "F.Fab")
		)
		(pad "1" smd circle
			(at -0.40005 0 90)
			(size 0 0)
			(layers "F.Cu" "F.Mask" "F.Paste")
			(net "P3V3_SSD8_SS")
		)
		(pad "2" smd circle
			(at 0.40005 0 90)
			(size 0 0)
			(layers "F.Cu" "F.Mask" "F.Paste")
			(net "GND")
		)
	)
	(footprint ""
		(layer "F.Cu")
		(at 81.002632 -89.1159)
		(property "Reference" "C873"
			(at 0 0 0)
			(layer "F.SilkS")
			(hide yes)
			(effects
				(font
					(size 1.27 1.27)
				)
			)
		)
		(property "Value" ""
			(at 0 0 0)
			(layer "F.Fab")
			(effects
				(font
					(size 1.27 1.27)
				)
			)
		)
		(duplicate_pad_numbers_are_jumpers no)
		(fp_line
			(start -0.7874 -0.4064)
			(end 0.7874 -0.4064)
			(stroke
				(width 0.1524)
				(type default)
			)
			(layer "F.SilkS")
		)
		(fp_line
			(start -0.7874 0.4064)
			(end -0.7874 -0.4064)
			(stroke
				(width 0.1524)
				(type default)
			)
			(layer "F.SilkS")
		)
		(fp_line
			(start 0.7874 -0.4064)
			(end 0.7874 0.4064)
			(stroke
				(width 0.1524)
				(type default)
			)
			(layer "F.SilkS")
		)
		(fp_line
			(start 0.7874 0.4064)
			(end -0.7874 0.4064)
			(stroke
				(width 0.1524)
				(type default)
			)
			(layer "F.SilkS")
		)
		(fp_line
			(start -0.67945 -0.305054)
			(end -0.12065 -0.305054)
			(stroke
				(width 0.1)
				(type default)
			)
			(layer "F.Fab")
		)
		(fp_line
			(start -0.67945 0.3048)
			(end -0.67945 -0.305054)
			(stroke
				(width 0.1)
				(type default)
			)
			(layer "F.Fab")
		)
		(fp_line
			(start -0.12065 -0.305054)
			(end -0.12065 -0.2794)
			(stroke
				(width 0.1)
				(type default)
			)
			(layer "F.Fab")
		)
		(fp_line
			(start -0.12065 -0.2794)
			(end 0.12065 -0.2794)
			(stroke
				(width 0.1)
				(type default)
			)
			(layer "F.Fab")
		)
		(fp_line
			(start -0.12065 0.2794)
			(end -0.12065 0.3048)
			(stroke
				(width 0.1)
				(type default)
			)
			(layer "F.Fab")
		)
		(fp_line
			(start -0.12065 0.3048)
			(end -0.67945 0.3048)
			(stroke
				(width 0.1)
				(type default)
			)
			(layer "F.Fab")
		)
		(fp_line
			(start 0.120396 0.2794)
			(end -0.12065 0.2794)
			(stroke
				(width 0.1)
				(type default)
			)
			(layer "F.Fab")
		)
		(fp_line
			(start 0.120396 0.3048)
			(end 0.120396 0.2794)
			(stroke
				(width 0.1)
				(type default)
			)
			(layer "F.Fab")
		)
		(fp_line
			(start 0.12065 -0.3048)
			(end 0.67945 -0.3048)
			(stroke
				(width 0.1)
				(type default)
			)
			(layer "F.Fab")
		)
		(fp_line
			(start 0.12065 -0.2794)
			(end 0.12065 -0.3048)
			(stroke
				(width 0.1)
				(type default)
			)
			(layer "F.Fab")
		)
		(fp_line
			(start 0.67945 -0.3048)
			(end 0.67945 0.3048)
			(stroke
				(width 0.1)
				(type default)
			)
			(layer "F.Fab")
		)
		(fp_line
			(start 0.67945 0.3048)
			(end 0.120396 0.3048)
			(stroke
				(width 0.1)
				(type default)
			)
			(layer "F.Fab")
		)
		(pad "1" smd circle
			(at -0.40005 0)
			(size 0 0)
			(layers "F.Cu" "F.Mask" "F.Paste")
			(net "P3V3_AUX")
		)
		(pad "2" smd circle
			(at 0.40005 0)
			(size 0 0)
			(layers "F.Cu" "F.Mask" "F.Paste")
			(net "GND")
		)
	)
	(footprint ""
		(layer "F.Cu")
		(at 14.668246 -214.151972)
		(property "Reference" "C4418"
			(at 0 0 0)
			(layer "F.SilkS")
			(hide yes)
			(effects
				(font
					(size 1.27 1.27)
				)
			)
		)
		(property "Value" ""
			(at 0 0 0)
			(layer "F.Fab")
			(effects
				(font
					(size 1.27 1.27)
				)
			)
		)
		(duplicate_pad_numbers_are_jumpers no)
		(fp_line
			(start -0.7874 -0.4064)
			(end 0.7874 -0.4064)
			(stroke
				(width 0.1524)
				(type default)
			)
			(layer "F.SilkS")
		)
		(fp_line
			(start -0.7874 0.4064)
			(end -0.7874 -0.4064)
			(stroke
				(width 0.1524)
				(type default)
			)
			(layer "F.SilkS")
		)
		(fp_line
			(start 0.7874 -0.4064)
			(end 0.7874 0.4064)
			(stroke
				(width 0.1524)
				(type default)
			)
			(layer "F.SilkS")
		)
		(fp_line
			(start 0.7874 0.4064)
			(end -0.7874 0.4064)
			(stroke
				(width 0.1524)
				(type default)
			)
			(layer "F.SilkS")
		)
		(fp_line
			(start -0.67945 -0.305054)
			(end -0.12065 -0.305054)
			(stroke
				(width 0.1)
				(type default)
			)
			(layer "F.Fab")
		)
		(fp_line
			(start -0.67945 0.3048)
			(end -0.67945 -0.305054)
			(stroke
				(width 0.1)
				(type default)
			)
			(layer "F.Fab")
		)
		(fp_line
			(start -0.12065 -0.305054)
			(end -0.12065 -0.2794)
			(stroke
				(width 0.1)
				(type default)
			)
			(layer "F.Fab")
		)
		(fp_line
			(start -0.12065 -0.2794)
			(end 0.12065 -0.2794)
			(stroke
				(width 0.1)
				(type default)
			)
			(layer "F.Fab")
		)
		(fp_line
			(start -0.12065 0.2794)
			(end -0.12065 0.3048)
			(stroke
				(width 0.1)
				(type default)
			)
			(layer "F.Fab")
		)
		(fp_line
			(start -0.12065 0.3048)
			(end -0.67945 0.3048)
			(stroke
				(width 0.1)
				(type default)
			)
			(layer "F.Fab")
		)
		(fp_line
			(start 0.120396 0.2794)
			(end -0.12065 0.2794)
			(stroke
				(width 0.1)
				(type default)
			)
			(layer "F.Fab")
		)
		(fp_line
			(start 0.120396 0.3048)
			(end 0.120396 0.2794)
			(stroke
				(width 0.1)
				(type default)
			)
			(layer "F.Fab")
		)
		(fp_line
			(start 0.12065 -0.3048)
			(end 0.67945 -0.3048)
			(stroke
				(width 0.1)
				(type default)
			)
			(layer "F.Fab")
		)
		(fp_line
			(start 0.12065 -0.2794)
			(end 0.12065 -0.3048)
			(stroke
				(width 0.1)
				(type default)
			)
			(layer "F.Fab")
		)
		(fp_line
			(start 0.67945 -0.3048)
			(end 0.67945 0.3048)
			(stroke
				(width 0.1)
				(type default)
			)
			(layer "F.Fab")
		)
		(fp_line
			(start 0.67945 0.3048)
			(end 0.120396 0.3048)
			(stroke
				(width 0.1)
				(type default)
			)
			(layer "F.Fab")
		)
		(pad "1" smd circle
			(at -0.40005 0)
			(size 0 0)
			(layers "F.Cu" "F.Mask" "F.Paste")
			(net "PEX0_P1V8_PLL_EN")
		)
		(pad "2" smd circle
			(at 0.40005 0)
			(size 0 0)
			(layers "F.Cu" "F.Mask" "F.Paste")
			(net "GND")
		)
	)
	(footprint ""
		(layer "F.Cu")
		(at 278.987504 -395.162532 90)
		(property "Reference" "R1804"
			(at 0 0 90)
			(layer "F.SilkS")
			(hide yes)
			(effects
				(font
					(size 1.27 1.27)
				)
			)
		)
		(property "Value" ""
			(at 0 0 90)
			(layer "F.Fab")
			(effects
				(font
					(size 1.27 1.27)
				)
			)
		)
		(duplicate_pad_numbers_are_jumpers no)
		(fp_line
			(start 0.7874 -0.4064)
			(end 0.7874 0.4064)
			(stroke
				(width 0.1524)
				(type default)
			)
			(layer "F.SilkS")
		)
		(fp_line
			(start -0.7874 -0.4064)
			(end 0.7874 -0.4064)
			(stroke
				(width 0.1524)
				(type default)
			)
			(layer "F.SilkS")
		)
		(fp_line
			(start 0.7874 0.4064)
			(end -0.7874 0.4064)
			(stroke
				(width 0.1524)
				(type default)
			)
			(layer "F.SilkS")
		)
		(fp_line
			(start -0.7874 0.4064)
			(end -0.7874 -0.4064)
			(stroke
				(width 0.1524)
				(type default)
			)
			(layer "F.SilkS")
		)
		(fp_line
			(start -0.12065 -0.305054)
			(end -0.12065 -0.2794)
			(stroke
				(width 0.1)
				(type default)
			)
			(layer "F.Fab")
		)
		(fp_line
			(start -0.67945 -0.305054)
			(end -0.12065 -0.305054)
			(stroke
				(width 0.1)
				(type default)
			)
			(layer "F.Fab")
		)
		(fp_line
			(start 0.67945 -0.3048)
			(end 0.67945 0.3048)
			(stroke
				(width 0.1)
				(type default)
			)
			(layer "F.Fab")
		)
		(fp_line
			(start 0.12065 -0.3048)
			(end 0.67945 -0.3048)
			(stroke
				(width 0.1)
				(type default)
			)
			(layer "F.Fab")
		)
		(fp_line
			(start 0.12065 -0.2794)
			(end 0.12065 -0.3048)
			(stroke
				(width 0.1)
				(type default)
			)
			(layer "F.Fab")
		)
		(fp_line
			(start -0.12065 -0.2794)
			(end 0.12065 -0.2794)
			(stroke
				(width 0.1)
				(type default)
			)
			(layer "F.Fab")
		)
		(fp_line
			(start 0.120396 0.2794)
			(end -0.12065 0.2794)
			(stroke
				(width 0.1)
				(type default)
			)
			(layer "F.Fab")
		)
		(fp_line
			(start -0.12065 0.2794)
			(end -0.12065 0.3048)
			(stroke
				(width 0.1)
				(type default)
			)
			(layer "F.Fab")
		)
		(fp_line
			(start 0.67945 0.3048)
			(end 0.120396 0.3048)
			(stroke
				(width 0.1)
				(type default)
			)
			(layer "F.Fab")
		)
		(fp_line
			(start 0.120396 0.3048)
			(end 0.120396 0.2794)
			(stroke
				(width 0.1)
				(type default)
			)
			(layer "F.Fab")
		)
		(fp_line
			(start -0.12065 0.3048)
			(end -0.67945 0.3048)
			(stroke
				(width 0.1)
				(type default)
			)
			(layer "F.Fab")
		)
		(fp_line
			(start -0.67945 0.3048)
			(end -0.67945 -0.305054)
			(stroke
				(width 0.1)
				(type default)
			)
			(layer "F.Fab")
		)
		(pad "1" smd circle
			(at -0.40005 0 90)
			(size 0 0)
			(layers "F.Cu" "F.Mask" "F.Paste")
			(net "P3V3_AUX")
		)
		(pad "2" smd circle
			(at 0.40005 0 90)
			(size 0 0)
			(layers "F.Cu" "F.Mask" "F.Paste")
			(net "RST_MB_BIC_N")
		)
	)
	(footprint ""
		(layer "F.Cu")
		(at 12.852908 -247.598184 -90)
		(property "Reference" "C4245"
			(at 0 0 270)
			(layer "F.SilkS")
			(hide yes)
			(effects
				(font
					(size 1.27 1.27)
				)
			)
		)
		(property "Value" ""
			(at 0 0 270)
			(layer "F.Fab")
			(effects
				(font
					(size 1.27 1.27)
				)
			)
		)
		(duplicate_pad_numbers_are_jumpers no)
		(fp_line
			(start -1.524 0.762)
			(end -1.524 -0.762)
			(stroke
				(width 0.1524)
				(type default)
			)
			(layer "F.SilkS")
		)
		(fp_line
			(start 1.524 0.762)
			(end -1.524 0.762)
			(stroke
				(width 0.1524)
				(type default)
			)
			(layer "F.SilkS")
		)
		(fp_line
			(start -1.524 -0.762)
			(end 1.524 -0.762)
			(stroke
				(width 0.1524)
				(type default)
			)
			(layer "F.SilkS")
		)
		(fp_line
			(start 1.524 -0.762)
			(end 1.524 0.762)
			(stroke
				(width 0.1524)
				(type default)
			)
			(layer "F.SilkS")
		)
		(fp_line
			(start -1.1049 0.724916)
			(end 1.1049 0.724916)
			(stroke
				(width 0.1)
				(type default)
			)
			(layer "F.Fab")
		)
		(fp_line
			(start 1.1049 0.724916)
			(end 1.1049 -0.724916)
			(stroke
				(width 0.1)
				(type default)
			)
			(layer "F.Fab")
		)
		(fp_line
			(start -1.1049 -0.724916)
			(end -1.1049 0.724916)
			(stroke
				(width 0.1)
				(type default)
			)
			(layer "F.Fab")
		)
		(fp_line
			(start 1.1049 -0.724916)
			(end -1.1049 -0.724916)
			(stroke
				(width 0.1)
				(type default)
			)
			(layer "F.Fab")
		)
		(pad "1" smd rect
			(at -0.889 0 90)
			(size 1.016 1.27)
			(layers "F.Cu" "F.Mask" "F.Paste")
			(net "P1V25_SERDES_VDDPLL_PEX0_C11")
		)
		(pad "2" smd rect
			(at 0.889 0 90)
			(size 1.016 1.27)
			(layers "F.Cu" "F.Mask" "F.Paste")
			(net "GND")
		)
		(zone
			(layer "F.Cu")
			(hatch none 0.5)
			(connect_pads
				(clearance 0)
			)
			(min_thickness 0.25)
			(keepout
				(tracks not_allowed)
				(vias allowed)
				(pads allowed)
				(copperpour not_allowed)
				(footprints allowed)
			)
			(placement
				(enabled no)
				(sheetname "")
			)
			(fill
				(thermal_gap 0.5)
				(thermal_bridge_width 0.5)
				(island_removal_mode 0)
			)
			(polygon
				(pts
					(xy 13.577824 -247.928384) (xy 12.127992 -247.928384) (xy 12.127992 -247.267984) (xy 13.577824 -247.267984)
				)
			)
		)
	)
	(footprint ""
		(layer "F.Cu")
		(at 239.935512 -231.416606 90)
		(property "Reference" "R4515"
			(at 0 0 90)
			(layer "F.SilkS")
			(hide yes)
			(effects
				(font
					(size 1.27 1.27)
				)
			)
		)
		(property "Value" ""
			(at 0 0 90)
			(layer "F.Fab")
			(effects
				(font
					(size 1.27 1.27)
				)
			)
		)
		(duplicate_pad_numbers_are_jumpers no)
		(fp_line
			(start 0.7874 -0.4064)
			(end 0.7874 0.4064)
			(stroke
				(width 0.1524)
				(type default)
			)
			(layer "F.SilkS")
		)
		(fp_line
			(start -0.7874 -0.4064)
			(end 0.7874 -0.4064)
			(stroke
				(width 0.1524)
				(type default)
			)
			(layer "F.SilkS")
		)
		(fp_line
			(start 0.7874 0.4064)
			(end -0.7874 0.4064)
			(stroke
				(width 0.1524)
				(type default)
			)
			(layer "F.SilkS")
		)
		(fp_line
			(start -0.7874 0.4064)
			(end -0.7874 -0.4064)
			(stroke
				(width 0.1524)
				(type default)
			)
			(layer "F.SilkS")
		)
		(fp_line
			(start -0.12065 -0.305054)
			(end -0.12065 -0.2794)
			(stroke
				(width 0.1)
				(type default)
			)
			(layer "F.Fab")
		)
		(fp_line
			(start -0.67945 -0.305054)
			(end -0.12065 -0.305054)
			(stroke
				(width 0.1)
				(type default)
			)
			(layer "F.Fab")
		)
		(fp_line
			(start 0.67945 -0.3048)
			(end 0.67945 0.3048)
			(stroke
				(width 0.1)
				(type default)
			)
			(layer "F.Fab")
		)
		(fp_line
			(start 0.12065 -0.3048)
			(end 0.67945 -0.3048)
			(stroke
				(width 0.1)
				(type default)
			)
			(layer "F.Fab")
		)
		(fp_line
			(start 0.12065 -0.2794)
			(end 0.12065 -0.3048)
			(stroke
				(width 0.1)
				(type default)
			)
			(layer "F.Fab")
		)
		(fp_line
			(start -0.12065 -0.2794)
			(end 0.12065 -0.2794)
			(stroke
				(width 0.1)
				(type default)
			)
			(layer "F.Fab")
		)
		(fp_line
			(start 0.120396 0.2794)
			(end -0.12065 0.2794)
			(stroke
				(width 0.1)
				(type default)
			)
			(layer "F.Fab")
		)
		(fp_line
			(start -0.12065 0.2794)
			(end -0.12065 0.3048)
			(stroke
				(width 0.1)
				(type default)
			)
			(layer "F.Fab")
		)
		(fp_line
			(start 0.67945 0.3048)
			(end 0.120396 0.3048)
			(stroke
				(width 0.1)
				(type default)
			)
			(layer "F.Fab")
		)
		(fp_line
			(start 0.120396 0.3048)
			(end 0.120396 0.2794)
			(stroke
				(width 0.1)
				(type default)
			)
			(layer "F.Fab")
		)
		(fp_line
			(start -0.12065 0.3048)
			(end -0.67945 0.3048)
			(stroke
				(width 0.1)
				(type default)
			)
			(layer "F.Fab")
		)
		(fp_line
			(start -0.67945 0.3048)
			(end -0.67945 -0.305054)
			(stroke
				(width 0.1)
				(type default)
			)
			(layer "F.Fab")
		)
		(pad "1" smd circle
			(at -0.40005 0 90)
			(size 0 0)
			(layers "F.Cu" "F.Mask" "F.Paste")
			(net "SSD1_PWRDIS_BIC")
		)
		(pad "2" smd circle
			(at 0.40005 0 90)
			(size 0 0)
			(layers "F.Cu" "F.Mask" "F.Paste")
			(net "SSD1_PWRDIS_BIC_R")
		)
	)
	(footprint ""
		(layer "F.Cu")
		(at 60.070492 -375.19356 90)
		(property "Reference" "C4033"
			(at 0 0 90)
			(layer "F.SilkS")
			(hide yes)
			(effects
				(font
					(size 1.27 1.27)
				)
			)
		)
		(property "Value" ""
			(at 0 0 90)
			(layer "F.Fab")
			(effects
				(font
					(size 1.27 1.27)
				)
			)
		)
		(duplicate_pad_numbers_are_jumpers no)
		(fp_line
			(start 0.7874 -0.4064)
			(end 0.7874 0.4064)
			(stroke
				(width 0.1524)
				(type default)
			)
			(layer "F.SilkS")
		)
		(fp_line
			(start -0.7874 -0.4064)
			(end 0.7874 -0.4064)
			(stroke
				(width 0.1524)
				(type default)
			)
			(layer "F.SilkS")
		)
		(fp_line
			(start 0.7874 0.4064)
			(end -0.7874 0.4064)
			(stroke
				(width 0.1524)
				(type default)
			)
			(layer "F.SilkS")
		)
		(fp_line
			(start -0.7874 0.4064)
			(end -0.7874 -0.4064)
			(stroke
				(width 0.1524)
				(type default)
			)
			(layer "F.SilkS")
		)
		(fp_line
			(start -0.12065 -0.305054)
			(end -0.12065 -0.2794)
			(stroke
				(width 0.1)
				(type default)
			)
			(layer "F.Fab")
		)
		(fp_line
			(start -0.67945 -0.305054)
			(end -0.12065 -0.305054)
			(stroke
				(width 0.1)
				(type default)
			)
			(layer "F.Fab")
		)
		(fp_line
			(start 0.67945 -0.3048)
			(end 0.67945 0.3048)
			(stroke
				(width 0.1)
				(type default)
			)
			(layer "F.Fab")
		)
		(fp_line
			(start 0.12065 -0.3048)
			(end 0.67945 -0.3048)
			(stroke
				(width 0.1)
				(type default)
			)
			(layer "F.Fab")
		)
		(fp_line
			(start 0.12065 -0.2794)
			(end 0.12065 -0.3048)
			(stroke
				(width 0.1)
				(type default)
			)
			(layer "F.Fab")
		)
		(fp_line
			(start -0.12065 -0.2794)
			(end 0.12065 -0.2794)
			(stroke
				(width 0.1)
				(type default)
			)
			(layer "F.Fab")
		)
		(fp_line
			(start 0.120396 0.2794)
			(end -0.12065 0.2794)
			(stroke
				(width 0.1)
				(type default)
			)
			(layer "F.Fab")
		)
		(fp_line
			(start -0.12065 0.2794)
			(end -0.12065 0.3048)
			(stroke
				(width 0.1)
				(type default)
			)
			(layer "F.Fab")
		)
		(fp_line
			(start 0.67945 0.3048)
			(end 0.120396 0.3048)
			(stroke
				(width 0.1)
				(type default)
			)
			(layer "F.Fab")
		)
		(fp_line
			(start 0.120396 0.3048)
			(end 0.120396 0.2794)
			(stroke
				(width 0.1)
				(type default)
			)
			(layer "F.Fab")
		)
		(fp_line
			(start -0.12065 0.3048)
			(end -0.67945 0.3048)
			(stroke
				(width 0.1)
				(type default)
			)
			(layer "F.Fab")
		)
		(fp_line
			(start -0.67945 0.3048)
			(end -0.67945 -0.305054)
			(stroke
				(width 0.1)
				(type default)
			)
			(layer "F.Fab")
		)
		(pad "1" smd circle
			(at -0.40005 0 90)
			(size 0 0)
			(layers "F.Cu" "F.Mask" "F.Paste")
			(net "GND")
		)
		(pad "2" smd circle
			(at 0.40005 0 90)
			(size 0 0)
			(layers "F.Cu" "F.Mask" "F.Paste")
			(net "GPU_BASE_PWR_EN")
		)
	)
	(footprint ""
		(layer "F.Cu")
		(at 400.543776 -46.90491)
		(property "Reference" "R653"
			(at 0 0 0)
			(layer "F.SilkS")
			(hide yes)
			(effects
				(font
					(size 1.27 1.27)
				)
			)
		)
		(property "Value" ""
			(at 0 0 0)
			(layer "F.Fab")
			(effects
				(font
					(size 1.27 1.27)
				)
			)
		)
		(duplicate_pad_numbers_are_jumpers no)
		(fp_line
			(start -0.7874 -0.4064)
			(end 0.7874 -0.4064)
			(stroke
				(width 0.1524)
				(type default)
			)
			(layer "F.SilkS")
		)
		(fp_line
			(start -0.7874 0.4064)
			(end -0.7874 -0.4064)
			(stroke
				(width 0.1524)
				(type default)
			)
			(layer "F.SilkS")
		)
		(fp_line
			(start 0.7874 -0.4064)
			(end 0.7874 0.4064)
			(stroke
				(width 0.1524)
				(type default)
			)
			(layer "F.SilkS")
		)
		(fp_line
			(start 0.7874 0.4064)
			(end -0.7874 0.4064)
			(stroke
				(width 0.1524)
				(type default)
			)
			(layer "F.SilkS")
		)
		(fp_line
			(start -0.67945 -0.305054)
			(end -0.12065 -0.305054)
			(stroke
				(width 0.1)
				(type default)
			)
			(layer "F.Fab")
		)
		(fp_line
			(start -0.67945 0.3048)
			(end -0.67945 -0.305054)
			(stroke
				(width 0.1)
				(type default)
			)
			(layer "F.Fab")
		)
		(fp_line
			(start -0.12065 -0.305054)
			(end -0.12065 -0.2794)
			(stroke
				(width 0.1)
				(type default)
			)
			(layer "F.Fab")
		)
		(fp_line
			(start -0.12065 -0.2794)
			(end 0.12065 -0.2794)
			(stroke
				(width 0.1)
				(type default)
			)
			(layer "F.Fab")
		)
		(fp_line
			(start -0.12065 0.2794)
			(end -0.12065 0.3048)
			(stroke
				(width 0.1)
				(type default)
			)
			(layer "F.Fab")
		)
		(fp_line
			(start -0.12065 0.3048)
			(end -0.67945 0.3048)
			(stroke
				(width 0.1)
				(type default)
			)
			(layer "F.Fab")
		)
		(fp_line
			(start 0.120396 0.2794)
			(end -0.12065 0.2794)
			(stroke
				(width 0.1)
				(type default)
			)
			(layer "F.Fab")
		)
		(fp_line
			(start 0.120396 0.3048)
			(end 0.120396 0.2794)
			(stroke
				(width 0.1)
				(type default)
			)
			(layer "F.Fab")
		)
		(fp_line
			(start 0.12065 -0.3048)
			(end 0.67945 -0.3048)
			(stroke
				(width 0.1)
				(type default)
			)
			(layer "F.Fab")
		)
		(fp_line
			(start 0.12065 -0.2794)
			(end 0.12065 -0.3048)
			(stroke
				(width 0.1)
				(type default)
			)
			(layer "F.Fab")
		)
		(fp_line
			(start 0.67945 -0.3048)
			(end 0.67945 0.3048)
			(stroke
				(width 0.1)
				(type default)
			)
			(layer "F.Fab")
		)
		(fp_line
			(start 0.67945 0.3048)
			(end 0.120396 0.3048)
			(stroke
				(width 0.1)
				(type default)
			)
			(layer "F.Fab")
		)
		(pad "1" smd circle
			(at -0.40005 0)
			(size 0 0)
			(layers "F.Cu" "F.Mask" "F.Paste")
			(net "SSD13_ADC_ALERT_N")
		)
		(pad "2" smd circle
			(at 0.40005 0)
			(size 0 0)
			(layers "F.Cu" "F.Mask" "F.Paste")
			(net "SSD_8_15_ADC_ALERT_N")
		)
	)
	(footprint ""
		(layer "F.Cu")
		(at 237.903512 -234.728004 -90)
		(property "Reference" "R6187"
			(at 0 0 270)
			(layer "F.SilkS")
			(hide yes)
			(effects
				(font
					(size 1.27 1.27)
				)
			)
		)
		(property "Value" ""
			(at 0 0 270)
			(layer "F.Fab")
			(effects
				(font
					(size 1.27 1.27)
				)
			)
		)
		(duplicate_pad_numbers_are_jumpers no)
		(fp_line
			(start -0.7874 0.4064)
			(end -0.7874 -0.4064)
			(stroke
				(width 0.1524)
				(type default)
			)
			(layer "F.SilkS")
		)
		(fp_line
			(start 0.7874 0.4064)
			(end -0.7874 0.4064)
			(stroke
				(width 0.1524)
				(type default)
			)
			(layer "F.SilkS")
		)
		(fp_line
			(start -0.7874 -0.4064)
			(end 0.7874 -0.4064)
			(stroke
				(width 0.1524)
				(type default)
			)
			(layer "F.SilkS")
		)
		(fp_line
			(start 0.7874 -0.4064)
			(end 0.7874 0.4064)
			(stroke
				(width 0.1524)
				(type default)
			)
			(layer "F.SilkS")
		)
		(fp_line
			(start -0.67945 0.3048)
			(end -0.67945 -0.305054)
			(stroke
				(width 0.1)
				(type default)
			)
			(layer "F.Fab")
		)
		(fp_line
			(start -0.12065 0.3048)
			(end -0.67945 0.3048)
			(stroke
				(width 0.1)
				(type default)
			)
			(layer "F.Fab")
		)
		(fp_line
			(start 0.120396 0.3048)
			(end 0.120396 0.2794)
			(stroke
				(width 0.1)
				(type default)
			)
			(layer "F.Fab")
		)
		(fp_line
			(start 0.67945 0.3048)
			(end 0.120396 0.3048)
			(stroke
				(width 0.1)
				(type default)
			)
			(layer "F.Fab")
		)
		(fp_line
			(start -0.12065 0.2794)
			(end -0.12065 0.3048)
			(stroke
				(width 0.1)
				(type default)
			)
			(layer "F.Fab")
		)
		(fp_line
			(start 0.120396 0.2794)
			(end -0.12065 0.2794)
			(stroke
				(width 0.1)
				(type default)
			)
			(layer "F.Fab")
		)
		(fp_line
			(start -0.12065 -0.2794)
			(end 0.12065 -0.2794)
			(stroke
				(width 0.1)
				(type default)
			)
			(layer "F.Fab")
		)
		(fp_line
			(start 0.12065 -0.2794)
			(end 0.12065 -0.3048)
			(stroke
				(width 0.1)
				(type default)
			)
			(layer "F.Fab")
		)
		(fp_line
			(start 0.12065 -0.3048)
			(end 0.67945 -0.3048)
			(stroke
				(width 0.1)
				(type default)
			)
			(layer "F.Fab")
		)
		(fp_line
			(start 0.67945 -0.3048)
			(end 0.67945 0.3048)
			(stroke
				(width 0.1)
				(type default)
			)
			(layer "F.Fab")
		)
		(fp_line
			(start -0.67945 -0.305054)
			(end -0.12065 -0.305054)
			(stroke
				(width 0.1)
				(type default)
			)
			(layer "F.Fab")
		)
		(fp_line
			(start -0.12065 -0.305054)
			(end -0.12065 -0.2794)
			(stroke
				(width 0.1)
				(type default)
			)
			(layer "F.Fab")
		)
		(pad "1" smd circle
			(at -0.40005 0 270)
			(size 0 0)
			(layers "F.Cu" "F.Mask" "F.Paste")
			(net "GND")
		)
		(pad "2" smd circle
			(at 0.40005 0 270)
			(size 0 0)
			(layers "F.Cu" "F.Mask" "F.Paste")
			(net "SSD5_PWRDIS_BIC_R")
		)
	)
	(footprint ""
		(layer "F.Cu")
		(at 381.254 -207.518)
		(property "Reference" "R4632"
			(at 0 0 0)
			(layer "F.SilkS")
			(hide yes)
			(effects
				(font
					(size 1.27 1.27)
				)
			)
		)
		(property "Value" ""
			(at 0 0 0)
			(layer "F.Fab")
			(effects
				(font
					(size 1.27 1.27)
				)
			)
		)
		(duplicate_pad_numbers_are_jumpers no)
		(fp_line
			(start -0.7874 -0.4064)
			(end 0.7874 -0.4064)
			(stroke
				(width 0.1524)
				(type default)
			)
			(layer "F.SilkS")
		)
		(fp_line
			(start -0.7874 0.4064)
			(end -0.7874 -0.4064)
			(stroke
				(width 0.1524)
				(type default)
			)
			(layer "F.SilkS")
		)
		(fp_line
			(start 0.7874 -0.4064)
			(end 0.7874 0.4064)
			(stroke
				(width 0.1524)
				(type default)
			)
			(layer "F.SilkS")
		)
		(fp_line
			(start 0.7874 0.4064)
			(end -0.7874 0.4064)
			(stroke
				(width 0.1524)
				(type default)
			)
			(layer "F.SilkS")
		)
		(fp_line
			(start -0.67945 -0.305054)
			(end -0.12065 -0.305054)
			(stroke
				(width 0.1)
				(type default)
			)
			(layer "F.Fab")
		)
		(fp_line
			(start -0.67945 0.3048)
			(end -0.67945 -0.305054)
			(stroke
				(width 0.1)
				(type default)
			)
			(layer "F.Fab")
		)
		(fp_line
			(start -0.12065 -0.305054)
			(end -0.12065 -0.2794)
			(stroke
				(width 0.1)
				(type default)
			)
			(layer "F.Fab")
		)
		(fp_line
			(start -0.12065 -0.2794)
			(end 0.12065 -0.2794)
			(stroke
				(width 0.1)
				(type default)
			)
			(layer "F.Fab")
		)
		(fp_line
			(start -0.12065 0.2794)
			(end -0.12065 0.3048)
			(stroke
				(width 0.1)
				(type default)
			)
			(layer "F.Fab")
		)
		(fp_line
			(start -0.12065 0.3048)
			(end -0.67945 0.3048)
			(stroke
				(width 0.1)
				(type default)
			)
			(layer "F.Fab")
		)
		(fp_line
			(start 0.120396 0.2794)
			(end -0.12065 0.2794)
			(stroke
				(width 0.1)
				(type default)
			)
			(layer "F.Fab")
		)
		(fp_line
			(start 0.120396 0.3048)
			(end 0.120396 0.2794)
			(stroke
				(width 0.1)
				(type default)
			)
			(layer "F.Fab")
		)
		(fp_line
			(start 0.12065 -0.3048)
			(end 0.67945 -0.3048)
			(stroke
				(width 0.1)
				(type default)
			)
			(layer "F.Fab")
		)
		(fp_line
			(start 0.12065 -0.2794)
			(end 0.12065 -0.3048)
			(stroke
				(width 0.1)
				(type default)
			)
			(layer "F.Fab")
		)
		(fp_line
			(start 0.67945 -0.3048)
			(end 0.67945 0.3048)
			(stroke
				(width 0.1)
				(type default)
			)
			(layer "F.Fab")
		)
		(fp_line
			(start 0.67945 0.3048)
			(end 0.120396 0.3048)
			(stroke
				(width 0.1)
				(type default)
			)
			(layer "F.Fab")
		)
		(pad "1" smd circle
			(at -0.40005 0)
			(size 0 0)
			(layers "F.Cu" "F.Mask" "F.Paste")
			(net "NIC0_PEX_PWR_EN")
		)
		(pad "2" smd circle
			(at 0.40005 0)
			(size 0 0)
			(layers "F.Cu" "F.Mask" "F.Paste")
			(net "NIC0_PEX_PWR_EN_R")
		)
	)
	(footprint ""
		(layer "F.Cu")
		(at 149.387814 -282.018232)
		(property "Reference" "C3241"
			(at 0 0 0)
			(layer "F.SilkS")
			(hide yes)
			(effects
				(font
					(size 1.27 1.27)
				)
			)
		)
		(property "Value" ""
			(at 0 0 0)
			(layer "F.Fab")
			(effects
				(font
					(size 1.27 1.27)
				)
			)
		)
		(duplicate_pad_numbers_are_jumpers no)
		(fp_line
			(start -1.2954 -0.5842)
			(end 1.2954 -0.5842)
			(stroke
				(width 0.1524)
				(type default)
			)
			(layer "F.SilkS")
		)
		(fp_line
			(start -1.2954 0.5842)
			(end -1.2954 -0.5842)
			(stroke
				(width 0.1524)
				(type default)
			)
			(layer "F.SilkS")
		)
		(fp_line
			(start 1.2954 -0.5842)
			(end 1.2954 0.5842)
			(stroke
				(width 0.1524)
				(type default)
			)
			(layer "F.SilkS")
		)
		(fp_line
			(start 1.2954 0.5842)
			(end -1.2954 0.5842)
			(stroke
				(width 0.1524)
				(type default)
			)
			(layer "F.SilkS")
		)
		(fp_line
			(start -1.1938 -0.4064)
			(end -0.8636 -0.4064)
			(stroke
				(width 0.1)
				(type default)
			)
			(layer "F.Fab")
		)
		(fp_line
			(start -1.1938 0.4064)
			(end -1.1938 -0.4064)
			(stroke
				(width 0.1)
				(type default)
			)
			(layer "F.Fab")
		)
		(fp_line
			(start -0.8636 -0.4572)
			(end 0.8636 -0.4572)
			(stroke
				(width 0.1)
				(type default)
			)
			(layer "F.Fab")
		)
		(fp_line
			(start -0.8636 -0.4064)
			(end -0.8636 -0.4572)
			(stroke
				(width 0.1)
				(type default)
			)
			(layer "F.Fab")
		)
		(fp_line
			(start -0.8636 0.4064)
			(end -1.1938 0.4064)
			(stroke
				(width 0.1)
				(type default)
			)
			(layer "F.Fab")
		)
		(fp_line
			(start -0.8636 0.4572)
			(end -0.8636 0.4064)
			(stroke
				(width 0.1)
				(type default)
			)
			(layer "F.Fab")
		)
		(fp_line
			(start 0.8636 -0.4572)
			(end 0.8636 -0.4064)
			(stroke
				(width 0.1)
				(type default)
			)
			(layer "F.Fab")
		)
		(fp_line
			(start 0.8636 -0.4064)
			(end 1.1938 -0.4064)
			(stroke
				(width 0.1)
				(type default)
			)
			(layer "F.Fab")
		)
		(fp_line
			(start 0.8636 0.4064)
			(end 0.8636 0.4572)
			(stroke
				(width 0.1)
				(type default)
			)
			(layer "F.Fab")
		)
		(fp_line
			(start 0.8636 0.4572)
			(end -0.8636 0.4572)
			(stroke
				(width 0.1)
				(type default)
			)
			(layer "F.Fab")
		)
		(fp_line
			(start 1.1938 -0.4064)
			(end 1.1938 0.4064)
			(stroke
				(width 0.1)
				(type default)
			)
			(layer "F.Fab")
		)
		(fp_line
			(start 1.1938 0.4064)
			(end 0.8636 0.4064)
			(stroke
				(width 0.1)
				(type default)
			)
			(layer "F.Fab")
		)
		(pad "1" smd rect
			(at -0.7366 0 270)
			(size 0.7112 0.8128)
			(layers "F.Cu" "F.Mask" "F.Paste")
			(net "SYSPLL_VDDA18_PEX1")
		)
		(pad "2" smd rect
			(at 0.7366 0 270)
			(size 0.7112 0.8128)
			(layers "F.Cu" "F.Mask" "F.Paste")
			(net "GND")
		)
	)
	(footprint ""
		(layer "F.Cu")
		(at 471.118184 -551.319192 180)
		(property "Reference" "SCREW_SSD8_1"
			(at -5.207 -1.402334 0)
			(unlocked yes)
			(layer "B.SilkS")
			(effects
				(font
					(size 0.7874 0.5842)
					(thickness 0.1524)
				)
				(justify mirror)
			)
		)
		(property "Value" ""
			(at 0 0 180)
			(layer "F.Fab")
			(effects
				(font
					(size 1.27 1.27)
				)
			)
		)
		(duplicate_pad_numbers_are_jumpers no)
		(pad "1" thru_hole circle
			(at 0 0 180)
			(size 0.4572 0.4572)
			(drill 0.2032)
			(layers "*.Cu" "*.Mask")
			(remove_unused_layers no)
			(net "Net_9128")
			(clearance 0.127)
			(thermal_gap 0.127)
			(padstack
				(mode front_inner_back)
				(layer "Inner"
					(shape circle)
					(size 0.4572 0.4572)
					(clearance 0.127)
				)
				(layer "B.Cu"
					(shape circle)
					(size 0.508 0.508)
					(clearance 0.1016)
				)
			)
		)
	)
	(footprint ""
		(layer "F.Cu")
		(at 2.989072 -387.038342 -90)
		(property "Reference" "R6747"
			(at 0 0 270)
			(layer "F.SilkS")
			(hide yes)
			(effects
				(font
					(size 1.27 1.27)
				)
			)
		)
		(property "Value" ""
			(at 0 0 270)
			(layer "F.Fab")
			(effects
				(font
					(size 1.27 1.27)
				)
			)
		)
		(duplicate_pad_numbers_are_jumpers no)
		(fp_line
			(start 0.7874 0.4064)
			(end -0.459486 0.4064)
			(stroke
				(width 0.1524)
				(type default)
			)
			(layer "F.SilkS")
		)
		(fp_line
			(start -0.43815 -0.4064)
			(end 0.7874 -0.4064)
			(stroke
				(width 0.1524)
				(type default)
			)
			(layer "F.SilkS")
		)
		(fp_line
			(start 0.7874 -0.4064)
			(end 0.7874 0.4064)
			(stroke
				(width 0.1524)
				(type default)
			)
			(layer "F.SilkS")
		)
		(fp_line
			(start -0.67945 0.3048)
			(end -0.67945 -0.305054)
			(stroke
				(width 0.1)
				(type default)
			)
			(layer "F.Fab")
		)
		(fp_line
			(start -0.12065 0.3048)
			(end -0.67945 0.3048)
			(stroke
				(width 0.1)
				(type default)
			)
			(layer "F.Fab")
		)
		(fp_line
			(start 0.120396 0.3048)
			(end 0.120396 0.2794)
			(stroke
				(width 0.1)
				(type default)
			)
			(layer "F.Fab")
		)
		(fp_line
			(start 0.67945 0.3048)
			(end 0.120396 0.3048)
			(stroke
				(width 0.1)
				(type default)
			)
			(layer "F.Fab")
		)
		(fp_line
			(start -0.12065 0.2794)
			(end -0.12065 0.3048)
			(stroke
				(width 0.1)
				(type default)
			)
			(layer "F.Fab")
		)
		(fp_line
			(start 0.120396 0.2794)
			(end -0.12065 0.2794)
			(stroke
				(width 0.1)
				(type default)
			)
			(layer "F.Fab")
		)
		(fp_line
			(start -0.12065 -0.2794)
			(end 0.12065 -0.2794)
			(stroke
				(width 0.1)
				(type default)
			)
			(layer "F.Fab")
		)
		(fp_line
			(start 0.12065 -0.2794)
			(end 0.12065 -0.3048)
			(stroke
				(width 0.1)
				(type default)
			)
			(layer "F.Fab")
		)
		(fp_line
			(start 0.12065 -0.3048)
			(end 0.67945 -0.3048)
			(stroke
				(width 0.1)
				(type default)
			)
			(layer "F.Fab")
		)
		(fp_line
			(start 0.67945 -0.3048)
			(end 0.67945 0.3048)
			(stroke
				(width 0.1)
				(type default)
			)
			(layer "F.Fab")
		)
		(fp_line
			(start -0.67945 -0.305054)
			(end -0.12065 -0.305054)
			(stroke
				(width 0.1)
				(type default)
			)
			(layer "F.Fab")
		)
		(fp_line
			(start -0.12065 -0.305054)
			(end -0.12065 -0.2794)
			(stroke
				(width 0.1)
				(type default)
			)
			(layer "F.Fab")
		)
		(pad "1" smd circle
			(at -0.40005 0 270)
			(size 0 0)
			(layers "F.Cu" "F.Mask" "F.Paste")
			(net "USB2_MB_BMC_USB8042_DN")
		)
		(pad "2" smd circle
			(at 0.40005 0 270)
			(size 0 0)
			(layers "F.Cu" "F.Mask" "F.Paste")
			(net "GND")
		)
	)
	(footprint ""
		(layer "F.Cu")
		(at 221.674944 -98.36912 -90)
		(property "Reference" "PC350"
			(at 0 0 270)
			(layer "F.SilkS")
			(hide yes)
			(effects
				(font
					(size 1.27 1.27)
				)
			)
		)
		(property "Value" ""
			(at 0 0 270)
			(layer "F.Fab")
			(effects
				(font
					(size 1.27 1.27)
				)
			)
		)
		(duplicate_pad_numbers_are_jumpers no)
		(fp_line
			(start -0.7874 0.4064)
			(end -0.7874 -0.4064)
			(stroke
				(width 0.1524)
				(type default)
			)
			(layer "F.SilkS")
		)
		(fp_line
			(start 0.7874 0.4064)
			(end -0.7874 0.4064)
			(stroke
				(width 0.1524)
				(type default)
			)
			(layer "F.SilkS")
		)
		(fp_line
			(start -0.7874 -0.4064)
			(end 0.7874 -0.4064)
			(stroke
				(width 0.1524)
				(type default)
			)
			(layer "F.SilkS")
		)
		(fp_line
			(start 0.7874 -0.4064)
			(end 0.7874 0.4064)
			(stroke
				(width 0.1524)
				(type default)
			)
			(layer "F.SilkS")
		)
		(fp_line
			(start -0.6858 0.3048)
			(end -0.6858 -0.3048)
			(stroke
				(width 0.1)
				(type default)
			)
			(layer "F.Fab")
		)
		(fp_line
			(start -0.1016 0.3048)
			(end -0.6858 0.3048)
			(stroke
				(width 0.1)
				(type default)
			)
			(layer "F.Fab")
		)
		(fp_line
			(start 0.1016 0.3048)
			(end 0.1016 0.2794)
			(stroke
				(width 0.1)
				(type default)
			)
			(layer "F.Fab")
		)
		(fp_line
			(start 0.6858 0.3048)
			(end 0.1016 0.3048)
			(stroke
				(width 0.1)
				(type default)
			)
			(layer "F.Fab")
		)
		(fp_line
			(start -0.1016 0.2794)
			(end -0.1016 0.3048)
			(stroke
				(width 0.1)
				(type default)
			)
			(layer "F.Fab")
		)
		(fp_line
			(start 0.1016 0.2794)
			(end -0.1016 0.2794)
			(stroke
				(width 0.1)
				(type default)
			)
			(layer "F.Fab")
		)
		(fp_line
			(start -0.1016 -0.2794)
			(end 0.1016 -0.2794)
			(stroke
				(width 0.1)
				(type default)
			)
			(layer "F.Fab")
		)
		(fp_line
			(start 0.1016 -0.2794)
			(end 0.1016 -0.3048)
			(stroke
				(width 0.1)
				(type default)
			)
			(layer "F.Fab")
		)
		(fp_line
			(start -0.6858 -0.3048)
			(end -0.1016 -0.3048)
			(stroke
				(width 0.1)
				(type default)
			)
			(layer "F.Fab")
		)
		(fp_line
			(start -0.1016 -0.3048)
			(end -0.1016 -0.2794)
			(stroke
				(width 0.1)
				(type default)
			)
			(layer "F.Fab")
		)
		(fp_line
			(start 0.1016 -0.3048)
			(end 0.6858 -0.3048)
			(stroke
				(width 0.1)
				(type default)
			)
			(layer "F.Fab")
		)
		(fp_line
			(start 0.6858 -0.3048)
			(end 0.6858 0.3048)
			(stroke
				(width 0.1)
				(type default)
			)
			(layer "F.Fab")
		)
		(pad "1" smd rect
			(at -0.40005 0 90)
			(size 0.4572 0.508)
			(layers "F.Cu" "F.Mask" "F.Paste")
			(net "P12V_NIC3_SS")
		)
		(pad "2" smd rect
			(at 0.40005 0 90)
			(size 0.4572 0.508)
			(layers "F.Cu" "F.Mask" "F.Paste")
			(net "GND")
		)
	)
	(footprint ""
		(layer "F.Cu")
		(at 428.319438 -150.70455 180)
		(property "Reference" "C640"
			(at 0 0 180)
			(layer "F.SilkS")
			(hide yes)
			(effects
				(font
					(size 1.27 1.27)
				)
			)
		)
		(property "Value" ""
			(at 0 0 180)
			(layer "F.Fab")
			(effects
				(font
					(size 1.27 1.27)
				)
			)
		)
		(duplicate_pad_numbers_are_jumpers no)
		(fp_line
			(start 0.299974 0.150114)
			(end -0.299974 0.150114)
			(stroke
				(width 0.1)
				(type default)
			)
			(layer "F.Fab")
		)
		(fp_line
			(start 0.299974 -0.150114)
			(end 0.299974 0.150114)
			(stroke
				(width 0.1)
				(type default)
			)
			(layer "F.Fab")
		)
		(fp_line
			(start -0.299974 0.150114)
			(end -0.299974 -0.150114)
			(stroke
				(width 0.1)
				(type default)
			)
			(layer "F.Fab")
		)
		(fp_line
			(start -0.299974 -0.150114)
			(end 0.299974 -0.150114)
			(stroke
				(width 0.1)
				(type default)
			)
			(layer "F.Fab")
		)
		(pad "1" smd rect
			(at -0.2667 0 180)
			(size 0.3048 0.381)
			(layers "F.Cu" "F.Mask" "F.Paste")
			(net "P5E_PEX3_STN0_TX_DN<12>")
		)
		(pad "2" smd rect
			(at 0.2667 0 180)
			(size 0.3048 0.381)
			(layers "F.Cu" "F.Mask" "F.Paste")
			(net "P5E_PEX3_STN0_TX_C_DN<12>")
		)
	)
	(footprint ""
		(layer "F.Cu")
		(at 150.394162 -239.726978 90)
		(property "Reference" "R6573"
			(at 0 0 90)
			(layer "F.SilkS")
			(hide yes)
			(effects
				(font
					(size 1.27 1.27)
				)
			)
		)
		(property "Value" ""
			(at 0 0 90)
			(layer "F.Fab")
			(effects
				(font
					(size 1.27 1.27)
				)
			)
		)
		(duplicate_pad_numbers_are_jumpers no)
		(fp_line
			(start 0.7874 -0.4064)
			(end 0.7874 0.4064)
			(stroke
				(width 0.1524)
				(type default)
			)
			(layer "F.SilkS")
		)
		(fp_line
			(start -0.7874 -0.4064)
			(end 0.7874 -0.4064)
			(stroke
				(width 0.1524)
				(type default)
			)
			(layer "F.SilkS")
		)
		(fp_line
			(start 0.7874 0.4064)
			(end -0.7874 0.4064)
			(stroke
				(width 0.1524)
				(type default)
			)
			(layer "F.SilkS")
		)
		(fp_line
			(start -0.7874 0.4064)
			(end -0.7874 -0.4064)
			(stroke
				(width 0.1524)
				(type default)
			)
			(layer "F.SilkS")
		)
		(fp_line
			(start -0.12065 -0.305054)
			(end -0.12065 -0.2794)
			(stroke
				(width 0.1)
				(type default)
			)
			(layer "F.Fab")
		)
		(fp_line
			(start -0.67945 -0.305054)
			(end -0.12065 -0.305054)
			(stroke
				(width 0.1)
				(type default)
			)
			(layer "F.Fab")
		)
		(fp_line
			(start 0.67945 -0.3048)
			(end 0.67945 0.3048)
			(stroke
				(width 0.1)
				(type default)
			)
			(layer "F.Fab")
		)
		(fp_line
			(start 0.12065 -0.3048)
			(end 0.67945 -0.3048)
			(stroke
				(width 0.1)
				(type default)
			)
			(layer "F.Fab")
		)
		(fp_line
			(start 0.12065 -0.2794)
			(end 0.12065 -0.3048)
			(stroke
				(width 0.1)
				(type default)
			)
			(layer "F.Fab")
		)
		(fp_line
			(start -0.12065 -0.2794)
			(end 0.12065 -0.2794)
			(stroke
				(width 0.1)
				(type default)
			)
			(layer "F.Fab")
		)
		(fp_line
			(start 0.120396 0.2794)
			(end -0.12065 0.2794)
			(stroke
				(width 0.1)
				(type default)
			)
			(layer "F.Fab")
		)
		(fp_line
			(start -0.12065 0.2794)
			(end -0.12065 0.3048)
			(stroke
				(width 0.1)
				(type default)
			)
			(layer "F.Fab")
		)
		(fp_line
			(start 0.67945 0.3048)
			(end 0.120396 0.3048)
			(stroke
				(width 0.1)
				(type default)
			)
			(layer "F.Fab")
		)
		(fp_line
			(start 0.120396 0.3048)
			(end 0.120396 0.2794)
			(stroke
				(width 0.1)
				(type default)
			)
			(layer "F.Fab")
		)
		(fp_line
			(start -0.12065 0.3048)
			(end -0.67945 0.3048)
			(stroke
				(width 0.1)
				(type default)
			)
			(layer "F.Fab")
		)
		(fp_line
			(start -0.67945 0.3048)
			(end -0.67945 -0.305054)
			(stroke
				(width 0.1)
				(type default)
			)
			(layer "F.Fab")
		)
		(pad "1" smd circle
			(at -0.40005 0 90)
			(size 0 0)
			(layers "F.Cu" "F.Mask" "F.Paste")
			(net "P1V8_PLL0_PEX1")
		)
		(pad "2" smd circle
			(at 0.40005 0 90)
			(size 0 0)
			(layers "F.Cu" "F.Mask" "F.Paste")
			(net "P1V8_PLL_PEX1_ADJ")
		)
	)
	(footprint ""
		(layer "F.Cu")
		(at 92.828872 -239.64392 180)
		(property "Reference" "R775"
			(at 0 0 180)
			(layer "F.SilkS")
			(hide yes)
			(effects
				(font
					(size 1.27 1.27)
				)
			)
		)
		(property "Value" ""
			(at 0 0 180)
			(layer "F.Fab")
			(effects
				(font
					(size 1.27 1.27)
				)
			)
		)
		(duplicate_pad_numbers_are_jumpers no)
		(fp_line
			(start 0.7874 0.4064)
			(end -0.7874 0.4064)
			(stroke
				(width 0.1524)
				(type default)
			)
			(layer "F.SilkS")
		)
		(fp_line
			(start 0.7874 -0.4064)
			(end 0.7874 0.4064)
			(stroke
				(width 0.1524)
				(type default)
			)
			(layer "F.SilkS")
		)
		(fp_line
			(start -0.7874 0.4064)
			(end -0.7874 -0.4064)
			(stroke
				(width 0.1524)
				(type default)
			)
			(layer "F.SilkS")
		)
		(fp_line
			(start -0.7874 -0.4064)
			(end 0.7874 -0.4064)
			(stroke
				(width 0.1524)
				(type default)
			)
			(layer "F.SilkS")
		)
		(fp_line
			(start 0.67945 0.3048)
			(end 0.120396 0.3048)
			(stroke
				(width 0.1)
				(type default)
			)
			(layer "F.Fab")
		)
		(fp_line
			(start 0.67945 -0.3048)
			(end 0.67945 0.3048)
			(stroke
				(width 0.1)
				(type default)
			)
			(layer "F.Fab")
		)
		(fp_line
			(start 0.12065 -0.2794)
			(end 0.12065 -0.3048)
			(stroke
				(width 0.1)
				(type default)
			)
			(layer "F.Fab")
		)
		(fp_line
			(start 0.12065 -0.3048)
			(end 0.67945 -0.3048)
			(stroke
				(width 0.1)
				(type default)
			)
			(layer "F.Fab")
		)
		(fp_line
			(start 0.120396 0.3048)
			(end 0.120396 0.2794)
			(stroke
				(width 0.1)
				(type default)
			)
			(layer "F.Fab")
		)
		(fp_line
			(start 0.120396 0.2794)
			(end -0.12065 0.2794)
			(stroke
				(width 0.1)
				(type default)
			)
			(layer "F.Fab")
		)
		(fp_line
			(start -0.12065 0.3048)
			(end -0.67945 0.3048)
			(stroke
				(width 0.1)
				(type default)
			)
			(layer "F.Fab")
		)
		(fp_line
			(start -0.12065 0.2794)
			(end -0.12065 0.3048)
			(stroke
				(width 0.1)
				(type default)
			)
			(layer "F.Fab")
		)
		(fp_line
			(start -0.12065 -0.2794)
			(end 0.12065 -0.2794)
			(stroke
				(width 0.1)
				(type default)
			)
			(layer "F.Fab")
		)
		(fp_line
			(start -0.12065 -0.305054)
			(end -0.12065 -0.2794)
			(stroke
				(width 0.1)
				(type default)
			)
			(layer "F.Fab")
		)
		(fp_line
			(start -0.67945 0.3048)
			(end -0.67945 -0.305054)
			(stroke
				(width 0.1)
				(type default)
			)
			(layer "F.Fab")
		)
		(fp_line
			(start -0.67945 -0.305054)
			(end -0.12065 -0.305054)
			(stroke
				(width 0.1)
				(type default)
			)
			(layer "F.Fab")
		)
		(pad "1" smd circle
			(at -0.40005 0 180)
			(size 0 0)
			(layers "F.Cu" "F.Mask" "F.Paste")
			(net "SMB_BIC_I2C6_MUX_PEX_ADC_R_SCL")
		)
		(pad "2" smd circle
			(at 0.40005 0 180)
			(size 0 0)
			(layers "F.Cu" "F.Mask" "F.Paste")
			(net "SMB_PEX0_P1V25_ADC_SCL")
		)
	)
	(footprint ""
		(layer "F.Cu")
		(at 261.74192 -305.648106 -135)
		(property "Reference" "R1375"
			(at 0 0 225)
			(layer "F.SilkS")
			(hide yes)
			(effects
				(font
					(size 1.27 1.27)
				)
			)
		)
		(property "Value" ""
			(at 0 0 225)
			(layer "F.Fab")
			(effects
				(font
					(size 1.27 1.27)
				)
			)
		)
		(duplicate_pad_numbers_are_jumpers no)
		(fp_line
			(start 0.787389 0.406267)
			(end -0.787389 0.406267)
			(stroke
				(width 0.1524)
				(type default)
			)
			(layer "F.SilkS")
		)
		(fp_line
			(start 0.787389 -0.406267)
			(end 0.787389 0.406267)
			(stroke
				(width 0.1524)
				(type default)
			)
			(layer "F.SilkS")
		)
		(fp_line
			(start -0.787389 0.406267)
			(end -0.787389 -0.406267)
			(stroke
				(width 0.1524)
				(type default)
			)
			(layer "F.SilkS")
		)
		(fp_line
			(start -0.787389 -0.406267)
			(end 0.787389 -0.406267)
			(stroke
				(width 0.1524)
				(type default)
			)
			(layer "F.SilkS")
		)
		(fp_line
			(start 0.679446 0.30479)
			(end 0.120515 0.30479)
			(stroke
				(width 0.1)
				(type default)
			)
			(layer "F.Fab")
		)
		(fp_line
			(start 0.120515 0.30479)
			(end 0.120335 0.279466)
			(stroke
				(width 0.1)
				(type default)
			)
			(layer "F.Fab")
		)
		(fp_line
			(start 0.120335 0.279466)
			(end -0.120695 0.279466)
			(stroke
				(width 0.1)
				(type default)
			)
			(layer "F.Fab")
		)
		(fp_line
			(start 0.679446 -0.30479)
			(end 0.679446 0.30479)
			(stroke
				(width 0.1)
				(type default)
			)
			(layer "F.Fab")
		)
		(fp_line
			(start -0.120515 0.30479)
			(end -0.679446 0.30479)
			(stroke
				(width 0.1)
				(type default)
			)
			(layer "F.Fab")
		)
		(fp_line
			(start -0.120695 0.279466)
			(end -0.120515 0.30479)
			(stroke
				(width 0.1)
				(type default)
			)
			(layer "F.Fab")
		)
		(fp_line
			(start 0.120695 -0.279466)
			(end 0.120515 -0.30479)
			(stroke
				(width 0.1)
				(type default)
			)
			(layer "F.Fab")
		)
		(fp_line
			(start 0.120515 -0.30479)
			(end 0.679446 -0.30479)
			(stroke
				(width 0.1)
				(type default)
			)
			(layer "F.Fab")
		)
		(fp_line
			(start -0.679446 0.30479)
			(end -0.679446 -0.305149)
			(stroke
				(width 0.1)
				(type default)
			)
			(layer "F.Fab")
		)
		(fp_line
			(start -0.120695 -0.279466)
			(end 0.120695 -0.279466)
			(stroke
				(width 0.1)
				(type default)
			)
			(layer "F.Fab")
		)
		(fp_line
			(start -0.120695 -0.304969)
			(end -0.120695 -0.279466)
			(stroke
				(width 0.1)
				(type default)
			)
			(layer "F.Fab")
		)
		(fp_line
			(start -0.679446 -0.305149)
			(end -0.120695 -0.304969)
			(stroke
				(width 0.1)
				(type default)
			)
			(layer "F.Fab")
		)
		(pad "1" smd circle
			(at -0.40005 0 225)
			(size 0 0)
			(layers "F.Cu" "F.Mask" "F.Paste")
			(net "PEX2_DFT_IDDT")
		)
		(pad "2" smd circle
			(at 0.40005 0 225)
			(size 0 0)
			(layers "F.Cu" "F.Mask" "F.Paste")
			(net "P1V8_PEX")
		)
	)
	(footprint ""
		(layer "F.Cu")
		(at 116.27739 -254.55372 180)
		(property "Reference" "PC47"
			(at 0 0 180)
			(layer "F.SilkS")
			(hide yes)
			(effects
				(font
					(size 1.27 1.27)
				)
			)
		)
		(property "Value" ""
			(at 0 0 180)
			(layer "F.Fab")
			(effects
				(font
					(size 1.27 1.27)
				)
			)
		)
		(duplicate_pad_numbers_are_jumpers no)
		(fp_line
			(start 0.7874 0.4064)
			(end -0.7874 0.4064)
			(stroke
				(width 0.1524)
				(type default)
			)
			(layer "F.SilkS")
		)
		(fp_line
			(start 0.7874 -0.4064)
			(end 0.7874 0.4064)
			(stroke
				(width 0.1524)
				(type default)
			)
			(layer "F.SilkS")
		)
		(fp_line
			(start -0.7874 0.4064)
			(end -0.7874 -0.4064)
			(stroke
				(width 0.1524)
				(type default)
			)
			(layer "F.SilkS")
		)
		(fp_line
			(start -0.7874 -0.4064)
			(end 0.7874 -0.4064)
			(stroke
				(width 0.1524)
				(type default)
			)
			(layer "F.SilkS")
		)
		(fp_line
			(start 0.67945 0.3048)
			(end 0.120396 0.3048)
			(stroke
				(width 0.1)
				(type default)
			)
			(layer "F.Fab")
		)
		(fp_line
			(start 0.67945 -0.3048)
			(end 0.67945 0.3048)
			(stroke
				(width 0.1)
				(type default)
			)
			(layer "F.Fab")
		)
		(fp_line
			(start 0.12065 -0.2794)
			(end 0.12065 -0.3048)
			(stroke
				(width 0.1)
				(type default)
			)
			(layer "F.Fab")
		)
		(fp_line
			(start 0.12065 -0.3048)
			(end 0.67945 -0.3048)
			(stroke
				(width 0.1)
				(type default)
			)
			(layer "F.Fab")
		)
		(fp_line
			(start 0.120396 0.3048)
			(end 0.120396 0.2794)
			(stroke
				(width 0.1)
				(type default)
			)
			(layer "F.Fab")
		)
		(fp_line
			(start 0.120396 0.2794)
			(end -0.12065 0.2794)
			(stroke
				(width 0.1)
				(type default)
			)
			(layer "F.Fab")
		)
		(fp_line
			(start -0.12065 0.3048)
			(end -0.67945 0.3048)
			(stroke
				(width 0.1)
				(type default)
			)
			(layer "F.Fab")
		)
		(fp_line
			(start -0.12065 0.2794)
			(end -0.12065 0.3048)
			(stroke
				(width 0.1)
				(type default)
			)
			(layer "F.Fab")
		)
		(fp_line
			(start -0.12065 -0.2794)
			(end 0.12065 -0.2794)
			(stroke
				(width 0.1)
				(type default)
			)
			(layer "F.Fab")
		)
		(fp_line
			(start -0.12065 -0.305054)
			(end -0.12065 -0.2794)
			(stroke
				(width 0.1)
				(type default)
			)
			(layer "F.Fab")
		)
		(fp_line
			(start -0.67945 0.3048)
			(end -0.67945 -0.305054)
			(stroke
				(width 0.1)
				(type default)
			)
			(layer "F.Fab")
		)
		(fp_line
			(start -0.67945 -0.305054)
			(end -0.12065 -0.305054)
			(stroke
				(width 0.1)
				(type default)
			)
			(layer "F.Fab")
		)
		(pad "1" smd circle
			(at -0.40005 0 180)
			(size 0 0)
			(layers "F.Cu" "F.Mask" "F.Paste")
			(net "P0V8_PEX0_VREF")
		)
		(pad "2" smd circle
			(at 0.40005 0 180)
			(size 0 0)
			(layers "F.Cu" "F.Mask" "F.Paste")
			(net "GND")
		)
	)
	(footprint ""
		(layer "F.Cu")
		(at 11.2776 -273.31543 135)
		(property "Reference" "C627"
			(at 0 0 135)
			(layer "F.SilkS")
			(hide yes)
			(effects
				(font
					(size 1.27 1.27)
				)
			)
		)
		(property "Value" ""
			(at 0 0 135)
			(layer "F.Fab")
			(effects
				(font
					(size 1.27 1.27)
				)
			)
		)
		(duplicate_pad_numbers_are_jumpers no)
		(fp_line
			(start 0.787389 -0.406267)
			(end 0.787389 0.406267)
			(stroke
				(width 0.1524)
				(type default)
			)
			(layer "F.SilkS")
		)
		(fp_line
			(start 0.787389 0.406267)
			(end -0.787389 0.406267)
			(stroke
				(width 0.1524)
				(type default)
			)
			(layer "F.SilkS")
		)
		(fp_line
			(start -0.787389 -0.406267)
			(end 0.787389 -0.406267)
			(stroke
				(width 0.1524)
				(type default)
			)
			(layer "F.SilkS")
		)
		(fp_line
			(start -0.787389 0.406267)
			(end -0.787389 -0.406267)
			(stroke
				(width 0.1524)
				(type default)
			)
			(layer "F.SilkS")
		)
		(fp_line
			(start 0.679446 -0.30479)
			(end 0.679446 0.30479)
			(stroke
				(width 0.1)
				(type default)
			)
			(layer "F.Fab")
		)
		(fp_line
			(start 0.120515 -0.30479)
			(end 0.679446 -0.30479)
			(stroke
				(width 0.1)
				(type default)
			)
			(layer "F.Fab")
		)
		(fp_line
			(start 0.120695 -0.279466)
			(end 0.120515 -0.30479)
			(stroke
				(width 0.1)
				(type default)
			)
			(layer "F.Fab")
		)
		(fp_line
			(start 0.679446 0.30479)
			(end 0.120515 0.30479)
			(stroke
				(width 0.1)
				(type default)
			)
			(layer "F.Fab")
		)
		(fp_line
			(start -0.120695 -0.304969)
			(end -0.120695 -0.279466)
			(stroke
				(width 0.1)
				(type default)
			)
			(layer "F.Fab")
		)
		(fp_line
			(start -0.120695 -0.279466)
			(end 0.120695 -0.279466)
			(stroke
				(width 0.1)
				(type default)
			)
			(layer "F.Fab")
		)
		(fp_line
			(start 0.120335 0.279466)
			(end -0.120695 0.279466)
			(stroke
				(width 0.1)
				(type default)
			)
			(layer "F.Fab")
		)
		(fp_line
			(start 0.120515 0.30479)
			(end 0.120335 0.279466)
			(stroke
				(width 0.1)
				(type default)
			)
			(layer "F.Fab")
		)
		(fp_line
			(start -0.679446 -0.305149)
			(end -0.120695 -0.304969)
			(stroke
				(width 0.1)
				(type default)
			)
			(layer "F.Fab")
		)
		(fp_line
			(start -0.120695 0.279466)
			(end -0.120515 0.30479)
			(stroke
				(width 0.1)
				(type default)
			)
			(layer "F.Fab")
		)
		(fp_line
			(start -0.120515 0.30479)
			(end -0.679446 0.30479)
			(stroke
				(width 0.1)
				(type default)
			)
			(layer "F.Fab")
		)
		(fp_line
			(start -0.679446 0.30479)
			(end -0.679446 -0.305149)
			(stroke
				(width 0.1)
				(type default)
			)
			(layer "F.Fab")
		)
		(pad "1" smd circle
			(at -0.40005 0 135)
			(size 0 0)
			(layers "F.Cu" "F.Mask" "F.Paste")
			(net "P12V_PEX0_P1V25_VIN_P")
		)
		(pad "2" smd circle
			(at 0.40005 0 135)
			(size 0 0)
			(layers "F.Cu" "F.Mask" "F.Paste")
			(net "P12V_PEX0_P1V25_VIN_N")
		)
	)
	(footprint ""
		(layer "F.Cu")
		(at 196.639434 -137.645648)
		(property "Reference" "R158"
			(at 0 0 0)
			(layer "F.SilkS")
			(hide yes)
			(effects
				(font
					(size 1.27 1.27)
				)
			)
		)
		(property "Value" ""
			(at 0 0 0)
			(layer "F.Fab")
			(effects
				(font
					(size 1.27 1.27)
				)
			)
		)
		(duplicate_pad_numbers_are_jumpers no)
		(fp_line
			(start -0.7874 -0.4064)
			(end 0.7874 -0.4064)
			(stroke
				(width 0.1524)
				(type default)
			)
			(layer "F.SilkS")
		)
		(fp_line
			(start -0.7874 0.4064)
			(end -0.7874 -0.4064)
			(stroke
				(width 0.1524)
				(type default)
			)
			(layer "F.SilkS")
		)
		(fp_line
			(start 0.7874 -0.4064)
			(end 0.7874 0.4064)
			(stroke
				(width 0.1524)
				(type default)
			)
			(layer "F.SilkS")
		)
		(fp_line
			(start 0.7874 0.4064)
			(end -0.7874 0.4064)
			(stroke
				(width 0.1524)
				(type default)
			)
			(layer "F.SilkS")
		)
		(fp_line
			(start -0.67945 -0.305054)
			(end -0.12065 -0.305054)
			(stroke
				(width 0.1)
				(type default)
			)
			(layer "F.Fab")
		)
		(fp_line
			(start -0.67945 0.3048)
			(end -0.67945 -0.305054)
			(stroke
				(width 0.1)
				(type default)
			)
			(layer "F.Fab")
		)
		(fp_line
			(start -0.12065 -0.305054)
			(end -0.12065 -0.2794)
			(stroke
				(width 0.1)
				(type default)
			)
			(layer "F.Fab")
		)
		(fp_line
			(start -0.12065 -0.2794)
			(end 0.12065 -0.2794)
			(stroke
				(width 0.1)
				(type default)
			)
			(layer "F.Fab")
		)
		(fp_line
			(start -0.12065 0.2794)
			(end -0.12065 0.3048)
			(stroke
				(width 0.1)
				(type default)
			)
			(layer "F.Fab")
		)
		(fp_line
			(start -0.12065 0.3048)
			(end -0.67945 0.3048)
			(stroke
				(width 0.1)
				(type default)
			)
			(layer "F.Fab")
		)
		(fp_line
			(start 0.120396 0.2794)
			(end -0.12065 0.2794)
			(stroke
				(width 0.1)
				(type default)
			)
			(layer "F.Fab")
		)
		(fp_line
			(start 0.120396 0.3048)
			(end 0.120396 0.2794)
			(stroke
				(width 0.1)
				(type default)
			)
			(layer "F.Fab")
		)
		(fp_line
			(start 0.12065 -0.3048)
			(end 0.67945 -0.3048)
			(stroke
				(width 0.1)
				(type default)
			)
			(layer "F.Fab")
		)
		(fp_line
			(start 0.12065 -0.2794)
			(end 0.12065 -0.3048)
			(stroke
				(width 0.1)
				(type default)
			)
			(layer "F.Fab")
		)
		(fp_line
			(start 0.67945 -0.3048)
			(end 0.67945 0.3048)
			(stroke
				(width 0.1)
				(type default)
			)
			(layer "F.Fab")
		)
		(fp_line
			(start 0.67945 0.3048)
			(end 0.120396 0.3048)
			(stroke
				(width 0.1)
				(type default)
			)
			(layer "F.Fab")
		)
		(pad "1" smd circle
			(at -0.40005 0)
			(size 0 0)
			(layers "F.Cu" "F.Mask" "F.Paste")
			(net "PRSNTB0_NIC3_N")
		)
		(pad "2" smd circle
			(at 0.40005 0)
			(size 0 0)
			(layers "F.Cu" "F.Mask" "F.Paste")
			(net "P3V3_AUX")
		)
	)
	(footprint ""
		(layer "F.Cu")
		(at 166.184072 -343.952322 90)
		(property "Reference" "C2515"
			(at 0 0 90)
			(layer "F.SilkS")
			(hide yes)
			(effects
				(font
					(size 1.27 1.27)
				)
			)
		)
		(property "Value" ""
			(at 0 0 90)
			(layer "F.Fab")
			(effects
				(font
					(size 1.27 1.27)
				)
			)
		)
		(duplicate_pad_numbers_are_jumpers no)
		(fp_line
			(start 0.299974 -0.150114)
			(end 0.299974 0.150114)
			(stroke
				(width 0.1)
				(type default)
			)
			(layer "F.Fab")
		)
		(fp_line
			(start -0.299974 -0.150114)
			(end 0.299974 -0.150114)
			(stroke
				(width 0.1)
				(type default)
			)
			(layer "F.Fab")
		)
		(fp_line
			(start 0.299974 0.150114)
			(end -0.299974 0.150114)
			(stroke
				(width 0.1)
				(type default)
			)
			(layer "F.Fab")
		)
		(fp_line
			(start -0.299974 0.150114)
			(end -0.299974 -0.150114)
			(stroke
				(width 0.1)
				(type default)
			)
			(layer "F.Fab")
		)
		(pad "1" smd rect
			(at -0.2667 0 90)
			(size 0.3048 0.381)
			(layers "F.Cu" "F.Mask" "F.Paste")
			(net "P5E_PEX1_STN4_TX_DN<78>")
		)
		(pad "2" smd rect
			(at 0.2667 0 90)
			(size 0.3048 0.381)
			(layers "F.Cu" "F.Mask" "F.Paste")
			(net "P5E_PEX1_STN4_TX_C_DN<78>")
		)
	)
	(footprint ""
		(layer "F.Cu")
		(at 305.730402 -66.32194 -90)
		(property "Reference" "PC873"
			(at 0 0 270)
			(layer "F.SilkS")
			(hide yes)
			(effects
				(font
					(size 1.27 1.27)
				)
			)
		)
		(property "Value" ""
			(at 0 0 270)
			(layer "F.Fab")
			(effects
				(font
					(size 1.27 1.27)
				)
			)
		)
		(duplicate_pad_numbers_are_jumpers no)
		(fp_line
			(start -0.7874 0.4064)
			(end -0.7874 -0.4064)
			(stroke
				(width 0.1524)
				(type default)
			)
			(layer "F.SilkS")
		)
		(fp_line
			(start 0.7874 0.4064)
			(end -0.7874 0.4064)
			(stroke
				(width 0.1524)
				(type default)
			)
			(layer "F.SilkS")
		)
		(fp_line
			(start -0.7874 -0.4064)
			(end 0.7874 -0.4064)
			(stroke
				(width 0.1524)
				(type default)
			)
			(layer "F.SilkS")
		)
		(fp_line
			(start 0.7874 -0.4064)
			(end 0.7874 0.4064)
			(stroke
				(width 0.1524)
				(type default)
			)
			(layer "F.SilkS")
		)
		(fp_line
			(start -0.67945 0.3048)
			(end -0.67945 -0.305054)
			(stroke
				(width 0.1)
				(type default)
			)
			(layer "F.Fab")
		)
		(fp_line
			(start -0.12065 0.3048)
			(end -0.67945 0.3048)
			(stroke
				(width 0.1)
				(type default)
			)
			(layer "F.Fab")
		)
		(fp_line
			(start 0.120396 0.3048)
			(end 0.120396 0.2794)
			(stroke
				(width 0.1)
				(type default)
			)
			(layer "F.Fab")
		)
		(fp_line
			(start 0.67945 0.3048)
			(end 0.120396 0.3048)
			(stroke
				(width 0.1)
				(type default)
			)
			(layer "F.Fab")
		)
		(fp_line
			(start -0.12065 0.2794)
			(end -0.12065 0.3048)
			(stroke
				(width 0.1)
				(type default)
			)
			(layer "F.Fab")
		)
		(fp_line
			(start 0.120396 0.2794)
			(end -0.12065 0.2794)
			(stroke
				(width 0.1)
				(type default)
			)
			(layer "F.Fab")
		)
		(fp_line
			(start -0.12065 -0.2794)
			(end 0.12065 -0.2794)
			(stroke
				(width 0.1)
				(type default)
			)
			(layer "F.Fab")
		)
		(fp_line
			(start 0.12065 -0.2794)
			(end 0.12065 -0.3048)
			(stroke
				(width 0.1)
				(type default)
			)
			(layer "F.Fab")
		)
		(fp_line
			(start 0.12065 -0.3048)
			(end 0.67945 -0.3048)
			(stroke
				(width 0.1)
				(type default)
			)
			(layer "F.Fab")
		)
		(fp_line
			(start 0.67945 -0.3048)
			(end 0.67945 0.3048)
			(stroke
				(width 0.1)
				(type default)
			)
			(layer "F.Fab")
		)
		(fp_line
			(start -0.67945 -0.305054)
			(end -0.12065 -0.305054)
			(stroke
				(width 0.1)
				(type default)
			)
			(layer "F.Fab")
		)
		(fp_line
			(start -0.12065 -0.305054)
			(end -0.12065 -0.2794)
			(stroke
				(width 0.1)
				(type default)
			)
			(layer "F.Fab")
		)
		(pad "1" smd circle
			(at -0.40005 0 270)
			(size 0 0)
			(layers "F.Cu" "F.Mask" "F.Paste")
			(net "P12V_SSD10_CO_DV_DT")
		)
		(pad "2" smd circle
			(at 0.40005 0 270)
			(size 0 0)
			(layers "F.Cu" "F.Mask" "F.Paste")
			(net "GND")
		)
	)
	(footprint ""
		(layer "F.Cu")
		(at 432.87569 -36.915598 -90)
		(property "Reference" "R5586"
			(at 0 0 270)
			(layer "F.SilkS")
			(hide yes)
			(effects
				(font
					(size 1.27 1.27)
				)
			)
		)
		(property "Value" ""
			(at 0 0 270)
			(layer "F.Fab")
			(effects
				(font
					(size 1.27 1.27)
				)
			)
		)
		(duplicate_pad_numbers_are_jumpers no)
		(fp_line
			(start -0.7874 0.4064)
			(end -0.7874 -0.4064)
			(stroke
				(width 0.1524)
				(type default)
			)
			(layer "F.SilkS")
		)
		(fp_line
			(start 0.7874 0.4064)
			(end -0.7874 0.4064)
			(stroke
				(width 0.1524)
				(type default)
			)
			(layer "F.SilkS")
		)
		(fp_line
			(start -0.7874 -0.4064)
			(end 0.7874 -0.4064)
			(stroke
				(width 0.1524)
				(type default)
			)
			(layer "F.SilkS")
		)
		(fp_line
			(start 0.7874 -0.4064)
			(end 0.7874 0.4064)
			(stroke
				(width 0.1524)
				(type default)
			)
			(layer "F.SilkS")
		)
		(fp_line
			(start -0.67945 0.3048)
			(end -0.67945 -0.305054)
			(stroke
				(width 0.1)
				(type default)
			)
			(layer "F.Fab")
		)
		(fp_line
			(start -0.12065 0.3048)
			(end -0.67945 0.3048)
			(stroke
				(width 0.1)
				(type default)
			)
			(layer "F.Fab")
		)
		(fp_line
			(start 0.120396 0.3048)
			(end 0.120396 0.2794)
			(stroke
				(width 0.1)
				(type default)
			)
			(layer "F.Fab")
		)
		(fp_line
			(start 0.67945 0.3048)
			(end 0.120396 0.3048)
			(stroke
				(width 0.1)
				(type default)
			)
			(layer "F.Fab")
		)
		(fp_line
			(start -0.12065 0.2794)
			(end -0.12065 0.3048)
			(stroke
				(width 0.1)
				(type default)
			)
			(layer "F.Fab")
		)
		(fp_line
			(start 0.120396 0.2794)
			(end -0.12065 0.2794)
			(stroke
				(width 0.1)
				(type default)
			)
			(layer "F.Fab")
		)
		(fp_line
			(start -0.12065 -0.2794)
			(end 0.12065 -0.2794)
			(stroke
				(width 0.1)
				(type default)
			)
			(layer "F.Fab")
		)
		(fp_line
			(start 0.12065 -0.2794)
			(end 0.12065 -0.3048)
			(stroke
				(width 0.1)
				(type default)
			)
			(layer "F.Fab")
		)
		(fp_line
			(start 0.12065 -0.3048)
			(end 0.67945 -0.3048)
			(stroke
				(width 0.1)
				(type default)
			)
			(layer "F.Fab")
		)
		(fp_line
			(start 0.67945 -0.3048)
			(end 0.67945 0.3048)
			(stroke
				(width 0.1)
				(type default)
			)
			(layer "F.Fab")
		)
		(fp_line
			(start -0.67945 -0.305054)
			(end -0.12065 -0.305054)
			(stroke
				(width 0.1)
				(type default)
			)
			(layer "F.Fab")
		)
		(fp_line
			(start -0.12065 -0.305054)
			(end -0.12065 -0.2794)
			(stroke
				(width 0.1)
				(type default)
			)
			(layer "F.Fab")
		)
		(pad "1" smd circle
			(at -0.40005 0 270)
			(size 0 0)
			(layers "F.Cu" "F.Mask" "F.Paste")
			(net "PRSNT_SSD15_R1_N")
		)
		(pad "2" smd circle
			(at 0.40005 0 270)
			(size 0 0)
			(layers "F.Cu" "F.Mask" "F.Paste")
			(net "PRSNT_SSD15_R_N")
		)
	)
	(footprint ""
		(layer "F.Cu")
		(at 38.608 -156.3624 180)
		(property "Reference" "R13"
			(at 0 0 180)
			(layer "F.SilkS")
			(hide yes)
			(effects
				(font
					(size 1.27 1.27)
				)
			)
		)
		(property "Value" ""
			(at 0 0 180)
			(layer "F.Fab")
			(effects
				(font
					(size 1.27 1.27)
				)
			)
		)
		(duplicate_pad_numbers_are_jumpers no)
		(fp_line
			(start 0.7874 0.4064)
			(end -0.7874 0.4064)
			(stroke
				(width 0.1524)
				(type default)
			)
			(layer "F.SilkS")
		)
		(fp_line
			(start 0.7874 -0.4064)
			(end 0.7874 0.4064)
			(stroke
				(width 0.1524)
				(type default)
			)
			(layer "F.SilkS")
		)
		(fp_line
			(start -0.7874 0.4064)
			(end -0.7874 -0.4064)
			(stroke
				(width 0.1524)
				(type default)
			)
			(layer "F.SilkS")
		)
		(fp_line
			(start -0.7874 -0.4064)
			(end 0.7874 -0.4064)
			(stroke
				(width 0.1524)
				(type default)
			)
			(layer "F.SilkS")
		)
		(fp_line
			(start 0.67945 0.3048)
			(end 0.120396 0.3048)
			(stroke
				(width 0.1)
				(type default)
			)
			(layer "F.Fab")
		)
		(fp_line
			(start 0.67945 -0.3048)
			(end 0.67945 0.3048)
			(stroke
				(width 0.1)
				(type default)
			)
			(layer "F.Fab")
		)
		(fp_line
			(start 0.12065 -0.2794)
			(end 0.12065 -0.3048)
			(stroke
				(width 0.1)
				(type default)
			)
			(layer "F.Fab")
		)
		(fp_line
			(start 0.12065 -0.3048)
			(end 0.67945 -0.3048)
			(stroke
				(width 0.1)
				(type default)
			)
			(layer "F.Fab")
		)
		(fp_line
			(start 0.120396 0.3048)
			(end 0.120396 0.2794)
			(stroke
				(width 0.1)
				(type default)
			)
			(layer "F.Fab")
		)
		(fp_line
			(start 0.120396 0.2794)
			(end -0.12065 0.2794)
			(stroke
				(width 0.1)
				(type default)
			)
			(layer "F.Fab")
		)
		(fp_line
			(start -0.12065 0.3048)
			(end -0.67945 0.3048)
			(stroke
				(width 0.1)
				(type default)
			)
			(layer "F.Fab")
		)
		(fp_line
			(start -0.12065 0.2794)
			(end -0.12065 0.3048)
			(stroke
				(width 0.1)
				(type default)
			)
			(layer "F.Fab")
		)
		(fp_line
			(start -0.12065 -0.2794)
			(end 0.12065 -0.2794)
			(stroke
				(width 0.1)
				(type default)
			)
			(layer "F.Fab")
		)
		(fp_line
			(start -0.12065 -0.305054)
			(end -0.12065 -0.2794)
			(stroke
				(width 0.1)
				(type default)
			)
			(layer "F.Fab")
		)
		(fp_line
			(start -0.67945 0.3048)
			(end -0.67945 -0.305054)
			(stroke
				(width 0.1)
				(type default)
			)
			(layer "F.Fab")
		)
		(fp_line
			(start -0.67945 -0.305054)
			(end -0.12065 -0.305054)
			(stroke
				(width 0.1)
				(type default)
			)
			(layer "F.Fab")
		)
		(pad "1" smd circle
			(at -0.40005 0 180)
			(size 0 0)
			(layers "F.Cu" "F.Mask" "F.Paste")
			(net "NIC0_DATA_OUT")
		)
		(pad "2" smd circle
			(at 0.40005 0 180)
			(size 0 0)
			(layers "F.Cu" "F.Mask" "F.Paste")
			(net "GND")
		)
	)
	(footprint ""
		(layer "F.Cu")
		(at 346.782136 -37.025072)
		(property "Reference" "R5701"
			(at 0 0 0)
			(layer "F.SilkS")
			(hide yes)
			(effects
				(font
					(size 1.27 1.27)
				)
			)
		)
		(property "Value" ""
			(at 0 0 0)
			(layer "F.Fab")
			(effects
				(font
					(size 1.27 1.27)
				)
			)
		)
		(duplicate_pad_numbers_are_jumpers no)
		(fp_line
			(start -0.7874 -0.4064)
			(end 0.7874 -0.4064)
			(stroke
				(width 0.1524)
				(type default)
			)
			(layer "F.SilkS")
		)
		(fp_line
			(start -0.7874 0.4064)
			(end -0.7874 -0.4064)
			(stroke
				(width 0.1524)
				(type default)
			)
			(layer "F.SilkS")
		)
		(fp_line
			(start 0.7874 -0.4064)
			(end 0.7874 0.4064)
			(stroke
				(width 0.1524)
				(type default)
			)
			(layer "F.SilkS")
		)
		(fp_line
			(start 0.7874 0.4064)
			(end -0.7874 0.4064)
			(stroke
				(width 0.1524)
				(type default)
			)
			(layer "F.SilkS")
		)
		(fp_line
			(start -0.67945 -0.305054)
			(end -0.12065 -0.305054)
			(stroke
				(width 0.1)
				(type default)
			)
			(layer "F.Fab")
		)
		(fp_line
			(start -0.67945 0.3048)
			(end -0.67945 -0.305054)
			(stroke
				(width 0.1)
				(type default)
			)
			(layer "F.Fab")
		)
		(fp_line
			(start -0.12065 -0.305054)
			(end -0.12065 -0.2794)
			(stroke
				(width 0.1)
				(type default)
			)
			(layer "F.Fab")
		)
		(fp_line
			(start -0.12065 -0.2794)
			(end 0.12065 -0.2794)
			(stroke
				(width 0.1)
				(type default)
			)
			(layer "F.Fab")
		)
		(fp_line
			(start -0.12065 0.2794)
			(end -0.12065 0.3048)
			(stroke
				(width 0.1)
				(type default)
			)
			(layer "F.Fab")
		)
		(fp_line
			(start -0.12065 0.3048)
			(end -0.67945 0.3048)
			(stroke
				(width 0.1)
				(type default)
			)
			(layer "F.Fab")
		)
		(fp_line
			(start 0.120396 0.2794)
			(end -0.12065 0.2794)
			(stroke
				(width 0.1)
				(type default)
			)
			(layer "F.Fab")
		)
		(fp_line
			(start 0.120396 0.3048)
			(end 0.120396 0.2794)
			(stroke
				(width 0.1)
				(type default)
			)
			(layer "F.Fab")
		)
		(fp_line
			(start 0.12065 -0.3048)
			(end 0.67945 -0.3048)
			(stroke
				(width 0.1)
				(type default)
			)
			(layer "F.Fab")
		)
		(fp_line
			(start 0.12065 -0.2794)
			(end 0.12065 -0.3048)
			(stroke
				(width 0.1)
				(type default)
			)
			(layer "F.Fab")
		)
		(fp_line
			(start 0.67945 -0.3048)
			(end 0.67945 0.3048)
			(stroke
				(width 0.1)
				(type default)
			)
			(layer "F.Fab")
		)
		(fp_line
			(start 0.67945 0.3048)
			(end 0.120396 0.3048)
			(stroke
				(width 0.1)
				(type default)
			)
			(layer "F.Fab")
		)
		(pad "1" smd circle
			(at -0.40005 0)
			(size 0 0)
			(layers "F.Cu" "F.Mask" "F.Paste")
			(net "RST_SMB_SSD_R_N")
		)
		(pad "2" smd circle
			(at 0.40005 0)
			(size 0 0)
			(layers "F.Cu" "F.Mask" "F.Paste")
			(net "RST_SMB_SSD12_N")
		)
	)
	(footprint ""
		(layer "F.Cu")
		(at 6.467348 -251.312426 -90)
		(property "Reference" "C4243"
			(at 0 0 270)
			(layer "F.SilkS")
			(hide yes)
			(effects
				(font
					(size 1.27 1.27)
				)
			)
		)
		(property "Value" ""
			(at 0 0 270)
			(layer "F.Fab")
			(effects
				(font
					(size 1.27 1.27)
				)
			)
		)
		(duplicate_pad_numbers_are_jumpers no)
		(fp_line
			(start -1.2954 0.5842)
			(end -1.2954 -0.5842)
			(stroke
				(width 0.1524)
				(type default)
			)
			(layer "F.SilkS")
		)
		(fp_line
			(start 1.2954 0.5842)
			(end -1.2954 0.5842)
			(stroke
				(width 0.1524)
				(type default)
			)
			(layer "F.SilkS")
		)
		(fp_line
			(start -1.2954 -0.5842)
			(end 1.2954 -0.5842)
			(stroke
				(width 0.1524)
				(type default)
			)
			(layer "F.SilkS")
		)
		(fp_line
			(start 1.2954 -0.5842)
			(end 1.2954 0.5842)
			(stroke
				(width 0.1524)
				(type default)
			)
			(layer "F.SilkS")
		)
		(fp_line
			(start -0.8636 0.4572)
			(end -0.8636 0.4064)
			(stroke
				(width 0.1)
				(type default)
			)
			(layer "F.Fab")
		)
		(fp_line
			(start 0.8636 0.4572)
			(end -0.8636 0.4572)
			(stroke
				(width 0.1)
				(type default)
			)
			(layer "F.Fab")
		)
		(fp_line
			(start -1.1938 0.4064)
			(end -1.1938 -0.4064)
			(stroke
				(width 0.1)
				(type default)
			)
			(layer "F.Fab")
		)
		(fp_line
			(start -0.8636 0.4064)
			(end -1.1938 0.4064)
			(stroke
				(width 0.1)
				(type default)
			)
			(layer "F.Fab")
		)
		(fp_line
			(start 0.8636 0.4064)
			(end 0.8636 0.4572)
			(stroke
				(width 0.1)
				(type default)
			)
			(layer "F.Fab")
		)
		(fp_line
			(start 1.1938 0.4064)
			(end 0.8636 0.4064)
			(stroke
				(width 0.1)
				(type default)
			)
			(layer "F.Fab")
		)
		(fp_line
			(start -1.1938 -0.4064)
			(end -0.8636 -0.4064)
			(stroke
				(width 0.1)
				(type default)
			)
			(layer "F.Fab")
		)
		(fp_line
			(start -0.8636 -0.4064)
			(end -0.8636 -0.4572)
			(stroke
				(width 0.1)
				(type default)
			)
			(layer "F.Fab")
		)
		(fp_line
			(start 0.8636 -0.4064)
			(end 1.1938 -0.4064)
			(stroke
				(width 0.1)
				(type default)
			)
			(layer "F.Fab")
		)
		(fp_line
			(start 1.1938 -0.4064)
			(end 1.1938 0.4064)
			(stroke
				(width 0.1)
				(type default)
			)
			(layer "F.Fab")
		)
		(fp_line
			(start -0.8636 -0.4572)
			(end 0.8636 -0.4572)
			(stroke
				(width 0.1)
				(type default)
			)
			(layer "F.Fab")
		)
		(fp_line
			(start 0.8636 -0.4572)
			(end 0.8636 -0.4064)
			(stroke
				(width 0.1)
				(type default)
			)
			(layer "F.Fab")
		)
		(pad "1" smd rect
			(at -0.7366 0 180)
			(size 0.7112 0.8128)
			(layers "F.Cu" "F.Mask" "F.Paste")
			(net "P1V25_SERDES_VDDPLL_PEX0_C9")
		)
		(pad "2" smd rect
			(at 0.7366 0 180)
			(size 0.7112 0.8128)
			(layers "F.Cu" "F.Mask" "F.Paste")
			(net "GND")
		)
	)
	(footprint ""
		(layer "F.Cu")
		(at 366.092486 -28.225242 180)
		(property "Reference" "C705"
			(at 0 0 180)
			(layer "F.SilkS")
			(hide yes)
			(effects
				(font
					(size 1.27 1.27)
				)
			)
		)
		(property "Value" ""
			(at 0 0 180)
			(layer "F.Fab")
			(effects
				(font
					(size 1.27 1.27)
				)
			)
		)
		(duplicate_pad_numbers_are_jumpers no)
		(fp_line
			(start 0.299974 0.150114)
			(end -0.299974 0.150114)
			(stroke
				(width 0.1)
				(type default)
			)
			(layer "F.Fab")
		)
		(fp_line
			(start 0.299974 -0.150114)
			(end 0.299974 0.150114)
			(stroke
				(width 0.1)
				(type default)
			)
			(layer "F.Fab")
		)
		(fp_line
			(start -0.299974 0.150114)
			(end -0.299974 -0.150114)
			(stroke
				(width 0.1)
				(type default)
			)
			(layer "F.Fab")
		)
		(fp_line
			(start -0.299974 -0.150114)
			(end 0.299974 -0.150114)
			(stroke
				(width 0.1)
				(type default)
			)
			(layer "F.Fab")
		)
		(pad "1" smd rect
			(at -0.2667 0 180)
			(size 0.3048 0.381)
			(layers "F.Cu" "F.Mask" "F.Paste")
			(net "P5E_PEX3_STN2_TX_DN<44>")
		)
		(pad "2" smd rect
			(at 0.2667 0 180)
			(size 0.3048 0.381)
			(layers "F.Cu" "F.Mask" "F.Paste")
			(net "P5E_PEX3_STN2_TX_C_DN<44>")
		)
	)
	(footprint ""
		(layer "F.Cu")
		(at 435.306724 -294.77335 90)
		(property "Reference" "U428"
			(at -1.0922 -2.174748 90)
			(unlocked yes)
			(layer "F.SilkS")
			(effects
				(font
					(size 0.7874 0.5842)
					(thickness 0.1524)
				)
				(justify left)
			)
		)
		(property "Value" ""
			(at 0 0 90)
			(layer "F.Fab")
			(effects
				(font
					(size 1.27 1.27)
				)
			)
		)
		(duplicate_pad_numbers_are_jumpers no)
		(fp_line
			(start 1.0414 -1.575054)
			(end 1.0414 1.575054)
			(stroke
				(width 0.1524)
				(type default)
			)
			(layer "F.SilkS")
		)
		(fp_line
			(start 0.254 -1.575054)
			(end 1.0414 -1.575054)
			(stroke
				(width 0.1524)
				(type default)
			)
			(layer "F.SilkS")
		)
		(fp_line
			(start 0.2286 -1.575054)
			(end 0 -1.272032)
			(stroke
				(width 0.1524)
				(type default)
			)
			(layer "F.SilkS")
		)
		(fp_line
			(start -1.0414 -1.575054)
			(end -0.254 -1.575054)
			(stroke
				(width 0.1524)
				(type default)
			)
			(layer "F.SilkS")
		)
		(fp_line
			(start 0 -1.272032)
			(end -0.254 -1.575054)
			(stroke
				(width 0.1524)
				(type default)
			)
			(layer "F.SilkS")
		)
		(fp_line
			(start 1.0414 1.575054)
			(end -1.0414 1.575054)
			(stroke
				(width 0.1524)
				(type default)
			)
			(layer "F.SilkS")
		)
		(fp_line
			(start -1.0414 1.575054)
			(end -1.0414 -1.575054)
			(stroke
				(width 0.1524)
				(type default)
			)
			(layer "F.SilkS")
		)
		(fp_poly
			(pts
				(xy -2.710688 -0.975106) (xy -3.726688 -1.483106) (xy -3.726688 -0.467106)
			)
			(stroke
				(width 0)
				(type default)
			)
			(fill yes)
			(layer "F.SilkS")
		)
		(fp_line
			(start 1.4478 -1.5748)
			(end 1.4478 -1.2192)
			(stroke
				(width 0.1)
				(type default)
			)
			(layer "F.Fab")
		)
		(fp_line
			(start -1.4478 -1.5748)
			(end 1.4478 -1.5748)
			(stroke
				(width 0.1)
				(type default)
			)
			(layer "F.Fab")
		)
		(fp_line
			(start 2.5654 -1.2192)
			(end 2.5654 1.2192)
			(stroke
				(width 0.1)
				(type default)
			)
			(layer "F.Fab")
		)
		(fp_line
			(start 1.4478 -1.2192)
			(end 2.5654 -1.2192)
			(stroke
				(width 0.1)
				(type default)
			)
			(layer "F.Fab")
		)
		(fp_line
			(start -1.4478 -1.2192)
			(end -1.4478 -1.5748)
			(stroke
				(width 0.1)
				(type default)
			)
			(layer "F.Fab")
		)
		(fp_line
			(start -2.5654 -1.2192)
			(end -1.4478 -1.2192)
			(stroke
				(width 0.1)
				(type default)
			)
			(layer "F.Fab")
		)
		(fp_line
			(start 2.5654 1.2192)
			(end 1.4478 1.2192)
			(stroke
				(width 0.1)
				(type default)
			)
			(layer "F.Fab")
		)
		(fp_line
			(start 1.4478 1.2192)
			(end 1.4478 1.5748)
			(stroke
				(width 0.1)
				(type default)
			)
			(layer "F.Fab")
		)
		(fp_line
			(start -1.4478 1.2192)
			(end -2.5654 1.2192)
			(stroke
				(width 0.1)
				(type default)
			)
			(layer "F.Fab")
		)
		(fp_line
			(start -2.5654 1.2192)
			(end -2.5654 -1.2192)
			(stroke
				(width 0.1)
				(type default)
			)
			(layer "F.Fab")
		)
		(fp_line
			(start 1.4478 1.5748)
			(end -1.4478 1.5748)
			(stroke
				(width 0.1)
				(type default)
			)
			(layer "F.Fab")
		)
		(fp_line
			(start -1.4478 1.5748)
			(end -1.4478 1.2192)
			(stroke
				(width 0.1)
				(type default)
			)
			(layer "F.Fab")
		)
		(fp_poly
			(pts
				(xy -2.710688 -0.975106) (xy -3.726688 -1.483106) (xy -3.726688 -0.467106)
			)
			(stroke
				(width 0)
				(type default)
			)
			(fill yes)
			(layer "F.Fab")
		)
		(pad "1" smd rect
			(at -1.849882 -0.975106)
			(size 0.3556 1.3208)
			(layers "F.Cu" "F.Mask" "F.Paste")
			(net "RST_PEX3_PERST_R_N")
		)
		(pad "2" smd rect
			(at -1.849882 -0.32512)
			(size 0.3556 1.3208)
			(layers "F.Cu" "F.Mask" "F.Paste")
			(net "RST_PEX3_S0_PERST_N")
		)
		(pad "3" smd rect
			(at -1.849882 0.32512)
			(size 0.3556 1.3208)
			(layers "F.Cu" "F.Mask" "F.Paste")
			(net "RST_PEX3_PERST_R_N")
		)
		(pad "4" smd rect
			(at -1.849882 0.975106)
			(size 0.3556 1.3208)
			(layers "F.Cu" "F.Mask" "F.Paste")
			(net "GND")
		)
		(pad "5" smd rect
			(at 1.849882 0.975106)
			(size 0.3556 1.3208)
			(layers "F.Cu" "F.Mask" "F.Paste")
			(net "RST_PEX3_S1_PERST_N")
		)
		(pad "6" smd rect
			(at 1.849882 0.32512)
			(size 0.3556 1.3208)
			(layers "F.Cu" "F.Mask" "F.Paste")
			(net "RST_PEX3_PERST_R_N")
		)
		(pad "7" smd rect
			(at 1.849882 -0.32512)
			(size 0.3556 1.3208)
			(layers "F.Cu" "F.Mask" "F.Paste")
			(net "RST_PEX3_S3_PERST_N")
		)
		(pad "8" smd rect
			(at 1.849882 -0.975106)
			(size 0.3556 1.3208)
			(layers "F.Cu" "F.Mask" "F.Paste")
			(net "P1V8_PEX")
		)
	)
	(footprint ""
		(layer "F.Cu")
		(at 215.006936 -188.652404 90)
		(property "Reference" "R5415"
			(at 0 0 90)
			(layer "F.SilkS")
			(hide yes)
			(effects
				(font
					(size 1.27 1.27)
				)
			)
		)
		(property "Value" ""
			(at 0 0 90)
			(layer "F.Fab")
			(effects
				(font
					(size 1.27 1.27)
				)
			)
		)
		(duplicate_pad_numbers_are_jumpers no)
		(fp_line
			(start 0.7874 -0.4064)
			(end 0.7874 0.4064)
			(stroke
				(width 0.1524)
				(type default)
			)
			(layer "F.SilkS")
		)
		(fp_line
			(start -0.7874 -0.4064)
			(end 0.7874 -0.4064)
			(stroke
				(width 0.1524)
				(type default)
			)
			(layer "F.SilkS")
		)
		(fp_line
			(start 0.7874 0.4064)
			(end -0.7874 0.4064)
			(stroke
				(width 0.1524)
				(type default)
			)
			(layer "F.SilkS")
		)
		(fp_line
			(start -0.7874 0.4064)
			(end -0.7874 -0.4064)
			(stroke
				(width 0.1524)
				(type default)
			)
			(layer "F.SilkS")
		)
		(fp_line
			(start -0.12065 -0.305054)
			(end -0.12065 -0.2794)
			(stroke
				(width 0.1)
				(type default)
			)
			(layer "F.Fab")
		)
		(fp_line
			(start -0.67945 -0.305054)
			(end -0.12065 -0.305054)
			(stroke
				(width 0.1)
				(type default)
			)
			(layer "F.Fab")
		)
		(fp_line
			(start 0.67945 -0.3048)
			(end 0.67945 0.3048)
			(stroke
				(width 0.1)
				(type default)
			)
			(layer "F.Fab")
		)
		(fp_line
			(start 0.12065 -0.3048)
			(end 0.67945 -0.3048)
			(stroke
				(width 0.1)
				(type default)
			)
			(layer "F.Fab")
		)
		(fp_line
			(start 0.12065 -0.2794)
			(end 0.12065 -0.3048)
			(stroke
				(width 0.1)
				(type default)
			)
			(layer "F.Fab")
		)
		(fp_line
			(start -0.12065 -0.2794)
			(end 0.12065 -0.2794)
			(stroke
				(width 0.1)
				(type default)
			)
			(layer "F.Fab")
		)
		(fp_line
			(start 0.120396 0.2794)
			(end -0.12065 0.2794)
			(stroke
				(width 0.1)
				(type default)
			)
			(layer "F.Fab")
		)
		(fp_line
			(start -0.12065 0.2794)
			(end -0.12065 0.3048)
			(stroke
				(width 0.1)
				(type default)
			)
			(layer "F.Fab")
		)
		(fp_line
			(start 0.67945 0.3048)
			(end 0.120396 0.3048)
			(stroke
				(width 0.1)
				(type default)
			)
			(layer "F.Fab")
		)
		(fp_line
			(start 0.120396 0.3048)
			(end 0.120396 0.2794)
			(stroke
				(width 0.1)
				(type default)
			)
			(layer "F.Fab")
		)
		(fp_line
			(start -0.12065 0.3048)
			(end -0.67945 0.3048)
			(stroke
				(width 0.1)
				(type default)
			)
			(layer "F.Fab")
		)
		(fp_line
			(start -0.67945 0.3048)
			(end -0.67945 -0.305054)
			(stroke
				(width 0.1)
				(type default)
			)
			(layer "F.Fab")
		)
		(pad "1" smd circle
			(at -0.40005 0 90)
			(size 0 0)
			(layers "F.Cu" "F.Mask" "F.Paste")
			(net "BIC_SEL_FLASH_SW1_R")
		)
		(pad "2" smd circle
			(at 0.40005 0 90)
			(size 0 0)
			(layers "F.Cu" "F.Mask" "F.Paste")
			(net "GND")
		)
	)
	(footprint ""
		(layer "F.Cu")
		(at 359.156 -177.038)
		(property "Reference" "R4669"
			(at 0 0 0)
			(layer "F.SilkS")
			(hide yes)
			(effects
				(font
					(size 1.27 1.27)
				)
			)
		)
		(property "Value" ""
			(at 0 0 0)
			(layer "F.Fab")
			(effects
				(font
					(size 1.27 1.27)
				)
			)
		)
		(duplicate_pad_numbers_are_jumpers no)
		(fp_line
			(start -0.7874 -0.4064)
			(end 0.7874 -0.4064)
			(stroke
				(width 0.1524)
				(type default)
			)
			(layer "F.SilkS")
		)
		(fp_line
			(start -0.7874 0.4064)
			(end -0.7874 -0.4064)
			(stroke
				(width 0.1524)
				(type default)
			)
			(layer "F.SilkS")
		)
		(fp_line
			(start 0.7874 -0.4064)
			(end 0.7874 0.4064)
			(stroke
				(width 0.1524)
				(type default)
			)
			(layer "F.SilkS")
		)
		(fp_line
			(start 0.7874 0.4064)
			(end -0.7874 0.4064)
			(stroke
				(width 0.1524)
				(type default)
			)
			(layer "F.SilkS")
		)
		(fp_line
			(start -0.67945 -0.305054)
			(end -0.12065 -0.305054)
			(stroke
				(width 0.1)
				(type default)
			)
			(layer "F.Fab")
		)
		(fp_line
			(start -0.67945 0.3048)
			(end -0.67945 -0.305054)
			(stroke
				(width 0.1)
				(type default)
			)
			(layer "F.Fab")
		)
		(fp_line
			(start -0.12065 -0.305054)
			(end -0.12065 -0.2794)
			(stroke
				(width 0.1)
				(type default)
			)
			(layer "F.Fab")
		)
		(fp_line
			(start -0.12065 -0.2794)
			(end 0.12065 -0.2794)
			(stroke
				(width 0.1)
				(type default)
			)
			(layer "F.Fab")
		)
		(fp_line
			(start -0.12065 0.2794)
			(end -0.12065 0.3048)
			(stroke
				(width 0.1)
				(type default)
			)
			(layer "F.Fab")
		)
		(fp_line
			(start -0.12065 0.3048)
			(end -0.67945 0.3048)
			(stroke
				(width 0.1)
				(type default)
			)
			(layer "F.Fab")
		)
		(fp_line
			(start 0.120396 0.2794)
			(end -0.12065 0.2794)
			(stroke
				(width 0.1)
				(type default)
			)
			(layer "F.Fab")
		)
		(fp_line
			(start 0.120396 0.3048)
			(end 0.120396 0.2794)
			(stroke
				(width 0.1)
				(type default)
			)
			(layer "F.Fab")
		)
		(fp_line
			(start 0.12065 -0.3048)
			(end 0.67945 -0.3048)
			(stroke
				(width 0.1)
				(type default)
			)
			(layer "F.Fab")
		)
		(fp_line
			(start 0.12065 -0.2794)
			(end 0.12065 -0.3048)
			(stroke
				(width 0.1)
				(type default)
			)
			(layer "F.Fab")
		)
		(fp_line
			(start 0.67945 -0.3048)
			(end 0.67945 0.3048)
			(stroke
				(width 0.1)
				(type default)
			)
			(layer "F.Fab")
		)
		(fp_line
			(start 0.67945 0.3048)
			(end 0.120396 0.3048)
			(stroke
				(width 0.1)
				(type default)
			)
			(layer "F.Fab")
		)
		(pad "1" smd circle
			(at -0.40005 0)
			(size 0 0)
			(layers "F.Cu" "F.Mask" "F.Paste")
			(net "P3V3_AUX")
		)
		(pad "2" smd circle
			(at 0.40005 0)
			(size 0 0)
			(layers "F.Cu" "F.Mask" "F.Paste")
			(net "RST_PEX_SSD6_PERST_R_N")
		)
	)
	(footprint ""
		(layer "F.Cu")
		(at 9.446768 -152.859994 180)
		(property "Reference" "PR6865"
			(at 0 0 180)
			(layer "F.SilkS")
			(hide yes)
			(effects
				(font
					(size 1.27 1.27)
				)
			)
		)
		(property "Value" ""
			(at 0 0 180)
			(layer "F.Fab")
			(effects
				(font
					(size 1.27 1.27)
				)
			)
		)
		(duplicate_pad_numbers_are_jumpers no)
		(fp_line
			(start 1.2954 0.5842)
			(end -1.2954 0.5842)
			(stroke
				(width 0.1524)
				(type default)
			)
			(layer "F.SilkS")
		)
		(fp_line
			(start 1.2954 -0.5842)
			(end 1.2954 0.5842)
			(stroke
				(width 0.1524)
				(type default)
			)
			(layer "F.SilkS")
		)
		(fp_line
			(start -1.2954 0.5842)
			(end -1.2954 -0.5842)
			(stroke
				(width 0.1524)
				(type default)
			)
			(layer "F.SilkS")
		)
		(fp_line
			(start -1.2954 -0.5842)
			(end 1.2954 -0.5842)
			(stroke
				(width 0.1524)
				(type default)
			)
			(layer "F.SilkS")
		)
		(fp_line
			(start 1.1938 0.4064)
			(end 0.8636 0.4064)
			(stroke
				(width 0.1)
				(type default)
			)
			(layer "F.Fab")
		)
		(fp_line
			(start 1.1938 -0.406654)
			(end 1.1938 0.4064)
			(stroke
				(width 0.1)
				(type default)
			)
			(layer "F.Fab")
		)
		(fp_line
			(start 0.8636 0.4572)
			(end -0.8636 0.4572)
			(stroke
				(width 0.1)
				(type default)
			)
			(layer "F.Fab")
		)
		(fp_line
			(start 0.8636 0.4064)
			(end 0.8636 0.4572)
			(stroke
				(width 0.1)
				(type default)
			)
			(layer "F.Fab")
		)
		(fp_line
			(start 0.8636 -0.406654)
			(end 1.1938 -0.406654)
			(stroke
				(width 0.1)
				(type default)
			)
			(layer "F.Fab")
		)
		(fp_line
			(start 0.8636 -0.4572)
			(end 0.8636 -0.406654)
			(stroke
				(width 0.1)
				(type default)
			)
			(layer "F.Fab")
		)
		(fp_line
			(start -0.8636 0.4572)
			(end -0.8636 0.4318)
			(stroke
				(width 0.1)
				(type default)
			)
			(layer "F.Fab")
		)
		(fp_line
			(start -0.8636 0.4318)
			(end -0.8636 0.4064)
			(stroke
				(width 0.1)
				(type default)
			)
			(layer "F.Fab")
		)
		(fp_line
			(start -0.8636 0.4064)
			(end -1.1938 0.4064)
			(stroke
				(width 0.1)
				(type default)
			)
			(layer "F.Fab")
		)
		(fp_line
			(start -0.8636 -0.406654)
			(end -0.8636 -0.4572)
			(stroke
				(width 0.1)
				(type default)
			)
			(layer "F.Fab")
		)
		(fp_line
			(start -0.8636 -0.4572)
			(end 0.8636 -0.4572)
			(stroke
				(width 0.1)
				(type default)
			)
			(layer "F.Fab")
		)
		(fp_line
			(start -1.1938 0.4064)
			(end -1.1938 -0.406654)
			(stroke
				(width 0.1)
				(type default)
			)
			(layer "F.Fab")
		)
		(fp_line
			(start -1.1938 -0.406654)
			(end -0.8636 -0.406654)
			(stroke
				(width 0.1)
				(type default)
			)
			(layer "F.Fab")
		)
		(pad "1" smd rect
			(at -0.7366 0 90)
			(size 0.7112 0.8128)
			(layers "F.Cu" "F.Mask" "F.Paste")
			(net "P12V_NIC0_CO_AVIN_PD")
		)
		(pad "2" smd rect
			(at 0.7366 0 90)
			(size 0.7112 0.8128)
			(layers "F.Cu" "F.Mask" "F.Paste")
			(net "P12V_AUX")
		)
	)
	(footprint ""
		(layer "F.Cu")
		(at 220.676978 -266.873228 180)
		(property "Reference" "R6131"
			(at 0 0 180)
			(layer "F.SilkS")
			(hide yes)
			(effects
				(font
					(size 1.27 1.27)
				)
			)
		)
		(property "Value" ""
			(at 0 0 180)
			(layer "F.Fab")
			(effects
				(font
					(size 1.27 1.27)
				)
			)
		)
		(duplicate_pad_numbers_are_jumpers no)
		(fp_line
			(start 2.576322 1.1303)
			(end -2.576322 1.1303)
			(stroke
				(width 0.1524)
				(type default)
			)
			(layer "F.SilkS")
		)
		(fp_line
			(start 2.576322 -1.1303)
			(end 2.576322 1.1303)
			(stroke
				(width 0.1524)
				(type default)
			)
			(layer "F.SilkS")
		)
		(fp_line
			(start -2.576322 1.1303)
			(end -2.576322 -1.1303)
			(stroke
				(width 0.1524)
				(type default)
			)
			(layer "F.SilkS")
		)
		(fp_line
			(start -2.576322 -1.1303)
			(end 2.576322 -1.1303)
			(stroke
				(width 0.1524)
				(type default)
			)
			(layer "F.SilkS")
		)
		(fp_line
			(start 1.649984 0.899922)
			(end 1.649984 -0.899922)
			(stroke
				(width 0.1)
				(type default)
			)
			(layer "F.Fab")
		)
		(fp_line
			(start 1.649984 -0.899922)
			(end -1.649984 -0.899922)
			(stroke
				(width 0.1)
				(type default)
			)
			(layer "F.Fab")
		)
		(fp_line
			(start -1.649984 0.899922)
			(end 1.649984 0.899922)
			(stroke
				(width 0.1)
				(type default)
			)
			(layer "F.Fab")
		)
		(fp_line
			(start -1.649984 -0.899922)
			(end -1.649984 0.899922)
			(stroke
				(width 0.1)
				(type default)
			)
			(layer "F.Fab")
		)
		(pad "1A" smd rect
			(at -1.700022 0 180)
			(size 1.4986 2.0066)
			(layers "F.Cu" "F.Mask" "F.Paste")
			(net "P1V25_PEX1")
		)
		(pad "1B" smd rect
			(at -1.077722 0 180)
			(size 0.254 0.508)
			(layers "F.Cu" "F.Mask" "F.Paste")
			(net "P1V25_PEX1")
		)
		(pad "2A" smd rect
			(at 1.700022 0 180)
			(size 1.4986 2.0066)
			(layers "F.Cu" "F.Mask" "F.Paste")
			(net "P1V25_SERDES_VDDPLL_PEX1")
		)
		(pad "2B" smd rect
			(at 1.077722 0 180)
			(size 0.254 0.508)
			(layers "F.Cu" "F.Mask" "F.Paste")
			(net "P1V25_SERDES_VDDPLL_PEX1")
		)
	)
	(footprint ""
		(layer "F.Cu")
		(at 30.153356 -281.789632)
		(property "Reference" "L96"
			(at 0 0 0)
			(layer "F.SilkS")
			(hide yes)
			(effects
				(font
					(size 1.27 1.27)
				)
			)
		)
		(property "Value" ""
			(at 0 0 0)
			(layer "F.Fab")
			(effects
				(font
					(size 1.27 1.27)
				)
			)
		)
		(duplicate_pad_numbers_are_jumpers no)
		(fp_line
			(start -1.63576 -0.8128)
			(end -1.63576 0.8128)
			(stroke
				(width 0.1524)
				(type default)
			)
			(layer "F.SilkS")
		)
		(fp_line
			(start -1.63576 -0.8128)
			(end 1.63576 -0.8128)
			(stroke
				(width 0.1524)
				(type default)
			)
			(layer "F.SilkS")
		)
		(fp_line
			(start 1.63576 -0.8128)
			(end 1.63576 0.8128)
			(stroke
				(width 0.1524)
				(type default)
			)
			(layer "F.SilkS")
		)
		(fp_line
			(start 1.63576 0.8128)
			(end -1.63576 0.8128)
			(stroke
				(width 0.1524)
				(type default)
			)
			(layer "F.SilkS")
		)
		(fp_line
			(start -1.56083 -0.738632)
			(end -1.56083 0.7366)
			(stroke
				(width 0.1)
				(type default)
			)
			(layer "F.Fab")
		)
		(fp_line
			(start -1.56083 0.7366)
			(end -1.524 0.7366)
			(stroke
				(width 0.1)
				(type default)
			)
			(layer "F.Fab")
		)
		(fp_line
			(start -1.524 0.7366)
			(end 1.524 0.7366)
			(stroke
				(width 0.1)
				(type default)
			)
			(layer "F.Fab")
		)
		(fp_line
			(start 1.524 0.7366)
			(end 1.560576 0.7366)
			(stroke
				(width 0.1)
				(type default)
			)
			(layer "F.Fab")
		)
		(fp_line
			(start 1.560576 -0.738632)
			(end -1.56083 -0.738632)
			(stroke
				(width 0.1)
				(type default)
			)
			(layer "F.Fab")
		)
		(fp_line
			(start 1.560576 0.7366)
			(end 1.560576 -0.738632)
			(stroke
				(width 0.1)
				(type default)
			)
			(layer "F.Fab")
		)
		(pad "1" smd rect
			(at -0.94996 0 180)
			(size 1.1176 1.3716)
			(layers "F.Cu" "F.Mask" "F.Paste")
			(net "P1V8_PLL0_PEX0")
		)
		(pad "2" smd rect
			(at 0.94996 0 180)
			(size 1.1176 1.3716)
			(layers "F.Cu" "F.Mask" "F.Paste")
			(net "SYSPLL_VDDA18_PEX0")
		)
	)
	(footprint ""
		(layer "F.Cu")
		(at 32.31769 -113.558574 -90)
		(property "Reference" "C3998"
			(at 0 0 270)
			(layer "F.SilkS")
			(hide yes)
			(effects
				(font
					(size 1.27 1.27)
				)
			)
		)
		(property "Value" ""
			(at 0 0 270)
			(layer "F.Fab")
			(effects
				(font
					(size 1.27 1.27)
				)
			)
		)
		(duplicate_pad_numbers_are_jumpers no)
		(fp_line
			(start -0.7874 0.4064)
			(end -0.7874 -0.4064)
			(stroke
				(width 0.1524)
				(type default)
			)
			(layer "F.SilkS")
		)
		(fp_line
			(start 0.7874 0.4064)
			(end -0.7874 0.4064)
			(stroke
				(width 0.1524)
				(type default)
			)
			(layer "F.SilkS")
		)
		(fp_line
			(start -0.7874 -0.4064)
			(end 0.7874 -0.4064)
			(stroke
				(width 0.1524)
				(type default)
			)
			(layer "F.SilkS")
		)
		(fp_line
			(start 0.7874 -0.4064)
			(end 0.7874 0.4064)
			(stroke
				(width 0.1524)
				(type default)
			)
			(layer "F.SilkS")
		)
		(fp_line
			(start -0.67945 0.3048)
			(end -0.67945 -0.305054)
			(stroke
				(width 0.1)
				(type default)
			)
			(layer "F.Fab")
		)
		(fp_line
			(start -0.12065 0.3048)
			(end -0.67945 0.3048)
			(stroke
				(width 0.1)
				(type default)
			)
			(layer "F.Fab")
		)
		(fp_line
			(start 0.120396 0.3048)
			(end 0.120396 0.2794)
			(stroke
				(width 0.1)
				(type default)
			)
			(layer "F.Fab")
		)
		(fp_line
			(start 0.67945 0.3048)
			(end 0.120396 0.3048)
			(stroke
				(width 0.1)
				(type default)
			)
			(layer "F.Fab")
		)
		(fp_line
			(start -0.12065 0.2794)
			(end -0.12065 0.3048)
			(stroke
				(width 0.1)
				(type default)
			)
			(layer "F.Fab")
		)
		(fp_line
			(start 0.120396 0.2794)
			(end -0.12065 0.2794)
			(stroke
				(width 0.1)
				(type default)
			)
			(layer "F.Fab")
		)
		(fp_line
			(start -0.12065 -0.2794)
			(end 0.12065 -0.2794)
			(stroke
				(width 0.1)
				(type default)
			)
			(layer "F.Fab")
		)
		(fp_line
			(start 0.12065 -0.2794)
			(end 0.12065 -0.3048)
			(stroke
				(width 0.1)
				(type default)
			)
			(layer "F.Fab")
		)
		(fp_line
			(start 0.12065 -0.3048)
			(end 0.67945 -0.3048)
			(stroke
				(width 0.1)
				(type default)
			)
			(layer "F.Fab")
		)
		(fp_line
			(start 0.67945 -0.3048)
			(end 0.67945 0.3048)
			(stroke
				(width 0.1)
				(type default)
			)
			(layer "F.Fab")
		)
		(fp_line
			(start -0.67945 -0.305054)
			(end -0.12065 -0.305054)
			(stroke
				(width 0.1)
				(type default)
			)
			(layer "F.Fab")
		)
		(fp_line
			(start -0.12065 -0.305054)
			(end -0.12065 -0.2794)
			(stroke
				(width 0.1)
				(type default)
			)
			(layer "F.Fab")
		)
		(pad "1" smd circle
			(at -0.40005 0 270)
			(size 0 0)
			(layers "F.Cu" "F.Mask" "F.Paste")
			(net "PRSNT_NIC0_R_N")
		)
		(pad "2" smd circle
			(at 0.40005 0 270)
			(size 0 0)
			(layers "F.Cu" "F.Mask" "F.Paste")
			(net "GND")
		)
	)
	(footprint ""
		(layer "F.Cu")
		(at 16.820896 -119.140986 90)
		(property "Reference" "PC660"
			(at 0 0 90)
			(layer "F.SilkS")
			(hide yes)
			(effects
				(font
					(size 1.27 1.27)
				)
			)
		)
		(property "Value" ""
			(at 0 0 90)
			(layer "F.Fab")
			(effects
				(font
					(size 1.27 1.27)
				)
			)
		)
		(duplicate_pad_numbers_are_jumpers no)
		(fp_line
			(start 0.7874 -0.4064)
			(end 0.7874 0.4064)
			(stroke
				(width 0.1524)
				(type default)
			)
			(layer "F.SilkS")
		)
		(fp_line
			(start -0.7874 -0.4064)
			(end 0.7874 -0.4064)
			(stroke
				(width 0.1524)
				(type default)
			)
			(layer "F.SilkS")
		)
		(fp_line
			(start 0.7874 0.4064)
			(end -0.7874 0.4064)
			(stroke
				(width 0.1524)
				(type default)
			)
			(layer "F.SilkS")
		)
		(fp_line
			(start -0.7874 0.4064)
			(end -0.7874 -0.4064)
			(stroke
				(width 0.1524)
				(type default)
			)
			(layer "F.SilkS")
		)
		(fp_line
			(start -0.12065 -0.305054)
			(end -0.12065 -0.2794)
			(stroke
				(width 0.1)
				(type default)
			)
			(layer "F.Fab")
		)
		(fp_line
			(start -0.67945 -0.305054)
			(end -0.12065 -0.305054)
			(stroke
				(width 0.1)
				(type default)
			)
			(layer "F.Fab")
		)
		(fp_line
			(start 0.67945 -0.3048)
			(end 0.67945 0.3048)
			(stroke
				(width 0.1)
				(type default)
			)
			(layer "F.Fab")
		)
		(fp_line
			(start 0.12065 -0.3048)
			(end 0.67945 -0.3048)
			(stroke
				(width 0.1)
				(type default)
			)
			(layer "F.Fab")
		)
		(fp_line
			(start 0.12065 -0.2794)
			(end 0.12065 -0.3048)
			(stroke
				(width 0.1)
				(type default)
			)
			(layer "F.Fab")
		)
		(fp_line
			(start -0.12065 -0.2794)
			(end 0.12065 -0.2794)
			(stroke
				(width 0.1)
				(type default)
			)
			(layer "F.Fab")
		)
		(fp_line
			(start 0.120396 0.2794)
			(end -0.12065 0.2794)
			(stroke
				(width 0.1)
				(type default)
			)
			(layer "F.Fab")
		)
		(fp_line
			(start -0.12065 0.2794)
			(end -0.12065 0.3048)
			(stroke
				(width 0.1)
				(type default)
			)
			(layer "F.Fab")
		)
		(fp_line
			(start 0.67945 0.3048)
			(end 0.120396 0.3048)
			(stroke
				(width 0.1)
				(type default)
			)
			(layer "F.Fab")
		)
		(fp_line
			(start 0.120396 0.3048)
			(end 0.120396 0.2794)
			(stroke
				(width 0.1)
				(type default)
			)
			(layer "F.Fab")
		)
		(fp_line
			(start -0.12065 0.3048)
			(end -0.67945 0.3048)
			(stroke
				(width 0.1)
				(type default)
			)
			(layer "F.Fab")
		)
		(fp_line
			(start -0.67945 0.3048)
			(end -0.67945 -0.305054)
			(stroke
				(width 0.1)
				(type default)
			)
			(layer "F.Fab")
		)
		(pad "1" smd circle
			(at -0.40005 0 90)
			(size 0 0)
			(layers "F.Cu" "F.Mask" "F.Paste")
			(net "P3V3_NIC0_CO_GATE")
		)
		(pad "2" smd circle
			(at 0.40005 0 90)
			(size 0 0)
			(layers "F.Cu" "F.Mask" "F.Paste")
			(net "GND")
		)
	)
	(footprint ""
		(layer "F.Cu")
		(at 279.14727 -21.37156)
		(property "Reference" "C3938"
			(at 0 0 0)
			(layer "F.SilkS")
			(hide yes)
			(effects
				(font
					(size 1.27 1.27)
				)
			)
		)
		(property "Value" ""
			(at 0 0 0)
			(layer "F.Fab")
			(effects
				(font
					(size 1.27 1.27)
				)
			)
		)
		(duplicate_pad_numbers_are_jumpers no)
		(fp_line
			(start -0.7874 -0.4064)
			(end 0.7874 -0.4064)
			(stroke
				(width 0.1524)
				(type default)
			)
			(layer "F.SilkS")
		)
		(fp_line
			(start -0.7874 0.4064)
			(end -0.7874 -0.4064)
			(stroke
				(width 0.1524)
				(type default)
			)
			(layer "F.SilkS")
		)
		(fp_line
			(start 0.7874 -0.4064)
			(end 0.7874 0.4064)
			(stroke
				(width 0.1524)
				(type default)
			)
			(layer "F.SilkS")
		)
		(fp_line
			(start 0.7874 0.4064)
			(end -0.7874 0.4064)
			(stroke
				(width 0.1524)
				(type default)
			)
			(layer "F.SilkS")
		)
		(fp_line
			(start -0.67945 -0.305054)
			(end -0.12065 -0.305054)
			(stroke
				(width 0.1)
				(type default)
			)
			(layer "F.Fab")
		)
		(fp_line
			(start -0.67945 0.3048)
			(end -0.67945 -0.305054)
			(stroke
				(width 0.1)
				(type default)
			)
			(layer "F.Fab")
		)
		(fp_line
			(start -0.12065 -0.305054)
			(end -0.12065 -0.2794)
			(stroke
				(width 0.1)
				(type default)
			)
			(layer "F.Fab")
		)
		(fp_line
			(start -0.12065 -0.2794)
			(end 0.12065 -0.2794)
			(stroke
				(width 0.1)
				(type default)
			)
			(layer "F.Fab")
		)
		(fp_line
			(start -0.12065 0.2794)
			(end -0.12065 0.3048)
			(stroke
				(width 0.1)
				(type default)
			)
			(layer "F.Fab")
		)
		(fp_line
			(start -0.12065 0.3048)
			(end -0.67945 0.3048)
			(stroke
				(width 0.1)
				(type default)
			)
			(layer "F.Fab")
		)
		(fp_line
			(start 0.120396 0.2794)
			(end -0.12065 0.2794)
			(stroke
				(width 0.1)
				(type default)
			)
			(layer "F.Fab")
		)
		(fp_line
			(start 0.120396 0.3048)
			(end 0.120396 0.2794)
			(stroke
				(width 0.1)
				(type default)
			)
			(layer "F.Fab")
		)
		(fp_line
			(start 0.12065 -0.3048)
			(end 0.67945 -0.3048)
			(stroke
				(width 0.1)
				(type default)
			)
			(layer "F.Fab")
		)
		(fp_line
			(start 0.12065 -0.2794)
			(end 0.12065 -0.3048)
			(stroke
				(width 0.1)
				(type default)
			)
			(layer "F.Fab")
		)
		(fp_line
			(start 0.67945 -0.3048)
			(end 0.67945 0.3048)
			(stroke
				(width 0.1)
				(type default)
			)
			(layer "F.Fab")
		)
		(fp_line
			(start 0.67945 0.3048)
			(end 0.120396 0.3048)
			(stroke
				(width 0.1)
				(type default)
			)
			(layer "F.Fab")
		)
		(pad "1" smd circle
			(at -0.40005 0)
			(size 0 0)
			(layers "F.Cu" "F.Mask" "F.Paste")
			(net "P12V_SSD9")
		)
		(pad "2" smd circle
			(at 0.40005 0)
			(size 0 0)
			(layers "F.Cu" "F.Mask" "F.Paste")
			(net "GND")
		)
	)
	(footprint ""
		(layer "F.Cu")
		(at 329.438 -85.598 180)
		(property "Reference" "R6260"
			(at 0 0 180)
			(layer "F.SilkS")
			(hide yes)
			(effects
				(font
					(size 1.27 1.27)
				)
			)
		)
		(property "Value" ""
			(at 0 0 180)
			(layer "F.Fab")
			(effects
				(font
					(size 1.27 1.27)
				)
			)
		)
		(duplicate_pad_numbers_are_jumpers no)
		(fp_line
			(start 0.7874 0.4064)
			(end -0.7874 0.4064)
			(stroke
				(width 0.1524)
				(type default)
			)
			(layer "F.SilkS")
		)
		(fp_line
			(start 0.7874 -0.4064)
			(end 0.7874 0.4064)
			(stroke
				(width 0.1524)
				(type default)
			)
			(layer "F.SilkS")
		)
		(fp_line
			(start -0.7874 0.4064)
			(end -0.7874 -0.4064)
			(stroke
				(width 0.1524)
				(type default)
			)
			(layer "F.SilkS")
		)
		(fp_line
			(start -0.7874 -0.4064)
			(end 0.7874 -0.4064)
			(stroke
				(width 0.1524)
				(type default)
			)
			(layer "F.SilkS")
		)
		(fp_line
			(start 0.67945 0.3048)
			(end 0.120396 0.3048)
			(stroke
				(width 0.1)
				(type default)
			)
			(layer "F.Fab")
		)
		(fp_line
			(start 0.67945 -0.3048)
			(end 0.67945 0.3048)
			(stroke
				(width 0.1)
				(type default)
			)
			(layer "F.Fab")
		)
		(fp_line
			(start 0.12065 -0.2794)
			(end 0.12065 -0.3048)
			(stroke
				(width 0.1)
				(type default)
			)
			(layer "F.Fab")
		)
		(fp_line
			(start 0.12065 -0.3048)
			(end 0.67945 -0.3048)
			(stroke
				(width 0.1)
				(type default)
			)
			(layer "F.Fab")
		)
		(fp_line
			(start 0.120396 0.3048)
			(end 0.120396 0.2794)
			(stroke
				(width 0.1)
				(type default)
			)
			(layer "F.Fab")
		)
		(fp_line
			(start 0.120396 0.2794)
			(end -0.12065 0.2794)
			(stroke
				(width 0.1)
				(type default)
			)
			(layer "F.Fab")
		)
		(fp_line
			(start -0.12065 0.3048)
			(end -0.67945 0.3048)
			(stroke
				(width 0.1)
				(type default)
			)
			(layer "F.Fab")
		)
		(fp_line
			(start -0.12065 0.2794)
			(end -0.12065 0.3048)
			(stroke
				(width 0.1)
				(type default)
			)
			(layer "F.Fab")
		)
		(fp_line
			(start -0.12065 -0.2794)
			(end 0.12065 -0.2794)
			(stroke
				(width 0.1)
				(type default)
			)
			(layer "F.Fab")
		)
		(fp_line
			(start -0.12065 -0.305054)
			(end -0.12065 -0.2794)
			(stroke
				(width 0.1)
				(type default)
			)
			(layer "F.Fab")
		)
		(fp_line
			(start -0.67945 0.3048)
			(end -0.67945 -0.305054)
			(stroke
				(width 0.1)
				(type default)
			)
			(layer "F.Fab")
		)
		(fp_line
			(start -0.67945 -0.305054)
			(end -0.12065 -0.305054)
			(stroke
				(width 0.1)
				(type default)
			)
			(layer "F.Fab")
		)
		(pad "1" smd circle
			(at -0.40005 0 180)
			(size 0 0)
			(layers "F.Cu" "F.Mask" "F.Paste")
			(net "SMB_ISO_CB_SDA")
		)
		(pad "2" smd circle
			(at 0.40005 0 180)
			(size 0 0)
			(layers "F.Cu" "F.Mask" "F.Paste")
			(net "P3V3")
		)
	)
	(footprint ""
		(layer "F.Cu")
		(at 412.378652 -356.244906 90)
		(property "Reference" "C2443"
			(at 0 0 90)
			(layer "F.SilkS")
			(hide yes)
			(effects
				(font
					(size 1.27 1.27)
				)
			)
		)
		(property "Value" ""
			(at 0 0 90)
			(layer "F.Fab")
			(effects
				(font
					(size 1.27 1.27)
				)
			)
		)
		(duplicate_pad_numbers_are_jumpers no)
		(fp_line
			(start 0.299974 -0.150114)
			(end 0.299974 0.150114)
			(stroke
				(width 0.1)
				(type default)
			)
			(layer "F.Fab")
		)
		(fp_line
			(start -0.299974 -0.150114)
			(end 0.299974 -0.150114)
			(stroke
				(width 0.1)
				(type default)
			)
			(layer "F.Fab")
		)
		(fp_line
			(start 0.299974 0.150114)
			(end -0.299974 0.150114)
			(stroke
				(width 0.1)
				(type default)
			)
			(layer "F.Fab")
		)
		(fp_line
			(start -0.299974 0.150114)
			(end -0.299974 -0.150114)
			(stroke
				(width 0.1)
				(type default)
			)
			(layer "F.Fab")
		)
		(pad "1" smd rect
			(at -0.2667 0 90)
			(size 0.3048 0.381)
			(layers "F.Cu" "F.Mask" "F.Paste")
			(net "P5E_PEX3_STN4_TX_DP<77>")
		)
		(pad "2" smd rect
			(at 0.2667 0 90)
			(size 0.3048 0.381)
			(layers "F.Cu" "F.Mask" "F.Paste")
			(net "P5E_PEX3_STN4_TX_C_DP<77>")
		)
	)
	(footprint ""
		(layer "F.Cu")
		(at 26.930096 -284.404308 -90)
		(property "Reference" "C3053"
			(at 0 0 270)
			(layer "F.SilkS")
			(hide yes)
			(effects
				(font
					(size 1.27 1.27)
				)
			)
		)
		(property "Value" ""
			(at 0 0 270)
			(layer "F.Fab")
			(effects
				(font
					(size 1.27 1.27)
				)
			)
		)
		(duplicate_pad_numbers_are_jumpers no)
		(fp_line
			(start -1.2954 0.5842)
			(end -1.2954 -0.5842)
			(stroke
				(width 0.1524)
				(type default)
			)
			(layer "F.SilkS")
		)
		(fp_line
			(start 1.2954 0.5842)
			(end -1.2954 0.5842)
			(stroke
				(width 0.1524)
				(type default)
			)
			(layer "F.SilkS")
		)
		(fp_line
			(start -1.2954 -0.5842)
			(end 1.2954 -0.5842)
			(stroke
				(width 0.1524)
				(type default)
			)
			(layer "F.SilkS")
		)
		(fp_line
			(start 1.2954 -0.5842)
			(end 1.2954 0.5842)
			(stroke
				(width 0.1524)
				(type default)
			)
			(layer "F.SilkS")
		)
		(fp_line
			(start -0.8636 0.4572)
			(end -0.8636 0.4064)
			(stroke
				(width 0.1)
				(type default)
			)
			(layer "F.Fab")
		)
		(fp_line
			(start 0.8636 0.4572)
			(end -0.8636 0.4572)
			(stroke
				(width 0.1)
				(type default)
			)
			(layer "F.Fab")
		)
		(fp_line
			(start -1.1938 0.4064)
			(end -1.1938 -0.4064)
			(stroke
				(width 0.1)
				(type default)
			)
			(layer "F.Fab")
		)
		(fp_line
			(start -0.8636 0.4064)
			(end -1.1938 0.4064)
			(stroke
				(width 0.1)
				(type default)
			)
			(layer "F.Fab")
		)
		(fp_line
			(start 0.8636 0.4064)
			(end 0.8636 0.4572)
			(stroke
				(width 0.1)
				(type default)
			)
			(layer "F.Fab")
		)
		(fp_line
			(start 1.1938 0.4064)
			(end 0.8636 0.4064)
			(stroke
				(width 0.1)
				(type default)
			)
			(layer "F.Fab")
		)
		(fp_line
			(start -1.1938 -0.4064)
			(end -0.8636 -0.4064)
			(stroke
				(width 0.1)
				(type default)
			)
			(layer "F.Fab")
		)
		(fp_line
			(start -0.8636 -0.4064)
			(end -0.8636 -0.4572)
			(stroke
				(width 0.1)
				(type default)
			)
			(layer "F.Fab")
		)
		(fp_line
			(start 0.8636 -0.4064)
			(end 1.1938 -0.4064)
			(stroke
				(width 0.1)
				(type default)
			)
			(layer "F.Fab")
		)
		(fp_line
			(start 1.1938 -0.4064)
			(end 1.1938 0.4064)
			(stroke
				(width 0.1)
				(type default)
			)
			(layer "F.Fab")
		)
		(fp_line
			(start -0.8636 -0.4572)
			(end 0.8636 -0.4572)
			(stroke
				(width 0.1)
				(type default)
			)
			(layer "F.Fab")
		)
		(fp_line
			(start 0.8636 -0.4572)
			(end 0.8636 -0.4064)
			(stroke
				(width 0.1)
				(type default)
			)
			(layer "F.Fab")
		)
		(pad "1" smd rect
			(at -0.7366 0 180)
			(size 0.7112 0.8128)
			(layers "F.Cu" "F.Mask" "F.Paste")
			(net "P1V8_PLL0_PEX0")
		)
		(pad "2" smd rect
			(at 0.7366 0 180)
			(size 0.7112 0.8128)
			(layers "F.Cu" "F.Mask" "F.Paste")
			(net "GND")
		)
	)
	(footprint ""
		(layer "F.Cu")
		(at 368.08283 -225.49993 180)
		(property "Reference" "JPEX3"
			(at 1.66243 -8.7884 0)
			(unlocked yes)
			(layer "F.SilkS")
			(effects
				(font
					(size 0.7874 0.5842)
					(thickness 0.1524)
				)
				(justify left)
			)
		)
		(property "Value" ""
			(at 0 0 180)
			(layer "F.Fab")
			(effects
				(font
					(size 1.27 1.27)
				)
			)
		)
		(duplicate_pad_numbers_are_jumpers no)
		(fp_line
			(start 12.46505 7.649972)
			(end -12.46505 7.649972)
			(stroke
				(width 0.1524)
				(type default)
			)
			(layer "F.SilkS")
		)
		(fp_line
			(start 12.46505 -7.649972)
			(end 12.46505 7.649972)
			(stroke
				(width 0.1524)
				(type default)
			)
			(layer "F.SilkS")
		)
		(fp_line
			(start 6.945122 7.649972)
			(end -6.945122 7.649972)
			(stroke
				(width 0.1524)
				(type default)
			)
			(layer "F.SilkS")
		)
		(fp_line
			(start 6.945122 -7.649972)
			(end 6.945122 7.649972)
			(stroke
				(width 0.1524)
				(type default)
			)
			(layer "F.SilkS")
		)
		(fp_line
			(start 6.945122 -7.649972)
			(end 0 -7.649972)
			(stroke
				(width 0.1524)
				(type default)
			)
			(layer "F.SilkS")
		)
		(fp_line
			(start 0 -7.649972)
			(end 12.46505 -7.649972)
			(stroke
				(width 0.1524)
				(type default)
			)
			(layer "F.SilkS")
		)
		(fp_line
			(start -6.945122 -7.649972)
			(end 0 -7.649972)
			(stroke
				(width 0.1524)
				(type default)
			)
			(layer "F.SilkS")
		)
		(fp_line
			(start -6.945122 -7.649972)
			(end -6.945122 7.649972)
			(stroke
				(width 0.1524)
				(type default)
			)
			(layer "F.SilkS")
		)
		(fp_line
			(start -12.46505 7.649972)
			(end -12.46505 5.641594)
			(stroke
				(width 0.1524)
				(type default)
			)
			(layer "F.SilkS")
		)
		(fp_line
			(start -12.46505 4.45262)
			(end -12.46505 4.123436)
			(stroke
				(width 0.1524)
				(type default)
			)
			(layer "F.SilkS")
		)
		(fp_line
			(start -12.46505 3.04419)
			(end -12.46505 -7.649972)
			(stroke
				(width 0.1524)
				(type default)
			)
			(layer "F.SilkS")
		)
		(fp_line
			(start -12.46505 -7.649972)
			(end 0 -7.649972)
			(stroke
				(width 0.1524)
				(type default)
			)
			(layer "F.SilkS")
		)
		(fp_poly
			(pts
				(xy -7.112 -4.445) (xy -8.128 -4.953) (xy -8.128 -3.937)
			)
			(stroke
				(width 0)
				(type default)
			)
			(fill yes)
			(layer "F.SilkS")
		)
		(fp_line
			(start 6.945122 7.649972)
			(end -6.945122 7.649972)
			(stroke
				(width 0.1)
				(type default)
			)
			(layer "F.Fab")
		)
		(fp_line
			(start 6.945122 -7.649972)
			(end 6.945122 7.649972)
			(stroke
				(width 0.1)
				(type default)
			)
			(layer "F.Fab")
		)
		(fp_line
			(start -6.945122 7.649972)
			(end -6.945122 -7.649972)
			(stroke
				(width 0.1)
				(type default)
			)
			(layer "F.Fab")
		)
		(fp_line
			(start -6.945122 -7.649972)
			(end 6.945122 -7.649972)
			(stroke
				(width 0.1)
				(type default)
			)
			(layer "F.Fab")
		)
		(fp_poly
			(pts
				(xy -7.112 -4.445) (xy -8.128 -4.953) (xy -8.128 -3.937)
			)
			(stroke
				(width 0)
				(type default)
			)
			(fill yes)
			(layer "F.Fab")
		)
		(fp_text user "9"
			(at 7.51713 4.1656 90)
			(unlocked yes)
			(layer "F.SilkS")
			(effects
				(font
					(size 0.7874 0.5842)
					(thickness 0.1524)
				)
				(justify left)
			)
		)
		(fp_text user "16"
			(at 7.49173 -5.2324 90)
			(unlocked yes)
			(layer "F.SilkS")
			(effects
				(font
					(size 0.7874 0.5842)
					(thickness 0.1524)
				)
				(justify left)
			)
		)
		(fp_text user "8"
			(at -7.77367 4.2164 90)
			(unlocked yes)
			(layer "F.SilkS")
			(effects
				(font
					(size 0.7874 0.5842)
					(thickness 0.1524)
				)
				(justify left)
			)
		)
		(fp_text user "9"
			(at 7.51713 4.1656 90)
			(unlocked yes)
			(layer "F.Fab")
			(effects
				(font
					(size 0.7874 0.5842)
					(thickness 0.1524)
				)
				(justify left)
			)
		)
		(fp_text user "16"
			(at 7.49173 -5.2324 90)
			(unlocked yes)
			(layer "F.Fab")
			(effects
				(font
					(size 0.7874 0.5842)
					(thickness 0.1524)
				)
				(justify left)
			)
		)
		(fp_text user "8"
			(at -7.77367 4.2164 90)
			(unlocked yes)
			(layer "F.Fab")
			(effects
				(font
					(size 0.7874 0.5842)
					(thickness 0.1524)
				)
				(justify left)
			)
		)
		(pad "1" smd rect
			(at -4.800092 -4.445 90)
			(size 0.508 1.524)
			(layers "F.Cu" "F.Mask" "F.Paste")
			(net "SPI_PEX3_SDIO3_R1")
		)
		(pad "2" smd rect
			(at -4.800092 -3.175 90)
			(size 0.508 1.524)
			(layers "F.Cu" "F.Mask" "F.Paste")
			(net "P1V8_PEX")
		)
		(pad "3" smd rect
			(at -4.800092 -1.905 90)
			(size 0.508 1.524)
			(layers "F.Cu" "F.Mask" "F.Paste")
			(net "SPI_PEX3_RST_R_N")
		)
		(pad "4" smd rect
			(at -4.800092 -0.635 90)
			(size 0.508 1.524)
			(layers "F.Cu" "F.Mask" "F.Paste")
			(net "Net_2705")
		)
		(pad "5" smd rect
			(at -4.800092 0.635 90)
			(size 0.508 1.524)
			(layers "F.Cu" "F.Mask" "F.Paste")
			(net "Net_2704")
		)
		(pad "6" smd rect
			(at -4.800092 1.905 90)
			(size 0.508 1.524)
			(layers "F.Cu" "F.Mask" "F.Paste")
			(net "Net_2703")
		)
		(pad "7" smd rect
			(at -4.800092 3.175 90)
			(size 0.508 1.524)
			(layers "F.Cu" "F.Mask" "F.Paste")
			(net "SPI_PEX3_CS_MUX_R_N")
		)
		(pad "8" smd rect
			(at -4.800092 4.445 90)
			(size 0.508 1.524)
			(layers "F.Cu" "F.Mask" "F.Paste")
			(net "SPI_PEX3_SDIO1_MUX_R")
		)
		(pad "9" smd rect
			(at 4.800092 4.445 90)
			(size 0.508 1.524)
			(layers "F.Cu" "F.Mask" "F.Paste")
			(net "SPI_PEX3_SDIO2_R1")
		)
		(pad "10" smd rect
			(at 4.800092 3.175 90)
			(size 0.508 1.524)
			(layers "F.Cu" "F.Mask" "F.Paste")
			(net "GND")
		)
		(pad "11" smd rect
			(at 4.800092 1.905 90)
			(size 0.508 1.524)
			(layers "F.Cu" "F.Mask" "F.Paste")
			(net "Net_2706")
		)
		(pad "12" smd rect
			(at 4.800092 0.635 90)
			(size 0.508 1.524)
			(layers "F.Cu" "F.Mask" "F.Paste")
			(net "Net_2707")
		)
		(pad "13" smd rect
			(at 4.800092 -0.635 90)
			(size 0.508 1.524)
			(layers "F.Cu" "F.Mask" "F.Paste")
			(net "Net_2708")
		)
		(pad "14" smd rect
			(at 4.800092 -1.905 90)
			(size 0.508 1.524)
			(layers "F.Cu" "F.Mask" "F.Paste")
			(net "Net_2709")
		)
		(pad "15" smd rect
			(at 4.800092 -3.175 90)
			(size 0.508 1.524)
			(layers "F.Cu" "F.Mask" "F.Paste")
			(net "SPI_PEX3_SDIO0_MUX_R")
		)
		(pad "16" smd rect
			(at 4.800092 -4.445 90)
			(size 0.508 1.524)
			(layers "F.Cu" "F.Mask" "F.Paste")
			(net "SPI_PEX3_CLK_MUX_R")
		)
	)
	(footprint ""
		(layer "F.Cu")
		(at 447.275712 -122.525028)
		(property "Reference" "PC492"
			(at 0 0 0)
			(layer "F.SilkS")
			(hide yes)
			(effects
				(font
					(size 1.27 1.27)
				)
			)
		)
		(property "Value" ""
			(at 0 0 0)
			(layer "F.Fab")
			(effects
				(font
					(size 1.27 1.27)
				)
			)
		)
		(duplicate_pad_numbers_are_jumpers no)
		(fp_line
			(start -0.7874 -0.4064)
			(end 0.7874 -0.4064)
			(stroke
				(width 0.1524)
				(type default)
			)
			(layer "F.SilkS")
		)
		(fp_line
			(start -0.7874 0.4064)
			(end -0.7874 -0.4064)
			(stroke
				(width 0.1524)
				(type default)
			)
			(layer "F.SilkS")
		)
		(fp_line
			(start 0.7874 -0.4064)
			(end 0.7874 0.4064)
			(stroke
				(width 0.1524)
				(type default)
			)
			(layer "F.SilkS")
		)
		(fp_line
			(start 0.7874 0.4064)
			(end -0.7874 0.4064)
			(stroke
				(width 0.1524)
				(type default)
			)
			(layer "F.SilkS")
		)
		(fp_line
			(start -0.67945 -0.305054)
			(end -0.12065 -0.305054)
			(stroke
				(width 0.1)
				(type default)
			)
			(layer "F.Fab")
		)
		(fp_line
			(start -0.67945 0.3048)
			(end -0.67945 -0.305054)
			(stroke
				(width 0.1)
				(type default)
			)
			(layer "F.Fab")
		)
		(fp_line
			(start -0.12065 -0.305054)
			(end -0.12065 -0.2794)
			(stroke
				(width 0.1)
				(type default)
			)
			(layer "F.Fab")
		)
		(fp_line
			(start -0.12065 -0.2794)
			(end 0.12065 -0.2794)
			(stroke
				(width 0.1)
				(type default)
			)
			(layer "F.Fab")
		)
		(fp_line
			(start -0.12065 0.2794)
			(end -0.12065 0.3048)
			(stroke
				(width 0.1)
				(type default)
			)
			(layer "F.Fab")
		)
		(fp_line
			(start -0.12065 0.3048)
			(end -0.67945 0.3048)
			(stroke
				(width 0.1)
				(type default)
			)
			(layer "F.Fab")
		)
		(fp_line
			(start 0.120396 0.2794)
			(end -0.12065 0.2794)
			(stroke
				(width 0.1)
				(type default)
			)
			(layer "F.Fab")
		)
		(fp_line
			(start 0.120396 0.3048)
			(end 0.120396 0.2794)
			(stroke
				(width 0.1)
				(type default)
			)
			(layer "F.Fab")
		)
		(fp_line
			(start 0.12065 -0.3048)
			(end 0.67945 -0.3048)
			(stroke
				(width 0.1)
				(type default)
			)
			(layer "F.Fab")
		)
		(fp_line
			(start 0.12065 -0.2794)
			(end 0.12065 -0.3048)
			(stroke
				(width 0.1)
				(type default)
			)
			(layer "F.Fab")
		)
		(fp_line
			(start 0.67945 -0.3048)
			(end 0.67945 0.3048)
			(stroke
				(width 0.1)
				(type default)
			)
			(layer "F.Fab")
		)
		(fp_line
			(start 0.67945 0.3048)
			(end 0.120396 0.3048)
			(stroke
				(width 0.1)
				(type default)
			)
			(layer "F.Fab")
		)
		(pad "1" smd circle
			(at -0.40005 0)
			(size 0 0)
			(layers "F.Cu" "F.Mask" "F.Paste")
			(net "P5V_AUX")
		)
		(pad "2" smd circle
			(at 0.40005 0)
			(size 0 0)
			(layers "F.Cu" "F.Mask" "F.Paste")
			(net "GND")
		)
	)
	(footprint ""
		(layer "F.Cu")
		(at 29.883608 -61.487812 180)
		(property "Reference" "R5839"
			(at 0 0 180)
			(layer "F.SilkS")
			(hide yes)
			(effects
				(font
					(size 1.27 1.27)
				)
			)
		)
		(property "Value" ""
			(at 0 0 180)
			(layer "F.Fab")
			(effects
				(font
					(size 1.27 1.27)
				)
			)
		)
		(duplicate_pad_numbers_are_jumpers no)
		(fp_line
			(start 0.7874 0.4064)
			(end -0.7874 0.4064)
			(stroke
				(width 0.1524)
				(type default)
			)
			(layer "F.SilkS")
		)
		(fp_line
			(start 0.7874 -0.4064)
			(end 0.7874 0.4064)
			(stroke
				(width 0.1524)
				(type default)
			)
			(layer "F.SilkS")
		)
		(fp_line
			(start -0.7874 0.4064)
			(end -0.7874 -0.4064)
			(stroke
				(width 0.1524)
				(type default)
			)
			(layer "F.SilkS")
		)
		(fp_line
			(start -0.7874 -0.4064)
			(end 0.7874 -0.4064)
			(stroke
				(width 0.1524)
				(type default)
			)
			(layer "F.SilkS")
		)
		(fp_line
			(start 0.67945 0.3048)
			(end 0.120396 0.3048)
			(stroke
				(width 0.1)
				(type default)
			)
			(layer "F.Fab")
		)
		(fp_line
			(start 0.67945 -0.3048)
			(end 0.67945 0.3048)
			(stroke
				(width 0.1)
				(type default)
			)
			(layer "F.Fab")
		)
		(fp_line
			(start 0.12065 -0.2794)
			(end 0.12065 -0.3048)
			(stroke
				(width 0.1)
				(type default)
			)
			(layer "F.Fab")
		)
		(fp_line
			(start 0.12065 -0.3048)
			(end 0.67945 -0.3048)
			(stroke
				(width 0.1)
				(type default)
			)
			(layer "F.Fab")
		)
		(fp_line
			(start 0.120396 0.3048)
			(end 0.120396 0.2794)
			(stroke
				(width 0.1)
				(type default)
			)
			(layer "F.Fab")
		)
		(fp_line
			(start 0.120396 0.2794)
			(end -0.12065 0.2794)
			(stroke
				(width 0.1)
				(type default)
			)
			(layer "F.Fab")
		)
		(fp_line
			(start -0.12065 0.3048)
			(end -0.67945 0.3048)
			(stroke
				(width 0.1)
				(type default)
			)
			(layer "F.Fab")
		)
		(fp_line
			(start -0.12065 0.2794)
			(end -0.12065 0.3048)
			(stroke
				(width 0.1)
				(type default)
			)
			(layer "F.Fab")
		)
		(fp_line
			(start -0.12065 -0.2794)
			(end 0.12065 -0.2794)
			(stroke
				(width 0.1)
				(type default)
			)
			(layer "F.Fab")
		)
		(fp_line
			(start -0.12065 -0.305054)
			(end -0.12065 -0.2794)
			(stroke
				(width 0.1)
				(type default)
			)
			(layer "F.Fab")
		)
		(fp_line
			(start -0.67945 0.3048)
			(end -0.67945 -0.305054)
			(stroke
				(width 0.1)
				(type default)
			)
			(layer "F.Fab")
		)
		(fp_line
			(start -0.67945 -0.305054)
			(end -0.12065 -0.305054)
			(stroke
				(width 0.1)
				(type default)
			)
			(layer "F.Fab")
		)
		(pad "1" smd circle
			(at -0.40005 0 180)
			(size 0 0)
			(layers "F.Cu" "F.Mask" "F.Paste")
			(net "PWRGD_P12V_SSD1_D")
		)
		(pad "2" smd circle
			(at 0.40005 0 180)
			(size 0 0)
			(layers "F.Cu" "F.Mask" "F.Paste")
			(net "PWRGD_P12V_SSD1_R")
		)
	)
	(footprint ""
		(layer "F.Cu")
		(at 306.846986 -54.3941)
		(property "Reference" "PU42"
			(at -1.780794 2.755646 0)
			(unlocked yes)
			(layer "F.SilkS")
			(effects
				(font
					(size 0.7874 0.5842)
					(thickness 0.1524)
				)
				(justify left)
			)
		)
		(property "Value" ""
			(at 0 0 0)
			(layer "F.Fab")
			(effects
				(font
					(size 1.27 1.27)
				)
			)
		)
		(duplicate_pad_numbers_are_jumpers no)
		(fp_line
			(start -1.943608 -1.549908)
			(end 1.943608 -1.549908)
			(stroke
				(width 0.1524)
				(type default)
			)
			(layer "F.SilkS")
		)
		(fp_line
			(start -1.943608 1.549908)
			(end -1.943608 -1.549908)
			(stroke
				(width 0.1524)
				(type default)
			)
			(layer "F.SilkS")
		)
		(fp_line
			(start 1.943608 -1.549908)
			(end 1.943608 1.549908)
			(stroke
				(width 0.1524)
				(type default)
			)
			(layer "F.SilkS")
		)
		(fp_line
			(start 1.943608 1.549908)
			(end -1.943608 1.549908)
			(stroke
				(width 0.1524)
				(type default)
			)
			(layer "F.SilkS")
		)
		(fp_poly
			(pts
				(xy -2.019808 -1.549908) (xy -1.257808 -1.549908) (xy -1.257808 -1.880108) (xy -2.019808 -1.880108)
			)
			(stroke
				(width 0)
				(type default)
			)
			(fill yes)
			(layer "F.SilkS")
		)
		(fp_line
			(start -1.549908 -1.549908)
			(end 1.549908 -1.549908)
			(stroke
				(width 0.1)
				(type default)
			)
			(layer "F.Fab")
		)
		(fp_line
			(start -1.549908 1.549908)
			(end -1.549908 -1.549908)
			(stroke
				(width 0.1)
				(type default)
			)
			(layer "F.Fab")
		)
		(fp_line
			(start 1.549908 -1.549908)
			(end 1.549908 1.549908)
			(stroke
				(width 0.1)
				(type default)
			)
			(layer "F.Fab")
		)
		(fp_line
			(start 1.549908 1.549908)
			(end -1.549908 1.549908)
			(stroke
				(width 0.1)
				(type default)
			)
			(layer "F.Fab")
		)
		(fp_poly
			(pts
				(xy -2.019808 -1.549908) (xy -1.257808 -1.549908) (xy -1.257808 -1.880108) (xy -2.019808 -1.880108)
			)
			(stroke
				(width 0)
				(type default)
			)
			(fill yes)
			(layer "F.Fab")
		)
		(pad "1" smd rect
			(at -1.500124 -1.249934 270)
			(size 0.2794 0.6096)
			(layers "F.Cu" "F.Mask" "F.Paste")
			(net "P12V_SSD10_R")
		)
		(pad "2" smd rect
			(at -1.500124 -0.750062 270)
			(size 0.2794 0.6096)
			(layers "F.Cu" "F.Mask" "F.Paste")
			(net "P12V_SSD10_R")
		)
		(pad "3" smd rect
			(at -1.500124 -0.249936 270)
			(size 0.2794 0.6096)
			(layers "F.Cu" "F.Mask" "F.Paste")
			(net "P12V_SSD10_R")
		)
		(pad "4" smd rect
			(at -1.500124 0.249936 270)
			(size 0.2794 0.6096)
			(layers "F.Cu" "F.Mask" "F.Paste")
			(net "P12V_SSD10_R")
		)
		(pad "5" smd rect
			(at -1.500124 0.750062 270)
			(size 0.2794 0.6096)
			(layers "F.Cu" "F.Mask" "F.Paste")
			(net "P12V_SSD10_R")
		)
		(pad "6" smd rect
			(at -1.500124 1.249934 270)
			(size 0.2794 0.6096)
			(layers "F.Cu" "F.Mask" "F.Paste")
			(net "GND")
		)
		(pad "7" smd rect
			(at 1.500124 1.249934 270)
			(size 0.2794 0.6096)
			(layers "F.Cu" "F.Mask" "F.Paste")
			(net "P12V_SSD10_SS")
		)
		(pad "8" smd rect
			(at 1.500124 0.750062 270)
			(size 0.2794 0.6096)
			(layers "F.Cu" "F.Mask" "F.Paste")
			(net "PWRGD_P12V_SSD10")
		)
		(pad "9" smd rect
			(at 1.500124 0.249936 270)
			(size 0.2794 0.6096)
			(layers "F.Cu" "F.Mask" "F.Paste")
			(net "P12V_SSD10_OCP")
		)
		(pad "10" smd rect
			(at 1.500124 -0.249936 270)
			(size 0.2794 0.6096)
			(layers "F.Cu" "F.Mask" "F.Paste")
			(net "P5V_AUX")
		)
		(pad "11" smd rect
			(at 1.500124 -0.750062 270)
			(size 0.2794 0.6096)
			(layers "F.Cu" "F.Mask" "F.Paste")
			(net "SSD10_PWR_EN_R")
		)
		(pad "12" smd rect
			(at 1.500124 -1.249934 270)
			(size 0.2794 0.6096)
			(layers "F.Cu" "F.Mask" "F.Paste")
			(net "P12V_AUX")
		)
		(pad "13" smd rect
			(at 0 0)
			(size 1.9812 2.7178)
			(layers "F.Cu" "F.Mask" "F.Paste")
			(net "P12V_AUX")
		)
		(zone
			(layer "F.Cu")
			(hatch none 0.5)
			(connect_pads
				(clearance 0)
			)
			(min_thickness 0.25)
			(keepout
				(tracks not_allowed)
				(vias allowed)
				(pads allowed)
				(copperpour not_allowed)
				(footprints allowed)
			)
			(placement
				(enabled no)
				(sheetname "")
			)
			(fill
				(thermal_gap 0.5)
				(thermal_bridge_width 0.5)
				(island_removal_mode 0)
			)
			(polygon
				(pts
					(xy 307.989986 -55.9435) (xy 307.989986 -55.8165) (xy 307.989986 -52.8447) (xy 307.989986 -52.844192)
					(xy 305.703986 -52.844192) (xy 305.703986 -52.8447) (xy 305.703986 -52.9717) (xy 305.703986 -54.3941)
					(xy 305.805586 -54.3941) (xy 305.805586 -52.9717) (xy 307.888386 -52.9717) (xy 307.888386 -55.8165)
					(xy 305.805586 -55.8165) (xy 305.805586 -54.4195) (xy 305.703986 -54.4195) (xy 305.703986 -55.8165)
					(xy 305.703986 -55.9435) (xy 305.703986 -55.944008) (xy 307.989986 -55.944008)
				)
			)
		)
	)
	(footprint ""
		(layer "F.Cu")
		(at 59.771788 -24.807418)
		(property "Reference" "R417"
			(at 0 0 0)
			(layer "F.SilkS")
			(hide yes)
			(effects
				(font
					(size 1.27 1.27)
				)
			)
		)
		(property "Value" ""
			(at 0 0 0)
			(layer "F.Fab")
			(effects
				(font
					(size 1.27 1.27)
				)
			)
		)
		(duplicate_pad_numbers_are_jumpers no)
		(fp_line
			(start -0.7874 -0.4064)
			(end 0.7874 -0.4064)
			(stroke
				(width 0.1524)
				(type default)
			)
			(layer "F.SilkS")
		)
		(fp_line
			(start -0.7874 0.4064)
			(end -0.7874 -0.4064)
			(stroke
				(width 0.1524)
				(type default)
			)
			(layer "F.SilkS")
		)
		(fp_line
			(start 0.7874 -0.4064)
			(end 0.7874 0.4064)
			(stroke
				(width 0.1524)
				(type default)
			)
			(layer "F.SilkS")
		)
		(fp_line
			(start 0.7874 0.4064)
			(end -0.7874 0.4064)
			(stroke
				(width 0.1524)
				(type default)
			)
			(layer "F.SilkS")
		)
		(fp_line
			(start -0.67945 -0.305054)
			(end -0.12065 -0.305054)
			(stroke
				(width 0.1)
				(type default)
			)
			(layer "F.Fab")
		)
		(fp_line
			(start -0.67945 0.3048)
			(end -0.67945 -0.305054)
			(stroke
				(width 0.1)
				(type default)
			)
			(layer "F.Fab")
		)
		(fp_line
			(start -0.12065 -0.305054)
			(end -0.12065 -0.2794)
			(stroke
				(width 0.1)
				(type default)
			)
			(layer "F.Fab")
		)
		(fp_line
			(start -0.12065 -0.2794)
			(end 0.12065 -0.2794)
			(stroke
				(width 0.1)
				(type default)
			)
			(layer "F.Fab")
		)
		(fp_line
			(start -0.12065 0.2794)
			(end -0.12065 0.3048)
			(stroke
				(width 0.1)
				(type default)
			)
			(layer "F.Fab")
		)
		(fp_line
			(start -0.12065 0.3048)
			(end -0.67945 0.3048)
			(stroke
				(width 0.1)
				(type default)
			)
			(layer "F.Fab")
		)
		(fp_line
			(start 0.120396 0.2794)
			(end -0.12065 0.2794)
			(stroke
				(width 0.1)
				(type default)
			)
			(layer "F.Fab")
		)
		(fp_line
			(start 0.120396 0.3048)
			(end 0.120396 0.2794)
			(stroke
				(width 0.1)
				(type default)
			)
			(layer "F.Fab")
		)
		(fp_line
			(start 0.12065 -0.3048)
			(end 0.67945 -0.3048)
			(stroke
				(width 0.1)
				(type default)
			)
			(layer "F.Fab")
		)
		(fp_line
			(start 0.12065 -0.2794)
			(end 0.12065 -0.3048)
			(stroke
				(width 0.1)
				(type default)
			)
			(layer "F.Fab")
		)
		(fp_line
			(start 0.67945 -0.3048)
			(end 0.67945 0.3048)
			(stroke
				(width 0.1)
				(type default)
			)
			(layer "F.Fab")
		)
		(fp_line
			(start 0.67945 0.3048)
			(end 0.120396 0.3048)
			(stroke
				(width 0.1)
				(type default)
			)
			(layer "F.Fab")
		)
		(pad "1" smd circle
			(at -0.40005 0)
			(size 0 0)
			(layers "F.Cu" "F.Mask" "F.Paste")
			(net "P3V3_SSD2")
		)
		(pad "2" smd circle
			(at 0.40005 0)
			(size 0 0)
			(layers "F.Cu" "F.Mask" "F.Paste")
			(net "PU_CLKREQ2")
		)
	)
	(footprint ""
		(layer "F.Cu")
		(at 362.65485 -303.698402 90)
		(property "Reference" "PC185"
			(at 0 0 90)
			(layer "F.SilkS")
			(hide yes)
			(effects
				(font
					(size 1.27 1.27)
				)
			)
		)
		(property "Value" ""
			(at 0 0 90)
			(layer "F.Fab")
			(effects
				(font
					(size 1.27 1.27)
				)
			)
		)
		(duplicate_pad_numbers_are_jumpers no)
		(fp_line
			(start -4.53898 -2.150618)
			(end -4.539742 2.152142)
			(stroke
				(width 0.1524)
				(type default)
			)
			(layer "F.SilkS")
		)
		(fp_line
			(start -4.69138 -2.150618)
			(end -4.692396 2.161032)
			(stroke
				(width 0.1524)
				(type default)
			)
			(layer "F.SilkS")
		)
		(fp_line
			(start -4.84378 -2.150618)
			(end -4.53898 -2.150618)
			(stroke
				(width 0.1524)
				(type default)
			)
			(layer "F.SilkS")
		)
		(fp_line
			(start -4.84378 -2.150618)
			(end -4.842256 2.163064)
			(stroke
				(width 0.1524)
				(type default)
			)
			(layer "F.SilkS")
		)
		(fp_line
			(start 4.53898 -2.15011)
			(end 4.53898 2.15011)
			(stroke
				(width 0.1524)
				(type default)
			)
			(layer "F.SilkS")
		)
		(fp_line
			(start -4.53898 -2.15011)
			(end 4.53898 -2.15011)
			(stroke
				(width 0.1524)
				(type default)
			)
			(layer "F.SilkS")
		)
		(fp_line
			(start 4.53898 2.15011)
			(end -4.53898 2.15011)
			(stroke
				(width 0.1524)
				(type default)
			)
			(layer "F.SilkS")
		)
		(fp_line
			(start -4.53898 2.15011)
			(end -4.53898 -2.15011)
			(stroke
				(width 0.1524)
				(type default)
			)
			(layer "F.SilkS")
		)
		(fp_line
			(start -4.83108 2.150364)
			(end -4.447794 2.149348)
			(stroke
				(width 0.1524)
				(type default)
			)
			(layer "F.SilkS")
		)
		(fp_line
			(start 3.64998 -2.15011)
			(end 3.64998 2.15011)
			(stroke
				(width 0.1)
				(type default)
			)
			(layer "F.Fab")
		)
		(fp_line
			(start -3.64998 -2.15011)
			(end 3.64998 -2.15011)
			(stroke
				(width 0.1)
				(type default)
			)
			(layer "F.Fab")
		)
		(fp_line
			(start 3.64998 2.15011)
			(end -3.64998 2.15011)
			(stroke
				(width 0.1)
				(type default)
			)
			(layer "F.Fab")
		)
		(fp_line
			(start -3.64998 2.15011)
			(end -3.64998 -2.15011)
			(stroke
				(width 0.1)
				(type default)
			)
			(layer "F.Fab")
		)
		(fp_text user "-"
			(at 4.736084 0.091694 90)
			(unlocked yes)
			(layer "F.SilkS")
			(effects
				(font
					(size 1.905 1.4224)
					(thickness 0.1524)
				)
				(justify left)
			)
		)
		(fp_text user "+"
			(at -4.86156 2.689606 90)
			(unlocked yes)
			(layer "F.SilkS")
			(effects
				(font
					(size 1.905 1.4224)
					(thickness 0.1524)
				)
				(justify left)
			)
		)
		(fp_text user "+"
			(at -6.214872 -0.337058 90)
			(unlocked yes)
			(layer "F.Fab")
			(effects
				(font
					(size 1.905 1.4224)
					(thickness 0.1524)
				)
				(justify left)
			)
		)
		(fp_text user "-"
			(at 4.313174 -0.094488 90)
			(unlocked yes)
			(layer "F.Fab")
			(effects
				(font
					(size 1.905 1.4224)
					(thickness 0.1524)
				)
				(justify left)
			)
		)
		(pad "1" smd rect
			(at -3.199892 0 90)
			(size 2.413 2.8194)
			(layers "F.Cu" "F.Mask" "F.Paste")
			(net "P0V8_PEX3")
		)
		(pad "2" smd rect
			(at 3.199892 0 90)
			(size 2.413 2.8194)
			(layers "F.Cu" "F.Mask" "F.Paste")
			(net "GND")
		)
	)
	(footprint ""
		(layer "F.Cu")
		(at 312.21934 -143.504666 180)
		(property "Reference" "C437"
			(at 0 0 180)
			(layer "F.SilkS")
			(hide yes)
			(effects
				(font
					(size 1.27 1.27)
				)
			)
		)
		(property "Value" ""
			(at 0 0 180)
			(layer "F.Fab")
			(effects
				(font
					(size 1.27 1.27)
				)
			)
		)
		(duplicate_pad_numbers_are_jumpers no)
		(fp_line
			(start 0.299974 0.150114)
			(end -0.299974 0.150114)
			(stroke
				(width 0.1)
				(type default)
			)
			(layer "F.Fab")
		)
		(fp_line
			(start 0.299974 -0.150114)
			(end 0.299974 0.150114)
			(stroke
				(width 0.1)
				(type default)
			)
			(layer "F.Fab")
		)
		(fp_line
			(start -0.299974 0.150114)
			(end -0.299974 -0.150114)
			(stroke
				(width 0.1)
				(type default)
			)
			(layer "F.Fab")
		)
		(fp_line
			(start -0.299974 -0.150114)
			(end 0.299974 -0.150114)
			(stroke
				(width 0.1)
				(type default)
			)
			(layer "F.Fab")
		)
		(pad "1" smd rect
			(at -0.2667 0 180)
			(size 0.3048 0.381)
			(layers "F.Cu" "F.Mask" "F.Paste")
			(net "P5E_PEX2_STN0_TX_DP<8>")
		)
		(pad "2" smd rect
			(at 0.2667 0 180)
			(size 0.3048 0.381)
			(layers "F.Cu" "F.Mask" "F.Paste")
			(net "P5E_PEX2_STN0_TX_C_DP<8>")
		)
	)
	(footprint ""
		(layer "F.Cu")
		(at 257.764026 -237.213648 -90)
		(property "Reference" "C4424"
			(at 0 0 270)
			(layer "F.SilkS")
			(hide yes)
			(effects
				(font
					(size 1.27 1.27)
				)
			)
		)
		(property "Value" ""
			(at 0 0 270)
			(layer "F.Fab")
			(effects
				(font
					(size 1.27 1.27)
				)
			)
		)
		(duplicate_pad_numbers_are_jumpers no)
		(fp_line
			(start -0.7874 0.4064)
			(end -0.7874 -0.4064)
			(stroke
				(width 0.1524)
				(type default)
			)
			(layer "F.SilkS")
		)
		(fp_line
			(start 0.7874 0.4064)
			(end -0.7874 0.4064)
			(stroke
				(width 0.1524)
				(type default)
			)
			(layer "F.SilkS")
		)
		(fp_line
			(start -0.7874 -0.4064)
			(end 0.7874 -0.4064)
			(stroke
				(width 0.1524)
				(type default)
			)
			(layer "F.SilkS")
		)
		(fp_line
			(start 0.7874 -0.4064)
			(end 0.7874 0.4064)
			(stroke
				(width 0.1524)
				(type default)
			)
			(layer "F.SilkS")
		)
		(fp_line
			(start -0.67945 0.3048)
			(end -0.67945 -0.305054)
			(stroke
				(width 0.1)
				(type default)
			)
			(layer "F.Fab")
		)
		(fp_line
			(start -0.12065 0.3048)
			(end -0.67945 0.3048)
			(stroke
				(width 0.1)
				(type default)
			)
			(layer "F.Fab")
		)
		(fp_line
			(start 0.120396 0.3048)
			(end 0.120396 0.2794)
			(stroke
				(width 0.1)
				(type default)
			)
			(layer "F.Fab")
		)
		(fp_line
			(start 0.67945 0.3048)
			(end 0.120396 0.3048)
			(stroke
				(width 0.1)
				(type default)
			)
			(layer "F.Fab")
		)
		(fp_line
			(start -0.12065 0.2794)
			(end -0.12065 0.3048)
			(stroke
				(width 0.1)
				(type default)
			)
			(layer "F.Fab")
		)
		(fp_line
			(start 0.120396 0.2794)
			(end -0.12065 0.2794)
			(stroke
				(width 0.1)
				(type default)
			)
			(layer "F.Fab")
		)
		(fp_line
			(start -0.12065 -0.2794)
			(end 0.12065 -0.2794)
			(stroke
				(width 0.1)
				(type default)
			)
			(layer "F.Fab")
		)
		(fp_line
			(start 0.12065 -0.2794)
			(end 0.12065 -0.3048)
			(stroke
				(width 0.1)
				(type default)
			)
			(layer "F.Fab")
		)
		(fp_line
			(start 0.12065 -0.3048)
			(end 0.67945 -0.3048)
			(stroke
				(width 0.1)
				(type default)
			)
			(layer "F.Fab")
		)
		(fp_line
			(start 0.67945 -0.3048)
			(end 0.67945 0.3048)
			(stroke
				(width 0.1)
				(type default)
			)
			(layer "F.Fab")
		)
		(fp_line
			(start -0.67945 -0.305054)
			(end -0.12065 -0.305054)
			(stroke
				(width 0.1)
				(type default)
			)
			(layer "F.Fab")
		)
		(fp_line
			(start -0.12065 -0.305054)
			(end -0.12065 -0.2794)
			(stroke
				(width 0.1)
				(type default)
			)
			(layer "F.Fab")
		)
		(pad "1" smd circle
			(at -0.40005 0 270)
			(size 0 0)
			(layers "F.Cu" "F.Mask" "F.Paste")
			(net "P5V_AUX")
		)
		(pad "2" smd circle
			(at 0.40005 0 270)
			(size 0 0)
			(layers "F.Cu" "F.Mask" "F.Paste")
			(net "GND")
		)
	)
	(footprint ""
		(layer "F.Cu")
		(at 384.834384 -250.070874 -90)
		(property "Reference" "R1411"
			(at 0 0 270)
			(layer "F.SilkS")
			(hide yes)
			(effects
				(font
					(size 1.27 1.27)
				)
			)
		)
		(property "Value" ""
			(at 0 0 270)
			(layer "F.Fab")
			(effects
				(font
					(size 1.27 1.27)
				)
			)
		)
		(duplicate_pad_numbers_are_jumpers no)
		(fp_line
			(start -0.7874 0.4064)
			(end -0.7874 -0.4064)
			(stroke
				(width 0.1524)
				(type default)
			)
			(layer "F.SilkS")
		)
		(fp_line
			(start 0.7874 0.4064)
			(end -0.7874 0.4064)
			(stroke
				(width 0.1524)
				(type default)
			)
			(layer "F.SilkS")
		)
		(fp_line
			(start -0.7874 -0.4064)
			(end 0.7874 -0.4064)
			(stroke
				(width 0.1524)
				(type default)
			)
			(layer "F.SilkS")
		)
		(fp_line
			(start 0.7874 -0.4064)
			(end 0.7874 0.4064)
			(stroke
				(width 0.1524)
				(type default)
			)
			(layer "F.SilkS")
		)
		(fp_line
			(start -0.67945 0.3048)
			(end -0.67945 -0.305054)
			(stroke
				(width 0.1)
				(type default)
			)
			(layer "F.Fab")
		)
		(fp_line
			(start -0.12065 0.3048)
			(end -0.67945 0.3048)
			(stroke
				(width 0.1)
				(type default)
			)
			(layer "F.Fab")
		)
		(fp_line
			(start 0.120396 0.3048)
			(end 0.120396 0.2794)
			(stroke
				(width 0.1)
				(type default)
			)
			(layer "F.Fab")
		)
		(fp_line
			(start 0.67945 0.3048)
			(end 0.120396 0.3048)
			(stroke
				(width 0.1)
				(type default)
			)
			(layer "F.Fab")
		)
		(fp_line
			(start -0.12065 0.2794)
			(end -0.12065 0.3048)
			(stroke
				(width 0.1)
				(type default)
			)
			(layer "F.Fab")
		)
		(fp_line
			(start 0.120396 0.2794)
			(end -0.12065 0.2794)
			(stroke
				(width 0.1)
				(type default)
			)
			(layer "F.Fab")
		)
		(fp_line
			(start -0.12065 -0.2794)
			(end 0.12065 -0.2794)
			(stroke
				(width 0.1)
				(type default)
			)
			(layer "F.Fab")
		)
		(fp_line
			(start 0.12065 -0.2794)
			(end 0.12065 -0.3048)
			(stroke
				(width 0.1)
				(type default)
			)
			(layer "F.Fab")
		)
		(fp_line
			(start 0.12065 -0.3048)
			(end 0.67945 -0.3048)
			(stroke
				(width 0.1)
				(type default)
			)
			(layer "F.Fab")
		)
		(fp_line
			(start 0.67945 -0.3048)
			(end 0.67945 0.3048)
			(stroke
				(width 0.1)
				(type default)
			)
			(layer "F.Fab")
		)
		(fp_line
			(start -0.67945 -0.305054)
			(end -0.12065 -0.305054)
			(stroke
				(width 0.1)
				(type default)
			)
			(layer "F.Fab")
		)
		(fp_line
			(start -0.12065 -0.305054)
			(end -0.12065 -0.2794)
			(stroke
				(width 0.1)
				(type default)
			)
			(layer "F.Fab")
		)
		(pad "1" smd circle
			(at -0.40005 0 270)
			(size 0 0)
			(layers "F.Cu" "F.Mask" "F.Paste")
			(net "PEX3_MODE_SEL6")
		)
		(pad "2" smd circle
			(at 0.40005 0 270)
			(size 0 0)
			(layers "F.Cu" "F.Mask" "F.Paste")
			(net "P1V8_PEX")
		)
	)
	(footprint ""
		(layer "F.Cu")
		(at 139.768072 -19.453098)
		(property "Reference" "R1667"
			(at 0 0 0)
			(layer "F.SilkS")
			(hide yes)
			(effects
				(font
					(size 1.27 1.27)
				)
			)
		)
		(property "Value" ""
			(at 0 0 0)
			(layer "F.Fab")
			(effects
				(font
					(size 1.27 1.27)
				)
			)
		)
		(duplicate_pad_numbers_are_jumpers no)
		(fp_line
			(start -0.7874 -0.4064)
			(end 0.7874 -0.4064)
			(stroke
				(width 0.1524)
				(type default)
			)
			(layer "F.SilkS")
		)
		(fp_line
			(start -0.7874 0.4064)
			(end -0.7874 -0.4064)
			(stroke
				(width 0.1524)
				(type default)
			)
			(layer "F.SilkS")
		)
		(fp_line
			(start 0.7874 -0.4064)
			(end 0.7874 0.4064)
			(stroke
				(width 0.1524)
				(type default)
			)
			(layer "F.SilkS")
		)
		(fp_line
			(start 0.7874 0.4064)
			(end -0.7874 0.4064)
			(stroke
				(width 0.1524)
				(type default)
			)
			(layer "F.SilkS")
		)
		(fp_line
			(start -0.67945 -0.305054)
			(end -0.12065 -0.305054)
			(stroke
				(width 0.1)
				(type default)
			)
			(layer "F.Fab")
		)
		(fp_line
			(start -0.67945 0.3048)
			(end -0.67945 -0.305054)
			(stroke
				(width 0.1)
				(type default)
			)
			(layer "F.Fab")
		)
		(fp_line
			(start -0.12065 -0.305054)
			(end -0.12065 -0.2794)
			(stroke
				(width 0.1)
				(type default)
			)
			(layer "F.Fab")
		)
		(fp_line
			(start -0.12065 -0.2794)
			(end 0.12065 -0.2794)
			(stroke
				(width 0.1)
				(type default)
			)
			(layer "F.Fab")
		)
		(fp_line
			(start -0.12065 0.2794)
			(end -0.12065 0.3048)
			(stroke
				(width 0.1)
				(type default)
			)
			(layer "F.Fab")
		)
		(fp_line
			(start -0.12065 0.3048)
			(end -0.67945 0.3048)
			(stroke
				(width 0.1)
				(type default)
			)
			(layer "F.Fab")
		)
		(fp_line
			(start 0.120396 0.2794)
			(end -0.12065 0.2794)
			(stroke
				(width 0.1)
				(type default)
			)
			(layer "F.Fab")
		)
		(fp_line
			(start 0.120396 0.3048)
			(end 0.120396 0.2794)
			(stroke
				(width 0.1)
				(type default)
			)
			(layer "F.Fab")
		)
		(fp_line
			(start 0.12065 -0.3048)
			(end 0.67945 -0.3048)
			(stroke
				(width 0.1)
				(type default)
			)
			(layer "F.Fab")
		)
		(fp_line
			(start 0.12065 -0.2794)
			(end 0.12065 -0.3048)
			(stroke
				(width 0.1)
				(type default)
			)
			(layer "F.Fab")
		)
		(fp_line
			(start 0.67945 -0.3048)
			(end 0.67945 0.3048)
			(stroke
				(width 0.1)
				(type default)
			)
			(layer "F.Fab")
		)
		(fp_line
			(start 0.67945 0.3048)
			(end 0.120396 0.3048)
			(stroke
				(width 0.1)
				(type default)
			)
			(layer "F.Fab")
		)
		(pad "1" smd circle
			(at -0.40005 0)
			(size 0 0)
			(layers "F.Cu" "F.Mask" "F.Paste")
			(net "SMB_ISO_SSD4_R_SDA")
		)
		(pad "2" smd circle
			(at 0.40005 0)
			(size 0 0)
			(layers "F.Cu" "F.Mask" "F.Paste")
			(net "SMB_ISO_SSD4_SDA")
		)
	)
	(footprint ""
		(layer "F.Cu")
		(at 212.046566 -235.756958 90)
		(property "Reference" "R1539"
			(at 0 0 90)
			(layer "F.SilkS")
			(hide yes)
			(effects
				(font
					(size 1.27 1.27)
				)
			)
		)
		(property "Value" ""
			(at 0 0 90)
			(layer "F.Fab")
			(effects
				(font
					(size 1.27 1.27)
				)
			)
		)
		(duplicate_pad_numbers_are_jumpers no)
		(fp_line
			(start 0.7874 -0.4064)
			(end 0.7874 0.4064)
			(stroke
				(width 0.1524)
				(type default)
			)
			(layer "F.SilkS")
		)
		(fp_line
			(start -0.7874 -0.4064)
			(end 0.7874 -0.4064)
			(stroke
				(width 0.1524)
				(type default)
			)
			(layer "F.SilkS")
		)
		(fp_line
			(start 0.7874 0.4064)
			(end -0.7874 0.4064)
			(stroke
				(width 0.1524)
				(type default)
			)
			(layer "F.SilkS")
		)
		(fp_line
			(start -0.7874 0.4064)
			(end -0.7874 -0.4064)
			(stroke
				(width 0.1524)
				(type default)
			)
			(layer "F.SilkS")
		)
		(fp_line
			(start -0.12065 -0.305054)
			(end -0.12065 -0.2794)
			(stroke
				(width 0.1)
				(type default)
			)
			(layer "F.Fab")
		)
		(fp_line
			(start -0.67945 -0.305054)
			(end -0.12065 -0.305054)
			(stroke
				(width 0.1)
				(type default)
			)
			(layer "F.Fab")
		)
		(fp_line
			(start 0.67945 -0.3048)
			(end 0.67945 0.3048)
			(stroke
				(width 0.1)
				(type default)
			)
			(layer "F.Fab")
		)
		(fp_line
			(start 0.12065 -0.3048)
			(end 0.67945 -0.3048)
			(stroke
				(width 0.1)
				(type default)
			)
			(layer "F.Fab")
		)
		(fp_line
			(start 0.12065 -0.2794)
			(end 0.12065 -0.3048)
			(stroke
				(width 0.1)
				(type default)
			)
			(layer "F.Fab")
		)
		(fp_line
			(start -0.12065 -0.2794)
			(end 0.12065 -0.2794)
			(stroke
				(width 0.1)
				(type default)
			)
			(layer "F.Fab")
		)
		(fp_line
			(start 0.120396 0.2794)
			(end -0.12065 0.2794)
			(stroke
				(width 0.1)
				(type default)
			)
			(layer "F.Fab")
		)
		(fp_line
			(start -0.12065 0.2794)
			(end -0.12065 0.3048)
			(stroke
				(width 0.1)
				(type default)
			)
			(layer "F.Fab")
		)
		(fp_line
			(start 0.67945 0.3048)
			(end 0.120396 0.3048)
			(stroke
				(width 0.1)
				(type default)
			)
			(layer "F.Fab")
		)
		(fp_line
			(start 0.120396 0.3048)
			(end 0.120396 0.2794)
			(stroke
				(width 0.1)
				(type default)
			)
			(layer "F.Fab")
		)
		(fp_line
			(start -0.12065 0.3048)
			(end -0.67945 0.3048)
			(stroke
				(width 0.1)
				(type default)
			)
			(layer "F.Fab")
		)
		(fp_line
			(start -0.67945 0.3048)
			(end -0.67945 -0.305054)
			(stroke
				(width 0.1)
				(type default)
			)
			(layer "F.Fab")
		)
		(pad "1" smd circle
			(at -0.40005 0 90)
			(size 0 0)
			(layers "F.Cu" "F.Mask" "F.Paste")
			(net "P1V8_PEX")
		)
		(pad "2" smd circle
			(at 0.40005 0 90)
			(size 0 0)
			(layers "F.Cu" "F.Mask" "F.Paste")
			(net "SMB_PEX_LS_SCL")
		)
	)
	(footprint ""
		(layer "F.Cu")
		(at 421.247316 -20.35556)
		(property "Reference" "C3974"
			(at 0 0 0)
			(layer "F.SilkS")
			(hide yes)
			(effects
				(font
					(size 1.27 1.27)
				)
			)
		)
		(property "Value" ""
			(at 0 0 0)
			(layer "F.Fab")
			(effects
				(font
					(size 1.27 1.27)
				)
			)
		)
		(duplicate_pad_numbers_are_jumpers no)
		(fp_line
			(start -0.7874 -0.4064)
			(end 0.7874 -0.4064)
			(stroke
				(width 0.1524)
				(type default)
			)
			(layer "F.SilkS")
		)
		(fp_line
			(start -0.7874 0.4064)
			(end -0.7874 -0.4064)
			(stroke
				(width 0.1524)
				(type default)
			)
			(layer "F.SilkS")
		)
		(fp_line
			(start 0.7874 -0.4064)
			(end 0.7874 0.4064)
			(stroke
				(width 0.1524)
				(type default)
			)
			(layer "F.SilkS")
		)
		(fp_line
			(start 0.7874 0.4064)
			(end -0.7874 0.4064)
			(stroke
				(width 0.1524)
				(type default)
			)
			(layer "F.SilkS")
		)
		(fp_line
			(start -0.67945 -0.305054)
			(end -0.12065 -0.305054)
			(stroke
				(width 0.1)
				(type default)
			)
			(layer "F.Fab")
		)
		(fp_line
			(start -0.67945 0.3048)
			(end -0.67945 -0.305054)
			(stroke
				(width 0.1)
				(type default)
			)
			(layer "F.Fab")
		)
		(fp_line
			(start -0.12065 -0.305054)
			(end -0.12065 -0.2794)
			(stroke
				(width 0.1)
				(type default)
			)
			(layer "F.Fab")
		)
		(fp_line
			(start -0.12065 -0.2794)
			(end 0.12065 -0.2794)
			(stroke
				(width 0.1)
				(type default)
			)
			(layer "F.Fab")
		)
		(fp_line
			(start -0.12065 0.2794)
			(end -0.12065 0.3048)
			(stroke
				(width 0.1)
				(type default)
			)
			(layer "F.Fab")
		)
		(fp_line
			(start -0.12065 0.3048)
			(end -0.67945 0.3048)
			(stroke
				(width 0.1)
				(type default)
			)
			(layer "F.Fab")
		)
		(fp_line
			(start 0.120396 0.2794)
			(end -0.12065 0.2794)
			(stroke
				(width 0.1)
				(type default)
			)
			(layer "F.Fab")
		)
		(fp_line
			(start 0.120396 0.3048)
			(end 0.120396 0.2794)
			(stroke
				(width 0.1)
				(type default)
			)
			(layer "F.Fab")
		)
		(fp_line
			(start 0.12065 -0.3048)
			(end 0.67945 -0.3048)
			(stroke
				(width 0.1)
				(type default)
			)
			(layer "F.Fab")
		)
		(fp_line
			(start 0.12065 -0.2794)
			(end 0.12065 -0.3048)
			(stroke
				(width 0.1)
				(type default)
			)
			(layer "F.Fab")
		)
		(fp_line
			(start 0.67945 -0.3048)
			(end 0.67945 0.3048)
			(stroke
				(width 0.1)
				(type default)
			)
			(layer "F.Fab")
		)
		(fp_line
			(start 0.67945 0.3048)
			(end 0.120396 0.3048)
			(stroke
				(width 0.1)
				(type default)
			)
			(layer "F.Fab")
		)
		(pad "1" smd circle
			(at -0.40005 0)
			(size 0 0)
			(layers "F.Cu" "F.Mask" "F.Paste")
			(net "P12V_SSD14")
		)
		(pad "2" smd circle
			(at 0.40005 0)
			(size 0 0)
			(layers "F.Cu" "F.Mask" "F.Paste")
			(net "GND")
		)
	)
	(footprint ""
		(layer "F.Cu")
		(at 260.6548 -22.961346 90)
		(property "Reference" "R1687"
			(at 0 0 90)
			(layer "F.SilkS")
			(hide yes)
			(effects
				(font
					(size 1.27 1.27)
				)
			)
		)
		(property "Value" ""
			(at 0 0 90)
			(layer "F.Fab")
			(effects
				(font
					(size 1.27 1.27)
				)
			)
		)
		(duplicate_pad_numbers_are_jumpers no)
		(fp_line
			(start 0.7874 -0.4064)
			(end 0.7874 0.4064)
			(stroke
				(width 0.1524)
				(type default)
			)
			(layer "F.SilkS")
		)
		(fp_line
			(start -0.7874 -0.4064)
			(end 0.7874 -0.4064)
			(stroke
				(width 0.1524)
				(type default)
			)
			(layer "F.SilkS")
		)
		(fp_line
			(start 0.7874 0.4064)
			(end -0.7874 0.4064)
			(stroke
				(width 0.1524)
				(type default)
			)
			(layer "F.SilkS")
		)
		(fp_line
			(start -0.7874 0.4064)
			(end -0.7874 -0.4064)
			(stroke
				(width 0.1524)
				(type default)
			)
			(layer "F.SilkS")
		)
		(fp_line
			(start -0.12065 -0.305054)
			(end -0.12065 -0.2794)
			(stroke
				(width 0.1)
				(type default)
			)
			(layer "F.Fab")
		)
		(fp_line
			(start -0.67945 -0.305054)
			(end -0.12065 -0.305054)
			(stroke
				(width 0.1)
				(type default)
			)
			(layer "F.Fab")
		)
		(fp_line
			(start 0.67945 -0.3048)
			(end 0.67945 0.3048)
			(stroke
				(width 0.1)
				(type default)
			)
			(layer "F.Fab")
		)
		(fp_line
			(start 0.12065 -0.3048)
			(end 0.67945 -0.3048)
			(stroke
				(width 0.1)
				(type default)
			)
			(layer "F.Fab")
		)
		(fp_line
			(start 0.12065 -0.2794)
			(end 0.12065 -0.3048)
			(stroke
				(width 0.1)
				(type default)
			)
			(layer "F.Fab")
		)
		(fp_line
			(start -0.12065 -0.2794)
			(end 0.12065 -0.2794)
			(stroke
				(width 0.1)
				(type default)
			)
			(layer "F.Fab")
		)
		(fp_line
			(start 0.120396 0.2794)
			(end -0.12065 0.2794)
			(stroke
				(width 0.1)
				(type default)
			)
			(layer "F.Fab")
		)
		(fp_line
			(start -0.12065 0.2794)
			(end -0.12065 0.3048)
			(stroke
				(width 0.1)
				(type default)
			)
			(layer "F.Fab")
		)
		(fp_line
			(start 0.67945 0.3048)
			(end 0.120396 0.3048)
			(stroke
				(width 0.1)
				(type default)
			)
			(layer "F.Fab")
		)
		(fp_line
			(start 0.120396 0.3048)
			(end 0.120396 0.2794)
			(stroke
				(width 0.1)
				(type default)
			)
			(layer "F.Fab")
		)
		(fp_line
			(start -0.12065 0.3048)
			(end -0.67945 0.3048)
			(stroke
				(width 0.1)
				(type default)
			)
			(layer "F.Fab")
		)
		(fp_line
			(start -0.67945 0.3048)
			(end -0.67945 -0.305054)
			(stroke
				(width 0.1)
				(type default)
			)
			(layer "F.Fab")
		)
		(pad "1" smd circle
			(at -0.40005 0 90)
			(size 0 0)
			(layers "F.Cu" "F.Mask" "F.Paste")
			(net "SMB_SSD8_ISO_EN")
		)
		(pad "2" smd circle
			(at 0.40005 0 90)
			(size 0 0)
			(layers "F.Cu" "F.Mask" "F.Paste")
			(net "P3V3_AUX")
		)
	)
	(footprint ""
		(layer "F.Cu")
		(at 363.474 -210.947)
		(property "Reference" "R4598"
			(at 0 0 0)
			(layer "F.SilkS")
			(hide yes)
			(effects
				(font
					(size 1.27 1.27)
				)
			)
		)
		(property "Value" ""
			(at 0 0 0)
			(layer "F.Fab")
			(effects
				(font
					(size 1.27 1.27)
				)
			)
		)
		(duplicate_pad_numbers_are_jumpers no)
		(fp_line
			(start -0.7874 -0.4064)
			(end 0.7874 -0.4064)
			(stroke
				(width 0.1524)
				(type default)
			)
			(layer "F.SilkS")
		)
		(fp_line
			(start -0.7874 0.4064)
			(end -0.7874 -0.4064)
			(stroke
				(width 0.1524)
				(type default)
			)
			(layer "F.SilkS")
		)
		(fp_line
			(start 0.7874 -0.4064)
			(end 0.7874 0.4064)
			(stroke
				(width 0.1524)
				(type default)
			)
			(layer "F.SilkS")
		)
		(fp_line
			(start 0.7874 0.4064)
			(end -0.7874 0.4064)
			(stroke
				(width 0.1524)
				(type default)
			)
			(layer "F.SilkS")
		)
		(fp_line
			(start -0.67945 -0.305054)
			(end -0.12065 -0.305054)
			(stroke
				(width 0.1)
				(type default)
			)
			(layer "F.Fab")
		)
		(fp_line
			(start -0.67945 0.3048)
			(end -0.67945 -0.305054)
			(stroke
				(width 0.1)
				(type default)
			)
			(layer "F.Fab")
		)
		(fp_line
			(start -0.12065 -0.305054)
			(end -0.12065 -0.2794)
			(stroke
				(width 0.1)
				(type default)
			)
			(layer "F.Fab")
		)
		(fp_line
			(start -0.12065 -0.2794)
			(end 0.12065 -0.2794)
			(stroke
				(width 0.1)
				(type default)
			)
			(layer "F.Fab")
		)
		(fp_line
			(start -0.12065 0.2794)
			(end -0.12065 0.3048)
			(stroke
				(width 0.1)
				(type default)
			)
			(layer "F.Fab")
		)
		(fp_line
			(start -0.12065 0.3048)
			(end -0.67945 0.3048)
			(stroke
				(width 0.1)
				(type default)
			)
			(layer "F.Fab")
		)
		(fp_line
			(start 0.120396 0.2794)
			(end -0.12065 0.2794)
			(stroke
				(width 0.1)
				(type default)
			)
			(layer "F.Fab")
		)
		(fp_line
			(start 0.120396 0.3048)
			(end 0.120396 0.2794)
			(stroke
				(width 0.1)
				(type default)
			)
			(layer "F.Fab")
		)
		(fp_line
			(start 0.12065 -0.3048)
			(end 0.67945 -0.3048)
			(stroke
				(width 0.1)
				(type default)
			)
			(layer "F.Fab")
		)
		(fp_line
			(start 0.12065 -0.2794)
			(end 0.12065 -0.3048)
			(stroke
				(width 0.1)
				(type default)
			)
			(layer "F.Fab")
		)
		(fp_line
			(start 0.67945 -0.3048)
			(end 0.67945 0.3048)
			(stroke
				(width 0.1)
				(type default)
			)
			(layer "F.Fab")
		)
		(fp_line
			(start 0.67945 0.3048)
			(end 0.120396 0.3048)
			(stroke
				(width 0.1)
				(type default)
			)
			(layer "F.Fab")
		)
		(pad "1" smd circle
			(at -0.40005 0)
			(size 0 0)
			(layers "F.Cu" "F.Mask" "F.Paste")
			(net "P3V3_AUX")
		)
		(pad "2" smd circle
			(at 0.40005 0)
			(size 0 0)
			(layers "F.Cu" "F.Mask" "F.Paste")
			(net "SSD0_PEX_PWR_EN_R")
		)
	)
	(footprint ""
		(layer "F.Cu")
		(at 186.789568 -406.59431 90)
		(property "Reference" "R4417"
			(at 0 0 90)
			(layer "F.SilkS")
			(hide yes)
			(effects
				(font
					(size 1.27 1.27)
				)
			)
		)
		(property "Value" ""
			(at 0 0 90)
			(layer "F.Fab")
			(effects
				(font
					(size 1.27 1.27)
				)
			)
		)
		(duplicate_pad_numbers_are_jumpers no)
		(fp_line
			(start 0.7874 -0.4064)
			(end 0.7874 0.4064)
			(stroke
				(width 0.1524)
				(type default)
			)
			(layer "F.SilkS")
		)
		(fp_line
			(start -0.7874 -0.4064)
			(end 0.7874 -0.4064)
			(stroke
				(width 0.1524)
				(type default)
			)
			(layer "F.SilkS")
		)
		(fp_line
			(start 0.7874 0.4064)
			(end -0.7874 0.4064)
			(stroke
				(width 0.1524)
				(type default)
			)
			(layer "F.SilkS")
		)
		(fp_line
			(start -0.7874 0.4064)
			(end -0.7874 -0.4064)
			(stroke
				(width 0.1524)
				(type default)
			)
			(layer "F.SilkS")
		)
		(fp_line
			(start -0.12065 -0.305054)
			(end -0.12065 -0.2794)
			(stroke
				(width 0.1)
				(type default)
			)
			(layer "F.Fab")
		)
		(fp_line
			(start -0.67945 -0.305054)
			(end -0.12065 -0.305054)
			(stroke
				(width 0.1)
				(type default)
			)
			(layer "F.Fab")
		)
		(fp_line
			(start 0.67945 -0.3048)
			(end 0.67945 0.3048)
			(stroke
				(width 0.1)
				(type default)
			)
			(layer "F.Fab")
		)
		(fp_line
			(start 0.12065 -0.3048)
			(end 0.67945 -0.3048)
			(stroke
				(width 0.1)
				(type default)
			)
			(layer "F.Fab")
		)
		(fp_line
			(start 0.12065 -0.2794)
			(end 0.12065 -0.3048)
			(stroke
				(width 0.1)
				(type default)
			)
			(layer "F.Fab")
		)
		(fp_line
			(start -0.12065 -0.2794)
			(end 0.12065 -0.2794)
			(stroke
				(width 0.1)
				(type default)
			)
			(layer "F.Fab")
		)
		(fp_line
			(start 0.120396 0.2794)
			(end -0.12065 0.2794)
			(stroke
				(width 0.1)
				(type default)
			)
			(layer "F.Fab")
		)
		(fp_line
			(start -0.12065 0.2794)
			(end -0.12065 0.3048)
			(stroke
				(width 0.1)
				(type default)
			)
			(layer "F.Fab")
		)
		(fp_line
			(start 0.67945 0.3048)
			(end 0.120396 0.3048)
			(stroke
				(width 0.1)
				(type default)
			)
			(layer "F.Fab")
		)
		(fp_line
			(start 0.120396 0.3048)
			(end 0.120396 0.2794)
			(stroke
				(width 0.1)
				(type default)
			)
			(layer "F.Fab")
		)
		(fp_line
			(start -0.12065 0.3048)
			(end -0.67945 0.3048)
			(stroke
				(width 0.1)
				(type default)
			)
			(layer "F.Fab")
		)
		(fp_line
			(start -0.67945 0.3048)
			(end -0.67945 -0.305054)
			(stroke
				(width 0.1)
				(type default)
			)
			(layer "F.Fab")
		)
		(pad "1" smd circle
			(at -0.40005 0 90)
			(size 0 0)
			(layers "F.Cu" "F.Mask" "F.Paste")
			(net "FM_UV_ADR_TRIGGER_N")
		)
		(pad "2" smd circle
			(at 0.40005 0 90)
			(size 0 0)
			(layers "F.Cu" "F.Mask" "F.Paste")
			(net "P3V3_AUX")
		)
	)
	(footprint ""
		(layer "F.Cu")
		(at 376.312684 -83.1088)
		(property "Reference" "R1748"
			(at 0 0 0)
			(layer "F.SilkS")
			(hide yes)
			(effects
				(font
					(size 1.27 1.27)
				)
			)
		)
		(property "Value" ""
			(at 0 0 0)
			(layer "F.Fab")
			(effects
				(font
					(size 1.27 1.27)
				)
			)
		)
		(duplicate_pad_numbers_are_jumpers no)
		(fp_line
			(start -0.7874 -0.4064)
			(end 0.7874 -0.4064)
			(stroke
				(width 0.1524)
				(type default)
			)
			(layer "F.SilkS")
		)
		(fp_line
			(start -0.7874 0.4064)
			(end -0.7874 -0.4064)
			(stroke
				(width 0.1524)
				(type default)
			)
			(layer "F.SilkS")
		)
		(fp_line
			(start 0.7874 -0.4064)
			(end 0.7874 0.4064)
			(stroke
				(width 0.1524)
				(type default)
			)
			(layer "F.SilkS")
		)
		(fp_line
			(start 0.7874 0.4064)
			(end -0.7874 0.4064)
			(stroke
				(width 0.1524)
				(type default)
			)
			(layer "F.SilkS")
		)
		(fp_line
			(start -0.67945 -0.305054)
			(end -0.12065 -0.305054)
			(stroke
				(width 0.1)
				(type default)
			)
			(layer "F.Fab")
		)
		(fp_line
			(start -0.67945 0.3048)
			(end -0.67945 -0.305054)
			(stroke
				(width 0.1)
				(type default)
			)
			(layer "F.Fab")
		)
		(fp_line
			(start -0.12065 -0.305054)
			(end -0.12065 -0.2794)
			(stroke
				(width 0.1)
				(type default)
			)
			(layer "F.Fab")
		)
		(fp_line
			(start -0.12065 -0.2794)
			(end 0.12065 -0.2794)
			(stroke
				(width 0.1)
				(type default)
			)
			(layer "F.Fab")
		)
		(fp_line
			(start -0.12065 0.2794)
			(end -0.12065 0.3048)
			(stroke
				(width 0.1)
				(type default)
			)
			(layer "F.Fab")
		)
		(fp_line
			(start -0.12065 0.3048)
			(end -0.67945 0.3048)
			(stroke
				(width 0.1)
				(type default)
			)
			(layer "F.Fab")
		)
		(fp_line
			(start 0.120396 0.2794)
			(end -0.12065 0.2794)
			(stroke
				(width 0.1)
				(type default)
			)
			(layer "F.Fab")
		)
		(fp_line
			(start 0.120396 0.3048)
			(end 0.120396 0.2794)
			(stroke
				(width 0.1)
				(type default)
			)
			(layer "F.Fab")
		)
		(fp_line
			(start 0.12065 -0.3048)
			(end 0.67945 -0.3048)
			(stroke
				(width 0.1)
				(type default)
			)
			(layer "F.Fab")
		)
		(fp_line
			(start 0.12065 -0.2794)
			(end 0.12065 -0.3048)
			(stroke
				(width 0.1)
				(type default)
			)
			(layer "F.Fab")
		)
		(fp_line
			(start 0.67945 -0.3048)
			(end 0.67945 0.3048)
			(stroke
				(width 0.1)
				(type default)
			)
			(layer "F.Fab")
		)
		(fp_line
			(start 0.67945 0.3048)
			(end 0.120396 0.3048)
			(stroke
				(width 0.1)
				(type default)
			)
			(layer "F.Fab")
		)
		(pad "1" smd circle
			(at -0.40005 0)
			(size 0 0)
			(layers "F.Cu" "F.Mask" "F.Paste")
			(net "P3V3_AUX")
		)
		(pad "2" smd circle
			(at 0.40005 0)
			(size 0 0)
			(layers "F.Cu" "F.Mask" "F.Paste")
			(net "SMB_BIC_I2C6_MUX_THERMAL_R_SCL")
		)
	)
	(footprint ""
		(layer "F.Cu")
		(at 313.391804 -350.098614 90)
		(property "Reference" "C550"
			(at 0 0 90)
			(layer "F.SilkS")
			(hide yes)
			(effects
				(font
					(size 1.27 1.27)
				)
			)
		)
		(property "Value" ""
			(at 0 0 90)
			(layer "F.Fab")
			(effects
				(font
					(size 1.27 1.27)
				)
			)
		)
		(duplicate_pad_numbers_are_jumpers no)
		(fp_line
			(start 0.299974 -0.150114)
			(end 0.299974 0.150114)
			(stroke
				(width 0.1)
				(type default)
			)
			(layer "F.Fab")
		)
		(fp_line
			(start -0.299974 -0.150114)
			(end 0.299974 -0.150114)
			(stroke
				(width 0.1)
				(type default)
			)
			(layer "F.Fab")
		)
		(fp_line
			(start 0.299974 0.150114)
			(end -0.299974 0.150114)
			(stroke
				(width 0.1)
				(type default)
			)
			(layer "F.Fab")
		)
		(fp_line
			(start -0.299974 0.150114)
			(end -0.299974 -0.150114)
			(stroke
				(width 0.1)
				(type default)
			)
			(layer "F.Fab")
		)
		(pad "1" smd rect
			(at -0.2667 0 90)
			(size 0.3048 0.381)
			(layers "F.Cu" "F.Mask" "F.Paste")
			(net "P5E_PEX2_STN5_TX_DN<80>")
		)
		(pad "2" smd rect
			(at 0.2667 0 90)
			(size 0.3048 0.381)
			(layers "F.Cu" "F.Mask" "F.Paste")
			(net "P5E_PEX2_STN5_TX_C_DN<80>")
		)
	)
	(footprint ""
		(layer "F.Cu")
		(at 277.854664 -22.867366 90)
		(property "Reference" "C3937"
			(at 0 0 90)
			(layer "F.SilkS")
			(hide yes)
			(effects
				(font
					(size 1.27 1.27)
				)
			)
		)
		(property "Value" ""
			(at 0 0 90)
			(layer "F.Fab")
			(effects
				(font
					(size 1.27 1.27)
				)
			)
		)
		(duplicate_pad_numbers_are_jumpers no)
		(fp_line
			(start 0.7874 -0.4064)
			(end 0.7874 0.4064)
			(stroke
				(width 0.1524)
				(type default)
			)
			(layer "F.SilkS")
		)
		(fp_line
			(start -0.7874 -0.4064)
			(end 0.7874 -0.4064)
			(stroke
				(width 0.1524)
				(type default)
			)
			(layer "F.SilkS")
		)
		(fp_line
			(start 0.7874 0.4064)
			(end -0.7874 0.4064)
			(stroke
				(width 0.1524)
				(type default)
			)
			(layer "F.SilkS")
		)
		(fp_line
			(start -0.7874 0.4064)
			(end -0.7874 -0.4064)
			(stroke
				(width 0.1524)
				(type default)
			)
			(layer "F.SilkS")
		)
		(fp_line
			(start -0.12065 -0.305054)
			(end -0.12065 -0.2794)
			(stroke
				(width 0.1)
				(type default)
			)
			(layer "F.Fab")
		)
		(fp_line
			(start -0.67945 -0.305054)
			(end -0.12065 -0.305054)
			(stroke
				(width 0.1)
				(type default)
			)
			(layer "F.Fab")
		)
		(fp_line
			(start 0.67945 -0.3048)
			(end 0.67945 0.3048)
			(stroke
				(width 0.1)
				(type default)
			)
			(layer "F.Fab")
		)
		(fp_line
			(start 0.12065 -0.3048)
			(end 0.67945 -0.3048)
			(stroke
				(width 0.1)
				(type default)
			)
			(layer "F.Fab")
		)
		(fp_line
			(start 0.12065 -0.2794)
			(end 0.12065 -0.3048)
			(stroke
				(width 0.1)
				(type default)
			)
			(layer "F.Fab")
		)
		(fp_line
			(start -0.12065 -0.2794)
			(end 0.12065 -0.2794)
			(stroke
				(width 0.1)
				(type default)
			)
			(layer "F.Fab")
		)
		(fp_line
			(start 0.120396 0.2794)
			(end -0.12065 0.2794)
			(stroke
				(width 0.1)
				(type default)
			)
			(layer "F.Fab")
		)
		(fp_line
			(start -0.12065 0.2794)
			(end -0.12065 0.3048)
			(stroke
				(width 0.1)
				(type default)
			)
			(layer "F.Fab")
		)
		(fp_line
			(start 0.67945 0.3048)
			(end 0.120396 0.3048)
			(stroke
				(width 0.1)
				(type default)
			)
			(layer "F.Fab")
		)
		(fp_line
			(start 0.120396 0.3048)
			(end 0.120396 0.2794)
			(stroke
				(width 0.1)
				(type default)
			)
			(layer "F.Fab")
		)
		(fp_line
			(start -0.12065 0.3048)
			(end -0.67945 0.3048)
			(stroke
				(width 0.1)
				(type default)
			)
			(layer "F.Fab")
		)
		(fp_line
			(start -0.67945 0.3048)
			(end -0.67945 -0.305054)
			(stroke
				(width 0.1)
				(type default)
			)
			(layer "F.Fab")
		)
		(pad "1" smd circle
			(at -0.40005 0 90)
			(size 0 0)
			(layers "F.Cu" "F.Mask" "F.Paste")
			(net "P12V_SSD9")
		)
		(pad "2" smd circle
			(at 0.40005 0 90)
			(size 0 0)
			(layers "F.Cu" "F.Mask" "F.Paste")
			(net "GND")
		)
	)
	(footprint ""
		(layer "F.Cu")
		(at 341.372444 -343.952322 90)
		(property "Reference" "C524"
			(at 0 0 90)
			(layer "F.SilkS")
			(hide yes)
			(effects
				(font
					(size 1.27 1.27)
				)
			)
		)
		(property "Value" ""
			(at 0 0 90)
			(layer "F.Fab")
			(effects
				(font
					(size 1.27 1.27)
				)
			)
		)
		(duplicate_pad_numbers_are_jumpers no)
		(fp_line
			(start 0.299974 -0.150114)
			(end 0.299974 0.150114)
			(stroke
				(width 0.1)
				(type default)
			)
			(layer "F.Fab")
		)
		(fp_line
			(start -0.299974 -0.150114)
			(end 0.299974 -0.150114)
			(stroke
				(width 0.1)
				(type default)
			)
			(layer "F.Fab")
		)
		(fp_line
			(start 0.299974 0.150114)
			(end -0.299974 0.150114)
			(stroke
				(width 0.1)
				(type default)
			)
			(layer "F.Fab")
		)
		(fp_line
			(start -0.299974 0.150114)
			(end -0.299974 -0.150114)
			(stroke
				(width 0.1)
				(type default)
			)
			(layer "F.Fab")
		)
		(pad "1" smd rect
			(at -0.2667 0 90)
			(size 0.3048 0.381)
			(layers "F.Cu" "F.Mask" "F.Paste")
			(net "P5E_PEX2_STN5_TX_DN<93>")
		)
		(pad "2" smd rect
			(at 0.2667 0 90)
			(size 0.3048 0.381)
			(layers "F.Cu" "F.Mask" "F.Paste")
			(net "P5E_PEX2_STN5_TX_C_DN<93>")
		)
	)
	(footprint ""
		(layer "F.Cu")
		(at 95.475044 -194.183 180)
		(property "Reference" "R6626"
			(at 0 0 180)
			(layer "F.SilkS")
			(hide yes)
			(effects
				(font
					(size 1.27 1.27)
				)
			)
		)
		(property "Value" ""
			(at 0 0 180)
			(layer "F.Fab")
			(effects
				(font
					(size 1.27 1.27)
				)
			)
		)
		(duplicate_pad_numbers_are_jumpers no)
		(fp_line
			(start 0.7874 0.4064)
			(end -0.7874 0.4064)
			(stroke
				(width 0.1524)
				(type default)
			)
			(layer "F.SilkS")
		)
		(fp_line
			(start 0.7874 -0.4064)
			(end 0.7874 0.4064)
			(stroke
				(width 0.1524)
				(type default)
			)
			(layer "F.SilkS")
		)
		(fp_line
			(start -0.7874 0.4064)
			(end -0.7874 -0.4064)
			(stroke
				(width 0.1524)
				(type default)
			)
			(layer "F.SilkS")
		)
		(fp_line
			(start -0.7874 -0.4064)
			(end 0.7874 -0.4064)
			(stroke
				(width 0.1524)
				(type default)
			)
			(layer "F.SilkS")
		)
		(fp_line
			(start 0.67945 0.3048)
			(end 0.120396 0.3048)
			(stroke
				(width 0.1)
				(type default)
			)
			(layer "F.Fab")
		)
		(fp_line
			(start 0.67945 -0.3048)
			(end 0.67945 0.3048)
			(stroke
				(width 0.1)
				(type default)
			)
			(layer "F.Fab")
		)
		(fp_line
			(start 0.12065 -0.2794)
			(end 0.12065 -0.3048)
			(stroke
				(width 0.1)
				(type default)
			)
			(layer "F.Fab")
		)
		(fp_line
			(start 0.12065 -0.3048)
			(end 0.67945 -0.3048)
			(stroke
				(width 0.1)
				(type default)
			)
			(layer "F.Fab")
		)
		(fp_line
			(start 0.120396 0.3048)
			(end 0.120396 0.2794)
			(stroke
				(width 0.1)
				(type default)
			)
			(layer "F.Fab")
		)
		(fp_line
			(start 0.120396 0.2794)
			(end -0.12065 0.2794)
			(stroke
				(width 0.1)
				(type default)
			)
			(layer "F.Fab")
		)
		(fp_line
			(start -0.12065 0.3048)
			(end -0.67945 0.3048)
			(stroke
				(width 0.1)
				(type default)
			)
			(layer "F.Fab")
		)
		(fp_line
			(start -0.12065 0.2794)
			(end -0.12065 0.3048)
			(stroke
				(width 0.1)
				(type default)
			)
			(layer "F.Fab")
		)
		(fp_line
			(start -0.12065 -0.2794)
			(end 0.12065 -0.2794)
			(stroke
				(width 0.1)
				(type default)
			)
			(layer "F.Fab")
		)
		(fp_line
			(start -0.12065 -0.305054)
			(end -0.12065 -0.2794)
			(stroke
				(width 0.1)
				(type default)
			)
			(layer "F.Fab")
		)
		(fp_line
			(start -0.67945 0.3048)
			(end -0.67945 -0.305054)
			(stroke
				(width 0.1)
				(type default)
			)
			(layer "F.Fab")
		)
		(fp_line
			(start -0.67945 -0.305054)
			(end -0.12065 -0.305054)
			(stroke
				(width 0.1)
				(type default)
			)
			(layer "F.Fab")
		)
		(pad "1" smd circle
			(at -0.40005 0 180)
			(size 0 0)
			(layers "F.Cu" "F.Mask" "F.Paste")
			(net "UART_PEX3_CLI_CP2108_RX")
		)
		(pad "2" smd circle
			(at 0.40005 0 180)
			(size 0 0)
			(layers "F.Cu" "F.Mask" "F.Paste")
			(net "UART_PEX3_CLI_R_RX")
		)
	)
	(footprint ""
		(layer "F.Cu")
		(at 278.874982 -56.977534 180)
		(property "Reference" "PC414"
			(at 0 0 180)
			(layer "F.SilkS")
			(hide yes)
			(effects
				(font
					(size 1.27 1.27)
				)
			)
		)
		(property "Value" ""
			(at 0 0 180)
			(layer "F.Fab")
			(effects
				(font
					(size 1.27 1.27)
				)
			)
		)
		(duplicate_pad_numbers_are_jumpers no)
		(fp_line
			(start 0.7874 0.4064)
			(end -0.7874 0.4064)
			(stroke
				(width 0.1524)
				(type default)
			)
			(layer "F.SilkS")
		)
		(fp_line
			(start 0.7874 -0.4064)
			(end 0.7874 0.4064)
			(stroke
				(width 0.1524)
				(type default)
			)
			(layer "F.SilkS")
		)
		(fp_line
			(start -0.7874 0.4064)
			(end -0.7874 -0.4064)
			(stroke
				(width 0.1524)
				(type default)
			)
			(layer "F.SilkS")
		)
		(fp_line
			(start -0.7874 -0.4064)
			(end 0.7874 -0.4064)
			(stroke
				(width 0.1524)
				(type default)
			)
			(layer "F.SilkS")
		)
		(fp_line
			(start 0.67945 0.3048)
			(end 0.120396 0.3048)
			(stroke
				(width 0.1)
				(type default)
			)
			(layer "F.Fab")
		)
		(fp_line
			(start 0.67945 -0.3048)
			(end 0.67945 0.3048)
			(stroke
				(width 0.1)
				(type default)
			)
			(layer "F.Fab")
		)
		(fp_line
			(start 0.12065 -0.2794)
			(end 0.12065 -0.3048)
			(stroke
				(width 0.1)
				(type default)
			)
			(layer "F.Fab")
		)
		(fp_line
			(start 0.12065 -0.3048)
			(end 0.67945 -0.3048)
			(stroke
				(width 0.1)
				(type default)
			)
			(layer "F.Fab")
		)
		(fp_line
			(start 0.120396 0.3048)
			(end 0.120396 0.2794)
			(stroke
				(width 0.1)
				(type default)
			)
			(layer "F.Fab")
		)
		(fp_line
			(start 0.120396 0.2794)
			(end -0.12065 0.2794)
			(stroke
				(width 0.1)
				(type default)
			)
			(layer "F.Fab")
		)
		(fp_line
			(start -0.12065 0.3048)
			(end -0.67945 0.3048)
			(stroke
				(width 0.1)
				(type default)
			)
			(layer "F.Fab")
		)
		(fp_line
			(start -0.12065 0.2794)
			(end -0.12065 0.3048)
			(stroke
				(width 0.1)
				(type default)
			)
			(layer "F.Fab")
		)
		(fp_line
			(start -0.12065 -0.2794)
			(end 0.12065 -0.2794)
			(stroke
				(width 0.1)
				(type default)
			)
			(layer "F.Fab")
		)
		(fp_line
			(start -0.12065 -0.305054)
			(end -0.12065 -0.2794)
			(stroke
				(width 0.1)
				(type default)
			)
			(layer "F.Fab")
		)
		(fp_line
			(start -0.67945 0.3048)
			(end -0.67945 -0.305054)
			(stroke
				(width 0.1)
				(type default)
			)
			(layer "F.Fab")
		)
		(fp_line
			(start -0.67945 -0.305054)
			(end -0.12065 -0.305054)
			(stroke
				(width 0.1)
				(type default)
			)
			(layer "F.Fab")
		)
		(pad "1" smd circle
			(at -0.40005 0 180)
			(size 0 0)
			(layers "F.Cu" "F.Mask" "F.Paste")
			(net "P12V_AUX")
		)
		(pad "2" smd circle
			(at 0.40005 0 180)
			(size 0 0)
			(layers "F.Cu" "F.Mask" "F.Paste")
			(net "GND")
		)
	)
	(footprint ""
		(layer "F.Cu")
		(at 210.59394 -114.886486)
		(property "Reference" "PR7012"
			(at 0 0 0)
			(layer "F.SilkS")
			(hide yes)
			(effects
				(font
					(size 1.27 1.27)
				)
			)
		)
		(property "Value" ""
			(at 0 0 0)
			(layer "F.Fab")
			(effects
				(font
					(size 1.27 1.27)
				)
			)
		)
		(duplicate_pad_numbers_are_jumpers no)
		(fp_line
			(start -0.7874 -0.4064)
			(end 0.7874 -0.4064)
			(stroke
				(width 0.1524)
				(type default)
			)
			(layer "F.SilkS")
		)
		(fp_line
			(start -0.7874 0.4064)
			(end -0.7874 -0.4064)
			(stroke
				(width 0.1524)
				(type default)
			)
			(layer "F.SilkS")
		)
		(fp_line
			(start 0.7874 -0.4064)
			(end 0.7874 0.4064)
			(stroke
				(width 0.1524)
				(type default)
			)
			(layer "F.SilkS")
		)
		(fp_line
			(start 0.7874 0.4064)
			(end -0.7874 0.4064)
			(stroke
				(width 0.1524)
				(type default)
			)
			(layer "F.SilkS")
		)
		(fp_line
			(start -0.67945 -0.305054)
			(end -0.12065 -0.305054)
			(stroke
				(width 0.1)
				(type default)
			)
			(layer "F.Fab")
		)
		(fp_line
			(start -0.67945 0.3048)
			(end -0.67945 -0.305054)
			(stroke
				(width 0.1)
				(type default)
			)
			(layer "F.Fab")
		)
		(fp_line
			(start -0.12065 -0.305054)
			(end -0.12065 -0.2794)
			(stroke
				(width 0.1)
				(type default)
			)
			(layer "F.Fab")
		)
		(fp_line
			(start -0.12065 -0.2794)
			(end 0.12065 -0.2794)
			(stroke
				(width 0.1)
				(type default)
			)
			(layer "F.Fab")
		)
		(fp_line
			(start -0.12065 0.2794)
			(end -0.12065 0.3048)
			(stroke
				(width 0.1)
				(type default)
			)
			(layer "F.Fab")
		)
		(fp_line
			(start -0.12065 0.3048)
			(end -0.67945 0.3048)
			(stroke
				(width 0.1)
				(type default)
			)
			(layer "F.Fab")
		)
		(fp_line
			(start 0.120396 0.2794)
			(end -0.12065 0.2794)
			(stroke
				(width 0.1)
				(type default)
			)
			(layer "F.Fab")
		)
		(fp_line
			(start 0.120396 0.3048)
			(end 0.120396 0.2794)
			(stroke
				(width 0.1)
				(type default)
			)
			(layer "F.Fab")
		)
		(fp_line
			(start 0.12065 -0.3048)
			(end 0.67945 -0.3048)
			(stroke
				(width 0.1)
				(type default)
			)
			(layer "F.Fab")
		)
		(fp_line
			(start 0.12065 -0.2794)
			(end 0.12065 -0.3048)
			(stroke
				(width 0.1)
				(type default)
			)
			(layer "F.Fab")
		)
		(fp_line
			(start 0.67945 -0.3048)
			(end 0.67945 0.3048)
			(stroke
				(width 0.1)
				(type default)
			)
			(layer "F.Fab")
		)
		(fp_line
			(start 0.67945 0.3048)
			(end 0.120396 0.3048)
			(stroke
				(width 0.1)
				(type default)
			)
			(layer "F.Fab")
		)
		(pad "1" smd circle
			(at -0.40005 0)
			(size 0 0)
			(layers "F.Cu" "F.Mask" "F.Paste")
			(net "P3V3_NIC3_CO_MODE")
		)
		(pad "2" smd circle
			(at 0.40005 0)
			(size 0 0)
			(layers "F.Cu" "F.Mask" "F.Paste")
			(net "GND")
		)
	)
	(footprint ""
		(layer "F.Cu")
		(at 188.355224 -35.876738)
		(property "Reference" "R6069"
			(at 0 0 0)
			(layer "F.SilkS")
			(hide yes)
			(effects
				(font
					(size 1.27 1.27)
				)
			)
		)
		(property "Value" ""
			(at 0 0 0)
			(layer "F.Fab")
			(effects
				(font
					(size 1.27 1.27)
				)
			)
		)
		(duplicate_pad_numbers_are_jumpers no)
		(fp_line
			(start -0.7874 -0.4064)
			(end 0.7874 -0.4064)
			(stroke
				(width 0.1524)
				(type default)
			)
			(layer "F.SilkS")
		)
		(fp_line
			(start -0.7874 0.4064)
			(end -0.7874 -0.4064)
			(stroke
				(width 0.1524)
				(type default)
			)
			(layer "F.SilkS")
		)
		(fp_line
			(start 0.7874 -0.4064)
			(end 0.7874 0.4064)
			(stroke
				(width 0.1524)
				(type default)
			)
			(layer "F.SilkS")
		)
		(fp_line
			(start 0.7874 0.4064)
			(end -0.7874 0.4064)
			(stroke
				(width 0.1524)
				(type default)
			)
			(layer "F.SilkS")
		)
		(fp_line
			(start -0.67945 -0.305054)
			(end -0.12065 -0.305054)
			(stroke
				(width 0.1)
				(type default)
			)
			(layer "F.Fab")
		)
		(fp_line
			(start -0.67945 0.3048)
			(end -0.67945 -0.305054)
			(stroke
				(width 0.1)
				(type default)
			)
			(layer "F.Fab")
		)
		(fp_line
			(start -0.12065 -0.305054)
			(end -0.12065 -0.2794)
			(stroke
				(width 0.1)
				(type default)
			)
			(layer "F.Fab")
		)
		(fp_line
			(start -0.12065 -0.2794)
			(end 0.12065 -0.2794)
			(stroke
				(width 0.1)
				(type default)
			)
			(layer "F.Fab")
		)
		(fp_line
			(start -0.12065 0.2794)
			(end -0.12065 0.3048)
			(stroke
				(width 0.1)
				(type default)
			)
			(layer "F.Fab")
		)
		(fp_line
			(start -0.12065 0.3048)
			(end -0.67945 0.3048)
			(stroke
				(width 0.1)
				(type default)
			)
			(layer "F.Fab")
		)
		(fp_line
			(start 0.120396 0.2794)
			(end -0.12065 0.2794)
			(stroke
				(width 0.1)
				(type default)
			)
			(layer "F.Fab")
		)
		(fp_line
			(start 0.120396 0.3048)
			(end 0.120396 0.2794)
			(stroke
				(width 0.1)
				(type default)
			)
			(layer "F.Fab")
		)
		(fp_line
			(start 0.12065 -0.3048)
			(end 0.67945 -0.3048)
			(stroke
				(width 0.1)
				(type default)
			)
			(layer "F.Fab")
		)
		(fp_line
			(start 0.12065 -0.2794)
			(end 0.12065 -0.3048)
			(stroke
				(width 0.1)
				(type default)
			)
			(layer "F.Fab")
		)
		(fp_line
			(start 0.67945 -0.3048)
			(end 0.67945 0.3048)
			(stroke
				(width 0.1)
				(type default)
			)
			(layer "F.Fab")
		)
		(fp_line
			(start 0.67945 0.3048)
			(end 0.120396 0.3048)
			(stroke
				(width 0.1)
				(type default)
			)
			(layer "F.Fab")
		)
		(pad "1" smd circle
			(at -0.40005 0)
			(size 0 0)
			(layers "F.Cu" "F.Mask" "F.Paste")
			(net "P3V3_AUX")
		)
		(pad "2" smd circle
			(at 0.40005 0)
			(size 0 0)
			(layers "F.Cu" "F.Mask" "F.Paste")
			(net "PWRGD_P3V3_SSD7_D")
		)
	)
	(footprint ""
		(layer "F.Cu")
		(at 275.992336 -28.225242 180)
		(property "Reference" "C502"
			(at 0 0 180)
			(layer "F.SilkS")
			(hide yes)
			(effects
				(font
					(size 1.27 1.27)
				)
			)
		)
		(property "Value" ""
			(at 0 0 180)
			(layer "F.Fab")
			(effects
				(font
					(size 1.27 1.27)
				)
			)
		)
		(duplicate_pad_numbers_are_jumpers no)
		(fp_line
			(start 0.299974 0.150114)
			(end -0.299974 0.150114)
			(stroke
				(width 0.1)
				(type default)
			)
			(layer "F.Fab")
		)
		(fp_line
			(start 0.299974 -0.150114)
			(end 0.299974 0.150114)
			(stroke
				(width 0.1)
				(type default)
			)
			(layer "F.Fab")
		)
		(fp_line
			(start -0.299974 0.150114)
			(end -0.299974 -0.150114)
			(stroke
				(width 0.1)
				(type default)
			)
			(layer "F.Fab")
		)
		(fp_line
			(start -0.299974 -0.150114)
			(end 0.299974 -0.150114)
			(stroke
				(width 0.1)
				(type default)
			)
			(layer "F.Fab")
		)
		(pad "1" smd rect
			(at -0.2667 0 180)
			(size 0.3048 0.381)
			(layers "F.Cu" "F.Mask" "F.Paste")
			(net "P5E_PEX2_STN2_TX_DN<40>")
		)
		(pad "2" smd rect
			(at 0.2667 0 180)
			(size 0.3048 0.381)
			(layers "F.Cu" "F.Mask" "F.Paste")
			(net "P5E_PEX2_STN2_TX_C_DN<40>")
		)
	)
	(footprint ""
		(layer "F.Cu")
		(at 445.826642 -55.418228 90)
		(property "Reference" "PC442"
			(at 0 0 90)
			(layer "F.SilkS")
			(hide yes)
			(effects
				(font
					(size 1.27 1.27)
				)
			)
		)
		(property "Value" ""
			(at 0 0 90)
			(layer "F.Fab")
			(effects
				(font
					(size 1.27 1.27)
				)
			)
		)
		(duplicate_pad_numbers_are_jumpers no)
		(fp_line
			(start 0.7874 -0.4064)
			(end 0.7874 0.4064)
			(stroke
				(width 0.1524)
				(type default)
			)
			(layer "F.SilkS")
		)
		(fp_line
			(start -0.7874 -0.4064)
			(end 0.7874 -0.4064)
			(stroke
				(width 0.1524)
				(type default)
			)
			(layer "F.SilkS")
		)
		(fp_line
			(start 0.7874 0.4064)
			(end -0.7874 0.4064)
			(stroke
				(width 0.1524)
				(type default)
			)
			(layer "F.SilkS")
		)
		(fp_line
			(start -0.7874 0.4064)
			(end -0.7874 -0.4064)
			(stroke
				(width 0.1524)
				(type default)
			)
			(layer "F.SilkS")
		)
		(fp_line
			(start -0.12065 -0.305054)
			(end -0.12065 -0.2794)
			(stroke
				(width 0.1)
				(type default)
			)
			(layer "F.Fab")
		)
		(fp_line
			(start -0.67945 -0.305054)
			(end -0.12065 -0.305054)
			(stroke
				(width 0.1)
				(type default)
			)
			(layer "F.Fab")
		)
		(fp_line
			(start 0.67945 -0.3048)
			(end 0.67945 0.3048)
			(stroke
				(width 0.1)
				(type default)
			)
			(layer "F.Fab")
		)
		(fp_line
			(start 0.12065 -0.3048)
			(end 0.67945 -0.3048)
			(stroke
				(width 0.1)
				(type default)
			)
			(layer "F.Fab")
		)
		(fp_line
			(start 0.12065 -0.2794)
			(end 0.12065 -0.3048)
			(stroke
				(width 0.1)
				(type default)
			)
			(layer "F.Fab")
		)
		(fp_line
			(start -0.12065 -0.2794)
			(end 0.12065 -0.2794)
			(stroke
				(width 0.1)
				(type default)
			)
			(layer "F.Fab")
		)
		(fp_line
			(start 0.120396 0.2794)
			(end -0.12065 0.2794)
			(stroke
				(width 0.1)
				(type default)
			)
			(layer "F.Fab")
		)
		(fp_line
			(start -0.12065 0.2794)
			(end -0.12065 0.3048)
			(stroke
				(width 0.1)
				(type default)
			)
			(layer "F.Fab")
		)
		(fp_line
			(start 0.67945 0.3048)
			(end 0.120396 0.3048)
			(stroke
				(width 0.1)
				(type default)
			)
			(layer "F.Fab")
		)
		(fp_line
			(start 0.120396 0.3048)
			(end 0.120396 0.2794)
			(stroke
				(width 0.1)
				(type default)
			)
			(layer "F.Fab")
		)
		(fp_line
			(start -0.12065 0.3048)
			(end -0.67945 0.3048)
			(stroke
				(width 0.1)
				(type default)
			)
			(layer "F.Fab")
		)
		(fp_line
			(start -0.67945 0.3048)
			(end -0.67945 -0.305054)
			(stroke
				(width 0.1)
				(type default)
			)
			(layer "F.Fab")
		)
		(pad "1" smd circle
			(at -0.40005 0 90)
			(size 0 0)
			(layers "F.Cu" "F.Mask" "F.Paste")
			(net "P12V_SSD15_R")
		)
		(pad "2" smd circle
			(at 0.40005 0 90)
			(size 0 0)
			(layers "F.Cu" "F.Mask" "F.Paste")
			(net "GND")
		)
	)
	(footprint ""
		(layer "F.Cu")
		(at 228.980746 -118.984268 90)
		(property "Reference" "PR6891"
			(at 0 0 90)
			(layer "F.SilkS")
			(hide yes)
			(effects
				(font
					(size 1.27 1.27)
				)
			)
		)
		(property "Value" ""
			(at 0 0 90)
			(layer "F.Fab")
			(effects
				(font
					(size 1.27 1.27)
				)
			)
		)
		(duplicate_pad_numbers_are_jumpers no)
		(fp_line
			(start 1.2954 -0.5842)
			(end 1.2954 0.5842)
			(stroke
				(width 0.1524)
				(type default)
			)
			(layer "F.SilkS")
		)
		(fp_line
			(start -1.2954 -0.5842)
			(end 1.2954 -0.5842)
			(stroke
				(width 0.1524)
				(type default)
			)
			(layer "F.SilkS")
		)
		(fp_line
			(start 1.2954 0.5842)
			(end -1.2954 0.5842)
			(stroke
				(width 0.1524)
				(type default)
			)
			(layer "F.SilkS")
		)
		(fp_line
			(start -1.2954 0.5842)
			(end -1.2954 -0.5842)
			(stroke
				(width 0.1524)
				(type default)
			)
			(layer "F.SilkS")
		)
		(fp_line
			(start 0.8636 -0.4572)
			(end 0.8636 -0.406654)
			(stroke
				(width 0.1)
				(type default)
			)
			(layer "F.Fab")
		)
		(fp_line
			(start -0.8636 -0.4572)
			(end 0.8636 -0.4572)
			(stroke
				(width 0.1)
				(type default)
			)
			(layer "F.Fab")
		)
		(fp_line
			(start 1.1938 -0.406654)
			(end 1.1938 0.4064)
			(stroke
				(width 0.1)
				(type default)
			)
			(layer "F.Fab")
		)
		(fp_line
			(start 0.8636 -0.406654)
			(end 1.1938 -0.406654)
			(stroke
				(width 0.1)
				(type default)
			)
			(layer "F.Fab")
		)
		(fp_line
			(start -0.8636 -0.406654)
			(end -0.8636 -0.4572)
			(stroke
				(width 0.1)
				(type default)
			)
			(layer "F.Fab")
		)
		(fp_line
			(start -1.1938 -0.406654)
			(end -0.8636 -0.406654)
			(stroke
				(width 0.1)
				(type default)
			)
			(layer "F.Fab")
		)
		(fp_line
			(start 1.1938 0.4064)
			(end 0.8636 0.4064)
			(stroke
				(width 0.1)
				(type default)
			)
			(layer "F.Fab")
		)
		(fp_line
			(start 0.8636 0.4064)
			(end 0.8636 0.4572)
			(stroke
				(width 0.1)
				(type default)
			)
			(layer "F.Fab")
		)
		(fp_line
			(start -0.8636 0.4064)
			(end -1.1938 0.4064)
			(stroke
				(width 0.1)
				(type default)
			)
			(layer "F.Fab")
		)
		(fp_line
			(start -1.1938 0.4064)
			(end -1.1938 -0.406654)
			(stroke
				(width 0.1)
				(type default)
			)
			(layer "F.Fab")
		)
		(fp_line
			(start -0.8636 0.4318)
			(end -0.8636 0.4064)
			(stroke
				(width 0.1)
				(type default)
			)
			(layer "F.Fab")
		)
		(fp_line
			(start 0.8636 0.4572)
			(end -0.8636 0.4572)
			(stroke
				(width 0.1)
				(type default)
			)
			(layer "F.Fab")
		)
		(fp_line
			(start -0.8636 0.4572)
			(end -0.8636 0.4318)
			(stroke
				(width 0.1)
				(type default)
			)
			(layer "F.Fab")
		)
		(pad "1" smd rect
			(at -0.7366 0)
			(size 0.7112 0.8128)
			(layers "F.Cu" "F.Mask" "F.Paste")
			(net "P12V_NIC3_CO_AVIN_PD")
		)
		(pad "2" smd rect
			(at 0.7366 0)
			(size 0.7112 0.8128)
			(layers "F.Cu" "F.Mask" "F.Paste")
			(net "P12V_AUX")
		)
	)
	(footprint ""
		(layer "F.Cu")
		(at 238.208312 -226.368864)
		(property "Reference" "R6594"
			(at 0 0 0)
			(layer "F.SilkS")
			(hide yes)
			(effects
				(font
					(size 1.27 1.27)
				)
			)
		)
		(property "Value" ""
			(at 0 0 0)
			(layer "F.Fab")
			(effects
				(font
					(size 1.27 1.27)
				)
			)
		)
		(duplicate_pad_numbers_are_jumpers no)
		(fp_line
			(start -0.7874 -0.4064)
			(end 0.7874 -0.4064)
			(stroke
				(width 0.1524)
				(type default)
			)
			(layer "F.SilkS")
		)
		(fp_line
			(start -0.7874 0.4064)
			(end -0.7874 -0.4064)
			(stroke
				(width 0.1524)
				(type default)
			)
			(layer "F.SilkS")
		)
		(fp_line
			(start 0.7874 -0.4064)
			(end 0.7874 0.4064)
			(stroke
				(width 0.1524)
				(type default)
			)
			(layer "F.SilkS")
		)
		(fp_line
			(start 0.7874 0.4064)
			(end -0.7874 0.4064)
			(stroke
				(width 0.1524)
				(type default)
			)
			(layer "F.SilkS")
		)
		(fp_line
			(start -0.67945 -0.305054)
			(end -0.12065 -0.305054)
			(stroke
				(width 0.1)
				(type default)
			)
			(layer "F.Fab")
		)
		(fp_line
			(start -0.67945 0.3048)
			(end -0.67945 -0.305054)
			(stroke
				(width 0.1)
				(type default)
			)
			(layer "F.Fab")
		)
		(fp_line
			(start -0.12065 -0.305054)
			(end -0.12065 -0.2794)
			(stroke
				(width 0.1)
				(type default)
			)
			(layer "F.Fab")
		)
		(fp_line
			(start -0.12065 -0.2794)
			(end 0.12065 -0.2794)
			(stroke
				(width 0.1)
				(type default)
			)
			(layer "F.Fab")
		)
		(fp_line
			(start -0.12065 0.2794)
			(end -0.12065 0.3048)
			(stroke
				(width 0.1)
				(type default)
			)
			(layer "F.Fab")
		)
		(fp_line
			(start -0.12065 0.3048)
			(end -0.67945 0.3048)
			(stroke
				(width 0.1)
				(type default)
			)
			(layer "F.Fab")
		)
		(fp_line
			(start 0.120396 0.2794)
			(end -0.12065 0.2794)
			(stroke
				(width 0.1)
				(type default)
			)
			(layer "F.Fab")
		)
		(fp_line
			(start 0.120396 0.3048)
			(end 0.120396 0.2794)
			(stroke
				(width 0.1)
				(type default)
			)
			(layer "F.Fab")
		)
		(fp_line
			(start 0.12065 -0.3048)
			(end 0.67945 -0.3048)
			(stroke
				(width 0.1)
				(type default)
			)
			(layer "F.Fab")
		)
		(fp_line
			(start 0.12065 -0.2794)
			(end 0.12065 -0.3048)
			(stroke
				(width 0.1)
				(type default)
			)
			(layer "F.Fab")
		)
		(fp_line
			(start 0.67945 -0.3048)
			(end 0.67945 0.3048)
			(stroke
				(width 0.1)
				(type default)
			)
			(layer "F.Fab")
		)
		(fp_line
			(start 0.67945 0.3048)
			(end 0.120396 0.3048)
			(stroke
				(width 0.1)
				(type default)
			)
			(layer "F.Fab")
		)
		(pad "1" smd circle
			(at -0.40005 0)
			(size 0 0)
			(layers "F.Cu" "F.Mask" "F.Paste")
			(net "P1V8_PLL0_PEX3")
		)
		(pad "2" smd circle
			(at 0.40005 0)
			(size 0 0)
			(layers "F.Cu" "F.Mask" "F.Paste")
			(net "P1V8_PLL0_PEX3_SCALED")
		)
	)
	(footprint ""
		(layer "F.Cu")
		(at 222.619316 -122.758962)
		(property "Reference" "Q215"
			(at 0.486918 -1.943862 0)
			(unlocked yes)
			(layer "F.SilkS")
			(effects
				(font
					(size 0.7874 0.5842)
					(thickness 0.1524)
				)
			)
		)
		(property "Value" ""
			(at 0 0 0)
			(layer "F.Fab")
			(effects
				(font
					(size 1.27 1.27)
				)
			)
		)
		(duplicate_pad_numbers_are_jumpers no)
		(fp_line
			(start -1.376172 -1.199896)
			(end -0.508 -1.199896)
			(stroke
				(width 0.1524)
				(type default)
			)
			(layer "F.SilkS")
		)
		(fp_line
			(start -1.376172 1.199896)
			(end -1.376172 -1.199896)
			(stroke
				(width 0.1524)
				(type default)
			)
			(layer "F.SilkS")
		)
		(fp_line
			(start -0.508 -1.199896)
			(end 0 -0.762)
			(stroke
				(width 0.1524)
				(type default)
			)
			(layer "F.SilkS")
		)
		(fp_line
			(start 0 -0.762)
			(end 0.508 -1.199896)
			(stroke
				(width 0.1524)
				(type default)
			)
			(layer "F.SilkS")
		)
		(fp_line
			(start 0.508 -1.199896)
			(end 1.376172 -1.199896)
			(stroke
				(width 0.1524)
				(type default)
			)
			(layer "F.SilkS")
		)
		(fp_line
			(start 1.376172 -1.199896)
			(end 1.376172 1.199896)
			(stroke
				(width 0.1524)
				(type default)
			)
			(layer "F.SilkS")
		)
		(fp_line
			(start 1.376172 1.199896)
			(end -1.376172 1.199896)
			(stroke
				(width 0.1524)
				(type default)
			)
			(layer "F.SilkS")
		)
		(fp_poly
			(pts
				(xy -1.130554 -1.321308) (xy -1.400048 -2.129536) (xy -1.938782 -1.590548)
			)
			(stroke
				(width 0)
				(type default)
			)
			(fill yes)
			(layer "F.SilkS")
		)
		(fp_line
			(start -0.674878 -1.100074)
			(end 0.674878 -1.100074)
			(stroke
				(width 0.1)
				(type default)
			)
			(layer "F.Fab")
		)
		(fp_line
			(start -0.674878 1.100074)
			(end -0.674878 -1.100074)
			(stroke
				(width 0.1)
				(type default)
			)
			(layer "F.Fab")
		)
		(fp_line
			(start 0.674878 -1.100074)
			(end 0.674878 1.100074)
			(stroke
				(width 0.1)
				(type default)
			)
			(layer "F.Fab")
		)
		(fp_line
			(start 0.674878 1.100074)
			(end -0.674878 1.100074)
			(stroke
				(width 0.1)
				(type default)
			)
			(layer "F.Fab")
		)
		(fp_poly
			(pts
				(xy -1.4605 -0.7493) (xy -2.2225 -1.1303) (xy -2.2225 -0.3683)
			)
			(stroke
				(width 0)
				(type default)
			)
			(fill yes)
			(layer "F.Fab")
		)
		(pad "1" smd rect
			(at -0.899922 -0.750062 270)
			(size 0.6096 0.6096)
			(layers "F.Cu" "F.Mask" "F.Paste")
			(net "GND")
		)
		(pad "2" smd rect
			(at -0.899922 0 270)
			(size 0.4064 0.6096)
			(layers "F.Cu" "F.Mask" "F.Paste")
			(net "P3V3_NIC3_PG_G1")
		)
		(pad "3" smd rect
			(at -0.899922 0.750062 270)
			(size 0.6096 0.6096)
			(layers "F.Cu" "F.Mask" "F.Paste")
			(net "PWRGD_P3V3_NIC3_D")
		)
		(pad "4" smd rect
			(at 0.899922 0.750062 270)
			(size 0.6096 0.6096)
			(layers "F.Cu" "F.Mask" "F.Paste")
			(net "GND")
		)
		(pad "5" smd rect
			(at 0.899922 0 270)
			(size 0.4064 0.6096)
			(layers "F.Cu" "F.Mask" "F.Paste")
			(net "P3V3_NIC3_PG_G2")
		)
		(pad "6" smd rect
			(at 0.899922 -0.750062 270)
			(size 0.6096 0.6096)
			(layers "F.Cu" "F.Mask" "F.Paste")
			(net "P3V3_NIC3_PG_G2")
		)
	)
	(footprint ""
		(layer "F.Cu")
		(at 149.080728 -381.428498)
		(property "Reference" "R1842"
			(at 0 0 0)
			(layer "F.SilkS")
			(hide yes)
			(effects
				(font
					(size 1.27 1.27)
				)
			)
		)
		(property "Value" ""
			(at 0 0 0)
			(layer "F.Fab")
			(effects
				(font
					(size 1.27 1.27)
				)
			)
		)
		(duplicate_pad_numbers_are_jumpers no)
		(fp_line
			(start -0.7874 -0.4064)
			(end 0.7874 -0.4064)
			(stroke
				(width 0.1524)
				(type default)
			)
			(layer "F.SilkS")
		)
		(fp_line
			(start -0.7874 0.4064)
			(end -0.7874 -0.4064)
			(stroke
				(width 0.1524)
				(type default)
			)
			(layer "F.SilkS")
		)
		(fp_line
			(start 0.7874 -0.4064)
			(end 0.7874 0.4064)
			(stroke
				(width 0.1524)
				(type default)
			)
			(layer "F.SilkS")
		)
		(fp_line
			(start 0.7874 0.4064)
			(end -0.7874 0.4064)
			(stroke
				(width 0.1524)
				(type default)
			)
			(layer "F.SilkS")
		)
		(fp_line
			(start -0.67945 -0.305054)
			(end -0.12065 -0.305054)
			(stroke
				(width 0.1)
				(type default)
			)
			(layer "F.Fab")
		)
		(fp_line
			(start -0.67945 0.3048)
			(end -0.67945 -0.305054)
			(stroke
				(width 0.1)
				(type default)
			)
			(layer "F.Fab")
		)
		(fp_line
			(start -0.12065 -0.305054)
			(end -0.12065 -0.2794)
			(stroke
				(width 0.1)
				(type default)
			)
			(layer "F.Fab")
		)
		(fp_line
			(start -0.12065 -0.2794)
			(end 0.12065 -0.2794)
			(stroke
				(width 0.1)
				(type default)
			)
			(layer "F.Fab")
		)
		(fp_line
			(start -0.12065 0.2794)
			(end -0.12065 0.3048)
			(stroke
				(width 0.1)
				(type default)
			)
			(layer "F.Fab")
		)
		(fp_line
			(start -0.12065 0.3048)
			(end -0.67945 0.3048)
			(stroke
				(width 0.1)
				(type default)
			)
			(layer "F.Fab")
		)
		(fp_line
			(start 0.120396 0.2794)
			(end -0.12065 0.2794)
			(stroke
				(width 0.1)
				(type default)
			)
			(layer "F.Fab")
		)
		(fp_line
			(start 0.120396 0.3048)
			(end 0.120396 0.2794)
			(stroke
				(width 0.1)
				(type default)
			)
			(layer "F.Fab")
		)
		(fp_line
			(start 0.12065 -0.3048)
			(end 0.67945 -0.3048)
			(stroke
				(width 0.1)
				(type default)
			)
			(layer "F.Fab")
		)
		(fp_line
			(start 0.12065 -0.2794)
			(end 0.12065 -0.3048)
			(stroke
				(width 0.1)
				(type default)
			)
			(layer "F.Fab")
		)
		(fp_line
			(start 0.67945 -0.3048)
			(end 0.67945 0.3048)
			(stroke
				(width 0.1)
				(type default)
			)
			(layer "F.Fab")
		)
		(fp_line
			(start 0.67945 0.3048)
			(end 0.120396 0.3048)
			(stroke
				(width 0.1)
				(type default)
			)
			(layer "F.Fab")
		)
		(pad "1" smd circle
			(at -0.40005 0)
			(size 0 0)
			(layers "F.Cu" "F.Mask" "F.Paste")
			(net "GPU_3V3IO_RSVD1_FFU_R")
		)
		(pad "2" smd circle
			(at 0.40005 0)
			(size 0 0)
			(layers "F.Cu" "F.Mask" "F.Paste")
			(net "GPU_3V3IO_RSVD1_FFU")
		)
	)
	(footprint ""
		(layer "F.Cu")
		(at 136.870948 -146.205956 180)
		(property "Reference" "C417"
			(at 0 0 180)
			(layer "F.SilkS")
			(hide yes)
			(effects
				(font
					(size 1.27 1.27)
				)
			)
		)
		(property "Value" ""
			(at 0 0 180)
			(layer "F.Fab")
			(effects
				(font
					(size 1.27 1.27)
				)
			)
		)
		(duplicate_pad_numbers_are_jumpers no)
		(fp_line
			(start 0.7874 0.4064)
			(end -0.7874 0.4064)
			(stroke
				(width 0.1524)
				(type default)
			)
			(layer "F.SilkS")
		)
		(fp_line
			(start 0.7874 -0.4064)
			(end 0.7874 0.4064)
			(stroke
				(width 0.1524)
				(type default)
			)
			(layer "F.SilkS")
		)
		(fp_line
			(start -0.7874 0.4064)
			(end -0.7874 -0.4064)
			(stroke
				(width 0.1524)
				(type default)
			)
			(layer "F.SilkS")
		)
		(fp_line
			(start -0.7874 -0.4064)
			(end 0.7874 -0.4064)
			(stroke
				(width 0.1524)
				(type default)
			)
			(layer "F.SilkS")
		)
		(fp_line
			(start 0.67945 0.3048)
			(end 0.120396 0.3048)
			(stroke
				(width 0.1)
				(type default)
			)
			(layer "F.Fab")
		)
		(fp_line
			(start 0.67945 -0.3048)
			(end 0.67945 0.3048)
			(stroke
				(width 0.1)
				(type default)
			)
			(layer "F.Fab")
		)
		(fp_line
			(start 0.12065 -0.2794)
			(end 0.12065 -0.3048)
			(stroke
				(width 0.1)
				(type default)
			)
			(layer "F.Fab")
		)
		(fp_line
			(start 0.12065 -0.3048)
			(end 0.67945 -0.3048)
			(stroke
				(width 0.1)
				(type default)
			)
			(layer "F.Fab")
		)
		(fp_line
			(start 0.120396 0.3048)
			(end 0.120396 0.2794)
			(stroke
				(width 0.1)
				(type default)
			)
			(layer "F.Fab")
		)
		(fp_line
			(start 0.120396 0.2794)
			(end -0.12065 0.2794)
			(stroke
				(width 0.1)
				(type default)
			)
			(layer "F.Fab")
		)
		(fp_line
			(start -0.12065 0.3048)
			(end -0.67945 0.3048)
			(stroke
				(width 0.1)
				(type default)
			)
			(layer "F.Fab")
		)
		(fp_line
			(start -0.12065 0.2794)
			(end -0.12065 0.3048)
			(stroke
				(width 0.1)
				(type default)
			)
			(layer "F.Fab")
		)
		(fp_line
			(start -0.12065 -0.2794)
			(end 0.12065 -0.2794)
			(stroke
				(width 0.1)
				(type default)
			)
			(layer "F.Fab")
		)
		(fp_line
			(start -0.12065 -0.305054)
			(end -0.12065 -0.2794)
			(stroke
				(width 0.1)
				(type default)
			)
			(layer "F.Fab")
		)
		(fp_line
			(start -0.67945 0.3048)
			(end -0.67945 -0.305054)
			(stroke
				(width 0.1)
				(type default)
			)
			(layer "F.Fab")
		)
		(fp_line
			(start -0.67945 -0.305054)
			(end -0.12065 -0.305054)
			(stroke
				(width 0.1)
				(type default)
			)
			(layer "F.Fab")
		)
		(pad "1" smd circle
			(at -0.40005 0 180)
			(size 0 0)
			(layers "F.Cu" "F.Mask" "F.Paste")
			(net "P12V_NIC2_VIN_P")
		)
		(pad "2" smd circle
			(at 0.40005 0 180)
			(size 0 0)
			(layers "F.Cu" "F.Mask" "F.Paste")
			(net "P12V_NIC2_VIN_N")
		)
	)
	(footprint ""
		(layer "F.Cu")
		(at 434.296058 -306.02936 -90)
		(property "Reference" "R6812"
			(at 0 0 270)
			(layer "F.SilkS")
			(hide yes)
			(effects
				(font
					(size 1.27 1.27)
				)
			)
		)
		(property "Value" ""
			(at 0 0 270)
			(layer "F.Fab")
			(effects
				(font
					(size 1.27 1.27)
				)
			)
		)
		(duplicate_pad_numbers_are_jumpers no)
		(fp_line
			(start -0.7874 0.4064)
			(end -0.7874 -0.4064)
			(stroke
				(width 0.1524)
				(type default)
			)
			(layer "F.SilkS")
		)
		(fp_line
			(start 0.7874 0.4064)
			(end -0.7874 0.4064)
			(stroke
				(width 0.1524)
				(type default)
			)
			(layer "F.SilkS")
		)
		(fp_line
			(start -0.7874 -0.4064)
			(end 0.7874 -0.4064)
			(stroke
				(width 0.1524)
				(type default)
			)
			(layer "F.SilkS")
		)
		(fp_line
			(start 0.7874 -0.4064)
			(end 0.7874 0.4064)
			(stroke
				(width 0.1524)
				(type default)
			)
			(layer "F.SilkS")
		)
		(fp_line
			(start -0.67945 0.3048)
			(end -0.67945 -0.305054)
			(stroke
				(width 0.1)
				(type default)
			)
			(layer "F.Fab")
		)
		(fp_line
			(start -0.12065 0.3048)
			(end -0.67945 0.3048)
			(stroke
				(width 0.1)
				(type default)
			)
			(layer "F.Fab")
		)
		(fp_line
			(start 0.120396 0.3048)
			(end 0.120396 0.2794)
			(stroke
				(width 0.1)
				(type default)
			)
			(layer "F.Fab")
		)
		(fp_line
			(start 0.67945 0.3048)
			(end 0.120396 0.3048)
			(stroke
				(width 0.1)
				(type default)
			)
			(layer "F.Fab")
		)
		(fp_line
			(start -0.12065 0.2794)
			(end -0.12065 0.3048)
			(stroke
				(width 0.1)
				(type default)
			)
			(layer "F.Fab")
		)
		(fp_line
			(start 0.120396 0.2794)
			(end -0.12065 0.2794)
			(stroke
				(width 0.1)
				(type default)
			)
			(layer "F.Fab")
		)
		(fp_line
			(start -0.12065 -0.2794)
			(end 0.12065 -0.2794)
			(stroke
				(width 0.1)
				(type default)
			)
			(layer "F.Fab")
		)
		(fp_line
			(start 0.12065 -0.2794)
			(end 0.12065 -0.3048)
			(stroke
				(width 0.1)
				(type default)
			)
			(layer "F.Fab")
		)
		(fp_line
			(start 0.12065 -0.3048)
			(end 0.67945 -0.3048)
			(stroke
				(width 0.1)
				(type default)
			)
			(layer "F.Fab")
		)
		(fp_line
			(start 0.67945 -0.3048)
			(end 0.67945 0.3048)
			(stroke
				(width 0.1)
				(type default)
			)
			(layer "F.Fab")
		)
		(fp_line
			(start -0.67945 -0.305054)
			(end -0.12065 -0.305054)
			(stroke
				(width 0.1)
				(type default)
			)
			(layer "F.Fab")
		)
		(fp_line
			(start -0.12065 -0.305054)
			(end -0.12065 -0.2794)
			(stroke
				(width 0.1)
				(type default)
			)
			(layer "F.Fab")
		)
		(pad "1" smd circle
			(at -0.40005 0 270)
			(size 0 0)
			(layers "F.Cu" "F.Mask" "F.Paste")
			(net "SMB_PEX3_R_SCL")
		)
		(pad "2" smd circle
			(at 0.40005 0 270)
			(size 0 0)
			(layers "F.Cu" "F.Mask" "F.Paste")
			(net "SMB_PEX3_SCL")
		)
	)
	(footprint ""
		(layer "F.Cu")
		(at 447.58991 -72.766682 90)
		(property "Reference" "PR7096"
			(at 0 0 90)
			(layer "F.SilkS")
			(hide yes)
			(effects
				(font
					(size 1.27 1.27)
				)
			)
		)
		(property "Value" ""
			(at 0 0 90)
			(layer "F.Fab")
			(effects
				(font
					(size 1.27 1.27)
				)
			)
		)
		(duplicate_pad_numbers_are_jumpers no)
		(fp_line
			(start 0.7874 -0.4064)
			(end 0.7874 0.4064)
			(stroke
				(width 0.1524)
				(type default)
			)
			(layer "F.SilkS")
		)
		(fp_line
			(start -0.7874 -0.4064)
			(end 0.7874 -0.4064)
			(stroke
				(width 0.1524)
				(type default)
			)
			(layer "F.SilkS")
		)
		(fp_line
			(start 0.7874 0.4064)
			(end -0.7874 0.4064)
			(stroke
				(width 0.1524)
				(type default)
			)
			(layer "F.SilkS")
		)
		(fp_line
			(start -0.7874 0.4064)
			(end -0.7874 -0.4064)
			(stroke
				(width 0.1524)
				(type default)
			)
			(layer "F.SilkS")
		)
		(fp_line
			(start -0.12065 -0.305054)
			(end -0.12065 -0.2794)
			(stroke
				(width 0.1)
				(type default)
			)
			(layer "F.Fab")
		)
		(fp_line
			(start -0.67945 -0.305054)
			(end -0.12065 -0.305054)
			(stroke
				(width 0.1)
				(type default)
			)
			(layer "F.Fab")
		)
		(fp_line
			(start 0.67945 -0.3048)
			(end 0.67945 0.3048)
			(stroke
				(width 0.1)
				(type default)
			)
			(layer "F.Fab")
		)
		(fp_line
			(start 0.12065 -0.3048)
			(end 0.67945 -0.3048)
			(stroke
				(width 0.1)
				(type default)
			)
			(layer "F.Fab")
		)
		(fp_line
			(start 0.12065 -0.2794)
			(end 0.12065 -0.3048)
			(stroke
				(width 0.1)
				(type default)
			)
			(layer "F.Fab")
		)
		(fp_line
			(start -0.12065 -0.2794)
			(end 0.12065 -0.2794)
			(stroke
				(width 0.1)
				(type default)
			)
			(layer "F.Fab")
		)
		(fp_line
			(start 0.120396 0.2794)
			(end -0.12065 0.2794)
			(stroke
				(width 0.1)
				(type default)
			)
			(layer "F.Fab")
		)
		(fp_line
			(start -0.12065 0.2794)
			(end -0.12065 0.3048)
			(stroke
				(width 0.1)
				(type default)
			)
			(layer "F.Fab")
		)
		(fp_line
			(start 0.67945 0.3048)
			(end 0.120396 0.3048)
			(stroke
				(width 0.1)
				(type default)
			)
			(layer "F.Fab")
		)
		(fp_line
			(start 0.120396 0.3048)
			(end 0.120396 0.2794)
			(stroke
				(width 0.1)
				(type default)
			)
			(layer "F.Fab")
		)
		(fp_line
			(start -0.12065 0.3048)
			(end -0.67945 0.3048)
			(stroke
				(width 0.1)
				(type default)
			)
			(layer "F.Fab")
		)
		(fp_line
			(start -0.67945 0.3048)
			(end -0.67945 -0.305054)
			(stroke
				(width 0.1)
				(type default)
			)
			(layer "F.Fab")
		)
		(pad "1" smd circle
			(at -0.40005 0 90)
			(size 0 0)
			(layers "F.Cu" "F.Mask" "F.Paste")
			(net "P12V_SSD15_CO_ILIMIT")
		)
		(pad "2" smd circle
			(at 0.40005 0 90)
			(size 0 0)
			(layers "F.Cu" "F.Mask" "F.Paste")
			(net "GND")
		)
	)
	(footprint ""
		(layer "F.Cu")
		(at 250.111768 -146.263614 180)
		(property "Reference" "C422"
			(at 0 0 180)
			(layer "F.SilkS")
			(hide yes)
			(effects
				(font
					(size 1.27 1.27)
				)
			)
		)
		(property "Value" ""
			(at 0 0 180)
			(layer "F.Fab")
			(effects
				(font
					(size 1.27 1.27)
				)
			)
		)
		(duplicate_pad_numbers_are_jumpers no)
		(fp_line
			(start 0.7874 0.4064)
			(end -0.7874 0.4064)
			(stroke
				(width 0.1524)
				(type default)
			)
			(layer "F.SilkS")
		)
		(fp_line
			(start 0.7874 -0.4064)
			(end 0.7874 0.4064)
			(stroke
				(width 0.1524)
				(type default)
			)
			(layer "F.SilkS")
		)
		(fp_line
			(start -0.7874 0.4064)
			(end -0.7874 -0.4064)
			(stroke
				(width 0.1524)
				(type default)
			)
			(layer "F.SilkS")
		)
		(fp_line
			(start -0.7874 -0.4064)
			(end 0.7874 -0.4064)
			(stroke
				(width 0.1524)
				(type default)
			)
			(layer "F.SilkS")
		)
		(fp_line
			(start 0.67945 0.3048)
			(end 0.120396 0.3048)
			(stroke
				(width 0.1)
				(type default)
			)
			(layer "F.Fab")
		)
		(fp_line
			(start 0.67945 -0.3048)
			(end 0.67945 0.3048)
			(stroke
				(width 0.1)
				(type default)
			)
			(layer "F.Fab")
		)
		(fp_line
			(start 0.12065 -0.2794)
			(end 0.12065 -0.3048)
			(stroke
				(width 0.1)
				(type default)
			)
			(layer "F.Fab")
		)
		(fp_line
			(start 0.12065 -0.3048)
			(end 0.67945 -0.3048)
			(stroke
				(width 0.1)
				(type default)
			)
			(layer "F.Fab")
		)
		(fp_line
			(start 0.120396 0.3048)
			(end 0.120396 0.2794)
			(stroke
				(width 0.1)
				(type default)
			)
			(layer "F.Fab")
		)
		(fp_line
			(start 0.120396 0.2794)
			(end -0.12065 0.2794)
			(stroke
				(width 0.1)
				(type default)
			)
			(layer "F.Fab")
		)
		(fp_line
			(start -0.12065 0.3048)
			(end -0.67945 0.3048)
			(stroke
				(width 0.1)
				(type default)
			)
			(layer "F.Fab")
		)
		(fp_line
			(start -0.12065 0.2794)
			(end -0.12065 0.3048)
			(stroke
				(width 0.1)
				(type default)
			)
			(layer "F.Fab")
		)
		(fp_line
			(start -0.12065 -0.2794)
			(end 0.12065 -0.2794)
			(stroke
				(width 0.1)
				(type default)
			)
			(layer "F.Fab")
		)
		(fp_line
			(start -0.12065 -0.305054)
			(end -0.12065 -0.2794)
			(stroke
				(width 0.1)
				(type default)
			)
			(layer "F.Fab")
		)
		(fp_line
			(start -0.67945 0.3048)
			(end -0.67945 -0.305054)
			(stroke
				(width 0.1)
				(type default)
			)
			(layer "F.Fab")
		)
		(fp_line
			(start -0.67945 -0.305054)
			(end -0.12065 -0.305054)
			(stroke
				(width 0.1)
				(type default)
			)
			(layer "F.Fab")
		)
		(pad "1" smd circle
			(at -0.40005 0 180)
			(size 0 0)
			(layers "F.Cu" "F.Mask" "F.Paste")
			(net "P12V_NIC4_R")
		)
		(pad "2" smd circle
			(at 0.40005 0 180)
			(size 0 0)
			(layers "F.Cu" "F.Mask" "F.Paste")
			(net "GND")
		)
	)
	(footprint ""
		(layer "F.Cu")
		(at 108.260896 -392.778488)
		(property "Reference" "R6844"
			(at 0 0 0)
			(layer "F.SilkS")
			(hide yes)
			(effects
				(font
					(size 1.27 1.27)
				)
			)
		)
		(property "Value" ""
			(at 0 0 0)
			(layer "F.Fab")
			(effects
				(font
					(size 1.27 1.27)
				)
			)
		)
		(duplicate_pad_numbers_are_jumpers no)
		(fp_line
			(start -0.7874 -0.4064)
			(end 0.7874 -0.4064)
			(stroke
				(width 0.1524)
				(type default)
			)
			(layer "F.SilkS")
		)
		(fp_line
			(start -0.7874 0.4064)
			(end -0.7874 -0.4064)
			(stroke
				(width 0.1524)
				(type default)
			)
			(layer "F.SilkS")
		)
		(fp_line
			(start 0.7874 -0.4064)
			(end 0.7874 0.4064)
			(stroke
				(width 0.1524)
				(type default)
			)
			(layer "F.SilkS")
		)
		(fp_line
			(start 0.7874 0.4064)
			(end -0.7874 0.4064)
			(stroke
				(width 0.1524)
				(type default)
			)
			(layer "F.SilkS")
		)
		(fp_line
			(start -0.67945 -0.305054)
			(end -0.12065 -0.305054)
			(stroke
				(width 0.1)
				(type default)
			)
			(layer "F.Fab")
		)
		(fp_line
			(start -0.67945 0.3048)
			(end -0.67945 -0.305054)
			(stroke
				(width 0.1)
				(type default)
			)
			(layer "F.Fab")
		)
		(fp_line
			(start -0.12065 -0.305054)
			(end -0.12065 -0.2794)
			(stroke
				(width 0.1)
				(type default)
			)
			(layer "F.Fab")
		)
		(fp_line
			(start -0.12065 -0.2794)
			(end 0.12065 -0.2794)
			(stroke
				(width 0.1)
				(type default)
			)
			(layer "F.Fab")
		)
		(fp_line
			(start -0.12065 0.2794)
			(end -0.12065 0.3048)
			(stroke
				(width 0.1)
				(type default)
			)
			(layer "F.Fab")
		)
		(fp_line
			(start -0.12065 0.3048)
			(end -0.67945 0.3048)
			(stroke
				(width 0.1)
				(type default)
			)
			(layer "F.Fab")
		)
		(fp_line
			(start 0.120396 0.2794)
			(end -0.12065 0.2794)
			(stroke
				(width 0.1)
				(type default)
			)
			(layer "F.Fab")
		)
		(fp_line
			(start 0.120396 0.3048)
			(end 0.120396 0.2794)
			(stroke
				(width 0.1)
				(type default)
			)
			(layer "F.Fab")
		)
		(fp_line
			(start 0.12065 -0.3048)
			(end 0.67945 -0.3048)
			(stroke
				(width 0.1)
				(type default)
			)
			(layer "F.Fab")
		)
		(fp_line
			(start 0.12065 -0.2794)
			(end 0.12065 -0.3048)
			(stroke
				(width 0.1)
				(type default)
			)
			(layer "F.Fab")
		)
		(fp_line
			(start 0.67945 -0.3048)
			(end 0.67945 0.3048)
			(stroke
				(width 0.1)
				(type default)
			)
			(layer "F.Fab")
		)
		(fp_line
			(start 0.67945 0.3048)
			(end 0.120396 0.3048)
			(stroke
				(width 0.1)
				(type default)
			)
			(layer "F.Fab")
		)
		(pad "1" smd circle
			(at -0.40005 0)
			(size 0 0)
			(layers "F.Cu" "F.Mask" "F.Paste")
			(net "BIC_USB_HUB_XOUT")
		)
		(pad "2" smd circle
			(at 0.40005 0)
			(size 0 0)
			(layers "F.Cu" "F.Mask" "F.Paste")
			(net "BIC_USB_HUB_XOUT_R")
		)
	)
	(footprint ""
		(layer "F.Cu")
		(at 88.007444 -96.811592 -90)
		(property "Reference" "R696"
			(at 0 0 270)
			(layer "F.SilkS")
			(hide yes)
			(effects
				(font
					(size 1.27 1.27)
				)
			)
		)
		(property "Value" ""
			(at 0 0 270)
			(layer "F.Fab")
			(effects
				(font
					(size 1.27 1.27)
				)
			)
		)
		(duplicate_pad_numbers_are_jumpers no)
		(fp_line
			(start -0.7874 0.4064)
			(end -0.7874 -0.4064)
			(stroke
				(width 0.1524)
				(type default)
			)
			(layer "F.SilkS")
		)
		(fp_line
			(start 0.7874 0.4064)
			(end -0.7874 0.4064)
			(stroke
				(width 0.1524)
				(type default)
			)
			(layer "F.SilkS")
		)
		(fp_line
			(start -0.7874 -0.4064)
			(end 0.7874 -0.4064)
			(stroke
				(width 0.1524)
				(type default)
			)
			(layer "F.SilkS")
		)
		(fp_line
			(start 0.7874 -0.4064)
			(end 0.7874 0.4064)
			(stroke
				(width 0.1524)
				(type default)
			)
			(layer "F.SilkS")
		)
		(fp_line
			(start -0.67945 0.3048)
			(end -0.67945 -0.305054)
			(stroke
				(width 0.1)
				(type default)
			)
			(layer "F.Fab")
		)
		(fp_line
			(start -0.12065 0.3048)
			(end -0.67945 0.3048)
			(stroke
				(width 0.1)
				(type default)
			)
			(layer "F.Fab")
		)
		(fp_line
			(start 0.120396 0.3048)
			(end 0.120396 0.2794)
			(stroke
				(width 0.1)
				(type default)
			)
			(layer "F.Fab")
		)
		(fp_line
			(start 0.67945 0.3048)
			(end 0.120396 0.3048)
			(stroke
				(width 0.1)
				(type default)
			)
			(layer "F.Fab")
		)
		(fp_line
			(start -0.12065 0.2794)
			(end -0.12065 0.3048)
			(stroke
				(width 0.1)
				(type default)
			)
			(layer "F.Fab")
		)
		(fp_line
			(start 0.120396 0.2794)
			(end -0.12065 0.2794)
			(stroke
				(width 0.1)
				(type default)
			)
			(layer "F.Fab")
		)
		(fp_line
			(start -0.12065 -0.2794)
			(end 0.12065 -0.2794)
			(stroke
				(width 0.1)
				(type default)
			)
			(layer "F.Fab")
		)
		(fp_line
			(start 0.12065 -0.2794)
			(end 0.12065 -0.3048)
			(stroke
				(width 0.1)
				(type default)
			)
			(layer "F.Fab")
		)
		(fp_line
			(start 0.12065 -0.3048)
			(end 0.67945 -0.3048)
			(stroke
				(width 0.1)
				(type default)
			)
			(layer "F.Fab")
		)
		(fp_line
			(start 0.67945 -0.3048)
			(end 0.67945 0.3048)
			(stroke
				(width 0.1)
				(type default)
			)
			(layer "F.Fab")
		)
		(fp_line
			(start -0.67945 -0.305054)
			(end -0.12065 -0.305054)
			(stroke
				(width 0.1)
				(type default)
			)
			(layer "F.Fab")
		)
		(fp_line
			(start -0.12065 -0.305054)
			(end -0.12065 -0.2794)
			(stroke
				(width 0.1)
				(type default)
			)
			(layer "F.Fab")
		)
		(pad "1" smd circle
			(at -0.40005 0 270)
			(size 0 0)
			(layers "F.Cu" "F.Mask" "F.Paste")
			(net "NIC1_ADC_A1")
		)
		(pad "2" smd circle
			(at 0.40005 0 270)
			(size 0 0)
			(layers "F.Cu" "F.Mask" "F.Paste")
			(net "GND")
		)
	)
	(footprint ""
		(layer "F.Cu")
		(at 252.971046 -146.205956 180)
		(property "Reference" "C615"
			(at 0 0 180)
			(layer "F.SilkS")
			(hide yes)
			(effects
				(font
					(size 1.27 1.27)
				)
			)
		)
		(property "Value" ""
			(at 0 0 180)
			(layer "F.Fab")
			(effects
				(font
					(size 1.27 1.27)
				)
			)
		)
		(duplicate_pad_numbers_are_jumpers no)
		(fp_line
			(start 0.7874 0.4064)
			(end -0.7874 0.4064)
			(stroke
				(width 0.1524)
				(type default)
			)
			(layer "F.SilkS")
		)
		(fp_line
			(start 0.7874 -0.4064)
			(end 0.7874 0.4064)
			(stroke
				(width 0.1524)
				(type default)
			)
			(layer "F.SilkS")
		)
		(fp_line
			(start -0.7874 0.4064)
			(end -0.7874 -0.4064)
			(stroke
				(width 0.1524)
				(type default)
			)
			(layer "F.SilkS")
		)
		(fp_line
			(start -0.7874 -0.4064)
			(end 0.7874 -0.4064)
			(stroke
				(width 0.1524)
				(type default)
			)
			(layer "F.SilkS")
		)
		(fp_line
			(start 0.67945 0.3048)
			(end 0.120396 0.3048)
			(stroke
				(width 0.1)
				(type default)
			)
			(layer "F.Fab")
		)
		(fp_line
			(start 0.67945 -0.3048)
			(end 0.67945 0.3048)
			(stroke
				(width 0.1)
				(type default)
			)
			(layer "F.Fab")
		)
		(fp_line
			(start 0.12065 -0.2794)
			(end 0.12065 -0.3048)
			(stroke
				(width 0.1)
				(type default)
			)
			(layer "F.Fab")
		)
		(fp_line
			(start 0.12065 -0.3048)
			(end 0.67945 -0.3048)
			(stroke
				(width 0.1)
				(type default)
			)
			(layer "F.Fab")
		)
		(fp_line
			(start 0.120396 0.3048)
			(end 0.120396 0.2794)
			(stroke
				(width 0.1)
				(type default)
			)
			(layer "F.Fab")
		)
		(fp_line
			(start 0.120396 0.2794)
			(end -0.12065 0.2794)
			(stroke
				(width 0.1)
				(type default)
			)
			(layer "F.Fab")
		)
		(fp_line
			(start -0.12065 0.3048)
			(end -0.67945 0.3048)
			(stroke
				(width 0.1)
				(type default)
			)
			(layer "F.Fab")
		)
		(fp_line
			(start -0.12065 0.2794)
			(end -0.12065 0.3048)
			(stroke
				(width 0.1)
				(type default)
			)
			(layer "F.Fab")
		)
		(fp_line
			(start -0.12065 -0.2794)
			(end 0.12065 -0.2794)
			(stroke
				(width 0.1)
				(type default)
			)
			(layer "F.Fab")
		)
		(fp_line
			(start -0.12065 -0.305054)
			(end -0.12065 -0.2794)
			(stroke
				(width 0.1)
				(type default)
			)
			(layer "F.Fab")
		)
		(fp_line
			(start -0.67945 0.3048)
			(end -0.67945 -0.305054)
			(stroke
				(width 0.1)
				(type default)
			)
			(layer "F.Fab")
		)
		(fp_line
			(start -0.67945 -0.305054)
			(end -0.12065 -0.305054)
			(stroke
				(width 0.1)
				(type default)
			)
			(layer "F.Fab")
		)
		(pad "1" smd circle
			(at -0.40005 0 180)
			(size 0 0)
			(layers "F.Cu" "F.Mask" "F.Paste")
			(net "P12V_NIC4_VIN_P")
		)
		(pad "2" smd circle
			(at 0.40005 0 180)
			(size 0 0)
			(layers "F.Cu" "F.Mask" "F.Paste")
			(net "P12V_NIC4_VIN_N")
		)
	)
	(footprint ""
		(layer "F.Cu")
		(at 324.321678 -84.31149 180)
		(property "Reference" "U420"
			(at 1.284478 -2.32156 0)
			(unlocked yes)
			(layer "F.SilkS")
			(effects
				(font
					(size 0.7874 0.5842)
					(thickness 0.1524)
				)
				(justify left)
			)
		)
		(property "Value" ""
			(at 0 0 180)
			(layer "F.Fab")
			(effects
				(font
					(size 1.27 1.27)
				)
			)
		)
		(duplicate_pad_numbers_are_jumpers no)
		(fp_line
			(start 1.463548 1.549908)
			(end -1.463548 1.549908)
			(stroke
				(width 0.1524)
				(type default)
			)
			(layer "F.SilkS")
		)
		(fp_line
			(start 1.463548 -1.549908)
			(end 1.463548 1.549908)
			(stroke
				(width 0.1524)
				(type default)
			)
			(layer "F.SilkS")
		)
		(fp_line
			(start 0.762 -1.549908)
			(end 1.463548 -1.549908)
			(stroke
				(width 0.1524)
				(type default)
			)
			(layer "F.SilkS")
		)
		(fp_line
			(start 0 -0.762)
			(end 0.762 -1.549908)
			(stroke
				(width 0.1524)
				(type default)
			)
			(layer "F.SilkS")
		)
		(fp_line
			(start -0.787908 -1.549908)
			(end 0 -0.762)
			(stroke
				(width 0.1524)
				(type default)
			)
			(layer "F.SilkS")
		)
		(fp_line
			(start -1.463548 1.549908)
			(end -1.463548 -1.549908)
			(stroke
				(width 0.1524)
				(type default)
			)
			(layer "F.SilkS")
		)
		(fp_line
			(start -1.463548 -1.549908)
			(end -0.787908 -1.549908)
			(stroke
				(width 0.1524)
				(type default)
			)
			(layer "F.SilkS")
		)
		(fp_poly
			(pts
				(xy -3.4798 -1.359916) (xy -2.86004 -1.050036) (xy -3.4798 -0.740156)
			)
			(stroke
				(width 0)
				(type default)
			)
			(fill yes)
			(layer "F.SilkS")
		)
		(fp_line
			(start 1.549908 1.549908)
			(end -1.549908 1.549908)
			(stroke
				(width 0.1)
				(type default)
			)
			(layer "F.Fab")
		)
		(fp_line
			(start 1.549908 -1.549908)
			(end 1.549908 1.549908)
			(stroke
				(width 0.1)
				(type default)
			)
			(layer "F.Fab")
		)
		(fp_line
			(start -1.549908 1.549908)
			(end -1.549908 -1.549908)
			(stroke
				(width 0.1)
				(type default)
			)
			(layer "F.Fab")
		)
		(fp_line
			(start -1.549908 -1.549908)
			(end 1.549908 -1.549908)
			(stroke
				(width 0.1)
				(type default)
			)
			(layer "F.Fab")
		)
		(fp_poly
			(pts
				(xy -3.4798 -1.359916) (xy -2.86004 -1.050036) (xy -3.4798 -0.740156)
			)
			(stroke
				(width 0)
				(type default)
			)
			(fill yes)
			(layer "F.Fab")
		)
		(pad "1" smd rect
			(at -2.175002 -1.050036 270)
			(size 0.6096 1.1684)
			(layers "F.Cu" "F.Mask" "F.Paste")
			(net "P3V3")
		)
		(pad "2" smd rect
			(at -2.175002 -0.32512 270)
			(size 0.4318 1.1684)
			(layers "F.Cu" "F.Mask" "F.Paste")
			(net "SMB_ISO_CB_SCL")
		)
		(pad "3" smd rect
			(at -2.175002 0.32512 270)
			(size 0.4318 1.1684)
			(layers "F.Cu" "F.Mask" "F.Paste")
			(net "SMB_ISO_CB_SDA")
		)
		(pad "4" smd rect
			(at -2.175002 1.050036 270)
			(size 0.6096 1.1684)
			(layers "F.Cu" "F.Mask" "F.Paste")
			(net "GND")
		)
		(pad "5" smd rect
			(at 2.175002 1.050036 270)
			(size 0.6096 1.1684)
			(layers "F.Cu" "F.Mask" "F.Paste")
			(net "CB_ISO_EN")
		)
		(pad "6" smd rect
			(at 2.175002 0.32512 270)
			(size 0.4318 1.1684)
			(layers "F.Cu" "F.Mask" "F.Paste")
			(net "SMB_BIC_I2C6_MUX_FRU_R_SDA")
		)
		(pad "7" smd rect
			(at 2.175002 -0.32512 270)
			(size 0.4318 1.1684)
			(layers "F.Cu" "F.Mask" "F.Paste")
			(net "SMB_BIC_I2C6_MUX_FRU_R_SCL")
		)
		(pad "8" smd rect
			(at 2.175002 -1.050036 270)
			(size 0.6096 1.1684)
			(layers "F.Cu" "F.Mask" "F.Paste")
			(net "P3V3_AUX")
		)
	)
	(footprint ""
		(layer "F.Cu")
		(at 275.50999 -220.192854)
		(property "Reference" "ME10"
			(at 0.0762 -5.705348 0)
			(unlocked yes)
			(layer "F.SilkS")
			(effects
				(font
					(size 0.7874 0.5842)
					(thickness 0.1524)
				)
				(justify left)
			)
		)
		(property "Value" ""
			(at 0 0 0)
			(layer "F.Fab")
			(effects
				(font
					(size 1.27 1.27)
				)
			)
		)
		(duplicate_pad_numbers_are_jumpers no)
		(fp_line
			(start 0 -4.99999)
			(end 0 -3.47599)
			(stroke
				(width 0.1524)
				(type default)
			)
			(layer "F.SilkS")
		)
		(fp_line
			(start 0 -0.524002)
			(end 0 0.999998)
			(stroke
				(width 0.1524)
				(type default)
			)
			(layer "F.SilkS")
		)
		(fp_line
			(start 0 0.999998)
			(end 1.524 0.999998)
			(stroke
				(width 0.1524)
				(type default)
			)
			(layer "F.SilkS")
		)
		(fp_line
			(start 1.524 -4.99999)
			(end 0 -4.99999)
			(stroke
				(width 0.1524)
				(type default)
			)
			(layer "F.SilkS")
		)
		(fp_line
			(start 15.475966 0.999998)
			(end 16.999966 0.999998)
			(stroke
				(width 0.1524)
				(type default)
			)
			(layer "F.SilkS")
		)
		(fp_line
			(start 16.999966 -4.99999)
			(end 15.475966 -4.99999)
			(stroke
				(width 0.1524)
				(type default)
			)
			(layer "F.SilkS")
		)
		(fp_line
			(start 16.999966 -3.47599)
			(end 16.999966 -4.99999)
			(stroke
				(width 0.1524)
				(type default)
			)
			(layer "F.SilkS")
		)
		(fp_line
			(start 16.999966 0.999998)
			(end 16.999966 -0.524002)
			(stroke
				(width 0.1524)
				(type default)
			)
			(layer "F.SilkS")
		)
		(fp_text user "S/N"
			(at 0.1016 -3.54965 0)
			(unlocked yes)
			(layer "F.SilkS")
			(effects
				(font
					(size 1.905 1.4224)
					(thickness 0.1524)
				)
				(justify left)
			)
		)
	)
	(footprint ""
		(layer "F.Cu")
		(at 204.761592 -350.312482 90)
		(property "Reference" "R5799"
			(at 0 0 90)
			(layer "F.SilkS")
			(hide yes)
			(effects
				(font
					(size 1.27 1.27)
				)
			)
		)
		(property "Value" ""
			(at 0 0 90)
			(layer "F.Fab")
			(effects
				(font
					(size 1.27 1.27)
				)
			)
		)
		(duplicate_pad_numbers_are_jumpers no)
		(fp_line
			(start 0.7874 -0.4064)
			(end 0.7874 0.4064)
			(stroke
				(width 0.1524)
				(type default)
			)
			(layer "F.SilkS")
		)
		(fp_line
			(start -0.7874 -0.4064)
			(end 0.7874 -0.4064)
			(stroke
				(width 0.1524)
				(type default)
			)
			(layer "F.SilkS")
		)
		(fp_line
			(start 0.7874 0.4064)
			(end -0.7874 0.4064)
			(stroke
				(width 0.1524)
				(type default)
			)
			(layer "F.SilkS")
		)
		(fp_line
			(start -0.7874 0.4064)
			(end -0.7874 -0.4064)
			(stroke
				(width 0.1524)
				(type default)
			)
			(layer "F.SilkS")
		)
		(fp_line
			(start -0.12065 -0.305054)
			(end -0.12065 -0.2794)
			(stroke
				(width 0.1)
				(type default)
			)
			(layer "F.Fab")
		)
		(fp_line
			(start -0.67945 -0.305054)
			(end -0.12065 -0.305054)
			(stroke
				(width 0.1)
				(type default)
			)
			(layer "F.Fab")
		)
		(fp_line
			(start 0.67945 -0.3048)
			(end 0.67945 0.3048)
			(stroke
				(width 0.1)
				(type default)
			)
			(layer "F.Fab")
		)
		(fp_line
			(start 0.12065 -0.3048)
			(end 0.67945 -0.3048)
			(stroke
				(width 0.1)
				(type default)
			)
			(layer "F.Fab")
		)
		(fp_line
			(start 0.12065 -0.2794)
			(end 0.12065 -0.3048)
			(stroke
				(width 0.1)
				(type default)
			)
			(layer "F.Fab")
		)
		(fp_line
			(start -0.12065 -0.2794)
			(end 0.12065 -0.2794)
			(stroke
				(width 0.1)
				(type default)
			)
			(layer "F.Fab")
		)
		(fp_line
			(start 0.120396 0.2794)
			(end -0.12065 0.2794)
			(stroke
				(width 0.1)
				(type default)
			)
			(layer "F.Fab")
		)
		(fp_line
			(start -0.12065 0.2794)
			(end -0.12065 0.3048)
			(stroke
				(width 0.1)
				(type default)
			)
			(layer "F.Fab")
		)
		(fp_line
			(start 0.67945 0.3048)
			(end 0.120396 0.3048)
			(stroke
				(width 0.1)
				(type default)
			)
			(layer "F.Fab")
		)
		(fp_line
			(start 0.120396 0.3048)
			(end 0.120396 0.2794)
			(stroke
				(width 0.1)
				(type default)
			)
			(layer "F.Fab")
		)
		(fp_line
			(start -0.12065 0.3048)
			(end -0.67945 0.3048)
			(stroke
				(width 0.1)
				(type default)
			)
			(layer "F.Fab")
		)
		(fp_line
			(start -0.67945 0.3048)
			(end -0.67945 -0.305054)
			(stroke
				(width 0.1)
				(type default)
			)
			(layer "F.Fab")
		)
		(pad "1" smd circle
			(at -0.40005 0 90)
			(size 0 0)
			(layers "F.Cu" "F.Mask" "F.Paste")
			(net "HSC_D_OC_BUF_R_N")
		)
		(pad "2" smd circle
			(at 0.40005 0 90)
			(size 0 0)
			(layers "F.Cu" "F.Mask" "F.Paste")
			(net "HSC_D_OC_BUF_N")
		)
	)
	(footprint ""
		(layer "F.Cu")
		(at 230.848408 -311.533032 90)
		(property "Reference" "R843"
			(at 0 0 90)
			(layer "F.SilkS")
			(hide yes)
			(effects
				(font
					(size 1.27 1.27)
				)
			)
		)
		(property "Value" ""
			(at 0 0 90)
			(layer "F.Fab")
			(effects
				(font
					(size 1.27 1.27)
				)
			)
		)
		(duplicate_pad_numbers_are_jumpers no)
		(fp_line
			(start 0.7874 -0.4064)
			(end 0.7874 0.4064)
			(stroke
				(width 0.1524)
				(type default)
			)
			(layer "F.SilkS")
		)
		(fp_line
			(start -0.7874 -0.4064)
			(end 0.7874 -0.4064)
			(stroke
				(width 0.1524)
				(type default)
			)
			(layer "F.SilkS")
		)
		(fp_line
			(start 0.7874 0.4064)
			(end -0.7874 0.4064)
			(stroke
				(width 0.1524)
				(type default)
			)
			(layer "F.SilkS")
		)
		(fp_line
			(start -0.7874 0.4064)
			(end -0.7874 -0.4064)
			(stroke
				(width 0.1524)
				(type default)
			)
			(layer "F.SilkS")
		)
		(fp_line
			(start -0.12065 -0.305054)
			(end -0.12065 -0.2794)
			(stroke
				(width 0.1)
				(type default)
			)
			(layer "F.Fab")
		)
		(fp_line
			(start -0.67945 -0.305054)
			(end -0.12065 -0.305054)
			(stroke
				(width 0.1)
				(type default)
			)
			(layer "F.Fab")
		)
		(fp_line
			(start 0.67945 -0.3048)
			(end 0.67945 0.3048)
			(stroke
				(width 0.1)
				(type default)
			)
			(layer "F.Fab")
		)
		(fp_line
			(start 0.12065 -0.3048)
			(end 0.67945 -0.3048)
			(stroke
				(width 0.1)
				(type default)
			)
			(layer "F.Fab")
		)
		(fp_line
			(start 0.12065 -0.2794)
			(end 0.12065 -0.3048)
			(stroke
				(width 0.1)
				(type default)
			)
			(layer "F.Fab")
		)
		(fp_line
			(start -0.12065 -0.2794)
			(end 0.12065 -0.2794)
			(stroke
				(width 0.1)
				(type default)
			)
			(layer "F.Fab")
		)
		(fp_line
			(start 0.120396 0.2794)
			(end -0.12065 0.2794)
			(stroke
				(width 0.1)
				(type default)
			)
			(layer "F.Fab")
		)
		(fp_line
			(start -0.12065 0.2794)
			(end -0.12065 0.3048)
			(stroke
				(width 0.1)
				(type default)
			)
			(layer "F.Fab")
		)
		(fp_line
			(start 0.67945 0.3048)
			(end 0.120396 0.3048)
			(stroke
				(width 0.1)
				(type default)
			)
			(layer "F.Fab")
		)
		(fp_line
			(start 0.120396 0.3048)
			(end 0.120396 0.2794)
			(stroke
				(width 0.1)
				(type default)
			)
			(layer "F.Fab")
		)
		(fp_line
			(start -0.12065 0.3048)
			(end -0.67945 0.3048)
			(stroke
				(width 0.1)
				(type default)
			)
			(layer "F.Fab")
		)
		(fp_line
			(start -0.67945 0.3048)
			(end -0.67945 -0.305054)
			(stroke
				(width 0.1)
				(type default)
			)
			(layer "F.Fab")
		)
		(pad "1" smd circle
			(at -0.40005 0 90)
			(size 0 0)
			(layers "F.Cu" "F.Mask" "F.Paste")
			(net "P1V25_PEX1_VCC")
		)
		(pad "2" smd circle
			(at 0.40005 0 90)
			(size 0 0)
			(layers "F.Cu" "F.Mask" "F.Paste")
			(net "PWRGD_P1V25_PEX1")
		)
	)
	(footprint ""
		(layer "F.Cu")
		(at 372.9228 -238.643922)
		(property "Reference" "R6408"
			(at 0 0 0)
			(layer "F.SilkS")
			(hide yes)
			(effects
				(font
					(size 1.27 1.27)
				)
			)
		)
		(property "Value" ""
			(at 0 0 0)
			(layer "F.Fab")
			(effects
				(font
					(size 1.27 1.27)
				)
			)
		)
		(duplicate_pad_numbers_are_jumpers no)
		(fp_line
			(start -0.7874 -0.4064)
			(end 0.7874 -0.4064)
			(stroke
				(width 0.1524)
				(type default)
			)
			(layer "F.SilkS")
		)
		(fp_line
			(start -0.7874 0.4064)
			(end -0.7874 -0.4064)
			(stroke
				(width 0.1524)
				(type default)
			)
			(layer "F.SilkS")
		)
		(fp_line
			(start 0.7874 -0.4064)
			(end 0.7874 0.4064)
			(stroke
				(width 0.1524)
				(type default)
			)
			(layer "F.SilkS")
		)
		(fp_line
			(start 0.7874 0.4064)
			(end -0.7874 0.4064)
			(stroke
				(width 0.1524)
				(type default)
			)
			(layer "F.SilkS")
		)
		(fp_line
			(start -0.67945 -0.305054)
			(end -0.12065 -0.305054)
			(stroke
				(width 0.1)
				(type default)
			)
			(layer "F.Fab")
		)
		(fp_line
			(start -0.67945 0.3048)
			(end -0.67945 -0.305054)
			(stroke
				(width 0.1)
				(type default)
			)
			(layer "F.Fab")
		)
		(fp_line
			(start -0.12065 -0.305054)
			(end -0.12065 -0.2794)
			(stroke
				(width 0.1)
				(type default)
			)
			(layer "F.Fab")
		)
		(fp_line
			(start -0.12065 -0.2794)
			(end 0.12065 -0.2794)
			(stroke
				(width 0.1)
				(type default)
			)
			(layer "F.Fab")
		)
		(fp_line
			(start -0.12065 0.2794)
			(end -0.12065 0.3048)
			(stroke
				(width 0.1)
				(type default)
			)
			(layer "F.Fab")
		)
		(fp_line
			(start -0.12065 0.3048)
			(end -0.67945 0.3048)
			(stroke
				(width 0.1)
				(type default)
			)
			(layer "F.Fab")
		)
		(fp_line
			(start 0.120396 0.2794)
			(end -0.12065 0.2794)
			(stroke
				(width 0.1)
				(type default)
			)
			(layer "F.Fab")
		)
		(fp_line
			(start 0.120396 0.3048)
			(end 0.120396 0.2794)
			(stroke
				(width 0.1)
				(type default)
			)
			(layer "F.Fab")
		)
		(fp_line
			(start 0.12065 -0.3048)
			(end 0.67945 -0.3048)
			(stroke
				(width 0.1)
				(type default)
			)
			(layer "F.Fab")
		)
		(fp_line
			(start 0.12065 -0.2794)
			(end 0.12065 -0.3048)
			(stroke
				(width 0.1)
				(type default)
			)
			(layer "F.Fab")
		)
		(fp_line
			(start 0.67945 -0.3048)
			(end 0.67945 0.3048)
			(stroke
				(width 0.1)
				(type default)
			)
			(layer "F.Fab")
		)
		(fp_line
			(start 0.67945 0.3048)
			(end 0.120396 0.3048)
			(stroke
				(width 0.1)
				(type default)
			)
			(layer "F.Fab")
		)
		(pad "1" smd circle
			(at -0.40005 0)
			(size 0 0)
			(layers "F.Cu" "F.Mask" "F.Paste")
			(net "PWRGD_P3V3_AUX_R2")
		)
		(pad "2" smd circle
			(at 0.40005 0)
			(size 0 0)
			(layers "F.Cu" "F.Mask" "F.Paste")
			(net "PWRGD_P3V3_AUX_R")
		)
	)
	(footprint ""
		(layer "F.Cu")
		(at 115.847114 -253.178564 180)
		(property "Reference" "PC46"
			(at 0 0 180)
			(layer "F.SilkS")
			(hide yes)
			(effects
				(font
					(size 1.27 1.27)
				)
			)
		)
		(property "Value" ""
			(at 0 0 180)
			(layer "F.Fab")
			(effects
				(font
					(size 1.27 1.27)
				)
			)
		)
		(duplicate_pad_numbers_are_jumpers no)
		(fp_line
			(start 1.524 0.762)
			(end -1.524 0.762)
			(stroke
				(width 0.1524)
				(type default)
			)
			(layer "F.SilkS")
		)
		(fp_line
			(start 1.524 -0.762)
			(end 1.524 0.762)
			(stroke
				(width 0.1524)
				(type default)
			)
			(layer "F.SilkS")
		)
		(fp_line
			(start -1.524 0.762)
			(end -1.524 -0.762)
			(stroke
				(width 0.1524)
				(type default)
			)
			(layer "F.SilkS")
		)
		(fp_line
			(start -1.524 -0.762)
			(end 1.524 -0.762)
			(stroke
				(width 0.1524)
				(type default)
			)
			(layer "F.SilkS")
		)
		(fp_line
			(start 1.1049 0.724916)
			(end 1.1049 -0.724916)
			(stroke
				(width 0.1)
				(type default)
			)
			(layer "F.Fab")
		)
		(fp_line
			(start 1.1049 -0.724916)
			(end -1.1049 -0.724916)
			(stroke
				(width 0.1)
				(type default)
			)
			(layer "F.Fab")
		)
		(fp_line
			(start -1.1049 0.724916)
			(end 1.1049 0.724916)
			(stroke
				(width 0.1)
				(type default)
			)
			(layer "F.Fab")
		)
		(fp_line
			(start -1.1049 -0.724916)
			(end -1.1049 0.724916)
			(stroke
				(width 0.1)
				(type default)
			)
			(layer "F.Fab")
		)
		(pad "1" smd rect
			(at -0.889 0)
			(size 1.016 1.27)
			(layers "F.Cu" "F.Mask" "F.Paste")
			(net "P0V8_PEX0_VREF")
		)
		(pad "2" smd rect
			(at 0.889 0)
			(size 1.016 1.27)
			(layers "F.Cu" "F.Mask" "F.Paste")
			(net "GND")
		)
	)
	(footprint ""
		(layer "F.Cu")
		(at 87.982298 -306.06492 90)
		(property "Reference" "R3893"
			(at 0 0 90)
			(layer "F.SilkS")
			(hide yes)
			(effects
				(font
					(size 1.27 1.27)
				)
			)
		)
		(property "Value" ""
			(at 0 0 90)
			(layer "F.Fab")
			(effects
				(font
					(size 1.27 1.27)
				)
			)
		)
		(duplicate_pad_numbers_are_jumpers no)
		(fp_line
			(start 0.7874 -0.4064)
			(end 0.7874 0.4064)
			(stroke
				(width 0.1524)
				(type default)
			)
			(layer "F.SilkS")
		)
		(fp_line
			(start -0.7874 -0.4064)
			(end 0.7874 -0.4064)
			(stroke
				(width 0.1524)
				(type default)
			)
			(layer "F.SilkS")
		)
		(fp_line
			(start 0.7874 0.4064)
			(end -0.7874 0.4064)
			(stroke
				(width 0.1524)
				(type default)
			)
			(layer "F.SilkS")
		)
		(fp_line
			(start -0.7874 0.4064)
			(end -0.7874 -0.4064)
			(stroke
				(width 0.1524)
				(type default)
			)
			(layer "F.SilkS")
		)
		(fp_line
			(start -0.12065 -0.305054)
			(end -0.12065 -0.2794)
			(stroke
				(width 0.1)
				(type default)
			)
			(layer "F.Fab")
		)
		(fp_line
			(start -0.67945 -0.305054)
			(end -0.12065 -0.305054)
			(stroke
				(width 0.1)
				(type default)
			)
			(layer "F.Fab")
		)
		(fp_line
			(start 0.67945 -0.3048)
			(end 0.67945 0.3048)
			(stroke
				(width 0.1)
				(type default)
			)
			(layer "F.Fab")
		)
		(fp_line
			(start 0.12065 -0.3048)
			(end 0.67945 -0.3048)
			(stroke
				(width 0.1)
				(type default)
			)
			(layer "F.Fab")
		)
		(fp_line
			(start 0.12065 -0.2794)
			(end 0.12065 -0.3048)
			(stroke
				(width 0.1)
				(type default)
			)
			(layer "F.Fab")
		)
		(fp_line
			(start -0.12065 -0.2794)
			(end 0.12065 -0.2794)
			(stroke
				(width 0.1)
				(type default)
			)
			(layer "F.Fab")
		)
		(fp_line
			(start 0.120396 0.2794)
			(end -0.12065 0.2794)
			(stroke
				(width 0.1)
				(type default)
			)
			(layer "F.Fab")
		)
		(fp_line
			(start -0.12065 0.2794)
			(end -0.12065 0.3048)
			(stroke
				(width 0.1)
				(type default)
			)
			(layer "F.Fab")
		)
		(fp_line
			(start 0.67945 0.3048)
			(end 0.120396 0.3048)
			(stroke
				(width 0.1)
				(type default)
			)
			(layer "F.Fab")
		)
		(fp_line
			(start 0.120396 0.3048)
			(end 0.120396 0.2794)
			(stroke
				(width 0.1)
				(type default)
			)
			(layer "F.Fab")
		)
		(fp_line
			(start -0.12065 0.3048)
			(end -0.67945 0.3048)
			(stroke
				(width 0.1)
				(type default)
			)
			(layer "F.Fab")
		)
		(fp_line
			(start -0.67945 0.3048)
			(end -0.67945 -0.305054)
			(stroke
				(width 0.1)
				(type default)
			)
			(layer "F.Fab")
		)
		(pad "1" smd circle
			(at -0.40005 0 90)
			(size 0 0)
			(layers "F.Cu" "F.Mask" "F.Paste")
			(net "SMB_PEX0_SLAVE_SDA")
		)
		(pad "2" smd circle
			(at 0.40005 0 90)
			(size 0 0)
			(layers "F.Cu" "F.Mask" "F.Paste")
			(net "SMB_PEX0_R_SDA")
		)
	)
	(footprint ""
		(layer "F.Cu")
		(at 211.722716 -22.867366 90)
		(property "Reference" "C3924"
			(at 0 0 90)
			(layer "F.SilkS")
			(hide yes)
			(effects
				(font
					(size 1.27 1.27)
				)
			)
		)
		(property "Value" ""
			(at 0 0 90)
			(layer "F.Fab")
			(effects
				(font
					(size 1.27 1.27)
				)
			)
		)
		(duplicate_pad_numbers_are_jumpers no)
		(fp_line
			(start 0.7874 -0.4064)
			(end 0.7874 0.4064)
			(stroke
				(width 0.1524)
				(type default)
			)
			(layer "F.SilkS")
		)
		(fp_line
			(start -0.7874 -0.4064)
			(end 0.7874 -0.4064)
			(stroke
				(width 0.1524)
				(type default)
			)
			(layer "F.SilkS")
		)
		(fp_line
			(start 0.7874 0.4064)
			(end -0.7874 0.4064)
			(stroke
				(width 0.1524)
				(type default)
			)
			(layer "F.SilkS")
		)
		(fp_line
			(start -0.7874 0.4064)
			(end -0.7874 -0.4064)
			(stroke
				(width 0.1524)
				(type default)
			)
			(layer "F.SilkS")
		)
		(fp_line
			(start -0.12065 -0.305054)
			(end -0.12065 -0.2794)
			(stroke
				(width 0.1)
				(type default)
			)
			(layer "F.Fab")
		)
		(fp_line
			(start -0.67945 -0.305054)
			(end -0.12065 -0.305054)
			(stroke
				(width 0.1)
				(type default)
			)
			(layer "F.Fab")
		)
		(fp_line
			(start 0.67945 -0.3048)
			(end 0.67945 0.3048)
			(stroke
				(width 0.1)
				(type default)
			)
			(layer "F.Fab")
		)
		(fp_line
			(start 0.12065 -0.3048)
			(end 0.67945 -0.3048)
			(stroke
				(width 0.1)
				(type default)
			)
			(layer "F.Fab")
		)
		(fp_line
			(start 0.12065 -0.2794)
			(end 0.12065 -0.3048)
			(stroke
				(width 0.1)
				(type default)
			)
			(layer "F.Fab")
		)
		(fp_line
			(start -0.12065 -0.2794)
			(end 0.12065 -0.2794)
			(stroke
				(width 0.1)
				(type default)
			)
			(layer "F.Fab")
		)
		(fp_line
			(start 0.120396 0.2794)
			(end -0.12065 0.2794)
			(stroke
				(width 0.1)
				(type default)
			)
			(layer "F.Fab")
		)
		(fp_line
			(start -0.12065 0.2794)
			(end -0.12065 0.3048)
			(stroke
				(width 0.1)
				(type default)
			)
			(layer "F.Fab")
		)
		(fp_line
			(start 0.67945 0.3048)
			(end 0.120396 0.3048)
			(stroke
				(width 0.1)
				(type default)
			)
			(layer "F.Fab")
		)
		(fp_line
			(start 0.120396 0.3048)
			(end 0.120396 0.2794)
			(stroke
				(width 0.1)
				(type default)
			)
			(layer "F.Fab")
		)
		(fp_line
			(start -0.12065 0.3048)
			(end -0.67945 0.3048)
			(stroke
				(width 0.1)
				(type default)
			)
			(layer "F.Fab")
		)
		(fp_line
			(start -0.67945 0.3048)
			(end -0.67945 -0.305054)
			(stroke
				(width 0.1)
				(type default)
			)
			(layer "F.Fab")
		)
		(pad "1" smd circle
			(at -0.40005 0 90)
			(size 0 0)
			(layers "F.Cu" "F.Mask" "F.Paste")
			(net "P12V_SSD7")
		)
		(pad "2" smd circle
			(at 0.40005 0 90)
			(size 0 0)
			(layers "F.Cu" "F.Mask" "F.Paste")
			(net "GND")
		)
	)
	(footprint ""
		(layer "F.Cu")
		(at 317.090806 -55.663846 90)
		(property "Reference" "PU69"
			(at -1.304036 2.718562 90)
			(unlocked yes)
			(layer "F.SilkS")
			(effects
				(font
					(size 0.7874 0.5842)
					(thickness 0.1524)
				)
				(justify left)
			)
		)
		(property "Value" ""
			(at 0 0 90)
			(layer "F.Fab")
			(effects
				(font
					(size 1.27 1.27)
				)
			)
		)
		(duplicate_pad_numbers_are_jumpers no)
		(fp_line
			(start 1.943608 -1.549908)
			(end 1.943608 1.549908)
			(stroke
				(width 0.1524)
				(type default)
			)
			(layer "F.SilkS")
		)
		(fp_line
			(start -1.943608 -1.549908)
			(end 1.943608 -1.549908)
			(stroke
				(width 0.1524)
				(type default)
			)
			(layer "F.SilkS")
		)
		(fp_line
			(start 1.943608 1.549908)
			(end -1.943608 1.549908)
			(stroke
				(width 0.1524)
				(type default)
			)
			(layer "F.SilkS")
		)
		(fp_line
			(start -1.943608 1.549908)
			(end -1.943608 -1.549908)
			(stroke
				(width 0.1524)
				(type default)
			)
			(layer "F.SilkS")
		)
		(fp_poly
			(pts
				(xy -2.019808 -1.549908) (xy -1.257808 -1.549908) (xy -1.257808 -1.880108) (xy -2.019808 -1.880108)
			)
			(stroke
				(width 0)
				(type default)
			)
			(fill yes)
			(layer "F.SilkS")
		)
		(fp_line
			(start 1.549908 -1.549908)
			(end 1.549908 1.549908)
			(stroke
				(width 0.1)
				(type default)
			)
			(layer "F.Fab")
		)
		(fp_line
			(start -1.549908 -1.549908)
			(end 1.549908 -1.549908)
			(stroke
				(width 0.1)
				(type default)
			)
			(layer "F.Fab")
		)
		(fp_line
			(start 1.549908 1.549908)
			(end -1.549908 1.549908)
			(stroke
				(width 0.1)
				(type default)
			)
			(layer "F.Fab")
		)
		(fp_line
			(start -1.549908 1.549908)
			(end -1.549908 -1.549908)
			(stroke
				(width 0.1)
				(type default)
			)
			(layer "F.Fab")
		)
		(fp_poly
			(pts
				(xy -2.019808 -1.549908) (xy -1.257808 -1.549908) (xy -1.257808 -1.880108) (xy -2.019808 -1.880108)
			)
			(stroke
				(width 0)
				(type default)
			)
			(fill yes)
			(layer "F.Fab")
		)
		(pad "1" smd rect
			(at -1.500124 -1.249934)
			(size 0.2794 0.6096)
			(layers "F.Cu" "F.Mask" "F.Paste")
			(net "P3V3_SSD11")
		)
		(pad "2" smd rect
			(at -1.500124 -0.750062)
			(size 0.2794 0.6096)
			(layers "F.Cu" "F.Mask" "F.Paste")
			(net "P3V3_SSD11")
		)
		(pad "3" smd rect
			(at -1.500124 -0.249936)
			(size 0.2794 0.6096)
			(layers "F.Cu" "F.Mask" "F.Paste")
			(net "P3V3_SSD11")
		)
		(pad "4" smd rect
			(at -1.500124 0.249936)
			(size 0.2794 0.6096)
			(layers "F.Cu" "F.Mask" "F.Paste")
			(net "P3V3_SSD11")
		)
		(pad "5" smd rect
			(at -1.500124 0.750062)
			(size 0.2794 0.6096)
			(layers "F.Cu" "F.Mask" "F.Paste")
			(net "P3V3_SSD11")
		)
		(pad "6" smd rect
			(at -1.500124 1.249934)
			(size 0.2794 0.6096)
			(layers "F.Cu" "F.Mask" "F.Paste")
			(net "GND")
		)
		(pad "7" smd rect
			(at 1.500124 1.249934)
			(size 0.2794 0.6096)
			(layers "F.Cu" "F.Mask" "F.Paste")
			(net "P3V3_SSD11_SS")
		)
		(pad "8" smd rect
			(at 1.500124 0.750062)
			(size 0.2794 0.6096)
			(layers "F.Cu" "F.Mask" "F.Paste")
			(net "PWRGD_P3V3_SSD11")
		)
		(pad "9" smd rect
			(at 1.500124 0.249936)
			(size 0.2794 0.6096)
			(layers "F.Cu" "F.Mask" "F.Paste")
			(net "P3V3_SSD11_OCP")
		)
		(pad "10" smd rect
			(at 1.500124 -0.249936)
			(size 0.2794 0.6096)
			(layers "F.Cu" "F.Mask" "F.Paste")
			(net "P5V_AUX")
		)
		(pad "11" smd rect
			(at 1.500124 -0.750062)
			(size 0.2794 0.6096)
			(layers "F.Cu" "F.Mask" "F.Paste")
			(net "SSD11_AUX_P3V3_EN_R")
		)
		(pad "12" smd rect
			(at 1.500124 -1.249934)
			(size 0.2794 0.6096)
			(layers "F.Cu" "F.Mask" "F.Paste")
			(net "P3V3_AUX")
		)
		(pad "13" smd rect
			(at 0 0 90)
			(size 1.9812 2.7178)
			(layers "F.Cu" "F.Mask" "F.Paste")
			(net "P3V3_AUX")
		)
		(zone
			(layer "F.Cu")
			(hatch none 0.5)
			(connect_pads
				(clearance 0)
			)
			(min_thickness 0.25)
			(keepout
				(tracks not_allowed)
				(vias allowed)
				(pads allowed)
				(copperpour not_allowed)
				(footprints allowed)
			)
			(placement
				(enabled no)
				(sheetname "")
			)
			(fill
				(thermal_gap 0.5)
				(thermal_bridge_width 0.5)
				(island_removal_mode 0)
			)
			(polygon
				(pts
					(xy 315.541406 -56.806846) (xy 315.668406 -56.806846) (xy 318.640206 -56.806846) (xy 318.640714 -56.806846)
					(xy 318.640714 -54.520846) (xy 318.640206 -54.520846) (xy 318.513206 -54.520846) (xy 317.090806 -54.520846)
					(xy 317.090806 -54.622446) (xy 318.513206 -54.622446) (xy 318.513206 -56.705246) (xy 315.668406 -56.705246)
					(xy 315.668406 -54.622446) (xy 317.065406 -54.622446) (xy 317.065406 -54.520846) (xy 315.668406 -54.520846)
					(xy 315.541406 -54.520846) (xy 315.540898 -54.520846) (xy 315.540898 -56.806846)
				)
			)
		)
	)
	(footprint ""
		(layer "F.Cu")
		(at 330.63434 -34.546286 180)
		(property "Reference" "C511"
			(at 0 0 180)
			(layer "F.SilkS")
			(hide yes)
			(effects
				(font
					(size 1.27 1.27)
				)
			)
		)
		(property "Value" ""
			(at 0 0 180)
			(layer "F.Fab")
			(effects
				(font
					(size 1.27 1.27)
				)
			)
		)
		(duplicate_pad_numbers_are_jumpers no)
		(fp_line
			(start 0.299974 0.150114)
			(end -0.299974 0.150114)
			(stroke
				(width 0.1)
				(type default)
			)
			(layer "F.Fab")
		)
		(fp_line
			(start 0.299974 -0.150114)
			(end 0.299974 0.150114)
			(stroke
				(width 0.1)
				(type default)
			)
			(layer "F.Fab")
		)
		(fp_line
			(start -0.299974 0.150114)
			(end -0.299974 -0.150114)
			(stroke
				(width 0.1)
				(type default)
			)
			(layer "F.Fab")
		)
		(fp_line
			(start -0.299974 -0.150114)
			(end 0.299974 -0.150114)
			(stroke
				(width 0.1)
				(type default)
			)
			(layer "F.Fab")
		)
		(pad "1" smd rect
			(at -0.2667 0 180)
			(size 0.3048 0.381)
			(layers "F.Cu" "F.Mask" "F.Paste")
			(net "P5E_PEX2_STN2_TX_DP<35>")
		)
		(pad "2" smd rect
			(at 0.2667 0 180)
			(size 0.3048 0.381)
			(layers "F.Cu" "F.Mask" "F.Paste")
			(net "P5E_PEX2_STN2_TX_C_DP<35>")
		)
	)
	(footprint ""
		(layer "F.Cu")
		(at 224.695512 -231.416606 90)
		(property "Reference" "R4544"
			(at 0 0 90)
			(layer "F.SilkS")
			(hide yes)
			(effects
				(font
					(size 1.27 1.27)
				)
			)
		)
		(property "Value" ""
			(at 0 0 90)
			(layer "F.Fab")
			(effects
				(font
					(size 1.27 1.27)
				)
			)
		)
		(duplicate_pad_numbers_are_jumpers no)
		(fp_line
			(start 0.7874 -0.4064)
			(end 0.7874 0.4064)
			(stroke
				(width 0.1524)
				(type default)
			)
			(layer "F.SilkS")
		)
		(fp_line
			(start -0.7874 -0.4064)
			(end 0.7874 -0.4064)
			(stroke
				(width 0.1524)
				(type default)
			)
			(layer "F.SilkS")
		)
		(fp_line
			(start 0.7874 0.4064)
			(end -0.7874 0.4064)
			(stroke
				(width 0.1524)
				(type default)
			)
			(layer "F.SilkS")
		)
		(fp_line
			(start -0.7874 0.4064)
			(end -0.7874 -0.4064)
			(stroke
				(width 0.1524)
				(type default)
			)
			(layer "F.SilkS")
		)
		(fp_line
			(start -0.12065 -0.305054)
			(end -0.12065 -0.2794)
			(stroke
				(width 0.1)
				(type default)
			)
			(layer "F.Fab")
		)
		(fp_line
			(start -0.67945 -0.305054)
			(end -0.12065 -0.305054)
			(stroke
				(width 0.1)
				(type default)
			)
			(layer "F.Fab")
		)
		(fp_line
			(start 0.67945 -0.3048)
			(end 0.67945 0.3048)
			(stroke
				(width 0.1)
				(type default)
			)
			(layer "F.Fab")
		)
		(fp_line
			(start 0.12065 -0.3048)
			(end 0.67945 -0.3048)
			(stroke
				(width 0.1)
				(type default)
			)
			(layer "F.Fab")
		)
		(fp_line
			(start 0.12065 -0.2794)
			(end 0.12065 -0.3048)
			(stroke
				(width 0.1)
				(type default)
			)
			(layer "F.Fab")
		)
		(fp_line
			(start -0.12065 -0.2794)
			(end 0.12065 -0.2794)
			(stroke
				(width 0.1)
				(type default)
			)
			(layer "F.Fab")
		)
		(fp_line
			(start 0.120396 0.2794)
			(end -0.12065 0.2794)
			(stroke
				(width 0.1)
				(type default)
			)
			(layer "F.Fab")
		)
		(fp_line
			(start -0.12065 0.2794)
			(end -0.12065 0.3048)
			(stroke
				(width 0.1)
				(type default)
			)
			(layer "F.Fab")
		)
		(fp_line
			(start 0.67945 0.3048)
			(end 0.120396 0.3048)
			(stroke
				(width 0.1)
				(type default)
			)
			(layer "F.Fab")
		)
		(fp_line
			(start 0.120396 0.3048)
			(end 0.120396 0.2794)
			(stroke
				(width 0.1)
				(type default)
			)
			(layer "F.Fab")
		)
		(fp_line
			(start -0.12065 0.3048)
			(end -0.67945 0.3048)
			(stroke
				(width 0.1)
				(type default)
			)
			(layer "F.Fab")
		)
		(fp_line
			(start -0.67945 0.3048)
			(end -0.67945 -0.305054)
			(stroke
				(width 0.1)
				(type default)
			)
			(layer "F.Fab")
		)
		(pad "1" smd circle
			(at -0.40005 0 90)
			(size 0 0)
			(layers "F.Cu" "F.Mask" "F.Paste")
			(net "REV_ID0")
		)
		(pad "2" smd circle
			(at 0.40005 0 90)
			(size 0 0)
			(layers "F.Cu" "F.Mask" "F.Paste")
			(net "P3V3_AUX")
		)
	)
	(footprint ""
		(layer "F.Cu")
		(at 259.130038 -300.406308 -90)
		(property "Reference" "C3367"
			(at 0 0 270)
			(layer "F.SilkS")
			(hide yes)
			(effects
				(font
					(size 1.27 1.27)
				)
			)
		)
		(property "Value" ""
			(at 0 0 270)
			(layer "F.Fab")
			(effects
				(font
					(size 1.27 1.27)
				)
			)
		)
		(duplicate_pad_numbers_are_jumpers no)
		(fp_line
			(start -1.2954 0.5842)
			(end -1.2954 -0.5842)
			(stroke
				(width 0.1524)
				(type default)
			)
			(layer "F.SilkS")
		)
		(fp_line
			(start 1.2954 0.5842)
			(end -1.2954 0.5842)
			(stroke
				(width 0.1524)
				(type default)
			)
			(layer "F.SilkS")
		)
		(fp_line
			(start -1.2954 -0.5842)
			(end 1.2954 -0.5842)
			(stroke
				(width 0.1524)
				(type default)
			)
			(layer "F.SilkS")
		)
		(fp_line
			(start 1.2954 -0.5842)
			(end 1.2954 0.5842)
			(stroke
				(width 0.1524)
				(type default)
			)
			(layer "F.SilkS")
		)
		(fp_line
			(start -0.8636 0.4572)
			(end -0.8636 0.4064)
			(stroke
				(width 0.1)
				(type default)
			)
			(layer "F.Fab")
		)
		(fp_line
			(start 0.8636 0.4572)
			(end -0.8636 0.4572)
			(stroke
				(width 0.1)
				(type default)
			)
			(layer "F.Fab")
		)
		(fp_line
			(start -1.1938 0.4064)
			(end -1.1938 -0.4064)
			(stroke
				(width 0.1)
				(type default)
			)
			(layer "F.Fab")
		)
		(fp_line
			(start -0.8636 0.4064)
			(end -1.1938 0.4064)
			(stroke
				(width 0.1)
				(type default)
			)
			(layer "F.Fab")
		)
		(fp_line
			(start 0.8636 0.4064)
			(end 0.8636 0.4572)
			(stroke
				(width 0.1)
				(type default)
			)
			(layer "F.Fab")
		)
		(fp_line
			(start 1.1938 0.4064)
			(end 0.8636 0.4064)
			(stroke
				(width 0.1)
				(type default)
			)
			(layer "F.Fab")
		)
		(fp_line
			(start -1.1938 -0.4064)
			(end -0.8636 -0.4064)
			(stroke
				(width 0.1)
				(type default)
			)
			(layer "F.Fab")
		)
		(fp_line
			(start -0.8636 -0.4064)
			(end -0.8636 -0.4572)
			(stroke
				(width 0.1)
				(type default)
			)
			(layer "F.Fab")
		)
		(fp_line
			(start 0.8636 -0.4064)
			(end 1.1938 -0.4064)
			(stroke
				(width 0.1)
				(type default)
			)
			(layer "F.Fab")
		)
		(fp_line
			(start 1.1938 -0.4064)
			(end 1.1938 0.4064)
			(stroke
				(width 0.1)
				(type default)
			)
			(layer "F.Fab")
		)
		(fp_line
			(start -0.8636 -0.4572)
			(end 0.8636 -0.4572)
			(stroke
				(width 0.1)
				(type default)
			)
			(layer "F.Fab")
		)
		(fp_line
			(start 0.8636 -0.4572)
			(end 0.8636 -0.4064)
			(stroke
				(width 0.1)
				(type default)
			)
			(layer "F.Fab")
		)
		(pad "1" smd rect
			(at -0.7366 0 180)
			(size 0.7112 0.8128)
			(layers "F.Cu" "F.Mask" "F.Paste")
			(net "P1V8_PLL0_PEX2")
		)
		(pad "2" smd rect
			(at 0.7366 0 180)
			(size 0.7112 0.8128)
			(layers "F.Cu" "F.Mask" "F.Paste")
			(net "GND")
		)
	)
	(footprint ""
		(layer "F.Cu")
		(at 370.071904 -259.346192)
		(property "Reference" "R1458"
			(at 0 0 0)
			(layer "F.SilkS")
			(hide yes)
			(effects
				(font
					(size 1.27 1.27)
				)
			)
		)
		(property "Value" ""
			(at 0 0 0)
			(layer "F.Fab")
			(effects
				(font
					(size 1.27 1.27)
				)
			)
		)
		(duplicate_pad_numbers_are_jumpers no)
		(fp_line
			(start -0.7874 -0.4064)
			(end 0.7874 -0.4064)
			(stroke
				(width 0.1524)
				(type default)
			)
			(layer "F.SilkS")
		)
		(fp_line
			(start -0.7874 0.4064)
			(end -0.7874 -0.4064)
			(stroke
				(width 0.1524)
				(type default)
			)
			(layer "F.SilkS")
		)
		(fp_line
			(start 0.7874 -0.4064)
			(end 0.7874 0.4064)
			(stroke
				(width 0.1524)
				(type default)
			)
			(layer "F.SilkS")
		)
		(fp_line
			(start 0.7874 0.4064)
			(end -0.7874 0.4064)
			(stroke
				(width 0.1524)
				(type default)
			)
			(layer "F.SilkS")
		)
		(fp_line
			(start -0.67945 -0.305054)
			(end -0.12065 -0.305054)
			(stroke
				(width 0.1)
				(type default)
			)
			(layer "F.Fab")
		)
		(fp_line
			(start -0.67945 0.3048)
			(end -0.67945 -0.305054)
			(stroke
				(width 0.1)
				(type default)
			)
			(layer "F.Fab")
		)
		(fp_line
			(start -0.12065 -0.305054)
			(end -0.12065 -0.2794)
			(stroke
				(width 0.1)
				(type default)
			)
			(layer "F.Fab")
		)
		(fp_line
			(start -0.12065 -0.2794)
			(end 0.12065 -0.2794)
			(stroke
				(width 0.1)
				(type default)
			)
			(layer "F.Fab")
		)
		(fp_line
			(start -0.12065 0.2794)
			(end -0.12065 0.3048)
			(stroke
				(width 0.1)
				(type default)
			)
			(layer "F.Fab")
		)
		(fp_line
			(start -0.12065 0.3048)
			(end -0.67945 0.3048)
			(stroke
				(width 0.1)
				(type default)
			)
			(layer "F.Fab")
		)
		(fp_line
			(start 0.120396 0.2794)
			(end -0.12065 0.2794)
			(stroke
				(width 0.1)
				(type default)
			)
			(layer "F.Fab")
		)
		(fp_line
			(start 0.120396 0.3048)
			(end 0.120396 0.2794)
			(stroke
				(width 0.1)
				(type default)
			)
			(layer "F.Fab")
		)
		(fp_line
			(start 0.12065 -0.3048)
			(end 0.67945 -0.3048)
			(stroke
				(width 0.1)
				(type default)
			)
			(layer "F.Fab")
		)
		(fp_line
			(start 0.12065 -0.2794)
			(end 0.12065 -0.3048)
			(stroke
				(width 0.1)
				(type default)
			)
			(layer "F.Fab")
		)
		(fp_line
			(start 0.67945 -0.3048)
			(end 0.67945 0.3048)
			(stroke
				(width 0.1)
				(type default)
			)
			(layer "F.Fab")
		)
		(fp_line
			(start 0.67945 0.3048)
			(end 0.120396 0.3048)
			(stroke
				(width 0.1)
				(type default)
			)
			(layer "F.Fab")
		)
		(pad "1" smd circle
			(at -0.40005 0)
			(size 0 0)
			(layers "F.Cu" "F.Mask" "F.Paste")
			(net "PEX3_SYS_ERR_N")
		)
		(pad "2" smd circle
			(at 0.40005 0)
			(size 0 0)
			(layers "F.Cu" "F.Mask" "F.Paste")
			(net "PEX3_SYS_ERR_R_N")
		)
	)
	(footprint ""
		(layer "F.Cu")
		(at 261.84987 -320.900044)
		(property "Reference" "H85"
			(at -6.472174 -7.562088 0)
			(unlocked yes)
			(layer "F.SilkS")
			(effects
				(font
					(size 0.7874 0.5842)
					(thickness 0.1524)
				)
				(justify left)
			)
		)
		(property "Value" ""
			(at 0 0 0)
			(layer "F.Fab")
			(effects
				(font
					(size 1.27 1.27)
				)
			)
		)
		(duplicate_pad_numbers_are_jumpers no)
		(fp_arc
			(start 5.559044 5.7531)
			(mid -7.365039 -3.124664)
			(end 7.999984 0)
			(stroke
				(width 0.1524)
				(type default)
			)
			(layer "F.SilkS")
		)
		(fp_arc
			(start 7.999984 0)
			(mid 7.999991 0.010414)
			(end 7.999984 0.020828)
			(stroke
				(width 0.1524)
				(type default)
			)
			(layer "F.SilkS")
		)
		(fp_arc
			(start 5.292598 5.998972)
			(mid -7.291736 -3.290917)
			(end 7.999984 0)
			(stroke
				(width 0.1524)
				(type default)
			)
			(layer "B.SilkS")
		)
		(fp_arc
			(start 7.999984 0)
			(mid 7.993019 0.334811)
			(end 7.972044 0.669036)
			(stroke
				(width 0.1524)
				(type default)
			)
			(layer "B.SilkS")
		)
		(fp_circle
			(center 0 0)
			(end 7.999984 0)
			(stroke
				(width 0.1)
				(type default)
			)
			(fill no)
			(layer "B.Fab")
		)
		(fp_circle
			(center 0 0)
			(end 7.999984 0)
			(stroke
				(width 0.1)
				(type default)
			)
			(fill no)
			(layer "F.Fab")
		)
		(pad "" np_thru_hole circle
			(at 0 0)
			(size 4.5212 4.5212)
			(drill 4.5212)
			(layers "*.Cu" "*.Mask")
			(clearance 0.381)
			(thermal_gap 0.381)
		)
		(pad "2" thru_hole circle
			(at 3.6322 0)
			(size 0.762 0.762)
			(drill 0.5588)
			(layers "*.Cu" "*.Mask")
			(remove_unused_layers no)
			(net "GND")
			(clearance 0.1524)
			(thermal_gap 0.1524)
		)
		(pad "3" thru_hole circle
			(at 2.568448 -2.568448)
			(size 0.762 0.762)
			(drill 0.5588)
			(layers "*.Cu" "*.Mask")
			(remove_unused_layers no)
			(net "GND")
			(clearance 0.1524)
			(thermal_gap 0.1524)
		)
		(pad "4" thru_hole circle
			(at 0 -3.6322)
			(size 0.762 0.762)
			(drill 0.5588)
			(layers "*.Cu" "*.Mask")
			(remove_unused_layers no)
			(net "GND")
			(clearance 0.1524)
			(thermal_gap 0.1524)
		)
		(pad "5" thru_hole circle
			(at -2.568448 -2.568448)
			(size 0.762 0.762)
			(drill 0.5588)
			(layers "*.Cu" "*.Mask")
			(remove_unused_layers no)
			(net "GND")
			(clearance 0.1524)
			(thermal_gap 0.1524)
		)
		(pad "6" thru_hole circle
			(at -3.6322 0)
			(size 0.762 0.762)
			(drill 0.5588)
			(layers "*.Cu" "*.Mask")
			(remove_unused_layers no)
			(net "GND")
			(clearance 0.1524)
			(thermal_gap 0.1524)
		)
		(pad "7" thru_hole circle
			(at -2.568448 2.568448)
			(size 0.762 0.762)
			(drill 0.5588)
			(layers "*.Cu" "*.Mask")
			(remove_unused_layers no)
			(net "GND")
			(clearance 0.1524)
			(thermal_gap 0.1524)
		)
		(pad "8" thru_hole circle
			(at 0 3.6322)
			(size 0.762 0.762)
			(drill 0.5588)
			(layers "*.Cu" "*.Mask")
			(remove_unused_layers no)
			(net "GND")
			(clearance 0.1524)
			(thermal_gap 0.1524)
		)
		(pad "9" thru_hole circle
			(at 2.568448 2.568448)
			(size 0.762 0.762)
			(drill 0.5588)
			(layers "*.Cu" "*.Mask")
			(remove_unused_layers no)
			(net "GND")
			(clearance 0.1524)
			(thermal_gap 0.1524)
		)
		(zone
			(layer "F.Cu")
			(hatch none 0.5)
			(connect_pads
				(clearance 0)
			)
			(min_thickness 0.25)
			(keepout
				(tracks not_allowed)
				(vias allowed)
				(pads allowed)
				(copperpour not_allowed)
				(footprints allowed)
			)
			(placement
				(enabled no)
				(sheetname "")
			)
			(fill
				(thermal_gap 0.5)
				(thermal_bridge_width 0.5)
				(island_removal_mode 0)
			)
			(polygon
				(pts
					(arc
						(start 261.84987 -312.90006)
						(mid 253.849886 -320.900044)
						(end 261.84987 -328.900028)
					)
					(arc
						(start 261.84987 -325.649844)
						(mid 257.10007 -320.900044)
						(end 261.84987 -316.150244)
					)
				)
			)
		)
		(zone
			(layer "F.Cu")
			(hatch none 0.5)
			(connect_pads
				(clearance 0)
			)
			(min_thickness 0.25)
			(keepout
				(tracks not_allowed)
				(vias allowed)
				(pads allowed)
				(copperpour not_allowed)
				(footprints allowed)
			)
			(placement
				(enabled no)
				(sheetname "")
			)
			(fill
				(thermal_gap 0.5)
				(thermal_bridge_width 0.5)
				(island_removal_mode 0)
			)
			(polygon
				(pts
					(arc
						(start 261.84987 -312.90006)
						(mid 269.849854 -320.900044)
						(end 261.84987 -328.900028)
					)
					(arc
						(start 261.84987 -325.649844)
						(mid 266.59967 -320.900044)
						(end 261.84987 -316.150244)
					)
				)
			)
		)
		(zone
			(layers "F.Cu" "B.Cu" "In1.Cu" "In2.Cu" "In3.Cu" "In4.Cu" "In5.Cu" "In6.Cu"
				"In7.Cu" "In8.Cu" "In9.Cu" "In10.Cu" "In11.Cu" "In12.Cu" "In13.Cu" "In14.Cu"
				"In15.Cu" "In16.Cu"
			)
			(hatch none 0.5)
			(connect_pads
				(clearance 0)
			)
			(min_thickness 0.25)
			(keepout
				(tracks not_allowed)
				(vias allowed)
				(pads allowed)
				(copperpour not_allowed)
				(footprints allowed)
			)
			(placement
				(enabled no)
				(sheetname "")
			)
			(fill
				(thermal_gap 0.5)
				(thermal_bridge_width 0.5)
				(island_removal_mode 0)
			)
			(polygon
				(pts
					(arc
						(start 264.61593 -320.900044)
						(mid 259.08381 -320.900044)
						(end 264.61593 -320.900044)
					)
				)
			)
		)
		(zone
			(layer "B.Cu")
			(hatch none 0.5)
			(connect_pads
				(clearance 0)
			)
			(min_thickness 0.25)
			(keepout
				(tracks not_allowed)
				(vias allowed)
				(pads allowed)
				(copperpour not_allowed)
				(footprints allowed)
			)
			(placement
				(enabled no)
				(sheetname "")
			)
			(fill
				(thermal_gap 0.5)
				(thermal_bridge_width 0.5)
				(island_removal_mode 0)
			)
			(polygon
				(pts
					(arc
						(start 261.84987 -315.896244)
						(mid 256.84607 -320.900044)
						(end 261.84987 -325.903844)
					)
					(arc
						(start 261.84987 -325.421244)
						(mid 257.32867 -320.900044)
						(end 261.84987 -316.378844)
					)
				)
			)
		)
		(zone
			(layer "B.Cu")
			(hatch none 0.5)
			(connect_pads
				(clearance 0)
			)
			(min_thickness 0.25)
			(keepout
				(tracks not_allowed)
				(vias allowed)
				(pads allowed)
				(copperpour not_allowed)
				(footprints allowed)
			)
			(placement
				(enabled no)
				(sheetname "")
			)
			(fill
				(thermal_gap 0.5)
				(thermal_bridge_width 0.5)
				(island_removal_mode 0)
			)
			(polygon
				(pts
					(arc
						(start 261.84987 -315.896244)
						(mid 266.85367 -320.900044)
						(end 261.84987 -325.903844)
					)
					(arc
						(start 261.84987 -325.421244)
						(mid 266.37107 -320.900044)
						(end 261.84987 -316.378844)
					)
				)
			)
		)
	)
	(footprint ""
		(layer "F.Cu")
		(at 160.041082 -438.984644 180)
		(property "Reference" "X66"
			(at -0.1778 -1.92913 180)
			(unlocked yes)
			(layer "F.SilkS")
			(effects
				(font
					(size 0.7874 0.5842)
					(thickness 0.1524)
				)
				(justify left)
			)
		)
		(property "Value" ""
			(at 0 0 180)
			(layer "F.Fab")
			(effects
				(font
					(size 1.27 1.27)
				)
			)
		)
		(property "Device Type" "TP_TDR_4P_FTS_MPKT4_H025P0200_IO_TP15_TP_TDR_4P_DIP"
			(at 1.30175 1.27 270)
			(unlocked yes)
			(layer "F.Fab")
			(hide yes)
			(effects
				(font
					(size 0.635 0.4064)
					(thickness 0.1524)
				)
			)
		)
		(property "User Part Number" "TP15"
			(at 1.30175 1.27 270)
			(unlocked yes)
			(layer "Cmts.User")
			(hide yes)
			(effects
				(font
					(size 0.635 0.4064)
					(thickness 0.1524)
				)
			)
		)
		(duplicate_pad_numbers_are_jumpers no)
		(fp_line
			(start 2.54 3.81)
			(end 2.54 3.6703)
			(stroke
				(width 0.1524)
				(type default)
			)
			(layer "F.SilkS")
		)
		(fp_line
			(start 2.54 1.4097)
			(end 2.54 1.1303)
			(stroke
				(width 0.1524)
				(type default)
			)
			(layer "F.SilkS")
		)
		(fp_line
			(start 2.54 -1.1303)
			(end 2.54 -1.27)
			(stroke
				(width 0.1524)
				(type default)
			)
			(layer "F.SilkS")
		)
		(fp_line
			(start 2.54 -1.27)
			(end 0 -1.27)
			(stroke
				(width 0.1524)
				(type default)
			)
			(layer "F.SilkS")
		)
		(fp_line
			(start 0 3.81)
			(end 2.54 3.81)
			(stroke
				(width 0.1524)
				(type default)
			)
			(layer "F.SilkS")
		)
		(fp_line
			(start 0 3.175)
			(end 0 3.81)
			(stroke
				(width 0.1524)
				(type default)
			)
			(layer "F.SilkS")
		)
		(fp_line
			(start 0 0.635)
			(end 0 1.905)
			(stroke
				(width 0.1524)
				(type default)
			)
			(layer "F.SilkS")
		)
		(fp_line
			(start 0 -1.27)
			(end 0 -0.635)
			(stroke
				(width 0.1524)
				(type default)
			)
			(layer "F.SilkS")
		)
		(fp_poly
			(pts
				(xy -0.761746 0) (xy -2.285746 -0.762) (xy -2.285746 0.762)
			)
			(stroke
				(width 0)
				(type default)
			)
			(fill yes)
			(layer "F.SilkS")
		)
		(fp_line
			(start 2.54 3.81)
			(end 2.54 -1.27)
			(stroke
				(width 0.1)
				(type default)
			)
			(layer "F.Fab")
		)
		(fp_line
			(start 2.54 -1.27)
			(end 0 -1.27)
			(stroke
				(width 0.1)
				(type default)
			)
			(layer "F.Fab")
		)
		(fp_line
			(start 0 3.81)
			(end 2.54 3.81)
			(stroke
				(width 0.1)
				(type default)
			)
			(layer "F.Fab")
		)
		(fp_line
			(start 0 -1.27)
			(end 0 3.81)
			(stroke
				(width 0.1)
				(type default)
			)
			(layer "F.Fab")
		)
		(fp_poly
			(pts
				(xy -0.761746 0) (xy -2.285746 -0.762) (xy -2.285746 0.762)
			)
			(stroke
				(width 0)
				(type default)
			)
			(fill yes)
			(layer "F.Fab")
		)
		(pad "1" thru_hole circle
			(at 0 0 180)
			(size 1.0033 1.0033)
			(drill 0.249936)
			(layers "*.Cu" "*.Mask")
			(remove_unused_layers no)
			(net "TDR_DIFF_100_TOP_DIP")
			(clearance 0.10795)
			(thermal_gap 0.10795)
			(padstack
				(mode front_inner_back)
				(layer "Inner"
					(shape circle)
					(size 0.8001 0.8001)
					(clearance 0.1524)
				)
				(layer "B.Cu"
					(shape circle)
					(size 1.0033 1.0033)
					(clearance 0.10795)
				)
			)
		)
		(pad "2" thru_hole circle
			(at 2.54 0 180)
			(size 1.9939 1.9939)
			(drill 0.249936)
			(layers "*.Cu" "*.Mask")
			(remove_unused_layers no)
			(net "COUPON_GND1")
			(clearance 0.10795)
			(thermal_gap 0.10795)
			(padstack
				(mode front_inner_back)
				(layer "Inner"
					(shape circle)
					(size 0.8001 0.8001)
					(clearance 0.1524)
				)
				(layer "B.Cu"
					(shape circle)
					(size 1.9939 1.9939)
					(clearance 0.10795)
				)
			)
		)
		(pad "3" thru_hole circle
			(at 2.54 2.54 180)
			(size 1.9939 1.9939)
			(drill 0.249936)
			(layers "*.Cu" "*.Mask")
			(remove_unused_layers no)
			(net "COUPON_GND1")
			(clearance 0.10795)
			(thermal_gap 0.10795)
			(padstack
				(mode front_inner_back)
				(layer "Inner"
					(shape circle)
					(size 0.8001 0.8001)
					(clearance 0.1524)
				)
				(layer "B.Cu"
					(shape circle)
					(size 1.9939 1.9939)
					(clearance 0.10795)
				)
			)
		)
		(pad "4" thru_hole circle
			(at 0 2.54 180)
			(size 1.0033 1.0033)
			(drill 0.249936)
			(layers "*.Cu" "*.Mask")
			(remove_unused_layers no)
			(net "TDR_DIFF_100_TOP_DIN")
			(clearance 0.10795)
			(thermal_gap 0.10795)
			(padstack
				(mode front_inner_back)
				(layer "Inner"
					(shape circle)
					(size 0.8001 0.8001)
					(clearance 0.1524)
				)
				(layer "B.Cu"
					(shape circle)
					(size 1.0033 1.0033)
					(clearance 0.10795)
				)
			)
		)
	)
	(footprint ""
		(layer "F.Cu")
		(at 381.587756 -298.020232)
		(property "Reference" "C3543"
			(at 0 0 0)
			(layer "F.SilkS")
			(hide yes)
			(effects
				(font
					(size 1.27 1.27)
				)
			)
		)
		(property "Value" ""
			(at 0 0 0)
			(layer "F.Fab")
			(effects
				(font
					(size 1.27 1.27)
				)
			)
		)
		(duplicate_pad_numbers_are_jumpers no)
		(fp_line
			(start -1.2954 -0.5842)
			(end 1.2954 -0.5842)
			(stroke
				(width 0.1524)
				(type default)
			)
			(layer "F.SilkS")
		)
		(fp_line
			(start -1.2954 0.5842)
			(end -1.2954 -0.5842)
			(stroke
				(width 0.1524)
				(type default)
			)
			(layer "F.SilkS")
		)
		(fp_line
			(start 1.2954 -0.5842)
			(end 1.2954 0.5842)
			(stroke
				(width 0.1524)
				(type default)
			)
			(layer "F.SilkS")
		)
		(fp_line
			(start 1.2954 0.5842)
			(end -1.2954 0.5842)
			(stroke
				(width 0.1524)
				(type default)
			)
			(layer "F.SilkS")
		)
		(fp_line
			(start -1.1938 -0.4064)
			(end -0.8636 -0.4064)
			(stroke
				(width 0.1)
				(type default)
			)
			(layer "F.Fab")
		)
		(fp_line
			(start -1.1938 0.4064)
			(end -1.1938 -0.4064)
			(stroke
				(width 0.1)
				(type default)
			)
			(layer "F.Fab")
		)
		(fp_line
			(start -0.8636 -0.4572)
			(end 0.8636 -0.4572)
			(stroke
				(width 0.1)
				(type default)
			)
			(layer "F.Fab")
		)
		(fp_line
			(start -0.8636 -0.4064)
			(end -0.8636 -0.4572)
			(stroke
				(width 0.1)
				(type default)
			)
			(layer "F.Fab")
		)
		(fp_line
			(start -0.8636 0.4064)
			(end -1.1938 0.4064)
			(stroke
				(width 0.1)
				(type default)
			)
			(layer "F.Fab")
		)
		(fp_line
			(start -0.8636 0.4572)
			(end -0.8636 0.4064)
			(stroke
				(width 0.1)
				(type default)
			)
			(layer "F.Fab")
		)
		(fp_line
			(start 0.8636 -0.4572)
			(end 0.8636 -0.4064)
			(stroke
				(width 0.1)
				(type default)
			)
			(layer "F.Fab")
		)
		(fp_line
			(start 0.8636 -0.4064)
			(end 1.1938 -0.4064)
			(stroke
				(width 0.1)
				(type default)
			)
			(layer "F.Fab")
		)
		(fp_line
			(start 0.8636 0.4064)
			(end 0.8636 0.4572)
			(stroke
				(width 0.1)
				(type default)
			)
			(layer "F.Fab")
		)
		(fp_line
			(start 0.8636 0.4572)
			(end -0.8636 0.4572)
			(stroke
				(width 0.1)
				(type default)
			)
			(layer "F.Fab")
		)
		(fp_line
			(start 1.1938 -0.4064)
			(end 1.1938 0.4064)
			(stroke
				(width 0.1)
				(type default)
			)
			(layer "F.Fab")
		)
		(fp_line
			(start 1.1938 0.4064)
			(end 0.8636 0.4064)
			(stroke
				(width 0.1)
				(type default)
			)
			(layer "F.Fab")
		)
		(pad "1" smd rect
			(at -0.7366 0 270)
			(size 0.7112 0.8128)
			(layers "F.Cu" "F.Mask" "F.Paste")
			(net "PCEPLL0_VDDA18_PEX3")
		)
		(pad "2" smd rect
			(at 0.7366 0 270)
			(size 0.7112 0.8128)
			(layers "F.Cu" "F.Mask" "F.Paste")
			(net "GND")
		)
	)
	(footprint ""
		(layer "F.Cu")
		(at 321.91325 -104.267508 -90)
		(property "Reference" "R745"
			(at 0 0 270)
			(layer "F.SilkS")
			(hide yes)
			(effects
				(font
					(size 1.27 1.27)
				)
			)
		)
		(property "Value" ""
			(at 0 0 270)
			(layer "F.Fab")
			(effects
				(font
					(size 1.27 1.27)
				)
			)
		)
		(duplicate_pad_numbers_are_jumpers no)
		(fp_line
			(start -0.7874 0.4064)
			(end -0.7874 -0.4064)
			(stroke
				(width 0.1524)
				(type default)
			)
			(layer "F.SilkS")
		)
		(fp_line
			(start 0.7874 0.4064)
			(end -0.7874 0.4064)
			(stroke
				(width 0.1524)
				(type default)
			)
			(layer "F.SilkS")
		)
		(fp_line
			(start -0.7874 -0.4064)
			(end 0.7874 -0.4064)
			(stroke
				(width 0.1524)
				(type default)
			)
			(layer "F.SilkS")
		)
		(fp_line
			(start 0.7874 -0.4064)
			(end 0.7874 0.4064)
			(stroke
				(width 0.1524)
				(type default)
			)
			(layer "F.SilkS")
		)
		(fp_line
			(start -0.67945 0.3048)
			(end -0.67945 -0.305054)
			(stroke
				(width 0.1)
				(type default)
			)
			(layer "F.Fab")
		)
		(fp_line
			(start -0.12065 0.3048)
			(end -0.67945 0.3048)
			(stroke
				(width 0.1)
				(type default)
			)
			(layer "F.Fab")
		)
		(fp_line
			(start 0.120396 0.3048)
			(end 0.120396 0.2794)
			(stroke
				(width 0.1)
				(type default)
			)
			(layer "F.Fab")
		)
		(fp_line
			(start 0.67945 0.3048)
			(end 0.120396 0.3048)
			(stroke
				(width 0.1)
				(type default)
			)
			(layer "F.Fab")
		)
		(fp_line
			(start -0.12065 0.2794)
			(end -0.12065 0.3048)
			(stroke
				(width 0.1)
				(type default)
			)
			(layer "F.Fab")
		)
		(fp_line
			(start 0.120396 0.2794)
			(end -0.12065 0.2794)
			(stroke
				(width 0.1)
				(type default)
			)
			(layer "F.Fab")
		)
		(fp_line
			(start -0.12065 -0.2794)
			(end 0.12065 -0.2794)
			(stroke
				(width 0.1)
				(type default)
			)
			(layer "F.Fab")
		)
		(fp_line
			(start 0.12065 -0.2794)
			(end 0.12065 -0.3048)
			(stroke
				(width 0.1)
				(type default)
			)
			(layer "F.Fab")
		)
		(fp_line
			(start 0.12065 -0.3048)
			(end 0.67945 -0.3048)
			(stroke
				(width 0.1)
				(type default)
			)
			(layer "F.Fab")
		)
		(fp_line
			(start 0.67945 -0.3048)
			(end 0.67945 0.3048)
			(stroke
				(width 0.1)
				(type default)
			)
			(layer "F.Fab")
		)
		(fp_line
			(start -0.67945 -0.305054)
			(end -0.12065 -0.305054)
			(stroke
				(width 0.1)
				(type default)
			)
			(layer "F.Fab")
		)
		(fp_line
			(start -0.12065 -0.305054)
			(end -0.12065 -0.2794)
			(stroke
				(width 0.1)
				(type default)
			)
			(layer "F.Fab")
		)
		(pad "1" smd circle
			(at -0.40005 0 270)
			(size 0 0)
			(layers "F.Cu" "F.Mask" "F.Paste")
			(net "P12V_NIC5")
		)
		(pad "2" smd circle
			(at 0.40005 0 270)
			(size 0 0)
			(layers "F.Cu" "F.Mask" "F.Paste")
			(net "P12V_NIC5_VIN_N")
		)
	)
	(footprint ""
		(layer "F.Cu")
		(at 21.541232 -25.915112 -90)
		(property "Reference" "R6198"
			(at 0 0 270)
			(layer "F.SilkS")
			(hide yes)
			(effects
				(font
					(size 1.27 1.27)
				)
			)
		)
		(property "Value" ""
			(at 0 0 270)
			(layer "F.Fab")
			(effects
				(font
					(size 1.27 1.27)
				)
			)
		)
		(duplicate_pad_numbers_are_jumpers no)
		(fp_line
			(start -0.7874 0.4064)
			(end -0.7874 -0.4064)
			(stroke
				(width 0.1524)
				(type default)
			)
			(layer "F.SilkS")
		)
		(fp_line
			(start 0.7874 0.4064)
			(end -0.7874 0.4064)
			(stroke
				(width 0.1524)
				(type default)
			)
			(layer "F.SilkS")
		)
		(fp_line
			(start -0.7874 -0.4064)
			(end 0.7874 -0.4064)
			(stroke
				(width 0.1524)
				(type default)
			)
			(layer "F.SilkS")
		)
		(fp_line
			(start 0.7874 -0.4064)
			(end 0.7874 0.4064)
			(stroke
				(width 0.1524)
				(type default)
			)
			(layer "F.SilkS")
		)
		(fp_line
			(start -0.67945 0.3048)
			(end -0.67945 -0.305054)
			(stroke
				(width 0.1)
				(type default)
			)
			(layer "F.Fab")
		)
		(fp_line
			(start -0.12065 0.3048)
			(end -0.67945 0.3048)
			(stroke
				(width 0.1)
				(type default)
			)
			(layer "F.Fab")
		)
		(fp_line
			(start 0.120396 0.3048)
			(end 0.120396 0.2794)
			(stroke
				(width 0.1)
				(type default)
			)
			(layer "F.Fab")
		)
		(fp_line
			(start 0.67945 0.3048)
			(end 0.120396 0.3048)
			(stroke
				(width 0.1)
				(type default)
			)
			(layer "F.Fab")
		)
		(fp_line
			(start -0.12065 0.2794)
			(end -0.12065 0.3048)
			(stroke
				(width 0.1)
				(type default)
			)
			(layer "F.Fab")
		)
		(fp_line
			(start 0.120396 0.2794)
			(end -0.12065 0.2794)
			(stroke
				(width 0.1)
				(type default)
			)
			(layer "F.Fab")
		)
		(fp_line
			(start -0.12065 -0.2794)
			(end 0.12065 -0.2794)
			(stroke
				(width 0.1)
				(type default)
			)
			(layer "F.Fab")
		)
		(fp_line
			(start 0.12065 -0.2794)
			(end 0.12065 -0.3048)
			(stroke
				(width 0.1)
				(type default)
			)
			(layer "F.Fab")
		)
		(fp_line
			(start 0.12065 -0.3048)
			(end 0.67945 -0.3048)
			(stroke
				(width 0.1)
				(type default)
			)
			(layer "F.Fab")
		)
		(fp_line
			(start 0.67945 -0.3048)
			(end 0.67945 0.3048)
			(stroke
				(width 0.1)
				(type default)
			)
			(layer "F.Fab")
		)
		(fp_line
			(start -0.67945 -0.305054)
			(end -0.12065 -0.305054)
			(stroke
				(width 0.1)
				(type default)
			)
			(layer "F.Fab")
		)
		(fp_line
			(start -0.12065 -0.305054)
			(end -0.12065 -0.2794)
			(stroke
				(width 0.1)
				(type default)
			)
			(layer "F.Fab")
		)
		(pad "1" smd circle
			(at -0.40005 0 270)
			(size 0 0)
			(layers "F.Cu" "F.Mask" "F.Paste")
			(net "GND")
		)
		(pad "2" smd circle
			(at 0.40005 0 270)
			(size 0 0)
			(layers "F.Cu" "F.Mask" "F.Paste")
			(net "SSD0_PWRDIS_R")
		)
	)
	(footprint ""
		(layer "F.Cu")
		(at 302.039782 -70.52437 90)
		(property "Reference" "PC429"
			(at 0 0 90)
			(layer "F.SilkS")
			(hide yes)
			(effects
				(font
					(size 1.27 1.27)
				)
			)
		)
		(property "Value" ""
			(at 0 0 90)
			(layer "F.Fab")
			(effects
				(font
					(size 1.27 1.27)
				)
			)
		)
		(duplicate_pad_numbers_are_jumpers no)
		(fp_line
			(start 1.524 -0.762)
			(end 1.524 0.762)
			(stroke
				(width 0.1524)
				(type default)
			)
			(layer "F.SilkS")
		)
		(fp_line
			(start -1.524 -0.762)
			(end 1.524 -0.762)
			(stroke
				(width 0.1524)
				(type default)
			)
			(layer "F.SilkS")
		)
		(fp_line
			(start 1.524 0.762)
			(end -1.524 0.762)
			(stroke
				(width 0.1524)
				(type default)
			)
			(layer "F.SilkS")
		)
		(fp_line
			(start -1.524 0.762)
			(end -1.524 -0.762)
			(stroke
				(width 0.1524)
				(type default)
			)
			(layer "F.SilkS")
		)
		(fp_line
			(start 1.1049 -0.724916)
			(end -1.1049 -0.724916)
			(stroke
				(width 0.1)
				(type default)
			)
			(layer "F.Fab")
		)
		(fp_line
			(start -1.1049 -0.724916)
			(end -1.1049 0.724916)
			(stroke
				(width 0.1)
				(type default)
			)
			(layer "F.Fab")
		)
		(fp_line
			(start 1.1049 0.724916)
			(end 1.1049 -0.724916)
			(stroke
				(width 0.1)
				(type default)
			)
			(layer "F.Fab")
		)
		(fp_line
			(start -1.1049 0.724916)
			(end 1.1049 0.724916)
			(stroke
				(width 0.1)
				(type default)
			)
			(layer "F.Fab")
		)
		(pad "1" smd rect
			(at -0.889 0 270)
			(size 1.016 1.27)
			(layers "F.Cu" "F.Mask" "F.Paste")
			(net "P12V_SSD10_R")
		)
		(pad "2" smd rect
			(at 0.889 0 270)
			(size 1.016 1.27)
			(layers "F.Cu" "F.Mask" "F.Paste")
			(net "GND")
		)
	)
	(footprint ""
		(layer "F.Cu")
		(at 190.245238 -412.21914 -90)
		(property "Reference" "R6776"
			(at 0 0 270)
			(layer "F.SilkS")
			(hide yes)
			(effects
				(font
					(size 1.27 1.27)
				)
			)
		)
		(property "Value" ""
			(at 0 0 270)
			(layer "F.Fab")
			(effects
				(font
					(size 1.27 1.27)
				)
			)
		)
		(duplicate_pad_numbers_are_jumpers no)
		(fp_line
			(start -0.7874 0.4064)
			(end -0.7874 -0.4064)
			(stroke
				(width 0.1524)
				(type default)
			)
			(layer "F.SilkS")
		)
		(fp_line
			(start 0.7874 0.4064)
			(end -0.7874 0.4064)
			(stroke
				(width 0.1524)
				(type default)
			)
			(layer "F.SilkS")
		)
		(fp_line
			(start -0.7874 -0.4064)
			(end 0.7874 -0.4064)
			(stroke
				(width 0.1524)
				(type default)
			)
			(layer "F.SilkS")
		)
		(fp_line
			(start 0.7874 -0.4064)
			(end 0.7874 0.4064)
			(stroke
				(width 0.1524)
				(type default)
			)
			(layer "F.SilkS")
		)
		(fp_line
			(start -0.67945 0.3048)
			(end -0.67945 -0.305054)
			(stroke
				(width 0.1)
				(type default)
			)
			(layer "F.Fab")
		)
		(fp_line
			(start -0.12065 0.3048)
			(end -0.67945 0.3048)
			(stroke
				(width 0.1)
				(type default)
			)
			(layer "F.Fab")
		)
		(fp_line
			(start 0.120396 0.3048)
			(end 0.120396 0.2794)
			(stroke
				(width 0.1)
				(type default)
			)
			(layer "F.Fab")
		)
		(fp_line
			(start 0.67945 0.3048)
			(end 0.120396 0.3048)
			(stroke
				(width 0.1)
				(type default)
			)
			(layer "F.Fab")
		)
		(fp_line
			(start -0.12065 0.2794)
			(end -0.12065 0.3048)
			(stroke
				(width 0.1)
				(type default)
			)
			(layer "F.Fab")
		)
		(fp_line
			(start 0.120396 0.2794)
			(end -0.12065 0.2794)
			(stroke
				(width 0.1)
				(type default)
			)
			(layer "F.Fab")
		)
		(fp_line
			(start -0.12065 -0.2794)
			(end 0.12065 -0.2794)
			(stroke
				(width 0.1)
				(type default)
			)
			(layer "F.Fab")
		)
		(fp_line
			(start 0.12065 -0.2794)
			(end 0.12065 -0.3048)
			(stroke
				(width 0.1)
				(type default)
			)
			(layer "F.Fab")
		)
		(fp_line
			(start 0.12065 -0.3048)
			(end 0.67945 -0.3048)
			(stroke
				(width 0.1)
				(type default)
			)
			(layer "F.Fab")
		)
		(fp_line
			(start 0.67945 -0.3048)
			(end 0.67945 0.3048)
			(stroke
				(width 0.1)
				(type default)
			)
			(layer "F.Fab")
		)
		(fp_line
			(start -0.67945 -0.305054)
			(end -0.12065 -0.305054)
			(stroke
				(width 0.1)
				(type default)
			)
			(layer "F.Fab")
		)
		(fp_line
			(start -0.12065 -0.305054)
			(end -0.12065 -0.2794)
			(stroke
				(width 0.1)
				(type default)
			)
			(layer "F.Fab")
		)
		(pad "1" smd circle
			(at -0.40005 0 270)
			(size 0 0)
			(layers "F.Cu" "F.Mask" "F.Paste")
			(net "P12V_AUX_FP_TRIGGER")
		)
		(pad "2" smd circle
			(at 0.40005 0 270)
			(size 0 0)
			(layers "F.Cu" "F.Mask" "F.Paste")
			(net "HSC_UV_R2_N")
		)
	)
	(footprint ""
		(layer "F.Cu")
		(at 169.940224 -32.848042 90)
		(property "Reference" "PC935"
			(at 0 0 90)
			(layer "F.SilkS")
			(hide yes)
			(effects
				(font
					(size 1.27 1.27)
				)
			)
		)
		(property "Value" ""
			(at 0 0 90)
			(layer "F.Fab")
			(effects
				(font
					(size 1.27 1.27)
				)
			)
		)
		(duplicate_pad_numbers_are_jumpers no)
		(fp_line
			(start 0.7874 -0.4064)
			(end 0.7874 0.4064)
			(stroke
				(width 0.1524)
				(type default)
			)
			(layer "F.SilkS")
		)
		(fp_line
			(start -0.7874 -0.4064)
			(end 0.7874 -0.4064)
			(stroke
				(width 0.1524)
				(type default)
			)
			(layer "F.SilkS")
		)
		(fp_line
			(start 0.7874 0.4064)
			(end -0.7874 0.4064)
			(stroke
				(width 0.1524)
				(type default)
			)
			(layer "F.SilkS")
		)
		(fp_line
			(start -0.7874 0.4064)
			(end -0.7874 -0.4064)
			(stroke
				(width 0.1524)
				(type default)
			)
			(layer "F.SilkS")
		)
		(fp_line
			(start -0.12065 -0.305054)
			(end -0.12065 -0.2794)
			(stroke
				(width 0.1)
				(type default)
			)
			(layer "F.Fab")
		)
		(fp_line
			(start -0.67945 -0.305054)
			(end -0.12065 -0.305054)
			(stroke
				(width 0.1)
				(type default)
			)
			(layer "F.Fab")
		)
		(fp_line
			(start 0.67945 -0.3048)
			(end 0.67945 0.3048)
			(stroke
				(width 0.1)
				(type default)
			)
			(layer "F.Fab")
		)
		(fp_line
			(start 0.12065 -0.3048)
			(end 0.67945 -0.3048)
			(stroke
				(width 0.1)
				(type default)
			)
			(layer "F.Fab")
		)
		(fp_line
			(start 0.12065 -0.2794)
			(end 0.12065 -0.3048)
			(stroke
				(width 0.1)
				(type default)
			)
			(layer "F.Fab")
		)
		(fp_line
			(start -0.12065 -0.2794)
			(end 0.12065 -0.2794)
			(stroke
				(width 0.1)
				(type default)
			)
			(layer "F.Fab")
		)
		(fp_line
			(start 0.120396 0.2794)
			(end -0.12065 0.2794)
			(stroke
				(width 0.1)
				(type default)
			)
			(layer "F.Fab")
		)
		(fp_line
			(start -0.12065 0.2794)
			(end -0.12065 0.3048)
			(stroke
				(width 0.1)
				(type default)
			)
			(layer "F.Fab")
		)
		(fp_line
			(start 0.67945 0.3048)
			(end 0.120396 0.3048)
			(stroke
				(width 0.1)
				(type default)
			)
			(layer "F.Fab")
		)
		(fp_line
			(start 0.120396 0.3048)
			(end 0.120396 0.2794)
			(stroke
				(width 0.1)
				(type default)
			)
			(layer "F.Fab")
		)
		(fp_line
			(start -0.12065 0.3048)
			(end -0.67945 0.3048)
			(stroke
				(width 0.1)
				(type default)
			)
			(layer "F.Fab")
		)
		(fp_line
			(start -0.67945 0.3048)
			(end -0.67945 -0.305054)
			(stroke
				(width 0.1)
				(type default)
			)
			(layer "F.Fab")
		)
		(pad "1" smd circle
			(at -0.40005 0 90)
			(size 0 0)
			(layers "F.Cu" "F.Mask" "F.Paste")
			(net "P3V3_SSD6_CO_DV_DT")
		)
		(pad "2" smd circle
			(at 0.40005 0 90)
			(size 0 0)
			(layers "F.Cu" "F.Mask" "F.Paste")
			(net "GND")
		)
	)
	(footprint ""
		(layer "F.Cu")
		(at 294.832024 -169.040302 -90)
		(property "Reference" "U32"
			(at 0.384302 -2.400046 90)
			(unlocked yes)
			(layer "F.SilkS")
			(effects
				(font
					(size 0.7874 0.5842)
					(thickness 0.1524)
				)
			)
		)
		(property "Value" ""
			(at 0 0 270)
			(layer "F.Fab")
			(effects
				(font
					(size 1.27 1.27)
				)
			)
		)
		(duplicate_pad_numbers_are_jumpers no)
		(fp_line
			(start -1.905 1.651)
			(end -1.905 -1.651)
			(stroke
				(width 0.1524)
				(type default)
			)
			(layer "F.SilkS")
		)
		(fp_line
			(start 1.905 1.651)
			(end -1.905 1.651)
			(stroke
				(width 0.1524)
				(type default)
			)
			(layer "F.SilkS")
		)
		(fp_line
			(start -1.905 -1.651)
			(end 1.905 -1.651)
			(stroke
				(width 0.1524)
				(type default)
			)
			(layer "F.SilkS")
		)
		(fp_line
			(start 1.905 -1.651)
			(end 1.905 1.651)
			(stroke
				(width 0.1524)
				(type default)
			)
			(layer "F.SilkS")
		)
		(fp_line
			(start -0.649986 1.524)
			(end -0.649986 1.169924)
			(stroke
				(width 0.1)
				(type default)
			)
			(layer "F.Fab")
		)
		(fp_line
			(start 0.6985 1.524)
			(end -0.649986 1.524)
			(stroke
				(width 0.1)
				(type default)
			)
			(layer "F.Fab")
		)
		(fp_line
			(start -1.249934 1.169924)
			(end -1.249934 0.729996)
			(stroke
				(width 0.1)
				(type default)
			)
			(layer "F.Fab")
		)
		(fp_line
			(start -0.649986 1.169924)
			(end -1.249934 1.169924)
			(stroke
				(width 0.1)
				(type default)
			)
			(layer "F.Fab")
		)
		(fp_line
			(start -1.249934 0.729996)
			(end -0.6985 0.729996)
			(stroke
				(width 0.1)
				(type default)
			)
			(layer "F.Fab")
		)
		(fp_line
			(start -0.6985 0.729996)
			(end -0.6985 -0.729996)
			(stroke
				(width 0.1)
				(type default)
			)
			(layer "F.Fab")
		)
		(fp_line
			(start 0.6985 0.219964)
			(end 0.6985 1.524)
			(stroke
				(width 0.1)
				(type default)
			)
			(layer "F.Fab")
		)
		(fp_line
			(start 1.249934 0.219964)
			(end 0.6985 0.219964)
			(stroke
				(width 0.1)
				(type default)
			)
			(layer "F.Fab")
		)
		(fp_line
			(start 0.6985 -0.219964)
			(end 1.249934 -0.219964)
			(stroke
				(width 0.1)
				(type default)
			)
			(layer "F.Fab")
		)
		(fp_line
			(start 1.249934 -0.219964)
			(end 1.249934 0.219964)
			(stroke
				(width 0.1)
				(type default)
			)
			(layer "F.Fab")
		)
		(fp_line
			(start -1.249934 -0.729996)
			(end -1.249934 -1.169924)
			(stroke
				(width 0.1)
				(type default)
			)
			(layer "F.Fab")
		)
		(fp_line
			(start -0.6985 -0.729996)
			(end -1.249934 -0.729996)
			(stroke
				(width 0.1)
				(type default)
			)
			(layer "F.Fab")
		)
		(fp_line
			(start -1.249934 -1.169924)
			(end -0.649986 -1.169924)
			(stroke
				(width 0.1)
				(type default)
			)
			(layer "F.Fab")
		)
		(fp_line
			(start -0.649986 -1.169924)
			(end -0.649986 -1.524)
			(stroke
				(width 0.1)
				(type default)
			)
			(layer "F.Fab")
		)
		(fp_line
			(start -0.649986 -1.524)
			(end 0.6985 -1.524)
			(stroke
				(width 0.1)
				(type default)
			)
			(layer "F.Fab")
		)
		(fp_line
			(start 0.6985 -1.524)
			(end 0.6985 -0.219964)
			(stroke
				(width 0.1)
				(type default)
			)
			(layer "F.Fab")
		)
		(pad "1" smd rect
			(at -1.1176 -1.016 180)
			(size 1.016 1.27)
			(layers "F.Cu" "F.Mask" "F.Paste")
			(net "HP_NIC4_PWRGD")
		)
		(pad "2" smd rect
			(at -1.1176 1.016 180)
			(size 1.016 1.27)
			(layers "F.Cu" "F.Mask" "F.Paste")
			(net "P3V3_NIC4")
		)
		(pad "3" smd rect
			(at 1.1176 0 180)
			(size 1.016 1.27)
			(layers "F.Cu" "F.Mask" "F.Paste")
			(net "GND")
		)
	)
	(footprint ""
		(layer "F.Cu")
		(at 247.886728 -112.139476 -90)
		(property "Reference" "PR7099"
			(at 0 0 270)
			(layer "F.SilkS")
			(hide yes)
			(effects
				(font
					(size 1.27 1.27)
				)
			)
		)
		(property "Value" ""
			(at 0 0 270)
			(layer "F.Fab")
			(effects
				(font
					(size 1.27 1.27)
				)
			)
		)
		(duplicate_pad_numbers_are_jumpers no)
		(fp_line
			(start -0.7874 0.4064)
			(end -0.7874 -0.4064)
			(stroke
				(width 0.1524)
				(type default)
			)
			(layer "F.SilkS")
		)
		(fp_line
			(start 0.7874 0.4064)
			(end -0.7874 0.4064)
			(stroke
				(width 0.1524)
				(type default)
			)
			(layer "F.SilkS")
		)
		(fp_line
			(start -0.7874 -0.4064)
			(end 0.7874 -0.4064)
			(stroke
				(width 0.1524)
				(type default)
			)
			(layer "F.SilkS")
		)
		(fp_line
			(start 0.7874 -0.4064)
			(end 0.7874 0.4064)
			(stroke
				(width 0.1524)
				(type default)
			)
			(layer "F.SilkS")
		)
		(fp_line
			(start -0.67945 0.3048)
			(end -0.67945 -0.305054)
			(stroke
				(width 0.1)
				(type default)
			)
			(layer "F.Fab")
		)
		(fp_line
			(start -0.12065 0.3048)
			(end -0.67945 0.3048)
			(stroke
				(width 0.1)
				(type default)
			)
			(layer "F.Fab")
		)
		(fp_line
			(start 0.120396 0.3048)
			(end 0.120396 0.2794)
			(stroke
				(width 0.1)
				(type default)
			)
			(layer "F.Fab")
		)
		(fp_line
			(start 0.67945 0.3048)
			(end 0.120396 0.3048)
			(stroke
				(width 0.1)
				(type default)
			)
			(layer "F.Fab")
		)
		(fp_line
			(start -0.12065 0.2794)
			(end -0.12065 0.3048)
			(stroke
				(width 0.1)
				(type default)
			)
			(layer "F.Fab")
		)
		(fp_line
			(start 0.120396 0.2794)
			(end -0.12065 0.2794)
			(stroke
				(width 0.1)
				(type default)
			)
			(layer "F.Fab")
		)
		(fp_line
			(start -0.12065 -0.2794)
			(end 0.12065 -0.2794)
			(stroke
				(width 0.1)
				(type default)
			)
			(layer "F.Fab")
		)
		(fp_line
			(start 0.12065 -0.2794)
			(end 0.12065 -0.3048)
			(stroke
				(width 0.1)
				(type default)
			)
			(layer "F.Fab")
		)
		(fp_line
			(start 0.12065 -0.3048)
			(end 0.67945 -0.3048)
			(stroke
				(width 0.1)
				(type default)
			)
			(layer "F.Fab")
		)
		(fp_line
			(start 0.67945 -0.3048)
			(end 0.67945 0.3048)
			(stroke
				(width 0.1)
				(type default)
			)
			(layer "F.Fab")
		)
		(fp_line
			(start -0.67945 -0.305054)
			(end -0.12065 -0.305054)
			(stroke
				(width 0.1)
				(type default)
			)
			(layer "F.Fab")
		)
		(fp_line
			(start -0.12065 -0.305054)
			(end -0.12065 -0.2794)
			(stroke
				(width 0.1)
				(type default)
			)
			(layer "F.Fab")
		)
		(pad "1" smd circle
			(at -0.40005 0 270)
			(size 0 0)
			(layers "F.Cu" "F.Mask" "F.Paste")
			(net "P3V3_NIC4_CO_MODE")
		)
		(pad "2" smd circle
			(at 0.40005 0 270)
			(size 0 0)
			(layers "F.Cu" "F.Mask" "F.Paste")
			(net "GND")
		)
	)
	(footprint ""
		(layer "F.Cu")
		(at 216.401396 -105.34904)
		(property "Reference" "C420"
			(at 0 0 0)
			(layer "F.SilkS")
			(hide yes)
			(effects
				(font
					(size 1.27 1.27)
				)
			)
		)
		(property "Value" ""
			(at 0 0 0)
			(layer "F.Fab")
			(effects
				(font
					(size 1.27 1.27)
				)
			)
		)
		(duplicate_pad_numbers_are_jumpers no)
		(fp_line
			(start -0.7874 -0.4064)
			(end 0.7874 -0.4064)
			(stroke
				(width 0.1524)
				(type default)
			)
			(layer "F.SilkS")
		)
		(fp_line
			(start -0.7874 0.4064)
			(end -0.7874 -0.4064)
			(stroke
				(width 0.1524)
				(type default)
			)
			(layer "F.SilkS")
		)
		(fp_line
			(start 0.7874 -0.4064)
			(end 0.7874 0.4064)
			(stroke
				(width 0.1524)
				(type default)
			)
			(layer "F.SilkS")
		)
		(fp_line
			(start 0.7874 0.4064)
			(end -0.7874 0.4064)
			(stroke
				(width 0.1524)
				(type default)
			)
			(layer "F.SilkS")
		)
		(fp_line
			(start -0.67945 -0.305054)
			(end -0.12065 -0.305054)
			(stroke
				(width 0.1)
				(type default)
			)
			(layer "F.Fab")
		)
		(fp_line
			(start -0.67945 0.3048)
			(end -0.67945 -0.305054)
			(stroke
				(width 0.1)
				(type default)
			)
			(layer "F.Fab")
		)
		(fp_line
			(start -0.12065 -0.305054)
			(end -0.12065 -0.2794)
			(stroke
				(width 0.1)
				(type default)
			)
			(layer "F.Fab")
		)
		(fp_line
			(start -0.12065 -0.2794)
			(end 0.12065 -0.2794)
			(stroke
				(width 0.1)
				(type default)
			)
			(layer "F.Fab")
		)
		(fp_line
			(start -0.12065 0.2794)
			(end -0.12065 0.3048)
			(stroke
				(width 0.1)
				(type default)
			)
			(layer "F.Fab")
		)
		(fp_line
			(start -0.12065 0.3048)
			(end -0.67945 0.3048)
			(stroke
				(width 0.1)
				(type default)
			)
			(layer "F.Fab")
		)
		(fp_line
			(start 0.120396 0.2794)
			(end -0.12065 0.2794)
			(stroke
				(width 0.1)
				(type default)
			)
			(layer "F.Fab")
		)
		(fp_line
			(start 0.120396 0.3048)
			(end 0.120396 0.2794)
			(stroke
				(width 0.1)
				(type default)
			)
			(layer "F.Fab")
		)
		(fp_line
			(start 0.12065 -0.3048)
			(end 0.67945 -0.3048)
			(stroke
				(width 0.1)
				(type default)
			)
			(layer "F.Fab")
		)
		(fp_line
			(start 0.12065 -0.2794)
			(end 0.12065 -0.3048)
			(stroke
				(width 0.1)
				(type default)
			)
			(layer "F.Fab")
		)
		(fp_line
			(start 0.67945 -0.3048)
			(end 0.67945 0.3048)
			(stroke
				(width 0.1)
				(type default)
			)
			(layer "F.Fab")
		)
		(fp_line
			(start 0.67945 0.3048)
			(end 0.120396 0.3048)
			(stroke
				(width 0.1)
				(type default)
			)
			(layer "F.Fab")
		)
		(pad "1" smd circle
			(at -0.40005 0)
			(size 0 0)
			(layers "F.Cu" "F.Mask" "F.Paste")
			(net "P12V_NIC3_VIN_P")
		)
		(pad "2" smd circle
			(at 0.40005 0)
			(size 0 0)
			(layers "F.Cu" "F.Mask" "F.Paste")
			(net "P12V_NIC3_VIN_N")
		)
	)
	(footprint ""
		(layer "F.Cu")
		(at 90.021156 -298.87291 -90)
		(property "Reference" "R4014"
			(at 0 0 270)
			(layer "F.SilkS")
			(hide yes)
			(effects
				(font
					(size 1.27 1.27)
				)
			)
		)
		(property "Value" ""
			(at 0 0 270)
			(layer "F.Fab")
			(effects
				(font
					(size 1.27 1.27)
				)
			)
		)
		(duplicate_pad_numbers_are_jumpers no)
		(fp_line
			(start -0.7874 0.4064)
			(end -0.7874 -0.4064)
			(stroke
				(width 0.1524)
				(type default)
			)
			(layer "F.SilkS")
		)
		(fp_line
			(start 0.7874 0.4064)
			(end -0.7874 0.4064)
			(stroke
				(width 0.1524)
				(type default)
			)
			(layer "F.SilkS")
		)
		(fp_line
			(start -0.7874 -0.4064)
			(end 0.7874 -0.4064)
			(stroke
				(width 0.1524)
				(type default)
			)
			(layer "F.SilkS")
		)
		(fp_line
			(start 0.7874 -0.4064)
			(end 0.7874 0.4064)
			(stroke
				(width 0.1524)
				(type default)
			)
			(layer "F.SilkS")
		)
		(fp_line
			(start -0.67945 0.3048)
			(end -0.67945 -0.305054)
			(stroke
				(width 0.1)
				(type default)
			)
			(layer "F.Fab")
		)
		(fp_line
			(start -0.12065 0.3048)
			(end -0.67945 0.3048)
			(stroke
				(width 0.1)
				(type default)
			)
			(layer "F.Fab")
		)
		(fp_line
			(start 0.120396 0.3048)
			(end 0.120396 0.2794)
			(stroke
				(width 0.1)
				(type default)
			)
			(layer "F.Fab")
		)
		(fp_line
			(start 0.67945 0.3048)
			(end 0.120396 0.3048)
			(stroke
				(width 0.1)
				(type default)
			)
			(layer "F.Fab")
		)
		(fp_line
			(start -0.12065 0.2794)
			(end -0.12065 0.3048)
			(stroke
				(width 0.1)
				(type default)
			)
			(layer "F.Fab")
		)
		(fp_line
			(start 0.120396 0.2794)
			(end -0.12065 0.2794)
			(stroke
				(width 0.1)
				(type default)
			)
			(layer "F.Fab")
		)
		(fp_line
			(start -0.12065 -0.2794)
			(end 0.12065 -0.2794)
			(stroke
				(width 0.1)
				(type default)
			)
			(layer "F.Fab")
		)
		(fp_line
			(start 0.12065 -0.2794)
			(end 0.12065 -0.3048)
			(stroke
				(width 0.1)
				(type default)
			)
			(layer "F.Fab")
		)
		(fp_line
			(start 0.12065 -0.3048)
			(end 0.67945 -0.3048)
			(stroke
				(width 0.1)
				(type default)
			)
			(layer "F.Fab")
		)
		(fp_line
			(start 0.67945 -0.3048)
			(end 0.67945 0.3048)
			(stroke
				(width 0.1)
				(type default)
			)
			(layer "F.Fab")
		)
		(fp_line
			(start -0.67945 -0.305054)
			(end -0.12065 -0.305054)
			(stroke
				(width 0.1)
				(type default)
			)
			(layer "F.Fab")
		)
		(fp_line
			(start -0.12065 -0.305054)
			(end -0.12065 -0.2794)
			(stroke
				(width 0.1)
				(type default)
			)
			(layer "F.Fab")
		)
		(pad "1" smd circle
			(at -0.40005 0 270)
			(size 0 0)
			(layers "F.Cu" "F.Mask" "F.Paste")
			(net "P1V8_PEX")
		)
		(pad "2" smd circle
			(at 0.40005 0 270)
			(size 0 0)
			(layers "F.Cu" "F.Mask" "F.Paste")
			(net "I2C_PEX0_HOST_R_SDA")
		)
	)
	(footprint ""
		(layer "F.Cu")
		(at 93.0656 -304.036476 90)
		(property "Reference" "R4180"
			(at 0 0 90)
			(layer "F.SilkS")
			(hide yes)
			(effects
				(font
					(size 1.27 1.27)
				)
			)
		)
		(property "Value" ""
			(at 0 0 90)
			(layer "F.Fab")
			(effects
				(font
					(size 1.27 1.27)
				)
			)
		)
		(duplicate_pad_numbers_are_jumpers no)
		(fp_line
			(start 0.7874 -0.4064)
			(end 0.7874 0.4064)
			(stroke
				(width 0.1524)
				(type default)
			)
			(layer "F.SilkS")
		)
		(fp_line
			(start -0.7874 -0.4064)
			(end 0.7874 -0.4064)
			(stroke
				(width 0.1524)
				(type default)
			)
			(layer "F.SilkS")
		)
		(fp_line
			(start 0.7874 0.4064)
			(end -0.7874 0.4064)
			(stroke
				(width 0.1524)
				(type default)
			)
			(layer "F.SilkS")
		)
		(fp_line
			(start -0.7874 0.4064)
			(end -0.7874 -0.4064)
			(stroke
				(width 0.1524)
				(type default)
			)
			(layer "F.SilkS")
		)
		(fp_line
			(start -0.12065 -0.305054)
			(end -0.12065 -0.2794)
			(stroke
				(width 0.1)
				(type default)
			)
			(layer "F.Fab")
		)
		(fp_line
			(start -0.67945 -0.305054)
			(end -0.12065 -0.305054)
			(stroke
				(width 0.1)
				(type default)
			)
			(layer "F.Fab")
		)
		(fp_line
			(start 0.67945 -0.3048)
			(end 0.67945 0.3048)
			(stroke
				(width 0.1)
				(type default)
			)
			(layer "F.Fab")
		)
		(fp_line
			(start 0.12065 -0.3048)
			(end 0.67945 -0.3048)
			(stroke
				(width 0.1)
				(type default)
			)
			(layer "F.Fab")
		)
		(fp_line
			(start 0.12065 -0.2794)
			(end 0.12065 -0.3048)
			(stroke
				(width 0.1)
				(type default)
			)
			(layer "F.Fab")
		)
		(fp_line
			(start -0.12065 -0.2794)
			(end 0.12065 -0.2794)
			(stroke
				(width 0.1)
				(type default)
			)
			(layer "F.Fab")
		)
		(fp_line
			(start 0.120396 0.2794)
			(end -0.12065 0.2794)
			(stroke
				(width 0.1)
				(type default)
			)
			(layer "F.Fab")
		)
		(fp_line
			(start -0.12065 0.2794)
			(end -0.12065 0.3048)
			(stroke
				(width 0.1)
				(type default)
			)
			(layer "F.Fab")
		)
		(fp_line
			(start 0.67945 0.3048)
			(end 0.120396 0.3048)
			(stroke
				(width 0.1)
				(type default)
			)
			(layer "F.Fab")
		)
		(fp_line
			(start 0.120396 0.3048)
			(end 0.120396 0.2794)
			(stroke
				(width 0.1)
				(type default)
			)
			(layer "F.Fab")
		)
		(fp_line
			(start -0.12065 0.3048)
			(end -0.67945 0.3048)
			(stroke
				(width 0.1)
				(type default)
			)
			(layer "F.Fab")
		)
		(fp_line
			(start -0.67945 0.3048)
			(end -0.67945 -0.305054)
			(stroke
				(width 0.1)
				(type default)
			)
			(layer "F.Fab")
		)
		(pad "1" smd circle
			(at -0.40005 0 90)
			(size 0 0)
			(layers "F.Cu" "F.Mask" "F.Paste")
			(net "GND")
		)
		(pad "2" smd circle
			(at 0.40005 0 90)
			(size 0 0)
			(layers "F.Cu" "F.Mask" "F.Paste")
			(net "PEX0_EXT_GPIO_LATCH_N")
		)
	)
	(footprint ""
		(layer "F.Cu")
		(at 452.864982 -114.833654 -90)
		(property "Reference" "PC832"
			(at 0 0 270)
			(layer "F.SilkS")
			(hide yes)
			(effects
				(font
					(size 1.27 1.27)
				)
			)
		)
		(property "Value" ""
			(at 0 0 270)
			(layer "F.Fab")
			(effects
				(font
					(size 1.27 1.27)
				)
			)
		)
		(duplicate_pad_numbers_are_jumpers no)
		(fp_line
			(start -1.2954 0.5842)
			(end -1.2954 -0.5842)
			(stroke
				(width 0.1524)
				(type default)
			)
			(layer "F.SilkS")
		)
		(fp_line
			(start 1.2954 0.5842)
			(end -1.2954 0.5842)
			(stroke
				(width 0.1524)
				(type default)
			)
			(layer "F.SilkS")
		)
		(fp_line
			(start -1.2954 -0.5842)
			(end 1.2954 -0.5842)
			(stroke
				(width 0.1524)
				(type default)
			)
			(layer "F.SilkS")
		)
		(fp_line
			(start 1.2954 -0.5842)
			(end 1.2954 0.5842)
			(stroke
				(width 0.1524)
				(type default)
			)
			(layer "F.SilkS")
		)
		(fp_line
			(start -0.8636 0.4572)
			(end -0.8636 0.4064)
			(stroke
				(width 0.1)
				(type default)
			)
			(layer "F.Fab")
		)
		(fp_line
			(start 0.8636 0.4572)
			(end -0.8636 0.4572)
			(stroke
				(width 0.1)
				(type default)
			)
			(layer "F.Fab")
		)
		(fp_line
			(start -1.1938 0.4064)
			(end -1.1938 -0.4064)
			(stroke
				(width 0.1)
				(type default)
			)
			(layer "F.Fab")
		)
		(fp_line
			(start -0.8636 0.4064)
			(end -1.1938 0.4064)
			(stroke
				(width 0.1)
				(type default)
			)
			(layer "F.Fab")
		)
		(fp_line
			(start 0.8636 0.4064)
			(end 0.8636 0.4572)
			(stroke
				(width 0.1)
				(type default)
			)
			(layer "F.Fab")
		)
		(fp_line
			(start 1.1938 0.4064)
			(end 0.8636 0.4064)
			(stroke
				(width 0.1)
				(type default)
			)
			(layer "F.Fab")
		)
		(fp_line
			(start -1.1938 -0.4064)
			(end -0.8636 -0.4064)
			(stroke
				(width 0.1)
				(type default)
			)
			(layer "F.Fab")
		)
		(fp_line
			(start -0.8636 -0.4064)
			(end -0.8636 -0.4572)
			(stroke
				(width 0.1)
				(type default)
			)
			(layer "F.Fab")
		)
		(fp_line
			(start 0.8636 -0.4064)
			(end 1.1938 -0.4064)
			(stroke
				(width 0.1)
				(type default)
			)
			(layer "F.Fab")
		)
		(fp_line
			(start 1.1938 -0.4064)
			(end 1.1938 0.4064)
			(stroke
				(width 0.1)
				(type default)
			)
			(layer "F.Fab")
		)
		(fp_line
			(start -0.8636 -0.4572)
			(end 0.8636 -0.4572)
			(stroke
				(width 0.1)
				(type default)
			)
			(layer "F.Fab")
		)
		(fp_line
			(start 0.8636 -0.4572)
			(end 0.8636 -0.4064)
			(stroke
				(width 0.1)
				(type default)
			)
			(layer "F.Fab")
		)
		(pad "1" smd rect
			(at -0.7366 0 180)
			(size 0.7112 0.8128)
			(layers "F.Cu" "F.Mask" "F.Paste")
			(net "GND")
		)
		(pad "2" smd rect
			(at 0.7366 0 180)
			(size 0.7112 0.8128)
			(layers "F.Cu" "F.Mask" "F.Paste")
			(net "P12V_NIC7_CO_AVIN_PD")
		)
	)
	(footprint ""
		(layer "F.Cu")
		(at 91.055444 -96.811592 -90)
		(property "Reference" "R695"
			(at 0 0 270)
			(layer "F.SilkS")
			(hide yes)
			(effects
				(font
					(size 1.27 1.27)
				)
			)
		)
		(property "Value" ""
			(at 0 0 270)
			(layer "F.Fab")
			(effects
				(font
					(size 1.27 1.27)
				)
			)
		)
		(duplicate_pad_numbers_are_jumpers no)
		(fp_line
			(start -0.7874 0.4064)
			(end -0.7874 -0.4064)
			(stroke
				(width 0.1524)
				(type default)
			)
			(layer "F.SilkS")
		)
		(fp_line
			(start 0.7874 0.4064)
			(end -0.7874 0.4064)
			(stroke
				(width 0.1524)
				(type default)
			)
			(layer "F.SilkS")
		)
		(fp_line
			(start -0.7874 -0.4064)
			(end 0.7874 -0.4064)
			(stroke
				(width 0.1524)
				(type default)
			)
			(layer "F.SilkS")
		)
		(fp_line
			(start 0.7874 -0.4064)
			(end 0.7874 0.4064)
			(stroke
				(width 0.1524)
				(type default)
			)
			(layer "F.SilkS")
		)
		(fp_line
			(start -0.67945 0.3048)
			(end -0.67945 -0.305054)
			(stroke
				(width 0.1)
				(type default)
			)
			(layer "F.Fab")
		)
		(fp_line
			(start -0.12065 0.3048)
			(end -0.67945 0.3048)
			(stroke
				(width 0.1)
				(type default)
			)
			(layer "F.Fab")
		)
		(fp_line
			(start 0.120396 0.3048)
			(end 0.120396 0.2794)
			(stroke
				(width 0.1)
				(type default)
			)
			(layer "F.Fab")
		)
		(fp_line
			(start 0.67945 0.3048)
			(end 0.120396 0.3048)
			(stroke
				(width 0.1)
				(type default)
			)
			(layer "F.Fab")
		)
		(fp_line
			(start -0.12065 0.2794)
			(end -0.12065 0.3048)
			(stroke
				(width 0.1)
				(type default)
			)
			(layer "F.Fab")
		)
		(fp_line
			(start 0.120396 0.2794)
			(end -0.12065 0.2794)
			(stroke
				(width 0.1)
				(type default)
			)
			(layer "F.Fab")
		)
		(fp_line
			(start -0.12065 -0.2794)
			(end 0.12065 -0.2794)
			(stroke
				(width 0.1)
				(type default)
			)
			(layer "F.Fab")
		)
		(fp_line
			(start 0.12065 -0.2794)
			(end 0.12065 -0.3048)
			(stroke
				(width 0.1)
				(type default)
			)
			(layer "F.Fab")
		)
		(fp_line
			(start 0.12065 -0.3048)
			(end 0.67945 -0.3048)
			(stroke
				(width 0.1)
				(type default)
			)
			(layer "F.Fab")
		)
		(fp_line
			(start 0.67945 -0.3048)
			(end 0.67945 0.3048)
			(stroke
				(width 0.1)
				(type default)
			)
			(layer "F.Fab")
		)
		(fp_line
			(start -0.67945 -0.305054)
			(end -0.12065 -0.305054)
			(stroke
				(width 0.1)
				(type default)
			)
			(layer "F.Fab")
		)
		(fp_line
			(start -0.12065 -0.305054)
			(end -0.12065 -0.2794)
			(stroke
				(width 0.1)
				(type default)
			)
			(layer "F.Fab")
		)
		(pad "1" smd circle
			(at -0.40005 0 270)
			(size 0 0)
			(layers "F.Cu" "F.Mask" "F.Paste")
			(net "NIC1_ADC_ALERT_N")
		)
		(pad "2" smd circle
			(at 0.40005 0 270)
			(size 0 0)
			(layers "F.Cu" "F.Mask" "F.Paste")
			(net "NIC_ADC_ALERT_N")
		)
	)
	(footprint ""
		(layer "F.Cu")
		(at 361.188 -192.278 180)
		(property "Reference" "R4655"
			(at 0 0 180)
			(layer "F.SilkS")
			(hide yes)
			(effects
				(font
					(size 1.27 1.27)
				)
			)
		)
		(property "Value" ""
			(at 0 0 180)
			(layer "F.Fab")
			(effects
				(font
					(size 1.27 1.27)
				)
			)
		)
		(duplicate_pad_numbers_are_jumpers no)
		(fp_line
			(start 0.7874 0.4064)
			(end -0.7874 0.4064)
			(stroke
				(width 0.1524)
				(type default)
			)
			(layer "F.SilkS")
		)
		(fp_line
			(start 0.7874 -0.4064)
			(end 0.7874 0.4064)
			(stroke
				(width 0.1524)
				(type default)
			)
			(layer "F.SilkS")
		)
		(fp_line
			(start -0.7874 0.4064)
			(end -0.7874 -0.4064)
			(stroke
				(width 0.1524)
				(type default)
			)
			(layer "F.SilkS")
		)
		(fp_line
			(start -0.7874 -0.4064)
			(end 0.7874 -0.4064)
			(stroke
				(width 0.1524)
				(type default)
			)
			(layer "F.SilkS")
		)
		(fp_line
			(start 0.67945 0.3048)
			(end 0.120396 0.3048)
			(stroke
				(width 0.1)
				(type default)
			)
			(layer "F.Fab")
		)
		(fp_line
			(start 0.67945 -0.3048)
			(end 0.67945 0.3048)
			(stroke
				(width 0.1)
				(type default)
			)
			(layer "F.Fab")
		)
		(fp_line
			(start 0.12065 -0.2794)
			(end 0.12065 -0.3048)
			(stroke
				(width 0.1)
				(type default)
			)
			(layer "F.Fab")
		)
		(fp_line
			(start 0.12065 -0.3048)
			(end 0.67945 -0.3048)
			(stroke
				(width 0.1)
				(type default)
			)
			(layer "F.Fab")
		)
		(fp_line
			(start 0.120396 0.3048)
			(end 0.120396 0.2794)
			(stroke
				(width 0.1)
				(type default)
			)
			(layer "F.Fab")
		)
		(fp_line
			(start 0.120396 0.2794)
			(end -0.12065 0.2794)
			(stroke
				(width 0.1)
				(type default)
			)
			(layer "F.Fab")
		)
		(fp_line
			(start -0.12065 0.3048)
			(end -0.67945 0.3048)
			(stroke
				(width 0.1)
				(type default)
			)
			(layer "F.Fab")
		)
		(fp_line
			(start -0.12065 0.2794)
			(end -0.12065 0.3048)
			(stroke
				(width 0.1)
				(type default)
			)
			(layer "F.Fab")
		)
		(fp_line
			(start -0.12065 -0.2794)
			(end 0.12065 -0.2794)
			(stroke
				(width 0.1)
				(type default)
			)
			(layer "F.Fab")
		)
		(fp_line
			(start -0.12065 -0.305054)
			(end -0.12065 -0.2794)
			(stroke
				(width 0.1)
				(type default)
			)
			(layer "F.Fab")
		)
		(fp_line
			(start -0.67945 0.3048)
			(end -0.67945 -0.305054)
			(stroke
				(width 0.1)
				(type default)
			)
			(layer "F.Fab")
		)
		(fp_line
			(start -0.67945 -0.305054)
			(end -0.12065 -0.305054)
			(stroke
				(width 0.1)
				(type default)
			)
			(layer "F.Fab")
		)
		(pad "1" smd circle
			(at -0.40005 0 180)
			(size 0 0)
			(layers "F.Cu" "F.Mask" "F.Paste")
			(net "GND")
		)
		(pad "2" smd circle
			(at 0.40005 0 180)
			(size 0 0)
			(layers "F.Cu" "F.Mask" "F.Paste")
			(net "PCA9555_1_PEX0_A1")
		)
	)
	(footprint ""
		(layer "F.Cu")
		(at 310.783986 -29.222954 -90)
		(property "Reference" "PC959"
			(at 0 0 270)
			(layer "F.SilkS")
			(hide yes)
			(effects
				(font
					(size 1.27 1.27)
				)
			)
		)
		(property "Value" ""
			(at 0 0 270)
			(layer "F.Fab")
			(effects
				(font
					(size 1.27 1.27)
				)
			)
		)
		(duplicate_pad_numbers_are_jumpers no)
		(fp_line
			(start -0.7874 0.4064)
			(end -0.7874 -0.4064)
			(stroke
				(width 0.1524)
				(type default)
			)
			(layer "F.SilkS")
		)
		(fp_line
			(start 0.7874 0.4064)
			(end -0.7874 0.4064)
			(stroke
				(width 0.1524)
				(type default)
			)
			(layer "F.SilkS")
		)
		(fp_line
			(start -0.7874 -0.4064)
			(end 0.7874 -0.4064)
			(stroke
				(width 0.1524)
				(type default)
			)
			(layer "F.SilkS")
		)
		(fp_line
			(start 0.7874 -0.4064)
			(end 0.7874 0.4064)
			(stroke
				(width 0.1524)
				(type default)
			)
			(layer "F.SilkS")
		)
		(fp_line
			(start -0.67945 0.3048)
			(end -0.67945 -0.305054)
			(stroke
				(width 0.1)
				(type default)
			)
			(layer "F.Fab")
		)
		(fp_line
			(start -0.12065 0.3048)
			(end -0.67945 0.3048)
			(stroke
				(width 0.1)
				(type default)
			)
			(layer "F.Fab")
		)
		(fp_line
			(start 0.120396 0.3048)
			(end 0.120396 0.2794)
			(stroke
				(width 0.1)
				(type default)
			)
			(layer "F.Fab")
		)
		(fp_line
			(start 0.67945 0.3048)
			(end 0.120396 0.3048)
			(stroke
				(width 0.1)
				(type default)
			)
			(layer "F.Fab")
		)
		(fp_line
			(start -0.12065 0.2794)
			(end -0.12065 0.3048)
			(stroke
				(width 0.1)
				(type default)
			)
			(layer "F.Fab")
		)
		(fp_line
			(start 0.120396 0.2794)
			(end -0.12065 0.2794)
			(stroke
				(width 0.1)
				(type default)
			)
			(layer "F.Fab")
		)
		(fp_line
			(start -0.12065 -0.2794)
			(end 0.12065 -0.2794)
			(stroke
				(width 0.1)
				(type default)
			)
			(layer "F.Fab")
		)
		(fp_line
			(start 0.12065 -0.2794)
			(end 0.12065 -0.3048)
			(stroke
				(width 0.1)
				(type default)
			)
			(layer "F.Fab")
		)
		(fp_line
			(start 0.12065 -0.3048)
			(end 0.67945 -0.3048)
			(stroke
				(width 0.1)
				(type default)
			)
			(layer "F.Fab")
		)
		(fp_line
			(start 0.67945 -0.3048)
			(end 0.67945 0.3048)
			(stroke
				(width 0.1)
				(type default)
			)
			(layer "F.Fab")
		)
		(fp_line
			(start -0.67945 -0.305054)
			(end -0.12065 -0.305054)
			(stroke
				(width 0.1)
				(type default)
			)
			(layer "F.Fab")
		)
		(fp_line
			(start -0.12065 -0.305054)
			(end -0.12065 -0.2794)
			(stroke
				(width 0.1)
				(type default)
			)
			(layer "F.Fab")
		)
		(pad "1" smd circle
			(at -0.40005 0 270)
			(size 0 0)
			(layers "F.Cu" "F.Mask" "F.Paste")
			(net "P3V3_AUX")
		)
		(pad "2" smd circle
			(at 0.40005 0 270)
			(size 0 0)
			(layers "F.Cu" "F.Mask" "F.Paste")
			(net "GND")
		)
	)
	(footprint ""
		(layer "F.Cu")
		(at 28.04922 -280.994612 -90)
		(property "Reference" "C3036"
			(at 0 0 270)
			(layer "F.SilkS")
			(hide yes)
			(effects
				(font
					(size 1.27 1.27)
				)
			)
		)
		(property "Value" ""
			(at 0 0 270)
			(layer "F.Fab")
			(effects
				(font
					(size 1.27 1.27)
				)
			)
		)
		(duplicate_pad_numbers_are_jumpers no)
		(fp_line
			(start -0.299974 0.150114)
			(end -0.299974 -0.150114)
			(stroke
				(width 0.1)
				(type default)
			)
			(layer "F.Fab")
		)
		(fp_line
			(start 0.299974 0.150114)
			(end -0.299974 0.150114)
			(stroke
				(width 0.1)
				(type default)
			)
			(layer "F.Fab")
		)
		(fp_line
			(start -0.299974 -0.150114)
			(end 0.299974 -0.150114)
			(stroke
				(width 0.1)
				(type default)
			)
			(layer "F.Fab")
		)
		(fp_line
			(start 0.299974 -0.150114)
			(end 0.299974 0.150114)
			(stroke
				(width 0.1)
				(type default)
			)
			(layer "F.Fab")
		)
		(pad "1" smd rect
			(at -0.2667 0 270)
			(size 0.3048 0.381)
			(layers "F.Cu" "F.Mask" "F.Paste")
			(net "P1V8_PLL0_PEX0")
		)
		(pad "2" smd rect
			(at 0.2667 0 270)
			(size 0.3048 0.381)
			(layers "F.Cu" "F.Mask" "F.Paste")
			(net "GND")
		)
	)
	(footprint ""
		(layer "F.Cu")
		(at 233.1974 -231.394 90)
		(property "Reference" "R4523"
			(at 0 0 90)
			(layer "F.SilkS")
			(hide yes)
			(effects
				(font
					(size 1.27 1.27)
				)
			)
		)
		(property "Value" ""
			(at 0 0 90)
			(layer "F.Fab")
			(effects
				(font
					(size 1.27 1.27)
				)
			)
		)
		(duplicate_pad_numbers_are_jumpers no)
		(fp_line
			(start 0.7874 -0.4064)
			(end 0.7874 0.4064)
			(stroke
				(width 0.1524)
				(type default)
			)
			(layer "F.SilkS")
		)
		(fp_line
			(start -0.7874 -0.4064)
			(end 0.7874 -0.4064)
			(stroke
				(width 0.1524)
				(type default)
			)
			(layer "F.SilkS")
		)
		(fp_line
			(start 0.7874 0.4064)
			(end -0.7874 0.4064)
			(stroke
				(width 0.1524)
				(type default)
			)
			(layer "F.SilkS")
		)
		(fp_line
			(start -0.7874 0.4064)
			(end -0.7874 -0.4064)
			(stroke
				(width 0.1524)
				(type default)
			)
			(layer "F.SilkS")
		)
		(fp_line
			(start -0.12065 -0.305054)
			(end -0.12065 -0.2794)
			(stroke
				(width 0.1)
				(type default)
			)
			(layer "F.Fab")
		)
		(fp_line
			(start -0.67945 -0.305054)
			(end -0.12065 -0.305054)
			(stroke
				(width 0.1)
				(type default)
			)
			(layer "F.Fab")
		)
		(fp_line
			(start 0.67945 -0.3048)
			(end 0.67945 0.3048)
			(stroke
				(width 0.1)
				(type default)
			)
			(layer "F.Fab")
		)
		(fp_line
			(start 0.12065 -0.3048)
			(end 0.67945 -0.3048)
			(stroke
				(width 0.1)
				(type default)
			)
			(layer "F.Fab")
		)
		(fp_line
			(start 0.12065 -0.2794)
			(end 0.12065 -0.3048)
			(stroke
				(width 0.1)
				(type default)
			)
			(layer "F.Fab")
		)
		(fp_line
			(start -0.12065 -0.2794)
			(end 0.12065 -0.2794)
			(stroke
				(width 0.1)
				(type default)
			)
			(layer "F.Fab")
		)
		(fp_line
			(start 0.120396 0.2794)
			(end -0.12065 0.2794)
			(stroke
				(width 0.1)
				(type default)
			)
			(layer "F.Fab")
		)
		(fp_line
			(start -0.12065 0.2794)
			(end -0.12065 0.3048)
			(stroke
				(width 0.1)
				(type default)
			)
			(layer "F.Fab")
		)
		(fp_line
			(start 0.67945 0.3048)
			(end 0.120396 0.3048)
			(stroke
				(width 0.1)
				(type default)
			)
			(layer "F.Fab")
		)
		(fp_line
			(start 0.120396 0.3048)
			(end 0.120396 0.2794)
			(stroke
				(width 0.1)
				(type default)
			)
			(layer "F.Fab")
		)
		(fp_line
			(start -0.12065 0.3048)
			(end -0.67945 0.3048)
			(stroke
				(width 0.1)
				(type default)
			)
			(layer "F.Fab")
		)
		(fp_line
			(start -0.67945 0.3048)
			(end -0.67945 -0.305054)
			(stroke
				(width 0.1)
				(type default)
			)
			(layer "F.Fab")
		)
		(pad "1" smd circle
			(at -0.40005 0 90)
			(size 0 0)
			(layers "F.Cu" "F.Mask" "F.Paste")
			(net "SSD9_PWRDIS_BIC")
		)
		(pad "2" smd circle
			(at 0.40005 0 90)
			(size 0 0)
			(layers "F.Cu" "F.Mask" "F.Paste")
			(net "SSD9_PWRDIS_BIC_R")
		)
	)
	(footprint ""
		(layer "F.Cu")
		(at 137.35558 -152.71115 90)
		(property "Reference" "R707"
			(at 0 0 90)
			(layer "F.SilkS")
			(hide yes)
			(effects
				(font
					(size 1.27 1.27)
				)
			)
		)
		(property "Value" ""
			(at 0 0 90)
			(layer "F.Fab")
			(effects
				(font
					(size 1.27 1.27)
				)
			)
		)
		(duplicate_pad_numbers_are_jumpers no)
		(fp_line
			(start 0.7874 -0.4064)
			(end 0.7874 0.4064)
			(stroke
				(width 0.1524)
				(type default)
			)
			(layer "F.SilkS")
		)
		(fp_line
			(start -0.7874 -0.4064)
			(end 0.7874 -0.4064)
			(stroke
				(width 0.1524)
				(type default)
			)
			(layer "F.SilkS")
		)
		(fp_line
			(start 0.7874 0.4064)
			(end -0.7874 0.4064)
			(stroke
				(width 0.1524)
				(type default)
			)
			(layer "F.SilkS")
		)
		(fp_line
			(start -0.7874 0.4064)
			(end -0.7874 -0.4064)
			(stroke
				(width 0.1524)
				(type default)
			)
			(layer "F.SilkS")
		)
		(fp_line
			(start -0.12065 -0.305054)
			(end -0.12065 -0.2794)
			(stroke
				(width 0.1)
				(type default)
			)
			(layer "F.Fab")
		)
		(fp_line
			(start -0.67945 -0.305054)
			(end -0.12065 -0.305054)
			(stroke
				(width 0.1)
				(type default)
			)
			(layer "F.Fab")
		)
		(fp_line
			(start 0.67945 -0.3048)
			(end 0.67945 0.3048)
			(stroke
				(width 0.1)
				(type default)
			)
			(layer "F.Fab")
		)
		(fp_line
			(start 0.12065 -0.3048)
			(end 0.67945 -0.3048)
			(stroke
				(width 0.1)
				(type default)
			)
			(layer "F.Fab")
		)
		(fp_line
			(start 0.12065 -0.2794)
			(end 0.12065 -0.3048)
			(stroke
				(width 0.1)
				(type default)
			)
			(layer "F.Fab")
		)
		(fp_line
			(start -0.12065 -0.2794)
			(end 0.12065 -0.2794)
			(stroke
				(width 0.1)
				(type default)
			)
			(layer "F.Fab")
		)
		(fp_line
			(start 0.120396 0.2794)
			(end -0.12065 0.2794)
			(stroke
				(width 0.1)
				(type default)
			)
			(layer "F.Fab")
		)
		(fp_line
			(start -0.12065 0.2794)
			(end -0.12065 0.3048)
			(stroke
				(width 0.1)
				(type default)
			)
			(layer "F.Fab")
		)
		(fp_line
			(start 0.67945 0.3048)
			(end 0.120396 0.3048)
			(stroke
				(width 0.1)
				(type default)
			)
			(layer "F.Fab")
		)
		(fp_line
			(start 0.120396 0.3048)
			(end 0.120396 0.2794)
			(stroke
				(width 0.1)
				(type default)
			)
			(layer "F.Fab")
		)
		(fp_line
			(start -0.12065 0.3048)
			(end -0.67945 0.3048)
			(stroke
				(width 0.1)
				(type default)
			)
			(layer "F.Fab")
		)
		(fp_line
			(start -0.67945 0.3048)
			(end -0.67945 -0.305054)
			(stroke
				(width 0.1)
				(type default)
			)
			(layer "F.Fab")
		)
		(pad "1" smd circle
			(at -0.40005 0 90)
			(size 0 0)
			(layers "F.Cu" "F.Mask" "F.Paste")
			(net "NIC2_ADC_A1")
		)
		(pad "2" smd circle
			(at 0.40005 0 90)
			(size 0 0)
			(layers "F.Cu" "F.Mask" "F.Paste")
			(net "GND")
		)
	)
	(footprint ""
		(layer "F.Cu")
		(at 224.718118 -319.392554 180)
		(property "Reference" "PC223"
			(at 0 0 180)
			(layer "F.SilkS")
			(hide yes)
			(effects
				(font
					(size 1.27 1.27)
				)
			)
		)
		(property "Value" ""
			(at 0 0 180)
			(layer "F.Fab")
			(effects
				(font
					(size 1.27 1.27)
				)
			)
		)
		(duplicate_pad_numbers_are_jumpers no)
		(fp_line
			(start 0.7874 0.4064)
			(end -0.7874 0.4064)
			(stroke
				(width 0.1524)
				(type default)
			)
			(layer "F.SilkS")
		)
		(fp_line
			(start 0.7874 -0.4064)
			(end 0.7874 0.4064)
			(stroke
				(width 0.1524)
				(type default)
			)
			(layer "F.SilkS")
		)
		(fp_line
			(start -0.7874 0.4064)
			(end -0.7874 -0.4064)
			(stroke
				(width 0.1524)
				(type default)
			)
			(layer "F.SilkS")
		)
		(fp_line
			(start -0.7874 -0.4064)
			(end 0.7874 -0.4064)
			(stroke
				(width 0.1524)
				(type default)
			)
			(layer "F.SilkS")
		)
		(fp_line
			(start 0.67945 0.3048)
			(end 0.120396 0.3048)
			(stroke
				(width 0.1)
				(type default)
			)
			(layer "F.Fab")
		)
		(fp_line
			(start 0.67945 -0.3048)
			(end 0.67945 0.3048)
			(stroke
				(width 0.1)
				(type default)
			)
			(layer "F.Fab")
		)
		(fp_line
			(start 0.12065 -0.2794)
			(end 0.12065 -0.3048)
			(stroke
				(width 0.1)
				(type default)
			)
			(layer "F.Fab")
		)
		(fp_line
			(start 0.12065 -0.3048)
			(end 0.67945 -0.3048)
			(stroke
				(width 0.1)
				(type default)
			)
			(layer "F.Fab")
		)
		(fp_line
			(start 0.120396 0.3048)
			(end 0.120396 0.2794)
			(stroke
				(width 0.1)
				(type default)
			)
			(layer "F.Fab")
		)
		(fp_line
			(start 0.120396 0.2794)
			(end -0.12065 0.2794)
			(stroke
				(width 0.1)
				(type default)
			)
			(layer "F.Fab")
		)
		(fp_line
			(start -0.12065 0.3048)
			(end -0.67945 0.3048)
			(stroke
				(width 0.1)
				(type default)
			)
			(layer "F.Fab")
		)
		(fp_line
			(start -0.12065 0.2794)
			(end -0.12065 0.3048)
			(stroke
				(width 0.1)
				(type default)
			)
			(layer "F.Fab")
		)
		(fp_line
			(start -0.12065 -0.2794)
			(end 0.12065 -0.2794)
			(stroke
				(width 0.1)
				(type default)
			)
			(layer "F.Fab")
		)
		(fp_line
			(start -0.12065 -0.305054)
			(end -0.12065 -0.2794)
			(stroke
				(width 0.1)
				(type default)
			)
			(layer "F.Fab")
		)
		(fp_line
			(start -0.67945 0.3048)
			(end -0.67945 -0.305054)
			(stroke
				(width 0.1)
				(type default)
			)
			(layer "F.Fab")
		)
		(fp_line
			(start -0.67945 -0.305054)
			(end -0.12065 -0.305054)
			(stroke
				(width 0.1)
				(type default)
			)
			(layer "F.Fab")
		)
		(pad "1" smd circle
			(at -0.40005 0 180)
			(size 0 0)
			(layers "F.Cu" "F.Mask" "F.Paste")
			(net "P12V_AUX")
		)
		(pad "2" smd circle
			(at 0.40005 0 180)
			(size 0 0)
			(layers "F.Cu" "F.Mask" "F.Paste")
			(net "GND")
		)
	)
	(footprint ""
		(layer "F.Cu")
		(at 407.949908 -295.89984)
		(property "Reference" "PEX3"
			(at -3.358642 35.5727 0)
			(unlocked yes)
			(layer "F.SilkS")
			(effects
				(font
					(size 2.032 1.524)
					(thickness 0.1524)
				)
				(justify left)
			)
		)
		(property "Value" ""
			(at 0 0 0)
			(layer "F.Fab")
			(effects
				(font
					(size 1.27 1.27)
				)
			)
		)
		(duplicate_pad_numbers_are_jumpers no)
		(fp_line
			(start -23.750016 -23.750016)
			(end -23.750016 23.750016)
			(stroke
				(width 0.1524)
				(type default)
			)
			(layer "F.SilkS")
		)
		(fp_line
			(start -23.750016 23.750016)
			(end 23.750016 23.750016)
			(stroke
				(width 0.1524)
				(type default)
			)
			(layer "F.SilkS")
		)
		(fp_line
			(start 23.750016 -23.750016)
			(end -23.750016 -23.750016)
			(stroke
				(width 0.1524)
				(type default)
			)
			(layer "F.SilkS")
		)
		(fp_line
			(start 23.750016 23.750016)
			(end 23.750016 -23.750016)
			(stroke
				(width 0.1524)
				(type default)
			)
			(layer "F.SilkS")
		)
		(fp_poly
			(pts
				(xy -21.850096 -23.750016) (xy -21.850096 -24.512016) (xy -24.512016 -24.512016) (xy -24.512016 -21.850096)
				(xy -23.750016 -21.850096) (xy -23.750016 -23.750016)
			)
			(stroke
				(width 0)
				(type default)
			)
			(fill yes)
			(layer "F.SilkS")
		)
		(fp_line
			(start -23.750016 -23.750016)
			(end -23.750016 23.750016)
			(stroke
				(width 0.1)
				(type default)
			)
			(layer "F.Fab")
		)
		(fp_line
			(start -23.750016 23.750016)
			(end 23.750016 23.750016)
			(stroke
				(width 0.1)
				(type default)
			)
			(layer "F.Fab")
		)
		(fp_line
			(start 23.750016 -23.750016)
			(end -23.750016 -23.750016)
			(stroke
				(width 0.1)
				(type default)
			)
			(layer "F.Fab")
		)
		(fp_line
			(start 23.750016 23.750016)
			(end 23.750016 -23.750016)
			(stroke
				(width 0.1)
				(type default)
			)
			(layer "F.Fab")
		)
		(fp_poly
			(pts
				(xy -21.850096 -23.750016) (xy -21.850096 -24.512016) (xy -24.512016 -24.512016) (xy -24.512016 -21.850096)
				(xy -23.750016 -21.850096) (xy -23.750016 -23.750016)
			)
			(stroke
				(width 0)
				(type default)
			)
			(fill yes)
			(layer "F.Fab")
		)
		(pad "A2" smd circle
			(at -21.850096 -22.800056)
			(size 0.4572 0.4572)
			(layers "F.Cu" "F.Mask" "F.Paste")
			(net "GND")
		)
		(pad "A3" smd circle
			(at -20.899882 -22.800056)
			(size 0.4572 0.4572)
			(layers "F.Cu" "F.Mask" "F.Paste")
			(net "P5E_PEX3_STN7_RX_DN<123>")
		)
		(pad "A4" smd circle
			(at -19.949922 -22.800056)
			(size 0.4572 0.4572)
			(layers "F.Cu" "F.Mask" "F.Paste")
			(net "GND")
		)
		(pad "A5" smd circle
			(at -18.999962 -22.800056)
			(size 0.4572 0.4572)
			(layers "F.Cu" "F.Mask" "F.Paste")
			(net "P5E_PEX3_STN7_RX_DN<125>")
		)
		(pad "A6" smd circle
			(at -18.050002 -22.800056)
			(size 0.4572 0.4572)
			(layers "F.Cu" "F.Mask" "F.Paste")
			(net "GND")
		)
		(pad "A7" smd circle
			(at -17.100042 -22.800056)
			(size 0.4572 0.4572)
			(layers "F.Cu" "F.Mask" "F.Paste")
			(net "P5E_PEX3_STN7_RX_DN<127>")
		)
		(pad "A8" smd circle
			(at -16.150082 -22.800056)
			(size 0.4572 0.4572)
			(layers "F.Cu" "F.Mask" "F.Paste")
			(net "GND")
		)
		(pad "A9" smd circle
			(at -15.200122 -22.800056)
			(size 0.4572 0.4572)
			(layers "F.Cu" "F.Mask" "F.Paste")
			(net "P5E_PEX3_STN6_RX_DN<110>")
		)
		(pad "A10" smd circle
			(at -14.249908 -22.800056)
			(size 0.4572 0.4572)
			(layers "F.Cu" "F.Mask" "F.Paste")
			(net "GND")
		)
		(pad "A11" smd circle
			(at -13.299948 -22.800056)
			(size 0.4572 0.4572)
			(layers "F.Cu" "F.Mask" "F.Paste")
			(net "P5E_PEX3_STN6_RX_DN<108>")
		)
		(pad "A12" smd circle
			(at -12.349988 -22.800056)
			(size 0.4572 0.4572)
			(layers "F.Cu" "F.Mask" "F.Paste")
			(net "GND")
		)
		(pad "A13" smd circle
			(at -11.400028 -22.800056)
			(size 0.4572 0.4572)
			(layers "F.Cu" "F.Mask" "F.Paste")
			(net "P5E_PEX3_STN6_RX_DN<106>")
		)
		(pad "A14" smd circle
			(at -10.450068 -22.800056)
			(size 0.4572 0.4572)
			(layers "F.Cu" "F.Mask" "F.Paste")
			(net "GND")
		)
		(pad "A15" smd circle
			(at -9.500108 -22.800056)
			(size 0.4572 0.4572)
			(layers "F.Cu" "F.Mask" "F.Paste")
			(net "P5E_PEX3_STN6_RX_DN<104>")
		)
		(pad "A16" smd circle
			(at -8.549894 -22.800056)
			(size 0.4572 0.4572)
			(layers "F.Cu" "F.Mask" "F.Paste")
			(net "GND")
		)
		(pad "A17" smd circle
			(at -7.599934 -22.800056)
			(size 0.4572 0.4572)
			(layers "F.Cu" "F.Mask" "F.Paste")
			(net "P5E_PEX3_STN6_RX_DN<102>")
		)
		(pad "A18" smd circle
			(at -6.649974 -22.800056)
			(size 0.4572 0.4572)
			(layers "F.Cu" "F.Mask" "F.Paste")
			(net "GND")
		)
		(pad "A19" smd circle
			(at -5.700014 -22.800056)
			(size 0.4572 0.4572)
			(layers "F.Cu" "F.Mask" "F.Paste")
			(net "P5E_PEX3_STN6_RX_DN<100>")
		)
		(pad "A20" smd circle
			(at -4.750054 -22.800056)
			(size 0.4572 0.4572)
			(layers "F.Cu" "F.Mask" "F.Paste")
			(net "GND")
		)
		(pad "A21" smd circle
			(at -3.800094 -22.800056)
			(size 0.4572 0.4572)
			(layers "F.Cu" "F.Mask" "F.Paste")
			(net "P5E_PEX3_STN6_RX_DN<98>")
		)
		(pad "A22" smd circle
			(at -2.84988 -22.800056)
			(size 0.4572 0.4572)
			(layers "F.Cu" "F.Mask" "F.Paste")
			(net "GND")
		)
		(pad "A23" smd circle
			(at -1.89992 -22.800056)
			(size 0.4572 0.4572)
			(layers "F.Cu" "F.Mask" "F.Paste")
			(net "P5E_PEX3_STN6_RX_DN<96>")
		)
		(pad "A24" smd circle
			(at -0.94996 -22.800056)
			(size 0.4572 0.4572)
			(layers "F.Cu" "F.Mask" "F.Paste")
			(net "GND")
		)
		(pad "A25" smd circle
			(at 0 -22.800056)
			(size 0.4572 0.4572)
			(layers "F.Cu" "F.Mask" "F.Paste")
			(net "P5E_PEX3_STN5_RX_DN<81>")
		)
		(pad "A26" smd circle
			(at 0.94996 -22.800056)
			(size 0.4572 0.4572)
			(layers "F.Cu" "F.Mask" "F.Paste")
			(net "GND")
		)
		(pad "A27" smd circle
			(at 1.89992 -22.800056)
			(size 0.4572 0.4572)
			(layers "F.Cu" "F.Mask" "F.Paste")
			(net "P5E_PEX3_STN5_RX_DN<83>")
		)
		(pad "A28" smd circle
			(at 2.84988 -22.800056)
			(size 0.4572 0.4572)
			(layers "F.Cu" "F.Mask" "F.Paste")
			(net "GND")
		)
		(pad "A29" smd circle
			(at 3.800094 -22.800056)
			(size 0.4572 0.4572)
			(layers "F.Cu" "F.Mask" "F.Paste")
			(net "P5E_PEX3_STN5_RX_DN<85>")
		)
		(pad "A30" smd circle
			(at 4.750054 -22.800056)
			(size 0.4572 0.4572)
			(layers "F.Cu" "F.Mask" "F.Paste")
			(net "GND")
		)
		(pad "A31" smd circle
			(at 5.700014 -22.800056)
			(size 0.4572 0.4572)
			(layers "F.Cu" "F.Mask" "F.Paste")
			(net "P5E_PEX3_STN5_RX_DN<87>")
		)
		(pad "A32" smd circle
			(at 6.649974 -22.800056)
			(size 0.4572 0.4572)
			(layers "F.Cu" "F.Mask" "F.Paste")
			(net "GND")
		)
		(pad "A33" smd circle
			(at 7.599934 -22.800056)
			(size 0.4572 0.4572)
			(layers "F.Cu" "F.Mask" "F.Paste")
			(net "P5E_PEX3_STN5_RX_DN<89>")
		)
		(pad "A34" smd circle
			(at 8.549894 -22.800056)
			(size 0.4572 0.4572)
			(layers "F.Cu" "F.Mask" "F.Paste")
			(net "GND")
		)
		(pad "A35" smd circle
			(at 9.500108 -22.800056)
			(size 0.4572 0.4572)
			(layers "F.Cu" "F.Mask" "F.Paste")
			(net "P5E_PEX3_STN5_RX_DN<91>")
		)
		(pad "A36" smd circle
			(at 10.450068 -22.800056)
			(size 0.4572 0.4572)
			(layers "F.Cu" "F.Mask" "F.Paste")
			(net "GND")
		)
		(pad "A37" smd circle
			(at 11.400028 -22.800056)
			(size 0.4572 0.4572)
			(layers "F.Cu" "F.Mask" "F.Paste")
			(net "P5E_PEX3_STN5_RX_DN<93>")
		)
		(pad "A38" smd circle
			(at 12.349988 -22.800056)
			(size 0.4572 0.4572)
			(layers "F.Cu" "F.Mask" "F.Paste")
			(net "GND")
		)
		(pad "A39" smd circle
			(at 13.299948 -22.800056)
			(size 0.4572 0.4572)
			(layers "F.Cu" "F.Mask" "F.Paste")
			(net "P5E_PEX3_STN5_RX_DN<95>")
		)
		(pad "A40" smd circle
			(at 14.249908 -22.800056)
			(size 0.4572 0.4572)
			(layers "F.Cu" "F.Mask" "F.Paste")
			(net "GND")
		)
		(pad "A41" smd circle
			(at 15.200122 -22.800056)
			(size 0.4572 0.4572)
			(layers "F.Cu" "F.Mask" "F.Paste")
			(net "P5E_PEX3_STN4_RX_DN<78>")
		)
		(pad "A42" smd circle
			(at 16.150082 -22.800056)
			(size 0.4572 0.4572)
			(layers "F.Cu" "F.Mask" "F.Paste")
			(net "GND")
		)
		(pad "A43" smd circle
			(at 17.100042 -22.800056)
			(size 0.4572 0.4572)
			(layers "F.Cu" "F.Mask" "F.Paste")
			(net "P5E_PEX3_STN4_RX_DN<76>")
		)
		(pad "A44" smd circle
			(at 18.050002 -22.800056)
			(size 0.4572 0.4572)
			(layers "F.Cu" "F.Mask" "F.Paste")
			(net "GND")
		)
		(pad "A45" smd circle
			(at 18.999962 -22.800056)
			(size 0.4572 0.4572)
			(layers "F.Cu" "F.Mask" "F.Paste")
			(net "P5E_PEX3_STN4_RX_DN<74>")
		)
		(pad "A46" smd circle
			(at 19.949922 -22.800056)
			(size 0.4572 0.4572)
			(layers "F.Cu" "F.Mask" "F.Paste")
			(net "GND")
		)
		(pad "A47" smd circle
			(at 20.899882 -22.800056)
			(size 0.4572 0.4572)
			(layers "F.Cu" "F.Mask" "F.Paste")
			(net "P5E_PEX3_STN4_RX_DN<72>")
		)
		(pad "A48" smd circle
			(at 21.850096 -22.800056)
			(size 0.4572 0.4572)
			(layers "F.Cu" "F.Mask" "F.Paste")
			(net "GND")
		)
		(pad "AA1" smd circle
			(at -22.800056 -3.800094)
			(size 0.4572 0.4572)
			(layers "F.Cu" "F.Mask" "F.Paste")
			(net "CLK_100M_PEX3_REF_R_DN")
		)
		(pad "AA2" smd circle
			(at -21.850096 -3.800094)
			(size 0.4572 0.4572)
			(layers "F.Cu" "F.Mask" "F.Paste")
			(net "CLK_100M_PEX3_REF_R_DP")
		)
		(pad "AA3" smd circle
			(at -20.899882 -3.800094)
			(size 0.4572 0.4572)
			(layers "F.Cu" "F.Mask" "F.Paste")
			(net "GND")
		)
		(pad "AA4" smd circle
			(at -19.949922 -3.800094)
			(size 0.4572 0.4572)
			(layers "F.Cu" "F.Mask" "F.Paste")
			(net "GND")
		)
		(pad "AA5" smd circle
			(at -18.999962 -3.800094)
			(size 0.4572 0.4572)
			(layers "F.Cu" "F.Mask" "F.Paste")
			(net "GND")
		)
		(pad "AA6" smd circle
			(at -18.050002 -3.800094)
			(size 0.4572 0.4572)
			(layers "F.Cu" "F.Mask" "F.Paste")
			(net "GND")
		)
		(pad "AA7" smd circle
			(at -17.100042 -3.800094)
			(size 0.4572 0.4572)
			(layers "F.Cu" "F.Mask" "F.Paste")
			(net "GND")
		)
		(pad "AA8" smd circle
			(at -16.150082 -3.800094)
			(size 0.4572 0.4572)
			(layers "F.Cu" "F.Mask" "F.Paste")
			(net "GND")
		)
		(pad "AA9" smd circle
			(at -15.200122 -3.800094)
			(size 0.4572 0.4572)
			(layers "F.Cu" "F.Mask" "F.Paste")
			(net "GND")
		)
		(pad "AA10" smd circle
			(at -14.249908 -3.800094)
			(size 0.4572 0.4572)
			(layers "F.Cu" "F.Mask" "F.Paste")
			(net "P1V8_VDDA_PEX3")
		)
		(pad "AA11" smd circle
			(at -13.299948 -3.800094)
			(size 0.4572 0.4572)
			(layers "F.Cu" "F.Mask" "F.Paste")
			(net "GND")
		)
		(pad "AA12" smd circle
			(at -12.349988 -3.800094)
			(size 0.4572 0.4572)
			(layers "F.Cu" "F.Mask" "F.Paste")
			(net "GND")
		)
		(pad "AA13" smd circle
			(at -11.400028 -3.800094)
			(size 0.4572 0.4572)
			(layers "F.Cu" "F.Mask" "F.Paste")
			(net "PCEPLL0_VDDA18_PEX3")
		)
		(pad "AA14" smd circle
			(at -10.450068 -3.800094)
			(size 0.4572 0.4572)
			(layers "F.Cu" "F.Mask" "F.Paste")
			(net "GND")
		)
		(pad "AA15" smd circle
			(at -9.500108 -3.800094)
			(size 0.4572 0.4572)
			(layers "F.Cu" "F.Mask" "F.Paste")
			(net "P0V8_PEX3")
		)
		(pad "AA16" smd circle
			(at -8.549894 -3.800094)
			(size 0.4572 0.4572)
			(layers "F.Cu" "F.Mask" "F.Paste")
			(net "GND")
		)
		(pad "AA17" smd circle
			(at -7.599934 -3.800094)
			(size 0.4572 0.4572)
			(layers "F.Cu" "F.Mask" "F.Paste")
			(net "GND")
		)
		(pad "AA18" smd circle
			(at -6.649974 -3.800094)
			(size 0.4572 0.4572)
			(layers "F.Cu" "F.Mask" "F.Paste")
			(net "GND")
		)
		(pad "AA19" smd circle
			(at -5.700014 -3.800094)
			(size 0.4572 0.4572)
			(layers "F.Cu" "F.Mask" "F.Paste")
			(net "GND")
		)
		(pad "AA20" smd circle
			(at -4.750054 -3.800094)
			(size 0.4572 0.4572)
			(layers "F.Cu" "F.Mask" "F.Paste")
			(net "GND")
		)
		(pad "AA21" smd circle
			(at -3.800094 -3.800094)
			(size 0.4572 0.4572)
			(layers "F.Cu" "F.Mask" "F.Paste")
			(net "GND")
		)
		(pad "AA22" smd circle
			(at -2.84988 -3.800094)
			(size 0.4572 0.4572)
			(layers "F.Cu" "F.Mask" "F.Paste")
			(net "GND")
		)
		(pad "AA23" smd circle
			(at -1.89992 -3.800094)
			(size 0.4572 0.4572)
			(layers "F.Cu" "F.Mask" "F.Paste")
			(net "GND")
		)
		(pad "AA24" smd circle
			(at -0.94996 -3.800094)
			(size 0.4572 0.4572)
			(layers "F.Cu" "F.Mask" "F.Paste")
			(net "GND")
		)
		(pad "AA25" smd circle
			(at 0 -3.800094)
			(size 0.4572 0.4572)
			(layers "F.Cu" "F.Mask" "F.Paste")
			(net "GND")
		)
		(pad "AA26" smd circle
			(at 0.94996 -3.800094)
			(size 0.4572 0.4572)
			(layers "F.Cu" "F.Mask" "F.Paste")
			(net "GND")
		)
		(pad "AA27" smd circle
			(at 1.89992 -3.800094)
			(size 0.4572 0.4572)
			(layers "F.Cu" "F.Mask" "F.Paste")
			(net "GND")
		)
		(pad "AA28" smd circle
			(at 2.84988 -3.800094)
			(size 0.4572 0.4572)
			(layers "F.Cu" "F.Mask" "F.Paste")
			(net "GND")
		)
		(pad "AA29" smd circle
			(at 3.800094 -3.800094)
			(size 0.4572 0.4572)
			(layers "F.Cu" "F.Mask" "F.Paste")
			(net "GND")
		)
		(pad "AA30" smd circle
			(at 4.750054 -3.800094)
			(size 0.4572 0.4572)
			(layers "F.Cu" "F.Mask" "F.Paste")
			(net "GND")
		)
		(pad "AA31" smd circle
			(at 5.700014 -3.800094)
			(size 0.4572 0.4572)
			(layers "F.Cu" "F.Mask" "F.Paste")
			(net "GND")
		)
		(pad "AA32" smd circle
			(at 6.649974 -3.800094)
			(size 0.4572 0.4572)
			(layers "F.Cu" "F.Mask" "F.Paste")
			(net "GND")
		)
		(pad "AA33" smd circle
			(at 7.599934 -3.800094)
			(size 0.4572 0.4572)
			(layers "F.Cu" "F.Mask" "F.Paste")
			(net "GND")
		)
		(pad "AA34" smd circle
			(at 8.549894 -3.800094)
			(size 0.4572 0.4572)
			(layers "F.Cu" "F.Mask" "F.Paste")
			(net "P1V8_VDDA_PEX3")
		)
		(pad "AA35" smd circle
			(at 9.500108 -3.800094)
			(size 0.4572 0.4572)
			(layers "F.Cu" "F.Mask" "F.Paste")
			(net "Net_537")
		)
		(pad "AA36" smd circle
			(at 10.450068 -3.800094)
			(size 0.4572 0.4572)
			(layers "F.Cu" "F.Mask" "F.Paste")
			(net "GND")
		)
		(pad "AA37" smd circle
			(at 11.400028 -3.800094)
			(size 0.4572 0.4572)
			(layers "F.Cu" "F.Mask" "F.Paste")
			(net "P1V8_VDDA_PEX3")
		)
		(pad "AA38" smd circle
			(at 12.349988 -3.800094)
			(size 0.4572 0.4572)
			(layers "F.Cu" "F.Mask" "F.Paste")
			(net "GND")
		)
		(pad "AA39" smd circle
			(at 13.299948 -3.800094)
			(size 0.4572 0.4572)
			(layers "F.Cu" "F.Mask" "F.Paste")
			(net "PEX3_ADCTEMP_VINP1")
		)
		(pad "AA40" smd circle
			(at 14.249908 -3.800094)
			(size 0.4572 0.4572)
			(layers "F.Cu" "F.Mask" "F.Paste")
			(net "GND")
		)
		(pad "AA41" smd circle
			(at 15.200122 -3.800094)
			(size 0.4572 0.4572)
			(layers "F.Cu" "F.Mask" "F.Paste")
			(net "GND")
		)
		(pad "AA42" smd circle
			(at 16.150082 -3.800094)
			(size 0.4572 0.4572)
			(layers "F.Cu" "F.Mask" "F.Paste")
			(net "GND")
		)
		(pad "AA43" smd circle
			(at 17.100042 -3.800094)
			(size 0.4572 0.4572)
			(layers "F.Cu" "F.Mask" "F.Paste")
			(net "Net_1521")
		)
		(pad "AA44" smd circle
			(at 18.050002 -3.800094)
			(size 0.4572 0.4572)
			(layers "F.Cu" "F.Mask" "F.Paste")
			(net "Net_1568")
		)
		(pad "AA45" smd circle
			(at 18.999962 -3.800094)
			(size 0.4572 0.4572)
			(layers "F.Cu" "F.Mask" "F.Paste")
			(net "GND")
		)
		(pad "AA46" smd circle
			(at 19.949922 -3.800094)
			(size 0.4572 0.4572)
			(layers "F.Cu" "F.Mask" "F.Paste")
			(net "Net_1490")
		)
		(pad "AA47" smd circle
			(at 20.899882 -3.800094)
			(size 0.4572 0.4572)
			(layers "F.Cu" "F.Mask" "F.Paste")
			(net "Net_1476")
		)
		(pad "AA48" smd circle
			(at 21.850096 -3.800094)
			(size 0.4572 0.4572)
			(layers "F.Cu" "F.Mask" "F.Paste")
			(net "GND")
		)
		(pad "AA49" smd circle
			(at 22.800056 -3.800094)
			(size 0.4572 0.4572)
			(layers "F.Cu" "F.Mask" "F.Paste")
			(net "GND")
		)
		(pad "AB1" smd circle
			(at -22.800056 -2.84988)
			(size 0.4572 0.4572)
			(layers "F.Cu" "F.Mask" "F.Paste")
			(net "GND")
		)
		(pad "AB2" smd circle
			(at -21.850096 -2.84988)
			(size 0.4572 0.4572)
			(layers "F.Cu" "F.Mask" "F.Paste")
			(net "GND")
		)
		(pad "AB3" smd circle
			(at -20.899882 -2.84988)
			(size 0.4572 0.4572)
			(layers "F.Cu" "F.Mask" "F.Paste")
			(net "GND")
		)
		(pad "AB4" smd circle
			(at -19.949922 -2.84988)
			(size 0.4572 0.4572)
			(layers "F.Cu" "F.Mask" "F.Paste")
			(net "CLK_100M_DB800ZL_PEX3_S0_R_DN")
		)
		(pad "AB5" smd circle
			(at -18.999962 -2.84988)
			(size 0.4572 0.4572)
			(layers "F.Cu" "F.Mask" "F.Paste")
			(net "CLK_100M_DB800ZL_PEX3_S0_R_DP")
		)
		(pad "AB6" smd circle
			(at -18.050002 -2.84988)
			(size 0.4572 0.4572)
			(layers "F.Cu" "F.Mask" "F.Paste")
			(net "GND")
		)
		(pad "AB7" smd circle
			(at -17.100042 -2.84988)
			(size 0.4572 0.4572)
			(layers "F.Cu" "F.Mask" "F.Paste")
			(net "Net_5486")
		)
		(pad "AB8" smd circle
			(at -16.150082 -2.84988)
			(size 0.4572 0.4572)
			(layers "F.Cu" "F.Mask" "F.Paste")
			(net "Net_5485")
		)
		(pad "AB9" smd circle
			(at -15.200122 -2.84988)
			(size 0.4572 0.4572)
			(layers "F.Cu" "F.Mask" "F.Paste")
			(net "GND")
		)
		(pad "AB10" smd circle
			(at -14.249908 -2.84988)
			(size 0.4572 0.4572)
			(layers "F.Cu" "F.Mask" "F.Paste")
			(net "P1V8_VDDA_PEX3")
		)
		(pad "AB11" smd circle
			(at -13.299948 -2.84988)
			(size 0.4572 0.4572)
			(layers "F.Cu" "F.Mask" "F.Paste")
			(net "GND")
		)
		(pad "AB12" smd circle
			(at -12.349988 -2.84988)
			(size 0.4572 0.4572)
			(layers "F.Cu" "F.Mask" "F.Paste")
			(net "PCEPLL1_VDDA18_PEX3")
		)
		(pad "AB13" smd circle
			(at -11.400028 -2.84988)
			(size 0.4572 0.4572)
			(layers "F.Cu" "F.Mask" "F.Paste")
			(net "GND")
		)
		(pad "AB14" smd circle
			(at -10.450068 -2.84988)
			(size 0.4572 0.4572)
			(layers "F.Cu" "F.Mask" "F.Paste")
			(net "P0V8_PEX3")
		)
		(pad "AB15" smd circle
			(at -9.500108 -2.84988)
			(size 0.4572 0.4572)
			(layers "F.Cu" "F.Mask" "F.Paste")
			(net "GND")
		)
		(pad "AB16" smd circle
			(at -8.549894 -2.84988)
			(size 0.4572 0.4572)
			(layers "F.Cu" "F.Mask" "F.Paste")
			(net "P0V8_SERDES_VDDA_PEX3")
		)
		(pad "AB17" smd circle
			(at -7.599934 -2.84988)
			(size 0.4572 0.4572)
			(layers "F.Cu" "F.Mask" "F.Paste")
			(net "P0V8_SERDES_VDDA_PEX3")
		)
		(pad "AB18" smd circle
			(at -6.649974 -2.84988)
			(size 0.4572 0.4572)
			(layers "F.Cu" "F.Mask" "F.Paste")
			(net "P0V8_SERDES_VDDA_PEX3")
		)
		(pad "AB19" smd circle
			(at -5.700014 -2.84988)
			(size 0.4572 0.4572)
			(layers "F.Cu" "F.Mask" "F.Paste")
			(net "P0V8_SERDES_VDDA_PEX3")
		)
		(pad "AB20" smd circle
			(at -4.750054 -2.84988)
			(size 0.4572 0.4572)
			(layers "F.Cu" "F.Mask" "F.Paste")
			(net "P0V8_SERDES_VDDA_PEX3")
		)
		(pad "AB21" smd circle
			(at -3.800094 -2.84988)
			(size 0.4572 0.4572)
			(layers "F.Cu" "F.Mask" "F.Paste")
			(net "P0V8_SERDES_VDDA_PEX3")
		)
		(pad "AB22" smd circle
			(at -2.84988 -2.84988)
			(size 0.4572 0.4572)
			(layers "F.Cu" "F.Mask" "F.Paste")
			(net "P0V8_SERDES_VDDA_PEX3")
		)
		(pad "AB23" smd circle
			(at -1.89992 -2.84988)
			(size 0.4572 0.4572)
			(layers "F.Cu" "F.Mask" "F.Paste")
			(net "P0V8_SERDES_VDDA_PEX3")
		)
		(pad "AB24" smd circle
			(at -0.94996 -2.84988)
			(size 0.4572 0.4572)
			(layers "F.Cu" "F.Mask" "F.Paste")
			(net "P0V8_SERDES_VDDA_PEX3")
		)
		(pad "AB25" smd circle
			(at 0 -2.84988)
			(size 0.4572 0.4572)
			(layers "F.Cu" "F.Mask" "F.Paste")
			(net "P0V8_SERDES_VDDA_PEX3")
		)
		(pad "AB26" smd circle
			(at 0.94996 -2.84988)
			(size 0.4572 0.4572)
			(layers "F.Cu" "F.Mask" "F.Paste")
			(net "P0V8_SERDES_VDDA_PEX3")
		)
		(pad "AB27" smd circle
			(at 1.89992 -2.84988)
			(size 0.4572 0.4572)
			(layers "F.Cu" "F.Mask" "F.Paste")
			(net "P0V8_SERDES_VDDA_PEX3")
		)
		(pad "AB28" smd circle
			(at 2.84988 -2.84988)
			(size 0.4572 0.4572)
			(layers "F.Cu" "F.Mask" "F.Paste")
			(net "P0V8_SERDES_VDDA_PEX3")
		)
		(pad "AB29" smd circle
			(at 3.800094 -2.84988)
			(size 0.4572 0.4572)
			(layers "F.Cu" "F.Mask" "F.Paste")
			(net "P0V8_SERDES_VDDA_PEX3")
		)
		(pad "AB30" smd circle
			(at 4.750054 -2.84988)
			(size 0.4572 0.4572)
			(layers "F.Cu" "F.Mask" "F.Paste")
			(net "P0V8_SERDES_VDDA_PEX3")
		)
		(pad "AB31" smd circle
			(at 5.700014 -2.84988)
			(size 0.4572 0.4572)
			(layers "F.Cu" "F.Mask" "F.Paste")
			(net "P0V8_SERDES_VDDA_PEX3")
		)
		(pad "AB32" smd circle
			(at 6.649974 -2.84988)
			(size 0.4572 0.4572)
			(layers "F.Cu" "F.Mask" "F.Paste")
			(net "P0V8_SERDES_VDDA_PEX3")
		)
		(pad "AB33" smd circle
			(at 7.599934 -2.84988)
			(size 0.4572 0.4572)
			(layers "F.Cu" "F.Mask" "F.Paste")
			(net "P0V8_SERDES_VDDA_PEX3")
		)
		(pad "AB34" smd circle
			(at 8.549894 -2.84988)
			(size 0.4572 0.4572)
			(layers "F.Cu" "F.Mask" "F.Paste")
			(net "GND")
		)
		(pad "AB35" smd circle
			(at 9.500108 -2.84988)
			(size 0.4572 0.4572)
			(layers "F.Cu" "F.Mask" "F.Paste")
			(net "Net_532")
		)
		(pad "AB36" smd circle
			(at 10.450068 -2.84988)
			(size 0.4572 0.4572)
			(layers "F.Cu" "F.Mask" "F.Paste")
			(net "GND")
		)
		(pad "AB37" smd circle
			(at 11.400028 -2.84988)
			(size 0.4572 0.4572)
			(layers "F.Cu" "F.Mask" "F.Paste")
			(net "GND")
		)
		(pad "AB38" smd circle
			(at 12.349988 -2.84988)
			(size 0.4572 0.4572)
			(layers "F.Cu" "F.Mask" "F.Paste")
			(net "GND")
		)
		(pad "AB39" smd circle
			(at 13.299948 -2.84988)
			(size 0.4572 0.4572)
			(layers "F.Cu" "F.Mask" "F.Paste")
			(net "GND")
		)
		(pad "AB40" smd circle
			(at 14.249908 -2.84988)
			(size 0.4572 0.4572)
			(layers "F.Cu" "F.Mask" "F.Paste")
			(net "GND")
		)
		(pad "AB41" smd circle
			(at 15.200122 -2.84988)
			(size 0.4572 0.4572)
			(layers "F.Cu" "F.Mask" "F.Paste")
			(net "Net_1566")
		)
		(pad "AB42" smd circle
			(at 16.150082 -2.84988)
			(size 0.4572 0.4572)
			(layers "F.Cu" "F.Mask" "F.Paste")
			(net "Net_1551")
		)
		(pad "AB43" smd circle
			(at 17.100042 -2.84988)
			(size 0.4572 0.4572)
			(layers "F.Cu" "F.Mask" "F.Paste")
			(net "GND")
		)
		(pad "AB44" smd circle
			(at 18.050002 -2.84988)
			(size 0.4572 0.4572)
			(layers "F.Cu" "F.Mask" "F.Paste")
			(net "GND")
		)
		(pad "AB45" smd circle
			(at 18.999962 -2.84988)
			(size 0.4572 0.4572)
			(layers "F.Cu" "F.Mask" "F.Paste")
			(net "GND")
		)
		(pad "AB46" smd circle
			(at 19.949922 -2.84988)
			(size 0.4572 0.4572)
			(layers "F.Cu" "F.Mask" "F.Paste")
			(net "GND")
		)
		(pad "AB47" smd circle
			(at 20.899882 -2.84988)
			(size 0.4572 0.4572)
			(layers "F.Cu" "F.Mask" "F.Paste")
			(net "GND")
		)
		(pad "AB48" smd circle
			(at 21.850096 -2.84988)
			(size 0.4572 0.4572)
			(layers "F.Cu" "F.Mask" "F.Paste")
			(net "Net_1405")
		)
		(pad "AB49" smd circle
			(at 22.800056 -2.84988)
			(size 0.4572 0.4572)
			(layers "F.Cu" "F.Mask" "F.Paste")
			(net "Net_1511")
		)
		(pad "AC1" smd circle
			(at -22.800056 -1.89992)
			(size 0.4572 0.4572)
			(layers "F.Cu" "F.Mask" "F.Paste")
			(net "CLK_100M_DB2000QL_PEX3_S1_R_DN")
		)
		(pad "AC2" smd circle
			(at -21.850096 -1.89992)
			(size 0.4572 0.4572)
			(layers "F.Cu" "F.Mask" "F.Paste")
			(net "CLK_100M_DB2000QL_PEX3_S1_R_DP")
		)
		(pad "AC3" smd circle
			(at -20.899882 -1.89992)
			(size 0.4572 0.4572)
			(layers "F.Cu" "F.Mask" "F.Paste")
			(net "GND")
		)
		(pad "AC4" smd circle
			(at -19.949922 -1.89992)
			(size 0.4572 0.4572)
			(layers "F.Cu" "F.Mask" "F.Paste")
			(net "GND")
		)
		(pad "AC5" smd circle
			(at -18.999962 -1.89992)
			(size 0.4572 0.4572)
			(layers "F.Cu" "F.Mask" "F.Paste")
			(net "GND")
		)
		(pad "AC6" smd circle
			(at -18.050002 -1.89992)
			(size 0.4572 0.4572)
			(layers "F.Cu" "F.Mask" "F.Paste")
			(net "GND")
		)
		(pad "AC7" smd circle
			(at -17.100042 -1.89992)
			(size 0.4572 0.4572)
			(layers "F.Cu" "F.Mask" "F.Paste")
			(net "Net_5488")
		)
		(pad "AC8" smd circle
			(at -16.150082 -1.89992)
			(size 0.4572 0.4572)
			(layers "F.Cu" "F.Mask" "F.Paste")
			(net "Net_5490")
		)
		(pad "AC9" smd circle
			(at -15.200122 -1.89992)
			(size 0.4572 0.4572)
			(layers "F.Cu" "F.Mask" "F.Paste")
			(net "GND")
		)
		(pad "AC10" smd circle
			(at -14.249908 -1.89992)
			(size 0.4572 0.4572)
			(layers "F.Cu" "F.Mask" "F.Paste")
			(net "P1V8_VDDA_PEX3")
		)
		(pad "AC11" smd circle
			(at -13.299948 -1.89992)
			(size 0.4572 0.4572)
			(layers "F.Cu" "F.Mask" "F.Paste")
			(net "GND")
		)
		(pad "AC12" smd circle
			(at -12.349988 -1.89992)
			(size 0.4572 0.4572)
			(layers "F.Cu" "F.Mask" "F.Paste")
			(net "GND")
		)
		(pad "AC13" smd circle
			(at -11.400028 -1.89992)
			(size 0.4572 0.4572)
			(layers "F.Cu" "F.Mask" "F.Paste")
			(net "SYSPLL_VDDA18_PEX3")
		)
		(pad "AC14" smd circle
			(at -10.450068 -1.89992)
			(size 0.4572 0.4572)
			(layers "F.Cu" "F.Mask" "F.Paste")
			(net "GND")
		)
		(pad "AC15" smd circle
			(at -9.500108 -1.89992)
			(size 0.4572 0.4572)
			(layers "F.Cu" "F.Mask" "F.Paste")
			(net "P0V8_PEX3")
		)
		(pad "AC16" smd circle
			(at -8.549894 -1.89992)
			(size 0.4572 0.4572)
			(layers "F.Cu" "F.Mask" "F.Paste")
			(net "GND")
		)
		(pad "AC17" smd circle
			(at -7.599934 -1.89992)
			(size 0.4572 0.4572)
			(layers "F.Cu" "F.Mask" "F.Paste")
			(net "P0V8_PEX3")
		)
		(pad "AC18" smd circle
			(at -6.649974 -1.89992)
			(size 0.4572 0.4572)
			(layers "F.Cu" "F.Mask" "F.Paste")
			(net "GND")
		)
		(pad "AC19" smd circle
			(at -5.700014 -1.89992)
			(size 0.4572 0.4572)
			(layers "F.Cu" "F.Mask" "F.Paste")
			(net "P0V8_PEX3")
		)
		(pad "AC20" smd circle
			(at -4.750054 -1.89992)
			(size 0.4572 0.4572)
			(layers "F.Cu" "F.Mask" "F.Paste")
			(net "GND")
		)
		(pad "AC21" smd circle
			(at -3.800094 -1.89992)
			(size 0.4572 0.4572)
			(layers "F.Cu" "F.Mask" "F.Paste")
			(net "P0V8_PEX3")
		)
		(pad "AC22" smd circle
			(at -2.84988 -1.89992)
			(size 0.4572 0.4572)
			(layers "F.Cu" "F.Mask" "F.Paste")
			(net "GND")
		)
		(pad "AC23" smd circle
			(at -1.89992 -1.89992)
			(size 0.4572 0.4572)
			(layers "F.Cu" "F.Mask" "F.Paste")
			(net "P0V8_PEX3")
		)
		(pad "AC24" smd circle
			(at -0.94996 -1.89992)
			(size 0.4572 0.4572)
			(layers "F.Cu" "F.Mask" "F.Paste")
			(net "GND")
		)
		(pad "AC25" smd circle
			(at 0 -1.89992)
			(size 0.4572 0.4572)
			(layers "F.Cu" "F.Mask" "F.Paste")
			(net "P0V8_PEX3")
		)
		(pad "AC26" smd circle
			(at 0.94996 -1.89992)
			(size 0.4572 0.4572)
			(layers "F.Cu" "F.Mask" "F.Paste")
			(net "GND")
		)
		(pad "AC27" smd circle
			(at 1.89992 -1.89992)
			(size 0.4572 0.4572)
			(layers "F.Cu" "F.Mask" "F.Paste")
			(net "P0V8_PEX3")
		)
		(pad "AC28" smd circle
			(at 2.84988 -1.89992)
			(size 0.4572 0.4572)
			(layers "F.Cu" "F.Mask" "F.Paste")
			(net "GND")
		)
		(pad "AC29" smd circle
			(at 3.800094 -1.89992)
			(size 0.4572 0.4572)
			(layers "F.Cu" "F.Mask" "F.Paste")
			(net "P0V8_PEX3")
		)
		(pad "AC30" smd circle
			(at 4.750054 -1.89992)
			(size 0.4572 0.4572)
			(layers "F.Cu" "F.Mask" "F.Paste")
			(net "GND")
		)
		(pad "AC31" smd circle
			(at 5.700014 -1.89992)
			(size 0.4572 0.4572)
			(layers "F.Cu" "F.Mask" "F.Paste")
			(net "P0V8_PEX3")
		)
		(pad "AC32" smd circle
			(at 6.649974 -1.89992)
			(size 0.4572 0.4572)
			(layers "F.Cu" "F.Mask" "F.Paste")
			(net "GND")
		)
		(pad "AC33" smd circle
			(at 7.599934 -1.89992)
			(size 0.4572 0.4572)
			(layers "F.Cu" "F.Mask" "F.Paste")
			(net "P0V8_PEX3")
		)
		(pad "AC34" smd circle
			(at 8.549894 -1.89992)
			(size 0.4572 0.4572)
			(layers "F.Cu" "F.Mask" "F.Paste")
			(net "GND")
		)
		(pad "AC35" smd circle
			(at 9.500108 -1.89992)
			(size 0.4572 0.4572)
			(layers "F.Cu" "F.Mask" "F.Paste")
			(net "GND")
		)
		(pad "AC36" smd circle
			(at 10.450068 -1.89992)
			(size 0.4572 0.4572)
			(layers "F.Cu" "F.Mask" "F.Paste")
			(net "P1V25_PEX3")
		)
		(pad "AC37" smd circle
			(at 11.400028 -1.89992)
			(size 0.4572 0.4572)
			(layers "F.Cu" "F.Mask" "F.Paste")
			(net "GND")
		)
		(pad "AC38" smd circle
			(at 12.349988 -1.89992)
			(size 0.4572 0.4572)
			(layers "F.Cu" "F.Mask" "F.Paste")
			(net "P1V25_SERDES_VDDPLL_PEX3")
		)
		(pad "AC39" smd circle
			(at 13.299948 -1.89992)
			(size 0.4572 0.4572)
			(layers "F.Cu" "F.Mask" "F.Paste")
			(net "GND")
		)
		(pad "AC40" smd circle
			(at 14.249908 -1.89992)
			(size 0.4572 0.4572)
			(layers "F.Cu" "F.Mask" "F.Paste")
			(net "GND")
		)
		(pad "AC41" smd circle
			(at 15.200122 -1.89992)
			(size 0.4572 0.4572)
			(layers "F.Cu" "F.Mask" "F.Paste")
			(net "GND")
		)
		(pad "AC42" smd circle
			(at 16.150082 -1.89992)
			(size 0.4572 0.4572)
			(layers "F.Cu" "F.Mask" "F.Paste")
			(net "GND")
		)
		(pad "AC43" smd circle
			(at 17.100042 -1.89992)
			(size 0.4572 0.4572)
			(layers "F.Cu" "F.Mask" "F.Paste")
			(net "Net_1527")
		)
		(pad "AC44" smd circle
			(at 18.050002 -1.89992)
			(size 0.4572 0.4572)
			(layers "F.Cu" "F.Mask" "F.Paste")
			(net "Net_1514")
		)
		(pad "AC45" smd circle
			(at 18.999962 -1.89992)
			(size 0.4572 0.4572)
			(layers "F.Cu" "F.Mask" "F.Paste")
			(net "GND")
		)
		(pad "AC46" smd circle
			(at 19.949922 -1.89992)
			(size 0.4572 0.4572)
			(layers "F.Cu" "F.Mask" "F.Paste")
			(net "Net_1456")
		)
		(pad "AC47" smd circle
			(at 20.899882 -1.89992)
			(size 0.4572 0.4572)
			(layers "F.Cu" "F.Mask" "F.Paste")
			(net "Net_1496")
		)
		(pad "AC48" smd circle
			(at 21.850096 -1.89992)
			(size 0.4572 0.4572)
			(layers "F.Cu" "F.Mask" "F.Paste")
			(net "GND")
		)
		(pad "AC49" smd circle
			(at 22.800056 -1.89992)
			(size 0.4572 0.4572)
			(layers "F.Cu" "F.Mask" "F.Paste")
			(net "GND")
		)
		(pad "AD1" smd circle
			(at -22.800056 -0.94996)
			(size 0.4572 0.4572)
			(layers "F.Cu" "F.Mask" "F.Paste")
			(net "GND")
		)
		(pad "AD2" smd circle
			(at -21.850096 -0.94996)
			(size 0.4572 0.4572)
			(layers "F.Cu" "F.Mask" "F.Paste")
			(net "GND")
		)
		(pad "AD3" smd circle
			(at -20.899882 -0.94996)
			(size 0.4572 0.4572)
			(layers "F.Cu" "F.Mask" "F.Paste")
			(net "GND")
		)
		(pad "AD4" smd circle
			(at -19.949922 -0.94996)
			(size 0.4572 0.4572)
			(layers "F.Cu" "F.Mask" "F.Paste")
			(net "Net_381")
		)
		(pad "AD5" smd circle
			(at -18.999962 -0.94996)
			(size 0.4572 0.4572)
			(layers "F.Cu" "F.Mask" "F.Paste")
			(net "Net_388")
		)
		(pad "AD6" smd circle
			(at -18.050002 -0.94996)
			(size 0.4572 0.4572)
			(layers "F.Cu" "F.Mask" "F.Paste")
			(net "GND")
		)
		(pad "AD7" smd circle
			(at -17.100042 -0.94996)
			(size 0.4572 0.4572)
			(layers "F.Cu" "F.Mask" "F.Paste")
			(net "Net_5487")
		)
		(pad "AD8" smd circle
			(at -16.150082 -0.94996)
			(size 0.4572 0.4572)
			(layers "F.Cu" "F.Mask" "F.Paste")
			(net "Net_5489")
		)
		(pad "AD9" smd circle
			(at -15.200122 -0.94996)
			(size 0.4572 0.4572)
			(layers "F.Cu" "F.Mask" "F.Paste")
			(net "GND")
		)
		(pad "AD10" smd circle
			(at -14.249908 -0.94996)
			(size 0.4572 0.4572)
			(layers "F.Cu" "F.Mask" "F.Paste")
			(net "GND")
		)
		(pad "AD11" smd circle
			(at -13.299948 -0.94996)
			(size 0.4572 0.4572)
			(layers "F.Cu" "F.Mask" "F.Paste")
			(net "GND")
		)
		(pad "AD12" smd circle
			(at -12.349988 -0.94996)
			(size 0.4572 0.4572)
			(layers "F.Cu" "F.Mask" "F.Paste")
			(net "PCEPLL2_VDDA18_PEX3")
		)
		(pad "AD13" smd circle
			(at -11.400028 -0.94996)
			(size 0.4572 0.4572)
			(layers "F.Cu" "F.Mask" "F.Paste")
			(net "GND")
		)
		(pad "AD14" smd circle
			(at -10.450068 -0.94996)
			(size 0.4572 0.4572)
			(layers "F.Cu" "F.Mask" "F.Paste")
			(net "P0V8_PEX3")
		)
		(pad "AD15" smd circle
			(at -9.500108 -0.94996)
			(size 0.4572 0.4572)
			(layers "F.Cu" "F.Mask" "F.Paste")
			(net "GND")
		)
		(pad "AD16" smd circle
			(at -8.549894 -0.94996)
			(size 0.4572 0.4572)
			(layers "F.Cu" "F.Mask" "F.Paste")
			(net "P0V8_PEX3")
		)
		(pad "AD17" smd circle
			(at -7.599934 -0.94996)
			(size 0.4572 0.4572)
			(layers "F.Cu" "F.Mask" "F.Paste")
			(net "GND")
		)
		(pad "AD18" smd circle
			(at -6.649974 -0.94996)
			(size 0.4572 0.4572)
			(layers "F.Cu" "F.Mask" "F.Paste")
			(net "P0V8_PEX3")
		)
		(pad "AD19" smd circle
			(at -5.700014 -0.94996)
			(size 0.4572 0.4572)
			(layers "F.Cu" "F.Mask" "F.Paste")
			(net "GND")
		)
		(pad "AD20" smd circle
			(at -4.750054 -0.94996)
			(size 0.4572 0.4572)
			(layers "F.Cu" "F.Mask" "F.Paste")
			(net "P0V8_PEX3")
		)
		(pad "AD21" smd circle
			(at -3.800094 -0.94996)
			(size 0.4572 0.4572)
			(layers "F.Cu" "F.Mask" "F.Paste")
			(net "GND")
		)
		(pad "AD22" smd circle
			(at -2.84988 -0.94996)
			(size 0.4572 0.4572)
			(layers "F.Cu" "F.Mask" "F.Paste")
			(net "P0V8_PEX3")
		)
		(pad "AD23" smd circle
			(at -1.89992 -0.94996)
			(size 0.4572 0.4572)
			(layers "F.Cu" "F.Mask" "F.Paste")
			(net "GND")
		)
		(pad "AD24" smd circle
			(at -0.94996 -0.94996)
			(size 0.4572 0.4572)
			(layers "F.Cu" "F.Mask" "F.Paste")
			(net "P0V8_PEX3")
		)
		(pad "AD25" smd circle
			(at 0 -0.94996)
			(size 0.4572 0.4572)
			(layers "F.Cu" "F.Mask" "F.Paste")
			(net "GND")
		)
		(pad "AD26" smd circle
			(at 0.94996 -0.94996)
			(size 0.4572 0.4572)
			(layers "F.Cu" "F.Mask" "F.Paste")
			(net "P0V8_PEX3")
		)
		(pad "AD27" smd circle
			(at 1.89992 -0.94996)
			(size 0.4572 0.4572)
			(layers "F.Cu" "F.Mask" "F.Paste")
			(net "GND")
		)
		(pad "AD28" smd circle
			(at 2.84988 -0.94996)
			(size 0.4572 0.4572)
			(layers "F.Cu" "F.Mask" "F.Paste")
			(net "P0V8_PEX3")
		)
		(pad "AD29" smd circle
			(at 3.800094 -0.94996)
			(size 0.4572 0.4572)
			(layers "F.Cu" "F.Mask" "F.Paste")
			(net "GND")
		)
		(pad "AD30" smd circle
			(at 4.750054 -0.94996)
			(size 0.4572 0.4572)
			(layers "F.Cu" "F.Mask" "F.Paste")
			(net "P0V8_PEX3")
		)
		(pad "AD31" smd circle
			(at 5.700014 -0.94996)
			(size 0.4572 0.4572)
			(layers "F.Cu" "F.Mask" "F.Paste")
			(net "GND")
		)
		(pad "AD32" smd circle
			(at 6.649974 -0.94996)
			(size 0.4572 0.4572)
			(layers "F.Cu" "F.Mask" "F.Paste")
			(net "P0V8_SERDES_VDDA_PEX3")
		)
		(pad "AD33" smd circle
			(at 7.599934 -0.94996)
			(size 0.4572 0.4572)
			(layers "F.Cu" "F.Mask" "F.Paste")
			(net "P0V8_SERDES_VDDA_PEX3")
		)
		(pad "AD34" smd circle
			(at 8.549894 -0.94996)
			(size 0.4572 0.4572)
			(layers "F.Cu" "F.Mask" "F.Paste")
			(net "P0V8_SERDES_VDDA_PEX3")
		)
		(pad "AD35" smd circle
			(at 9.500108 -0.94996)
			(size 0.4572 0.4572)
			(layers "F.Cu" "F.Mask" "F.Paste")
			(net "GND")
		)
		(pad "AD36" smd circle
			(at 10.450068 -0.94996)
			(size 0.4572 0.4572)
			(layers "F.Cu" "F.Mask" "F.Paste")
			(net "P1V25_PEX3")
		)
		(pad "AD37" smd circle
			(at 11.400028 -0.94996)
			(size 0.4572 0.4572)
			(layers "F.Cu" "F.Mask" "F.Paste")
			(net "GND")
		)
		(pad "AD38" smd circle
			(at 12.349988 -0.94996)
			(size 0.4572 0.4572)
			(layers "F.Cu" "F.Mask" "F.Paste")
			(net "P1V25_SERDES_VDDPLL_PEX3")
		)
		(pad "AD39" smd circle
			(at 13.299948 -0.94996)
			(size 0.4572 0.4572)
			(layers "F.Cu" "F.Mask" "F.Paste")
			(net "GND")
		)
		(pad "AD40" smd circle
			(at 14.249908 -0.94996)
			(size 0.4572 0.4572)
			(layers "F.Cu" "F.Mask" "F.Paste")
			(net "GND")
		)
		(pad "AD41" smd circle
			(at 15.200122 -0.94996)
			(size 0.4572 0.4572)
			(layers "F.Cu" "F.Mask" "F.Paste")
			(net "Net_1558")
		)
		(pad "AD42" smd circle
			(at 16.150082 -0.94996)
			(size 0.4572 0.4572)
			(layers "F.Cu" "F.Mask" "F.Paste")
			(net "Net_1547")
		)
		(pad "AD43" smd circle
			(at 17.100042 -0.94996)
			(size 0.4572 0.4572)
			(layers "F.Cu" "F.Mask" "F.Paste")
			(net "GND")
		)
		(pad "AD44" smd circle
			(at 18.050002 -0.94996)
			(size 0.4572 0.4572)
			(layers "F.Cu" "F.Mask" "F.Paste")
			(net "GND")
		)
		(pad "AD45" smd circle
			(at 18.999962 -0.94996)
			(size 0.4572 0.4572)
			(layers "F.Cu" "F.Mask" "F.Paste")
			(net "GND")
		)
		(pad "AD46" smd circle
			(at 19.949922 -0.94996)
			(size 0.4572 0.4572)
			(layers "F.Cu" "F.Mask" "F.Paste")
			(net "GND")
		)
		(pad "AD47" smd circle
			(at 20.899882 -0.94996)
			(size 0.4572 0.4572)
			(layers "F.Cu" "F.Mask" "F.Paste")
			(net "GND")
		)
		(pad "AD48" smd circle
			(at 21.850096 -0.94996)
			(size 0.4572 0.4572)
			(layers "F.Cu" "F.Mask" "F.Paste")
			(net "Net_1488")
		)
		(pad "AD49" smd circle
			(at 22.800056 -0.94996)
			(size 0.4572 0.4572)
			(layers "F.Cu" "F.Mask" "F.Paste")
			(net "Net_1478")
		)
		(pad "AE1" smd circle
			(at -22.800056 0)
			(size 0.4572 0.4572)
			(layers "F.Cu" "F.Mask" "F.Paste")
			(net "CLK_100M_DB800ZL_PEX3_S3_R_DN")
		)
		(pad "AE2" smd circle
			(at -21.850096 0)
			(size 0.4572 0.4572)
			(layers "F.Cu" "F.Mask" "F.Paste")
			(net "CLK_100M_DB800ZL_PEX3_S3_R_DP")
		)
		(pad "AE3" smd circle
			(at -20.899882 0)
			(size 0.4572 0.4572)
			(layers "F.Cu" "F.Mask" "F.Paste")
			(net "GND")
		)
		(pad "AE4" smd circle
			(at -19.949922 0)
			(size 0.4572 0.4572)
			(layers "F.Cu" "F.Mask" "F.Paste")
			(net "GND")
		)
		(pad "AE5" smd circle
			(at -18.999962 0)
			(size 0.4572 0.4572)
			(layers "F.Cu" "F.Mask" "F.Paste")
			(net "GND")
		)
		(pad "AE6" smd circle
			(at -18.050002 0)
			(size 0.4572 0.4572)
			(layers "F.Cu" "F.Mask" "F.Paste")
			(net "GND")
		)
		(pad "AE7" smd circle
			(at -17.100042 0)
			(size 0.4572 0.4572)
			(layers "F.Cu" "F.Mask" "F.Paste")
			(net "Net_5484")
		)
		(pad "AE8" smd circle
			(at -16.150082 0)
			(size 0.4572 0.4572)
			(layers "F.Cu" "F.Mask" "F.Paste")
			(net "Net_5491")
		)
		(pad "AE9" smd circle
			(at -15.200122 0)
			(size 0.4572 0.4572)
			(layers "F.Cu" "F.Mask" "F.Paste")
			(net "GND")
		)
		(pad "AE10" smd circle
			(at -14.249908 0)
			(size 0.4572 0.4572)
			(layers "F.Cu" "F.Mask" "F.Paste")
			(net "P1V8_PEX")
		)
		(pad "AE11" smd circle
			(at -13.299948 0)
			(size 0.4572 0.4572)
			(layers "F.Cu" "F.Mask" "F.Paste")
			(net "GND")
		)
		(pad "AE12" smd circle
			(at -12.349988 0)
			(size 0.4572 0.4572)
			(layers "F.Cu" "F.Mask" "F.Paste")
			(net "GND")
		)
		(pad "AE13" smd circle
			(at -11.400028 0)
			(size 0.4572 0.4572)
			(layers "F.Cu" "F.Mask" "F.Paste")
			(net "PCEPLL3_VDDA18_PEX3")
		)
		(pad "AE14" smd circle
			(at -10.450068 0)
			(size 0.4572 0.4572)
			(layers "F.Cu" "F.Mask" "F.Paste")
			(net "GND")
		)
		(pad "AE15" smd circle
			(at -9.500108 0)
			(size 0.4572 0.4572)
			(layers "F.Cu" "F.Mask" "F.Paste")
			(net "P0V8_PEX3")
		)
		(pad "AE16" smd circle
			(at -8.549894 0)
			(size 0.4572 0.4572)
			(layers "F.Cu" "F.Mask" "F.Paste")
			(net "GND")
		)
		(pad "AE17" smd circle
			(at -7.599934 0)
			(size 0.4572 0.4572)
			(layers "F.Cu" "F.Mask" "F.Paste")
			(net "P0V8_PEX3")
		)
		(pad "AE18" smd circle
			(at -6.649974 0)
			(size 0.4572 0.4572)
			(layers "F.Cu" "F.Mask" "F.Paste")
			(net "GND")
		)
		(pad "AE19" smd circle
			(at -5.700014 0)
			(size 0.4572 0.4572)
			(layers "F.Cu" "F.Mask" "F.Paste")
			(net "P0V8_PEX3")
		)
		(pad "AE20" smd circle
			(at -4.750054 0)
			(size 0.4572 0.4572)
			(layers "F.Cu" "F.Mask" "F.Paste")
			(net "GND")
		)
		(pad "AE21" smd circle
			(at -3.800094 0)
			(size 0.4572 0.4572)
			(layers "F.Cu" "F.Mask" "F.Paste")
			(net "P0V8_PEX3")
		)
		(pad "AE22" smd circle
			(at -2.84988 0)
			(size 0.4572 0.4572)
			(layers "F.Cu" "F.Mask" "F.Paste")
			(net "GND")
		)
		(pad "AE23" smd circle
			(at -1.89992 0)
			(size 0.4572 0.4572)
			(layers "F.Cu" "F.Mask" "F.Paste")
			(net "P0V8_PEX3")
		)
		(pad "AE24" smd circle
			(at -0.94996 0)
			(size 0.4572 0.4572)
			(layers "F.Cu" "F.Mask" "F.Paste")
			(net "GND")
		)
		(pad "AE25" smd circle
			(at 0 0)
			(size 0.4572 0.4572)
			(layers "F.Cu" "F.Mask" "F.Paste")
			(net "P0V8_PEX3")
		)
		(pad "AE26" smd circle
			(at 0.94996 0)
			(size 0.4572 0.4572)
			(layers "F.Cu" "F.Mask" "F.Paste")
			(net "GND")
		)
		(pad "AE27" smd circle
			(at 1.89992 0)
			(size 0.4572 0.4572)
			(layers "F.Cu" "F.Mask" "F.Paste")
			(net "P0V8_PEX3")
		)
		(pad "AE28" smd circle
			(at 2.84988 0)
			(size 0.4572 0.4572)
			(layers "F.Cu" "F.Mask" "F.Paste")
			(net "GND")
		)
		(pad "AE29" smd circle
			(at 3.800094 0)
			(size 0.4572 0.4572)
			(layers "F.Cu" "F.Mask" "F.Paste")
			(net "P0V8_PEX3")
		)
		(pad "AE30" smd circle
			(at 4.750054 0)
			(size 0.4572 0.4572)
			(layers "F.Cu" "F.Mask" "F.Paste")
			(net "GND")
		)
		(pad "AE31" smd circle
			(at 5.700014 0)
			(size 0.4572 0.4572)
			(layers "F.Cu" "F.Mask" "F.Paste")
			(net "P0V8_PEX3")
		)
		(pad "AE32" smd circle
			(at 6.649974 0)
			(size 0.4572 0.4572)
			(layers "F.Cu" "F.Mask" "F.Paste")
			(net "GND")
		)
		(pad "AE33" smd circle
			(at 7.599934 0)
			(size 0.4572 0.4572)
			(layers "F.Cu" "F.Mask" "F.Paste")
			(net "P0V8_SERDES_VDDA_PEX3")
		)
		(pad "AE34" smd circle
			(at 8.549894 0)
			(size 0.4572 0.4572)
			(layers "F.Cu" "F.Mask" "F.Paste")
			(net "P0V8_SERDES_VDDA_PEX3")
		)
		(pad "AE35" smd circle
			(at 9.500108 0)
			(size 0.4572 0.4572)
			(layers "F.Cu" "F.Mask" "F.Paste")
			(net "GND")
		)
		(pad "AE36" smd circle
			(at 10.450068 0)
			(size 0.4572 0.4572)
			(layers "F.Cu" "F.Mask" "F.Paste")
			(net "P1V25_PEX3")
		)
		(pad "AE37" smd circle
			(at 11.400028 0)
			(size 0.4572 0.4572)
			(layers "F.Cu" "F.Mask" "F.Paste")
			(net "GND")
		)
		(pad "AE38" smd circle
			(at 12.349988 0)
			(size 0.4572 0.4572)
			(layers "F.Cu" "F.Mask" "F.Paste")
			(net "P1V25_SERDES_VDDPLL_PEX3")
		)
		(pad "AE39" smd circle
			(at 13.299948 0)
			(size 0.4572 0.4572)
			(layers "F.Cu" "F.Mask" "F.Paste")
			(net "GND")
		)
		(pad "AE40" smd circle
			(at 14.249908 0)
			(size 0.4572 0.4572)
			(layers "F.Cu" "F.Mask" "F.Paste")
			(net "GND")
		)
		(pad "AE41" smd circle
			(at 15.200122 0)
			(size 0.4572 0.4572)
			(layers "F.Cu" "F.Mask" "F.Paste")
			(net "GND")
		)
		(pad "AE42" smd circle
			(at 16.150082 0)
			(size 0.4572 0.4572)
			(layers "F.Cu" "F.Mask" "F.Paste")
			(net "GND")
		)
		(pad "AE43" smd circle
			(at 17.100042 0)
			(size 0.4572 0.4572)
			(layers "F.Cu" "F.Mask" "F.Paste")
			(net "Net_1540")
		)
		(pad "AE44" smd circle
			(at 18.050002 0)
			(size 0.4572 0.4572)
			(layers "F.Cu" "F.Mask" "F.Paste")
			(net "Net_1526")
		)
		(pad "AE45" smd circle
			(at 18.999962 0)
			(size 0.4572 0.4572)
			(layers "F.Cu" "F.Mask" "F.Paste")
			(net "GND")
		)
		(pad "AE46" smd circle
			(at 19.949922 0)
			(size 0.4572 0.4572)
			(layers "F.Cu" "F.Mask" "F.Paste")
			(net "Net_1419")
		)
		(pad "AE47" smd circle
			(at 20.899882 0)
			(size 0.4572 0.4572)
			(layers "F.Cu" "F.Mask" "F.Paste")
			(net "Net_1453")
		)
		(pad "AE48" smd circle
			(at 21.850096 0)
			(size 0.4572 0.4572)
			(layers "F.Cu" "F.Mask" "F.Paste")
			(net "GND")
		)
		(pad "AE49" smd circle
			(at 22.800056 0)
			(size 0.4572 0.4572)
			(layers "F.Cu" "F.Mask" "F.Paste")
			(net "GND")
		)
		(pad "AF1" smd circle
			(at -22.800056 0.94996)
			(size 0.4572 0.4572)
			(layers "F.Cu" "F.Mask" "F.Paste")
			(net "GND")
		)
		(pad "AF2" smd circle
			(at -21.850096 0.94996)
			(size 0.4572 0.4572)
			(layers "F.Cu" "F.Mask" "F.Paste")
			(net "GND")
		)
		(pad "AF3" smd circle
			(at -20.899882 0.94996)
			(size 0.4572 0.4572)
			(layers "F.Cu" "F.Mask" "F.Paste")
			(net "GND")
		)
		(pad "AF4" smd circle
			(at -19.949922 0.94996)
			(size 0.4572 0.4572)
			(layers "F.Cu" "F.Mask" "F.Paste")
			(net "Net_5403")
		)
		(pad "AF5" smd circle
			(at -18.999962 0.94996)
			(size 0.4572 0.4572)
			(layers "F.Cu" "F.Mask" "F.Paste")
			(net "Net_5404")
		)
		(pad "AF6" smd circle
			(at -18.050002 0.94996)
			(size 0.4572 0.4572)
			(layers "F.Cu" "F.Mask" "F.Paste")
			(net "GND")
		)
		(pad "AF7" smd circle
			(at -17.100042 0.94996)
			(size 0.4572 0.4572)
			(layers "F.Cu" "F.Mask" "F.Paste")
			(net "SPI_PEX3_SDIO0")
		)
		(pad "AF8" smd circle
			(at -16.150082 0.94996)
			(size 0.4572 0.4572)
			(layers "F.Cu" "F.Mask" "F.Paste")
			(net "SPI_PEX3_SDIO1")
		)
		(pad "AF9" smd circle
			(at -15.200122 0.94996)
			(size 0.4572 0.4572)
			(layers "F.Cu" "F.Mask" "F.Paste")
			(net "GND")
		)
		(pad "AF10" smd circle
			(at -14.249908 0.94996)
			(size 0.4572 0.4572)
			(layers "F.Cu" "F.Mask" "F.Paste")
			(net "P1V8_PEX")
		)
		(pad "AF11" smd circle
			(at -13.299948 0.94996)
			(size 0.4572 0.4572)
			(layers "F.Cu" "F.Mask" "F.Paste")
			(net "GND")
		)
		(pad "AF12" smd circle
			(at -12.349988 0.94996)
			(size 0.4572 0.4572)
			(layers "F.Cu" "F.Mask" "F.Paste")
			(net "PCEPLL4_VDDA18_PEX3")
		)
		(pad "AF13" smd circle
			(at -11.400028 0.94996)
			(size 0.4572 0.4572)
			(layers "F.Cu" "F.Mask" "F.Paste")
			(net "GND")
		)
		(pad "AF14" smd circle
			(at -10.450068 0.94996)
			(size 0.4572 0.4572)
			(layers "F.Cu" "F.Mask" "F.Paste")
			(net "P0V8_PEX3")
		)
		(pad "AF15" smd circle
			(at -9.500108 0.94996)
			(size 0.4572 0.4572)
			(layers "F.Cu" "F.Mask" "F.Paste")
			(net "GND")
		)
		(pad "AF16" smd circle
			(at -8.549894 0.94996)
			(size 0.4572 0.4572)
			(layers "F.Cu" "F.Mask" "F.Paste")
			(net "P0V8_PEX3")
		)
		(pad "AF17" smd circle
			(at -7.599934 0.94996)
			(size 0.4572 0.4572)
			(layers "F.Cu" "F.Mask" "F.Paste")
			(net "GND")
		)
		(pad "AF18" smd circle
			(at -6.649974 0.94996)
			(size 0.4572 0.4572)
			(layers "F.Cu" "F.Mask" "F.Paste")
			(net "P0V8_PEX3")
		)
		(pad "AF19" smd circle
			(at -5.700014 0.94996)
			(size 0.4572 0.4572)
			(layers "F.Cu" "F.Mask" "F.Paste")
			(net "GND")
		)
		(pad "AF20" smd circle
			(at -4.750054 0.94996)
			(size 0.4572 0.4572)
			(layers "F.Cu" "F.Mask" "F.Paste")
			(net "P0V8_PEX3")
		)
		(pad "AF21" smd circle
			(at -3.800094 0.94996)
			(size 0.4572 0.4572)
			(layers "F.Cu" "F.Mask" "F.Paste")
			(net "GND")
		)
		(pad "AF22" smd circle
			(at -2.84988 0.94996)
			(size 0.4572 0.4572)
			(layers "F.Cu" "F.Mask" "F.Paste")
			(net "P0V8_PEX3")
		)
		(pad "AF23" smd circle
			(at -1.89992 0.94996)
			(size 0.4572 0.4572)
			(layers "F.Cu" "F.Mask" "F.Paste")
			(net "GND")
		)
		(pad "AF24" smd circle
			(at -0.94996 0.94996)
			(size 0.4572 0.4572)
			(layers "F.Cu" "F.Mask" "F.Paste")
			(net "P0V8_PEX3")
		)
		(pad "AF25" smd circle
			(at 0 0.94996)
			(size 0.4572 0.4572)
			(layers "F.Cu" "F.Mask" "F.Paste")
			(net "GND")
		)
		(pad "AF26" smd circle
			(at 0.94996 0.94996)
			(size 0.4572 0.4572)
			(layers "F.Cu" "F.Mask" "F.Paste")
			(net "P0V8_PEX3")
		)
		(pad "AF27" smd circle
			(at 1.89992 0.94996)
			(size 0.4572 0.4572)
			(layers "F.Cu" "F.Mask" "F.Paste")
			(net "GND")
		)
		(pad "AF28" smd circle
			(at 2.84988 0.94996)
			(size 0.4572 0.4572)
			(layers "F.Cu" "F.Mask" "F.Paste")
			(net "P0V8_PEX3")
		)
		(pad "AF29" smd circle
			(at 3.800094 0.94996)
			(size 0.4572 0.4572)
			(layers "F.Cu" "F.Mask" "F.Paste")
			(net "GND")
		)
		(pad "AF30" smd circle
			(at 4.750054 0.94996)
			(size 0.4572 0.4572)
			(layers "F.Cu" "F.Mask" "F.Paste")
			(net "P0V8_PEX3")
		)
		(pad "AF31" smd circle
			(at 5.700014 0.94996)
			(size 0.4572 0.4572)
			(layers "F.Cu" "F.Mask" "F.Paste")
			(net "GND")
		)
		(pad "AF32" smd circle
			(at 6.649974 0.94996)
			(size 0.4572 0.4572)
			(layers "F.Cu" "F.Mask" "F.Paste")
			(net "P0V8_SERDES_VDDA_PEX3")
		)
		(pad "AF33" smd circle
			(at 7.599934 0.94996)
			(size 0.4572 0.4572)
			(layers "F.Cu" "F.Mask" "F.Paste")
			(net "P0V8_SERDES_VDDA_PEX3")
		)
		(pad "AF34" smd circle
			(at 8.549894 0.94996)
			(size 0.4572 0.4572)
			(layers "F.Cu" "F.Mask" "F.Paste")
			(net "P0V8_SERDES_VDDA_PEX3")
		)
		(pad "AF35" smd circle
			(at 9.500108 0.94996)
			(size 0.4572 0.4572)
			(layers "F.Cu" "F.Mask" "F.Paste")
			(net "GND")
		)
		(pad "AF36" smd circle
			(at 10.450068 0.94996)
			(size 0.4572 0.4572)
			(layers "F.Cu" "F.Mask" "F.Paste")
			(net "P1V25_PEX3")
		)
		(pad "AF37" smd circle
			(at 11.400028 0.94996)
			(size 0.4572 0.4572)
			(layers "F.Cu" "F.Mask" "F.Paste")
			(net "GND")
		)
		(pad "AF38" smd circle
			(at 12.349988 0.94996)
			(size 0.4572 0.4572)
			(layers "F.Cu" "F.Mask" "F.Paste")
			(net "P1V25_SERDES_VDDPLL_PEX3")
		)
		(pad "AF39" smd circle
			(at 13.299948 0.94996)
			(size 0.4572 0.4572)
			(layers "F.Cu" "F.Mask" "F.Paste")
			(net "GND")
		)
		(pad "AF40" smd circle
			(at 14.249908 0.94996)
			(size 0.4572 0.4572)
			(layers "F.Cu" "F.Mask" "F.Paste")
			(net "GND")
		)
		(pad "AF41" smd circle
			(at 15.200122 0.94996)
			(size 0.4572 0.4572)
			(layers "F.Cu" "F.Mask" "F.Paste")
			(net "Net_1530")
		)
		(pad "AF42" smd circle
			(at 16.150082 0.94996)
			(size 0.4572 0.4572)
			(layers "F.Cu" "F.Mask" "F.Paste")
			(net "Net_1519")
		)
		(pad "AF43" smd circle
			(at 17.100042 0.94996)
			(size 0.4572 0.4572)
			(layers "F.Cu" "F.Mask" "F.Paste")
			(net "GND")
		)
		(pad "AF44" smd circle
			(at 18.050002 0.94996)
			(size 0.4572 0.4572)
			(layers "F.Cu" "F.Mask" "F.Paste")
			(net "GND")
		)
		(pad "AF45" smd circle
			(at 18.999962 0.94996)
			(size 0.4572 0.4572)
			(layers "F.Cu" "F.Mask" "F.Paste")
			(net "GND")
		)
		(pad "AF46" smd circle
			(at 19.949922 0.94996)
			(size 0.4572 0.4572)
			(layers "F.Cu" "F.Mask" "F.Paste")
			(net "GND")
		)
		(pad "AF47" smd circle
			(at 20.899882 0.94996)
			(size 0.4572 0.4572)
			(layers "F.Cu" "F.Mask" "F.Paste")
			(net "GND")
		)
		(pad "AF48" smd circle
			(at 21.850096 0.94996)
			(size 0.4572 0.4572)
			(layers "F.Cu" "F.Mask" "F.Paste")
			(net "Net_1447")
		)
		(pad "AF49" smd circle
			(at 22.800056 0.94996)
			(size 0.4572 0.4572)
			(layers "F.Cu" "F.Mask" "F.Paste")
			(net "Net_1464")
		)
		(pad "AG1" smd circle
			(at -22.800056 1.89992)
			(size 0.4572 0.4572)
			(layers "F.Cu" "F.Mask" "F.Paste")
			(net "Net_5406")
		)
		(pad "AG2" smd circle
			(at -21.850096 1.89992)
			(size 0.4572 0.4572)
			(layers "F.Cu" "F.Mask" "F.Paste")
			(net "Net_5407")
		)
		(pad "AG3" smd circle
			(at -20.899882 1.89992)
			(size 0.4572 0.4572)
			(layers "F.Cu" "F.Mask" "F.Paste")
			(net "GND")
		)
		(pad "AG4" smd circle
			(at -19.949922 1.89992)
			(size 0.4572 0.4572)
			(layers "F.Cu" "F.Mask" "F.Paste")
			(net "GND")
		)
		(pad "AG5" smd circle
			(at -18.999962 1.89992)
			(size 0.4572 0.4572)
			(layers "F.Cu" "F.Mask" "F.Paste")
			(net "GND")
		)
		(pad "AG6" smd circle
			(at -18.050002 1.89992)
			(size 0.4572 0.4572)
			(layers "F.Cu" "F.Mask" "F.Paste")
			(net "GND")
		)
		(pad "AG7" smd circle
			(at -17.100042 1.89992)
			(size 0.4572 0.4572)
			(layers "F.Cu" "F.Mask" "F.Paste")
			(net "SPI_PEX3_RST_N")
		)
		(pad "AG8" smd circle
			(at -16.150082 1.89992)
			(size 0.4572 0.4572)
			(layers "F.Cu" "F.Mask" "F.Paste")
			(net "SPI_PEX3_SDIO2")
		)
		(pad "AG9" smd circle
			(at -15.200122 1.89992)
			(size 0.4572 0.4572)
			(layers "F.Cu" "F.Mask" "F.Paste")
			(net "GND")
		)
		(pad "AG10" smd circle
			(at -14.249908 1.89992)
			(size 0.4572 0.4572)
			(layers "F.Cu" "F.Mask" "F.Paste")
			(net "GND")
		)
		(pad "AG11" smd circle
			(at -13.299948 1.89992)
			(size 0.4572 0.4572)
			(layers "F.Cu" "F.Mask" "F.Paste")
			(net "GND")
		)
		(pad "AG12" smd circle
			(at -12.349988 1.89992)
			(size 0.4572 0.4572)
			(layers "F.Cu" "F.Mask" "F.Paste")
			(net "GND")
		)
		(pad "AG13" smd circle
			(at -11.400028 1.89992)
			(size 0.4572 0.4572)
			(layers "F.Cu" "F.Mask" "F.Paste")
			(net "PCEPLL5_VDDA18_PEX3")
		)
		(pad "AG14" smd circle
			(at -10.450068 1.89992)
			(size 0.4572 0.4572)
			(layers "F.Cu" "F.Mask" "F.Paste")
			(net "GND")
		)
		(pad "AG15" smd circle
			(at -9.500108 1.89992)
			(size 0.4572 0.4572)
			(layers "F.Cu" "F.Mask" "F.Paste")
			(net "P0V8_PEX3")
		)
		(pad "AG16" smd circle
			(at -8.549894 1.89992)
			(size 0.4572 0.4572)
			(layers "F.Cu" "F.Mask" "F.Paste")
			(net "GND")
		)
		(pad "AG17" smd circle
			(at -7.599934 1.89992)
			(size 0.4572 0.4572)
			(layers "F.Cu" "F.Mask" "F.Paste")
			(net "P0V8_PEX3")
		)
		(pad "AG18" smd circle
			(at -6.649974 1.89992)
			(size 0.4572 0.4572)
			(layers "F.Cu" "F.Mask" "F.Paste")
			(net "GND")
		)
		(pad "AG19" smd circle
			(at -5.700014 1.89992)
			(size 0.4572 0.4572)
			(layers "F.Cu" "F.Mask" "F.Paste")
			(net "P0V8_PEX3")
		)
		(pad "AG20" smd circle
			(at -4.750054 1.89992)
			(size 0.4572 0.4572)
			(layers "F.Cu" "F.Mask" "F.Paste")
			(net "GND")
		)
		(pad "AG21" smd circle
			(at -3.800094 1.89992)
			(size 0.4572 0.4572)
			(layers "F.Cu" "F.Mask" "F.Paste")
			(net "P0V8_PEX3")
		)
		(pad "AG22" smd circle
			(at -2.84988 1.89992)
			(size 0.4572 0.4572)
			(layers "F.Cu" "F.Mask" "F.Paste")
			(net "GND")
		)
		(pad "AG23" smd circle
			(at -1.89992 1.89992)
			(size 0.4572 0.4572)
			(layers "F.Cu" "F.Mask" "F.Paste")
			(net "P0V8_PEX3")
		)
		(pad "AG24" smd circle
			(at -0.94996 1.89992)
			(size 0.4572 0.4572)
			(layers "F.Cu" "F.Mask" "F.Paste")
			(net "GND")
		)
		(pad "AG25" smd circle
			(at 0 1.89992)
			(size 0.4572 0.4572)
			(layers "F.Cu" "F.Mask" "F.Paste")
			(net "P0V8_PEX3")
		)
		(pad "AG26" smd circle
			(at 0.94996 1.89992)
			(size 0.4572 0.4572)
			(layers "F.Cu" "F.Mask" "F.Paste")
			(net "GND")
		)
		(pad "AG27" smd circle
			(at 1.89992 1.89992)
			(size 0.4572 0.4572)
			(layers "F.Cu" "F.Mask" "F.Paste")
			(net "P0V8_PEX3")
		)
		(pad "AG28" smd circle
			(at 2.84988 1.89992)
			(size 0.4572 0.4572)
			(layers "F.Cu" "F.Mask" "F.Paste")
			(net "GND")
		)
		(pad "AG29" smd circle
			(at 3.800094 1.89992)
			(size 0.4572 0.4572)
			(layers "F.Cu" "F.Mask" "F.Paste")
			(net "P0V8_PEX3")
		)
		(pad "AG30" smd circle
			(at 4.750054 1.89992)
			(size 0.4572 0.4572)
			(layers "F.Cu" "F.Mask" "F.Paste")
			(net "GND")
		)
		(pad "AG31" smd circle
			(at 5.700014 1.89992)
			(size 0.4572 0.4572)
			(layers "F.Cu" "F.Mask" "F.Paste")
			(net "P0V8_PEX3")
		)
		(pad "AG32" smd circle
			(at 6.649974 1.89992)
			(size 0.4572 0.4572)
			(layers "F.Cu" "F.Mask" "F.Paste")
			(net "GND")
		)
		(pad "AG33" smd circle
			(at 7.599934 1.89992)
			(size 0.4572 0.4572)
			(layers "F.Cu" "F.Mask" "F.Paste")
			(net "P0V8_PEX3")
		)
		(pad "AG34" smd circle
			(at 8.549894 1.89992)
			(size 0.4572 0.4572)
			(layers "F.Cu" "F.Mask" "F.Paste")
			(net "GND")
		)
		(pad "AG35" smd circle
			(at 9.500108 1.89992)
			(size 0.4572 0.4572)
			(layers "F.Cu" "F.Mask" "F.Paste")
			(net "GND")
		)
		(pad "AG36" smd circle
			(at 10.450068 1.89992)
			(size 0.4572 0.4572)
			(layers "F.Cu" "F.Mask" "F.Paste")
			(net "P1V25_PEX3")
		)
		(pad "AG37" smd circle
			(at 11.400028 1.89992)
			(size 0.4572 0.4572)
			(layers "F.Cu" "F.Mask" "F.Paste")
			(net "GND")
		)
		(pad "AG38" smd circle
			(at 12.349988 1.89992)
			(size 0.4572 0.4572)
			(layers "F.Cu" "F.Mask" "F.Paste")
			(net "P1V25_SERDES_VDDPLL_PEX3")
		)
		(pad "AG39" smd circle
			(at 13.299948 1.89992)
			(size 0.4572 0.4572)
			(layers "F.Cu" "F.Mask" "F.Paste")
			(net "GND")
		)
		(pad "AG40" smd circle
			(at 14.249908 1.89992)
			(size 0.4572 0.4572)
			(layers "F.Cu" "F.Mask" "F.Paste")
			(net "GND")
		)
		(pad "AG41" smd circle
			(at 15.200122 1.89992)
			(size 0.4572 0.4572)
			(layers "F.Cu" "F.Mask" "F.Paste")
			(net "GND")
		)
		(pad "AG42" smd circle
			(at 16.150082 1.89992)
			(size 0.4572 0.4572)
			(layers "F.Cu" "F.Mask" "F.Paste")
			(net "GND")
		)
		(pad "AG43" smd circle
			(at 17.100042 1.89992)
			(size 0.4572 0.4572)
			(layers "F.Cu" "F.Mask" "F.Paste")
			(net "Net_1535")
		)
		(pad "AG44" smd circle
			(at 18.050002 1.89992)
			(size 0.4572 0.4572)
			(layers "F.Cu" "F.Mask" "F.Paste")
			(net "Net_1554")
		)
		(pad "AG45" smd circle
			(at 18.999962 1.89992)
			(size 0.4572 0.4572)
			(layers "F.Cu" "F.Mask" "F.Paste")
			(net "GND")
		)
		(pad "AG46" smd circle
			(at 19.949922 1.89992)
			(size 0.4572 0.4572)
			(layers "F.Cu" "F.Mask" "F.Paste")
			(net "Net_1393")
		)
		(pad "AG47" smd circle
			(at 20.899882 1.89992)
			(size 0.4572 0.4572)
			(layers "F.Cu" "F.Mask" "F.Paste")
			(net "Net_1473")
		)
		(pad "AG48" smd circle
			(at 21.850096 1.89992)
			(size 0.4572 0.4572)
			(layers "F.Cu" "F.Mask" "F.Paste")
			(net "GND")
		)
		(pad "AG49" smd circle
			(at 22.800056 1.89992)
			(size 0.4572 0.4572)
			(layers "F.Cu" "F.Mask" "F.Paste")
			(net "GND")
		)
		(pad "AH1" smd circle
			(at -22.800056 2.84988)
			(size 0.4572 0.4572)
			(layers "F.Cu" "F.Mask" "F.Paste")
			(net "GND")
		)
		(pad "AH2" smd circle
			(at -21.850096 2.84988)
			(size 0.4572 0.4572)
			(layers "F.Cu" "F.Mask" "F.Paste")
			(net "GND")
		)
		(pad "AH3" smd circle
			(at -20.899882 2.84988)
			(size 0.4572 0.4572)
			(layers "F.Cu" "F.Mask" "F.Paste")
			(net "GND")
		)
		(pad "AH4" smd circle
			(at -19.949922 2.84988)
			(size 0.4572 0.4572)
			(layers "F.Cu" "F.Mask" "F.Paste")
			(net "Net_5409")
		)
		(pad "AH5" smd circle
			(at -18.999962 2.84988)
			(size 0.4572 0.4572)
			(layers "F.Cu" "F.Mask" "F.Paste")
			(net "Net_5410")
		)
		(pad "AH6" smd circle
			(at -18.050002 2.84988)
			(size 0.4572 0.4572)
			(layers "F.Cu" "F.Mask" "F.Paste")
			(net "GND")
		)
		(pad "AH7" smd circle
			(at -17.100042 2.84988)
			(size 0.4572 0.4572)
			(layers "F.Cu" "F.Mask" "F.Paste")
			(net "SPI_PEX3_CLK")
		)
		(pad "AH8" smd circle
			(at -16.150082 2.84988)
			(size 0.4572 0.4572)
			(layers "F.Cu" "F.Mask" "F.Paste")
			(net "SPI_PEX3_SDIO3")
		)
		(pad "AH9" smd circle
			(at -15.200122 2.84988)
			(size 0.4572 0.4572)
			(layers "F.Cu" "F.Mask" "F.Paste")
			(net "GND")
		)
		(pad "AH10" smd circle
			(at -14.249908 2.84988)
			(size 0.4572 0.4572)
			(layers "F.Cu" "F.Mask" "F.Paste")
			(net "P1V8_PEX")
		)
		(pad "AH11" smd circle
			(at -13.299948 2.84988)
			(size 0.4572 0.4572)
			(layers "F.Cu" "F.Mask" "F.Paste")
			(net "GND")
		)
		(pad "AH12" smd circle
			(at -12.349988 2.84988)
			(size 0.4572 0.4572)
			(layers "F.Cu" "F.Mask" "F.Paste")
			(net "PCEPLL6_VDDA18_PEX3")
		)
		(pad "AH13" smd circle
			(at -11.400028 2.84988)
			(size 0.4572 0.4572)
			(layers "F.Cu" "F.Mask" "F.Paste")
			(net "GND")
		)
		(pad "AH14" smd circle
			(at -10.450068 2.84988)
			(size 0.4572 0.4572)
			(layers "F.Cu" "F.Mask" "F.Paste")
			(net "P0V8_PEX3")
		)
		(pad "AH15" smd circle
			(at -9.500108 2.84988)
			(size 0.4572 0.4572)
			(layers "F.Cu" "F.Mask" "F.Paste")
			(net "GND")
		)
		(pad "AH16" smd circle
			(at -8.549894 2.84988)
			(size 0.4572 0.4572)
			(layers "F.Cu" "F.Mask" "F.Paste")
			(net "P0V8_SERDES_VDDA_PEX3")
		)
		(pad "AH17" smd circle
			(at -7.599934 2.84988)
			(size 0.4572 0.4572)
			(layers "F.Cu" "F.Mask" "F.Paste")
			(net "P0V8_SERDES_VDDA_PEX3")
		)
		(pad "AH18" smd circle
			(at -6.649974 2.84988)
			(size 0.4572 0.4572)
			(layers "F.Cu" "F.Mask" "F.Paste")
			(net "P0V8_SERDES_VDDA_PEX3")
		)
		(pad "AH19" smd circle
			(at -5.700014 2.84988)
			(size 0.4572 0.4572)
			(layers "F.Cu" "F.Mask" "F.Paste")
			(net "P0V8_SERDES_VDDA_PEX3")
		)
		(pad "AH20" smd circle
			(at -4.750054 2.84988)
			(size 0.4572 0.4572)
			(layers "F.Cu" "F.Mask" "F.Paste")
			(net "P0V8_SERDES_VDDA_PEX3")
		)
		(pad "AH21" smd circle
			(at -3.800094 2.84988)
			(size 0.4572 0.4572)
			(layers "F.Cu" "F.Mask" "F.Paste")
			(net "P0V8_SERDES_VDDA_PEX3")
		)
		(pad "AH22" smd circle
			(at -2.84988 2.84988)
			(size 0.4572 0.4572)
			(layers "F.Cu" "F.Mask" "F.Paste")
			(net "P0V8_SERDES_VDDA_PEX3")
		)
		(pad "AH23" smd circle
			(at -1.89992 2.84988)
			(size 0.4572 0.4572)
			(layers "F.Cu" "F.Mask" "F.Paste")
			(net "P0V8_SERDES_VDDA_PEX3")
		)
		(pad "AH24" smd circle
			(at -0.94996 2.84988)
			(size 0.4572 0.4572)
			(layers "F.Cu" "F.Mask" "F.Paste")
			(net "P0V8_SERDES_VDDA_PEX3")
		)
		(pad "AH25" smd circle
			(at 0 2.84988)
			(size 0.4572 0.4572)
			(layers "F.Cu" "F.Mask" "F.Paste")
			(net "P0V8_SERDES_VDDA_PEX3")
		)
		(pad "AH26" smd circle
			(at 0.94996 2.84988)
			(size 0.4572 0.4572)
			(layers "F.Cu" "F.Mask" "F.Paste")
			(net "P0V8_SERDES_VDDA_PEX3")
		)
		(pad "AH27" smd circle
			(at 1.89992 2.84988)
			(size 0.4572 0.4572)
			(layers "F.Cu" "F.Mask" "F.Paste")
			(net "P0V8_SERDES_VDDA_PEX3")
		)
		(pad "AH28" smd circle
			(at 2.84988 2.84988)
			(size 0.4572 0.4572)
			(layers "F.Cu" "F.Mask" "F.Paste")
			(net "P0V8_SERDES_VDDA_PEX3")
		)
		(pad "AH29" smd circle
			(at 3.800094 2.84988)
			(size 0.4572 0.4572)
			(layers "F.Cu" "F.Mask" "F.Paste")
			(net "P0V8_SERDES_VDDA_PEX3")
		)
		(pad "AH30" smd circle
			(at 4.750054 2.84988)
			(size 0.4572 0.4572)
			(layers "F.Cu" "F.Mask" "F.Paste")
			(net "P0V8_SERDES_VDDA_PEX3")
		)
		(pad "AH31" smd circle
			(at 5.700014 2.84988)
			(size 0.4572 0.4572)
			(layers "F.Cu" "F.Mask" "F.Paste")
			(net "P0V8_SERDES_VDDA_PEX3")
		)
		(pad "AH32" smd circle
			(at 6.649974 2.84988)
			(size 0.4572 0.4572)
			(layers "F.Cu" "F.Mask" "F.Paste")
			(net "P0V8_SERDES_VDDA_PEX3")
		)
		(pad "AH33" smd circle
			(at 7.599934 2.84988)
			(size 0.4572 0.4572)
			(layers "F.Cu" "F.Mask" "F.Paste")
			(net "P0V8_SERDES_VDDA_PEX3")
		)
		(pad "AH34" smd circle
			(at 8.549894 2.84988)
			(size 0.4572 0.4572)
			(layers "F.Cu" "F.Mask" "F.Paste")
			(net "GND")
		)
		(pad "AH35" smd circle
			(at 9.500108 2.84988)
			(size 0.4572 0.4572)
			(layers "F.Cu" "F.Mask" "F.Paste")
			(net "GND")
		)
		(pad "AH36" smd circle
			(at 10.450068 2.84988)
			(size 0.4572 0.4572)
			(layers "F.Cu" "F.Mask" "F.Paste")
			(net "GND")
		)
		(pad "AH37" smd circle
			(at 11.400028 2.84988)
			(size 0.4572 0.4572)
			(layers "F.Cu" "F.Mask" "F.Paste")
			(net "GND")
		)
		(pad "AH38" smd circle
			(at 12.349988 2.84988)
			(size 0.4572 0.4572)
			(layers "F.Cu" "F.Mask" "F.Paste")
			(net "GND")
		)
		(pad "AH39" smd circle
			(at 13.299948 2.84988)
			(size 0.4572 0.4572)
			(layers "F.Cu" "F.Mask" "F.Paste")
			(net "GND")
		)
		(pad "AH40" smd circle
			(at 14.249908 2.84988)
			(size 0.4572 0.4572)
			(layers "F.Cu" "F.Mask" "F.Paste")
			(net "GND")
		)
		(pad "AH41" smd circle
			(at 15.200122 2.84988)
			(size 0.4572 0.4572)
			(layers "F.Cu" "F.Mask" "F.Paste")
			(net "Net_1537")
		)
		(pad "AH42" smd circle
			(at 16.150082 2.84988)
			(size 0.4572 0.4572)
			(layers "F.Cu" "F.Mask" "F.Paste")
			(net "Net_1544")
		)
		(pad "AH43" smd circle
			(at 17.100042 2.84988)
			(size 0.4572 0.4572)
			(layers "F.Cu" "F.Mask" "F.Paste")
			(net "GND")
		)
		(pad "AH44" smd circle
			(at 18.050002 2.84988)
			(size 0.4572 0.4572)
			(layers "F.Cu" "F.Mask" "F.Paste")
			(net "GND")
		)
		(pad "AH45" smd circle
			(at 18.999962 2.84988)
			(size 0.4572 0.4572)
			(layers "F.Cu" "F.Mask" "F.Paste")
			(net "GND")
		)
		(pad "AH46" smd circle
			(at 19.949922 2.84988)
			(size 0.4572 0.4572)
			(layers "F.Cu" "F.Mask" "F.Paste")
			(net "GND")
		)
		(pad "AH47" smd circle
			(at 20.899882 2.84988)
			(size 0.4572 0.4572)
			(layers "F.Cu" "F.Mask" "F.Paste")
			(net "GND")
		)
		(pad "AH48" smd circle
			(at 21.850096 2.84988)
			(size 0.4572 0.4572)
			(layers "F.Cu" "F.Mask" "F.Paste")
			(net "Net_1508")
		)
		(pad "AH49" smd circle
			(at 22.800056 2.84988)
			(size 0.4572 0.4572)
			(layers "F.Cu" "F.Mask" "F.Paste")
			(net "Net_1499")
		)
		(pad "AJ1" smd circle
			(at -22.800056 3.800094)
			(size 0.4572 0.4572)
			(layers "F.Cu" "F.Mask" "F.Paste")
			(net "Net_5412")
		)
		(pad "AJ2" smd circle
			(at -21.850096 3.800094)
			(size 0.4572 0.4572)
			(layers "F.Cu" "F.Mask" "F.Paste")
			(net "Net_5413")
		)
		(pad "AJ3" smd circle
			(at -20.899882 3.800094)
			(size 0.4572 0.4572)
			(layers "F.Cu" "F.Mask" "F.Paste")
			(net "GND")
		)
		(pad "AJ4" smd circle
			(at -19.949922 3.800094)
			(size 0.4572 0.4572)
			(layers "F.Cu" "F.Mask" "F.Paste")
			(net "GND")
		)
		(pad "AJ5" smd circle
			(at -18.999962 3.800094)
			(size 0.4572 0.4572)
			(layers "F.Cu" "F.Mask" "F.Paste")
			(net "GND")
		)
		(pad "AJ6" smd circle
			(at -18.050002 3.800094)
			(size 0.4572 0.4572)
			(layers "F.Cu" "F.Mask" "F.Paste")
			(net "GND")
		)
		(pad "AJ7" smd circle
			(at -17.100042 3.800094)
			(size 0.4572 0.4572)
			(layers "F.Cu" "F.Mask" "F.Paste")
			(net "SPI_PEX3_CS_N")
		)
		(pad "AJ8" smd circle
			(at -16.150082 3.800094)
			(size 0.4572 0.4572)
			(layers "F.Cu" "F.Mask" "F.Paste")
			(net "Net_5483")
		)
		(pad "AJ9" smd circle
			(at -15.200122 3.800094)
			(size 0.4572 0.4572)
			(layers "F.Cu" "F.Mask" "F.Paste")
			(net "GND")
		)
		(pad "AJ10" smd circle
			(at -14.249908 3.800094)
			(size 0.4572 0.4572)
			(layers "F.Cu" "F.Mask" "F.Paste")
			(net "P1V8_PEX")
		)
		(pad "AJ11" smd circle
			(at -13.299948 3.800094)
			(size 0.4572 0.4572)
			(layers "F.Cu" "F.Mask" "F.Paste")
			(net "GND")
		)
		(pad "AJ12" smd circle
			(at -12.349988 3.800094)
			(size 0.4572 0.4572)
			(layers "F.Cu" "F.Mask" "F.Paste")
			(net "GND")
		)
		(pad "AJ13" smd circle
			(at -11.400028 3.800094)
			(size 0.4572 0.4572)
			(layers "F.Cu" "F.Mask" "F.Paste")
			(net "PCEPLL7_VDDA18_PEX3")
		)
		(pad "AJ14" smd circle
			(at -10.450068 3.800094)
			(size 0.4572 0.4572)
			(layers "F.Cu" "F.Mask" "F.Paste")
			(net "GND")
		)
		(pad "AJ15" smd circle
			(at -9.500108 3.800094)
			(size 0.4572 0.4572)
			(layers "F.Cu" "F.Mask" "F.Paste")
			(net "P0V8_PEX3")
		)
		(pad "AJ16" smd circle
			(at -8.549894 3.800094)
			(size 0.4572 0.4572)
			(layers "F.Cu" "F.Mask" "F.Paste")
			(net "GND")
		)
		(pad "AJ17" smd circle
			(at -7.599934 3.800094)
			(size 0.4572 0.4572)
			(layers "F.Cu" "F.Mask" "F.Paste")
			(net "GND")
		)
		(pad "AJ18" smd circle
			(at -6.649974 3.800094)
			(size 0.4572 0.4572)
			(layers "F.Cu" "F.Mask" "F.Paste")
			(net "GND")
		)
		(pad "AJ19" smd circle
			(at -5.700014 3.800094)
			(size 0.4572 0.4572)
			(layers "F.Cu" "F.Mask" "F.Paste")
			(net "GND")
		)
		(pad "AJ20" smd circle
			(at -4.750054 3.800094)
			(size 0.4572 0.4572)
			(layers "F.Cu" "F.Mask" "F.Paste")
			(net "GND")
		)
		(pad "AJ21" smd circle
			(at -3.800094 3.800094)
			(size 0.4572 0.4572)
			(layers "F.Cu" "F.Mask" "F.Paste")
			(net "GND")
		)
		(pad "AJ22" smd circle
			(at -2.84988 3.800094)
			(size 0.4572 0.4572)
			(layers "F.Cu" "F.Mask" "F.Paste")
			(net "GND")
		)
		(pad "AJ23" smd circle
			(at -1.89992 3.800094)
			(size 0.4572 0.4572)
			(layers "F.Cu" "F.Mask" "F.Paste")
			(net "GND")
		)
		(pad "AJ24" smd circle
			(at -0.94996 3.800094)
			(size 0.4572 0.4572)
			(layers "F.Cu" "F.Mask" "F.Paste")
			(net "GND")
		)
		(pad "AJ25" smd circle
			(at 0 3.800094)
			(size 0.4572 0.4572)
			(layers "F.Cu" "F.Mask" "F.Paste")
			(net "GND")
		)
		(pad "AJ26" smd circle
			(at 0.94996 3.800094)
			(size 0.4572 0.4572)
			(layers "F.Cu" "F.Mask" "F.Paste")
			(net "GND")
		)
		(pad "AJ27" smd circle
			(at 1.89992 3.800094)
			(size 0.4572 0.4572)
			(layers "F.Cu" "F.Mask" "F.Paste")
			(net "GND")
		)
		(pad "AJ28" smd circle
			(at 2.84988 3.800094)
			(size 0.4572 0.4572)
			(layers "F.Cu" "F.Mask" "F.Paste")
			(net "GND")
		)
		(pad "AJ29" smd circle
			(at 3.800094 3.800094)
			(size 0.4572 0.4572)
			(layers "F.Cu" "F.Mask" "F.Paste")
			(net "GND")
		)
		(pad "AJ30" smd circle
			(at 4.750054 3.800094)
			(size 0.4572 0.4572)
			(layers "F.Cu" "F.Mask" "F.Paste")
			(net "GND")
		)
		(pad "AJ31" smd circle
			(at 5.700014 3.800094)
			(size 0.4572 0.4572)
			(layers "F.Cu" "F.Mask" "F.Paste")
			(net "GND")
		)
		(pad "AJ32" smd circle
			(at 6.649974 3.800094)
			(size 0.4572 0.4572)
			(layers "F.Cu" "F.Mask" "F.Paste")
			(net "GND")
		)
		(pad "AJ33" smd circle
			(at 7.599934 3.800094)
			(size 0.4572 0.4572)
			(layers "F.Cu" "F.Mask" "F.Paste")
			(net "GND")
		)
		(pad "AJ34" smd circle
			(at 8.549894 3.800094)
			(size 0.4572 0.4572)
			(layers "F.Cu" "F.Mask" "F.Paste")
			(net "GND")
		)
		(pad "AJ35" smd circle
			(at 9.500108 3.800094)
			(size 0.4572 0.4572)
			(layers "F.Cu" "F.Mask" "F.Paste")
			(net "GND")
		)
		(pad "AJ36" smd circle
			(at 10.450068 3.800094)
			(size 0.4572 0.4572)
			(layers "F.Cu" "F.Mask" "F.Paste")
			(net "GND")
		)
		(pad "AJ37" smd circle
			(at 11.400028 3.800094)
			(size 0.4572 0.4572)
			(layers "F.Cu" "F.Mask" "F.Paste")
			(net "GND")
		)
		(pad "AJ38" smd circle
			(at 12.349988 3.800094)
			(size 0.4572 0.4572)
			(layers "F.Cu" "F.Mask" "F.Paste")
			(net "UART_PEX3_CLI_TX")
		)
		(pad "AJ39" smd circle
			(at 13.299948 3.800094)
			(size 0.4572 0.4572)
			(layers "F.Cu" "F.Mask" "F.Paste")
			(net "Net_5418")
		)
		(pad "AJ40" smd circle
			(at 14.249908 3.800094)
			(size 0.4572 0.4572)
			(layers "F.Cu" "F.Mask" "F.Paste")
			(net "GND")
		)
		(pad "AJ41" smd circle
			(at 15.200122 3.800094)
			(size 0.4572 0.4572)
			(layers "F.Cu" "F.Mask" "F.Paste")
			(net "GND")
		)
		(pad "AJ42" smd circle
			(at 16.150082 3.800094)
			(size 0.4572 0.4572)
			(layers "F.Cu" "F.Mask" "F.Paste")
			(net "GND")
		)
		(pad "AJ43" smd circle
			(at 17.100042 3.800094)
			(size 0.4572 0.4572)
			(layers "F.Cu" "F.Mask" "F.Paste")
			(net "Net_1516")
		)
		(pad "AJ44" smd circle
			(at 18.050002 3.800094)
			(size 0.4572 0.4572)
			(layers "F.Cu" "F.Mask" "F.Paste")
			(net "Net_1555")
		)
		(pad "AJ45" smd circle
			(at 18.999962 3.800094)
			(size 0.4572 0.4572)
			(layers "F.Cu" "F.Mask" "F.Paste")
			(net "GND")
		)
		(pad "AJ46" smd circle
			(at 19.949922 3.800094)
			(size 0.4572 0.4572)
			(layers "F.Cu" "F.Mask" "F.Paste")
			(net "Net_1509")
		)
		(pad "AJ47" smd circle
			(at 20.899882 3.800094)
			(size 0.4572 0.4572)
			(layers "F.Cu" "F.Mask" "F.Paste")
			(net "Net_1438")
		)
		(pad "AJ48" smd circle
			(at 21.850096 3.800094)
			(size 0.4572 0.4572)
			(layers "F.Cu" "F.Mask" "F.Paste")
			(net "GND")
		)
		(pad "AJ49" smd circle
			(at 22.800056 3.800094)
			(size 0.4572 0.4572)
			(layers "F.Cu" "F.Mask" "F.Paste")
			(net "GND")
		)
		(pad "AK1" smd circle
			(at -22.800056 4.750054)
			(size 0.4572 0.4572)
			(layers "F.Cu" "F.Mask" "F.Paste")
			(net "GND")
		)
		(pad "AK2" smd circle
			(at -21.850096 4.750054)
			(size 0.4572 0.4572)
			(layers "F.Cu" "F.Mask" "F.Paste")
			(net "GND")
		)
		(pad "AK3" smd circle
			(at -20.899882 4.750054)
			(size 0.4572 0.4572)
			(layers "F.Cu" "F.Mask" "F.Paste")
			(net "GND")
		)
		(pad "AK4" smd circle
			(at -19.949922 4.750054)
			(size 0.4572 0.4572)
			(layers "F.Cu" "F.Mask" "F.Paste")
			(net "Net_539")
		)
		(pad "AK5" smd circle
			(at -18.999962 4.750054)
			(size 0.4572 0.4572)
			(layers "F.Cu" "F.Mask" "F.Paste")
			(net "Net_535")
		)
		(pad "AK6" smd circle
			(at -18.050002 4.750054)
			(size 0.4572 0.4572)
			(layers "F.Cu" "F.Mask" "F.Paste")
			(net "GND")
		)
		(pad "AK7" smd circle
			(at -17.100042 4.750054)
			(size 0.4572 0.4572)
			(layers "F.Cu" "F.Mask" "F.Paste")
			(net "Net_5482")
		)
		(pad "AK8" smd circle
			(at -16.150082 4.750054)
			(size 0.4572 0.4572)
			(layers "F.Cu" "F.Mask" "F.Paste")
			(net "GND")
		)
		(pad "AK9" smd circle
			(at -15.200122 4.750054)
			(size 0.4572 0.4572)
			(layers "F.Cu" "F.Mask" "F.Paste")
			(net "GND")
		)
		(pad "AK10" smd circle
			(at -14.249908 4.750054)
			(size 0.4572 0.4572)
			(layers "F.Cu" "F.Mask" "F.Paste")
			(net "P1V8_PEX")
		)
		(pad "AK11" smd circle
			(at -13.299948 4.750054)
			(size 0.4572 0.4572)
			(layers "F.Cu" "F.Mask" "F.Paste")
			(net "GND")
		)
		(pad "AK12" smd circle
			(at -12.349988 4.750054)
			(size 0.4572 0.4572)
			(layers "F.Cu" "F.Mask" "F.Paste")
			(net "P1V8_PEX")
		)
		(pad "AK13" smd circle
			(at -11.400028 4.750054)
			(size 0.4572 0.4572)
			(layers "F.Cu" "F.Mask" "F.Paste")
			(net "GND")
		)
		(pad "AK14" smd circle
			(at -10.450068 4.750054)
			(size 0.4572 0.4572)
			(layers "F.Cu" "F.Mask" "F.Paste")
			(net "P0V8_PEX3")
		)
		(pad "AK15" smd circle
			(at -9.500108 4.750054)
			(size 0.4572 0.4572)
			(layers "F.Cu" "F.Mask" "F.Paste")
			(net "GND")
		)
		(pad "AK16" smd circle
			(at -8.549894 4.750054)
			(size 0.4572 0.4572)
			(layers "F.Cu" "F.Mask" "F.Paste")
			(net "P0V8_SERDES_VDDA_PEX3")
		)
		(pad "AK17" smd circle
			(at -7.599934 4.750054)
			(size 0.4572 0.4572)
			(layers "F.Cu" "F.Mask" "F.Paste")
			(net "P0V8_SERDES_VDDA_PEX3")
		)
		(pad "AK18" smd circle
			(at -6.649974 4.750054)
			(size 0.4572 0.4572)
			(layers "F.Cu" "F.Mask" "F.Paste")
			(net "P0V8_SERDES_VDDA_PEX3")
		)
		(pad "AK19" smd circle
			(at -5.700014 4.750054)
			(size 0.4572 0.4572)
			(layers "F.Cu" "F.Mask" "F.Paste")
			(net "P0V8_SERDES_VDDA_PEX3")
		)
		(pad "AK20" smd circle
			(at -4.750054 4.750054)
			(size 0.4572 0.4572)
			(layers "F.Cu" "F.Mask" "F.Paste")
			(net "P0V8_SERDES_VDDA_PEX3")
		)
		(pad "AK21" smd circle
			(at -3.800094 4.750054)
			(size 0.4572 0.4572)
			(layers "F.Cu" "F.Mask" "F.Paste")
			(net "P0V8_SERDES_VDDA_PEX3")
		)
		(pad "AK22" smd circle
			(at -2.84988 4.750054)
			(size 0.4572 0.4572)
			(layers "F.Cu" "F.Mask" "F.Paste")
			(net "P0V8_SERDES_VDDA_PEX3")
		)
		(pad "AK23" smd circle
			(at -1.89992 4.750054)
			(size 0.4572 0.4572)
			(layers "F.Cu" "F.Mask" "F.Paste")
			(net "P0V8_SERDES_VDDA_PEX3")
		)
		(pad "AK24" smd circle
			(at -0.94996 4.750054)
			(size 0.4572 0.4572)
			(layers "F.Cu" "F.Mask" "F.Paste")
			(net "P0V8_SERDES_VDDA_PEX3")
		)
		(pad "AK25" smd circle
			(at 0 4.750054)
			(size 0.4572 0.4572)
			(layers "F.Cu" "F.Mask" "F.Paste")
			(net "P0V8_SERDES_VDDA_PEX3")
		)
		(pad "AK26" smd circle
			(at 0.94996 4.750054)
			(size 0.4572 0.4572)
			(layers "F.Cu" "F.Mask" "F.Paste")
			(net "P0V8_SERDES_VDDA_PEX3")
		)
		(pad "AK27" smd circle
			(at 1.89992 4.750054)
			(size 0.4572 0.4572)
			(layers "F.Cu" "F.Mask" "F.Paste")
			(net "P0V8_SERDES_VDDA_PEX3")
		)
		(pad "AK28" smd circle
			(at 2.84988 4.750054)
			(size 0.4572 0.4572)
			(layers "F.Cu" "F.Mask" "F.Paste")
			(net "P0V8_SERDES_VDDA_PEX3")
		)
		(pad "AK29" smd circle
			(at 3.800094 4.750054)
			(size 0.4572 0.4572)
			(layers "F.Cu" "F.Mask" "F.Paste")
			(net "P0V8_SERDES_VDDA_PEX3")
		)
		(pad "AK30" smd circle
			(at 4.750054 4.750054)
			(size 0.4572 0.4572)
			(layers "F.Cu" "F.Mask" "F.Paste")
			(net "P0V8_SERDES_VDDA_PEX3")
		)
		(pad "AK31" smd circle
			(at 5.700014 4.750054)
			(size 0.4572 0.4572)
			(layers "F.Cu" "F.Mask" "F.Paste")
			(net "P0V8_SERDES_VDDA_PEX3")
		)
		(pad "AK32" smd circle
			(at 6.649974 4.750054)
			(size 0.4572 0.4572)
			(layers "F.Cu" "F.Mask" "F.Paste")
			(net "P0V8_SERDES_VDDA_PEX3")
		)
		(pad "AK33" smd circle
			(at 7.599934 4.750054)
			(size 0.4572 0.4572)
			(layers "F.Cu" "F.Mask" "F.Paste")
			(net "P0V8_SERDES_VDDA_PEX3")
		)
		(pad "AK34" smd circle
			(at 8.549894 4.750054)
			(size 0.4572 0.4572)
			(layers "F.Cu" "F.Mask" "F.Paste")
			(net "GND")
		)
		(pad "AK35" smd circle
			(at 9.500108 4.750054)
			(size 0.4572 0.4572)
			(layers "F.Cu" "F.Mask" "F.Paste")
			(net "P1V8_PEX")
		)
		(pad "AK36" smd circle
			(at 10.450068 4.750054)
			(size 0.4572 0.4572)
			(layers "F.Cu" "F.Mask" "F.Paste")
			(net "GND")
		)
		(pad "AK37" smd circle
			(at 11.400028 4.750054)
			(size 0.4572 0.4572)
			(layers "F.Cu" "F.Mask" "F.Paste")
			(net "GND")
		)
		(pad "AK38" smd circle
			(at 12.349988 4.750054)
			(size 0.4572 0.4572)
			(layers "F.Cu" "F.Mask" "F.Paste")
			(net "UART_PEX3_CLI_BUF_RX")
		)
		(pad "AK39" smd circle
			(at 13.299948 4.750054)
			(size 0.4572 0.4572)
			(layers "F.Cu" "F.Mask" "F.Paste")
			(net "UART_PEX3_SDB_BUF_RX")
		)
		(pad "AK40" smd circle
			(at 14.249908 4.750054)
			(size 0.4572 0.4572)
			(layers "F.Cu" "F.Mask" "F.Paste")
			(net "GND")
		)
		(pad "AK41" smd circle
			(at 15.200122 4.750054)
			(size 0.4572 0.4572)
			(layers "F.Cu" "F.Mask" "F.Paste")
			(net "Net_1541")
		)
		(pad "AK42" smd circle
			(at 16.150082 4.750054)
			(size 0.4572 0.4572)
			(layers "F.Cu" "F.Mask" "F.Paste")
			(net "Net_1520")
		)
		(pad "AK43" smd circle
			(at 17.100042 4.750054)
			(size 0.4572 0.4572)
			(layers "F.Cu" "F.Mask" "F.Paste")
			(net "GND")
		)
		(pad "AK44" smd circle
			(at 18.050002 4.750054)
			(size 0.4572 0.4572)
			(layers "F.Cu" "F.Mask" "F.Paste")
			(net "GND")
		)
		(pad "AK45" smd circle
			(at 18.999962 4.750054)
			(size 0.4572 0.4572)
			(layers "F.Cu" "F.Mask" "F.Paste")
			(net "GND")
		)
		(pad "AK46" smd circle
			(at 19.949922 4.750054)
			(size 0.4572 0.4572)
			(layers "F.Cu" "F.Mask" "F.Paste")
			(net "GND")
		)
		(pad "AK47" smd circle
			(at 20.899882 4.750054)
			(size 0.4572 0.4572)
			(layers "F.Cu" "F.Mask" "F.Paste")
			(net "GND")
		)
		(pad "AK48" smd circle
			(at 21.850096 4.750054)
			(size 0.4572 0.4572)
			(layers "F.Cu" "F.Mask" "F.Paste")
			(net "Net_1494")
		)
		(pad "AK49" smd circle
			(at 22.800056 4.750054)
			(size 0.4572 0.4572)
			(layers "F.Cu" "F.Mask" "F.Paste")
			(net "Net_1480")
		)
		(pad "AL1" smd circle
			(at -22.800056 5.700014)
			(size 0.4572 0.4572)
			(layers "F.Cu" "F.Mask" "F.Paste")
			(net "GND")
		)
		(pad "AL2" smd circle
			(at -21.850096 5.700014)
			(size 0.4572 0.4572)
			(layers "F.Cu" "F.Mask" "F.Paste")
			(net "GND")
		)
		(pad "AL3" smd circle
			(at -20.899882 5.700014)
			(size 0.4572 0.4572)
			(layers "F.Cu" "F.Mask" "F.Paste")
			(net "GND")
		)
		(pad "AL4" smd circle
			(at -19.949922 5.700014)
			(size 0.4572 0.4572)
			(layers "F.Cu" "F.Mask" "F.Paste")
			(net "GND")
		)
		(pad "AL5" smd circle
			(at -18.999962 5.700014)
			(size 0.4572 0.4572)
			(layers "F.Cu" "F.Mask" "F.Paste")
			(net "GND")
		)
		(pad "AL6" smd circle
			(at -18.050002 5.700014)
			(size 0.4572 0.4572)
			(layers "F.Cu" "F.Mask" "F.Paste")
			(net "GND")
		)
		(pad "AL7" smd circle
			(at -17.100042 5.700014)
			(size 0.4572 0.4572)
			(layers "F.Cu" "F.Mask" "F.Paste")
			(net "GND")
		)
		(pad "AL8" smd circle
			(at -16.150082 5.700014)
			(size 0.4572 0.4572)
			(layers "F.Cu" "F.Mask" "F.Paste")
			(net "GND")
		)
		(pad "AL9" smd circle
			(at -15.200122 5.700014)
			(size 0.4572 0.4572)
			(layers "F.Cu" "F.Mask" "F.Paste")
			(net "GND")
		)
		(pad "AL10" smd circle
			(at -14.249908 5.700014)
			(size 0.4572 0.4572)
			(layers "F.Cu" "F.Mask" "F.Paste")
			(net "GND")
		)
		(pad "AL11" smd circle
			(at -13.299948 5.700014)
			(size 0.4572 0.4572)
			(layers "F.Cu" "F.Mask" "F.Paste")
			(net "GND")
		)
		(pad "AL12" smd circle
			(at -12.349988 5.700014)
			(size 0.4572 0.4572)
			(layers "F.Cu" "F.Mask" "F.Paste")
			(net "GND")
		)
		(pad "AL13" smd circle
			(at -11.400028 5.700014)
			(size 0.4572 0.4572)
			(layers "F.Cu" "F.Mask" "F.Paste")
			(net "GND")
		)
		(pad "AL14" smd circle
			(at -10.450068 5.700014)
			(size 0.4572 0.4572)
			(layers "F.Cu" "F.Mask" "F.Paste")
			(net "VSSA_SENSE")
		)
		(pad "AL15" smd circle
			(at -9.500108 5.700014)
			(size 0.4572 0.4572)
			(layers "F.Cu" "F.Mask" "F.Paste")
			(net "VDDA_SENSE")
		)
		(pad "AL16" smd circle
			(at -8.549894 5.700014)
			(size 0.4572 0.4572)
			(layers "F.Cu" "F.Mask" "F.Paste")
			(net "GND")
		)
		(pad "AL17" smd circle
			(at -7.599934 5.700014)
			(size 0.4572 0.4572)
			(layers "F.Cu" "F.Mask" "F.Paste")
			(net "GND")
		)
		(pad "AL18" smd circle
			(at -6.649974 5.700014)
			(size 0.4572 0.4572)
			(layers "F.Cu" "F.Mask" "F.Paste")
			(net "GND")
		)
		(pad "AL19" smd circle
			(at -5.700014 5.700014)
			(size 0.4572 0.4572)
			(layers "F.Cu" "F.Mask" "F.Paste")
			(net "GND")
		)
		(pad "AL20" smd circle
			(at -4.750054 5.700014)
			(size 0.4572 0.4572)
			(layers "F.Cu" "F.Mask" "F.Paste")
			(net "GND")
		)
		(pad "AL21" smd circle
			(at -3.800094 5.700014)
			(size 0.4572 0.4572)
			(layers "F.Cu" "F.Mask" "F.Paste")
			(net "GND")
		)
		(pad "AL22" smd circle
			(at -2.84988 5.700014)
			(size 0.4572 0.4572)
			(layers "F.Cu" "F.Mask" "F.Paste")
			(net "GND")
		)
		(pad "AL23" smd circle
			(at -1.89992 5.700014)
			(size 0.4572 0.4572)
			(layers "F.Cu" "F.Mask" "F.Paste")
			(net "GND")
		)
		(pad "AL24" smd circle
			(at -0.94996 5.700014)
			(size 0.4572 0.4572)
			(layers "F.Cu" "F.Mask" "F.Paste")
			(net "GND")
		)
		(pad "AL25" smd circle
			(at 0 5.700014)
			(size 0.4572 0.4572)
			(layers "F.Cu" "F.Mask" "F.Paste")
			(net "GND")
		)
		(pad "AL26" smd circle
			(at 0.94996 5.700014)
			(size 0.4572 0.4572)
			(layers "F.Cu" "F.Mask" "F.Paste")
			(net "GND")
		)
		(pad "AL27" smd circle
			(at 1.89992 5.700014)
			(size 0.4572 0.4572)
			(layers "F.Cu" "F.Mask" "F.Paste")
			(net "GND")
		)
		(pad "AL28" smd circle
			(at 2.84988 5.700014)
			(size 0.4572 0.4572)
			(layers "F.Cu" "F.Mask" "F.Paste")
			(net "GND")
		)
		(pad "AL29" smd circle
			(at 3.800094 5.700014)
			(size 0.4572 0.4572)
			(layers "F.Cu" "F.Mask" "F.Paste")
			(net "GND")
		)
		(pad "AL30" smd circle
			(at 4.750054 5.700014)
			(size 0.4572 0.4572)
			(layers "F.Cu" "F.Mask" "F.Paste")
			(net "GND")
		)
		(pad "AL31" smd circle
			(at 5.700014 5.700014)
			(size 0.4572 0.4572)
			(layers "F.Cu" "F.Mask" "F.Paste")
			(net "GND")
		)
		(pad "AL32" smd circle
			(at 6.649974 5.700014)
			(size 0.4572 0.4572)
			(layers "F.Cu" "F.Mask" "F.Paste")
			(net "GND")
		)
		(pad "AL33" smd circle
			(at 7.599934 5.700014)
			(size 0.4572 0.4572)
			(layers "F.Cu" "F.Mask" "F.Paste")
			(net "GND")
		)
		(pad "AL34" smd circle
			(at 8.549894 5.700014)
			(size 0.4572 0.4572)
			(layers "F.Cu" "F.Mask" "F.Paste")
			(net "GND")
		)
		(pad "AL35" smd circle
			(at 9.500108 5.700014)
			(size 0.4572 0.4572)
			(layers "F.Cu" "F.Mask" "F.Paste")
			(net "P1V8_PEX")
		)
		(pad "AL36" smd circle
			(at 10.450068 5.700014)
			(size 0.4572 0.4572)
			(layers "F.Cu" "F.Mask" "F.Paste")
			(net "GND")
		)
		(pad "AL37" smd circle
			(at 11.400028 5.700014)
			(size 0.4572 0.4572)
			(layers "F.Cu" "F.Mask" "F.Paste")
			(net "GND")
		)
		(pad "AL38" smd circle
			(at 12.349988 5.700014)
			(size 0.4572 0.4572)
			(layers "F.Cu" "F.Mask" "F.Paste")
			(net "Net_5449")
		)
		(pad "AL39" smd circle
			(at 13.299948 5.700014)
			(size 0.4572 0.4572)
			(layers "F.Cu" "F.Mask" "F.Paste")
			(net "UART_PEX3_SDB_TX")
		)
		(pad "AL40" smd circle
			(at 14.249908 5.700014)
			(size 0.4572 0.4572)
			(layers "F.Cu" "F.Mask" "F.Paste")
			(net "GND")
		)
		(pad "AL41" smd circle
			(at 15.200122 5.700014)
			(size 0.4572 0.4572)
			(layers "F.Cu" "F.Mask" "F.Paste")
			(net "GND")
		)
		(pad "AL42" smd circle
			(at 16.150082 5.700014)
			(size 0.4572 0.4572)
			(layers "F.Cu" "F.Mask" "F.Paste")
			(net "GND")
		)
		(pad "AL43" smd circle
			(at 17.100042 5.700014)
			(size 0.4572 0.4572)
			(layers "F.Cu" "F.Mask" "F.Paste")
			(net "Net_1525")
		)
		(pad "AL44" smd circle
			(at 18.050002 5.700014)
			(size 0.4572 0.4572)
			(layers "F.Cu" "F.Mask" "F.Paste")
			(net "Net_1517")
		)
		(pad "AL45" smd circle
			(at 18.999962 5.700014)
			(size 0.4572 0.4572)
			(layers "F.Cu" "F.Mask" "F.Paste")
			(net "GND")
		)
		(pad "AL46" smd circle
			(at 19.949922 5.700014)
			(size 0.4572 0.4572)
			(layers "F.Cu" "F.Mask" "F.Paste")
			(net "Net_1444")
		)
		(pad "AL47" smd circle
			(at 20.899882 5.700014)
			(size 0.4572 0.4572)
			(layers "F.Cu" "F.Mask" "F.Paste")
			(net "Net_1504")
		)
		(pad "AL48" smd circle
			(at 21.850096 5.700014)
			(size 0.4572 0.4572)
			(layers "F.Cu" "F.Mask" "F.Paste")
			(net "GND")
		)
		(pad "AL49" smd circle
			(at 22.800056 5.700014)
			(size 0.4572 0.4572)
			(layers "F.Cu" "F.Mask" "F.Paste")
			(net "GND")
		)
		(pad "AM1" smd circle
			(at -22.800056 6.649974)
			(size 0.4572 0.4572)
			(layers "F.Cu" "F.Mask" "F.Paste")
			(net "Net_1413")
		)
		(pad "AM2" smd circle
			(at -21.850096 6.649974)
			(size 0.4572 0.4572)
			(layers "F.Cu" "F.Mask" "F.Paste")
			(net "Net_1443")
		)
		(pad "AM3" smd circle
			(at -20.899882 6.649974)
			(size 0.4572 0.4572)
			(layers "F.Cu" "F.Mask" "F.Paste")
			(net "GND")
		)
		(pad "AM4" smd circle
			(at -19.949922 6.649974)
			(size 0.4572 0.4572)
			(layers "F.Cu" "F.Mask" "F.Paste")
			(net "GND")
		)
		(pad "AM5" smd circle
			(at -18.999962 6.649974)
			(size 0.4572 0.4572)
			(layers "F.Cu" "F.Mask" "F.Paste")
			(net "GND")
		)
		(pad "AM6" smd circle
			(at -18.050002 6.649974)
			(size 0.4572 0.4572)
			(layers "F.Cu" "F.Mask" "F.Paste")
			(net "GND")
		)
		(pad "AM7" smd circle
			(at -17.100042 6.649974)
			(size 0.4572 0.4572)
			(layers "F.Cu" "F.Mask" "F.Paste")
			(net "GND")
		)
		(pad "AM8" smd circle
			(at -16.150082 6.649974)
			(size 0.4572 0.4572)
			(layers "F.Cu" "F.Mask" "F.Paste")
			(net "Net_1471")
		)
		(pad "AM9" smd circle
			(at -15.200122 6.649974)
			(size 0.4572 0.4572)
			(layers "F.Cu" "F.Mask" "F.Paste")
			(net "Net_1437")
		)
		(pad "AM10" smd circle
			(at -14.249908 6.649974)
			(size 0.4572 0.4572)
			(layers "F.Cu" "F.Mask" "F.Paste")
			(net "GND")
		)
		(pad "AM11" smd circle
			(at -13.299948 6.649974)
			(size 0.4572 0.4572)
			(layers "F.Cu" "F.Mask" "F.Paste")
			(net "GND")
		)
		(pad "AM12" smd circle
			(at -12.349988 6.649974)
			(size 0.4572 0.4572)
			(layers "F.Cu" "F.Mask" "F.Paste")
			(net "TP_PEX3_VDDQ_EFUSE")
		)
		(pad "AM13" smd circle
			(at -11.400028 6.649974)
			(size 0.4572 0.4572)
			(layers "F.Cu" "F.Mask" "F.Paste")
			(net "GND")
		)
		(pad "AM14" smd circle
			(at -10.450068 6.649974)
			(size 0.4572 0.4572)
			(layers "F.Cu" "F.Mask" "F.Paste")
			(net "P1V8_VDDA_PEX3")
		)
		(pad "AM15" smd circle
			(at -9.500108 6.649974)
			(size 0.4572 0.4572)
			(layers "F.Cu" "F.Mask" "F.Paste")
			(net "GND")
		)
		(pad "AM16" smd circle
			(at -8.549894 6.649974)
			(size 0.4572 0.4572)
			(layers "F.Cu" "F.Mask" "F.Paste")
			(net "P1V25_PEX3")
		)
		(pad "AM17" smd circle
			(at -7.599934 6.649974)
			(size 0.4572 0.4572)
			(layers "F.Cu" "F.Mask" "F.Paste")
			(net "P1V25_PEX3")
		)
		(pad "AM18" smd circle
			(at -6.649974 6.649974)
			(size 0.4572 0.4572)
			(layers "F.Cu" "F.Mask" "F.Paste")
			(net "P1V25_PEX3")
		)
		(pad "AM19" smd circle
			(at -5.700014 6.649974)
			(size 0.4572 0.4572)
			(layers "F.Cu" "F.Mask" "F.Paste")
			(net "P1V25_PEX3")
		)
		(pad "AM20" smd circle
			(at -4.750054 6.649974)
			(size 0.4572 0.4572)
			(layers "F.Cu" "F.Mask" "F.Paste")
			(net "P1V25_PEX3")
		)
		(pad "AM21" smd circle
			(at -3.800094 6.649974)
			(size 0.4572 0.4572)
			(layers "F.Cu" "F.Mask" "F.Paste")
			(net "P1V25_PEX3")
		)
		(pad "AM22" smd circle
			(at -2.84988 6.649974)
			(size 0.4572 0.4572)
			(layers "F.Cu" "F.Mask" "F.Paste")
			(net "P1V25_PEX3")
		)
		(pad "AM23" smd circle
			(at -1.89992 6.649974)
			(size 0.4572 0.4572)
			(layers "F.Cu" "F.Mask" "F.Paste")
			(net "P1V25_PEX3")
		)
		(pad "AM24" smd circle
			(at -0.94996 6.649974)
			(size 0.4572 0.4572)
			(layers "F.Cu" "F.Mask" "F.Paste")
			(net "P1V25_PEX3")
		)
		(pad "AM25" smd circle
			(at 0 6.649974)
			(size 0.4572 0.4572)
			(layers "F.Cu" "F.Mask" "F.Paste")
			(net "P1V25_PEX3")
		)
		(pad "AM26" smd circle
			(at 0.94996 6.649974)
			(size 0.4572 0.4572)
			(layers "F.Cu" "F.Mask" "F.Paste")
			(net "P1V25_PEX3")
		)
		(pad "AM27" smd circle
			(at 1.89992 6.649974)
			(size 0.4572 0.4572)
			(layers "F.Cu" "F.Mask" "F.Paste")
			(net "P1V25_PEX3")
		)
		(pad "AM28" smd circle
			(at 2.84988 6.649974)
			(size 0.4572 0.4572)
			(layers "F.Cu" "F.Mask" "F.Paste")
			(net "P1V25_PEX3")
		)
		(pad "AM29" smd circle
			(at 3.800094 6.649974)
			(size 0.4572 0.4572)
			(layers "F.Cu" "F.Mask" "F.Paste")
			(net "P1V25_PEX3")
		)
		(pad "AM30" smd circle
			(at 4.750054 6.649974)
			(size 0.4572 0.4572)
			(layers "F.Cu" "F.Mask" "F.Paste")
			(net "P1V25_PEX3")
		)
		(pad "AM31" smd circle
			(at 5.700014 6.649974)
			(size 0.4572 0.4572)
			(layers "F.Cu" "F.Mask" "F.Paste")
			(net "P1V25_PEX3")
		)
		(pad "AM32" smd circle
			(at 6.649974 6.649974)
			(size 0.4572 0.4572)
			(layers "F.Cu" "F.Mask" "F.Paste")
			(net "P1V25_PEX3")
		)
		(pad "AM33" smd circle
			(at 7.599934 6.649974)
			(size 0.4572 0.4572)
			(layers "F.Cu" "F.Mask" "F.Paste")
			(net "P1V25_PEX3")
		)
		(pad "AM34" smd circle
			(at 8.549894 6.649974)
			(size 0.4572 0.4572)
			(layers "F.Cu" "F.Mask" "F.Paste")
			(net "GND")
		)
		(pad "AM35" smd circle
			(at 9.500108 6.649974)
			(size 0.4572 0.4572)
			(layers "F.Cu" "F.Mask" "F.Paste")
			(net "P1V8_PEX")
		)
		(pad "AM36" smd circle
			(at 10.450068 6.649974)
			(size 0.4572 0.4572)
			(layers "F.Cu" "F.Mask" "F.Paste")
			(net "GND")
		)
		(pad "AM37" smd circle
			(at 11.400028 6.649974)
			(size 0.4572 0.4572)
			(layers "F.Cu" "F.Mask" "F.Paste")
			(net "GND")
		)
		(pad "AM38" smd circle
			(at 12.349988 6.649974)
			(size 0.4572 0.4572)
			(layers "F.Cu" "F.Mask" "F.Paste")
			(net "Net_5416")
		)
		(pad "AM39" smd circle
			(at 13.299948 6.649974)
			(size 0.4572 0.4572)
			(layers "F.Cu" "F.Mask" "F.Paste")
			(net "Net_5459")
		)
		(pad "AM40" smd circle
			(at 14.249908 6.649974)
			(size 0.4572 0.4572)
			(layers "F.Cu" "F.Mask" "F.Paste")
			(net "GND")
		)
		(pad "AM41" smd circle
			(at 15.200122 6.649974)
			(size 0.4572 0.4572)
			(layers "F.Cu" "F.Mask" "F.Paste")
			(net "Net_1515")
		)
		(pad "AM42" smd circle
			(at 16.150082 6.649974)
			(size 0.4572 0.4572)
			(layers "F.Cu" "F.Mask" "F.Paste")
			(net "Net_1518")
		)
		(pad "AM43" smd circle
			(at 17.100042 6.649974)
			(size 0.4572 0.4572)
			(layers "F.Cu" "F.Mask" "F.Paste")
			(net "GND")
		)
		(pad "AM44" smd circle
			(at 18.050002 6.649974)
			(size 0.4572 0.4572)
			(layers "F.Cu" "F.Mask" "F.Paste")
			(net "GND")
		)
		(pad "AM45" smd circle
			(at 18.999962 6.649974)
			(size 0.4572 0.4572)
			(layers "F.Cu" "F.Mask" "F.Paste")
			(net "GND")
		)
		(pad "AM46" smd circle
			(at 19.949922 6.649974)
			(size 0.4572 0.4572)
			(layers "F.Cu" "F.Mask" "F.Paste")
			(net "GND")
		)
		(pad "AM47" smd circle
			(at 20.899882 6.649974)
			(size 0.4572 0.4572)
			(layers "F.Cu" "F.Mask" "F.Paste")
			(net "GND")
		)
		(pad "AM48" smd circle
			(at 21.850096 6.649974)
			(size 0.4572 0.4572)
			(layers "F.Cu" "F.Mask" "F.Paste")
			(net "Net_1510")
		)
		(pad "AM49" smd circle
			(at 22.800056 6.649974)
			(size 0.4572 0.4572)
			(layers "F.Cu" "F.Mask" "F.Paste")
			(net "Net_1461")
		)
		(pad "AN1" smd circle
			(at -22.800056 7.599934)
			(size 0.4572 0.4572)
			(layers "F.Cu" "F.Mask" "F.Paste")
			(net "GND")
		)
		(pad "AN2" smd circle
			(at -21.850096 7.599934)
			(size 0.4572 0.4572)
			(layers "F.Cu" "F.Mask" "F.Paste")
			(net "GND")
		)
		(pad "AN3" smd circle
			(at -20.899882 7.599934)
			(size 0.4572 0.4572)
			(layers "F.Cu" "F.Mask" "F.Paste")
			(net "Net_1441")
		)
		(pad "AN4" smd circle
			(at -19.949922 7.599934)
			(size 0.4572 0.4572)
			(layers "F.Cu" "F.Mask" "F.Paste")
			(net "Net_1460")
		)
		(pad "AN5" smd circle
			(at -18.999962 7.599934)
			(size 0.4572 0.4572)
			(layers "F.Cu" "F.Mask" "F.Paste")
			(net "GND")
		)
		(pad "AN6" smd circle
			(at -18.050002 7.599934)
			(size 0.4572 0.4572)
			(layers "F.Cu" "F.Mask" "F.Paste")
			(net "Net_1731")
		)
		(pad "AN7" smd circle
			(at -17.100042 7.599934)
			(size 0.4572 0.4572)
			(layers "F.Cu" "F.Mask" "F.Paste")
			(net "Net_1732")
		)
		(pad "AN8" smd circle
			(at -16.150082 7.599934)
			(size 0.4572 0.4572)
			(layers "F.Cu" "F.Mask" "F.Paste")
			(net "GND")
		)
		(pad "AN9" smd circle
			(at -15.200122 7.599934)
			(size 0.4572 0.4572)
			(layers "F.Cu" "F.Mask" "F.Paste")
			(net "GND")
		)
		(pad "AN10" smd circle
			(at -14.249908 7.599934)
			(size 0.4572 0.4572)
			(layers "F.Cu" "F.Mask" "F.Paste")
			(net "GND")
		)
		(pad "AN11" smd circle
			(at -13.299948 7.599934)
			(size 0.4572 0.4572)
			(layers "F.Cu" "F.Mask" "F.Paste")
			(net "GND")
		)
		(pad "AN12" smd circle
			(at -12.349988 7.599934)
			(size 0.4572 0.4572)
			(layers "F.Cu" "F.Mask" "F.Paste")
			(net "GND")
		)
		(pad "AN13" smd circle
			(at -11.400028 7.599934)
			(size 0.4572 0.4572)
			(layers "F.Cu" "F.Mask" "F.Paste")
			(net "GND")
		)
		(pad "AN14" smd circle
			(at -10.450068 7.599934)
			(size 0.4572 0.4572)
			(layers "F.Cu" "F.Mask" "F.Paste")
			(net "Net_527")
		)
		(pad "AN15" smd circle
			(at -9.500108 7.599934)
			(size 0.4572 0.4572)
			(layers "F.Cu" "F.Mask" "F.Paste")
			(net "GND")
		)
		(pad "AN16" smd circle
			(at -8.549894 7.599934)
			(size 0.4572 0.4572)
			(layers "F.Cu" "F.Mask" "F.Paste")
			(net "GND")
		)
		(pad "AN17" smd circle
			(at -7.599934 7.599934)
			(size 0.4572 0.4572)
			(layers "F.Cu" "F.Mask" "F.Paste")
			(net "GND")
		)
		(pad "AN18" smd circle
			(at -6.649974 7.599934)
			(size 0.4572 0.4572)
			(layers "F.Cu" "F.Mask" "F.Paste")
			(net "GND")
		)
		(pad "AN19" smd circle
			(at -5.700014 7.599934)
			(size 0.4572 0.4572)
			(layers "F.Cu" "F.Mask" "F.Paste")
			(net "GND")
		)
		(pad "AN20" smd circle
			(at -4.750054 7.599934)
			(size 0.4572 0.4572)
			(layers "F.Cu" "F.Mask" "F.Paste")
			(net "GND")
		)
		(pad "AN21" smd circle
			(at -3.800094 7.599934)
			(size 0.4572 0.4572)
			(layers "F.Cu" "F.Mask" "F.Paste")
			(net "GND")
		)
		(pad "AN22" smd circle
			(at -2.84988 7.599934)
			(size 0.4572 0.4572)
			(layers "F.Cu" "F.Mask" "F.Paste")
			(net "GND")
		)
		(pad "AN23" smd circle
			(at -1.89992 7.599934)
			(size 0.4572 0.4572)
			(layers "F.Cu" "F.Mask" "F.Paste")
			(net "GND")
		)
		(pad "AN24" smd circle
			(at -0.94996 7.599934)
			(size 0.4572 0.4572)
			(layers "F.Cu" "F.Mask" "F.Paste")
			(net "GND")
		)
		(pad "AN25" smd circle
			(at 0 7.599934)
			(size 0.4572 0.4572)
			(layers "F.Cu" "F.Mask" "F.Paste")
			(net "GND")
		)
		(pad "AN26" smd circle
			(at 0.94996 7.599934)
			(size 0.4572 0.4572)
			(layers "F.Cu" "F.Mask" "F.Paste")
			(net "GND")
		)
		(pad "AN27" smd circle
			(at 1.89992 7.599934)
			(size 0.4572 0.4572)
			(layers "F.Cu" "F.Mask" "F.Paste")
			(net "GND")
		)
		(pad "AN28" smd circle
			(at 2.84988 7.599934)
			(size 0.4572 0.4572)
			(layers "F.Cu" "F.Mask" "F.Paste")
			(net "GND")
		)
		(pad "AN29" smd circle
			(at 3.800094 7.599934)
			(size 0.4572 0.4572)
			(layers "F.Cu" "F.Mask" "F.Paste")
			(net "GND")
		)
		(pad "AN30" smd circle
			(at 4.750054 7.599934)
			(size 0.4572 0.4572)
			(layers "F.Cu" "F.Mask" "F.Paste")
			(net "GND")
		)
		(pad "AN31" smd circle
			(at 5.700014 7.599934)
			(size 0.4572 0.4572)
			(layers "F.Cu" "F.Mask" "F.Paste")
			(net "GND")
		)
		(pad "AN32" smd circle
			(at 6.649974 7.599934)
			(size 0.4572 0.4572)
			(layers "F.Cu" "F.Mask" "F.Paste")
			(net "GND")
		)
		(pad "AN33" smd circle
			(at 7.599934 7.599934)
			(size 0.4572 0.4572)
			(layers "F.Cu" "F.Mask" "F.Paste")
			(net "GND")
		)
		(pad "AN34" smd circle
			(at 8.549894 7.599934)
			(size 0.4572 0.4572)
			(layers "F.Cu" "F.Mask" "F.Paste")
			(net "GND")
		)
		(pad "AN35" smd circle
			(at 9.500108 7.599934)
			(size 0.4572 0.4572)
			(layers "F.Cu" "F.Mask" "F.Paste")
			(net "GND")
		)
		(pad "AN36" smd circle
			(at 10.450068 7.599934)
			(size 0.4572 0.4572)
			(layers "F.Cu" "F.Mask" "F.Paste")
			(net "Net_540")
		)
		(pad "AN37" smd circle
			(at 11.400028 7.599934)
			(size 0.4572 0.4572)
			(layers "F.Cu" "F.Mask" "F.Paste")
			(net "GND")
		)
		(pad "AN38" smd circle
			(at 12.349988 7.599934)
			(size 0.4572 0.4572)
			(layers "F.Cu" "F.Mask" "F.Paste")
			(net "Net_5450")
		)
		(pad "AN39" smd circle
			(at 13.299948 7.599934)
			(size 0.4572 0.4572)
			(layers "F.Cu" "F.Mask" "F.Paste")
			(net "Net_5417")
		)
		(pad "AN40" smd circle
			(at 14.249908 7.599934)
			(size 0.4572 0.4572)
			(layers "F.Cu" "F.Mask" "F.Paste")
			(net "GND")
		)
		(pad "AN41" smd circle
			(at 15.200122 7.599934)
			(size 0.4572 0.4572)
			(layers "F.Cu" "F.Mask" "F.Paste")
			(net "GND")
		)
		(pad "AN42" smd circle
			(at 16.150082 7.599934)
			(size 0.4572 0.4572)
			(layers "F.Cu" "F.Mask" "F.Paste")
			(net "GND")
		)
		(pad "AN43" smd circle
			(at 17.100042 7.599934)
			(size 0.4572 0.4572)
			(layers "F.Cu" "F.Mask" "F.Paste")
			(net "P5E_PEX3_STN0_TX_DP<0>")
		)
		(pad "AN44" smd circle
			(at 18.050002 7.599934)
			(size 0.4572 0.4572)
			(layers "F.Cu" "F.Mask" "F.Paste")
			(net "P5E_PEX3_STN0_TX_DN<0>")
		)
		(pad "AN45" smd circle
			(at 18.999962 7.599934)
			(size 0.4572 0.4572)
			(layers "F.Cu" "F.Mask" "F.Paste")
			(net "GND")
		)
		(pad "AN46" smd circle
			(at 19.949922 7.599934)
			(size 0.4572 0.4572)
			(layers "F.Cu" "F.Mask" "F.Paste")
			(net "P5E_PEX3_STN0_RX_DP<0>")
		)
		(pad "AN47" smd circle
			(at 20.899882 7.599934)
			(size 0.4572 0.4572)
			(layers "F.Cu" "F.Mask" "F.Paste")
			(net "P5E_PEX3_STN0_RX_DN<0>")
		)
		(pad "AN48" smd circle
			(at 21.850096 7.599934)
			(size 0.4572 0.4572)
			(layers "F.Cu" "F.Mask" "F.Paste")
			(net "GND")
		)
		(pad "AN49" smd circle
			(at 22.800056 7.599934)
			(size 0.4572 0.4572)
			(layers "F.Cu" "F.Mask" "F.Paste")
			(net "GND")
		)
		(pad "AP1" smd circle
			(at -22.800056 8.549894)
			(size 0.4572 0.4572)
			(layers "F.Cu" "F.Mask" "F.Paste")
			(net "Net_1472")
		)
		(pad "AP2" smd circle
			(at -21.850096 8.549894)
			(size 0.4572 0.4572)
			(layers "F.Cu" "F.Mask" "F.Paste")
			(net "Net_1493")
		)
		(pad "AP3" smd circle
			(at -20.899882 8.549894)
			(size 0.4572 0.4572)
			(layers "F.Cu" "F.Mask" "F.Paste")
			(net "GND")
		)
		(pad "AP4" smd circle
			(at -19.949922 8.549894)
			(size 0.4572 0.4572)
			(layers "F.Cu" "F.Mask" "F.Paste")
			(net "GND")
		)
		(pad "AP5" smd circle
			(at -18.999962 8.549894)
			(size 0.4572 0.4572)
			(layers "F.Cu" "F.Mask" "F.Paste")
			(net "GND")
		)
		(pad "AP6" smd circle
			(at -18.050002 8.549894)
			(size 0.4572 0.4572)
			(layers "F.Cu" "F.Mask" "F.Paste")
			(net "GND")
		)
		(pad "AP7" smd circle
			(at -17.100042 8.549894)
			(size 0.4572 0.4572)
			(layers "F.Cu" "F.Mask" "F.Paste")
			(net "GND")
		)
		(pad "AP8" smd circle
			(at -16.150082 8.549894)
			(size 0.4572 0.4572)
			(layers "F.Cu" "F.Mask" "F.Paste")
			(net "Net_1463")
		)
		(pad "AP9" smd circle
			(at -15.200122 8.549894)
			(size 0.4572 0.4572)
			(layers "F.Cu" "F.Mask" "F.Paste")
			(net "Net_1474")
		)
		(pad "AP10" smd circle
			(at -14.249908 8.549894)
			(size 0.4572 0.4572)
			(layers "F.Cu" "F.Mask" "F.Paste")
			(net "GND")
		)
		(pad "AP11" smd circle
			(at -13.299948 8.549894)
			(size 0.4572 0.4572)
			(layers "F.Cu" "F.Mask" "F.Paste")
			(net "GND")
		)
		(pad "AP12" smd circle
			(at -12.349988 8.549894)
			(size 0.4572 0.4572)
			(layers "F.Cu" "F.Mask" "F.Paste")
			(net "GND")
		)
		(pad "AP13" smd circle
			(at -11.400028 8.549894)
			(size 0.4572 0.4572)
			(layers "F.Cu" "F.Mask" "F.Paste")
			(net "GND")
		)
		(pad "AP14" smd circle
			(at -10.450068 8.549894)
			(size 0.4572 0.4572)
			(layers "F.Cu" "F.Mask" "F.Paste")
			(net "Net_530")
		)
		(pad "AP15" smd circle
			(at -9.500108 8.549894)
			(size 0.4572 0.4572)
			(layers "F.Cu" "F.Mask" "F.Paste")
			(net "GND")
		)
		(pad "AP16" smd circle
			(at -8.549894 8.549894)
			(size 0.4572 0.4572)
			(layers "F.Cu" "F.Mask" "F.Paste")
			(net "P1V25_SERDES_VDDPLL_PEX3")
		)
		(pad "AP17" smd circle
			(at -7.599934 8.549894)
			(size 0.4572 0.4572)
			(layers "F.Cu" "F.Mask" "F.Paste")
			(net "P1V25_SERDES_VDDPLL_PEX3")
		)
		(pad "AP18" smd circle
			(at -6.649974 8.549894)
			(size 0.4572 0.4572)
			(layers "F.Cu" "F.Mask" "F.Paste")
			(net "P1V25_SERDES_VDDPLL_PEX3")
		)
		(pad "AP19" smd circle
			(at -5.700014 8.549894)
			(size 0.4572 0.4572)
			(layers "F.Cu" "F.Mask" "F.Paste")
			(net "P1V25_SERDES_VDDPLL_PEX3")
		)
		(pad "AP20" smd circle
			(at -4.750054 8.549894)
			(size 0.4572 0.4572)
			(layers "F.Cu" "F.Mask" "F.Paste")
			(net "P1V25_SERDES_VDDPLL_PEX3")
		)
		(pad "AP21" smd circle
			(at -3.800094 8.549894)
			(size 0.4572 0.4572)
			(layers "F.Cu" "F.Mask" "F.Paste")
			(net "P1V25_SERDES_VDDPLL_PEX3")
		)
		(pad "AP22" smd circle
			(at -2.84988 8.549894)
			(size 0.4572 0.4572)
			(layers "F.Cu" "F.Mask" "F.Paste")
			(net "P1V25_SERDES_VDDPLL_PEX3")
		)
		(pad "AP23" smd circle
			(at -1.89992 8.549894)
			(size 0.4572 0.4572)
			(layers "F.Cu" "F.Mask" "F.Paste")
			(net "P1V25_SERDES_VDDPLL_PEX3")
		)
		(pad "AP24" smd circle
			(at -0.94996 8.549894)
			(size 0.4572 0.4572)
			(layers "F.Cu" "F.Mask" "F.Paste")
			(net "P1V25_SERDES_VDDPLL_PEX3")
		)
		(pad "AP25" smd circle
			(at 0 8.549894)
			(size 0.4572 0.4572)
			(layers "F.Cu" "F.Mask" "F.Paste")
			(net "P1V25_SERDES_VDDPLL_PEX3")
		)
		(pad "AP26" smd circle
			(at 0.94996 8.549894)
			(size 0.4572 0.4572)
			(layers "F.Cu" "F.Mask" "F.Paste")
			(net "P1V25_SERDES_VDDPLL_PEX3")
		)
		(pad "AP27" smd circle
			(at 1.89992 8.549894)
			(size 0.4572 0.4572)
			(layers "F.Cu" "F.Mask" "F.Paste")
			(net "P1V25_SERDES_VDDPLL_PEX3")
		)
		(pad "AP28" smd circle
			(at 2.84988 8.549894)
			(size 0.4572 0.4572)
			(layers "F.Cu" "F.Mask" "F.Paste")
			(net "P1V25_SERDES_VDDPLL_PEX3")
		)
		(pad "AP29" smd circle
			(at 3.800094 8.549894)
			(size 0.4572 0.4572)
			(layers "F.Cu" "F.Mask" "F.Paste")
			(net "P1V25_SERDES_VDDPLL_PEX3")
		)
		(pad "AP30" smd circle
			(at 4.750054 8.549894)
			(size 0.4572 0.4572)
			(layers "F.Cu" "F.Mask" "F.Paste")
			(net "P1V25_SERDES_VDDPLL_PEX3")
		)
		(pad "AP31" smd circle
			(at 5.700014 8.549894)
			(size 0.4572 0.4572)
			(layers "F.Cu" "F.Mask" "F.Paste")
			(net "P1V25_SERDES_VDDPLL_PEX3")
		)
		(pad "AP32" smd circle
			(at 6.649974 8.549894)
			(size 0.4572 0.4572)
			(layers "F.Cu" "F.Mask" "F.Paste")
			(net "P1V25_SERDES_VDDPLL_PEX3")
		)
		(pad "AP33" smd circle
			(at 7.599934 8.549894)
			(size 0.4572 0.4572)
			(layers "F.Cu" "F.Mask" "F.Paste")
			(net "P1V25_SERDES_VDDPLL_PEX3")
		)
		(pad "AP34" smd circle
			(at 8.549894 8.549894)
			(size 0.4572 0.4572)
			(layers "F.Cu" "F.Mask" "F.Paste")
			(net "GND")
		)
		(pad "AP35" smd circle
			(at 9.500108 8.549894)
			(size 0.4572 0.4572)
			(layers "F.Cu" "F.Mask" "F.Paste")
			(net "P1V8_VDDA_PEX3")
		)
		(pad "AP36" smd circle
			(at 10.450068 8.549894)
			(size 0.4572 0.4572)
			(layers "F.Cu" "F.Mask" "F.Paste")
			(net "Net_536")
		)
		(pad "AP37" smd circle
			(at 11.400028 8.549894)
			(size 0.4572 0.4572)
			(layers "F.Cu" "F.Mask" "F.Paste")
			(net "GND")
		)
		(pad "AP38" smd circle
			(at 12.349988 8.549894)
			(size 0.4572 0.4572)
			(layers "F.Cu" "F.Mask" "F.Paste")
			(net "Net_5470")
		)
		(pad "AP39" smd circle
			(at 13.299948 8.549894)
			(size 0.4572 0.4572)
			(layers "F.Cu" "F.Mask" "F.Paste")
			(net "Net_5476")
		)
		(pad "AP40" smd circle
			(at 14.249908 8.549894)
			(size 0.4572 0.4572)
			(layers "F.Cu" "F.Mask" "F.Paste")
			(net "GND")
		)
		(pad "AP41" smd circle
			(at 15.200122 8.549894)
			(size 0.4572 0.4572)
			(layers "F.Cu" "F.Mask" "F.Paste")
			(net "P5E_PEX3_STN0_TX_DP<1>")
		)
		(pad "AP42" smd circle
			(at 16.150082 8.549894)
			(size 0.4572 0.4572)
			(layers "F.Cu" "F.Mask" "F.Paste")
			(net "P5E_PEX3_STN0_TX_DN<1>")
		)
		(pad "AP43" smd circle
			(at 17.100042 8.549894)
			(size 0.4572 0.4572)
			(layers "F.Cu" "F.Mask" "F.Paste")
			(net "GND")
		)
		(pad "AP44" smd circle
			(at 18.050002 8.549894)
			(size 0.4572 0.4572)
			(layers "F.Cu" "F.Mask" "F.Paste")
			(net "GND")
		)
		(pad "AP45" smd circle
			(at 18.999962 8.549894)
			(size 0.4572 0.4572)
			(layers "F.Cu" "F.Mask" "F.Paste")
			(net "GND")
		)
		(pad "AP46" smd circle
			(at 19.949922 8.549894)
			(size 0.4572 0.4572)
			(layers "F.Cu" "F.Mask" "F.Paste")
			(net "GND")
		)
		(pad "AP47" smd circle
			(at 20.899882 8.549894)
			(size 0.4572 0.4572)
			(layers "F.Cu" "F.Mask" "F.Paste")
			(net "GND")
		)
		(pad "AP48" smd circle
			(at 21.850096 8.549894)
			(size 0.4572 0.4572)
			(layers "F.Cu" "F.Mask" "F.Paste")
			(net "P5E_PEX3_STN0_RX_DP<1>")
		)
		(pad "AP49" smd circle
			(at 22.800056 8.549894)
			(size 0.4572 0.4572)
			(layers "F.Cu" "F.Mask" "F.Paste")
			(net "P5E_PEX3_STN0_RX_DN<1>")
		)
		(pad "AR1" smd circle
			(at -22.800056 9.500108)
			(size 0.4572 0.4572)
			(layers "F.Cu" "F.Mask" "F.Paste")
			(net "GND")
		)
		(pad "AR2" smd circle
			(at -21.850096 9.500108)
			(size 0.4572 0.4572)
			(layers "F.Cu" "F.Mask" "F.Paste")
			(net "GND")
		)
		(pad "AR3" smd circle
			(at -20.899882 9.500108)
			(size 0.4572 0.4572)
			(layers "F.Cu" "F.Mask" "F.Paste")
			(net "Net_1487")
		)
		(pad "AR4" smd circle
			(at -19.949922 9.500108)
			(size 0.4572 0.4572)
			(layers "F.Cu" "F.Mask" "F.Paste")
			(net "Net_1502")
		)
		(pad "AR5" smd circle
			(at -18.999962 9.500108)
			(size 0.4572 0.4572)
			(layers "F.Cu" "F.Mask" "F.Paste")
			(net "GND")
		)
		(pad "AR6" smd circle
			(at -18.050002 9.500108)
			(size 0.4572 0.4572)
			(layers "F.Cu" "F.Mask" "F.Paste")
			(net "Net_1484")
		)
		(pad "AR7" smd circle
			(at -17.100042 9.500108)
			(size 0.4572 0.4572)
			(layers "F.Cu" "F.Mask" "F.Paste")
			(net "Net_1390")
		)
		(pad "AR8" smd circle
			(at -16.150082 9.500108)
			(size 0.4572 0.4572)
			(layers "F.Cu" "F.Mask" "F.Paste")
			(net "GND")
		)
		(pad "AR9" smd circle
			(at -15.200122 9.500108)
			(size 0.4572 0.4572)
			(layers "F.Cu" "F.Mask" "F.Paste")
			(net "GND")
		)
		(pad "AR10" smd circle
			(at -14.249908 9.500108)
			(size 0.4572 0.4572)
			(layers "F.Cu" "F.Mask" "F.Paste")
			(net "GND")
		)
		(pad "AR11" smd circle
			(at -13.299948 9.500108)
			(size 0.4572 0.4572)
			(layers "F.Cu" "F.Mask" "F.Paste")
			(net "GND")
		)
		(pad "AR12" smd circle
			(at -12.349988 9.500108)
			(size 0.4572 0.4572)
			(layers "F.Cu" "F.Mask" "F.Paste")
			(net "GND")
		)
		(pad "AR13" smd circle
			(at -11.400028 9.500108)
			(size 0.4572 0.4572)
			(layers "F.Cu" "F.Mask" "F.Paste")
			(net "GND")
		)
		(pad "AR14" smd circle
			(at -10.450068 9.500108)
			(size 0.4572 0.4572)
			(layers "F.Cu" "F.Mask" "F.Paste")
			(net "GND")
		)
		(pad "AR15" smd circle
			(at -9.500108 9.500108)
			(size 0.4572 0.4572)
			(layers "F.Cu" "F.Mask" "F.Paste")
			(net "GND")
		)
		(pad "AR16" smd circle
			(at -8.549894 9.500108)
			(size 0.4572 0.4572)
			(layers "F.Cu" "F.Mask" "F.Paste")
			(net "GND")
		)
		(pad "AR17" smd circle
			(at -7.599934 9.500108)
			(size 0.4572 0.4572)
			(layers "F.Cu" "F.Mask" "F.Paste")
			(net "GND")
		)
		(pad "AR18" smd circle
			(at -6.649974 9.500108)
			(size 0.4572 0.4572)
			(layers "F.Cu" "F.Mask" "F.Paste")
			(net "GND")
		)
		(pad "AR19" smd circle
			(at -5.700014 9.500108)
			(size 0.4572 0.4572)
			(layers "F.Cu" "F.Mask" "F.Paste")
			(net "GND")
		)
		(pad "AR20" smd circle
			(at -4.750054 9.500108)
			(size 0.4572 0.4572)
			(layers "F.Cu" "F.Mask" "F.Paste")
			(net "GND")
		)
		(pad "AR21" smd circle
			(at -3.800094 9.500108)
			(size 0.4572 0.4572)
			(layers "F.Cu" "F.Mask" "F.Paste")
			(net "GND")
		)
		(pad "AR22" smd circle
			(at -2.84988 9.500108)
			(size 0.4572 0.4572)
			(layers "F.Cu" "F.Mask" "F.Paste")
			(net "GND")
		)
		(pad "AR23" smd circle
			(at -1.89992 9.500108)
			(size 0.4572 0.4572)
			(layers "F.Cu" "F.Mask" "F.Paste")
			(net "GND")
		)
		(pad "AR24" smd circle
			(at -0.94996 9.500108)
			(size 0.4572 0.4572)
			(layers "F.Cu" "F.Mask" "F.Paste")
			(net "GND")
		)
		(pad "AR25" smd circle
			(at 0 9.500108)
			(size 0.4572 0.4572)
			(layers "F.Cu" "F.Mask" "F.Paste")
			(net "GND")
		)
		(pad "AR26" smd circle
			(at 0.94996 9.500108)
			(size 0.4572 0.4572)
			(layers "F.Cu" "F.Mask" "F.Paste")
			(net "GND")
		)
		(pad "AR27" smd circle
			(at 1.89992 9.500108)
			(size 0.4572 0.4572)
			(layers "F.Cu" "F.Mask" "F.Paste")
			(net "GND")
		)
		(pad "AR28" smd circle
			(at 2.84988 9.500108)
			(size 0.4572 0.4572)
			(layers "F.Cu" "F.Mask" "F.Paste")
			(net "GND")
		)
		(pad "AR29" smd circle
			(at 3.800094 9.500108)
			(size 0.4572 0.4572)
			(layers "F.Cu" "F.Mask" "F.Paste")
			(net "GND")
		)
		(pad "AR30" smd circle
			(at 4.750054 9.500108)
			(size 0.4572 0.4572)
			(layers "F.Cu" "F.Mask" "F.Paste")
			(net "GND")
		)
		(pad "AR31" smd circle
			(at 5.700014 9.500108)
			(size 0.4572 0.4572)
			(layers "F.Cu" "F.Mask" "F.Paste")
			(net "GND")
		)
		(pad "AR32" smd circle
			(at 6.649974 9.500108)
			(size 0.4572 0.4572)
			(layers "F.Cu" "F.Mask" "F.Paste")
			(net "GND")
		)
		(pad "AR33" smd circle
			(at 7.599934 9.500108)
			(size 0.4572 0.4572)
			(layers "F.Cu" "F.Mask" "F.Paste")
			(net "GND")
		)
		(pad "AR34" smd circle
			(at 8.549894 9.500108)
			(size 0.4572 0.4572)
			(layers "F.Cu" "F.Mask" "F.Paste")
			(net "GND")
		)
		(pad "AR35" smd circle
			(at 9.500108 9.500108)
			(size 0.4572 0.4572)
			(layers "F.Cu" "F.Mask" "F.Paste")
			(net "GND")
		)
		(pad "AR36" smd circle
			(at 10.450068 9.500108)
			(size 0.4572 0.4572)
			(layers "F.Cu" "F.Mask" "F.Paste")
			(net "Net_531")
		)
		(pad "AR37" smd circle
			(at 11.400028 9.500108)
			(size 0.4572 0.4572)
			(layers "F.Cu" "F.Mask" "F.Paste")
			(net "GND")
		)
		(pad "AR38" smd circle
			(at 12.349988 9.500108)
			(size 0.4572 0.4572)
			(layers "F.Cu" "F.Mask" "F.Paste")
			(net "Net_5475")
		)
		(pad "AR39" smd circle
			(at 13.299948 9.500108)
			(size 0.4572 0.4572)
			(layers "F.Cu" "F.Mask" "F.Paste")
			(net "Net_5477")
		)
		(pad "AR40" smd circle
			(at 14.249908 9.500108)
			(size 0.4572 0.4572)
			(layers "F.Cu" "F.Mask" "F.Paste")
			(net "GND")
		)
		(pad "AR41" smd circle
			(at 15.200122 9.500108)
			(size 0.4572 0.4572)
			(layers "F.Cu" "F.Mask" "F.Paste")
			(net "GND")
		)
		(pad "AR42" smd circle
			(at 16.150082 9.500108)
			(size 0.4572 0.4572)
			(layers "F.Cu" "F.Mask" "F.Paste")
			(net "GND")
		)
		(pad "AR43" smd circle
			(at 17.100042 9.500108)
			(size 0.4572 0.4572)
			(layers "F.Cu" "F.Mask" "F.Paste")
			(net "P5E_PEX3_STN0_TX_DP<2>")
		)
		(pad "AR44" smd circle
			(at 18.050002 9.500108)
			(size 0.4572 0.4572)
			(layers "F.Cu" "F.Mask" "F.Paste")
			(net "P5E_PEX3_STN0_TX_DN<2>")
		)
		(pad "AR45" smd circle
			(at 18.999962 9.500108)
			(size 0.4572 0.4572)
			(layers "F.Cu" "F.Mask" "F.Paste")
			(net "GND")
		)
		(pad "AR46" smd circle
			(at 19.949922 9.500108)
			(size 0.4572 0.4572)
			(layers "F.Cu" "F.Mask" "F.Paste")
			(net "P5E_PEX3_STN0_RX_DP<2>")
		)
		(pad "AR47" smd circle
			(at 20.899882 9.500108)
			(size 0.4572 0.4572)
			(layers "F.Cu" "F.Mask" "F.Paste")
			(net "P5E_PEX3_STN0_RX_DN<2>")
		)
		(pad "AR48" smd circle
			(at 21.850096 9.500108)
			(size 0.4572 0.4572)
			(layers "F.Cu" "F.Mask" "F.Paste")
			(net "GND")
		)
		(pad "AR49" smd circle
			(at 22.800056 9.500108)
			(size 0.4572 0.4572)
			(layers "F.Cu" "F.Mask" "F.Paste")
			(net "GND")
		)
		(pad "AT1" smd circle
			(at -22.800056 10.450068)
			(size 0.4572 0.4572)
			(layers "F.Cu" "F.Mask" "F.Paste")
			(net "Net_1491")
		)
		(pad "AT2" smd circle
			(at -21.850096 10.450068)
			(size 0.4572 0.4572)
			(layers "F.Cu" "F.Mask" "F.Paste")
			(net "Net_1495")
		)
		(pad "AT3" smd circle
			(at -20.899882 10.450068)
			(size 0.4572 0.4572)
			(layers "F.Cu" "F.Mask" "F.Paste")
			(net "GND")
		)
		(pad "AT4" smd circle
			(at -19.949922 10.450068)
			(size 0.4572 0.4572)
			(layers "F.Cu" "F.Mask" "F.Paste")
			(net "GND")
		)
		(pad "AT5" smd circle
			(at -18.999962 10.450068)
			(size 0.4572 0.4572)
			(layers "F.Cu" "F.Mask" "F.Paste")
			(net "GND")
		)
		(pad "AT6" smd circle
			(at -18.050002 10.450068)
			(size 0.4572 0.4572)
			(layers "F.Cu" "F.Mask" "F.Paste")
			(net "GND")
		)
		(pad "AT7" smd circle
			(at -17.100042 10.450068)
			(size 0.4572 0.4572)
			(layers "F.Cu" "F.Mask" "F.Paste")
			(net "GND")
		)
		(pad "AT8" smd circle
			(at -16.150082 10.450068)
			(size 0.4572 0.4572)
			(layers "F.Cu" "F.Mask" "F.Paste")
			(net "Net_1367")
		)
		(pad "AT9" smd circle
			(at -15.200122 10.450068)
			(size 0.4572 0.4572)
			(layers "F.Cu" "F.Mask" "F.Paste")
			(net "Net_1468")
		)
		(pad "AT10" smd circle
			(at -14.249908 10.450068)
			(size 0.4572 0.4572)
			(layers "F.Cu" "F.Mask" "F.Paste")
			(net "GND")
		)
		(pad "AT11" smd circle
			(at -13.299948 10.450068)
			(size 0.4572 0.4572)
			(layers "F.Cu" "F.Mask" "F.Paste")
			(net "GND")
		)
		(pad "AT12" smd circle
			(at -12.349988 10.450068)
			(size 0.4572 0.4572)
			(layers "F.Cu" "F.Mask" "F.Paste")
			(net "GND")
		)
		(pad "AT13" smd circle
			(at -11.400028 10.450068)
			(size 0.4572 0.4572)
			(layers "F.Cu" "F.Mask" "F.Paste")
			(net "GND")
		)
		(pad "AT14" smd circle
			(at -10.450068 10.450068)
			(size 0.4572 0.4572)
			(layers "F.Cu" "F.Mask" "F.Paste")
			(net "GND")
		)
		(pad "AT15" smd circle
			(at -9.500108 10.450068)
			(size 0.4572 0.4572)
			(layers "F.Cu" "F.Mask" "F.Paste")
			(net "GND")
		)
		(pad "AT16" smd circle
			(at -8.549894 10.450068)
			(size 0.4572 0.4572)
			(layers "F.Cu" "F.Mask" "F.Paste")
			(net "GND")
		)
		(pad "AT17" smd circle
			(at -7.599934 10.450068)
			(size 0.4572 0.4572)
			(layers "F.Cu" "F.Mask" "F.Paste")
			(net "GND")
		)
		(pad "AT18" smd circle
			(at -6.649974 10.450068)
			(size 0.4572 0.4572)
			(layers "F.Cu" "F.Mask" "F.Paste")
			(net "GND")
		)
		(pad "AT19" smd circle
			(at -5.700014 10.450068)
			(size 0.4572 0.4572)
			(layers "F.Cu" "F.Mask" "F.Paste")
			(net "GND")
		)
		(pad "AT20" smd circle
			(at -4.750054 10.450068)
			(size 0.4572 0.4572)
			(layers "F.Cu" "F.Mask" "F.Paste")
			(net "GND")
		)
		(pad "AT21" smd circle
			(at -3.800094 10.450068)
			(size 0.4572 0.4572)
			(layers "F.Cu" "F.Mask" "F.Paste")
			(net "GND")
		)
		(pad "AT22" smd circle
			(at -2.84988 10.450068)
			(size 0.4572 0.4572)
			(layers "F.Cu" "F.Mask" "F.Paste")
			(net "GND")
		)
		(pad "AT23" smd circle
			(at -1.89992 10.450068)
			(size 0.4572 0.4572)
			(layers "F.Cu" "F.Mask" "F.Paste")
			(net "GND")
		)
		(pad "AT24" smd circle
			(at -0.94996 10.450068)
			(size 0.4572 0.4572)
			(layers "F.Cu" "F.Mask" "F.Paste")
			(net "GND")
		)
		(pad "AT25" smd circle
			(at 0 10.450068)
			(size 0.4572 0.4572)
			(layers "F.Cu" "F.Mask" "F.Paste")
			(net "GND")
		)
		(pad "AT26" smd circle
			(at 0.94996 10.450068)
			(size 0.4572 0.4572)
			(layers "F.Cu" "F.Mask" "F.Paste")
			(net "GND")
		)
		(pad "AT27" smd circle
			(at 1.89992 10.450068)
			(size 0.4572 0.4572)
			(layers "F.Cu" "F.Mask" "F.Paste")
			(net "GND")
		)
		(pad "AT28" smd circle
			(at 2.84988 10.450068)
			(size 0.4572 0.4572)
			(layers "F.Cu" "F.Mask" "F.Paste")
			(net "GND")
		)
		(pad "AT29" smd circle
			(at 3.800094 10.450068)
			(size 0.4572 0.4572)
			(layers "F.Cu" "F.Mask" "F.Paste")
			(net "GND")
		)
		(pad "AT30" smd circle
			(at 4.750054 10.450068)
			(size 0.4572 0.4572)
			(layers "F.Cu" "F.Mask" "F.Paste")
			(net "GND")
		)
		(pad "AT31" smd circle
			(at 5.700014 10.450068)
			(size 0.4572 0.4572)
			(layers "F.Cu" "F.Mask" "F.Paste")
			(net "GND")
		)
		(pad "AT32" smd circle
			(at 6.649974 10.450068)
			(size 0.4572 0.4572)
			(layers "F.Cu" "F.Mask" "F.Paste")
			(net "GND")
		)
		(pad "AT33" smd circle
			(at 7.599934 10.450068)
			(size 0.4572 0.4572)
			(layers "F.Cu" "F.Mask" "F.Paste")
			(net "GND")
		)
		(pad "AT34" smd circle
			(at 8.549894 10.450068)
			(size 0.4572 0.4572)
			(layers "F.Cu" "F.Mask" "F.Paste")
			(net "GND")
		)
		(pad "AT35" smd circle
			(at 9.500108 10.450068)
			(size 0.4572 0.4572)
			(layers "F.Cu" "F.Mask" "F.Paste")
			(net "GND")
		)
		(pad "AT36" smd circle
			(at 10.450068 10.450068)
			(size 0.4572 0.4572)
			(layers "F.Cu" "F.Mask" "F.Paste")
			(net "Net_541")
		)
		(pad "AT37" smd circle
			(at 11.400028 10.450068)
			(size 0.4572 0.4572)
			(layers "F.Cu" "F.Mask" "F.Paste")
			(net "GND")
		)
		(pad "AT38" smd circle
			(at 12.349988 10.450068)
			(size 0.4572 0.4572)
			(layers "F.Cu" "F.Mask" "F.Paste")
			(net "Net_5441")
		)
		(pad "AT39" smd circle
			(at 13.299948 10.450068)
			(size 0.4572 0.4572)
			(layers "F.Cu" "F.Mask" "F.Paste")
			(net "Net_5426")
		)
		(pad "AT40" smd circle
			(at 14.249908 10.450068)
			(size 0.4572 0.4572)
			(layers "F.Cu" "F.Mask" "F.Paste")
			(net "GND")
		)
		(pad "AT41" smd circle
			(at 15.200122 10.450068)
			(size 0.4572 0.4572)
			(layers "F.Cu" "F.Mask" "F.Paste")
			(net "P5E_PEX3_STN0_TX_DP<3>")
		)
		(pad "AT42" smd circle
			(at 16.150082 10.450068)
			(size 0.4572 0.4572)
			(layers "F.Cu" "F.Mask" "F.Paste")
			(net "P5E_PEX3_STN0_TX_DN<3>")
		)
		(pad "AT43" smd circle
			(at 17.100042 10.450068)
			(size 0.4572 0.4572)
			(layers "F.Cu" "F.Mask" "F.Paste")
			(net "GND")
		)
		(pad "AT44" smd circle
			(at 18.050002 10.450068)
			(size 0.4572 0.4572)
			(layers "F.Cu" "F.Mask" "F.Paste")
			(net "GND")
		)
		(pad "AT45" smd circle
			(at 18.999962 10.450068)
			(size 0.4572 0.4572)
			(layers "F.Cu" "F.Mask" "F.Paste")
			(net "GND")
		)
		(pad "AT46" smd circle
			(at 19.949922 10.450068)
			(size 0.4572 0.4572)
			(layers "F.Cu" "F.Mask" "F.Paste")
			(net "GND")
		)
		(pad "AT47" smd circle
			(at 20.899882 10.450068)
			(size 0.4572 0.4572)
			(layers "F.Cu" "F.Mask" "F.Paste")
			(net "GND")
		)
		(pad "AT48" smd circle
			(at 21.850096 10.450068)
			(size 0.4572 0.4572)
			(layers "F.Cu" "F.Mask" "F.Paste")
			(net "P5E_PEX3_STN0_RX_DP<3>")
		)
		(pad "AT49" smd circle
			(at 22.800056 10.450068)
			(size 0.4572 0.4572)
			(layers "F.Cu" "F.Mask" "F.Paste")
			(net "P5E_PEX3_STN0_RX_DN<3>")
		)
		(pad "AU1" smd circle
			(at -22.800056 11.400028)
			(size 0.4572 0.4572)
			(layers "F.Cu" "F.Mask" "F.Paste")
			(net "GND")
		)
		(pad "AU2" smd circle
			(at -21.850096 11.400028)
			(size 0.4572 0.4572)
			(layers "F.Cu" "F.Mask" "F.Paste")
			(net "GND")
		)
		(pad "AU3" smd circle
			(at -20.899882 11.400028)
			(size 0.4572 0.4572)
			(layers "F.Cu" "F.Mask" "F.Paste")
			(net "Net_1482")
		)
		(pad "AU4" smd circle
			(at -19.949922 11.400028)
			(size 0.4572 0.4572)
			(layers "F.Cu" "F.Mask" "F.Paste")
			(net "Net_1430")
		)
		(pad "AU5" smd circle
			(at -18.999962 11.400028)
			(size 0.4572 0.4572)
			(layers "F.Cu" "F.Mask" "F.Paste")
			(net "GND")
		)
		(pad "AU6" smd circle
			(at -18.050002 11.400028)
			(size 0.4572 0.4572)
			(layers "F.Cu" "F.Mask" "F.Paste")
			(net "Net_1401")
		)
		(pad "AU7" smd circle
			(at -17.100042 11.400028)
			(size 0.4572 0.4572)
			(layers "F.Cu" "F.Mask" "F.Paste")
			(net "Net_1354")
		)
		(pad "AU8" smd circle
			(at -16.150082 11.400028)
			(size 0.4572 0.4572)
			(layers "F.Cu" "F.Mask" "F.Paste")
			(net "GND")
		)
		(pad "AU9" smd circle
			(at -15.200122 11.400028)
			(size 0.4572 0.4572)
			(layers "F.Cu" "F.Mask" "F.Paste")
			(net "GND")
		)
		(pad "AU10" smd circle
			(at -14.249908 11.400028)
			(size 0.4572 0.4572)
			(layers "F.Cu" "F.Mask" "F.Paste")
			(net "GND")
		)
		(pad "AU11" smd circle
			(at -13.299948 11.400028)
			(size 0.4572 0.4572)
			(layers "F.Cu" "F.Mask" "F.Paste")
			(net "GND")
		)
		(pad "AU12" smd circle
			(at -12.349988 11.400028)
			(size 0.4572 0.4572)
			(layers "F.Cu" "F.Mask" "F.Paste")
			(net "GND")
		)
		(pad "AU13" smd circle
			(at -11.400028 11.400028)
			(size 0.4572 0.4572)
			(layers "F.Cu" "F.Mask" "F.Paste")
			(net "GND")
		)
		(pad "AU14" smd circle
			(at -10.450068 11.400028)
			(size 0.4572 0.4572)
			(layers "F.Cu" "F.Mask" "F.Paste")
			(net "GND")
		)
		(pad "AU15" smd circle
			(at -9.500108 11.400028)
			(size 0.4572 0.4572)
			(layers "F.Cu" "F.Mask" "F.Paste")
			(net "GND")
		)
		(pad "AU16" smd circle
			(at -8.549894 11.400028)
			(size 0.4572 0.4572)
			(layers "F.Cu" "F.Mask" "F.Paste")
			(net "GND")
		)
		(pad "AU17" smd circle
			(at -7.599934 11.400028)
			(size 0.4572 0.4572)
			(layers "F.Cu" "F.Mask" "F.Paste")
			(net "GND")
		)
		(pad "AU18" smd circle
			(at -6.649974 11.400028)
			(size 0.4572 0.4572)
			(layers "F.Cu" "F.Mask" "F.Paste")
			(net "GND")
		)
		(pad "AU19" smd circle
			(at -5.700014 11.400028)
			(size 0.4572 0.4572)
			(layers "F.Cu" "F.Mask" "F.Paste")
			(net "GND")
		)
		(pad "AU20" smd circle
			(at -4.750054 11.400028)
			(size 0.4572 0.4572)
			(layers "F.Cu" "F.Mask" "F.Paste")
			(net "GND")
		)
		(pad "AU21" smd circle
			(at -3.800094 11.400028)
			(size 0.4572 0.4572)
			(layers "F.Cu" "F.Mask" "F.Paste")
			(net "GND")
		)
		(pad "AU22" smd circle
			(at -2.84988 11.400028)
			(size 0.4572 0.4572)
			(layers "F.Cu" "F.Mask" "F.Paste")
			(net "GND")
		)
		(pad "AU23" smd circle
			(at -1.89992 11.400028)
			(size 0.4572 0.4572)
			(layers "F.Cu" "F.Mask" "F.Paste")
			(net "GND")
		)
		(pad "AU24" smd circle
			(at -0.94996 11.400028)
			(size 0.4572 0.4572)
			(layers "F.Cu" "F.Mask" "F.Paste")
			(net "GND")
		)
		(pad "AU25" smd circle
			(at 0 11.400028)
			(size 0.4572 0.4572)
			(layers "F.Cu" "F.Mask" "F.Paste")
			(net "GND")
		)
		(pad "AU26" smd circle
			(at 0.94996 11.400028)
			(size 0.4572 0.4572)
			(layers "F.Cu" "F.Mask" "F.Paste")
			(net "GND")
		)
		(pad "AU27" smd circle
			(at 1.89992 11.400028)
			(size 0.4572 0.4572)
			(layers "F.Cu" "F.Mask" "F.Paste")
			(net "GND")
		)
		(pad "AU28" smd circle
			(at 2.84988 11.400028)
			(size 0.4572 0.4572)
			(layers "F.Cu" "F.Mask" "F.Paste")
			(net "GND")
		)
		(pad "AU29" smd circle
			(at 3.800094 11.400028)
			(size 0.4572 0.4572)
			(layers "F.Cu" "F.Mask" "F.Paste")
			(net "GND")
		)
		(pad "AU30" smd circle
			(at 4.750054 11.400028)
			(size 0.4572 0.4572)
			(layers "F.Cu" "F.Mask" "F.Paste")
			(net "GND")
		)
		(pad "AU31" smd circle
			(at 5.700014 11.400028)
			(size 0.4572 0.4572)
			(layers "F.Cu" "F.Mask" "F.Paste")
			(net "GND")
		)
		(pad "AU32" smd circle
			(at 6.649974 11.400028)
			(size 0.4572 0.4572)
			(layers "F.Cu" "F.Mask" "F.Paste")
			(net "GND")
		)
		(pad "AU33" smd circle
			(at 7.599934 11.400028)
			(size 0.4572 0.4572)
			(layers "F.Cu" "F.Mask" "F.Paste")
			(net "GND")
		)
		(pad "AU34" smd circle
			(at 8.549894 11.400028)
			(size 0.4572 0.4572)
			(layers "F.Cu" "F.Mask" "F.Paste")
			(net "GND")
		)
		(pad "AU35" smd circle
			(at 9.500108 11.400028)
			(size 0.4572 0.4572)
			(layers "F.Cu" "F.Mask" "F.Paste")
			(net "GND")
		)
		(pad "AU36" smd circle
			(at 10.450068 11.400028)
			(size 0.4572 0.4572)
			(layers "F.Cu" "F.Mask" "F.Paste")
			(net "GND")
		)
		(pad "AU37" smd circle
			(at 11.400028 11.400028)
			(size 0.4572 0.4572)
			(layers "F.Cu" "F.Mask" "F.Paste")
			(net "GND")
		)
		(pad "AU38" smd circle
			(at 12.349988 11.400028)
			(size 0.4572 0.4572)
			(layers "F.Cu" "F.Mask" "F.Paste")
			(net "Net_5448")
		)
		(pad "AU39" smd circle
			(at 13.299948 11.400028)
			(size 0.4572 0.4572)
			(layers "F.Cu" "F.Mask" "F.Paste")
			(net "Net_5420")
		)
		(pad "AU40" smd circle
			(at 14.249908 11.400028)
			(size 0.4572 0.4572)
			(layers "F.Cu" "F.Mask" "F.Paste")
			(net "GND")
		)
		(pad "AU41" smd circle
			(at 15.200122 11.400028)
			(size 0.4572 0.4572)
			(layers "F.Cu" "F.Mask" "F.Paste")
			(net "GND")
		)
		(pad "AU42" smd circle
			(at 16.150082 11.400028)
			(size 0.4572 0.4572)
			(layers "F.Cu" "F.Mask" "F.Paste")
			(net "GND")
		)
		(pad "AU43" smd circle
			(at 17.100042 11.400028)
			(size 0.4572 0.4572)
			(layers "F.Cu" "F.Mask" "F.Paste")
			(net "P5E_PEX3_STN0_TX_DP<4>")
		)
		(pad "AU44" smd circle
			(at 18.050002 11.400028)
			(size 0.4572 0.4572)
			(layers "F.Cu" "F.Mask" "F.Paste")
			(net "P5E_PEX3_STN0_TX_DN<4>")
		)
		(pad "AU45" smd circle
			(at 18.999962 11.400028)
			(size 0.4572 0.4572)
			(layers "F.Cu" "F.Mask" "F.Paste")
			(net "GND")
		)
		(pad "AU46" smd circle
			(at 19.949922 11.400028)
			(size 0.4572 0.4572)
			(layers "F.Cu" "F.Mask" "F.Paste")
			(net "P5E_PEX3_STN0_RX_DP<4>")
		)
		(pad "AU47" smd circle
			(at 20.899882 11.400028)
			(size 0.4572 0.4572)
			(layers "F.Cu" "F.Mask" "F.Paste")
			(net "P5E_PEX3_STN0_RX_DN<4>")
		)
		(pad "AU48" smd circle
			(at 21.850096 11.400028)
			(size 0.4572 0.4572)
			(layers "F.Cu" "F.Mask" "F.Paste")
			(net "GND")
		)
		(pad "AU49" smd circle
			(at 22.800056 11.400028)
			(size 0.4572 0.4572)
			(layers "F.Cu" "F.Mask" "F.Paste")
			(net "GND")
		)
		(pad "AV1" smd circle
			(at -22.800056 12.349988)
			(size 0.4572 0.4572)
			(layers "F.Cu" "F.Mask" "F.Paste")
			(net "Net_1485")
		)
		(pad "AV2" smd circle
			(at -21.850096 12.349988)
			(size 0.4572 0.4572)
			(layers "F.Cu" "F.Mask" "F.Paste")
			(net "Net_1507")
		)
		(pad "AV3" smd circle
			(at -20.899882 12.349988)
			(size 0.4572 0.4572)
			(layers "F.Cu" "F.Mask" "F.Paste")
			(net "GND")
		)
		(pad "AV4" smd circle
			(at -19.949922 12.349988)
			(size 0.4572 0.4572)
			(layers "F.Cu" "F.Mask" "F.Paste")
			(net "GND")
		)
		(pad "AV5" smd circle
			(at -18.999962 12.349988)
			(size 0.4572 0.4572)
			(layers "F.Cu" "F.Mask" "F.Paste")
			(net "GND")
		)
		(pad "AV6" smd circle
			(at -18.050002 12.349988)
			(size 0.4572 0.4572)
			(layers "F.Cu" "F.Mask" "F.Paste")
			(net "GND")
		)
		(pad "AV7" smd circle
			(at -17.100042 12.349988)
			(size 0.4572 0.4572)
			(layers "F.Cu" "F.Mask" "F.Paste")
			(net "GND")
		)
		(pad "AV8" smd circle
			(at -16.150082 12.349988)
			(size 0.4572 0.4572)
			(layers "F.Cu" "F.Mask" "F.Paste")
			(net "Net_1365")
		)
		(pad "AV9" smd circle
			(at -15.200122 12.349988)
			(size 0.4572 0.4572)
			(layers "F.Cu" "F.Mask" "F.Paste")
			(net "Net_1481")
		)
		(pad "AV10" smd circle
			(at -14.249908 12.349988)
			(size 0.4572 0.4572)
			(layers "F.Cu" "F.Mask" "F.Paste")
			(net "GND")
		)
		(pad "AV11" smd circle
			(at -13.299948 12.349988)
			(size 0.4572 0.4572)
			(layers "F.Cu" "F.Mask" "F.Paste")
			(net "GND")
		)
		(pad "AV12" smd circle
			(at -12.349988 12.349988)
			(size 0.4572 0.4572)
			(layers "F.Cu" "F.Mask" "F.Paste")
			(net "Net_5438")
		)
		(pad "AV13" smd circle
			(at -11.400028 12.349988)
			(size 0.4572 0.4572)
			(layers "F.Cu" "F.Mask" "F.Paste")
			(net "Net_5439")
		)
		(pad "AV14" smd circle
			(at -10.450068 12.349988)
			(size 0.4572 0.4572)
			(layers "F.Cu" "F.Mask" "F.Paste")
			(net "Net_5430")
		)
		(pad "AV15" smd circle
			(at -9.500108 12.349988)
			(size 0.4572 0.4572)
			(layers "F.Cu" "F.Mask" "F.Paste")
			(net "Net_5424")
		)
		(pad "AV16" smd circle
			(at -8.549894 12.349988)
			(size 0.4572 0.4572)
			(layers "F.Cu" "F.Mask" "F.Paste")
			(net "Net_5433")
		)
		(pad "AV17" smd circle
			(at -7.599934 12.349988)
			(size 0.4572 0.4572)
			(layers "F.Cu" "F.Mask" "F.Paste")
			(net "Net_5434")
		)
		(pad "AV18" smd circle
			(at -6.649974 12.349988)
			(size 0.4572 0.4572)
			(layers "F.Cu" "F.Mask" "F.Paste")
			(net "Net_5429")
		)
		(pad "AV19" smd circle
			(at -5.700014 12.349988)
			(size 0.4572 0.4572)
			(layers "F.Cu" "F.Mask" "F.Paste")
			(net "Net_5425")
		)
		(pad "AV20" smd circle
			(at -4.750054 12.349988)
			(size 0.4572 0.4572)
			(layers "F.Cu" "F.Mask" "F.Paste")
			(net "GND")
		)
		(pad "AV21" smd circle
			(at -3.800094 12.349988)
			(size 0.4572 0.4572)
			(layers "F.Cu" "F.Mask" "F.Paste")
			(net "Net_5464")
		)
		(pad "AV22" smd circle
			(at -2.84988 12.349988)
			(size 0.4572 0.4572)
			(layers "F.Cu" "F.Mask" "F.Paste")
			(net "Net_5465")
		)
		(pad "AV23" smd circle
			(at -1.89992 12.349988)
			(size 0.4572 0.4572)
			(layers "F.Cu" "F.Mask" "F.Paste")
			(net "Net_5467")
		)
		(pad "AV24" smd circle
			(at -0.94996 12.349988)
			(size 0.4572 0.4572)
			(layers "F.Cu" "F.Mask" "F.Paste")
			(net "GND")
		)
		(pad "AV25" smd circle
			(at 0 12.349988)
			(size 0.4572 0.4572)
			(layers "F.Cu" "F.Mask" "F.Paste")
			(net "PEX3_MODE_SEL2")
		)
		(pad "AV26" smd circle
			(at 0.94996 12.349988)
			(size 0.4572 0.4572)
			(layers "F.Cu" "F.Mask" "F.Paste")
			(net "PEX3_MODE_SEL7")
		)
		(pad "AV27" smd circle
			(at 1.89992 12.349988)
			(size 0.4572 0.4572)
			(layers "F.Cu" "F.Mask" "F.Paste")
			(net "PEX3_MODE_SEL3")
		)
		(pad "AV28" smd circle
			(at 2.84988 12.349988)
			(size 0.4572 0.4572)
			(layers "F.Cu" "F.Mask" "F.Paste")
			(net "PEX3_MODE_SEL9")
		)
		(pad "AV29" smd circle
			(at 3.800094 12.349988)
			(size 0.4572 0.4572)
			(layers "F.Cu" "F.Mask" "F.Paste")
			(net "PEX3_PCA9555_INT_R_N")
		)
		(pad "AV30" smd circle
			(at 4.750054 12.349988)
			(size 0.4572 0.4572)
			(layers "F.Cu" "F.Mask" "F.Paste")
			(net "PEX3_SYS_ERR_N")
		)
		(pad "AV31" smd circle
			(at 5.700014 12.349988)
			(size 0.4572 0.4572)
			(layers "F.Cu" "F.Mask" "F.Paste")
			(net "PEX3_MODE_SEL6")
		)
		(pad "AV32" smd circle
			(at 6.649974 12.349988)
			(size 0.4572 0.4572)
			(layers "F.Cu" "F.Mask" "F.Paste")
			(net "PEX3_MODE_SEL10")
		)
		(pad "AV33" smd circle
			(at 7.599934 12.349988)
			(size 0.4572 0.4572)
			(layers "F.Cu" "F.Mask" "F.Paste")
			(net "Net_5442")
		)
		(pad "AV34" smd circle
			(at 8.549894 12.349988)
			(size 0.4572 0.4572)
			(layers "F.Cu" "F.Mask" "F.Paste")
			(net "Net_5415")
		)
		(pad "AV35" smd circle
			(at 9.500108 12.349988)
			(size 0.4572 0.4572)
			(layers "F.Cu" "F.Mask" "F.Paste")
			(net "Net_5444")
		)
		(pad "AV36" smd circle
			(at 10.450068 12.349988)
			(size 0.4572 0.4572)
			(layers "F.Cu" "F.Mask" "F.Paste")
			(net "Net_5421")
		)
		(pad "AV37" smd circle
			(at 11.400028 12.349988)
			(size 0.4572 0.4572)
			(layers "F.Cu" "F.Mask" "F.Paste")
			(net "Net_5446")
		)
		(pad "AV38" smd circle
			(at 12.349988 12.349988)
			(size 0.4572 0.4572)
			(layers "F.Cu" "F.Mask" "F.Paste")
			(net "Net_5445")
		)
		(pad "AV39" smd circle
			(at 13.299948 12.349988)
			(size 0.4572 0.4572)
			(layers "F.Cu" "F.Mask" "F.Paste")
			(net "Net_5437")
		)
		(pad "AV40" smd circle
			(at 14.249908 12.349988)
			(size 0.4572 0.4572)
			(layers "F.Cu" "F.Mask" "F.Paste")
			(net "GND")
		)
		(pad "AV41" smd circle
			(at 15.200122 12.349988)
			(size 0.4572 0.4572)
			(layers "F.Cu" "F.Mask" "F.Paste")
			(net "P5E_PEX3_STN0_TX_DP<5>")
		)
		(pad "AV42" smd circle
			(at 16.150082 12.349988)
			(size 0.4572 0.4572)
			(layers "F.Cu" "F.Mask" "F.Paste")
			(net "P5E_PEX3_STN0_TX_DN<5>")
		)
		(pad "AV43" smd circle
			(at 17.100042 12.349988)
			(size 0.4572 0.4572)
			(layers "F.Cu" "F.Mask" "F.Paste")
			(net "GND")
		)
		(pad "AV44" smd circle
			(at 18.050002 12.349988)
			(size 0.4572 0.4572)
			(layers "F.Cu" "F.Mask" "F.Paste")
			(net "GND")
		)
		(pad "AV45" smd circle
			(at 18.999962 12.349988)
			(size 0.4572 0.4572)
			(layers "F.Cu" "F.Mask" "F.Paste")
			(net "GND")
		)
		(pad "AV46" smd circle
			(at 19.949922 12.349988)
			(size 0.4572 0.4572)
			(layers "F.Cu" "F.Mask" "F.Paste")
			(net "GND")
		)
		(pad "AV47" smd circle
			(at 20.899882 12.349988)
			(size 0.4572 0.4572)
			(layers "F.Cu" "F.Mask" "F.Paste")
			(net "GND")
		)
		(pad "AV48" smd circle
			(at 21.850096 12.349988)
			(size 0.4572 0.4572)
			(layers "F.Cu" "F.Mask" "F.Paste")
			(net "P5E_PEX3_STN0_RX_DP<5>")
		)
		(pad "AV49" smd circle
			(at 22.800056 12.349988)
			(size 0.4572 0.4572)
			(layers "F.Cu" "F.Mask" "F.Paste")
			(net "P5E_PEX3_STN0_RX_DN<5>")
		)
		(pad "AW1" smd circle
			(at -22.800056 13.299948)
			(size 0.4572 0.4572)
			(layers "F.Cu" "F.Mask" "F.Paste")
			(net "GND")
		)
		(pad "AW2" smd circle
			(at -21.850096 13.299948)
			(size 0.4572 0.4572)
			(layers "F.Cu" "F.Mask" "F.Paste")
			(net "GND")
		)
		(pad "AW3" smd circle
			(at -20.899882 13.299948)
			(size 0.4572 0.4572)
			(layers "F.Cu" "F.Mask" "F.Paste")
			(net "Net_1513")
		)
		(pad "AW4" smd circle
			(at -19.949922 13.299948)
			(size 0.4572 0.4572)
			(layers "F.Cu" "F.Mask" "F.Paste")
			(net "Net_1505")
		)
		(pad "AW5" smd circle
			(at -18.999962 13.299948)
			(size 0.4572 0.4572)
			(layers "F.Cu" "F.Mask" "F.Paste")
			(net "GND")
		)
		(pad "AW6" smd circle
			(at -18.050002 13.299948)
			(size 0.4572 0.4572)
			(layers "F.Cu" "F.Mask" "F.Paste")
			(net "Net_1376")
		)
		(pad "AW7" smd circle
			(at -17.100042 13.299948)
			(size 0.4572 0.4572)
			(layers "F.Cu" "F.Mask" "F.Paste")
			(net "Net_1378")
		)
		(pad "AW8" smd circle
			(at -16.150082 13.299948)
			(size 0.4572 0.4572)
			(layers "F.Cu" "F.Mask" "F.Paste")
			(net "GND")
		)
		(pad "AW9" smd circle
			(at -15.200122 13.299948)
			(size 0.4572 0.4572)
			(layers "F.Cu" "F.Mask" "F.Paste")
			(net "GND")
		)
		(pad "AW10" smd circle
			(at -14.249908 13.299948)
			(size 0.4572 0.4572)
			(layers "F.Cu" "F.Mask" "F.Paste")
			(net "GND")
		)
		(pad "AW11" smd circle
			(at -13.299948 13.299948)
			(size 0.4572 0.4572)
			(layers "F.Cu" "F.Mask" "F.Paste")
			(net "GND")
		)
		(pad "AW12" smd circle
			(at -12.349988 13.299948)
			(size 0.4572 0.4572)
			(layers "F.Cu" "F.Mask" "F.Paste")
			(net "Net_5436")
		)
		(pad "AW13" smd circle
			(at -11.400028 13.299948)
			(size 0.4572 0.4572)
			(layers "F.Cu" "F.Mask" "F.Paste")
			(net "Net_5432")
		)
		(pad "AW14" smd circle
			(at -10.450068 13.299948)
			(size 0.4572 0.4572)
			(layers "F.Cu" "F.Mask" "F.Paste")
			(net "Net_5428")
		)
		(pad "AW15" smd circle
			(at -9.500108 13.299948)
			(size 0.4572 0.4572)
			(layers "F.Cu" "F.Mask" "F.Paste")
			(net "Net_5423")
		)
		(pad "AW16" smd circle
			(at -8.549894 13.299948)
			(size 0.4572 0.4572)
			(layers "F.Cu" "F.Mask" "F.Paste")
			(net "Net_5435")
		)
		(pad "AW17" smd circle
			(at -7.599934 13.299948)
			(size 0.4572 0.4572)
			(layers "F.Cu" "F.Mask" "F.Paste")
			(net "Net_5431")
		)
		(pad "AW18" smd circle
			(at -6.649974 13.299948)
			(size 0.4572 0.4572)
			(layers "F.Cu" "F.Mask" "F.Paste")
			(net "Net_5427")
		)
		(pad "AW19" smd circle
			(at -5.700014 13.299948)
			(size 0.4572 0.4572)
			(layers "F.Cu" "F.Mask" "F.Paste")
			(net "Net_5422")
		)
		(pad "AW20" smd circle
			(at -4.750054 13.299948)
			(size 0.4572 0.4572)
			(layers "F.Cu" "F.Mask" "F.Paste")
			(net "GND")
		)
		(pad "AW21" smd circle
			(at -3.800094 13.299948)
			(size 0.4572 0.4572)
			(layers "F.Cu" "F.Mask" "F.Paste")
			(net "Net_5456")
		)
		(pad "AW22" smd circle
			(at -2.84988 13.299948)
			(size 0.4572 0.4572)
			(layers "F.Cu" "F.Mask" "F.Paste")
			(net "Net_5466")
		)
		(pad "AW23" smd circle
			(at -1.89992 13.299948)
			(size 0.4572 0.4572)
			(layers "F.Cu" "F.Mask" "F.Paste")
			(net "Net_5455")
		)
		(pad "AW24" smd circle
			(at -0.94996 13.299948)
			(size 0.4572 0.4572)
			(layers "F.Cu" "F.Mask" "F.Paste")
			(net "GND")
		)
		(pad "AW25" smd circle
			(at 0 13.299948)
			(size 0.4572 0.4572)
			(layers "F.Cu" "F.Mask" "F.Paste")
			(net "PEX3_MODE_SEL5")
		)
		(pad "AW26" smd circle
			(at 0.94996 13.299948)
			(size 0.4572 0.4572)
			(layers "F.Cu" "F.Mask" "F.Paste")
			(net "PEX3_DBG_MODE3")
		)
		(pad "AW27" smd circle
			(at 1.89992 13.299948)
			(size 0.4572 0.4572)
			(layers "F.Cu" "F.Mask" "F.Paste")
			(net "PEX3_MODE_SEL0")
		)
		(pad "AW28" smd circle
			(at 2.84988 13.299948)
			(size 0.4572 0.4572)
			(layers "F.Cu" "F.Mask" "F.Paste")
			(net "PEX3_MODE_SEL4")
		)
		(pad "AW29" smd circle
			(at 3.800094 13.299948)
			(size 0.4572 0.4572)
			(layers "F.Cu" "F.Mask" "F.Paste")
			(net "PEX3_MODE_SEL8")
		)
		(pad "AW30" smd circle
			(at 4.750054 13.299948)
			(size 0.4572 0.4572)
			(layers "F.Cu" "F.Mask" "F.Paste")
			(net "PEX3_DBG_MODE2")
		)
		(pad "AW31" smd circle
			(at 5.700014 13.299948)
			(size 0.4572 0.4572)
			(layers "F.Cu" "F.Mask" "F.Paste")
			(net "PEX3_MODE_SEL11")
		)
		(pad "AW32" smd circle
			(at 6.649974 13.299948)
			(size 0.4572 0.4572)
			(layers "F.Cu" "F.Mask" "F.Paste")
			(net "PEX3_MODE_SEL12")
		)
		(pad "AW33" smd circle
			(at 7.599934 13.299948)
			(size 0.4572 0.4572)
			(layers "F.Cu" "F.Mask" "F.Paste")
			(net "Net_5440")
		)
		(pad "AW34" smd circle
			(at 8.549894 13.299948)
			(size 0.4572 0.4572)
			(layers "F.Cu" "F.Mask" "F.Paste")
			(net "PEX3_DBG_MODE4")
		)
		(pad "AW35" smd circle
			(at 9.500108 13.299948)
			(size 0.4572 0.4572)
			(layers "F.Cu" "F.Mask" "F.Paste")
			(net "Net_5419")
		)
		(pad "AW36" smd circle
			(at 10.450068 13.299948)
			(size 0.4572 0.4572)
			(layers "F.Cu" "F.Mask" "F.Paste")
			(net "Net_5443")
		)
		(pad "AW37" smd circle
			(at 11.400028 13.299948)
			(size 0.4572 0.4572)
			(layers "F.Cu" "F.Mask" "F.Paste")
			(net "Net_5447")
		)
		(pad "AW38" smd circle
			(at 12.349988 13.299948)
			(size 0.4572 0.4572)
			(layers "F.Cu" "F.Mask" "F.Paste")
			(net "PEX3_MODE_SEL1")
		)
		(pad "AW39" smd circle
			(at 13.299948 13.299948)
			(size 0.4572 0.4572)
			(layers "F.Cu" "F.Mask" "F.Paste")
			(net "Net_5414")
		)
		(pad "AW40" smd circle
			(at 14.249908 13.299948)
			(size 0.4572 0.4572)
			(layers "F.Cu" "F.Mask" "F.Paste")
			(net "GND")
		)
		(pad "AW41" smd circle
			(at 15.200122 13.299948)
			(size 0.4572 0.4572)
			(layers "F.Cu" "F.Mask" "F.Paste")
			(net "GND")
		)
		(pad "AW42" smd circle
			(at 16.150082 13.299948)
			(size 0.4572 0.4572)
			(layers "F.Cu" "F.Mask" "F.Paste")
			(net "GND")
		)
		(pad "AW43" smd circle
			(at 17.100042 13.299948)
			(size 0.4572 0.4572)
			(layers "F.Cu" "F.Mask" "F.Paste")
			(net "P5E_PEX3_STN0_TX_DP<6>")
		)
		(pad "AW44" smd circle
			(at 18.050002 13.299948)
			(size 0.4572 0.4572)
			(layers "F.Cu" "F.Mask" "F.Paste")
			(net "P5E_PEX3_STN0_TX_DN<6>")
		)
		(pad "AW45" smd circle
			(at 18.999962 13.299948)
			(size 0.4572 0.4572)
			(layers "F.Cu" "F.Mask" "F.Paste")
			(net "GND")
		)
		(pad "AW46" smd circle
			(at 19.949922 13.299948)
			(size 0.4572 0.4572)
			(layers "F.Cu" "F.Mask" "F.Paste")
			(net "P5E_PEX3_STN0_RX_DP<6>")
		)
		(pad "AW47" smd circle
			(at 20.899882 13.299948)
			(size 0.4572 0.4572)
			(layers "F.Cu" "F.Mask" "F.Paste")
			(net "P5E_PEX3_STN0_RX_DN<6>")
		)
		(pad "AW48" smd circle
			(at 21.850096 13.299948)
			(size 0.4572 0.4572)
			(layers "F.Cu" "F.Mask" "F.Paste")
			(net "GND")
		)
		(pad "AW49" smd circle
			(at 22.800056 13.299948)
			(size 0.4572 0.4572)
			(layers "F.Cu" "F.Mask" "F.Paste")
			(net "GND")
		)
		(pad "AY1" smd circle
			(at -22.800056 14.249908)
			(size 0.4572 0.4572)
			(layers "F.Cu" "F.Mask" "F.Paste")
			(net "Net_1408")
		)
		(pad "AY2" smd circle
			(at -21.850096 14.249908)
			(size 0.4572 0.4572)
			(layers "F.Cu" "F.Mask" "F.Paste")
			(net "Net_1435")
		)
		(pad "AY3" smd circle
			(at -20.899882 14.249908)
			(size 0.4572 0.4572)
			(layers "F.Cu" "F.Mask" "F.Paste")
			(net "GND")
		)
		(pad "AY4" smd circle
			(at -19.949922 14.249908)
			(size 0.4572 0.4572)
			(layers "F.Cu" "F.Mask" "F.Paste")
			(net "GND")
		)
		(pad "AY5" smd circle
			(at -18.999962 14.249908)
			(size 0.4572 0.4572)
			(layers "F.Cu" "F.Mask" "F.Paste")
			(net "GND")
		)
		(pad "AY6" smd circle
			(at -18.050002 14.249908)
			(size 0.4572 0.4572)
			(layers "F.Cu" "F.Mask" "F.Paste")
			(net "GND")
		)
		(pad "AY7" smd circle
			(at -17.100042 14.249908)
			(size 0.4572 0.4572)
			(layers "F.Cu" "F.Mask" "F.Paste")
			(net "GND")
		)
		(pad "AY8" smd circle
			(at -16.150082 14.249908)
			(size 0.4572 0.4572)
			(layers "F.Cu" "F.Mask" "F.Paste")
			(net "GND")
		)
		(pad "AY9" smd circle
			(at -15.200122 14.249908)
			(size 0.4572 0.4572)
			(layers "F.Cu" "F.Mask" "F.Paste")
			(net "GND")
		)
		(pad "AY10" smd circle
			(at -14.249908 14.249908)
			(size 0.4572 0.4572)
			(layers "F.Cu" "F.Mask" "F.Paste")
			(net "GND")
		)
		(pad "AY11" smd circle
			(at -13.299948 14.249908)
			(size 0.4572 0.4572)
			(layers "F.Cu" "F.Mask" "F.Paste")
			(net "GND")
		)
		(pad "AY12" smd circle
			(at -12.349988 14.249908)
			(size 0.4572 0.4572)
			(layers "F.Cu" "F.Mask" "F.Paste")
			(net "GND")
		)
		(pad "AY13" smd circle
			(at -11.400028 14.249908)
			(size 0.4572 0.4572)
			(layers "F.Cu" "F.Mask" "F.Paste")
			(net "GND")
		)
		(pad "AY14" smd circle
			(at -10.450068 14.249908)
			(size 0.4572 0.4572)
			(layers "F.Cu" "F.Mask" "F.Paste")
			(net "GND")
		)
		(pad "AY15" smd circle
			(at -9.500108 14.249908)
			(size 0.4572 0.4572)
			(layers "F.Cu" "F.Mask" "F.Paste")
			(net "GND")
		)
		(pad "AY16" smd circle
			(at -8.549894 14.249908)
			(size 0.4572 0.4572)
			(layers "F.Cu" "F.Mask" "F.Paste")
			(net "GND")
		)
		(pad "AY17" smd circle
			(at -7.599934 14.249908)
			(size 0.4572 0.4572)
			(layers "F.Cu" "F.Mask" "F.Paste")
			(net "GND")
		)
		(pad "AY18" smd circle
			(at -6.649974 14.249908)
			(size 0.4572 0.4572)
			(layers "F.Cu" "F.Mask" "F.Paste")
			(net "GND")
		)
		(pad "AY19" smd circle
			(at -5.700014 14.249908)
			(size 0.4572 0.4572)
			(layers "F.Cu" "F.Mask" "F.Paste")
			(net "GND")
		)
		(pad "AY20" smd circle
			(at -4.750054 14.249908)
			(size 0.4572 0.4572)
			(layers "F.Cu" "F.Mask" "F.Paste")
			(net "GND")
		)
		(pad "AY21" smd circle
			(at -3.800094 14.249908)
			(size 0.4572 0.4572)
			(layers "F.Cu" "F.Mask" "F.Paste")
			(net "GND")
		)
		(pad "AY22" smd circle
			(at -2.84988 14.249908)
			(size 0.4572 0.4572)
			(layers "F.Cu" "F.Mask" "F.Paste")
			(net "GND")
		)
		(pad "AY23" smd circle
			(at -1.89992 14.249908)
			(size 0.4572 0.4572)
			(layers "F.Cu" "F.Mask" "F.Paste")
			(net "GND")
		)
		(pad "AY24" smd circle
			(at -0.94996 14.249908)
			(size 0.4572 0.4572)
			(layers "F.Cu" "F.Mask" "F.Paste")
			(net "GND")
		)
		(pad "AY25" smd circle
			(at 0 14.249908)
			(size 0.4572 0.4572)
			(layers "F.Cu" "F.Mask" "F.Paste")
			(net "GND")
		)
		(pad "AY26" smd circle
			(at 0.94996 14.249908)
			(size 0.4572 0.4572)
			(layers "F.Cu" "F.Mask" "F.Paste")
			(net "GND")
		)
		(pad "AY27" smd circle
			(at 1.89992 14.249908)
			(size 0.4572 0.4572)
			(layers "F.Cu" "F.Mask" "F.Paste")
			(net "GND")
		)
		(pad "AY28" smd circle
			(at 2.84988 14.249908)
			(size 0.4572 0.4572)
			(layers "F.Cu" "F.Mask" "F.Paste")
			(net "GND")
		)
		(pad "AY29" smd circle
			(at 3.800094 14.249908)
			(size 0.4572 0.4572)
			(layers "F.Cu" "F.Mask" "F.Paste")
			(net "GND")
		)
		(pad "AY30" smd circle
			(at 4.750054 14.249908)
			(size 0.4572 0.4572)
			(layers "F.Cu" "F.Mask" "F.Paste")
			(net "GND")
		)
		(pad "AY31" smd circle
			(at 5.700014 14.249908)
			(size 0.4572 0.4572)
			(layers "F.Cu" "F.Mask" "F.Paste")
			(net "GND")
		)
		(pad "AY32" smd circle
			(at 6.649974 14.249908)
			(size 0.4572 0.4572)
			(layers "F.Cu" "F.Mask" "F.Paste")
			(net "GND")
		)
		(pad "AY33" smd circle
			(at 7.599934 14.249908)
			(size 0.4572 0.4572)
			(layers "F.Cu" "F.Mask" "F.Paste")
			(net "GND")
		)
		(pad "AY34" smd circle
			(at 8.549894 14.249908)
			(size 0.4572 0.4572)
			(layers "F.Cu" "F.Mask" "F.Paste")
			(net "GND")
		)
		(pad "AY35" smd circle
			(at 9.500108 14.249908)
			(size 0.4572 0.4572)
			(layers "F.Cu" "F.Mask" "F.Paste")
			(net "GND")
		)
		(pad "AY36" smd circle
			(at 10.450068 14.249908)
			(size 0.4572 0.4572)
			(layers "F.Cu" "F.Mask" "F.Paste")
			(net "GND")
		)
		(pad "AY37" smd circle
			(at 11.400028 14.249908)
			(size 0.4572 0.4572)
			(layers "F.Cu" "F.Mask" "F.Paste")
			(net "GND")
		)
		(pad "AY38" smd circle
			(at 12.349988 14.249908)
			(size 0.4572 0.4572)
			(layers "F.Cu" "F.Mask" "F.Paste")
			(net "GND")
		)
		(pad "AY39" smd circle
			(at 13.299948 14.249908)
			(size 0.4572 0.4572)
			(layers "F.Cu" "F.Mask" "F.Paste")
			(net "GND")
		)
		(pad "AY40" smd circle
			(at 14.249908 14.249908)
			(size 0.4572 0.4572)
			(layers "F.Cu" "F.Mask" "F.Paste")
			(net "GND")
		)
		(pad "AY41" smd circle
			(at 15.200122 14.249908)
			(size 0.4572 0.4572)
			(layers "F.Cu" "F.Mask" "F.Paste")
			(net "GND")
		)
		(pad "AY42" smd circle
			(at 16.150082 14.249908)
			(size 0.4572 0.4572)
			(layers "F.Cu" "F.Mask" "F.Paste")
			(net "GND")
		)
		(pad "AY43" smd circle
			(at 17.100042 14.249908)
			(size 0.4572 0.4572)
			(layers "F.Cu" "F.Mask" "F.Paste")
			(net "GND")
		)
		(pad "AY44" smd circle
			(at 18.050002 14.249908)
			(size 0.4572 0.4572)
			(layers "F.Cu" "F.Mask" "F.Paste")
			(net "GND")
		)
		(pad "AY45" smd circle
			(at 18.999962 14.249908)
			(size 0.4572 0.4572)
			(layers "F.Cu" "F.Mask" "F.Paste")
			(net "GND")
		)
		(pad "AY46" smd circle
			(at 19.949922 14.249908)
			(size 0.4572 0.4572)
			(layers "F.Cu" "F.Mask" "F.Paste")
			(net "GND")
		)
		(pad "AY47" smd circle
			(at 20.899882 14.249908)
			(size 0.4572 0.4572)
			(layers "F.Cu" "F.Mask" "F.Paste")
			(net "GND")
		)
		(pad "AY48" smd circle
			(at 21.850096 14.249908)
			(size 0.4572 0.4572)
			(layers "F.Cu" "F.Mask" "F.Paste")
			(net "P5E_PEX3_STN0_RX_DP<7>")
		)
		(pad "AY49" smd circle
			(at 22.800056 14.249908)
			(size 0.4572 0.4572)
			(layers "F.Cu" "F.Mask" "F.Paste")
			(net "P5E_PEX3_STN0_RX_DN<7>")
		)
		(pad "B1" smd circle
			(at -22.800056 -21.850096)
			(size 0.4572 0.4572)
			(layers "F.Cu" "F.Mask" "F.Paste")
			(net "GND")
		)
		(pad "B2" smd circle
			(at -21.850096 -21.850096)
			(size 0.4572 0.4572)
			(layers "F.Cu" "F.Mask" "F.Paste")
			(net "GND")
		)
		(pad "B3" smd circle
			(at -20.899882 -21.850096)
			(size 0.4572 0.4572)
			(layers "F.Cu" "F.Mask" "F.Paste")
			(net "P5E_PEX3_STN7_RX_DP<123>")
		)
		(pad "B4" smd circle
			(at -19.949922 -21.850096)
			(size 0.4572 0.4572)
			(layers "F.Cu" "F.Mask" "F.Paste")
			(net "GND")
		)
		(pad "B5" smd circle
			(at -18.999962 -21.850096)
			(size 0.4572 0.4572)
			(layers "F.Cu" "F.Mask" "F.Paste")
			(net "P5E_PEX3_STN7_RX_DP<125>")
		)
		(pad "B6" smd circle
			(at -18.050002 -21.850096)
			(size 0.4572 0.4572)
			(layers "F.Cu" "F.Mask" "F.Paste")
			(net "GND")
		)
		(pad "B7" smd circle
			(at -17.100042 -21.850096)
			(size 0.4572 0.4572)
			(layers "F.Cu" "F.Mask" "F.Paste")
			(net "P5E_PEX3_STN7_RX_DP<127>")
		)
		(pad "B8" smd circle
			(at -16.150082 -21.850096)
			(size 0.4572 0.4572)
			(layers "F.Cu" "F.Mask" "F.Paste")
			(net "GND")
		)
		(pad "B9" smd circle
			(at -15.200122 -21.850096)
			(size 0.4572 0.4572)
			(layers "F.Cu" "F.Mask" "F.Paste")
			(net "P5E_PEX3_STN6_RX_DP<110>")
		)
		(pad "B10" smd circle
			(at -14.249908 -21.850096)
			(size 0.4572 0.4572)
			(layers "F.Cu" "F.Mask" "F.Paste")
			(net "GND")
		)
		(pad "B11" smd circle
			(at -13.299948 -21.850096)
			(size 0.4572 0.4572)
			(layers "F.Cu" "F.Mask" "F.Paste")
			(net "P5E_PEX3_STN6_RX_DP<108>")
		)
		(pad "B12" smd circle
			(at -12.349988 -21.850096)
			(size 0.4572 0.4572)
			(layers "F.Cu" "F.Mask" "F.Paste")
			(net "GND")
		)
		(pad "B13" smd circle
			(at -11.400028 -21.850096)
			(size 0.4572 0.4572)
			(layers "F.Cu" "F.Mask" "F.Paste")
			(net "P5E_PEX3_STN6_RX_DP<106>")
		)
		(pad "B14" smd circle
			(at -10.450068 -21.850096)
			(size 0.4572 0.4572)
			(layers "F.Cu" "F.Mask" "F.Paste")
			(net "GND")
		)
		(pad "B15" smd circle
			(at -9.500108 -21.850096)
			(size 0.4572 0.4572)
			(layers "F.Cu" "F.Mask" "F.Paste")
			(net "P5E_PEX3_STN6_RX_DP<104>")
		)
		(pad "B16" smd circle
			(at -8.549894 -21.850096)
			(size 0.4572 0.4572)
			(layers "F.Cu" "F.Mask" "F.Paste")
			(net "GND")
		)
		(pad "B17" smd circle
			(at -7.599934 -21.850096)
			(size 0.4572 0.4572)
			(layers "F.Cu" "F.Mask" "F.Paste")
			(net "P5E_PEX3_STN6_RX_DP<102>")
		)
		(pad "B18" smd circle
			(at -6.649974 -21.850096)
			(size 0.4572 0.4572)
			(layers "F.Cu" "F.Mask" "F.Paste")
			(net "GND")
		)
		(pad "B19" smd circle
			(at -5.700014 -21.850096)
			(size 0.4572 0.4572)
			(layers "F.Cu" "F.Mask" "F.Paste")
			(net "P5E_PEX3_STN6_RX_DP<100>")
		)
		(pad "B20" smd circle
			(at -4.750054 -21.850096)
			(size 0.4572 0.4572)
			(layers "F.Cu" "F.Mask" "F.Paste")
			(net "GND")
		)
		(pad "B21" smd circle
			(at -3.800094 -21.850096)
			(size 0.4572 0.4572)
			(layers "F.Cu" "F.Mask" "F.Paste")
			(net "P5E_PEX3_STN6_RX_DP<98>")
		)
		(pad "B22" smd circle
			(at -2.84988 -21.850096)
			(size 0.4572 0.4572)
			(layers "F.Cu" "F.Mask" "F.Paste")
			(net "GND")
		)
		(pad "B23" smd circle
			(at -1.89992 -21.850096)
			(size 0.4572 0.4572)
			(layers "F.Cu" "F.Mask" "F.Paste")
			(net "P5E_PEX3_STN6_RX_DP<96>")
		)
		(pad "B24" smd circle
			(at -0.94996 -21.850096)
			(size 0.4572 0.4572)
			(layers "F.Cu" "F.Mask" "F.Paste")
			(net "GND")
		)
		(pad "B25" smd circle
			(at 0 -21.850096)
			(size 0.4572 0.4572)
			(layers "F.Cu" "F.Mask" "F.Paste")
			(net "P5E_PEX3_STN5_RX_DP<81>")
		)
		(pad "B26" smd circle
			(at 0.94996 -21.850096)
			(size 0.4572 0.4572)
			(layers "F.Cu" "F.Mask" "F.Paste")
			(net "GND")
		)
		(pad "B27" smd circle
			(at 1.89992 -21.850096)
			(size 0.4572 0.4572)
			(layers "F.Cu" "F.Mask" "F.Paste")
			(net "P5E_PEX3_STN5_RX_DP<83>")
		)
		(pad "B28" smd circle
			(at 2.84988 -21.850096)
			(size 0.4572 0.4572)
			(layers "F.Cu" "F.Mask" "F.Paste")
			(net "GND")
		)
		(pad "B29" smd circle
			(at 3.800094 -21.850096)
			(size 0.4572 0.4572)
			(layers "F.Cu" "F.Mask" "F.Paste")
			(net "P5E_PEX3_STN5_RX_DP<85>")
		)
		(pad "B30" smd circle
			(at 4.750054 -21.850096)
			(size 0.4572 0.4572)
			(layers "F.Cu" "F.Mask" "F.Paste")
			(net "GND")
		)
		(pad "B31" smd circle
			(at 5.700014 -21.850096)
			(size 0.4572 0.4572)
			(layers "F.Cu" "F.Mask" "F.Paste")
			(net "P5E_PEX3_STN5_RX_DP<87>")
		)
		(pad "B32" smd circle
			(at 6.649974 -21.850096)
			(size 0.4572 0.4572)
			(layers "F.Cu" "F.Mask" "F.Paste")
			(net "GND")
		)
		(pad "B33" smd circle
			(at 7.599934 -21.850096)
			(size 0.4572 0.4572)
			(layers "F.Cu" "F.Mask" "F.Paste")
			(net "P5E_PEX3_STN5_RX_DP<89>")
		)
		(pad "B34" smd circle
			(at 8.549894 -21.850096)
			(size 0.4572 0.4572)
			(layers "F.Cu" "F.Mask" "F.Paste")
			(net "GND")
		)
		(pad "B35" smd circle
			(at 9.500108 -21.850096)
			(size 0.4572 0.4572)
			(layers "F.Cu" "F.Mask" "F.Paste")
			(net "P5E_PEX3_STN5_RX_DP<91>")
		)
		(pad "B36" smd circle
			(at 10.450068 -21.850096)
			(size 0.4572 0.4572)
			(layers "F.Cu" "F.Mask" "F.Paste")
			(net "GND")
		)
		(pad "B37" smd circle
			(at 11.400028 -21.850096)
			(size 0.4572 0.4572)
			(layers "F.Cu" "F.Mask" "F.Paste")
			(net "P5E_PEX3_STN5_RX_DP<93>")
		)
		(pad "B38" smd circle
			(at 12.349988 -21.850096)
			(size 0.4572 0.4572)
			(layers "F.Cu" "F.Mask" "F.Paste")
			(net "GND")
		)
		(pad "B39" smd circle
			(at 13.299948 -21.850096)
			(size 0.4572 0.4572)
			(layers "F.Cu" "F.Mask" "F.Paste")
			(net "P5E_PEX3_STN5_RX_DP<95>")
		)
		(pad "B40" smd circle
			(at 14.249908 -21.850096)
			(size 0.4572 0.4572)
			(layers "F.Cu" "F.Mask" "F.Paste")
			(net "GND")
		)
		(pad "B41" smd circle
			(at 15.200122 -21.850096)
			(size 0.4572 0.4572)
			(layers "F.Cu" "F.Mask" "F.Paste")
			(net "P5E_PEX3_STN4_RX_DP<78>")
		)
		(pad "B42" smd circle
			(at 16.150082 -21.850096)
			(size 0.4572 0.4572)
			(layers "F.Cu" "F.Mask" "F.Paste")
			(net "GND")
		)
		(pad "B43" smd circle
			(at 17.100042 -21.850096)
			(size 0.4572 0.4572)
			(layers "F.Cu" "F.Mask" "F.Paste")
			(net "P5E_PEX3_STN4_RX_DP<76>")
		)
		(pad "B44" smd circle
			(at 18.050002 -21.850096)
			(size 0.4572 0.4572)
			(layers "F.Cu" "F.Mask" "F.Paste")
			(net "GND")
		)
		(pad "B45" smd circle
			(at 18.999962 -21.850096)
			(size 0.4572 0.4572)
			(layers "F.Cu" "F.Mask" "F.Paste")
			(net "P5E_PEX3_STN4_RX_DP<74>")
		)
		(pad "B46" smd circle
			(at 19.949922 -21.850096)
			(size 0.4572 0.4572)
			(layers "F.Cu" "F.Mask" "F.Paste")
			(net "GND")
		)
		(pad "B47" smd circle
			(at 20.899882 -21.850096)
			(size 0.4572 0.4572)
			(layers "F.Cu" "F.Mask" "F.Paste")
			(net "P5E_PEX3_STN4_RX_DP<72>")
		)
		(pad "B48" smd circle
			(at 21.850096 -21.850096)
			(size 0.4572 0.4572)
			(layers "F.Cu" "F.Mask" "F.Paste")
			(net "GND")
		)
		(pad "B49" smd circle
			(at 22.800056 -21.850096)
			(size 0.4572 0.4572)
			(layers "F.Cu" "F.Mask" "F.Paste")
			(net "GND")
		)
		(pad "BA1" smd circle
			(at -22.800056 15.200122)
			(size 0.4572 0.4572)
			(layers "F.Cu" "F.Mask" "F.Paste")
			(net "GND")
		)
		(pad "BA2" smd circle
			(at -21.850096 15.200122)
			(size 0.4572 0.4572)
			(layers "F.Cu" "F.Mask" "F.Paste")
			(net "GND")
		)
		(pad "BA3" smd circle
			(at -20.899882 15.200122)
			(size 0.4572 0.4572)
			(layers "F.Cu" "F.Mask" "F.Paste")
			(net "GND")
		)
		(pad "BA4" smd circle
			(at -19.949922 15.200122)
			(size 0.4572 0.4572)
			(layers "F.Cu" "F.Mask" "F.Paste")
			(net "Net_1450")
		)
		(pad "BA5" smd circle
			(at -18.999962 15.200122)
			(size 0.4572 0.4572)
			(layers "F.Cu" "F.Mask" "F.Paste")
			(net "GND")
		)
		(pad "BA6" smd circle
			(at -18.050002 15.200122)
			(size 0.4572 0.4572)
			(layers "F.Cu" "F.Mask" "F.Paste")
			(net "Net_1361")
		)
		(pad "BA7" smd circle
			(at -17.100042 15.200122)
			(size 0.4572 0.4572)
			(layers "F.Cu" "F.Mask" "F.Paste")
			(net "GND")
		)
		(pad "BA8" smd circle
			(at -16.150082 15.200122)
			(size 0.4572 0.4572)
			(layers "F.Cu" "F.Mask" "F.Paste")
			(net "Net_1440")
		)
		(pad "BA9" smd circle
			(at -15.200122 15.200122)
			(size 0.4572 0.4572)
			(layers "F.Cu" "F.Mask" "F.Paste")
			(net "GND")
		)
		(pad "BA10" smd circle
			(at -14.249908 15.200122)
			(size 0.4572 0.4572)
			(layers "F.Cu" "F.Mask" "F.Paste")
			(net "P5E_PEX3_STN2_TX_DP<46>")
		)
		(pad "BA11" smd circle
			(at -13.299948 15.200122)
			(size 0.4572 0.4572)
			(layers "F.Cu" "F.Mask" "F.Paste")
			(net "GND")
		)
		(pad "BA12" smd circle
			(at -12.349988 15.200122)
			(size 0.4572 0.4572)
			(layers "F.Cu" "F.Mask" "F.Paste")
			(net "P5E_PEX3_STN2_TX_DP<44>")
		)
		(pad "BA13" smd circle
			(at -11.400028 15.200122)
			(size 0.4572 0.4572)
			(layers "F.Cu" "F.Mask" "F.Paste")
			(net "GND")
		)
		(pad "BA14" smd circle
			(at -10.450068 15.200122)
			(size 0.4572 0.4572)
			(layers "F.Cu" "F.Mask" "F.Paste")
			(net "P5E_PEX3_STN2_TX_DP<42>")
		)
		(pad "BA15" smd circle
			(at -9.500108 15.200122)
			(size 0.4572 0.4572)
			(layers "F.Cu" "F.Mask" "F.Paste")
			(net "GND")
		)
		(pad "BA16" smd circle
			(at -8.549894 15.200122)
			(size 0.4572 0.4572)
			(layers "F.Cu" "F.Mask" "F.Paste")
			(net "P5E_PEX3_STN2_TX_DP<40>")
		)
		(pad "BA17" smd circle
			(at -7.599934 15.200122)
			(size 0.4572 0.4572)
			(layers "F.Cu" "F.Mask" "F.Paste")
			(net "GND")
		)
		(pad "BA18" smd circle
			(at -6.649974 15.200122)
			(size 0.4572 0.4572)
			(layers "F.Cu" "F.Mask" "F.Paste")
			(net "P5E_PEX3_STN2_TX_DP<38>")
		)
		(pad "BA19" smd circle
			(at -5.700014 15.200122)
			(size 0.4572 0.4572)
			(layers "F.Cu" "F.Mask" "F.Paste")
			(net "GND")
		)
		(pad "BA20" smd circle
			(at -4.750054 15.200122)
			(size 0.4572 0.4572)
			(layers "F.Cu" "F.Mask" "F.Paste")
			(net "P5E_PEX3_STN2_TX_DP<36>")
		)
		(pad "BA21" smd circle
			(at -3.800094 15.200122)
			(size 0.4572 0.4572)
			(layers "F.Cu" "F.Mask" "F.Paste")
			(net "GND")
		)
		(pad "BA22" smd circle
			(at -2.84988 15.200122)
			(size 0.4572 0.4572)
			(layers "F.Cu" "F.Mask" "F.Paste")
			(net "P5E_PEX3_STN2_TX_DP<34>")
		)
		(pad "BA23" smd circle
			(at -1.89992 15.200122)
			(size 0.4572 0.4572)
			(layers "F.Cu" "F.Mask" "F.Paste")
			(net "GND")
		)
		(pad "BA24" smd circle
			(at -0.94996 15.200122)
			(size 0.4572 0.4572)
			(layers "F.Cu" "F.Mask" "F.Paste")
			(net "P5E_PEX3_STN2_TX_DP<32>")
		)
		(pad "BA25" smd circle
			(at 0 15.200122)
			(size 0.4572 0.4572)
			(layers "F.Cu" "F.Mask" "F.Paste")
			(net "GND")
		)
		(pad "BA26" smd circle
			(at 0.94996 15.200122)
			(size 0.4572 0.4572)
			(layers "F.Cu" "F.Mask" "F.Paste")
			(net "P5E_PEX3_STN1_TX_DN<17>")
		)
		(pad "BA27" smd circle
			(at 1.89992 15.200122)
			(size 0.4572 0.4572)
			(layers "F.Cu" "F.Mask" "F.Paste")
			(net "GND")
		)
		(pad "BA28" smd circle
			(at 2.84988 15.200122)
			(size 0.4572 0.4572)
			(layers "F.Cu" "F.Mask" "F.Paste")
			(net "P5E_PEX3_STN1_TX_DN<19>")
		)
		(pad "BA29" smd circle
			(at 3.800094 15.200122)
			(size 0.4572 0.4572)
			(layers "F.Cu" "F.Mask" "F.Paste")
			(net "GND")
		)
		(pad "BA30" smd circle
			(at 4.750054 15.200122)
			(size 0.4572 0.4572)
			(layers "F.Cu" "F.Mask" "F.Paste")
			(net "P5E_PEX3_STN1_TX_DN<21>")
		)
		(pad "BA31" smd circle
			(at 5.700014 15.200122)
			(size 0.4572 0.4572)
			(layers "F.Cu" "F.Mask" "F.Paste")
			(net "GND")
		)
		(pad "BA32" smd circle
			(at 6.649974 15.200122)
			(size 0.4572 0.4572)
			(layers "F.Cu" "F.Mask" "F.Paste")
			(net "P5E_PEX3_STN1_TX_DN<23>")
		)
		(pad "BA33" smd circle
			(at 7.599934 15.200122)
			(size 0.4572 0.4572)
			(layers "F.Cu" "F.Mask" "F.Paste")
			(net "GND")
		)
		(pad "BA34" smd circle
			(at 8.549894 15.200122)
			(size 0.4572 0.4572)
			(layers "F.Cu" "F.Mask" "F.Paste")
			(net "P5E_PEX3_STN1_TX_DN<25>")
		)
		(pad "BA35" smd circle
			(at 9.500108 15.200122)
			(size 0.4572 0.4572)
			(layers "F.Cu" "F.Mask" "F.Paste")
			(net "GND")
		)
		(pad "BA36" smd circle
			(at 10.450068 15.200122)
			(size 0.4572 0.4572)
			(layers "F.Cu" "F.Mask" "F.Paste")
			(net "P5E_PEX3_STN1_TX_DN<27>")
		)
		(pad "BA37" smd circle
			(at 11.400028 15.200122)
			(size 0.4572 0.4572)
			(layers "F.Cu" "F.Mask" "F.Paste")
			(net "GND")
		)
		(pad "BA38" smd circle
			(at 12.349988 15.200122)
			(size 0.4572 0.4572)
			(layers "F.Cu" "F.Mask" "F.Paste")
			(net "P5E_PEX3_STN1_TX_DN<29>")
		)
		(pad "BA39" smd circle
			(at 13.299948 15.200122)
			(size 0.4572 0.4572)
			(layers "F.Cu" "F.Mask" "F.Paste")
			(net "GND")
		)
		(pad "BA40" smd circle
			(at 14.249908 15.200122)
			(size 0.4572 0.4572)
			(layers "F.Cu" "F.Mask" "F.Paste")
			(net "P5E_PEX3_STN1_TX_DN<31>")
		)
		(pad "BA41" smd circle
			(at 15.200122 15.200122)
			(size 0.4572 0.4572)
			(layers "F.Cu" "F.Mask" "F.Paste")
			(net "GND")
		)
		(pad "BA42" smd circle
			(at 16.150082 15.200122)
			(size 0.4572 0.4572)
			(layers "F.Cu" "F.Mask" "F.Paste")
			(net "P5E_PEX3_STN0_TX_DN<14>")
		)
		(pad "BA43" smd circle
			(at 17.100042 15.200122)
			(size 0.4572 0.4572)
			(layers "F.Cu" "F.Mask" "F.Paste")
			(net "GND")
		)
		(pad "BA44" smd circle
			(at 18.050002 15.200122)
			(size 0.4572 0.4572)
			(layers "F.Cu" "F.Mask" "F.Paste")
			(net "P5E_PEX3_STN0_TX_DN<12>")
		)
		(pad "BA45" smd circle
			(at 18.999962 15.200122)
			(size 0.4572 0.4572)
			(layers "F.Cu" "F.Mask" "F.Paste")
			(net "GND")
		)
		(pad "BA46" smd circle
			(at 19.949922 15.200122)
			(size 0.4572 0.4572)
			(layers "F.Cu" "F.Mask" "F.Paste")
			(net "P5E_PEX3_STN0_TX_DP<10>")
		)
		(pad "BA47" smd circle
			(at 20.899882 15.200122)
			(size 0.4572 0.4572)
			(layers "F.Cu" "F.Mask" "F.Paste")
			(net "GND")
		)
		(pad "BA48" smd circle
			(at 21.850096 15.200122)
			(size 0.4572 0.4572)
			(layers "F.Cu" "F.Mask" "F.Paste")
			(net "GND")
		)
		(pad "BA49" smd circle
			(at 22.800056 15.200122)
			(size 0.4572 0.4572)
			(layers "F.Cu" "F.Mask" "F.Paste")
			(net "GND")
		)
		(pad "BB1" smd circle
			(at -22.800056 16.150082)
			(size 0.4572 0.4572)
			(layers "F.Cu" "F.Mask" "F.Paste")
			(net "Net_1728")
		)
		(pad "BB2" smd circle
			(at -21.850096 16.150082)
			(size 0.4572 0.4572)
			(layers "F.Cu" "F.Mask" "F.Paste")
			(net "Net_1469")
		)
		(pad "BB3" smd circle
			(at -20.899882 16.150082)
			(size 0.4572 0.4572)
			(layers "F.Cu" "F.Mask" "F.Paste")
			(net "GND")
		)
		(pad "BB4" smd circle
			(at -19.949922 16.150082)
			(size 0.4572 0.4572)
			(layers "F.Cu" "F.Mask" "F.Paste")
			(net "Net_1458")
		)
		(pad "BB5" smd circle
			(at -18.999962 16.150082)
			(size 0.4572 0.4572)
			(layers "F.Cu" "F.Mask" "F.Paste")
			(net "GND")
		)
		(pad "BB6" smd circle
			(at -18.050002 16.150082)
			(size 0.4572 0.4572)
			(layers "F.Cu" "F.Mask" "F.Paste")
			(net "Net_1446")
		)
		(pad "BB7" smd circle
			(at -17.100042 16.150082)
			(size 0.4572 0.4572)
			(layers "F.Cu" "F.Mask" "F.Paste")
			(net "GND")
		)
		(pad "BB8" smd circle
			(at -16.150082 16.150082)
			(size 0.4572 0.4572)
			(layers "F.Cu" "F.Mask" "F.Paste")
			(net "Net_1412")
		)
		(pad "BB9" smd circle
			(at -15.200122 16.150082)
			(size 0.4572 0.4572)
			(layers "F.Cu" "F.Mask" "F.Paste")
			(net "GND")
		)
		(pad "BB10" smd circle
			(at -14.249908 16.150082)
			(size 0.4572 0.4572)
			(layers "F.Cu" "F.Mask" "F.Paste")
			(net "P5E_PEX3_STN2_TX_DN<46>")
		)
		(pad "BB11" smd circle
			(at -13.299948 16.150082)
			(size 0.4572 0.4572)
			(layers "F.Cu" "F.Mask" "F.Paste")
			(net "GND")
		)
		(pad "BB12" smd circle
			(at -12.349988 16.150082)
			(size 0.4572 0.4572)
			(layers "F.Cu" "F.Mask" "F.Paste")
			(net "P5E_PEX3_STN2_TX_DN<44>")
		)
		(pad "BB13" smd circle
			(at -11.400028 16.150082)
			(size 0.4572 0.4572)
			(layers "F.Cu" "F.Mask" "F.Paste")
			(net "GND")
		)
		(pad "BB14" smd circle
			(at -10.450068 16.150082)
			(size 0.4572 0.4572)
			(layers "F.Cu" "F.Mask" "F.Paste")
			(net "P5E_PEX3_STN2_TX_DN<42>")
		)
		(pad "BB15" smd circle
			(at -9.500108 16.150082)
			(size 0.4572 0.4572)
			(layers "F.Cu" "F.Mask" "F.Paste")
			(net "GND")
		)
		(pad "BB16" smd circle
			(at -8.549894 16.150082)
			(size 0.4572 0.4572)
			(layers "F.Cu" "F.Mask" "F.Paste")
			(net "P5E_PEX3_STN2_TX_DN<40>")
		)
		(pad "BB17" smd circle
			(at -7.599934 16.150082)
			(size 0.4572 0.4572)
			(layers "F.Cu" "F.Mask" "F.Paste")
			(net "GND")
		)
		(pad "BB18" smd circle
			(at -6.649974 16.150082)
			(size 0.4572 0.4572)
			(layers "F.Cu" "F.Mask" "F.Paste")
			(net "P5E_PEX3_STN2_TX_DN<38>")
		)
		(pad "BB19" smd circle
			(at -5.700014 16.150082)
			(size 0.4572 0.4572)
			(layers "F.Cu" "F.Mask" "F.Paste")
			(net "GND")
		)
		(pad "BB20" smd circle
			(at -4.750054 16.150082)
			(size 0.4572 0.4572)
			(layers "F.Cu" "F.Mask" "F.Paste")
			(net "P5E_PEX3_STN2_TX_DN<36>")
		)
		(pad "BB21" smd circle
			(at -3.800094 16.150082)
			(size 0.4572 0.4572)
			(layers "F.Cu" "F.Mask" "F.Paste")
			(net "GND")
		)
		(pad "BB22" smd circle
			(at -2.84988 16.150082)
			(size 0.4572 0.4572)
			(layers "F.Cu" "F.Mask" "F.Paste")
			(net "P5E_PEX3_STN2_TX_DN<34>")
		)
		(pad "BB23" smd circle
			(at -1.89992 16.150082)
			(size 0.4572 0.4572)
			(layers "F.Cu" "F.Mask" "F.Paste")
			(net "GND")
		)
		(pad "BB24" smd circle
			(at -0.94996 16.150082)
			(size 0.4572 0.4572)
			(layers "F.Cu" "F.Mask" "F.Paste")
			(net "P5E_PEX3_STN2_TX_DN<32>")
		)
		(pad "BB25" smd circle
			(at 0 16.150082)
			(size 0.4572 0.4572)
			(layers "F.Cu" "F.Mask" "F.Paste")
			(net "GND")
		)
		(pad "BB26" smd circle
			(at 0.94996 16.150082)
			(size 0.4572 0.4572)
			(layers "F.Cu" "F.Mask" "F.Paste")
			(net "P5E_PEX3_STN1_TX_DP<17>")
		)
		(pad "BB27" smd circle
			(at 1.89992 16.150082)
			(size 0.4572 0.4572)
			(layers "F.Cu" "F.Mask" "F.Paste")
			(net "GND")
		)
		(pad "BB28" smd circle
			(at 2.84988 16.150082)
			(size 0.4572 0.4572)
			(layers "F.Cu" "F.Mask" "F.Paste")
			(net "P5E_PEX3_STN1_TX_DP<19>")
		)
		(pad "BB29" smd circle
			(at 3.800094 16.150082)
			(size 0.4572 0.4572)
			(layers "F.Cu" "F.Mask" "F.Paste")
			(net "GND")
		)
		(pad "BB30" smd circle
			(at 4.750054 16.150082)
			(size 0.4572 0.4572)
			(layers "F.Cu" "F.Mask" "F.Paste")
			(net "P5E_PEX3_STN1_TX_DP<21>")
		)
		(pad "BB31" smd circle
			(at 5.700014 16.150082)
			(size 0.4572 0.4572)
			(layers "F.Cu" "F.Mask" "F.Paste")
			(net "GND")
		)
		(pad "BB32" smd circle
			(at 6.649974 16.150082)
			(size 0.4572 0.4572)
			(layers "F.Cu" "F.Mask" "F.Paste")
			(net "P5E_PEX3_STN1_TX_DP<23>")
		)
		(pad "BB33" smd circle
			(at 7.599934 16.150082)
			(size 0.4572 0.4572)
			(layers "F.Cu" "F.Mask" "F.Paste")
			(net "GND")
		)
		(pad "BB34" smd circle
			(at 8.549894 16.150082)
			(size 0.4572 0.4572)
			(layers "F.Cu" "F.Mask" "F.Paste")
			(net "P5E_PEX3_STN1_TX_DP<25>")
		)
		(pad "BB35" smd circle
			(at 9.500108 16.150082)
			(size 0.4572 0.4572)
			(layers "F.Cu" "F.Mask" "F.Paste")
			(net "GND")
		)
		(pad "BB36" smd circle
			(at 10.450068 16.150082)
			(size 0.4572 0.4572)
			(layers "F.Cu" "F.Mask" "F.Paste")
			(net "P5E_PEX3_STN1_TX_DP<27>")
		)
		(pad "BB37" smd circle
			(at 11.400028 16.150082)
			(size 0.4572 0.4572)
			(layers "F.Cu" "F.Mask" "F.Paste")
			(net "GND")
		)
		(pad "BB38" smd circle
			(at 12.349988 16.150082)
			(size 0.4572 0.4572)
			(layers "F.Cu" "F.Mask" "F.Paste")
			(net "P5E_PEX3_STN1_TX_DP<29>")
		)
		(pad "BB39" smd circle
			(at 13.299948 16.150082)
			(size 0.4572 0.4572)
			(layers "F.Cu" "F.Mask" "F.Paste")
			(net "GND")
		)
		(pad "BB40" smd circle
			(at 14.249908 16.150082)
			(size 0.4572 0.4572)
			(layers "F.Cu" "F.Mask" "F.Paste")
			(net "P5E_PEX3_STN1_TX_DP<31>")
		)
		(pad "BB41" smd circle
			(at 15.200122 16.150082)
			(size 0.4572 0.4572)
			(layers "F.Cu" "F.Mask" "F.Paste")
			(net "GND")
		)
		(pad "BB42" smd circle
			(at 16.150082 16.150082)
			(size 0.4572 0.4572)
			(layers "F.Cu" "F.Mask" "F.Paste")
			(net "P5E_PEX3_STN0_TX_DP<14>")
		)
		(pad "BB43" smd circle
			(at 17.100042 16.150082)
			(size 0.4572 0.4572)
			(layers "F.Cu" "F.Mask" "F.Paste")
			(net "GND")
		)
		(pad "BB44" smd circle
			(at 18.050002 16.150082)
			(size 0.4572 0.4572)
			(layers "F.Cu" "F.Mask" "F.Paste")
			(net "P5E_PEX3_STN0_TX_DP<12>")
		)
		(pad "BB45" smd circle
			(at 18.999962 16.150082)
			(size 0.4572 0.4572)
			(layers "F.Cu" "F.Mask" "F.Paste")
			(net "GND")
		)
		(pad "BB46" smd circle
			(at 19.949922 16.150082)
			(size 0.4572 0.4572)
			(layers "F.Cu" "F.Mask" "F.Paste")
			(net "P5E_PEX3_STN0_TX_DN<10>")
		)
		(pad "BB47" smd circle
			(at 20.899882 16.150082)
			(size 0.4572 0.4572)
			(layers "F.Cu" "F.Mask" "F.Paste")
			(net "GND")
		)
		(pad "BB48" smd circle
			(at 21.850096 16.150082)
			(size 0.4572 0.4572)
			(layers "F.Cu" "F.Mask" "F.Paste")
			(net "P5E_PEX3_STN0_TX_DP<7>")
		)
		(pad "BB49" smd circle
			(at 22.800056 16.150082)
			(size 0.4572 0.4572)
			(layers "F.Cu" "F.Mask" "F.Paste")
			(net "P5E_PEX3_STN0_TX_DN<7>")
		)
		(pad "BC1" smd circle
			(at -22.800056 17.100042)
			(size 0.4572 0.4572)
			(layers "F.Cu" "F.Mask" "F.Paste")
			(net "GND")
		)
		(pad "BC2" smd circle
			(at -21.850096 17.100042)
			(size 0.4572 0.4572)
			(layers "F.Cu" "F.Mask" "F.Paste")
			(net "GND")
		)
		(pad "BC3" smd circle
			(at -20.899882 17.100042)
			(size 0.4572 0.4572)
			(layers "F.Cu" "F.Mask" "F.Paste")
			(net "Net_1428")
		)
		(pad "BC4" smd circle
			(at -19.949922 17.100042)
			(size 0.4572 0.4572)
			(layers "F.Cu" "F.Mask" "F.Paste")
			(net "GND")
		)
		(pad "BC5" smd circle
			(at -18.999962 17.100042)
			(size 0.4572 0.4572)
			(layers "F.Cu" "F.Mask" "F.Paste")
			(net "Net_1452")
		)
		(pad "BC6" smd circle
			(at -18.050002 17.100042)
			(size 0.4572 0.4572)
			(layers "F.Cu" "F.Mask" "F.Paste")
			(net "GND")
		)
		(pad "BC7" smd circle
			(at -17.100042 17.100042)
			(size 0.4572 0.4572)
			(layers "F.Cu" "F.Mask" "F.Paste")
			(net "Net_1466")
		)
		(pad "BC8" smd circle
			(at -16.150082 17.100042)
			(size 0.4572 0.4572)
			(layers "F.Cu" "F.Mask" "F.Paste")
			(net "GND")
		)
		(pad "BC9" smd circle
			(at -15.200122 17.100042)
			(size 0.4572 0.4572)
			(layers "F.Cu" "F.Mask" "F.Paste")
			(net "P5E_PEX3_STN2_TX_DP<47>")
		)
		(pad "BC10" smd circle
			(at -14.249908 17.100042)
			(size 0.4572 0.4572)
			(layers "F.Cu" "F.Mask" "F.Paste")
			(net "GND")
		)
		(pad "BC11" smd circle
			(at -13.299948 17.100042)
			(size 0.4572 0.4572)
			(layers "F.Cu" "F.Mask" "F.Paste")
			(net "P5E_PEX3_STN2_TX_DP<45>")
		)
		(pad "BC12" smd circle
			(at -12.349988 17.100042)
			(size 0.4572 0.4572)
			(layers "F.Cu" "F.Mask" "F.Paste")
			(net "GND")
		)
		(pad "BC13" smd circle
			(at -11.400028 17.100042)
			(size 0.4572 0.4572)
			(layers "F.Cu" "F.Mask" "F.Paste")
			(net "P5E_PEX3_STN2_TX_DP<43>")
		)
		(pad "BC14" smd circle
			(at -10.450068 17.100042)
			(size 0.4572 0.4572)
			(layers "F.Cu" "F.Mask" "F.Paste")
			(net "GND")
		)
		(pad "BC15" smd circle
			(at -9.500108 17.100042)
			(size 0.4572 0.4572)
			(layers "F.Cu" "F.Mask" "F.Paste")
			(net "P5E_PEX3_STN2_TX_DP<41>")
		)
		(pad "BC16" smd circle
			(at -8.549894 17.100042)
			(size 0.4572 0.4572)
			(layers "F.Cu" "F.Mask" "F.Paste")
			(net "GND")
		)
		(pad "BC17" smd circle
			(at -7.599934 17.100042)
			(size 0.4572 0.4572)
			(layers "F.Cu" "F.Mask" "F.Paste")
			(net "P5E_PEX3_STN2_TX_DP<39>")
		)
		(pad "BC18" smd circle
			(at -6.649974 17.100042)
			(size 0.4572 0.4572)
			(layers "F.Cu" "F.Mask" "F.Paste")
			(net "GND")
		)
		(pad "BC19" smd circle
			(at -5.700014 17.100042)
			(size 0.4572 0.4572)
			(layers "F.Cu" "F.Mask" "F.Paste")
			(net "P5E_PEX3_STN2_TX_DP<37>")
		)
		(pad "BC20" smd circle
			(at -4.750054 17.100042)
			(size 0.4572 0.4572)
			(layers "F.Cu" "F.Mask" "F.Paste")
			(net "GND")
		)
		(pad "BC21" smd circle
			(at -3.800094 17.100042)
			(size 0.4572 0.4572)
			(layers "F.Cu" "F.Mask" "F.Paste")
			(net "P5E_PEX3_STN2_TX_DP<35>")
		)
		(pad "BC22" smd circle
			(at -2.84988 17.100042)
			(size 0.4572 0.4572)
			(layers "F.Cu" "F.Mask" "F.Paste")
			(net "GND")
		)
		(pad "BC23" smd circle
			(at -1.89992 17.100042)
			(size 0.4572 0.4572)
			(layers "F.Cu" "F.Mask" "F.Paste")
			(net "P5E_PEX3_STN2_TX_DP<33>")
		)
		(pad "BC24" smd circle
			(at -0.94996 17.100042)
			(size 0.4572 0.4572)
			(layers "F.Cu" "F.Mask" "F.Paste")
			(net "GND")
		)
		(pad "BC25" smd circle
			(at 0 17.100042)
			(size 0.4572 0.4572)
			(layers "F.Cu" "F.Mask" "F.Paste")
			(net "P5E_PEX3_STN1_TX_DP<16>")
		)
		(pad "BC26" smd circle
			(at 0.94996 17.100042)
			(size 0.4572 0.4572)
			(layers "F.Cu" "F.Mask" "F.Paste")
			(net "GND")
		)
		(pad "BC27" smd circle
			(at 1.89992 17.100042)
			(size 0.4572 0.4572)
			(layers "F.Cu" "F.Mask" "F.Paste")
			(net "P5E_PEX3_STN1_TX_DP<18>")
		)
		(pad "BC28" smd circle
			(at 2.84988 17.100042)
			(size 0.4572 0.4572)
			(layers "F.Cu" "F.Mask" "F.Paste")
			(net "GND")
		)
		(pad "BC29" smd circle
			(at 3.800094 17.100042)
			(size 0.4572 0.4572)
			(layers "F.Cu" "F.Mask" "F.Paste")
			(net "P5E_PEX3_STN1_TX_DP<20>")
		)
		(pad "BC30" smd circle
			(at 4.750054 17.100042)
			(size 0.4572 0.4572)
			(layers "F.Cu" "F.Mask" "F.Paste")
			(net "GND")
		)
		(pad "BC31" smd circle
			(at 5.700014 17.100042)
			(size 0.4572 0.4572)
			(layers "F.Cu" "F.Mask" "F.Paste")
			(net "P5E_PEX3_STN1_TX_DP<22>")
		)
		(pad "BC32" smd circle
			(at 6.649974 17.100042)
			(size 0.4572 0.4572)
			(layers "F.Cu" "F.Mask" "F.Paste")
			(net "GND")
		)
		(pad "BC33" smd circle
			(at 7.599934 17.100042)
			(size 0.4572 0.4572)
			(layers "F.Cu" "F.Mask" "F.Paste")
			(net "P5E_PEX3_STN1_TX_DP<24>")
		)
		(pad "BC34" smd circle
			(at 8.549894 17.100042)
			(size 0.4572 0.4572)
			(layers "F.Cu" "F.Mask" "F.Paste")
			(net "GND")
		)
		(pad "BC35" smd circle
			(at 9.500108 17.100042)
			(size 0.4572 0.4572)
			(layers "F.Cu" "F.Mask" "F.Paste")
			(net "P5E_PEX3_STN1_TX_DP<26>")
		)
		(pad "BC36" smd circle
			(at 10.450068 17.100042)
			(size 0.4572 0.4572)
			(layers "F.Cu" "F.Mask" "F.Paste")
			(net "GND")
		)
		(pad "BC37" smd circle
			(at 11.400028 17.100042)
			(size 0.4572 0.4572)
			(layers "F.Cu" "F.Mask" "F.Paste")
			(net "P5E_PEX3_STN1_TX_DP<28>")
		)
		(pad "BC38" smd circle
			(at 12.349988 17.100042)
			(size 0.4572 0.4572)
			(layers "F.Cu" "F.Mask" "F.Paste")
			(net "GND")
		)
		(pad "BC39" smd circle
			(at 13.299948 17.100042)
			(size 0.4572 0.4572)
			(layers "F.Cu" "F.Mask" "F.Paste")
			(net "P5E_PEX3_STN1_TX_DP<30>")
		)
		(pad "BC40" smd circle
			(at 14.249908 17.100042)
			(size 0.4572 0.4572)
			(layers "F.Cu" "F.Mask" "F.Paste")
			(net "GND")
		)
		(pad "BC41" smd circle
			(at 15.200122 17.100042)
			(size 0.4572 0.4572)
			(layers "F.Cu" "F.Mask" "F.Paste")
			(net "P5E_PEX3_STN0_TX_DP<15>")
		)
		(pad "BC42" smd circle
			(at 16.150082 17.100042)
			(size 0.4572 0.4572)
			(layers "F.Cu" "F.Mask" "F.Paste")
			(net "GND")
		)
		(pad "BC43" smd circle
			(at 17.100042 17.100042)
			(size 0.4572 0.4572)
			(layers "F.Cu" "F.Mask" "F.Paste")
			(net "P5E_PEX3_STN0_TX_DP<13>")
		)
		(pad "BC44" smd circle
			(at 18.050002 17.100042)
			(size 0.4572 0.4572)
			(layers "F.Cu" "F.Mask" "F.Paste")
			(net "GND")
		)
		(pad "BC45" smd circle
			(at 18.999962 17.100042)
			(size 0.4572 0.4572)
			(layers "F.Cu" "F.Mask" "F.Paste")
			(net "P5E_PEX3_STN0_TX_DP<11>")
		)
		(pad "BC46" smd circle
			(at 19.949922 17.100042)
			(size 0.4572 0.4572)
			(layers "F.Cu" "F.Mask" "F.Paste")
			(net "GND")
		)
		(pad "BC47" smd circle
			(at 20.899882 17.100042)
			(size 0.4572 0.4572)
			(layers "F.Cu" "F.Mask" "F.Paste")
			(net "P5E_PEX3_STN0_TX_DP<9>")
		)
		(pad "BC48" smd circle
			(at 21.850096 17.100042)
			(size 0.4572 0.4572)
			(layers "F.Cu" "F.Mask" "F.Paste")
			(net "GND")
		)
		(pad "BC49" smd circle
			(at 22.800056 17.100042)
			(size 0.4572 0.4572)
			(layers "F.Cu" "F.Mask" "F.Paste")
			(net "GND")
		)
		(pad "BD1" smd circle
			(at -22.800056 18.050002)
			(size 0.4572 0.4572)
			(layers "F.Cu" "F.Mask" "F.Paste")
			(net "GND")
		)
		(pad "BD2" smd circle
			(at -21.850096 18.050002)
			(size 0.4572 0.4572)
			(layers "F.Cu" "F.Mask" "F.Paste")
			(net "GND")
		)
		(pad "BD3" smd circle
			(at -20.899882 18.050002)
			(size 0.4572 0.4572)
			(layers "F.Cu" "F.Mask" "F.Paste")
			(net "Net_1434")
		)
		(pad "BD4" smd circle
			(at -19.949922 18.050002)
			(size 0.4572 0.4572)
			(layers "F.Cu" "F.Mask" "F.Paste")
			(net "GND")
		)
		(pad "BD5" smd circle
			(at -18.999962 18.050002)
			(size 0.4572 0.4572)
			(layers "F.Cu" "F.Mask" "F.Paste")
			(net "Net_1465")
		)
		(pad "BD6" smd circle
			(at -18.050002 18.050002)
			(size 0.4572 0.4572)
			(layers "F.Cu" "F.Mask" "F.Paste")
			(net "GND")
		)
		(pad "BD7" smd circle
			(at -17.100042 18.050002)
			(size 0.4572 0.4572)
			(layers "F.Cu" "F.Mask" "F.Paste")
			(net "Net_1395")
		)
		(pad "BD8" smd circle
			(at -16.150082 18.050002)
			(size 0.4572 0.4572)
			(layers "F.Cu" "F.Mask" "F.Paste")
			(net "GND")
		)
		(pad "BD9" smd circle
			(at -15.200122 18.050002)
			(size 0.4572 0.4572)
			(layers "F.Cu" "F.Mask" "F.Paste")
			(net "P5E_PEX3_STN2_TX_DN<47>")
		)
		(pad "BD10" smd circle
			(at -14.249908 18.050002)
			(size 0.4572 0.4572)
			(layers "F.Cu" "F.Mask" "F.Paste")
			(net "GND")
		)
		(pad "BD11" smd circle
			(at -13.299948 18.050002)
			(size 0.4572 0.4572)
			(layers "F.Cu" "F.Mask" "F.Paste")
			(net "P5E_PEX3_STN2_TX_DN<45>")
		)
		(pad "BD12" smd circle
			(at -12.349988 18.050002)
			(size 0.4572 0.4572)
			(layers "F.Cu" "F.Mask" "F.Paste")
			(net "GND")
		)
		(pad "BD13" smd circle
			(at -11.400028 18.050002)
			(size 0.4572 0.4572)
			(layers "F.Cu" "F.Mask" "F.Paste")
			(net "P5E_PEX3_STN2_TX_DN<43>")
		)
		(pad "BD14" smd circle
			(at -10.450068 18.050002)
			(size 0.4572 0.4572)
			(layers "F.Cu" "F.Mask" "F.Paste")
			(net "GND")
		)
		(pad "BD15" smd circle
			(at -9.500108 18.050002)
			(size 0.4572 0.4572)
			(layers "F.Cu" "F.Mask" "F.Paste")
			(net "P5E_PEX3_STN2_TX_DN<41>")
		)
		(pad "BD16" smd circle
			(at -8.549894 18.050002)
			(size 0.4572 0.4572)
			(layers "F.Cu" "F.Mask" "F.Paste")
			(net "GND")
		)
		(pad "BD17" smd circle
			(at -7.599934 18.050002)
			(size 0.4572 0.4572)
			(layers "F.Cu" "F.Mask" "F.Paste")
			(net "P5E_PEX3_STN2_TX_DN<39>")
		)
		(pad "BD18" smd circle
			(at -6.649974 18.050002)
			(size 0.4572 0.4572)
			(layers "F.Cu" "F.Mask" "F.Paste")
			(net "GND")
		)
		(pad "BD19" smd circle
			(at -5.700014 18.050002)
			(size 0.4572 0.4572)
			(layers "F.Cu" "F.Mask" "F.Paste")
			(net "P5E_PEX3_STN2_TX_DN<37>")
		)
		(pad "BD20" smd circle
			(at -4.750054 18.050002)
			(size 0.4572 0.4572)
			(layers "F.Cu" "F.Mask" "F.Paste")
			(net "GND")
		)
		(pad "BD21" smd circle
			(at -3.800094 18.050002)
			(size 0.4572 0.4572)
			(layers "F.Cu" "F.Mask" "F.Paste")
			(net "P5E_PEX3_STN2_TX_DN<35>")
		)
		(pad "BD22" smd circle
			(at -2.84988 18.050002)
			(size 0.4572 0.4572)
			(layers "F.Cu" "F.Mask" "F.Paste")
			(net "GND")
		)
		(pad "BD23" smd circle
			(at -1.89992 18.050002)
			(size 0.4572 0.4572)
			(layers "F.Cu" "F.Mask" "F.Paste")
			(net "P5E_PEX3_STN2_TX_DN<33>")
		)
		(pad "BD24" smd circle
			(at -0.94996 18.050002)
			(size 0.4572 0.4572)
			(layers "F.Cu" "F.Mask" "F.Paste")
			(net "GND")
		)
		(pad "BD25" smd circle
			(at 0 18.050002)
			(size 0.4572 0.4572)
			(layers "F.Cu" "F.Mask" "F.Paste")
			(net "P5E_PEX3_STN1_TX_DN<16>")
		)
		(pad "BD26" smd circle
			(at 0.94996 18.050002)
			(size 0.4572 0.4572)
			(layers "F.Cu" "F.Mask" "F.Paste")
			(net "GND")
		)
		(pad "BD27" smd circle
			(at 1.89992 18.050002)
			(size 0.4572 0.4572)
			(layers "F.Cu" "F.Mask" "F.Paste")
			(net "P5E_PEX3_STN1_TX_DN<18>")
		)
		(pad "BD28" smd circle
			(at 2.84988 18.050002)
			(size 0.4572 0.4572)
			(layers "F.Cu" "F.Mask" "F.Paste")
			(net "GND")
		)
		(pad "BD29" smd circle
			(at 3.800094 18.050002)
			(size 0.4572 0.4572)
			(layers "F.Cu" "F.Mask" "F.Paste")
			(net "P5E_PEX3_STN1_TX_DN<20>")
		)
		(pad "BD30" smd circle
			(at 4.750054 18.050002)
			(size 0.4572 0.4572)
			(layers "F.Cu" "F.Mask" "F.Paste")
			(net "GND")
		)
		(pad "BD31" smd circle
			(at 5.700014 18.050002)
			(size 0.4572 0.4572)
			(layers "F.Cu" "F.Mask" "F.Paste")
			(net "P5E_PEX3_STN1_TX_DN<22>")
		)
		(pad "BD32" smd circle
			(at 6.649974 18.050002)
			(size 0.4572 0.4572)
			(layers "F.Cu" "F.Mask" "F.Paste")
			(net "GND")
		)
		(pad "BD33" smd circle
			(at 7.599934 18.050002)
			(size 0.4572 0.4572)
			(layers "F.Cu" "F.Mask" "F.Paste")
			(net "P5E_PEX3_STN1_TX_DN<24>")
		)
		(pad "BD34" smd circle
			(at 8.549894 18.050002)
			(size 0.4572 0.4572)
			(layers "F.Cu" "F.Mask" "F.Paste")
			(net "GND")
		)
		(pad "BD35" smd circle
			(at 9.500108 18.050002)
			(size 0.4572 0.4572)
			(layers "F.Cu" "F.Mask" "F.Paste")
			(net "P5E_PEX3_STN1_TX_DN<26>")
		)
		(pad "BD36" smd circle
			(at 10.450068 18.050002)
			(size 0.4572 0.4572)
			(layers "F.Cu" "F.Mask" "F.Paste")
			(net "GND")
		)
		(pad "BD37" smd circle
			(at 11.400028 18.050002)
			(size 0.4572 0.4572)
			(layers "F.Cu" "F.Mask" "F.Paste")
			(net "P5E_PEX3_STN1_TX_DN<28>")
		)
		(pad "BD38" smd circle
			(at 12.349988 18.050002)
			(size 0.4572 0.4572)
			(layers "F.Cu" "F.Mask" "F.Paste")
			(net "GND")
		)
		(pad "BD39" smd circle
			(at 13.299948 18.050002)
			(size 0.4572 0.4572)
			(layers "F.Cu" "F.Mask" "F.Paste")
			(net "P5E_PEX3_STN1_TX_DN<30>")
		)
		(pad "BD40" smd circle
			(at 14.249908 18.050002)
			(size 0.4572 0.4572)
			(layers "F.Cu" "F.Mask" "F.Paste")
			(net "GND")
		)
		(pad "BD41" smd circle
			(at 15.200122 18.050002)
			(size 0.4572 0.4572)
			(layers "F.Cu" "F.Mask" "F.Paste")
			(net "P5E_PEX3_STN0_TX_DN<15>")
		)
		(pad "BD42" smd circle
			(at 16.150082 18.050002)
			(size 0.4572 0.4572)
			(layers "F.Cu" "F.Mask" "F.Paste")
			(net "GND")
		)
		(pad "BD43" smd circle
			(at 17.100042 18.050002)
			(size 0.4572 0.4572)
			(layers "F.Cu" "F.Mask" "F.Paste")
			(net "P5E_PEX3_STN0_TX_DN<13>")
		)
		(pad "BD44" smd circle
			(at 18.050002 18.050002)
			(size 0.4572 0.4572)
			(layers "F.Cu" "F.Mask" "F.Paste")
			(net "GND")
		)
		(pad "BD45" smd circle
			(at 18.999962 18.050002)
			(size 0.4572 0.4572)
			(layers "F.Cu" "F.Mask" "F.Paste")
			(net "P5E_PEX3_STN0_TX_DN<11>")
		)
		(pad "BD46" smd circle
			(at 19.949922 18.050002)
			(size 0.4572 0.4572)
			(layers "F.Cu" "F.Mask" "F.Paste")
			(net "GND")
		)
		(pad "BD47" smd circle
			(at 20.899882 18.050002)
			(size 0.4572 0.4572)
			(layers "F.Cu" "F.Mask" "F.Paste")
			(net "P5E_PEX3_STN0_TX_DN<9>")
		)
		(pad "BD48" smd circle
			(at 21.850096 18.050002)
			(size 0.4572 0.4572)
			(layers "F.Cu" "F.Mask" "F.Paste")
			(net "GND")
		)
		(pad "BD49" smd circle
			(at 22.800056 18.050002)
			(size 0.4572 0.4572)
			(layers "F.Cu" "F.Mask" "F.Paste")
			(net "GND")
		)
		(pad "BE1" smd circle
			(at -22.800056 18.999962)
			(size 0.4572 0.4572)
			(layers "F.Cu" "F.Mask" "F.Paste")
			(net "Net_1455")
		)
		(pad "BE2" smd circle
			(at -21.850096 18.999962)
			(size 0.4572 0.4572)
			(layers "F.Cu" "F.Mask" "F.Paste")
			(net "Net_1423")
		)
		(pad "BE3" smd circle
			(at -20.899882 18.999962)
			(size 0.4572 0.4572)
			(layers "F.Cu" "F.Mask" "F.Paste")
			(net "GND")
		)
		(pad "BE4" smd circle
			(at -19.949922 18.999962)
			(size 0.4572 0.4572)
			(layers "F.Cu" "F.Mask" "F.Paste")
			(net "GND")
		)
		(pad "BE5" smd circle
			(at -18.999962 18.999962)
			(size 0.4572 0.4572)
			(layers "F.Cu" "F.Mask" "F.Paste")
			(net "GND")
		)
		(pad "BE6" smd circle
			(at -18.050002 18.999962)
			(size 0.4572 0.4572)
			(layers "F.Cu" "F.Mask" "F.Paste")
			(net "GND")
		)
		(pad "BE7" smd circle
			(at -17.100042 18.999962)
			(size 0.4572 0.4572)
			(layers "F.Cu" "F.Mask" "F.Paste")
			(net "GND")
		)
		(pad "BE8" smd circle
			(at -16.150082 18.999962)
			(size 0.4572 0.4572)
			(layers "F.Cu" "F.Mask" "F.Paste")
			(net "GND")
		)
		(pad "BE9" smd circle
			(at -15.200122 18.999962)
			(size 0.4572 0.4572)
			(layers "F.Cu" "F.Mask" "F.Paste")
			(net "GND")
		)
		(pad "BE10" smd circle
			(at -14.249908 18.999962)
			(size 0.4572 0.4572)
			(layers "F.Cu" "F.Mask" "F.Paste")
			(net "GND")
		)
		(pad "BE11" smd circle
			(at -13.299948 18.999962)
			(size 0.4572 0.4572)
			(layers "F.Cu" "F.Mask" "F.Paste")
			(net "GND")
		)
		(pad "BE12" smd circle
			(at -12.349988 18.999962)
			(size 0.4572 0.4572)
			(layers "F.Cu" "F.Mask" "F.Paste")
			(net "GND")
		)
		(pad "BE13" smd circle
			(at -11.400028 18.999962)
			(size 0.4572 0.4572)
			(layers "F.Cu" "F.Mask" "F.Paste")
			(net "GND")
		)
		(pad "BE14" smd circle
			(at -10.450068 18.999962)
			(size 0.4572 0.4572)
			(layers "F.Cu" "F.Mask" "F.Paste")
			(net "GND")
		)
		(pad "BE15" smd circle
			(at -9.500108 18.999962)
			(size 0.4572 0.4572)
			(layers "F.Cu" "F.Mask" "F.Paste")
			(net "GND")
		)
		(pad "BE16" smd circle
			(at -8.549894 18.999962)
			(size 0.4572 0.4572)
			(layers "F.Cu" "F.Mask" "F.Paste")
			(net "GND")
		)
		(pad "BE17" smd circle
			(at -7.599934 18.999962)
			(size 0.4572 0.4572)
			(layers "F.Cu" "F.Mask" "F.Paste")
			(net "GND")
		)
		(pad "BE18" smd circle
			(at -6.649974 18.999962)
			(size 0.4572 0.4572)
			(layers "F.Cu" "F.Mask" "F.Paste")
			(net "GND")
		)
		(pad "BE19" smd circle
			(at -5.700014 18.999962)
			(size 0.4572 0.4572)
			(layers "F.Cu" "F.Mask" "F.Paste")
			(net "GND")
		)
		(pad "BE20" smd circle
			(at -4.750054 18.999962)
			(size 0.4572 0.4572)
			(layers "F.Cu" "F.Mask" "F.Paste")
			(net "GND")
		)
		(pad "BE21" smd circle
			(at -3.800094 18.999962)
			(size 0.4572 0.4572)
			(layers "F.Cu" "F.Mask" "F.Paste")
			(net "GND")
		)
		(pad "BE22" smd circle
			(at -2.84988 18.999962)
			(size 0.4572 0.4572)
			(layers "F.Cu" "F.Mask" "F.Paste")
			(net "GND")
		)
		(pad "BE23" smd circle
			(at -1.89992 18.999962)
			(size 0.4572 0.4572)
			(layers "F.Cu" "F.Mask" "F.Paste")
			(net "GND")
		)
		(pad "BE24" smd circle
			(at -0.94996 18.999962)
			(size 0.4572 0.4572)
			(layers "F.Cu" "F.Mask" "F.Paste")
			(net "GND")
		)
		(pad "BE25" smd circle
			(at 0 18.999962)
			(size 0.4572 0.4572)
			(layers "F.Cu" "F.Mask" "F.Paste")
			(net "GND")
		)
		(pad "BE26" smd circle
			(at 0.94996 18.999962)
			(size 0.4572 0.4572)
			(layers "F.Cu" "F.Mask" "F.Paste")
			(net "GND")
		)
		(pad "BE27" smd circle
			(at 1.89992 18.999962)
			(size 0.4572 0.4572)
			(layers "F.Cu" "F.Mask" "F.Paste")
			(net "GND")
		)
		(pad "BE28" smd circle
			(at 2.84988 18.999962)
			(size 0.4572 0.4572)
			(layers "F.Cu" "F.Mask" "F.Paste")
			(net "GND")
		)
		(pad "BE29" smd circle
			(at 3.800094 18.999962)
			(size 0.4572 0.4572)
			(layers "F.Cu" "F.Mask" "F.Paste")
			(net "GND")
		)
		(pad "BE30" smd circle
			(at 4.750054 18.999962)
			(size 0.4572 0.4572)
			(layers "F.Cu" "F.Mask" "F.Paste")
			(net "GND")
		)
		(pad "BE31" smd circle
			(at 5.700014 18.999962)
			(size 0.4572 0.4572)
			(layers "F.Cu" "F.Mask" "F.Paste")
			(net "GND")
		)
		(pad "BE32" smd circle
			(at 6.649974 18.999962)
			(size 0.4572 0.4572)
			(layers "F.Cu" "F.Mask" "F.Paste")
			(net "GND")
		)
		(pad "BE33" smd circle
			(at 7.599934 18.999962)
			(size 0.4572 0.4572)
			(layers "F.Cu" "F.Mask" "F.Paste")
			(net "GND")
		)
		(pad "BE34" smd circle
			(at 8.549894 18.999962)
			(size 0.4572 0.4572)
			(layers "F.Cu" "F.Mask" "F.Paste")
			(net "GND")
		)
		(pad "BE35" smd circle
			(at 9.500108 18.999962)
			(size 0.4572 0.4572)
			(layers "F.Cu" "F.Mask" "F.Paste")
			(net "GND")
		)
		(pad "BE36" smd circle
			(at 10.450068 18.999962)
			(size 0.4572 0.4572)
			(layers "F.Cu" "F.Mask" "F.Paste")
			(net "GND")
		)
		(pad "BE37" smd circle
			(at 11.400028 18.999962)
			(size 0.4572 0.4572)
			(layers "F.Cu" "F.Mask" "F.Paste")
			(net "GND")
		)
		(pad "BE38" smd circle
			(at 12.349988 18.999962)
			(size 0.4572 0.4572)
			(layers "F.Cu" "F.Mask" "F.Paste")
			(net "GND")
		)
		(pad "BE39" smd circle
			(at 13.299948 18.999962)
			(size 0.4572 0.4572)
			(layers "F.Cu" "F.Mask" "F.Paste")
			(net "GND")
		)
		(pad "BE40" smd circle
			(at 14.249908 18.999962)
			(size 0.4572 0.4572)
			(layers "F.Cu" "F.Mask" "F.Paste")
			(net "GND")
		)
		(pad "BE41" smd circle
			(at 15.200122 18.999962)
			(size 0.4572 0.4572)
			(layers "F.Cu" "F.Mask" "F.Paste")
			(net "GND")
		)
		(pad "BE42" smd circle
			(at 16.150082 18.999962)
			(size 0.4572 0.4572)
			(layers "F.Cu" "F.Mask" "F.Paste")
			(net "GND")
		)
		(pad "BE43" smd circle
			(at 17.100042 18.999962)
			(size 0.4572 0.4572)
			(layers "F.Cu" "F.Mask" "F.Paste")
			(net "GND")
		)
		(pad "BE44" smd circle
			(at 18.050002 18.999962)
			(size 0.4572 0.4572)
			(layers "F.Cu" "F.Mask" "F.Paste")
			(net "GND")
		)
		(pad "BE45" smd circle
			(at 18.999962 18.999962)
			(size 0.4572 0.4572)
			(layers "F.Cu" "F.Mask" "F.Paste")
			(net "GND")
		)
		(pad "BE46" smd circle
			(at 19.949922 18.999962)
			(size 0.4572 0.4572)
			(layers "F.Cu" "F.Mask" "F.Paste")
			(net "GND")
		)
		(pad "BE47" smd circle
			(at 20.899882 18.999962)
			(size 0.4572 0.4572)
			(layers "F.Cu" "F.Mask" "F.Paste")
			(net "GND")
		)
		(pad "BE48" smd circle
			(at 21.850096 18.999962)
			(size 0.4572 0.4572)
			(layers "F.Cu" "F.Mask" "F.Paste")
			(net "P5E_PEX3_STN0_TX_DP<8>")
		)
		(pad "BE49" smd circle
			(at 22.800056 18.999962)
			(size 0.4572 0.4572)
			(layers "F.Cu" "F.Mask" "F.Paste")
			(net "P5E_PEX3_STN0_TX_DN<8>")
		)
		(pad "BF1" smd circle
			(at -22.800056 19.949922)
			(size 0.4572 0.4572)
			(layers "F.Cu" "F.Mask" "F.Paste")
			(net "GND")
		)
		(pad "BF2" smd circle
			(at -21.850096 19.949922)
			(size 0.4572 0.4572)
			(layers "F.Cu" "F.Mask" "F.Paste")
			(net "GND")
		)
		(pad "BF3" smd circle
			(at -20.899882 19.949922)
			(size 0.4572 0.4572)
			(layers "F.Cu" "F.Mask" "F.Paste")
			(net "GND")
		)
		(pad "BF4" smd circle
			(at -19.949922 19.949922)
			(size 0.4572 0.4572)
			(layers "F.Cu" "F.Mask" "F.Paste")
			(net "Net_1498")
		)
		(pad "BF5" smd circle
			(at -18.999962 19.949922)
			(size 0.4572 0.4572)
			(layers "F.Cu" "F.Mask" "F.Paste")
			(net "GND")
		)
		(pad "BF6" smd circle
			(at -18.050002 19.949922)
			(size 0.4572 0.4572)
			(layers "F.Cu" "F.Mask" "F.Paste")
			(net "Net_1489")
		)
		(pad "BF7" smd circle
			(at -17.100042 19.949922)
			(size 0.4572 0.4572)
			(layers "F.Cu" "F.Mask" "F.Paste")
			(net "GND")
		)
		(pad "BF8" smd circle
			(at -16.150082 19.949922)
			(size 0.4572 0.4572)
			(layers "F.Cu" "F.Mask" "F.Paste")
			(net "Net_1424")
		)
		(pad "BF9" smd circle
			(at -15.200122 19.949922)
			(size 0.4572 0.4572)
			(layers "F.Cu" "F.Mask" "F.Paste")
			(net "GND")
		)
		(pad "BF10" smd circle
			(at -14.249908 19.949922)
			(size 0.4572 0.4572)
			(layers "F.Cu" "F.Mask" "F.Paste")
			(net "P5E_PEX3_STN2_RX_DP<46>")
		)
		(pad "BF11" smd circle
			(at -13.299948 19.949922)
			(size 0.4572 0.4572)
			(layers "F.Cu" "F.Mask" "F.Paste")
			(net "GND")
		)
		(pad "BF12" smd circle
			(at -12.349988 19.949922)
			(size 0.4572 0.4572)
			(layers "F.Cu" "F.Mask" "F.Paste")
			(net "P5E_PEX3_STN2_RX_DP<44>")
		)
		(pad "BF13" smd circle
			(at -11.400028 19.949922)
			(size 0.4572 0.4572)
			(layers "F.Cu" "F.Mask" "F.Paste")
			(net "GND")
		)
		(pad "BF14" smd circle
			(at -10.450068 19.949922)
			(size 0.4572 0.4572)
			(layers "F.Cu" "F.Mask" "F.Paste")
			(net "P5E_PEX3_STN2_RX_DP<42>")
		)
		(pad "BF15" smd circle
			(at -9.500108 19.949922)
			(size 0.4572 0.4572)
			(layers "F.Cu" "F.Mask" "F.Paste")
			(net "GND")
		)
		(pad "BF16" smd circle
			(at -8.549894 19.949922)
			(size 0.4572 0.4572)
			(layers "F.Cu" "F.Mask" "F.Paste")
			(net "P5E_PEX3_STN2_RX_DP<40>")
		)
		(pad "BF17" smd circle
			(at -7.599934 19.949922)
			(size 0.4572 0.4572)
			(layers "F.Cu" "F.Mask" "F.Paste")
			(net "GND")
		)
		(pad "BF18" smd circle
			(at -6.649974 19.949922)
			(size 0.4572 0.4572)
			(layers "F.Cu" "F.Mask" "F.Paste")
			(net "P5E_PEX3_STN2_RX_DP<38>")
		)
		(pad "BF19" smd circle
			(at -5.700014 19.949922)
			(size 0.4572 0.4572)
			(layers "F.Cu" "F.Mask" "F.Paste")
			(net "GND")
		)
		(pad "BF20" smd circle
			(at -4.750054 19.949922)
			(size 0.4572 0.4572)
			(layers "F.Cu" "F.Mask" "F.Paste")
			(net "P5E_PEX3_STN2_RX_DP<36>")
		)
		(pad "BF21" smd circle
			(at -3.800094 19.949922)
			(size 0.4572 0.4572)
			(layers "F.Cu" "F.Mask" "F.Paste")
			(net "GND")
		)
		(pad "BF22" smd circle
			(at -2.84988 19.949922)
			(size 0.4572 0.4572)
			(layers "F.Cu" "F.Mask" "F.Paste")
			(net "P5E_PEX3_STN2_RX_DP<34>")
		)
		(pad "BF23" smd circle
			(at -1.89992 19.949922)
			(size 0.4572 0.4572)
			(layers "F.Cu" "F.Mask" "F.Paste")
			(net "GND")
		)
		(pad "BF24" smd circle
			(at -0.94996 19.949922)
			(size 0.4572 0.4572)
			(layers "F.Cu" "F.Mask" "F.Paste")
			(net "P5E_PEX3_STN2_RX_DP<32>")
		)
		(pad "BF25" smd circle
			(at 0 19.949922)
			(size 0.4572 0.4572)
			(layers "F.Cu" "F.Mask" "F.Paste")
			(net "GND")
		)
		(pad "BF26" smd circle
			(at 0.94996 19.949922)
			(size 0.4572 0.4572)
			(layers "F.Cu" "F.Mask" "F.Paste")
			(net "P5E_PEX3_STN1_RX_DP<17>")
		)
		(pad "BF27" smd circle
			(at 1.89992 19.949922)
			(size 0.4572 0.4572)
			(layers "F.Cu" "F.Mask" "F.Paste")
			(net "GND")
		)
		(pad "BF28" smd circle
			(at 2.84988 19.949922)
			(size 0.4572 0.4572)
			(layers "F.Cu" "F.Mask" "F.Paste")
			(net "P5E_PEX3_STN1_RX_DP<19>")
		)
		(pad "BF29" smd circle
			(at 3.800094 19.949922)
			(size 0.4572 0.4572)
			(layers "F.Cu" "F.Mask" "F.Paste")
			(net "GND")
		)
		(pad "BF30" smd circle
			(at 4.750054 19.949922)
			(size 0.4572 0.4572)
			(layers "F.Cu" "F.Mask" "F.Paste")
			(net "P5E_PEX3_STN1_RX_DP<21>")
		)
		(pad "BF31" smd circle
			(at 5.700014 19.949922)
			(size 0.4572 0.4572)
			(layers "F.Cu" "F.Mask" "F.Paste")
			(net "GND")
		)
		(pad "BF32" smd circle
			(at 6.649974 19.949922)
			(size 0.4572 0.4572)
			(layers "F.Cu" "F.Mask" "F.Paste")
			(net "P5E_PEX3_STN1_RX_DP<23>")
		)
		(pad "BF33" smd circle
			(at 7.599934 19.949922)
			(size 0.4572 0.4572)
			(layers "F.Cu" "F.Mask" "F.Paste")
			(net "GND")
		)
		(pad "BF34" smd circle
			(at 8.549894 19.949922)
			(size 0.4572 0.4572)
			(layers "F.Cu" "F.Mask" "F.Paste")
			(net "P5E_PEX3_STN1_RX_DP<25>")
		)
		(pad "BF35" smd circle
			(at 9.500108 19.949922)
			(size 0.4572 0.4572)
			(layers "F.Cu" "F.Mask" "F.Paste")
			(net "GND")
		)
		(pad "BF36" smd circle
			(at 10.450068 19.949922)
			(size 0.4572 0.4572)
			(layers "F.Cu" "F.Mask" "F.Paste")
			(net "P5E_PEX3_STN1_RX_DP<27>")
		)
		(pad "BF37" smd circle
			(at 11.400028 19.949922)
			(size 0.4572 0.4572)
			(layers "F.Cu" "F.Mask" "F.Paste")
			(net "GND")
		)
		(pad "BF38" smd circle
			(at 12.349988 19.949922)
			(size 0.4572 0.4572)
			(layers "F.Cu" "F.Mask" "F.Paste")
			(net "P5E_PEX3_STN1_RX_DP<29>")
		)
		(pad "BF39" smd circle
			(at 13.299948 19.949922)
			(size 0.4572 0.4572)
			(layers "F.Cu" "F.Mask" "F.Paste")
			(net "GND")
		)
		(pad "BF40" smd circle
			(at 14.249908 19.949922)
			(size 0.4572 0.4572)
			(layers "F.Cu" "F.Mask" "F.Paste")
			(net "P5E_PEX3_STN1_RX_DP<31>")
		)
		(pad "BF41" smd circle
			(at 15.200122 19.949922)
			(size 0.4572 0.4572)
			(layers "F.Cu" "F.Mask" "F.Paste")
			(net "GND")
		)
		(pad "BF42" smd circle
			(at 16.150082 19.949922)
			(size 0.4572 0.4572)
			(layers "F.Cu" "F.Mask" "F.Paste")
			(net "P5E_PEX3_STN0_RX_DP<14>")
		)
		(pad "BF43" smd circle
			(at 17.100042 19.949922)
			(size 0.4572 0.4572)
			(layers "F.Cu" "F.Mask" "F.Paste")
			(net "GND")
		)
		(pad "BF44" smd circle
			(at 18.050002 19.949922)
			(size 0.4572 0.4572)
			(layers "F.Cu" "F.Mask" "F.Paste")
			(net "P5E_PEX3_STN0_RX_DP<12>")
		)
		(pad "BF45" smd circle
			(at 18.999962 19.949922)
			(size 0.4572 0.4572)
			(layers "F.Cu" "F.Mask" "F.Paste")
			(net "GND")
		)
		(pad "BF46" smd circle
			(at 19.949922 19.949922)
			(size 0.4572 0.4572)
			(layers "F.Cu" "F.Mask" "F.Paste")
			(net "P5E_PEX3_STN0_RX_DP<10>")
		)
		(pad "BF47" smd circle
			(at 20.899882 19.949922)
			(size 0.4572 0.4572)
			(layers "F.Cu" "F.Mask" "F.Paste")
			(net "GND")
		)
		(pad "BF48" smd circle
			(at 21.850096 19.949922)
			(size 0.4572 0.4572)
			(layers "F.Cu" "F.Mask" "F.Paste")
			(net "GND")
		)
		(pad "BF49" smd circle
			(at 22.800056 19.949922)
			(size 0.4572 0.4572)
			(layers "F.Cu" "F.Mask" "F.Paste")
			(net "GND")
		)
		(pad "BG1" smd circle
			(at -22.800056 20.899882)
			(size 0.4572 0.4572)
			(layers "F.Cu" "F.Mask" "F.Paste")
			(net "Net_1462")
		)
		(pad "BG2" smd circle
			(at -21.850096 20.899882)
			(size 0.4572 0.4572)
			(layers "F.Cu" "F.Mask" "F.Paste")
			(net "Net_1500")
		)
		(pad "BG3" smd circle
			(at -20.899882 20.899882)
			(size 0.4572 0.4572)
			(layers "F.Cu" "F.Mask" "F.Paste")
			(net "GND")
		)
		(pad "BG4" smd circle
			(at -19.949922 20.899882)
			(size 0.4572 0.4572)
			(layers "F.Cu" "F.Mask" "F.Paste")
			(net "Net_1404")
		)
		(pad "BG5" smd circle
			(at -18.999962 20.899882)
			(size 0.4572 0.4572)
			(layers "F.Cu" "F.Mask" "F.Paste")
			(net "GND")
		)
		(pad "BG6" smd circle
			(at -18.050002 20.899882)
			(size 0.4572 0.4572)
			(layers "F.Cu" "F.Mask" "F.Paste")
			(net "Net_1492")
		)
		(pad "BG7" smd circle
			(at -17.100042 20.899882)
			(size 0.4572 0.4572)
			(layers "F.Cu" "F.Mask" "F.Paste")
			(net "GND")
		)
		(pad "BG8" smd circle
			(at -16.150082 20.899882)
			(size 0.4572 0.4572)
			(layers "F.Cu" "F.Mask" "F.Paste")
			(net "Net_1477")
		)
		(pad "BG9" smd circle
			(at -15.200122 20.899882)
			(size 0.4572 0.4572)
			(layers "F.Cu" "F.Mask" "F.Paste")
			(net "GND")
		)
		(pad "BG10" smd circle
			(at -14.249908 20.899882)
			(size 0.4572 0.4572)
			(layers "F.Cu" "F.Mask" "F.Paste")
			(net "P5E_PEX3_STN2_RX_DN<46>")
		)
		(pad "BG11" smd circle
			(at -13.299948 20.899882)
			(size 0.4572 0.4572)
			(layers "F.Cu" "F.Mask" "F.Paste")
			(net "GND")
		)
		(pad "BG12" smd circle
			(at -12.349988 20.899882)
			(size 0.4572 0.4572)
			(layers "F.Cu" "F.Mask" "F.Paste")
			(net "P5E_PEX3_STN2_RX_DN<44>")
		)
		(pad "BG13" smd circle
			(at -11.400028 20.899882)
			(size 0.4572 0.4572)
			(layers "F.Cu" "F.Mask" "F.Paste")
			(net "GND")
		)
		(pad "BG14" smd circle
			(at -10.450068 20.899882)
			(size 0.4572 0.4572)
			(layers "F.Cu" "F.Mask" "F.Paste")
			(net "P5E_PEX3_STN2_RX_DN<42>")
		)
		(pad "BG15" smd circle
			(at -9.500108 20.899882)
			(size 0.4572 0.4572)
			(layers "F.Cu" "F.Mask" "F.Paste")
			(net "GND")
		)
		(pad "BG16" smd circle
			(at -8.549894 20.899882)
			(size 0.4572 0.4572)
			(layers "F.Cu" "F.Mask" "F.Paste")
			(net "P5E_PEX3_STN2_RX_DN<40>")
		)
		(pad "BG17" smd circle
			(at -7.599934 20.899882)
			(size 0.4572 0.4572)
			(layers "F.Cu" "F.Mask" "F.Paste")
			(net "GND")
		)
		(pad "BG18" smd circle
			(at -6.649974 20.899882)
			(size 0.4572 0.4572)
			(layers "F.Cu" "F.Mask" "F.Paste")
			(net "P5E_PEX3_STN2_RX_DN<38>")
		)
		(pad "BG19" smd circle
			(at -5.700014 20.899882)
			(size 0.4572 0.4572)
			(layers "F.Cu" "F.Mask" "F.Paste")
			(net "GND")
		)
		(pad "BG20" smd circle
			(at -4.750054 20.899882)
			(size 0.4572 0.4572)
			(layers "F.Cu" "F.Mask" "F.Paste")
			(net "P5E_PEX3_STN2_RX_DN<36>")
		)
		(pad "BG21" smd circle
			(at -3.800094 20.899882)
			(size 0.4572 0.4572)
			(layers "F.Cu" "F.Mask" "F.Paste")
			(net "GND")
		)
		(pad "BG22" smd circle
			(at -2.84988 20.899882)
			(size 0.4572 0.4572)
			(layers "F.Cu" "F.Mask" "F.Paste")
			(net "P5E_PEX3_STN2_RX_DN<34>")
		)
		(pad "BG23" smd circle
			(at -1.89992 20.899882)
			(size 0.4572 0.4572)
			(layers "F.Cu" "F.Mask" "F.Paste")
			(net "GND")
		)
		(pad "BG24" smd circle
			(at -0.94996 20.899882)
			(size 0.4572 0.4572)
			(layers "F.Cu" "F.Mask" "F.Paste")
			(net "P5E_PEX3_STN2_RX_DN<32>")
		)
		(pad "BG25" smd circle
			(at 0 20.899882)
			(size 0.4572 0.4572)
			(layers "F.Cu" "F.Mask" "F.Paste")
			(net "GND")
		)
		(pad "BG26" smd circle
			(at 0.94996 20.899882)
			(size 0.4572 0.4572)
			(layers "F.Cu" "F.Mask" "F.Paste")
			(net "P5E_PEX3_STN1_RX_DN<17>")
		)
		(pad "BG27" smd circle
			(at 1.89992 20.899882)
			(size 0.4572 0.4572)
			(layers "F.Cu" "F.Mask" "F.Paste")
			(net "GND")
		)
		(pad "BG28" smd circle
			(at 2.84988 20.899882)
			(size 0.4572 0.4572)
			(layers "F.Cu" "F.Mask" "F.Paste")
			(net "P5E_PEX3_STN1_RX_DN<19>")
		)
		(pad "BG29" smd circle
			(at 3.800094 20.899882)
			(size 0.4572 0.4572)
			(layers "F.Cu" "F.Mask" "F.Paste")
			(net "GND")
		)
		(pad "BG30" smd circle
			(at 4.750054 20.899882)
			(size 0.4572 0.4572)
			(layers "F.Cu" "F.Mask" "F.Paste")
			(net "P5E_PEX3_STN1_RX_DN<21>")
		)
		(pad "BG31" smd circle
			(at 5.700014 20.899882)
			(size 0.4572 0.4572)
			(layers "F.Cu" "F.Mask" "F.Paste")
			(net "GND")
		)
		(pad "BG32" smd circle
			(at 6.649974 20.899882)
			(size 0.4572 0.4572)
			(layers "F.Cu" "F.Mask" "F.Paste")
			(net "P5E_PEX3_STN1_RX_DN<23>")
		)
		(pad "BG33" smd circle
			(at 7.599934 20.899882)
			(size 0.4572 0.4572)
			(layers "F.Cu" "F.Mask" "F.Paste")
			(net "GND")
		)
		(pad "BG34" smd circle
			(at 8.549894 20.899882)
			(size 0.4572 0.4572)
			(layers "F.Cu" "F.Mask" "F.Paste")
			(net "P5E_PEX3_STN1_RX_DN<25>")
		)
		(pad "BG35" smd circle
			(at 9.500108 20.899882)
			(size 0.4572 0.4572)
			(layers "F.Cu" "F.Mask" "F.Paste")
			(net "GND")
		)
		(pad "BG36" smd circle
			(at 10.450068 20.899882)
			(size 0.4572 0.4572)
			(layers "F.Cu" "F.Mask" "F.Paste")
			(net "P5E_PEX3_STN1_RX_DN<27>")
		)
		(pad "BG37" smd circle
			(at 11.400028 20.899882)
			(size 0.4572 0.4572)
			(layers "F.Cu" "F.Mask" "F.Paste")
			(net "GND")
		)
		(pad "BG38" smd circle
			(at 12.349988 20.899882)
			(size 0.4572 0.4572)
			(layers "F.Cu" "F.Mask" "F.Paste")
			(net "P5E_PEX3_STN1_RX_DN<29>")
		)
		(pad "BG39" smd circle
			(at 13.299948 20.899882)
			(size 0.4572 0.4572)
			(layers "F.Cu" "F.Mask" "F.Paste")
			(net "GND")
		)
		(pad "BG40" smd circle
			(at 14.249908 20.899882)
			(size 0.4572 0.4572)
			(layers "F.Cu" "F.Mask" "F.Paste")
			(net "P5E_PEX3_STN1_RX_DN<31>")
		)
		(pad "BG41" smd circle
			(at 15.200122 20.899882)
			(size 0.4572 0.4572)
			(layers "F.Cu" "F.Mask" "F.Paste")
			(net "GND")
		)
		(pad "BG42" smd circle
			(at 16.150082 20.899882)
			(size 0.4572 0.4572)
			(layers "F.Cu" "F.Mask" "F.Paste")
			(net "P5E_PEX3_STN0_RX_DN<14>")
		)
		(pad "BG43" smd circle
			(at 17.100042 20.899882)
			(size 0.4572 0.4572)
			(layers "F.Cu" "F.Mask" "F.Paste")
			(net "GND")
		)
		(pad "BG44" smd circle
			(at 18.050002 20.899882)
			(size 0.4572 0.4572)
			(layers "F.Cu" "F.Mask" "F.Paste")
			(net "P5E_PEX3_STN0_RX_DN<12>")
		)
		(pad "BG45" smd circle
			(at 18.999962 20.899882)
			(size 0.4572 0.4572)
			(layers "F.Cu" "F.Mask" "F.Paste")
			(net "GND")
		)
		(pad "BG46" smd circle
			(at 19.949922 20.899882)
			(size 0.4572 0.4572)
			(layers "F.Cu" "F.Mask" "F.Paste")
			(net "P5E_PEX3_STN0_RX_DN<10>")
		)
		(pad "BG47" smd circle
			(at 20.899882 20.899882)
			(size 0.4572 0.4572)
			(layers "F.Cu" "F.Mask" "F.Paste")
			(net "GND")
		)
		(pad "BG48" smd circle
			(at 21.850096 20.899882)
			(size 0.4572 0.4572)
			(layers "F.Cu" "F.Mask" "F.Paste")
			(net "P5E_PEX3_STN0_RX_DP<8>")
		)
		(pad "BG49" smd circle
			(at 22.800056 20.899882)
			(size 0.4572 0.4572)
			(layers "F.Cu" "F.Mask" "F.Paste")
			(net "P5E_PEX3_STN0_RX_DN<8>")
		)
		(pad "BH1" smd circle
			(at -22.800056 21.850096)
			(size 0.4572 0.4572)
			(layers "F.Cu" "F.Mask" "F.Paste")
			(net "GND")
		)
		(pad "BH2" smd circle
			(at -21.850096 21.850096)
			(size 0.4572 0.4572)
			(layers "F.Cu" "F.Mask" "F.Paste")
			(net "GND")
		)
		(pad "BH3" smd circle
			(at -20.899882 21.850096)
			(size 0.4572 0.4572)
			(layers "F.Cu" "F.Mask" "F.Paste")
			(net "Net_1479")
		)
		(pad "BH4" smd circle
			(at -19.949922 21.850096)
			(size 0.4572 0.4572)
			(layers "F.Cu" "F.Mask" "F.Paste")
			(net "GND")
		)
		(pad "BH5" smd circle
			(at -18.999962 21.850096)
			(size 0.4572 0.4572)
			(layers "F.Cu" "F.Mask" "F.Paste")
			(net "Net_1512")
		)
		(pad "BH6" smd circle
			(at -18.050002 21.850096)
			(size 0.4572 0.4572)
			(layers "F.Cu" "F.Mask" "F.Paste")
			(net "GND")
		)
		(pad "BH7" smd circle
			(at -17.100042 21.850096)
			(size 0.4572 0.4572)
			(layers "F.Cu" "F.Mask" "F.Paste")
			(net "Net_1459")
		)
		(pad "BH8" smd circle
			(at -16.150082 21.850096)
			(size 0.4572 0.4572)
			(layers "F.Cu" "F.Mask" "F.Paste")
			(net "GND")
		)
		(pad "BH9" smd circle
			(at -15.200122 21.850096)
			(size 0.4572 0.4572)
			(layers "F.Cu" "F.Mask" "F.Paste")
			(net "P5E_PEX3_STN2_RX_DP<47>")
		)
		(pad "BH10" smd circle
			(at -14.249908 21.850096)
			(size 0.4572 0.4572)
			(layers "F.Cu" "F.Mask" "F.Paste")
			(net "GND")
		)
		(pad "BH11" smd circle
			(at -13.299948 21.850096)
			(size 0.4572 0.4572)
			(layers "F.Cu" "F.Mask" "F.Paste")
			(net "P5E_PEX3_STN2_RX_DP<45>")
		)
		(pad "BH12" smd circle
			(at -12.349988 21.850096)
			(size 0.4572 0.4572)
			(layers "F.Cu" "F.Mask" "F.Paste")
			(net "GND")
		)
		(pad "BH13" smd circle
			(at -11.400028 21.850096)
			(size 0.4572 0.4572)
			(layers "F.Cu" "F.Mask" "F.Paste")
			(net "P5E_PEX3_STN2_RX_DP<43>")
		)
		(pad "BH14" smd circle
			(at -10.450068 21.850096)
			(size 0.4572 0.4572)
			(layers "F.Cu" "F.Mask" "F.Paste")
			(net "GND")
		)
		(pad "BH15" smd circle
			(at -9.500108 21.850096)
			(size 0.4572 0.4572)
			(layers "F.Cu" "F.Mask" "F.Paste")
			(net "P5E_PEX3_STN2_RX_DP<41>")
		)
		(pad "BH16" smd circle
			(at -8.549894 21.850096)
			(size 0.4572 0.4572)
			(layers "F.Cu" "F.Mask" "F.Paste")
			(net "GND")
		)
		(pad "BH17" smd circle
			(at -7.599934 21.850096)
			(size 0.4572 0.4572)
			(layers "F.Cu" "F.Mask" "F.Paste")
			(net "P5E_PEX3_STN2_RX_DP<39>")
		)
		(pad "BH18" smd circle
			(at -6.649974 21.850096)
			(size 0.4572 0.4572)
			(layers "F.Cu" "F.Mask" "F.Paste")
			(net "GND")
		)
		(pad "BH19" smd circle
			(at -5.700014 21.850096)
			(size 0.4572 0.4572)
			(layers "F.Cu" "F.Mask" "F.Paste")
			(net "P5E_PEX3_STN2_RX_DP<37>")
		)
		(pad "BH20" smd circle
			(at -4.750054 21.850096)
			(size 0.4572 0.4572)
			(layers "F.Cu" "F.Mask" "F.Paste")
			(net "GND")
		)
		(pad "BH21" smd circle
			(at -3.800094 21.850096)
			(size 0.4572 0.4572)
			(layers "F.Cu" "F.Mask" "F.Paste")
			(net "P5E_PEX3_STN2_RX_DP<35>")
		)
		(pad "BH22" smd circle
			(at -2.84988 21.850096)
			(size 0.4572 0.4572)
			(layers "F.Cu" "F.Mask" "F.Paste")
			(net "GND")
		)
		(pad "BH23" smd circle
			(at -1.89992 21.850096)
			(size 0.4572 0.4572)
			(layers "F.Cu" "F.Mask" "F.Paste")
			(net "P5E_PEX3_STN2_RX_DP<33>")
		)
		(pad "BH24" smd circle
			(at -0.94996 21.850096)
			(size 0.4572 0.4572)
			(layers "F.Cu" "F.Mask" "F.Paste")
			(net "GND")
		)
		(pad "BH25" smd circle
			(at 0 21.850096)
			(size 0.4572 0.4572)
			(layers "F.Cu" "F.Mask" "F.Paste")
			(net "P5E_PEX3_STN1_RX_DP<16>")
		)
		(pad "BH26" smd circle
			(at 0.94996 21.850096)
			(size 0.4572 0.4572)
			(layers "F.Cu" "F.Mask" "F.Paste")
			(net "GND")
		)
		(pad "BH27" smd circle
			(at 1.89992 21.850096)
			(size 0.4572 0.4572)
			(layers "F.Cu" "F.Mask" "F.Paste")
			(net "P5E_PEX3_STN1_RX_DP<18>")
		)
		(pad "BH28" smd circle
			(at 2.84988 21.850096)
			(size 0.4572 0.4572)
			(layers "F.Cu" "F.Mask" "F.Paste")
			(net "GND")
		)
		(pad "BH29" smd circle
			(at 3.800094 21.850096)
			(size 0.4572 0.4572)
			(layers "F.Cu" "F.Mask" "F.Paste")
			(net "P5E_PEX3_STN1_RX_DP<20>")
		)
		(pad "BH30" smd circle
			(at 4.750054 21.850096)
			(size 0.4572 0.4572)
			(layers "F.Cu" "F.Mask" "F.Paste")
			(net "GND")
		)
		(pad "BH31" smd circle
			(at 5.700014 21.850096)
			(size 0.4572 0.4572)
			(layers "F.Cu" "F.Mask" "F.Paste")
			(net "P5E_PEX3_STN1_RX_DP<22>")
		)
		(pad "BH32" smd circle
			(at 6.649974 21.850096)
			(size 0.4572 0.4572)
			(layers "F.Cu" "F.Mask" "F.Paste")
			(net "GND")
		)
		(pad "BH33" smd circle
			(at 7.599934 21.850096)
			(size 0.4572 0.4572)
			(layers "F.Cu" "F.Mask" "F.Paste")
			(net "P5E_PEX3_STN1_RX_DP<24>")
		)
		(pad "BH34" smd circle
			(at 8.549894 21.850096)
			(size 0.4572 0.4572)
			(layers "F.Cu" "F.Mask" "F.Paste")
			(net "GND")
		)
		(pad "BH35" smd circle
			(at 9.500108 21.850096)
			(size 0.4572 0.4572)
			(layers "F.Cu" "F.Mask" "F.Paste")
			(net "P5E_PEX3_STN1_RX_DP<26>")
		)
		(pad "BH36" smd circle
			(at 10.450068 21.850096)
			(size 0.4572 0.4572)
			(layers "F.Cu" "F.Mask" "F.Paste")
			(net "GND")
		)
		(pad "BH37" smd circle
			(at 11.400028 21.850096)
			(size 0.4572 0.4572)
			(layers "F.Cu" "F.Mask" "F.Paste")
			(net "P5E_PEX3_STN1_RX_DP<28>")
		)
		(pad "BH38" smd circle
			(at 12.349988 21.850096)
			(size 0.4572 0.4572)
			(layers "F.Cu" "F.Mask" "F.Paste")
			(net "GND")
		)
		(pad "BH39" smd circle
			(at 13.299948 21.850096)
			(size 0.4572 0.4572)
			(layers "F.Cu" "F.Mask" "F.Paste")
			(net "P5E_PEX3_STN1_RX_DP<30>")
		)
		(pad "BH40" smd circle
			(at 14.249908 21.850096)
			(size 0.4572 0.4572)
			(layers "F.Cu" "F.Mask" "F.Paste")
			(net "GND")
		)
		(pad "BH41" smd circle
			(at 15.200122 21.850096)
			(size 0.4572 0.4572)
			(layers "F.Cu" "F.Mask" "F.Paste")
			(net "P5E_PEX3_STN0_RX_DP<15>")
		)
		(pad "BH42" smd circle
			(at 16.150082 21.850096)
			(size 0.4572 0.4572)
			(layers "F.Cu" "F.Mask" "F.Paste")
			(net "GND")
		)
		(pad "BH43" smd circle
			(at 17.100042 21.850096)
			(size 0.4572 0.4572)
			(layers "F.Cu" "F.Mask" "F.Paste")
			(net "P5E_PEX3_STN0_RX_DP<13>")
		)
		(pad "BH44" smd circle
			(at 18.050002 21.850096)
			(size 0.4572 0.4572)
			(layers "F.Cu" "F.Mask" "F.Paste")
			(net "GND")
		)
		(pad "BH45" smd circle
			(at 18.999962 21.850096)
			(size 0.4572 0.4572)
			(layers "F.Cu" "F.Mask" "F.Paste")
			(net "P5E_PEX3_STN0_RX_DP<11>")
		)
		(pad "BH46" smd circle
			(at 19.949922 21.850096)
			(size 0.4572 0.4572)
			(layers "F.Cu" "F.Mask" "F.Paste")
			(net "GND")
		)
		(pad "BH47" smd circle
			(at 20.899882 21.850096)
			(size 0.4572 0.4572)
			(layers "F.Cu" "F.Mask" "F.Paste")
			(net "P5E_PEX3_STN0_RX_DP<9>")
		)
		(pad "BH48" smd circle
			(at 21.850096 21.850096)
			(size 0.4572 0.4572)
			(layers "F.Cu" "F.Mask" "F.Paste")
			(net "GND")
		)
		(pad "BH49" smd circle
			(at 22.800056 21.850096)
			(size 0.4572 0.4572)
			(layers "F.Cu" "F.Mask" "F.Paste")
			(net "GND")
		)
		(pad "BJ2" smd circle
			(at -21.850096 22.800056)
			(size 0.4572 0.4572)
			(layers "F.Cu" "F.Mask" "F.Paste")
			(net "GND")
		)
		(pad "BJ3" smd circle
			(at -20.899882 22.800056)
			(size 0.4572 0.4572)
			(layers "F.Cu" "F.Mask" "F.Paste")
			(net "Net_1503")
		)
		(pad "BJ4" smd circle
			(at -19.949922 22.800056)
			(size 0.4572 0.4572)
			(layers "F.Cu" "F.Mask" "F.Paste")
			(net "GND")
		)
		(pad "BJ5" smd circle
			(at -18.999962 22.800056)
			(size 0.4572 0.4572)
			(layers "F.Cu" "F.Mask" "F.Paste")
			(net "Net_1475")
		)
		(pad "BJ6" smd circle
			(at -18.050002 22.800056)
			(size 0.4572 0.4572)
			(layers "F.Cu" "F.Mask" "F.Paste")
			(net "GND")
		)
		(pad "BJ7" smd circle
			(at -17.100042 22.800056)
			(size 0.4572 0.4572)
			(layers "F.Cu" "F.Mask" "F.Paste")
			(net "Net_1497")
		)
		(pad "BJ8" smd circle
			(at -16.150082 22.800056)
			(size 0.4572 0.4572)
			(layers "F.Cu" "F.Mask" "F.Paste")
			(net "GND")
		)
		(pad "BJ9" smd circle
			(at -15.200122 22.800056)
			(size 0.4572 0.4572)
			(layers "F.Cu" "F.Mask" "F.Paste")
			(net "P5E_PEX3_STN2_RX_DN<47>")
		)
		(pad "BJ10" smd circle
			(at -14.249908 22.800056)
			(size 0.4572 0.4572)
			(layers "F.Cu" "F.Mask" "F.Paste")
			(net "GND")
		)
		(pad "BJ11" smd circle
			(at -13.299948 22.800056)
			(size 0.4572 0.4572)
			(layers "F.Cu" "F.Mask" "F.Paste")
			(net "P5E_PEX3_STN2_RX_DN<45>")
		)
		(pad "BJ12" smd circle
			(at -12.349988 22.800056)
			(size 0.4572 0.4572)
			(layers "F.Cu" "F.Mask" "F.Paste")
			(net "GND")
		)
		(pad "BJ13" smd circle
			(at -11.400028 22.800056)
			(size 0.4572 0.4572)
			(layers "F.Cu" "F.Mask" "F.Paste")
			(net "P5E_PEX3_STN2_RX_DN<43>")
		)
		(pad "BJ14" smd circle
			(at -10.450068 22.800056)
			(size 0.4572 0.4572)
			(layers "F.Cu" "F.Mask" "F.Paste")
			(net "GND")
		)
		(pad "BJ15" smd circle
			(at -9.500108 22.800056)
			(size 0.4572 0.4572)
			(layers "F.Cu" "F.Mask" "F.Paste")
			(net "P5E_PEX3_STN2_RX_DN<41>")
		)
		(pad "BJ16" smd circle
			(at -8.549894 22.800056)
			(size 0.4572 0.4572)
			(layers "F.Cu" "F.Mask" "F.Paste")
			(net "GND")
		)
		(pad "BJ17" smd circle
			(at -7.599934 22.800056)
			(size 0.4572 0.4572)
			(layers "F.Cu" "F.Mask" "F.Paste")
			(net "P5E_PEX3_STN2_RX_DN<39>")
		)
		(pad "BJ18" smd circle
			(at -6.649974 22.800056)
			(size 0.4572 0.4572)
			(layers "F.Cu" "F.Mask" "F.Paste")
			(net "GND")
		)
		(pad "BJ19" smd circle
			(at -5.700014 22.800056)
			(size 0.4572 0.4572)
			(layers "F.Cu" "F.Mask" "F.Paste")
			(net "P5E_PEX3_STN2_RX_DN<37>")
		)
		(pad "BJ20" smd circle
			(at -4.750054 22.800056)
			(size 0.4572 0.4572)
			(layers "F.Cu" "F.Mask" "F.Paste")
			(net "GND")
		)
		(pad "BJ21" smd circle
			(at -3.800094 22.800056)
			(size 0.4572 0.4572)
			(layers "F.Cu" "F.Mask" "F.Paste")
			(net "P5E_PEX3_STN2_RX_DN<35>")
		)
		(pad "BJ22" smd circle
			(at -2.84988 22.800056)
			(size 0.4572 0.4572)
			(layers "F.Cu" "F.Mask" "F.Paste")
			(net "GND")
		)
		(pad "BJ23" smd circle
			(at -1.89992 22.800056)
			(size 0.4572 0.4572)
			(layers "F.Cu" "F.Mask" "F.Paste")
			(net "P5E_PEX3_STN2_RX_DN<33>")
		)
		(pad "BJ24" smd circle
			(at -0.94996 22.800056)
			(size 0.4572 0.4572)
			(layers "F.Cu" "F.Mask" "F.Paste")
			(net "GND")
		)
		(pad "BJ25" smd circle
			(at 0 22.800056)
			(size 0.4572 0.4572)
			(layers "F.Cu" "F.Mask" "F.Paste")
			(net "P5E_PEX3_STN1_RX_DN<16>")
		)
		(pad "BJ26" smd circle
			(at 0.94996 22.800056)
			(size 0.4572 0.4572)
			(layers "F.Cu" "F.Mask" "F.Paste")
			(net "GND")
		)
		(pad "BJ27" smd circle
			(at 1.89992 22.800056)
			(size 0.4572 0.4572)
			(layers "F.Cu" "F.Mask" "F.Paste")
			(net "P5E_PEX3_STN1_RX_DN<18>")
		)
		(pad "BJ28" smd circle
			(at 2.84988 22.800056)
			(size 0.4572 0.4572)
			(layers "F.Cu" "F.Mask" "F.Paste")
			(net "GND")
		)
		(pad "BJ29" smd circle
			(at 3.800094 22.800056)
			(size 0.4572 0.4572)
			(layers "F.Cu" "F.Mask" "F.Paste")
			(net "P5E_PEX3_STN1_RX_DN<20>")
		)
		(pad "BJ30" smd circle
			(at 4.750054 22.800056)
			(size 0.4572 0.4572)
			(layers "F.Cu" "F.Mask" "F.Paste")
			(net "GND")
		)
		(pad "BJ31" smd circle
			(at 5.700014 22.800056)
			(size 0.4572 0.4572)
			(layers "F.Cu" "F.Mask" "F.Paste")
			(net "P5E_PEX3_STN1_RX_DN<22>")
		)
		(pad "BJ32" smd circle
			(at 6.649974 22.800056)
			(size 0.4572 0.4572)
			(layers "F.Cu" "F.Mask" "F.Paste")
			(net "GND")
		)
		(pad "BJ33" smd circle
			(at 7.599934 22.800056)
			(size 0.4572 0.4572)
			(layers "F.Cu" "F.Mask" "F.Paste")
			(net "P5E_PEX3_STN1_RX_DN<24>")
		)
		(pad "BJ34" smd circle
			(at 8.549894 22.800056)
			(size 0.4572 0.4572)
			(layers "F.Cu" "F.Mask" "F.Paste")
			(net "GND")
		)
		(pad "BJ35" smd circle
			(at 9.500108 22.800056)
			(size 0.4572 0.4572)
			(layers "F.Cu" "F.Mask" "F.Paste")
			(net "P5E_PEX3_STN1_RX_DN<26>")
		)
		(pad "BJ36" smd circle
			(at 10.450068 22.800056)
			(size 0.4572 0.4572)
			(layers "F.Cu" "F.Mask" "F.Paste")
			(net "GND")
		)
		(pad "BJ37" smd circle
			(at 11.400028 22.800056)
			(size 0.4572 0.4572)
			(layers "F.Cu" "F.Mask" "F.Paste")
			(net "P5E_PEX3_STN1_RX_DN<28>")
		)
		(pad "BJ38" smd circle
			(at 12.349988 22.800056)
			(size 0.4572 0.4572)
			(layers "F.Cu" "F.Mask" "F.Paste")
			(net "GND")
		)
		(pad "BJ39" smd circle
			(at 13.299948 22.800056)
			(size 0.4572 0.4572)
			(layers "F.Cu" "F.Mask" "F.Paste")
			(net "P5E_PEX3_STN1_RX_DN<30>")
		)
		(pad "BJ40" smd circle
			(at 14.249908 22.800056)
			(size 0.4572 0.4572)
			(layers "F.Cu" "F.Mask" "F.Paste")
			(net "GND")
		)
		(pad "BJ41" smd circle
			(at 15.200122 22.800056)
			(size 0.4572 0.4572)
			(layers "F.Cu" "F.Mask" "F.Paste")
			(net "P5E_PEX3_STN0_RX_DN<15>")
		)
		(pad "BJ42" smd circle
			(at 16.150082 22.800056)
			(size 0.4572 0.4572)
			(layers "F.Cu" "F.Mask" "F.Paste")
			(net "GND")
		)
		(pad "BJ43" smd circle
			(at 17.100042 22.800056)
			(size 0.4572 0.4572)
			(layers "F.Cu" "F.Mask" "F.Paste")
			(net "P5E_PEX3_STN0_RX_DN<13>")
		)
		(pad "BJ44" smd circle
			(at 18.050002 22.800056)
			(size 0.4572 0.4572)
			(layers "F.Cu" "F.Mask" "F.Paste")
			(net "GND")
		)
		(pad "BJ45" smd circle
			(at 18.999962 22.800056)
			(size 0.4572 0.4572)
			(layers "F.Cu" "F.Mask" "F.Paste")
			(net "P5E_PEX3_STN0_RX_DN<11>")
		)
		(pad "BJ46" smd circle
			(at 19.949922 22.800056)
			(size 0.4572 0.4572)
			(layers "F.Cu" "F.Mask" "F.Paste")
			(net "GND")
		)
		(pad "BJ47" smd circle
			(at 20.899882 22.800056)
			(size 0.4572 0.4572)
			(layers "F.Cu" "F.Mask" "F.Paste")
			(net "P5E_PEX3_STN0_RX_DN<9>")
		)
		(pad "BJ48" smd circle
			(at 21.850096 22.800056)
			(size 0.4572 0.4572)
			(layers "F.Cu" "F.Mask" "F.Paste")
			(net "GND")
		)
		(pad "C1" smd circle
			(at -22.800056 -20.899882)
			(size 0.4572 0.4572)
			(layers "F.Cu" "F.Mask" "F.Paste")
			(net "P5E_PEX3_STN7_RX_DN<122>")
		)
		(pad "C2" smd circle
			(at -21.850096 -20.899882)
			(size 0.4572 0.4572)
			(layers "F.Cu" "F.Mask" "F.Paste")
			(net "P5E_PEX3_STN7_RX_DP<122>")
		)
		(pad "C3" smd circle
			(at -20.899882 -20.899882)
			(size 0.4572 0.4572)
			(layers "F.Cu" "F.Mask" "F.Paste")
			(net "GND")
		)
		(pad "C4" smd circle
			(at -19.949922 -20.899882)
			(size 0.4572 0.4572)
			(layers "F.Cu" "F.Mask" "F.Paste")
			(net "P5E_PEX3_STN7_RX_DN<124>")
		)
		(pad "C5" smd circle
			(at -18.999962 -20.899882)
			(size 0.4572 0.4572)
			(layers "F.Cu" "F.Mask" "F.Paste")
			(net "GND")
		)
		(pad "C6" smd circle
			(at -18.050002 -20.899882)
			(size 0.4572 0.4572)
			(layers "F.Cu" "F.Mask" "F.Paste")
			(net "P5E_PEX3_STN7_RX_DN<126>")
		)
		(pad "C7" smd circle
			(at -17.100042 -20.899882)
			(size 0.4572 0.4572)
			(layers "F.Cu" "F.Mask" "F.Paste")
			(net "GND")
		)
		(pad "C8" smd circle
			(at -16.150082 -20.899882)
			(size 0.4572 0.4572)
			(layers "F.Cu" "F.Mask" "F.Paste")
			(net "P5E_PEX3_STN6_RX_DN<111>")
		)
		(pad "C9" smd circle
			(at -15.200122 -20.899882)
			(size 0.4572 0.4572)
			(layers "F.Cu" "F.Mask" "F.Paste")
			(net "GND")
		)
		(pad "C10" smd circle
			(at -14.249908 -20.899882)
			(size 0.4572 0.4572)
			(layers "F.Cu" "F.Mask" "F.Paste")
			(net "P5E_PEX3_STN6_RX_DN<109>")
		)
		(pad "C11" smd circle
			(at -13.299948 -20.899882)
			(size 0.4572 0.4572)
			(layers "F.Cu" "F.Mask" "F.Paste")
			(net "GND")
		)
		(pad "C12" smd circle
			(at -12.349988 -20.899882)
			(size 0.4572 0.4572)
			(layers "F.Cu" "F.Mask" "F.Paste")
			(net "P5E_PEX3_STN6_RX_DN<107>")
		)
		(pad "C13" smd circle
			(at -11.400028 -20.899882)
			(size 0.4572 0.4572)
			(layers "F.Cu" "F.Mask" "F.Paste")
			(net "GND")
		)
		(pad "C14" smd circle
			(at -10.450068 -20.899882)
			(size 0.4572 0.4572)
			(layers "F.Cu" "F.Mask" "F.Paste")
			(net "P5E_PEX3_STN6_RX_DN<105>")
		)
		(pad "C15" smd circle
			(at -9.500108 -20.899882)
			(size 0.4572 0.4572)
			(layers "F.Cu" "F.Mask" "F.Paste")
			(net "GND")
		)
		(pad "C16" smd circle
			(at -8.549894 -20.899882)
			(size 0.4572 0.4572)
			(layers "F.Cu" "F.Mask" "F.Paste")
			(net "P5E_PEX3_STN6_RX_DN<103>")
		)
		(pad "C17" smd circle
			(at -7.599934 -20.899882)
			(size 0.4572 0.4572)
			(layers "F.Cu" "F.Mask" "F.Paste")
			(net "GND")
		)
		(pad "C18" smd circle
			(at -6.649974 -20.899882)
			(size 0.4572 0.4572)
			(layers "F.Cu" "F.Mask" "F.Paste")
			(net "P5E_PEX3_STN6_RX_DN<101>")
		)
		(pad "C19" smd circle
			(at -5.700014 -20.899882)
			(size 0.4572 0.4572)
			(layers "F.Cu" "F.Mask" "F.Paste")
			(net "GND")
		)
		(pad "C20" smd circle
			(at -4.750054 -20.899882)
			(size 0.4572 0.4572)
			(layers "F.Cu" "F.Mask" "F.Paste")
			(net "P5E_PEX3_STN6_RX_DN<99>")
		)
		(pad "C21" smd circle
			(at -3.800094 -20.899882)
			(size 0.4572 0.4572)
			(layers "F.Cu" "F.Mask" "F.Paste")
			(net "GND")
		)
		(pad "C22" smd circle
			(at -2.84988 -20.899882)
			(size 0.4572 0.4572)
			(layers "F.Cu" "F.Mask" "F.Paste")
			(net "P5E_PEX3_STN6_RX_DN<97>")
		)
		(pad "C23" smd circle
			(at -1.89992 -20.899882)
			(size 0.4572 0.4572)
			(layers "F.Cu" "F.Mask" "F.Paste")
			(net "GND")
		)
		(pad "C24" smd circle
			(at -0.94996 -20.899882)
			(size 0.4572 0.4572)
			(layers "F.Cu" "F.Mask" "F.Paste")
			(net "P5E_PEX3_STN5_RX_DN<80>")
		)
		(pad "C25" smd circle
			(at 0 -20.899882)
			(size 0.4572 0.4572)
			(layers "F.Cu" "F.Mask" "F.Paste")
			(net "GND")
		)
		(pad "C26" smd circle
			(at 0.94996 -20.899882)
			(size 0.4572 0.4572)
			(layers "F.Cu" "F.Mask" "F.Paste")
			(net "P5E_PEX3_STN5_RX_DN<82>")
		)
		(pad "C27" smd circle
			(at 1.89992 -20.899882)
			(size 0.4572 0.4572)
			(layers "F.Cu" "F.Mask" "F.Paste")
			(net "GND")
		)
		(pad "C28" smd circle
			(at 2.84988 -20.899882)
			(size 0.4572 0.4572)
			(layers "F.Cu" "F.Mask" "F.Paste")
			(net "P5E_PEX3_STN5_RX_DN<84>")
		)
		(pad "C29" smd circle
			(at 3.800094 -20.899882)
			(size 0.4572 0.4572)
			(layers "F.Cu" "F.Mask" "F.Paste")
			(net "GND")
		)
		(pad "C30" smd circle
			(at 4.750054 -20.899882)
			(size 0.4572 0.4572)
			(layers "F.Cu" "F.Mask" "F.Paste")
			(net "P5E_PEX3_STN5_RX_DN<86>")
		)
		(pad "C31" smd circle
			(at 5.700014 -20.899882)
			(size 0.4572 0.4572)
			(layers "F.Cu" "F.Mask" "F.Paste")
			(net "GND")
		)
		(pad "C32" smd circle
			(at 6.649974 -20.899882)
			(size 0.4572 0.4572)
			(layers "F.Cu" "F.Mask" "F.Paste")
			(net "P5E_PEX3_STN5_RX_DN<88>")
		)
		(pad "C33" smd circle
			(at 7.599934 -20.899882)
			(size 0.4572 0.4572)
			(layers "F.Cu" "F.Mask" "F.Paste")
			(net "GND")
		)
		(pad "C34" smd circle
			(at 8.549894 -20.899882)
			(size 0.4572 0.4572)
			(layers "F.Cu" "F.Mask" "F.Paste")
			(net "P5E_PEX3_STN5_RX_DN<90>")
		)
		(pad "C35" smd circle
			(at 9.500108 -20.899882)
			(size 0.4572 0.4572)
			(layers "F.Cu" "F.Mask" "F.Paste")
			(net "GND")
		)
		(pad "C36" smd circle
			(at 10.450068 -20.899882)
			(size 0.4572 0.4572)
			(layers "F.Cu" "F.Mask" "F.Paste")
			(net "P5E_PEX3_STN5_RX_DN<92>")
		)
		(pad "C37" smd circle
			(at 11.400028 -20.899882)
			(size 0.4572 0.4572)
			(layers "F.Cu" "F.Mask" "F.Paste")
			(net "GND")
		)
		(pad "C38" smd circle
			(at 12.349988 -20.899882)
			(size 0.4572 0.4572)
			(layers "F.Cu" "F.Mask" "F.Paste")
			(net "P5E_PEX3_STN5_RX_DN<94>")
		)
		(pad "C39" smd circle
			(at 13.299948 -20.899882)
			(size 0.4572 0.4572)
			(layers "F.Cu" "F.Mask" "F.Paste")
			(net "GND")
		)
		(pad "C40" smd circle
			(at 14.249908 -20.899882)
			(size 0.4572 0.4572)
			(layers "F.Cu" "F.Mask" "F.Paste")
			(net "P5E_PEX3_STN4_RX_DN<79>")
		)
		(pad "C41" smd circle
			(at 15.200122 -20.899882)
			(size 0.4572 0.4572)
			(layers "F.Cu" "F.Mask" "F.Paste")
			(net "GND")
		)
		(pad "C42" smd circle
			(at 16.150082 -20.899882)
			(size 0.4572 0.4572)
			(layers "F.Cu" "F.Mask" "F.Paste")
			(net "P5E_PEX3_STN4_RX_DN<77>")
		)
		(pad "C43" smd circle
			(at 17.100042 -20.899882)
			(size 0.4572 0.4572)
			(layers "F.Cu" "F.Mask" "F.Paste")
			(net "GND")
		)
		(pad "C44" smd circle
			(at 18.050002 -20.899882)
			(size 0.4572 0.4572)
			(layers "F.Cu" "F.Mask" "F.Paste")
			(net "P5E_PEX3_STN4_RX_DN<75>")
		)
		(pad "C45" smd circle
			(at 18.999962 -20.899882)
			(size 0.4572 0.4572)
			(layers "F.Cu" "F.Mask" "F.Paste")
			(net "GND")
		)
		(pad "C46" smd circle
			(at 19.949922 -20.899882)
			(size 0.4572 0.4572)
			(layers "F.Cu" "F.Mask" "F.Paste")
			(net "P5E_PEX3_STN4_RX_DN<73>")
		)
		(pad "C47" smd circle
			(at 20.899882 -20.899882)
			(size 0.4572 0.4572)
			(layers "F.Cu" "F.Mask" "F.Paste")
			(net "GND")
		)
		(pad "C48" smd circle
			(at 21.850096 -20.899882)
			(size 0.4572 0.4572)
			(layers "F.Cu" "F.Mask" "F.Paste")
			(net "P5E_PEX3_STN4_RX_DP<71>")
		)
		(pad "C49" smd circle
			(at 22.800056 -20.899882)
			(size 0.4572 0.4572)
			(layers "F.Cu" "F.Mask" "F.Paste")
			(net "P5E_PEX3_STN4_RX_DN<71>")
		)
		(pad "D1" smd circle
			(at -22.800056 -19.949922)
			(size 0.4572 0.4572)
			(layers "F.Cu" "F.Mask" "F.Paste")
			(net "GND")
		)
		(pad "D2" smd circle
			(at -21.850096 -19.949922)
			(size 0.4572 0.4572)
			(layers "F.Cu" "F.Mask" "F.Paste")
			(net "GND")
		)
		(pad "D3" smd circle
			(at -20.899882 -19.949922)
			(size 0.4572 0.4572)
			(layers "F.Cu" "F.Mask" "F.Paste")
			(net "GND")
		)
		(pad "D4" smd circle
			(at -19.949922 -19.949922)
			(size 0.4572 0.4572)
			(layers "F.Cu" "F.Mask" "F.Paste")
			(net "P5E_PEX3_STN7_RX_DP<124>")
		)
		(pad "D5" smd circle
			(at -18.999962 -19.949922)
			(size 0.4572 0.4572)
			(layers "F.Cu" "F.Mask" "F.Paste")
			(net "GND")
		)
		(pad "D6" smd circle
			(at -18.050002 -19.949922)
			(size 0.4572 0.4572)
			(layers "F.Cu" "F.Mask" "F.Paste")
			(net "P5E_PEX3_STN7_RX_DP<126>")
		)
		(pad "D7" smd circle
			(at -17.100042 -19.949922)
			(size 0.4572 0.4572)
			(layers "F.Cu" "F.Mask" "F.Paste")
			(net "GND")
		)
		(pad "D8" smd circle
			(at -16.150082 -19.949922)
			(size 0.4572 0.4572)
			(layers "F.Cu" "F.Mask" "F.Paste")
			(net "P5E_PEX3_STN6_RX_DP<111>")
		)
		(pad "D9" smd circle
			(at -15.200122 -19.949922)
			(size 0.4572 0.4572)
			(layers "F.Cu" "F.Mask" "F.Paste")
			(net "GND")
		)
		(pad "D10" smd circle
			(at -14.249908 -19.949922)
			(size 0.4572 0.4572)
			(layers "F.Cu" "F.Mask" "F.Paste")
			(net "P5E_PEX3_STN6_RX_DP<109>")
		)
		(pad "D11" smd circle
			(at -13.299948 -19.949922)
			(size 0.4572 0.4572)
			(layers "F.Cu" "F.Mask" "F.Paste")
			(net "GND")
		)
		(pad "D12" smd circle
			(at -12.349988 -19.949922)
			(size 0.4572 0.4572)
			(layers "F.Cu" "F.Mask" "F.Paste")
			(net "P5E_PEX3_STN6_RX_DP<107>")
		)
		(pad "D13" smd circle
			(at -11.400028 -19.949922)
			(size 0.4572 0.4572)
			(layers "F.Cu" "F.Mask" "F.Paste")
			(net "GND")
		)
		(pad "D14" smd circle
			(at -10.450068 -19.949922)
			(size 0.4572 0.4572)
			(layers "F.Cu" "F.Mask" "F.Paste")
			(net "P5E_PEX3_STN6_RX_DP<105>")
		)
		(pad "D15" smd circle
			(at -9.500108 -19.949922)
			(size 0.4572 0.4572)
			(layers "F.Cu" "F.Mask" "F.Paste")
			(net "GND")
		)
		(pad "D16" smd circle
			(at -8.549894 -19.949922)
			(size 0.4572 0.4572)
			(layers "F.Cu" "F.Mask" "F.Paste")
			(net "P5E_PEX3_STN6_RX_DP<103>")
		)
		(pad "D17" smd circle
			(at -7.599934 -19.949922)
			(size 0.4572 0.4572)
			(layers "F.Cu" "F.Mask" "F.Paste")
			(net "GND")
		)
		(pad "D18" smd circle
			(at -6.649974 -19.949922)
			(size 0.4572 0.4572)
			(layers "F.Cu" "F.Mask" "F.Paste")
			(net "P5E_PEX3_STN6_RX_DP<101>")
		)
		(pad "D19" smd circle
			(at -5.700014 -19.949922)
			(size 0.4572 0.4572)
			(layers "F.Cu" "F.Mask" "F.Paste")
			(net "GND")
		)
		(pad "D20" smd circle
			(at -4.750054 -19.949922)
			(size 0.4572 0.4572)
			(layers "F.Cu" "F.Mask" "F.Paste")
			(net "P5E_PEX3_STN6_RX_DP<99>")
		)
		(pad "D21" smd circle
			(at -3.800094 -19.949922)
			(size 0.4572 0.4572)
			(layers "F.Cu" "F.Mask" "F.Paste")
			(net "GND")
		)
		(pad "D22" smd circle
			(at -2.84988 -19.949922)
			(size 0.4572 0.4572)
			(layers "F.Cu" "F.Mask" "F.Paste")
			(net "P5E_PEX3_STN6_RX_DP<97>")
		)
		(pad "D23" smd circle
			(at -1.89992 -19.949922)
			(size 0.4572 0.4572)
			(layers "F.Cu" "F.Mask" "F.Paste")
			(net "GND")
		)
		(pad "D24" smd circle
			(at -0.94996 -19.949922)
			(size 0.4572 0.4572)
			(layers "F.Cu" "F.Mask" "F.Paste")
			(net "P5E_PEX3_STN5_RX_DP<80>")
		)
		(pad "D25" smd circle
			(at 0 -19.949922)
			(size 0.4572 0.4572)
			(layers "F.Cu" "F.Mask" "F.Paste")
			(net "GND")
		)
		(pad "D26" smd circle
			(at 0.94996 -19.949922)
			(size 0.4572 0.4572)
			(layers "F.Cu" "F.Mask" "F.Paste")
			(net "P5E_PEX3_STN5_RX_DP<82>")
		)
		(pad "D27" smd circle
			(at 1.89992 -19.949922)
			(size 0.4572 0.4572)
			(layers "F.Cu" "F.Mask" "F.Paste")
			(net "GND")
		)
		(pad "D28" smd circle
			(at 2.84988 -19.949922)
			(size 0.4572 0.4572)
			(layers "F.Cu" "F.Mask" "F.Paste")
			(net "P5E_PEX3_STN5_RX_DP<84>")
		)
		(pad "D29" smd circle
			(at 3.800094 -19.949922)
			(size 0.4572 0.4572)
			(layers "F.Cu" "F.Mask" "F.Paste")
			(net "GND")
		)
		(pad "D30" smd circle
			(at 4.750054 -19.949922)
			(size 0.4572 0.4572)
			(layers "F.Cu" "F.Mask" "F.Paste")
			(net "P5E_PEX3_STN5_RX_DP<86>")
		)
		(pad "D31" smd circle
			(at 5.700014 -19.949922)
			(size 0.4572 0.4572)
			(layers "F.Cu" "F.Mask" "F.Paste")
			(net "GND")
		)
		(pad "D32" smd circle
			(at 6.649974 -19.949922)
			(size 0.4572 0.4572)
			(layers "F.Cu" "F.Mask" "F.Paste")
			(net "P5E_PEX3_STN5_RX_DP<88>")
		)
		(pad "D33" smd circle
			(at 7.599934 -19.949922)
			(size 0.4572 0.4572)
			(layers "F.Cu" "F.Mask" "F.Paste")
			(net "GND")
		)
		(pad "D34" smd circle
			(at 8.549894 -19.949922)
			(size 0.4572 0.4572)
			(layers "F.Cu" "F.Mask" "F.Paste")
			(net "P5E_PEX3_STN5_RX_DP<90>")
		)
		(pad "D35" smd circle
			(at 9.500108 -19.949922)
			(size 0.4572 0.4572)
			(layers "F.Cu" "F.Mask" "F.Paste")
			(net "GND")
		)
		(pad "D36" smd circle
			(at 10.450068 -19.949922)
			(size 0.4572 0.4572)
			(layers "F.Cu" "F.Mask" "F.Paste")
			(net "P5E_PEX3_STN5_RX_DP<92>")
		)
		(pad "D37" smd circle
			(at 11.400028 -19.949922)
			(size 0.4572 0.4572)
			(layers "F.Cu" "F.Mask" "F.Paste")
			(net "GND")
		)
		(pad "D38" smd circle
			(at 12.349988 -19.949922)
			(size 0.4572 0.4572)
			(layers "F.Cu" "F.Mask" "F.Paste")
			(net "P5E_PEX3_STN5_RX_DP<94>")
		)
		(pad "D39" smd circle
			(at 13.299948 -19.949922)
			(size 0.4572 0.4572)
			(layers "F.Cu" "F.Mask" "F.Paste")
			(net "GND")
		)
		(pad "D40" smd circle
			(at 14.249908 -19.949922)
			(size 0.4572 0.4572)
			(layers "F.Cu" "F.Mask" "F.Paste")
			(net "P5E_PEX3_STN4_RX_DP<79>")
		)
		(pad "D41" smd circle
			(at 15.200122 -19.949922)
			(size 0.4572 0.4572)
			(layers "F.Cu" "F.Mask" "F.Paste")
			(net "GND")
		)
		(pad "D42" smd circle
			(at 16.150082 -19.949922)
			(size 0.4572 0.4572)
			(layers "F.Cu" "F.Mask" "F.Paste")
			(net "P5E_PEX3_STN4_RX_DP<77>")
		)
		(pad "D43" smd circle
			(at 17.100042 -19.949922)
			(size 0.4572 0.4572)
			(layers "F.Cu" "F.Mask" "F.Paste")
			(net "GND")
		)
		(pad "D44" smd circle
			(at 18.050002 -19.949922)
			(size 0.4572 0.4572)
			(layers "F.Cu" "F.Mask" "F.Paste")
			(net "P5E_PEX3_STN4_RX_DP<75>")
		)
		(pad "D45" smd circle
			(at 18.999962 -19.949922)
			(size 0.4572 0.4572)
			(layers "F.Cu" "F.Mask" "F.Paste")
			(net "GND")
		)
		(pad "D46" smd circle
			(at 19.949922 -19.949922)
			(size 0.4572 0.4572)
			(layers "F.Cu" "F.Mask" "F.Paste")
			(net "P5E_PEX3_STN4_RX_DP<73>")
		)
		(pad "D47" smd circle
			(at 20.899882 -19.949922)
			(size 0.4572 0.4572)
			(layers "F.Cu" "F.Mask" "F.Paste")
			(net "GND")
		)
		(pad "D48" smd circle
			(at 21.850096 -19.949922)
			(size 0.4572 0.4572)
			(layers "F.Cu" "F.Mask" "F.Paste")
			(net "GND")
		)
		(pad "D49" smd circle
			(at 22.800056 -19.949922)
			(size 0.4572 0.4572)
			(layers "F.Cu" "F.Mask" "F.Paste")
			(net "GND")
		)
		(pad "E1" smd circle
			(at -22.800056 -18.999962)
			(size 0.4572 0.4572)
			(layers "F.Cu" "F.Mask" "F.Paste")
			(net "P5E_PEX3_STN7_TX_DN<122>")
		)
		(pad "E2" smd circle
			(at -21.850096 -18.999962)
			(size 0.4572 0.4572)
			(layers "F.Cu" "F.Mask" "F.Paste")
			(net "P5E_PEX3_STN7_TX_DP<122>")
		)
		(pad "E3" smd circle
			(at -20.899882 -18.999962)
			(size 0.4572 0.4572)
			(layers "F.Cu" "F.Mask" "F.Paste")
			(net "GND")
		)
		(pad "E4" smd circle
			(at -19.949922 -18.999962)
			(size 0.4572 0.4572)
			(layers "F.Cu" "F.Mask" "F.Paste")
			(net "GND")
		)
		(pad "E5" smd circle
			(at -18.999962 -18.999962)
			(size 0.4572 0.4572)
			(layers "F.Cu" "F.Mask" "F.Paste")
			(net "GND")
		)
		(pad "E6" smd circle
			(at -18.050002 -18.999962)
			(size 0.4572 0.4572)
			(layers "F.Cu" "F.Mask" "F.Paste")
			(net "GND")
		)
		(pad "E7" smd circle
			(at -17.100042 -18.999962)
			(size 0.4572 0.4572)
			(layers "F.Cu" "F.Mask" "F.Paste")
			(net "GND")
		)
		(pad "E8" smd circle
			(at -16.150082 -18.999962)
			(size 0.4572 0.4572)
			(layers "F.Cu" "F.Mask" "F.Paste")
			(net "GND")
		)
		(pad "E9" smd circle
			(at -15.200122 -18.999962)
			(size 0.4572 0.4572)
			(layers "F.Cu" "F.Mask" "F.Paste")
			(net "GND")
		)
		(pad "E10" smd circle
			(at -14.249908 -18.999962)
			(size 0.4572 0.4572)
			(layers "F.Cu" "F.Mask" "F.Paste")
			(net "GND")
		)
		(pad "E11" smd circle
			(at -13.299948 -18.999962)
			(size 0.4572 0.4572)
			(layers "F.Cu" "F.Mask" "F.Paste")
			(net "GND")
		)
		(pad "E12" smd circle
			(at -12.349988 -18.999962)
			(size 0.4572 0.4572)
			(layers "F.Cu" "F.Mask" "F.Paste")
			(net "GND")
		)
		(pad "E13" smd circle
			(at -11.400028 -18.999962)
			(size 0.4572 0.4572)
			(layers "F.Cu" "F.Mask" "F.Paste")
			(net "GND")
		)
		(pad "E14" smd circle
			(at -10.450068 -18.999962)
			(size 0.4572 0.4572)
			(layers "F.Cu" "F.Mask" "F.Paste")
			(net "GND")
		)
		(pad "E15" smd circle
			(at -9.500108 -18.999962)
			(size 0.4572 0.4572)
			(layers "F.Cu" "F.Mask" "F.Paste")
			(net "GND")
		)
		(pad "E16" smd circle
			(at -8.549894 -18.999962)
			(size 0.4572 0.4572)
			(layers "F.Cu" "F.Mask" "F.Paste")
			(net "GND")
		)
		(pad "E17" smd circle
			(at -7.599934 -18.999962)
			(size 0.4572 0.4572)
			(layers "F.Cu" "F.Mask" "F.Paste")
			(net "GND")
		)
		(pad "E18" smd circle
			(at -6.649974 -18.999962)
			(size 0.4572 0.4572)
			(layers "F.Cu" "F.Mask" "F.Paste")
			(net "GND")
		)
		(pad "E19" smd circle
			(at -5.700014 -18.999962)
			(size 0.4572 0.4572)
			(layers "F.Cu" "F.Mask" "F.Paste")
			(net "GND")
		)
		(pad "E20" smd circle
			(at -4.750054 -18.999962)
			(size 0.4572 0.4572)
			(layers "F.Cu" "F.Mask" "F.Paste")
			(net "GND")
		)
		(pad "E21" smd circle
			(at -3.800094 -18.999962)
			(size 0.4572 0.4572)
			(layers "F.Cu" "F.Mask" "F.Paste")
			(net "GND")
		)
		(pad "E22" smd circle
			(at -2.84988 -18.999962)
			(size 0.4572 0.4572)
			(layers "F.Cu" "F.Mask" "F.Paste")
			(net "GND")
		)
		(pad "E23" smd circle
			(at -1.89992 -18.999962)
			(size 0.4572 0.4572)
			(layers "F.Cu" "F.Mask" "F.Paste")
			(net "GND")
		)
		(pad "E24" smd circle
			(at -0.94996 -18.999962)
			(size 0.4572 0.4572)
			(layers "F.Cu" "F.Mask" "F.Paste")
			(net "GND")
		)
		(pad "E25" smd circle
			(at 0 -18.999962)
			(size 0.4572 0.4572)
			(layers "F.Cu" "F.Mask" "F.Paste")
			(net "GND")
		)
		(pad "E26" smd circle
			(at 0.94996 -18.999962)
			(size 0.4572 0.4572)
			(layers "F.Cu" "F.Mask" "F.Paste")
			(net "GND")
		)
		(pad "E27" smd circle
			(at 1.89992 -18.999962)
			(size 0.4572 0.4572)
			(layers "F.Cu" "F.Mask" "F.Paste")
			(net "GND")
		)
		(pad "E28" smd circle
			(at 2.84988 -18.999962)
			(size 0.4572 0.4572)
			(layers "F.Cu" "F.Mask" "F.Paste")
			(net "GND")
		)
		(pad "E29" smd circle
			(at 3.800094 -18.999962)
			(size 0.4572 0.4572)
			(layers "F.Cu" "F.Mask" "F.Paste")
			(net "GND")
		)
		(pad "E30" smd circle
			(at 4.750054 -18.999962)
			(size 0.4572 0.4572)
			(layers "F.Cu" "F.Mask" "F.Paste")
			(net "GND")
		)
		(pad "E31" smd circle
			(at 5.700014 -18.999962)
			(size 0.4572 0.4572)
			(layers "F.Cu" "F.Mask" "F.Paste")
			(net "GND")
		)
		(pad "E32" smd circle
			(at 6.649974 -18.999962)
			(size 0.4572 0.4572)
			(layers "F.Cu" "F.Mask" "F.Paste")
			(net "GND")
		)
		(pad "E33" smd circle
			(at 7.599934 -18.999962)
			(size 0.4572 0.4572)
			(layers "F.Cu" "F.Mask" "F.Paste")
			(net "GND")
		)
		(pad "E34" smd circle
			(at 8.549894 -18.999962)
			(size 0.4572 0.4572)
			(layers "F.Cu" "F.Mask" "F.Paste")
			(net "GND")
		)
		(pad "E35" smd circle
			(at 9.500108 -18.999962)
			(size 0.4572 0.4572)
			(layers "F.Cu" "F.Mask" "F.Paste")
			(net "GND")
		)
		(pad "E36" smd circle
			(at 10.450068 -18.999962)
			(size 0.4572 0.4572)
			(layers "F.Cu" "F.Mask" "F.Paste")
			(net "GND")
		)
		(pad "E37" smd circle
			(at 11.400028 -18.999962)
			(size 0.4572 0.4572)
			(layers "F.Cu" "F.Mask" "F.Paste")
			(net "GND")
		)
		(pad "E38" smd circle
			(at 12.349988 -18.999962)
			(size 0.4572 0.4572)
			(layers "F.Cu" "F.Mask" "F.Paste")
			(net "GND")
		)
		(pad "E39" smd circle
			(at 13.299948 -18.999962)
			(size 0.4572 0.4572)
			(layers "F.Cu" "F.Mask" "F.Paste")
			(net "GND")
		)
		(pad "E40" smd circle
			(at 14.249908 -18.999962)
			(size 0.4572 0.4572)
			(layers "F.Cu" "F.Mask" "F.Paste")
			(net "GND")
		)
		(pad "E41" smd circle
			(at 15.200122 -18.999962)
			(size 0.4572 0.4572)
			(layers "F.Cu" "F.Mask" "F.Paste")
			(net "GND")
		)
		(pad "E42" smd circle
			(at 16.150082 -18.999962)
			(size 0.4572 0.4572)
			(layers "F.Cu" "F.Mask" "F.Paste")
			(net "GND")
		)
		(pad "E43" smd circle
			(at 17.100042 -18.999962)
			(size 0.4572 0.4572)
			(layers "F.Cu" "F.Mask" "F.Paste")
			(net "GND")
		)
		(pad "E44" smd circle
			(at 18.050002 -18.999962)
			(size 0.4572 0.4572)
			(layers "F.Cu" "F.Mask" "F.Paste")
			(net "GND")
		)
		(pad "E45" smd circle
			(at 18.999962 -18.999962)
			(size 0.4572 0.4572)
			(layers "F.Cu" "F.Mask" "F.Paste")
			(net "GND")
		)
		(pad "E46" smd circle
			(at 19.949922 -18.999962)
			(size 0.4572 0.4572)
			(layers "F.Cu" "F.Mask" "F.Paste")
			(net "GND")
		)
		(pad "E47" smd circle
			(at 20.899882 -18.999962)
			(size 0.4572 0.4572)
			(layers "F.Cu" "F.Mask" "F.Paste")
			(net "GND")
		)
		(pad "E48" smd circle
			(at 21.850096 -18.999962)
			(size 0.4572 0.4572)
			(layers "F.Cu" "F.Mask" "F.Paste")
			(net "P5E_PEX3_STN4_TX_DP<71>")
		)
		(pad "E49" smd circle
			(at 22.800056 -18.999962)
			(size 0.4572 0.4572)
			(layers "F.Cu" "F.Mask" "F.Paste")
			(net "P5E_PEX3_STN4_TX_DN<71>")
		)
		(pad "F1" smd circle
			(at -22.800056 -18.050002)
			(size 0.4572 0.4572)
			(layers "F.Cu" "F.Mask" "F.Paste")
			(net "GND")
		)
		(pad "F2" smd circle
			(at -21.850096 -18.050002)
			(size 0.4572 0.4572)
			(layers "F.Cu" "F.Mask" "F.Paste")
			(net "GND")
		)
		(pad "F3" smd circle
			(at -20.899882 -18.050002)
			(size 0.4572 0.4572)
			(layers "F.Cu" "F.Mask" "F.Paste")
			(net "P5E_PEX3_STN7_TX_DN<123>")
		)
		(pad "F4" smd circle
			(at -19.949922 -18.050002)
			(size 0.4572 0.4572)
			(layers "F.Cu" "F.Mask" "F.Paste")
			(net "GND")
		)
		(pad "F5" smd circle
			(at -18.999962 -18.050002)
			(size 0.4572 0.4572)
			(layers "F.Cu" "F.Mask" "F.Paste")
			(net "P5E_PEX3_STN7_TX_DN<125>")
		)
		(pad "F6" smd circle
			(at -18.050002 -18.050002)
			(size 0.4572 0.4572)
			(layers "F.Cu" "F.Mask" "F.Paste")
			(net "GND")
		)
		(pad "F7" smd circle
			(at -17.100042 -18.050002)
			(size 0.4572 0.4572)
			(layers "F.Cu" "F.Mask" "F.Paste")
			(net "P5E_PEX3_STN7_TX_DN<127>")
		)
		(pad "F8" smd circle
			(at -16.150082 -18.050002)
			(size 0.4572 0.4572)
			(layers "F.Cu" "F.Mask" "F.Paste")
			(net "GND")
		)
		(pad "F9" smd circle
			(at -15.200122 -18.050002)
			(size 0.4572 0.4572)
			(layers "F.Cu" "F.Mask" "F.Paste")
			(net "P5E_PEX3_STN6_TX_DN<110>")
		)
		(pad "F10" smd circle
			(at -14.249908 -18.050002)
			(size 0.4572 0.4572)
			(layers "F.Cu" "F.Mask" "F.Paste")
			(net "GND")
		)
		(pad "F11" smd circle
			(at -13.299948 -18.050002)
			(size 0.4572 0.4572)
			(layers "F.Cu" "F.Mask" "F.Paste")
			(net "P5E_PEX3_STN6_TX_DN<108>")
		)
		(pad "F12" smd circle
			(at -12.349988 -18.050002)
			(size 0.4572 0.4572)
			(layers "F.Cu" "F.Mask" "F.Paste")
			(net "GND")
		)
		(pad "F13" smd circle
			(at -11.400028 -18.050002)
			(size 0.4572 0.4572)
			(layers "F.Cu" "F.Mask" "F.Paste")
			(net "P5E_PEX3_STN6_TX_DN<106>")
		)
		(pad "F14" smd circle
			(at -10.450068 -18.050002)
			(size 0.4572 0.4572)
			(layers "F.Cu" "F.Mask" "F.Paste")
			(net "GND")
		)
		(pad "F15" smd circle
			(at -9.500108 -18.050002)
			(size 0.4572 0.4572)
			(layers "F.Cu" "F.Mask" "F.Paste")
			(net "P5E_PEX3_STN6_TX_DN<104>")
		)
		(pad "F16" smd circle
			(at -8.549894 -18.050002)
			(size 0.4572 0.4572)
			(layers "F.Cu" "F.Mask" "F.Paste")
			(net "GND")
		)
		(pad "F17" smd circle
			(at -7.599934 -18.050002)
			(size 0.4572 0.4572)
			(layers "F.Cu" "F.Mask" "F.Paste")
			(net "P5E_PEX3_STN6_TX_DN<102>")
		)
		(pad "F18" smd circle
			(at -6.649974 -18.050002)
			(size 0.4572 0.4572)
			(layers "F.Cu" "F.Mask" "F.Paste")
			(net "GND")
		)
		(pad "F19" smd circle
			(at -5.700014 -18.050002)
			(size 0.4572 0.4572)
			(layers "F.Cu" "F.Mask" "F.Paste")
			(net "P5E_PEX3_STN6_TX_DN<100>")
		)
		(pad "F20" smd circle
			(at -4.750054 -18.050002)
			(size 0.4572 0.4572)
			(layers "F.Cu" "F.Mask" "F.Paste")
			(net "GND")
		)
		(pad "F21" smd circle
			(at -3.800094 -18.050002)
			(size 0.4572 0.4572)
			(layers "F.Cu" "F.Mask" "F.Paste")
			(net "P5E_PEX3_STN6_TX_DN<98>")
		)
		(pad "F22" smd circle
			(at -2.84988 -18.050002)
			(size 0.4572 0.4572)
			(layers "F.Cu" "F.Mask" "F.Paste")
			(net "GND")
		)
		(pad "F23" smd circle
			(at -1.89992 -18.050002)
			(size 0.4572 0.4572)
			(layers "F.Cu" "F.Mask" "F.Paste")
			(net "P5E_PEX3_STN6_TX_DN<96>")
		)
		(pad "F24" smd circle
			(at -0.94996 -18.050002)
			(size 0.4572 0.4572)
			(layers "F.Cu" "F.Mask" "F.Paste")
			(net "GND")
		)
		(pad "F25" smd circle
			(at 0 -18.050002)
			(size 0.4572 0.4572)
			(layers "F.Cu" "F.Mask" "F.Paste")
			(net "P5E_PEX3_STN5_TX_DN<81>")
		)
		(pad "F26" smd circle
			(at 0.94996 -18.050002)
			(size 0.4572 0.4572)
			(layers "F.Cu" "F.Mask" "F.Paste")
			(net "GND")
		)
		(pad "F27" smd circle
			(at 1.89992 -18.050002)
			(size 0.4572 0.4572)
			(layers "F.Cu" "F.Mask" "F.Paste")
			(net "P5E_PEX3_STN5_TX_DN<83>")
		)
		(pad "F28" smd circle
			(at 2.84988 -18.050002)
			(size 0.4572 0.4572)
			(layers "F.Cu" "F.Mask" "F.Paste")
			(net "GND")
		)
		(pad "F29" smd circle
			(at 3.800094 -18.050002)
			(size 0.4572 0.4572)
			(layers "F.Cu" "F.Mask" "F.Paste")
			(net "P5E_PEX3_STN5_TX_DN<85>")
		)
		(pad "F30" smd circle
			(at 4.750054 -18.050002)
			(size 0.4572 0.4572)
			(layers "F.Cu" "F.Mask" "F.Paste")
			(net "GND")
		)
		(pad "F31" smd circle
			(at 5.700014 -18.050002)
			(size 0.4572 0.4572)
			(layers "F.Cu" "F.Mask" "F.Paste")
			(net "P5E_PEX3_STN5_TX_DN<87>")
		)
		(pad "F32" smd circle
			(at 6.649974 -18.050002)
			(size 0.4572 0.4572)
			(layers "F.Cu" "F.Mask" "F.Paste")
			(net "GND")
		)
		(pad "F33" smd circle
			(at 7.599934 -18.050002)
			(size 0.4572 0.4572)
			(layers "F.Cu" "F.Mask" "F.Paste")
			(net "P5E_PEX3_STN5_TX_DN<89>")
		)
		(pad "F34" smd circle
			(at 8.549894 -18.050002)
			(size 0.4572 0.4572)
			(layers "F.Cu" "F.Mask" "F.Paste")
			(net "GND")
		)
		(pad "F35" smd circle
			(at 9.500108 -18.050002)
			(size 0.4572 0.4572)
			(layers "F.Cu" "F.Mask" "F.Paste")
			(net "P5E_PEX3_STN5_TX_DN<91>")
		)
		(pad "F36" smd circle
			(at 10.450068 -18.050002)
			(size 0.4572 0.4572)
			(layers "F.Cu" "F.Mask" "F.Paste")
			(net "GND")
		)
		(pad "F37" smd circle
			(at 11.400028 -18.050002)
			(size 0.4572 0.4572)
			(layers "F.Cu" "F.Mask" "F.Paste")
			(net "P5E_PEX3_STN5_TX_DN<93>")
		)
		(pad "F38" smd circle
			(at 12.349988 -18.050002)
			(size 0.4572 0.4572)
			(layers "F.Cu" "F.Mask" "F.Paste")
			(net "GND")
		)
		(pad "F39" smd circle
			(at 13.299948 -18.050002)
			(size 0.4572 0.4572)
			(layers "F.Cu" "F.Mask" "F.Paste")
			(net "P5E_PEX3_STN5_TX_DN<95>")
		)
		(pad "F40" smd circle
			(at 14.249908 -18.050002)
			(size 0.4572 0.4572)
			(layers "F.Cu" "F.Mask" "F.Paste")
			(net "GND")
		)
		(pad "F41" smd circle
			(at 15.200122 -18.050002)
			(size 0.4572 0.4572)
			(layers "F.Cu" "F.Mask" "F.Paste")
			(net "P5E_PEX3_STN4_TX_DN<78>")
		)
		(pad "F42" smd circle
			(at 16.150082 -18.050002)
			(size 0.4572 0.4572)
			(layers "F.Cu" "F.Mask" "F.Paste")
			(net "GND")
		)
		(pad "F43" smd circle
			(at 17.100042 -18.050002)
			(size 0.4572 0.4572)
			(layers "F.Cu" "F.Mask" "F.Paste")
			(net "P5E_PEX3_STN4_TX_DN<76>")
		)
		(pad "F44" smd circle
			(at 18.050002 -18.050002)
			(size 0.4572 0.4572)
			(layers "F.Cu" "F.Mask" "F.Paste")
			(net "GND")
		)
		(pad "F45" smd circle
			(at 18.999962 -18.050002)
			(size 0.4572 0.4572)
			(layers "F.Cu" "F.Mask" "F.Paste")
			(net "P5E_PEX3_STN4_TX_DN<74>")
		)
		(pad "F46" smd circle
			(at 19.949922 -18.050002)
			(size 0.4572 0.4572)
			(layers "F.Cu" "F.Mask" "F.Paste")
			(net "GND")
		)
		(pad "F47" smd circle
			(at 20.899882 -18.050002)
			(size 0.4572 0.4572)
			(layers "F.Cu" "F.Mask" "F.Paste")
			(net "P5E_PEX3_STN4_TX_DN<72>")
		)
		(pad "F48" smd circle
			(at 21.850096 -18.050002)
			(size 0.4572 0.4572)
			(layers "F.Cu" "F.Mask" "F.Paste")
			(net "GND")
		)
		(pad "F49" smd circle
			(at 22.800056 -18.050002)
			(size 0.4572 0.4572)
			(layers "F.Cu" "F.Mask" "F.Paste")
			(net "GND")
		)
		(pad "G1" smd circle
			(at -22.800056 -17.100042)
			(size 0.4572 0.4572)
			(layers "F.Cu" "F.Mask" "F.Paste")
			(net "GND")
		)
		(pad "G2" smd circle
			(at -21.850096 -17.100042)
			(size 0.4572 0.4572)
			(layers "F.Cu" "F.Mask" "F.Paste")
			(net "GND")
		)
		(pad "G3" smd circle
			(at -20.899882 -17.100042)
			(size 0.4572 0.4572)
			(layers "F.Cu" "F.Mask" "F.Paste")
			(net "P5E_PEX3_STN7_TX_DP<123>")
		)
		(pad "G4" smd circle
			(at -19.949922 -17.100042)
			(size 0.4572 0.4572)
			(layers "F.Cu" "F.Mask" "F.Paste")
			(net "GND")
		)
		(pad "G5" smd circle
			(at -18.999962 -17.100042)
			(size 0.4572 0.4572)
			(layers "F.Cu" "F.Mask" "F.Paste")
			(net "P5E_PEX3_STN7_TX_DP<125>")
		)
		(pad "G6" smd circle
			(at -18.050002 -17.100042)
			(size 0.4572 0.4572)
			(layers "F.Cu" "F.Mask" "F.Paste")
			(net "GND")
		)
		(pad "G7" smd circle
			(at -17.100042 -17.100042)
			(size 0.4572 0.4572)
			(layers "F.Cu" "F.Mask" "F.Paste")
			(net "P5E_PEX3_STN7_TX_DP<127>")
		)
		(pad "G8" smd circle
			(at -16.150082 -17.100042)
			(size 0.4572 0.4572)
			(layers "F.Cu" "F.Mask" "F.Paste")
			(net "GND")
		)
		(pad "G9" smd circle
			(at -15.200122 -17.100042)
			(size 0.4572 0.4572)
			(layers "F.Cu" "F.Mask" "F.Paste")
			(net "P5E_PEX3_STN6_TX_DP<110>")
		)
		(pad "G10" smd circle
			(at -14.249908 -17.100042)
			(size 0.4572 0.4572)
			(layers "F.Cu" "F.Mask" "F.Paste")
			(net "GND")
		)
		(pad "G11" smd circle
			(at -13.299948 -17.100042)
			(size 0.4572 0.4572)
			(layers "F.Cu" "F.Mask" "F.Paste")
			(net "P5E_PEX3_STN6_TX_DP<108>")
		)
		(pad "G12" smd circle
			(at -12.349988 -17.100042)
			(size 0.4572 0.4572)
			(layers "F.Cu" "F.Mask" "F.Paste")
			(net "GND")
		)
		(pad "G13" smd circle
			(at -11.400028 -17.100042)
			(size 0.4572 0.4572)
			(layers "F.Cu" "F.Mask" "F.Paste")
			(net "P5E_PEX3_STN6_TX_DP<106>")
		)
		(pad "G14" smd circle
			(at -10.450068 -17.100042)
			(size 0.4572 0.4572)
			(layers "F.Cu" "F.Mask" "F.Paste")
			(net "GND")
		)
		(pad "G15" smd circle
			(at -9.500108 -17.100042)
			(size 0.4572 0.4572)
			(layers "F.Cu" "F.Mask" "F.Paste")
			(net "P5E_PEX3_STN6_TX_DP<104>")
		)
		(pad "G16" smd circle
			(at -8.549894 -17.100042)
			(size 0.4572 0.4572)
			(layers "F.Cu" "F.Mask" "F.Paste")
			(net "GND")
		)
		(pad "G17" smd circle
			(at -7.599934 -17.100042)
			(size 0.4572 0.4572)
			(layers "F.Cu" "F.Mask" "F.Paste")
			(net "P5E_PEX3_STN6_TX_DP<102>")
		)
		(pad "G18" smd circle
			(at -6.649974 -17.100042)
			(size 0.4572 0.4572)
			(layers "F.Cu" "F.Mask" "F.Paste")
			(net "GND")
		)
		(pad "G19" smd circle
			(at -5.700014 -17.100042)
			(size 0.4572 0.4572)
			(layers "F.Cu" "F.Mask" "F.Paste")
			(net "P5E_PEX3_STN6_TX_DP<100>")
		)
		(pad "G20" smd circle
			(at -4.750054 -17.100042)
			(size 0.4572 0.4572)
			(layers "F.Cu" "F.Mask" "F.Paste")
			(net "GND")
		)
		(pad "G21" smd circle
			(at -3.800094 -17.100042)
			(size 0.4572 0.4572)
			(layers "F.Cu" "F.Mask" "F.Paste")
			(net "P5E_PEX3_STN6_TX_DP<98>")
		)
		(pad "G22" smd circle
			(at -2.84988 -17.100042)
			(size 0.4572 0.4572)
			(layers "F.Cu" "F.Mask" "F.Paste")
			(net "GND")
		)
		(pad "G23" smd circle
			(at -1.89992 -17.100042)
			(size 0.4572 0.4572)
			(layers "F.Cu" "F.Mask" "F.Paste")
			(net "P5E_PEX3_STN6_TX_DP<96>")
		)
		(pad "G24" smd circle
			(at -0.94996 -17.100042)
			(size 0.4572 0.4572)
			(layers "F.Cu" "F.Mask" "F.Paste")
			(net "GND")
		)
		(pad "G25" smd circle
			(at 0 -17.100042)
			(size 0.4572 0.4572)
			(layers "F.Cu" "F.Mask" "F.Paste")
			(net "P5E_PEX3_STN5_TX_DP<81>")
		)
		(pad "G26" smd circle
			(at 0.94996 -17.100042)
			(size 0.4572 0.4572)
			(layers "F.Cu" "F.Mask" "F.Paste")
			(net "GND")
		)
		(pad "G27" smd circle
			(at 1.89992 -17.100042)
			(size 0.4572 0.4572)
			(layers "F.Cu" "F.Mask" "F.Paste")
			(net "P5E_PEX3_STN5_TX_DP<83>")
		)
		(pad "G28" smd circle
			(at 2.84988 -17.100042)
			(size 0.4572 0.4572)
			(layers "F.Cu" "F.Mask" "F.Paste")
			(net "GND")
		)
		(pad "G29" smd circle
			(at 3.800094 -17.100042)
			(size 0.4572 0.4572)
			(layers "F.Cu" "F.Mask" "F.Paste")
			(net "P5E_PEX3_STN5_TX_DP<85>")
		)
		(pad "G30" smd circle
			(at 4.750054 -17.100042)
			(size 0.4572 0.4572)
			(layers "F.Cu" "F.Mask" "F.Paste")
			(net "GND")
		)
		(pad "G31" smd circle
			(at 5.700014 -17.100042)
			(size 0.4572 0.4572)
			(layers "F.Cu" "F.Mask" "F.Paste")
			(net "P5E_PEX3_STN5_TX_DP<87>")
		)
		(pad "G32" smd circle
			(at 6.649974 -17.100042)
			(size 0.4572 0.4572)
			(layers "F.Cu" "F.Mask" "F.Paste")
			(net "GND")
		)
		(pad "G33" smd circle
			(at 7.599934 -17.100042)
			(size 0.4572 0.4572)
			(layers "F.Cu" "F.Mask" "F.Paste")
			(net "P5E_PEX3_STN5_TX_DP<89>")
		)
		(pad "G34" smd circle
			(at 8.549894 -17.100042)
			(size 0.4572 0.4572)
			(layers "F.Cu" "F.Mask" "F.Paste")
			(net "GND")
		)
		(pad "G35" smd circle
			(at 9.500108 -17.100042)
			(size 0.4572 0.4572)
			(layers "F.Cu" "F.Mask" "F.Paste")
			(net "P5E_PEX3_STN5_TX_DP<91>")
		)
		(pad "G36" smd circle
			(at 10.450068 -17.100042)
			(size 0.4572 0.4572)
			(layers "F.Cu" "F.Mask" "F.Paste")
			(net "GND")
		)
		(pad "G37" smd circle
			(at 11.400028 -17.100042)
			(size 0.4572 0.4572)
			(layers "F.Cu" "F.Mask" "F.Paste")
			(net "P5E_PEX3_STN5_TX_DP<93>")
		)
		(pad "G38" smd circle
			(at 12.349988 -17.100042)
			(size 0.4572 0.4572)
			(layers "F.Cu" "F.Mask" "F.Paste")
			(net "GND")
		)
		(pad "G39" smd circle
			(at 13.299948 -17.100042)
			(size 0.4572 0.4572)
			(layers "F.Cu" "F.Mask" "F.Paste")
			(net "P5E_PEX3_STN5_TX_DP<95>")
		)
		(pad "G40" smd circle
			(at 14.249908 -17.100042)
			(size 0.4572 0.4572)
			(layers "F.Cu" "F.Mask" "F.Paste")
			(net "GND")
		)
		(pad "G41" smd circle
			(at 15.200122 -17.100042)
			(size 0.4572 0.4572)
			(layers "F.Cu" "F.Mask" "F.Paste")
			(net "P5E_PEX3_STN4_TX_DP<78>")
		)
		(pad "G42" smd circle
			(at 16.150082 -17.100042)
			(size 0.4572 0.4572)
			(layers "F.Cu" "F.Mask" "F.Paste")
			(net "GND")
		)
		(pad "G43" smd circle
			(at 17.100042 -17.100042)
			(size 0.4572 0.4572)
			(layers "F.Cu" "F.Mask" "F.Paste")
			(net "P5E_PEX3_STN4_TX_DP<76>")
		)
		(pad "G44" smd circle
			(at 18.050002 -17.100042)
			(size 0.4572 0.4572)
			(layers "F.Cu" "F.Mask" "F.Paste")
			(net "GND")
		)
		(pad "G45" smd circle
			(at 18.999962 -17.100042)
			(size 0.4572 0.4572)
			(layers "F.Cu" "F.Mask" "F.Paste")
			(net "P5E_PEX3_STN4_TX_DP<74>")
		)
		(pad "G46" smd circle
			(at 19.949922 -17.100042)
			(size 0.4572 0.4572)
			(layers "F.Cu" "F.Mask" "F.Paste")
			(net "GND")
		)
		(pad "G47" smd circle
			(at 20.899882 -17.100042)
			(size 0.4572 0.4572)
			(layers "F.Cu" "F.Mask" "F.Paste")
			(net "P5E_PEX3_STN4_TX_DP<72>")
		)
		(pad "G48" smd circle
			(at 21.850096 -17.100042)
			(size 0.4572 0.4572)
			(layers "F.Cu" "F.Mask" "F.Paste")
			(net "GND")
		)
		(pad "G49" smd circle
			(at 22.800056 -17.100042)
			(size 0.4572 0.4572)
			(layers "F.Cu" "F.Mask" "F.Paste")
			(net "GND")
		)
		(pad "H1" smd circle
			(at -22.800056 -16.150082)
			(size 0.4572 0.4572)
			(layers "F.Cu" "F.Mask" "F.Paste")
			(net "P5E_PEX3_STN7_TX_DN<121>")
		)
		(pad "H2" smd circle
			(at -21.850096 -16.150082)
			(size 0.4572 0.4572)
			(layers "F.Cu" "F.Mask" "F.Paste")
			(net "P5E_PEX3_STN7_TX_DP<121>")
		)
		(pad "H3" smd circle
			(at -20.899882 -16.150082)
			(size 0.4572 0.4572)
			(layers "F.Cu" "F.Mask" "F.Paste")
			(net "GND")
		)
		(pad "H4" smd circle
			(at -19.949922 -16.150082)
			(size 0.4572 0.4572)
			(layers "F.Cu" "F.Mask" "F.Paste")
			(net "P5E_PEX3_STN7_TX_DN<124>")
		)
		(pad "H5" smd circle
			(at -18.999962 -16.150082)
			(size 0.4572 0.4572)
			(layers "F.Cu" "F.Mask" "F.Paste")
			(net "GND")
		)
		(pad "H6" smd circle
			(at -18.050002 -16.150082)
			(size 0.4572 0.4572)
			(layers "F.Cu" "F.Mask" "F.Paste")
			(net "P5E_PEX3_STN7_TX_DN<126>")
		)
		(pad "H7" smd circle
			(at -17.100042 -16.150082)
			(size 0.4572 0.4572)
			(layers "F.Cu" "F.Mask" "F.Paste")
			(net "GND")
		)
		(pad "H8" smd circle
			(at -16.150082 -16.150082)
			(size 0.4572 0.4572)
			(layers "F.Cu" "F.Mask" "F.Paste")
			(net "P5E_PEX3_STN6_TX_DN<111>")
		)
		(pad "H9" smd circle
			(at -15.200122 -16.150082)
			(size 0.4572 0.4572)
			(layers "F.Cu" "F.Mask" "F.Paste")
			(net "GND")
		)
		(pad "H10" smd circle
			(at -14.249908 -16.150082)
			(size 0.4572 0.4572)
			(layers "F.Cu" "F.Mask" "F.Paste")
			(net "P5E_PEX3_STN6_TX_DN<109>")
		)
		(pad "H11" smd circle
			(at -13.299948 -16.150082)
			(size 0.4572 0.4572)
			(layers "F.Cu" "F.Mask" "F.Paste")
			(net "GND")
		)
		(pad "H12" smd circle
			(at -12.349988 -16.150082)
			(size 0.4572 0.4572)
			(layers "F.Cu" "F.Mask" "F.Paste")
			(net "P5E_PEX3_STN6_TX_DN<107>")
		)
		(pad "H13" smd circle
			(at -11.400028 -16.150082)
			(size 0.4572 0.4572)
			(layers "F.Cu" "F.Mask" "F.Paste")
			(net "GND")
		)
		(pad "H14" smd circle
			(at -10.450068 -16.150082)
			(size 0.4572 0.4572)
			(layers "F.Cu" "F.Mask" "F.Paste")
			(net "P5E_PEX3_STN6_TX_DN<105>")
		)
		(pad "H15" smd circle
			(at -9.500108 -16.150082)
			(size 0.4572 0.4572)
			(layers "F.Cu" "F.Mask" "F.Paste")
			(net "GND")
		)
		(pad "H16" smd circle
			(at -8.549894 -16.150082)
			(size 0.4572 0.4572)
			(layers "F.Cu" "F.Mask" "F.Paste")
			(net "P5E_PEX3_STN6_TX_DN<103>")
		)
		(pad "H17" smd circle
			(at -7.599934 -16.150082)
			(size 0.4572 0.4572)
			(layers "F.Cu" "F.Mask" "F.Paste")
			(net "GND")
		)
		(pad "H18" smd circle
			(at -6.649974 -16.150082)
			(size 0.4572 0.4572)
			(layers "F.Cu" "F.Mask" "F.Paste")
			(net "P5E_PEX3_STN6_TX_DN<101>")
		)
		(pad "H19" smd circle
			(at -5.700014 -16.150082)
			(size 0.4572 0.4572)
			(layers "F.Cu" "F.Mask" "F.Paste")
			(net "GND")
		)
		(pad "H20" smd circle
			(at -4.750054 -16.150082)
			(size 0.4572 0.4572)
			(layers "F.Cu" "F.Mask" "F.Paste")
			(net "P5E_PEX3_STN6_TX_DN<99>")
		)
		(pad "H21" smd circle
			(at -3.800094 -16.150082)
			(size 0.4572 0.4572)
			(layers "F.Cu" "F.Mask" "F.Paste")
			(net "GND")
		)
		(pad "H22" smd circle
			(at -2.84988 -16.150082)
			(size 0.4572 0.4572)
			(layers "F.Cu" "F.Mask" "F.Paste")
			(net "P5E_PEX3_STN6_TX_DN<97>")
		)
		(pad "H23" smd circle
			(at -1.89992 -16.150082)
			(size 0.4572 0.4572)
			(layers "F.Cu" "F.Mask" "F.Paste")
			(net "GND")
		)
		(pad "H24" smd circle
			(at -0.94996 -16.150082)
			(size 0.4572 0.4572)
			(layers "F.Cu" "F.Mask" "F.Paste")
			(net "P5E_PEX3_STN5_TX_DN<80>")
		)
		(pad "H25" smd circle
			(at 0 -16.150082)
			(size 0.4572 0.4572)
			(layers "F.Cu" "F.Mask" "F.Paste")
			(net "GND")
		)
		(pad "H26" smd circle
			(at 0.94996 -16.150082)
			(size 0.4572 0.4572)
			(layers "F.Cu" "F.Mask" "F.Paste")
			(net "P5E_PEX3_STN5_TX_DN<82>")
		)
		(pad "H27" smd circle
			(at 1.89992 -16.150082)
			(size 0.4572 0.4572)
			(layers "F.Cu" "F.Mask" "F.Paste")
			(net "GND")
		)
		(pad "H28" smd circle
			(at 2.84988 -16.150082)
			(size 0.4572 0.4572)
			(layers "F.Cu" "F.Mask" "F.Paste")
			(net "P5E_PEX3_STN5_TX_DN<84>")
		)
		(pad "H29" smd circle
			(at 3.800094 -16.150082)
			(size 0.4572 0.4572)
			(layers "F.Cu" "F.Mask" "F.Paste")
			(net "GND")
		)
		(pad "H30" smd circle
			(at 4.750054 -16.150082)
			(size 0.4572 0.4572)
			(layers "F.Cu" "F.Mask" "F.Paste")
			(net "P5E_PEX3_STN5_TX_DN<86>")
		)
		(pad "H31" smd circle
			(at 5.700014 -16.150082)
			(size 0.4572 0.4572)
			(layers "F.Cu" "F.Mask" "F.Paste")
			(net "GND")
		)
		(pad "H32" smd circle
			(at 6.649974 -16.150082)
			(size 0.4572 0.4572)
			(layers "F.Cu" "F.Mask" "F.Paste")
			(net "P5E_PEX3_STN5_TX_DN<88>")
		)
		(pad "H33" smd circle
			(at 7.599934 -16.150082)
			(size 0.4572 0.4572)
			(layers "F.Cu" "F.Mask" "F.Paste")
			(net "GND")
		)
		(pad "H34" smd circle
			(at 8.549894 -16.150082)
			(size 0.4572 0.4572)
			(layers "F.Cu" "F.Mask" "F.Paste")
			(net "P5E_PEX3_STN5_TX_DN<90>")
		)
		(pad "H35" smd circle
			(at 9.500108 -16.150082)
			(size 0.4572 0.4572)
			(layers "F.Cu" "F.Mask" "F.Paste")
			(net "GND")
		)
		(pad "H36" smd circle
			(at 10.450068 -16.150082)
			(size 0.4572 0.4572)
			(layers "F.Cu" "F.Mask" "F.Paste")
			(net "P5E_PEX3_STN5_TX_DN<92>")
		)
		(pad "H37" smd circle
			(at 11.400028 -16.150082)
			(size 0.4572 0.4572)
			(layers "F.Cu" "F.Mask" "F.Paste")
			(net "GND")
		)
		(pad "H38" smd circle
			(at 12.349988 -16.150082)
			(size 0.4572 0.4572)
			(layers "F.Cu" "F.Mask" "F.Paste")
			(net "P5E_PEX3_STN5_TX_DN<94>")
		)
		(pad "H39" smd circle
			(at 13.299948 -16.150082)
			(size 0.4572 0.4572)
			(layers "F.Cu" "F.Mask" "F.Paste")
			(net "GND")
		)
		(pad "H40" smd circle
			(at 14.249908 -16.150082)
			(size 0.4572 0.4572)
			(layers "F.Cu" "F.Mask" "F.Paste")
			(net "P5E_PEX3_STN4_TX_DN<79>")
		)
		(pad "H41" smd circle
			(at 15.200122 -16.150082)
			(size 0.4572 0.4572)
			(layers "F.Cu" "F.Mask" "F.Paste")
			(net "GND")
		)
		(pad "H42" smd circle
			(at 16.150082 -16.150082)
			(size 0.4572 0.4572)
			(layers "F.Cu" "F.Mask" "F.Paste")
			(net "P5E_PEX3_STN4_TX_DN<77>")
		)
		(pad "H43" smd circle
			(at 17.100042 -16.150082)
			(size 0.4572 0.4572)
			(layers "F.Cu" "F.Mask" "F.Paste")
			(net "GND")
		)
		(pad "H44" smd circle
			(at 18.050002 -16.150082)
			(size 0.4572 0.4572)
			(layers "F.Cu" "F.Mask" "F.Paste")
			(net "P5E_PEX3_STN4_TX_DN<75>")
		)
		(pad "H45" smd circle
			(at 18.999962 -16.150082)
			(size 0.4572 0.4572)
			(layers "F.Cu" "F.Mask" "F.Paste")
			(net "GND")
		)
		(pad "H46" smd circle
			(at 19.949922 -16.150082)
			(size 0.4572 0.4572)
			(layers "F.Cu" "F.Mask" "F.Paste")
			(net "P5E_PEX3_STN4_TX_DN<73>")
		)
		(pad "H47" smd circle
			(at 20.899882 -16.150082)
			(size 0.4572 0.4572)
			(layers "F.Cu" "F.Mask" "F.Paste")
			(net "GND")
		)
		(pad "H48" smd circle
			(at 21.850096 -16.150082)
			(size 0.4572 0.4572)
			(layers "F.Cu" "F.Mask" "F.Paste")
			(net "P5E_PEX3_STN4_TX_DP<70>")
		)
		(pad "H49" smd circle
			(at 22.800056 -16.150082)
			(size 0.4572 0.4572)
			(layers "F.Cu" "F.Mask" "F.Paste")
			(net "P5E_PEX3_STN4_TX_DN<70>")
		)
		(pad "J1" smd circle
			(at -22.800056 -15.200122)
			(size 0.4572 0.4572)
			(layers "F.Cu" "F.Mask" "F.Paste")
			(net "GND")
		)
		(pad "J2" smd circle
			(at -21.850096 -15.200122)
			(size 0.4572 0.4572)
			(layers "F.Cu" "F.Mask" "F.Paste")
			(net "GND")
		)
		(pad "J3" smd circle
			(at -20.899882 -15.200122)
			(size 0.4572 0.4572)
			(layers "F.Cu" "F.Mask" "F.Paste")
			(net "GND")
		)
		(pad "J4" smd circle
			(at -19.949922 -15.200122)
			(size 0.4572 0.4572)
			(layers "F.Cu" "F.Mask" "F.Paste")
			(net "P5E_PEX3_STN7_TX_DP<124>")
		)
		(pad "J5" smd circle
			(at -18.999962 -15.200122)
			(size 0.4572 0.4572)
			(layers "F.Cu" "F.Mask" "F.Paste")
			(net "GND")
		)
		(pad "J6" smd circle
			(at -18.050002 -15.200122)
			(size 0.4572 0.4572)
			(layers "F.Cu" "F.Mask" "F.Paste")
			(net "P5E_PEX3_STN7_TX_DP<126>")
		)
		(pad "J7" smd circle
			(at -17.100042 -15.200122)
			(size 0.4572 0.4572)
			(layers "F.Cu" "F.Mask" "F.Paste")
			(net "GND")
		)
		(pad "J8" smd circle
			(at -16.150082 -15.200122)
			(size 0.4572 0.4572)
			(layers "F.Cu" "F.Mask" "F.Paste")
			(net "P5E_PEX3_STN6_TX_DP<111>")
		)
		(pad "J9" smd circle
			(at -15.200122 -15.200122)
			(size 0.4572 0.4572)
			(layers "F.Cu" "F.Mask" "F.Paste")
			(net "GND")
		)
		(pad "J10" smd circle
			(at -14.249908 -15.200122)
			(size 0.4572 0.4572)
			(layers "F.Cu" "F.Mask" "F.Paste")
			(net "P5E_PEX3_STN6_TX_DP<109>")
		)
		(pad "J11" smd circle
			(at -13.299948 -15.200122)
			(size 0.4572 0.4572)
			(layers "F.Cu" "F.Mask" "F.Paste")
			(net "GND")
		)
		(pad "J12" smd circle
			(at -12.349988 -15.200122)
			(size 0.4572 0.4572)
			(layers "F.Cu" "F.Mask" "F.Paste")
			(net "P5E_PEX3_STN6_TX_DP<107>")
		)
		(pad "J13" smd circle
			(at -11.400028 -15.200122)
			(size 0.4572 0.4572)
			(layers "F.Cu" "F.Mask" "F.Paste")
			(net "GND")
		)
		(pad "J14" smd circle
			(at -10.450068 -15.200122)
			(size 0.4572 0.4572)
			(layers "F.Cu" "F.Mask" "F.Paste")
			(net "P5E_PEX3_STN6_TX_DP<105>")
		)
		(pad "J15" smd circle
			(at -9.500108 -15.200122)
			(size 0.4572 0.4572)
			(layers "F.Cu" "F.Mask" "F.Paste")
			(net "GND")
		)
		(pad "J16" smd circle
			(at -8.549894 -15.200122)
			(size 0.4572 0.4572)
			(layers "F.Cu" "F.Mask" "F.Paste")
			(net "P5E_PEX3_STN6_TX_DP<103>")
		)
		(pad "J17" smd circle
			(at -7.599934 -15.200122)
			(size 0.4572 0.4572)
			(layers "F.Cu" "F.Mask" "F.Paste")
			(net "GND")
		)
		(pad "J18" smd circle
			(at -6.649974 -15.200122)
			(size 0.4572 0.4572)
			(layers "F.Cu" "F.Mask" "F.Paste")
			(net "P5E_PEX3_STN6_TX_DP<101>")
		)
		(pad "J19" smd circle
			(at -5.700014 -15.200122)
			(size 0.4572 0.4572)
			(layers "F.Cu" "F.Mask" "F.Paste")
			(net "GND")
		)
		(pad "J20" smd circle
			(at -4.750054 -15.200122)
			(size 0.4572 0.4572)
			(layers "F.Cu" "F.Mask" "F.Paste")
			(net "P5E_PEX3_STN6_TX_DP<99>")
		)
		(pad "J21" smd circle
			(at -3.800094 -15.200122)
			(size 0.4572 0.4572)
			(layers "F.Cu" "F.Mask" "F.Paste")
			(net "GND")
		)
		(pad "J22" smd circle
			(at -2.84988 -15.200122)
			(size 0.4572 0.4572)
			(layers "F.Cu" "F.Mask" "F.Paste")
			(net "P5E_PEX3_STN6_TX_DP<97>")
		)
		(pad "J23" smd circle
			(at -1.89992 -15.200122)
			(size 0.4572 0.4572)
			(layers "F.Cu" "F.Mask" "F.Paste")
			(net "GND")
		)
		(pad "J24" smd circle
			(at -0.94996 -15.200122)
			(size 0.4572 0.4572)
			(layers "F.Cu" "F.Mask" "F.Paste")
			(net "P5E_PEX3_STN5_TX_DP<80>")
		)
		(pad "J25" smd circle
			(at 0 -15.200122)
			(size 0.4572 0.4572)
			(layers "F.Cu" "F.Mask" "F.Paste")
			(net "GND")
		)
		(pad "J26" smd circle
			(at 0.94996 -15.200122)
			(size 0.4572 0.4572)
			(layers "F.Cu" "F.Mask" "F.Paste")
			(net "P5E_PEX3_STN5_TX_DP<82>")
		)
		(pad "J27" smd circle
			(at 1.89992 -15.200122)
			(size 0.4572 0.4572)
			(layers "F.Cu" "F.Mask" "F.Paste")
			(net "GND")
		)
		(pad "J28" smd circle
			(at 2.84988 -15.200122)
			(size 0.4572 0.4572)
			(layers "F.Cu" "F.Mask" "F.Paste")
			(net "P5E_PEX3_STN5_TX_DP<84>")
		)
		(pad "J29" smd circle
			(at 3.800094 -15.200122)
			(size 0.4572 0.4572)
			(layers "F.Cu" "F.Mask" "F.Paste")
			(net "GND")
		)
		(pad "J30" smd circle
			(at 4.750054 -15.200122)
			(size 0.4572 0.4572)
			(layers "F.Cu" "F.Mask" "F.Paste")
			(net "P5E_PEX3_STN5_TX_DP<86>")
		)
		(pad "J31" smd circle
			(at 5.700014 -15.200122)
			(size 0.4572 0.4572)
			(layers "F.Cu" "F.Mask" "F.Paste")
			(net "GND")
		)
		(pad "J32" smd circle
			(at 6.649974 -15.200122)
			(size 0.4572 0.4572)
			(layers "F.Cu" "F.Mask" "F.Paste")
			(net "P5E_PEX3_STN5_TX_DP<88>")
		)
		(pad "J33" smd circle
			(at 7.599934 -15.200122)
			(size 0.4572 0.4572)
			(layers "F.Cu" "F.Mask" "F.Paste")
			(net "GND")
		)
		(pad "J34" smd circle
			(at 8.549894 -15.200122)
			(size 0.4572 0.4572)
			(layers "F.Cu" "F.Mask" "F.Paste")
			(net "P5E_PEX3_STN5_TX_DP<90>")
		)
		(pad "J35" smd circle
			(at 9.500108 -15.200122)
			(size 0.4572 0.4572)
			(layers "F.Cu" "F.Mask" "F.Paste")
			(net "GND")
		)
		(pad "J36" smd circle
			(at 10.450068 -15.200122)
			(size 0.4572 0.4572)
			(layers "F.Cu" "F.Mask" "F.Paste")
			(net "P5E_PEX3_STN5_TX_DP<92>")
		)
		(pad "J37" smd circle
			(at 11.400028 -15.200122)
			(size 0.4572 0.4572)
			(layers "F.Cu" "F.Mask" "F.Paste")
			(net "GND")
		)
		(pad "J38" smd circle
			(at 12.349988 -15.200122)
			(size 0.4572 0.4572)
			(layers "F.Cu" "F.Mask" "F.Paste")
			(net "P5E_PEX3_STN5_TX_DP<94>")
		)
		(pad "J39" smd circle
			(at 13.299948 -15.200122)
			(size 0.4572 0.4572)
			(layers "F.Cu" "F.Mask" "F.Paste")
			(net "GND")
		)
		(pad "J40" smd circle
			(at 14.249908 -15.200122)
			(size 0.4572 0.4572)
			(layers "F.Cu" "F.Mask" "F.Paste")
			(net "P5E_PEX3_STN4_TX_DP<79>")
		)
		(pad "J41" smd circle
			(at 15.200122 -15.200122)
			(size 0.4572 0.4572)
			(layers "F.Cu" "F.Mask" "F.Paste")
			(net "GND")
		)
		(pad "J42" smd circle
			(at 16.150082 -15.200122)
			(size 0.4572 0.4572)
			(layers "F.Cu" "F.Mask" "F.Paste")
			(net "P5E_PEX3_STN4_TX_DP<77>")
		)
		(pad "J43" smd circle
			(at 17.100042 -15.200122)
			(size 0.4572 0.4572)
			(layers "F.Cu" "F.Mask" "F.Paste")
			(net "GND")
		)
		(pad "J44" smd circle
			(at 18.050002 -15.200122)
			(size 0.4572 0.4572)
			(layers "F.Cu" "F.Mask" "F.Paste")
			(net "P5E_PEX3_STN4_TX_DP<75>")
		)
		(pad "J45" smd circle
			(at 18.999962 -15.200122)
			(size 0.4572 0.4572)
			(layers "F.Cu" "F.Mask" "F.Paste")
			(net "GND")
		)
		(pad "J46" smd circle
			(at 19.949922 -15.200122)
			(size 0.4572 0.4572)
			(layers "F.Cu" "F.Mask" "F.Paste")
			(net "P5E_PEX3_STN4_TX_DP<73>")
		)
		(pad "J47" smd circle
			(at 20.899882 -15.200122)
			(size 0.4572 0.4572)
			(layers "F.Cu" "F.Mask" "F.Paste")
			(net "GND")
		)
		(pad "J48" smd circle
			(at 21.850096 -15.200122)
			(size 0.4572 0.4572)
			(layers "F.Cu" "F.Mask" "F.Paste")
			(net "GND")
		)
		(pad "J49" smd circle
			(at 22.800056 -15.200122)
			(size 0.4572 0.4572)
			(layers "F.Cu" "F.Mask" "F.Paste")
			(net "GND")
		)
		(pad "K1" smd circle
			(at -22.800056 -14.249908)
			(size 0.4572 0.4572)
			(layers "F.Cu" "F.Mask" "F.Paste")
			(net "P5E_PEX3_STN7_RX_DN<121>")
		)
		(pad "K2" smd circle
			(at -21.850096 -14.249908)
			(size 0.4572 0.4572)
			(layers "F.Cu" "F.Mask" "F.Paste")
			(net "P5E_PEX3_STN7_RX_DP<121>")
		)
		(pad "K3" smd circle
			(at -20.899882 -14.249908)
			(size 0.4572 0.4572)
			(layers "F.Cu" "F.Mask" "F.Paste")
			(net "GND")
		)
		(pad "K4" smd circle
			(at -19.949922 -14.249908)
			(size 0.4572 0.4572)
			(layers "F.Cu" "F.Mask" "F.Paste")
			(net "GND")
		)
		(pad "K5" smd circle
			(at -18.999962 -14.249908)
			(size 0.4572 0.4572)
			(layers "F.Cu" "F.Mask" "F.Paste")
			(net "GND")
		)
		(pad "K6" smd circle
			(at -18.050002 -14.249908)
			(size 0.4572 0.4572)
			(layers "F.Cu" "F.Mask" "F.Paste")
			(net "GND")
		)
		(pad "K7" smd circle
			(at -17.100042 -14.249908)
			(size 0.4572 0.4572)
			(layers "F.Cu" "F.Mask" "F.Paste")
			(net "GND")
		)
		(pad "K8" smd circle
			(at -16.150082 -14.249908)
			(size 0.4572 0.4572)
			(layers "F.Cu" "F.Mask" "F.Paste")
			(net "GND")
		)
		(pad "K9" smd circle
			(at -15.200122 -14.249908)
			(size 0.4572 0.4572)
			(layers "F.Cu" "F.Mask" "F.Paste")
			(net "GND")
		)
		(pad "K10" smd circle
			(at -14.249908 -14.249908)
			(size 0.4572 0.4572)
			(layers "F.Cu" "F.Mask" "F.Paste")
			(net "GND")
		)
		(pad "K11" smd circle
			(at -13.299948 -14.249908)
			(size 0.4572 0.4572)
			(layers "F.Cu" "F.Mask" "F.Paste")
			(net "GND")
		)
		(pad "K12" smd circle
			(at -12.349988 -14.249908)
			(size 0.4572 0.4572)
			(layers "F.Cu" "F.Mask" "F.Paste")
			(net "GND")
		)
		(pad "K13" smd circle
			(at -11.400028 -14.249908)
			(size 0.4572 0.4572)
			(layers "F.Cu" "F.Mask" "F.Paste")
			(net "GND")
		)
		(pad "K14" smd circle
			(at -10.450068 -14.249908)
			(size 0.4572 0.4572)
			(layers "F.Cu" "F.Mask" "F.Paste")
			(net "GND")
		)
		(pad "K15" smd circle
			(at -9.500108 -14.249908)
			(size 0.4572 0.4572)
			(layers "F.Cu" "F.Mask" "F.Paste")
			(net "GND")
		)
		(pad "K16" smd circle
			(at -8.549894 -14.249908)
			(size 0.4572 0.4572)
			(layers "F.Cu" "F.Mask" "F.Paste")
			(net "GND")
		)
		(pad "K17" smd circle
			(at -7.599934 -14.249908)
			(size 0.4572 0.4572)
			(layers "F.Cu" "F.Mask" "F.Paste")
			(net "GND")
		)
		(pad "K18" smd circle
			(at -6.649974 -14.249908)
			(size 0.4572 0.4572)
			(layers "F.Cu" "F.Mask" "F.Paste")
			(net "GND")
		)
		(pad "K19" smd circle
			(at -5.700014 -14.249908)
			(size 0.4572 0.4572)
			(layers "F.Cu" "F.Mask" "F.Paste")
			(net "GND")
		)
		(pad "K20" smd circle
			(at -4.750054 -14.249908)
			(size 0.4572 0.4572)
			(layers "F.Cu" "F.Mask" "F.Paste")
			(net "GND")
		)
		(pad "K21" smd circle
			(at -3.800094 -14.249908)
			(size 0.4572 0.4572)
			(layers "F.Cu" "F.Mask" "F.Paste")
			(net "GND")
		)
		(pad "K22" smd circle
			(at -2.84988 -14.249908)
			(size 0.4572 0.4572)
			(layers "F.Cu" "F.Mask" "F.Paste")
			(net "GND")
		)
		(pad "K23" smd circle
			(at -1.89992 -14.249908)
			(size 0.4572 0.4572)
			(layers "F.Cu" "F.Mask" "F.Paste")
			(net "GND")
		)
		(pad "K24" smd circle
			(at -0.94996 -14.249908)
			(size 0.4572 0.4572)
			(layers "F.Cu" "F.Mask" "F.Paste")
			(net "GND")
		)
		(pad "K25" smd circle
			(at 0 -14.249908)
			(size 0.4572 0.4572)
			(layers "F.Cu" "F.Mask" "F.Paste")
			(net "GND")
		)
		(pad "K26" smd circle
			(at 0.94996 -14.249908)
			(size 0.4572 0.4572)
			(layers "F.Cu" "F.Mask" "F.Paste")
			(net "GND")
		)
		(pad "K27" smd circle
			(at 1.89992 -14.249908)
			(size 0.4572 0.4572)
			(layers "F.Cu" "F.Mask" "F.Paste")
			(net "GND")
		)
		(pad "K28" smd circle
			(at 2.84988 -14.249908)
			(size 0.4572 0.4572)
			(layers "F.Cu" "F.Mask" "F.Paste")
			(net "GND")
		)
		(pad "K29" smd circle
			(at 3.800094 -14.249908)
			(size 0.4572 0.4572)
			(layers "F.Cu" "F.Mask" "F.Paste")
			(net "GND")
		)
		(pad "K30" smd circle
			(at 4.750054 -14.249908)
			(size 0.4572 0.4572)
			(layers "F.Cu" "F.Mask" "F.Paste")
			(net "GND")
		)
		(pad "K31" smd circle
			(at 5.700014 -14.249908)
			(size 0.4572 0.4572)
			(layers "F.Cu" "F.Mask" "F.Paste")
			(net "GND")
		)
		(pad "K32" smd circle
			(at 6.649974 -14.249908)
			(size 0.4572 0.4572)
			(layers "F.Cu" "F.Mask" "F.Paste")
			(net "GND")
		)
		(pad "K33" smd circle
			(at 7.599934 -14.249908)
			(size 0.4572 0.4572)
			(layers "F.Cu" "F.Mask" "F.Paste")
			(net "GND")
		)
		(pad "K34" smd circle
			(at 8.549894 -14.249908)
			(size 0.4572 0.4572)
			(layers "F.Cu" "F.Mask" "F.Paste")
			(net "GND")
		)
		(pad "K35" smd circle
			(at 9.500108 -14.249908)
			(size 0.4572 0.4572)
			(layers "F.Cu" "F.Mask" "F.Paste")
			(net "GND")
		)
		(pad "K36" smd circle
			(at 10.450068 -14.249908)
			(size 0.4572 0.4572)
			(layers "F.Cu" "F.Mask" "F.Paste")
			(net "GND")
		)
		(pad "K37" smd circle
			(at 11.400028 -14.249908)
			(size 0.4572 0.4572)
			(layers "F.Cu" "F.Mask" "F.Paste")
			(net "GND")
		)
		(pad "K38" smd circle
			(at 12.349988 -14.249908)
			(size 0.4572 0.4572)
			(layers "F.Cu" "F.Mask" "F.Paste")
			(net "GND")
		)
		(pad "K39" smd circle
			(at 13.299948 -14.249908)
			(size 0.4572 0.4572)
			(layers "F.Cu" "F.Mask" "F.Paste")
			(net "GND")
		)
		(pad "K40" smd circle
			(at 14.249908 -14.249908)
			(size 0.4572 0.4572)
			(layers "F.Cu" "F.Mask" "F.Paste")
			(net "GND")
		)
		(pad "K41" smd circle
			(at 15.200122 -14.249908)
			(size 0.4572 0.4572)
			(layers "F.Cu" "F.Mask" "F.Paste")
			(net "GND")
		)
		(pad "K42" smd circle
			(at 16.150082 -14.249908)
			(size 0.4572 0.4572)
			(layers "F.Cu" "F.Mask" "F.Paste")
			(net "GND")
		)
		(pad "K43" smd circle
			(at 17.100042 -14.249908)
			(size 0.4572 0.4572)
			(layers "F.Cu" "F.Mask" "F.Paste")
			(net "GND")
		)
		(pad "K44" smd circle
			(at 18.050002 -14.249908)
			(size 0.4572 0.4572)
			(layers "F.Cu" "F.Mask" "F.Paste")
			(net "GND")
		)
		(pad "K45" smd circle
			(at 18.999962 -14.249908)
			(size 0.4572 0.4572)
			(layers "F.Cu" "F.Mask" "F.Paste")
			(net "GND")
		)
		(pad "K46" smd circle
			(at 19.949922 -14.249908)
			(size 0.4572 0.4572)
			(layers "F.Cu" "F.Mask" "F.Paste")
			(net "GND")
		)
		(pad "K47" smd circle
			(at 20.899882 -14.249908)
			(size 0.4572 0.4572)
			(layers "F.Cu" "F.Mask" "F.Paste")
			(net "GND")
		)
		(pad "K48" smd circle
			(at 21.850096 -14.249908)
			(size 0.4572 0.4572)
			(layers "F.Cu" "F.Mask" "F.Paste")
			(net "P5E_PEX3_STN4_RX_DP<70>")
		)
		(pad "K49" smd circle
			(at 22.800056 -14.249908)
			(size 0.4572 0.4572)
			(layers "F.Cu" "F.Mask" "F.Paste")
			(net "P5E_PEX3_STN4_RX_DN<70>")
		)
		(pad "L1" smd circle
			(at -22.800056 -13.299948)
			(size 0.4572 0.4572)
			(layers "F.Cu" "F.Mask" "F.Paste")
			(net "GND")
		)
		(pad "L2" smd circle
			(at -21.850096 -13.299948)
			(size 0.4572 0.4572)
			(layers "F.Cu" "F.Mask" "F.Paste")
			(net "GND")
		)
		(pad "L3" smd circle
			(at -20.899882 -13.299948)
			(size 0.4572 0.4572)
			(layers "F.Cu" "F.Mask" "F.Paste")
			(net "P5E_PEX3_STN7_RX_DN<120>")
		)
		(pad "L4" smd circle
			(at -19.949922 -13.299948)
			(size 0.4572 0.4572)
			(layers "F.Cu" "F.Mask" "F.Paste")
			(net "P5E_PEX3_STN7_RX_DP<120>")
		)
		(pad "L5" smd circle
			(at -18.999962 -13.299948)
			(size 0.4572 0.4572)
			(layers "F.Cu" "F.Mask" "F.Paste")
			(net "GND")
		)
		(pad "L6" smd circle
			(at -18.050002 -13.299948)
			(size 0.4572 0.4572)
			(layers "F.Cu" "F.Mask" "F.Paste")
			(net "P5E_PEX3_STN7_TX_DN<120>")
		)
		(pad "L7" smd circle
			(at -17.100042 -13.299948)
			(size 0.4572 0.4572)
			(layers "F.Cu" "F.Mask" "F.Paste")
			(net "P5E_PEX3_STN7_TX_DP<120>")
		)
		(pad "L8" smd circle
			(at -16.150082 -13.299948)
			(size 0.4572 0.4572)
			(layers "F.Cu" "F.Mask" "F.Paste")
			(net "GND")
		)
		(pad "L9" smd circle
			(at -15.200122 -13.299948)
			(size 0.4572 0.4572)
			(layers "F.Cu" "F.Mask" "F.Paste")
			(net "GND")
		)
		(pad "L10" smd circle
			(at -14.249908 -13.299948)
			(size 0.4572 0.4572)
			(layers "F.Cu" "F.Mask" "F.Paste")
			(net "GND")
		)
		(pad "L11" smd circle
			(at -13.299948 -13.299948)
			(size 0.4572 0.4572)
			(layers "F.Cu" "F.Mask" "F.Paste")
			(net "GND")
		)
		(pad "L12" smd circle
			(at -12.349988 -13.299948)
			(size 0.4572 0.4572)
			(layers "F.Cu" "F.Mask" "F.Paste")
			(net "PEX3_DBG_MODE0")
		)
		(pad "L13" smd circle
			(at -11.400028 -13.299948)
			(size 0.4572 0.4572)
			(layers "F.Cu" "F.Mask" "F.Paste")
			(net "PEX3_DBG_MODE1")
		)
		(pad "L14" smd circle
			(at -10.450068 -13.299948)
			(size 0.4572 0.4572)
			(layers "F.Cu" "F.Mask" "F.Paste")
			(net "GND")
		)
		(pad "L15" smd circle
			(at -9.500108 -13.299948)
			(size 0.4572 0.4572)
			(layers "F.Cu" "F.Mask" "F.Paste")
			(net "PU_PEX3_ATPG_MODE_L")
		)
		(pad "L16" smd circle
			(at -8.549894 -13.299948)
			(size 0.4572 0.4572)
			(layers "F.Cu" "F.Mask" "F.Paste")
			(net "PU_PEX3_PAD_TRI_L")
		)
		(pad "L17" smd circle
			(at -7.599934 -13.299948)
			(size 0.4572 0.4572)
			(layers "F.Cu" "F.Mask" "F.Paste")
			(net "TP_PEX3_TDI")
		)
		(pad "L18" smd circle
			(at -6.649974 -13.299948)
			(size 0.4572 0.4572)
			(layers "F.Cu" "F.Mask" "F.Paste")
			(net "PEX3_DBG_SEL0")
		)
		(pad "L19" smd circle
			(at -5.700014 -13.299948)
			(size 0.4572 0.4572)
			(layers "F.Cu" "F.Mask" "F.Paste")
			(net "TP_PEX3_TDO")
		)
		(pad "L20" smd circle
			(at -4.750054 -13.299948)
			(size 0.4572 0.4572)
			(layers "F.Cu" "F.Mask" "F.Paste")
			(net "PU_PEX3_TR_TCK")
		)
		(pad "L21" smd circle
			(at -3.800094 -13.299948)
			(size 0.4572 0.4572)
			(layers "F.Cu" "F.Mask" "F.Paste")
			(net "GND")
		)
		(pad "L22" smd circle
			(at -2.84988 -13.299948)
			(size 0.4572 0.4572)
			(layers "F.Cu" "F.Mask" "F.Paste")
			(net "Net_5469")
		)
		(pad "L23" smd circle
			(at -1.89992 -13.299948)
			(size 0.4572 0.4572)
			(layers "F.Cu" "F.Mask" "F.Paste")
			(net "Net_5473")
		)
		(pad "L24" smd circle
			(at -0.94996 -13.299948)
			(size 0.4572 0.4572)
			(layers "F.Cu" "F.Mask" "F.Paste")
			(net "Net_5468")
		)
		(pad "L25" smd circle
			(at 0 -13.299948)
			(size 0.4572 0.4572)
			(layers "F.Cu" "F.Mask" "F.Paste")
			(net "PEX3_SPARE5")
		)
		(pad "L26" smd circle
			(at 0.94996 -13.299948)
			(size 0.4572 0.4572)
			(layers "F.Cu" "F.Mask" "F.Paste")
			(net "PU_PEX3_SIO_BLINK")
		)
		(pad "L27" smd circle
			(at 1.89992 -13.299948)
			(size 0.4572 0.4572)
			(layers "F.Cu" "F.Mask" "F.Paste")
			(net "PEX3_SPARE2")
		)
		(pad "L28" smd circle
			(at 2.84988 -13.299948)
			(size 0.4572 0.4572)
			(layers "F.Cu" "F.Mask" "F.Paste")
			(net "PEX3_SPARE6")
		)
		(pad "L29" smd circle
			(at 3.800094 -13.299948)
			(size 0.4572 0.4572)
			(layers "F.Cu" "F.Mask" "F.Paste")
			(net "Net_5458")
		)
		(pad "L30" smd circle
			(at 4.750054 -13.299948)
			(size 0.4572 0.4572)
			(layers "F.Cu" "F.Mask" "F.Paste")
			(net "PEX3_SPARE1")
		)
		(pad "L31" smd circle
			(at 5.700014 -13.299948)
			(size 0.4572 0.4572)
			(layers "F.Cu" "F.Mask" "F.Paste")
			(net "Net_5462")
		)
		(pad "L32" smd circle
			(at 6.649974 -13.299948)
			(size 0.4572 0.4572)
			(layers "F.Cu" "F.Mask" "F.Paste")
			(net "PEX3_SPARE3")
		)
		(pad "L33" smd circle
			(at 7.599934 -13.299948)
			(size 0.4572 0.4572)
			(layers "F.Cu" "F.Mask" "F.Paste")
			(net "Net_5454")
		)
		(pad "L34" smd circle
			(at 8.549894 -13.299948)
			(size 0.4572 0.4572)
			(layers "F.Cu" "F.Mask" "F.Paste")
			(net "SMB_PEX3_SLAVE1_SCL")
		)
		(pad "L35" smd circle
			(at 9.500108 -13.299948)
			(size 0.4572 0.4572)
			(layers "F.Cu" "F.Mask" "F.Paste")
			(net "Net_5451")
		)
		(pad "L36" smd circle
			(at 10.450068 -13.299948)
			(size 0.4572 0.4572)
			(layers "F.Cu" "F.Mask" "F.Paste")
			(net "Net_5481")
		)
		(pad "L37" smd circle
			(at 11.400028 -13.299948)
			(size 0.4572 0.4572)
			(layers "F.Cu" "F.Mask" "F.Paste")
			(net "PEX3_EXT_GPIO_LATCH_N")
		)
		(pad "L38" smd circle
			(at 12.349988 -13.299948)
			(size 0.4572 0.4572)
			(layers "F.Cu" "F.Mask" "F.Paste")
			(net "Net_5478")
		)
		(pad "L39" smd circle
			(at 13.299948 -13.299948)
			(size 0.4572 0.4572)
			(layers "F.Cu" "F.Mask" "F.Paste")
			(net "SMB_PEX3_SLAVE_SDA")
		)
		(pad "L40" smd circle
			(at 14.249908 -13.299948)
			(size 0.4572 0.4572)
			(layers "F.Cu" "F.Mask" "F.Paste")
			(net "GND")
		)
		(pad "L41" smd circle
			(at 15.200122 -13.299948)
			(size 0.4572 0.4572)
			(layers "F.Cu" "F.Mask" "F.Paste")
			(net "GND")
		)
		(pad "L42" smd circle
			(at 16.150082 -13.299948)
			(size 0.4572 0.4572)
			(layers "F.Cu" "F.Mask" "F.Paste")
			(net "GND")
		)
		(pad "L43" smd circle
			(at 17.100042 -13.299948)
			(size 0.4572 0.4572)
			(layers "F.Cu" "F.Mask" "F.Paste")
			(net "P5E_PEX3_STN4_TX_DP<69>")
		)
		(pad "L44" smd circle
			(at 18.050002 -13.299948)
			(size 0.4572 0.4572)
			(layers "F.Cu" "F.Mask" "F.Paste")
			(net "P5E_PEX3_STN4_TX_DN<69>")
		)
		(pad "L45" smd circle
			(at 18.999962 -13.299948)
			(size 0.4572 0.4572)
			(layers "F.Cu" "F.Mask" "F.Paste")
			(net "GND")
		)
		(pad "L46" smd circle
			(at 19.949922 -13.299948)
			(size 0.4572 0.4572)
			(layers "F.Cu" "F.Mask" "F.Paste")
			(net "P5E_PEX3_STN4_RX_DP<69>")
		)
		(pad "L47" smd circle
			(at 20.899882 -13.299948)
			(size 0.4572 0.4572)
			(layers "F.Cu" "F.Mask" "F.Paste")
			(net "P5E_PEX3_STN4_RX_DN<69>")
		)
		(pad "L48" smd circle
			(at 21.850096 -13.299948)
			(size 0.4572 0.4572)
			(layers "F.Cu" "F.Mask" "F.Paste")
			(net "GND")
		)
		(pad "L49" smd circle
			(at 22.800056 -13.299948)
			(size 0.4572 0.4572)
			(layers "F.Cu" "F.Mask" "F.Paste")
			(net "GND")
		)
		(pad "M1" smd circle
			(at -22.800056 -12.349988)
			(size 0.4572 0.4572)
			(layers "F.Cu" "F.Mask" "F.Paste")
			(net "P5E_PEX3_STN7_RX_DN<119>")
		)
		(pad "M2" smd circle
			(at -21.850096 -12.349988)
			(size 0.4572 0.4572)
			(layers "F.Cu" "F.Mask" "F.Paste")
			(net "P5E_PEX3_STN7_RX_DP<119>")
		)
		(pad "M3" smd circle
			(at -20.899882 -12.349988)
			(size 0.4572 0.4572)
			(layers "F.Cu" "F.Mask" "F.Paste")
			(net "GND")
		)
		(pad "M4" smd circle
			(at -19.949922 -12.349988)
			(size 0.4572 0.4572)
			(layers "F.Cu" "F.Mask" "F.Paste")
			(net "GND")
		)
		(pad "M5" smd circle
			(at -18.999962 -12.349988)
			(size 0.4572 0.4572)
			(layers "F.Cu" "F.Mask" "F.Paste")
			(net "GND")
		)
		(pad "M6" smd circle
			(at -18.050002 -12.349988)
			(size 0.4572 0.4572)
			(layers "F.Cu" "F.Mask" "F.Paste")
			(net "GND")
		)
		(pad "M7" smd circle
			(at -17.100042 -12.349988)
			(size 0.4572 0.4572)
			(layers "F.Cu" "F.Mask" "F.Paste")
			(net "GND")
		)
		(pad "M8" smd circle
			(at -16.150082 -12.349988)
			(size 0.4572 0.4572)
			(layers "F.Cu" "F.Mask" "F.Paste")
			(net "P5E_PEX3_STN7_TX_DN<119>")
		)
		(pad "M9" smd circle
			(at -15.200122 -12.349988)
			(size 0.4572 0.4572)
			(layers "F.Cu" "F.Mask" "F.Paste")
			(net "P5E_PEX3_STN7_TX_DP<119>")
		)
		(pad "M10" smd circle
			(at -14.249908 -12.349988)
			(size 0.4572 0.4572)
			(layers "F.Cu" "F.Mask" "F.Paste")
			(net "GND")
		)
		(pad "M11" smd circle
			(at -13.299948 -12.349988)
			(size 0.4572 0.4572)
			(layers "F.Cu" "F.Mask" "F.Paste")
			(net "GND")
		)
		(pad "M12" smd circle
			(at -12.349988 -12.349988)
			(size 0.4572 0.4572)
			(layers "F.Cu" "F.Mask" "F.Paste")
			(net "GND")
		)
		(pad "M13" smd circle
			(at -11.400028 -12.349988)
			(size 0.4572 0.4572)
			(layers "F.Cu" "F.Mask" "F.Paste")
			(net "IRQ_PEX3_CLKREQ_INT_N")
		)
		(pad "M14" smd circle
			(at -10.450068 -12.349988)
			(size 0.4572 0.4572)
			(layers "F.Cu" "F.Mask" "F.Paste")
			(net "GND")
		)
		(pad "M15" smd circle
			(at -9.500108 -12.349988)
			(size 0.4572 0.4572)
			(layers "F.Cu" "F.Mask" "F.Paste")
			(net "TP_PEX3_TCK")
		)
		(pad "M16" smd circle
			(at -8.549894 -12.349988)
			(size 0.4572 0.4572)
			(layers "F.Cu" "F.Mask" "F.Paste")
			(net "PEX3_DFT_IDDT")
		)
		(pad "M17" smd circle
			(at -7.599934 -12.349988)
			(size 0.4572 0.4572)
			(layers "F.Cu" "F.Mask" "F.Paste")
			(net "RST_PEX3_SYS_N")
		)
		(pad "M18" smd circle
			(at -6.649974 -12.349988)
			(size 0.4572 0.4572)
			(layers "F.Cu" "F.Mask" "F.Paste")
			(net "TP_PEX3_TRST_L")
		)
		(pad "M19" smd circle
			(at -5.700014 -12.349988)
			(size 0.4572 0.4572)
			(layers "F.Cu" "F.Mask" "F.Paste")
			(net "PEX3_DBG_SEL1")
		)
		(pad "M20" smd circle
			(at -4.750054 -12.349988)
			(size 0.4572 0.4572)
			(layers "F.Cu" "F.Mask" "F.Paste")
			(net "TP_PEX3_TMS")
		)
		(pad "M21" smd circle
			(at -3.800094 -12.349988)
			(size 0.4572 0.4572)
			(layers "F.Cu" "F.Mask" "F.Paste")
			(net "GND")
		)
		(pad "M22" smd circle
			(at -2.84988 -12.349988)
			(size 0.4572 0.4572)
			(layers "F.Cu" "F.Mask" "F.Paste")
			(net "Net_5471")
		)
		(pad "M23" smd circle
			(at -1.89992 -12.349988)
			(size 0.4572 0.4572)
			(layers "F.Cu" "F.Mask" "F.Paste")
			(net "Net_5472")
		)
		(pad "M24" smd circle
			(at -0.94996 -12.349988)
			(size 0.4572 0.4572)
			(layers "F.Cu" "F.Mask" "F.Paste")
			(net "Net_5474")
		)
		(pad "M25" smd circle
			(at 0 -12.349988)
			(size 0.4572 0.4572)
			(layers "F.Cu" "F.Mask" "F.Paste")
			(net "PEX3_SPARE4")
		)
		(pad "M26" smd circle
			(at 0.94996 -12.349988)
			(size 0.4572 0.4572)
			(layers "F.Cu" "F.Mask" "F.Paste")
			(net "PEX3_SPARE0")
		)
		(pad "M27" smd circle
			(at 1.89992 -12.349988)
			(size 0.4572 0.4572)
			(layers "F.Cu" "F.Mask" "F.Paste")
			(net "PEX3_SPARE7")
		)
		(pad "M28" smd circle
			(at 2.84988 -12.349988)
			(size 0.4572 0.4572)
			(layers "F.Cu" "F.Mask" "F.Paste")
			(net "I2C0_PEX3_SHPC_SDA")
		)
		(pad "M29" smd circle
			(at 3.800094 -12.349988)
			(size 0.4572 0.4572)
			(layers "F.Cu" "F.Mask" "F.Paste")
			(net "I2C0_PEX3_SHPC_SCL")
		)
		(pad "M30" smd circle
			(at 4.750054 -12.349988)
			(size 0.4572 0.4572)
			(layers "F.Cu" "F.Mask" "F.Paste")
			(net "Net_5452")
		)
		(pad "M31" smd circle
			(at 5.700014 -12.349988)
			(size 0.4572 0.4572)
			(layers "F.Cu" "F.Mask" "F.Paste")
			(net "Net_5453")
		)
		(pad "M32" smd circle
			(at 6.649974 -12.349988)
			(size 0.4572 0.4572)
			(layers "F.Cu" "F.Mask" "F.Paste")
			(net "Net_5463")
		)
		(pad "M33" smd circle
			(at 7.599934 -12.349988)
			(size 0.4572 0.4572)
			(layers "F.Cu" "F.Mask" "F.Paste")
			(net "Net_5457")
		)
		(pad "M34" smd circle
			(at 8.549894 -12.349988)
			(size 0.4572 0.4572)
			(layers "F.Cu" "F.Mask" "F.Paste")
			(net "Net_5461")
		)
		(pad "M35" smd circle
			(at 9.500108 -12.349988)
			(size 0.4572 0.4572)
			(layers "F.Cu" "F.Mask" "F.Paste")
			(net "I2C0_PEX3_SCL")
		)
		(pad "M36" smd circle
			(at 10.450068 -12.349988)
			(size 0.4572 0.4572)
			(layers "F.Cu" "F.Mask" "F.Paste")
			(net "Net_5480")
		)
		(pad "M37" smd circle
			(at 11.400028 -12.349988)
			(size 0.4572 0.4572)
			(layers "F.Cu" "F.Mask" "F.Paste")
			(net "Net_5479")
		)
		(pad "M38" smd circle
			(at 12.349988 -12.349988)
			(size 0.4572 0.4572)
			(layers "F.Cu" "F.Mask" "F.Paste")
			(net "SMB_PEX3_SLAVE1_SDA")
		)
		(pad "M39" smd circle
			(at 13.299948 -12.349988)
			(size 0.4572 0.4572)
			(layers "F.Cu" "F.Mask" "F.Paste")
			(net "I2C0_PEX3_SDA")
		)
		(pad "M40" smd circle
			(at 14.249908 -12.349988)
			(size 0.4572 0.4572)
			(layers "F.Cu" "F.Mask" "F.Paste")
			(net "GND")
		)
		(pad "M41" smd circle
			(at 15.200122 -12.349988)
			(size 0.4572 0.4572)
			(layers "F.Cu" "F.Mask" "F.Paste")
			(net "P5E_PEX3_STN4_TX_DP<68>")
		)
		(pad "M42" smd circle
			(at 16.150082 -12.349988)
			(size 0.4572 0.4572)
			(layers "F.Cu" "F.Mask" "F.Paste")
			(net "P5E_PEX3_STN4_TX_DN<68>")
		)
		(pad "M43" smd circle
			(at 17.100042 -12.349988)
			(size 0.4572 0.4572)
			(layers "F.Cu" "F.Mask" "F.Paste")
			(net "GND")
		)
		(pad "M44" smd circle
			(at 18.050002 -12.349988)
			(size 0.4572 0.4572)
			(layers "F.Cu" "F.Mask" "F.Paste")
			(net "GND")
		)
		(pad "M45" smd circle
			(at 18.999962 -12.349988)
			(size 0.4572 0.4572)
			(layers "F.Cu" "F.Mask" "F.Paste")
			(net "GND")
		)
		(pad "M46" smd circle
			(at 19.949922 -12.349988)
			(size 0.4572 0.4572)
			(layers "F.Cu" "F.Mask" "F.Paste")
			(net "GND")
		)
		(pad "M47" smd circle
			(at 20.899882 -12.349988)
			(size 0.4572 0.4572)
			(layers "F.Cu" "F.Mask" "F.Paste")
			(net "GND")
		)
		(pad "M48" smd circle
			(at 21.850096 -12.349988)
			(size 0.4572 0.4572)
			(layers "F.Cu" "F.Mask" "F.Paste")
			(net "P5E_PEX3_STN4_RX_DP<68>")
		)
		(pad "M49" smd circle
			(at 22.800056 -12.349988)
			(size 0.4572 0.4572)
			(layers "F.Cu" "F.Mask" "F.Paste")
			(net "P5E_PEX3_STN4_RX_DN<68>")
		)
		(pad "N1" smd circle
			(at -22.800056 -11.400028)
			(size 0.4572 0.4572)
			(layers "F.Cu" "F.Mask" "F.Paste")
			(net "GND")
		)
		(pad "N2" smd circle
			(at -21.850096 -11.400028)
			(size 0.4572 0.4572)
			(layers "F.Cu" "F.Mask" "F.Paste")
			(net "GND")
		)
		(pad "N3" smd circle
			(at -20.899882 -11.400028)
			(size 0.4572 0.4572)
			(layers "F.Cu" "F.Mask" "F.Paste")
			(net "P5E_PEX3_STN7_RX_DN<118>")
		)
		(pad "N4" smd circle
			(at -19.949922 -11.400028)
			(size 0.4572 0.4572)
			(layers "F.Cu" "F.Mask" "F.Paste")
			(net "P5E_PEX3_STN7_RX_DP<118>")
		)
		(pad "N5" smd circle
			(at -18.999962 -11.400028)
			(size 0.4572 0.4572)
			(layers "F.Cu" "F.Mask" "F.Paste")
			(net "GND")
		)
		(pad "N6" smd circle
			(at -18.050002 -11.400028)
			(size 0.4572 0.4572)
			(layers "F.Cu" "F.Mask" "F.Paste")
			(net "P5E_PEX3_STN7_TX_DN<118>")
		)
		(pad "N7" smd circle
			(at -17.100042 -11.400028)
			(size 0.4572 0.4572)
			(layers "F.Cu" "F.Mask" "F.Paste")
			(net "P5E_PEX3_STN7_TX_DP<118>")
		)
		(pad "N8" smd circle
			(at -16.150082 -11.400028)
			(size 0.4572 0.4572)
			(layers "F.Cu" "F.Mask" "F.Paste")
			(net "GND")
		)
		(pad "N9" smd circle
			(at -15.200122 -11.400028)
			(size 0.4572 0.4572)
			(layers "F.Cu" "F.Mask" "F.Paste")
			(net "GND")
		)
		(pad "N10" smd circle
			(at -14.249908 -11.400028)
			(size 0.4572 0.4572)
			(layers "F.Cu" "F.Mask" "F.Paste")
			(net "GND")
		)
		(pad "N11" smd circle
			(at -13.299948 -11.400028)
			(size 0.4572 0.4572)
			(layers "F.Cu" "F.Mask" "F.Paste")
			(net "GND")
		)
		(pad "N12" smd circle
			(at -12.349988 -11.400028)
			(size 0.4572 0.4572)
			(layers "F.Cu" "F.Mask" "F.Paste")
			(net "GND")
		)
		(pad "N13" smd circle
			(at -11.400028 -11.400028)
			(size 0.4572 0.4572)
			(layers "F.Cu" "F.Mask" "F.Paste")
			(net "GND")
		)
		(pad "N14" smd circle
			(at -10.450068 -11.400028)
			(size 0.4572 0.4572)
			(layers "F.Cu" "F.Mask" "F.Paste")
			(net "GND")
		)
		(pad "N15" smd circle
			(at -9.500108 -11.400028)
			(size 0.4572 0.4572)
			(layers "F.Cu" "F.Mask" "F.Paste")
			(net "GND")
		)
		(pad "N16" smd circle
			(at -8.549894 -11.400028)
			(size 0.4572 0.4572)
			(layers "F.Cu" "F.Mask" "F.Paste")
			(net "GND")
		)
		(pad "N17" smd circle
			(at -7.599934 -11.400028)
			(size 0.4572 0.4572)
			(layers "F.Cu" "F.Mask" "F.Paste")
			(net "GND")
		)
		(pad "N18" smd circle
			(at -6.649974 -11.400028)
			(size 0.4572 0.4572)
			(layers "F.Cu" "F.Mask" "F.Paste")
			(net "GND")
		)
		(pad "N19" smd circle
			(at -5.700014 -11.400028)
			(size 0.4572 0.4572)
			(layers "F.Cu" "F.Mask" "F.Paste")
			(net "GND")
		)
		(pad "N20" smd circle
			(at -4.750054 -11.400028)
			(size 0.4572 0.4572)
			(layers "F.Cu" "F.Mask" "F.Paste")
			(net "GND")
		)
		(pad "N21" smd circle
			(at -3.800094 -11.400028)
			(size 0.4572 0.4572)
			(layers "F.Cu" "F.Mask" "F.Paste")
			(net "GND")
		)
		(pad "N22" smd circle
			(at -2.84988 -11.400028)
			(size 0.4572 0.4572)
			(layers "F.Cu" "F.Mask" "F.Paste")
			(net "GND")
		)
		(pad "N23" smd circle
			(at -1.89992 -11.400028)
			(size 0.4572 0.4572)
			(layers "F.Cu" "F.Mask" "F.Paste")
			(net "GND")
		)
		(pad "N24" smd circle
			(at -0.94996 -11.400028)
			(size 0.4572 0.4572)
			(layers "F.Cu" "F.Mask" "F.Paste")
			(net "GND")
		)
		(pad "N25" smd circle
			(at 0 -11.400028)
			(size 0.4572 0.4572)
			(layers "F.Cu" "F.Mask" "F.Paste")
			(net "GND")
		)
		(pad "N26" smd circle
			(at 0.94996 -11.400028)
			(size 0.4572 0.4572)
			(layers "F.Cu" "F.Mask" "F.Paste")
			(net "GND")
		)
		(pad "N27" smd circle
			(at 1.89992 -11.400028)
			(size 0.4572 0.4572)
			(layers "F.Cu" "F.Mask" "F.Paste")
			(net "GND")
		)
		(pad "N28" smd circle
			(at 2.84988 -11.400028)
			(size 0.4572 0.4572)
			(layers "F.Cu" "F.Mask" "F.Paste")
			(net "GND")
		)
		(pad "N29" smd circle
			(at 3.800094 -11.400028)
			(size 0.4572 0.4572)
			(layers "F.Cu" "F.Mask" "F.Paste")
			(net "GND")
		)
		(pad "N30" smd circle
			(at 4.750054 -11.400028)
			(size 0.4572 0.4572)
			(layers "F.Cu" "F.Mask" "F.Paste")
			(net "GND")
		)
		(pad "N31" smd circle
			(at 5.700014 -11.400028)
			(size 0.4572 0.4572)
			(layers "F.Cu" "F.Mask" "F.Paste")
			(net "GND")
		)
		(pad "N32" smd circle
			(at 6.649974 -11.400028)
			(size 0.4572 0.4572)
			(layers "F.Cu" "F.Mask" "F.Paste")
			(net "GND")
		)
		(pad "N33" smd circle
			(at 7.599934 -11.400028)
			(size 0.4572 0.4572)
			(layers "F.Cu" "F.Mask" "F.Paste")
			(net "GND")
		)
		(pad "N34" smd circle
			(at 8.549894 -11.400028)
			(size 0.4572 0.4572)
			(layers "F.Cu" "F.Mask" "F.Paste")
			(net "GND")
		)
		(pad "N35" smd circle
			(at 9.500108 -11.400028)
			(size 0.4572 0.4572)
			(layers "F.Cu" "F.Mask" "F.Paste")
			(net "GND")
		)
		(pad "N36" smd circle
			(at 10.450068 -11.400028)
			(size 0.4572 0.4572)
			(layers "F.Cu" "F.Mask" "F.Paste")
			(net "GND")
		)
		(pad "N37" smd circle
			(at 11.400028 -11.400028)
			(size 0.4572 0.4572)
			(layers "F.Cu" "F.Mask" "F.Paste")
			(net "GND")
		)
		(pad "N38" smd circle
			(at 12.349988 -11.400028)
			(size 0.4572 0.4572)
			(layers "F.Cu" "F.Mask" "F.Paste")
			(net "SMB_PEX3_SLAVE_SCL")
		)
		(pad "N39" smd circle
			(at 13.299948 -11.400028)
			(size 0.4572 0.4572)
			(layers "F.Cu" "F.Mask" "F.Paste")
			(net "Net_5460")
		)
		(pad "N40" smd circle
			(at 14.249908 -11.400028)
			(size 0.4572 0.4572)
			(layers "F.Cu" "F.Mask" "F.Paste")
			(net "GND")
		)
		(pad "N41" smd circle
			(at 15.200122 -11.400028)
			(size 0.4572 0.4572)
			(layers "F.Cu" "F.Mask" "F.Paste")
			(net "GND")
		)
		(pad "N42" smd circle
			(at 16.150082 -11.400028)
			(size 0.4572 0.4572)
			(layers "F.Cu" "F.Mask" "F.Paste")
			(net "GND")
		)
		(pad "N43" smd circle
			(at 17.100042 -11.400028)
			(size 0.4572 0.4572)
			(layers "F.Cu" "F.Mask" "F.Paste")
			(net "P5E_PEX3_STN4_TX_DP<67>")
		)
		(pad "N44" smd circle
			(at 18.050002 -11.400028)
			(size 0.4572 0.4572)
			(layers "F.Cu" "F.Mask" "F.Paste")
			(net "P5E_PEX3_STN4_TX_DN<67>")
		)
		(pad "N45" smd circle
			(at 18.999962 -11.400028)
			(size 0.4572 0.4572)
			(layers "F.Cu" "F.Mask" "F.Paste")
			(net "GND")
		)
		(pad "N46" smd circle
			(at 19.949922 -11.400028)
			(size 0.4572 0.4572)
			(layers "F.Cu" "F.Mask" "F.Paste")
			(net "P5E_PEX3_STN4_RX_DP<67>")
		)
		(pad "N47" smd circle
			(at 20.899882 -11.400028)
			(size 0.4572 0.4572)
			(layers "F.Cu" "F.Mask" "F.Paste")
			(net "P5E_PEX3_STN4_RX_DN<67>")
		)
		(pad "N48" smd circle
			(at 21.850096 -11.400028)
			(size 0.4572 0.4572)
			(layers "F.Cu" "F.Mask" "F.Paste")
			(net "GND")
		)
		(pad "N49" smd circle
			(at 22.800056 -11.400028)
			(size 0.4572 0.4572)
			(layers "F.Cu" "F.Mask" "F.Paste")
			(net "GND")
		)
		(pad "P1" smd circle
			(at -22.800056 -10.450068)
			(size 0.4572 0.4572)
			(layers "F.Cu" "F.Mask" "F.Paste")
			(net "P5E_PEX3_STN7_RX_DN<117>")
		)
		(pad "P2" smd circle
			(at -21.850096 -10.450068)
			(size 0.4572 0.4572)
			(layers "F.Cu" "F.Mask" "F.Paste")
			(net "P5E_PEX3_STN7_RX_DP<117>")
		)
		(pad "P3" smd circle
			(at -20.899882 -10.450068)
			(size 0.4572 0.4572)
			(layers "F.Cu" "F.Mask" "F.Paste")
			(net "GND")
		)
		(pad "P4" smd circle
			(at -19.949922 -10.450068)
			(size 0.4572 0.4572)
			(layers "F.Cu" "F.Mask" "F.Paste")
			(net "GND")
		)
		(pad "P5" smd circle
			(at -18.999962 -10.450068)
			(size 0.4572 0.4572)
			(layers "F.Cu" "F.Mask" "F.Paste")
			(net "GND")
		)
		(pad "P6" smd circle
			(at -18.050002 -10.450068)
			(size 0.4572 0.4572)
			(layers "F.Cu" "F.Mask" "F.Paste")
			(net "GND")
		)
		(pad "P7" smd circle
			(at -17.100042 -10.450068)
			(size 0.4572 0.4572)
			(layers "F.Cu" "F.Mask" "F.Paste")
			(net "GND")
		)
		(pad "P8" smd circle
			(at -16.150082 -10.450068)
			(size 0.4572 0.4572)
			(layers "F.Cu" "F.Mask" "F.Paste")
			(net "P5E_PEX3_STN7_TX_DN<117>")
		)
		(pad "P9" smd circle
			(at -15.200122 -10.450068)
			(size 0.4572 0.4572)
			(layers "F.Cu" "F.Mask" "F.Paste")
			(net "P5E_PEX3_STN7_TX_DP<117>")
		)
		(pad "P10" smd circle
			(at -14.249908 -10.450068)
			(size 0.4572 0.4572)
			(layers "F.Cu" "F.Mask" "F.Paste")
			(net "GND")
		)
		(pad "P11" smd circle
			(at -13.299948 -10.450068)
			(size 0.4572 0.4572)
			(layers "F.Cu" "F.Mask" "F.Paste")
			(net "GND")
		)
		(pad "P12" smd circle
			(at -12.349988 -10.450068)
			(size 0.4572 0.4572)
			(layers "F.Cu" "F.Mask" "F.Paste")
			(net "GND")
		)
		(pad "P13" smd circle
			(at -11.400028 -10.450068)
			(size 0.4572 0.4572)
			(layers "F.Cu" "F.Mask" "F.Paste")
			(net "GND")
		)
		(pad "P14" smd circle
			(at -10.450068 -10.450068)
			(size 0.4572 0.4572)
			(layers "F.Cu" "F.Mask" "F.Paste")
			(net "GND")
		)
		(pad "P15" smd circle
			(at -9.500108 -10.450068)
			(size 0.4572 0.4572)
			(layers "F.Cu" "F.Mask" "F.Paste")
			(net "GND")
		)
		(pad "P16" smd circle
			(at -8.549894 -10.450068)
			(size 0.4572 0.4572)
			(layers "F.Cu" "F.Mask" "F.Paste")
			(net "GND")
		)
		(pad "P17" smd circle
			(at -7.599934 -10.450068)
			(size 0.4572 0.4572)
			(layers "F.Cu" "F.Mask" "F.Paste")
			(net "GND")
		)
		(pad "P18" smd circle
			(at -6.649974 -10.450068)
			(size 0.4572 0.4572)
			(layers "F.Cu" "F.Mask" "F.Paste")
			(net "GND")
		)
		(pad "P19" smd circle
			(at -5.700014 -10.450068)
			(size 0.4572 0.4572)
			(layers "F.Cu" "F.Mask" "F.Paste")
			(net "GND")
		)
		(pad "P20" smd circle
			(at -4.750054 -10.450068)
			(size 0.4572 0.4572)
			(layers "F.Cu" "F.Mask" "F.Paste")
			(net "GND")
		)
		(pad "P21" smd circle
			(at -3.800094 -10.450068)
			(size 0.4572 0.4572)
			(layers "F.Cu" "F.Mask" "F.Paste")
			(net "GND")
		)
		(pad "P22" smd circle
			(at -2.84988 -10.450068)
			(size 0.4572 0.4572)
			(layers "F.Cu" "F.Mask" "F.Paste")
			(net "GND")
		)
		(pad "P23" smd circle
			(at -1.89992 -10.450068)
			(size 0.4572 0.4572)
			(layers "F.Cu" "F.Mask" "F.Paste")
			(net "GND")
		)
		(pad "P24" smd circle
			(at -0.94996 -10.450068)
			(size 0.4572 0.4572)
			(layers "F.Cu" "F.Mask" "F.Paste")
			(net "GND")
		)
		(pad "P25" smd circle
			(at 0 -10.450068)
			(size 0.4572 0.4572)
			(layers "F.Cu" "F.Mask" "F.Paste")
			(net "GND")
		)
		(pad "P26" smd circle
			(at 0.94996 -10.450068)
			(size 0.4572 0.4572)
			(layers "F.Cu" "F.Mask" "F.Paste")
			(net "GND")
		)
		(pad "P27" smd circle
			(at 1.89992 -10.450068)
			(size 0.4572 0.4572)
			(layers "F.Cu" "F.Mask" "F.Paste")
			(net "GND")
		)
		(pad "P28" smd circle
			(at 2.84988 -10.450068)
			(size 0.4572 0.4572)
			(layers "F.Cu" "F.Mask" "F.Paste")
			(net "GND")
		)
		(pad "P29" smd circle
			(at 3.800094 -10.450068)
			(size 0.4572 0.4572)
			(layers "F.Cu" "F.Mask" "F.Paste")
			(net "GND")
		)
		(pad "P30" smd circle
			(at 4.750054 -10.450068)
			(size 0.4572 0.4572)
			(layers "F.Cu" "F.Mask" "F.Paste")
			(net "GND")
		)
		(pad "P31" smd circle
			(at 5.700014 -10.450068)
			(size 0.4572 0.4572)
			(layers "F.Cu" "F.Mask" "F.Paste")
			(net "GND")
		)
		(pad "P32" smd circle
			(at 6.649974 -10.450068)
			(size 0.4572 0.4572)
			(layers "F.Cu" "F.Mask" "F.Paste")
			(net "GND")
		)
		(pad "P33" smd circle
			(at 7.599934 -10.450068)
			(size 0.4572 0.4572)
			(layers "F.Cu" "F.Mask" "F.Paste")
			(net "GND")
		)
		(pad "P34" smd circle
			(at 8.549894 -10.450068)
			(size 0.4572 0.4572)
			(layers "F.Cu" "F.Mask" "F.Paste")
			(net "GND")
		)
		(pad "P35" smd circle
			(at 9.500108 -10.450068)
			(size 0.4572 0.4572)
			(layers "F.Cu" "F.Mask" "F.Paste")
			(net "GND")
		)
		(pad "P36" smd circle
			(at 10.450068 -10.450068)
			(size 0.4572 0.4572)
			(layers "F.Cu" "F.Mask" "F.Paste")
			(net "Net_538")
		)
		(pad "P37" smd circle
			(at 11.400028 -10.450068)
			(size 0.4572 0.4572)
			(layers "F.Cu" "F.Mask" "F.Paste")
			(net "GND")
		)
		(pad "P38" smd circle
			(at 12.349988 -10.450068)
			(size 0.4572 0.4572)
			(layers "F.Cu" "F.Mask" "F.Paste")
			(net "RST_PEX3_S3_PERST_R_N")
		)
		(pad "P39" smd circle
			(at 13.299948 -10.450068)
			(size 0.4572 0.4572)
			(layers "F.Cu" "F.Mask" "F.Paste")
			(net "RST_PEX3_S1_PERST_R_N")
		)
		(pad "P40" smd circle
			(at 14.249908 -10.450068)
			(size 0.4572 0.4572)
			(layers "F.Cu" "F.Mask" "F.Paste")
			(net "GND")
		)
		(pad "P41" smd circle
			(at 15.200122 -10.450068)
			(size 0.4572 0.4572)
			(layers "F.Cu" "F.Mask" "F.Paste")
			(net "P5E_PEX3_STN4_TX_DP<66>")
		)
		(pad "P42" smd circle
			(at 16.150082 -10.450068)
			(size 0.4572 0.4572)
			(layers "F.Cu" "F.Mask" "F.Paste")
			(net "P5E_PEX3_STN4_TX_DN<66>")
		)
		(pad "P43" smd circle
			(at 17.100042 -10.450068)
			(size 0.4572 0.4572)
			(layers "F.Cu" "F.Mask" "F.Paste")
			(net "GND")
		)
		(pad "P44" smd circle
			(at 18.050002 -10.450068)
			(size 0.4572 0.4572)
			(layers "F.Cu" "F.Mask" "F.Paste")
			(net "GND")
		)
		(pad "P45" smd circle
			(at 18.999962 -10.450068)
			(size 0.4572 0.4572)
			(layers "F.Cu" "F.Mask" "F.Paste")
			(net "GND")
		)
		(pad "P46" smd circle
			(at 19.949922 -10.450068)
			(size 0.4572 0.4572)
			(layers "F.Cu" "F.Mask" "F.Paste")
			(net "GND")
		)
		(pad "P47" smd circle
			(at 20.899882 -10.450068)
			(size 0.4572 0.4572)
			(layers "F.Cu" "F.Mask" "F.Paste")
			(net "GND")
		)
		(pad "P48" smd circle
			(at 21.850096 -10.450068)
			(size 0.4572 0.4572)
			(layers "F.Cu" "F.Mask" "F.Paste")
			(net "P5E_PEX3_STN4_RX_DP<66>")
		)
		(pad "P49" smd circle
			(at 22.800056 -10.450068)
			(size 0.4572 0.4572)
			(layers "F.Cu" "F.Mask" "F.Paste")
			(net "P5E_PEX3_STN4_RX_DN<66>")
		)
		(pad "R1" smd circle
			(at -22.800056 -9.500108)
			(size 0.4572 0.4572)
			(layers "F.Cu" "F.Mask" "F.Paste")
			(net "GND")
		)
		(pad "R2" smd circle
			(at -21.850096 -9.500108)
			(size 0.4572 0.4572)
			(layers "F.Cu" "F.Mask" "F.Paste")
			(net "GND")
		)
		(pad "R3" smd circle
			(at -20.899882 -9.500108)
			(size 0.4572 0.4572)
			(layers "F.Cu" "F.Mask" "F.Paste")
			(net "P5E_PEX3_STN7_RX_DN<116>")
		)
		(pad "R4" smd circle
			(at -19.949922 -9.500108)
			(size 0.4572 0.4572)
			(layers "F.Cu" "F.Mask" "F.Paste")
			(net "P5E_PEX3_STN7_RX_DP<116>")
		)
		(pad "R5" smd circle
			(at -18.999962 -9.500108)
			(size 0.4572 0.4572)
			(layers "F.Cu" "F.Mask" "F.Paste")
			(net "GND")
		)
		(pad "R6" smd circle
			(at -18.050002 -9.500108)
			(size 0.4572 0.4572)
			(layers "F.Cu" "F.Mask" "F.Paste")
			(net "P5E_PEX3_STN7_TX_DN<116>")
		)
		(pad "R7" smd circle
			(at -17.100042 -9.500108)
			(size 0.4572 0.4572)
			(layers "F.Cu" "F.Mask" "F.Paste")
			(net "P5E_PEX3_STN7_TX_DP<116>")
		)
		(pad "R8" smd circle
			(at -16.150082 -9.500108)
			(size 0.4572 0.4572)
			(layers "F.Cu" "F.Mask" "F.Paste")
			(net "GND")
		)
		(pad "R9" smd circle
			(at -15.200122 -9.500108)
			(size 0.4572 0.4572)
			(layers "F.Cu" "F.Mask" "F.Paste")
			(net "GND")
		)
		(pad "R10" smd circle
			(at -14.249908 -9.500108)
			(size 0.4572 0.4572)
			(layers "F.Cu" "F.Mask" "F.Paste")
			(net "GND")
		)
		(pad "R11" smd circle
			(at -13.299948 -9.500108)
			(size 0.4572 0.4572)
			(layers "F.Cu" "F.Mask" "F.Paste")
			(net "GND")
		)
		(pad "R12" smd circle
			(at -12.349988 -9.500108)
			(size 0.4572 0.4572)
			(layers "F.Cu" "F.Mask" "F.Paste")
			(net "GND")
		)
		(pad "R13" smd circle
			(at -11.400028 -9.500108)
			(size 0.4572 0.4572)
			(layers "F.Cu" "F.Mask" "F.Paste")
			(net "GND")
		)
		(pad "R14" smd circle
			(at -10.450068 -9.500108)
			(size 0.4572 0.4572)
			(layers "F.Cu" "F.Mask" "F.Paste")
			(net "GND")
		)
		(pad "R15" smd circle
			(at -9.500108 -9.500108)
			(size 0.4572 0.4572)
			(layers "F.Cu" "F.Mask" "F.Paste")
			(net "GND")
		)
		(pad "R16" smd circle
			(at -8.549894 -9.500108)
			(size 0.4572 0.4572)
			(layers "F.Cu" "F.Mask" "F.Paste")
			(net "GND")
		)
		(pad "R17" smd circle
			(at -7.599934 -9.500108)
			(size 0.4572 0.4572)
			(layers "F.Cu" "F.Mask" "F.Paste")
			(net "GND")
		)
		(pad "R18" smd circle
			(at -6.649974 -9.500108)
			(size 0.4572 0.4572)
			(layers "F.Cu" "F.Mask" "F.Paste")
			(net "GND")
		)
		(pad "R19" smd circle
			(at -5.700014 -9.500108)
			(size 0.4572 0.4572)
			(layers "F.Cu" "F.Mask" "F.Paste")
			(net "GND")
		)
		(pad "R20" smd circle
			(at -4.750054 -9.500108)
			(size 0.4572 0.4572)
			(layers "F.Cu" "F.Mask" "F.Paste")
			(net "GND")
		)
		(pad "R21" smd circle
			(at -3.800094 -9.500108)
			(size 0.4572 0.4572)
			(layers "F.Cu" "F.Mask" "F.Paste")
			(net "GND")
		)
		(pad "R22" smd circle
			(at -2.84988 -9.500108)
			(size 0.4572 0.4572)
			(layers "F.Cu" "F.Mask" "F.Paste")
			(net "GND")
		)
		(pad "R23" smd circle
			(at -1.89992 -9.500108)
			(size 0.4572 0.4572)
			(layers "F.Cu" "F.Mask" "F.Paste")
			(net "GND")
		)
		(pad "R24" smd circle
			(at -0.94996 -9.500108)
			(size 0.4572 0.4572)
			(layers "F.Cu" "F.Mask" "F.Paste")
			(net "GND")
		)
		(pad "R25" smd circle
			(at 0 -9.500108)
			(size 0.4572 0.4572)
			(layers "F.Cu" "F.Mask" "F.Paste")
			(net "GND")
		)
		(pad "R26" smd circle
			(at 0.94996 -9.500108)
			(size 0.4572 0.4572)
			(layers "F.Cu" "F.Mask" "F.Paste")
			(net "GND")
		)
		(pad "R27" smd circle
			(at 1.89992 -9.500108)
			(size 0.4572 0.4572)
			(layers "F.Cu" "F.Mask" "F.Paste")
			(net "GND")
		)
		(pad "R28" smd circle
			(at 2.84988 -9.500108)
			(size 0.4572 0.4572)
			(layers "F.Cu" "F.Mask" "F.Paste")
			(net "GND")
		)
		(pad "R29" smd circle
			(at 3.800094 -9.500108)
			(size 0.4572 0.4572)
			(layers "F.Cu" "F.Mask" "F.Paste")
			(net "GND")
		)
		(pad "R30" smd circle
			(at 4.750054 -9.500108)
			(size 0.4572 0.4572)
			(layers "F.Cu" "F.Mask" "F.Paste")
			(net "GND")
		)
		(pad "R31" smd circle
			(at 5.700014 -9.500108)
			(size 0.4572 0.4572)
			(layers "F.Cu" "F.Mask" "F.Paste")
			(net "GND")
		)
		(pad "R32" smd circle
			(at 6.649974 -9.500108)
			(size 0.4572 0.4572)
			(layers "F.Cu" "F.Mask" "F.Paste")
			(net "GND")
		)
		(pad "R33" smd circle
			(at 7.599934 -9.500108)
			(size 0.4572 0.4572)
			(layers "F.Cu" "F.Mask" "F.Paste")
			(net "GND")
		)
		(pad "R34" smd circle
			(at 8.549894 -9.500108)
			(size 0.4572 0.4572)
			(layers "F.Cu" "F.Mask" "F.Paste")
			(net "GND")
		)
		(pad "R35" smd circle
			(at 9.500108 -9.500108)
			(size 0.4572 0.4572)
			(layers "F.Cu" "F.Mask" "F.Paste")
			(net "GND")
		)
		(pad "R36" smd circle
			(at 10.450068 -9.500108)
			(size 0.4572 0.4572)
			(layers "F.Cu" "F.Mask" "F.Paste")
			(net "Net_534")
		)
		(pad "R37" smd circle
			(at 11.400028 -9.500108)
			(size 0.4572 0.4572)
			(layers "F.Cu" "F.Mask" "F.Paste")
			(net "GND")
		)
		(pad "R38" smd circle
			(at 12.349988 -9.500108)
			(size 0.4572 0.4572)
			(layers "F.Cu" "F.Mask" "F.Paste")
			(net "Net_5408")
		)
		(pad "R39" smd circle
			(at 13.299948 -9.500108)
			(size 0.4572 0.4572)
			(layers "F.Cu" "F.Mask" "F.Paste")
			(net "Net_5402")
		)
		(pad "R40" smd circle
			(at 14.249908 -9.500108)
			(size 0.4572 0.4572)
			(layers "F.Cu" "F.Mask" "F.Paste")
			(net "GND")
		)
		(pad "R41" smd circle
			(at 15.200122 -9.500108)
			(size 0.4572 0.4572)
			(layers "F.Cu" "F.Mask" "F.Paste")
			(net "GND")
		)
		(pad "R42" smd circle
			(at 16.150082 -9.500108)
			(size 0.4572 0.4572)
			(layers "F.Cu" "F.Mask" "F.Paste")
			(net "GND")
		)
		(pad "R43" smd circle
			(at 17.100042 -9.500108)
			(size 0.4572 0.4572)
			(layers "F.Cu" "F.Mask" "F.Paste")
			(net "P5E_PEX3_STN4_TX_DP<65>")
		)
		(pad "R44" smd circle
			(at 18.050002 -9.500108)
			(size 0.4572 0.4572)
			(layers "F.Cu" "F.Mask" "F.Paste")
			(net "P5E_PEX3_STN4_TX_DN<65>")
		)
		(pad "R45" smd circle
			(at 18.999962 -9.500108)
			(size 0.4572 0.4572)
			(layers "F.Cu" "F.Mask" "F.Paste")
			(net "GND")
		)
		(pad "R46" smd circle
			(at 19.949922 -9.500108)
			(size 0.4572 0.4572)
			(layers "F.Cu" "F.Mask" "F.Paste")
			(net "P5E_PEX3_STN4_RX_DP<65>")
		)
		(pad "R47" smd circle
			(at 20.899882 -9.500108)
			(size 0.4572 0.4572)
			(layers "F.Cu" "F.Mask" "F.Paste")
			(net "P5E_PEX3_STN4_RX_DN<65>")
		)
		(pad "R48" smd circle
			(at 21.850096 -9.500108)
			(size 0.4572 0.4572)
			(layers "F.Cu" "F.Mask" "F.Paste")
			(net "GND")
		)
		(pad "R49" smd circle
			(at 22.800056 -9.500108)
			(size 0.4572 0.4572)
			(layers "F.Cu" "F.Mask" "F.Paste")
			(net "GND")
		)
		(pad "T1" smd circle
			(at -22.800056 -8.549894)
			(size 0.4572 0.4572)
			(layers "F.Cu" "F.Mask" "F.Paste")
			(net "P5E_PEX3_STN7_RX_DN<115>")
		)
		(pad "T2" smd circle
			(at -21.850096 -8.549894)
			(size 0.4572 0.4572)
			(layers "F.Cu" "F.Mask" "F.Paste")
			(net "P5E_PEX3_STN7_RX_DP<115>")
		)
		(pad "T3" smd circle
			(at -20.899882 -8.549894)
			(size 0.4572 0.4572)
			(layers "F.Cu" "F.Mask" "F.Paste")
			(net "GND")
		)
		(pad "T4" smd circle
			(at -19.949922 -8.549894)
			(size 0.4572 0.4572)
			(layers "F.Cu" "F.Mask" "F.Paste")
			(net "GND")
		)
		(pad "T5" smd circle
			(at -18.999962 -8.549894)
			(size 0.4572 0.4572)
			(layers "F.Cu" "F.Mask" "F.Paste")
			(net "GND")
		)
		(pad "T6" smd circle
			(at -18.050002 -8.549894)
			(size 0.4572 0.4572)
			(layers "F.Cu" "F.Mask" "F.Paste")
			(net "GND")
		)
		(pad "T7" smd circle
			(at -17.100042 -8.549894)
			(size 0.4572 0.4572)
			(layers "F.Cu" "F.Mask" "F.Paste")
			(net "GND")
		)
		(pad "T8" smd circle
			(at -16.150082 -8.549894)
			(size 0.4572 0.4572)
			(layers "F.Cu" "F.Mask" "F.Paste")
			(net "P5E_PEX3_STN7_TX_DN<115>")
		)
		(pad "T9" smd circle
			(at -15.200122 -8.549894)
			(size 0.4572 0.4572)
			(layers "F.Cu" "F.Mask" "F.Paste")
			(net "P5E_PEX3_STN7_TX_DP<115>")
		)
		(pad "T10" smd circle
			(at -14.249908 -8.549894)
			(size 0.4572 0.4572)
			(layers "F.Cu" "F.Mask" "F.Paste")
			(net "GND")
		)
		(pad "T11" smd circle
			(at -13.299948 -8.549894)
			(size 0.4572 0.4572)
			(layers "F.Cu" "F.Mask" "F.Paste")
			(net "GND")
		)
		(pad "T12" smd circle
			(at -12.349988 -8.549894)
			(size 0.4572 0.4572)
			(layers "F.Cu" "F.Mask" "F.Paste")
			(net "GND")
		)
		(pad "T13" smd circle
			(at -11.400028 -8.549894)
			(size 0.4572 0.4572)
			(layers "F.Cu" "F.Mask" "F.Paste")
			(net "GND")
		)
		(pad "T14" smd circle
			(at -10.450068 -8.549894)
			(size 0.4572 0.4572)
			(layers "F.Cu" "F.Mask" "F.Paste")
			(net "Net_542")
		)
		(pad "T15" smd circle
			(at -9.500108 -8.549894)
			(size 0.4572 0.4572)
			(layers "F.Cu" "F.Mask" "F.Paste")
			(net "GND")
		)
		(pad "T16" smd circle
			(at -8.549894 -8.549894)
			(size 0.4572 0.4572)
			(layers "F.Cu" "F.Mask" "F.Paste")
			(net "P1V25_SERDES_VDDPLL_PEX3")
		)
		(pad "T17" smd circle
			(at -7.599934 -8.549894)
			(size 0.4572 0.4572)
			(layers "F.Cu" "F.Mask" "F.Paste")
			(net "P1V25_SERDES_VDDPLL_PEX3")
		)
		(pad "T18" smd circle
			(at -6.649974 -8.549894)
			(size 0.4572 0.4572)
			(layers "F.Cu" "F.Mask" "F.Paste")
			(net "P1V25_SERDES_VDDPLL_PEX3")
		)
		(pad "T19" smd circle
			(at -5.700014 -8.549894)
			(size 0.4572 0.4572)
			(layers "F.Cu" "F.Mask" "F.Paste")
			(net "P1V25_SERDES_VDDPLL_PEX3")
		)
		(pad "T20" smd circle
			(at -4.750054 -8.549894)
			(size 0.4572 0.4572)
			(layers "F.Cu" "F.Mask" "F.Paste")
			(net "P1V25_SERDES_VDDPLL_PEX3")
		)
		(pad "T21" smd circle
			(at -3.800094 -8.549894)
			(size 0.4572 0.4572)
			(layers "F.Cu" "F.Mask" "F.Paste")
			(net "P1V25_SERDES_VDDPLL_PEX3")
		)
		(pad "T22" smd circle
			(at -2.84988 -8.549894)
			(size 0.4572 0.4572)
			(layers "F.Cu" "F.Mask" "F.Paste")
			(net "P1V25_SERDES_VDDPLL_PEX3")
		)
		(pad "T23" smd circle
			(at -1.89992 -8.549894)
			(size 0.4572 0.4572)
			(layers "F.Cu" "F.Mask" "F.Paste")
			(net "P1V25_SERDES_VDDPLL_PEX3")
		)
		(pad "T24" smd circle
			(at -0.94996 -8.549894)
			(size 0.4572 0.4572)
			(layers "F.Cu" "F.Mask" "F.Paste")
			(net "P1V25_SERDES_VDDPLL_PEX3")
		)
		(pad "T25" smd circle
			(at 0 -8.549894)
			(size 0.4572 0.4572)
			(layers "F.Cu" "F.Mask" "F.Paste")
			(net "P1V25_SERDES_VDDPLL_PEX3")
		)
		(pad "T26" smd circle
			(at 0.94996 -8.549894)
			(size 0.4572 0.4572)
			(layers "F.Cu" "F.Mask" "F.Paste")
			(net "P1V25_SERDES_VDDPLL_PEX3")
		)
		(pad "T27" smd circle
			(at 1.89992 -8.549894)
			(size 0.4572 0.4572)
			(layers "F.Cu" "F.Mask" "F.Paste")
			(net "P1V25_SERDES_VDDPLL_PEX3")
		)
		(pad "T28" smd circle
			(at 2.84988 -8.549894)
			(size 0.4572 0.4572)
			(layers "F.Cu" "F.Mask" "F.Paste")
			(net "P1V25_SERDES_VDDPLL_PEX3")
		)
		(pad "T29" smd circle
			(at 3.800094 -8.549894)
			(size 0.4572 0.4572)
			(layers "F.Cu" "F.Mask" "F.Paste")
			(net "P1V25_SERDES_VDDPLL_PEX3")
		)
		(pad "T30" smd circle
			(at 4.750054 -8.549894)
			(size 0.4572 0.4572)
			(layers "F.Cu" "F.Mask" "F.Paste")
			(net "P1V25_SERDES_VDDPLL_PEX3")
		)
		(pad "T31" smd circle
			(at 5.700014 -8.549894)
			(size 0.4572 0.4572)
			(layers "F.Cu" "F.Mask" "F.Paste")
			(net "P1V25_SERDES_VDDPLL_PEX3")
		)
		(pad "T32" smd circle
			(at 6.649974 -8.549894)
			(size 0.4572 0.4572)
			(layers "F.Cu" "F.Mask" "F.Paste")
			(net "P1V25_SERDES_VDDPLL_PEX3")
		)
		(pad "T33" smd circle
			(at 7.599934 -8.549894)
			(size 0.4572 0.4572)
			(layers "F.Cu" "F.Mask" "F.Paste")
			(net "P1V25_SERDES_VDDPLL_PEX3")
		)
		(pad "T34" smd circle
			(at 8.549894 -8.549894)
			(size 0.4572 0.4572)
			(layers "F.Cu" "F.Mask" "F.Paste")
			(net "GND")
		)
		(pad "T35" smd circle
			(at 9.500108 -8.549894)
			(size 0.4572 0.4572)
			(layers "F.Cu" "F.Mask" "F.Paste")
			(net "P1V8_VDDA_PEX3")
		)
		(pad "T36" smd circle
			(at 10.450068 -8.549894)
			(size 0.4572 0.4572)
			(layers "F.Cu" "F.Mask" "F.Paste")
			(net "Net_529")
		)
		(pad "T37" smd circle
			(at 11.400028 -8.549894)
			(size 0.4572 0.4572)
			(layers "F.Cu" "F.Mask" "F.Paste")
			(net "GND")
		)
		(pad "T38" smd circle
			(at 12.349988 -8.549894)
			(size 0.4572 0.4572)
			(layers "F.Cu" "F.Mask" "F.Paste")
			(net "RST_PEX3_S0_PERST_R_N")
		)
		(pad "T39" smd circle
			(at 13.299948 -8.549894)
			(size 0.4572 0.4572)
			(layers "F.Cu" "F.Mask" "F.Paste")
			(net "Net_389")
		)
		(pad "T40" smd circle
			(at 14.249908 -8.549894)
			(size 0.4572 0.4572)
			(layers "F.Cu" "F.Mask" "F.Paste")
			(net "GND")
		)
		(pad "T41" smd circle
			(at 15.200122 -8.549894)
			(size 0.4572 0.4572)
			(layers "F.Cu" "F.Mask" "F.Paste")
			(net "P5E_PEX3_STN4_TX_DP<64>")
		)
		(pad "T42" smd circle
			(at 16.150082 -8.549894)
			(size 0.4572 0.4572)
			(layers "F.Cu" "F.Mask" "F.Paste")
			(net "P5E_PEX3_STN4_TX_DN<64>")
		)
		(pad "T43" smd circle
			(at 17.100042 -8.549894)
			(size 0.4572 0.4572)
			(layers "F.Cu" "F.Mask" "F.Paste")
			(net "GND")
		)
		(pad "T44" smd circle
			(at 18.050002 -8.549894)
			(size 0.4572 0.4572)
			(layers "F.Cu" "F.Mask" "F.Paste")
			(net "GND")
		)
		(pad "T45" smd circle
			(at 18.999962 -8.549894)
			(size 0.4572 0.4572)
			(layers "F.Cu" "F.Mask" "F.Paste")
			(net "GND")
		)
		(pad "T46" smd circle
			(at 19.949922 -8.549894)
			(size 0.4572 0.4572)
			(layers "F.Cu" "F.Mask" "F.Paste")
			(net "GND")
		)
		(pad "T47" smd circle
			(at 20.899882 -8.549894)
			(size 0.4572 0.4572)
			(layers "F.Cu" "F.Mask" "F.Paste")
			(net "GND")
		)
		(pad "T48" smd circle
			(at 21.850096 -8.549894)
			(size 0.4572 0.4572)
			(layers "F.Cu" "F.Mask" "F.Paste")
			(net "P5E_PEX3_STN4_RX_DP<64>")
		)
		(pad "T49" smd circle
			(at 22.800056 -8.549894)
			(size 0.4572 0.4572)
			(layers "F.Cu" "F.Mask" "F.Paste")
			(net "P5E_PEX3_STN4_RX_DN<64>")
		)
		(pad "U1" smd circle
			(at -22.800056 -7.599934)
			(size 0.4572 0.4572)
			(layers "F.Cu" "F.Mask" "F.Paste")
			(net "GND")
		)
		(pad "U2" smd circle
			(at -21.850096 -7.599934)
			(size 0.4572 0.4572)
			(layers "F.Cu" "F.Mask" "F.Paste")
			(net "GND")
		)
		(pad "U3" smd circle
			(at -20.899882 -7.599934)
			(size 0.4572 0.4572)
			(layers "F.Cu" "F.Mask" "F.Paste")
			(net "P5E_PEX3_STN7_RX_DN<114>")
		)
		(pad "U4" smd circle
			(at -19.949922 -7.599934)
			(size 0.4572 0.4572)
			(layers "F.Cu" "F.Mask" "F.Paste")
			(net "P5E_PEX3_STN7_RX_DP<114>")
		)
		(pad "U5" smd circle
			(at -18.999962 -7.599934)
			(size 0.4572 0.4572)
			(layers "F.Cu" "F.Mask" "F.Paste")
			(net "GND")
		)
		(pad "U6" smd circle
			(at -18.050002 -7.599934)
			(size 0.4572 0.4572)
			(layers "F.Cu" "F.Mask" "F.Paste")
			(net "P5E_PEX3_STN7_TX_DN<114>")
		)
		(pad "U7" smd circle
			(at -17.100042 -7.599934)
			(size 0.4572 0.4572)
			(layers "F.Cu" "F.Mask" "F.Paste")
			(net "P5E_PEX3_STN7_TX_DP<114>")
		)
		(pad "U8" smd circle
			(at -16.150082 -7.599934)
			(size 0.4572 0.4572)
			(layers "F.Cu" "F.Mask" "F.Paste")
			(net "GND")
		)
		(pad "U9" smd circle
			(at -15.200122 -7.599934)
			(size 0.4572 0.4572)
			(layers "F.Cu" "F.Mask" "F.Paste")
			(net "GND")
		)
		(pad "U10" smd circle
			(at -14.249908 -7.599934)
			(size 0.4572 0.4572)
			(layers "F.Cu" "F.Mask" "F.Paste")
			(net "GND")
		)
		(pad "U11" smd circle
			(at -13.299948 -7.599934)
			(size 0.4572 0.4572)
			(layers "F.Cu" "F.Mask" "F.Paste")
			(net "GND")
		)
		(pad "U12" smd circle
			(at -12.349988 -7.599934)
			(size 0.4572 0.4572)
			(layers "F.Cu" "F.Mask" "F.Paste")
			(net "GND")
		)
		(pad "U13" smd circle
			(at -11.400028 -7.599934)
			(size 0.4572 0.4572)
			(layers "F.Cu" "F.Mask" "F.Paste")
			(net "GND")
		)
		(pad "U14" smd circle
			(at -10.450068 -7.599934)
			(size 0.4572 0.4572)
			(layers "F.Cu" "F.Mask" "F.Paste")
			(net "Net_528")
		)
		(pad "U15" smd circle
			(at -9.500108 -7.599934)
			(size 0.4572 0.4572)
			(layers "F.Cu" "F.Mask" "F.Paste")
			(net "GND")
		)
		(pad "U16" smd circle
			(at -8.549894 -7.599934)
			(size 0.4572 0.4572)
			(layers "F.Cu" "F.Mask" "F.Paste")
			(net "GND")
		)
		(pad "U17" smd circle
			(at -7.599934 -7.599934)
			(size 0.4572 0.4572)
			(layers "F.Cu" "F.Mask" "F.Paste")
			(net "GND")
		)
		(pad "U18" smd circle
			(at -6.649974 -7.599934)
			(size 0.4572 0.4572)
			(layers "F.Cu" "F.Mask" "F.Paste")
			(net "GND")
		)
		(pad "U19" smd circle
			(at -5.700014 -7.599934)
			(size 0.4572 0.4572)
			(layers "F.Cu" "F.Mask" "F.Paste")
			(net "GND")
		)
		(pad "U20" smd circle
			(at -4.750054 -7.599934)
			(size 0.4572 0.4572)
			(layers "F.Cu" "F.Mask" "F.Paste")
			(net "GND")
		)
		(pad "U21" smd circle
			(at -3.800094 -7.599934)
			(size 0.4572 0.4572)
			(layers "F.Cu" "F.Mask" "F.Paste")
			(net "GND")
		)
		(pad "U22" smd circle
			(at -2.84988 -7.599934)
			(size 0.4572 0.4572)
			(layers "F.Cu" "F.Mask" "F.Paste")
			(net "GND")
		)
		(pad "U23" smd circle
			(at -1.89992 -7.599934)
			(size 0.4572 0.4572)
			(layers "F.Cu" "F.Mask" "F.Paste")
			(net "GND")
		)
		(pad "U24" smd circle
			(at -0.94996 -7.599934)
			(size 0.4572 0.4572)
			(layers "F.Cu" "F.Mask" "F.Paste")
			(net "GND")
		)
		(pad "U25" smd circle
			(at 0 -7.599934)
			(size 0.4572 0.4572)
			(layers "F.Cu" "F.Mask" "F.Paste")
			(net "GND")
		)
		(pad "U26" smd circle
			(at 0.94996 -7.599934)
			(size 0.4572 0.4572)
			(layers "F.Cu" "F.Mask" "F.Paste")
			(net "GND")
		)
		(pad "U27" smd circle
			(at 1.89992 -7.599934)
			(size 0.4572 0.4572)
			(layers "F.Cu" "F.Mask" "F.Paste")
			(net "GND")
		)
		(pad "U28" smd circle
			(at 2.84988 -7.599934)
			(size 0.4572 0.4572)
			(layers "F.Cu" "F.Mask" "F.Paste")
			(net "GND")
		)
		(pad "U29" smd circle
			(at 3.800094 -7.599934)
			(size 0.4572 0.4572)
			(layers "F.Cu" "F.Mask" "F.Paste")
			(net "GND")
		)
		(pad "U30" smd circle
			(at 4.750054 -7.599934)
			(size 0.4572 0.4572)
			(layers "F.Cu" "F.Mask" "F.Paste")
			(net "GND")
		)
		(pad "U31" smd circle
			(at 5.700014 -7.599934)
			(size 0.4572 0.4572)
			(layers "F.Cu" "F.Mask" "F.Paste")
			(net "GND")
		)
		(pad "U32" smd circle
			(at 6.649974 -7.599934)
			(size 0.4572 0.4572)
			(layers "F.Cu" "F.Mask" "F.Paste")
			(net "GND")
		)
		(pad "U33" smd circle
			(at 7.599934 -7.599934)
			(size 0.4572 0.4572)
			(layers "F.Cu" "F.Mask" "F.Paste")
			(net "GND")
		)
		(pad "U34" smd circle
			(at 8.549894 -7.599934)
			(size 0.4572 0.4572)
			(layers "F.Cu" "F.Mask" "F.Paste")
			(net "GND")
		)
		(pad "U35" smd circle
			(at 9.500108 -7.599934)
			(size 0.4572 0.4572)
			(layers "F.Cu" "F.Mask" "F.Paste")
			(net "GND")
		)
		(pad "U36" smd circle
			(at 10.450068 -7.599934)
			(size 0.4572 0.4572)
			(layers "F.Cu" "F.Mask" "F.Paste")
			(net "Net_533")
		)
		(pad "U37" smd circle
			(at 11.400028 -7.599934)
			(size 0.4572 0.4572)
			(layers "F.Cu" "F.Mask" "F.Paste")
			(net "GND")
		)
		(pad "U38" smd circle
			(at 12.349988 -7.599934)
			(size 0.4572 0.4572)
			(layers "F.Cu" "F.Mask" "F.Paste")
			(net "Net_5411")
		)
		(pad "U39" smd circle
			(at 13.299948 -7.599934)
			(size 0.4572 0.4572)
			(layers "F.Cu" "F.Mask" "F.Paste")
			(net "Net_5405")
		)
		(pad "U40" smd circle
			(at 14.249908 -7.599934)
			(size 0.4572 0.4572)
			(layers "F.Cu" "F.Mask" "F.Paste")
			(net "GND")
		)
		(pad "U41" smd circle
			(at 15.200122 -7.599934)
			(size 0.4572 0.4572)
			(layers "F.Cu" "F.Mask" "F.Paste")
			(net "GND")
		)
		(pad "U42" smd circle
			(at 16.150082 -7.599934)
			(size 0.4572 0.4572)
			(layers "F.Cu" "F.Mask" "F.Paste")
			(net "GND")
		)
		(pad "U43" smd circle
			(at 17.100042 -7.599934)
			(size 0.4572 0.4572)
			(layers "F.Cu" "F.Mask" "F.Paste")
			(net "Net_1549")
		)
		(pad "U44" smd circle
			(at 18.050002 -7.599934)
			(size 0.4572 0.4572)
			(layers "F.Cu" "F.Mask" "F.Paste")
			(net "Net_1522")
		)
		(pad "U45" smd circle
			(at 18.999962 -7.599934)
			(size 0.4572 0.4572)
			(layers "F.Cu" "F.Mask" "F.Paste")
			(net "GND")
		)
		(pad "U46" smd circle
			(at 19.949922 -7.599934)
			(size 0.4572 0.4572)
			(layers "F.Cu" "F.Mask" "F.Paste")
			(net "Net_1486")
		)
		(pad "U47" smd circle
			(at 20.899882 -7.599934)
			(size 0.4572 0.4572)
			(layers "F.Cu" "F.Mask" "F.Paste")
			(net "Net_1501")
		)
		(pad "U48" smd circle
			(at 21.850096 -7.599934)
			(size 0.4572 0.4572)
			(layers "F.Cu" "F.Mask" "F.Paste")
			(net "GND")
		)
		(pad "U49" smd circle
			(at 22.800056 -7.599934)
			(size 0.4572 0.4572)
			(layers "F.Cu" "F.Mask" "F.Paste")
			(net "GND")
		)
		(pad "V1" smd circle
			(at -22.800056 -6.649974)
			(size 0.4572 0.4572)
			(layers "F.Cu" "F.Mask" "F.Paste")
			(net "P5E_PEX3_STN7_RX_DN<113>")
		)
		(pad "V2" smd circle
			(at -21.850096 -6.649974)
			(size 0.4572 0.4572)
			(layers "F.Cu" "F.Mask" "F.Paste")
			(net "P5E_PEX3_STN7_RX_DP<113>")
		)
		(pad "V3" smd circle
			(at -20.899882 -6.649974)
			(size 0.4572 0.4572)
			(layers "F.Cu" "F.Mask" "F.Paste")
			(net "GND")
		)
		(pad "V4" smd circle
			(at -19.949922 -6.649974)
			(size 0.4572 0.4572)
			(layers "F.Cu" "F.Mask" "F.Paste")
			(net "GND")
		)
		(pad "V5" smd circle
			(at -18.999962 -6.649974)
			(size 0.4572 0.4572)
			(layers "F.Cu" "F.Mask" "F.Paste")
			(net "GND")
		)
		(pad "V6" smd circle
			(at -18.050002 -6.649974)
			(size 0.4572 0.4572)
			(layers "F.Cu" "F.Mask" "F.Paste")
			(net "GND")
		)
		(pad "V7" smd circle
			(at -17.100042 -6.649974)
			(size 0.4572 0.4572)
			(layers "F.Cu" "F.Mask" "F.Paste")
			(net "GND")
		)
		(pad "V8" smd circle
			(at -16.150082 -6.649974)
			(size 0.4572 0.4572)
			(layers "F.Cu" "F.Mask" "F.Paste")
			(net "P5E_PEX3_STN7_TX_DN<113>")
		)
		(pad "V9" smd circle
			(at -15.200122 -6.649974)
			(size 0.4572 0.4572)
			(layers "F.Cu" "F.Mask" "F.Paste")
			(net "P5E_PEX3_STN7_TX_DP<113>")
		)
		(pad "V10" smd circle
			(at -14.249908 -6.649974)
			(size 0.4572 0.4572)
			(layers "F.Cu" "F.Mask" "F.Paste")
			(net "GND")
		)
		(pad "V11" smd circle
			(at -13.299948 -6.649974)
			(size 0.4572 0.4572)
			(layers "F.Cu" "F.Mask" "F.Paste")
			(net "GND")
		)
		(pad "V12" smd circle
			(at -12.349988 -6.649974)
			(size 0.4572 0.4572)
			(layers "F.Cu" "F.Mask" "F.Paste")
			(net "GND")
		)
		(pad "V13" smd circle
			(at -11.400028 -6.649974)
			(size 0.4572 0.4572)
			(layers "F.Cu" "F.Mask" "F.Paste")
			(net "GND")
		)
		(pad "V14" smd circle
			(at -10.450068 -6.649974)
			(size 0.4572 0.4572)
			(layers "F.Cu" "F.Mask" "F.Paste")
			(net "P1V8_VDDA_PEX3")
		)
		(pad "V15" smd circle
			(at -9.500108 -6.649974)
			(size 0.4572 0.4572)
			(layers "F.Cu" "F.Mask" "F.Paste")
			(net "GND")
		)
		(pad "V16" smd circle
			(at -8.549894 -6.649974)
			(size 0.4572 0.4572)
			(layers "F.Cu" "F.Mask" "F.Paste")
			(net "P1V25_PEX3")
		)
		(pad "V17" smd circle
			(at -7.599934 -6.649974)
			(size 0.4572 0.4572)
			(layers "F.Cu" "F.Mask" "F.Paste")
			(net "P1V25_PEX3")
		)
		(pad "V18" smd circle
			(at -6.649974 -6.649974)
			(size 0.4572 0.4572)
			(layers "F.Cu" "F.Mask" "F.Paste")
			(net "P1V25_PEX3")
		)
		(pad "V19" smd circle
			(at -5.700014 -6.649974)
			(size 0.4572 0.4572)
			(layers "F.Cu" "F.Mask" "F.Paste")
			(net "P1V25_PEX3")
		)
		(pad "V20" smd circle
			(at -4.750054 -6.649974)
			(size 0.4572 0.4572)
			(layers "F.Cu" "F.Mask" "F.Paste")
			(net "P1V25_PEX3")
		)
		(pad "V21" smd circle
			(at -3.800094 -6.649974)
			(size 0.4572 0.4572)
			(layers "F.Cu" "F.Mask" "F.Paste")
			(net "P1V25_PEX3")
		)
		(pad "V22" smd circle
			(at -2.84988 -6.649974)
			(size 0.4572 0.4572)
			(layers "F.Cu" "F.Mask" "F.Paste")
			(net "P1V25_PEX3")
		)
		(pad "V23" smd circle
			(at -1.89992 -6.649974)
			(size 0.4572 0.4572)
			(layers "F.Cu" "F.Mask" "F.Paste")
			(net "P1V25_PEX3")
		)
		(pad "V24" smd circle
			(at -0.94996 -6.649974)
			(size 0.4572 0.4572)
			(layers "F.Cu" "F.Mask" "F.Paste")
			(net "P1V25_PEX3")
		)
		(pad "V25" smd circle
			(at 0 -6.649974)
			(size 0.4572 0.4572)
			(layers "F.Cu" "F.Mask" "F.Paste")
			(net "P1V25_PEX3")
		)
		(pad "V26" smd circle
			(at 0.94996 -6.649974)
			(size 0.4572 0.4572)
			(layers "F.Cu" "F.Mask" "F.Paste")
			(net "P1V25_PEX3")
		)
		(pad "V27" smd circle
			(at 1.89992 -6.649974)
			(size 0.4572 0.4572)
			(layers "F.Cu" "F.Mask" "F.Paste")
			(net "P1V25_PEX3")
		)
		(pad "V28" smd circle
			(at 2.84988 -6.649974)
			(size 0.4572 0.4572)
			(layers "F.Cu" "F.Mask" "F.Paste")
			(net "P1V25_PEX3")
		)
		(pad "V29" smd circle
			(at 3.800094 -6.649974)
			(size 0.4572 0.4572)
			(layers "F.Cu" "F.Mask" "F.Paste")
			(net "P1V25_PEX3")
		)
		(pad "V30" smd circle
			(at 4.750054 -6.649974)
			(size 0.4572 0.4572)
			(layers "F.Cu" "F.Mask" "F.Paste")
			(net "P1V25_PEX3")
		)
		(pad "V31" smd circle
			(at 5.700014 -6.649974)
			(size 0.4572 0.4572)
			(layers "F.Cu" "F.Mask" "F.Paste")
			(net "P1V25_PEX3")
		)
		(pad "V32" smd circle
			(at 6.649974 -6.649974)
			(size 0.4572 0.4572)
			(layers "F.Cu" "F.Mask" "F.Paste")
			(net "P1V25_PEX3")
		)
		(pad "V33" smd circle
			(at 7.599934 -6.649974)
			(size 0.4572 0.4572)
			(layers "F.Cu" "F.Mask" "F.Paste")
			(net "P1V25_PEX3")
		)
		(pad "V34" smd circle
			(at 8.549894 -6.649974)
			(size 0.4572 0.4572)
			(layers "F.Cu" "F.Mask" "F.Paste")
			(net "GND")
		)
		(pad "V35" smd circle
			(at 9.500108 -6.649974)
			(size 0.4572 0.4572)
			(layers "F.Cu" "F.Mask" "F.Paste")
			(net "P1V8_PEX")
		)
		(pad "V36" smd circle
			(at 10.450068 -6.649974)
			(size 0.4572 0.4572)
			(layers "F.Cu" "F.Mask" "F.Paste")
			(net "GND")
		)
		(pad "V37" smd circle
			(at 11.400028 -6.649974)
			(size 0.4572 0.4572)
			(layers "F.Cu" "F.Mask" "F.Paste")
			(net "GND")
		)
		(pad "V38" smd circle
			(at 12.349988 -6.649974)
			(size 0.4572 0.4572)
			(layers "F.Cu" "F.Mask" "F.Paste")
			(net "GND")
		)
		(pad "V39" smd circle
			(at 13.299948 -6.649974)
			(size 0.4572 0.4572)
			(layers "F.Cu" "F.Mask" "F.Paste")
			(net "VSENSE_P0V8_PEX3_SKT_VSEN")
		)
		(pad "V40" smd circle
			(at 14.249908 -6.649974)
			(size 0.4572 0.4572)
			(layers "F.Cu" "F.Mask" "F.Paste")
			(net "GND")
		)
		(pad "V41" smd circle
			(at 15.200122 -6.649974)
			(size 0.4572 0.4572)
			(layers "F.Cu" "F.Mask" "F.Paste")
			(net "Net_1533")
		)
		(pad "V42" smd circle
			(at 16.150082 -6.649974)
			(size 0.4572 0.4572)
			(layers "F.Cu" "F.Mask" "F.Paste")
			(net "Net_1571")
		)
		(pad "V43" smd circle
			(at 17.100042 -6.649974)
			(size 0.4572 0.4572)
			(layers "F.Cu" "F.Mask" "F.Paste")
			(net "GND")
		)
		(pad "V44" smd circle
			(at 18.050002 -6.649974)
			(size 0.4572 0.4572)
			(layers "F.Cu" "F.Mask" "F.Paste")
			(net "GND")
		)
		(pad "V45" smd circle
			(at 18.999962 -6.649974)
			(size 0.4572 0.4572)
			(layers "F.Cu" "F.Mask" "F.Paste")
			(net "GND")
		)
		(pad "V46" smd circle
			(at 19.949922 -6.649974)
			(size 0.4572 0.4572)
			(layers "F.Cu" "F.Mask" "F.Paste")
			(net "GND")
		)
		(pad "V47" smd circle
			(at 20.899882 -6.649974)
			(size 0.4572 0.4572)
			(layers "F.Cu" "F.Mask" "F.Paste")
			(net "GND")
		)
		(pad "V48" smd circle
			(at 21.850096 -6.649974)
			(size 0.4572 0.4572)
			(layers "F.Cu" "F.Mask" "F.Paste")
			(net "Net_1483")
		)
		(pad "V49" smd circle
			(at 22.800056 -6.649974)
			(size 0.4572 0.4572)
			(layers "F.Cu" "F.Mask" "F.Paste")
			(net "Net_1467")
		)
		(pad "W1" smd circle
			(at -22.800056 -5.700014)
			(size 0.4572 0.4572)
			(layers "F.Cu" "F.Mask" "F.Paste")
			(net "GND")
		)
		(pad "W2" smd circle
			(at -21.850096 -5.700014)
			(size 0.4572 0.4572)
			(layers "F.Cu" "F.Mask" "F.Paste")
			(net "GND")
		)
		(pad "W3" smd circle
			(at -20.899882 -5.700014)
			(size 0.4572 0.4572)
			(layers "F.Cu" "F.Mask" "F.Paste")
			(net "P5E_PEX3_STN7_RX_DN<112>")
		)
		(pad "W4" smd circle
			(at -19.949922 -5.700014)
			(size 0.4572 0.4572)
			(layers "F.Cu" "F.Mask" "F.Paste")
			(net "P5E_PEX3_STN7_RX_DP<112>")
		)
		(pad "W5" smd circle
			(at -18.999962 -5.700014)
			(size 0.4572 0.4572)
			(layers "F.Cu" "F.Mask" "F.Paste")
			(net "GND")
		)
		(pad "W6" smd circle
			(at -18.050002 -5.700014)
			(size 0.4572 0.4572)
			(layers "F.Cu" "F.Mask" "F.Paste")
			(net "P5E_PEX3_STN7_TX_DN<112>")
		)
		(pad "W7" smd circle
			(at -17.100042 -5.700014)
			(size 0.4572 0.4572)
			(layers "F.Cu" "F.Mask" "F.Paste")
			(net "P5E_PEX3_STN7_TX_DP<112>")
		)
		(pad "W8" smd circle
			(at -16.150082 -5.700014)
			(size 0.4572 0.4572)
			(layers "F.Cu" "F.Mask" "F.Paste")
			(net "GND")
		)
		(pad "W9" smd circle
			(at -15.200122 -5.700014)
			(size 0.4572 0.4572)
			(layers "F.Cu" "F.Mask" "F.Paste")
			(net "GND")
		)
		(pad "W10" smd circle
			(at -14.249908 -5.700014)
			(size 0.4572 0.4572)
			(layers "F.Cu" "F.Mask" "F.Paste")
			(net "GND")
		)
		(pad "W11" smd circle
			(at -13.299948 -5.700014)
			(size 0.4572 0.4572)
			(layers "F.Cu" "F.Mask" "F.Paste")
			(net "GND")
		)
		(pad "W12" smd circle
			(at -12.349988 -5.700014)
			(size 0.4572 0.4572)
			(layers "F.Cu" "F.Mask" "F.Paste")
			(net "GND")
		)
		(pad "W13" smd circle
			(at -11.400028 -5.700014)
			(size 0.4572 0.4572)
			(layers "F.Cu" "F.Mask" "F.Paste")
			(net "GND")
		)
		(pad "W14" smd circle
			(at -10.450068 -5.700014)
			(size 0.4572 0.4572)
			(layers "F.Cu" "F.Mask" "F.Paste")
			(net "GND")
		)
		(pad "W15" smd circle
			(at -9.500108 -5.700014)
			(size 0.4572 0.4572)
			(layers "F.Cu" "F.Mask" "F.Paste")
			(net "GND")
		)
		(pad "W16" smd circle
			(at -8.549894 -5.700014)
			(size 0.4572 0.4572)
			(layers "F.Cu" "F.Mask" "F.Paste")
			(net "GND")
		)
		(pad "W17" smd circle
			(at -7.599934 -5.700014)
			(size 0.4572 0.4572)
			(layers "F.Cu" "F.Mask" "F.Paste")
			(net "GND")
		)
		(pad "W18" smd circle
			(at -6.649974 -5.700014)
			(size 0.4572 0.4572)
			(layers "F.Cu" "F.Mask" "F.Paste")
			(net "GND")
		)
		(pad "W19" smd circle
			(at -5.700014 -5.700014)
			(size 0.4572 0.4572)
			(layers "F.Cu" "F.Mask" "F.Paste")
			(net "GND")
		)
		(pad "W20" smd circle
			(at -4.750054 -5.700014)
			(size 0.4572 0.4572)
			(layers "F.Cu" "F.Mask" "F.Paste")
			(net "GND")
		)
		(pad "W21" smd circle
			(at -3.800094 -5.700014)
			(size 0.4572 0.4572)
			(layers "F.Cu" "F.Mask" "F.Paste")
			(net "GND")
		)
		(pad "W22" smd circle
			(at -2.84988 -5.700014)
			(size 0.4572 0.4572)
			(layers "F.Cu" "F.Mask" "F.Paste")
			(net "GND")
		)
		(pad "W23" smd circle
			(at -1.89992 -5.700014)
			(size 0.4572 0.4572)
			(layers "F.Cu" "F.Mask" "F.Paste")
			(net "GND")
		)
		(pad "W24" smd circle
			(at -0.94996 -5.700014)
			(size 0.4572 0.4572)
			(layers "F.Cu" "F.Mask" "F.Paste")
			(net "GND")
		)
		(pad "W25" smd circle
			(at 0 -5.700014)
			(size 0.4572 0.4572)
			(layers "F.Cu" "F.Mask" "F.Paste")
			(net "GND")
		)
		(pad "W26" smd circle
			(at 0.94996 -5.700014)
			(size 0.4572 0.4572)
			(layers "F.Cu" "F.Mask" "F.Paste")
			(net "GND")
		)
		(pad "W27" smd circle
			(at 1.89992 -5.700014)
			(size 0.4572 0.4572)
			(layers "F.Cu" "F.Mask" "F.Paste")
			(net "GND")
		)
		(pad "W28" smd circle
			(at 2.84988 -5.700014)
			(size 0.4572 0.4572)
			(layers "F.Cu" "F.Mask" "F.Paste")
			(net "GND")
		)
		(pad "W29" smd circle
			(at 3.800094 -5.700014)
			(size 0.4572 0.4572)
			(layers "F.Cu" "F.Mask" "F.Paste")
			(net "GND")
		)
		(pad "W30" smd circle
			(at 4.750054 -5.700014)
			(size 0.4572 0.4572)
			(layers "F.Cu" "F.Mask" "F.Paste")
			(net "GND")
		)
		(pad "W31" smd circle
			(at 5.700014 -5.700014)
			(size 0.4572 0.4572)
			(layers "F.Cu" "F.Mask" "F.Paste")
			(net "GND")
		)
		(pad "W32" smd circle
			(at 6.649974 -5.700014)
			(size 0.4572 0.4572)
			(layers "F.Cu" "F.Mask" "F.Paste")
			(net "GND")
		)
		(pad "W33" smd circle
			(at 7.599934 -5.700014)
			(size 0.4572 0.4572)
			(layers "F.Cu" "F.Mask" "F.Paste")
			(net "GND")
		)
		(pad "W34" smd circle
			(at 8.549894 -5.700014)
			(size 0.4572 0.4572)
			(layers "F.Cu" "F.Mask" "F.Paste")
			(net "GND")
		)
		(pad "W35" smd circle
			(at 9.500108 -5.700014)
			(size 0.4572 0.4572)
			(layers "F.Cu" "F.Mask" "F.Paste")
			(net "P1V8_PEX")
		)
		(pad "W36" smd circle
			(at 10.450068 -5.700014)
			(size 0.4572 0.4572)
			(layers "F.Cu" "F.Mask" "F.Paste")
			(net "GND")
		)
		(pad "W37" smd circle
			(at 11.400028 -5.700014)
			(size 0.4572 0.4572)
			(layers "F.Cu" "F.Mask" "F.Paste")
			(net "GND")
		)
		(pad "W38" smd circle
			(at 12.349988 -5.700014)
			(size 0.4572 0.4572)
			(layers "F.Cu" "F.Mask" "F.Paste")
			(net "GND")
		)
		(pad "W39" smd circle
			(at 13.299948 -5.700014)
			(size 0.4572 0.4572)
			(layers "F.Cu" "F.Mask" "F.Paste")
			(net "VSENSE_P0V8_PEX3_SKT_VRTN")
		)
		(pad "W40" smd circle
			(at 14.249908 -5.700014)
			(size 0.4572 0.4572)
			(layers "F.Cu" "F.Mask" "F.Paste")
			(net "GND")
		)
		(pad "W41" smd circle
			(at 15.200122 -5.700014)
			(size 0.4572 0.4572)
			(layers "F.Cu" "F.Mask" "F.Paste")
			(net "GND")
		)
		(pad "W42" smd circle
			(at 16.150082 -5.700014)
			(size 0.4572 0.4572)
			(layers "F.Cu" "F.Mask" "F.Paste")
			(net "GND")
		)
		(pad "W43" smd circle
			(at 17.100042 -5.700014)
			(size 0.4572 0.4572)
			(layers "F.Cu" "F.Mask" "F.Paste")
			(net "Net_1563")
		)
		(pad "W44" smd circle
			(at 18.050002 -5.700014)
			(size 0.4572 0.4572)
			(layers "F.Cu" "F.Mask" "F.Paste")
			(net "Net_1532")
		)
		(pad "W45" smd circle
			(at 18.999962 -5.700014)
			(size 0.4572 0.4572)
			(layers "F.Cu" "F.Mask" "F.Paste")
			(net "GND")
		)
		(pad "W46" smd circle
			(at 19.949922 -5.700014)
			(size 0.4572 0.4572)
			(layers "F.Cu" "F.Mask" "F.Paste")
			(net "Net_1470")
		)
		(pad "W47" smd circle
			(at 20.899882 -5.700014)
			(size 0.4572 0.4572)
			(layers "F.Cu" "F.Mask" "F.Paste")
			(net "Net_1506")
		)
		(pad "W48" smd circle
			(at 21.850096 -5.700014)
			(size 0.4572 0.4572)
			(layers "F.Cu" "F.Mask" "F.Paste")
			(net "GND")
		)
		(pad "W49" smd circle
			(at 22.800056 -5.700014)
			(size 0.4572 0.4572)
			(layers "F.Cu" "F.Mask" "F.Paste")
			(net "GND")
		)
		(pad "Y1" smd circle
			(at -22.800056 -4.750054)
			(size 0.4572 0.4572)
			(layers "F.Cu" "F.Mask" "F.Paste")
			(net "GND")
		)
		(pad "Y2" smd circle
			(at -21.850096 -4.750054)
			(size 0.4572 0.4572)
			(layers "F.Cu" "F.Mask" "F.Paste")
			(net "GND")
		)
		(pad "Y3" smd circle
			(at -20.899882 -4.750054)
			(size 0.4572 0.4572)
			(layers "F.Cu" "F.Mask" "F.Paste")
			(net "GND")
		)
		(pad "Y4" smd circle
			(at -19.949922 -4.750054)
			(size 0.4572 0.4572)
			(layers "F.Cu" "F.Mask" "F.Paste")
			(net "GND")
		)
		(pad "Y5" smd circle
			(at -18.999962 -4.750054)
			(size 0.4572 0.4572)
			(layers "F.Cu" "F.Mask" "F.Paste")
			(net "GND")
		)
		(pad "Y6" smd circle
			(at -18.050002 -4.750054)
			(size 0.4572 0.4572)
			(layers "F.Cu" "F.Mask" "F.Paste")
			(net "GND")
		)
		(pad "Y7" smd circle
			(at -17.100042 -4.750054)
			(size 0.4572 0.4572)
			(layers "F.Cu" "F.Mask" "F.Paste")
			(net "GND")
		)
		(pad "Y8" smd circle
			(at -16.150082 -4.750054)
			(size 0.4572 0.4572)
			(layers "F.Cu" "F.Mask" "F.Paste")
			(net "GND")
		)
		(pad "Y9" smd circle
			(at -15.200122 -4.750054)
			(size 0.4572 0.4572)
			(layers "F.Cu" "F.Mask" "F.Paste")
			(net "GND")
		)
		(pad "Y10" smd circle
			(at -14.249908 -4.750054)
			(size 0.4572 0.4572)
			(layers "F.Cu" "F.Mask" "F.Paste")
			(net "GND")
		)
		(pad "Y11" smd circle
			(at -13.299948 -4.750054)
			(size 0.4572 0.4572)
			(layers "F.Cu" "F.Mask" "F.Paste")
			(net "GND")
		)
		(pad "Y12" smd circle
			(at -12.349988 -4.750054)
			(size 0.4572 0.4572)
			(layers "F.Cu" "F.Mask" "F.Paste")
			(net "P1V8_PEX")
		)
		(pad "Y13" smd circle
			(at -11.400028 -4.750054)
			(size 0.4572 0.4572)
			(layers "F.Cu" "F.Mask" "F.Paste")
			(net "GND")
		)
		(pad "Y14" smd circle
			(at -10.450068 -4.750054)
			(size 0.4572 0.4572)
			(layers "F.Cu" "F.Mask" "F.Paste")
			(net "P0V8_PEX3")
		)
		(pad "Y15" smd circle
			(at -9.500108 -4.750054)
			(size 0.4572 0.4572)
			(layers "F.Cu" "F.Mask" "F.Paste")
			(net "GND")
		)
		(pad "Y16" smd circle
			(at -8.549894 -4.750054)
			(size 0.4572 0.4572)
			(layers "F.Cu" "F.Mask" "F.Paste")
			(net "P0V8_SERDES_VDDA_PEX3")
		)
		(pad "Y17" smd circle
			(at -7.599934 -4.750054)
			(size 0.4572 0.4572)
			(layers "F.Cu" "F.Mask" "F.Paste")
			(net "P0V8_SERDES_VDDA_PEX3")
		)
		(pad "Y18" smd circle
			(at -6.649974 -4.750054)
			(size 0.4572 0.4572)
			(layers "F.Cu" "F.Mask" "F.Paste")
			(net "P0V8_SERDES_VDDA_PEX3")
		)
		(pad "Y19" smd circle
			(at -5.700014 -4.750054)
			(size 0.4572 0.4572)
			(layers "F.Cu" "F.Mask" "F.Paste")
			(net "P0V8_SERDES_VDDA_PEX3")
		)
		(pad "Y20" smd circle
			(at -4.750054 -4.750054)
			(size 0.4572 0.4572)
			(layers "F.Cu" "F.Mask" "F.Paste")
			(net "P0V8_SERDES_VDDA_PEX3")
		)
		(pad "Y21" smd circle
			(at -3.800094 -4.750054)
			(size 0.4572 0.4572)
			(layers "F.Cu" "F.Mask" "F.Paste")
			(net "P0V8_SERDES_VDDA_PEX3")
		)
		(pad "Y22" smd circle
			(at -2.84988 -4.750054)
			(size 0.4572 0.4572)
			(layers "F.Cu" "F.Mask" "F.Paste")
			(net "P0V8_SERDES_VDDA_PEX3")
		)
		(pad "Y23" smd circle
			(at -1.89992 -4.750054)
			(size 0.4572 0.4572)
			(layers "F.Cu" "F.Mask" "F.Paste")
			(net "P0V8_SERDES_VDDA_PEX3")
		)
		(pad "Y24" smd circle
			(at -0.94996 -4.750054)
			(size 0.4572 0.4572)
			(layers "F.Cu" "F.Mask" "F.Paste")
			(net "P0V8_SERDES_VDDA_PEX3")
		)
		(pad "Y25" smd circle
			(at 0 -4.750054)
			(size 0.4572 0.4572)
			(layers "F.Cu" "F.Mask" "F.Paste")
			(net "P0V8_SERDES_VDDA_PEX3")
		)
		(pad "Y26" smd circle
			(at 0.94996 -4.750054)
			(size 0.4572 0.4572)
			(layers "F.Cu" "F.Mask" "F.Paste")
			(net "P0V8_SERDES_VDDA_PEX3")
		)
		(pad "Y27" smd circle
			(at 1.89992 -4.750054)
			(size 0.4572 0.4572)
			(layers "F.Cu" "F.Mask" "F.Paste")
			(net "P0V8_SERDES_VDDA_PEX3")
		)
		(pad "Y28" smd circle
			(at 2.84988 -4.750054)
			(size 0.4572 0.4572)
			(layers "F.Cu" "F.Mask" "F.Paste")
			(net "P0V8_SERDES_VDDA_PEX3")
		)
		(pad "Y29" smd circle
			(at 3.800094 -4.750054)
			(size 0.4572 0.4572)
			(layers "F.Cu" "F.Mask" "F.Paste")
			(net "P0V8_SERDES_VDDA_PEX3")
		)
		(pad "Y30" smd circle
			(at 4.750054 -4.750054)
			(size 0.4572 0.4572)
			(layers "F.Cu" "F.Mask" "F.Paste")
			(net "P0V8_SERDES_VDDA_PEX3")
		)
		(pad "Y31" smd circle
			(at 5.700014 -4.750054)
			(size 0.4572 0.4572)
			(layers "F.Cu" "F.Mask" "F.Paste")
			(net "P0V8_SERDES_VDDA_PEX3")
		)
		(pad "Y32" smd circle
			(at 6.649974 -4.750054)
			(size 0.4572 0.4572)
			(layers "F.Cu" "F.Mask" "F.Paste")
			(net "P0V8_SERDES_VDDA_PEX3")
		)
		(pad "Y33" smd circle
			(at 7.599934 -4.750054)
			(size 0.4572 0.4572)
			(layers "F.Cu" "F.Mask" "F.Paste")
			(net "P0V8_SERDES_VDDA_PEX3")
		)
		(pad "Y34" smd circle
			(at 8.549894 -4.750054)
			(size 0.4572 0.4572)
			(layers "F.Cu" "F.Mask" "F.Paste")
			(net "GND")
		)
		(pad "Y35" smd circle
			(at 9.500108 -4.750054)
			(size 0.4572 0.4572)
			(layers "F.Cu" "F.Mask" "F.Paste")
			(net "P1V8_PEX")
		)
		(pad "Y36" smd circle
			(at 10.450068 -4.750054)
			(size 0.4572 0.4572)
			(layers "F.Cu" "F.Mask" "F.Paste")
			(net "GND")
		)
		(pad "Y37" smd circle
			(at 11.400028 -4.750054)
			(size 0.4572 0.4572)
			(layers "F.Cu" "F.Mask" "F.Paste")
			(net "GND")
		)
		(pad "Y38" smd circle
			(at 12.349988 -4.750054)
			(size 0.4572 0.4572)
			(layers "F.Cu" "F.Mask" "F.Paste")
			(net "GND")
		)
		(pad "Y39" smd circle
			(at 13.299948 -4.750054)
			(size 0.4572 0.4572)
			(layers "F.Cu" "F.Mask" "F.Paste")
			(net "PEX3_ADCTEMP_VINP0")
		)
		(pad "Y40" smd circle
			(at 14.249908 -4.750054)
			(size 0.4572 0.4572)
			(layers "F.Cu" "F.Mask" "F.Paste")
			(net "GND")
		)
		(pad "Y41" smd circle
			(at 15.200122 -4.750054)
			(size 0.4572 0.4572)
			(layers "F.Cu" "F.Mask" "F.Paste")
			(net "Net_1523")
		)
		(pad "Y42" smd circle
			(at 16.150082 -4.750054)
			(size 0.4572 0.4572)
			(layers "F.Cu" "F.Mask" "F.Paste")
			(net "Net_1561")
		)
		(pad "Y43" smd circle
			(at 17.100042 -4.750054)
			(size 0.4572 0.4572)
			(layers "F.Cu" "F.Mask" "F.Paste")
			(net "GND")
		)
		(pad "Y44" smd circle
			(at 18.050002 -4.750054)
			(size 0.4572 0.4572)
			(layers "F.Cu" "F.Mask" "F.Paste")
			(net "GND")
		)
		(pad "Y45" smd circle
			(at 18.999962 -4.750054)
			(size 0.4572 0.4572)
			(layers "F.Cu" "F.Mask" "F.Paste")
			(net "GND")
		)
		(pad "Y46" smd circle
			(at 19.949922 -4.750054)
			(size 0.4572 0.4572)
			(layers "F.Cu" "F.Mask" "F.Paste")
			(net "GND")
		)
		(pad "Y47" smd circle
			(at 20.899882 -4.750054)
			(size 0.4572 0.4572)
			(layers "F.Cu" "F.Mask" "F.Paste")
			(net "GND")
		)
		(pad "Y48" smd circle
			(at 21.850096 -4.750054)
			(size 0.4572 0.4572)
			(layers "F.Cu" "F.Mask" "F.Paste")
			(net "Net_1409")
		)
		(pad "Y49" smd circle
			(at 22.800056 -4.750054)
			(size 0.4572 0.4572)
			(layers "F.Cu" "F.Mask" "F.Paste")
			(net "Net_1451")
		)
		(zone
			(layer "F.Cu")
			(hatch none 0.5)
			(connect_pads
				(clearance 0)
			)
			(min_thickness 0.25)
			(keepout
				(tracks allowed)
				(vias not_allowed)
				(pads allowed)
				(copperpour not_allowed)
				(footprints allowed)
			)
			(placement
				(enabled no)
				(sheetname "")
			)
			(fill
				(thermal_gap 0.5)
				(thermal_bridge_width 0.5)
				(island_removal_mode 0)
			)
			(polygon
				(pts
					(xy 408.229308 -319.741296) (xy 408.620468 -319.741296) (xy 408.620468 -295.62044) (xy 431.791364 -295.62044)
					(xy 431.791364 -295.22928) (xy 408.620468 -295.22928) (xy 408.620468 -272.058384) (xy 408.229308 -272.058384)
					(xy 408.229308 -295.22928) (xy 384.108452 -295.22928) (xy 384.108452 -295.62044) (xy 408.229308 -295.62044)
				)
			)
		)
	)
	(footprint ""
		(layer "F.Cu")
		(at 336.042 -157.734)
		(property "Reference" "R4793"
			(at 0 0 0)
			(layer "F.SilkS")
			(hide yes)
			(effects
				(font
					(size 1.27 1.27)
				)
			)
		)
		(property "Value" ""
			(at 0 0 0)
			(layer "F.Fab")
			(effects
				(font
					(size 1.27 1.27)
				)
			)
		)
		(duplicate_pad_numbers_are_jumpers no)
		(fp_line
			(start -0.7874 -0.4064)
			(end 0.7874 -0.4064)
			(stroke
				(width 0.1524)
				(type default)
			)
			(layer "F.SilkS")
		)
		(fp_line
			(start -0.7874 0.4064)
			(end -0.7874 -0.4064)
			(stroke
				(width 0.1524)
				(type default)
			)
			(layer "F.SilkS")
		)
		(fp_line
			(start 0.7874 -0.4064)
			(end 0.7874 0.4064)
			(stroke
				(width 0.1524)
				(type default)
			)
			(layer "F.SilkS")
		)
		(fp_line
			(start 0.7874 0.4064)
			(end -0.7874 0.4064)
			(stroke
				(width 0.1524)
				(type default)
			)
			(layer "F.SilkS")
		)
		(fp_line
			(start -0.67945 -0.305054)
			(end -0.12065 -0.305054)
			(stroke
				(width 0.1)
				(type default)
			)
			(layer "F.Fab")
		)
		(fp_line
			(start -0.67945 0.3048)
			(end -0.67945 -0.305054)
			(stroke
				(width 0.1)
				(type default)
			)
			(layer "F.Fab")
		)
		(fp_line
			(start -0.12065 -0.305054)
			(end -0.12065 -0.2794)
			(stroke
				(width 0.1)
				(type default)
			)
			(layer "F.Fab")
		)
		(fp_line
			(start -0.12065 -0.2794)
			(end 0.12065 -0.2794)
			(stroke
				(width 0.1)
				(type default)
			)
			(layer "F.Fab")
		)
		(fp_line
			(start -0.12065 0.2794)
			(end -0.12065 0.3048)
			(stroke
				(width 0.1)
				(type default)
			)
			(layer "F.Fab")
		)
		(fp_line
			(start -0.12065 0.3048)
			(end -0.67945 0.3048)
			(stroke
				(width 0.1)
				(type default)
			)
			(layer "F.Fab")
		)
		(fp_line
			(start 0.120396 0.2794)
			(end -0.12065 0.2794)
			(stroke
				(width 0.1)
				(type default)
			)
			(layer "F.Fab")
		)
		(fp_line
			(start 0.120396 0.3048)
			(end 0.120396 0.2794)
			(stroke
				(width 0.1)
				(type default)
			)
			(layer "F.Fab")
		)
		(fp_line
			(start 0.12065 -0.3048)
			(end 0.67945 -0.3048)
			(stroke
				(width 0.1)
				(type default)
			)
			(layer "F.Fab")
		)
		(fp_line
			(start 0.12065 -0.2794)
			(end 0.12065 -0.3048)
			(stroke
				(width 0.1)
				(type default)
			)
			(layer "F.Fab")
		)
		(fp_line
			(start 0.67945 -0.3048)
			(end 0.67945 0.3048)
			(stroke
				(width 0.1)
				(type default)
			)
			(layer "F.Fab")
		)
		(fp_line
			(start 0.67945 0.3048)
			(end 0.120396 0.3048)
			(stroke
				(width 0.1)
				(type default)
			)
			(layer "F.Fab")
		)
		(pad "1" smd circle
			(at -0.40005 0)
			(size 0 0)
			(layers "F.Cu" "F.Mask" "F.Paste")
			(net "P3V3_AUX")
		)
		(pad "2" smd circle
			(at 0.40005 0)
			(size 0 0)
			(layers "F.Cu" "F.Mask" "F.Paste")
			(net "RST_PEX_SSD12_PERST_R_N")
		)
	)
	(footprint ""
		(layer "F.Cu")
		(at 28.04922 -290.595812 -90)
		(property "Reference" "C3064"
			(at 0 0 270)
			(layer "F.SilkS")
			(hide yes)
			(effects
				(font
					(size 1.27 1.27)
				)
			)
		)
		(property "Value" ""
			(at 0 0 270)
			(layer "F.Fab")
			(effects
				(font
					(size 1.27 1.27)
				)
			)
		)
		(duplicate_pad_numbers_are_jumpers no)
		(fp_line
			(start -0.299974 0.150114)
			(end -0.299974 -0.150114)
			(stroke
				(width 0.1)
				(type default)
			)
			(layer "F.Fab")
		)
		(fp_line
			(start 0.299974 0.150114)
			(end -0.299974 0.150114)
			(stroke
				(width 0.1)
				(type default)
			)
			(layer "F.Fab")
		)
		(fp_line
			(start -0.299974 -0.150114)
			(end 0.299974 -0.150114)
			(stroke
				(width 0.1)
				(type default)
			)
			(layer "F.Fab")
		)
		(fp_line
			(start 0.299974 -0.150114)
			(end 0.299974 0.150114)
			(stroke
				(width 0.1)
				(type default)
			)
			(layer "F.Fab")
		)
		(pad "1" smd rect
			(at -0.2667 0 270)
			(size 0.3048 0.381)
			(layers "F.Cu" "F.Mask" "F.Paste")
			(net "P1V8_PLL0_PEX0")
		)
		(pad "2" smd rect
			(at 0.2667 0 270)
			(size 0.3048 0.381)
			(layers "F.Cu" "F.Mask" "F.Paste")
			(net "GND")
		)
	)
	(footprint ""
		(layer "F.Cu")
		(at 368.734594 -30.94609 180)
		(property "Reference" "C702"
			(at 0 0 180)
			(layer "F.SilkS")
			(hide yes)
			(effects
				(font
					(size 1.27 1.27)
				)
			)
		)
		(property "Value" ""
			(at 0 0 180)
			(layer "F.Fab")
			(effects
				(font
					(size 1.27 1.27)
				)
			)
		)
		(duplicate_pad_numbers_are_jumpers no)
		(fp_line
			(start 0.299974 0.150114)
			(end -0.299974 0.150114)
			(stroke
				(width 0.1)
				(type default)
			)
			(layer "F.Fab")
		)
		(fp_line
			(start 0.299974 -0.150114)
			(end 0.299974 0.150114)
			(stroke
				(width 0.1)
				(type default)
			)
			(layer "F.Fab")
		)
		(fp_line
			(start -0.299974 0.150114)
			(end -0.299974 -0.150114)
			(stroke
				(width 0.1)
				(type default)
			)
			(layer "F.Fab")
		)
		(fp_line
			(start -0.299974 -0.150114)
			(end 0.299974 -0.150114)
			(stroke
				(width 0.1)
				(type default)
			)
			(layer "F.Fab")
		)
		(pad "1" smd rect
			(at -0.2667 0 180)
			(size 0.3048 0.381)
			(layers "F.Cu" "F.Mask" "F.Paste")
			(net "P5E_PEX3_STN2_TX_DP<45>")
		)
		(pad "2" smd rect
			(at 0.2667 0 180)
			(size 0.3048 0.381)
			(layers "F.Cu" "F.Mask" "F.Paste")
			(net "P5E_PEX3_STN2_TX_C_DP<45>")
		)
	)
	(footprint ""
		(layer "F.Cu")
		(at 71.588122 -350.098614 90)
		(property "Reference" "C138"
			(at 0 0 90)
			(layer "F.SilkS")
			(hide yes)
			(effects
				(font
					(size 1.27 1.27)
				)
			)
		)
		(property "Value" ""
			(at 0 0 90)
			(layer "F.Fab")
			(effects
				(font
					(size 1.27 1.27)
				)
			)
		)
		(duplicate_pad_numbers_are_jumpers no)
		(fp_line
			(start 0.299974 -0.150114)
			(end 0.299974 0.150114)
			(stroke
				(width 0.1)
				(type default)
			)
			(layer "F.Fab")
		)
		(fp_line
			(start -0.299974 -0.150114)
			(end 0.299974 -0.150114)
			(stroke
				(width 0.1)
				(type default)
			)
			(layer "F.Fab")
		)
		(fp_line
			(start 0.299974 0.150114)
			(end -0.299974 0.150114)
			(stroke
				(width 0.1)
				(type default)
			)
			(layer "F.Fab")
		)
		(fp_line
			(start -0.299974 0.150114)
			(end -0.299974 -0.150114)
			(stroke
				(width 0.1)
				(type default)
			)
			(layer "F.Fab")
		)
		(pad "1" smd rect
			(at -0.2667 0 90)
			(size 0.3048 0.381)
			(layers "F.Cu" "F.Mask" "F.Paste")
			(net "P5E_PEX0_STN6_TX_DN<107>")
		)
		(pad "2" smd rect
			(at 0.2667 0 90)
			(size 0.3048 0.381)
			(layers "F.Cu" "F.Mask" "F.Paste")
			(net "P5E_PEX0_STN6_TX_C_DN<107>")
		)
	)
	(footprint ""
		(layer "F.Cu")
		(at 181.064916 -26.785062 180)
		(property "Reference" "J36"
			(at 4.509516 -11.475466 90)
			(unlocked yes)
			(layer "F.SilkS")
			(effects
				(font
					(size 0.7874 0.5842)
					(thickness 0.1524)
				)
			)
		)
		(property "Value" ""
			(at 0 0 180)
			(layer "F.Fab")
			(effects
				(font
					(size 1.27 1.27)
				)
			)
		)
		(duplicate_pad_numbers_are_jumpers no)
		(fp_line
			(start 3.150108 12.115038)
			(end 1.529334 12.115038)
			(stroke
				(width 0.1524)
				(type default)
			)
			(layer "F.SilkS")
		)
		(fp_line
			(start 3.074924 12.014962)
			(end 1.632204 12.014962)
			(stroke
				(width 0.1524)
				(type default)
			)
			(layer "F.SilkS")
		)
		(fp_line
			(start 1.632204 -12.014962)
			(end 3.074924 -12.014962)
			(stroke
				(width 0.1524)
				(type default)
			)
			(layer "F.SilkS")
		)
		(fp_line
			(start 1.529334 -12.115038)
			(end 3.150108 -12.115038)
			(stroke
				(width 0.1524)
				(type default)
			)
			(layer "F.SilkS")
		)
		(fp_line
			(start -1.529334 12.115038)
			(end -3.150108 12.115038)
			(stroke
				(width 0.1524)
				(type default)
			)
			(layer "F.SilkS")
		)
		(fp_line
			(start -1.632204 12.014962)
			(end -3.074924 12.014962)
			(stroke
				(width 0.1524)
				(type default)
			)
			(layer "F.SilkS")
		)
		(fp_line
			(start -3.074924 -12.014962)
			(end -1.632204 -12.014962)
			(stroke
				(width 0.1524)
				(type default)
			)
			(layer "F.SilkS")
		)
		(fp_line
			(start -3.150108 -12.115038)
			(end -1.529334 -12.115038)
			(stroke
				(width 0.1524)
				(type default)
			)
			(layer "F.SilkS")
		)
		(fp_poly
			(pts
				(xy 3.451098 -8.920226) (xy 3.8735 -10.18794) (xy 4.718558 -9.342882)
			)
			(stroke
				(width 0)
				(type default)
			)
			(fill yes)
			(layer "F.SilkS")
		)
		(fp_line
			(start 3.074924 12.014962)
			(end -3.074924 12.014962)
			(stroke
				(width 0.1)
				(type default)
			)
			(layer "F.Fab")
		)
		(fp_line
			(start 3.074924 -12.014962)
			(end 3.074924 12.014962)
			(stroke
				(width 0.1)
				(type default)
			)
			(layer "F.Fab")
		)
		(fp_line
			(start -3.074924 12.014962)
			(end -3.074924 -12.014962)
			(stroke
				(width 0.1)
				(type default)
			)
			(layer "F.Fab")
		)
		(fp_line
			(start -3.074924 -12.014962)
			(end 3.074924 -12.014962)
			(stroke
				(width 0.1)
				(type default)
			)
			(layer "F.Fab")
		)
		(fp_poly
			(pts
				(xy 3.348736 -7.994904) (xy 4.543806 -8.592566) (xy 4.543806 -7.397496)
			)
			(stroke
				(width 0)
				(type default)
			)
			(fill yes)
			(layer "F.Fab")
		)
		(pad "" np_thru_hole circle
			(at -1.75006 -9.815068 90)
			(size 1.1176 1.1176)
			(drill 1.1176)
			(layers "*.Cu" "*.Mask")
			(clearance 0.381)
			(thermal_gap 0.381)
		)
		(pad "" np_thru_hole circle
			(at 0 9.815068 90)
			(size 1.1176 1.1176)
			(drill 1.1176)
			(layers "*.Cu" "*.Mask")
			(clearance 0.381)
			(thermal_gap 0.381)
		)
		(pad "A1" smd rect
			(at 2.29997 -7.994904 90)
			(size 0.381 1.27)
			(layers "F.Cu" "F.Mask" "F.Paste")
			(net "GND")
		)
		(pad "A2" smd rect
			(at 2.29997 -7.394956 90)
			(size 0.381 1.27)
			(layers "F.Cu" "F.Mask" "F.Paste")
			(net "GND")
		)
		(pad "A3" smd rect
			(at 2.29997 -6.795008 90)
			(size 0.381 1.27)
			(layers "F.Cu" "F.Mask" "F.Paste")
			(net "GND")
		)
		(pad "A4" smd rect
			(at 2.29997 -6.19506 90)
			(size 0.381 1.27)
			(layers "F.Cu" "F.Mask" "F.Paste")
			(net "GND")
		)
		(pad "A5" smd rect
			(at 2.29997 -5.595112 90)
			(size 0.381 1.27)
			(layers "F.Cu" "F.Mask" "F.Paste")
			(net "GND")
		)
		(pad "A6" smd rect
			(at 2.29997 -4.99491 90)
			(size 0.381 1.27)
			(layers "F.Cu" "F.Mask" "F.Paste")
			(net "GND")
		)
		(pad "A7" smd rect
			(at 2.29997 -4.394962 90)
			(size 0.381 1.27)
			(layers "F.Cu" "F.Mask" "F.Paste")
			(net "SMB_ISO_SSD6_R_SCL")
		)
		(pad "A8" smd rect
			(at 2.29997 -3.795014 90)
			(size 0.381 1.27)
			(layers "F.Cu" "F.Mask" "F.Paste")
			(net "SMB_ISO_SSD6_R_SDA")
		)
		(pad "A9" smd rect
			(at 2.29997 -3.195066 90)
			(size 0.381 1.27)
			(layers "F.Cu" "F.Mask" "F.Paste")
			(net "RST_SMB_SSD6_ISO_R_N")
		)
		(pad "A10" smd rect
			(at 2.29997 -2.595118 90)
			(size 0.381 1.27)
			(layers "F.Cu" "F.Mask" "F.Paste")
			(net "SSD6_LED_ISO_R_N")
		)
		(pad "A11" smd rect
			(at 2.29997 -1.994916 90)
			(size 0.381 1.27)
			(layers "F.Cu" "F.Mask" "F.Paste")
			(net "PU_CLKREQ6")
		)
		(pad "A12" smd rect
			(at 2.29997 -1.394968 90)
			(size 0.381 1.27)
			(layers "F.Cu" "F.Mask" "F.Paste")
			(net "PRSNT_SSD6_N")
		)
		(pad "A13" smd rect
			(at 2.29997 -0.79502 90)
			(size 0.381 1.27)
			(layers "F.Cu" "F.Mask" "F.Paste")
			(net "GND")
		)
		(pad "A14" smd rect
			(at 2.29997 -0.195072 90)
			(size 0.381 1.27)
			(layers "F.Cu" "F.Mask" "F.Paste")
			(net "Net_8513")
		)
		(pad "A15" smd rect
			(at 2.29997 0.404876 90)
			(size 0.381 1.27)
			(layers "F.Cu" "F.Mask" "F.Paste")
			(net "Net_8512")
		)
		(pad "A16" smd rect
			(at 2.29997 1.005078 90)
			(size 0.381 1.27)
			(layers "F.Cu" "F.Mask" "F.Paste")
			(net "GND")
		)
		(pad "A17" smd rect
			(at 2.29997 1.605026 90)
			(size 0.381 1.27)
			(layers "F.Cu" "F.Mask" "F.Paste")
			(net "P5E_PEX1_STN2_RX_DN<36>")
		)
		(pad "A18" smd rect
			(at 2.29997 2.204974 90)
			(size 0.381 1.27)
			(layers "F.Cu" "F.Mask" "F.Paste")
			(net "P5E_PEX1_STN2_RX_DP<36>")
		)
		(pad "A19" smd rect
			(at 2.29997 2.804922 90)
			(size 0.381 1.27)
			(layers "F.Cu" "F.Mask" "F.Paste")
			(net "GND")
		)
		(pad "A20" smd rect
			(at 2.29997 3.405124 90)
			(size 0.381 1.27)
			(layers "F.Cu" "F.Mask" "F.Paste")
			(net "P5E_PEX1_STN2_RX_DN<37>")
		)
		(pad "A21" smd rect
			(at 2.29997 4.005072 90)
			(size 0.381 1.27)
			(layers "F.Cu" "F.Mask" "F.Paste")
			(net "P5E_PEX1_STN2_RX_DP<37>")
		)
		(pad "A22" smd rect
			(at 2.29997 4.60502 90)
			(size 0.381 1.27)
			(layers "F.Cu" "F.Mask" "F.Paste")
			(net "GND")
		)
		(pad "A23" smd rect
			(at 2.29997 5.204968 90)
			(size 0.381 1.27)
			(layers "F.Cu" "F.Mask" "F.Paste")
			(net "P5E_PEX1_STN2_RX_DN<38>")
		)
		(pad "A24" smd rect
			(at 2.29997 5.804916 90)
			(size 0.381 1.27)
			(layers "F.Cu" "F.Mask" "F.Paste")
			(net "P5E_PEX1_STN2_RX_DP<38>")
		)
		(pad "A25" smd rect
			(at 2.29997 6.405118 90)
			(size 0.381 1.27)
			(layers "F.Cu" "F.Mask" "F.Paste")
			(net "GND")
		)
		(pad "A26" smd rect
			(at 2.29997 7.005066 90)
			(size 0.381 1.27)
			(layers "F.Cu" "F.Mask" "F.Paste")
			(net "P5E_PEX1_STN2_RX_DN<39>")
		)
		(pad "A27" smd rect
			(at 2.29997 7.605014 90)
			(size 0.381 1.27)
			(layers "F.Cu" "F.Mask" "F.Paste")
			(net "P5E_PEX1_STN2_RX_DP<39>")
		)
		(pad "A28" smd rect
			(at 2.29997 8.204962 90)
			(size 0.381 1.27)
			(layers "F.Cu" "F.Mask" "F.Paste")
			(net "GND")
		)
		(pad "B1" smd rect
			(at -2.29997 -7.994904 90)
			(size 0.381 1.27)
			(layers "F.Cu" "F.Mask" "F.Paste")
			(net "P12V_SSD6")
		)
		(pad "B2" smd rect
			(at -2.29997 -7.394956 90)
			(size 0.381 1.27)
			(layers "F.Cu" "F.Mask" "F.Paste")
			(net "P12V_SSD6")
		)
		(pad "B3" smd rect
			(at -2.29997 -6.795008 90)
			(size 0.381 1.27)
			(layers "F.Cu" "F.Mask" "F.Paste")
			(net "P12V_SSD6")
		)
		(pad "B4" smd rect
			(at -2.29997 -6.19506 90)
			(size 0.381 1.27)
			(layers "F.Cu" "F.Mask" "F.Paste")
			(net "P12V_SSD6")
		)
		(pad "B5" smd rect
			(at -2.29997 -5.595112 90)
			(size 0.381 1.27)
			(layers "F.Cu" "F.Mask" "F.Paste")
			(net "P12V_SSD6")
		)
		(pad "B6" smd rect
			(at -2.29997 -4.99491 90)
			(size 0.381 1.27)
			(layers "F.Cu" "F.Mask" "F.Paste")
			(net "P12V_SSD6")
		)
		(pad "B7" smd rect
			(at -2.29997 -4.394962 90)
			(size 0.381 1.27)
			(layers "F.Cu" "F.Mask" "F.Paste")
			(net "Net_8514")
		)
		(pad "B8" smd rect
			(at -2.29997 -3.795014 90)
			(size 0.381 1.27)
			(layers "F.Cu" "F.Mask" "F.Paste")
			(net "Net_8511")
		)
		(pad "B9" smd rect
			(at -2.29997 -3.195066 90)
			(size 0.381 1.27)
			(layers "F.Cu" "F.Mask" "F.Paste")
			(net "DUALPORT_N_SSD6")
		)
		(pad "B10" smd rect
			(at -2.29997 -2.595118 90)
			(size 0.381 1.27)
			(layers "F.Cu" "F.Mask" "F.Paste")
			(net "RST_SSD6_PERST_R_N")
		)
		(pad "B11" smd rect
			(at -2.29997 -1.994916 90)
			(size 0.381 1.27)
			(layers "F.Cu" "F.Mask" "F.Paste")
			(net "P3V3_SSD6")
		)
		(pad "B12" smd rect
			(at -2.29997 -1.394968 90)
			(size 0.381 1.27)
			(layers "F.Cu" "F.Mask" "F.Paste")
			(net "SSD6_PWRDIS_R")
		)
		(pad "B13" smd rect
			(at -2.29997 -0.79502 90)
			(size 0.381 1.27)
			(layers "F.Cu" "F.Mask" "F.Paste")
			(net "GND")
		)
		(pad "B14" smd rect
			(at -2.29997 -0.195072 90)
			(size 0.381 1.27)
			(layers "F.Cu" "F.Mask" "F.Paste")
			(net "CLK_100M_DB800ZL_SSD6_R_DN")
		)
		(pad "B15" smd rect
			(at -2.29997 0.404876 90)
			(size 0.381 1.27)
			(layers "F.Cu" "F.Mask" "F.Paste")
			(net "CLK_100M_DB800ZL_SSD6_R_DP")
		)
		(pad "B16" smd rect
			(at -2.29997 1.005078 90)
			(size 0.381 1.27)
			(layers "F.Cu" "F.Mask" "F.Paste")
			(net "GND")
		)
		(pad "B17" smd rect
			(at -2.29997 1.605026 90)
			(size 0.381 1.27)
			(layers "F.Cu" "F.Mask" "F.Paste")
			(net "P5E_PEX1_STN2_TX_C_DN<36>")
		)
		(pad "B18" smd rect
			(at -2.29997 2.204974 90)
			(size 0.381 1.27)
			(layers "F.Cu" "F.Mask" "F.Paste")
			(net "P5E_PEX1_STN2_TX_C_DP<36>")
		)
		(pad "B19" smd rect
			(at -2.29997 2.804922 90)
			(size 0.381 1.27)
			(layers "F.Cu" "F.Mask" "F.Paste")
			(net "GND")
		)
		(pad "B20" smd rect
			(at -2.29997 3.405124 90)
			(size 0.381 1.27)
			(layers "F.Cu" "F.Mask" "F.Paste")
			(net "P5E_PEX1_STN2_TX_C_DN<37>")
		)
		(pad "B21" smd rect
			(at -2.29997 4.005072 90)
			(size 0.381 1.27)
			(layers "F.Cu" "F.Mask" "F.Paste")
			(net "P5E_PEX1_STN2_TX_C_DP<37>")
		)
		(pad "B22" smd rect
			(at -2.29997 4.60502 90)
			(size 0.381 1.27)
			(layers "F.Cu" "F.Mask" "F.Paste")
			(net "GND")
		)
		(pad "B23" smd rect
			(at -2.29997 5.204968 90)
			(size 0.381 1.27)
			(layers "F.Cu" "F.Mask" "F.Paste")
			(net "P5E_PEX1_STN2_TX_C_DN<38>")
		)
		(pad "B24" smd rect
			(at -2.29997 5.804916 90)
			(size 0.381 1.27)
			(layers "F.Cu" "F.Mask" "F.Paste")
			(net "P5E_PEX1_STN2_TX_C_DP<38>")
		)
		(pad "B25" smd rect
			(at -2.29997 6.405118 90)
			(size 0.381 1.27)
			(layers "F.Cu" "F.Mask" "F.Paste")
			(net "GND")
		)
		(pad "B26" smd rect
			(at -2.29997 7.005066 90)
			(size 0.381 1.27)
			(layers "F.Cu" "F.Mask" "F.Paste")
			(net "P5E_PEX1_STN2_TX_C_DN<39>")
		)
		(pad "B27" smd rect
			(at -2.29997 7.605014 90)
			(size 0.381 1.27)
			(layers "F.Cu" "F.Mask" "F.Paste")
			(net "P5E_PEX1_STN2_TX_C_DP<39>")
		)
		(pad "B28" smd rect
			(at -2.29997 8.204962 90)
			(size 0.381 1.27)
			(layers "F.Cu" "F.Mask" "F.Paste")
			(net "GND")
		)
		(pad "G1" thru_hole oval
			(at 0 -11.364976 90)
			(size 1.6256 3.4798)
			(drill oval 1.1176 2.4638)
			(layers "*.Cu" "*.Mask")
			(remove_unused_layers no)
			(net "GND")
			(clearance 0.127)
			(thermal_gap 0.127)
		)
		(pad "G2" thru_hole oval
			(at 0 11.364976 90)
			(size 1.6256 3.4798)
			(drill oval 1.1176 2.4638)
			(layers "*.Cu" "*.Mask")
			(remove_unused_layers no)
			(net "GND")
			(clearance 0.127)
			(thermal_gap 0.127)
		)
		(zone
			(layer "F.Cu")
			(hatch none 0.5)
			(connect_pads
				(clearance 0)
			)
			(min_thickness 0.25)
			(keepout
				(tracks not_allowed)
				(vias allowed)
				(pads allowed)
				(copperpour not_allowed)
				(footprints allowed)
			)
			(placement
				(enabled no)
				(sheetname "")
			)
			(fill
				(thermal_gap 0.5)
				(thermal_bridge_width 0.5)
				(island_removal_mode 0)
			)
			(polygon
				(pts
					(xy 182.444898 -38.850062) (xy 179.69484 -38.850062) (xy 179.69484 -35.900106) (xy 182.444898 -35.900106)
				)
			)
		)
		(zone
			(layer "F.Cu")
			(hatch none 0.5)
			(connect_pads
				(clearance 0)
			)
			(min_thickness 0.25)
			(keepout
				(tracks not_allowed)
				(vias allowed)
				(pads allowed)
				(copperpour not_allowed)
				(footprints allowed)
			)
			(placement
				(enabled no)
				(sheetname "")
			)
			(fill
				(thermal_gap 0.5)
				(thermal_bridge_width 0.5)
				(island_removal_mode 0)
			)
			(polygon
				(pts
					(xy 183.515 -17.670018) (xy 179.684934 -17.670018) (xy 179.684934 -14.720062) (xy 183.515 -14.720062)
				)
			)
		)
		(zone
			(layers "F.Cu" "B.Cu" "In1.Cu" "In2.Cu" "In3.Cu" "In4.Cu" "In5.Cu" "In6.Cu"
				"In7.Cu" "In8.Cu" "In9.Cu" "In10.Cu" "In11.Cu" "In12.Cu" "In13.Cu" "In14.Cu"
				"In15.Cu" "In16.Cu"
			)
			(hatch none 0.5)
			(connect_pads
				(clearance 0)
			)
			(min_thickness 0.25)
			(keepout
				(tracks not_allowed)
				(vias allowed)
				(pads allowed)
				(copperpour not_allowed)
				(footprints allowed)
			)
			(placement
				(enabled no)
				(sheetname "")
			)
			(fill
				(thermal_gap 0.5)
				(thermal_bridge_width 0.5)
				(island_removal_mode 0)
			)
			(polygon
				(pts
					(arc
						(start 182.030116 -36.60013)
						(mid 180.099716 -36.60013)
						(end 182.030116 -36.60013)
					)
				)
			)
		)
		(zone
			(layers "F.Cu" "B.Cu" "In1.Cu" "In2.Cu" "In3.Cu" "In4.Cu" "In5.Cu" "In6.Cu"
				"In7.Cu" "In8.Cu" "In9.Cu" "In10.Cu" "In11.Cu" "In12.Cu" "In13.Cu" "In14.Cu"
				"In15.Cu" "In16.Cu"
			)
			(hatch none 0.5)
			(connect_pads
				(clearance 0)
			)
			(min_thickness 0.25)
			(keepout
				(tracks not_allowed)
				(vias allowed)
				(pads allowed)
				(copperpour not_allowed)
				(footprints allowed)
			)
			(placement
				(enabled no)
				(sheetname "")
			)
			(fill
				(thermal_gap 0.5)
				(thermal_bridge_width 0.5)
				(island_removal_mode 0)
			)
			(polygon
				(pts
					(arc
						(start 183.780176 -16.969994)
						(mid 181.849776 -16.969994)
						(end 183.780176 -16.969994)
					)
				)
			)
		)
	)
	(footprint ""
		(layer "F.Cu")
		(at 395.619986 -127.700024)
		(property "Reference" "J26"
			(at -5.373116 34.736024 90)
			(unlocked yes)
			(layer "F.SilkS")
			(effects
				(font
					(size 0.7874 0.5842)
					(thickness 0.1524)
				)
				(justify left)
			)
		)
		(property "Value" ""
			(at 0 0 0)
			(layer "F.Fab")
			(effects
				(font
					(size 1.27 1.27)
				)
			)
		)
		(duplicate_pad_numbers_are_jumpers no)
		(fp_line
			(start -4.507484 34.720022)
			(end -0.5588 34.720022)
			(stroke
				(width 0.1524)
				(type default)
			)
			(layer "F.SilkS")
		)
		(fp_line
			(start -0.57658 -34.720022)
			(end -4.507484 -34.720022)
			(stroke
				(width 0.1524)
				(type default)
			)
			(layer "F.SilkS")
		)
		(fp_line
			(start 2.6035 34.720022)
			(end 4.507484 34.720022)
			(stroke
				(width 0.1524)
				(type default)
			)
			(layer "F.SilkS")
		)
		(fp_line
			(start 4.507484 -34.720022)
			(end 2.6162 -34.720022)
			(stroke
				(width 0.1524)
				(type default)
			)
			(layer "F.SilkS")
		)
		(fp_line
			(start 4.507484 -21.5265)
			(end 4.507484 -34.720022)
			(stroke
				(width 0.1524)
				(type default)
			)
			(layer "F.SilkS")
		)
		(fp_poly
			(pts
				(xy 5.735574 -17.957038) (xy 5.735574 -18.973038) (xy 4.719574 -18.465038)
			)
			(stroke
				(width 0)
				(type default)
			)
			(fill yes)
			(layer "F.SilkS")
		)
		(fp_line
			(start -4.507484 -34.720022)
			(end -4.507484 34.720022)
			(stroke
				(width 0.1)
				(type default)
			)
			(layer "F.Fab")
		)
		(fp_line
			(start -4.507484 34.720022)
			(end 4.507484 34.720022)
			(stroke
				(width 0.1)
				(type default)
			)
			(layer "F.Fab")
		)
		(fp_line
			(start 4.507484 -34.720022)
			(end -4.507484 -34.720022)
			(stroke
				(width 0.1)
				(type default)
			)
			(layer "F.Fab")
		)
		(fp_line
			(start 4.507484 34.720022)
			(end 4.507484 -34.720022)
			(stroke
				(width 0.1)
				(type default)
			)
			(layer "F.Fab")
		)
		(fp_poly
			(pts
				(xy 5.735574 -17.957038) (xy 5.735574 -18.973038) (xy 4.719574 -18.465038)
			)
			(stroke
				(width 0)
				(type default)
			)
			(fill yes)
			(layer "F.Fab")
		)
		(pad "" np_thru_hole circle
			(at -0.727456 -32.485076)
			(size 1.1176 1.1176)
			(drill 1.1176)
			(layers "*.Cu" "*.Mask")
			(clearance 0.381)
			(thermal_gap 0.381)
		)
		(pad "" np_thru_hole circle
			(at 1.022604 32.485076)
			(size 1.1176 1.1176)
			(drill 1.1176)
			(layers "*.Cu" "*.Mask")
			(clearance 0.381)
			(thermal_gap 0.381)
		)
		(pad "A1" smd rect
			(at 3.322574 -18.465038 270)
			(size 0.3556 1.2192)
			(layers "F.Cu" "F.Mask" "F.Paste")
			(net "GND")
		)
		(pad "A2" smd rect
			(at 3.322574 -17.86509 270)
			(size 0.3556 1.2192)
			(layers "F.Cu" "F.Mask" "F.Paste")
			(net "GND")
		)
		(pad "A3" smd rect
			(at 3.322574 -17.264888 270)
			(size 0.3556 1.2192)
			(layers "F.Cu" "F.Mask" "F.Paste")
			(net "GND")
		)
		(pad "A4" smd rect
			(at 3.322574 -16.66494 270)
			(size 0.3556 1.2192)
			(layers "F.Cu" "F.Mask" "F.Paste")
			(net "GND")
		)
		(pad "A5" smd rect
			(at 3.322574 -16.064992 270)
			(size 0.3556 1.2192)
			(layers "F.Cu" "F.Mask" "F.Paste")
			(net "GND")
		)
		(pad "A6" smd rect
			(at 3.322574 -15.465044 270)
			(size 0.3556 1.2192)
			(layers "F.Cu" "F.Mask" "F.Paste")
			(net "GND")
		)
		(pad "A7" smd rect
			(at 3.322574 -14.865096 270)
			(size 0.3556 1.2192)
			(layers "F.Cu" "F.Mask" "F.Paste")
			(net "SMB_NIC6_LS_SCL")
		)
		(pad "A8" smd rect
			(at 3.322574 -14.264894 270)
			(size 0.3556 1.2192)
			(layers "F.Cu" "F.Mask" "F.Paste")
			(net "SMB_NIC6_LS_SDA")
		)
		(pad "A9" smd rect
			(at 3.322574 -13.664946 270)
			(size 0.3556 1.2192)
			(layers "F.Cu" "F.Mask" "F.Paste")
			(net "RST_SMB_NIC6_MUX_ISO_R_N")
		)
		(pad "A10" smd rect
			(at 3.322574 -13.064998 270)
			(size 0.3556 1.2192)
			(layers "F.Cu" "F.Mask" "F.Paste")
			(net "GND")
		)
		(pad "A11" smd rect
			(at 3.322574 -12.46505 270)
			(size 0.3556 1.2192)
			(layers "F.Cu" "F.Mask" "F.Paste")
			(net "RST_NIC6_PERST1_R_N")
		)
		(pad "A12" smd rect
			(at 3.322574 -11.865102 270)
			(size 0.3556 1.2192)
			(layers "F.Cu" "F.Mask" "F.Paste")
			(net "PRSNTB2_NIC6_N")
		)
		(pad "A13" smd rect
			(at 3.322574 -11.2649 270)
			(size 0.3556 1.2192)
			(layers "F.Cu" "F.Mask" "F.Paste")
			(net "GND")
		)
		(pad "A14" smd rect
			(at 3.322574 -10.664952 270)
			(size 0.3556 1.2192)
			(layers "F.Cu" "F.Mask" "F.Paste")
			(net "Net_2653")
		)
		(pad "A15" smd rect
			(at 3.322574 -10.065004 270)
			(size 0.3556 1.2192)
			(layers "F.Cu" "F.Mask" "F.Paste")
			(net "Net_2656")
		)
		(pad "A16" smd rect
			(at 3.322574 -9.465056 270)
			(size 0.3556 1.2192)
			(layers "F.Cu" "F.Mask" "F.Paste")
			(net "GND")
		)
		(pad "A17" smd rect
			(at 3.322574 -8.865108 270)
			(size 0.3556 1.2192)
			(layers "F.Cu" "F.Mask" "F.Paste")
			(net "P5E_PEX3_STN1_RX_DN<31>")
		)
		(pad "A18" smd rect
			(at 3.322574 -8.264906 270)
			(size 0.3556 1.2192)
			(layers "F.Cu" "F.Mask" "F.Paste")
			(net "P5E_PEX3_STN1_RX_DP<31>")
		)
		(pad "A19" smd rect
			(at 3.322574 -7.664958 270)
			(size 0.3556 1.2192)
			(layers "F.Cu" "F.Mask" "F.Paste")
			(net "GND")
		)
		(pad "A20" smd rect
			(at 3.322574 -7.06501 270)
			(size 0.3556 1.2192)
			(layers "F.Cu" "F.Mask" "F.Paste")
			(net "P5E_PEX3_STN1_RX_DN<30>")
		)
		(pad "A21" smd rect
			(at 3.322574 -6.465062 270)
			(size 0.3556 1.2192)
			(layers "F.Cu" "F.Mask" "F.Paste")
			(net "P5E_PEX3_STN1_RX_DP<30>")
		)
		(pad "A22" smd rect
			(at 3.322574 -5.865114 270)
			(size 0.3556 1.2192)
			(layers "F.Cu" "F.Mask" "F.Paste")
			(net "GND")
		)
		(pad "A23" smd rect
			(at 3.322574 -5.264912 270)
			(size 0.3556 1.2192)
			(layers "F.Cu" "F.Mask" "F.Paste")
			(net "P5E_PEX3_STN1_RX_DN<29>")
		)
		(pad "A24" smd rect
			(at 3.322574 -4.664964 270)
			(size 0.3556 1.2192)
			(layers "F.Cu" "F.Mask" "F.Paste")
			(net "P5E_PEX3_STN1_RX_DP<29>")
		)
		(pad "A25" smd rect
			(at 3.322574 -4.065016 270)
			(size 0.3556 1.2192)
			(layers "F.Cu" "F.Mask" "F.Paste")
			(net "GND")
		)
		(pad "A26" smd rect
			(at 3.322574 -3.465068 270)
			(size 0.3556 1.2192)
			(layers "F.Cu" "F.Mask" "F.Paste")
			(net "P5E_PEX3_STN1_RX_DN<28>")
		)
		(pad "A27" smd rect
			(at 3.322574 -2.86512 270)
			(size 0.3556 1.2192)
			(layers "F.Cu" "F.Mask" "F.Paste")
			(net "P5E_PEX3_STN1_RX_DP<28>")
		)
		(pad "A28" smd rect
			(at 3.322574 -2.264918 270)
			(size 0.3556 1.2192)
			(layers "F.Cu" "F.Mask" "F.Paste")
			(net "GND")
		)
		(pad "A29" smd rect
			(at 3.322574 1.74498 270)
			(size 0.3556 1.2192)
			(layers "F.Cu" "F.Mask" "F.Paste")
			(net "GND")
		)
		(pad "A30" smd rect
			(at 3.322574 2.344928 270)
			(size 0.3556 1.2192)
			(layers "F.Cu" "F.Mask" "F.Paste")
			(net "P5E_PEX3_STN1_RX_DN<27>")
		)
		(pad "A31" smd rect
			(at 3.322574 2.944876 270)
			(size 0.3556 1.2192)
			(layers "F.Cu" "F.Mask" "F.Paste")
			(net "P5E_PEX3_STN1_RX_DP<27>")
		)
		(pad "A32" smd rect
			(at 3.322574 3.545078 270)
			(size 0.3556 1.2192)
			(layers "F.Cu" "F.Mask" "F.Paste")
			(net "GND")
		)
		(pad "A33" smd rect
			(at 3.322574 4.145026 270)
			(size 0.3556 1.2192)
			(layers "F.Cu" "F.Mask" "F.Paste")
			(net "P5E_PEX3_STN1_RX_DN<26>")
		)
		(pad "A34" smd rect
			(at 3.322574 4.744974 270)
			(size 0.3556 1.2192)
			(layers "F.Cu" "F.Mask" "F.Paste")
			(net "P5E_PEX3_STN1_RX_DP<26>")
		)
		(pad "A35" smd rect
			(at 3.322574 5.344922 270)
			(size 0.3556 1.2192)
			(layers "F.Cu" "F.Mask" "F.Paste")
			(net "GND")
		)
		(pad "A36" smd rect
			(at 3.322574 5.945124 270)
			(size 0.3556 1.2192)
			(layers "F.Cu" "F.Mask" "F.Paste")
			(net "P5E_PEX3_STN1_RX_DN<25>")
		)
		(pad "A37" smd rect
			(at 3.322574 6.545072 270)
			(size 0.3556 1.2192)
			(layers "F.Cu" "F.Mask" "F.Paste")
			(net "P5E_PEX3_STN1_RX_DP<25>")
		)
		(pad "A38" smd rect
			(at 3.322574 7.14502 270)
			(size 0.3556 1.2192)
			(layers "F.Cu" "F.Mask" "F.Paste")
			(net "GND")
		)
		(pad "A39" smd rect
			(at 3.322574 7.744968 270)
			(size 0.3556 1.2192)
			(layers "F.Cu" "F.Mask" "F.Paste")
			(net "P5E_PEX3_STN1_RX_DN<24>")
		)
		(pad "A40" smd rect
			(at 3.322574 8.344916 270)
			(size 0.3556 1.2192)
			(layers "F.Cu" "F.Mask" "F.Paste")
			(net "P5E_PEX3_STN1_RX_DP<24>")
		)
		(pad "A41" smd rect
			(at 3.322574 8.945118 270)
			(size 0.3556 1.2192)
			(layers "F.Cu" "F.Mask" "F.Paste")
			(net "GND")
		)
		(pad "A42" smd rect
			(at 3.322574 9.545066 270)
			(size 0.3556 1.2192)
			(layers "F.Cu" "F.Mask" "F.Paste")
			(net "PRSNTB1_NIC6_N")
		)
		(pad "A43" smd rect
			(at 3.322574 14.454886 270)
			(size 0.3556 1.2192)
			(layers "F.Cu" "F.Mask" "F.Paste")
			(net "GND")
		)
		(pad "A44" smd rect
			(at 3.322574 15.055088 270)
			(size 0.3556 1.2192)
			(layers "F.Cu" "F.Mask" "F.Paste")
			(net "P5E_PEX3_STN1_RX_DN<23>")
		)
		(pad "A45" smd rect
			(at 3.322574 15.655036 270)
			(size 0.3556 1.2192)
			(layers "F.Cu" "F.Mask" "F.Paste")
			(net "P5E_PEX3_STN1_RX_DP<23>")
		)
		(pad "A46" smd rect
			(at 3.322574 16.254984 270)
			(size 0.3556 1.2192)
			(layers "F.Cu" "F.Mask" "F.Paste")
			(net "GND")
		)
		(pad "A47" smd rect
			(at 3.322574 16.854932 270)
			(size 0.3556 1.2192)
			(layers "F.Cu" "F.Mask" "F.Paste")
			(net "P5E_PEX3_STN1_RX_DN<22>")
		)
		(pad "A48" smd rect
			(at 3.322574 17.45488 270)
			(size 0.3556 1.2192)
			(layers "F.Cu" "F.Mask" "F.Paste")
			(net "P5E_PEX3_STN1_RX_DP<22>")
		)
		(pad "A49" smd rect
			(at 3.322574 18.055082 270)
			(size 0.3556 1.2192)
			(layers "F.Cu" "F.Mask" "F.Paste")
			(net "GND")
		)
		(pad "A50" smd rect
			(at 3.322574 18.65503 270)
			(size 0.3556 1.2192)
			(layers "F.Cu" "F.Mask" "F.Paste")
			(net "P5E_PEX3_STN1_RX_DN<21>")
		)
		(pad "A51" smd rect
			(at 3.322574 19.254978 270)
			(size 0.3556 1.2192)
			(layers "F.Cu" "F.Mask" "F.Paste")
			(net "P5E_PEX3_STN1_RX_DP<21>")
		)
		(pad "A52" smd rect
			(at 3.322574 19.854926 270)
			(size 0.3556 1.2192)
			(layers "F.Cu" "F.Mask" "F.Paste")
			(net "GND")
		)
		(pad "A53" smd rect
			(at 3.322574 20.455128 270)
			(size 0.3556 1.2192)
			(layers "F.Cu" "F.Mask" "F.Paste")
			(net "P5E_PEX3_STN1_RX_DN<20>")
		)
		(pad "A54" smd rect
			(at 3.322574 21.055076 270)
			(size 0.3556 1.2192)
			(layers "F.Cu" "F.Mask" "F.Paste")
			(net "P5E_PEX3_STN1_RX_DP<20>")
		)
		(pad "A55" smd rect
			(at 3.322574 21.655024 270)
			(size 0.3556 1.2192)
			(layers "F.Cu" "F.Mask" "F.Paste")
			(net "GND")
		)
		(pad "A56" smd rect
			(at 3.322574 22.254972 270)
			(size 0.3556 1.2192)
			(layers "F.Cu" "F.Mask" "F.Paste")
			(net "P5E_PEX3_STN1_RX_DN<19>")
		)
		(pad "A57" smd rect
			(at 3.322574 22.85492 270)
			(size 0.3556 1.2192)
			(layers "F.Cu" "F.Mask" "F.Paste")
			(net "P5E_PEX3_STN1_RX_DP<19>")
		)
		(pad "A58" smd rect
			(at 3.322574 23.455122 270)
			(size 0.3556 1.2192)
			(layers "F.Cu" "F.Mask" "F.Paste")
			(net "GND")
		)
		(pad "A59" smd rect
			(at 3.322574 24.05507 270)
			(size 0.3556 1.2192)
			(layers "F.Cu" "F.Mask" "F.Paste")
			(net "P5E_PEX3_STN1_RX_DN<18>")
		)
		(pad "A60" smd rect
			(at 3.322574 24.655018 270)
			(size 0.3556 1.2192)
			(layers "F.Cu" "F.Mask" "F.Paste")
			(net "P5E_PEX3_STN1_RX_DP<18>")
		)
		(pad "A61" smd rect
			(at 3.322574 25.254966 270)
			(size 0.3556 1.2192)
			(layers "F.Cu" "F.Mask" "F.Paste")
			(net "GND")
		)
		(pad "A62" smd rect
			(at 3.322574 25.854914 270)
			(size 0.3556 1.2192)
			(layers "F.Cu" "F.Mask" "F.Paste")
			(net "P5E_PEX3_STN1_RX_DN<17>")
		)
		(pad "A63" smd rect
			(at 3.322574 26.455116 270)
			(size 0.3556 1.2192)
			(layers "F.Cu" "F.Mask" "F.Paste")
			(net "P5E_PEX3_STN1_RX_DP<17>")
		)
		(pad "A64" smd rect
			(at 3.322574 27.055064 270)
			(size 0.3556 1.2192)
			(layers "F.Cu" "F.Mask" "F.Paste")
			(net "GND")
		)
		(pad "A65" smd rect
			(at 3.322574 27.655012 270)
			(size 0.3556 1.2192)
			(layers "F.Cu" "F.Mask" "F.Paste")
			(net "P5E_PEX3_STN1_RX_DN<16>")
		)
		(pad "A66" smd rect
			(at 3.322574 28.25496 270)
			(size 0.3556 1.2192)
			(layers "F.Cu" "F.Mask" "F.Paste")
			(net "P5E_PEX3_STN1_RX_DP<16>")
		)
		(pad "A67" smd rect
			(at 3.322574 28.854908 270)
			(size 0.3556 1.2192)
			(layers "F.Cu" "F.Mask" "F.Paste")
			(net "GND")
		)
		(pad "A68" smd rect
			(at 3.322574 29.45511 270)
			(size 0.3556 1.2192)
			(layers "F.Cu" "F.Mask" "F.Paste")
			(net "Net_2661")
		)
		(pad "A69" smd rect
			(at 3.322574 30.055058 270)
			(size 0.3556 1.2192)
			(layers "F.Cu" "F.Mask" "F.Paste")
			(net "Net_2662")
		)
		(pad "A70" smd rect
			(at 3.322574 30.655006 270)
			(size 0.3556 1.2192)
			(layers "F.Cu" "F.Mask" "F.Paste")
			(net "NIC6_PWRBRK_R_N")
		)
		(pad "B1" smd rect
			(at -1.27762 -18.465038 270)
			(size 0.3556 1.2192)
			(layers "F.Cu" "F.Mask" "F.Paste")
			(net "P12V_NIC6")
		)
		(pad "B2" smd rect
			(at -1.27762 -17.86509 270)
			(size 0.3556 1.2192)
			(layers "F.Cu" "F.Mask" "F.Paste")
			(net "P12V_NIC6")
		)
		(pad "B3" smd rect
			(at -1.27762 -17.264888 270)
			(size 0.3556 1.2192)
			(layers "F.Cu" "F.Mask" "F.Paste")
			(net "P12V_NIC6")
		)
		(pad "B4" smd rect
			(at -1.27762 -16.66494 270)
			(size 0.3556 1.2192)
			(layers "F.Cu" "F.Mask" "F.Paste")
			(net "P12V_NIC6")
		)
		(pad "B5" smd rect
			(at -1.27762 -16.064992 270)
			(size 0.3556 1.2192)
			(layers "F.Cu" "F.Mask" "F.Paste")
			(net "P12V_NIC6")
		)
		(pad "B6" smd rect
			(at -1.27762 -15.465044 270)
			(size 0.3556 1.2192)
			(layers "F.Cu" "F.Mask" "F.Paste")
			(net "P12V_NIC6")
		)
		(pad "B7" smd rect
			(at -1.27762 -14.865096 270)
			(size 0.3556 1.2192)
			(layers "F.Cu" "F.Mask" "F.Paste")
			(net "NIC6_BIF0_N")
		)
		(pad "B8" smd rect
			(at -1.27762 -14.264894 270)
			(size 0.3556 1.2192)
			(layers "F.Cu" "F.Mask" "F.Paste")
			(net "NIC6_BIF1_N")
		)
		(pad "B9" smd rect
			(at -1.27762 -13.664946 270)
			(size 0.3556 1.2192)
			(layers "F.Cu" "F.Mask" "F.Paste")
			(net "NIC6_BIF2_N")
		)
		(pad "B10" smd rect
			(at -1.27762 -13.064998 270)
			(size 0.3556 1.2192)
			(layers "F.Cu" "F.Mask" "F.Paste")
			(net "RST_NIC6_PERST0_R_N")
		)
		(pad "B11" smd rect
			(at -1.27762 -12.46505 270)
			(size 0.3556 1.2192)
			(layers "F.Cu" "F.Mask" "F.Paste")
			(net "P3V3_NIC6")
		)
		(pad "B12" smd rect
			(at -1.27762 -11.865102 270)
			(size 0.3556 1.2192)
			(layers "F.Cu" "F.Mask" "F.Paste")
			(net "NIC6_AUX_PWR_EN_R")
		)
		(pad "B13" smd rect
			(at -1.27762 -11.2649 270)
			(size 0.3556 1.2192)
			(layers "F.Cu" "F.Mask" "F.Paste")
			(net "GND")
		)
		(pad "B14" smd rect
			(at -1.27762 -10.664952 270)
			(size 0.3556 1.2192)
			(layers "F.Cu" "F.Mask" "F.Paste")
			(net "CLK_100M_DB2000QL_NIC6_R_DN")
		)
		(pad "B15" smd rect
			(at -1.27762 -10.065004 270)
			(size 0.3556 1.2192)
			(layers "F.Cu" "F.Mask" "F.Paste")
			(net "CLK_100M_DB2000QL_NIC6_R_DP")
		)
		(pad "B16" smd rect
			(at -1.27762 -9.465056 270)
			(size 0.3556 1.2192)
			(layers "F.Cu" "F.Mask" "F.Paste")
			(net "GND")
		)
		(pad "B17" smd rect
			(at -1.27762 -8.865108 270)
			(size 0.3556 1.2192)
			(layers "F.Cu" "F.Mask" "F.Paste")
			(net "P5E_PEX3_STN1_TX_C_DP<31>")
		)
		(pad "B18" smd rect
			(at -1.27762 -8.264906 270)
			(size 0.3556 1.2192)
			(layers "F.Cu" "F.Mask" "F.Paste")
			(net "P5E_PEX3_STN1_TX_C_DN<31>")
		)
		(pad "B19" smd rect
			(at -1.27762 -7.664958 270)
			(size 0.3556 1.2192)
			(layers "F.Cu" "F.Mask" "F.Paste")
			(net "GND")
		)
		(pad "B20" smd rect
			(at -1.27762 -7.06501 270)
			(size 0.3556 1.2192)
			(layers "F.Cu" "F.Mask" "F.Paste")
			(net "P5E_PEX3_STN1_TX_C_DN<30>")
		)
		(pad "B21" smd rect
			(at -1.27762 -6.465062 270)
			(size 0.3556 1.2192)
			(layers "F.Cu" "F.Mask" "F.Paste")
			(net "P5E_PEX3_STN1_TX_C_DP<30>")
		)
		(pad "B22" smd rect
			(at -1.27762 -5.865114 270)
			(size 0.3556 1.2192)
			(layers "F.Cu" "F.Mask" "F.Paste")
			(net "GND")
		)
		(pad "B23" smd rect
			(at -1.27762 -5.264912 270)
			(size 0.3556 1.2192)
			(layers "F.Cu" "F.Mask" "F.Paste")
			(net "P5E_PEX3_STN1_TX_C_DP<29>")
		)
		(pad "B24" smd rect
			(at -1.27762 -4.664964 270)
			(size 0.3556 1.2192)
			(layers "F.Cu" "F.Mask" "F.Paste")
			(net "P5E_PEX3_STN1_TX_C_DN<29>")
		)
		(pad "B25" smd rect
			(at -1.27762 -4.065016 270)
			(size 0.3556 1.2192)
			(layers "F.Cu" "F.Mask" "F.Paste")
			(net "GND")
		)
		(pad "B26" smd rect
			(at -1.27762 -3.465068 270)
			(size 0.3556 1.2192)
			(layers "F.Cu" "F.Mask" "F.Paste")
			(net "P5E_PEX3_STN1_TX_C_DN<28>")
		)
		(pad "B27" smd rect
			(at -1.27762 -2.86512 270)
			(size 0.3556 1.2192)
			(layers "F.Cu" "F.Mask" "F.Paste")
			(net "P5E_PEX3_STN1_TX_C_DP<28>")
		)
		(pad "B28" smd rect
			(at -1.27762 -2.264918 270)
			(size 0.3556 1.2192)
			(layers "F.Cu" "F.Mask" "F.Paste")
			(net "GND")
		)
		(pad "B29" smd rect
			(at -1.27762 1.74498 270)
			(size 0.3556 1.2192)
			(layers "F.Cu" "F.Mask" "F.Paste")
			(net "GND")
		)
		(pad "B30" smd rect
			(at -1.27762 2.344928 270)
			(size 0.3556 1.2192)
			(layers "F.Cu" "F.Mask" "F.Paste")
			(net "P5E_PEX3_STN1_TX_C_DP<27>")
		)
		(pad "B31" smd rect
			(at -1.27762 2.944876 270)
			(size 0.3556 1.2192)
			(layers "F.Cu" "F.Mask" "F.Paste")
			(net "P5E_PEX3_STN1_TX_C_DN<27>")
		)
		(pad "B32" smd rect
			(at -1.27762 3.545078 270)
			(size 0.3556 1.2192)
			(layers "F.Cu" "F.Mask" "F.Paste")
			(net "GND")
		)
		(pad "B33" smd rect
			(at -1.27762 4.145026 270)
			(size 0.3556 1.2192)
			(layers "F.Cu" "F.Mask" "F.Paste")
			(net "P5E_PEX3_STN1_TX_C_DN<26>")
		)
		(pad "B34" smd rect
			(at -1.27762 4.744974 270)
			(size 0.3556 1.2192)
			(layers "F.Cu" "F.Mask" "F.Paste")
			(net "P5E_PEX3_STN1_TX_C_DP<26>")
		)
		(pad "B35" smd rect
			(at -1.27762 5.344922 270)
			(size 0.3556 1.2192)
			(layers "F.Cu" "F.Mask" "F.Paste")
			(net "GND")
		)
		(pad "B36" smd rect
			(at -1.27762 5.945124 270)
			(size 0.3556 1.2192)
			(layers "F.Cu" "F.Mask" "F.Paste")
			(net "P5E_PEX3_STN1_TX_C_DP<25>")
		)
		(pad "B37" smd rect
			(at -1.27762 6.545072 270)
			(size 0.3556 1.2192)
			(layers "F.Cu" "F.Mask" "F.Paste")
			(net "P5E_PEX3_STN1_TX_C_DN<25>")
		)
		(pad "B38" smd rect
			(at -1.27762 7.14502 270)
			(size 0.3556 1.2192)
			(layers "F.Cu" "F.Mask" "F.Paste")
			(net "GND")
		)
		(pad "B39" smd rect
			(at -1.27762 7.744968 270)
			(size 0.3556 1.2192)
			(layers "F.Cu" "F.Mask" "F.Paste")
			(net "P5E_PEX3_STN1_TX_C_DN<24>")
		)
		(pad "B40" smd rect
			(at -1.27762 8.344916 270)
			(size 0.3556 1.2192)
			(layers "F.Cu" "F.Mask" "F.Paste")
			(net "P5E_PEX3_STN1_TX_C_DP<24>")
		)
		(pad "B41" smd rect
			(at -1.27762 8.945118 270)
			(size 0.3556 1.2192)
			(layers "F.Cu" "F.Mask" "F.Paste")
			(net "GND")
		)
		(pad "B42" smd rect
			(at -1.27762 9.545066 270)
			(size 0.3556 1.2192)
			(layers "F.Cu" "F.Mask" "F.Paste")
			(net "PRSNTB0_NIC6_N")
		)
		(pad "B43" smd rect
			(at -1.27762 14.454886 270)
			(size 0.3556 1.2192)
			(layers "F.Cu" "F.Mask" "F.Paste")
			(net "GND")
		)
		(pad "B44" smd rect
			(at -1.27762 15.055088 270)
			(size 0.3556 1.2192)
			(layers "F.Cu" "F.Mask" "F.Paste")
			(net "P5E_PEX3_STN1_TX_C_DP<23>")
		)
		(pad "B45" smd rect
			(at -1.27762 15.655036 270)
			(size 0.3556 1.2192)
			(layers "F.Cu" "F.Mask" "F.Paste")
			(net "P5E_PEX3_STN1_TX_C_DN<23>")
		)
		(pad "B46" smd rect
			(at -1.27762 16.254984 270)
			(size 0.3556 1.2192)
			(layers "F.Cu" "F.Mask" "F.Paste")
			(net "GND")
		)
		(pad "B47" smd rect
			(at -1.27762 16.854932 270)
			(size 0.3556 1.2192)
			(layers "F.Cu" "F.Mask" "F.Paste")
			(net "P5E_PEX3_STN1_TX_C_DN<22>")
		)
		(pad "B48" smd rect
			(at -1.27762 17.45488 270)
			(size 0.3556 1.2192)
			(layers "F.Cu" "F.Mask" "F.Paste")
			(net "P5E_PEX3_STN1_TX_C_DP<22>")
		)
		(pad "B49" smd rect
			(at -1.27762 18.055082 270)
			(size 0.3556 1.2192)
			(layers "F.Cu" "F.Mask" "F.Paste")
			(net "GND")
		)
		(pad "B50" smd rect
			(at -1.27762 18.65503 270)
			(size 0.3556 1.2192)
			(layers "F.Cu" "F.Mask" "F.Paste")
			(net "P5E_PEX3_STN1_TX_C_DP<21>")
		)
		(pad "B51" smd rect
			(at -1.27762 19.254978 270)
			(size 0.3556 1.2192)
			(layers "F.Cu" "F.Mask" "F.Paste")
			(net "P5E_PEX3_STN1_TX_C_DN<21>")
		)
		(pad "B52" smd rect
			(at -1.27762 19.854926 270)
			(size 0.3556 1.2192)
			(layers "F.Cu" "F.Mask" "F.Paste")
			(net "GND")
		)
		(pad "B53" smd rect
			(at -1.27762 20.455128 270)
			(size 0.3556 1.2192)
			(layers "F.Cu" "F.Mask" "F.Paste")
			(net "P5E_PEX3_STN1_TX_C_DN<20>")
		)
		(pad "B54" smd rect
			(at -1.27762 21.055076 270)
			(size 0.3556 1.2192)
			(layers "F.Cu" "F.Mask" "F.Paste")
			(net "P5E_PEX3_STN1_TX_C_DP<20>")
		)
		(pad "B55" smd rect
			(at -1.27762 21.655024 270)
			(size 0.3556 1.2192)
			(layers "F.Cu" "F.Mask" "F.Paste")
			(net "GND")
		)
		(pad "B56" smd rect
			(at -1.27762 22.254972 270)
			(size 0.3556 1.2192)
			(layers "F.Cu" "F.Mask" "F.Paste")
			(net "P5E_PEX3_STN1_TX_C_DP<19>")
		)
		(pad "B57" smd rect
			(at -1.27762 22.85492 270)
			(size 0.3556 1.2192)
			(layers "F.Cu" "F.Mask" "F.Paste")
			(net "P5E_PEX3_STN1_TX_C_DN<19>")
		)
		(pad "B58" smd rect
			(at -1.27762 23.455122 270)
			(size 0.3556 1.2192)
			(layers "F.Cu" "F.Mask" "F.Paste")
			(net "GND")
		)
		(pad "B59" smd rect
			(at -1.27762 24.05507 270)
			(size 0.3556 1.2192)
			(layers "F.Cu" "F.Mask" "F.Paste")
			(net "P5E_PEX3_STN1_TX_C_DN<18>")
		)
		(pad "B60" smd rect
			(at -1.27762 24.655018 270)
			(size 0.3556 1.2192)
			(layers "F.Cu" "F.Mask" "F.Paste")
			(net "P5E_PEX3_STN1_TX_C_DP<18>")
		)
		(pad "B61" smd rect
			(at -1.27762 25.254966 270)
			(size 0.3556 1.2192)
			(layers "F.Cu" "F.Mask" "F.Paste")
			(net "GND")
		)
		(pad "B62" smd rect
			(at -1.27762 25.854914 270)
			(size 0.3556 1.2192)
			(layers "F.Cu" "F.Mask" "F.Paste")
			(net "P5E_PEX3_STN1_TX_C_DP<17>")
		)
		(pad "B63" smd rect
			(at -1.27762 26.455116 270)
			(size 0.3556 1.2192)
			(layers "F.Cu" "F.Mask" "F.Paste")
			(net "P5E_PEX3_STN1_TX_C_DN<17>")
		)
		(pad "B64" smd rect
			(at -1.27762 27.055064 270)
			(size 0.3556 1.2192)
			(layers "F.Cu" "F.Mask" "F.Paste")
			(net "GND")
		)
		(pad "B65" smd rect
			(at -1.27762 27.655012 270)
			(size 0.3556 1.2192)
			(layers "F.Cu" "F.Mask" "F.Paste")
			(net "P5E_PEX3_STN1_TX_C_DN<16>")
		)
		(pad "B66" smd rect
			(at -1.27762 28.25496 270)
			(size 0.3556 1.2192)
			(layers "F.Cu" "F.Mask" "F.Paste")
			(net "P5E_PEX3_STN1_TX_C_DP<16>")
		)
		(pad "B67" smd rect
			(at -1.27762 28.854908 270)
			(size 0.3556 1.2192)
			(layers "F.Cu" "F.Mask" "F.Paste")
			(net "GND")
		)
		(pad "B68" smd rect
			(at -1.27762 29.45511 270)
			(size 0.3556 1.2192)
			(layers "F.Cu" "F.Mask" "F.Paste")
			(net "Net_2659")
		)
		(pad "B69" smd rect
			(at -1.27762 30.055058 270)
			(size 0.3556 1.2192)
			(layers "F.Cu" "F.Mask" "F.Paste")
			(net "Net_2660")
		)
		(pad "B70" smd rect
			(at -1.27762 30.655006 270)
			(size 0.3556 1.2192)
			(layers "F.Cu" "F.Mask" "F.Paste")
			(net "PRSNTB3_NIC6_N")
		)
		(pad "G1" thru_hole oval
			(at 1.022604 -34.034984 270)
			(size 1.6256 3.4798)
			(drill oval 1.1176 2.4638)
			(layers "*.Cu" "*.Mask")
			(remove_unused_layers no)
			(net "GND")
			(clearance 0.127)
			(thermal_gap 0.127)
		)
		(pad "G2" thru_hole oval
			(at 1.022604 -20.625054 270)
			(size 1.6256 3.4798)
			(drill oval 1.1176 2.4638)
			(layers "*.Cu" "*.Mask")
			(remove_unused_layers no)
			(net "GND")
			(clearance 0.127)
			(thermal_gap 0.127)
		)
		(pad "G3" thru_hole oval
			(at 1.022604 -0.255016 270)
			(size 1.6256 3.4798)
			(drill oval 1.1176 2.4638)
			(layers "*.Cu" "*.Mask")
			(remove_unused_layers no)
			(net "GND")
			(clearance 0.127)
			(thermal_gap 0.127)
		)
		(pad "G4" thru_hole oval
			(at 1.022604 12.005056 270)
			(size 1.6256 3.4798)
			(drill oval 1.1176 2.4638)
			(layers "*.Cu" "*.Mask")
			(remove_unused_layers no)
			(net "GND")
			(clearance 0.127)
			(thermal_gap 0.127)
		)
		(pad "G5" thru_hole oval
			(at 1.022604 34.034984 270)
			(size 1.5748 3.4798)
			(drill oval 1.1176 2.4638)
			(layers "*.Cu" "*.Mask")
			(remove_unused_layers no)
			(net "GND")
			(clearance 0.1524)
			(thermal_gap 0.1524)
		)
		(pad "G6" thru_hole circle
			(at -3.16738 -20.625054)
			(size 1.6256 1.6256)
			(drill 1.1176)
			(layers "*.Cu" "*.Mask")
			(remove_unused_layers no)
			(net "GND")
			(clearance 0)
		)
		(pad "G7" thru_hole circle
			(at -3.16738 12.005056)
			(size 1.6256 1.6256)
			(drill 1.1176)
			(layers "*.Cu" "*.Mask")
			(remove_unused_layers no)
			(net "GND")
			(clearance 0)
		)
		(pad "G8" thru_hole circle
			(at 4.20243 -20.625054)
			(size 1.6256 1.6256)
			(drill 1.1176)
			(layers "*.Cu" "*.Mask")
			(remove_unused_layers no)
			(net "GND")
			(clearance 0)
		)
		(pad "G9" thru_hole circle
			(at 4.20243 12.005056)
			(size 1.6256 1.6256)
			(drill 1.1176)
			(layers "*.Cu" "*.Mask")
			(remove_unused_layers no)
			(net "GND")
			(clearance 0)
		)
		(pad "OA1" smd rect
			(at 3.322574 -30.660086 270)
			(size 0.3556 1.2192)
			(layers "F.Cu" "F.Mask" "F.Paste")
			(net "RST_NIC6_PERST2_R_N")
		)
		(pad "OA2" smd rect
			(at 3.322574 -30.059884 270)
			(size 0.3556 1.2192)
			(layers "F.Cu" "F.Mask" "F.Paste")
			(net "RST_NIC6_PERST3_R_N")
		)
		(pad "OA3" smd rect
			(at 3.322574 -29.459936 270)
			(size 0.3556 1.2192)
			(layers "F.Cu" "F.Mask" "F.Paste")
			(net "Net_2663")
		)
		(pad "OA4" smd rect
			(at 3.322574 -28.859988 270)
			(size 0.3556 1.2192)
			(layers "F.Cu" "F.Mask" "F.Paste")
			(net "NIC6_RBT_ARB_IN")
		)
		(pad "OA5" smd rect
			(at 3.322574 -28.26004 270)
			(size 0.3556 1.2192)
			(layers "F.Cu" "F.Mask" "F.Paste")
			(net "NIC6_RBT_ARB_OUT")
		)
		(pad "OA6" smd rect
			(at 3.322574 -27.660092 270)
			(size 0.3556 1.2192)
			(layers "F.Cu" "F.Mask" "F.Paste")
			(net "NIC6_SLOT_ID1")
		)
		(pad "OA7" smd rect
			(at 3.322574 -27.05989 270)
			(size 0.3556 1.2192)
			(layers "F.Cu" "F.Mask" "F.Paste")
			(net "NCSI_NIC6_TX_EN")
		)
		(pad "OA8" smd rect
			(at 3.322574 -26.459942 270)
			(size 0.3556 1.2192)
			(layers "F.Cu" "F.Mask" "F.Paste")
			(net "NCSI_NIC6_TXD1")
		)
		(pad "OA9" smd rect
			(at 3.322574 -25.859994 270)
			(size 0.3556 1.2192)
			(layers "F.Cu" "F.Mask" "F.Paste")
			(net "NCSI_NIC6_TXD0")
		)
		(pad "OA10" smd rect
			(at 3.322574 -25.260046 270)
			(size 0.3556 1.2192)
			(layers "F.Cu" "F.Mask" "F.Paste")
			(net "GND")
		)
		(pad "OA11" smd rect
			(at 3.322574 -24.660098 270)
			(size 0.3556 1.2192)
			(layers "F.Cu" "F.Mask" "F.Paste")
			(net "Net_2655")
		)
		(pad "OA12" smd rect
			(at 3.322574 -24.059896 270)
			(size 0.3556 1.2192)
			(layers "F.Cu" "F.Mask" "F.Paste")
			(net "Net_2658")
		)
		(pad "OA13" smd rect
			(at 3.322574 -23.459948 270)
			(size 0.3556 1.2192)
			(layers "F.Cu" "F.Mask" "F.Paste")
			(net "GND")
		)
		(pad "OA14" smd rect
			(at 3.322574 -22.86 270)
			(size 0.3556 1.2192)
			(layers "F.Cu" "F.Mask" "F.Paste")
			(net "CLK_50M_NIC6_RBT_REF")
		)
		(pad "OB1" smd rect
			(at -1.27762 -30.660086 270)
			(size 0.3556 1.2192)
			(layers "F.Cu" "F.Mask" "F.Paste")
			(net "PWRGD_NIC6_PWR_GOOD")
		)
		(pad "OB2" smd rect
			(at -1.27762 -30.059884 270)
			(size 0.3556 1.2192)
			(layers "F.Cu" "F.Mask" "F.Paste")
			(net "NIC6_MAIN_PWR_EN_R")
		)
		(pad "OB3" smd rect
			(at -1.27762 -29.459936 270)
			(size 0.3556 1.2192)
			(layers "F.Cu" "F.Mask" "F.Paste")
			(net "NIC6_LD_N")
		)
		(pad "OB4" smd rect
			(at -1.27762 -28.859988 270)
			(size 0.3556 1.2192)
			(layers "F.Cu" "F.Mask" "F.Paste")
			(net "NIC6_DATA_IN")
		)
		(pad "OB5" smd rect
			(at -1.27762 -28.26004 270)
			(size 0.3556 1.2192)
			(layers "F.Cu" "F.Mask" "F.Paste")
			(net "NIC6_DATA_OUT")
		)
		(pad "OB6" smd rect
			(at -1.27762 -27.660092 270)
			(size 0.3556 1.2192)
			(layers "F.Cu" "F.Mask" "F.Paste")
			(net "NIC6_CLK")
		)
		(pad "OB7" smd rect
			(at -1.27762 -27.05989 270)
			(size 0.3556 1.2192)
			(layers "F.Cu" "F.Mask" "F.Paste")
			(net "NIC6_SLOT_ID0")
		)
		(pad "OB8" smd rect
			(at -1.27762 -26.459942 270)
			(size 0.3556 1.2192)
			(layers "F.Cu" "F.Mask" "F.Paste")
			(net "NCSI_NIC6_RXD1")
		)
		(pad "OB9" smd rect
			(at -1.27762 -25.859994 270)
			(size 0.3556 1.2192)
			(layers "F.Cu" "F.Mask" "F.Paste")
			(net "NCSI_NIC6_RXD0")
		)
		(pad "OB10" smd rect
			(at -1.27762 -25.260046 270)
			(size 0.3556 1.2192)
			(layers "F.Cu" "F.Mask" "F.Paste")
			(net "GND")
		)
		(pad "OB11" smd rect
			(at -1.27762 -24.660098 270)
			(size 0.3556 1.2192)
			(layers "F.Cu" "F.Mask" "F.Paste")
			(net "Net_2654")
		)
		(pad "OB12" smd rect
			(at -1.27762 -24.059896 270)
			(size 0.3556 1.2192)
			(layers "F.Cu" "F.Mask" "F.Paste")
			(net "Net_2657")
		)
		(pad "OB13" smd rect
			(at -1.27762 -23.459948 270)
			(size 0.3556 1.2192)
			(layers "F.Cu" "F.Mask" "F.Paste")
			(net "GND")
		)
		(pad "OB14" smd rect
			(at -1.27762 -22.86 270)
			(size 0.3556 1.2192)
			(layers "F.Cu" "F.Mask" "F.Paste")
			(net "NCSI_NIC6_CRS_DV")
		)
		(zone
			(layers "F.Cu" "B.Cu" "In1.Cu" "In2.Cu" "In3.Cu" "In4.Cu" "In5.Cu" "In6.Cu"
				"In7.Cu" "In8.Cu" "In9.Cu" "In10.Cu" "In11.Cu" "In12.Cu" "In13.Cu" "In14.Cu"
				"In15.Cu" "In16.Cu"
			)
			(hatch none 0.5)
			(connect_pads
				(clearance 0)
			)
			(min_thickness 0.25)
			(keepout
				(tracks not_allowed)
				(vias allowed)
				(pads allowed)
				(copperpour not_allowed)
				(footprints allowed)
			)
			(placement
				(enabled no)
				(sheetname "")
			)
			(fill
				(thermal_gap 0.5)
				(thermal_bridge_width 0.5)
				(island_removal_mode 0)
			)
			(polygon
				(pts
					(arc
						(start 395.95933 -160.1851)
						(mid 393.82573 -160.1851)
						(end 395.95933 -160.1851)
					)
				)
			)
		)
		(zone
			(layers "F.Cu" "B.Cu" "In1.Cu" "In2.Cu" "In3.Cu" "In4.Cu" "In5.Cu" "In6.Cu"
				"In7.Cu" "In8.Cu" "In9.Cu" "In10.Cu" "In11.Cu" "In12.Cu" "In13.Cu" "In14.Cu"
				"In15.Cu" "In16.Cu"
			)
			(hatch none 0.5)
			(connect_pads
				(clearance 0)
			)
			(min_thickness 0.25)
			(keepout
				(tracks not_allowed)
				(vias allowed)
				(pads allowed)
				(copperpour not_allowed)
				(footprints allowed)
			)
			(placement
				(enabled no)
				(sheetname "")
			)
			(fill
				(thermal_gap 0.5)
				(thermal_bridge_width 0.5)
				(island_removal_mode 0)
			)
			(polygon
				(pts
					(arc
						(start 397.70939 -95.214948)
						(mid 395.57579 -95.214948)
						(end 397.70939 -95.214948)
					)
				)
			)
		)
	)
	(footprint ""
		(layer "F.Cu")
		(at 269.750286 -252.356874 -90)
		(property "Reference" "R1366"
			(at 0 0 270)
			(layer "F.SilkS")
			(hide yes)
			(effects
				(font
					(size 1.27 1.27)
				)
			)
		)
		(property "Value" ""
			(at 0 0 270)
			(layer "F.Fab")
			(effects
				(font
					(size 1.27 1.27)
				)
			)
		)
		(duplicate_pad_numbers_are_jumpers no)
		(fp_line
			(start -0.7874 0.4064)
			(end -0.7874 -0.4064)
			(stroke
				(width 0.1524)
				(type default)
			)
			(layer "F.SilkS")
		)
		(fp_line
			(start 0.7874 0.4064)
			(end -0.7874 0.4064)
			(stroke
				(width 0.1524)
				(type default)
			)
			(layer "F.SilkS")
		)
		(fp_line
			(start -0.7874 -0.4064)
			(end 0.7874 -0.4064)
			(stroke
				(width 0.1524)
				(type default)
			)
			(layer "F.SilkS")
		)
		(fp_line
			(start 0.7874 -0.4064)
			(end 0.7874 0.4064)
			(stroke
				(width 0.1524)
				(type default)
			)
			(layer "F.SilkS")
		)
		(fp_line
			(start -0.67945 0.3048)
			(end -0.67945 -0.305054)
			(stroke
				(width 0.1)
				(type default)
			)
			(layer "F.Fab")
		)
		(fp_line
			(start -0.12065 0.3048)
			(end -0.67945 0.3048)
			(stroke
				(width 0.1)
				(type default)
			)
			(layer "F.Fab")
		)
		(fp_line
			(start 0.120396 0.3048)
			(end 0.120396 0.2794)
			(stroke
				(width 0.1)
				(type default)
			)
			(layer "F.Fab")
		)
		(fp_line
			(start 0.67945 0.3048)
			(end 0.120396 0.3048)
			(stroke
				(width 0.1)
				(type default)
			)
			(layer "F.Fab")
		)
		(fp_line
			(start -0.12065 0.2794)
			(end -0.12065 0.3048)
			(stroke
				(width 0.1)
				(type default)
			)
			(layer "F.Fab")
		)
		(fp_line
			(start 0.120396 0.2794)
			(end -0.12065 0.2794)
			(stroke
				(width 0.1)
				(type default)
			)
			(layer "F.Fab")
		)
		(fp_line
			(start -0.12065 -0.2794)
			(end 0.12065 -0.2794)
			(stroke
				(width 0.1)
				(type default)
			)
			(layer "F.Fab")
		)
		(fp_line
			(start 0.12065 -0.2794)
			(end 0.12065 -0.3048)
			(stroke
				(width 0.1)
				(type default)
			)
			(layer "F.Fab")
		)
		(fp_line
			(start 0.12065 -0.3048)
			(end 0.67945 -0.3048)
			(stroke
				(width 0.1)
				(type default)
			)
			(layer "F.Fab")
		)
		(fp_line
			(start 0.67945 -0.3048)
			(end 0.67945 0.3048)
			(stroke
				(width 0.1)
				(type default)
			)
			(layer "F.Fab")
		)
		(fp_line
			(start -0.67945 -0.305054)
			(end -0.12065 -0.305054)
			(stroke
				(width 0.1)
				(type default)
			)
			(layer "F.Fab")
		)
		(fp_line
			(start -0.12065 -0.305054)
			(end -0.12065 -0.2794)
			(stroke
				(width 0.1)
				(type default)
			)
			(layer "F.Fab")
		)
		(pad "1" smd circle
			(at -0.40005 0 270)
			(size 0 0)
			(layers "F.Cu" "F.Mask" "F.Paste")
			(net "GND")
		)
		(pad "2" smd circle
			(at 0.40005 0 270)
			(size 0 0)
			(layers "F.Cu" "F.Mask" "F.Paste")
			(net "PEX2_MODE_SEL10")
		)
	)
	(footprint ""
		(layer "F.Cu")
		(at 82.661506 -145.311114 180)
		(property "Reference" "C13"
			(at 0 0 180)
			(layer "F.SilkS")
			(hide yes)
			(effects
				(font
					(size 1.27 1.27)
				)
			)
		)
		(property "Value" ""
			(at 0 0 180)
			(layer "F.Fab")
			(effects
				(font
					(size 1.27 1.27)
				)
			)
		)
		(duplicate_pad_numbers_are_jumpers no)
		(fp_line
			(start 0.299974 0.150114)
			(end -0.299974 0.150114)
			(stroke
				(width 0.1)
				(type default)
			)
			(layer "F.Fab")
		)
		(fp_line
			(start 0.299974 -0.150114)
			(end 0.299974 0.150114)
			(stroke
				(width 0.1)
				(type default)
			)
			(layer "F.Fab")
		)
		(fp_line
			(start -0.299974 0.150114)
			(end -0.299974 -0.150114)
			(stroke
				(width 0.1)
				(type default)
			)
			(layer "F.Fab")
		)
		(fp_line
			(start -0.299974 -0.150114)
			(end 0.299974 -0.150114)
			(stroke
				(width 0.1)
				(type default)
			)
			(layer "F.Fab")
		)
		(pad "1" smd rect
			(at -0.2667 0 180)
			(size 0.3048 0.381)
			(layers "F.Cu" "F.Mask" "F.Paste")
			(net "P5E_PEX0_STN0_TX_DP<9>")
		)
		(pad "2" smd rect
			(at 0.2667 0 180)
			(size 0.3048 0.381)
			(layers "F.Cu" "F.Mask" "F.Paste")
			(net "P5E_PEX0_STN0_TX_C_DP<9>")
		)
	)
	(footprint ""
		(layer "F.Cu")
		(at 394.555218 -35.876738)
		(property "Reference" "R6116"
			(at 0 0 0)
			(layer "F.SilkS")
			(hide yes)
			(effects
				(font
					(size 1.27 1.27)
				)
			)
		)
		(property "Value" ""
			(at 0 0 0)
			(layer "F.Fab")
			(effects
				(font
					(size 1.27 1.27)
				)
			)
		)
		(duplicate_pad_numbers_are_jumpers no)
		(fp_line
			(start -0.7874 -0.4064)
			(end 0.7874 -0.4064)
			(stroke
				(width 0.1524)
				(type default)
			)
			(layer "F.SilkS")
		)
		(fp_line
			(start -0.7874 0.4064)
			(end -0.7874 -0.4064)
			(stroke
				(width 0.1524)
				(type default)
			)
			(layer "F.SilkS")
		)
		(fp_line
			(start 0.7874 -0.4064)
			(end 0.7874 0.4064)
			(stroke
				(width 0.1524)
				(type default)
			)
			(layer "F.SilkS")
		)
		(fp_line
			(start 0.7874 0.4064)
			(end -0.7874 0.4064)
			(stroke
				(width 0.1524)
				(type default)
			)
			(layer "F.SilkS")
		)
		(fp_line
			(start -0.67945 -0.305054)
			(end -0.12065 -0.305054)
			(stroke
				(width 0.1)
				(type default)
			)
			(layer "F.Fab")
		)
		(fp_line
			(start -0.67945 0.3048)
			(end -0.67945 -0.305054)
			(stroke
				(width 0.1)
				(type default)
			)
			(layer "F.Fab")
		)
		(fp_line
			(start -0.12065 -0.305054)
			(end -0.12065 -0.2794)
			(stroke
				(width 0.1)
				(type default)
			)
			(layer "F.Fab")
		)
		(fp_line
			(start -0.12065 -0.2794)
			(end 0.12065 -0.2794)
			(stroke
				(width 0.1)
				(type default)
			)
			(layer "F.Fab")
		)
		(fp_line
			(start -0.12065 0.2794)
			(end -0.12065 0.3048)
			(stroke
				(width 0.1)
				(type default)
			)
			(layer "F.Fab")
		)
		(fp_line
			(start -0.12065 0.3048)
			(end -0.67945 0.3048)
			(stroke
				(width 0.1)
				(type default)
			)
			(layer "F.Fab")
		)
		(fp_line
			(start 0.120396 0.2794)
			(end -0.12065 0.2794)
			(stroke
				(width 0.1)
				(type default)
			)
			(layer "F.Fab")
		)
		(fp_line
			(start 0.120396 0.3048)
			(end 0.120396 0.2794)
			(stroke
				(width 0.1)
				(type default)
			)
			(layer "F.Fab")
		)
		(fp_line
			(start 0.12065 -0.3048)
			(end 0.67945 -0.3048)
			(stroke
				(width 0.1)
				(type default)
			)
			(layer "F.Fab")
		)
		(fp_line
			(start 0.12065 -0.2794)
			(end 0.12065 -0.3048)
			(stroke
				(width 0.1)
				(type default)
			)
			(layer "F.Fab")
		)
		(fp_line
			(start 0.67945 -0.3048)
			(end 0.67945 0.3048)
			(stroke
				(width 0.1)
				(type default)
			)
			(layer "F.Fab")
		)
		(fp_line
			(start 0.67945 0.3048)
			(end 0.120396 0.3048)
			(stroke
				(width 0.1)
				(type default)
			)
			(layer "F.Fab")
		)
		(pad "1" smd circle
			(at -0.40005 0)
			(size 0 0)
			(layers "F.Cu" "F.Mask" "F.Paste")
			(net "P3V3_AUX")
		)
		(pad "2" smd circle
			(at 0.40005 0)
			(size 0 0)
			(layers "F.Cu" "F.Mask" "F.Paste")
			(net "PWRGD_P3V3_SSD14_D")
		)
	)
	(footprint ""
		(layer "F.Cu")
		(at 217.235786 -216.270586 180)
		(property "Reference" "R1502"
			(at 0 0 180)
			(layer "F.SilkS")
			(hide yes)
			(effects
				(font
					(size 1.27 1.27)
				)
			)
		)
		(property "Value" ""
			(at 0 0 180)
			(layer "F.Fab")
			(effects
				(font
					(size 1.27 1.27)
				)
			)
		)
		(duplicate_pad_numbers_are_jumpers no)
		(fp_line
			(start 0.7874 0.4064)
			(end -0.7874 0.4064)
			(stroke
				(width 0.1524)
				(type default)
			)
			(layer "F.SilkS")
		)
		(fp_line
			(start 0.7874 -0.4064)
			(end 0.7874 0.4064)
			(stroke
				(width 0.1524)
				(type default)
			)
			(layer "F.SilkS")
		)
		(fp_line
			(start -0.7874 0.4064)
			(end -0.7874 -0.4064)
			(stroke
				(width 0.1524)
				(type default)
			)
			(layer "F.SilkS")
		)
		(fp_line
			(start -0.7874 -0.4064)
			(end 0.7874 -0.4064)
			(stroke
				(width 0.1524)
				(type default)
			)
			(layer "F.SilkS")
		)
		(fp_line
			(start 0.67945 0.3048)
			(end 0.120396 0.3048)
			(stroke
				(width 0.1)
				(type default)
			)
			(layer "F.Fab")
		)
		(fp_line
			(start 0.67945 -0.3048)
			(end 0.67945 0.3048)
			(stroke
				(width 0.1)
				(type default)
			)
			(layer "F.Fab")
		)
		(fp_line
			(start 0.12065 -0.2794)
			(end 0.12065 -0.3048)
			(stroke
				(width 0.1)
				(type default)
			)
			(layer "F.Fab")
		)
		(fp_line
			(start 0.12065 -0.3048)
			(end 0.67945 -0.3048)
			(stroke
				(width 0.1)
				(type default)
			)
			(layer "F.Fab")
		)
		(fp_line
			(start 0.120396 0.3048)
			(end 0.120396 0.2794)
			(stroke
				(width 0.1)
				(type default)
			)
			(layer "F.Fab")
		)
		(fp_line
			(start 0.120396 0.2794)
			(end -0.12065 0.2794)
			(stroke
				(width 0.1)
				(type default)
			)
			(layer "F.Fab")
		)
		(fp_line
			(start -0.12065 0.3048)
			(end -0.67945 0.3048)
			(stroke
				(width 0.1)
				(type default)
			)
			(layer "F.Fab")
		)
		(fp_line
			(start -0.12065 0.2794)
			(end -0.12065 0.3048)
			(stroke
				(width 0.1)
				(type default)
			)
			(layer "F.Fab")
		)
		(fp_line
			(start -0.12065 -0.2794)
			(end 0.12065 -0.2794)
			(stroke
				(width 0.1)
				(type default)
			)
			(layer "F.Fab")
		)
		(fp_line
			(start -0.12065 -0.305054)
			(end -0.12065 -0.2794)
			(stroke
				(width 0.1)
				(type default)
			)
			(layer "F.Fab")
		)
		(fp_line
			(start -0.67945 0.3048)
			(end -0.67945 -0.305054)
			(stroke
				(width 0.1)
				(type default)
			)
			(layer "F.Fab")
		)
		(fp_line
			(start -0.67945 -0.305054)
			(end -0.12065 -0.305054)
			(stroke
				(width 0.1)
				(type default)
			)
			(layer "F.Fab")
		)
		(pad "1" smd circle
			(at -0.40005 0 180)
			(size 0 0)
			(layers "F.Cu" "F.Mask" "F.Paste")
			(net "SMB_NIC6_SCL")
		)
		(pad "2" smd circle
			(at 0.40005 0 180)
			(size 0 0)
			(layers "F.Cu" "F.Mask" "F.Paste")
			(net "SMB_NIC6_R_SCL")
		)
	)
	(footprint ""
		(layer "F.Cu")
		(at 363.104684 -384.01498 -90)
		(property "Reference" "Q247"
			(at -0.223012 -3.465068 0)
			(unlocked yes)
			(layer "F.SilkS")
			(effects
				(font
					(size 0.7874 0.5842)
					(thickness 0.1524)
				)
			)
		)
		(property "Value" ""
			(at 0 0 270)
			(layer "F.Fab")
			(effects
				(font
					(size 1.27 1.27)
				)
			)
		)
		(duplicate_pad_numbers_are_jumpers no)
		(fp_line
			(start -1.376172 1.199896)
			(end -1.376172 -1.199896)
			(stroke
				(width 0.1524)
				(type default)
			)
			(layer "F.SilkS")
		)
		(fp_line
			(start 1.376172 1.199896)
			(end -1.376172 1.199896)
			(stroke
				(width 0.1524)
				(type default)
			)
			(layer "F.SilkS")
		)
		(fp_line
			(start 0 -0.762)
			(end 0.508 -1.199896)
			(stroke
				(width 0.1524)
				(type default)
			)
			(layer "F.SilkS")
		)
		(fp_line
			(start -1.376172 -1.199896)
			(end -0.508 -1.199896)
			(stroke
				(width 0.1524)
				(type default)
			)
			(layer "F.SilkS")
		)
		(fp_line
			(start -0.508 -1.199896)
			(end 0 -0.762)
			(stroke
				(width 0.1524)
				(type default)
			)
			(layer "F.SilkS")
		)
		(fp_line
			(start 0.508 -1.199896)
			(end 1.376172 -1.199896)
			(stroke
				(width 0.1524)
				(type default)
			)
			(layer "F.SilkS")
		)
		(fp_line
			(start 1.376172 -1.199896)
			(end 1.376172 1.199896)
			(stroke
				(width 0.1524)
				(type default)
			)
			(layer "F.SilkS")
		)
		(fp_poly
			(pts
				(xy -1.4605 -0.7493) (xy -2.2225 -1.1303) (xy -2.2225 -0.3683)
			)
			(stroke
				(width 0)
				(type default)
			)
			(fill yes)
			(layer "F.SilkS")
		)
		(fp_line
			(start -0.674878 1.100074)
			(end -0.674878 -1.100074)
			(stroke
				(width 0.1)
				(type default)
			)
			(layer "F.Fab")
		)
		(fp_line
			(start 0.674878 1.100074)
			(end -0.674878 1.100074)
			(stroke
				(width 0.1)
				(type default)
			)
			(layer "F.Fab")
		)
		(fp_line
			(start -0.674878 -1.100074)
			(end 0.674878 -1.100074)
			(stroke
				(width 0.1)
				(type default)
			)
			(layer "F.Fab")
		)
		(fp_line
			(start 0.674878 -1.100074)
			(end 0.674878 1.100074)
			(stroke
				(width 0.1)
				(type default)
			)
			(layer "F.Fab")
		)
		(fp_poly
			(pts
				(xy -1.4605 -0.7493) (xy -2.2225 -1.1303) (xy -2.2225 -0.3683)
			)
			(stroke
				(width 0)
				(type default)
			)
			(fill yes)
			(layer "F.Fab")
		)
		(pad "1" smd rect
			(at -0.899922 -0.750062 180)
			(size 0.6096 0.6096)
			(layers "F.Cu" "F.Mask" "F.Paste")
			(net "GND")
		)
		(pad "2" smd rect
			(at -0.899922 0 180)
			(size 0.4064 0.6096)
			(layers "F.Cu" "F.Mask" "F.Paste")
			(net "MB_3V3IO_RSVD4")
		)
		(pad "3" smd rect
			(at -0.899922 0.750062 180)
			(size 0.6096 0.6096)
			(layers "F.Cu" "F.Mask" "F.Paste")
			(net "MB_3V3IO_RSVD4_ISO")
		)
		(pad "4" smd rect
			(at 0.899922 0.750062 180)
			(size 0.6096 0.6096)
			(layers "F.Cu" "F.Mask" "F.Paste")
			(net "GND")
		)
		(pad "5" smd rect
			(at 0.899922 0 180)
			(size 0.4064 0.6096)
			(layers "F.Cu" "F.Mask" "F.Paste")
			(net "MB_3V3IO_RSVD4_N")
		)
		(pad "6" smd rect
			(at 0.899922 -0.750062 180)
			(size 0.6096 0.6096)
			(layers "F.Cu" "F.Mask" "F.Paste")
			(net "MB_3V3IO_RSVD4_N")
		)
	)
	(footprint ""
		(layer "F.Cu")
		(at 334.899 -244.729 90)
		(property "Reference" "C2746"
			(at 0 0 90)
			(layer "F.SilkS")
			(hide yes)
			(effects
				(font
					(size 1.27 1.27)
				)
			)
		)
		(property "Value" ""
			(at 0 0 90)
			(layer "F.Fab")
			(effects
				(font
					(size 1.27 1.27)
				)
			)
		)
		(duplicate_pad_numbers_are_jumpers no)
		(fp_line
			(start 0.7874 -0.4064)
			(end 0.7874 0.4064)
			(stroke
				(width 0.1524)
				(type default)
			)
			(layer "F.SilkS")
		)
		(fp_line
			(start -0.7874 -0.4064)
			(end 0.7874 -0.4064)
			(stroke
				(width 0.1524)
				(type default)
			)
			(layer "F.SilkS")
		)
		(fp_line
			(start 0.7874 0.4064)
			(end -0.7874 0.4064)
			(stroke
				(width 0.1524)
				(type default)
			)
			(layer "F.SilkS")
		)
		(fp_line
			(start -0.7874 0.4064)
			(end -0.7874 -0.4064)
			(stroke
				(width 0.1524)
				(type default)
			)
			(layer "F.SilkS")
		)
		(fp_line
			(start -0.12065 -0.305054)
			(end -0.12065 -0.2794)
			(stroke
				(width 0.1)
				(type default)
			)
			(layer "F.Fab")
		)
		(fp_line
			(start -0.67945 -0.305054)
			(end -0.12065 -0.305054)
			(stroke
				(width 0.1)
				(type default)
			)
			(layer "F.Fab")
		)
		(fp_line
			(start 0.67945 -0.3048)
			(end 0.67945 0.3048)
			(stroke
				(width 0.1)
				(type default)
			)
			(layer "F.Fab")
		)
		(fp_line
			(start 0.12065 -0.3048)
			(end 0.67945 -0.3048)
			(stroke
				(width 0.1)
				(type default)
			)
			(layer "F.Fab")
		)
		(fp_line
			(start 0.12065 -0.2794)
			(end 0.12065 -0.3048)
			(stroke
				(width 0.1)
				(type default)
			)
			(layer "F.Fab")
		)
		(fp_line
			(start -0.12065 -0.2794)
			(end 0.12065 -0.2794)
			(stroke
				(width 0.1)
				(type default)
			)
			(layer "F.Fab")
		)
		(fp_line
			(start 0.120396 0.2794)
			(end -0.12065 0.2794)
			(stroke
				(width 0.1)
				(type default)
			)
			(layer "F.Fab")
		)
		(fp_line
			(start -0.12065 0.2794)
			(end -0.12065 0.3048)
			(stroke
				(width 0.1)
				(type default)
			)
			(layer "F.Fab")
		)
		(fp_line
			(start 0.67945 0.3048)
			(end 0.120396 0.3048)
			(stroke
				(width 0.1)
				(type default)
			)
			(layer "F.Fab")
		)
		(fp_line
			(start 0.120396 0.3048)
			(end 0.120396 0.2794)
			(stroke
				(width 0.1)
				(type default)
			)
			(layer "F.Fab")
		)
		(fp_line
			(start -0.12065 0.3048)
			(end -0.67945 0.3048)
			(stroke
				(width 0.1)
				(type default)
			)
			(layer "F.Fab")
		)
		(fp_line
			(start -0.67945 0.3048)
			(end -0.67945 -0.305054)
			(stroke
				(width 0.1)
				(type default)
			)
			(layer "F.Fab")
		)
		(pad "1" smd circle
			(at -0.40005 0 90)
			(size 0 0)
			(layers "F.Cu" "F.Mask" "F.Paste")
			(net "P3V3_AUX")
		)
		(pad "2" smd circle
			(at 0.40005 0 90)
			(size 0 0)
			(layers "F.Cu" "F.Mask" "F.Paste")
			(net "GND")
		)
	)
	(footprint ""
		(layer "F.Cu")
		(at 143.938752 -311.156604 -90)
		(property "Reference" "R1263"
			(at 0 0 270)
			(layer "F.SilkS")
			(hide yes)
			(effects
				(font
					(size 1.27 1.27)
				)
			)
		)
		(property "Value" ""
			(at 0 0 270)
			(layer "F.Fab")
			(effects
				(font
					(size 1.27 1.27)
				)
			)
		)
		(duplicate_pad_numbers_are_jumpers no)
		(fp_line
			(start -0.7874 0.4064)
			(end -0.7874 -0.4064)
			(stroke
				(width 0.1524)
				(type default)
			)
			(layer "F.SilkS")
		)
		(fp_line
			(start 0.7874 0.4064)
			(end -0.7874 0.4064)
			(stroke
				(width 0.1524)
				(type default)
			)
			(layer "F.SilkS")
		)
		(fp_line
			(start -0.7874 -0.4064)
			(end 0.7874 -0.4064)
			(stroke
				(width 0.1524)
				(type default)
			)
			(layer "F.SilkS")
		)
		(fp_line
			(start 0.7874 -0.4064)
			(end 0.7874 0.4064)
			(stroke
				(width 0.1524)
				(type default)
			)
			(layer "F.SilkS")
		)
		(fp_line
			(start -0.67945 0.3048)
			(end -0.67945 -0.305054)
			(stroke
				(width 0.1)
				(type default)
			)
			(layer "F.Fab")
		)
		(fp_line
			(start -0.12065 0.3048)
			(end -0.67945 0.3048)
			(stroke
				(width 0.1)
				(type default)
			)
			(layer "F.Fab")
		)
		(fp_line
			(start 0.120396 0.3048)
			(end 0.120396 0.2794)
			(stroke
				(width 0.1)
				(type default)
			)
			(layer "F.Fab")
		)
		(fp_line
			(start 0.67945 0.3048)
			(end 0.120396 0.3048)
			(stroke
				(width 0.1)
				(type default)
			)
			(layer "F.Fab")
		)
		(fp_line
			(start -0.12065 0.2794)
			(end -0.12065 0.3048)
			(stroke
				(width 0.1)
				(type default)
			)
			(layer "F.Fab")
		)
		(fp_line
			(start 0.120396 0.2794)
			(end -0.12065 0.2794)
			(stroke
				(width 0.1)
				(type default)
			)
			(layer "F.Fab")
		)
		(fp_line
			(start -0.12065 -0.2794)
			(end 0.12065 -0.2794)
			(stroke
				(width 0.1)
				(type default)
			)
			(layer "F.Fab")
		)
		(fp_line
			(start 0.12065 -0.2794)
			(end 0.12065 -0.3048)
			(stroke
				(width 0.1)
				(type default)
			)
			(layer "F.Fab")
		)
		(fp_line
			(start 0.12065 -0.3048)
			(end 0.67945 -0.3048)
			(stroke
				(width 0.1)
				(type default)
			)
			(layer "F.Fab")
		)
		(fp_line
			(start 0.67945 -0.3048)
			(end 0.67945 0.3048)
			(stroke
				(width 0.1)
				(type default)
			)
			(layer "F.Fab")
		)
		(fp_line
			(start -0.67945 -0.305054)
			(end -0.12065 -0.305054)
			(stroke
				(width 0.1)
				(type default)
			)
			(layer "F.Fab")
		)
		(fp_line
			(start -0.12065 -0.305054)
			(end -0.12065 -0.2794)
			(stroke
				(width 0.1)
				(type default)
			)
			(layer "F.Fab")
		)
		(pad "1" smd circle
			(at -0.40005 0 270)
			(size 0 0)
			(layers "F.Cu" "F.Mask" "F.Paste")
			(net "PEX1_DBG_SEL1")
		)
		(pad "2" smd circle
			(at 0.40005 0 270)
			(size 0 0)
			(layers "F.Cu" "F.Mask" "F.Paste")
			(net "P1V8_PEX")
		)
	)
	(footprint ""
		(layer "F.Cu")
		(at 327.19137 -227.711 -90)
		(property "Reference" "R4384"
			(at 0 0 270)
			(layer "F.SilkS")
			(hide yes)
			(effects
				(font
					(size 1.27 1.27)
				)
			)
		)
		(property "Value" ""
			(at 0 0 270)
			(layer "F.Fab")
			(effects
				(font
					(size 1.27 1.27)
				)
			)
		)
		(duplicate_pad_numbers_are_jumpers no)
		(fp_line
			(start -0.7874 0.4064)
			(end -0.7874 -0.4064)
			(stroke
				(width 0.1524)
				(type default)
			)
			(layer "F.SilkS")
		)
		(fp_line
			(start 0.7874 0.4064)
			(end -0.7874 0.4064)
			(stroke
				(width 0.1524)
				(type default)
			)
			(layer "F.SilkS")
		)
		(fp_line
			(start -0.7874 -0.4064)
			(end 0.7874 -0.4064)
			(stroke
				(width 0.1524)
				(type default)
			)
			(layer "F.SilkS")
		)
		(fp_line
			(start 0.7874 -0.4064)
			(end 0.7874 0.4064)
			(stroke
				(width 0.1524)
				(type default)
			)
			(layer "F.SilkS")
		)
		(fp_line
			(start -0.67945 0.3048)
			(end -0.67945 -0.305054)
			(stroke
				(width 0.1)
				(type default)
			)
			(layer "F.Fab")
		)
		(fp_line
			(start -0.12065 0.3048)
			(end -0.67945 0.3048)
			(stroke
				(width 0.1)
				(type default)
			)
			(layer "F.Fab")
		)
		(fp_line
			(start 0.120396 0.3048)
			(end 0.120396 0.2794)
			(stroke
				(width 0.1)
				(type default)
			)
			(layer "F.Fab")
		)
		(fp_line
			(start 0.67945 0.3048)
			(end 0.120396 0.3048)
			(stroke
				(width 0.1)
				(type default)
			)
			(layer "F.Fab")
		)
		(fp_line
			(start -0.12065 0.2794)
			(end -0.12065 0.3048)
			(stroke
				(width 0.1)
				(type default)
			)
			(layer "F.Fab")
		)
		(fp_line
			(start 0.120396 0.2794)
			(end -0.12065 0.2794)
			(stroke
				(width 0.1)
				(type default)
			)
			(layer "F.Fab")
		)
		(fp_line
			(start -0.12065 -0.2794)
			(end 0.12065 -0.2794)
			(stroke
				(width 0.1)
				(type default)
			)
			(layer "F.Fab")
		)
		(fp_line
			(start 0.12065 -0.2794)
			(end 0.12065 -0.3048)
			(stroke
				(width 0.1)
				(type default)
			)
			(layer "F.Fab")
		)
		(fp_line
			(start 0.12065 -0.3048)
			(end 0.67945 -0.3048)
			(stroke
				(width 0.1)
				(type default)
			)
			(layer "F.Fab")
		)
		(fp_line
			(start 0.67945 -0.3048)
			(end 0.67945 0.3048)
			(stroke
				(width 0.1)
				(type default)
			)
			(layer "F.Fab")
		)
		(fp_line
			(start -0.67945 -0.305054)
			(end -0.12065 -0.305054)
			(stroke
				(width 0.1)
				(type default)
			)
			(layer "F.Fab")
		)
		(fp_line
			(start -0.12065 -0.305054)
			(end -0.12065 -0.2794)
			(stroke
				(width 0.1)
				(type default)
			)
			(layer "F.Fab")
		)
		(pad "1" smd circle
			(at -0.40005 0 270)
			(size 0 0)
			(layers "F.Cu" "F.Mask" "F.Paste")
			(net "RST_PEX_SYS_R_N")
		)
		(pad "2" smd circle
			(at 0.40005 0 270)
			(size 0 0)
			(layers "F.Cu" "F.Mask" "F.Paste")
			(net "P3V3_AUX")
		)
	)
	(footprint ""
		(layer "F.Cu")
		(at 460.611982 -111.531654)
		(property "Reference" "PR7061"
			(at 0 0 0)
			(layer "F.SilkS")
			(hide yes)
			(effects
				(font
					(size 1.27 1.27)
				)
			)
		)
		(property "Value" ""
			(at 0 0 0)
			(layer "F.Fab")
			(effects
				(font
					(size 1.27 1.27)
				)
			)
		)
		(duplicate_pad_numbers_are_jumpers no)
		(fp_line
			(start -0.7874 -0.4064)
			(end 0.7874 -0.4064)
			(stroke
				(width 0.1524)
				(type default)
			)
			(layer "F.SilkS")
		)
		(fp_line
			(start -0.7874 0.4064)
			(end -0.7874 -0.4064)
			(stroke
				(width 0.1524)
				(type default)
			)
			(layer "F.SilkS")
		)
		(fp_line
			(start 0.7874 -0.4064)
			(end 0.7874 0.4064)
			(stroke
				(width 0.1524)
				(type default)
			)
			(layer "F.SilkS")
		)
		(fp_line
			(start 0.7874 0.4064)
			(end -0.7874 0.4064)
			(stroke
				(width 0.1524)
				(type default)
			)
			(layer "F.SilkS")
		)
		(fp_line
			(start -0.67945 -0.305054)
			(end -0.12065 -0.305054)
			(stroke
				(width 0.1)
				(type default)
			)
			(layer "F.Fab")
		)
		(fp_line
			(start -0.67945 0.3048)
			(end -0.67945 -0.305054)
			(stroke
				(width 0.1)
				(type default)
			)
			(layer "F.Fab")
		)
		(fp_line
			(start -0.12065 -0.305054)
			(end -0.12065 -0.2794)
			(stroke
				(width 0.1)
				(type default)
			)
			(layer "F.Fab")
		)
		(fp_line
			(start -0.12065 -0.2794)
			(end 0.12065 -0.2794)
			(stroke
				(width 0.1)
				(type default)
			)
			(layer "F.Fab")
		)
		(fp_line
			(start -0.12065 0.2794)
			(end -0.12065 0.3048)
			(stroke
				(width 0.1)
				(type default)
			)
			(layer "F.Fab")
		)
		(fp_line
			(start -0.12065 0.3048)
			(end -0.67945 0.3048)
			(stroke
				(width 0.1)
				(type default)
			)
			(layer "F.Fab")
		)
		(fp_line
			(start 0.120396 0.2794)
			(end -0.12065 0.2794)
			(stroke
				(width 0.1)
				(type default)
			)
			(layer "F.Fab")
		)
		(fp_line
			(start 0.120396 0.3048)
			(end 0.120396 0.2794)
			(stroke
				(width 0.1)
				(type default)
			)
			(layer "F.Fab")
		)
		(fp_line
			(start 0.12065 -0.3048)
			(end 0.67945 -0.3048)
			(stroke
				(width 0.1)
				(type default)
			)
			(layer "F.Fab")
		)
		(fp_line
			(start 0.12065 -0.2794)
			(end 0.12065 -0.3048)
			(stroke
				(width 0.1)
				(type default)
			)
			(layer "F.Fab")
		)
		(fp_line
			(start 0.67945 -0.3048)
			(end 0.67945 0.3048)
			(stroke
				(width 0.1)
				(type default)
			)
			(layer "F.Fab")
		)
		(fp_line
			(start 0.67945 0.3048)
			(end 0.120396 0.3048)
			(stroke
				(width 0.1)
				(type default)
			)
			(layer "F.Fab")
		)
		(pad "1" smd circle
			(at -0.40005 0)
			(size 0 0)
			(layers "F.Cu" "F.Mask" "F.Paste")
			(net "P12V_NIC7_CO_ISET")
		)
		(pad "2" smd circle
			(at 0.40005 0)
			(size 0 0)
			(layers "F.Cu" "F.Mask" "F.Paste")
			(net "GND")
		)
	)
	(footprint ""
		(layer "F.Cu")
		(at 126.205488 -285.088584 90)
		(property "Reference" "PC107"
			(at 0 0 90)
			(layer "F.SilkS")
			(hide yes)
			(effects
				(font
					(size 1.27 1.27)
				)
			)
		)
		(property "Value" ""
			(at 0 0 90)
			(layer "F.Fab")
			(effects
				(font
					(size 1.27 1.27)
				)
			)
		)
		(duplicate_pad_numbers_are_jumpers no)
		(fp_line
			(start 0.7874 -0.4064)
			(end 0.7874 0.4064)
			(stroke
				(width 0.1524)
				(type default)
			)
			(layer "F.SilkS")
		)
		(fp_line
			(start -0.7874 -0.4064)
			(end 0.7874 -0.4064)
			(stroke
				(width 0.1524)
				(type default)
			)
			(layer "F.SilkS")
		)
		(fp_line
			(start 0.7874 0.4064)
			(end -0.7874 0.4064)
			(stroke
				(width 0.1524)
				(type default)
			)
			(layer "F.SilkS")
		)
		(fp_line
			(start -0.7874 0.4064)
			(end -0.7874 -0.4064)
			(stroke
				(width 0.1524)
				(type default)
			)
			(layer "F.SilkS")
		)
		(fp_line
			(start -0.12065 -0.305054)
			(end -0.12065 -0.2794)
			(stroke
				(width 0.1)
				(type default)
			)
			(layer "F.Fab")
		)
		(fp_line
			(start -0.67945 -0.305054)
			(end -0.12065 -0.305054)
			(stroke
				(width 0.1)
				(type default)
			)
			(layer "F.Fab")
		)
		(fp_line
			(start 0.67945 -0.3048)
			(end 0.67945 0.3048)
			(stroke
				(width 0.1)
				(type default)
			)
			(layer "F.Fab")
		)
		(fp_line
			(start 0.12065 -0.3048)
			(end 0.67945 -0.3048)
			(stroke
				(width 0.1)
				(type default)
			)
			(layer "F.Fab")
		)
		(fp_line
			(start 0.12065 -0.2794)
			(end 0.12065 -0.3048)
			(stroke
				(width 0.1)
				(type default)
			)
			(layer "F.Fab")
		)
		(fp_line
			(start -0.12065 -0.2794)
			(end 0.12065 -0.2794)
			(stroke
				(width 0.1)
				(type default)
			)
			(layer "F.Fab")
		)
		(fp_line
			(start 0.120396 0.2794)
			(end -0.12065 0.2794)
			(stroke
				(width 0.1)
				(type default)
			)
			(layer "F.Fab")
		)
		(fp_line
			(start -0.12065 0.2794)
			(end -0.12065 0.3048)
			(stroke
				(width 0.1)
				(type default)
			)
			(layer "F.Fab")
		)
		(fp_line
			(start 0.67945 0.3048)
			(end 0.120396 0.3048)
			(stroke
				(width 0.1)
				(type default)
			)
			(layer "F.Fab")
		)
		(fp_line
			(start 0.120396 0.3048)
			(end 0.120396 0.2794)
			(stroke
				(width 0.1)
				(type default)
			)
			(layer "F.Fab")
		)
		(fp_line
			(start -0.12065 0.3048)
			(end -0.67945 0.3048)
			(stroke
				(width 0.1)
				(type default)
			)
			(layer "F.Fab")
		)
		(fp_line
			(start -0.67945 0.3048)
			(end -0.67945 -0.305054)
			(stroke
				(width 0.1)
				(type default)
			)
			(layer "F.Fab")
		)
		(pad "1" smd circle
			(at -0.40005 0 90)
			(size 0 0)
			(layers "F.Cu" "F.Mask" "F.Paste")
			(net "P0V8_PEX1_PVCC")
		)
		(pad "2" smd circle
			(at 0.40005 0 90)
			(size 0 0)
			(layers "F.Cu" "F.Mask" "F.Paste")
			(net "GND")
		)
	)
	(footprint ""
		(layer "F.Cu")
		(at 253.489968 -72.766682 90)
		(property "Reference" "PR7076"
			(at 0 0 90)
			(layer "F.SilkS")
			(hide yes)
			(effects
				(font
					(size 1.27 1.27)
				)
			)
		)
		(property "Value" ""
			(at 0 0 90)
			(layer "F.Fab")
			(effects
				(font
					(size 1.27 1.27)
				)
			)
		)
		(duplicate_pad_numbers_are_jumpers no)
		(fp_line
			(start 0.7874 -0.4064)
			(end 0.7874 0.4064)
			(stroke
				(width 0.1524)
				(type default)
			)
			(layer "F.SilkS")
		)
		(fp_line
			(start -0.7874 -0.4064)
			(end 0.7874 -0.4064)
			(stroke
				(width 0.1524)
				(type default)
			)
			(layer "F.SilkS")
		)
		(fp_line
			(start 0.7874 0.4064)
			(end -0.7874 0.4064)
			(stroke
				(width 0.1524)
				(type default)
			)
			(layer "F.SilkS")
		)
		(fp_line
			(start -0.7874 0.4064)
			(end -0.7874 -0.4064)
			(stroke
				(width 0.1524)
				(type default)
			)
			(layer "F.SilkS")
		)
		(fp_line
			(start -0.12065 -0.305054)
			(end -0.12065 -0.2794)
			(stroke
				(width 0.1)
				(type default)
			)
			(layer "F.Fab")
		)
		(fp_line
			(start -0.67945 -0.305054)
			(end -0.12065 -0.305054)
			(stroke
				(width 0.1)
				(type default)
			)
			(layer "F.Fab")
		)
		(fp_line
			(start 0.67945 -0.3048)
			(end 0.67945 0.3048)
			(stroke
				(width 0.1)
				(type default)
			)
			(layer "F.Fab")
		)
		(fp_line
			(start 0.12065 -0.3048)
			(end 0.67945 -0.3048)
			(stroke
				(width 0.1)
				(type default)
			)
			(layer "F.Fab")
		)
		(fp_line
			(start 0.12065 -0.2794)
			(end 0.12065 -0.3048)
			(stroke
				(width 0.1)
				(type default)
			)
			(layer "F.Fab")
		)
		(fp_line
			(start -0.12065 -0.2794)
			(end 0.12065 -0.2794)
			(stroke
				(width 0.1)
				(type default)
			)
			(layer "F.Fab")
		)
		(fp_line
			(start 0.120396 0.2794)
			(end -0.12065 0.2794)
			(stroke
				(width 0.1)
				(type default)
			)
			(layer "F.Fab")
		)
		(fp_line
			(start -0.12065 0.2794)
			(end -0.12065 0.3048)
			(stroke
				(width 0.1)
				(type default)
			)
			(layer "F.Fab")
		)
		(fp_line
			(start 0.67945 0.3048)
			(end 0.120396 0.3048)
			(stroke
				(width 0.1)
				(type default)
			)
			(layer "F.Fab")
		)
		(fp_line
			(start 0.120396 0.3048)
			(end 0.120396 0.2794)
			(stroke
				(width 0.1)
				(type default)
			)
			(layer "F.Fab")
		)
		(fp_line
			(start -0.12065 0.3048)
			(end -0.67945 0.3048)
			(stroke
				(width 0.1)
				(type default)
			)
			(layer "F.Fab")
		)
		(fp_line
			(start -0.67945 0.3048)
			(end -0.67945 -0.305054)
			(stroke
				(width 0.1)
				(type default)
			)
			(layer "F.Fab")
		)
		(pad "1" smd circle
			(at -0.40005 0 90)
			(size 0 0)
			(layers "F.Cu" "F.Mask" "F.Paste")
			(net "P12V_SSD8_CO_ILIMIT")
		)
		(pad "2" smd circle
			(at 0.40005 0 90)
			(size 0 0)
			(layers "F.Cu" "F.Mask" "F.Paste")
			(net "GND")
		)
	)
	(footprint ""
		(layer "F.Cu")
		(at 166.58209 -38.041072 180)
		(property "Reference" "R6072"
			(at 0 0 180)
			(layer "F.SilkS")
			(hide yes)
			(effects
				(font
					(size 1.27 1.27)
				)
			)
		)
		(property "Value" ""
			(at 0 0 180)
			(layer "F.Fab")
			(effects
				(font
					(size 1.27 1.27)
				)
			)
		)
		(duplicate_pad_numbers_are_jumpers no)
		(fp_line
			(start 0.7874 0.4064)
			(end -0.7874 0.4064)
			(stroke
				(width 0.1524)
				(type default)
			)
			(layer "F.SilkS")
		)
		(fp_line
			(start 0.7874 -0.4064)
			(end 0.7874 0.4064)
			(stroke
				(width 0.1524)
				(type default)
			)
			(layer "F.SilkS")
		)
		(fp_line
			(start -0.7874 0.4064)
			(end -0.7874 -0.4064)
			(stroke
				(width 0.1524)
				(type default)
			)
			(layer "F.SilkS")
		)
		(fp_line
			(start -0.7874 -0.4064)
			(end 0.7874 -0.4064)
			(stroke
				(width 0.1524)
				(type default)
			)
			(layer "F.SilkS")
		)
		(fp_line
			(start 0.67945 0.3048)
			(end 0.120396 0.3048)
			(stroke
				(width 0.1)
				(type default)
			)
			(layer "F.Fab")
		)
		(fp_line
			(start 0.67945 -0.3048)
			(end 0.67945 0.3048)
			(stroke
				(width 0.1)
				(type default)
			)
			(layer "F.Fab")
		)
		(fp_line
			(start 0.12065 -0.2794)
			(end 0.12065 -0.3048)
			(stroke
				(width 0.1)
				(type default)
			)
			(layer "F.Fab")
		)
		(fp_line
			(start 0.12065 -0.3048)
			(end 0.67945 -0.3048)
			(stroke
				(width 0.1)
				(type default)
			)
			(layer "F.Fab")
		)
		(fp_line
			(start 0.120396 0.3048)
			(end 0.120396 0.2794)
			(stroke
				(width 0.1)
				(type default)
			)
			(layer "F.Fab")
		)
		(fp_line
			(start 0.120396 0.2794)
			(end -0.12065 0.2794)
			(stroke
				(width 0.1)
				(type default)
			)
			(layer "F.Fab")
		)
		(fp_line
			(start -0.12065 0.3048)
			(end -0.67945 0.3048)
			(stroke
				(width 0.1)
				(type default)
			)
			(layer "F.Fab")
		)
		(fp_line
			(start -0.12065 0.2794)
			(end -0.12065 0.3048)
			(stroke
				(width 0.1)
				(type default)
			)
			(layer "F.Fab")
		)
		(fp_line
			(start -0.12065 -0.2794)
			(end 0.12065 -0.2794)
			(stroke
				(width 0.1)
				(type default)
			)
			(layer "F.Fab")
		)
		(fp_line
			(start -0.12065 -0.305054)
			(end -0.12065 -0.2794)
			(stroke
				(width 0.1)
				(type default)
			)
			(layer "F.Fab")
		)
		(fp_line
			(start -0.67945 0.3048)
			(end -0.67945 -0.305054)
			(stroke
				(width 0.1)
				(type default)
			)
			(layer "F.Fab")
		)
		(fp_line
			(start -0.67945 -0.305054)
			(end -0.12065 -0.305054)
			(stroke
				(width 0.1)
				(type default)
			)
			(layer "F.Fab")
		)
		(pad "1" smd circle
			(at -0.40005 0 180)
			(size 0 0)
			(layers "F.Cu" "F.Mask" "F.Paste")
			(net "P5V_AUX")
		)
		(pad "2" smd circle
			(at 0.40005 0 180)
			(size 0 0)
			(layers "F.Cu" "F.Mask" "F.Paste")
			(net "P3V3_SSD6_PG_G2")
		)
	)
	(footprint ""
		(layer "F.Cu")
		(at 133.940042 -70.52437 90)
		(property "Reference" "PC841"
			(at 0 0 90)
			(layer "F.SilkS")
			(hide yes)
			(effects
				(font
					(size 1.27 1.27)
				)
			)
		)
		(property "Value" ""
			(at 0 0 90)
			(layer "F.Fab")
			(effects
				(font
					(size 1.27 1.27)
				)
			)
		)
		(duplicate_pad_numbers_are_jumpers no)
		(fp_line
			(start 1.524 -0.762)
			(end 1.524 0.762)
			(stroke
				(width 0.1524)
				(type default)
			)
			(layer "F.SilkS")
		)
		(fp_line
			(start -1.524 -0.762)
			(end 1.524 -0.762)
			(stroke
				(width 0.1524)
				(type default)
			)
			(layer "F.SilkS")
		)
		(fp_line
			(start 1.524 0.762)
			(end -1.524 0.762)
			(stroke
				(width 0.1524)
				(type default)
			)
			(layer "F.SilkS")
		)
		(fp_line
			(start -1.524 0.762)
			(end -1.524 -0.762)
			(stroke
				(width 0.1524)
				(type default)
			)
			(layer "F.SilkS")
		)
		(fp_line
			(start 1.1049 -0.724916)
			(end -1.1049 -0.724916)
			(stroke
				(width 0.1)
				(type default)
			)
			(layer "F.Fab")
		)
		(fp_line
			(start -1.1049 -0.724916)
			(end -1.1049 0.724916)
			(stroke
				(width 0.1)
				(type default)
			)
			(layer "F.Fab")
		)
		(fp_line
			(start 1.1049 0.724916)
			(end 1.1049 -0.724916)
			(stroke
				(width 0.1)
				(type default)
			)
			(layer "F.Fab")
		)
		(fp_line
			(start -1.1049 0.724916)
			(end 1.1049 0.724916)
			(stroke
				(width 0.1)
				(type default)
			)
			(layer "F.Fab")
		)
		(pad "1" smd rect
			(at -0.889 0 270)
			(size 1.016 1.27)
			(layers "F.Cu" "F.Mask" "F.Paste")
			(net "P12V_SSD4_R")
		)
		(pad "2" smd rect
			(at 0.889 0 270)
			(size 1.016 1.27)
			(layers "F.Cu" "F.Mask" "F.Paste")
			(net "GND")
		)
	)
	(footprint ""
		(layer "F.Cu")
		(at 358.405684 -282.421584 -90)
		(property "Reference" "PC178"
			(at 0 0 270)
			(layer "F.SilkS")
			(hide yes)
			(effects
				(font
					(size 1.27 1.27)
				)
			)
		)
		(property "Value" ""
			(at 0 0 270)
			(layer "F.Fab")
			(effects
				(font
					(size 1.27 1.27)
				)
			)
		)
		(duplicate_pad_numbers_are_jumpers no)
		(fp_line
			(start -0.7874 0.4064)
			(end -0.7874 -0.4064)
			(stroke
				(width 0.1524)
				(type default)
			)
			(layer "F.SilkS")
		)
		(fp_line
			(start 0.7874 0.4064)
			(end -0.7874 0.4064)
			(stroke
				(width 0.1524)
				(type default)
			)
			(layer "F.SilkS")
		)
		(fp_line
			(start -0.7874 -0.4064)
			(end 0.7874 -0.4064)
			(stroke
				(width 0.1524)
				(type default)
			)
			(layer "F.SilkS")
		)
		(fp_line
			(start 0.7874 -0.4064)
			(end 0.7874 0.4064)
			(stroke
				(width 0.1524)
				(type default)
			)
			(layer "F.SilkS")
		)
		(fp_line
			(start -0.67945 0.3048)
			(end -0.67945 -0.305054)
			(stroke
				(width 0.1)
				(type default)
			)
			(layer "F.Fab")
		)
		(fp_line
			(start -0.12065 0.3048)
			(end -0.67945 0.3048)
			(stroke
				(width 0.1)
				(type default)
			)
			(layer "F.Fab")
		)
		(fp_line
			(start 0.120396 0.3048)
			(end 0.120396 0.2794)
			(stroke
				(width 0.1)
				(type default)
			)
			(layer "F.Fab")
		)
		(fp_line
			(start 0.67945 0.3048)
			(end 0.120396 0.3048)
			(stroke
				(width 0.1)
				(type default)
			)
			(layer "F.Fab")
		)
		(fp_line
			(start -0.12065 0.2794)
			(end -0.12065 0.3048)
			(stroke
				(width 0.1)
				(type default)
			)
			(layer "F.Fab")
		)
		(fp_line
			(start 0.120396 0.2794)
			(end -0.12065 0.2794)
			(stroke
				(width 0.1)
				(type default)
			)
			(layer "F.Fab")
		)
		(fp_line
			(start -0.12065 -0.2794)
			(end 0.12065 -0.2794)
			(stroke
				(width 0.1)
				(type default)
			)
			(layer "F.Fab")
		)
		(fp_line
			(start 0.12065 -0.2794)
			(end 0.12065 -0.3048)
			(stroke
				(width 0.1)
				(type default)
			)
			(layer "F.Fab")
		)
		(fp_line
			(start 0.12065 -0.3048)
			(end 0.67945 -0.3048)
			(stroke
				(width 0.1)
				(type default)
			)
			(layer "F.Fab")
		)
		(fp_line
			(start 0.67945 -0.3048)
			(end 0.67945 0.3048)
			(stroke
				(width 0.1)
				(type default)
			)
			(layer "F.Fab")
		)
		(fp_line
			(start -0.67945 -0.305054)
			(end -0.12065 -0.305054)
			(stroke
				(width 0.1)
				(type default)
			)
			(layer "F.Fab")
		)
		(fp_line
			(start -0.12065 -0.305054)
			(end -0.12065 -0.2794)
			(stroke
				(width 0.1)
				(type default)
			)
			(layer "F.Fab")
		)
		(pad "1" smd circle
			(at -0.40005 0 270)
			(size 0 0)
			(layers "F.Cu" "F.Mask" "F.Paste")
			(net "P0V8_PEX3_VCC1")
		)
		(pad "2" smd circle
			(at 0.40005 0 270)
			(size 0 0)
			(layers "F.Cu" "F.Mask" "F.Paste")
			(net "GND")
		)
	)
	(footprint ""
		(layer "F.Cu")
		(at 232.823512 -234.728004 -90)
		(property "Reference" "R6192"
			(at 0 0 270)
			(layer "F.SilkS")
			(hide yes)
			(effects
				(font
					(size 1.27 1.27)
				)
			)
		)
		(property "Value" ""
			(at 0 0 270)
			(layer "F.Fab")
			(effects
				(font
					(size 1.27 1.27)
				)
			)
		)
		(duplicate_pad_numbers_are_jumpers no)
		(fp_line
			(start -0.7874 0.4064)
			(end -0.7874 -0.4064)
			(stroke
				(width 0.1524)
				(type default)
			)
			(layer "F.SilkS")
		)
		(fp_line
			(start 0.7874 0.4064)
			(end -0.7874 0.4064)
			(stroke
				(width 0.1524)
				(type default)
			)
			(layer "F.SilkS")
		)
		(fp_line
			(start -0.7874 -0.4064)
			(end 0.7874 -0.4064)
			(stroke
				(width 0.1524)
				(type default)
			)
			(layer "F.SilkS")
		)
		(fp_line
			(start 0.7874 -0.4064)
			(end 0.7874 0.4064)
			(stroke
				(width 0.1524)
				(type default)
			)
			(layer "F.SilkS")
		)
		(fp_line
			(start -0.67945 0.3048)
			(end -0.67945 -0.305054)
			(stroke
				(width 0.1)
				(type default)
			)
			(layer "F.Fab")
		)
		(fp_line
			(start -0.12065 0.3048)
			(end -0.67945 0.3048)
			(stroke
				(width 0.1)
				(type default)
			)
			(layer "F.Fab")
		)
		(fp_line
			(start 0.120396 0.3048)
			(end 0.120396 0.2794)
			(stroke
				(width 0.1)
				(type default)
			)
			(layer "F.Fab")
		)
		(fp_line
			(start 0.67945 0.3048)
			(end 0.120396 0.3048)
			(stroke
				(width 0.1)
				(type default)
			)
			(layer "F.Fab")
		)
		(fp_line
			(start -0.12065 0.2794)
			(end -0.12065 0.3048)
			(stroke
				(width 0.1)
				(type default)
			)
			(layer "F.Fab")
		)
		(fp_line
			(start 0.120396 0.2794)
			(end -0.12065 0.2794)
			(stroke
				(width 0.1)
				(type default)
			)
			(layer "F.Fab")
		)
		(fp_line
			(start -0.12065 -0.2794)
			(end 0.12065 -0.2794)
			(stroke
				(width 0.1)
				(type default)
			)
			(layer "F.Fab")
		)
		(fp_line
			(start 0.12065 -0.2794)
			(end 0.12065 -0.3048)
			(stroke
				(width 0.1)
				(type default)
			)
			(layer "F.Fab")
		)
		(fp_line
			(start 0.12065 -0.3048)
			(end 0.67945 -0.3048)
			(stroke
				(width 0.1)
				(type default)
			)
			(layer "F.Fab")
		)
		(fp_line
			(start 0.67945 -0.3048)
			(end 0.67945 0.3048)
			(stroke
				(width 0.1)
				(type default)
			)
			(layer "F.Fab")
		)
		(fp_line
			(start -0.67945 -0.305054)
			(end -0.12065 -0.305054)
			(stroke
				(width 0.1)
				(type default)
			)
			(layer "F.Fab")
		)
		(fp_line
			(start -0.12065 -0.305054)
			(end -0.12065 -0.2794)
			(stroke
				(width 0.1)
				(type default)
			)
			(layer "F.Fab")
		)
		(pad "1" smd circle
			(at -0.40005 0 270)
			(size 0 0)
			(layers "F.Cu" "F.Mask" "F.Paste")
			(net "GND")
		)
		(pad "2" smd circle
			(at 0.40005 0 270)
			(size 0 0)
			(layers "F.Cu" "F.Mask" "F.Paste")
			(net "SSD10_PWRDIS_BIC_R")
		)
	)
	(footprint ""
		(layer "F.Cu")
		(at 369.08359 -6.703822)
		(property "Reference" "R5819"
			(at 0 0 0)
			(layer "F.SilkS")
			(hide yes)
			(effects
				(font
					(size 1.27 1.27)
				)
			)
		)
		(property "Value" ""
			(at 0 0 0)
			(layer "F.Fab")
			(effects
				(font
					(size 1.27 1.27)
				)
			)
		)
		(duplicate_pad_numbers_are_jumpers no)
		(fp_line
			(start -0.7874 -0.4064)
			(end 0.7874 -0.4064)
			(stroke
				(width 0.1524)
				(type default)
			)
			(layer "F.SilkS")
		)
		(fp_line
			(start -0.7874 0.4064)
			(end -0.7874 -0.4064)
			(stroke
				(width 0.1524)
				(type default)
			)
			(layer "F.SilkS")
		)
		(fp_line
			(start 0.7874 -0.4064)
			(end 0.7874 0.4064)
			(stroke
				(width 0.1524)
				(type default)
			)
			(layer "F.SilkS")
		)
		(fp_line
			(start 0.7874 0.4064)
			(end -0.7874 0.4064)
			(stroke
				(width 0.1524)
				(type default)
			)
			(layer "F.SilkS")
		)
		(fp_line
			(start -0.67945 -0.305054)
			(end -0.12065 -0.305054)
			(stroke
				(width 0.1)
				(type default)
			)
			(layer "F.Fab")
		)
		(fp_line
			(start -0.67945 0.3048)
			(end -0.67945 -0.305054)
			(stroke
				(width 0.1)
				(type default)
			)
			(layer "F.Fab")
		)
		(fp_line
			(start -0.12065 -0.305054)
			(end -0.12065 -0.2794)
			(stroke
				(width 0.1)
				(type default)
			)
			(layer "F.Fab")
		)
		(fp_line
			(start -0.12065 -0.2794)
			(end 0.12065 -0.2794)
			(stroke
				(width 0.1)
				(type default)
			)
			(layer "F.Fab")
		)
		(fp_line
			(start -0.12065 0.2794)
			(end -0.12065 0.3048)
			(stroke
				(width 0.1)
				(type default)
			)
			(layer "F.Fab")
		)
		(fp_line
			(start -0.12065 0.3048)
			(end -0.67945 0.3048)
			(stroke
				(width 0.1)
				(type default)
			)
			(layer "F.Fab")
		)
		(fp_line
			(start 0.120396 0.2794)
			(end -0.12065 0.2794)
			(stroke
				(width 0.1)
				(type default)
			)
			(layer "F.Fab")
		)
		(fp_line
			(start 0.120396 0.3048)
			(end 0.120396 0.2794)
			(stroke
				(width 0.1)
				(type default)
			)
			(layer "F.Fab")
		)
		(fp_line
			(start 0.12065 -0.3048)
			(end 0.67945 -0.3048)
			(stroke
				(width 0.1)
				(type default)
			)
			(layer "F.Fab")
		)
		(fp_line
			(start 0.12065 -0.2794)
			(end 0.12065 -0.3048)
			(stroke
				(width 0.1)
				(type default)
			)
			(layer "F.Fab")
		)
		(fp_line
			(start 0.67945 -0.3048)
			(end 0.67945 0.3048)
			(stroke
				(width 0.1)
				(type default)
			)
			(layer "F.Fab")
		)
		(fp_line
			(start 0.67945 0.3048)
			(end 0.120396 0.3048)
			(stroke
				(width 0.1)
				(type default)
			)
			(layer "F.Fab")
		)
		(pad "1" smd circle
			(at -0.40005 0)
			(size 0 0)
			(layers "F.Cu" "F.Mask" "F.Paste")
			(net "SMB_BIC_I2C6_MUX_THERMAL_R2_SCL")
		)
		(pad "2" smd circle
			(at 0.40005 0)
			(size 0 0)
			(layers "F.Cu" "F.Mask" "F.Paste")
			(net "SMB_LM75_3_SCL")
		)
	)
	(footprint ""
		(layer "F.Cu")
		(at 238.992664 -203.59116 180)
		(property "Reference" "OSC2"
			(at -1.422146 1.070102 0)
			(unlocked yes)
			(layer "F.SilkS")
			(effects
				(font
					(size 0.7874 0.5842)
					(thickness 0.1524)
				)
				(justify left)
			)
		)
		(property "Value" ""
			(at 0 0 180)
			(layer "F.Fab")
			(effects
				(font
					(size 1.27 1.27)
				)
			)
		)
		(duplicate_pad_numbers_are_jumpers no)
		(fp_line
			(start 1.299972 1.599946)
			(end -1.299972 1.599946)
			(stroke
				(width 0.1524)
				(type default)
			)
			(layer "F.SilkS")
		)
		(fp_line
			(start 1.299972 -1.599946)
			(end 1.299972 1.599946)
			(stroke
				(width 0.1524)
				(type default)
			)
			(layer "F.SilkS")
		)
		(fp_line
			(start -1.299972 1.599946)
			(end -1.299972 -1.599946)
			(stroke
				(width 0.1524)
				(type default)
			)
			(layer "F.SilkS")
		)
		(fp_line
			(start -1.299972 -1.599946)
			(end 1.299972 -1.599946)
			(stroke
				(width 0.1524)
				(type default)
			)
			(layer "F.SilkS")
		)
		(fp_poly
			(pts
				(xy -1.815592 0.656082) (xy -2.533904 -0.062484) (xy -1.456436 -0.42164)
			)
			(stroke
				(width 0)
				(type default)
			)
			(fill yes)
			(layer "F.SilkS")
		)
		(fp_line
			(start 1.050036 1.299972)
			(end -1.050036 1.299972)
			(stroke
				(width 0.1)
				(type default)
			)
			(layer "F.Fab")
		)
		(fp_line
			(start 1.050036 -1.299972)
			(end 1.050036 1.299972)
			(stroke
				(width 0.1)
				(type default)
			)
			(layer "F.Fab")
		)
		(fp_line
			(start -1.050036 1.299972)
			(end -1.050036 -1.299972)
			(stroke
				(width 0.1)
				(type default)
			)
			(layer "F.Fab")
		)
		(fp_line
			(start -1.050036 -1.299972)
			(end 1.050036 -1.299972)
			(stroke
				(width 0.1)
				(type default)
			)
			(layer "F.Fab")
		)
		(fp_poly
			(pts
				(xy -2.4892 -0.24892) (xy -2.4892 -1.26492) (xy -1.4732 -0.75692)
			)
			(stroke
				(width 0)
				(type default)
			)
			(fill yes)
			(layer "F.Fab")
		)
		(pad "1" smd rect
			(at -0.649986 -0.849884 180)
			(size 1.016 1.2192)
			(layers "F.Cu" "F.Mask" "F.Paste")
			(net "PU_CLK_25M_BIC_EN")
		)
		(pad "2" smd rect
			(at -0.649986 0.849884 180)
			(size 1.016 1.2192)
			(layers "F.Cu" "F.Mask" "F.Paste")
			(net "GND")
		)
		(pad "3" smd rect
			(at 0.649986 0.849884 180)
			(size 1.016 1.2192)
			(layers "F.Cu" "F.Mask" "F.Paste")
			(net "CLK_25M_BIC")
		)
		(pad "4" smd rect
			(at 0.649986 -0.849884 180)
			(size 1.016 1.2192)
			(layers "F.Cu" "F.Mask" "F.Paste")
			(net "P3V3_AUX")
		)
	)
	(footprint ""
		(layer "F.Cu")
		(at 143.432276 -32.848042 90)
		(property "Reference" "PC927"
			(at 0 0 90)
			(layer "F.SilkS")
			(hide yes)
			(effects
				(font
					(size 1.27 1.27)
				)
			)
		)
		(property "Value" ""
			(at 0 0 90)
			(layer "F.Fab")
			(effects
				(font
					(size 1.27 1.27)
				)
			)
		)
		(duplicate_pad_numbers_are_jumpers no)
		(fp_line
			(start 0.7874 -0.4064)
			(end 0.7874 0.4064)
			(stroke
				(width 0.1524)
				(type default)
			)
			(layer "F.SilkS")
		)
		(fp_line
			(start -0.7874 -0.4064)
			(end 0.7874 -0.4064)
			(stroke
				(width 0.1524)
				(type default)
			)
			(layer "F.SilkS")
		)
		(fp_line
			(start 0.7874 0.4064)
			(end -0.7874 0.4064)
			(stroke
				(width 0.1524)
				(type default)
			)
			(layer "F.SilkS")
		)
		(fp_line
			(start -0.7874 0.4064)
			(end -0.7874 -0.4064)
			(stroke
				(width 0.1524)
				(type default)
			)
			(layer "F.SilkS")
		)
		(fp_line
			(start -0.12065 -0.305054)
			(end -0.12065 -0.2794)
			(stroke
				(width 0.1)
				(type default)
			)
			(layer "F.Fab")
		)
		(fp_line
			(start -0.67945 -0.305054)
			(end -0.12065 -0.305054)
			(stroke
				(width 0.1)
				(type default)
			)
			(layer "F.Fab")
		)
		(fp_line
			(start 0.67945 -0.3048)
			(end 0.67945 0.3048)
			(stroke
				(width 0.1)
				(type default)
			)
			(layer "F.Fab")
		)
		(fp_line
			(start 0.12065 -0.3048)
			(end 0.67945 -0.3048)
			(stroke
				(width 0.1)
				(type default)
			)
			(layer "F.Fab")
		)
		(fp_line
			(start 0.12065 -0.2794)
			(end 0.12065 -0.3048)
			(stroke
				(width 0.1)
				(type default)
			)
			(layer "F.Fab")
		)
		(fp_line
			(start -0.12065 -0.2794)
			(end 0.12065 -0.2794)
			(stroke
				(width 0.1)
				(type default)
			)
			(layer "F.Fab")
		)
		(fp_line
			(start 0.120396 0.2794)
			(end -0.12065 0.2794)
			(stroke
				(width 0.1)
				(type default)
			)
			(layer "F.Fab")
		)
		(fp_line
			(start -0.12065 0.2794)
			(end -0.12065 0.3048)
			(stroke
				(width 0.1)
				(type default)
			)
			(layer "F.Fab")
		)
		(fp_line
			(start 0.67945 0.3048)
			(end 0.120396 0.3048)
			(stroke
				(width 0.1)
				(type default)
			)
			(layer "F.Fab")
		)
		(fp_line
			(start 0.120396 0.3048)
			(end 0.120396 0.2794)
			(stroke
				(width 0.1)
				(type default)
			)
			(layer "F.Fab")
		)
		(fp_line
			(start -0.12065 0.3048)
			(end -0.67945 0.3048)
			(stroke
				(width 0.1)
				(type default)
			)
			(layer "F.Fab")
		)
		(fp_line
			(start -0.67945 0.3048)
			(end -0.67945 -0.305054)
			(stroke
				(width 0.1)
				(type default)
			)
			(layer "F.Fab")
		)
		(pad "1" smd circle
			(at -0.40005 0 90)
			(size 0 0)
			(layers "F.Cu" "F.Mask" "F.Paste")
			(net "P3V3_SSD5_CO_DV_DT")
		)
		(pad "2" smd circle
			(at 0.40005 0 90)
			(size 0 0)
			(layers "F.Cu" "F.Mask" "F.Paste")
			(net "GND")
		)
	)
	(footprint ""
		(layer "F.Cu")
		(at 160.82264 -44.341542 90)
		(property "Reference" "R569"
			(at 0 0 90)
			(layer "F.SilkS")
			(hide yes)
			(effects
				(font
					(size 1.27 1.27)
				)
			)
		)
		(property "Value" ""
			(at 0 0 90)
			(layer "F.Fab")
			(effects
				(font
					(size 1.27 1.27)
				)
			)
		)
		(duplicate_pad_numbers_are_jumpers no)
		(fp_line
			(start 0.7874 -0.4064)
			(end 0.7874 0.4064)
			(stroke
				(width 0.1524)
				(type default)
			)
			(layer "F.SilkS")
		)
		(fp_line
			(start -0.7874 -0.4064)
			(end 0.7874 -0.4064)
			(stroke
				(width 0.1524)
				(type default)
			)
			(layer "F.SilkS")
		)
		(fp_line
			(start 0.7874 0.4064)
			(end -0.7874 0.4064)
			(stroke
				(width 0.1524)
				(type default)
			)
			(layer "F.SilkS")
		)
		(fp_line
			(start -0.7874 0.4064)
			(end -0.7874 -0.4064)
			(stroke
				(width 0.1524)
				(type default)
			)
			(layer "F.SilkS")
		)
		(fp_line
			(start -0.12065 -0.305054)
			(end -0.12065 -0.2794)
			(stroke
				(width 0.1)
				(type default)
			)
			(layer "F.Fab")
		)
		(fp_line
			(start -0.67945 -0.305054)
			(end -0.12065 -0.305054)
			(stroke
				(width 0.1)
				(type default)
			)
			(layer "F.Fab")
		)
		(fp_line
			(start 0.67945 -0.3048)
			(end 0.67945 0.3048)
			(stroke
				(width 0.1)
				(type default)
			)
			(layer "F.Fab")
		)
		(fp_line
			(start 0.12065 -0.3048)
			(end 0.67945 -0.3048)
			(stroke
				(width 0.1)
				(type default)
			)
			(layer "F.Fab")
		)
		(fp_line
			(start 0.12065 -0.2794)
			(end 0.12065 -0.3048)
			(stroke
				(width 0.1)
				(type default)
			)
			(layer "F.Fab")
		)
		(fp_line
			(start -0.12065 -0.2794)
			(end 0.12065 -0.2794)
			(stroke
				(width 0.1)
				(type default)
			)
			(layer "F.Fab")
		)
		(fp_line
			(start 0.120396 0.2794)
			(end -0.12065 0.2794)
			(stroke
				(width 0.1)
				(type default)
			)
			(layer "F.Fab")
		)
		(fp_line
			(start -0.12065 0.2794)
			(end -0.12065 0.3048)
			(stroke
				(width 0.1)
				(type default)
			)
			(layer "F.Fab")
		)
		(fp_line
			(start 0.67945 0.3048)
			(end 0.120396 0.3048)
			(stroke
				(width 0.1)
				(type default)
			)
			(layer "F.Fab")
		)
		(fp_line
			(start 0.120396 0.3048)
			(end 0.120396 0.2794)
			(stroke
				(width 0.1)
				(type default)
			)
			(layer "F.Fab")
		)
		(fp_line
			(start -0.12065 0.3048)
			(end -0.67945 0.3048)
			(stroke
				(width 0.1)
				(type default)
			)
			(layer "F.Fab")
		)
		(fp_line
			(start -0.67945 0.3048)
			(end -0.67945 -0.305054)
			(stroke
				(width 0.1)
				(type default)
			)
			(layer "F.Fab")
		)
		(pad "1" smd circle
			(at -0.40005 0 90)
			(size 0 0)
			(layers "F.Cu" "F.Mask" "F.Paste")
			(net "P12V_SSD5")
		)
		(pad "2" smd circle
			(at 0.40005 0 90)
			(size 0 0)
			(layers "F.Cu" "F.Mask" "F.Paste")
			(net "P12V_SSD5_VIN_N")
		)
	)
	(footprint ""
		(layer "F.Cu")
		(at 156.698442 -250.070874 -90)
		(property "Reference" "R1270"
			(at 0 0 270)
			(layer "F.SilkS")
			(hide yes)
			(effects
				(font
					(size 1.27 1.27)
				)
			)
		)
		(property "Value" ""
			(at 0 0 270)
			(layer "F.Fab")
			(effects
				(font
					(size 1.27 1.27)
				)
			)
		)
		(duplicate_pad_numbers_are_jumpers no)
		(fp_line
			(start -0.7874 0.4064)
			(end -0.7874 -0.4064)
			(stroke
				(width 0.1524)
				(type default)
			)
			(layer "F.SilkS")
		)
		(fp_line
			(start 0.7874 0.4064)
			(end -0.7874 0.4064)
			(stroke
				(width 0.1524)
				(type default)
			)
			(layer "F.SilkS")
		)
		(fp_line
			(start -0.7874 -0.4064)
			(end 0.7874 -0.4064)
			(stroke
				(width 0.1524)
				(type default)
			)
			(layer "F.SilkS")
		)
		(fp_line
			(start 0.7874 -0.4064)
			(end 0.7874 0.4064)
			(stroke
				(width 0.1524)
				(type default)
			)
			(layer "F.SilkS")
		)
		(fp_line
			(start -0.67945 0.3048)
			(end -0.67945 -0.305054)
			(stroke
				(width 0.1)
				(type default)
			)
			(layer "F.Fab")
		)
		(fp_line
			(start -0.12065 0.3048)
			(end -0.67945 0.3048)
			(stroke
				(width 0.1)
				(type default)
			)
			(layer "F.Fab")
		)
		(fp_line
			(start 0.120396 0.3048)
			(end 0.120396 0.2794)
			(stroke
				(width 0.1)
				(type default)
			)
			(layer "F.Fab")
		)
		(fp_line
			(start 0.67945 0.3048)
			(end 0.120396 0.3048)
			(stroke
				(width 0.1)
				(type default)
			)
			(layer "F.Fab")
		)
		(fp_line
			(start -0.12065 0.2794)
			(end -0.12065 0.3048)
			(stroke
				(width 0.1)
				(type default)
			)
			(layer "F.Fab")
		)
		(fp_line
			(start 0.120396 0.2794)
			(end -0.12065 0.2794)
			(stroke
				(width 0.1)
				(type default)
			)
			(layer "F.Fab")
		)
		(fp_line
			(start -0.12065 -0.2794)
			(end 0.12065 -0.2794)
			(stroke
				(width 0.1)
				(type default)
			)
			(layer "F.Fab")
		)
		(fp_line
			(start 0.12065 -0.2794)
			(end 0.12065 -0.3048)
			(stroke
				(width 0.1)
				(type default)
			)
			(layer "F.Fab")
		)
		(fp_line
			(start 0.12065 -0.3048)
			(end 0.67945 -0.3048)
			(stroke
				(width 0.1)
				(type default)
			)
			(layer "F.Fab")
		)
		(fp_line
			(start 0.67945 -0.3048)
			(end 0.67945 0.3048)
			(stroke
				(width 0.1)
				(type default)
			)
			(layer "F.Fab")
		)
		(fp_line
			(start -0.67945 -0.305054)
			(end -0.12065 -0.305054)
			(stroke
				(width 0.1)
				(type default)
			)
			(layer "F.Fab")
		)
		(fp_line
			(start -0.12065 -0.305054)
			(end -0.12065 -0.2794)
			(stroke
				(width 0.1)
				(type default)
			)
			(layer "F.Fab")
		)
		(pad "1" smd circle
			(at -0.40005 0 270)
			(size 0 0)
			(layers "F.Cu" "F.Mask" "F.Paste")
			(net "PEX1_MODE_SEL1")
		)
		(pad "2" smd circle
			(at 0.40005 0 270)
			(size 0 0)
			(layers "F.Cu" "F.Mask" "F.Paste")
			(net "P1V8_PEX")
		)
	)
	(footprint ""
		(layer "F.Cu")
		(at 271.480534 -99.288854)
		(property "Reference" "C485"
			(at 0 0 0)
			(layer "F.SilkS")
			(hide yes)
			(effects
				(font
					(size 1.27 1.27)
				)
			)
		)
		(property "Value" ""
			(at 0 0 0)
			(layer "F.Fab")
			(effects
				(font
					(size 1.27 1.27)
				)
			)
		)
		(duplicate_pad_numbers_are_jumpers no)
		(fp_line
			(start -0.299974 -0.150114)
			(end 0.299974 -0.150114)
			(stroke
				(width 0.1)
				(type default)
			)
			(layer "F.Fab")
		)
		(fp_line
			(start -0.299974 0.150114)
			(end -0.299974 -0.150114)
			(stroke
				(width 0.1)
				(type default)
			)
			(layer "F.Fab")
		)
		(fp_line
			(start 0.299974 -0.150114)
			(end 0.299974 0.150114)
			(stroke
				(width 0.1)
				(type default)
			)
			(layer "F.Fab")
		)
		(fp_line
			(start 0.299974 0.150114)
			(end -0.299974 0.150114)
			(stroke
				(width 0.1)
				(type default)
			)
			(layer "F.Fab")
		)
		(pad "1" smd rect
			(at -0.2667 0)
			(size 0.3048 0.381)
			(layers "F.Cu" "F.Mask" "F.Paste")
			(net "P5E_PEX2_STN1_TX_DP<16>")
		)
		(pad "2" smd rect
			(at 0.2667 0)
			(size 0.3048 0.381)
			(layers "F.Cu" "F.Mask" "F.Paste")
			(net "P5E_PEX2_STN1_TX_C_DP<16>")
		)
	)
	(footprint ""
		(layer "F.Cu")
		(at 150.2791 -59.577986 -90)
		(property "Reference" "R889"
			(at 0 0 270)
			(layer "F.SilkS")
			(hide yes)
			(effects
				(font
					(size 1.27 1.27)
				)
			)
		)
		(property "Value" ""
			(at 0 0 270)
			(layer "F.Fab")
			(effects
				(font
					(size 1.27 1.27)
				)
			)
		)
		(duplicate_pad_numbers_are_jumpers no)
		(fp_line
			(start -0.7874 0.4064)
			(end -0.7874 -0.4064)
			(stroke
				(width 0.1524)
				(type default)
			)
			(layer "F.SilkS")
		)
		(fp_line
			(start 0.7874 0.4064)
			(end -0.7874 0.4064)
			(stroke
				(width 0.1524)
				(type default)
			)
			(layer "F.SilkS")
		)
		(fp_line
			(start -0.7874 -0.4064)
			(end 0.7874 -0.4064)
			(stroke
				(width 0.1524)
				(type default)
			)
			(layer "F.SilkS")
		)
		(fp_line
			(start 0.7874 -0.4064)
			(end 0.7874 0.4064)
			(stroke
				(width 0.1524)
				(type default)
			)
			(layer "F.SilkS")
		)
		(fp_line
			(start -0.67945 0.3048)
			(end -0.67945 -0.305054)
			(stroke
				(width 0.1)
				(type default)
			)
			(layer "F.Fab")
		)
		(fp_line
			(start -0.12065 0.3048)
			(end -0.67945 0.3048)
			(stroke
				(width 0.1)
				(type default)
			)
			(layer "F.Fab")
		)
		(fp_line
			(start 0.120396 0.3048)
			(end 0.120396 0.2794)
			(stroke
				(width 0.1)
				(type default)
			)
			(layer "F.Fab")
		)
		(fp_line
			(start 0.67945 0.3048)
			(end 0.120396 0.3048)
			(stroke
				(width 0.1)
				(type default)
			)
			(layer "F.Fab")
		)
		(fp_line
			(start -0.12065 0.2794)
			(end -0.12065 0.3048)
			(stroke
				(width 0.1)
				(type default)
			)
			(layer "F.Fab")
		)
		(fp_line
			(start 0.120396 0.2794)
			(end -0.12065 0.2794)
			(stroke
				(width 0.1)
				(type default)
			)
			(layer "F.Fab")
		)
		(fp_line
			(start -0.12065 -0.2794)
			(end 0.12065 -0.2794)
			(stroke
				(width 0.1)
				(type default)
			)
			(layer "F.Fab")
		)
		(fp_line
			(start 0.12065 -0.2794)
			(end 0.12065 -0.3048)
			(stroke
				(width 0.1)
				(type default)
			)
			(layer "F.Fab")
		)
		(fp_line
			(start 0.12065 -0.3048)
			(end 0.67945 -0.3048)
			(stroke
				(width 0.1)
				(type default)
			)
			(layer "F.Fab")
		)
		(fp_line
			(start 0.67945 -0.3048)
			(end 0.67945 0.3048)
			(stroke
				(width 0.1)
				(type default)
			)
			(layer "F.Fab")
		)
		(fp_line
			(start -0.67945 -0.305054)
			(end -0.12065 -0.305054)
			(stroke
				(width 0.1)
				(type default)
			)
			(layer "F.Fab")
		)
		(fp_line
			(start -0.12065 -0.305054)
			(end -0.12065 -0.2794)
			(stroke
				(width 0.1)
				(type default)
			)
			(layer "F.Fab")
		)
		(pad "1" smd circle
			(at -0.40005 0 270)
			(size 0 0)
			(layers "F.Cu" "F.Mask" "F.Paste")
			(net "P3V3_SSD5")
		)
		(pad "2" smd circle
			(at 0.40005 0 270)
			(size 0 0)
			(layers "F.Cu" "F.Mask" "F.Paste")
			(net "PWRGD_P3V3_SSD5")
		)
	)
	(footprint ""
		(layer "F.Cu")
		(at 260.606286 -252.356874 -90)
		(property "Reference" "R1354"
			(at 0 0 270)
			(layer "F.SilkS")
			(hide yes)
			(effects
				(font
					(size 1.27 1.27)
				)
			)
		)
		(property "Value" ""
			(at 0 0 270)
			(layer "F.Fab")
			(effects
				(font
					(size 1.27 1.27)
				)
			)
		)
		(duplicate_pad_numbers_are_jumpers no)
		(fp_line
			(start -0.7874 0.4064)
			(end -0.7874 -0.4064)
			(stroke
				(width 0.1524)
				(type default)
			)
			(layer "F.SilkS")
		)
		(fp_line
			(start 0.7874 0.4064)
			(end -0.7874 0.4064)
			(stroke
				(width 0.1524)
				(type default)
			)
			(layer "F.SilkS")
		)
		(fp_line
			(start -0.7874 -0.4064)
			(end 0.7874 -0.4064)
			(stroke
				(width 0.1524)
				(type default)
			)
			(layer "F.SilkS")
		)
		(fp_line
			(start 0.7874 -0.4064)
			(end 0.7874 0.4064)
			(stroke
				(width 0.1524)
				(type default)
			)
			(layer "F.SilkS")
		)
		(fp_line
			(start -0.67945 0.3048)
			(end -0.67945 -0.305054)
			(stroke
				(width 0.1)
				(type default)
			)
			(layer "F.Fab")
		)
		(fp_line
			(start -0.12065 0.3048)
			(end -0.67945 0.3048)
			(stroke
				(width 0.1)
				(type default)
			)
			(layer "F.Fab")
		)
		(fp_line
			(start 0.120396 0.3048)
			(end 0.120396 0.2794)
			(stroke
				(width 0.1)
				(type default)
			)
			(layer "F.Fab")
		)
		(fp_line
			(start 0.67945 0.3048)
			(end 0.120396 0.3048)
			(stroke
				(width 0.1)
				(type default)
			)
			(layer "F.Fab")
		)
		(fp_line
			(start -0.12065 0.2794)
			(end -0.12065 0.3048)
			(stroke
				(width 0.1)
				(type default)
			)
			(layer "F.Fab")
		)
		(fp_line
			(start 0.120396 0.2794)
			(end -0.12065 0.2794)
			(stroke
				(width 0.1)
				(type default)
			)
			(layer "F.Fab")
		)
		(fp_line
			(start -0.12065 -0.2794)
			(end 0.12065 -0.2794)
			(stroke
				(width 0.1)
				(type default)
			)
			(layer "F.Fab")
		)
		(fp_line
			(start 0.12065 -0.2794)
			(end 0.12065 -0.3048)
			(stroke
				(width 0.1)
				(type default)
			)
			(layer "F.Fab")
		)
		(fp_line
			(start 0.12065 -0.3048)
			(end 0.67945 -0.3048)
			(stroke
				(width 0.1)
				(type default)
			)
			(layer "F.Fab")
		)
		(fp_line
			(start 0.67945 -0.3048)
			(end 0.67945 0.3048)
			(stroke
				(width 0.1)
				(type default)
			)
			(layer "F.Fab")
		)
		(fp_line
			(start -0.67945 -0.305054)
			(end -0.12065 -0.305054)
			(stroke
				(width 0.1)
				(type default)
			)
			(layer "F.Fab")
		)
		(fp_line
			(start -0.12065 -0.305054)
			(end -0.12065 -0.2794)
			(stroke
				(width 0.1)
				(type default)
			)
			(layer "F.Fab")
		)
		(pad "1" smd circle
			(at -0.40005 0 270)
			(size 0 0)
			(layers "F.Cu" "F.Mask" "F.Paste")
			(net "GND")
		)
		(pad "2" smd circle
			(at 0.40005 0 270)
			(size 0 0)
			(layers "F.Cu" "F.Mask" "F.Paste")
			(net "PEX2_DBG_MODE3")
		)
	)
	(footprint ""
		(layer "F.Cu")
		(at 490.661452 -554.392338 180)
		(property "Reference" "SCREW_SSD6_1"
			(at -5.207 -1.402334 0)
			(unlocked yes)
			(layer "B.SilkS")
			(effects
				(font
					(size 0.7874 0.5842)
					(thickness 0.1524)
				)
				(justify mirror)
			)
		)
		(property "Value" ""
			(at 0 0 180)
			(layer "F.Fab")
			(effects
				(font
					(size 1.27 1.27)
				)
			)
		)
		(duplicate_pad_numbers_are_jumpers no)
		(pad "1" thru_hole circle
			(at 0 0 180)
			(size 0.4572 0.4572)
			(drill 0.2032)
			(layers "*.Cu" "*.Mask")
			(remove_unused_layers no)
			(net "Net_9132")
			(clearance 0.127)
			(thermal_gap 0.127)
			(padstack
				(mode front_inner_back)
				(layer "Inner"
					(shape circle)
					(size 0.4572 0.4572)
					(clearance 0.127)
				)
				(layer "B.Cu"
					(shape circle)
					(size 0.508 0.508)
					(clearance 0.1016)
				)
			)
		)
	)
	(footprint ""
		(layer "F.Cu")
		(at 255.32842 -260.807708 90)
		(property "Reference" "R5801"
			(at 0 0 90)
			(layer "F.SilkS")
			(hide yes)
			(effects
				(font
					(size 1.27 1.27)
				)
			)
		)
		(property "Value" ""
			(at 0 0 90)
			(layer "F.Fab")
			(effects
				(font
					(size 1.27 1.27)
				)
			)
		)
		(duplicate_pad_numbers_are_jumpers no)
		(fp_line
			(start 0.7874 -0.4064)
			(end 0.7874 0.4064)
			(stroke
				(width 0.1524)
				(type default)
			)
			(layer "F.SilkS")
		)
		(fp_line
			(start -0.7874 -0.4064)
			(end 0.7874 -0.4064)
			(stroke
				(width 0.1524)
				(type default)
			)
			(layer "F.SilkS")
		)
		(fp_line
			(start 0.7874 0.4064)
			(end -0.7874 0.4064)
			(stroke
				(width 0.1524)
				(type default)
			)
			(layer "F.SilkS")
		)
		(fp_line
			(start -0.7874 0.4064)
			(end -0.7874 -0.4064)
			(stroke
				(width 0.1524)
				(type default)
			)
			(layer "F.SilkS")
		)
		(fp_line
			(start -0.12065 -0.305054)
			(end -0.12065 -0.2794)
			(stroke
				(width 0.1)
				(type default)
			)
			(layer "F.Fab")
		)
		(fp_line
			(start -0.67945 -0.305054)
			(end -0.12065 -0.305054)
			(stroke
				(width 0.1)
				(type default)
			)
			(layer "F.Fab")
		)
		(fp_line
			(start 0.67945 -0.3048)
			(end 0.67945 0.3048)
			(stroke
				(width 0.1)
				(type default)
			)
			(layer "F.Fab")
		)
		(fp_line
			(start 0.12065 -0.3048)
			(end 0.67945 -0.3048)
			(stroke
				(width 0.1)
				(type default)
			)
			(layer "F.Fab")
		)
		(fp_line
			(start 0.12065 -0.2794)
			(end 0.12065 -0.3048)
			(stroke
				(width 0.1)
				(type default)
			)
			(layer "F.Fab")
		)
		(fp_line
			(start -0.12065 -0.2794)
			(end 0.12065 -0.2794)
			(stroke
				(width 0.1)
				(type default)
			)
			(layer "F.Fab")
		)
		(fp_line
			(start 0.120396 0.2794)
			(end -0.12065 0.2794)
			(stroke
				(width 0.1)
				(type default)
			)
			(layer "F.Fab")
		)
		(fp_line
			(start -0.12065 0.2794)
			(end -0.12065 0.3048)
			(stroke
				(width 0.1)
				(type default)
			)
			(layer "F.Fab")
		)
		(fp_line
			(start 0.67945 0.3048)
			(end 0.120396 0.3048)
			(stroke
				(width 0.1)
				(type default)
			)
			(layer "F.Fab")
		)
		(fp_line
			(start 0.120396 0.3048)
			(end 0.120396 0.2794)
			(stroke
				(width 0.1)
				(type default)
			)
			(layer "F.Fab")
		)
		(fp_line
			(start -0.12065 0.3048)
			(end -0.67945 0.3048)
			(stroke
				(width 0.1)
				(type default)
			)
			(layer "F.Fab")
		)
		(fp_line
			(start -0.67945 0.3048)
			(end -0.67945 -0.305054)
			(stroke
				(width 0.1)
				(type default)
			)
			(layer "F.Fab")
		)
		(pad "1" smd circle
			(at -0.40005 0 90)
			(size 0 0)
			(layers "F.Cu" "F.Mask" "F.Paste")
			(net "PEX2_SYS_ERR_N_G")
		)
		(pad "2" smd circle
			(at 0.40005 0 90)
			(size 0 0)
			(layers "F.Cu" "F.Mask" "F.Paste")
			(net "PEX2_SYS_ERR_FPGA")
		)
	)
	(footprint ""
		(layer "F.Cu")
		(at 196.375528 -368.26698 180)
		(property "Reference" "R6249"
			(at 0 0 180)
			(layer "F.SilkS")
			(hide yes)
			(effects
				(font
					(size 1.27 1.27)
				)
			)
		)
		(property "Value" ""
			(at 0 0 180)
			(layer "F.Fab")
			(effects
				(font
					(size 1.27 1.27)
				)
			)
		)
		(duplicate_pad_numbers_are_jumpers no)
		(fp_line
			(start 0.7874 0.4064)
			(end -0.7874 0.4064)
			(stroke
				(width 0.1524)
				(type default)
			)
			(layer "F.SilkS")
		)
		(fp_line
			(start 0.7874 -0.4064)
			(end 0.7874 0.4064)
			(stroke
				(width 0.1524)
				(type default)
			)
			(layer "F.SilkS")
		)
		(fp_line
			(start -0.7874 0.4064)
			(end -0.7874 -0.4064)
			(stroke
				(width 0.1524)
				(type default)
			)
			(layer "F.SilkS")
		)
		(fp_line
			(start -0.7874 -0.4064)
			(end 0.7874 -0.4064)
			(stroke
				(width 0.1524)
				(type default)
			)
			(layer "F.SilkS")
		)
		(fp_line
			(start 0.67945 0.3048)
			(end 0.120396 0.3048)
			(stroke
				(width 0.1)
				(type default)
			)
			(layer "F.Fab")
		)
		(fp_line
			(start 0.67945 -0.3048)
			(end 0.67945 0.3048)
			(stroke
				(width 0.1)
				(type default)
			)
			(layer "F.Fab")
		)
		(fp_line
			(start 0.12065 -0.2794)
			(end 0.12065 -0.3048)
			(stroke
				(width 0.1)
				(type default)
			)
			(layer "F.Fab")
		)
		(fp_line
			(start 0.12065 -0.3048)
			(end 0.67945 -0.3048)
			(stroke
				(width 0.1)
				(type default)
			)
			(layer "F.Fab")
		)
		(fp_line
			(start 0.120396 0.3048)
			(end 0.120396 0.2794)
			(stroke
				(width 0.1)
				(type default)
			)
			(layer "F.Fab")
		)
		(fp_line
			(start 0.120396 0.2794)
			(end -0.12065 0.2794)
			(stroke
				(width 0.1)
				(type default)
			)
			(layer "F.Fab")
		)
		(fp_line
			(start -0.12065 0.3048)
			(end -0.67945 0.3048)
			(stroke
				(width 0.1)
				(type default)
			)
			(layer "F.Fab")
		)
		(fp_line
			(start -0.12065 0.2794)
			(end -0.12065 0.3048)
			(stroke
				(width 0.1)
				(type default)
			)
			(layer "F.Fab")
		)
		(fp_line
			(start -0.12065 -0.2794)
			(end 0.12065 -0.2794)
			(stroke
				(width 0.1)
				(type default)
			)
			(layer "F.Fab")
		)
		(fp_line
			(start -0.12065 -0.305054)
			(end -0.12065 -0.2794)
			(stroke
				(width 0.1)
				(type default)
			)
			(layer "F.Fab")
		)
		(fp_line
			(start -0.67945 0.3048)
			(end -0.67945 -0.305054)
			(stroke
				(width 0.1)
				(type default)
			)
			(layer "F.Fab")
		)
		(fp_line
			(start -0.67945 -0.305054)
			(end -0.12065 -0.305054)
			(stroke
				(width 0.1)
				(type default)
			)
			(layer "F.Fab")
		)
		(pad "1" smd circle
			(at -0.40005 0 180)
			(size 0 0)
			(layers "F.Cu" "F.Mask" "F.Paste")
			(net "FM_HSC_PWROK")
		)
		(pad "2" smd circle
			(at 0.40005 0 180)
			(size 0 0)
			(layers "F.Cu" "F.Mask" "F.Paste")
			(net "P12V_AUX")
		)
	)
	(footprint ""
		(layer "F.Cu")
		(at 242.347496 -223.91878 90)
		(property "Reference" "R6194"
			(at 0 0 90)
			(layer "F.SilkS")
			(hide yes)
			(effects
				(font
					(size 1.27 1.27)
				)
			)
		)
		(property "Value" ""
			(at 0 0 90)
			(layer "F.Fab")
			(effects
				(font
					(size 1.27 1.27)
				)
			)
		)
		(duplicate_pad_numbers_are_jumpers no)
		(fp_line
			(start 0.7874 -0.4064)
			(end 0.7874 0.4064)
			(stroke
				(width 0.1524)
				(type default)
			)
			(layer "F.SilkS")
		)
		(fp_line
			(start -0.7874 -0.4064)
			(end 0.7874 -0.4064)
			(stroke
				(width 0.1524)
				(type default)
			)
			(layer "F.SilkS")
		)
		(fp_line
			(start 0.7874 0.4064)
			(end -0.7874 0.4064)
			(stroke
				(width 0.1524)
				(type default)
			)
			(layer "F.SilkS")
		)
		(fp_line
			(start -0.7874 0.4064)
			(end -0.7874 -0.4064)
			(stroke
				(width 0.1524)
				(type default)
			)
			(layer "F.SilkS")
		)
		(fp_line
			(start -0.12065 -0.305054)
			(end -0.12065 -0.2794)
			(stroke
				(width 0.1)
				(type default)
			)
			(layer "F.Fab")
		)
		(fp_line
			(start -0.67945 -0.305054)
			(end -0.12065 -0.305054)
			(stroke
				(width 0.1)
				(type default)
			)
			(layer "F.Fab")
		)
		(fp_line
			(start 0.67945 -0.3048)
			(end 0.67945 0.3048)
			(stroke
				(width 0.1)
				(type default)
			)
			(layer "F.Fab")
		)
		(fp_line
			(start 0.12065 -0.3048)
			(end 0.67945 -0.3048)
			(stroke
				(width 0.1)
				(type default)
			)
			(layer "F.Fab")
		)
		(fp_line
			(start 0.12065 -0.2794)
			(end 0.12065 -0.3048)
			(stroke
				(width 0.1)
				(type default)
			)
			(layer "F.Fab")
		)
		(fp_line
			(start -0.12065 -0.2794)
			(end 0.12065 -0.2794)
			(stroke
				(width 0.1)
				(type default)
			)
			(layer "F.Fab")
		)
		(fp_line
			(start 0.120396 0.2794)
			(end -0.12065 0.2794)
			(stroke
				(width 0.1)
				(type default)
			)
			(layer "F.Fab")
		)
		(fp_line
			(start -0.12065 0.2794)
			(end -0.12065 0.3048)
			(stroke
				(width 0.1)
				(type default)
			)
			(layer "F.Fab")
		)
		(fp_line
			(start 0.67945 0.3048)
			(end 0.120396 0.3048)
			(stroke
				(width 0.1)
				(type default)
			)
			(layer "F.Fab")
		)
		(fp_line
			(start 0.120396 0.3048)
			(end 0.120396 0.2794)
			(stroke
				(width 0.1)
				(type default)
			)
			(layer "F.Fab")
		)
		(fp_line
			(start -0.12065 0.3048)
			(end -0.67945 0.3048)
			(stroke
				(width 0.1)
				(type default)
			)
			(layer "F.Fab")
		)
		(fp_line
			(start -0.67945 0.3048)
			(end -0.67945 -0.305054)
			(stroke
				(width 0.1)
				(type default)
			)
			(layer "F.Fab")
		)
		(pad "1" smd circle
			(at -0.40005 0 90)
			(size 0 0)
			(layers "F.Cu" "F.Mask" "F.Paste")
			(net "GND")
		)
		(pad "2" smd circle
			(at 0.40005 0 90)
			(size 0 0)
			(layers "F.Cu" "F.Mask" "F.Paste")
			(net "SSD12_PWRDIS_BIC_R")
		)
	)
	(footprint ""
		(layer "F.Cu")
		(at 281.221942 -356.244906 90)
		(property "Reference" "C2354"
			(at 0 0 90)
			(layer "F.SilkS")
			(hide yes)
			(effects
				(font
					(size 1.27 1.27)
				)
			)
		)
		(property "Value" ""
			(at 0 0 90)
			(layer "F.Fab")
			(effects
				(font
					(size 1.27 1.27)
				)
			)
		)
		(duplicate_pad_numbers_are_jumpers no)
		(fp_line
			(start 0.299974 -0.150114)
			(end 0.299974 0.150114)
			(stroke
				(width 0.1)
				(type default)
			)
			(layer "F.Fab")
		)
		(fp_line
			(start -0.299974 -0.150114)
			(end 0.299974 -0.150114)
			(stroke
				(width 0.1)
				(type default)
			)
			(layer "F.Fab")
		)
		(fp_line
			(start 0.299974 0.150114)
			(end -0.299974 0.150114)
			(stroke
				(width 0.1)
				(type default)
			)
			(layer "F.Fab")
		)
		(fp_line
			(start -0.299974 0.150114)
			(end -0.299974 -0.150114)
			(stroke
				(width 0.1)
				(type default)
			)
			(layer "F.Fab")
		)
		(pad "1" smd rect
			(at -0.2667 0 90)
			(size 0.3048 0.381)
			(layers "F.Cu" "F.Mask" "F.Paste")
			(net "P5E_PEX2_STN4_TX_DN<73>")
		)
		(pad "2" smd rect
			(at 0.2667 0 90)
			(size 0.3048 0.381)
			(layers "F.Cu" "F.Mask" "F.Paste")
			(net "P5E_PEX2_STN4_TX_C_DN<73>")
		)
	)
	(footprint ""
		(layer "F.Cu")
		(at 350.139 -234.061 -90)
		(property "Reference" "R3576"
			(at 0 0 270)
			(layer "F.SilkS")
			(hide yes)
			(effects
				(font
					(size 1.27 1.27)
				)
			)
		)
		(property "Value" ""
			(at 0 0 270)
			(layer "F.Fab")
			(effects
				(font
					(size 1.27 1.27)
				)
			)
		)
		(duplicate_pad_numbers_are_jumpers no)
		(fp_line
			(start -0.7874 0.4064)
			(end -0.7874 -0.4064)
			(stroke
				(width 0.1524)
				(type default)
			)
			(layer "F.SilkS")
		)
		(fp_line
			(start 0.7874 0.4064)
			(end -0.7874 0.4064)
			(stroke
				(width 0.1524)
				(type default)
			)
			(layer "F.SilkS")
		)
		(fp_line
			(start -0.7874 -0.4064)
			(end 0.7874 -0.4064)
			(stroke
				(width 0.1524)
				(type default)
			)
			(layer "F.SilkS")
		)
		(fp_line
			(start 0.7874 -0.4064)
			(end 0.7874 0.4064)
			(stroke
				(width 0.1524)
				(type default)
			)
			(layer "F.SilkS")
		)
		(fp_line
			(start -0.67945 0.3048)
			(end -0.67945 -0.305054)
			(stroke
				(width 0.1)
				(type default)
			)
			(layer "F.Fab")
		)
		(fp_line
			(start -0.12065 0.3048)
			(end -0.67945 0.3048)
			(stroke
				(width 0.1)
				(type default)
			)
			(layer "F.Fab")
		)
		(fp_line
			(start 0.120396 0.3048)
			(end 0.120396 0.2794)
			(stroke
				(width 0.1)
				(type default)
			)
			(layer "F.Fab")
		)
		(fp_line
			(start 0.67945 0.3048)
			(end 0.120396 0.3048)
			(stroke
				(width 0.1)
				(type default)
			)
			(layer "F.Fab")
		)
		(fp_line
			(start -0.12065 0.2794)
			(end -0.12065 0.3048)
			(stroke
				(width 0.1)
				(type default)
			)
			(layer "F.Fab")
		)
		(fp_line
			(start 0.120396 0.2794)
			(end -0.12065 0.2794)
			(stroke
				(width 0.1)
				(type default)
			)
			(layer "F.Fab")
		)
		(fp_line
			(start -0.12065 -0.2794)
			(end 0.12065 -0.2794)
			(stroke
				(width 0.1)
				(type default)
			)
			(layer "F.Fab")
		)
		(fp_line
			(start 0.12065 -0.2794)
			(end 0.12065 -0.3048)
			(stroke
				(width 0.1)
				(type default)
			)
			(layer "F.Fab")
		)
		(fp_line
			(start 0.12065 -0.3048)
			(end 0.67945 -0.3048)
			(stroke
				(width 0.1)
				(type default)
			)
			(layer "F.Fab")
		)
		(fp_line
			(start 0.67945 -0.3048)
			(end 0.67945 0.3048)
			(stroke
				(width 0.1)
				(type default)
			)
			(layer "F.Fab")
		)
		(fp_line
			(start -0.67945 -0.305054)
			(end -0.12065 -0.305054)
			(stroke
				(width 0.1)
				(type default)
			)
			(layer "F.Fab")
		)
		(fp_line
			(start -0.12065 -0.305054)
			(end -0.12065 -0.2794)
			(stroke
				(width 0.1)
				(type default)
			)
			(layer "F.Fab")
		)
		(pad "1" smd circle
			(at -0.40005 0 270)
			(size 0 0)
			(layers "F.Cu" "F.Mask" "F.Paste")
			(net "SSD6_PWR_EN_R")
		)
		(pad "2" smd circle
			(at 0.40005 0 270)
			(size 0 0)
			(layers "F.Cu" "F.Mask" "F.Paste")
			(net "SSD6_PWR_EN")
		)
	)
	(footprint ""
		(layer "F.Cu")
		(at 206.623158 -78.579472)
		(property "Reference" "R4308"
			(at 0 0 0)
			(layer "F.SilkS")
			(hide yes)
			(effects
				(font
					(size 1.27 1.27)
				)
			)
		)
		(property "Value" ""
			(at 0 0 0)
			(layer "F.Fab")
			(effects
				(font
					(size 1.27 1.27)
				)
			)
		)
		(duplicate_pad_numbers_are_jumpers no)
		(fp_line
			(start -0.7874 -0.4064)
			(end 0.7874 -0.4064)
			(stroke
				(width 0.1524)
				(type default)
			)
			(layer "F.SilkS")
		)
		(fp_line
			(start -0.7874 0.4064)
			(end -0.7874 -0.4064)
			(stroke
				(width 0.1524)
				(type default)
			)
			(layer "F.SilkS")
		)
		(fp_line
			(start 0.7874 -0.4064)
			(end 0.7874 0.4064)
			(stroke
				(width 0.1524)
				(type default)
			)
			(layer "F.SilkS")
		)
		(fp_line
			(start 0.7874 0.4064)
			(end -0.7874 0.4064)
			(stroke
				(width 0.1524)
				(type default)
			)
			(layer "F.SilkS")
		)
		(fp_line
			(start -0.67945 -0.305054)
			(end -0.12065 -0.305054)
			(stroke
				(width 0.1)
				(type default)
			)
			(layer "F.Fab")
		)
		(fp_line
			(start -0.67945 0.3048)
			(end -0.67945 -0.305054)
			(stroke
				(width 0.1)
				(type default)
			)
			(layer "F.Fab")
		)
		(fp_line
			(start -0.12065 -0.305054)
			(end -0.12065 -0.2794)
			(stroke
				(width 0.1)
				(type default)
			)
			(layer "F.Fab")
		)
		(fp_line
			(start -0.12065 -0.2794)
			(end 0.12065 -0.2794)
			(stroke
				(width 0.1)
				(type default)
			)
			(layer "F.Fab")
		)
		(fp_line
			(start -0.12065 0.2794)
			(end -0.12065 0.3048)
			(stroke
				(width 0.1)
				(type default)
			)
			(layer "F.Fab")
		)
		(fp_line
			(start -0.12065 0.3048)
			(end -0.67945 0.3048)
			(stroke
				(width 0.1)
				(type default)
			)
			(layer "F.Fab")
		)
		(fp_line
			(start 0.120396 0.2794)
			(end -0.12065 0.2794)
			(stroke
				(width 0.1)
				(type default)
			)
			(layer "F.Fab")
		)
		(fp_line
			(start 0.120396 0.3048)
			(end 0.120396 0.2794)
			(stroke
				(width 0.1)
				(type default)
			)
			(layer "F.Fab")
		)
		(fp_line
			(start 0.12065 -0.3048)
			(end 0.67945 -0.3048)
			(stroke
				(width 0.1)
				(type default)
			)
			(layer "F.Fab")
		)
		(fp_line
			(start 0.12065 -0.2794)
			(end 0.12065 -0.3048)
			(stroke
				(width 0.1)
				(type default)
			)
			(layer "F.Fab")
		)
		(fp_line
			(start 0.67945 -0.3048)
			(end 0.67945 0.3048)
			(stroke
				(width 0.1)
				(type default)
			)
			(layer "F.Fab")
		)
		(fp_line
			(start 0.67945 0.3048)
			(end 0.120396 0.3048)
			(stroke
				(width 0.1)
				(type default)
			)
			(layer "F.Fab")
		)
		(pad "1" smd circle
			(at -0.40005 0)
			(size 0 0)
			(layers "F.Cu" "F.Mask" "F.Paste")
			(net "SSD6_LED_R")
		)
		(pad "2" smd circle
			(at 0.40005 0)
			(size 0 0)
			(layers "F.Cu" "F.Mask" "F.Paste")
			(net "SSD6_LED")
		)
	)
	(footprint ""
		(layer "F.Cu")
		(at 168.343834 -47.92091)
		(property "Reference" "R559"
			(at 0 0 0)
			(layer "F.SilkS")
			(hide yes)
			(effects
				(font
					(size 1.27 1.27)
				)
			)
		)
		(property "Value" ""
			(at 0 0 0)
			(layer "F.Fab")
			(effects
				(font
					(size 1.27 1.27)
				)
			)
		)
		(duplicate_pad_numbers_are_jumpers no)
		(fp_line
			(start -0.7874 -0.4064)
			(end 0.7874 -0.4064)
			(stroke
				(width 0.1524)
				(type default)
			)
			(layer "F.SilkS")
		)
		(fp_line
			(start -0.7874 0.4064)
			(end -0.7874 -0.4064)
			(stroke
				(width 0.1524)
				(type default)
			)
			(layer "F.SilkS")
		)
		(fp_line
			(start 0.7874 -0.4064)
			(end 0.7874 0.4064)
			(stroke
				(width 0.1524)
				(type default)
			)
			(layer "F.SilkS")
		)
		(fp_line
			(start 0.7874 0.4064)
			(end -0.7874 0.4064)
			(stroke
				(width 0.1524)
				(type default)
			)
			(layer "F.SilkS")
		)
		(fp_line
			(start -0.67945 -0.305054)
			(end -0.12065 -0.305054)
			(stroke
				(width 0.1)
				(type default)
			)
			(layer "F.Fab")
		)
		(fp_line
			(start -0.67945 0.3048)
			(end -0.67945 -0.305054)
			(stroke
				(width 0.1)
				(type default)
			)
			(layer "F.Fab")
		)
		(fp_line
			(start -0.12065 -0.305054)
			(end -0.12065 -0.2794)
			(stroke
				(width 0.1)
				(type default)
			)
			(layer "F.Fab")
		)
		(fp_line
			(start -0.12065 -0.2794)
			(end 0.12065 -0.2794)
			(stroke
				(width 0.1)
				(type default)
			)
			(layer "F.Fab")
		)
		(fp_line
			(start -0.12065 0.2794)
			(end -0.12065 0.3048)
			(stroke
				(width 0.1)
				(type default)
			)
			(layer "F.Fab")
		)
		(fp_line
			(start -0.12065 0.3048)
			(end -0.67945 0.3048)
			(stroke
				(width 0.1)
				(type default)
			)
			(layer "F.Fab")
		)
		(fp_line
			(start 0.120396 0.2794)
			(end -0.12065 0.2794)
			(stroke
				(width 0.1)
				(type default)
			)
			(layer "F.Fab")
		)
		(fp_line
			(start 0.120396 0.3048)
			(end 0.120396 0.2794)
			(stroke
				(width 0.1)
				(type default)
			)
			(layer "F.Fab")
		)
		(fp_line
			(start 0.12065 -0.3048)
			(end 0.67945 -0.3048)
			(stroke
				(width 0.1)
				(type default)
			)
			(layer "F.Fab")
		)
		(fp_line
			(start 0.12065 -0.2794)
			(end 0.12065 -0.3048)
			(stroke
				(width 0.1)
				(type default)
			)
			(layer "F.Fab")
		)
		(fp_line
			(start 0.67945 -0.3048)
			(end 0.67945 0.3048)
			(stroke
				(width 0.1)
				(type default)
			)
			(layer "F.Fab")
		)
		(fp_line
			(start 0.67945 0.3048)
			(end 0.120396 0.3048)
			(stroke
				(width 0.1)
				(type default)
			)
			(layer "F.Fab")
		)
		(pad "1" smd circle
			(at -0.40005 0)
			(size 0 0)
			(layers "F.Cu" "F.Mask" "F.Paste")
			(net "P3V3_AUX")
		)
		(pad "2" smd circle
			(at 0.40005 0)
			(size 0 0)
			(layers "F.Cu" "F.Mask" "F.Paste")
			(net "SSD_0_7_ADC_ALERT_N")
		)
	)
	(footprint ""
		(layer "F.Cu")
		(at 143.562578 -22.937216 90)
		(property "Reference" "R1669"
			(at 0 0 90)
			(layer "F.SilkS")
			(hide yes)
			(effects
				(font
					(size 1.27 1.27)
				)
			)
		)
		(property "Value" ""
			(at 0 0 90)
			(layer "F.Fab")
			(effects
				(font
					(size 1.27 1.27)
				)
			)
		)
		(duplicate_pad_numbers_are_jumpers no)
		(fp_line
			(start 0.7874 -0.4064)
			(end 0.7874 0.4064)
			(stroke
				(width 0.1524)
				(type default)
			)
			(layer "F.SilkS")
		)
		(fp_line
			(start -0.7874 -0.4064)
			(end 0.7874 -0.4064)
			(stroke
				(width 0.1524)
				(type default)
			)
			(layer "F.SilkS")
		)
		(fp_line
			(start 0.7874 0.4064)
			(end -0.7874 0.4064)
			(stroke
				(width 0.1524)
				(type default)
			)
			(layer "F.SilkS")
		)
		(fp_line
			(start -0.7874 0.4064)
			(end -0.7874 -0.4064)
			(stroke
				(width 0.1524)
				(type default)
			)
			(layer "F.SilkS")
		)
		(fp_line
			(start -0.12065 -0.305054)
			(end -0.12065 -0.2794)
			(stroke
				(width 0.1)
				(type default)
			)
			(layer "F.Fab")
		)
		(fp_line
			(start -0.67945 -0.305054)
			(end -0.12065 -0.305054)
			(stroke
				(width 0.1)
				(type default)
			)
			(layer "F.Fab")
		)
		(fp_line
			(start 0.67945 -0.3048)
			(end 0.67945 0.3048)
			(stroke
				(width 0.1)
				(type default)
			)
			(layer "F.Fab")
		)
		(fp_line
			(start 0.12065 -0.3048)
			(end 0.67945 -0.3048)
			(stroke
				(width 0.1)
				(type default)
			)
			(layer "F.Fab")
		)
		(fp_line
			(start 0.12065 -0.2794)
			(end 0.12065 -0.3048)
			(stroke
				(width 0.1)
				(type default)
			)
			(layer "F.Fab")
		)
		(fp_line
			(start -0.12065 -0.2794)
			(end 0.12065 -0.2794)
			(stroke
				(width 0.1)
				(type default)
			)
			(layer "F.Fab")
		)
		(fp_line
			(start 0.120396 0.2794)
			(end -0.12065 0.2794)
			(stroke
				(width 0.1)
				(type default)
			)
			(layer "F.Fab")
		)
		(fp_line
			(start -0.12065 0.2794)
			(end -0.12065 0.3048)
			(stroke
				(width 0.1)
				(type default)
			)
			(layer "F.Fab")
		)
		(fp_line
			(start 0.67945 0.3048)
			(end 0.120396 0.3048)
			(stroke
				(width 0.1)
				(type default)
			)
			(layer "F.Fab")
		)
		(fp_line
			(start 0.120396 0.3048)
			(end 0.120396 0.2794)
			(stroke
				(width 0.1)
				(type default)
			)
			(layer "F.Fab")
		)
		(fp_line
			(start -0.12065 0.3048)
			(end -0.67945 0.3048)
			(stroke
				(width 0.1)
				(type default)
			)
			(layer "F.Fab")
		)
		(fp_line
			(start -0.67945 0.3048)
			(end -0.67945 -0.305054)
			(stroke
				(width 0.1)
				(type default)
			)
			(layer "F.Fab")
		)
		(pad "1" smd circle
			(at -0.40005 0 90)
			(size 0 0)
			(layers "F.Cu" "F.Mask" "F.Paste")
			(net "SMB_BIC_I2C9_MUX0_SSD4_R_SDA")
		)
		(pad "2" smd circle
			(at 0.40005 0 90)
			(size 0 0)
			(layers "F.Cu" "F.Mask" "F.Paste")
			(net "SMB_ISO_SSD4_SDA")
		)
	)
	(footprint ""
		(layer "F.Cu")
		(at 400.567906 -56.353456)
		(property "Reference" "C2872"
			(at 0 0 0)
			(layer "F.SilkS")
			(hide yes)
			(effects
				(font
					(size 1.27 1.27)
				)
			)
		)
		(property "Value" ""
			(at 0 0 0)
			(layer "F.Fab")
			(effects
				(font
					(size 1.27 1.27)
				)
			)
		)
		(duplicate_pad_numbers_are_jumpers no)
		(fp_line
			(start -0.7874 -0.4064)
			(end 0.7874 -0.4064)
			(stroke
				(width 0.1524)
				(type default)
			)
			(layer "F.SilkS")
		)
		(fp_line
			(start -0.7874 0.4064)
			(end -0.7874 -0.4064)
			(stroke
				(width 0.1524)
				(type default)
			)
			(layer "F.SilkS")
		)
		(fp_line
			(start 0.7874 -0.4064)
			(end 0.7874 0.4064)
			(stroke
				(width 0.1524)
				(type default)
			)
			(layer "F.SilkS")
		)
		(fp_line
			(start 0.7874 0.4064)
			(end -0.7874 0.4064)
			(stroke
				(width 0.1524)
				(type default)
			)
			(layer "F.SilkS")
		)
		(fp_line
			(start -0.67945 -0.305054)
			(end -0.12065 -0.305054)
			(stroke
				(width 0.1)
				(type default)
			)
			(layer "F.Fab")
		)
		(fp_line
			(start -0.67945 0.3048)
			(end -0.67945 -0.305054)
			(stroke
				(width 0.1)
				(type default)
			)
			(layer "F.Fab")
		)
		(fp_line
			(start -0.12065 -0.305054)
			(end -0.12065 -0.2794)
			(stroke
				(width 0.1)
				(type default)
			)
			(layer "F.Fab")
		)
		(fp_line
			(start -0.12065 -0.2794)
			(end 0.12065 -0.2794)
			(stroke
				(width 0.1)
				(type default)
			)
			(layer "F.Fab")
		)
		(fp_line
			(start -0.12065 0.2794)
			(end -0.12065 0.3048)
			(stroke
				(width 0.1)
				(type default)
			)
			(layer "F.Fab")
		)
		(fp_line
			(start -0.12065 0.3048)
			(end -0.67945 0.3048)
			(stroke
				(width 0.1)
				(type default)
			)
			(layer "F.Fab")
		)
		(fp_line
			(start 0.120396 0.2794)
			(end -0.12065 0.2794)
			(stroke
				(width 0.1)
				(type default)
			)
			(layer "F.Fab")
		)
		(fp_line
			(start 0.120396 0.3048)
			(end 0.120396 0.2794)
			(stroke
				(width 0.1)
				(type default)
			)
			(layer "F.Fab")
		)
		(fp_line
			(start 0.12065 -0.3048)
			(end 0.67945 -0.3048)
			(stroke
				(width 0.1)
				(type default)
			)
			(layer "F.Fab")
		)
		(fp_line
			(start 0.12065 -0.2794)
			(end 0.12065 -0.3048)
			(stroke
				(width 0.1)
				(type default)
			)
			(layer "F.Fab")
		)
		(fp_line
			(start 0.67945 -0.3048)
			(end 0.67945 0.3048)
			(stroke
				(width 0.1)
				(type default)
			)
			(layer "F.Fab")
		)
		(fp_line
			(start 0.67945 0.3048)
			(end 0.120396 0.3048)
			(stroke
				(width 0.1)
				(type default)
			)
			(layer "F.Fab")
		)
		(pad "1" smd circle
			(at -0.40005 0)
			(size 0 0)
			(layers "F.Cu" "F.Mask" "F.Paste")
			(net "SSD13_PWR_EN_R")
		)
		(pad "2" smd circle
			(at 0.40005 0)
			(size 0 0)
			(layers "F.Cu" "F.Mask" "F.Paste")
			(net "GND")
		)
	)
	(footprint ""
		(layer "F.Cu")
		(at 320.354452 -225.929698 180)
		(property "Reference" "D13"
			(at 3.743452 0.103632 0)
			(unlocked yes)
			(layer "F.SilkS")
			(effects
				(font
					(size 0.7874 0.5842)
					(thickness 0.1524)
				)
				(justify left)
			)
		)
		(property "Value" ""
			(at 0 0 180)
			(layer "F.Fab")
			(effects
				(font
					(size 1.27 1.27)
				)
			)
		)
		(duplicate_pad_numbers_are_jumpers no)
		(fp_line
			(start 1.16078 0.4826)
			(end -0.64008 0.4826)
			(stroke
				(width 0.1524)
				(type default)
			)
			(layer "F.SilkS")
		)
		(fp_line
			(start 1.16078 -0.4826)
			(end 1.16078 0.4826)
			(stroke
				(width 0.1524)
				(type default)
			)
			(layer "F.SilkS")
		)
		(fp_line
			(start 1.03378 0.4826)
			(end -0.79248 0.4826)
			(stroke
				(width 0.1524)
				(type default)
			)
			(layer "F.SilkS")
		)
		(fp_line
			(start 1.03378 -0.4826)
			(end 1.03378 0.4826)
			(stroke
				(width 0.1524)
				(type default)
			)
			(layer "F.SilkS")
		)
		(fp_line
			(start 0.90678 0.4826)
			(end -0.90678 0.4826)
			(stroke
				(width 0.1524)
				(type default)
			)
			(layer "F.SilkS")
		)
		(fp_line
			(start 0.90678 -0.4826)
			(end 0.90678 0.4826)
			(stroke
				(width 0.1524)
				(type default)
			)
			(layer "F.SilkS")
		)
		(fp_line
			(start -0.64008 -0.4826)
			(end 1.16078 -0.4826)
			(stroke
				(width 0.1524)
				(type default)
			)
			(layer "F.SilkS")
		)
		(fp_line
			(start -0.79248 -0.4826)
			(end 1.03378 -0.4826)
			(stroke
				(width 0.1524)
				(type default)
			)
			(layer "F.SilkS")
		)
		(fp_line
			(start -0.89408 -0.4826)
			(end 0.90678 -0.4826)
			(stroke
				(width 0.1524)
				(type default)
			)
			(layer "F.SilkS")
		)
		(fp_line
			(start -0.90678 0.4826)
			(end -0.90678 -0.4699)
			(stroke
				(width 0.1524)
				(type default)
			)
			(layer "F.SilkS")
		)
		(fp_line
			(start 0.499872 0.249936)
			(end -0.499872 0.249936)
			(stroke
				(width 0.1)
				(type default)
			)
			(layer "F.Fab")
		)
		(fp_line
			(start 0.499872 -0.249936)
			(end 0.499872 0.249936)
			(stroke
				(width 0.1)
				(type default)
			)
			(layer "F.Fab")
		)
		(fp_line
			(start -0.499872 0.249936)
			(end -0.499872 -0.249936)
			(stroke
				(width 0.1)
				(type default)
			)
			(layer "F.Fab")
		)
		(fp_line
			(start -0.499872 -0.249936)
			(end 0.499872 -0.249936)
			(stroke
				(width 0.1)
				(type default)
			)
			(layer "F.Fab")
		)
		(pad "A" smd rect
			(at -0.47498 0 180)
			(size 0.6096 0.7112)
			(layers "F.Cu" "F.Mask" "F.Paste")
			(net "LED_POSTCODE_R_0")
		)
		(pad "C" smd rect
			(at 0.47498 0 180)
			(size 0.6096 0.7112)
			(layers "F.Cu" "F.Mask" "F.Paste")
			(net "FPGA_DEBUG_LED_R_N")
		)
	)
	(footprint ""
		(layer "F.Cu")
		(at 168.71061 -18.61439 90)
		(property "Reference" "U131"
			(at -1.34239 2.33426 90)
			(unlocked yes)
			(layer "F.SilkS")
			(effects
				(font
					(size 0.7874 0.5842)
					(thickness 0.1524)
				)
				(justify left)
			)
		)
		(property "Value" ""
			(at 0 0 90)
			(layer "F.Fab")
			(effects
				(font
					(size 1.27 1.27)
				)
			)
		)
		(duplicate_pad_numbers_are_jumpers no)
		(fp_line
			(start 1.463548 -1.549908)
			(end 1.463548 1.549908)
			(stroke
				(width 0.1524)
				(type default)
			)
			(layer "F.SilkS")
		)
		(fp_line
			(start 0.762 -1.549908)
			(end 1.463548 -1.549908)
			(stroke
				(width 0.1524)
				(type default)
			)
			(layer "F.SilkS")
		)
		(fp_line
			(start -0.787908 -1.549908)
			(end 0 -0.762)
			(stroke
				(width 0.1524)
				(type default)
			)
			(layer "F.SilkS")
		)
		(fp_line
			(start -1.463548 -1.549908)
			(end -0.787908 -1.549908)
			(stroke
				(width 0.1524)
				(type default)
			)
			(layer "F.SilkS")
		)
		(fp_line
			(start 0 -0.762)
			(end 0.762 -1.549908)
			(stroke
				(width 0.1524)
				(type default)
			)
			(layer "F.SilkS")
		)
		(fp_line
			(start 1.463548 1.549908)
			(end -1.463548 1.549908)
			(stroke
				(width 0.1524)
				(type default)
			)
			(layer "F.SilkS")
		)
		(fp_line
			(start -1.463548 1.549908)
			(end -1.463548 -1.549908)
			(stroke
				(width 0.1524)
				(type default)
			)
			(layer "F.SilkS")
		)
		(fp_poly
			(pts
				(xy -3.4798 -1.359916) (xy -2.86004 -1.050036) (xy -3.4798 -0.740156)
			)
			(stroke
				(width 0)
				(type default)
			)
			(fill yes)
			(layer "F.SilkS")
		)
		(fp_line
			(start 1.549908 -1.549908)
			(end 1.549908 1.549908)
			(stroke
				(width 0.1)
				(type default)
			)
			(layer "F.Fab")
		)
		(fp_line
			(start -1.549908 -1.549908)
			(end 1.549908 -1.549908)
			(stroke
				(width 0.1)
				(type default)
			)
			(layer "F.Fab")
		)
		(fp_line
			(start 1.549908 1.549908)
			(end -1.549908 1.549908)
			(stroke
				(width 0.1)
				(type default)
			)
			(layer "F.Fab")
		)
		(fp_line
			(start -1.549908 1.549908)
			(end -1.549908 -1.549908)
			(stroke
				(width 0.1)
				(type default)
			)
			(layer "F.Fab")
		)
		(fp_poly
			(pts
				(xy -3.4798 -1.359916) (xy -2.86004 -1.050036) (xy -3.4798 -0.740156)
			)
			(stroke
				(width 0)
				(type default)
			)
			(fill yes)
			(layer "F.Fab")
		)
		(pad "1" smd rect
			(at -2.175002 -1.050036 180)
			(size 0.6096 1.1684)
			(layers "F.Cu" "F.Mask" "F.Paste")
			(net "P3V3_SSD5")
		)
		(pad "2" smd rect
			(at -2.175002 -0.32512 180)
			(size 0.4318 1.1684)
			(layers "F.Cu" "F.Mask" "F.Paste")
			(net "SMB_ISO_SSD5_SCL")
		)
		(pad "3" smd rect
			(at -2.175002 0.32512 180)
			(size 0.4318 1.1684)
			(layers "F.Cu" "F.Mask" "F.Paste")
			(net "SMB_ISO_SSD5_SDA")
		)
		(pad "4" smd rect
			(at -2.175002 1.050036 180)
			(size 0.6096 1.1684)
			(layers "F.Cu" "F.Mask" "F.Paste")
			(net "GND")
		)
		(pad "5" smd rect
			(at 2.175002 1.050036 180)
			(size 0.6096 1.1684)
			(layers "F.Cu" "F.Mask" "F.Paste")
			(net "SMB_SSD5_ISO_EN")
		)
		(pad "6" smd rect
			(at 2.175002 0.32512 180)
			(size 0.4318 1.1684)
			(layers "F.Cu" "F.Mask" "F.Paste")
			(net "SMB_BIC_I2C9_MUX0_SSD5_R_SDA")
		)
		(pad "7" smd rect
			(at 2.175002 -0.32512 180)
			(size 0.4318 1.1684)
			(layers "F.Cu" "F.Mask" "F.Paste")
			(net "SMB_BIC_I2C9_MUX0_SSD5_R_SCL")
		)
		(pad "8" smd rect
			(at 2.175002 -1.050036 180)
			(size 0.6096 1.1684)
			(layers "F.Cu" "F.Mask" "F.Paste")
			(net "P3V3_AUX")
		)
	)
	(footprint ""
		(layer "F.Cu")
		(at 407.615136 -20.72513)
		(property "Reference" "H105"
			(at 1.502664 -2.613914 0)
			(unlocked yes)
			(layer "B.SilkS")
			(effects
				(font
					(size 0.7874 0.5842)
					(thickness 0.1524)
				)
				(justify left mirror)
			)
		)
		(property "Value" ""
			(at 0 0 0)
			(layer "F.Fab")
			(effects
				(font
					(size 1.27 1.27)
				)
			)
		)
		(duplicate_pad_numbers_are_jumpers no)
		(pad "1" thru_hole rect
			(at 0 0)
			(size 4.2164 5.0038)
			(drill 2.0066
				(offset 0.099822 0)
			)
			(layers "*.Cu" "*.Mask")
			(remove_unused_layers no)
			(net "Net_8558")
			(clearance -0.8509)
			(padstack
				(mode front_inner_back)
				(layer "Inner"
					(shape circle)
					(size 4.0132 4.0132)
					(clearance -0.7493)
				)
				(layer "B.Cu"
					(shape circle)
					(size 4.0132 4.0132)
					(clearance -0.7493)
				)
			)
		)
	)
	(footprint ""
		(layer "F.Cu")
		(at 176.279048 -59.577986 -90)
		(property "Reference" "R891"
			(at 0 0 270)
			(layer "F.SilkS")
			(hide yes)
			(effects
				(font
					(size 1.27 1.27)
				)
			)
		)
		(property "Value" ""
			(at 0 0 270)
			(layer "F.Fab")
			(effects
				(font
					(size 1.27 1.27)
				)
			)
		)
		(duplicate_pad_numbers_are_jumpers no)
		(fp_line
			(start -0.7874 0.4064)
			(end -0.7874 -0.4064)
			(stroke
				(width 0.1524)
				(type default)
			)
			(layer "F.SilkS")
		)
		(fp_line
			(start 0.7874 0.4064)
			(end -0.7874 0.4064)
			(stroke
				(width 0.1524)
				(type default)
			)
			(layer "F.SilkS")
		)
		(fp_line
			(start -0.7874 -0.4064)
			(end 0.7874 -0.4064)
			(stroke
				(width 0.1524)
				(type default)
			)
			(layer "F.SilkS")
		)
		(fp_line
			(start 0.7874 -0.4064)
			(end 0.7874 0.4064)
			(stroke
				(width 0.1524)
				(type default)
			)
			(layer "F.SilkS")
		)
		(fp_line
			(start -0.67945 0.3048)
			(end -0.67945 -0.305054)
			(stroke
				(width 0.1)
				(type default)
			)
			(layer "F.Fab")
		)
		(fp_line
			(start -0.12065 0.3048)
			(end -0.67945 0.3048)
			(stroke
				(width 0.1)
				(type default)
			)
			(layer "F.Fab")
		)
		(fp_line
			(start 0.120396 0.3048)
			(end 0.120396 0.2794)
			(stroke
				(width 0.1)
				(type default)
			)
			(layer "F.Fab")
		)
		(fp_line
			(start 0.67945 0.3048)
			(end 0.120396 0.3048)
			(stroke
				(width 0.1)
				(type default)
			)
			(layer "F.Fab")
		)
		(fp_line
			(start -0.12065 0.2794)
			(end -0.12065 0.3048)
			(stroke
				(width 0.1)
				(type default)
			)
			(layer "F.Fab")
		)
		(fp_line
			(start 0.120396 0.2794)
			(end -0.12065 0.2794)
			(stroke
				(width 0.1)
				(type default)
			)
			(layer "F.Fab")
		)
		(fp_line
			(start -0.12065 -0.2794)
			(end 0.12065 -0.2794)
			(stroke
				(width 0.1)
				(type default)
			)
			(layer "F.Fab")
		)
		(fp_line
			(start 0.12065 -0.2794)
			(end 0.12065 -0.3048)
			(stroke
				(width 0.1)
				(type default)
			)
			(layer "F.Fab")
		)
		(fp_line
			(start 0.12065 -0.3048)
			(end 0.67945 -0.3048)
			(stroke
				(width 0.1)
				(type default)
			)
			(layer "F.Fab")
		)
		(fp_line
			(start 0.67945 -0.3048)
			(end 0.67945 0.3048)
			(stroke
				(width 0.1)
				(type default)
			)
			(layer "F.Fab")
		)
		(fp_line
			(start -0.67945 -0.305054)
			(end -0.12065 -0.305054)
			(stroke
				(width 0.1)
				(type default)
			)
			(layer "F.Fab")
		)
		(fp_line
			(start -0.12065 -0.305054)
			(end -0.12065 -0.2794)
			(stroke
				(width 0.1)
				(type default)
			)
			(layer "F.Fab")
		)
		(pad "1" smd circle
			(at -0.40005 0 270)
			(size 0 0)
			(layers "F.Cu" "F.Mask" "F.Paste")
			(net "P3V3_SSD6")
		)
		(pad "2" smd circle
			(at 0.40005 0 270)
			(size 0 0)
			(layers "F.Cu" "F.Mask" "F.Paste")
			(net "PWRGD_P3V3_SSD6")
		)
	)
	(footprint ""
		(layer "F.Cu")
		(at 408.42057 -26.666444 -90)
		(property "Reference" "R4081"
			(at 0 0 270)
			(layer "F.SilkS")
			(hide yes)
			(effects
				(font
					(size 1.27 1.27)
				)
			)
		)
		(property "Value" ""
			(at 0 0 270)
			(layer "F.Fab")
			(effects
				(font
					(size 1.27 1.27)
				)
			)
		)
		(duplicate_pad_numbers_are_jumpers no)
		(fp_line
			(start -0.7874 0.4064)
			(end -0.7874 -0.4064)
			(stroke
				(width 0.1524)
				(type default)
			)
			(layer "F.SilkS")
		)
		(fp_line
			(start 0.7874 0.4064)
			(end -0.7874 0.4064)
			(stroke
				(width 0.1524)
				(type default)
			)
			(layer "F.SilkS")
		)
		(fp_line
			(start -0.7874 -0.4064)
			(end 0.7874 -0.4064)
			(stroke
				(width 0.1524)
				(type default)
			)
			(layer "F.SilkS")
		)
		(fp_line
			(start 0.7874 -0.4064)
			(end 0.7874 0.4064)
			(stroke
				(width 0.1524)
				(type default)
			)
			(layer "F.SilkS")
		)
		(fp_line
			(start -0.67945 0.3048)
			(end -0.67945 -0.305054)
			(stroke
				(width 0.1)
				(type default)
			)
			(layer "F.Fab")
		)
		(fp_line
			(start -0.12065 0.3048)
			(end -0.67945 0.3048)
			(stroke
				(width 0.1)
				(type default)
			)
			(layer "F.Fab")
		)
		(fp_line
			(start 0.120396 0.3048)
			(end 0.120396 0.2794)
			(stroke
				(width 0.1)
				(type default)
			)
			(layer "F.Fab")
		)
		(fp_line
			(start 0.67945 0.3048)
			(end 0.120396 0.3048)
			(stroke
				(width 0.1)
				(type default)
			)
			(layer "F.Fab")
		)
		(fp_line
			(start -0.12065 0.2794)
			(end -0.12065 0.3048)
			(stroke
				(width 0.1)
				(type default)
			)
			(layer "F.Fab")
		)
		(fp_line
			(start 0.120396 0.2794)
			(end -0.12065 0.2794)
			(stroke
				(width 0.1)
				(type default)
			)
			(layer "F.Fab")
		)
		(fp_line
			(start -0.12065 -0.2794)
			(end 0.12065 -0.2794)
			(stroke
				(width 0.1)
				(type default)
			)
			(layer "F.Fab")
		)
		(fp_line
			(start 0.12065 -0.2794)
			(end 0.12065 -0.3048)
			(stroke
				(width 0.1)
				(type default)
			)
			(layer "F.Fab")
		)
		(fp_line
			(start 0.12065 -0.3048)
			(end 0.67945 -0.3048)
			(stroke
				(width 0.1)
				(type default)
			)
			(layer "F.Fab")
		)
		(fp_line
			(start 0.67945 -0.3048)
			(end 0.67945 0.3048)
			(stroke
				(width 0.1)
				(type default)
			)
			(layer "F.Fab")
		)
		(fp_line
			(start -0.67945 -0.305054)
			(end -0.12065 -0.305054)
			(stroke
				(width 0.1)
				(type default)
			)
			(layer "F.Fab")
		)
		(fp_line
			(start -0.12065 -0.305054)
			(end -0.12065 -0.2794)
			(stroke
				(width 0.1)
				(type default)
			)
			(layer "F.Fab")
		)
		(pad "1" smd circle
			(at -0.40005 0 270)
			(size 0 0)
			(layers "F.Cu" "F.Mask" "F.Paste")
			(net "PRSNT_SSD14_R_N")
		)
		(pad "2" smd circle
			(at 0.40005 0 270)
			(size 0 0)
			(layers "F.Cu" "F.Mask" "F.Paste")
			(net "PRSNT_SSD14_N")
		)
	)
	(footprint ""
		(layer "F.Cu")
		(at 86.991444 -96.811592 -90)
		(property "Reference" "R692"
			(at 0 0 270)
			(layer "F.SilkS")
			(hide yes)
			(effects
				(font
					(size 1.27 1.27)
				)
			)
		)
		(property "Value" ""
			(at 0 0 270)
			(layer "F.Fab")
			(effects
				(font
					(size 1.27 1.27)
				)
			)
		)
		(duplicate_pad_numbers_are_jumpers no)
		(fp_line
			(start -0.7874 0.4064)
			(end -0.7874 -0.4064)
			(stroke
				(width 0.1524)
				(type default)
			)
			(layer "F.SilkS")
		)
		(fp_line
			(start 0.7874 0.4064)
			(end -0.7874 0.4064)
			(stroke
				(width 0.1524)
				(type default)
			)
			(layer "F.SilkS")
		)
		(fp_line
			(start -0.7874 -0.4064)
			(end 0.7874 -0.4064)
			(stroke
				(width 0.1524)
				(type default)
			)
			(layer "F.SilkS")
		)
		(fp_line
			(start 0.7874 -0.4064)
			(end 0.7874 0.4064)
			(stroke
				(width 0.1524)
				(type default)
			)
			(layer "F.SilkS")
		)
		(fp_line
			(start -0.67945 0.3048)
			(end -0.67945 -0.305054)
			(stroke
				(width 0.1)
				(type default)
			)
			(layer "F.Fab")
		)
		(fp_line
			(start -0.12065 0.3048)
			(end -0.67945 0.3048)
			(stroke
				(width 0.1)
				(type default)
			)
			(layer "F.Fab")
		)
		(fp_line
			(start 0.120396 0.3048)
			(end 0.120396 0.2794)
			(stroke
				(width 0.1)
				(type default)
			)
			(layer "F.Fab")
		)
		(fp_line
			(start 0.67945 0.3048)
			(end 0.120396 0.3048)
			(stroke
				(width 0.1)
				(type default)
			)
			(layer "F.Fab")
		)
		(fp_line
			(start -0.12065 0.2794)
			(end -0.12065 0.3048)
			(stroke
				(width 0.1)
				(type default)
			)
			(layer "F.Fab")
		)
		(fp_line
			(start 0.120396 0.2794)
			(end -0.12065 0.2794)
			(stroke
				(width 0.1)
				(type default)
			)
			(layer "F.Fab")
		)
		(fp_line
			(start -0.12065 -0.2794)
			(end 0.12065 -0.2794)
			(stroke
				(width 0.1)
				(type default)
			)
			(layer "F.Fab")
		)
		(fp_line
			(start 0.12065 -0.2794)
			(end 0.12065 -0.3048)
			(stroke
				(width 0.1)
				(type default)
			)
			(layer "F.Fab")
		)
		(fp_line
			(start 0.12065 -0.3048)
			(end 0.67945 -0.3048)
			(stroke
				(width 0.1)
				(type default)
			)
			(layer "F.Fab")
		)
		(fp_line
			(start 0.67945 -0.3048)
			(end 0.67945 0.3048)
			(stroke
				(width 0.1)
				(type default)
			)
			(layer "F.Fab")
		)
		(fp_line
			(start -0.67945 -0.305054)
			(end -0.12065 -0.305054)
			(stroke
				(width 0.1)
				(type default)
			)
			(layer "F.Fab")
		)
		(fp_line
			(start -0.12065 -0.305054)
			(end -0.12065 -0.2794)
			(stroke
				(width 0.1)
				(type default)
			)
			(layer "F.Fab")
		)
		(pad "1" smd circle
			(at -0.40005 0 270)
			(size 0 0)
			(layers "F.Cu" "F.Mask" "F.Paste")
			(net "NIC1_ADC_A1")
		)
		(pad "2" smd circle
			(at 0.40005 0 270)
			(size 0 0)
			(layers "F.Cu" "F.Mask" "F.Paste")
			(net "P3V3_AUX")
		)
	)
	(footprint ""
		(layer "F.Cu")
		(at 168.545002 -175.182276)
		(property "Reference" "R153"
			(at 0 0 0)
			(layer "F.SilkS")
			(hide yes)
			(effects
				(font
					(size 1.27 1.27)
				)
			)
		)
		(property "Value" ""
			(at 0 0 0)
			(layer "F.Fab")
			(effects
				(font
					(size 1.27 1.27)
				)
			)
		)
		(duplicate_pad_numbers_are_jumpers no)
		(fp_line
			(start -0.7874 -0.4064)
			(end 0.7874 -0.4064)
			(stroke
				(width 0.1524)
				(type default)
			)
			(layer "F.SilkS")
		)
		(fp_line
			(start -0.7874 0.4064)
			(end -0.7874 -0.4064)
			(stroke
				(width 0.1524)
				(type default)
			)
			(layer "F.SilkS")
		)
		(fp_line
			(start 0.7874 -0.4064)
			(end 0.7874 0.4064)
			(stroke
				(width 0.1524)
				(type default)
			)
			(layer "F.SilkS")
		)
		(fp_line
			(start 0.7874 0.4064)
			(end -0.7874 0.4064)
			(stroke
				(width 0.1524)
				(type default)
			)
			(layer "F.SilkS")
		)
		(fp_line
			(start -0.67945 -0.305054)
			(end -0.12065 -0.305054)
			(stroke
				(width 0.1)
				(type default)
			)
			(layer "F.Fab")
		)
		(fp_line
			(start -0.67945 0.3048)
			(end -0.67945 -0.305054)
			(stroke
				(width 0.1)
				(type default)
			)
			(layer "F.Fab")
		)
		(fp_line
			(start -0.12065 -0.305054)
			(end -0.12065 -0.2794)
			(stroke
				(width 0.1)
				(type default)
			)
			(layer "F.Fab")
		)
		(fp_line
			(start -0.12065 -0.2794)
			(end 0.12065 -0.2794)
			(stroke
				(width 0.1)
				(type default)
			)
			(layer "F.Fab")
		)
		(fp_line
			(start -0.12065 0.2794)
			(end -0.12065 0.3048)
			(stroke
				(width 0.1)
				(type default)
			)
			(layer "F.Fab")
		)
		(fp_line
			(start -0.12065 0.3048)
			(end -0.67945 0.3048)
			(stroke
				(width 0.1)
				(type default)
			)
			(layer "F.Fab")
		)
		(fp_line
			(start 0.120396 0.2794)
			(end -0.12065 0.2794)
			(stroke
				(width 0.1)
				(type default)
			)
			(layer "F.Fab")
		)
		(fp_line
			(start 0.120396 0.3048)
			(end 0.120396 0.2794)
			(stroke
				(width 0.1)
				(type default)
			)
			(layer "F.Fab")
		)
		(fp_line
			(start 0.12065 -0.3048)
			(end 0.67945 -0.3048)
			(stroke
				(width 0.1)
				(type default)
			)
			(layer "F.Fab")
		)
		(fp_line
			(start 0.12065 -0.2794)
			(end 0.12065 -0.3048)
			(stroke
				(width 0.1)
				(type default)
			)
			(layer "F.Fab")
		)
		(fp_line
			(start 0.67945 -0.3048)
			(end 0.67945 0.3048)
			(stroke
				(width 0.1)
				(type default)
			)
			(layer "F.Fab")
		)
		(fp_line
			(start 0.67945 0.3048)
			(end 0.120396 0.3048)
			(stroke
				(width 0.1)
				(type default)
			)
			(layer "F.Fab")
		)
		(pad "1" smd circle
			(at -0.40005 0)
			(size 0 0)
			(layers "F.Cu" "F.Mask" "F.Paste")
			(net "HP_NIC2_PWRGD_R")
		)
		(pad "2" smd circle
			(at 0.40005 0)
			(size 0 0)
			(layers "F.Cu" "F.Mask" "F.Paste")
			(net "HP_NIC2_PWRGD")
		)
	)
	(footprint ""
		(layer "F.Cu")
		(at 224.022158 -80.611472 180)
		(property "Reference" "R4349"
			(at 0 0 180)
			(layer "F.SilkS")
			(hide yes)
			(effects
				(font
					(size 1.27 1.27)
				)
			)
		)
		(property "Value" ""
			(at 0 0 180)
			(layer "F.Fab")
			(effects
				(font
					(size 1.27 1.27)
				)
			)
		)
		(duplicate_pad_numbers_are_jumpers no)
		(fp_line
			(start 0.7874 0.4064)
			(end -0.7874 0.4064)
			(stroke
				(width 0.1524)
				(type default)
			)
			(layer "F.SilkS")
		)
		(fp_line
			(start 0.7874 -0.4064)
			(end 0.7874 0.4064)
			(stroke
				(width 0.1524)
				(type default)
			)
			(layer "F.SilkS")
		)
		(fp_line
			(start -0.7874 0.4064)
			(end -0.7874 -0.4064)
			(stroke
				(width 0.1524)
				(type default)
			)
			(layer "F.SilkS")
		)
		(fp_line
			(start -0.7874 -0.4064)
			(end 0.7874 -0.4064)
			(stroke
				(width 0.1524)
				(type default)
			)
			(layer "F.SilkS")
		)
		(fp_line
			(start 0.67945 0.3048)
			(end 0.120396 0.3048)
			(stroke
				(width 0.1)
				(type default)
			)
			(layer "F.Fab")
		)
		(fp_line
			(start 0.67945 -0.3048)
			(end 0.67945 0.3048)
			(stroke
				(width 0.1)
				(type default)
			)
			(layer "F.Fab")
		)
		(fp_line
			(start 0.12065 -0.2794)
			(end 0.12065 -0.3048)
			(stroke
				(width 0.1)
				(type default)
			)
			(layer "F.Fab")
		)
		(fp_line
			(start 0.12065 -0.3048)
			(end 0.67945 -0.3048)
			(stroke
				(width 0.1)
				(type default)
			)
			(layer "F.Fab")
		)
		(fp_line
			(start 0.120396 0.3048)
			(end 0.120396 0.2794)
			(stroke
				(width 0.1)
				(type default)
			)
			(layer "F.Fab")
		)
		(fp_line
			(start 0.120396 0.2794)
			(end -0.12065 0.2794)
			(stroke
				(width 0.1)
				(type default)
			)
			(layer "F.Fab")
		)
		(fp_line
			(start -0.12065 0.3048)
			(end -0.67945 0.3048)
			(stroke
				(width 0.1)
				(type default)
			)
			(layer "F.Fab")
		)
		(fp_line
			(start -0.12065 0.2794)
			(end -0.12065 0.3048)
			(stroke
				(width 0.1)
				(type default)
			)
			(layer "F.Fab")
		)
		(fp_line
			(start -0.12065 -0.2794)
			(end 0.12065 -0.2794)
			(stroke
				(width 0.1)
				(type default)
			)
			(layer "F.Fab")
		)
		(fp_line
			(start -0.12065 -0.305054)
			(end -0.12065 -0.2794)
			(stroke
				(width 0.1)
				(type default)
			)
			(layer "F.Fab")
		)
		(fp_line
			(start -0.67945 0.3048)
			(end -0.67945 -0.305054)
			(stroke
				(width 0.1)
				(type default)
			)
			(layer "F.Fab")
		)
		(fp_line
			(start -0.67945 -0.305054)
			(end -0.12065 -0.305054)
			(stroke
				(width 0.1)
				(type default)
			)
			(layer "F.Fab")
		)
		(pad "1" smd circle
			(at -0.40005 0 180)
			(size 0 0)
			(layers "F.Cu" "F.Mask" "F.Paste")
			(net "P3V3_AUX")
		)
		(pad "2" smd circle
			(at 0.40005 0 180)
			(size 0 0)
			(layers "F.Cu" "F.Mask" "F.Paste")
			(net "SSD11_LED_R")
		)
	)
	(footprint ""
		(layer "F.Cu")
		(at 207.064864 -26.785062 180)
		(property "Reference" "J37"
			(at 4.53009 -10.920222 90)
			(unlocked yes)
			(layer "F.SilkS")
			(effects
				(font
					(size 0.7874 0.5842)
					(thickness 0.1524)
				)
			)
		)
		(property "Value" ""
			(at 0 0 180)
			(layer "F.Fab")
			(effects
				(font
					(size 1.27 1.27)
				)
			)
		)
		(duplicate_pad_numbers_are_jumpers no)
		(fp_line
			(start 3.150108 12.115038)
			(end 1.529334 12.115038)
			(stroke
				(width 0.1524)
				(type default)
			)
			(layer "F.SilkS")
		)
		(fp_line
			(start 3.074924 12.014962)
			(end 1.632204 12.014962)
			(stroke
				(width 0.1524)
				(type default)
			)
			(layer "F.SilkS")
		)
		(fp_line
			(start 1.632204 -12.014962)
			(end 3.074924 -12.014962)
			(stroke
				(width 0.1524)
				(type default)
			)
			(layer "F.SilkS")
		)
		(fp_line
			(start 1.529334 -12.115038)
			(end 3.150108 -12.115038)
			(stroke
				(width 0.1524)
				(type default)
			)
			(layer "F.SilkS")
		)
		(fp_line
			(start -1.529334 12.115038)
			(end -3.150108 12.115038)
			(stroke
				(width 0.1524)
				(type default)
			)
			(layer "F.SilkS")
		)
		(fp_line
			(start -1.632204 12.014962)
			(end -3.074924 12.014962)
			(stroke
				(width 0.1524)
				(type default)
			)
			(layer "F.SilkS")
		)
		(fp_line
			(start -3.074924 -12.014962)
			(end -1.632204 -12.014962)
			(stroke
				(width 0.1524)
				(type default)
			)
			(layer "F.SilkS")
		)
		(fp_line
			(start -3.150108 -12.115038)
			(end -1.529334 -12.115038)
			(stroke
				(width 0.1524)
				(type default)
			)
			(layer "F.SilkS")
		)
		(fp_poly
			(pts
				(xy 3.446526 -8.951214) (xy 3.868928 -10.218928) (xy 4.713986 -9.37387)
			)
			(stroke
				(width 0)
				(type default)
			)
			(fill yes)
			(layer "F.SilkS")
		)
		(fp_line
			(start 3.074924 12.014962)
			(end -3.074924 12.014962)
			(stroke
				(width 0.1)
				(type default)
			)
			(layer "F.Fab")
		)
		(fp_line
			(start 3.074924 -12.014962)
			(end 3.074924 12.014962)
			(stroke
				(width 0.1)
				(type default)
			)
			(layer "F.Fab")
		)
		(fp_line
			(start -3.074924 12.014962)
			(end -3.074924 -12.014962)
			(stroke
				(width 0.1)
				(type default)
			)
			(layer "F.Fab")
		)
		(fp_line
			(start -3.074924 -12.014962)
			(end 3.074924 -12.014962)
			(stroke
				(width 0.1)
				(type default)
			)
			(layer "F.Fab")
		)
		(fp_poly
			(pts
				(xy 3.348736 -7.994904) (xy 4.543806 -8.592566) (xy 4.543806 -7.397496)
			)
			(stroke
				(width 0)
				(type default)
			)
			(fill yes)
			(layer "F.Fab")
		)
		(pad "" np_thru_hole circle
			(at -1.75006 -9.815068 90)
			(size 1.1176 1.1176)
			(drill 1.1176)
			(layers "*.Cu" "*.Mask")
			(clearance 0.381)
			(thermal_gap 0.381)
		)
		(pad "" np_thru_hole circle
			(at 0 9.815068 90)
			(size 1.1176 1.1176)
			(drill 1.1176)
			(layers "*.Cu" "*.Mask")
			(clearance 0.381)
			(thermal_gap 0.381)
		)
		(pad "A1" smd rect
			(at 2.29997 -7.994904 90)
			(size 0.381 1.27)
			(layers "F.Cu" "F.Mask" "F.Paste")
			(net "GND")
		)
		(pad "A2" smd rect
			(at 2.29997 -7.394956 90)
			(size 0.381 1.27)
			(layers "F.Cu" "F.Mask" "F.Paste")
			(net "GND")
		)
		(pad "A3" smd rect
			(at 2.29997 -6.795008 90)
			(size 0.381 1.27)
			(layers "F.Cu" "F.Mask" "F.Paste")
			(net "GND")
		)
		(pad "A4" smd rect
			(at 2.29997 -6.19506 90)
			(size 0.381 1.27)
			(layers "F.Cu" "F.Mask" "F.Paste")
			(net "GND")
		)
		(pad "A5" smd rect
			(at 2.29997 -5.595112 90)
			(size 0.381 1.27)
			(layers "F.Cu" "F.Mask" "F.Paste")
			(net "GND")
		)
		(pad "A6" smd rect
			(at 2.29997 -4.99491 90)
			(size 0.381 1.27)
			(layers "F.Cu" "F.Mask" "F.Paste")
			(net "GND")
		)
		(pad "A7" smd rect
			(at 2.29997 -4.394962 90)
			(size 0.381 1.27)
			(layers "F.Cu" "F.Mask" "F.Paste")
			(net "SMB_ISO_SSD7_R_SCL")
		)
		(pad "A8" smd rect
			(at 2.29997 -3.795014 90)
			(size 0.381 1.27)
			(layers "F.Cu" "F.Mask" "F.Paste")
			(net "SMB_ISO_SSD7_R_SDA")
		)
		(pad "A9" smd rect
			(at 2.29997 -3.195066 90)
			(size 0.381 1.27)
			(layers "F.Cu" "F.Mask" "F.Paste")
			(net "RST_SMB_SSD7_ISO_R_N")
		)
		(pad "A10" smd rect
			(at 2.29997 -2.595118 90)
			(size 0.381 1.27)
			(layers "F.Cu" "F.Mask" "F.Paste")
			(net "SSD7_LED_ISO_R_N")
		)
		(pad "A11" smd rect
			(at 2.29997 -1.994916 90)
			(size 0.381 1.27)
			(layers "F.Cu" "F.Mask" "F.Paste")
			(net "PU_CLKREQ7")
		)
		(pad "A12" smd rect
			(at 2.29997 -1.394968 90)
			(size 0.381 1.27)
			(layers "F.Cu" "F.Mask" "F.Paste")
			(net "PRSNT_SSD7_N")
		)
		(pad "A13" smd rect
			(at 2.29997 -0.79502 90)
			(size 0.381 1.27)
			(layers "F.Cu" "F.Mask" "F.Paste")
			(net "GND")
		)
		(pad "A14" smd rect
			(at 2.29997 -0.195072 90)
			(size 0.381 1.27)
			(layers "F.Cu" "F.Mask" "F.Paste")
			(net "Net_8507")
		)
		(pad "A15" smd rect
			(at 2.29997 0.404876 90)
			(size 0.381 1.27)
			(layers "F.Cu" "F.Mask" "F.Paste")
			(net "Net_8506")
		)
		(pad "A16" smd rect
			(at 2.29997 1.005078 90)
			(size 0.381 1.27)
			(layers "F.Cu" "F.Mask" "F.Paste")
			(net "GND")
		)
		(pad "A17" smd rect
			(at 2.29997 1.605026 90)
			(size 0.381 1.27)
			(layers "F.Cu" "F.Mask" "F.Paste")
			(net "P5E_PEX1_STN2_RX_DN<32>")
		)
		(pad "A18" smd rect
			(at 2.29997 2.204974 90)
			(size 0.381 1.27)
			(layers "F.Cu" "F.Mask" "F.Paste")
			(net "P5E_PEX1_STN2_RX_DP<32>")
		)
		(pad "A19" smd rect
			(at 2.29997 2.804922 90)
			(size 0.381 1.27)
			(layers "F.Cu" "F.Mask" "F.Paste")
			(net "GND")
		)
		(pad "A20" smd rect
			(at 2.29997 3.405124 90)
			(size 0.381 1.27)
			(layers "F.Cu" "F.Mask" "F.Paste")
			(net "P5E_PEX1_STN2_RX_DN<33>")
		)
		(pad "A21" smd rect
			(at 2.29997 4.005072 90)
			(size 0.381 1.27)
			(layers "F.Cu" "F.Mask" "F.Paste")
			(net "P5E_PEX1_STN2_RX_DP<33>")
		)
		(pad "A22" smd rect
			(at 2.29997 4.60502 90)
			(size 0.381 1.27)
			(layers "F.Cu" "F.Mask" "F.Paste")
			(net "GND")
		)
		(pad "A23" smd rect
			(at 2.29997 5.204968 90)
			(size 0.381 1.27)
			(layers "F.Cu" "F.Mask" "F.Paste")
			(net "P5E_PEX1_STN2_RX_DN<34>")
		)
		(pad "A24" smd rect
			(at 2.29997 5.804916 90)
			(size 0.381 1.27)
			(layers "F.Cu" "F.Mask" "F.Paste")
			(net "P5E_PEX1_STN2_RX_DP<34>")
		)
		(pad "A25" smd rect
			(at 2.29997 6.405118 90)
			(size 0.381 1.27)
			(layers "F.Cu" "F.Mask" "F.Paste")
			(net "GND")
		)
		(pad "A26" smd rect
			(at 2.29997 7.005066 90)
			(size 0.381 1.27)
			(layers "F.Cu" "F.Mask" "F.Paste")
			(net "P5E_PEX1_STN2_RX_DN<35>")
		)
		(pad "A27" smd rect
			(at 2.29997 7.605014 90)
			(size 0.381 1.27)
			(layers "F.Cu" "F.Mask" "F.Paste")
			(net "P5E_PEX1_STN2_RX_DP<35>")
		)
		(pad "A28" smd rect
			(at 2.29997 8.204962 90)
			(size 0.381 1.27)
			(layers "F.Cu" "F.Mask" "F.Paste")
			(net "GND")
		)
		(pad "B1" smd rect
			(at -2.29997 -7.994904 90)
			(size 0.381 1.27)
			(layers "F.Cu" "F.Mask" "F.Paste")
			(net "P12V_SSD7")
		)
		(pad "B2" smd rect
			(at -2.29997 -7.394956 90)
			(size 0.381 1.27)
			(layers "F.Cu" "F.Mask" "F.Paste")
			(net "P12V_SSD7")
		)
		(pad "B3" smd rect
			(at -2.29997 -6.795008 90)
			(size 0.381 1.27)
			(layers "F.Cu" "F.Mask" "F.Paste")
			(net "P12V_SSD7")
		)
		(pad "B4" smd rect
			(at -2.29997 -6.19506 90)
			(size 0.381 1.27)
			(layers "F.Cu" "F.Mask" "F.Paste")
			(net "P12V_SSD7")
		)
		(pad "B5" smd rect
			(at -2.29997 -5.595112 90)
			(size 0.381 1.27)
			(layers "F.Cu" "F.Mask" "F.Paste")
			(net "P12V_SSD7")
		)
		(pad "B6" smd rect
			(at -2.29997 -4.99491 90)
			(size 0.381 1.27)
			(layers "F.Cu" "F.Mask" "F.Paste")
			(net "P12V_SSD7")
		)
		(pad "B7" smd rect
			(at -2.29997 -4.394962 90)
			(size 0.381 1.27)
			(layers "F.Cu" "F.Mask" "F.Paste")
			(net "Net_8508")
		)
		(pad "B8" smd rect
			(at -2.29997 -3.795014 90)
			(size 0.381 1.27)
			(layers "F.Cu" "F.Mask" "F.Paste")
			(net "Net_8505")
		)
		(pad "B9" smd rect
			(at -2.29997 -3.195066 90)
			(size 0.381 1.27)
			(layers "F.Cu" "F.Mask" "F.Paste")
			(net "DUALPORT_N_SSD7")
		)
		(pad "B10" smd rect
			(at -2.29997 -2.595118 90)
			(size 0.381 1.27)
			(layers "F.Cu" "F.Mask" "F.Paste")
			(net "RST_SSD7_PERST_R_N")
		)
		(pad "B11" smd rect
			(at -2.29997 -1.994916 90)
			(size 0.381 1.27)
			(layers "F.Cu" "F.Mask" "F.Paste")
			(net "P3V3_SSD7")
		)
		(pad "B12" smd rect
			(at -2.29997 -1.394968 90)
			(size 0.381 1.27)
			(layers "F.Cu" "F.Mask" "F.Paste")
			(net "SSD7_PWRDIS_R")
		)
		(pad "B13" smd rect
			(at -2.29997 -0.79502 90)
			(size 0.381 1.27)
			(layers "F.Cu" "F.Mask" "F.Paste")
			(net "GND")
		)
		(pad "B14" smd rect
			(at -2.29997 -0.195072 90)
			(size 0.381 1.27)
			(layers "F.Cu" "F.Mask" "F.Paste")
			(net "CLK_100M_DB800ZL_SSD7_R_DN")
		)
		(pad "B15" smd rect
			(at -2.29997 0.404876 90)
			(size 0.381 1.27)
			(layers "F.Cu" "F.Mask" "F.Paste")
			(net "CLK_100M_DB800ZL_SSD7_R_DP")
		)
		(pad "B16" smd rect
			(at -2.29997 1.005078 90)
			(size 0.381 1.27)
			(layers "F.Cu" "F.Mask" "F.Paste")
			(net "GND")
		)
		(pad "B17" smd rect
			(at -2.29997 1.605026 90)
			(size 0.381 1.27)
			(layers "F.Cu" "F.Mask" "F.Paste")
			(net "P5E_PEX1_STN2_TX_C_DN<32>")
		)
		(pad "B18" smd rect
			(at -2.29997 2.204974 90)
			(size 0.381 1.27)
			(layers "F.Cu" "F.Mask" "F.Paste")
			(net "P5E_PEX1_STN2_TX_C_DP<32>")
		)
		(pad "B19" smd rect
			(at -2.29997 2.804922 90)
			(size 0.381 1.27)
			(layers "F.Cu" "F.Mask" "F.Paste")
			(net "GND")
		)
		(pad "B20" smd rect
			(at -2.29997 3.405124 90)
			(size 0.381 1.27)
			(layers "F.Cu" "F.Mask" "F.Paste")
			(net "P5E_PEX1_STN2_TX_C_DN<33>")
		)
		(pad "B21" smd rect
			(at -2.29997 4.005072 90)
			(size 0.381 1.27)
			(layers "F.Cu" "F.Mask" "F.Paste")
			(net "P5E_PEX1_STN2_TX_C_DP<33>")
		)
		(pad "B22" smd rect
			(at -2.29997 4.60502 90)
			(size 0.381 1.27)
			(layers "F.Cu" "F.Mask" "F.Paste")
			(net "GND")
		)
		(pad "B23" smd rect
			(at -2.29997 5.204968 90)
			(size 0.381 1.27)
			(layers "F.Cu" "F.Mask" "F.Paste")
			(net "P5E_PEX1_STN2_TX_C_DN<34>")
		)
		(pad "B24" smd rect
			(at -2.29997 5.804916 90)
			(size 0.381 1.27)
			(layers "F.Cu" "F.Mask" "F.Paste")
			(net "P5E_PEX1_STN2_TX_C_DP<34>")
		)
		(pad "B25" smd rect
			(at -2.29997 6.405118 90)
			(size 0.381 1.27)
			(layers "F.Cu" "F.Mask" "F.Paste")
			(net "GND")
		)
		(pad "B26" smd rect
			(at -2.29997 7.005066 90)
			(size 0.381 1.27)
			(layers "F.Cu" "F.Mask" "F.Paste")
			(net "P5E_PEX1_STN2_TX_C_DN<35>")
		)
		(pad "B27" smd rect
			(at -2.29997 7.605014 90)
			(size 0.381 1.27)
			(layers "F.Cu" "F.Mask" "F.Paste")
			(net "P5E_PEX1_STN2_TX_C_DP<35>")
		)
		(pad "B28" smd rect
			(at -2.29997 8.204962 90)
			(size 0.381 1.27)
			(layers "F.Cu" "F.Mask" "F.Paste")
			(net "GND")
		)
		(pad "G1" thru_hole oval
			(at 0 -11.364976 90)
			(size 1.6256 3.4798)
			(drill oval 1.1176 2.4638)
			(layers "*.Cu" "*.Mask")
			(remove_unused_layers no)
			(net "GND")
			(clearance 0.127)
			(thermal_gap 0.127)
		)
		(pad "G2" thru_hole oval
			(at 0 11.364976 90)
			(size 1.6256 3.4798)
			(drill oval 1.1176 2.4638)
			(layers "*.Cu" "*.Mask")
			(remove_unused_layers no)
			(net "GND")
			(clearance 0.127)
			(thermal_gap 0.127)
		)
		(zone
			(layer "F.Cu")
			(hatch none 0.5)
			(connect_pads
				(clearance 0)
			)
			(min_thickness 0.25)
			(keepout
				(tracks not_allowed)
				(vias allowed)
				(pads allowed)
				(copperpour not_allowed)
				(footprints allowed)
			)
			(placement
				(enabled no)
				(sheetname "")
			)
			(fill
				(thermal_gap 0.5)
				(thermal_bridge_width 0.5)
				(island_removal_mode 0)
			)
			(polygon
				(pts
					(xy 208.444846 -38.850062) (xy 205.694788 -38.850062) (xy 205.694788 -35.900106) (xy 208.444846 -35.900106)
				)
			)
		)
		(zone
			(layer "F.Cu")
			(hatch none 0.5)
			(connect_pads
				(clearance 0)
			)
			(min_thickness 0.25)
			(keepout
				(tracks not_allowed)
				(vias allowed)
				(pads allowed)
				(copperpour not_allowed)
				(footprints allowed)
			)
			(placement
				(enabled no)
				(sheetname "")
			)
			(fill
				(thermal_gap 0.5)
				(thermal_bridge_width 0.5)
				(island_removal_mode 0)
			)
			(polygon
				(pts
					(xy 209.514948 -17.670018) (xy 205.684882 -17.670018) (xy 205.684882 -14.720062) (xy 209.514948 -14.720062)
				)
			)
		)
		(zone
			(layers "F.Cu" "B.Cu" "In1.Cu" "In2.Cu" "In3.Cu" "In4.Cu" "In5.Cu" "In6.Cu"
				"In7.Cu" "In8.Cu" "In9.Cu" "In10.Cu" "In11.Cu" "In12.Cu" "In13.Cu" "In14.Cu"
				"In15.Cu" "In16.Cu"
			)
			(hatch none 0.5)
			(connect_pads
				(clearance 0)
			)
			(min_thickness 0.25)
			(keepout
				(tracks not_allowed)
				(vias allowed)
				(pads allowed)
				(copperpour not_allowed)
				(footprints allowed)
			)
			(placement
				(enabled no)
				(sheetname "")
			)
			(fill
				(thermal_gap 0.5)
				(thermal_bridge_width 0.5)
				(island_removal_mode 0)
			)
			(polygon
				(pts
					(arc
						(start 208.030064 -36.60013)
						(mid 206.099664 -36.60013)
						(end 208.030064 -36.60013)
					)
				)
			)
		)
		(zone
			(layers "F.Cu" "B.Cu" "In1.Cu" "In2.Cu" "In3.Cu" "In4.Cu" "In5.Cu" "In6.Cu"
				"In7.Cu" "In8.Cu" "In9.Cu" "In10.Cu" "In11.Cu" "In12.Cu" "In13.Cu" "In14.Cu"
				"In15.Cu" "In16.Cu"
			)
			(hatch none 0.5)
			(connect_pads
				(clearance 0)
			)
			(min_thickness 0.25)
			(keepout
				(tracks not_allowed)
				(vias allowed)
				(pads allowed)
				(copperpour not_allowed)
				(footprints allowed)
			)
			(placement
				(enabled no)
				(sheetname "")
			)
			(fill
				(thermal_gap 0.5)
				(thermal_bridge_width 0.5)
				(island_removal_mode 0)
			)
			(polygon
				(pts
					(arc
						(start 209.780124 -16.969994)
						(mid 207.849724 -16.969994)
						(end 209.780124 -16.969994)
					)
				)
			)
		)
	)
	(footprint ""
		(layer "F.Cu")
		(at 446.734438 -30.94609 180)
		(property "Reference" "C726"
			(at 0 0 180)
			(layer "F.SilkS")
			(hide yes)
			(effects
				(font
					(size 1.27 1.27)
				)
			)
		)
		(property "Value" ""
			(at 0 0 180)
			(layer "F.Fab")
			(effects
				(font
					(size 1.27 1.27)
				)
			)
		)
		(duplicate_pad_numbers_are_jumpers no)
		(fp_line
			(start 0.299974 0.150114)
			(end -0.299974 0.150114)
			(stroke
				(width 0.1)
				(type default)
			)
			(layer "F.Fab")
		)
		(fp_line
			(start 0.299974 -0.150114)
			(end 0.299974 0.150114)
			(stroke
				(width 0.1)
				(type default)
			)
			(layer "F.Fab")
		)
		(fp_line
			(start -0.299974 0.150114)
			(end -0.299974 -0.150114)
			(stroke
				(width 0.1)
				(type default)
			)
			(layer "F.Fab")
		)
		(fp_line
			(start -0.299974 -0.150114)
			(end 0.299974 -0.150114)
			(stroke
				(width 0.1)
				(type default)
			)
			(layer "F.Fab")
		)
		(pad "1" smd rect
			(at -0.2667 0 180)
			(size 0.3048 0.381)
			(layers "F.Cu" "F.Mask" "F.Paste")
			(net "P5E_PEX3_STN2_TX_DP<33>")
		)
		(pad "2" smd rect
			(at 0.2667 0 180)
			(size 0.3048 0.381)
			(layers "F.Cu" "F.Mask" "F.Paste")
			(net "P5E_PEX3_STN2_TX_C_DP<33>")
		)
	)
	(footprint ""
		(layer "F.Cu")
		(at 278.443182 -402.338032 -90)
		(property "Reference" "C2704"
			(at 0 0 270)
			(layer "F.SilkS")
			(hide yes)
			(effects
				(font
					(size 1.27 1.27)
				)
			)
		)
		(property "Value" ""
			(at 0 0 270)
			(layer "F.Fab")
			(effects
				(font
					(size 1.27 1.27)
				)
			)
		)
		(duplicate_pad_numbers_are_jumpers no)
		(fp_line
			(start -0.7874 0.4064)
			(end -0.7874 -0.4064)
			(stroke
				(width 0.1524)
				(type default)
			)
			(layer "F.SilkS")
		)
		(fp_line
			(start 0.7874 0.4064)
			(end -0.7874 0.4064)
			(stroke
				(width 0.1524)
				(type default)
			)
			(layer "F.SilkS")
		)
		(fp_line
			(start -0.7874 -0.4064)
			(end 0.7874 -0.4064)
			(stroke
				(width 0.1524)
				(type default)
			)
			(layer "F.SilkS")
		)
		(fp_line
			(start 0.7874 -0.4064)
			(end 0.7874 0.4064)
			(stroke
				(width 0.1524)
				(type default)
			)
			(layer "F.SilkS")
		)
		(fp_line
			(start -0.67945 0.3048)
			(end -0.67945 -0.305054)
			(stroke
				(width 0.1)
				(type default)
			)
			(layer "F.Fab")
		)
		(fp_line
			(start -0.12065 0.3048)
			(end -0.67945 0.3048)
			(stroke
				(width 0.1)
				(type default)
			)
			(layer "F.Fab")
		)
		(fp_line
			(start 0.120396 0.3048)
			(end 0.120396 0.2794)
			(stroke
				(width 0.1)
				(type default)
			)
			(layer "F.Fab")
		)
		(fp_line
			(start 0.67945 0.3048)
			(end 0.120396 0.3048)
			(stroke
				(width 0.1)
				(type default)
			)
			(layer "F.Fab")
		)
		(fp_line
			(start -0.12065 0.2794)
			(end -0.12065 0.3048)
			(stroke
				(width 0.1)
				(type default)
			)
			(layer "F.Fab")
		)
		(fp_line
			(start 0.120396 0.2794)
			(end -0.12065 0.2794)
			(stroke
				(width 0.1)
				(type default)
			)
			(layer "F.Fab")
		)
		(fp_line
			(start -0.12065 -0.2794)
			(end 0.12065 -0.2794)
			(stroke
				(width 0.1)
				(type default)
			)
			(layer "F.Fab")
		)
		(fp_line
			(start 0.12065 -0.2794)
			(end 0.12065 -0.3048)
			(stroke
				(width 0.1)
				(type default)
			)
			(layer "F.Fab")
		)
		(fp_line
			(start 0.12065 -0.3048)
			(end 0.67945 -0.3048)
			(stroke
				(width 0.1)
				(type default)
			)
			(layer "F.Fab")
		)
		(fp_line
			(start 0.67945 -0.3048)
			(end 0.67945 0.3048)
			(stroke
				(width 0.1)
				(type default)
			)
			(layer "F.Fab")
		)
		(fp_line
			(start -0.67945 -0.305054)
			(end -0.12065 -0.305054)
			(stroke
				(width 0.1)
				(type default)
			)
			(layer "F.Fab")
		)
		(fp_line
			(start -0.12065 -0.305054)
			(end -0.12065 -0.2794)
			(stroke
				(width 0.1)
				(type default)
			)
			(layer "F.Fab")
		)
		(pad "1" smd circle
			(at -0.40005 0 270)
			(size 0 0)
			(layers "F.Cu" "F.Mask" "F.Paste")
			(net "GND")
		)
		(pad "2" smd circle
			(at 0.40005 0 270)
			(size 0 0)
			(layers "F.Cu" "F.Mask" "F.Paste")
			(net "P3V3_AUX")
		)
	)
	(footprint ""
		(layer "F.Cu")
		(at 454.251822 -108.054902 180)
		(property "Reference" "PC821"
			(at 0 0 180)
			(layer "F.SilkS")
			(hide yes)
			(effects
				(font
					(size 1.27 1.27)
				)
			)
		)
		(property "Value" ""
			(at 0 0 180)
			(layer "F.Fab")
			(effects
				(font
					(size 1.27 1.27)
				)
			)
		)
		(duplicate_pad_numbers_are_jumpers no)
		(fp_line
			(start 0.7874 0.4064)
			(end -0.7874 0.4064)
			(stroke
				(width 0.1524)
				(type default)
			)
			(layer "F.SilkS")
		)
		(fp_line
			(start 0.7874 -0.4064)
			(end 0.7874 0.4064)
			(stroke
				(width 0.1524)
				(type default)
			)
			(layer "F.SilkS")
		)
		(fp_line
			(start -0.7874 0.4064)
			(end -0.7874 -0.4064)
			(stroke
				(width 0.1524)
				(type default)
			)
			(layer "F.SilkS")
		)
		(fp_line
			(start -0.7874 -0.4064)
			(end 0.7874 -0.4064)
			(stroke
				(width 0.1524)
				(type default)
			)
			(layer "F.SilkS")
		)
		(fp_line
			(start 0.67945 0.3048)
			(end 0.120396 0.3048)
			(stroke
				(width 0.1)
				(type default)
			)
			(layer "F.Fab")
		)
		(fp_line
			(start 0.67945 -0.3048)
			(end 0.67945 0.3048)
			(stroke
				(width 0.1)
				(type default)
			)
			(layer "F.Fab")
		)
		(fp_line
			(start 0.12065 -0.2794)
			(end 0.12065 -0.3048)
			(stroke
				(width 0.1)
				(type default)
			)
			(layer "F.Fab")
		)
		(fp_line
			(start 0.12065 -0.3048)
			(end 0.67945 -0.3048)
			(stroke
				(width 0.1)
				(type default)
			)
			(layer "F.Fab")
		)
		(fp_line
			(start 0.120396 0.3048)
			(end 0.120396 0.2794)
			(stroke
				(width 0.1)
				(type default)
			)
			(layer "F.Fab")
		)
		(fp_line
			(start 0.120396 0.2794)
			(end -0.12065 0.2794)
			(stroke
				(width 0.1)
				(type default)
			)
			(layer "F.Fab")
		)
		(fp_line
			(start -0.12065 0.3048)
			(end -0.67945 0.3048)
			(stroke
				(width 0.1)
				(type default)
			)
			(layer "F.Fab")
		)
		(fp_line
			(start -0.12065 0.2794)
			(end -0.12065 0.3048)
			(stroke
				(width 0.1)
				(type default)
			)
			(layer "F.Fab")
		)
		(fp_line
			(start -0.12065 -0.2794)
			(end 0.12065 -0.2794)
			(stroke
				(width 0.1)
				(type default)
			)
			(layer "F.Fab")
		)
		(fp_line
			(start -0.12065 -0.305054)
			(end -0.12065 -0.2794)
			(stroke
				(width 0.1)
				(type default)
			)
			(layer "F.Fab")
		)
		(fp_line
			(start -0.67945 0.3048)
			(end -0.67945 -0.305054)
			(stroke
				(width 0.1)
				(type default)
			)
			(layer "F.Fab")
		)
		(fp_line
			(start -0.67945 -0.305054)
			(end -0.12065 -0.305054)
			(stroke
				(width 0.1)
				(type default)
			)
			(layer "F.Fab")
		)
		(pad "1" smd circle
			(at -0.40005 0 180)
			(size 0 0)
			(layers "F.Cu" "F.Mask" "F.Paste")
			(net "P12V_AUX")
		)
		(pad "2" smd circle
			(at 0.40005 0 180)
			(size 0 0)
			(layers "F.Cu" "F.Mask" "F.Paste")
			(net "GND")
		)
	)
	(footprint ""
		(layer "F.Cu")
		(at 224.845626 -368.976402 180)
		(property "Reference" "PR13"
			(at 0 0 180)
			(layer "F.SilkS")
			(hide yes)
			(effects
				(font
					(size 1.27 1.27)
				)
			)
		)
		(property "Value" ""
			(at 0 0 180)
			(layer "F.Fab")
			(effects
				(font
					(size 1.27 1.27)
				)
			)
		)
		(duplicate_pad_numbers_are_jumpers no)
		(fp_line
			(start 0.7874 0.4064)
			(end -0.7874 0.4064)
			(stroke
				(width 0.1524)
				(type default)
			)
			(layer "F.SilkS")
		)
		(fp_line
			(start 0.7874 -0.4064)
			(end 0.7874 0.4064)
			(stroke
				(width 0.1524)
				(type default)
			)
			(layer "F.SilkS")
		)
		(fp_line
			(start -0.7874 0.4064)
			(end -0.7874 -0.4064)
			(stroke
				(width 0.1524)
				(type default)
			)
			(layer "F.SilkS")
		)
		(fp_line
			(start -0.7874 -0.4064)
			(end 0.7874 -0.4064)
			(stroke
				(width 0.1524)
				(type default)
			)
			(layer "F.SilkS")
		)
		(fp_line
			(start 0.67945 0.3048)
			(end 0.120396 0.3048)
			(stroke
				(width 0.1)
				(type default)
			)
			(layer "F.Fab")
		)
		(fp_line
			(start 0.67945 -0.3048)
			(end 0.67945 0.3048)
			(stroke
				(width 0.1)
				(type default)
			)
			(layer "F.Fab")
		)
		(fp_line
			(start 0.12065 -0.2794)
			(end 0.12065 -0.3048)
			(stroke
				(width 0.1)
				(type default)
			)
			(layer "F.Fab")
		)
		(fp_line
			(start 0.12065 -0.3048)
			(end 0.67945 -0.3048)
			(stroke
				(width 0.1)
				(type default)
			)
			(layer "F.Fab")
		)
		(fp_line
			(start 0.120396 0.3048)
			(end 0.120396 0.2794)
			(stroke
				(width 0.1)
				(type default)
			)
			(layer "F.Fab")
		)
		(fp_line
			(start 0.120396 0.2794)
			(end -0.12065 0.2794)
			(stroke
				(width 0.1)
				(type default)
			)
			(layer "F.Fab")
		)
		(fp_line
			(start -0.12065 0.3048)
			(end -0.67945 0.3048)
			(stroke
				(width 0.1)
				(type default)
			)
			(layer "F.Fab")
		)
		(fp_line
			(start -0.12065 0.2794)
			(end -0.12065 0.3048)
			(stroke
				(width 0.1)
				(type default)
			)
			(layer "F.Fab")
		)
		(fp_line
			(start -0.12065 -0.2794)
			(end 0.12065 -0.2794)
			(stroke
				(width 0.1)
				(type default)
			)
			(layer "F.Fab")
		)
		(fp_line
			(start -0.12065 -0.305054)
			(end -0.12065 -0.2794)
			(stroke
				(width 0.1)
				(type default)
			)
			(layer "F.Fab")
		)
		(fp_line
			(start -0.67945 0.3048)
			(end -0.67945 -0.305054)
			(stroke
				(width 0.1)
				(type default)
			)
			(layer "F.Fab")
		)
		(fp_line
			(start -0.67945 -0.305054)
			(end -0.12065 -0.305054)
			(stroke
				(width 0.1)
				(type default)
			)
			(layer "F.Fab")
		)
		(pad "1" smd circle
			(at -0.40005 0 180)
			(size 0 0)
			(layers "F.Cu" "F.Mask" "F.Paste")
			(net "HSC_IMON")
		)
		(pad "2" smd circle
			(at 0.40005 0 180)
			(size 0 0)
			(layers "F.Cu" "F.Mask" "F.Paste")
			(net "AGND_HSC")
		)
	)
	(footprint ""
		(layer "F.Cu")
		(at 122.011948 -165.838124 180)
		(property "Reference" "R6662"
			(at 0 0 180)
			(layer "F.SilkS")
			(hide yes)
			(effects
				(font
					(size 1.27 1.27)
				)
			)
		)
		(property "Value" ""
			(at 0 0 180)
			(layer "F.Fab")
			(effects
				(font
					(size 1.27 1.27)
				)
			)
		)
		(duplicate_pad_numbers_are_jumpers no)
		(fp_line
			(start 0.7874 0.4064)
			(end -0.7874 0.4064)
			(stroke
				(width 0.1524)
				(type default)
			)
			(layer "F.SilkS")
		)
		(fp_line
			(start 0.7874 -0.4064)
			(end 0.7874 0.4064)
			(stroke
				(width 0.1524)
				(type default)
			)
			(layer "F.SilkS")
		)
		(fp_line
			(start -0.7874 0.4064)
			(end -0.7874 -0.4064)
			(stroke
				(width 0.1524)
				(type default)
			)
			(layer "F.SilkS")
		)
		(fp_line
			(start -0.7874 -0.4064)
			(end 0.7874 -0.4064)
			(stroke
				(width 0.1524)
				(type default)
			)
			(layer "F.SilkS")
		)
		(fp_line
			(start 0.67945 0.3048)
			(end 0.120396 0.3048)
			(stroke
				(width 0.1)
				(type default)
			)
			(layer "F.Fab")
		)
		(fp_line
			(start 0.67945 -0.3048)
			(end 0.67945 0.3048)
			(stroke
				(width 0.1)
				(type default)
			)
			(layer "F.Fab")
		)
		(fp_line
			(start 0.12065 -0.2794)
			(end 0.12065 -0.3048)
			(stroke
				(width 0.1)
				(type default)
			)
			(layer "F.Fab")
		)
		(fp_line
			(start 0.12065 -0.3048)
			(end 0.67945 -0.3048)
			(stroke
				(width 0.1)
				(type default)
			)
			(layer "F.Fab")
		)
		(fp_line
			(start 0.120396 0.3048)
			(end 0.120396 0.2794)
			(stroke
				(width 0.1)
				(type default)
			)
			(layer "F.Fab")
		)
		(fp_line
			(start 0.120396 0.2794)
			(end -0.12065 0.2794)
			(stroke
				(width 0.1)
				(type default)
			)
			(layer "F.Fab")
		)
		(fp_line
			(start -0.12065 0.3048)
			(end -0.67945 0.3048)
			(stroke
				(width 0.1)
				(type default)
			)
			(layer "F.Fab")
		)
		(fp_line
			(start -0.12065 0.2794)
			(end -0.12065 0.3048)
			(stroke
				(width 0.1)
				(type default)
			)
			(layer "F.Fab")
		)
		(fp_line
			(start -0.12065 -0.2794)
			(end 0.12065 -0.2794)
			(stroke
				(width 0.1)
				(type default)
			)
			(layer "F.Fab")
		)
		(fp_line
			(start -0.12065 -0.305054)
			(end -0.12065 -0.2794)
			(stroke
				(width 0.1)
				(type default)
			)
			(layer "F.Fab")
		)
		(fp_line
			(start -0.67945 0.3048)
			(end -0.67945 -0.305054)
			(stroke
				(width 0.1)
				(type default)
			)
			(layer "F.Fab")
		)
		(fp_line
			(start -0.67945 -0.305054)
			(end -0.12065 -0.305054)
			(stroke
				(width 0.1)
				(type default)
			)
			(layer "F.Fab")
		)
		(pad "1" smd circle
			(at -0.40005 0 180)
			(size 0 0)
			(layers "F.Cu" "F.Mask" "F.Paste")
			(net "NIC1_CLK_EN_BUF_N")
		)
		(pad "2" smd circle
			(at 0.40005 0 180)
			(size 0 0)
			(layers "F.Cu" "F.Mask" "F.Paste")
			(net "NIC1_CLK_EN_BUF_R_N")
		)
	)
	(footprint ""
		(layer "F.Cu")
		(at 220.36786 -53.051456)
		(property "Reference" "R4465"
			(at 0 0 0)
			(layer "F.SilkS")
			(hide yes)
			(effects
				(font
					(size 1.27 1.27)
				)
			)
		)
		(property "Value" ""
			(at 0 0 0)
			(layer "F.Fab")
			(effects
				(font
					(size 1.27 1.27)
				)
			)
		)
		(duplicate_pad_numbers_are_jumpers no)
		(fp_line
			(start -0.7874 -0.4064)
			(end 0.7874 -0.4064)
			(stroke
				(width 0.1524)
				(type default)
			)
			(layer "F.SilkS")
		)
		(fp_line
			(start -0.7874 0.4064)
			(end -0.7874 -0.4064)
			(stroke
				(width 0.1524)
				(type default)
			)
			(layer "F.SilkS")
		)
		(fp_line
			(start 0.7874 -0.4064)
			(end 0.7874 0.4064)
			(stroke
				(width 0.1524)
				(type default)
			)
			(layer "F.SilkS")
		)
		(fp_line
			(start 0.7874 0.4064)
			(end -0.7874 0.4064)
			(stroke
				(width 0.1524)
				(type default)
			)
			(layer "F.SilkS")
		)
		(fp_line
			(start -0.67945 -0.305054)
			(end -0.12065 -0.305054)
			(stroke
				(width 0.1)
				(type default)
			)
			(layer "F.Fab")
		)
		(fp_line
			(start -0.67945 0.3048)
			(end -0.67945 -0.305054)
			(stroke
				(width 0.1)
				(type default)
			)
			(layer "F.Fab")
		)
		(fp_line
			(start -0.12065 -0.305054)
			(end -0.12065 -0.2794)
			(stroke
				(width 0.1)
				(type default)
			)
			(layer "F.Fab")
		)
		(fp_line
			(start -0.12065 -0.2794)
			(end 0.12065 -0.2794)
			(stroke
				(width 0.1)
				(type default)
			)
			(layer "F.Fab")
		)
		(fp_line
			(start -0.12065 0.2794)
			(end -0.12065 0.3048)
			(stroke
				(width 0.1)
				(type default)
			)
			(layer "F.Fab")
		)
		(fp_line
			(start -0.12065 0.3048)
			(end -0.67945 0.3048)
			(stroke
				(width 0.1)
				(type default)
			)
			(layer "F.Fab")
		)
		(fp_line
			(start 0.120396 0.2794)
			(end -0.12065 0.2794)
			(stroke
				(width 0.1)
				(type default)
			)
			(layer "F.Fab")
		)
		(fp_line
			(start 0.120396 0.3048)
			(end 0.120396 0.2794)
			(stroke
				(width 0.1)
				(type default)
			)
			(layer "F.Fab")
		)
		(fp_line
			(start 0.12065 -0.3048)
			(end 0.67945 -0.3048)
			(stroke
				(width 0.1)
				(type default)
			)
			(layer "F.Fab")
		)
		(fp_line
			(start 0.12065 -0.2794)
			(end 0.12065 -0.3048)
			(stroke
				(width 0.1)
				(type default)
			)
			(layer "F.Fab")
		)
		(fp_line
			(start 0.67945 -0.3048)
			(end 0.67945 0.3048)
			(stroke
				(width 0.1)
				(type default)
			)
			(layer "F.Fab")
		)
		(fp_line
			(start 0.67945 0.3048)
			(end 0.120396 0.3048)
			(stroke
				(width 0.1)
				(type default)
			)
			(layer "F.Fab")
		)
		(pad "1" smd circle
			(at -0.40005 0)
			(size 0 0)
			(layers "F.Cu" "F.Mask" "F.Paste")
			(net "PWRGD_P12V_SSD7")
		)
		(pad "2" smd circle
			(at 0.40005 0)
			(size 0 0)
			(layers "F.Cu" "F.Mask" "F.Paste")
			(net "PWRGD_P12V_SSD7_R")
		)
	)
	(footprint ""
		(layer "F.Cu")
		(at 472.194128 -521.354304 180)
		(property "Reference" "J59_12"
			(at -2.8448 -1.402334 0)
			(unlocked yes)
			(layer "B.SilkS")
			(effects
				(font
					(size 0.7874 0.5842)
					(thickness 0.1524)
				)
				(justify mirror)
			)
		)
		(property "Value" ""
			(at 0 0 180)
			(layer "F.Fab")
			(effects
				(font
					(size 1.27 1.27)
				)
			)
		)
		(duplicate_pad_numbers_are_jumpers no)
		(pad "1" thru_hole circle
			(at 0 0 180)
			(size 0.4572 0.4572)
			(drill 0.2032)
			(layers "*.Cu" "*.Mask")
			(remove_unused_layers no)
			(net "Net_583")
			(clearance 0.127)
			(thermal_gap 0.127)
			(padstack
				(mode front_inner_back)
				(layer "Inner"
					(shape circle)
					(size 0.4572 0.4572)
					(clearance 0.127)
				)
				(layer "B.Cu"
					(shape circle)
					(size 0.508 0.508)
					(clearance 0.1016)
				)
			)
		)
	)
	(footprint ""
		(layer "F.Cu")
		(at 328.936604 -350.098614 90)
		(property "Reference" "C566"
			(at 0 0 90)
			(layer "F.SilkS")
			(hide yes)
			(effects
				(font
					(size 1.27 1.27)
				)
			)
		)
		(property "Value" ""
			(at 0 0 90)
			(layer "F.Fab")
			(effects
				(font
					(size 1.27 1.27)
				)
			)
		)
		(duplicate_pad_numbers_are_jumpers no)
		(fp_line
			(start 0.299974 -0.150114)
			(end 0.299974 0.150114)
			(stroke
				(width 0.1)
				(type default)
			)
			(layer "F.Fab")
		)
		(fp_line
			(start -0.299974 -0.150114)
			(end 0.299974 -0.150114)
			(stroke
				(width 0.1)
				(type default)
			)
			(layer "F.Fab")
		)
		(fp_line
			(start 0.299974 0.150114)
			(end -0.299974 0.150114)
			(stroke
				(width 0.1)
				(type default)
			)
			(layer "F.Fab")
		)
		(fp_line
			(start -0.299974 0.150114)
			(end -0.299974 -0.150114)
			(stroke
				(width 0.1)
				(type default)
			)
			(layer "F.Fab")
		)
		(pad "1" smd rect
			(at -0.2667 0 90)
			(size 0.3048 0.381)
			(layers "F.Cu" "F.Mask" "F.Paste")
			(net "P5E_PEX2_STN6_TX_DN<104>")
		)
		(pad "2" smd rect
			(at 0.2667 0 90)
			(size 0.3048 0.381)
			(layers "F.Cu" "F.Mask" "F.Paste")
			(net "P5E_PEX2_STN6_TX_C_DN<104>")
		)
	)
	(footprint ""
		(layer "F.Cu")
		(at 347.683836 -279.486868 -90)
		(property "Reference" "PR155"
			(at 0 0 270)
			(layer "F.SilkS")
			(hide yes)
			(effects
				(font
					(size 1.27 1.27)
				)
			)
		)
		(property "Value" ""
			(at 0 0 270)
			(layer "F.Fab")
			(effects
				(font
					(size 1.27 1.27)
				)
			)
		)
		(duplicate_pad_numbers_are_jumpers no)
		(fp_line
			(start -0.7874 0.4064)
			(end -0.7874 -0.4064)
			(stroke
				(width 0.1524)
				(type default)
			)
			(layer "F.SilkS")
		)
		(fp_line
			(start 0.7874 0.4064)
			(end -0.7874 0.4064)
			(stroke
				(width 0.1524)
				(type default)
			)
			(layer "F.SilkS")
		)
		(fp_line
			(start -0.7874 -0.4064)
			(end 0.7874 -0.4064)
			(stroke
				(width 0.1524)
				(type default)
			)
			(layer "F.SilkS")
		)
		(fp_line
			(start 0.7874 -0.4064)
			(end 0.7874 0.4064)
			(stroke
				(width 0.1524)
				(type default)
			)
			(layer "F.SilkS")
		)
		(fp_line
			(start -0.67945 0.3048)
			(end -0.67945 -0.305054)
			(stroke
				(width 0.1)
				(type default)
			)
			(layer "F.Fab")
		)
		(fp_line
			(start -0.12065 0.3048)
			(end -0.67945 0.3048)
			(stroke
				(width 0.1)
				(type default)
			)
			(layer "F.Fab")
		)
		(fp_line
			(start 0.120396 0.3048)
			(end 0.120396 0.2794)
			(stroke
				(width 0.1)
				(type default)
			)
			(layer "F.Fab")
		)
		(fp_line
			(start 0.67945 0.3048)
			(end 0.120396 0.3048)
			(stroke
				(width 0.1)
				(type default)
			)
			(layer "F.Fab")
		)
		(fp_line
			(start -0.12065 0.2794)
			(end -0.12065 0.3048)
			(stroke
				(width 0.1)
				(type default)
			)
			(layer "F.Fab")
		)
		(fp_line
			(start 0.120396 0.2794)
			(end -0.12065 0.2794)
			(stroke
				(width 0.1)
				(type default)
			)
			(layer "F.Fab")
		)
		(fp_line
			(start -0.12065 -0.2794)
			(end 0.12065 -0.2794)
			(stroke
				(width 0.1)
				(type default)
			)
			(layer "F.Fab")
		)
		(fp_line
			(start 0.12065 -0.2794)
			(end 0.12065 -0.3048)
			(stroke
				(width 0.1)
				(type default)
			)
			(layer "F.Fab")
		)
		(fp_line
			(start 0.12065 -0.3048)
			(end 0.67945 -0.3048)
			(stroke
				(width 0.1)
				(type default)
			)
			(layer "F.Fab")
		)
		(fp_line
			(start 0.67945 -0.3048)
			(end 0.67945 0.3048)
			(stroke
				(width 0.1)
				(type default)
			)
			(layer "F.Fab")
		)
		(fp_line
			(start -0.67945 -0.305054)
			(end -0.12065 -0.305054)
			(stroke
				(width 0.1)
				(type default)
			)
			(layer "F.Fab")
		)
		(fp_line
			(start -0.12065 -0.305054)
			(end -0.12065 -0.2794)
			(stroke
				(width 0.1)
				(type default)
			)
			(layer "F.Fab")
		)
		(pad "1" smd circle
			(at -0.40005 0 270)
			(size 0 0)
			(layers "F.Cu" "F.Mask" "F.Paste")
			(net "P0V8_PEX2_LSET2")
		)
		(pad "2" smd circle
			(at 0.40005 0 270)
			(size 0 0)
			(layers "F.Cu" "F.Mask" "F.Paste")
			(net "GND")
		)
	)
	(footprint ""
		(layer "F.Cu")
		(at 117.706902 -282.421584 -90)
		(property "Reference" "PC81"
			(at 0 0 270)
			(layer "F.SilkS")
			(hide yes)
			(effects
				(font
					(size 1.27 1.27)
				)
			)
		)
		(property "Value" ""
			(at 0 0 270)
			(layer "F.Fab")
			(effects
				(font
					(size 1.27 1.27)
				)
			)
		)
		(duplicate_pad_numbers_are_jumpers no)
		(fp_line
			(start -0.7874 0.4064)
			(end -0.7874 -0.4064)
			(stroke
				(width 0.1524)
				(type default)
			)
			(layer "F.SilkS")
		)
		(fp_line
			(start 0.7874 0.4064)
			(end -0.7874 0.4064)
			(stroke
				(width 0.1524)
				(type default)
			)
			(layer "F.SilkS")
		)
		(fp_line
			(start -0.7874 -0.4064)
			(end 0.7874 -0.4064)
			(stroke
				(width 0.1524)
				(type default)
			)
			(layer "F.SilkS")
		)
		(fp_line
			(start 0.7874 -0.4064)
			(end 0.7874 0.4064)
			(stroke
				(width 0.1524)
				(type default)
			)
			(layer "F.SilkS")
		)
		(fp_line
			(start -0.67945 0.3048)
			(end -0.67945 -0.305054)
			(stroke
				(width 0.1)
				(type default)
			)
			(layer "F.Fab")
		)
		(fp_line
			(start -0.12065 0.3048)
			(end -0.67945 0.3048)
			(stroke
				(width 0.1)
				(type default)
			)
			(layer "F.Fab")
		)
		(fp_line
			(start 0.120396 0.3048)
			(end 0.120396 0.2794)
			(stroke
				(width 0.1)
				(type default)
			)
			(layer "F.Fab")
		)
		(fp_line
			(start 0.67945 0.3048)
			(end 0.120396 0.3048)
			(stroke
				(width 0.1)
				(type default)
			)
			(layer "F.Fab")
		)
		(fp_line
			(start -0.12065 0.2794)
			(end -0.12065 0.3048)
			(stroke
				(width 0.1)
				(type default)
			)
			(layer "F.Fab")
		)
		(fp_line
			(start 0.120396 0.2794)
			(end -0.12065 0.2794)
			(stroke
				(width 0.1)
				(type default)
			)
			(layer "F.Fab")
		)
		(fp_line
			(start -0.12065 -0.2794)
			(end 0.12065 -0.2794)
			(stroke
				(width 0.1)
				(type default)
			)
			(layer "F.Fab")
		)
		(fp_line
			(start 0.12065 -0.2794)
			(end 0.12065 -0.3048)
			(stroke
				(width 0.1)
				(type default)
			)
			(layer "F.Fab")
		)
		(fp_line
			(start 0.12065 -0.3048)
			(end 0.67945 -0.3048)
			(stroke
				(width 0.1)
				(type default)
			)
			(layer "F.Fab")
		)
		(fp_line
			(start 0.67945 -0.3048)
			(end 0.67945 0.3048)
			(stroke
				(width 0.1)
				(type default)
			)
			(layer "F.Fab")
		)
		(fp_line
			(start -0.67945 -0.305054)
			(end -0.12065 -0.305054)
			(stroke
				(width 0.1)
				(type default)
			)
			(layer "F.Fab")
		)
		(fp_line
			(start -0.12065 -0.305054)
			(end -0.12065 -0.2794)
			(stroke
				(width 0.1)
				(type default)
			)
			(layer "F.Fab")
		)
		(pad "1" smd circle
			(at -0.40005 0 270)
			(size 0 0)
			(layers "F.Cu" "F.Mask" "F.Paste")
			(net "P0V8_PEX0_VCC2")
		)
		(pad "2" smd circle
			(at 0.40005 0 270)
			(size 0 0)
			(layers "F.Cu" "F.Mask" "F.Paste")
			(net "GND")
		)
	)
	(footprint ""
		(layer "F.Cu")
		(at 26.405332 -258.582922 90)
		(property "Reference" "L97"
			(at 0 0 90)
			(layer "F.SilkS")
			(hide yes)
			(effects
				(font
					(size 1.27 1.27)
				)
			)
		)
		(property "Value" ""
			(at 0 0 90)
			(layer "F.Fab")
			(effects
				(font
					(size 1.27 1.27)
				)
			)
		)
		(duplicate_pad_numbers_are_jumpers no)
		(fp_line
			(start 1.63576 -0.8128)
			(end 1.63576 0.8128)
			(stroke
				(width 0.1524)
				(type default)
			)
			(layer "F.SilkS")
		)
		(fp_line
			(start -1.63576 -0.8128)
			(end 1.63576 -0.8128)
			(stroke
				(width 0.1524)
				(type default)
			)
			(layer "F.SilkS")
		)
		(fp_line
			(start -1.63576 -0.8128)
			(end -1.63576 0.8128)
			(stroke
				(width 0.1524)
				(type default)
			)
			(layer "F.SilkS")
		)
		(fp_line
			(start 1.63576 0.8128)
			(end -1.63576 0.8128)
			(stroke
				(width 0.1524)
				(type default)
			)
			(layer "F.SilkS")
		)
		(fp_line
			(start 1.560576 -0.738632)
			(end -1.56083 -0.738632)
			(stroke
				(width 0.1)
				(type default)
			)
			(layer "F.Fab")
		)
		(fp_line
			(start -1.56083 -0.738632)
			(end -1.56083 0.7366)
			(stroke
				(width 0.1)
				(type default)
			)
			(layer "F.Fab")
		)
		(fp_line
			(start 1.560576 0.7366)
			(end 1.560576 -0.738632)
			(stroke
				(width 0.1)
				(type default)
			)
			(layer "F.Fab")
		)
		(fp_line
			(start 1.524 0.7366)
			(end 1.560576 0.7366)
			(stroke
				(width 0.1)
				(type default)
			)
			(layer "F.Fab")
		)
		(fp_line
			(start -1.524 0.7366)
			(end 1.524 0.7366)
			(stroke
				(width 0.1)
				(type default)
			)
			(layer "F.Fab")
		)
		(fp_line
			(start -1.56083 0.7366)
			(end -1.524 0.7366)
			(stroke
				(width 0.1)
				(type default)
			)
			(layer "F.Fab")
		)
		(pad "1" smd rect
			(at -0.94996 0 270)
			(size 1.1176 1.3716)
			(layers "F.Cu" "F.Mask" "F.Paste")
			(net "P1V8_PLL0_PEX0")
		)
		(pad "2" smd rect
			(at 0.94996 0 270)
			(size 1.1176 1.3716)
			(layers "F.Cu" "F.Mask" "F.Paste")
			(net "P1V8_VDDA_PEX0")
		)
	)
	(footprint ""
		(layer "F.Cu")
		(at 32.470344 -252.356874 -90)
		(property "Reference" "R1204"
			(at 0 0 270)
			(layer "F.SilkS")
			(hide yes)
			(effects
				(font
					(size 1.27 1.27)
				)
			)
		)
		(property "Value" ""
			(at 0 0 270)
			(layer "F.Fab")
			(effects
				(font
					(size 1.27 1.27)
				)
			)
		)
		(duplicate_pad_numbers_are_jumpers no)
		(fp_line
			(start -0.7874 0.4064)
			(end -0.7874 -0.4064)
			(stroke
				(width 0.1524)
				(type default)
			)
			(layer "F.SilkS")
		)
		(fp_line
			(start 0.7874 0.4064)
			(end -0.7874 0.4064)
			(stroke
				(width 0.1524)
				(type default)
			)
			(layer "F.SilkS")
		)
		(fp_line
			(start -0.7874 -0.4064)
			(end 0.7874 -0.4064)
			(stroke
				(width 0.1524)
				(type default)
			)
			(layer "F.SilkS")
		)
		(fp_line
			(start 0.7874 -0.4064)
			(end 0.7874 0.4064)
			(stroke
				(width 0.1524)
				(type default)
			)
			(layer "F.SilkS")
		)
		(fp_line
			(start -0.67945 0.3048)
			(end -0.67945 -0.305054)
			(stroke
				(width 0.1)
				(type default)
			)
			(layer "F.Fab")
		)
		(fp_line
			(start -0.12065 0.3048)
			(end -0.67945 0.3048)
			(stroke
				(width 0.1)
				(type default)
			)
			(layer "F.Fab")
		)
		(fp_line
			(start 0.120396 0.3048)
			(end 0.120396 0.2794)
			(stroke
				(width 0.1)
				(type default)
			)
			(layer "F.Fab")
		)
		(fp_line
			(start 0.67945 0.3048)
			(end 0.120396 0.3048)
			(stroke
				(width 0.1)
				(type default)
			)
			(layer "F.Fab")
		)
		(fp_line
			(start -0.12065 0.2794)
			(end -0.12065 0.3048)
			(stroke
				(width 0.1)
				(type default)
			)
			(layer "F.Fab")
		)
		(fp_line
			(start 0.120396 0.2794)
			(end -0.12065 0.2794)
			(stroke
				(width 0.1)
				(type default)
			)
			(layer "F.Fab")
		)
		(fp_line
			(start -0.12065 -0.2794)
			(end 0.12065 -0.2794)
			(stroke
				(width 0.1)
				(type default)
			)
			(layer "F.Fab")
		)
		(fp_line
			(start 0.12065 -0.2794)
			(end 0.12065 -0.3048)
			(stroke
				(width 0.1)
				(type default)
			)
			(layer "F.Fab")
		)
		(fp_line
			(start 0.12065 -0.3048)
			(end 0.67945 -0.3048)
			(stroke
				(width 0.1)
				(type default)
			)
			(layer "F.Fab")
		)
		(fp_line
			(start 0.67945 -0.3048)
			(end 0.67945 0.3048)
			(stroke
				(width 0.1)
				(type default)
			)
			(layer "F.Fab")
		)
		(fp_line
			(start -0.67945 -0.305054)
			(end -0.12065 -0.305054)
			(stroke
				(width 0.1)
				(type default)
			)
			(layer "F.Fab")
		)
		(fp_line
			(start -0.12065 -0.305054)
			(end -0.12065 -0.2794)
			(stroke
				(width 0.1)
				(type default)
			)
			(layer "F.Fab")
		)
		(pad "1" smd circle
			(at -0.40005 0 270)
			(size 0 0)
			(layers "F.Cu" "F.Mask" "F.Paste")
			(net "GND")
		)
		(pad "2" smd circle
			(at 0.40005 0 270)
			(size 0 0)
			(layers "F.Cu" "F.Mask" "F.Paste")
			(net "PEX0_MODE_SEL8")
		)
	)
	(footprint ""
		(layer "F.Cu")
		(at 58.995056 -99.750372 180)
		(property "Reference" "R79"
			(at 0 0 180)
			(layer "F.SilkS")
			(hide yes)
			(effects
				(font
					(size 1.27 1.27)
				)
			)
		)
		(property "Value" ""
			(at 0 0 180)
			(layer "F.Fab")
			(effects
				(font
					(size 1.27 1.27)
				)
			)
		)
		(duplicate_pad_numbers_are_jumpers no)
		(fp_line
			(start 0.7874 0.4064)
			(end -0.7874 0.4064)
			(stroke
				(width 0.1524)
				(type default)
			)
			(layer "F.SilkS")
		)
		(fp_line
			(start 0.7874 -0.4064)
			(end 0.7874 0.4064)
			(stroke
				(width 0.1524)
				(type default)
			)
			(layer "F.SilkS")
		)
		(fp_line
			(start -0.7874 0.4064)
			(end -0.7874 -0.4064)
			(stroke
				(width 0.1524)
				(type default)
			)
			(layer "F.SilkS")
		)
		(fp_line
			(start -0.7874 -0.4064)
			(end 0.7874 -0.4064)
			(stroke
				(width 0.1524)
				(type default)
			)
			(layer "F.SilkS")
		)
		(fp_line
			(start 0.67945 0.3048)
			(end 0.120396 0.3048)
			(stroke
				(width 0.1)
				(type default)
			)
			(layer "F.Fab")
		)
		(fp_line
			(start 0.67945 -0.3048)
			(end 0.67945 0.3048)
			(stroke
				(width 0.1)
				(type default)
			)
			(layer "F.Fab")
		)
		(fp_line
			(start 0.12065 -0.2794)
			(end 0.12065 -0.3048)
			(stroke
				(width 0.1)
				(type default)
			)
			(layer "F.Fab")
		)
		(fp_line
			(start 0.12065 -0.3048)
			(end 0.67945 -0.3048)
			(stroke
				(width 0.1)
				(type default)
			)
			(layer "F.Fab")
		)
		(fp_line
			(start 0.120396 0.3048)
			(end 0.120396 0.2794)
			(stroke
				(width 0.1)
				(type default)
			)
			(layer "F.Fab")
		)
		(fp_line
			(start 0.120396 0.2794)
			(end -0.12065 0.2794)
			(stroke
				(width 0.1)
				(type default)
			)
			(layer "F.Fab")
		)
		(fp_line
			(start -0.12065 0.3048)
			(end -0.67945 0.3048)
			(stroke
				(width 0.1)
				(type default)
			)
			(layer "F.Fab")
		)
		(fp_line
			(start -0.12065 0.2794)
			(end -0.12065 0.3048)
			(stroke
				(width 0.1)
				(type default)
			)
			(layer "F.Fab")
		)
		(fp_line
			(start -0.12065 -0.2794)
			(end 0.12065 -0.2794)
			(stroke
				(width 0.1)
				(type default)
			)
			(layer "F.Fab")
		)
		(fp_line
			(start -0.12065 -0.305054)
			(end -0.12065 -0.2794)
			(stroke
				(width 0.1)
				(type default)
			)
			(layer "F.Fab")
		)
		(fp_line
			(start -0.67945 0.3048)
			(end -0.67945 -0.305054)
			(stroke
				(width 0.1)
				(type default)
			)
			(layer "F.Fab")
		)
		(fp_line
			(start -0.67945 -0.305054)
			(end -0.12065 -0.305054)
			(stroke
				(width 0.1)
				(type default)
			)
			(layer "F.Fab")
		)
		(pad "1" smd circle
			(at -0.40005 0 180)
			(size 0 0)
			(layers "F.Cu" "F.Mask" "F.Paste")
			(net "NIC1_SLOT_ID1")
		)
		(pad "2" smd circle
			(at 0.40005 0 180)
			(size 0 0)
			(layers "F.Cu" "F.Mask" "F.Paste")
			(net "GND")
		)
	)
	(footprint ""
		(layer "F.Cu")
		(at 195.699888 -378.70003)
		(property "Reference" "H80"
			(at -5.748528 -8.024368 0)
			(unlocked yes)
			(layer "F.SilkS")
			(effects
				(font
					(size 0.7874 0.5842)
					(thickness 0.1524)
				)
				(justify left)
			)
		)
		(property "Value" ""
			(at 0 0 0)
			(layer "F.Fab")
			(effects
				(font
					(size 1.27 1.27)
				)
			)
		)
		(duplicate_pad_numbers_are_jumpers no)
		(fp_arc
			(start 3.237738 7.315454)
			(mid -7.629888 2.404398)
			(end -1.540764 -7.84987)
			(stroke
				(width 0.1524)
				(type default)
			)
			(layer "F.SilkS")
		)
		(fp_arc
			(start 5.216906 -6.064758)
			(mid 7.270957 -3.336409)
			(end 7.999984 0)
			(stroke
				(width 0.1524)
				(type default)
			)
			(layer "F.SilkS")
		)
		(fp_arc
			(start 7.999984 0)
			(mid 7.276035 3.325462)
			(end 5.235194 6.04901)
			(stroke
				(width 0.1524)
				(type default)
			)
			(layer "F.SilkS")
		)
		(fp_arc
			(start 2.386838 7.635748)
			(mid -7.745564 2.008288)
			(end -1.623822 -7.83336)
			(stroke
				(width 0.1524)
				(type default)
			)
			(layer "B.SilkS")
		)
		(fp_arc
			(start 4.790694 6.40715)
			(mid 4.299861 6.746338)
			(end 3.785108 7.047992)
			(stroke
				(width 0.1524)
				(type default)
			)
			(layer "B.SilkS")
		)
		(fp_arc
			(start 5.308854 -5.984748)
			(mid 7.296334 -3.281019)
			(end 7.999984 0)
			(stroke
				(width 0.1524)
				(type default)
			)
			(layer "B.SilkS")
		)
		(fp_arc
			(start 7.999984 0)
			(mid 7.44841 2.918885)
			(end 5.86994 5.435346)
			(stroke
				(width 0.1524)
				(type default)
			)
			(layer "B.SilkS")
		)
		(fp_circle
			(center 0 0)
			(end 7.999984 0)
			(stroke
				(width 0.1)
				(type default)
			)
			(fill no)
			(layer "B.Fab")
		)
		(fp_circle
			(center 0 0)
			(end 7.999984 0)
			(stroke
				(width 0.1)
				(type default)
			)
			(fill no)
			(layer "F.Fab")
		)
		(pad "" np_thru_hole circle
			(at 0 0)
			(size 3.4036 3.4036)
			(drill 3.4036)
			(layers "*.Cu" "*.Mask")
			(clearance 0.381)
			(thermal_gap 0.381)
		)
		(pad "2" thru_hole circle
			(at 3.606292 0)
			(size 0.762 0.762)
			(drill 0.5588)
			(layers "*.Cu" "*.Mask")
			(remove_unused_layers no)
			(net "GND")
			(clearance 0.1524)
			(thermal_gap 0.1524)
		)
		(pad "3" thru_hole circle
			(at 2.549906 -2.549906)
			(size 0.762 0.762)
			(drill 0.5588)
			(layers "*.Cu" "*.Mask")
			(remove_unused_layers no)
			(net "GND")
			(clearance 0.1524)
			(thermal_gap 0.1524)
		)
		(pad "4" thru_hole circle
			(at 0 -3.606292)
			(size 0.762 0.762)
			(drill 0.5588)
			(layers "*.Cu" "*.Mask")
			(remove_unused_layers no)
			(net "GND")
			(clearance 0.1524)
			(thermal_gap 0.1524)
		)
		(pad "5" thru_hole circle
			(at -2.549906 -2.549906)
			(size 0.762 0.762)
			(drill 0.5588)
			(layers "*.Cu" "*.Mask")
			(remove_unused_layers no)
			(net "GND")
			(clearance 0.1524)
			(thermal_gap 0.1524)
		)
		(pad "6" thru_hole circle
			(at -3.606292 0)
			(size 0.762 0.762)
			(drill 0.5588)
			(layers "*.Cu" "*.Mask")
			(remove_unused_layers no)
			(net "GND")
			(clearance 0.1524)
			(thermal_gap 0.1524)
		)
		(pad "7" thru_hole circle
			(at -2.549906 2.549906)
			(size 0.762 0.762)
			(drill 0.5588)
			(layers "*.Cu" "*.Mask")
			(remove_unused_layers no)
			(net "GND")
			(clearance 0.1524)
			(thermal_gap 0.1524)
		)
		(pad "8" thru_hole circle
			(at 0 3.606292)
			(size 0.762 0.762)
			(drill 0.5588)
			(layers "*.Cu" "*.Mask")
			(remove_unused_layers no)
			(net "GND")
			(clearance 0.1524)
			(thermal_gap 0.1524)
		)
		(pad "9" thru_hole circle
			(at 2.549906 2.549906)
			(size 0.762 0.762)
			(drill 0.5588)
			(layers "*.Cu" "*.Mask")
			(remove_unused_layers no)
			(net "GND")
			(clearance 0.1524)
			(thermal_gap 0.1524)
		)
		(zone
			(layer "F.Cu")
			(hatch none 0.5)
			(connect_pads
				(clearance 0)
			)
			(min_thickness 0.25)
			(keepout
				(tracks not_allowed)
				(vias allowed)
				(pads allowed)
				(copperpour not_allowed)
				(footprints allowed)
			)
			(placement
				(enabled no)
				(sheetname "")
			)
			(fill
				(thermal_gap 0.5)
				(thermal_bridge_width 0.5)
				(island_removal_mode 0)
			)
			(polygon
				(pts
					(arc
						(start 195.699888 -370.700046)
						(mid 187.699904 -378.70003)
						(end 195.699888 -386.700014)
					)
					(arc
						(start 195.699888 -383.95402)
						(mid 190.445898 -378.70003)
						(end 195.699888 -373.44604)
					)
				)
			)
		)
		(zone
			(layer "F.Cu")
			(hatch none 0.5)
			(connect_pads
				(clearance 0)
			)
			(min_thickness 0.25)
			(keepout
				(tracks not_allowed)
				(vias allowed)
				(pads allowed)
				(copperpour not_allowed)
				(footprints allowed)
			)
			(placement
				(enabled no)
				(sheetname "")
			)
			(fill
				(thermal_gap 0.5)
				(thermal_bridge_width 0.5)
				(island_removal_mode 0)
			)
			(polygon
				(pts
					(arc
						(start 195.699888 -370.700046)
						(mid 203.699872 -378.70003)
						(end 195.699888 -386.700014)
					)
					(arc
						(start 195.699888 -383.95402)
						(mid 200.953878 -378.70003)
						(end 195.699888 -373.44604)
					)
				)
			)
		)
		(zone
			(layers "F.Cu" "B.Cu" "In1.Cu" "In2.Cu" "In3.Cu" "In4.Cu" "In5.Cu" "In6.Cu"
				"In7.Cu" "In8.Cu" "In9.Cu" "In10.Cu" "In11.Cu" "In12.Cu" "In13.Cu" "In14.Cu"
				"In15.Cu" "In16.Cu"
			)
			(hatch none 0.5)
			(connect_pads
				(clearance 0)
			)
			(min_thickness 0.25)
			(keepout
				(tracks not_allowed)
				(vias allowed)
				(pads allowed)
				(copperpour not_allowed)
				(footprints allowed)
			)
			(placement
				(enabled no)
				(sheetname "")
			)
			(fill
				(thermal_gap 0.5)
				(thermal_bridge_width 0.5)
				(island_removal_mode 0)
			)
			(polygon
				(pts
					(arc
						(start 197.909688 -378.70003)
						(mid 193.490088 -378.70003)
						(end 197.909688 -378.70003)
					)
				)
			)
		)
		(zone
			(layer "B.Cu")
			(hatch none 0.5)
			(connect_pads
				(clearance 0)
			)
			(min_thickness 0.25)
			(keepout
				(tracks not_allowed)
				(vias allowed)
				(pads allowed)
				(copperpour not_allowed)
				(footprints allowed)
			)
			(placement
				(enabled no)
				(sheetname "")
			)
			(fill
				(thermal_gap 0.5)
				(thermal_bridge_width 0.5)
				(island_removal_mode 0)
			)
			(polygon
				(pts
					(arc
						(start 195.699888 -373.19204)
						(mid 190.191898 -378.70003)
						(end 195.699888 -384.20802)
					)
					(arc
						(start 195.699888 -383.72542)
						(mid 190.674498 -378.70003)
						(end 195.699888 -373.67464)
					)
				)
			)
		)
		(zone
			(layer "B.Cu")
			(hatch none 0.5)
			(connect_pads
				(clearance 0)
			)
			(min_thickness 0.25)
			(keepout
				(tracks not_allowed)
				(vias allowed)
				(pads allowed)
				(copperpour not_allowed)
				(footprints allowed)
			)
			(placement
				(enabled no)
				(sheetname "")
			)
			(fill
				(thermal_gap 0.5)
				(thermal_bridge_width 0.5)
				(island_removal_mode 0)
			)
			(polygon
				(pts
					(arc
						(start 195.699888 -373.19204)
						(mid 201.207878 -378.70003)
						(end 195.699888 -384.20802)
					)
					(arc
						(start 195.699888 -383.72542)
						(mid 200.725278 -378.70003)
						(end 195.699888 -373.67464)
					)
				)
			)
		)
	)
	(footprint ""
		(layer "F.Cu")
		(at 104.309672 -280.44902 -90)
		(property "Reference" "PC66"
			(at 0 0 270)
			(layer "F.SilkS")
			(hide yes)
			(effects
				(font
					(size 1.27 1.27)
				)
			)
		)
		(property "Value" ""
			(at 0 0 270)
			(layer "F.Fab")
			(effects
				(font
					(size 1.27 1.27)
				)
			)
		)
		(duplicate_pad_numbers_are_jumpers no)
		(fp_line
			(start -0.7874 0.4064)
			(end -0.7874 -0.4064)
			(stroke
				(width 0.1524)
				(type default)
			)
			(layer "F.SilkS")
		)
		(fp_line
			(start 0.7874 0.4064)
			(end -0.7874 0.4064)
			(stroke
				(width 0.1524)
				(type default)
			)
			(layer "F.SilkS")
		)
		(fp_line
			(start -0.7874 -0.4064)
			(end 0.7874 -0.4064)
			(stroke
				(width 0.1524)
				(type default)
			)
			(layer "F.SilkS")
		)
		(fp_line
			(start 0.7874 -0.4064)
			(end 0.7874 0.4064)
			(stroke
				(width 0.1524)
				(type default)
			)
			(layer "F.SilkS")
		)
		(fp_line
			(start -0.67945 0.3048)
			(end -0.67945 -0.305054)
			(stroke
				(width 0.1)
				(type default)
			)
			(layer "F.Fab")
		)
		(fp_line
			(start -0.12065 0.3048)
			(end -0.67945 0.3048)
			(stroke
				(width 0.1)
				(type default)
			)
			(layer "F.Fab")
		)
		(fp_line
			(start 0.120396 0.3048)
			(end 0.120396 0.2794)
			(stroke
				(width 0.1)
				(type default)
			)
			(layer "F.Fab")
		)
		(fp_line
			(start 0.67945 0.3048)
			(end 0.120396 0.3048)
			(stroke
				(width 0.1)
				(type default)
			)
			(layer "F.Fab")
		)
		(fp_line
			(start -0.12065 0.2794)
			(end -0.12065 0.3048)
			(stroke
				(width 0.1)
				(type default)
			)
			(layer "F.Fab")
		)
		(fp_line
			(start 0.120396 0.2794)
			(end -0.12065 0.2794)
			(stroke
				(width 0.1)
				(type default)
			)
			(layer "F.Fab")
		)
		(fp_line
			(start -0.12065 -0.2794)
			(end 0.12065 -0.2794)
			(stroke
				(width 0.1)
				(type default)
			)
			(layer "F.Fab")
		)
		(fp_line
			(start 0.12065 -0.2794)
			(end 0.12065 -0.3048)
			(stroke
				(width 0.1)
				(type default)
			)
			(layer "F.Fab")
		)
		(fp_line
			(start 0.12065 -0.3048)
			(end 0.67945 -0.3048)
			(stroke
				(width 0.1)
				(type default)
			)
			(layer "F.Fab")
		)
		(fp_line
			(start 0.67945 -0.3048)
			(end 0.67945 0.3048)
			(stroke
				(width 0.1)
				(type default)
			)
			(layer "F.Fab")
		)
		(fp_line
			(start -0.67945 -0.305054)
			(end -0.12065 -0.305054)
			(stroke
				(width 0.1)
				(type default)
			)
			(layer "F.Fab")
		)
		(fp_line
			(start -0.12065 -0.305054)
			(end -0.12065 -0.2794)
			(stroke
				(width 0.1)
				(type default)
			)
			(layer "F.Fab")
		)
		(pad "1" smd circle
			(at -0.40005 0 270)
			(size 0 0)
			(layers "F.Cu" "F.Mask" "F.Paste")
			(net "SW_P0V8_PEX0_PHASE1")
		)
		(pad "2" smd circle
			(at 0.40005 0 270)
			(size 0 0)
			(layers "F.Cu" "F.Mask" "F.Paste")
			(net "SW_P0V8_PEX0_BOOT1_R")
		)
	)
	(footprint ""
		(layer "F.Cu")
		(at 461.924908 -307.607716)
		(property "Reference" "PJ16"
			(at 0 0 0)
			(layer "F.SilkS")
			(hide yes)
			(effects
				(font
					(size 1.27 1.27)
				)
			)
		)
		(property "Value" ""
			(at 0 0 0)
			(layer "F.Fab")
			(effects
				(font
					(size 1.27 1.27)
				)
			)
		)
		(duplicate_pad_numbers_are_jumpers no)
		(pad "1" smd circle
			(at -0.40005 0 90)
			(size 0 0)
			(layers "F.Cu" "F.Mask" "F.Paste")
			(net "SH_P1V25_PEX3_FB_N")
		)
		(pad "2" smd rect
			(at 0.40005 0 180)
			(size 0.4572 0.508)
			(layers "F.Cu" "F.Mask" "F.Paste")
			(net "GND")
		)
		(zone
			(layer "F.Cu")
			(hatch none 0.5)
			(connect_pads
				(clearance 0)
			)
			(min_thickness 0.25)
			(keepout
				(tracks allowed)
				(vias not_allowed)
				(pads allowed)
				(copperpour not_allowed)
				(footprints allowed)
			)
			(placement
				(enabled no)
				(sheetname "")
			)
			(fill
				(thermal_gap 0.5)
				(thermal_bridge_width 0.5)
				(island_removal_mode 0)
			)
			(polygon
				(pts
					(xy 461.239108 -307.302916) (xy 462.610708 -307.302916) (xy 462.610708 -307.912516) (xy 461.239108 -307.912516)
				)
			)
		)
	)
	(footprint ""
		(layer "F.Cu")
		(at 331.489812 -72.766682 90)
		(property "Reference" "PR7084"
			(at 0 0 90)
			(layer "F.SilkS")
			(hide yes)
			(effects
				(font
					(size 1.27 1.27)
				)
			)
		)
		(property "Value" ""
			(at 0 0 90)
			(layer "F.Fab")
			(effects
				(font
					(size 1.27 1.27)
				)
			)
		)
		(duplicate_pad_numbers_are_jumpers no)
		(fp_line
			(start 0.7874 -0.4064)
			(end 0.7874 0.4064)
			(stroke
				(width 0.1524)
				(type default)
			)
			(layer "F.SilkS")
		)
		(fp_line
			(start -0.7874 -0.4064)
			(end 0.7874 -0.4064)
			(stroke
				(width 0.1524)
				(type default)
			)
			(layer "F.SilkS")
		)
		(fp_line
			(start 0.7874 0.4064)
			(end -0.7874 0.4064)
			(stroke
				(width 0.1524)
				(type default)
			)
			(layer "F.SilkS")
		)
		(fp_line
			(start -0.7874 0.4064)
			(end -0.7874 -0.4064)
			(stroke
				(width 0.1524)
				(type default)
			)
			(layer "F.SilkS")
		)
		(fp_line
			(start -0.12065 -0.305054)
			(end -0.12065 -0.2794)
			(stroke
				(width 0.1)
				(type default)
			)
			(layer "F.Fab")
		)
		(fp_line
			(start -0.67945 -0.305054)
			(end -0.12065 -0.305054)
			(stroke
				(width 0.1)
				(type default)
			)
			(layer "F.Fab")
		)
		(fp_line
			(start 0.67945 -0.3048)
			(end 0.67945 0.3048)
			(stroke
				(width 0.1)
				(type default)
			)
			(layer "F.Fab")
		)
		(fp_line
			(start 0.12065 -0.3048)
			(end 0.67945 -0.3048)
			(stroke
				(width 0.1)
				(type default)
			)
			(layer "F.Fab")
		)
		(fp_line
			(start 0.12065 -0.2794)
			(end 0.12065 -0.3048)
			(stroke
				(width 0.1)
				(type default)
			)
			(layer "F.Fab")
		)
		(fp_line
			(start -0.12065 -0.2794)
			(end 0.12065 -0.2794)
			(stroke
				(width 0.1)
				(type default)
			)
			(layer "F.Fab")
		)
		(fp_line
			(start 0.120396 0.2794)
			(end -0.12065 0.2794)
			(stroke
				(width 0.1)
				(type default)
			)
			(layer "F.Fab")
		)
		(fp_line
			(start -0.12065 0.2794)
			(end -0.12065 0.3048)
			(stroke
				(width 0.1)
				(type default)
			)
			(layer "F.Fab")
		)
		(fp_line
			(start 0.67945 0.3048)
			(end 0.120396 0.3048)
			(stroke
				(width 0.1)
				(type default)
			)
			(layer "F.Fab")
		)
		(fp_line
			(start 0.120396 0.3048)
			(end 0.120396 0.2794)
			(stroke
				(width 0.1)
				(type default)
			)
			(layer "F.Fab")
		)
		(fp_line
			(start -0.12065 0.3048)
			(end -0.67945 0.3048)
			(stroke
				(width 0.1)
				(type default)
			)
			(layer "F.Fab")
		)
		(fp_line
			(start -0.67945 0.3048)
			(end -0.67945 -0.305054)
			(stroke
				(width 0.1)
				(type default)
			)
			(layer "F.Fab")
		)
		(pad "1" smd circle
			(at -0.40005 0 90)
			(size 0 0)
			(layers "F.Cu" "F.Mask" "F.Paste")
			(net "P12V_SSD11_CO_ILIMIT")
		)
		(pad "2" smd circle
			(at 0.40005 0 90)
			(size 0 0)
			(layers "F.Cu" "F.Mask" "F.Paste")
			(net "GND")
		)
	)
	(footprint ""
		(layer "F.Cu")
		(at 380.16688 -52.543456 180)
		(property "Reference" "PC562"
			(at 0 0 180)
			(layer "F.SilkS")
			(hide yes)
			(effects
				(font
					(size 1.27 1.27)
				)
			)
		)
		(property "Value" ""
			(at 0 0 180)
			(layer "F.Fab")
			(effects
				(font
					(size 1.27 1.27)
				)
			)
		)
		(duplicate_pad_numbers_are_jumpers no)
		(fp_line
			(start 0.7874 0.4064)
			(end -0.7874 0.4064)
			(stroke
				(width 0.1524)
				(type default)
			)
			(layer "F.SilkS")
		)
		(fp_line
			(start 0.7874 -0.4064)
			(end 0.7874 0.4064)
			(stroke
				(width 0.1524)
				(type default)
			)
			(layer "F.SilkS")
		)
		(fp_line
			(start -0.7874 0.4064)
			(end -0.7874 -0.4064)
			(stroke
				(width 0.1524)
				(type default)
			)
			(layer "F.SilkS")
		)
		(fp_line
			(start -0.7874 -0.4064)
			(end 0.7874 -0.4064)
			(stroke
				(width 0.1524)
				(type default)
			)
			(layer "F.SilkS")
		)
		(fp_line
			(start 0.67945 0.3048)
			(end 0.120396 0.3048)
			(stroke
				(width 0.1)
				(type default)
			)
			(layer "F.Fab")
		)
		(fp_line
			(start 0.67945 -0.3048)
			(end 0.67945 0.3048)
			(stroke
				(width 0.1)
				(type default)
			)
			(layer "F.Fab")
		)
		(fp_line
			(start 0.12065 -0.2794)
			(end 0.12065 -0.3048)
			(stroke
				(width 0.1)
				(type default)
			)
			(layer "F.Fab")
		)
		(fp_line
			(start 0.12065 -0.3048)
			(end 0.67945 -0.3048)
			(stroke
				(width 0.1)
				(type default)
			)
			(layer "F.Fab")
		)
		(fp_line
			(start 0.120396 0.3048)
			(end 0.120396 0.2794)
			(stroke
				(width 0.1)
				(type default)
			)
			(layer "F.Fab")
		)
		(fp_line
			(start 0.120396 0.2794)
			(end -0.12065 0.2794)
			(stroke
				(width 0.1)
				(type default)
			)
			(layer "F.Fab")
		)
		(fp_line
			(start -0.12065 0.3048)
			(end -0.67945 0.3048)
			(stroke
				(width 0.1)
				(type default)
			)
			(layer "F.Fab")
		)
		(fp_line
			(start -0.12065 0.2794)
			(end -0.12065 0.3048)
			(stroke
				(width 0.1)
				(type default)
			)
			(layer "F.Fab")
		)
		(fp_line
			(start -0.12065 -0.2794)
			(end 0.12065 -0.2794)
			(stroke
				(width 0.1)
				(type default)
			)
			(layer "F.Fab")
		)
		(fp_line
			(start -0.12065 -0.305054)
			(end -0.12065 -0.2794)
			(stroke
				(width 0.1)
				(type default)
			)
			(layer "F.Fab")
		)
		(fp_line
			(start -0.67945 0.3048)
			(end -0.67945 -0.305054)
			(stroke
				(width 0.1)
				(type default)
			)
			(layer "F.Fab")
		)
		(fp_line
			(start -0.67945 -0.305054)
			(end -0.12065 -0.305054)
			(stroke
				(width 0.1)
				(type default)
			)
			(layer "F.Fab")
		)
		(pad "1" smd circle
			(at -0.40005 0 180)
			(size 0 0)
			(layers "F.Cu" "F.Mask" "F.Paste")
			(net "P3V3_SSD13")
		)
		(pad "2" smd circle
			(at 0.40005 0 180)
			(size 0 0)
			(layers "F.Cu" "F.Mask" "F.Paste")
			(net "GND")
		)
	)
	(footprint ""
		(layer "F.Cu")
		(at 143.030194 -290.805108 -90)
		(property "Reference" "C3209"
			(at 0 0 270)
			(layer "F.SilkS")
			(hide yes)
			(effects
				(font
					(size 1.27 1.27)
				)
			)
		)
		(property "Value" ""
			(at 0 0 270)
			(layer "F.Fab")
			(effects
				(font
					(size 1.27 1.27)
				)
			)
		)
		(duplicate_pad_numbers_are_jumpers no)
		(fp_line
			(start -1.2954 0.5842)
			(end -1.2954 -0.5842)
			(stroke
				(width 0.1524)
				(type default)
			)
			(layer "F.SilkS")
		)
		(fp_line
			(start 1.2954 0.5842)
			(end -1.2954 0.5842)
			(stroke
				(width 0.1524)
				(type default)
			)
			(layer "F.SilkS")
		)
		(fp_line
			(start -1.2954 -0.5842)
			(end 1.2954 -0.5842)
			(stroke
				(width 0.1524)
				(type default)
			)
			(layer "F.SilkS")
		)
		(fp_line
			(start 1.2954 -0.5842)
			(end 1.2954 0.5842)
			(stroke
				(width 0.1524)
				(type default)
			)
			(layer "F.SilkS")
		)
		(fp_line
			(start -0.8636 0.4572)
			(end -0.8636 0.4064)
			(stroke
				(width 0.1)
				(type default)
			)
			(layer "F.Fab")
		)
		(fp_line
			(start 0.8636 0.4572)
			(end -0.8636 0.4572)
			(stroke
				(width 0.1)
				(type default)
			)
			(layer "F.Fab")
		)
		(fp_line
			(start -1.1938 0.4064)
			(end -1.1938 -0.4064)
			(stroke
				(width 0.1)
				(type default)
			)
			(layer "F.Fab")
		)
		(fp_line
			(start -0.8636 0.4064)
			(end -1.1938 0.4064)
			(stroke
				(width 0.1)
				(type default)
			)
			(layer "F.Fab")
		)
		(fp_line
			(start 0.8636 0.4064)
			(end 0.8636 0.4572)
			(stroke
				(width 0.1)
				(type default)
			)
			(layer "F.Fab")
		)
		(fp_line
			(start 1.1938 0.4064)
			(end 0.8636 0.4064)
			(stroke
				(width 0.1)
				(type default)
			)
			(layer "F.Fab")
		)
		(fp_line
			(start -1.1938 -0.4064)
			(end -0.8636 -0.4064)
			(stroke
				(width 0.1)
				(type default)
			)
			(layer "F.Fab")
		)
		(fp_line
			(start -0.8636 -0.4064)
			(end -0.8636 -0.4572)
			(stroke
				(width 0.1)
				(type default)
			)
			(layer "F.Fab")
		)
		(fp_line
			(start 0.8636 -0.4064)
			(end 1.1938 -0.4064)
			(stroke
				(width 0.1)
				(type default)
			)
			(layer "F.Fab")
		)
		(fp_line
			(start 1.1938 -0.4064)
			(end 1.1938 0.4064)
			(stroke
				(width 0.1)
				(type default)
			)
			(layer "F.Fab")
		)
		(fp_line
			(start -0.8636 -0.4572)
			(end 0.8636 -0.4572)
			(stroke
				(width 0.1)
				(type default)
			)
			(layer "F.Fab")
		)
		(fp_line
			(start 0.8636 -0.4572)
			(end 0.8636 -0.4064)
			(stroke
				(width 0.1)
				(type default)
			)
			(layer "F.Fab")
		)
		(pad "1" smd rect
			(at -0.7366 0 180)
			(size 0.7112 0.8128)
			(layers "F.Cu" "F.Mask" "F.Paste")
			(net "P1V8_PLL0_PEX1")
		)
		(pad "2" smd rect
			(at 0.7366 0 180)
			(size 0.7112 0.8128)
			(layers "F.Cu" "F.Mask" "F.Paste")
			(net "GND")
		)
	)
	(footprint ""
		(layer "F.Cu")
		(at 161.346896 -38.49116 180)
		(property "Reference" "R6076"
			(at 0 0 180)
			(layer "F.SilkS")
			(hide yes)
			(effects
				(font
					(size 1.27 1.27)
				)
			)
		)
		(property "Value" ""
			(at 0 0 180)
			(layer "F.Fab")
			(effects
				(font
					(size 1.27 1.27)
				)
			)
		)
		(duplicate_pad_numbers_are_jumpers no)
		(fp_line
			(start 0.7874 0.4064)
			(end -0.7874 0.4064)
			(stroke
				(width 0.1524)
				(type default)
			)
			(layer "F.SilkS")
		)
		(fp_line
			(start 0.7874 -0.4064)
			(end 0.7874 0.4064)
			(stroke
				(width 0.1524)
				(type default)
			)
			(layer "F.SilkS")
		)
		(fp_line
			(start -0.7874 0.4064)
			(end -0.7874 -0.4064)
			(stroke
				(width 0.1524)
				(type default)
			)
			(layer "F.SilkS")
		)
		(fp_line
			(start -0.7874 -0.4064)
			(end 0.7874 -0.4064)
			(stroke
				(width 0.1524)
				(type default)
			)
			(layer "F.SilkS")
		)
		(fp_line
			(start 0.67945 0.3048)
			(end 0.120396 0.3048)
			(stroke
				(width 0.1)
				(type default)
			)
			(layer "F.Fab")
		)
		(fp_line
			(start 0.67945 -0.3048)
			(end 0.67945 0.3048)
			(stroke
				(width 0.1)
				(type default)
			)
			(layer "F.Fab")
		)
		(fp_line
			(start 0.12065 -0.2794)
			(end 0.12065 -0.3048)
			(stroke
				(width 0.1)
				(type default)
			)
			(layer "F.Fab")
		)
		(fp_line
			(start 0.12065 -0.3048)
			(end 0.67945 -0.3048)
			(stroke
				(width 0.1)
				(type default)
			)
			(layer "F.Fab")
		)
		(fp_line
			(start 0.120396 0.3048)
			(end 0.120396 0.2794)
			(stroke
				(width 0.1)
				(type default)
			)
			(layer "F.Fab")
		)
		(fp_line
			(start 0.120396 0.2794)
			(end -0.12065 0.2794)
			(stroke
				(width 0.1)
				(type default)
			)
			(layer "F.Fab")
		)
		(fp_line
			(start -0.12065 0.3048)
			(end -0.67945 0.3048)
			(stroke
				(width 0.1)
				(type default)
			)
			(layer "F.Fab")
		)
		(fp_line
			(start -0.12065 0.2794)
			(end -0.12065 0.3048)
			(stroke
				(width 0.1)
				(type default)
			)
			(layer "F.Fab")
		)
		(fp_line
			(start -0.12065 -0.2794)
			(end 0.12065 -0.2794)
			(stroke
				(width 0.1)
				(type default)
			)
			(layer "F.Fab")
		)
		(fp_line
			(start -0.12065 -0.305054)
			(end -0.12065 -0.2794)
			(stroke
				(width 0.1)
				(type default)
			)
			(layer "F.Fab")
		)
		(fp_line
			(start -0.67945 0.3048)
			(end -0.67945 -0.305054)
			(stroke
				(width 0.1)
				(type default)
			)
			(layer "F.Fab")
		)
		(fp_line
			(start -0.67945 -0.305054)
			(end -0.12065 -0.305054)
			(stroke
				(width 0.1)
				(type default)
			)
			(layer "F.Fab")
		)
		(pad "1" smd circle
			(at -0.40005 0 180)
			(size 0 0)
			(layers "F.Cu" "F.Mask" "F.Paste")
			(net "P3V3_SSD6_PG_G1")
		)
		(pad "2" smd circle
			(at 0.40005 0 180)
			(size 0 0)
			(layers "F.Cu" "F.Mask" "F.Paste")
			(net "GND")
		)
	)
	(footprint ""
		(layer "F.Cu")
		(at 223.45396 -239.446054 -90)
		(property "Reference" "R6218"
			(at 0 0 270)
			(layer "F.SilkS")
			(hide yes)
			(effects
				(font
					(size 1.27 1.27)
				)
			)
		)
		(property "Value" ""
			(at 0 0 270)
			(layer "F.Fab")
			(effects
				(font
					(size 1.27 1.27)
				)
			)
		)
		(duplicate_pad_numbers_are_jumpers no)
		(fp_line
			(start -0.7874 0.4064)
			(end -0.7874 -0.4064)
			(stroke
				(width 0.1524)
				(type default)
			)
			(layer "F.SilkS")
		)
		(fp_line
			(start 0.7874 0.4064)
			(end -0.7874 0.4064)
			(stroke
				(width 0.1524)
				(type default)
			)
			(layer "F.SilkS")
		)
		(fp_line
			(start -0.7874 -0.4064)
			(end 0.7874 -0.4064)
			(stroke
				(width 0.1524)
				(type default)
			)
			(layer "F.SilkS")
		)
		(fp_line
			(start 0.7874 -0.4064)
			(end 0.7874 0.4064)
			(stroke
				(width 0.1524)
				(type default)
			)
			(layer "F.SilkS")
		)
		(fp_line
			(start -0.67945 0.3048)
			(end -0.67945 -0.305054)
			(stroke
				(width 0.1)
				(type default)
			)
			(layer "F.Fab")
		)
		(fp_line
			(start -0.12065 0.3048)
			(end -0.67945 0.3048)
			(stroke
				(width 0.1)
				(type default)
			)
			(layer "F.Fab")
		)
		(fp_line
			(start 0.120396 0.3048)
			(end 0.120396 0.2794)
			(stroke
				(width 0.1)
				(type default)
			)
			(layer "F.Fab")
		)
		(fp_line
			(start 0.67945 0.3048)
			(end 0.120396 0.3048)
			(stroke
				(width 0.1)
				(type default)
			)
			(layer "F.Fab")
		)
		(fp_line
			(start -0.12065 0.2794)
			(end -0.12065 0.3048)
			(stroke
				(width 0.1)
				(type default)
			)
			(layer "F.Fab")
		)
		(fp_line
			(start 0.120396 0.2794)
			(end -0.12065 0.2794)
			(stroke
				(width 0.1)
				(type default)
			)
			(layer "F.Fab")
		)
		(fp_line
			(start -0.12065 -0.2794)
			(end 0.12065 -0.2794)
			(stroke
				(width 0.1)
				(type default)
			)
			(layer "F.Fab")
		)
		(fp_line
			(start 0.12065 -0.2794)
			(end 0.12065 -0.3048)
			(stroke
				(width 0.1)
				(type default)
			)
			(layer "F.Fab")
		)
		(fp_line
			(start 0.12065 -0.3048)
			(end 0.67945 -0.3048)
			(stroke
				(width 0.1)
				(type default)
			)
			(layer "F.Fab")
		)
		(fp_line
			(start 0.67945 -0.3048)
			(end 0.67945 0.3048)
			(stroke
				(width 0.1)
				(type default)
			)
			(layer "F.Fab")
		)
		(fp_line
			(start -0.67945 -0.305054)
			(end -0.12065 -0.305054)
			(stroke
				(width 0.1)
				(type default)
			)
			(layer "F.Fab")
		)
		(fp_line
			(start -0.12065 -0.305054)
			(end -0.12065 -0.2794)
			(stroke
				(width 0.1)
				(type default)
			)
			(layer "F.Fab")
		)
		(pad "1" smd circle
			(at -0.40005 0 270)
			(size 0 0)
			(layers "F.Cu" "F.Mask" "F.Paste")
			(net "BIC_UART_BIC_SEL_R")
		)
		(pad "2" smd circle
			(at 0.40005 0 270)
			(size 0 0)
			(layers "F.Cu" "F.Mask" "F.Paste")
			(net "GND")
		)
	)
	(footprint ""
		(layer "F.Cu")
		(at 194.367912 -53.051456)
		(property "Reference" "R4463"
			(at 0 0 0)
			(layer "F.SilkS")
			(hide yes)
			(effects
				(font
					(size 1.27 1.27)
				)
			)
		)
		(property "Value" ""
			(at 0 0 0)
			(layer "F.Fab")
			(effects
				(font
					(size 1.27 1.27)
				)
			)
		)
		(duplicate_pad_numbers_are_jumpers no)
		(fp_line
			(start -0.7874 -0.4064)
			(end 0.7874 -0.4064)
			(stroke
				(width 0.1524)
				(type default)
			)
			(layer "F.SilkS")
		)
		(fp_line
			(start -0.7874 0.4064)
			(end -0.7874 -0.4064)
			(stroke
				(width 0.1524)
				(type default)
			)
			(layer "F.SilkS")
		)
		(fp_line
			(start 0.7874 -0.4064)
			(end 0.7874 0.4064)
			(stroke
				(width 0.1524)
				(type default)
			)
			(layer "F.SilkS")
		)
		(fp_line
			(start 0.7874 0.4064)
			(end -0.7874 0.4064)
			(stroke
				(width 0.1524)
				(type default)
			)
			(layer "F.SilkS")
		)
		(fp_line
			(start -0.67945 -0.305054)
			(end -0.12065 -0.305054)
			(stroke
				(width 0.1)
				(type default)
			)
			(layer "F.Fab")
		)
		(fp_line
			(start -0.67945 0.3048)
			(end -0.67945 -0.305054)
			(stroke
				(width 0.1)
				(type default)
			)
			(layer "F.Fab")
		)
		(fp_line
			(start -0.12065 -0.305054)
			(end -0.12065 -0.2794)
			(stroke
				(width 0.1)
				(type default)
			)
			(layer "F.Fab")
		)
		(fp_line
			(start -0.12065 -0.2794)
			(end 0.12065 -0.2794)
			(stroke
				(width 0.1)
				(type default)
			)
			(layer "F.Fab")
		)
		(fp_line
			(start -0.12065 0.2794)
			(end -0.12065 0.3048)
			(stroke
				(width 0.1)
				(type default)
			)
			(layer "F.Fab")
		)
		(fp_line
			(start -0.12065 0.3048)
			(end -0.67945 0.3048)
			(stroke
				(width 0.1)
				(type default)
			)
			(layer "F.Fab")
		)
		(fp_line
			(start 0.120396 0.2794)
			(end -0.12065 0.2794)
			(stroke
				(width 0.1)
				(type default)
			)
			(layer "F.Fab")
		)
		(fp_line
			(start 0.120396 0.3048)
			(end 0.120396 0.2794)
			(stroke
				(width 0.1)
				(type default)
			)
			(layer "F.Fab")
		)
		(fp_line
			(start 0.12065 -0.3048)
			(end 0.67945 -0.3048)
			(stroke
				(width 0.1)
				(type default)
			)
			(layer "F.Fab")
		)
		(fp_line
			(start 0.12065 -0.2794)
			(end 0.12065 -0.3048)
			(stroke
				(width 0.1)
				(type default)
			)
			(layer "F.Fab")
		)
		(fp_line
			(start 0.67945 -0.3048)
			(end 0.67945 0.3048)
			(stroke
				(width 0.1)
				(type default)
			)
			(layer "F.Fab")
		)
		(fp_line
			(start 0.67945 0.3048)
			(end 0.120396 0.3048)
			(stroke
				(width 0.1)
				(type default)
			)
			(layer "F.Fab")
		)
		(pad "1" smd circle
			(at -0.40005 0)
			(size 0 0)
			(layers "F.Cu" "F.Mask" "F.Paste")
			(net "PWRGD_P12V_SSD6")
		)
		(pad "2" smd circle
			(at 0.40005 0)
			(size 0 0)
			(layers "F.Cu" "F.Mask" "F.Paste")
			(net "PWRGD_P12V_SSD6_R")
		)
	)
	(footprint ""
		(layer "F.Cu")
		(at 338.498434 -5.747258)
		(property "Reference" "R1704"
			(at 0 0 0)
			(layer "F.SilkS")
			(hide yes)
			(effects
				(font
					(size 1.27 1.27)
				)
			)
		)
		(property "Value" ""
			(at 0 0 0)
			(layer "F.Fab")
			(effects
				(font
					(size 1.27 1.27)
				)
			)
		)
		(duplicate_pad_numbers_are_jumpers no)
		(fp_line
			(start -0.7874 -0.4064)
			(end 0.7874 -0.4064)
			(stroke
				(width 0.1524)
				(type default)
			)
			(layer "F.SilkS")
		)
		(fp_line
			(start -0.7874 0.4064)
			(end -0.7874 -0.4064)
			(stroke
				(width 0.1524)
				(type default)
			)
			(layer "F.SilkS")
		)
		(fp_line
			(start 0.7874 -0.4064)
			(end 0.7874 0.4064)
			(stroke
				(width 0.1524)
				(type default)
			)
			(layer "F.SilkS")
		)
		(fp_line
			(start 0.7874 0.4064)
			(end -0.7874 0.4064)
			(stroke
				(width 0.1524)
				(type default)
			)
			(layer "F.SilkS")
		)
		(fp_line
			(start -0.67945 -0.305054)
			(end -0.12065 -0.305054)
			(stroke
				(width 0.1)
				(type default)
			)
			(layer "F.Fab")
		)
		(fp_line
			(start -0.67945 0.3048)
			(end -0.67945 -0.305054)
			(stroke
				(width 0.1)
				(type default)
			)
			(layer "F.Fab")
		)
		(fp_line
			(start -0.12065 -0.305054)
			(end -0.12065 -0.2794)
			(stroke
				(width 0.1)
				(type default)
			)
			(layer "F.Fab")
		)
		(fp_line
			(start -0.12065 -0.2794)
			(end 0.12065 -0.2794)
			(stroke
				(width 0.1)
				(type default)
			)
			(layer "F.Fab")
		)
		(fp_line
			(start -0.12065 0.2794)
			(end -0.12065 0.3048)
			(stroke
				(width 0.1)
				(type default)
			)
			(layer "F.Fab")
		)
		(fp_line
			(start -0.12065 0.3048)
			(end -0.67945 0.3048)
			(stroke
				(width 0.1)
				(type default)
			)
			(layer "F.Fab")
		)
		(fp_line
			(start 0.120396 0.2794)
			(end -0.12065 0.2794)
			(stroke
				(width 0.1)
				(type default)
			)
			(layer "F.Fab")
		)
		(fp_line
			(start 0.120396 0.3048)
			(end 0.120396 0.2794)
			(stroke
				(width 0.1)
				(type default)
			)
			(layer "F.Fab")
		)
		(fp_line
			(start 0.12065 -0.3048)
			(end 0.67945 -0.3048)
			(stroke
				(width 0.1)
				(type default)
			)
			(layer "F.Fab")
		)
		(fp_line
			(start 0.12065 -0.2794)
			(end 0.12065 -0.3048)
			(stroke
				(width 0.1)
				(type default)
			)
			(layer "F.Fab")
		)
		(fp_line
			(start 0.67945 -0.3048)
			(end 0.67945 0.3048)
			(stroke
				(width 0.1)
				(type default)
			)
			(layer "F.Fab")
		)
		(fp_line
			(start 0.67945 0.3048)
			(end 0.120396 0.3048)
			(stroke
				(width 0.1)
				(type default)
			)
			(layer "F.Fab")
		)
		(pad "1" smd circle
			(at -0.40005 0)
			(size 0 0)
			(layers "F.Cu" "F.Mask" "F.Paste")
			(net "SMB_SSD11_ISO_EN")
		)
		(pad "2" smd circle
			(at 0.40005 0)
			(size 0 0)
			(layers "F.Cu" "F.Mask" "F.Paste")
			(net "P3V3_AUX")
		)
	)
	(footprint ""
		(layer "F.Cu")
		(at 240.389156 -228.57206 180)
		(property "Reference" "R6761"
			(at 0 0 180)
			(layer "F.SilkS")
			(hide yes)
			(effects
				(font
					(size 1.27 1.27)
				)
			)
		)
		(property "Value" ""
			(at 0 0 180)
			(layer "F.Fab")
			(effects
				(font
					(size 1.27 1.27)
				)
			)
		)
		(duplicate_pad_numbers_are_jumpers no)
		(fp_line
			(start 0.7874 -0.4064)
			(end 0.7874 0.4064)
			(stroke
				(width 0.1524)
				(type default)
			)
			(layer "F.SilkS")
		)
		(fp_line
			(start 0.67945 0.3048)
			(end 0.120396 0.3048)
			(stroke
				(width 0.1)
				(type default)
			)
			(layer "F.Fab")
		)
		(fp_line
			(start 0.67945 -0.3048)
			(end 0.67945 0.3048)
			(stroke
				(width 0.1)
				(type default)
			)
			(layer "F.Fab")
		)
		(fp_line
			(start 0.12065 -0.2794)
			(end 0.12065 -0.3048)
			(stroke
				(width 0.1)
				(type default)
			)
			(layer "F.Fab")
		)
		(fp_line
			(start 0.12065 -0.3048)
			(end 0.67945 -0.3048)
			(stroke
				(width 0.1)
				(type default)
			)
			(layer "F.Fab")
		)
		(fp_line
			(start 0.120396 0.3048)
			(end 0.120396 0.2794)
			(stroke
				(width 0.1)
				(type default)
			)
			(layer "F.Fab")
		)
		(fp_line
			(start 0.120396 0.2794)
			(end -0.12065 0.2794)
			(stroke
				(width 0.1)
				(type default)
			)
			(layer "F.Fab")
		)
		(fp_line
			(start -0.12065 0.3048)
			(end -0.67945 0.3048)
			(stroke
				(width 0.1)
				(type default)
			)
			(layer "F.Fab")
		)
		(fp_line
			(start -0.12065 0.2794)
			(end -0.12065 0.3048)
			(stroke
				(width 0.1)
				(type default)
			)
			(layer "F.Fab")
		)
		(fp_line
			(start -0.12065 -0.2794)
			(end 0.12065 -0.2794)
			(stroke
				(width 0.1)
				(type default)
			)
			(layer "F.Fab")
		)
		(fp_line
			(start -0.12065 -0.305054)
			(end -0.12065 -0.2794)
			(stroke
				(width 0.1)
				(type default)
			)
			(layer "F.Fab")
		)
		(fp_line
			(start -0.67945 0.3048)
			(end -0.67945 -0.305054)
			(stroke
				(width 0.1)
				(type default)
			)
			(layer "F.Fab")
		)
		(fp_line
			(start -0.67945 -0.305054)
			(end -0.12065 -0.305054)
			(stroke
				(width 0.1)
				(type default)
			)
			(layer "F.Fab")
		)
		(pad "1" smd circle
			(at -0.40005 0 180)
			(size 0 0)
			(layers "F.Cu" "F.Mask" "F.Paste")
			(net "USB2_BIC_DN")
		)
		(pad "2" smd circle
			(at 0.40005 0 180)
			(size 0 0)
			(layers "F.Cu" "F.Mask" "F.Paste")
			(net "GND")
		)
	)
	(footprint ""
		(layer "F.Cu")
		(at 445.318134 -411.500066 -90)
		(property "Reference" "C3653"
			(at 0 0 270)
			(layer "F.SilkS")
			(hide yes)
			(effects
				(font
					(size 1.27 1.27)
				)
			)
		)
		(property "Value" ""
			(at 0 0 270)
			(layer "F.Fab")
			(effects
				(font
					(size 1.27 1.27)
				)
			)
		)
		(duplicate_pad_numbers_are_jumpers no)
		(fp_line
			(start -0.7874 0.4064)
			(end -0.7874 -0.4064)
			(stroke
				(width 0.1524)
				(type default)
			)
			(layer "F.SilkS")
		)
		(fp_line
			(start 0.7874 0.4064)
			(end -0.7874 0.4064)
			(stroke
				(width 0.1524)
				(type default)
			)
			(layer "F.SilkS")
		)
		(fp_line
			(start -0.7874 -0.4064)
			(end 0.7874 -0.4064)
			(stroke
				(width 0.1524)
				(type default)
			)
			(layer "F.SilkS")
		)
		(fp_line
			(start 0.7874 -0.4064)
			(end 0.7874 0.4064)
			(stroke
				(width 0.1524)
				(type default)
			)
			(layer "F.SilkS")
		)
		(fp_line
			(start -0.67945 0.3048)
			(end -0.67945 -0.305054)
			(stroke
				(width 0.1)
				(type default)
			)
			(layer "F.Fab")
		)
		(fp_line
			(start -0.12065 0.3048)
			(end -0.67945 0.3048)
			(stroke
				(width 0.1)
				(type default)
			)
			(layer "F.Fab")
		)
		(fp_line
			(start 0.120396 0.3048)
			(end 0.120396 0.2794)
			(stroke
				(width 0.1)
				(type default)
			)
			(layer "F.Fab")
		)
		(fp_line
			(start 0.67945 0.3048)
			(end 0.120396 0.3048)
			(stroke
				(width 0.1)
				(type default)
			)
			(layer "F.Fab")
		)
		(fp_line
			(start -0.12065 0.2794)
			(end -0.12065 0.3048)
			(stroke
				(width 0.1)
				(type default)
			)
			(layer "F.Fab")
		)
		(fp_line
			(start 0.120396 0.2794)
			(end -0.12065 0.2794)
			(stroke
				(width 0.1)
				(type default)
			)
			(layer "F.Fab")
		)
		(fp_line
			(start -0.12065 -0.2794)
			(end 0.12065 -0.2794)
			(stroke
				(width 0.1)
				(type default)
			)
			(layer "F.Fab")
		)
		(fp_line
			(start 0.12065 -0.2794)
			(end 0.12065 -0.3048)
			(stroke
				(width 0.1)
				(type default)
			)
			(layer "F.Fab")
		)
		(fp_line
			(start 0.12065 -0.3048)
			(end 0.67945 -0.3048)
			(stroke
				(width 0.1)
				(type default)
			)
			(layer "F.Fab")
		)
		(fp_line
			(start 0.67945 -0.3048)
			(end 0.67945 0.3048)
			(stroke
				(width 0.1)
				(type default)
			)
			(layer "F.Fab")
		)
		(fp_line
			(start -0.67945 -0.305054)
			(end -0.12065 -0.305054)
			(stroke
				(width 0.1)
				(type default)
			)
			(layer "F.Fab")
		)
		(fp_line
			(start -0.12065 -0.305054)
			(end -0.12065 -0.2794)
			(stroke
				(width 0.1)
				(type default)
			)
			(layer "F.Fab")
		)
		(pad "1" smd circle
			(at -0.40005 0 270)
			(size 0 0)
			(layers "F.Cu" "F.Mask" "F.Paste")
			(net "P3V3_AUX")
		)
		(pad "2" smd circle
			(at 0.40005 0 270)
			(size 0 0)
			(layers "F.Cu" "F.Mask" "F.Paste")
			(net "GND")
		)
	)
	(footprint ""
		(layer "F.Cu")
		(at 217.235786 -214.238586 180)
		(property "Reference" "R1503"
			(at 0 0 180)
			(layer "F.SilkS")
			(hide yes)
			(effects
				(font
					(size 1.27 1.27)
				)
			)
		)
		(property "Value" ""
			(at 0 0 180)
			(layer "F.Fab")
			(effects
				(font
					(size 1.27 1.27)
				)
			)
		)
		(duplicate_pad_numbers_are_jumpers no)
		(fp_line
			(start 0.7874 0.4064)
			(end -0.7874 0.4064)
			(stroke
				(width 0.1524)
				(type default)
			)
			(layer "F.SilkS")
		)
		(fp_line
			(start 0.7874 -0.4064)
			(end 0.7874 0.4064)
			(stroke
				(width 0.1524)
				(type default)
			)
			(layer "F.SilkS")
		)
		(fp_line
			(start -0.7874 0.4064)
			(end -0.7874 -0.4064)
			(stroke
				(width 0.1524)
				(type default)
			)
			(layer "F.SilkS")
		)
		(fp_line
			(start -0.7874 -0.4064)
			(end 0.7874 -0.4064)
			(stroke
				(width 0.1524)
				(type default)
			)
			(layer "F.SilkS")
		)
		(fp_line
			(start 0.67945 0.3048)
			(end 0.120396 0.3048)
			(stroke
				(width 0.1)
				(type default)
			)
			(layer "F.Fab")
		)
		(fp_line
			(start 0.67945 -0.3048)
			(end 0.67945 0.3048)
			(stroke
				(width 0.1)
				(type default)
			)
			(layer "F.Fab")
		)
		(fp_line
			(start 0.12065 -0.2794)
			(end 0.12065 -0.3048)
			(stroke
				(width 0.1)
				(type default)
			)
			(layer "F.Fab")
		)
		(fp_line
			(start 0.12065 -0.3048)
			(end 0.67945 -0.3048)
			(stroke
				(width 0.1)
				(type default)
			)
			(layer "F.Fab")
		)
		(fp_line
			(start 0.120396 0.3048)
			(end 0.120396 0.2794)
			(stroke
				(width 0.1)
				(type default)
			)
			(layer "F.Fab")
		)
		(fp_line
			(start 0.120396 0.2794)
			(end -0.12065 0.2794)
			(stroke
				(width 0.1)
				(type default)
			)
			(layer "F.Fab")
		)
		(fp_line
			(start -0.12065 0.3048)
			(end -0.67945 0.3048)
			(stroke
				(width 0.1)
				(type default)
			)
			(layer "F.Fab")
		)
		(fp_line
			(start -0.12065 0.2794)
			(end -0.12065 0.3048)
			(stroke
				(width 0.1)
				(type default)
			)
			(layer "F.Fab")
		)
		(fp_line
			(start -0.12065 -0.2794)
			(end 0.12065 -0.2794)
			(stroke
				(width 0.1)
				(type default)
			)
			(layer "F.Fab")
		)
		(fp_line
			(start -0.12065 -0.305054)
			(end -0.12065 -0.2794)
			(stroke
				(width 0.1)
				(type default)
			)
			(layer "F.Fab")
		)
		(fp_line
			(start -0.67945 0.3048)
			(end -0.67945 -0.305054)
			(stroke
				(width 0.1)
				(type default)
			)
			(layer "F.Fab")
		)
		(fp_line
			(start -0.67945 -0.305054)
			(end -0.12065 -0.305054)
			(stroke
				(width 0.1)
				(type default)
			)
			(layer "F.Fab")
		)
		(pad "1" smd circle
			(at -0.40005 0 180)
			(size 0 0)
			(layers "F.Cu" "F.Mask" "F.Paste")
			(net "SMB_NIC6_SDA")
		)
		(pad "2" smd circle
			(at 0.40005 0 180)
			(size 0 0)
			(layers "F.Cu" "F.Mask" "F.Paste")
			(net "SMB_NIC6_R_SDA")
		)
	)
	(footprint ""
		(layer "F.Cu")
		(at 373.364506 -29.079952 180)
		(property "Reference" "R6210"
			(at 0 0 180)
			(layer "F.SilkS")
			(hide yes)
			(effects
				(font
					(size 1.27 1.27)
				)
			)
		)
		(property "Value" ""
			(at 0 0 180)
			(layer "F.Fab")
			(effects
				(font
					(size 1.27 1.27)
				)
			)
		)
		(duplicate_pad_numbers_are_jumpers no)
		(fp_line
			(start 0.7874 0.4064)
			(end -0.7874 0.4064)
			(stroke
				(width 0.1524)
				(type default)
			)
			(layer "F.SilkS")
		)
		(fp_line
			(start 0.7874 -0.4064)
			(end 0.7874 0.4064)
			(stroke
				(width 0.1524)
				(type default)
			)
			(layer "F.SilkS")
		)
		(fp_line
			(start -0.7874 0.4064)
			(end -0.7874 -0.4064)
			(stroke
				(width 0.1524)
				(type default)
			)
			(layer "F.SilkS")
		)
		(fp_line
			(start -0.7874 -0.4064)
			(end 0.7874 -0.4064)
			(stroke
				(width 0.1524)
				(type default)
			)
			(layer "F.SilkS")
		)
		(fp_line
			(start 0.67945 0.3048)
			(end 0.120396 0.3048)
			(stroke
				(width 0.1)
				(type default)
			)
			(layer "F.Fab")
		)
		(fp_line
			(start 0.67945 -0.3048)
			(end 0.67945 0.3048)
			(stroke
				(width 0.1)
				(type default)
			)
			(layer "F.Fab")
		)
		(fp_line
			(start 0.12065 -0.2794)
			(end 0.12065 -0.3048)
			(stroke
				(width 0.1)
				(type default)
			)
			(layer "F.Fab")
		)
		(fp_line
			(start 0.12065 -0.3048)
			(end 0.67945 -0.3048)
			(stroke
				(width 0.1)
				(type default)
			)
			(layer "F.Fab")
		)
		(fp_line
			(start 0.120396 0.3048)
			(end 0.120396 0.2794)
			(stroke
				(width 0.1)
				(type default)
			)
			(layer "F.Fab")
		)
		(fp_line
			(start 0.120396 0.2794)
			(end -0.12065 0.2794)
			(stroke
				(width 0.1)
				(type default)
			)
			(layer "F.Fab")
		)
		(fp_line
			(start -0.12065 0.3048)
			(end -0.67945 0.3048)
			(stroke
				(width 0.1)
				(type default)
			)
			(layer "F.Fab")
		)
		(fp_line
			(start -0.12065 0.2794)
			(end -0.12065 0.3048)
			(stroke
				(width 0.1)
				(type default)
			)
			(layer "F.Fab")
		)
		(fp_line
			(start -0.12065 -0.2794)
			(end 0.12065 -0.2794)
			(stroke
				(width 0.1)
				(type default)
			)
			(layer "F.Fab")
		)
		(fp_line
			(start -0.12065 -0.305054)
			(end -0.12065 -0.2794)
			(stroke
				(width 0.1)
				(type default)
			)
			(layer "F.Fab")
		)
		(fp_line
			(start -0.67945 0.3048)
			(end -0.67945 -0.305054)
			(stroke
				(width 0.1)
				(type default)
			)
			(layer "F.Fab")
		)
		(fp_line
			(start -0.67945 -0.305054)
			(end -0.12065 -0.305054)
			(stroke
				(width 0.1)
				(type default)
			)
			(layer "F.Fab")
		)
		(pad "1" smd circle
			(at -0.40005 0 180)
			(size 0 0)
			(layers "F.Cu" "F.Mask" "F.Paste")
			(net "GND")
		)
		(pad "2" smd circle
			(at 0.40005 0 180)
			(size 0 0)
			(layers "F.Cu" "F.Mask" "F.Paste")
			(net "SSD12_PWRDIS_R")
		)
	)
	(footprint ""
		(layer "F.Cu")
		(at 208.782158 -237.127034)
		(property "Reference" "C2708"
			(at 0 0 0)
			(layer "F.SilkS")
			(hide yes)
			(effects
				(font
					(size 1.27 1.27)
				)
			)
		)
		(property "Value" ""
			(at 0 0 0)
			(layer "F.Fab")
			(effects
				(font
					(size 1.27 1.27)
				)
			)
		)
		(duplicate_pad_numbers_are_jumpers no)
		(fp_line
			(start -0.7874 -0.4064)
			(end 0.7874 -0.4064)
			(stroke
				(width 0.1524)
				(type default)
			)
			(layer "F.SilkS")
		)
		(fp_line
			(start -0.7874 0.4064)
			(end -0.7874 -0.4064)
			(stroke
				(width 0.1524)
				(type default)
			)
			(layer "F.SilkS")
		)
		(fp_line
			(start 0.7874 -0.4064)
			(end 0.7874 0.4064)
			(stroke
				(width 0.1524)
				(type default)
			)
			(layer "F.SilkS")
		)
		(fp_line
			(start 0.7874 0.4064)
			(end -0.7874 0.4064)
			(stroke
				(width 0.1524)
				(type default)
			)
			(layer "F.SilkS")
		)
		(fp_line
			(start -0.67945 -0.305054)
			(end -0.12065 -0.305054)
			(stroke
				(width 0.1)
				(type default)
			)
			(layer "F.Fab")
		)
		(fp_line
			(start -0.67945 0.3048)
			(end -0.67945 -0.305054)
			(stroke
				(width 0.1)
				(type default)
			)
			(layer "F.Fab")
		)
		(fp_line
			(start -0.12065 -0.305054)
			(end -0.12065 -0.2794)
			(stroke
				(width 0.1)
				(type default)
			)
			(layer "F.Fab")
		)
		(fp_line
			(start -0.12065 -0.2794)
			(end 0.12065 -0.2794)
			(stroke
				(width 0.1)
				(type default)
			)
			(layer "F.Fab")
		)
		(fp_line
			(start -0.12065 0.2794)
			(end -0.12065 0.3048)
			(stroke
				(width 0.1)
				(type default)
			)
			(layer "F.Fab")
		)
		(fp_line
			(start -0.12065 0.3048)
			(end -0.67945 0.3048)
			(stroke
				(width 0.1)
				(type default)
			)
			(layer "F.Fab")
		)
		(fp_line
			(start 0.120396 0.2794)
			(end -0.12065 0.2794)
			(stroke
				(width 0.1)
				(type default)
			)
			(layer "F.Fab")
		)
		(fp_line
			(start 0.120396 0.3048)
			(end 0.120396 0.2794)
			(stroke
				(width 0.1)
				(type default)
			)
			(layer "F.Fab")
		)
		(fp_line
			(start 0.12065 -0.3048)
			(end 0.67945 -0.3048)
			(stroke
				(width 0.1)
				(type default)
			)
			(layer "F.Fab")
		)
		(fp_line
			(start 0.12065 -0.2794)
			(end 0.12065 -0.3048)
			(stroke
				(width 0.1)
				(type default)
			)
			(layer "F.Fab")
		)
		(fp_line
			(start 0.67945 -0.3048)
			(end 0.67945 0.3048)
			(stroke
				(width 0.1)
				(type default)
			)
			(layer "F.Fab")
		)
		(fp_line
			(start 0.67945 0.3048)
			(end 0.120396 0.3048)
			(stroke
				(width 0.1)
				(type default)
			)
			(layer "F.Fab")
		)
		(pad "1" smd circle
			(at -0.40005 0)
			(size 0 0)
			(layers "F.Cu" "F.Mask" "F.Paste")
			(net "GND")
		)
		(pad "2" smd circle
			(at 0.40005 0)
			(size 0 0)
			(layers "F.Cu" "F.Mask" "F.Paste")
			(net "P1V8_PEX")
		)
	)
	(footprint ""
		(layer "F.Cu")
		(at 104.728772 -92.366846 -90)
		(property "Reference" "R1130"
			(at 0 0 270)
			(layer "F.SilkS")
			(hide yes)
			(effects
				(font
					(size 1.27 1.27)
				)
			)
		)
		(property "Value" ""
			(at 0 0 270)
			(layer "F.Fab")
			(effects
				(font
					(size 1.27 1.27)
				)
			)
		)
		(duplicate_pad_numbers_are_jumpers no)
		(fp_line
			(start -0.7874 0.4064)
			(end -0.7874 -0.4064)
			(stroke
				(width 0.1524)
				(type default)
			)
			(layer "F.SilkS")
		)
		(fp_line
			(start 0.7874 0.4064)
			(end -0.7874 0.4064)
			(stroke
				(width 0.1524)
				(type default)
			)
			(layer "F.SilkS")
		)
		(fp_line
			(start -0.7874 -0.4064)
			(end 0.7874 -0.4064)
			(stroke
				(width 0.1524)
				(type default)
			)
			(layer "F.SilkS")
		)
		(fp_line
			(start 0.7874 -0.4064)
			(end 0.7874 0.4064)
			(stroke
				(width 0.1524)
				(type default)
			)
			(layer "F.SilkS")
		)
		(fp_line
			(start -0.67945 0.3048)
			(end -0.67945 -0.305054)
			(stroke
				(width 0.1)
				(type default)
			)
			(layer "F.Fab")
		)
		(fp_line
			(start -0.12065 0.3048)
			(end -0.67945 0.3048)
			(stroke
				(width 0.1)
				(type default)
			)
			(layer "F.Fab")
		)
		(fp_line
			(start 0.120396 0.3048)
			(end 0.120396 0.2794)
			(stroke
				(width 0.1)
				(type default)
			)
			(layer "F.Fab")
		)
		(fp_line
			(start 0.67945 0.3048)
			(end 0.120396 0.3048)
			(stroke
				(width 0.1)
				(type default)
			)
			(layer "F.Fab")
		)
		(fp_line
			(start -0.12065 0.2794)
			(end -0.12065 0.3048)
			(stroke
				(width 0.1)
				(type default)
			)
			(layer "F.Fab")
		)
		(fp_line
			(start 0.120396 0.2794)
			(end -0.12065 0.2794)
			(stroke
				(width 0.1)
				(type default)
			)
			(layer "F.Fab")
		)
		(fp_line
			(start -0.12065 -0.2794)
			(end 0.12065 -0.2794)
			(stroke
				(width 0.1)
				(type default)
			)
			(layer "F.Fab")
		)
		(fp_line
			(start 0.12065 -0.2794)
			(end 0.12065 -0.3048)
			(stroke
				(width 0.1)
				(type default)
			)
			(layer "F.Fab")
		)
		(fp_line
			(start 0.12065 -0.3048)
			(end 0.67945 -0.3048)
			(stroke
				(width 0.1)
				(type default)
			)
			(layer "F.Fab")
		)
		(fp_line
			(start 0.67945 -0.3048)
			(end 0.67945 0.3048)
			(stroke
				(width 0.1)
				(type default)
			)
			(layer "F.Fab")
		)
		(fp_line
			(start -0.67945 -0.305054)
			(end -0.12065 -0.305054)
			(stroke
				(width 0.1)
				(type default)
			)
			(layer "F.Fab")
		)
		(fp_line
			(start -0.12065 -0.305054)
			(end -0.12065 -0.2794)
			(stroke
				(width 0.1)
				(type default)
			)
			(layer "F.Fab")
		)
		(pad "1" smd circle
			(at -0.40005 0 270)
			(size 0 0)
			(layers "F.Cu" "F.Mask" "F.Paste")
			(net "P3V3")
		)
		(pad "2" smd circle
			(at 0.40005 0 270)
			(size 0 0)
			(layers "F.Cu" "F.Mask" "F.Paste")
			(net "PU_9ZXL0851_0_7_HBW")
		)
	)
	(footprint ""
		(layer "F.Cu")
		(at 455.009758 -276.316694)
		(property "Reference" "R811"
			(at 0 0 0)
			(layer "F.SilkS")
			(hide yes)
			(effects
				(font
					(size 1.27 1.27)
				)
			)
		)
		(property "Value" ""
			(at 0 0 0)
			(layer "F.Fab")
			(effects
				(font
					(size 1.27 1.27)
				)
			)
		)
		(duplicate_pad_numbers_are_jumpers no)
		(fp_line
			(start -0.7874 -0.4064)
			(end 0.7874 -0.4064)
			(stroke
				(width 0.1524)
				(type default)
			)
			(layer "F.SilkS")
		)
		(fp_line
			(start -0.7874 0.4064)
			(end -0.7874 -0.4064)
			(stroke
				(width 0.1524)
				(type default)
			)
			(layer "F.SilkS")
		)
		(fp_line
			(start 0.7874 -0.4064)
			(end 0.7874 0.4064)
			(stroke
				(width 0.1524)
				(type default)
			)
			(layer "F.SilkS")
		)
		(fp_line
			(start 0.7874 0.4064)
			(end -0.7874 0.4064)
			(stroke
				(width 0.1524)
				(type default)
			)
			(layer "F.SilkS")
		)
		(fp_line
			(start -0.67945 -0.305054)
			(end -0.12065 -0.305054)
			(stroke
				(width 0.1)
				(type default)
			)
			(layer "F.Fab")
		)
		(fp_line
			(start -0.67945 0.3048)
			(end -0.67945 -0.305054)
			(stroke
				(width 0.1)
				(type default)
			)
			(layer "F.Fab")
		)
		(fp_line
			(start -0.12065 -0.305054)
			(end -0.12065 -0.2794)
			(stroke
				(width 0.1)
				(type default)
			)
			(layer "F.Fab")
		)
		(fp_line
			(start -0.12065 -0.2794)
			(end 0.12065 -0.2794)
			(stroke
				(width 0.1)
				(type default)
			)
			(layer "F.Fab")
		)
		(fp_line
			(start -0.12065 0.2794)
			(end -0.12065 0.3048)
			(stroke
				(width 0.1)
				(type default)
			)
			(layer "F.Fab")
		)
		(fp_line
			(start -0.12065 0.3048)
			(end -0.67945 0.3048)
			(stroke
				(width 0.1)
				(type default)
			)
			(layer "F.Fab")
		)
		(fp_line
			(start 0.120396 0.2794)
			(end -0.12065 0.2794)
			(stroke
				(width 0.1)
				(type default)
			)
			(layer "F.Fab")
		)
		(fp_line
			(start 0.120396 0.3048)
			(end 0.120396 0.2794)
			(stroke
				(width 0.1)
				(type default)
			)
			(layer "F.Fab")
		)
		(fp_line
			(start 0.12065 -0.3048)
			(end 0.67945 -0.3048)
			(stroke
				(width 0.1)
				(type default)
			)
			(layer "F.Fab")
		)
		(fp_line
			(start 0.12065 -0.2794)
			(end 0.12065 -0.3048)
			(stroke
				(width 0.1)
				(type default)
			)
			(layer "F.Fab")
		)
		(fp_line
			(start 0.67945 -0.3048)
			(end 0.67945 0.3048)
			(stroke
				(width 0.1)
				(type default)
			)
			(layer "F.Fab")
		)
		(fp_line
			(start 0.67945 0.3048)
			(end 0.120396 0.3048)
			(stroke
				(width 0.1)
				(type default)
			)
			(layer "F.Fab")
		)
		(pad "1" smd circle
			(at -0.40005 0)
			(size 0 0)
			(layers "F.Cu" "F.Mask" "F.Paste")
			(net "P1V25_PEX3")
		)
		(pad "2" smd circle
			(at 0.40005 0)
			(size 0 0)
			(layers "F.Cu" "F.Mask" "F.Paste")
			(net "P12V_PEX3_P1V25_VIN_N")
		)
	)
	(footprint ""
		(layer "F.Cu")
		(at 147.258532 -386.64261 90)
		(property "Reference" "C4104"
			(at 0 0 90)
			(layer "F.SilkS")
			(hide yes)
			(effects
				(font
					(size 1.27 1.27)
				)
			)
		)
		(property "Value" ""
			(at 0 0 90)
			(layer "F.Fab")
			(effects
				(font
					(size 1.27 1.27)
				)
			)
		)
		(duplicate_pad_numbers_are_jumpers no)
		(fp_line
			(start 0.7874 -0.4064)
			(end 0.7874 0.4064)
			(stroke
				(width 0.1524)
				(type default)
			)
			(layer "F.SilkS")
		)
		(fp_line
			(start -0.7874 -0.4064)
			(end 0.7874 -0.4064)
			(stroke
				(width 0.1524)
				(type default)
			)
			(layer "F.SilkS")
		)
		(fp_line
			(start 0.7874 0.4064)
			(end -0.7874 0.4064)
			(stroke
				(width 0.1524)
				(type default)
			)
			(layer "F.SilkS")
		)
		(fp_line
			(start -0.7874 0.4064)
			(end -0.7874 -0.4064)
			(stroke
				(width 0.1524)
				(type default)
			)
			(layer "F.SilkS")
		)
		(fp_line
			(start -0.12065 -0.305054)
			(end -0.12065 -0.2794)
			(stroke
				(width 0.1)
				(type default)
			)
			(layer "F.Fab")
		)
		(fp_line
			(start -0.67945 -0.305054)
			(end -0.12065 -0.305054)
			(stroke
				(width 0.1)
				(type default)
			)
			(layer "F.Fab")
		)
		(fp_line
			(start 0.67945 -0.3048)
			(end 0.67945 0.3048)
			(stroke
				(width 0.1)
				(type default)
			)
			(layer "F.Fab")
		)
		(fp_line
			(start 0.12065 -0.3048)
			(end 0.67945 -0.3048)
			(stroke
				(width 0.1)
				(type default)
			)
			(layer "F.Fab")
		)
		(fp_line
			(start 0.12065 -0.2794)
			(end 0.12065 -0.3048)
			(stroke
				(width 0.1)
				(type default)
			)
			(layer "F.Fab")
		)
		(fp_line
			(start -0.12065 -0.2794)
			(end 0.12065 -0.2794)
			(stroke
				(width 0.1)
				(type default)
			)
			(layer "F.Fab")
		)
		(fp_line
			(start 0.120396 0.2794)
			(end -0.12065 0.2794)
			(stroke
				(width 0.1)
				(type default)
			)
			(layer "F.Fab")
		)
		(fp_line
			(start -0.12065 0.2794)
			(end -0.12065 0.3048)
			(stroke
				(width 0.1)
				(type default)
			)
			(layer "F.Fab")
		)
		(fp_line
			(start 0.67945 0.3048)
			(end 0.120396 0.3048)
			(stroke
				(width 0.1)
				(type default)
			)
			(layer "F.Fab")
		)
		(fp_line
			(start 0.120396 0.3048)
			(end 0.120396 0.2794)
			(stroke
				(width 0.1)
				(type default)
			)
			(layer "F.Fab")
		)
		(fp_line
			(start -0.12065 0.3048)
			(end -0.67945 0.3048)
			(stroke
				(width 0.1)
				(type default)
			)
			(layer "F.Fab")
		)
		(fp_line
			(start -0.67945 0.3048)
			(end -0.67945 -0.305054)
			(stroke
				(width 0.1)
				(type default)
			)
			(layer "F.Fab")
		)
		(pad "1" smd circle
			(at -0.40005 0 90)
			(size 0 0)
			(layers "F.Cu" "F.Mask" "F.Paste")
			(net "GND")
		)
		(pad "2" smd circle
			(at 0.40005 0 90)
			(size 0 0)
			(layers "F.Cu" "F.Mask" "F.Paste")
			(net "SMB_GPU2_ALERT_N")
		)
	)
	(footprint ""
		(layer "F.Cu")
		(at 166.330884 -195.868798)
		(property "Reference" "R3404"
			(at 0 0 0)
			(layer "F.SilkS")
			(hide yes)
			(effects
				(font
					(size 1.27 1.27)
				)
			)
		)
		(property "Value" ""
			(at 0 0 0)
			(layer "F.Fab")
			(effects
				(font
					(size 1.27 1.27)
				)
			)
		)
		(duplicate_pad_numbers_are_jumpers no)
		(fp_line
			(start -0.7874 -0.4064)
			(end 0.7874 -0.4064)
			(stroke
				(width 0.1524)
				(type default)
			)
			(layer "F.SilkS")
		)
		(fp_line
			(start -0.7874 0.4064)
			(end -0.7874 -0.4064)
			(stroke
				(width 0.1524)
				(type default)
			)
			(layer "F.SilkS")
		)
		(fp_line
			(start 0.7874 -0.4064)
			(end 0.7874 0.4064)
			(stroke
				(width 0.1524)
				(type default)
			)
			(layer "F.SilkS")
		)
		(fp_line
			(start 0.7874 0.4064)
			(end -0.7874 0.4064)
			(stroke
				(width 0.1524)
				(type default)
			)
			(layer "F.SilkS")
		)
		(fp_line
			(start -0.67945 -0.305054)
			(end -0.12065 -0.305054)
			(stroke
				(width 0.1)
				(type default)
			)
			(layer "F.Fab")
		)
		(fp_line
			(start -0.67945 0.3048)
			(end -0.67945 -0.305054)
			(stroke
				(width 0.1)
				(type default)
			)
			(layer "F.Fab")
		)
		(fp_line
			(start -0.12065 -0.305054)
			(end -0.12065 -0.2794)
			(stroke
				(width 0.1)
				(type default)
			)
			(layer "F.Fab")
		)
		(fp_line
			(start -0.12065 -0.2794)
			(end 0.12065 -0.2794)
			(stroke
				(width 0.1)
				(type default)
			)
			(layer "F.Fab")
		)
		(fp_line
			(start -0.12065 0.2794)
			(end -0.12065 0.3048)
			(stroke
				(width 0.1)
				(type default)
			)
			(layer "F.Fab")
		)
		(fp_line
			(start -0.12065 0.3048)
			(end -0.67945 0.3048)
			(stroke
				(width 0.1)
				(type default)
			)
			(layer "F.Fab")
		)
		(fp_line
			(start 0.120396 0.2794)
			(end -0.12065 0.2794)
			(stroke
				(width 0.1)
				(type default)
			)
			(layer "F.Fab")
		)
		(fp_line
			(start 0.120396 0.3048)
			(end 0.120396 0.2794)
			(stroke
				(width 0.1)
				(type default)
			)
			(layer "F.Fab")
		)
		(fp_line
			(start 0.12065 -0.3048)
			(end 0.67945 -0.3048)
			(stroke
				(width 0.1)
				(type default)
			)
			(layer "F.Fab")
		)
		(fp_line
			(start 0.12065 -0.2794)
			(end 0.12065 -0.3048)
			(stroke
				(width 0.1)
				(type default)
			)
			(layer "F.Fab")
		)
		(fp_line
			(start 0.67945 -0.3048)
			(end 0.67945 0.3048)
			(stroke
				(width 0.1)
				(type default)
			)
			(layer "F.Fab")
		)
		(fp_line
			(start 0.67945 0.3048)
			(end 0.120396 0.3048)
			(stroke
				(width 0.1)
				(type default)
			)
			(layer "F.Fab")
		)
		(pad "1" smd circle
			(at -0.40005 0)
			(size 0 0)
			(layers "F.Cu" "F.Mask" "F.Paste")
			(net "SPI_BIC1_MOSI_LS01_R1")
		)
		(pad "2" smd circle
			(at 0.40005 0)
			(size 0 0)
			(layers "F.Cu" "F.Mask" "F.Paste")
			(net "SPI_BIC1_MOSI_LS01_R")
		)
	)
	(footprint ""
		(layer "F.Cu")
		(at 84.890864 -55.663846 90)
		(property "Reference" "PU60"
			(at -1.120394 2.791968 90)
			(unlocked yes)
			(layer "F.SilkS")
			(effects
				(font
					(size 0.7874 0.5842)
					(thickness 0.1524)
				)
				(justify left)
			)
		)
		(property "Value" ""
			(at 0 0 90)
			(layer "F.Fab")
			(effects
				(font
					(size 1.27 1.27)
				)
			)
		)
		(duplicate_pad_numbers_are_jumpers no)
		(fp_line
			(start 1.943608 -1.549908)
			(end 1.943608 1.549908)
			(stroke
				(width 0.1524)
				(type default)
			)
			(layer "F.SilkS")
		)
		(fp_line
			(start -1.943608 -1.549908)
			(end 1.943608 -1.549908)
			(stroke
				(width 0.1524)
				(type default)
			)
			(layer "F.SilkS")
		)
		(fp_line
			(start 1.943608 1.549908)
			(end -1.943608 1.549908)
			(stroke
				(width 0.1524)
				(type default)
			)
			(layer "F.SilkS")
		)
		(fp_line
			(start -1.943608 1.549908)
			(end -1.943608 -1.549908)
			(stroke
				(width 0.1524)
				(type default)
			)
			(layer "F.SilkS")
		)
		(fp_poly
			(pts
				(xy -2.019808 -1.549908) (xy -1.257808 -1.549908) (xy -1.257808 -1.880108) (xy -2.019808 -1.880108)
			)
			(stroke
				(width 0)
				(type default)
			)
			(fill yes)
			(layer "F.SilkS")
		)
		(fp_line
			(start 1.549908 -1.549908)
			(end 1.549908 1.549908)
			(stroke
				(width 0.1)
				(type default)
			)
			(layer "F.Fab")
		)
		(fp_line
			(start -1.549908 -1.549908)
			(end 1.549908 -1.549908)
			(stroke
				(width 0.1)
				(type default)
			)
			(layer "F.Fab")
		)
		(fp_line
			(start 1.549908 1.549908)
			(end -1.549908 1.549908)
			(stroke
				(width 0.1)
				(type default)
			)
			(layer "F.Fab")
		)
		(fp_line
			(start -1.549908 1.549908)
			(end -1.549908 -1.549908)
			(stroke
				(width 0.1)
				(type default)
			)
			(layer "F.Fab")
		)
		(fp_poly
			(pts
				(xy -2.019808 -1.549908) (xy -1.257808 -1.549908) (xy -1.257808 -1.880108) (xy -2.019808 -1.880108)
			)
			(stroke
				(width 0)
				(type default)
			)
			(fill yes)
			(layer "F.Fab")
		)
		(pad "1" smd rect
			(at -1.500124 -1.249934)
			(size 0.2794 0.6096)
			(layers "F.Cu" "F.Mask" "F.Paste")
			(net "P3V3_SSD3")
		)
		(pad "2" smd rect
			(at -1.500124 -0.750062)
			(size 0.2794 0.6096)
			(layers "F.Cu" "F.Mask" "F.Paste")
			(net "P3V3_SSD3")
		)
		(pad "3" smd rect
			(at -1.500124 -0.249936)
			(size 0.2794 0.6096)
			(layers "F.Cu" "F.Mask" "F.Paste")
			(net "P3V3_SSD3")
		)
		(pad "4" smd rect
			(at -1.500124 0.249936)
			(size 0.2794 0.6096)
			(layers "F.Cu" "F.Mask" "F.Paste")
			(net "P3V3_SSD3")
		)
		(pad "5" smd rect
			(at -1.500124 0.750062)
			(size 0.2794 0.6096)
			(layers "F.Cu" "F.Mask" "F.Paste")
			(net "P3V3_SSD3")
		)
		(pad "6" smd rect
			(at -1.500124 1.249934)
			(size 0.2794 0.6096)
			(layers "F.Cu" "F.Mask" "F.Paste")
			(net "GND")
		)
		(pad "7" smd rect
			(at 1.500124 1.249934)
			(size 0.2794 0.6096)
			(layers "F.Cu" "F.Mask" "F.Paste")
			(net "P3V3_SSD3_SS")
		)
		(pad "8" smd rect
			(at 1.500124 0.750062)
			(size 0.2794 0.6096)
			(layers "F.Cu" "F.Mask" "F.Paste")
			(net "PWRGD_P3V3_SSD3")
		)
		(pad "9" smd rect
			(at 1.500124 0.249936)
			(size 0.2794 0.6096)
			(layers "F.Cu" "F.Mask" "F.Paste")
			(net "P3V3_SSD3_OCP")
		)
		(pad "10" smd rect
			(at 1.500124 -0.249936)
			(size 0.2794 0.6096)
			(layers "F.Cu" "F.Mask" "F.Paste")
			(net "P5V_AUX")
		)
		(pad "11" smd rect
			(at 1.500124 -0.750062)
			(size 0.2794 0.6096)
			(layers "F.Cu" "F.Mask" "F.Paste")
			(net "SSD3_AUX_P3V3_EN_R")
		)
		(pad "12" smd rect
			(at 1.500124 -1.249934)
			(size 0.2794 0.6096)
			(layers "F.Cu" "F.Mask" "F.Paste")
			(net "P3V3_AUX")
		)
		(pad "13" smd rect
			(at 0 0 90)
			(size 1.9812 2.7178)
			(layers "F.Cu" "F.Mask" "F.Paste")
			(net "P3V3_AUX")
		)
		(zone
			(layer "F.Cu")
			(hatch none 0.5)
			(connect_pads
				(clearance 0)
			)
			(min_thickness 0.25)
			(keepout
				(tracks not_allowed)
				(vias allowed)
				(pads allowed)
				(copperpour not_allowed)
				(footprints allowed)
			)
			(placement
				(enabled no)
				(sheetname "")
			)
			(fill
				(thermal_gap 0.5)
				(thermal_bridge_width 0.5)
				(island_removal_mode 0)
			)
			(polygon
				(pts
					(xy 83.341464 -56.806846) (xy 83.468464 -56.806846) (xy 86.440264 -56.806846) (xy 86.440772 -56.806846)
					(xy 86.440772 -54.520846) (xy 86.440264 -54.520846) (xy 86.313264 -54.520846) (xy 84.890864 -54.520846)
					(xy 84.890864 -54.622446) (xy 86.313264 -54.622446) (xy 86.313264 -56.705246) (xy 83.468464 -56.705246)
					(xy 83.468464 -54.622446) (xy 84.865464 -54.622446) (xy 84.865464 -54.520846) (xy 83.468464 -54.520846)
					(xy 83.341464 -54.520846) (xy 83.340956 -54.520846) (xy 83.340956 -56.806846)
				)
			)
		)
	)
	(footprint ""
		(layer "F.Cu")
		(at 396.185644 -27.092148 -90)
		(property "Reference" "R5753"
			(at 0 0 270)
			(layer "F.SilkS")
			(hide yes)
			(effects
				(font
					(size 1.27 1.27)
				)
			)
		)
		(property "Value" ""
			(at 0 0 270)
			(layer "F.Fab")
			(effects
				(font
					(size 1.27 1.27)
				)
			)
		)
		(duplicate_pad_numbers_are_jumpers no)
		(fp_line
			(start -0.7874 0.4064)
			(end -0.7874 -0.4064)
			(stroke
				(width 0.1524)
				(type default)
			)
			(layer "F.SilkS")
		)
		(fp_line
			(start 0.7874 0.4064)
			(end -0.7874 0.4064)
			(stroke
				(width 0.1524)
				(type default)
			)
			(layer "F.SilkS")
		)
		(fp_line
			(start -0.7874 -0.4064)
			(end 0.7874 -0.4064)
			(stroke
				(width 0.1524)
				(type default)
			)
			(layer "F.SilkS")
		)
		(fp_line
			(start 0.7874 -0.4064)
			(end 0.7874 0.4064)
			(stroke
				(width 0.1524)
				(type default)
			)
			(layer "F.SilkS")
		)
		(fp_line
			(start -0.67945 0.3048)
			(end -0.67945 -0.305054)
			(stroke
				(width 0.1)
				(type default)
			)
			(layer "F.Fab")
		)
		(fp_line
			(start -0.12065 0.3048)
			(end -0.67945 0.3048)
			(stroke
				(width 0.1)
				(type default)
			)
			(layer "F.Fab")
		)
		(fp_line
			(start 0.120396 0.3048)
			(end 0.120396 0.2794)
			(stroke
				(width 0.1)
				(type default)
			)
			(layer "F.Fab")
		)
		(fp_line
			(start 0.67945 0.3048)
			(end 0.120396 0.3048)
			(stroke
				(width 0.1)
				(type default)
			)
			(layer "F.Fab")
		)
		(fp_line
			(start -0.12065 0.2794)
			(end -0.12065 0.3048)
			(stroke
				(width 0.1)
				(type default)
			)
			(layer "F.Fab")
		)
		(fp_line
			(start 0.120396 0.2794)
			(end -0.12065 0.2794)
			(stroke
				(width 0.1)
				(type default)
			)
			(layer "F.Fab")
		)
		(fp_line
			(start -0.12065 -0.2794)
			(end 0.12065 -0.2794)
			(stroke
				(width 0.1)
				(type default)
			)
			(layer "F.Fab")
		)
		(fp_line
			(start 0.12065 -0.2794)
			(end 0.12065 -0.3048)
			(stroke
				(width 0.1)
				(type default)
			)
			(layer "F.Fab")
		)
		(fp_line
			(start 0.12065 -0.3048)
			(end 0.67945 -0.3048)
			(stroke
				(width 0.1)
				(type default)
			)
			(layer "F.Fab")
		)
		(fp_line
			(start 0.67945 -0.3048)
			(end 0.67945 0.3048)
			(stroke
				(width 0.1)
				(type default)
			)
			(layer "F.Fab")
		)
		(fp_line
			(start -0.67945 -0.305054)
			(end -0.12065 -0.305054)
			(stroke
				(width 0.1)
				(type default)
			)
			(layer "F.Fab")
		)
		(fp_line
			(start -0.12065 -0.305054)
			(end -0.12065 -0.2794)
			(stroke
				(width 0.1)
				(type default)
			)
			(layer "F.Fab")
		)
		(pad "1" smd circle
			(at -0.40005 0 270)
			(size 0 0)
			(layers "F.Cu" "F.Mask" "F.Paste")
			(net "P3V3_SSD13")
		)
		(pad "2" smd circle
			(at 0.40005 0 270)
			(size 0 0)
			(layers "F.Cu" "F.Mask" "F.Paste")
			(net "SSD13_LED_ISO_N")
		)
	)
	(footprint ""
		(layer "F.Cu")
		(at 380.054358 -48.21809)
		(property "Reference" "PD71"
			(at -3.423158 2.24536 0)
			(unlocked yes)
			(layer "F.SilkS")
			(effects
				(font
					(size 0.7874 0.5842)
					(thickness 0.1524)
				)
				(justify left)
			)
		)
		(property "Value" ""
			(at 0 0 0)
			(layer "F.Fab")
			(effects
				(font
					(size 1.27 1.27)
				)
			)
		)
		(duplicate_pad_numbers_are_jumpers no)
		(fp_line
			(start -3.400044 -1.459992)
			(end 4.107942 -1.459992)
			(stroke
				(width 0.1524)
				(type default)
			)
			(layer "F.SilkS")
		)
		(fp_line
			(start -3.400044 1.459992)
			(end -3.400044 -1.459992)
			(stroke
				(width 0.1524)
				(type default)
			)
			(layer "F.SilkS")
		)
		(fp_line
			(start 4.107942 -1.459992)
			(end 4.107942 1.459992)
			(stroke
				(width 0.1524)
				(type default)
			)
			(layer "F.SilkS")
		)
		(fp_line
			(start 4.107942 1.459992)
			(end -3.400044 1.459992)
			(stroke
				(width 0.1524)
				(type default)
			)
			(layer "F.SilkS")
		)
		(fp_poly
			(pts
				(xy 4.107942 -1.459992) (xy 4.107942 1.459992) (xy 3.308096 1.459992) (xy 3.308096 -1.459992)
			)
			(stroke
				(width 0)
				(type default)
			)
			(fill yes)
			(layer "F.SilkS")
		)
		(fp_line
			(start -2.29997 -1.459992)
			(end 2.29997 -1.459992)
			(stroke
				(width 0.1)
				(type default)
			)
			(layer "F.Fab")
		)
		(fp_line
			(start -2.29997 1.459992)
			(end -2.29997 -1.459992)
			(stroke
				(width 0.1)
				(type default)
			)
			(layer "F.Fab")
		)
		(fp_line
			(start 2.29997 -1.459992)
			(end 2.29997 1.459992)
			(stroke
				(width 0.1)
				(type default)
			)
			(layer "F.Fab")
		)
		(fp_line
			(start 2.29997 1.459992)
			(end -2.29997 1.459992)
			(stroke
				(width 0.1)
				(type default)
			)
			(layer "F.Fab")
		)
		(fp_text user "+"
			(at -4.7752 -0.12065 0)
			(unlocked yes)
			(layer "F.SilkS")
			(effects
				(font
					(size 1.905 1.4224)
					(thickness 0.1524)
				)
				(justify left)
			)
		)
		(fp_text user "-"
			(at 5.4102 0.29845 180)
			(unlocked yes)
			(layer "F.SilkS")
			(effects
				(font
					(size 1.905 1.4224)
					(thickness 0.1524)
				)
				(justify left)
			)
		)
		(fp_text user "+"
			(at -4.7752 -0.12065 0)
			(unlocked yes)
			(layer "F.Fab")
			(effects
				(font
					(size 1.905 1.4224)
					(thickness 0.1524)
				)
				(justify left)
			)
		)
		(fp_text user "-"
			(at 5.4102 0.29845 180)
			(unlocked yes)
			(layer "F.Fab")
			(effects
				(font
					(size 1.905 1.4224)
					(thickness 0.1524)
				)
				(justify left)
			)
		)
		(pad "A" smd rect
			(at -1.999996 0 90)
			(size 1.7018 2.5146)
			(layers "F.Cu" "F.Mask" "F.Paste")
			(net "GND")
		)
		(pad "C" smd rect
			(at 1.999996 0 90)
			(size 1.7018 2.5146)
			(layers "F.Cu" "F.Mask" "F.Paste")
			(net "P3V3_SSD13")
		)
	)
	(footprint ""
		(layer "F.Cu")
		(at 437.250332 -356.244906 90)
		(property "Reference" "C2467"
			(at 0 0 90)
			(layer "F.SilkS")
			(hide yes)
			(effects
				(font
					(size 1.27 1.27)
				)
			)
		)
		(property "Value" ""
			(at 0 0 90)
			(layer "F.Fab")
			(effects
				(font
					(size 1.27 1.27)
				)
			)
		)
		(duplicate_pad_numbers_are_jumpers no)
		(fp_line
			(start 0.299974 -0.150114)
			(end 0.299974 0.150114)
			(stroke
				(width 0.1)
				(type default)
			)
			(layer "F.Fab")
		)
		(fp_line
			(start -0.299974 -0.150114)
			(end 0.299974 -0.150114)
			(stroke
				(width 0.1)
				(type default)
			)
			(layer "F.Fab")
		)
		(fp_line
			(start 0.299974 0.150114)
			(end -0.299974 0.150114)
			(stroke
				(width 0.1)
				(type default)
			)
			(layer "F.Fab")
		)
		(fp_line
			(start -0.299974 0.150114)
			(end -0.299974 -0.150114)
			(stroke
				(width 0.1)
				(type default)
			)
			(layer "F.Fab")
		)
		(pad "1" smd rect
			(at -0.2667 0 90)
			(size 0.3048 0.381)
			(layers "F.Cu" "F.Mask" "F.Paste")
			(net "P5E_PEX3_STN4_TX_DP<65>")
		)
		(pad "2" smd rect
			(at 0.2667 0 90)
			(size 0.3048 0.381)
			(layers "F.Cu" "F.Mask" "F.Paste")
			(net "P5E_PEX3_STN4_TX_C_DP<65>")
		)
	)
	(footprint ""
		(layer "F.Cu")
		(at 362.339382 -239.62106)
		(property "Reference" "R6410"
			(at 0 0 0)
			(layer "F.SilkS")
			(hide yes)
			(effects
				(font
					(size 1.27 1.27)
				)
			)
		)
		(property "Value" ""
			(at 0 0 0)
			(layer "F.Fab")
			(effects
				(font
					(size 1.27 1.27)
				)
			)
		)
		(duplicate_pad_numbers_are_jumpers no)
		(fp_line
			(start -0.7874 -0.4064)
			(end 0.7874 -0.4064)
			(stroke
				(width 0.1524)
				(type default)
			)
			(layer "F.SilkS")
		)
		(fp_line
			(start -0.7874 0.4064)
			(end -0.7874 -0.4064)
			(stroke
				(width 0.1524)
				(type default)
			)
			(layer "F.SilkS")
		)
		(fp_line
			(start 0.7874 -0.4064)
			(end 0.7874 0.4064)
			(stroke
				(width 0.1524)
				(type default)
			)
			(layer "F.SilkS")
		)
		(fp_line
			(start 0.7874 0.4064)
			(end -0.7874 0.4064)
			(stroke
				(width 0.1524)
				(type default)
			)
			(layer "F.SilkS")
		)
		(fp_line
			(start -0.67945 -0.305054)
			(end -0.12065 -0.305054)
			(stroke
				(width 0.1)
				(type default)
			)
			(layer "F.Fab")
		)
		(fp_line
			(start -0.67945 0.3048)
			(end -0.67945 -0.305054)
			(stroke
				(width 0.1)
				(type default)
			)
			(layer "F.Fab")
		)
		(fp_line
			(start -0.12065 -0.305054)
			(end -0.12065 -0.2794)
			(stroke
				(width 0.1)
				(type default)
			)
			(layer "F.Fab")
		)
		(fp_line
			(start -0.12065 -0.2794)
			(end 0.12065 -0.2794)
			(stroke
				(width 0.1)
				(type default)
			)
			(layer "F.Fab")
		)
		(fp_line
			(start -0.12065 0.2794)
			(end -0.12065 0.3048)
			(stroke
				(width 0.1)
				(type default)
			)
			(layer "F.Fab")
		)
		(fp_line
			(start -0.12065 0.3048)
			(end -0.67945 0.3048)
			(stroke
				(width 0.1)
				(type default)
			)
			(layer "F.Fab")
		)
		(fp_line
			(start 0.120396 0.2794)
			(end -0.12065 0.2794)
			(stroke
				(width 0.1)
				(type default)
			)
			(layer "F.Fab")
		)
		(fp_line
			(start 0.120396 0.3048)
			(end 0.120396 0.2794)
			(stroke
				(width 0.1)
				(type default)
			)
			(layer "F.Fab")
		)
		(fp_line
			(start 0.12065 -0.3048)
			(end 0.67945 -0.3048)
			(stroke
				(width 0.1)
				(type default)
			)
			(layer "F.Fab")
		)
		(fp_line
			(start 0.12065 -0.2794)
			(end 0.12065 -0.3048)
			(stroke
				(width 0.1)
				(type default)
			)
			(layer "F.Fab")
		)
		(fp_line
			(start 0.67945 -0.3048)
			(end 0.67945 0.3048)
			(stroke
				(width 0.1)
				(type default)
			)
			(layer "F.Fab")
		)
		(fp_line
			(start 0.67945 0.3048)
			(end 0.120396 0.3048)
			(stroke
				(width 0.1)
				(type default)
			)
			(layer "F.Fab")
		)
		(pad "1" smd circle
			(at -0.40005 0)
			(size 0 0)
			(layers "F.Cu" "F.Mask" "F.Paste")
			(net "GND")
		)
		(pad "2" smd circle
			(at 0.40005 0)
			(size 0 0)
			(layers "F.Cu" "F.Mask" "F.Paste")
			(net "PWRGD_P3V3_AUX_BUF")
		)
	)
	(footprint ""
		(layer "F.Cu")
		(at 337.349084 -343.952322 90)
		(property "Reference" "C573"
			(at 0 0 90)
			(layer "F.SilkS")
			(hide yes)
			(effects
				(font
					(size 1.27 1.27)
				)
			)
		)
		(property "Value" ""
			(at 0 0 90)
			(layer "F.Fab")
			(effects
				(font
					(size 1.27 1.27)
				)
			)
		)
		(duplicate_pad_numbers_are_jumpers no)
		(fp_line
			(start 0.299974 -0.150114)
			(end 0.299974 0.150114)
			(stroke
				(width 0.1)
				(type default)
			)
			(layer "F.Fab")
		)
		(fp_line
			(start -0.299974 -0.150114)
			(end 0.299974 -0.150114)
			(stroke
				(width 0.1)
				(type default)
			)
			(layer "F.Fab")
		)
		(fp_line
			(start 0.299974 0.150114)
			(end -0.299974 0.150114)
			(stroke
				(width 0.1)
				(type default)
			)
			(layer "F.Fab")
		)
		(fp_line
			(start -0.299974 0.150114)
			(end -0.299974 -0.150114)
			(stroke
				(width 0.1)
				(type default)
			)
			(layer "F.Fab")
		)
		(pad "1" smd rect
			(at -0.2667 0 90)
			(size 0.3048 0.381)
			(layers "F.Cu" "F.Mask" "F.Paste")
			(net "P5E_PEX2_STN6_TX_DP<100>")
		)
		(pad "2" smd rect
			(at 0.2667 0 90)
			(size 0.3048 0.381)
			(layers "F.Cu" "F.Mask" "F.Paste")
			(net "P5E_PEX2_STN6_TX_C_DP<100>")
		)
	)
	(footprint ""
		(layer "F.Cu")
		(at 142.368016 -51.019456)
		(property "Reference" "PC363"
			(at 0 0 0)
			(layer "F.SilkS")
			(hide yes)
			(effects
				(font
					(size 1.27 1.27)
				)
			)
		)
		(property "Value" ""
			(at 0 0 0)
			(layer "F.Fab")
			(effects
				(font
					(size 1.27 1.27)
				)
			)
		)
		(duplicate_pad_numbers_are_jumpers no)
		(fp_line
			(start -0.7874 -0.4064)
			(end 0.7874 -0.4064)
			(stroke
				(width 0.1524)
				(type default)
			)
			(layer "F.SilkS")
		)
		(fp_line
			(start -0.7874 0.4064)
			(end -0.7874 -0.4064)
			(stroke
				(width 0.1524)
				(type default)
			)
			(layer "F.SilkS")
		)
		(fp_line
			(start 0.7874 -0.4064)
			(end 0.7874 0.4064)
			(stroke
				(width 0.1524)
				(type default)
			)
			(layer "F.SilkS")
		)
		(fp_line
			(start 0.7874 0.4064)
			(end -0.7874 0.4064)
			(stroke
				(width 0.1524)
				(type default)
			)
			(layer "F.SilkS")
		)
		(fp_line
			(start -0.6858 -0.3048)
			(end -0.1016 -0.3048)
			(stroke
				(width 0.1)
				(type default)
			)
			(layer "F.Fab")
		)
		(fp_line
			(start -0.6858 0.3048)
			(end -0.6858 -0.3048)
			(stroke
				(width 0.1)
				(type default)
			)
			(layer "F.Fab")
		)
		(fp_line
			(start -0.1016 -0.3048)
			(end -0.1016 -0.2794)
			(stroke
				(width 0.1)
				(type default)
			)
			(layer "F.Fab")
		)
		(fp_line
			(start -0.1016 -0.2794)
			(end 0.1016 -0.2794)
			(stroke
				(width 0.1)
				(type default)
			)
			(layer "F.Fab")
		)
		(fp_line
			(start -0.1016 0.2794)
			(end -0.1016 0.3048)
			(stroke
				(width 0.1)
				(type default)
			)
			(layer "F.Fab")
		)
		(fp_line
			(start -0.1016 0.3048)
			(end -0.6858 0.3048)
			(stroke
				(width 0.1)
				(type default)
			)
			(layer "F.Fab")
		)
		(fp_line
			(start 0.1016 -0.3048)
			(end 0.6858 -0.3048)
			(stroke
				(width 0.1)
				(type default)
			)
			(layer "F.Fab")
		)
		(fp_line
			(start 0.1016 -0.2794)
			(end 0.1016 -0.3048)
			(stroke
				(width 0.1)
				(type default)
			)
			(layer "F.Fab")
		)
		(fp_line
			(start 0.1016 0.2794)
			(end -0.1016 0.2794)
			(stroke
				(width 0.1)
				(type default)
			)
			(layer "F.Fab")
		)
		(fp_line
			(start 0.1016 0.3048)
			(end 0.1016 0.2794)
			(stroke
				(width 0.1)
				(type default)
			)
			(layer "F.Fab")
		)
		(fp_line
			(start 0.6858 -0.3048)
			(end 0.6858 0.3048)
			(stroke
				(width 0.1)
				(type default)
			)
			(layer "F.Fab")
		)
		(fp_line
			(start 0.6858 0.3048)
			(end 0.1016 0.3048)
			(stroke
				(width 0.1)
				(type default)
			)
			(layer "F.Fab")
		)
		(pad "1" smd rect
			(at -0.40005 0 180)
			(size 0.4572 0.508)
			(layers "F.Cu" "F.Mask" "F.Paste")
			(net "P12V_SSD4_SS")
		)
		(pad "2" smd rect
			(at 0.40005 0 180)
			(size 0.4572 0.508)
			(layers "F.Cu" "F.Mask" "F.Paste")
			(net "GND")
		)
	)
	(footprint ""
		(layer "F.Cu")
		(at 77.353922 -83.932268 90)
		(property "Reference" "C872"
			(at 0 0 90)
			(layer "F.SilkS")
			(hide yes)
			(effects
				(font
					(size 1.27 1.27)
				)
			)
		)
		(property "Value" ""
			(at 0 0 90)
			(layer "F.Fab")
			(effects
				(font
					(size 1.27 1.27)
				)
			)
		)
		(duplicate_pad_numbers_are_jumpers no)
		(fp_line
			(start 0.7874 -0.4064)
			(end 0.7874 0.4064)
			(stroke
				(width 0.1524)
				(type default)
			)
			(layer "F.SilkS")
		)
		(fp_line
			(start -0.7874 -0.4064)
			(end 0.7874 -0.4064)
			(stroke
				(width 0.1524)
				(type default)
			)
			(layer "F.SilkS")
		)
		(fp_line
			(start 0.7874 0.4064)
			(end -0.7874 0.4064)
			(stroke
				(width 0.1524)
				(type default)
			)
			(layer "F.SilkS")
		)
		(fp_line
			(start -0.7874 0.4064)
			(end -0.7874 -0.4064)
			(stroke
				(width 0.1524)
				(type default)
			)
			(layer "F.SilkS")
		)
		(fp_line
			(start -0.12065 -0.305054)
			(end -0.12065 -0.2794)
			(stroke
				(width 0.1)
				(type default)
			)
			(layer "F.Fab")
		)
		(fp_line
			(start -0.67945 -0.305054)
			(end -0.12065 -0.305054)
			(stroke
				(width 0.1)
				(type default)
			)
			(layer "F.Fab")
		)
		(fp_line
			(start 0.67945 -0.3048)
			(end 0.67945 0.3048)
			(stroke
				(width 0.1)
				(type default)
			)
			(layer "F.Fab")
		)
		(fp_line
			(start 0.12065 -0.3048)
			(end 0.67945 -0.3048)
			(stroke
				(width 0.1)
				(type default)
			)
			(layer "F.Fab")
		)
		(fp_line
			(start 0.12065 -0.2794)
			(end 0.12065 -0.3048)
			(stroke
				(width 0.1)
				(type default)
			)
			(layer "F.Fab")
		)
		(fp_line
			(start -0.12065 -0.2794)
			(end 0.12065 -0.2794)
			(stroke
				(width 0.1)
				(type default)
			)
			(layer "F.Fab")
		)
		(fp_line
			(start 0.120396 0.2794)
			(end -0.12065 0.2794)
			(stroke
				(width 0.1)
				(type default)
			)
			(layer "F.Fab")
		)
		(fp_line
			(start -0.12065 0.2794)
			(end -0.12065 0.3048)
			(stroke
				(width 0.1)
				(type default)
			)
			(layer "F.Fab")
		)
		(fp_line
			(start 0.67945 0.3048)
			(end 0.120396 0.3048)
			(stroke
				(width 0.1)
				(type default)
			)
			(layer "F.Fab")
		)
		(fp_line
			(start 0.120396 0.3048)
			(end 0.120396 0.2794)
			(stroke
				(width 0.1)
				(type default)
			)
			(layer "F.Fab")
		)
		(fp_line
			(start -0.12065 0.3048)
			(end -0.67945 0.3048)
			(stroke
				(width 0.1)
				(type default)
			)
			(layer "F.Fab")
		)
		(fp_line
			(start -0.67945 0.3048)
			(end -0.67945 -0.305054)
			(stroke
				(width 0.1)
				(type default)
			)
			(layer "F.Fab")
		)
		(pad "1" smd circle
			(at -0.40005 0 90)
			(size 0 0)
			(layers "F.Cu" "F.Mask" "F.Paste")
			(net "P3V3_AUX")
		)
		(pad "2" smd circle
			(at 0.40005 0 90)
			(size 0 0)
			(layers "F.Cu" "F.Mask" "F.Paste")
			(net "GND")
		)
	)
	(footprint ""
		(layer "F.Cu")
		(at 84.023962 -350.098614 90)
		(property "Reference" "C150"
			(at 0 0 90)
			(layer "F.SilkS")
			(hide yes)
			(effects
				(font
					(size 1.27 1.27)
				)
			)
		)
		(property "Value" ""
			(at 0 0 90)
			(layer "F.Fab")
			(effects
				(font
					(size 1.27 1.27)
				)
			)
		)
		(duplicate_pad_numbers_are_jumpers no)
		(fp_line
			(start 0.299974 -0.150114)
			(end 0.299974 0.150114)
			(stroke
				(width 0.1)
				(type default)
			)
			(layer "F.Fab")
		)
		(fp_line
			(start -0.299974 -0.150114)
			(end 0.299974 -0.150114)
			(stroke
				(width 0.1)
				(type default)
			)
			(layer "F.Fab")
		)
		(fp_line
			(start 0.299974 0.150114)
			(end -0.299974 0.150114)
			(stroke
				(width 0.1)
				(type default)
			)
			(layer "F.Fab")
		)
		(fp_line
			(start -0.299974 0.150114)
			(end -0.299974 -0.150114)
			(stroke
				(width 0.1)
				(type default)
			)
			(layer "F.Fab")
		)
		(pad "1" smd rect
			(at -0.2667 0 90)
			(size 0.3048 0.381)
			(layers "F.Cu" "F.Mask" "F.Paste")
			(net "P5E_PEX0_STN6_TX_DN<101>")
		)
		(pad "2" smd rect
			(at 0.2667 0 90)
			(size 0.3048 0.381)
			(layers "F.Cu" "F.Mask" "F.Paste")
			(net "P5E_PEX0_STN6_TX_C_DN<101>")
		)
	)
	(footprint ""
		(layer "F.Cu")
		(at 33.486344 -250.070874 -90)
		(property "Reference" "R1119"
			(at 0 0 270)
			(layer "F.SilkS")
			(hide yes)
			(effects
				(font
					(size 1.27 1.27)
				)
			)
		)
		(property "Value" ""
			(at 0 0 270)
			(layer "F.Fab")
			(effects
				(font
					(size 1.27 1.27)
				)
			)
		)
		(duplicate_pad_numbers_are_jumpers no)
		(fp_line
			(start -0.7874 0.4064)
			(end -0.7874 -0.4064)
			(stroke
				(width 0.1524)
				(type default)
			)
			(layer "F.SilkS")
		)
		(fp_line
			(start 0.7874 0.4064)
			(end -0.7874 0.4064)
			(stroke
				(width 0.1524)
				(type default)
			)
			(layer "F.SilkS")
		)
		(fp_line
			(start -0.7874 -0.4064)
			(end 0.7874 -0.4064)
			(stroke
				(width 0.1524)
				(type default)
			)
			(layer "F.SilkS")
		)
		(fp_line
			(start 0.7874 -0.4064)
			(end 0.7874 0.4064)
			(stroke
				(width 0.1524)
				(type default)
			)
			(layer "F.SilkS")
		)
		(fp_line
			(start -0.67945 0.3048)
			(end -0.67945 -0.305054)
			(stroke
				(width 0.1)
				(type default)
			)
			(layer "F.Fab")
		)
		(fp_line
			(start -0.12065 0.3048)
			(end -0.67945 0.3048)
			(stroke
				(width 0.1)
				(type default)
			)
			(layer "F.Fab")
		)
		(fp_line
			(start 0.120396 0.3048)
			(end 0.120396 0.2794)
			(stroke
				(width 0.1)
				(type default)
			)
			(layer "F.Fab")
		)
		(fp_line
			(start 0.67945 0.3048)
			(end 0.120396 0.3048)
			(stroke
				(width 0.1)
				(type default)
			)
			(layer "F.Fab")
		)
		(fp_line
			(start -0.12065 0.2794)
			(end -0.12065 0.3048)
			(stroke
				(width 0.1)
				(type default)
			)
			(layer "F.Fab")
		)
		(fp_line
			(start 0.120396 0.2794)
			(end -0.12065 0.2794)
			(stroke
				(width 0.1)
				(type default)
			)
			(layer "F.Fab")
		)
		(fp_line
			(start -0.12065 -0.2794)
			(end 0.12065 -0.2794)
			(stroke
				(width 0.1)
				(type default)
			)
			(layer "F.Fab")
		)
		(fp_line
			(start 0.12065 -0.2794)
			(end 0.12065 -0.3048)
			(stroke
				(width 0.1)
				(type default)
			)
			(layer "F.Fab")
		)
		(fp_line
			(start 0.12065 -0.3048)
			(end 0.67945 -0.3048)
			(stroke
				(width 0.1)
				(type default)
			)
			(layer "F.Fab")
		)
		(fp_line
			(start 0.67945 -0.3048)
			(end 0.67945 0.3048)
			(stroke
				(width 0.1)
				(type default)
			)
			(layer "F.Fab")
		)
		(fp_line
			(start -0.67945 -0.305054)
			(end -0.12065 -0.305054)
			(stroke
				(width 0.1)
				(type default)
			)
			(layer "F.Fab")
		)
		(fp_line
			(start -0.12065 -0.305054)
			(end -0.12065 -0.2794)
			(stroke
				(width 0.1)
				(type default)
			)
			(layer "F.Fab")
		)
		(pad "1" smd circle
			(at -0.40005 0 270)
			(size 0 0)
			(layers "F.Cu" "F.Mask" "F.Paste")
			(net "PEX0_DBG_MODE2")
		)
		(pad "2" smd circle
			(at 0.40005 0 270)
			(size 0 0)
			(layers "F.Cu" "F.Mask" "F.Paste")
			(net "P1V8_PEX")
		)
	)
	(footprint ""
		(layer "F.Cu")
		(at 246.85371 -162.003994 -90)
		(property "Reference" "R954"
			(at 0 0 270)
			(layer "F.SilkS")
			(hide yes)
			(effects
				(font
					(size 1.27 1.27)
				)
			)
		)
		(property "Value" ""
			(at 0 0 270)
			(layer "F.Fab")
			(effects
				(font
					(size 1.27 1.27)
				)
			)
		)
		(duplicate_pad_numbers_are_jumpers no)
		(fp_line
			(start -0.7874 0.4064)
			(end -0.7874 -0.4064)
			(stroke
				(width 0.1524)
				(type default)
			)
			(layer "F.SilkS")
		)
		(fp_line
			(start 0.7874 0.4064)
			(end -0.7874 0.4064)
			(stroke
				(width 0.1524)
				(type default)
			)
			(layer "F.SilkS")
		)
		(fp_line
			(start -0.7874 -0.4064)
			(end 0.7874 -0.4064)
			(stroke
				(width 0.1524)
				(type default)
			)
			(layer "F.SilkS")
		)
		(fp_line
			(start 0.7874 -0.4064)
			(end 0.7874 0.4064)
			(stroke
				(width 0.1524)
				(type default)
			)
			(layer "F.SilkS")
		)
		(fp_line
			(start -0.67945 0.3048)
			(end -0.67945 -0.305054)
			(stroke
				(width 0.1)
				(type default)
			)
			(layer "F.Fab")
		)
		(fp_line
			(start -0.12065 0.3048)
			(end -0.67945 0.3048)
			(stroke
				(width 0.1)
				(type default)
			)
			(layer "F.Fab")
		)
		(fp_line
			(start 0.120396 0.3048)
			(end 0.120396 0.2794)
			(stroke
				(width 0.1)
				(type default)
			)
			(layer "F.Fab")
		)
		(fp_line
			(start 0.67945 0.3048)
			(end 0.120396 0.3048)
			(stroke
				(width 0.1)
				(type default)
			)
			(layer "F.Fab")
		)
		(fp_line
			(start -0.12065 0.2794)
			(end -0.12065 0.3048)
			(stroke
				(width 0.1)
				(type default)
			)
			(layer "F.Fab")
		)
		(fp_line
			(start 0.120396 0.2794)
			(end -0.12065 0.2794)
			(stroke
				(width 0.1)
				(type default)
			)
			(layer "F.Fab")
		)
		(fp_line
			(start -0.12065 -0.2794)
			(end 0.12065 -0.2794)
			(stroke
				(width 0.1)
				(type default)
			)
			(layer "F.Fab")
		)
		(fp_line
			(start 0.12065 -0.2794)
			(end 0.12065 -0.3048)
			(stroke
				(width 0.1)
				(type default)
			)
			(layer "F.Fab")
		)
		(fp_line
			(start 0.12065 -0.3048)
			(end 0.67945 -0.3048)
			(stroke
				(width 0.1)
				(type default)
			)
			(layer "F.Fab")
		)
		(fp_line
			(start 0.67945 -0.3048)
			(end 0.67945 0.3048)
			(stroke
				(width 0.1)
				(type default)
			)
			(layer "F.Fab")
		)
		(fp_line
			(start -0.67945 -0.305054)
			(end -0.12065 -0.305054)
			(stroke
				(width 0.1)
				(type default)
			)
			(layer "F.Fab")
		)
		(fp_line
			(start -0.12065 -0.305054)
			(end -0.12065 -0.2794)
			(stroke
				(width 0.1)
				(type default)
			)
			(layer "F.Fab")
		)
		(pad "1" smd circle
			(at -0.40005 0 270)
			(size 0 0)
			(layers "F.Cu" "F.Mask" "F.Paste")
			(net "GND")
		)
		(pad "2" smd circle
			(at 0.40005 0 270)
			(size 0 0)
			(layers "F.Cu" "F.Mask" "F.Paste")
			(net "P12V_NIC4_CO_EN")
		)
	)
	(footprint ""
		(layer "F.Cu")
		(at 72.43445 -33.631886 180)
		(property "Reference" "C82"
			(at 0 0 180)
			(layer "F.SilkS")
			(hide yes)
			(effects
				(font
					(size 1.27 1.27)
				)
			)
		)
		(property "Value" ""
			(at 0 0 180)
			(layer "F.Fab")
			(effects
				(font
					(size 1.27 1.27)
				)
			)
		)
		(duplicate_pad_numbers_are_jumpers no)
		(fp_line
			(start 0.299974 0.150114)
			(end -0.299974 0.150114)
			(stroke
				(width 0.1)
				(type default)
			)
			(layer "F.Fab")
		)
		(fp_line
			(start 0.299974 -0.150114)
			(end 0.299974 0.150114)
			(stroke
				(width 0.1)
				(type default)
			)
			(layer "F.Fab")
		)
		(fp_line
			(start -0.299974 0.150114)
			(end -0.299974 -0.150114)
			(stroke
				(width 0.1)
				(type default)
			)
			(layer "F.Fab")
		)
		(fp_line
			(start -0.299974 -0.150114)
			(end 0.299974 -0.150114)
			(stroke
				(width 0.1)
				(type default)
			)
			(layer "F.Fab")
		)
		(pad "1" smd rect
			(at -0.2667 0 180)
			(size 0.3048 0.381)
			(layers "F.Cu" "F.Mask" "F.Paste")
			(net "P5E_PEX0_STN2_TX_DN<39>")
		)
		(pad "2" smd rect
			(at 0.2667 0 180)
			(size 0.3048 0.381)
			(layers "F.Cu" "F.Mask" "F.Paste")
			(net "P5E_PEX0_STN2_TX_C_DN<39>")
		)
	)
	(footprint ""
		(layer "F.Cu")
		(at 376.34926 -290.595812 -90)
		(property "Reference" "C3558"
			(at 0 0 270)
			(layer "F.SilkS")
			(hide yes)
			(effects
				(font
					(size 1.27 1.27)
				)
			)
		)
		(property "Value" ""
			(at 0 0 270)
			(layer "F.Fab")
			(effects
				(font
					(size 1.27 1.27)
				)
			)
		)
		(duplicate_pad_numbers_are_jumpers no)
		(fp_line
			(start -0.299974 0.150114)
			(end -0.299974 -0.150114)
			(stroke
				(width 0.1)
				(type default)
			)
			(layer "F.Fab")
		)
		(fp_line
			(start 0.299974 0.150114)
			(end -0.299974 0.150114)
			(stroke
				(width 0.1)
				(type default)
			)
			(layer "F.Fab")
		)
		(fp_line
			(start -0.299974 -0.150114)
			(end 0.299974 -0.150114)
			(stroke
				(width 0.1)
				(type default)
			)
			(layer "F.Fab")
		)
		(fp_line
			(start 0.299974 -0.150114)
			(end 0.299974 0.150114)
			(stroke
				(width 0.1)
				(type default)
			)
			(layer "F.Fab")
		)
		(pad "1" smd rect
			(at -0.2667 0 270)
			(size 0.3048 0.381)
			(layers "F.Cu" "F.Mask" "F.Paste")
			(net "P1V8_PLL0_PEX3")
		)
		(pad "2" smd rect
			(at 0.2667 0 270)
			(size 0.3048 0.381)
			(layers "F.Cu" "F.Mask" "F.Paste")
			(net "GND")
		)
	)
	(footprint ""
		(layer "F.Cu")
		(at 241.64671 -152.859994 180)
		(property "Reference" "PR7023"
			(at 0 0 180)
			(layer "F.SilkS")
			(hide yes)
			(effects
				(font
					(size 1.27 1.27)
				)
			)
		)
		(property "Value" ""
			(at 0 0 180)
			(layer "F.Fab")
			(effects
				(font
					(size 1.27 1.27)
				)
			)
		)
		(duplicate_pad_numbers_are_jumpers no)
		(fp_line
			(start 1.2954 0.5842)
			(end -1.2954 0.5842)
			(stroke
				(width 0.1524)
				(type default)
			)
			(layer "F.SilkS")
		)
		(fp_line
			(start 1.2954 -0.5842)
			(end 1.2954 0.5842)
			(stroke
				(width 0.1524)
				(type default)
			)
			(layer "F.SilkS")
		)
		(fp_line
			(start -1.2954 0.5842)
			(end -1.2954 -0.5842)
			(stroke
				(width 0.1524)
				(type default)
			)
			(layer "F.SilkS")
		)
		(fp_line
			(start -1.2954 -0.5842)
			(end 1.2954 -0.5842)
			(stroke
				(width 0.1524)
				(type default)
			)
			(layer "F.SilkS")
		)
		(fp_line
			(start 1.1938 0.4064)
			(end 0.8636 0.4064)
			(stroke
				(width 0.1)
				(type default)
			)
			(layer "F.Fab")
		)
		(fp_line
			(start 1.1938 -0.406654)
			(end 1.1938 0.4064)
			(stroke
				(width 0.1)
				(type default)
			)
			(layer "F.Fab")
		)
		(fp_line
			(start 0.8636 0.4572)
			(end -0.8636 0.4572)
			(stroke
				(width 0.1)
				(type default)
			)
			(layer "F.Fab")
		)
		(fp_line
			(start 0.8636 0.4064)
			(end 0.8636 0.4572)
			(stroke
				(width 0.1)
				(type default)
			)
			(layer "F.Fab")
		)
		(fp_line
			(start 0.8636 -0.406654)
			(end 1.1938 -0.406654)
			(stroke
				(width 0.1)
				(type default)
			)
			(layer "F.Fab")
		)
		(fp_line
			(start 0.8636 -0.4572)
			(end 0.8636 -0.406654)
			(stroke
				(width 0.1)
				(type default)
			)
			(layer "F.Fab")
		)
		(fp_line
			(start -0.8636 0.4572)
			(end -0.8636 0.4318)
			(stroke
				(width 0.1)
				(type default)
			)
			(layer "F.Fab")
		)
		(fp_line
			(start -0.8636 0.4318)
			(end -0.8636 0.4064)
			(stroke
				(width 0.1)
				(type default)
			)
			(layer "F.Fab")
		)
		(fp_line
			(start -0.8636 0.4064)
			(end -1.1938 0.4064)
			(stroke
				(width 0.1)
				(type default)
			)
			(layer "F.Fab")
		)
		(fp_line
			(start -0.8636 -0.406654)
			(end -0.8636 -0.4572)
			(stroke
				(width 0.1)
				(type default)
			)
			(layer "F.Fab")
		)
		(fp_line
			(start -0.8636 -0.4572)
			(end 0.8636 -0.4572)
			(stroke
				(width 0.1)
				(type default)
			)
			(layer "F.Fab")
		)
		(fp_line
			(start -1.1938 0.4064)
			(end -1.1938 -0.406654)
			(stroke
				(width 0.1)
				(type default)
			)
			(layer "F.Fab")
		)
		(fp_line
			(start -1.1938 -0.406654)
			(end -0.8636 -0.406654)
			(stroke
				(width 0.1)
				(type default)
			)
			(layer "F.Fab")
		)
		(pad "1" smd rect
			(at -0.7366 0 90)
			(size 0.7112 0.8128)
			(layers "F.Cu" "F.Mask" "F.Paste")
			(net "P12V_NIC4_CO_AVIN_PD")
		)
		(pad "2" smd rect
			(at 0.7366 0 90)
			(size 0.7112 0.8128)
			(layers "F.Cu" "F.Mask" "F.Paste")
			(net "P12V_AUX")
		)
	)
	(footprint ""
		(layer "F.Cu")
		(at 115.281456 -303.649634 90)
		(property "Reference" "PC85"
			(at 0 0 90)
			(layer "F.SilkS")
			(hide yes)
			(effects
				(font
					(size 1.27 1.27)
				)
			)
		)
		(property "Value" ""
			(at 0 0 90)
			(layer "F.Fab")
			(effects
				(font
					(size 1.27 1.27)
				)
			)
		)
		(duplicate_pad_numbers_are_jumpers no)
		(fp_line
			(start 1.524 -0.762)
			(end 1.524 0.762)
			(stroke
				(width 0.1524)
				(type default)
			)
			(layer "F.SilkS")
		)
		(fp_line
			(start -1.524 -0.762)
			(end 1.524 -0.762)
			(stroke
				(width 0.1524)
				(type default)
			)
			(layer "F.SilkS")
		)
		(fp_line
			(start 1.524 0.762)
			(end -1.524 0.762)
			(stroke
				(width 0.1524)
				(type default)
			)
			(layer "F.SilkS")
		)
		(fp_line
			(start -1.524 0.762)
			(end -1.524 -0.762)
			(stroke
				(width 0.1524)
				(type default)
			)
			(layer "F.SilkS")
		)
		(fp_line
			(start 1.1049 -0.724916)
			(end -1.1049 -0.724916)
			(stroke
				(width 0.1)
				(type default)
			)
			(layer "F.Fab")
		)
		(fp_line
			(start -1.1049 -0.724916)
			(end -1.1049 0.724916)
			(stroke
				(width 0.1)
				(type default)
			)
			(layer "F.Fab")
		)
		(fp_line
			(start 1.1049 0.724916)
			(end 1.1049 -0.724916)
			(stroke
				(width 0.1)
				(type default)
			)
			(layer "F.Fab")
		)
		(fp_line
			(start -1.1049 0.724916)
			(end 1.1049 0.724916)
			(stroke
				(width 0.1)
				(type default)
			)
			(layer "F.Fab")
		)
		(pad "1" smd rect
			(at -0.889 0 270)
			(size 1.016 1.27)
			(layers "F.Cu" "F.Mask" "F.Paste")
			(net "P0V8_PEX0")
		)
		(pad "2" smd rect
			(at 0.889 0 270)
			(size 1.016 1.27)
			(layers "F.Cu" "F.Mask" "F.Paste")
			(net "GND")
		)
	)
	(footprint ""
		(layer "F.Cu")
		(at 129.864612 -162.003994 90)
		(property "Reference" "PC634"
			(at 0 0 90)
			(layer "F.SilkS")
			(hide yes)
			(effects
				(font
					(size 1.27 1.27)
				)
			)
		)
		(property "Value" ""
			(at 0 0 90)
			(layer "F.Fab")
			(effects
				(font
					(size 1.27 1.27)
				)
			)
		)
		(duplicate_pad_numbers_are_jumpers no)
		(fp_line
			(start 0.7874 -0.4064)
			(end 0.7874 0.4064)
			(stroke
				(width 0.1524)
				(type default)
			)
			(layer "F.SilkS")
		)
		(fp_line
			(start -0.7874 -0.4064)
			(end 0.7874 -0.4064)
			(stroke
				(width 0.1524)
				(type default)
			)
			(layer "F.SilkS")
		)
		(fp_line
			(start 0.7874 0.4064)
			(end -0.7874 0.4064)
			(stroke
				(width 0.1524)
				(type default)
			)
			(layer "F.SilkS")
		)
		(fp_line
			(start -0.7874 0.4064)
			(end -0.7874 -0.4064)
			(stroke
				(width 0.1524)
				(type default)
			)
			(layer "F.SilkS")
		)
		(fp_line
			(start -0.12065 -0.305054)
			(end -0.12065 -0.2794)
			(stroke
				(width 0.1)
				(type default)
			)
			(layer "F.Fab")
		)
		(fp_line
			(start -0.67945 -0.305054)
			(end -0.12065 -0.305054)
			(stroke
				(width 0.1)
				(type default)
			)
			(layer "F.Fab")
		)
		(fp_line
			(start 0.67945 -0.3048)
			(end 0.67945 0.3048)
			(stroke
				(width 0.1)
				(type default)
			)
			(layer "F.Fab")
		)
		(fp_line
			(start 0.12065 -0.3048)
			(end 0.67945 -0.3048)
			(stroke
				(width 0.1)
				(type default)
			)
			(layer "F.Fab")
		)
		(fp_line
			(start 0.12065 -0.2794)
			(end 0.12065 -0.3048)
			(stroke
				(width 0.1)
				(type default)
			)
			(layer "F.Fab")
		)
		(fp_line
			(start -0.12065 -0.2794)
			(end 0.12065 -0.2794)
			(stroke
				(width 0.1)
				(type default)
			)
			(layer "F.Fab")
		)
		(fp_line
			(start 0.120396 0.2794)
			(end -0.12065 0.2794)
			(stroke
				(width 0.1)
				(type default)
			)
			(layer "F.Fab")
		)
		(fp_line
			(start -0.12065 0.2794)
			(end -0.12065 0.3048)
			(stroke
				(width 0.1)
				(type default)
			)
			(layer "F.Fab")
		)
		(fp_line
			(start 0.67945 0.3048)
			(end 0.120396 0.3048)
			(stroke
				(width 0.1)
				(type default)
			)
			(layer "F.Fab")
		)
		(fp_line
			(start 0.120396 0.3048)
			(end 0.120396 0.2794)
			(stroke
				(width 0.1)
				(type default)
			)
			(layer "F.Fab")
		)
		(fp_line
			(start -0.12065 0.3048)
			(end -0.67945 0.3048)
			(stroke
				(width 0.1)
				(type default)
			)
			(layer "F.Fab")
		)
		(fp_line
			(start -0.67945 0.3048)
			(end -0.67945 -0.305054)
			(stroke
				(width 0.1)
				(type default)
			)
			(layer "F.Fab")
		)
		(pad "1" smd circle
			(at -0.40005 0 90)
			(size 0 0)
			(layers "F.Cu" "F.Mask" "F.Paste")
			(net "P12V_NIC2_CO_TIMER")
		)
		(pad "2" smd circle
			(at 0.40005 0 90)
			(size 0 0)
			(layers "F.Cu" "F.Mask" "F.Paste")
			(net "GND")
		)
	)
	(footprint ""
		(layer "F.Cu")
		(at 13.649198 -304.39487 -90)
		(property "Reference" "PR167"
			(at 0 0 270)
			(layer "F.SilkS")
			(hide yes)
			(effects
				(font
					(size 1.27 1.27)
				)
			)
		)
		(property "Value" ""
			(at 0 0 270)
			(layer "F.Fab")
			(effects
				(font
					(size 1.27 1.27)
				)
			)
		)
		(duplicate_pad_numbers_are_jumpers no)
		(fp_line
			(start -0.7874 0.4064)
			(end -0.7874 -0.4064)
			(stroke
				(width 0.1524)
				(type default)
			)
			(layer "F.SilkS")
		)
		(fp_line
			(start 0.7874 0.4064)
			(end -0.7874 0.4064)
			(stroke
				(width 0.1524)
				(type default)
			)
			(layer "F.SilkS")
		)
		(fp_line
			(start -0.7874 -0.4064)
			(end 0.7874 -0.4064)
			(stroke
				(width 0.1524)
				(type default)
			)
			(layer "F.SilkS")
		)
		(fp_line
			(start 0.7874 -0.4064)
			(end 0.7874 0.4064)
			(stroke
				(width 0.1524)
				(type default)
			)
			(layer "F.SilkS")
		)
		(fp_line
			(start -0.67945 0.3048)
			(end -0.67945 -0.305054)
			(stroke
				(width 0.1)
				(type default)
			)
			(layer "F.Fab")
		)
		(fp_line
			(start -0.12065 0.3048)
			(end -0.67945 0.3048)
			(stroke
				(width 0.1)
				(type default)
			)
			(layer "F.Fab")
		)
		(fp_line
			(start 0.120396 0.3048)
			(end 0.120396 0.2794)
			(stroke
				(width 0.1)
				(type default)
			)
			(layer "F.Fab")
		)
		(fp_line
			(start 0.67945 0.3048)
			(end 0.120396 0.3048)
			(stroke
				(width 0.1)
				(type default)
			)
			(layer "F.Fab")
		)
		(fp_line
			(start -0.12065 0.2794)
			(end -0.12065 0.3048)
			(stroke
				(width 0.1)
				(type default)
			)
			(layer "F.Fab")
		)
		(fp_line
			(start 0.120396 0.2794)
			(end -0.12065 0.2794)
			(stroke
				(width 0.1)
				(type default)
			)
			(layer "F.Fab")
		)
		(fp_line
			(start -0.12065 -0.2794)
			(end 0.12065 -0.2794)
			(stroke
				(width 0.1)
				(type default)
			)
			(layer "F.Fab")
		)
		(fp_line
			(start 0.12065 -0.2794)
			(end 0.12065 -0.3048)
			(stroke
				(width 0.1)
				(type default)
			)
			(layer "F.Fab")
		)
		(fp_line
			(start 0.12065 -0.3048)
			(end 0.67945 -0.3048)
			(stroke
				(width 0.1)
				(type default)
			)
			(layer "F.Fab")
		)
		(fp_line
			(start 0.67945 -0.3048)
			(end 0.67945 0.3048)
			(stroke
				(width 0.1)
				(type default)
			)
			(layer "F.Fab")
		)
		(fp_line
			(start -0.67945 -0.305054)
			(end -0.12065 -0.305054)
			(stroke
				(width 0.1)
				(type default)
			)
			(layer "F.Fab")
		)
		(fp_line
			(start -0.12065 -0.305054)
			(end -0.12065 -0.2794)
			(stroke
				(width 0.1)
				(type default)
			)
			(layer "F.Fab")
		)
		(pad "1" smd circle
			(at -0.40005 0 270)
			(size 0 0)
			(layers "F.Cu" "F.Mask" "F.Paste")
			(net "P1V25_PEX0_CS")
		)
		(pad "2" smd circle
			(at 0.40005 0 270)
			(size 0 0)
			(layers "F.Cu" "F.Mask" "F.Paste")
			(net "GND")
		)
	)
	(footprint ""
		(layer "F.Cu")
		(at 242.310412 -122.931428 180)
		(property "Reference" "PC493"
			(at 0 0 180)
			(layer "F.SilkS")
			(hide yes)
			(effects
				(font
					(size 1.27 1.27)
				)
			)
		)
		(property "Value" ""
			(at 0 0 180)
			(layer "F.Fab")
			(effects
				(font
					(size 1.27 1.27)
				)
			)
		)
		(duplicate_pad_numbers_are_jumpers no)
		(fp_line
			(start 0.7874 0.4064)
			(end -0.7874 0.4064)
			(stroke
				(width 0.1524)
				(type default)
			)
			(layer "F.SilkS")
		)
		(fp_line
			(start 0.7874 -0.4064)
			(end 0.7874 0.4064)
			(stroke
				(width 0.1524)
				(type default)
			)
			(layer "F.SilkS")
		)
		(fp_line
			(start -0.7874 0.4064)
			(end -0.7874 -0.4064)
			(stroke
				(width 0.1524)
				(type default)
			)
			(layer "F.SilkS")
		)
		(fp_line
			(start -0.7874 -0.4064)
			(end 0.7874 -0.4064)
			(stroke
				(width 0.1524)
				(type default)
			)
			(layer "F.SilkS")
		)
		(fp_line
			(start 0.67945 0.3048)
			(end 0.120396 0.3048)
			(stroke
				(width 0.1)
				(type default)
			)
			(layer "F.Fab")
		)
		(fp_line
			(start 0.67945 -0.3048)
			(end 0.67945 0.3048)
			(stroke
				(width 0.1)
				(type default)
			)
			(layer "F.Fab")
		)
		(fp_line
			(start 0.12065 -0.2794)
			(end 0.12065 -0.3048)
			(stroke
				(width 0.1)
				(type default)
			)
			(layer "F.Fab")
		)
		(fp_line
			(start 0.12065 -0.3048)
			(end 0.67945 -0.3048)
			(stroke
				(width 0.1)
				(type default)
			)
			(layer "F.Fab")
		)
		(fp_line
			(start 0.120396 0.3048)
			(end 0.120396 0.2794)
			(stroke
				(width 0.1)
				(type default)
			)
			(layer "F.Fab")
		)
		(fp_line
			(start 0.120396 0.2794)
			(end -0.12065 0.2794)
			(stroke
				(width 0.1)
				(type default)
			)
			(layer "F.Fab")
		)
		(fp_line
			(start -0.12065 0.3048)
			(end -0.67945 0.3048)
			(stroke
				(width 0.1)
				(type default)
			)
			(layer "F.Fab")
		)
		(fp_line
			(start -0.12065 0.2794)
			(end -0.12065 0.3048)
			(stroke
				(width 0.1)
				(type default)
			)
			(layer "F.Fab")
		)
		(fp_line
			(start -0.12065 -0.2794)
			(end 0.12065 -0.2794)
			(stroke
				(width 0.1)
				(type default)
			)
			(layer "F.Fab")
		)
		(fp_line
			(start -0.12065 -0.305054)
			(end -0.12065 -0.2794)
			(stroke
				(width 0.1)
				(type default)
			)
			(layer "F.Fab")
		)
		(fp_line
			(start -0.67945 0.3048)
			(end -0.67945 -0.305054)
			(stroke
				(width 0.1)
				(type default)
			)
			(layer "F.Fab")
		)
		(fp_line
			(start -0.67945 -0.305054)
			(end -0.12065 -0.305054)
			(stroke
				(width 0.1)
				(type default)
			)
			(layer "F.Fab")
		)
		(pad "1" smd circle
			(at -0.40005 0 180)
			(size 0 0)
			(layers "F.Cu" "F.Mask" "F.Paste")
			(net "P5V_AUX")
		)
		(pad "2" smd circle
			(at 0.40005 0 180)
			(size 0 0)
			(layers "F.Cu" "F.Mask" "F.Paste")
			(net "GND")
		)
	)
	(footprint ""
		(layer "F.Cu")
		(at 416.402012 -356.244906 90)
		(property "Reference" "C819"
			(at 0 0 90)
			(layer "F.SilkS")
			(hide yes)
			(effects
				(font
					(size 1.27 1.27)
				)
			)
		)
		(property "Value" ""
			(at 0 0 90)
			(layer "F.Fab")
			(effects
				(font
					(size 1.27 1.27)
				)
			)
		)
		(duplicate_pad_numbers_are_jumpers no)
		(fp_line
			(start 0.299974 -0.150114)
			(end 0.299974 0.150114)
			(stroke
				(width 0.1)
				(type default)
			)
			(layer "F.Fab")
		)
		(fp_line
			(start -0.299974 -0.150114)
			(end 0.299974 -0.150114)
			(stroke
				(width 0.1)
				(type default)
			)
			(layer "F.Fab")
		)
		(fp_line
			(start 0.299974 0.150114)
			(end -0.299974 0.150114)
			(stroke
				(width 0.1)
				(type default)
			)
			(layer "F.Fab")
		)
		(fp_line
			(start -0.299974 0.150114)
			(end -0.299974 -0.150114)
			(stroke
				(width 0.1)
				(type default)
			)
			(layer "F.Fab")
		)
		(pad "1" smd rect
			(at -0.2667 0 90)
			(size 0.3048 0.381)
			(layers "F.Cu" "F.Mask" "F.Paste")
			(net "P5E_PEX3_STN7_TX_DN<115>")
		)
		(pad "2" smd rect
			(at 0.2667 0 90)
			(size 0.3048 0.381)
			(layers "F.Cu" "F.Mask" "F.Paste")
			(net "P5E_PEX3_STN7_TX_C_DN<115>")
		)
	)
	(footprint ""
		(layer "F.Cu")
		(at 385.48564 -115.2652 90)
		(property "Reference" "R350"
			(at 0 0 90)
			(layer "F.SilkS")
			(hide yes)
			(effects
				(font
					(size 1.27 1.27)
				)
			)
		)
		(property "Value" ""
			(at 0 0 90)
			(layer "F.Fab")
			(effects
				(font
					(size 1.27 1.27)
				)
			)
		)
		(duplicate_pad_numbers_are_jumpers no)
		(fp_line
			(start 0.7874 -0.4064)
			(end 0.7874 0.4064)
			(stroke
				(width 0.1524)
				(type default)
			)
			(layer "F.SilkS")
		)
		(fp_line
			(start -0.7874 -0.4064)
			(end 0.7874 -0.4064)
			(stroke
				(width 0.1524)
				(type default)
			)
			(layer "F.SilkS")
		)
		(fp_line
			(start 0.7874 0.4064)
			(end -0.7874 0.4064)
			(stroke
				(width 0.1524)
				(type default)
			)
			(layer "F.SilkS")
		)
		(fp_line
			(start -0.7874 0.4064)
			(end -0.7874 -0.4064)
			(stroke
				(width 0.1524)
				(type default)
			)
			(layer "F.SilkS")
		)
		(fp_line
			(start -0.12065 -0.305054)
			(end -0.12065 -0.2794)
			(stroke
				(width 0.1)
				(type default)
			)
			(layer "F.Fab")
		)
		(fp_line
			(start -0.67945 -0.305054)
			(end -0.12065 -0.305054)
			(stroke
				(width 0.1)
				(type default)
			)
			(layer "F.Fab")
		)
		(fp_line
			(start 0.67945 -0.3048)
			(end 0.67945 0.3048)
			(stroke
				(width 0.1)
				(type default)
			)
			(layer "F.Fab")
		)
		(fp_line
			(start 0.12065 -0.3048)
			(end 0.67945 -0.3048)
			(stroke
				(width 0.1)
				(type default)
			)
			(layer "F.Fab")
		)
		(fp_line
			(start 0.12065 -0.2794)
			(end 0.12065 -0.3048)
			(stroke
				(width 0.1)
				(type default)
			)
			(layer "F.Fab")
		)
		(fp_line
			(start -0.12065 -0.2794)
			(end 0.12065 -0.2794)
			(stroke
				(width 0.1)
				(type default)
			)
			(layer "F.Fab")
		)
		(fp_line
			(start 0.120396 0.2794)
			(end -0.12065 0.2794)
			(stroke
				(width 0.1)
				(type default)
			)
			(layer "F.Fab")
		)
		(fp_line
			(start -0.12065 0.2794)
			(end -0.12065 0.3048)
			(stroke
				(width 0.1)
				(type default)
			)
			(layer "F.Fab")
		)
		(fp_line
			(start 0.67945 0.3048)
			(end 0.120396 0.3048)
			(stroke
				(width 0.1)
				(type default)
			)
			(layer "F.Fab")
		)
		(fp_line
			(start 0.120396 0.3048)
			(end 0.120396 0.2794)
			(stroke
				(width 0.1)
				(type default)
			)
			(layer "F.Fab")
		)
		(fp_line
			(start -0.12065 0.3048)
			(end -0.67945 0.3048)
			(stroke
				(width 0.1)
				(type default)
			)
			(layer "F.Fab")
		)
		(fp_line
			(start -0.67945 0.3048)
			(end -0.67945 -0.305054)
			(stroke
				(width 0.1)
				(type default)
			)
			(layer "F.Fab")
		)
		(pad "1" smd circle
			(at -0.40005 0 90)
			(size 0 0)
			(layers "F.Cu" "F.Mask" "F.Paste")
			(net "P3V3_AUX")
		)
		(pad "2" smd circle
			(at 0.40005 0 90)
			(size 0 0)
			(layers "F.Cu" "F.Mask" "F.Paste")
			(net "HP_NIC6_EN")
		)
	)
	(footprint ""
		(layer "F.Cu")
		(at 359.837736 -384.339846 -90)
		(property "Reference" "R6712"
			(at 0 0 270)
			(layer "F.SilkS")
			(hide yes)
			(effects
				(font
					(size 1.27 1.27)
				)
			)
		)
		(property "Value" ""
			(at 0 0 270)
			(layer "F.Fab")
			(effects
				(font
					(size 1.27 1.27)
				)
			)
		)
		(duplicate_pad_numbers_are_jumpers no)
		(fp_line
			(start -0.7874 0.4064)
			(end -0.7874 -0.4064)
			(stroke
				(width 0.1524)
				(type default)
			)
			(layer "F.SilkS")
		)
		(fp_line
			(start 0.7874 0.4064)
			(end -0.7874 0.4064)
			(stroke
				(width 0.1524)
				(type default)
			)
			(layer "F.SilkS")
		)
		(fp_line
			(start -0.7874 -0.4064)
			(end 0.7874 -0.4064)
			(stroke
				(width 0.1524)
				(type default)
			)
			(layer "F.SilkS")
		)
		(fp_line
			(start 0.7874 -0.4064)
			(end 0.7874 0.4064)
			(stroke
				(width 0.1524)
				(type default)
			)
			(layer "F.SilkS")
		)
		(fp_line
			(start -0.67945 0.3048)
			(end -0.67945 -0.305054)
			(stroke
				(width 0.1)
				(type default)
			)
			(layer "F.Fab")
		)
		(fp_line
			(start -0.12065 0.3048)
			(end -0.67945 0.3048)
			(stroke
				(width 0.1)
				(type default)
			)
			(layer "F.Fab")
		)
		(fp_line
			(start 0.120396 0.3048)
			(end 0.120396 0.2794)
			(stroke
				(width 0.1)
				(type default)
			)
			(layer "F.Fab")
		)
		(fp_line
			(start 0.67945 0.3048)
			(end 0.120396 0.3048)
			(stroke
				(width 0.1)
				(type default)
			)
			(layer "F.Fab")
		)
		(fp_line
			(start -0.12065 0.2794)
			(end -0.12065 0.3048)
			(stroke
				(width 0.1)
				(type default)
			)
			(layer "F.Fab")
		)
		(fp_line
			(start 0.120396 0.2794)
			(end -0.12065 0.2794)
			(stroke
				(width 0.1)
				(type default)
			)
			(layer "F.Fab")
		)
		(fp_line
			(start -0.12065 -0.2794)
			(end 0.12065 -0.2794)
			(stroke
				(width 0.1)
				(type default)
			)
			(layer "F.Fab")
		)
		(fp_line
			(start 0.12065 -0.2794)
			(end 0.12065 -0.3048)
			(stroke
				(width 0.1)
				(type default)
			)
			(layer "F.Fab")
		)
		(fp_line
			(start 0.12065 -0.3048)
			(end 0.67945 -0.3048)
			(stroke
				(width 0.1)
				(type default)
			)
			(layer "F.Fab")
		)
		(fp_line
			(start 0.67945 -0.3048)
			(end 0.67945 0.3048)
			(stroke
				(width 0.1)
				(type default)
			)
			(layer "F.Fab")
		)
		(fp_line
			(start -0.67945 -0.305054)
			(end -0.12065 -0.305054)
			(stroke
				(width 0.1)
				(type default)
			)
			(layer "F.Fab")
		)
		(fp_line
			(start -0.12065 -0.305054)
			(end -0.12065 -0.2794)
			(stroke
				(width 0.1)
				(type default)
			)
			(layer "F.Fab")
		)
		(pad "1" smd circle
			(at -0.40005 0 270)
			(size 0 0)
			(layers "F.Cu" "F.Mask" "F.Paste")
			(net "MB_3V3IO_RSVD4_ISO")
		)
		(pad "2" smd circle
			(at 0.40005 0 270)
			(size 0 0)
			(layers "F.Cu" "F.Mask" "F.Paste")
			(net "MB_3V3IO_RSVD4")
		)
	)
	(footprint ""
		(layer "F.Cu")
		(at 5.589524 -68.64223)
		(property "Reference" "Q133"
			(at -2.823718 -2.09042 0)
			(unlocked yes)
			(layer "F.SilkS")
			(effects
				(font
					(size 0.7874 0.5842)
					(thickness 0.1524)
				)
			)
		)
		(property "Value" ""
			(at 0 0 0)
			(layer "F.Fab")
			(effects
				(font
					(size 1.27 1.27)
				)
			)
		)
		(duplicate_pad_numbers_are_jumpers no)
		(fp_line
			(start -1.376172 -1.199896)
			(end -0.508 -1.199896)
			(stroke
				(width 0.1524)
				(type default)
			)
			(layer "F.SilkS")
		)
		(fp_line
			(start -1.376172 1.199896)
			(end -1.376172 -1.199896)
			(stroke
				(width 0.1524)
				(type default)
			)
			(layer "F.SilkS")
		)
		(fp_line
			(start -0.508 -1.199896)
			(end 0 -0.762)
			(stroke
				(width 0.1524)
				(type default)
			)
			(layer "F.SilkS")
		)
		(fp_line
			(start 0 -0.762)
			(end 0.508 -1.199896)
			(stroke
				(width 0.1524)
				(type default)
			)
			(layer "F.SilkS")
		)
		(fp_line
			(start 0.508 -1.199896)
			(end 1.376172 -1.199896)
			(stroke
				(width 0.1524)
				(type default)
			)
			(layer "F.SilkS")
		)
		(fp_line
			(start 1.376172 -1.199896)
			(end 1.376172 1.199896)
			(stroke
				(width 0.1524)
				(type default)
			)
			(layer "F.SilkS")
		)
		(fp_line
			(start 1.376172 1.199896)
			(end -1.376172 1.199896)
			(stroke
				(width 0.1524)
				(type default)
			)
			(layer "F.SilkS")
		)
		(fp_poly
			(pts
				(xy -1.352804 -0.832866) (xy -1.622044 -1.641094) (xy -2.161032 -1.10236)
			)
			(stroke
				(width 0)
				(type default)
			)
			(fill yes)
			(layer "F.SilkS")
		)
		(fp_line
			(start -0.674878 -1.100074)
			(end 0.674878 -1.100074)
			(stroke
				(width 0.1)
				(type default)
			)
			(layer "F.Fab")
		)
		(fp_line
			(start -0.674878 1.100074)
			(end -0.674878 -1.100074)
			(stroke
				(width 0.1)
				(type default)
			)
			(layer "F.Fab")
		)
		(fp_line
			(start 0.674878 -1.100074)
			(end 0.674878 1.100074)
			(stroke
				(width 0.1)
				(type default)
			)
			(layer "F.Fab")
		)
		(fp_line
			(start 0.674878 1.100074)
			(end -0.674878 1.100074)
			(stroke
				(width 0.1)
				(type default)
			)
			(layer "F.Fab")
		)
		(fp_poly
			(pts
				(xy -1.4605 -0.7493) (xy -2.2225 -1.1303) (xy -2.2225 -0.3683)
			)
			(stroke
				(width 0)
				(type default)
			)
			(fill yes)
			(layer "F.Fab")
		)
		(pad "1" smd rect
			(at -0.899922 -0.750062 270)
			(size 0.6096 0.6096)
			(layers "F.Cu" "F.Mask" "F.Paste")
			(net "GND")
		)
		(pad "2" smd rect
			(at -0.899922 0 270)
			(size 0.4064 0.6096)
			(layers "F.Cu" "F.Mask" "F.Paste")
			(net "P3V3_SSD0_PG_G1")
		)
		(pad "3" smd rect
			(at -0.899922 0.750062 270)
			(size 0.6096 0.6096)
			(layers "F.Cu" "F.Mask" "F.Paste")
			(net "PWRGD_P3V3_SSD0_D")
		)
		(pad "4" smd rect
			(at 0.899922 0.750062 270)
			(size 0.6096 0.6096)
			(layers "F.Cu" "F.Mask" "F.Paste")
			(net "GND")
		)
		(pad "5" smd rect
			(at 0.899922 0 270)
			(size 0.4064 0.6096)
			(layers "F.Cu" "F.Mask" "F.Paste")
			(net "P3V3_SSD0_PG_G2")
		)
		(pad "6" smd rect
			(at 0.899922 -0.750062 270)
			(size 0.6096 0.6096)
			(layers "F.Cu" "F.Mask" "F.Paste")
			(net "P3V3_SSD0_PG_G2")
		)
	)
	(footprint ""
		(layer "F.Cu")
		(at 378.382022 -292.991032 180)
		(property "Reference" "C3554"
			(at 0 0 180)
			(layer "F.SilkS")
			(hide yes)
			(effects
				(font
					(size 1.27 1.27)
				)
			)
		)
		(property "Value" ""
			(at 0 0 180)
			(layer "F.Fab")
			(effects
				(font
					(size 1.27 1.27)
				)
			)
		)
		(duplicate_pad_numbers_are_jumpers no)
		(fp_line
			(start 1.2954 0.5842)
			(end -1.2954 0.5842)
			(stroke
				(width 0.1524)
				(type default)
			)
			(layer "F.SilkS")
		)
		(fp_line
			(start 1.2954 -0.5842)
			(end 1.2954 0.5842)
			(stroke
				(width 0.1524)
				(type default)
			)
			(layer "F.SilkS")
		)
		(fp_line
			(start -1.2954 0.5842)
			(end -1.2954 -0.5842)
			(stroke
				(width 0.1524)
				(type default)
			)
			(layer "F.SilkS")
		)
		(fp_line
			(start -1.2954 -0.5842)
			(end 1.2954 -0.5842)
			(stroke
				(width 0.1524)
				(type default)
			)
			(layer "F.SilkS")
		)
		(fp_line
			(start 1.1938 0.4064)
			(end 0.8636 0.4064)
			(stroke
				(width 0.1)
				(type default)
			)
			(layer "F.Fab")
		)
		(fp_line
			(start 1.1938 -0.4064)
			(end 1.1938 0.4064)
			(stroke
				(width 0.1)
				(type default)
			)
			(layer "F.Fab")
		)
		(fp_line
			(start 0.8636 0.4572)
			(end -0.8636 0.4572)
			(stroke
				(width 0.1)
				(type default)
			)
			(layer "F.Fab")
		)
		(fp_line
			(start 0.8636 0.4064)
			(end 0.8636 0.4572)
			(stroke
				(width 0.1)
				(type default)
			)
			(layer "F.Fab")
		)
		(fp_line
			(start 0.8636 -0.4064)
			(end 1.1938 -0.4064)
			(stroke
				(width 0.1)
				(type default)
			)
			(layer "F.Fab")
		)
		(fp_line
			(start 0.8636 -0.4572)
			(end 0.8636 -0.4064)
			(stroke
				(width 0.1)
				(type default)
			)
			(layer "F.Fab")
		)
		(fp_line
			(start -0.8636 0.4572)
			(end -0.8636 0.4064)
			(stroke
				(width 0.1)
				(type default)
			)
			(layer "F.Fab")
		)
		(fp_line
			(start -0.8636 0.4064)
			(end -1.1938 0.4064)
			(stroke
				(width 0.1)
				(type default)
			)
			(layer "F.Fab")
		)
		(fp_line
			(start -0.8636 -0.4064)
			(end -0.8636 -0.4572)
			(stroke
				(width 0.1)
				(type default)
			)
			(layer "F.Fab")
		)
		(fp_line
			(start -0.8636 -0.4572)
			(end 0.8636 -0.4572)
			(stroke
				(width 0.1)
				(type default)
			)
			(layer "F.Fab")
		)
		(fp_line
			(start -1.1938 0.4064)
			(end -1.1938 -0.4064)
			(stroke
				(width 0.1)
				(type default)
			)
			(layer "F.Fab")
		)
		(fp_line
			(start -1.1938 -0.4064)
			(end -0.8636 -0.4064)
			(stroke
				(width 0.1)
				(type default)
			)
			(layer "F.Fab")
		)
		(pad "1" smd rect
			(at -0.7366 0 90)
			(size 0.7112 0.8128)
			(layers "F.Cu" "F.Mask" "F.Paste")
			(net "PCEPLL2_VDDA18_PEX3_R")
		)
		(pad "2" smd rect
			(at 0.7366 0 90)
			(size 0.7112 0.8128)
			(layers "F.Cu" "F.Mask" "F.Paste")
			(net "GND")
		)
	)
	(footprint ""
		(layer "F.Cu")
		(at 31.454344 -252.356874 -90)
		(property "Reference" "R1195"
			(at 0 0 270)
			(layer "F.SilkS")
			(hide yes)
			(effects
				(font
					(size 1.27 1.27)
				)
			)
		)
		(property "Value" ""
			(at 0 0 270)
			(layer "F.Fab")
			(effects
				(font
					(size 1.27 1.27)
				)
			)
		)
		(duplicate_pad_numbers_are_jumpers no)
		(fp_line
			(start -0.7874 0.4064)
			(end -0.7874 -0.4064)
			(stroke
				(width 0.1524)
				(type default)
			)
			(layer "F.SilkS")
		)
		(fp_line
			(start 0.7874 0.4064)
			(end -0.7874 0.4064)
			(stroke
				(width 0.1524)
				(type default)
			)
			(layer "F.SilkS")
		)
		(fp_line
			(start -0.7874 -0.4064)
			(end 0.7874 -0.4064)
			(stroke
				(width 0.1524)
				(type default)
			)
			(layer "F.SilkS")
		)
		(fp_line
			(start 0.7874 -0.4064)
			(end 0.7874 0.4064)
			(stroke
				(width 0.1524)
				(type default)
			)
			(layer "F.SilkS")
		)
		(fp_line
			(start -0.67945 0.3048)
			(end -0.67945 -0.305054)
			(stroke
				(width 0.1)
				(type default)
			)
			(layer "F.Fab")
		)
		(fp_line
			(start -0.12065 0.3048)
			(end -0.67945 0.3048)
			(stroke
				(width 0.1)
				(type default)
			)
			(layer "F.Fab")
		)
		(fp_line
			(start 0.120396 0.3048)
			(end 0.120396 0.2794)
			(stroke
				(width 0.1)
				(type default)
			)
			(layer "F.Fab")
		)
		(fp_line
			(start 0.67945 0.3048)
			(end 0.120396 0.3048)
			(stroke
				(width 0.1)
				(type default)
			)
			(layer "F.Fab")
		)
		(fp_line
			(start -0.12065 0.2794)
			(end -0.12065 0.3048)
			(stroke
				(width 0.1)
				(type default)
			)
			(layer "F.Fab")
		)
		(fp_line
			(start 0.120396 0.2794)
			(end -0.12065 0.2794)
			(stroke
				(width 0.1)
				(type default)
			)
			(layer "F.Fab")
		)
		(fp_line
			(start -0.12065 -0.2794)
			(end 0.12065 -0.2794)
			(stroke
				(width 0.1)
				(type default)
			)
			(layer "F.Fab")
		)
		(fp_line
			(start 0.12065 -0.2794)
			(end 0.12065 -0.3048)
			(stroke
				(width 0.1)
				(type default)
			)
			(layer "F.Fab")
		)
		(fp_line
			(start 0.12065 -0.3048)
			(end 0.67945 -0.3048)
			(stroke
				(width 0.1)
				(type default)
			)
			(layer "F.Fab")
		)
		(fp_line
			(start 0.67945 -0.3048)
			(end 0.67945 0.3048)
			(stroke
				(width 0.1)
				(type default)
			)
			(layer "F.Fab")
		)
		(fp_line
			(start -0.67945 -0.305054)
			(end -0.12065 -0.305054)
			(stroke
				(width 0.1)
				(type default)
			)
			(layer "F.Fab")
		)
		(fp_line
			(start -0.12065 -0.305054)
			(end -0.12065 -0.2794)
			(stroke
				(width 0.1)
				(type default)
			)
			(layer "F.Fab")
		)
		(pad "1" smd circle
			(at -0.40005 0 270)
			(size 0 0)
			(layers "F.Cu" "F.Mask" "F.Paste")
			(net "GND")
		)
		(pad "2" smd circle
			(at 0.40005 0 270)
			(size 0 0)
			(layers "F.Cu" "F.Mask" "F.Paste")
			(net "PEX0_MODE_SEL4")
		)
	)
	(footprint ""
		(layer "F.Cu")
		(at 456.62088 -254.5969 -90)
		(property "Reference" "C4397"
			(at 0 0 270)
			(layer "F.SilkS")
			(hide yes)
			(effects
				(font
					(size 1.27 1.27)
				)
			)
		)
		(property "Value" ""
			(at 0 0 270)
			(layer "F.Fab")
			(effects
				(font
					(size 1.27 1.27)
				)
			)
		)
		(duplicate_pad_numbers_are_jumpers no)
		(fp_line
			(start -1.2954 0.5842)
			(end -1.2954 -0.5842)
			(stroke
				(width 0.1524)
				(type default)
			)
			(layer "F.SilkS")
		)
		(fp_line
			(start 1.2954 0.5842)
			(end -1.2954 0.5842)
			(stroke
				(width 0.1524)
				(type default)
			)
			(layer "F.SilkS")
		)
		(fp_line
			(start -1.2954 -0.5842)
			(end 1.2954 -0.5842)
			(stroke
				(width 0.1524)
				(type default)
			)
			(layer "F.SilkS")
		)
		(fp_line
			(start 1.2954 -0.5842)
			(end 1.2954 0.5842)
			(stroke
				(width 0.1524)
				(type default)
			)
			(layer "F.SilkS")
		)
		(fp_line
			(start -0.8636 0.4572)
			(end -0.8636 0.4064)
			(stroke
				(width 0.1)
				(type default)
			)
			(layer "F.Fab")
		)
		(fp_line
			(start 0.8636 0.4572)
			(end -0.8636 0.4572)
			(stroke
				(width 0.1)
				(type default)
			)
			(layer "F.Fab")
		)
		(fp_line
			(start -1.1938 0.4064)
			(end -1.1938 -0.4064)
			(stroke
				(width 0.1)
				(type default)
			)
			(layer "F.Fab")
		)
		(fp_line
			(start -0.8636 0.4064)
			(end -1.1938 0.4064)
			(stroke
				(width 0.1)
				(type default)
			)
			(layer "F.Fab")
		)
		(fp_line
			(start 0.8636 0.4064)
			(end 0.8636 0.4572)
			(stroke
				(width 0.1)
				(type default)
			)
			(layer "F.Fab")
		)
		(fp_line
			(start 1.1938 0.4064)
			(end 0.8636 0.4064)
			(stroke
				(width 0.1)
				(type default)
			)
			(layer "F.Fab")
		)
		(fp_line
			(start -1.1938 -0.4064)
			(end -0.8636 -0.4064)
			(stroke
				(width 0.1)
				(type default)
			)
			(layer "F.Fab")
		)
		(fp_line
			(start -0.8636 -0.4064)
			(end -0.8636 -0.4572)
			(stroke
				(width 0.1)
				(type default)
			)
			(layer "F.Fab")
		)
		(fp_line
			(start 0.8636 -0.4064)
			(end 1.1938 -0.4064)
			(stroke
				(width 0.1)
				(type default)
			)
			(layer "F.Fab")
		)
		(fp_line
			(start 1.1938 -0.4064)
			(end 1.1938 0.4064)
			(stroke
				(width 0.1)
				(type default)
			)
			(layer "F.Fab")
		)
		(fp_line
			(start -0.8636 -0.4572)
			(end 0.8636 -0.4572)
			(stroke
				(width 0.1)
				(type default)
			)
			(layer "F.Fab")
		)
		(fp_line
			(start 0.8636 -0.4572)
			(end 0.8636 -0.4064)
			(stroke
				(width 0.1)
				(type default)
			)
			(layer "F.Fab")
		)
		(pad "1" smd rect
			(at -0.7366 0 180)
			(size 0.7112 0.8128)
			(layers "F.Cu" "F.Mask" "F.Paste")
			(net "P1V25_SERDES_VDDPLL_PEX3_C3")
		)
		(pad "2" smd rect
			(at 0.7366 0 180)
			(size 0.7112 0.8128)
			(layers "F.Cu" "F.Mask" "F.Paste")
			(net "GND")
		)
	)
	(footprint ""
		(layer "F.Cu")
		(at 439.334148 -306.074572 90)
		(property "Reference" "R1442"
			(at 0 0 90)
			(layer "F.SilkS")
			(hide yes)
			(effects
				(font
					(size 1.27 1.27)
				)
			)
		)
		(property "Value" ""
			(at 0 0 90)
			(layer "F.Fab")
			(effects
				(font
					(size 1.27 1.27)
				)
			)
		)
		(duplicate_pad_numbers_are_jumpers no)
		(fp_line
			(start 0.7874 -0.4064)
			(end 0.7874 0.4064)
			(stroke
				(width 0.1524)
				(type default)
			)
			(layer "F.SilkS")
		)
		(fp_line
			(start -0.7874 -0.4064)
			(end 0.7874 -0.4064)
			(stroke
				(width 0.1524)
				(type default)
			)
			(layer "F.SilkS")
		)
		(fp_line
			(start 0.7874 0.4064)
			(end -0.7874 0.4064)
			(stroke
				(width 0.1524)
				(type default)
			)
			(layer "F.SilkS")
		)
		(fp_line
			(start -0.7874 0.4064)
			(end -0.7874 -0.4064)
			(stroke
				(width 0.1524)
				(type default)
			)
			(layer "F.SilkS")
		)
		(fp_line
			(start -0.12065 -0.305054)
			(end -0.12065 -0.2794)
			(stroke
				(width 0.1)
				(type default)
			)
			(layer "F.Fab")
		)
		(fp_line
			(start -0.67945 -0.305054)
			(end -0.12065 -0.305054)
			(stroke
				(width 0.1)
				(type default)
			)
			(layer "F.Fab")
		)
		(fp_line
			(start 0.67945 -0.3048)
			(end 0.67945 0.3048)
			(stroke
				(width 0.1)
				(type default)
			)
			(layer "F.Fab")
		)
		(fp_line
			(start 0.12065 -0.3048)
			(end 0.67945 -0.3048)
			(stroke
				(width 0.1)
				(type default)
			)
			(layer "F.Fab")
		)
		(fp_line
			(start 0.12065 -0.2794)
			(end 0.12065 -0.3048)
			(stroke
				(width 0.1)
				(type default)
			)
			(layer "F.Fab")
		)
		(fp_line
			(start -0.12065 -0.2794)
			(end 0.12065 -0.2794)
			(stroke
				(width 0.1)
				(type default)
			)
			(layer "F.Fab")
		)
		(fp_line
			(start 0.120396 0.2794)
			(end -0.12065 0.2794)
			(stroke
				(width 0.1)
				(type default)
			)
			(layer "F.Fab")
		)
		(fp_line
			(start -0.12065 0.2794)
			(end -0.12065 0.3048)
			(stroke
				(width 0.1)
				(type default)
			)
			(layer "F.Fab")
		)
		(fp_line
			(start 0.67945 0.3048)
			(end 0.120396 0.3048)
			(stroke
				(width 0.1)
				(type default)
			)
			(layer "F.Fab")
		)
		(fp_line
			(start 0.120396 0.3048)
			(end 0.120396 0.2794)
			(stroke
				(width 0.1)
				(type default)
			)
			(layer "F.Fab")
		)
		(fp_line
			(start -0.12065 0.3048)
			(end -0.67945 0.3048)
			(stroke
				(width 0.1)
				(type default)
			)
			(layer "F.Fab")
		)
		(fp_line
			(start -0.67945 0.3048)
			(end -0.67945 -0.305054)
			(stroke
				(width 0.1)
				(type default)
			)
			(layer "F.Fab")
		)
		(pad "1" smd circle
			(at -0.40005 0 90)
			(size 0 0)
			(layers "F.Cu" "F.Mask" "F.Paste")
			(net "PEX3_SPARE1")
		)
		(pad "2" smd circle
			(at 0.40005 0 90)
			(size 0 0)
			(layers "F.Cu" "F.Mask" "F.Paste")
			(net "P1V8_PEX")
		)
	)
	(footprint ""
		(layer "F.Cu")
		(at 212.71992 -15.649956 180)
		(property "Reference" "H131"
			(at -1.44018 2.69621 0)
			(unlocked yes)
			(layer "B.SilkS")
			(effects
				(font
					(size 0.7874 0.5842)
					(thickness 0.1524)
				)
				(justify left mirror)
			)
		)
		(property "Value" ""
			(at 0 0 180)
			(layer "F.Fab")
			(effects
				(font
					(size 1.27 1.27)
				)
			)
		)
		(duplicate_pad_numbers_are_jumpers no)
		(pad "1" thru_hole rect
			(at 0 0 180)
			(size 4.2164 5.0038)
			(drill 2.0066
				(offset 0.099822 0)
			)
			(layers "*.Cu" "*.Mask")
			(remove_unused_layers no)
			(net "Net_8532")
			(clearance -0.8509)
			(padstack
				(mode front_inner_back)
				(layer "Inner"
					(shape circle)
					(size 4.0132 4.0132)
					(clearance -0.7493)
				)
				(layer "B.Cu"
					(shape circle)
					(size 4.0132 4.0132)
					(clearance -0.7493)
				)
			)
		)
	)
	(footprint ""
		(layer "F.Cu")
		(at 238.909098 -27.04973 180)
		(property "Reference" "C2771"
			(at 0 0 180)
			(layer "F.SilkS")
			(hide yes)
			(effects
				(font
					(size 1.27 1.27)
				)
			)
		)
		(property "Value" ""
			(at 0 0 180)
			(layer "F.Fab")
			(effects
				(font
					(size 1.27 1.27)
				)
			)
		)
		(duplicate_pad_numbers_are_jumpers no)
		(fp_line
			(start 0.7874 0.4064)
			(end -0.7874 0.4064)
			(stroke
				(width 0.1524)
				(type default)
			)
			(layer "F.SilkS")
		)
		(fp_line
			(start 0.7874 -0.4064)
			(end 0.7874 0.4064)
			(stroke
				(width 0.1524)
				(type default)
			)
			(layer "F.SilkS")
		)
		(fp_line
			(start -0.7874 0.4064)
			(end -0.7874 -0.4064)
			(stroke
				(width 0.1524)
				(type default)
			)
			(layer "F.SilkS")
		)
		(fp_line
			(start -0.7874 -0.4064)
			(end 0.7874 -0.4064)
			(stroke
				(width 0.1524)
				(type default)
			)
			(layer "F.SilkS")
		)
		(fp_line
			(start 0.67945 0.3048)
			(end 0.120396 0.3048)
			(stroke
				(width 0.1)
				(type default)
			)
			(layer "F.Fab")
		)
		(fp_line
			(start 0.67945 -0.3048)
			(end 0.67945 0.3048)
			(stroke
				(width 0.1)
				(type default)
			)
			(layer "F.Fab")
		)
		(fp_line
			(start 0.12065 -0.2794)
			(end 0.12065 -0.3048)
			(stroke
				(width 0.1)
				(type default)
			)
			(layer "F.Fab")
		)
		(fp_line
			(start 0.12065 -0.3048)
			(end 0.67945 -0.3048)
			(stroke
				(width 0.1)
				(type default)
			)
			(layer "F.Fab")
		)
		(fp_line
			(start 0.120396 0.3048)
			(end 0.120396 0.2794)
			(stroke
				(width 0.1)
				(type default)
			)
			(layer "F.Fab")
		)
		(fp_line
			(start 0.120396 0.2794)
			(end -0.12065 0.2794)
			(stroke
				(width 0.1)
				(type default)
			)
			(layer "F.Fab")
		)
		(fp_line
			(start -0.12065 0.3048)
			(end -0.67945 0.3048)
			(stroke
				(width 0.1)
				(type default)
			)
			(layer "F.Fab")
		)
		(fp_line
			(start -0.12065 0.2794)
			(end -0.12065 0.3048)
			(stroke
				(width 0.1)
				(type default)
			)
			(layer "F.Fab")
		)
		(fp_line
			(start -0.12065 -0.2794)
			(end 0.12065 -0.2794)
			(stroke
				(width 0.1)
				(type default)
			)
			(layer "F.Fab")
		)
		(fp_line
			(start -0.12065 -0.305054)
			(end -0.12065 -0.2794)
			(stroke
				(width 0.1)
				(type default)
			)
			(layer "F.Fab")
		)
		(fp_line
			(start -0.67945 0.3048)
			(end -0.67945 -0.305054)
			(stroke
				(width 0.1)
				(type default)
			)
			(layer "F.Fab")
		)
		(fp_line
			(start -0.67945 -0.305054)
			(end -0.12065 -0.305054)
			(stroke
				(width 0.1)
				(type default)
			)
			(layer "F.Fab")
		)
		(pad "1" smd circle
			(at -0.40005 0 180)
			(size 0 0)
			(layers "F.Cu" "F.Mask" "F.Paste")
			(net "PRSNT_SSD8_R_N")
		)
		(pad "2" smd circle
			(at 0.40005 0 180)
			(size 0 0)
			(layers "F.Cu" "F.Mask" "F.Paste")
			(net "GND")
		)
	)
	(footprint ""
		(layer "F.Cu")
		(at 430.183544 -61.487812 180)
		(property "Reference" "R6025"
			(at 0 0 180)
			(layer "F.SilkS")
			(hide yes)
			(effects
				(font
					(size 1.27 1.27)
				)
			)
		)
		(property "Value" ""
			(at 0 0 180)
			(layer "F.Fab")
			(effects
				(font
					(size 1.27 1.27)
				)
			)
		)
		(duplicate_pad_numbers_are_jumpers no)
		(fp_line
			(start 0.7874 0.4064)
			(end -0.7874 0.4064)
			(stroke
				(width 0.1524)
				(type default)
			)
			(layer "F.SilkS")
		)
		(fp_line
			(start 0.7874 -0.4064)
			(end 0.7874 0.4064)
			(stroke
				(width 0.1524)
				(type default)
			)
			(layer "F.SilkS")
		)
		(fp_line
			(start -0.7874 0.4064)
			(end -0.7874 -0.4064)
			(stroke
				(width 0.1524)
				(type default)
			)
			(layer "F.SilkS")
		)
		(fp_line
			(start -0.7874 -0.4064)
			(end 0.7874 -0.4064)
			(stroke
				(width 0.1524)
				(type default)
			)
			(layer "F.SilkS")
		)
		(fp_line
			(start 0.67945 0.3048)
			(end 0.120396 0.3048)
			(stroke
				(width 0.1)
				(type default)
			)
			(layer "F.Fab")
		)
		(fp_line
			(start 0.67945 -0.3048)
			(end 0.67945 0.3048)
			(stroke
				(width 0.1)
				(type default)
			)
			(layer "F.Fab")
		)
		(fp_line
			(start 0.12065 -0.2794)
			(end 0.12065 -0.3048)
			(stroke
				(width 0.1)
				(type default)
			)
			(layer "F.Fab")
		)
		(fp_line
			(start 0.12065 -0.3048)
			(end 0.67945 -0.3048)
			(stroke
				(width 0.1)
				(type default)
			)
			(layer "F.Fab")
		)
		(fp_line
			(start 0.120396 0.3048)
			(end 0.120396 0.2794)
			(stroke
				(width 0.1)
				(type default)
			)
			(layer "F.Fab")
		)
		(fp_line
			(start 0.120396 0.2794)
			(end -0.12065 0.2794)
			(stroke
				(width 0.1)
				(type default)
			)
			(layer "F.Fab")
		)
		(fp_line
			(start -0.12065 0.3048)
			(end -0.67945 0.3048)
			(stroke
				(width 0.1)
				(type default)
			)
			(layer "F.Fab")
		)
		(fp_line
			(start -0.12065 0.2794)
			(end -0.12065 0.3048)
			(stroke
				(width 0.1)
				(type default)
			)
			(layer "F.Fab")
		)
		(fp_line
			(start -0.12065 -0.2794)
			(end 0.12065 -0.2794)
			(stroke
				(width 0.1)
				(type default)
			)
			(layer "F.Fab")
		)
		(fp_line
			(start -0.12065 -0.305054)
			(end -0.12065 -0.2794)
			(stroke
				(width 0.1)
				(type default)
			)
			(layer "F.Fab")
		)
		(fp_line
			(start -0.67945 0.3048)
			(end -0.67945 -0.305054)
			(stroke
				(width 0.1)
				(type default)
			)
			(layer "F.Fab")
		)
		(fp_line
			(start -0.67945 -0.305054)
			(end -0.12065 -0.305054)
			(stroke
				(width 0.1)
				(type default)
			)
			(layer "F.Fab")
		)
		(pad "1" smd circle
			(at -0.40005 0 180)
			(size 0 0)
			(layers "F.Cu" "F.Mask" "F.Paste")
			(net "PWRGD_P12V_SSD15_D")
		)
		(pad "2" smd circle
			(at 0.40005 0 180)
			(size 0 0)
			(layers "F.Cu" "F.Mask" "F.Paste")
			(net "PWRGD_P12V_SSD15_R")
		)
	)
	(footprint ""
		(layer "F.Cu")
		(at 16.85163 -124.120656 -90)
		(property "Reference" "PC452"
			(at 0 0 270)
			(layer "F.SilkS")
			(hide yes)
			(effects
				(font
					(size 1.27 1.27)
				)
			)
		)
		(property "Value" ""
			(at 0 0 270)
			(layer "F.Fab")
			(effects
				(font
					(size 1.27 1.27)
				)
			)
		)
		(duplicate_pad_numbers_are_jumpers no)
		(fp_line
			(start -0.7874 0.4064)
			(end -0.7874 -0.4064)
			(stroke
				(width 0.1524)
				(type default)
			)
			(layer "F.SilkS")
		)
		(fp_line
			(start 0.7874 0.4064)
			(end -0.7874 0.4064)
			(stroke
				(width 0.1524)
				(type default)
			)
			(layer "F.SilkS")
		)
		(fp_line
			(start -0.7874 -0.4064)
			(end 0.7874 -0.4064)
			(stroke
				(width 0.1524)
				(type default)
			)
			(layer "F.SilkS")
		)
		(fp_line
			(start 0.7874 -0.4064)
			(end 0.7874 0.4064)
			(stroke
				(width 0.1524)
				(type default)
			)
			(layer "F.SilkS")
		)
		(fp_line
			(start -0.67945 0.3048)
			(end -0.67945 -0.305054)
			(stroke
				(width 0.1)
				(type default)
			)
			(layer "F.Fab")
		)
		(fp_line
			(start -0.12065 0.3048)
			(end -0.67945 0.3048)
			(stroke
				(width 0.1)
				(type default)
			)
			(layer "F.Fab")
		)
		(fp_line
			(start 0.120396 0.3048)
			(end 0.120396 0.2794)
			(stroke
				(width 0.1)
				(type default)
			)
			(layer "F.Fab")
		)
		(fp_line
			(start 0.67945 0.3048)
			(end 0.120396 0.3048)
			(stroke
				(width 0.1)
				(type default)
			)
			(layer "F.Fab")
		)
		(fp_line
			(start -0.12065 0.2794)
			(end -0.12065 0.3048)
			(stroke
				(width 0.1)
				(type default)
			)
			(layer "F.Fab")
		)
		(fp_line
			(start 0.120396 0.2794)
			(end -0.12065 0.2794)
			(stroke
				(width 0.1)
				(type default)
			)
			(layer "F.Fab")
		)
		(fp_line
			(start -0.12065 -0.2794)
			(end 0.12065 -0.2794)
			(stroke
				(width 0.1)
				(type default)
			)
			(layer "F.Fab")
		)
		(fp_line
			(start 0.12065 -0.2794)
			(end 0.12065 -0.3048)
			(stroke
				(width 0.1)
				(type default)
			)
			(layer "F.Fab")
		)
		(fp_line
			(start 0.12065 -0.3048)
			(end 0.67945 -0.3048)
			(stroke
				(width 0.1)
				(type default)
			)
			(layer "F.Fab")
		)
		(fp_line
			(start 0.67945 -0.3048)
			(end 0.67945 0.3048)
			(stroke
				(width 0.1)
				(type default)
			)
			(layer "F.Fab")
		)
		(fp_line
			(start -0.67945 -0.305054)
			(end -0.12065 -0.305054)
			(stroke
				(width 0.1)
				(type default)
			)
			(layer "F.Fab")
		)
		(fp_line
			(start -0.12065 -0.305054)
			(end -0.12065 -0.2794)
			(stroke
				(width 0.1)
				(type default)
			)
			(layer "F.Fab")
		)
		(pad "1" smd circle
			(at -0.40005 0 270)
			(size 0 0)
			(layers "F.Cu" "F.Mask" "F.Paste")
			(net "P3V3_NIC0")
		)
		(pad "2" smd circle
			(at 0.40005 0 270)
			(size 0 0)
			(layers "F.Cu" "F.Mask" "F.Paste")
			(net "GND")
		)
	)
	(footprint ""
		(layer "F.Cu")
		(at 107.518454 -120.53824 180)
		(property "Reference" "R5861"
			(at 0 0 180)
			(layer "F.SilkS")
			(hide yes)
			(effects
				(font
					(size 1.27 1.27)
				)
			)
		)
		(property "Value" ""
			(at 0 0 180)
			(layer "F.Fab")
			(effects
				(font
					(size 1.27 1.27)
				)
			)
		)
		(duplicate_pad_numbers_are_jumpers no)
		(fp_line
			(start 0.7874 0.4064)
			(end -0.7874 0.4064)
			(stroke
				(width 0.1524)
				(type default)
			)
			(layer "F.SilkS")
		)
		(fp_line
			(start 0.7874 -0.4064)
			(end 0.7874 0.4064)
			(stroke
				(width 0.1524)
				(type default)
			)
			(layer "F.SilkS")
		)
		(fp_line
			(start -0.7874 0.4064)
			(end -0.7874 -0.4064)
			(stroke
				(width 0.1524)
				(type default)
			)
			(layer "F.SilkS")
		)
		(fp_line
			(start -0.7874 -0.4064)
			(end 0.7874 -0.4064)
			(stroke
				(width 0.1524)
				(type default)
			)
			(layer "F.SilkS")
		)
		(fp_line
			(start 0.67945 0.3048)
			(end 0.120396 0.3048)
			(stroke
				(width 0.1)
				(type default)
			)
			(layer "F.Fab")
		)
		(fp_line
			(start 0.67945 -0.3048)
			(end 0.67945 0.3048)
			(stroke
				(width 0.1)
				(type default)
			)
			(layer "F.Fab")
		)
		(fp_line
			(start 0.12065 -0.2794)
			(end 0.12065 -0.3048)
			(stroke
				(width 0.1)
				(type default)
			)
			(layer "F.Fab")
		)
		(fp_line
			(start 0.12065 -0.3048)
			(end 0.67945 -0.3048)
			(stroke
				(width 0.1)
				(type default)
			)
			(layer "F.Fab")
		)
		(fp_line
			(start 0.120396 0.3048)
			(end 0.120396 0.2794)
			(stroke
				(width 0.1)
				(type default)
			)
			(layer "F.Fab")
		)
		(fp_line
			(start 0.120396 0.2794)
			(end -0.12065 0.2794)
			(stroke
				(width 0.1)
				(type default)
			)
			(layer "F.Fab")
		)
		(fp_line
			(start -0.12065 0.3048)
			(end -0.67945 0.3048)
			(stroke
				(width 0.1)
				(type default)
			)
			(layer "F.Fab")
		)
		(fp_line
			(start -0.12065 0.2794)
			(end -0.12065 0.3048)
			(stroke
				(width 0.1)
				(type default)
			)
			(layer "F.Fab")
		)
		(fp_line
			(start -0.12065 -0.2794)
			(end 0.12065 -0.2794)
			(stroke
				(width 0.1)
				(type default)
			)
			(layer "F.Fab")
		)
		(fp_line
			(start -0.12065 -0.305054)
			(end -0.12065 -0.2794)
			(stroke
				(width 0.1)
				(type default)
			)
			(layer "F.Fab")
		)
		(fp_line
			(start -0.67945 0.3048)
			(end -0.67945 -0.305054)
			(stroke
				(width 0.1)
				(type default)
			)
			(layer "F.Fab")
		)
		(fp_line
			(start -0.67945 -0.305054)
			(end -0.12065 -0.305054)
			(stroke
				(width 0.1)
				(type default)
			)
			(layer "F.Fab")
		)
		(pad "1" smd circle
			(at -0.40005 0 180)
			(size 0 0)
			(layers "F.Cu" "F.Mask" "F.Paste")
			(net "P5V_AUX")
		)
		(pad "2" smd circle
			(at 0.40005 0 180)
			(size 0 0)
			(layers "F.Cu" "F.Mask" "F.Paste")
			(net "P3V3_NIC1_PG_G2")
		)
	)
	(footprint ""
		(layer "F.Cu")
		(at 172.081444 -157.8356)
		(property "Reference" "R150"
			(at 0 0 0)
			(layer "F.SilkS")
			(hide yes)
			(effects
				(font
					(size 1.27 1.27)
				)
			)
		)
		(property "Value" ""
			(at 0 0 0)
			(layer "F.Fab")
			(effects
				(font
					(size 1.27 1.27)
				)
			)
		)
		(duplicate_pad_numbers_are_jumpers no)
		(fp_line
			(start -0.7874 -0.4064)
			(end 0.7874 -0.4064)
			(stroke
				(width 0.1524)
				(type default)
			)
			(layer "F.SilkS")
		)
		(fp_line
			(start -0.7874 0.4064)
			(end -0.7874 -0.4064)
			(stroke
				(width 0.1524)
				(type default)
			)
			(layer "F.SilkS")
		)
		(fp_line
			(start 0.7874 -0.4064)
			(end 0.7874 0.4064)
			(stroke
				(width 0.1524)
				(type default)
			)
			(layer "F.SilkS")
		)
		(fp_line
			(start 0.7874 0.4064)
			(end -0.7874 0.4064)
			(stroke
				(width 0.1524)
				(type default)
			)
			(layer "F.SilkS")
		)
		(fp_line
			(start -0.67945 -0.305054)
			(end -0.12065 -0.305054)
			(stroke
				(width 0.1)
				(type default)
			)
			(layer "F.Fab")
		)
		(fp_line
			(start -0.67945 0.3048)
			(end -0.67945 -0.305054)
			(stroke
				(width 0.1)
				(type default)
			)
			(layer "F.Fab")
		)
		(fp_line
			(start -0.12065 -0.305054)
			(end -0.12065 -0.2794)
			(stroke
				(width 0.1)
				(type default)
			)
			(layer "F.Fab")
		)
		(fp_line
			(start -0.12065 -0.2794)
			(end 0.12065 -0.2794)
			(stroke
				(width 0.1)
				(type default)
			)
			(layer "F.Fab")
		)
		(fp_line
			(start -0.12065 0.2794)
			(end -0.12065 0.3048)
			(stroke
				(width 0.1)
				(type default)
			)
			(layer "F.Fab")
		)
		(fp_line
			(start -0.12065 0.3048)
			(end -0.67945 0.3048)
			(stroke
				(width 0.1)
				(type default)
			)
			(layer "F.Fab")
		)
		(fp_line
			(start 0.120396 0.2794)
			(end -0.12065 0.2794)
			(stroke
				(width 0.1)
				(type default)
			)
			(layer "F.Fab")
		)
		(fp_line
			(start 0.120396 0.3048)
			(end 0.120396 0.2794)
			(stroke
				(width 0.1)
				(type default)
			)
			(layer "F.Fab")
		)
		(fp_line
			(start 0.12065 -0.3048)
			(end 0.67945 -0.3048)
			(stroke
				(width 0.1)
				(type default)
			)
			(layer "F.Fab")
		)
		(fp_line
			(start 0.12065 -0.2794)
			(end 0.12065 -0.3048)
			(stroke
				(width 0.1)
				(type default)
			)
			(layer "F.Fab")
		)
		(fp_line
			(start 0.67945 -0.3048)
			(end 0.67945 0.3048)
			(stroke
				(width 0.1)
				(type default)
			)
			(layer "F.Fab")
		)
		(fp_line
			(start 0.67945 0.3048)
			(end 0.120396 0.3048)
			(stroke
				(width 0.1)
				(type default)
			)
			(layer "F.Fab")
		)
		(pad "1" smd circle
			(at -0.40005 0)
			(size 0 0)
			(layers "F.Cu" "F.Mask" "F.Paste")
			(net "RST_NIC2_PERST3_R_N")
		)
		(pad "2" smd circle
			(at 0.40005 0)
			(size 0 0)
			(layers "F.Cu" "F.Mask" "F.Paste")
			(net "RST_HP_NIC2_BUF_N")
		)
	)
	(footprint ""
		(layer "F.Cu")
		(at 460.19974 -288.140648)
		(property "Reference" "PC276"
			(at 0 0 0)
			(layer "F.SilkS")
			(hide yes)
			(effects
				(font
					(size 1.27 1.27)
				)
			)
		)
		(property "Value" ""
			(at 0 0 0)
			(layer "F.Fab")
			(effects
				(font
					(size 1.27 1.27)
				)
			)
		)
		(duplicate_pad_numbers_are_jumpers no)
		(fp_line
			(start -0.7874 -0.4064)
			(end 0.7874 -0.4064)
			(stroke
				(width 0.1524)
				(type default)
			)
			(layer "F.SilkS")
		)
		(fp_line
			(start -0.7874 0.4064)
			(end -0.7874 -0.4064)
			(stroke
				(width 0.1524)
				(type default)
			)
			(layer "F.SilkS")
		)
		(fp_line
			(start 0.7874 -0.4064)
			(end 0.7874 0.4064)
			(stroke
				(width 0.1524)
				(type default)
			)
			(layer "F.SilkS")
		)
		(fp_line
			(start 0.7874 0.4064)
			(end -0.7874 0.4064)
			(stroke
				(width 0.1524)
				(type default)
			)
			(layer "F.SilkS")
		)
		(fp_line
			(start -0.67945 -0.305054)
			(end -0.12065 -0.305054)
			(stroke
				(width 0.1)
				(type default)
			)
			(layer "F.Fab")
		)
		(fp_line
			(start -0.67945 0.3048)
			(end -0.67945 -0.305054)
			(stroke
				(width 0.1)
				(type default)
			)
			(layer "F.Fab")
		)
		(fp_line
			(start -0.12065 -0.305054)
			(end -0.12065 -0.2794)
			(stroke
				(width 0.1)
				(type default)
			)
			(layer "F.Fab")
		)
		(fp_line
			(start -0.12065 -0.2794)
			(end 0.12065 -0.2794)
			(stroke
				(width 0.1)
				(type default)
			)
			(layer "F.Fab")
		)
		(fp_line
			(start -0.12065 0.2794)
			(end -0.12065 0.3048)
			(stroke
				(width 0.1)
				(type default)
			)
			(layer "F.Fab")
		)
		(fp_line
			(start -0.12065 0.3048)
			(end -0.67945 0.3048)
			(stroke
				(width 0.1)
				(type default)
			)
			(layer "F.Fab")
		)
		(fp_line
			(start 0.120396 0.2794)
			(end -0.12065 0.2794)
			(stroke
				(width 0.1)
				(type default)
			)
			(layer "F.Fab")
		)
		(fp_line
			(start 0.120396 0.3048)
			(end 0.120396 0.2794)
			(stroke
				(width 0.1)
				(type default)
			)
			(layer "F.Fab")
		)
		(fp_line
			(start 0.12065 -0.3048)
			(end 0.67945 -0.3048)
			(stroke
				(width 0.1)
				(type default)
			)
			(layer "F.Fab")
		)
		(fp_line
			(start 0.12065 -0.2794)
			(end 0.12065 -0.3048)
			(stroke
				(width 0.1)
				(type default)
			)
			(layer "F.Fab")
		)
		(fp_line
			(start 0.67945 -0.3048)
			(end 0.67945 0.3048)
			(stroke
				(width 0.1)
				(type default)
			)
			(layer "F.Fab")
		)
		(fp_line
			(start 0.67945 0.3048)
			(end 0.120396 0.3048)
			(stroke
				(width 0.1)
				(type default)
			)
			(layer "F.Fab")
		)
		(pad "1" smd circle
			(at -0.40005 0)
			(size 0 0)
			(layers "F.Cu" "F.Mask" "F.Paste")
			(net "P1V25_PEX3_R")
		)
		(pad "2" smd circle
			(at 0.40005 0)
			(size 0 0)
			(layers "F.Cu" "F.Mask" "F.Paste")
			(net "GND")
		)
	)
	(footprint ""
		(layer "F.Cu")
		(at 79.683356 -238.6076)
		(property "Reference" "J73"
			(at -1.4224 -4.562348 0)
			(unlocked yes)
			(layer "F.SilkS")
			(effects
				(font
					(size 0.7874 0.5842)
					(thickness 0.1524)
				)
				(justify left)
			)
		)
		(property "Value" ""
			(at 0 0 0)
			(layer "F.Fab")
			(effects
				(font
					(size 1.27 1.27)
				)
			)
		)
		(duplicate_pad_numbers_are_jumpers no)
		(fp_line
			(start -1.27 -3.81)
			(end 1.27 -3.81)
			(stroke
				(width 0.1524)
				(type default)
			)
			(layer "F.SilkS")
		)
		(fp_line
			(start -1.27 -0.7747)
			(end -1.27 -3.81)
			(stroke
				(width 0.1524)
				(type default)
			)
			(layer "F.SilkS")
		)
		(fp_line
			(start -1.27 3.81)
			(end -1.27 0.7747)
			(stroke
				(width 0.1524)
				(type default)
			)
			(layer "F.SilkS")
		)
		(fp_line
			(start 1.27 -3.81)
			(end 1.27 -3.3147)
			(stroke
				(width 0.1524)
				(type default)
			)
			(layer "F.SilkS")
		)
		(fp_line
			(start 1.27 -1.7653)
			(end 1.27 1.7653)
			(stroke
				(width 0.1524)
				(type default)
			)
			(layer "F.SilkS")
		)
		(fp_line
			(start 1.27 3.3147)
			(end 1.27 3.81)
			(stroke
				(width 0.1524)
				(type default)
			)
			(layer "F.SilkS")
		)
		(fp_line
			(start 1.27 3.81)
			(end -1.27 3.81)
			(stroke
				(width 0.1524)
				(type default)
			)
			(layer "F.SilkS")
		)
		(fp_poly
			(pts
				(xy 4.3942 -3.048) (xy 4.3942 -2.032) (xy 3.3782 -2.54)
			)
			(stroke
				(width 0)
				(type default)
			)
			(fill yes)
			(layer "F.SilkS")
		)
		(fp_line
			(start -1.27 -3.81)
			(end -1.27 3.81)
			(stroke
				(width 0.1)
				(type default)
			)
			(layer "F.Fab")
		)
		(fp_line
			(start -1.27 3.81)
			(end 1.27 3.81)
			(stroke
				(width 0.1)
				(type default)
			)
			(layer "F.Fab")
		)
		(fp_line
			(start 1.27 -3.81)
			(end -1.27 -3.81)
			(stroke
				(width 0.1)
				(type default)
			)
			(layer "F.Fab")
		)
		(fp_line
			(start 1.27 3.81)
			(end 1.27 -3.81)
			(stroke
				(width 0.1)
				(type default)
			)
			(layer "F.Fab")
		)
		(fp_poly
			(pts
				(xy 4.3942 -3.048) (xy 4.3942 -2.032) (xy 3.3782 -2.54)
			)
			(stroke
				(width 0)
				(type default)
			)
			(fill yes)
			(layer "F.Fab")
		)
		(fp_text user "3"
			(at 3.921252 2.54 90)
			(unlocked yes)
			(layer "F.SilkS")
			(effects
				(font
					(size 0.7874 0.5842)
					(thickness 0.1524)
				)
			)
		)
		(fp_text user "3"
			(at 3.921252 2.54 90)
			(unlocked yes)
			(layer "F.Fab")
			(effects
				(font
					(size 0.7874 0.5842)
					(thickness 0.1524)
				)
			)
		)
		(pad "1" smd rect
			(at 1.459992 -2.54 90)
			(size 1.27 3.429)
			(layers "F.Cu" "F.Mask" "F.Paste")
			(net "GND")
		)
		(pad "2" smd rect
			(at -1.459992 0 90)
			(size 1.27 3.429)
			(layers "F.Cu" "F.Mask" "F.Paste")
			(net "UART_PEX0_CLI_BUF_R1_TX")
		)
		(pad "3" smd rect
			(at 1.459992 2.54 90)
			(size 1.27 3.429)
			(layers "F.Cu" "F.Mask" "F.Paste")
			(net "UART_PEX0_CLI_R1_RX")
		)
	)
	(footprint ""
		(layer "F.Cu")
		(at 399.161254 -169.23385 180)
		(property "Reference" "C948"
			(at 0 0 180)
			(layer "F.SilkS")
			(hide yes)
			(effects
				(font
					(size 1.27 1.27)
				)
			)
		)
		(property "Value" ""
			(at 0 0 180)
			(layer "F.Fab")
			(effects
				(font
					(size 1.27 1.27)
				)
			)
		)
		(duplicate_pad_numbers_are_jumpers no)
		(fp_line
			(start 0.7874 0.4064)
			(end -0.7874 0.4064)
			(stroke
				(width 0.1524)
				(type default)
			)
			(layer "F.SilkS")
		)
		(fp_line
			(start 0.7874 -0.4064)
			(end 0.7874 0.4064)
			(stroke
				(width 0.1524)
				(type default)
			)
			(layer "F.SilkS")
		)
		(fp_line
			(start -0.7874 0.4064)
			(end -0.7874 -0.4064)
			(stroke
				(width 0.1524)
				(type default)
			)
			(layer "F.SilkS")
		)
		(fp_line
			(start -0.7874 -0.4064)
			(end 0.7874 -0.4064)
			(stroke
				(width 0.1524)
				(type default)
			)
			(layer "F.SilkS")
		)
		(fp_line
			(start 0.67945 0.3048)
			(end 0.120396 0.3048)
			(stroke
				(width 0.1)
				(type default)
			)
			(layer "F.Fab")
		)
		(fp_line
			(start 0.67945 -0.3048)
			(end 0.67945 0.3048)
			(stroke
				(width 0.1)
				(type default)
			)
			(layer "F.Fab")
		)
		(fp_line
			(start 0.12065 -0.2794)
			(end 0.12065 -0.3048)
			(stroke
				(width 0.1)
				(type default)
			)
			(layer "F.Fab")
		)
		(fp_line
			(start 0.12065 -0.3048)
			(end 0.67945 -0.3048)
			(stroke
				(width 0.1)
				(type default)
			)
			(layer "F.Fab")
		)
		(fp_line
			(start 0.120396 0.3048)
			(end 0.120396 0.2794)
			(stroke
				(width 0.1)
				(type default)
			)
			(layer "F.Fab")
		)
		(fp_line
			(start 0.120396 0.2794)
			(end -0.12065 0.2794)
			(stroke
				(width 0.1)
				(type default)
			)
			(layer "F.Fab")
		)
		(fp_line
			(start -0.12065 0.3048)
			(end -0.67945 0.3048)
			(stroke
				(width 0.1)
				(type default)
			)
			(layer "F.Fab")
		)
		(fp_line
			(start -0.12065 0.2794)
			(end -0.12065 0.3048)
			(stroke
				(width 0.1)
				(type default)
			)
			(layer "F.Fab")
		)
		(fp_line
			(start -0.12065 -0.2794)
			(end 0.12065 -0.2794)
			(stroke
				(width 0.1)
				(type default)
			)
			(layer "F.Fab")
		)
		(fp_line
			(start -0.12065 -0.305054)
			(end -0.12065 -0.2794)
			(stroke
				(width 0.1)
				(type default)
			)
			(layer "F.Fab")
		)
		(fp_line
			(start -0.67945 0.3048)
			(end -0.67945 -0.305054)
			(stroke
				(width 0.1)
				(type default)
			)
			(layer "F.Fab")
		)
		(fp_line
			(start -0.67945 -0.305054)
			(end -0.12065 -0.305054)
			(stroke
				(width 0.1)
				(type default)
			)
			(layer "F.Fab")
		)
		(pad "1" smd circle
			(at -0.40005 0 180)
			(size 0 0)
			(layers "F.Cu" "F.Mask" "F.Paste")
			(net "P3V3_AUX")
		)
		(pad "2" smd circle
			(at 0.40005 0 180)
			(size 0 0)
			(layers "F.Cu" "F.Mask" "F.Paste")
			(net "GND")
		)
	)
	(footprint ""
		(layer "F.Cu")
		(at 261.84987 -270.89989)
		(property "Reference" "H87"
			(at -6.03758 -7.57301 0)
			(unlocked yes)
			(layer "F.SilkS")
			(effects
				(font
					(size 0.7874 0.5842)
					(thickness 0.1524)
				)
				(justify left)
			)
		)
		(property "Value" ""
			(at 0 0 0)
			(layer "F.Fab")
			(effects
				(font
					(size 1.27 1.27)
				)
			)
		)
		(duplicate_pad_numbers_are_jumpers no)
		(fp_arc
			(start 7.956804 -0.829056)
			(mid 7.989153 -0.415088)
			(end 7.999984 0)
			(stroke
				(width 0.1524)
				(type default)
			)
			(layer "F.SilkS")
		)
		(fp_arc
			(start 7.999984 0)
			(mid -7.434041 2.956443)
			(end 5.815076 -5.49402)
			(stroke
				(width 0.1524)
				(type default)
			)
			(layer "F.SilkS")
		)
		(fp_arc
			(start -7.978902 0.572262)
			(mid -6.692786 -4.381853)
			(end -2.666746 -7.542276)
			(stroke
				(width 0.1524)
				(type default)
			)
			(layer "B.SilkS")
		)
		(fp_arc
			(start 1.305052 -7.892796)
			(mid 3.864626 -7.004714)
			(end 5.980938 -5.313172)
			(stroke
				(width 0.1524)
				(type default)
			)
			(layer "B.SilkS")
		)
		(fp_arc
			(start 7.90702 -1.216914)
			(mid 7.976737 -0.610232)
			(end 7.999984 0)
			(stroke
				(width 0.1524)
				(type default)
			)
			(layer "B.SilkS")
		)
		(fp_arc
			(start 7.999984 0)
			(mid 2.208063 7.688973)
			(end -6.780784 4.244086)
			(stroke
				(width 0.1524)
				(type default)
			)
			(layer "B.SilkS")
		)
		(fp_circle
			(center 0 0)
			(end 7.999984 0)
			(stroke
				(width 0.1)
				(type default)
			)
			(fill no)
			(layer "B.Fab")
		)
		(fp_circle
			(center 0 0)
			(end 7.999984 0)
			(stroke
				(width 0.1)
				(type default)
			)
			(fill no)
			(layer "F.Fab")
		)
		(pad "" np_thru_hole circle
			(at 0 0)
			(size 4.5212 4.5212)
			(drill 4.5212)
			(layers "*.Cu" "*.Mask")
			(clearance 0.381)
			(thermal_gap 0.381)
		)
		(pad "2" thru_hole circle
			(at 3.6322 0)
			(size 0.762 0.762)
			(drill 0.5588)
			(layers "*.Cu" "*.Mask")
			(remove_unused_layers no)
			(net "GND")
			(clearance 0.1524)
			(thermal_gap 0.1524)
		)
		(pad "3" thru_hole circle
			(at 2.568448 -2.568448)
			(size 0.762 0.762)
			(drill 0.5588)
			(layers "*.Cu" "*.Mask")
			(remove_unused_layers no)
			(net "GND")
			(clearance 0.1524)
			(thermal_gap 0.1524)
		)
		(pad "4" thru_hole circle
			(at 0 -3.6322)
			(size 0.762 0.762)
			(drill 0.5588)
			(layers "*.Cu" "*.Mask")
			(remove_unused_layers no)
			(net "GND")
			(clearance 0.1524)
			(thermal_gap 0.1524)
		)
		(pad "5" thru_hole circle
			(at -2.568448 -2.568448)
			(size 0.762 0.762)
			(drill 0.5588)
			(layers "*.Cu" "*.Mask")
			(remove_unused_layers no)
			(net "GND")
			(clearance 0.1524)
			(thermal_gap 0.1524)
		)
		(pad "6" thru_hole circle
			(at -3.6322 0)
			(size 0.762 0.762)
			(drill 0.5588)
			(layers "*.Cu" "*.Mask")
			(remove_unused_layers no)
			(net "GND")
			(clearance 0.1524)
			(thermal_gap 0.1524)
		)
		(pad "7" thru_hole circle
			(at -2.568448 2.568448)
			(size 0.762 0.762)
			(drill 0.5588)
			(layers "*.Cu" "*.Mask")
			(remove_unused_layers no)
			(net "GND")
			(clearance 0.1524)
			(thermal_gap 0.1524)
		)
		(pad "8" thru_hole circle
			(at 0 3.6322)
			(size 0.762 0.762)
			(drill 0.5588)
			(layers "*.Cu" "*.Mask")
			(remove_unused_layers no)
			(net "GND")
			(clearance 0.1524)
			(thermal_gap 0.1524)
		)
		(pad "9" thru_hole circle
			(at 2.568448 2.568448)
			(size 0.762 0.762)
			(drill 0.5588)
			(layers "*.Cu" "*.Mask")
			(remove_unused_layers no)
			(net "GND")
			(clearance 0.1524)
			(thermal_gap 0.1524)
		)
		(zone
			(layer "F.Cu")
			(hatch none 0.5)
			(connect_pads
				(clearance 0)
			)
			(min_thickness 0.25)
			(keepout
				(tracks not_allowed)
				(vias allowed)
				(pads allowed)
				(copperpour not_allowed)
				(footprints allowed)
			)
			(placement
				(enabled no)
				(sheetname "")
			)
			(fill
				(thermal_gap 0.5)
				(thermal_bridge_width 0.5)
				(island_removal_mode 0)
			)
			(polygon
				(pts
					(arc
						(start 261.84987 -262.899906)
						(mid 253.849886 -270.89989)
						(end 261.84987 -278.899874)
					)
					(arc
						(start 261.84987 -275.64969)
						(mid 257.10007 -270.89989)
						(end 261.84987 -266.15009)
					)
				)
			)
		)
		(zone
			(layer "F.Cu")
			(hatch none 0.5)
			(connect_pads
				(clearance 0)
			)
			(min_thickness 0.25)
			(keepout
				(tracks not_allowed)
				(vias allowed)
				(pads allowed)
				(copperpour not_allowed)
				(footprints allowed)
			)
			(placement
				(enabled no)
				(sheetname "")
			)
			(fill
				(thermal_gap 0.5)
				(thermal_bridge_width 0.5)
				(island_removal_mode 0)
			)
			(polygon
				(pts
					(arc
						(start 261.84987 -262.899906)
						(mid 269.849854 -270.89989)
						(end 261.84987 -278.899874)
					)
					(arc
						(start 261.84987 -275.64969)
						(mid 266.59967 -270.89989)
						(end 261.84987 -266.15009)
					)
				)
			)
		)
		(zone
			(layers "F.Cu" "B.Cu" "In1.Cu" "In2.Cu" "In3.Cu" "In4.Cu" "In5.Cu" "In6.Cu"
				"In7.Cu" "In8.Cu" "In9.Cu" "In10.Cu" "In11.Cu" "In12.Cu" "In13.Cu" "In14.Cu"
				"In15.Cu" "In16.Cu"
			)
			(hatch none 0.5)
			(connect_pads
				(clearance 0)
			)
			(min_thickness 0.25)
			(keepout
				(tracks not_allowed)
				(vias allowed)
				(pads allowed)
				(copperpour not_allowed)
				(footprints allowed)
			)
			(placement
				(enabled no)
				(sheetname "")
			)
			(fill
				(thermal_gap 0.5)
				(thermal_bridge_width 0.5)
				(island_removal_mode 0)
			)
			(polygon
				(pts
					(arc
						(start 264.61593 -270.89989)
						(mid 259.08381 -270.89989)
						(end 264.61593 -270.89989)
					)
				)
			)
		)
		(zone
			(layer "B.Cu")
			(hatch none 0.5)
			(connect_pads
				(clearance 0)
			)
			(min_thickness 0.25)
			(keepout
				(tracks not_allowed)
				(vias allowed)
				(pads allowed)
				(copperpour not_allowed)
				(footprints allowed)
			)
			(placement
				(enabled no)
				(sheetname "")
			)
			(fill
				(thermal_gap 0.5)
				(thermal_bridge_width 0.5)
				(island_removal_mode 0)
			)
			(polygon
				(pts
					(arc
						(start 261.84987 -265.89609)
						(mid 256.84607 -270.89989)
						(end 261.84987 -275.90369)
					)
					(arc
						(start 261.84987 -275.42109)
						(mid 257.32867 -270.89989)
						(end 261.84987 -266.37869)
					)
				)
			)
		)
		(zone
			(layer "B.Cu")
			(hatch none 0.5)
			(connect_pads
				(clearance 0)
			)
			(min_thickness 0.25)
			(keepout
				(tracks not_allowed)
				(vias allowed)
				(pads allowed)
				(copperpour not_allowed)
				(footprints allowed)
			)
			(placement
				(enabled no)
				(sheetname "")
			)
			(fill
				(thermal_gap 0.5)
				(thermal_bridge_width 0.5)
				(island_removal_mode 0)
			)
			(polygon
				(pts
					(arc
						(start 261.84987 -265.89609)
						(mid 266.85367 -270.89989)
						(end 261.84987 -275.90369)
					)
					(arc
						(start 261.84987 -275.42109)
						(mid 266.37107 -270.89989)
						(end 261.84987 -266.37869)
					)
				)
			)
		)
	)
	(footprint ""
		(layer "F.Cu")
		(at 84.709 -26.03373)
		(property "Reference" "R4058"
			(at 0 0 0)
			(layer "F.SilkS")
			(hide yes)
			(effects
				(font
					(size 1.27 1.27)
				)
			)
		)
		(property "Value" ""
			(at 0 0 0)
			(layer "F.Fab")
			(effects
				(font
					(size 1.27 1.27)
				)
			)
		)
		(duplicate_pad_numbers_are_jumpers no)
		(fp_line
			(start -0.7874 -0.4064)
			(end 0.7874 -0.4064)
			(stroke
				(width 0.1524)
				(type default)
			)
			(layer "F.SilkS")
		)
		(fp_line
			(start -0.7874 0.4064)
			(end -0.7874 -0.4064)
			(stroke
				(width 0.1524)
				(type default)
			)
			(layer "F.SilkS")
		)
		(fp_line
			(start 0.7874 -0.4064)
			(end 0.7874 0.4064)
			(stroke
				(width 0.1524)
				(type default)
			)
			(layer "F.SilkS")
		)
		(fp_line
			(start 0.7874 0.4064)
			(end -0.7874 0.4064)
			(stroke
				(width 0.1524)
				(type default)
			)
			(layer "F.SilkS")
		)
		(fp_line
			(start -0.67945 -0.305054)
			(end -0.12065 -0.305054)
			(stroke
				(width 0.1)
				(type default)
			)
			(layer "F.Fab")
		)
		(fp_line
			(start -0.67945 0.3048)
			(end -0.67945 -0.305054)
			(stroke
				(width 0.1)
				(type default)
			)
			(layer "F.Fab")
		)
		(fp_line
			(start -0.12065 -0.305054)
			(end -0.12065 -0.2794)
			(stroke
				(width 0.1)
				(type default)
			)
			(layer "F.Fab")
		)
		(fp_line
			(start -0.12065 -0.2794)
			(end 0.12065 -0.2794)
			(stroke
				(width 0.1)
				(type default)
			)
			(layer "F.Fab")
		)
		(fp_line
			(start -0.12065 0.2794)
			(end -0.12065 0.3048)
			(stroke
				(width 0.1)
				(type default)
			)
			(layer "F.Fab")
		)
		(fp_line
			(start -0.12065 0.3048)
			(end -0.67945 0.3048)
			(stroke
				(width 0.1)
				(type default)
			)
			(layer "F.Fab")
		)
		(fp_line
			(start 0.120396 0.2794)
			(end -0.12065 0.2794)
			(stroke
				(width 0.1)
				(type default)
			)
			(layer "F.Fab")
		)
		(fp_line
			(start 0.120396 0.3048)
			(end 0.120396 0.2794)
			(stroke
				(width 0.1)
				(type default)
			)
			(layer "F.Fab")
		)
		(fp_line
			(start 0.12065 -0.3048)
			(end 0.67945 -0.3048)
			(stroke
				(width 0.1)
				(type default)
			)
			(layer "F.Fab")
		)
		(fp_line
			(start 0.12065 -0.2794)
			(end 0.12065 -0.3048)
			(stroke
				(width 0.1)
				(type default)
			)
			(layer "F.Fab")
		)
		(fp_line
			(start 0.67945 -0.3048)
			(end 0.67945 0.3048)
			(stroke
				(width 0.1)
				(type default)
			)
			(layer "F.Fab")
		)
		(fp_line
			(start 0.67945 0.3048)
			(end 0.120396 0.3048)
			(stroke
				(width 0.1)
				(type default)
			)
			(layer "F.Fab")
		)
		(pad "1" smd circle
			(at -0.40005 0)
			(size 0 0)
			(layers "F.Cu" "F.Mask" "F.Paste")
			(net "P3V3_AUX")
		)
		(pad "2" smd circle
			(at 0.40005 0)
			(size 0 0)
			(layers "F.Cu" "F.Mask" "F.Paste")
			(net "PRSNT_SSD3_R_N")
		)
	)
	(footprint ""
		(layer "F.Cu")
		(at 414.197292 -178.532282)
		(property "Reference" "Q234"
			(at -3.784092 -1.592834 0)
			(unlocked yes)
			(layer "F.SilkS")
			(effects
				(font
					(size 0.7874 0.5842)
					(thickness 0.1524)
				)
			)
		)
		(property "Value" ""
			(at 0 0 0)
			(layer "F.Fab")
			(effects
				(font
					(size 1.27 1.27)
				)
			)
		)
		(duplicate_pad_numbers_are_jumpers no)
		(fp_line
			(start -1.376172 -1.199896)
			(end -0.508 -1.199896)
			(stroke
				(width 0.1524)
				(type default)
			)
			(layer "F.SilkS")
		)
		(fp_line
			(start -1.376172 1.199896)
			(end -1.376172 -1.199896)
			(stroke
				(width 0.1524)
				(type default)
			)
			(layer "F.SilkS")
		)
		(fp_line
			(start -0.508 -1.199896)
			(end 0 -0.762)
			(stroke
				(width 0.1524)
				(type default)
			)
			(layer "F.SilkS")
		)
		(fp_line
			(start 0 -0.762)
			(end 0.508 -1.199896)
			(stroke
				(width 0.1524)
				(type default)
			)
			(layer "F.SilkS")
		)
		(fp_line
			(start 0.508 -1.199896)
			(end 1.376172 -1.199896)
			(stroke
				(width 0.1524)
				(type default)
			)
			(layer "F.SilkS")
		)
		(fp_line
			(start 1.376172 -1.199896)
			(end 1.376172 1.199896)
			(stroke
				(width 0.1524)
				(type default)
			)
			(layer "F.SilkS")
		)
		(fp_line
			(start 1.376172 1.199896)
			(end -1.376172 1.199896)
			(stroke
				(width 0.1524)
				(type default)
			)
			(layer "F.SilkS")
		)
		(fp_poly
			(pts
				(xy -1.4605 -0.7493) (xy -2.2225 -1.1303) (xy -2.2225 -0.3683)
			)
			(stroke
				(width 0)
				(type default)
			)
			(fill yes)
			(layer "F.SilkS")
		)
		(fp_line
			(start -0.674878 -1.100074)
			(end 0.674878 -1.100074)
			(stroke
				(width 0.1)
				(type default)
			)
			(layer "F.Fab")
		)
		(fp_line
			(start -0.674878 1.100074)
			(end -0.674878 -1.100074)
			(stroke
				(width 0.1)
				(type default)
			)
			(layer "F.Fab")
		)
		(fp_line
			(start 0.674878 -1.100074)
			(end 0.674878 1.100074)
			(stroke
				(width 0.1)
				(type default)
			)
			(layer "F.Fab")
		)
		(fp_line
			(start 0.674878 1.100074)
			(end -0.674878 1.100074)
			(stroke
				(width 0.1)
				(type default)
			)
			(layer "F.Fab")
		)
		(fp_poly
			(pts
				(xy -1.4605 -0.7493) (xy -2.2225 -1.1303) (xy -2.2225 -0.3683)
			)
			(stroke
				(width 0)
				(type default)
			)
			(fill yes)
			(layer "F.Fab")
		)
		(pad "1" smd rect
			(at -0.899922 -0.750062 270)
			(size 0.6096 0.6096)
			(layers "F.Cu" "F.Mask" "F.Paste")
			(net "GND")
		)
		(pad "2" smd rect
			(at -0.899922 0 270)
			(size 0.4064 0.6096)
			(layers "F.Cu" "F.Mask" "F.Paste")
			(net "FPGA_PEX1_MODE_SEL1_R")
		)
		(pad "3" smd rect
			(at -0.899922 0.750062 270)
			(size 0.6096 0.6096)
			(layers "F.Cu" "F.Mask" "F.Paste")
			(net "FPGA_PEX1_MODE_SEL1_ISO")
		)
		(pad "4" smd rect
			(at 0.899922 0.750062 270)
			(size 0.6096 0.6096)
			(layers "F.Cu" "F.Mask" "F.Paste")
			(net "GND")
		)
		(pad "5" smd rect
			(at 0.899922 0 270)
			(size 0.4064 0.6096)
			(layers "F.Cu" "F.Mask" "F.Paste")
			(net "FPGA_PEX1_MODE_SEL1_D_N")
		)
		(pad "6" smd rect
			(at 0.899922 -0.750062 270)
			(size 0.6096 0.6096)
			(layers "F.Cu" "F.Mask" "F.Paste")
			(net "FPGA_PEX1_MODE_SEL1_D_N")
		)
	)
	(footprint ""
		(layer "F.Cu")
		(at 456.420982 -116.230654 -90)
		(property "Reference" "R959"
			(at 0 0 270)
			(layer "F.SilkS")
			(hide yes)
			(effects
				(font
					(size 1.27 1.27)
				)
			)
		)
		(property "Value" ""
			(at 0 0 270)
			(layer "F.Fab")
			(effects
				(font
					(size 1.27 1.27)
				)
			)
		)
		(duplicate_pad_numbers_are_jumpers no)
		(fp_line
			(start -0.7874 0.4064)
			(end -0.7874 -0.4064)
			(stroke
				(width 0.1524)
				(type default)
			)
			(layer "F.SilkS")
		)
		(fp_line
			(start 0.7874 0.4064)
			(end -0.7874 0.4064)
			(stroke
				(width 0.1524)
				(type default)
			)
			(layer "F.SilkS")
		)
		(fp_line
			(start -0.7874 -0.4064)
			(end 0.7874 -0.4064)
			(stroke
				(width 0.1524)
				(type default)
			)
			(layer "F.SilkS")
		)
		(fp_line
			(start 0.7874 -0.4064)
			(end 0.7874 0.4064)
			(stroke
				(width 0.1524)
				(type default)
			)
			(layer "F.SilkS")
		)
		(fp_line
			(start -0.67945 0.3048)
			(end -0.67945 -0.305054)
			(stroke
				(width 0.1)
				(type default)
			)
			(layer "F.Fab")
		)
		(fp_line
			(start -0.12065 0.3048)
			(end -0.67945 0.3048)
			(stroke
				(width 0.1)
				(type default)
			)
			(layer "F.Fab")
		)
		(fp_line
			(start 0.120396 0.3048)
			(end 0.120396 0.2794)
			(stroke
				(width 0.1)
				(type default)
			)
			(layer "F.Fab")
		)
		(fp_line
			(start 0.67945 0.3048)
			(end 0.120396 0.3048)
			(stroke
				(width 0.1)
				(type default)
			)
			(layer "F.Fab")
		)
		(fp_line
			(start -0.12065 0.2794)
			(end -0.12065 0.3048)
			(stroke
				(width 0.1)
				(type default)
			)
			(layer "F.Fab")
		)
		(fp_line
			(start 0.120396 0.2794)
			(end -0.12065 0.2794)
			(stroke
				(width 0.1)
				(type default)
			)
			(layer "F.Fab")
		)
		(fp_line
			(start -0.12065 -0.2794)
			(end 0.12065 -0.2794)
			(stroke
				(width 0.1)
				(type default)
			)
			(layer "F.Fab")
		)
		(fp_line
			(start 0.12065 -0.2794)
			(end 0.12065 -0.3048)
			(stroke
				(width 0.1)
				(type default)
			)
			(layer "F.Fab")
		)
		(fp_line
			(start 0.12065 -0.3048)
			(end 0.67945 -0.3048)
			(stroke
				(width 0.1)
				(type default)
			)
			(layer "F.Fab")
		)
		(fp_line
			(start 0.67945 -0.3048)
			(end 0.67945 0.3048)
			(stroke
				(width 0.1)
				(type default)
			)
			(layer "F.Fab")
		)
		(fp_line
			(start -0.67945 -0.305054)
			(end -0.12065 -0.305054)
			(stroke
				(width 0.1)
				(type default)
			)
			(layer "F.Fab")
		)
		(fp_line
			(start -0.12065 -0.305054)
			(end -0.12065 -0.2794)
			(stroke
				(width 0.1)
				(type default)
			)
			(layer "F.Fab")
		)
		(pad "1" smd circle
			(at -0.40005 0 270)
			(size 0 0)
			(layers "F.Cu" "F.Mask" "F.Paste")
			(net "P3V3_AUX")
		)
		(pad "2" smd circle
			(at 0.40005 0 270)
			(size 0 0)
			(layers "F.Cu" "F.Mask" "F.Paste")
			(net "PWRGD_P12V_NIC7_CO")
		)
	)
	(footprint ""
		(layer "F.Cu")
		(at 188.759592 -61.612526)
		(property "Reference" "PD32"
			(at -3.695192 -2.648204 0)
			(unlocked yes)
			(layer "F.SilkS")
			(effects
				(font
					(size 0.7874 0.5842)
					(thickness 0.1524)
				)
				(justify left)
			)
		)
		(property "Value" ""
			(at 0 0 0)
			(layer "F.Fab")
			(effects
				(font
					(size 1.27 1.27)
				)
			)
		)
		(duplicate_pad_numbers_are_jumpers no)
		(fp_line
			(start -3.656584 -1.970024)
			(end -3.656584 1.970024)
			(stroke
				(width 0.1524)
				(type default)
			)
			(layer "F.SilkS")
		)
		(fp_line
			(start -3.656584 1.970024)
			(end 4.240784 1.970024)
			(stroke
				(width 0.1524)
				(type default)
			)
			(layer "F.SilkS")
		)
		(fp_line
			(start 4.240784 -1.970024)
			(end -3.656584 -1.970024)
			(stroke
				(width 0.1524)
				(type default)
			)
			(layer "F.SilkS")
		)
		(fp_line
			(start 4.240784 1.970024)
			(end 4.240784 -1.970024)
			(stroke
				(width 0.1524)
				(type default)
			)
			(layer "F.SilkS")
		)
		(fp_poly
			(pts
				(xy 3.580384 1.970024) (xy 3.580384 -1.970024) (xy 4.240784 -1.970024) (xy 4.240784 1.970024)
			)
			(stroke
				(width 0)
				(type default)
			)
			(fill yes)
			(layer "F.SilkS")
		)
		(fp_line
			(start -2.3749 -1.970024)
			(end -2.3749 1.970024)
			(stroke
				(width 0.1)
				(type default)
			)
			(layer "F.Fab")
		)
		(fp_line
			(start -2.3749 1.970024)
			(end 2.3749 1.970024)
			(stroke
				(width 0.1)
				(type default)
			)
			(layer "F.Fab")
		)
		(fp_line
			(start 2.3749 -1.970024)
			(end -2.3749 -1.970024)
			(stroke
				(width 0.1)
				(type default)
			)
			(layer "F.Fab")
		)
		(fp_line
			(start 2.3749 1.970024)
			(end 2.3749 -1.970024)
			(stroke
				(width 0.1)
				(type default)
			)
			(layer "F.Fab")
		)
		(fp_text user "+"
			(at -4.9784 -0.23495 0)
			(unlocked yes)
			(layer "F.Fab")
			(effects
				(font
					(size 1.905 1.4224)
					(thickness 0.1524)
				)
				(justify left)
			)
		)
		(fp_text user "-"
			(at 4.1656 -0.23495 0)
			(unlocked yes)
			(layer "F.Fab")
			(effects
				(font
					(size 1.905 1.4224)
					(thickness 0.1524)
				)
				(justify left)
			)
		)
		(pad "A" smd rect
			(at -2.450084 0)
			(size 2.159 2.2606)
			(layers "F.Cu" "F.Mask" "F.Paste")
			(net "GND")
		)
		(pad "C" smd rect
			(at 2.450084 0)
			(size 2.159 2.2606)
			(layers "F.Cu" "F.Mask" "F.Paste")
			(net "P12V_AUX")
		)
	)
	(footprint ""
		(layer "F.Cu")
		(at 389.50138 -55.78475 -90)
		(property "Reference" "PD43"
			(at 4.01955 2.09931 90)
			(unlocked yes)
			(layer "F.SilkS")
			(effects
				(font
					(size 0.7874 0.5842)
					(thickness 0.1524)
				)
				(justify left)
			)
		)
		(property "Value" ""
			(at 0 0 270)
			(layer "F.Fab")
			(effects
				(font
					(size 1.27 1.27)
				)
			)
		)
		(duplicate_pad_numbers_are_jumpers no)
		(fp_line
			(start -3.400044 1.459992)
			(end -3.400044 -1.459992)
			(stroke
				(width 0.1524)
				(type default)
			)
			(layer "F.SilkS")
		)
		(fp_line
			(start 4.107942 1.459992)
			(end -3.400044 1.459992)
			(stroke
				(width 0.1524)
				(type default)
			)
			(layer "F.SilkS")
		)
		(fp_line
			(start -3.400044 -1.459992)
			(end 4.107942 -1.459992)
			(stroke
				(width 0.1524)
				(type default)
			)
			(layer "F.SilkS")
		)
		(fp_line
			(start 4.107942 -1.459992)
			(end 4.107942 1.459992)
			(stroke
				(width 0.1524)
				(type default)
			)
			(layer "F.SilkS")
		)
		(fp_poly
			(pts
				(xy 4.107942 -1.459992) (xy 4.107942 1.459992) (xy 3.308096 1.459992) (xy 3.308096 -1.459992)
			)
			(stroke
				(width 0)
				(type default)
			)
			(fill yes)
			(layer "F.SilkS")
		)
		(fp_line
			(start -2.29997 1.459992)
			(end -2.29997 -1.459992)
			(stroke
				(width 0.1)
				(type default)
			)
			(layer "F.Fab")
		)
		(fp_line
			(start 2.29997 1.459992)
			(end -2.29997 1.459992)
			(stroke
				(width 0.1)
				(type default)
			)
			(layer "F.Fab")
		)
		(fp_line
			(start -2.29997 -1.459992)
			(end 2.29997 -1.459992)
			(stroke
				(width 0.1)
				(type default)
			)
			(layer "F.Fab")
		)
		(fp_line
			(start 2.29997 -1.459992)
			(end 2.29997 1.459992)
			(stroke
				(width 0.1)
				(type default)
			)
			(layer "F.Fab")
		)
		(fp_text user "-"
			(at 5.4102 0.29845 90)
			(unlocked yes)
			(layer "F.SilkS")
			(effects
				(font
					(size 1.905 1.4224)
					(thickness 0.1524)
				)
				(justify left)
			)
		)
		(fp_text user "+"
			(at -4.7752 -0.12065 270)
			(unlocked yes)
			(layer "F.SilkS")
			(effects
				(font
					(size 1.905 1.4224)
					(thickness 0.1524)
				)
				(justify left)
			)
		)
		(fp_text user "-"
			(at 5.4102 0.29845 90)
			(unlocked yes)
			(layer "F.Fab")
			(effects
				(font
					(size 1.905 1.4224)
					(thickness 0.1524)
				)
				(justify left)
			)
		)
		(fp_text user "+"
			(at -4.7752 -0.12065 270)
			(unlocked yes)
			(layer "F.Fab")
			(effects
				(font
					(size 1.905 1.4224)
					(thickness 0.1524)
				)
				(justify left)
			)
		)
		(pad "A" smd rect
			(at -1.999996 0)
			(size 1.7018 2.5146)
			(layers "F.Cu" "F.Mask" "F.Paste")
			(net "GND")
		)
		(pad "C" smd rect
			(at 1.999996 0)
			(size 1.7018 2.5146)
			(layers "F.Cu" "F.Mask" "F.Paste")
			(net "P12V_SSD13_R")
		)
	)
	(footprint ""
		(layer "F.Cu")
		(at 49.667922 -19.453098)
		(property "Reference" "R1640"
			(at 0 0 0)
			(layer "F.SilkS")
			(hide yes)
			(effects
				(font
					(size 1.27 1.27)
				)
			)
		)
		(property "Value" ""
			(at 0 0 0)
			(layer "F.Fab")
			(effects
				(font
					(size 1.27 1.27)
				)
			)
		)
		(duplicate_pad_numbers_are_jumpers no)
		(fp_line
			(start -0.7874 -0.4064)
			(end 0.7874 -0.4064)
			(stroke
				(width 0.1524)
				(type default)
			)
			(layer "F.SilkS")
		)
		(fp_line
			(start -0.7874 0.4064)
			(end -0.7874 -0.4064)
			(stroke
				(width 0.1524)
				(type default)
			)
			(layer "F.SilkS")
		)
		(fp_line
			(start 0.7874 -0.4064)
			(end 0.7874 0.4064)
			(stroke
				(width 0.1524)
				(type default)
			)
			(layer "F.SilkS")
		)
		(fp_line
			(start 0.7874 0.4064)
			(end -0.7874 0.4064)
			(stroke
				(width 0.1524)
				(type default)
			)
			(layer "F.SilkS")
		)
		(fp_line
			(start -0.67945 -0.305054)
			(end -0.12065 -0.305054)
			(stroke
				(width 0.1)
				(type default)
			)
			(layer "F.Fab")
		)
		(fp_line
			(start -0.67945 0.3048)
			(end -0.67945 -0.305054)
			(stroke
				(width 0.1)
				(type default)
			)
			(layer "F.Fab")
		)
		(fp_line
			(start -0.12065 -0.305054)
			(end -0.12065 -0.2794)
			(stroke
				(width 0.1)
				(type default)
			)
			(layer "F.Fab")
		)
		(fp_line
			(start -0.12065 -0.2794)
			(end 0.12065 -0.2794)
			(stroke
				(width 0.1)
				(type default)
			)
			(layer "F.Fab")
		)
		(fp_line
			(start -0.12065 0.2794)
			(end -0.12065 0.3048)
			(stroke
				(width 0.1)
				(type default)
			)
			(layer "F.Fab")
		)
		(fp_line
			(start -0.12065 0.3048)
			(end -0.67945 0.3048)
			(stroke
				(width 0.1)
				(type default)
			)
			(layer "F.Fab")
		)
		(fp_line
			(start 0.120396 0.2794)
			(end -0.12065 0.2794)
			(stroke
				(width 0.1)
				(type default)
			)
			(layer "F.Fab")
		)
		(fp_line
			(start 0.120396 0.3048)
			(end 0.120396 0.2794)
			(stroke
				(width 0.1)
				(type default)
			)
			(layer "F.Fab")
		)
		(fp_line
			(start 0.12065 -0.3048)
			(end 0.67945 -0.3048)
			(stroke
				(width 0.1)
				(type default)
			)
			(layer "F.Fab")
		)
		(fp_line
			(start 0.12065 -0.2794)
			(end 0.12065 -0.3048)
			(stroke
				(width 0.1)
				(type default)
			)
			(layer "F.Fab")
		)
		(fp_line
			(start 0.67945 -0.3048)
			(end 0.67945 0.3048)
			(stroke
				(width 0.1)
				(type default)
			)
			(layer "F.Fab")
		)
		(fp_line
			(start 0.67945 0.3048)
			(end 0.120396 0.3048)
			(stroke
				(width 0.1)
				(type default)
			)
			(layer "F.Fab")
		)
		(pad "1" smd circle
			(at -0.40005 0)
			(size 0 0)
			(layers "F.Cu" "F.Mask" "F.Paste")
			(net "SMB_ISO_SSD1_R_SDA")
		)
		(pad "2" smd circle
			(at 0.40005 0)
			(size 0 0)
			(layers "F.Cu" "F.Mask" "F.Paste")
			(net "SMB_ISO_SSD1_SDA")
		)
	)
	(footprint ""
		(layer "F.Cu")
		(at 367.826798 -55.418228 90)
		(property "Reference" "PC406"
			(at 0 0 90)
			(layer "F.SilkS")
			(hide yes)
			(effects
				(font
					(size 1.27 1.27)
				)
			)
		)
		(property "Value" ""
			(at 0 0 90)
			(layer "F.Fab")
			(effects
				(font
					(size 1.27 1.27)
				)
			)
		)
		(duplicate_pad_numbers_are_jumpers no)
		(fp_line
			(start 0.7874 -0.4064)
			(end 0.7874 0.4064)
			(stroke
				(width 0.1524)
				(type default)
			)
			(layer "F.SilkS")
		)
		(fp_line
			(start -0.7874 -0.4064)
			(end 0.7874 -0.4064)
			(stroke
				(width 0.1524)
				(type default)
			)
			(layer "F.SilkS")
		)
		(fp_line
			(start 0.7874 0.4064)
			(end -0.7874 0.4064)
			(stroke
				(width 0.1524)
				(type default)
			)
			(layer "F.SilkS")
		)
		(fp_line
			(start -0.7874 0.4064)
			(end -0.7874 -0.4064)
			(stroke
				(width 0.1524)
				(type default)
			)
			(layer "F.SilkS")
		)
		(fp_line
			(start -0.12065 -0.305054)
			(end -0.12065 -0.2794)
			(stroke
				(width 0.1)
				(type default)
			)
			(layer "F.Fab")
		)
		(fp_line
			(start -0.67945 -0.305054)
			(end -0.12065 -0.305054)
			(stroke
				(width 0.1)
				(type default)
			)
			(layer "F.Fab")
		)
		(fp_line
			(start 0.67945 -0.3048)
			(end 0.67945 0.3048)
			(stroke
				(width 0.1)
				(type default)
			)
			(layer "F.Fab")
		)
		(fp_line
			(start 0.12065 -0.3048)
			(end 0.67945 -0.3048)
			(stroke
				(width 0.1)
				(type default)
			)
			(layer "F.Fab")
		)
		(fp_line
			(start 0.12065 -0.2794)
			(end 0.12065 -0.3048)
			(stroke
				(width 0.1)
				(type default)
			)
			(layer "F.Fab")
		)
		(fp_line
			(start -0.12065 -0.2794)
			(end 0.12065 -0.2794)
			(stroke
				(width 0.1)
				(type default)
			)
			(layer "F.Fab")
		)
		(fp_line
			(start 0.120396 0.2794)
			(end -0.12065 0.2794)
			(stroke
				(width 0.1)
				(type default)
			)
			(layer "F.Fab")
		)
		(fp_line
			(start -0.12065 0.2794)
			(end -0.12065 0.3048)
			(stroke
				(width 0.1)
				(type default)
			)
			(layer "F.Fab")
		)
		(fp_line
			(start 0.67945 0.3048)
			(end 0.120396 0.3048)
			(stroke
				(width 0.1)
				(type default)
			)
			(layer "F.Fab")
		)
		(fp_line
			(start 0.120396 0.3048)
			(end 0.120396 0.2794)
			(stroke
				(width 0.1)
				(type default)
			)
			(layer "F.Fab")
		)
		(fp_line
			(start -0.12065 0.3048)
			(end -0.67945 0.3048)
			(stroke
				(width 0.1)
				(type default)
			)
			(layer "F.Fab")
		)
		(fp_line
			(start -0.67945 0.3048)
			(end -0.67945 -0.305054)
			(stroke
				(width 0.1)
				(type default)
			)
			(layer "F.Fab")
		)
		(pad "1" smd circle
			(at -0.40005 0 90)
			(size 0 0)
			(layers "F.Cu" "F.Mask" "F.Paste")
			(net "P12V_SSD12_R")
		)
		(pad "2" smd circle
			(at 0.40005 0 90)
			(size 0 0)
			(layers "F.Cu" "F.Mask" "F.Paste")
			(net "GND")
		)
	)
	(footprint ""
		(layer "F.Cu")
		(at 428.83963 -158.219648)
		(property "Reference" "R365"
			(at 0 0 0)
			(layer "F.SilkS")
			(hide yes)
			(effects
				(font
					(size 1.27 1.27)
				)
			)
		)
		(property "Value" ""
			(at 0 0 0)
			(layer "F.Fab")
			(effects
				(font
					(size 1.27 1.27)
				)
			)
		)
		(duplicate_pad_numbers_are_jumpers no)
		(fp_line
			(start -0.7874 -0.4064)
			(end 0.7874 -0.4064)
			(stroke
				(width 0.1524)
				(type default)
			)
			(layer "F.SilkS")
		)
		(fp_line
			(start -0.7874 0.4064)
			(end -0.7874 -0.4064)
			(stroke
				(width 0.1524)
				(type default)
			)
			(layer "F.SilkS")
		)
		(fp_line
			(start 0.7874 -0.4064)
			(end 0.7874 0.4064)
			(stroke
				(width 0.1524)
				(type default)
			)
			(layer "F.SilkS")
		)
		(fp_line
			(start 0.7874 0.4064)
			(end -0.7874 0.4064)
			(stroke
				(width 0.1524)
				(type default)
			)
			(layer "F.SilkS")
		)
		(fp_line
			(start -0.67945 -0.305054)
			(end -0.12065 -0.305054)
			(stroke
				(width 0.1)
				(type default)
			)
			(layer "F.Fab")
		)
		(fp_line
			(start -0.67945 0.3048)
			(end -0.67945 -0.305054)
			(stroke
				(width 0.1)
				(type default)
			)
			(layer "F.Fab")
		)
		(fp_line
			(start -0.12065 -0.305054)
			(end -0.12065 -0.2794)
			(stroke
				(width 0.1)
				(type default)
			)
			(layer "F.Fab")
		)
		(fp_line
			(start -0.12065 -0.2794)
			(end 0.12065 -0.2794)
			(stroke
				(width 0.1)
				(type default)
			)
			(layer "F.Fab")
		)
		(fp_line
			(start -0.12065 0.2794)
			(end -0.12065 0.3048)
			(stroke
				(width 0.1)
				(type default)
			)
			(layer "F.Fab")
		)
		(fp_line
			(start -0.12065 0.3048)
			(end -0.67945 0.3048)
			(stroke
				(width 0.1)
				(type default)
			)
			(layer "F.Fab")
		)
		(fp_line
			(start 0.120396 0.2794)
			(end -0.12065 0.2794)
			(stroke
				(width 0.1)
				(type default)
			)
			(layer "F.Fab")
		)
		(fp_line
			(start 0.120396 0.3048)
			(end 0.120396 0.2794)
			(stroke
				(width 0.1)
				(type default)
			)
			(layer "F.Fab")
		)
		(fp_line
			(start 0.12065 -0.3048)
			(end 0.67945 -0.3048)
			(stroke
				(width 0.1)
				(type default)
			)
			(layer "F.Fab")
		)
		(fp_line
			(start 0.12065 -0.2794)
			(end 0.12065 -0.3048)
			(stroke
				(width 0.1)
				(type default)
			)
			(layer "F.Fab")
		)
		(fp_line
			(start 0.67945 -0.3048)
			(end 0.67945 0.3048)
			(stroke
				(width 0.1)
				(type default)
			)
			(layer "F.Fab")
		)
		(fp_line
			(start 0.67945 0.3048)
			(end 0.120396 0.3048)
			(stroke
				(width 0.1)
				(type default)
			)
			(layer "F.Fab")
		)
		(pad "1" smd circle
			(at -0.40005 0)
			(size 0 0)
			(layers "F.Cu" "F.Mask" "F.Paste")
			(net "PRSNTB3_NIC7_N")
		)
		(pad "2" smd circle
			(at 0.40005 0)
			(size 0 0)
			(layers "F.Cu" "F.Mask" "F.Paste")
			(net "P3V3_AUX")
		)
	)
	(footprint ""
		(layer "F.Cu")
		(at 2.992374 -388.845298 90)
		(property "Reference" "R6748"
			(at 0 0 90)
			(layer "F.SilkS")
			(hide yes)
			(effects
				(font
					(size 1.27 1.27)
				)
			)
		)
		(property "Value" ""
			(at 0 0 90)
			(layer "F.Fab")
			(effects
				(font
					(size 1.27 1.27)
				)
			)
		)
		(duplicate_pad_numbers_are_jumpers no)
		(fp_line
			(start 0.7874 -0.4064)
			(end 0.7874 0.4064)
			(stroke
				(width 0.1524)
				(type default)
			)
			(layer "F.SilkS")
		)
		(fp_line
			(start -0.508762 -0.4064)
			(end 0.7874 -0.4064)
			(stroke
				(width 0.1524)
				(type default)
			)
			(layer "F.SilkS")
		)
		(fp_line
			(start 0.7874 0.4064)
			(end -0.503428 0.4064)
			(stroke
				(width 0.1524)
				(type default)
			)
			(layer "F.SilkS")
		)
		(fp_line
			(start -0.12065 -0.305054)
			(end -0.12065 -0.2794)
			(stroke
				(width 0.1)
				(type default)
			)
			(layer "F.Fab")
		)
		(fp_line
			(start -0.67945 -0.305054)
			(end -0.12065 -0.305054)
			(stroke
				(width 0.1)
				(type default)
			)
			(layer "F.Fab")
		)
		(fp_line
			(start 0.67945 -0.3048)
			(end 0.67945 0.3048)
			(stroke
				(width 0.1)
				(type default)
			)
			(layer "F.Fab")
		)
		(fp_line
			(start 0.12065 -0.3048)
			(end 0.67945 -0.3048)
			(stroke
				(width 0.1)
				(type default)
			)
			(layer "F.Fab")
		)
		(fp_line
			(start 0.12065 -0.2794)
			(end 0.12065 -0.3048)
			(stroke
				(width 0.1)
				(type default)
			)
			(layer "F.Fab")
		)
		(fp_line
			(start -0.12065 -0.2794)
			(end 0.12065 -0.2794)
			(stroke
				(width 0.1)
				(type default)
			)
			(layer "F.Fab")
		)
		(fp_line
			(start 0.120396 0.2794)
			(end -0.12065 0.2794)
			(stroke
				(width 0.1)
				(type default)
			)
			(layer "F.Fab")
		)
		(fp_line
			(start -0.12065 0.2794)
			(end -0.12065 0.3048)
			(stroke
				(width 0.1)
				(type default)
			)
			(layer "F.Fab")
		)
		(fp_line
			(start 0.67945 0.3048)
			(end 0.120396 0.3048)
			(stroke
				(width 0.1)
				(type default)
			)
			(layer "F.Fab")
		)
		(fp_line
			(start 0.120396 0.3048)
			(end 0.120396 0.2794)
			(stroke
				(width 0.1)
				(type default)
			)
			(layer "F.Fab")
		)
		(fp_line
			(start -0.12065 0.3048)
			(end -0.67945 0.3048)
			(stroke
				(width 0.1)
				(type default)
			)
			(layer "F.Fab")
		)
		(fp_line
			(start -0.67945 0.3048)
			(end -0.67945 -0.305054)
			(stroke
				(width 0.1)
				(type default)
			)
			(layer "F.Fab")
		)
		(pad "1" smd circle
			(at -0.40005 0 90)
			(size 0 0)
			(layers "F.Cu" "F.Mask" "F.Paste")
			(net "USB2_MB_BMC_USB8042_DP")
		)
		(pad "2" smd circle
			(at 0.40005 0 90)
			(size 0 0)
			(layers "F.Cu" "F.Mask" "F.Paste")
			(net "GND")
		)
	)
	(footprint ""
		(layer "F.Cu")
		(at 220.34373 -45.88891)
		(property "Reference" "R586"
			(at 0 0 0)
			(layer "F.SilkS")
			(hide yes)
			(effects
				(font
					(size 1.27 1.27)
				)
			)
		)
		(property "Value" ""
			(at 0 0 0)
			(layer "F.Fab")
			(effects
				(font
					(size 1.27 1.27)
				)
			)
		)
		(duplicate_pad_numbers_are_jumpers no)
		(fp_line
			(start -0.7874 -0.4064)
			(end 0.7874 -0.4064)
			(stroke
				(width 0.1524)
				(type default)
			)
			(layer "F.SilkS")
		)
		(fp_line
			(start -0.7874 0.4064)
			(end -0.7874 -0.4064)
			(stroke
				(width 0.1524)
				(type default)
			)
			(layer "F.SilkS")
		)
		(fp_line
			(start 0.7874 -0.4064)
			(end 0.7874 0.4064)
			(stroke
				(width 0.1524)
				(type default)
			)
			(layer "F.SilkS")
		)
		(fp_line
			(start 0.7874 0.4064)
			(end -0.7874 0.4064)
			(stroke
				(width 0.1524)
				(type default)
			)
			(layer "F.SilkS")
		)
		(fp_line
			(start -0.67945 -0.305054)
			(end -0.12065 -0.305054)
			(stroke
				(width 0.1)
				(type default)
			)
			(layer "F.Fab")
		)
		(fp_line
			(start -0.67945 0.3048)
			(end -0.67945 -0.305054)
			(stroke
				(width 0.1)
				(type default)
			)
			(layer "F.Fab")
		)
		(fp_line
			(start -0.12065 -0.305054)
			(end -0.12065 -0.2794)
			(stroke
				(width 0.1)
				(type default)
			)
			(layer "F.Fab")
		)
		(fp_line
			(start -0.12065 -0.2794)
			(end 0.12065 -0.2794)
			(stroke
				(width 0.1)
				(type default)
			)
			(layer "F.Fab")
		)
		(fp_line
			(start -0.12065 0.2794)
			(end -0.12065 0.3048)
			(stroke
				(width 0.1)
				(type default)
			)
			(layer "F.Fab")
		)
		(fp_line
			(start -0.12065 0.3048)
			(end -0.67945 0.3048)
			(stroke
				(width 0.1)
				(type default)
			)
			(layer "F.Fab")
		)
		(fp_line
			(start 0.120396 0.2794)
			(end -0.12065 0.2794)
			(stroke
				(width 0.1)
				(type default)
			)
			(layer "F.Fab")
		)
		(fp_line
			(start 0.120396 0.3048)
			(end 0.120396 0.2794)
			(stroke
				(width 0.1)
				(type default)
			)
			(layer "F.Fab")
		)
		(fp_line
			(start 0.12065 -0.3048)
			(end 0.67945 -0.3048)
			(stroke
				(width 0.1)
				(type default)
			)
			(layer "F.Fab")
		)
		(fp_line
			(start 0.12065 -0.2794)
			(end 0.12065 -0.3048)
			(stroke
				(width 0.1)
				(type default)
			)
			(layer "F.Fab")
		)
		(fp_line
			(start 0.67945 -0.3048)
			(end 0.67945 0.3048)
			(stroke
				(width 0.1)
				(type default)
			)
			(layer "F.Fab")
		)
		(fp_line
			(start 0.67945 0.3048)
			(end 0.120396 0.3048)
			(stroke
				(width 0.1)
				(type default)
			)
			(layer "F.Fab")
		)
		(pad "1" smd circle
			(at -0.40005 0)
			(size 0 0)
			(layers "F.Cu" "F.Mask" "F.Paste")
			(net "SSD7_ADC_A0")
		)
		(pad "2" smd circle
			(at 0.40005 0)
			(size 0 0)
			(layers "F.Cu" "F.Mask" "F.Paste")
			(net "GND")
		)
	)
	(footprint ""
		(layer "F.Cu")
		(at 263.50976 -344.772488)
		(property "Reference" "R6652"
			(at 0 0 0)
			(layer "F.SilkS")
			(hide yes)
			(effects
				(font
					(size 1.27 1.27)
				)
			)
		)
		(property "Value" ""
			(at 0 0 0)
			(layer "F.Fab")
			(effects
				(font
					(size 1.27 1.27)
				)
			)
		)
		(duplicate_pad_numbers_are_jumpers no)
		(fp_line
			(start -0.7874 -0.4064)
			(end 0.7874 -0.4064)
			(stroke
				(width 0.1524)
				(type default)
			)
			(layer "F.SilkS")
		)
		(fp_line
			(start -0.7874 0.4064)
			(end -0.7874 -0.4064)
			(stroke
				(width 0.1524)
				(type default)
			)
			(layer "F.SilkS")
		)
		(fp_line
			(start 0.7874 -0.4064)
			(end 0.7874 0.4064)
			(stroke
				(width 0.1524)
				(type default)
			)
			(layer "F.SilkS")
		)
		(fp_line
			(start 0.7874 0.4064)
			(end -0.7874 0.4064)
			(stroke
				(width 0.1524)
				(type default)
			)
			(layer "F.SilkS")
		)
		(fp_line
			(start -0.67945 -0.305054)
			(end -0.12065 -0.305054)
			(stroke
				(width 0.1)
				(type default)
			)
			(layer "F.Fab")
		)
		(fp_line
			(start -0.67945 0.3048)
			(end -0.67945 -0.305054)
			(stroke
				(width 0.1)
				(type default)
			)
			(layer "F.Fab")
		)
		(fp_line
			(start -0.12065 -0.305054)
			(end -0.12065 -0.2794)
			(stroke
				(width 0.1)
				(type default)
			)
			(layer "F.Fab")
		)
		(fp_line
			(start -0.12065 -0.2794)
			(end 0.12065 -0.2794)
			(stroke
				(width 0.1)
				(type default)
			)
			(layer "F.Fab")
		)
		(fp_line
			(start -0.12065 0.2794)
			(end -0.12065 0.3048)
			(stroke
				(width 0.1)
				(type default)
			)
			(layer "F.Fab")
		)
		(fp_line
			(start -0.12065 0.3048)
			(end -0.67945 0.3048)
			(stroke
				(width 0.1)
				(type default)
			)
			(layer "F.Fab")
		)
		(fp_line
			(start 0.120396 0.2794)
			(end -0.12065 0.2794)
			(stroke
				(width 0.1)
				(type default)
			)
			(layer "F.Fab")
		)
		(fp_line
			(start 0.120396 0.3048)
			(end 0.120396 0.2794)
			(stroke
				(width 0.1)
				(type default)
			)
			(layer "F.Fab")
		)
		(fp_line
			(start 0.12065 -0.3048)
			(end 0.67945 -0.3048)
			(stroke
				(width 0.1)
				(type default)
			)
			(layer "F.Fab")
		)
		(fp_line
			(start 0.12065 -0.2794)
			(end 0.12065 -0.3048)
			(stroke
				(width 0.1)
				(type default)
			)
			(layer "F.Fab")
		)
		(fp_line
			(start 0.67945 -0.3048)
			(end 0.67945 0.3048)
			(stroke
				(width 0.1)
				(type default)
			)
			(layer "F.Fab")
		)
		(fp_line
			(start 0.67945 0.3048)
			(end 0.120396 0.3048)
			(stroke
				(width 0.1)
				(type default)
			)
			(layer "F.Fab")
		)
		(pad "1" smd circle
			(at -0.40005 0)
			(size 0 0)
			(layers "F.Cu" "F.Mask" "F.Paste")
			(net "P3V3_AUX")
		)
		(pad "2" smd circle
			(at 0.40005 0)
			(size 0 0)
			(layers "F.Cu" "F.Mask" "F.Paste")
			(net "HSC_D_OC_R")
		)
	)
	(footprint ""
		(layer "F.Cu")
		(at 8.362696 -171.64431 180)
		(property "Reference" "PC21"
			(at 0 0 180)
			(layer "F.SilkS")
			(hide yes)
			(effects
				(font
					(size 1.27 1.27)
				)
			)
		)
		(property "Value" ""
			(at 0 0 180)
			(layer "F.Fab")
			(effects
				(font
					(size 1.27 1.27)
				)
			)
		)
		(duplicate_pad_numbers_are_jumpers no)
		(fp_line
			(start 1.524 0.762)
			(end -1.524 0.762)
			(stroke
				(width 0.1524)
				(type default)
			)
			(layer "F.SilkS")
		)
		(fp_line
			(start 1.524 -0.762)
			(end 1.524 0.762)
			(stroke
				(width 0.1524)
				(type default)
			)
			(layer "F.SilkS")
		)
		(fp_line
			(start -1.524 0.762)
			(end -1.524 -0.762)
			(stroke
				(width 0.1524)
				(type default)
			)
			(layer "F.SilkS")
		)
		(fp_line
			(start -1.524 -0.762)
			(end 1.524 -0.762)
			(stroke
				(width 0.1524)
				(type default)
			)
			(layer "F.SilkS")
		)
		(fp_line
			(start 1.1049 0.724916)
			(end 1.1049 -0.724916)
			(stroke
				(width 0.1)
				(type default)
			)
			(layer "F.Fab")
		)
		(fp_line
			(start 1.1049 -0.724916)
			(end -1.1049 -0.724916)
			(stroke
				(width 0.1)
				(type default)
			)
			(layer "F.Fab")
		)
		(fp_line
			(start -1.1049 0.724916)
			(end 1.1049 0.724916)
			(stroke
				(width 0.1)
				(type default)
			)
			(layer "F.Fab")
		)
		(fp_line
			(start -1.1049 -0.724916)
			(end -1.1049 0.724916)
			(stroke
				(width 0.1)
				(type default)
			)
			(layer "F.Fab")
		)
		(pad "1" smd rect
			(at -0.889 0)
			(size 1.016 1.27)
			(layers "F.Cu" "F.Mask" "F.Paste")
			(net "P5V_AUX")
		)
		(pad "2" smd rect
			(at 0.889 0)
			(size 1.016 1.27)
			(layers "F.Cu" "F.Mask" "F.Paste")
			(net "GND")
		)
	)
	(footprint ""
		(layer "F.Cu")
		(at 338.074 -147.955 180)
		(property "Reference" "R4831"
			(at 0 0 180)
			(layer "F.SilkS")
			(hide yes)
			(effects
				(font
					(size 1.27 1.27)
				)
			)
		)
		(property "Value" ""
			(at 0 0 180)
			(layer "F.Fab")
			(effects
				(font
					(size 1.27 1.27)
				)
			)
		)
		(duplicate_pad_numbers_are_jumpers no)
		(fp_line
			(start 0.7874 0.4064)
			(end -0.7874 0.4064)
			(stroke
				(width 0.1524)
				(type default)
			)
			(layer "F.SilkS")
		)
		(fp_line
			(start 0.7874 -0.4064)
			(end 0.7874 0.4064)
			(stroke
				(width 0.1524)
				(type default)
			)
			(layer "F.SilkS")
		)
		(fp_line
			(start -0.7874 0.4064)
			(end -0.7874 -0.4064)
			(stroke
				(width 0.1524)
				(type default)
			)
			(layer "F.SilkS")
		)
		(fp_line
			(start -0.7874 -0.4064)
			(end 0.7874 -0.4064)
			(stroke
				(width 0.1524)
				(type default)
			)
			(layer "F.SilkS")
		)
		(fp_line
			(start 0.67945 0.3048)
			(end 0.120396 0.3048)
			(stroke
				(width 0.1)
				(type default)
			)
			(layer "F.Fab")
		)
		(fp_line
			(start 0.67945 -0.3048)
			(end 0.67945 0.3048)
			(stroke
				(width 0.1)
				(type default)
			)
			(layer "F.Fab")
		)
		(fp_line
			(start 0.12065 -0.2794)
			(end 0.12065 -0.3048)
			(stroke
				(width 0.1)
				(type default)
			)
			(layer "F.Fab")
		)
		(fp_line
			(start 0.12065 -0.3048)
			(end 0.67945 -0.3048)
			(stroke
				(width 0.1)
				(type default)
			)
			(layer "F.Fab")
		)
		(fp_line
			(start 0.120396 0.3048)
			(end 0.120396 0.2794)
			(stroke
				(width 0.1)
				(type default)
			)
			(layer "F.Fab")
		)
		(fp_line
			(start 0.120396 0.2794)
			(end -0.12065 0.2794)
			(stroke
				(width 0.1)
				(type default)
			)
			(layer "F.Fab")
		)
		(fp_line
			(start -0.12065 0.3048)
			(end -0.67945 0.3048)
			(stroke
				(width 0.1)
				(type default)
			)
			(layer "F.Fab")
		)
		(fp_line
			(start -0.12065 0.2794)
			(end -0.12065 0.3048)
			(stroke
				(width 0.1)
				(type default)
			)
			(layer "F.Fab")
		)
		(fp_line
			(start -0.12065 -0.2794)
			(end 0.12065 -0.2794)
			(stroke
				(width 0.1)
				(type default)
			)
			(layer "F.Fab")
		)
		(fp_line
			(start -0.12065 -0.305054)
			(end -0.12065 -0.2794)
			(stroke
				(width 0.1)
				(type default)
			)
			(layer "F.Fab")
		)
		(fp_line
			(start -0.67945 0.3048)
			(end -0.67945 -0.305054)
			(stroke
				(width 0.1)
				(type default)
			)
			(layer "F.Fab")
		)
		(fp_line
			(start -0.67945 -0.305054)
			(end -0.12065 -0.305054)
			(stroke
				(width 0.1)
				(type default)
			)
			(layer "F.Fab")
		)
		(pad "1" smd circle
			(at -0.40005 0 180)
			(size 0 0)
			(layers "F.Cu" "F.Mask" "F.Paste")
			(net "PRSNT_SSD14_FPGA_PCA9555_N")
		)
		(pad "2" smd circle
			(at 0.40005 0 180)
			(size 0 0)
			(layers "F.Cu" "F.Mask" "F.Paste")
			(net "PRSNT_SSD14_FPGA_R_N")
		)
	)
	(footprint ""
		(layer "F.Cu")
		(at 248.63171 -162.003994 -90)
		(property "Reference" "R952"
			(at 0 0 270)
			(layer "F.SilkS")
			(hide yes)
			(effects
				(font
					(size 1.27 1.27)
				)
			)
		)
		(property "Value" ""
			(at 0 0 270)
			(layer "F.Fab")
			(effects
				(font
					(size 1.27 1.27)
				)
			)
		)
		(duplicate_pad_numbers_are_jumpers no)
		(fp_line
			(start -0.7874 0.4064)
			(end -0.7874 -0.4064)
			(stroke
				(width 0.1524)
				(type default)
			)
			(layer "F.SilkS")
		)
		(fp_line
			(start 0.7874 0.4064)
			(end -0.7874 0.4064)
			(stroke
				(width 0.1524)
				(type default)
			)
			(layer "F.SilkS")
		)
		(fp_line
			(start -0.7874 -0.4064)
			(end 0.7874 -0.4064)
			(stroke
				(width 0.1524)
				(type default)
			)
			(layer "F.SilkS")
		)
		(fp_line
			(start 0.7874 -0.4064)
			(end 0.7874 0.4064)
			(stroke
				(width 0.1524)
				(type default)
			)
			(layer "F.SilkS")
		)
		(fp_line
			(start -0.67945 0.3048)
			(end -0.67945 -0.305054)
			(stroke
				(width 0.1)
				(type default)
			)
			(layer "F.Fab")
		)
		(fp_line
			(start -0.12065 0.3048)
			(end -0.67945 0.3048)
			(stroke
				(width 0.1)
				(type default)
			)
			(layer "F.Fab")
		)
		(fp_line
			(start 0.120396 0.3048)
			(end 0.120396 0.2794)
			(stroke
				(width 0.1)
				(type default)
			)
			(layer "F.Fab")
		)
		(fp_line
			(start 0.67945 0.3048)
			(end 0.120396 0.3048)
			(stroke
				(width 0.1)
				(type default)
			)
			(layer "F.Fab")
		)
		(fp_line
			(start -0.12065 0.2794)
			(end -0.12065 0.3048)
			(stroke
				(width 0.1)
				(type default)
			)
			(layer "F.Fab")
		)
		(fp_line
			(start 0.120396 0.2794)
			(end -0.12065 0.2794)
			(stroke
				(width 0.1)
				(type default)
			)
			(layer "F.Fab")
		)
		(fp_line
			(start -0.12065 -0.2794)
			(end 0.12065 -0.2794)
			(stroke
				(width 0.1)
				(type default)
			)
			(layer "F.Fab")
		)
		(fp_line
			(start 0.12065 -0.2794)
			(end 0.12065 -0.3048)
			(stroke
				(width 0.1)
				(type default)
			)
			(layer "F.Fab")
		)
		(fp_line
			(start 0.12065 -0.3048)
			(end 0.67945 -0.3048)
			(stroke
				(width 0.1)
				(type default)
			)
			(layer "F.Fab")
		)
		(fp_line
			(start 0.67945 -0.3048)
			(end 0.67945 0.3048)
			(stroke
				(width 0.1)
				(type default)
			)
			(layer "F.Fab")
		)
		(fp_line
			(start -0.67945 -0.305054)
			(end -0.12065 -0.305054)
			(stroke
				(width 0.1)
				(type default)
			)
			(layer "F.Fab")
		)
		(fp_line
			(start -0.12065 -0.305054)
			(end -0.12065 -0.2794)
			(stroke
				(width 0.1)
				(type default)
			)
			(layer "F.Fab")
		)
		(pad "1" smd circle
			(at -0.40005 0 270)
			(size 0 0)
			(layers "F.Cu" "F.Mask" "F.Paste")
			(net "HP_NIC4_EN")
		)
		(pad "2" smd circle
			(at 0.40005 0 270)
			(size 0 0)
			(layers "F.Cu" "F.Mask" "F.Paste")
			(net "P12V_NIC4_CO_EN")
		)
	)
	(footprint ""
		(layer "F.Cu")
		(at 132.721096 -177.650394)
		(property "Reference" "U114"
			(at -4.385818 -3.764534 0)
			(unlocked yes)
			(layer "F.SilkS")
			(effects
				(font
					(size 0.7874 0.5842)
					(thickness 0.1524)
				)
				(justify left)
			)
		)
		(property "Value" ""
			(at 0 0 0)
			(layer "F.Fab")
			(effects
				(font
					(size 1.27 1.27)
				)
			)
		)
		(duplicate_pad_numbers_are_jumpers no)
		(fp_poly
			(pts
				(xy -4.191 -3.258058) (xy -4.191 -2.242058) (xy -3.175 -2.750058)
			)
			(stroke
				(width 0)
				(type default)
			)
			(fill yes)
			(layer "F.SilkS")
		)
		(fp_line
			(start -3.050032 -3.050032)
			(end -3.050032 3.050032)
			(stroke
				(width 0.1)
				(type default)
			)
			(layer "F.Fab")
		)
		(fp_line
			(start -3.050032 3.050032)
			(end 3.050032 3.050032)
			(stroke
				(width 0.1)
				(type default)
			)
			(layer "F.Fab")
		)
		(fp_line
			(start 3.050032 -3.050032)
			(end -3.050032 -3.050032)
			(stroke
				(width 0.1)
				(type default)
			)
			(layer "F.Fab")
		)
		(fp_line
			(start 3.050032 3.050032)
			(end 3.050032 -3.050032)
			(stroke
				(width 0.1)
				(type default)
			)
			(layer "F.Fab")
		)
		(fp_poly
			(pts
				(xy -4.191 -3.258058) (xy -4.191 -2.242058) (xy -3.175 -2.750058)
			)
			(stroke
				(width 0)
				(type default)
			)
			(fill yes)
			(layer "F.Fab")
		)
		(pad "A1" smd circle
			(at -2.750058 -2.750058)
			(size 0.2286 0.2286)
			(layers "F.Cu" "F.Mask" "F.Paste")
			(net "Net_4313")
		)
		(pad "A2" smd circle
			(at -2.249932 -2.750058)
			(size 0.2286 0.2286)
			(layers "F.Cu" "F.Mask" "F.Paste")
			(net "Net_4312")
		)
		(pad "A3" smd circle
			(at -1.75006 -2.750058)
			(size 0.2286 0.2286)
			(layers "F.Cu" "F.Mask" "F.Paste")
			(net "Net_4311")
		)
		(pad "A4" smd circle
			(at -1.249934 -2.750058)
			(size 0.2286 0.2286)
			(layers "F.Cu" "F.Mask" "F.Paste")
			(net "CLK_100M_DB2000QL_GPU_REF2_DN")
		)
		(pad "A5" smd circle
			(at -0.750062 -2.750058)
			(size 0.2286 0.2286)
			(layers "F.Cu" "F.Mask" "F.Paste")
			(net "CLK_100M_DB2000QL_GPU_REF2_DP")
		)
		(pad "A6" smd circle
			(at -0.249936 -2.750058)
			(size 0.2286 0.2286)
			(layers "F.Cu" "F.Mask" "F.Paste")
			(net "CLK_100M_DB2000QL_GPU_REF1_DN")
		)
		(pad "A7" smd circle
			(at 0.249936 -2.750058)
			(size 0.2286 0.2286)
			(layers "F.Cu" "F.Mask" "F.Paste")
			(net "CLK_100M_DB2000QL_GPU_REF1_DP")
		)
		(pad "A8" smd circle
			(at 0.750062 -2.750058)
			(size 0.2286 0.2286)
			(layers "F.Cu" "F.Mask" "F.Paste")
			(net "CLK_100M_DB2000QL_GPU_REF0_DN")
		)
		(pad "A9" smd circle
			(at 1.249934 -2.750058)
			(size 0.2286 0.2286)
			(layers "F.Cu" "F.Mask" "F.Paste")
			(net "CLK_100M_DB2000QL_GPU_REF0_DP")
		)
		(pad "A10" smd circle
			(at 1.75006 -2.750058)
			(size 0.2286 0.2286)
			(layers "F.Cu" "F.Mask" "F.Paste")
			(net "CLK_100M_DB2000QL_NIC7_DN")
		)
		(pad "A11" smd circle
			(at 2.249932 -2.750058)
			(size 0.2286 0.2286)
			(layers "F.Cu" "F.Mask" "F.Paste")
			(net "CLK_100M_DB2000QL_NIC7_DP")
		)
		(pad "A12" smd circle
			(at 2.750058 -2.750058)
			(size 0.2286 0.2286)
			(layers "F.Cu" "F.Mask" "F.Paste")
			(net "CLK_100M_DB2000QL_NIC6_DN")
		)
		(pad "B1" smd circle
			(at -2.750058 -2.249932)
			(size 0.2286 0.2286)
			(layers "F.Cu" "F.Mask" "F.Paste")
			(net "Net_4314")
		)
		(pad "B2" smd circle
			(at -2.249932 -2.249932)
			(size 0.2286 0.2286)
			(layers "F.Cu" "F.Mask" "F.Paste")
			(net "P3V3_DB2000QL_VDD")
		)
		(pad "B3" smd circle
			(at -1.75006 -2.249932)
			(size 0.2286 0.2286)
			(layers "F.Cu" "F.Mask" "F.Paste")
			(net "Net_4321")
		)
		(pad "B4" smd circle
			(at -1.249934 -2.249932)
			(size 0.2286 0.2286)
			(layers "F.Cu" "F.Mask" "F.Paste")
			(net "FM_DB2000QL_SMB_SA0")
		)
		(pad "B5" smd circle
			(at -0.750062 -2.249932)
			(size 0.2286 0.2286)
			(layers "F.Cu" "F.Mask" "F.Paste")
			(net "Net_4331")
		)
		(pad "B6" smd circle
			(at -0.249936 -2.249932)
			(size 0.2286 0.2286)
			(layers "F.Cu" "F.Mask" "F.Paste")
			(net "P3V3_DB2000QL_VDDA")
		)
		(pad "B7" smd circle
			(at 0.249936 -2.249932)
			(size 0.2286 0.2286)
			(layers "F.Cu" "F.Mask" "F.Paste")
			(net "Net_4332")
		)
		(pad "B8" smd circle
			(at 0.750062 -2.249932)
			(size 0.2286 0.2286)
			(layers "F.Cu" "F.Mask" "F.Paste")
			(net "FM_DB2000QL_SMB_SA1")
		)
		(pad "B9" smd circle
			(at 1.249934 -2.249932)
			(size 0.2286 0.2286)
			(layers "F.Cu" "F.Mask" "F.Paste")
			(net "Net_4333")
		)
		(pad "B10" smd circle
			(at 1.75006 -2.249932)
			(size 0.2286 0.2286)
			(layers "F.Cu" "F.Mask" "F.Paste")
			(net "NIC7_CLK_EN_BUF_R_N")
		)
		(pad "B11" smd circle
			(at 2.249932 -2.249932)
			(size 0.2286 0.2286)
			(layers "F.Cu" "F.Mask" "F.Paste")
			(net "P3V3_DB2000QL_VDD")
		)
		(pad "B12" smd circle
			(at 2.750058 -2.249932)
			(size 0.2286 0.2286)
			(layers "F.Cu" "F.Mask" "F.Paste")
			(net "CLK_100M_DB2000QL_NIC6_DP")
		)
		(pad "C1" smd circle
			(at -2.750058 -1.75006)
			(size 0.2286 0.2286)
			(layers "F.Cu" "F.Mask" "F.Paste")
			(net "Net_4315")
		)
		(pad "C2" smd circle
			(at -2.249932 -1.75006)
			(size 0.2286 0.2286)
			(layers "F.Cu" "F.Mask" "F.Paste")
			(net "Net_4334")
		)
		(pad "C11" smd circle
			(at 2.249932 -1.75006)
			(size 0.2286 0.2286)
			(layers "F.Cu" "F.Mask" "F.Paste")
			(net "NIC6_CLK_EN_BUF_R_N")
		)
		(pad "C12" smd circle
			(at 2.750058 -1.75006)
			(size 0.2286 0.2286)
			(layers "F.Cu" "F.Mask" "F.Paste")
			(net "CLK_100M_DB2000QL_NIC5_DN")
		)
		(pad "D1" smd circle
			(at -2.750058 -1.249934)
			(size 0.2286 0.2286)
			(layers "F.Cu" "F.Mask" "F.Paste")
			(net "Net_4316")
		)
		(pad "D2" smd circle
			(at -2.249932 -1.249934)
			(size 0.2286 0.2286)
			(layers "F.Cu" "F.Mask" "F.Paste")
			(net "Net_4335")
		)
		(pad "D11" smd circle
			(at 2.249932 -1.249934)
			(size 0.2286 0.2286)
			(layers "F.Cu" "F.Mask" "F.Paste")
			(net "Net_4336")
		)
		(pad "D12" smd circle
			(at 2.750058 -1.249934)
			(size 0.2286 0.2286)
			(layers "F.Cu" "F.Mask" "F.Paste")
			(net "CLK_100M_DB2000QL_NIC5_DP")
		)
		(pad "E1" smd circle
			(at -2.750058 -0.750062)
			(size 0.2286 0.2286)
			(layers "F.Cu" "F.Mask" "F.Paste")
			(net "Net_4317")
		)
		(pad "E2" smd circle
			(at -2.249932 -0.750062)
			(size 0.2286 0.2286)
			(layers "F.Cu" "F.Mask" "F.Paste")
			(net "FM_DB2000QL_VSBEN")
		)
		(pad "E11" smd circle
			(at 2.249932 -0.750062)
			(size 0.2286 0.2286)
			(layers "F.Cu" "F.Mask" "F.Paste")
			(net "NIC5_CLK_EN_BUF_R_N")
		)
		(pad "E12" smd circle
			(at 2.750058 -0.750062)
			(size 0.2286 0.2286)
			(layers "F.Cu" "F.Mask" "F.Paste")
			(net "NIC4_CLK_EN_BUF_R_N")
		)
		(pad "F1" smd circle
			(at -2.750058 -0.249936)
			(size 0.2286 0.2286)
			(layers "F.Cu" "F.Mask" "F.Paste")
			(net "Net_4318")
		)
		(pad "F2" smd circle
			(at -2.249932 -0.249936)
			(size 0.2286 0.2286)
			(layers "F.Cu" "F.Mask" "F.Paste")
			(net "Net_4337")
		)
		(pad "F11" smd circle
			(at 2.249932 -0.249936)
			(size 0.2286 0.2286)
			(layers "F.Cu" "F.Mask" "F.Paste")
			(net "Net_4338")
		)
		(pad "F12" smd circle
			(at 2.750058 -0.249936)
			(size 0.2286 0.2286)
			(layers "F.Cu" "F.Mask" "F.Paste")
			(net "CLK_100M_DB2000QL_NIC4_DN")
		)
		(pad "G1" smd circle
			(at -2.750058 0.249936)
			(size 0.2286 0.2286)
			(layers "F.Cu" "F.Mask" "F.Paste")
			(net "CLK_100M_CK440Q_0_DB2000QL_R_DP")
		)
		(pad "G2" smd circle
			(at -2.249932 0.249936)
			(size 0.2286 0.2286)
			(layers "F.Cu" "F.Mask" "F.Paste")
			(net "Net_4322")
		)
		(pad "G11" smd circle
			(at 2.249932 0.249936)
			(size 0.2286 0.2286)
			(layers "F.Cu" "F.Mask" "F.Paste")
			(net "Net_4323")
		)
		(pad "G12" smd circle
			(at 2.750058 0.249936)
			(size 0.2286 0.2286)
			(layers "F.Cu" "F.Mask" "F.Paste")
			(net "CLK_100M_DB2000QL_NIC4_DP")
		)
		(pad "H1" smd circle
			(at -2.750058 0.750062)
			(size 0.2286 0.2286)
			(layers "F.Cu" "F.Mask" "F.Paste")
			(net "CLK_100M_CK440Q_0_DB2000QL_R_DN")
		)
		(pad "H2" smd circle
			(at -2.249932 0.750062)
			(size 0.2286 0.2286)
			(layers "F.Cu" "F.Mask" "F.Paste")
			(net "P3V3_DB2000QL_VDDR")
		)
		(pad "H11" smd circle
			(at 2.249932 0.750062)
			(size 0.2286 0.2286)
			(layers "F.Cu" "F.Mask" "F.Paste")
			(net "NIC3_CLK_EN_BUF_R_N")
		)
		(pad "H12" smd circle
			(at 2.750058 0.750062)
			(size 0.2286 0.2286)
			(layers "F.Cu" "F.Mask" "F.Paste")
			(net "CLK_100M_DB2000QL_NIC3_DN")
		)
		(pad "J1" smd circle
			(at -2.750058 1.249934)
			(size 0.2286 0.2286)
			(layers "F.Cu" "F.Mask" "F.Paste")
			(net "CLK_100M_DB2000QL_PEX0_S1_DP")
		)
		(pad "J2" smd circle
			(at -2.249932 1.249934)
			(size 0.2286 0.2286)
			(layers "F.Cu" "F.Mask" "F.Paste")
			(net "Net_4324")
		)
		(pad "J11" smd circle
			(at 2.249932 1.249934)
			(size 0.2286 0.2286)
			(layers "F.Cu" "F.Mask" "F.Paste")
			(net "Net_4325")
		)
		(pad "J12" smd circle
			(at 2.750058 1.249934)
			(size 0.2286 0.2286)
			(layers "F.Cu" "F.Mask" "F.Paste")
			(net "CLK_100M_DB2000QL_NIC3_DP")
		)
		(pad "K1" smd circle
			(at -2.750058 1.75006)
			(size 0.2286 0.2286)
			(layers "F.Cu" "F.Mask" "F.Paste")
			(net "CLK_100M_DB2000QL_PEX0_S1_DN")
		)
		(pad "K2" smd circle
			(at -2.249932 1.75006)
			(size 0.2286 0.2286)
			(layers "F.Cu" "F.Mask" "F.Paste")
			(net "Net_4326")
		)
		(pad "K11" smd circle
			(at 2.249932 1.75006)
			(size 0.2286 0.2286)
			(layers "F.Cu" "F.Mask" "F.Paste")
			(net "NIC2_CLK_EN_BUF_R_N")
		)
		(pad "K12" smd circle
			(at 2.750058 1.75006)
			(size 0.2286 0.2286)
			(layers "F.Cu" "F.Mask" "F.Paste")
			(net "CLK_100M_DB2000QL_NIC2_DN")
		)
		(pad "L1" smd circle
			(at -2.750058 2.249932)
			(size 0.2286 0.2286)
			(layers "F.Cu" "F.Mask" "F.Paste")
			(net "CLK_100M_DB2000QL_PEX1_S1_DP")
		)
		(pad "L2" smd circle
			(at -2.249932 2.249932)
			(size 0.2286 0.2286)
			(layers "F.Cu" "F.Mask" "F.Paste")
			(net "P3V3_DB2000QL_VDD")
		)
		(pad "L3" smd circle
			(at -1.75006 2.249932)
			(size 0.2286 0.2286)
			(layers "F.Cu" "F.Mask" "F.Paste")
			(net "Net_4329")
		)
		(pad "L4" smd circle
			(at -1.249934 2.249932)
			(size 0.2286 0.2286)
			(layers "F.Cu" "F.Mask" "F.Paste")
			(net "SMB_BMC_9QXL2001_SDA")
		)
		(pad "L5" smd circle
			(at -0.750062 2.249932)
			(size 0.2286 0.2286)
			(layers "F.Cu" "F.Mask" "F.Paste")
			(net "SMB_BMC_9QXL2001_SCL")
		)
		(pad "L6" smd circle
			(at -0.249936 2.249932)
			(size 0.2286 0.2286)
			(layers "F.Cu" "F.Mask" "F.Paste")
			(net "Net_4327")
		)
		(pad "L7" smd circle
			(at 0.249936 2.249932)
			(size 0.2286 0.2286)
			(layers "F.Cu" "F.Mask" "F.Paste")
			(net "Net_4328")
		)
		(pad "L8" smd circle
			(at 0.750062 2.249932)
			(size 0.2286 0.2286)
			(layers "F.Cu" "F.Mask" "F.Paste")
			(net "NIC0_CLK_EN_BUF_R_N")
		)
		(pad "L9" smd circle
			(at 1.249934 2.249932)
			(size 0.2286 0.2286)
			(layers "F.Cu" "F.Mask" "F.Paste")
			(net "Net_4330")
		)
		(pad "L10" smd circle
			(at 1.75006 2.249932)
			(size 0.2286 0.2286)
			(layers "F.Cu" "F.Mask" "F.Paste")
			(net "NIC1_CLK_EN_BUF_R_N")
		)
		(pad "L11" smd circle
			(at 2.249932 2.249932)
			(size 0.2286 0.2286)
			(layers "F.Cu" "F.Mask" "F.Paste")
			(net "P3V3_DB2000QL_VDD")
		)
		(pad "L12" smd circle
			(at 2.750058 2.249932)
			(size 0.2286 0.2286)
			(layers "F.Cu" "F.Mask" "F.Paste")
			(net "CLK_100M_DB2000QL_NIC2_DP")
		)
		(pad "M1" smd circle
			(at -2.750058 2.750058)
			(size 0.2286 0.2286)
			(layers "F.Cu" "F.Mask" "F.Paste")
			(net "CLK_100M_DB2000QL_PEX1_S1_DN")
		)
		(pad "M2" smd circle
			(at -2.249932 2.750058)
			(size 0.2286 0.2286)
			(layers "F.Cu" "F.Mask" "F.Paste")
			(net "CLK_100M_DB2000QL_PEX2_S1_DP")
		)
		(pad "M3" smd circle
			(at -1.75006 2.750058)
			(size 0.2286 0.2286)
			(layers "F.Cu" "F.Mask" "F.Paste")
			(net "CLK_100M_DB2000QL_PEX2_S1_DN")
		)
		(pad "M4" smd circle
			(at -1.249934 2.750058)
			(size 0.2286 0.2286)
			(layers "F.Cu" "F.Mask" "F.Paste")
			(net "CLK_100M_DB2000QL_PEX3_S1_DP")
		)
		(pad "M5" smd circle
			(at -0.750062 2.750058)
			(size 0.2286 0.2286)
			(layers "F.Cu" "F.Mask" "F.Paste")
			(net "CLK_100M_DB2000QL_PEX3_S1_DN")
		)
		(pad "M6" smd circle
			(at -0.249936 2.750058)
			(size 0.2286 0.2286)
			(layers "F.Cu" "F.Mask" "F.Paste")
			(net "FM_CLK_EN_R")
		)
		(pad "M7" smd circle
			(at 0.249936 2.750058)
			(size 0.2286 0.2286)
			(layers "F.Cu" "F.Mask" "F.Paste")
			(net "Net_4319")
		)
		(pad "M8" smd circle
			(at 0.750062 2.750058)
			(size 0.2286 0.2286)
			(layers "F.Cu" "F.Mask" "F.Paste")
			(net "Net_4320")
		)
		(pad "M9" smd circle
			(at 1.249934 2.750058)
			(size 0.2286 0.2286)
			(layers "F.Cu" "F.Mask" "F.Paste")
			(net "CLK_100M_DB2000QL_NIC0_DP")
		)
		(pad "M10" smd circle
			(at 1.75006 2.750058)
			(size 0.2286 0.2286)
			(layers "F.Cu" "F.Mask" "F.Paste")
			(net "CLK_100M_DB2000QL_NIC0_DN")
		)
		(pad "M11" smd circle
			(at 2.249932 2.750058)
			(size 0.2286 0.2286)
			(layers "F.Cu" "F.Mask" "F.Paste")
			(net "CLK_100M_DB2000QL_NIC1_DP")
		)
		(pad "M12" smd circle
			(at 2.750058 2.750058)
			(size 0.2286 0.2286)
			(layers "F.Cu" "F.Mask" "F.Paste")
			(net "CLK_100M_DB2000QL_NIC1_DN")
		)
		(pad "TH" smd circle
			(at 0 0)
			(size 0 0)
			(layers "F.Cu" "F.Mask" "F.Paste")
			(net "GND")
		)
		(zone
			(layer "F.Cu")
			(hatch none 0.5)
			(connect_pads
				(clearance 0)
			)
			(min_thickness 0.25)
			(keepout
				(tracks not_allowed)
				(vias allowed)
				(pads allowed)
				(copperpour not_allowed)
				(footprints allowed)
			)
			(placement
				(enabled no)
				(sheetname "")
			)
			(fill
				(thermal_gap 0.5)
				(thermal_bridge_width 0.5)
				(island_removal_mode 0)
			)
			(polygon
				(pts
					(xy 131.959096 -179.733194) (xy 134.803896 -179.733194) (xy 134.803896 -175.567594) (xy 130.638296 -175.567594)
					(xy 130.638296 -179.733194) (xy 131.933696 -179.733194) (xy 131.933696 -179.123594) (xy 131.654296 -179.123594)
					(xy 131.247896 -178.717194) (xy 131.247896 -176.177194) (xy 134.194296 -176.177194) (xy 134.194296 -179.123594)
					(xy 131.959096 -179.123594)
				)
			)
		)
	)
	(footprint ""
		(layer "F.Cu")
		(at 444.920116 -15.649956 180)
		(property "Reference" "H123"
			(at -1.310894 2.814066 0)
			(unlocked yes)
			(layer "B.SilkS")
			(effects
				(font
					(size 0.7874 0.5842)
					(thickness 0.1524)
				)
				(justify left mirror)
			)
		)
		(property "Value" ""
			(at 0 0 180)
			(layer "F.Fab")
			(effects
				(font
					(size 1.27 1.27)
				)
			)
		)
		(duplicate_pad_numbers_are_jumpers no)
		(pad "1" thru_hole rect
			(at 0 0 180)
			(size 4.2164 5.0038)
			(drill 2.0066
				(offset 0.099822 0)
			)
			(layers "*.Cu" "*.Mask")
			(remove_unused_layers no)
			(net "Net_8540")
			(clearance -0.8509)
			(padstack
				(mode front_inner_back)
				(layer "Inner"
					(shape circle)
					(size 4.0132 4.0132)
					(clearance -0.7493)
				)
				(layer "B.Cu"
					(shape circle)
					(size 4.0132 4.0132)
					(clearance -0.7493)
				)
			)
		)
	)
	(footprint ""
		(layer "F.Cu")
		(at 354.830888 -284.8991 180)
		(property "Reference" "PU14"
			(at -15.450058 -2.694178 90)
			(unlocked yes)
			(layer "F.SilkS")
			(effects
				(font
					(size 0.7874 0.5842)
					(thickness 0.1524)
				)
				(justify left)
			)
		)
		(property "Value" ""
			(at 0 0 180)
			(layer "F.Fab")
			(effects
				(font
					(size 1.27 1.27)
				)
			)
		)
		(duplicate_pad_numbers_are_jumpers no)
		(fp_line
			(start 2.500122 2.999994)
			(end 2.2987 2.999994)
			(stroke
				(width 0.1524)
				(type default)
			)
			(layer "F.SilkS")
		)
		(fp_line
			(start 2.500122 2.339594)
			(end 2.500122 2.999994)
			(stroke
				(width 0.1524)
				(type default)
			)
			(layer "F.SilkS")
		)
		(fp_line
			(start 2.500122 -2.999994)
			(end 2.500122 -2.44348)
			(stroke
				(width 0.1524)
				(type default)
			)
			(layer "F.SilkS")
		)
		(fp_line
			(start 2.31394 -2.999994)
			(end 2.500122 -2.999994)
			(stroke
				(width 0.1524)
				(type default)
			)
			(layer "F.SilkS")
		)
		(fp_line
			(start -2.2987 2.999994)
			(end -2.500122 2.999994)
			(stroke
				(width 0.1524)
				(type default)
			)
			(layer "F.SilkS")
		)
		(fp_line
			(start -2.500122 2.999994)
			(end -2.500122 2.339594)
			(stroke
				(width 0.1524)
				(type default)
			)
			(layer "F.SilkS")
		)
		(fp_line
			(start -2.500122 0.6604)
			(end -2.500122 0.229108)
			(stroke
				(width 0.1524)
				(type default)
			)
			(layer "F.SilkS")
		)
		(fp_line
			(start -2.500122 -2.529078)
			(end -2.500122 -2.999994)
			(stroke
				(width 0.1524)
				(type default)
			)
			(layer "F.SilkS")
		)
		(fp_line
			(start -2.500122 -2.999994)
			(end -2.24409 -2.999994)
			(stroke
				(width 0.1524)
				(type default)
			)
			(layer "F.SilkS")
		)
		(fp_poly
			(pts
				(xy -4.02336 -4.518406) (xy -4.741672 -3.79984) (xy -3.664204 -3.440684)
			)
			(stroke
				(width 0)
				(type default)
			)
			(fill yes)
			(layer "F.SilkS")
		)
		(fp_line
			(start 2.500122 2.999994)
			(end -2.500122 2.999994)
			(stroke
				(width 0.1)
				(type default)
			)
			(layer "F.Fab")
		)
		(fp_line
			(start 2.500122 -2.999994)
			(end 2.500122 2.999994)
			(stroke
				(width 0.1)
				(type default)
			)
			(layer "F.Fab")
		)
		(fp_line
			(start -2.500122 2.999994)
			(end -2.500122 -2.999994)
			(stroke
				(width 0.1)
				(type default)
			)
			(layer "F.Fab")
		)
		(fp_line
			(start -2.500122 -2.999994)
			(end 2.500122 -2.999994)
			(stroke
				(width 0.1)
				(type default)
			)
			(layer "F.Fab")
		)
		(fp_poly
			(pts
				(xy -4.218432 -2.783078) (xy -4.218432 -1.767078) (xy -3.202432 -2.275078)
			)
			(stroke
				(width 0)
				(type default)
			)
			(fill yes)
			(layer "F.Fab")
		)
		(pad "1" smd rect
			(at -2.400046 -2.275078 270)
			(size 0.2286 0.6096)
			(layers "F.Cu" "F.Mask" "F.Paste")
			(net "SW_P0V8_PEX3_VOS1")
		)
		(pad "2" smd rect
			(at -2.400046 -1.82499 270)
			(size 0.2286 0.6096)
			(layers "F.Cu" "F.Mask" "F.Paste")
			(net "GND")
		)
		(pad "3" smd rect
			(at -2.400046 -1.374902 270)
			(size 0.2286 0.6096)
			(layers "F.Cu" "F.Mask" "F.Paste")
			(net "P0V8_PEX3_VCC1")
		)
		(pad "4" smd rect
			(at -2.400046 -0.925068 270)
			(size 0.2286 0.6096)
			(layers "F.Cu" "F.Mask" "F.Paste")
			(net "P0V8_PEX3_PVCC")
		)
		(pad "5" smd rect
			(at -2.400046 -0.47498 270)
			(size 0.2286 0.6096)
			(layers "F.Cu" "F.Mask" "F.Paste")
			(net "GND")
		)
		(pad "6" smd rect
			(at -2.400046 -0.024892 270)
			(size 0.2286 0.6096)
			(layers "F.Cu" "F.Mask" "F.Paste")
			(net "NC_P0V8_PEX3_PH1_NC1")
		)
		(pad "7_9-20_24" smd circle
			(at 0 1.150112 270)
			(size 0 0)
			(layers "F.Cu" "F.Mask" "F.Paste")
			(net "GND")
		)
		(pad "10_19" smd rect
			(at 0 2.899918 270)
			(size 0.6096 4.318)
			(layers "F.Cu" "F.Mask" "F.Paste")
			(net "SW_P0V8_PEX3_PH1")
		)
		(pad "25_29" smd rect
			(at 1.549908 -1.279906 90)
			(size 2.0574 2.3114)
			(layers "F.Cu" "F.Mask" "F.Paste")
			(net "SW_P12V_P0V8_PEX3_FLT")
		)
		(pad "30" smd rect
			(at 2.05994 -2.899918 180)
			(size 0.2286 0.6096)
			(layers "F.Cu" "F.Mask" "F.Paste")
			(net "SW_P12V_P0V8_PEX3_FLT")
		)
		(pad "31" smd rect
			(at 1.610106 -2.899918 180)
			(size 0.2286 0.6096)
			(layers "F.Cu" "F.Mask" "F.Paste")
			(net "NC_P0V8_PEX3_PH1_NC3")
		)
		(pad "32" smd rect
			(at 1.160018 -2.899918 180)
			(size 0.2286 0.6096)
			(layers "F.Cu" "F.Mask" "F.Paste")
			(net "SW_P0V8_PEX3_PHASE1")
		)
		(pad "33" smd rect
			(at 0.70993 -2.899918 180)
			(size 0.2286 0.6096)
			(layers "F.Cu" "F.Mask" "F.Paste")
			(net "SW_P0V8_PEX3_BOOT1")
		)
		(pad "34" smd rect
			(at 0.260096 -2.899918 180)
			(size 0.2286 0.6096)
			(layers "F.Cu" "F.Mask" "F.Paste")
			(net "P0V8_PEX3_PWM1")
		)
		(pad "35" smd rect
			(at -0.189992 -2.899918 180)
			(size 0.2286 0.6096)
			(layers "F.Cu" "F.Mask" "F.Paste")
			(net "P0V8_PEX2_EN3")
		)
		(pad "36" smd rect
			(at -0.64008 -2.899918 180)
			(size 0.2286 0.6096)
			(layers "F.Cu" "F.Mask" "F.Paste")
			(net "P0V8_PEX3_TSEN")
		)
		(pad "37" smd rect
			(at -1.089914 -2.899918 180)
			(size 0.2286 0.6096)
			(layers "F.Cu" "F.Mask" "F.Paste")
			(net "P0V8_PEX3_LSET1")
		)
		(pad "38" smd rect
			(at -1.540002 -2.899918 180)
			(size 0.2286 0.6096)
			(layers "F.Cu" "F.Mask" "F.Paste")
			(net "P0V8_PEX3_ISEN1")
		)
		(pad "39" smd rect
			(at -1.99009 -2.899918 180)
			(size 0.2286 0.6096)
			(layers "F.Cu" "F.Mask" "F.Paste")
			(net "P0V8_PEX2_VREF")
		)
		(pad "40" smd rect
			(at -0.87503 -1.27508 180)
			(size 1.7526 1.9558)
			(layers "F.Cu" "F.Mask" "F.Paste")
			(net "GND")
		)
		(pad "41" smd rect
			(at -1.525016 0.249936 90)
			(size 0.3048 0.4572)
			(layers "F.Cu" "F.Mask" "F.Paste")
			(net "NC_P0V8_PEX3_PH1_NC2")
		)
		(zone
			(layer "F.Cu")
			(hatch none 0.5)
			(connect_pads
				(clearance 0)
			)
			(min_thickness 0.25)
			(keepout
				(tracks not_allowed)
				(vias allowed)
				(pads allowed)
				(copperpour not_allowed)
				(footprints allowed)
			)
			(placement
				(enabled no)
				(sheetname "")
			)
			(fill
				(thermal_gap 0.5)
				(thermal_bridge_width 0.5)
				(island_removal_mode 0)
			)
			(polygon
				(pts
					(xy 357.33101 -287.899094) (xy 357.33101 -287.149794) (xy 352.330766 -287.149794) (xy 352.330766 -287.899094)
					(xy 352.621088 -287.899094) (xy 352.621088 -287.443418) (xy 357.040688 -287.443418) (xy 357.040688 -287.899094)
				)
			)
		)
	)
	(footprint ""
		(layer "F.Cu")
		(at 152.634442 -250.070874 -90)
		(property "Reference" "R1275"
			(at 0 0 270)
			(layer "F.SilkS")
			(hide yes)
			(effects
				(font
					(size 1.27 1.27)
				)
			)
		)
		(property "Value" ""
			(at 0 0 270)
			(layer "F.Fab")
			(effects
				(font
					(size 1.27 1.27)
				)
			)
		)
		(duplicate_pad_numbers_are_jumpers no)
		(fp_line
			(start -0.7874 0.4064)
			(end -0.7874 -0.4064)
			(stroke
				(width 0.1524)
				(type default)
			)
			(layer "F.SilkS")
		)
		(fp_line
			(start 0.7874 0.4064)
			(end -0.7874 0.4064)
			(stroke
				(width 0.1524)
				(type default)
			)
			(layer "F.SilkS")
		)
		(fp_line
			(start -0.7874 -0.4064)
			(end 0.7874 -0.4064)
			(stroke
				(width 0.1524)
				(type default)
			)
			(layer "F.SilkS")
		)
		(fp_line
			(start 0.7874 -0.4064)
			(end 0.7874 0.4064)
			(stroke
				(width 0.1524)
				(type default)
			)
			(layer "F.SilkS")
		)
		(fp_line
			(start -0.67945 0.3048)
			(end -0.67945 -0.305054)
			(stroke
				(width 0.1)
				(type default)
			)
			(layer "F.Fab")
		)
		(fp_line
			(start -0.12065 0.3048)
			(end -0.67945 0.3048)
			(stroke
				(width 0.1)
				(type default)
			)
			(layer "F.Fab")
		)
		(fp_line
			(start 0.120396 0.3048)
			(end 0.120396 0.2794)
			(stroke
				(width 0.1)
				(type default)
			)
			(layer "F.Fab")
		)
		(fp_line
			(start 0.67945 0.3048)
			(end 0.120396 0.3048)
			(stroke
				(width 0.1)
				(type default)
			)
			(layer "F.Fab")
		)
		(fp_line
			(start -0.12065 0.2794)
			(end -0.12065 0.3048)
			(stroke
				(width 0.1)
				(type default)
			)
			(layer "F.Fab")
		)
		(fp_line
			(start 0.120396 0.2794)
			(end -0.12065 0.2794)
			(stroke
				(width 0.1)
				(type default)
			)
			(layer "F.Fab")
		)
		(fp_line
			(start -0.12065 -0.2794)
			(end 0.12065 -0.2794)
			(stroke
				(width 0.1)
				(type default)
			)
			(layer "F.Fab")
		)
		(fp_line
			(start 0.12065 -0.2794)
			(end 0.12065 -0.3048)
			(stroke
				(width 0.1)
				(type default)
			)
			(layer "F.Fab")
		)
		(fp_line
			(start 0.12065 -0.3048)
			(end 0.67945 -0.3048)
			(stroke
				(width 0.1)
				(type default)
			)
			(layer "F.Fab")
		)
		(fp_line
			(start 0.67945 -0.3048)
			(end 0.67945 0.3048)
			(stroke
				(width 0.1)
				(type default)
			)
			(layer "F.Fab")
		)
		(fp_line
			(start -0.67945 -0.305054)
			(end -0.12065 -0.305054)
			(stroke
				(width 0.1)
				(type default)
			)
			(layer "F.Fab")
		)
		(fp_line
			(start -0.12065 -0.305054)
			(end -0.12065 -0.2794)
			(stroke
				(width 0.1)
				(type default)
			)
			(layer "F.Fab")
		)
		(pad "1" smd circle
			(at -0.40005 0 270)
			(size 0 0)
			(layers "F.Cu" "F.Mask" "F.Paste")
			(net "PEX1_MODE_SEL6")
		)
		(pad "2" smd circle
			(at 0.40005 0 270)
			(size 0 0)
			(layers "F.Cu" "F.Mask" "F.Paste")
			(net "P1V8_PEX")
		)
	)
	(footprint ""
		(layer "F.Cu")
		(at 228.494082 -273.064732 90)
		(property "Reference" "C4281"
			(at 0 0 90)
			(layer "F.SilkS")
			(hide yes)
			(effects
				(font
					(size 1.27 1.27)
				)
			)
		)
		(property "Value" ""
			(at 0 0 90)
			(layer "F.Fab")
			(effects
				(font
					(size 1.27 1.27)
				)
			)
		)
		(duplicate_pad_numbers_are_jumpers no)
		(fp_line
			(start 0.299974 -0.150114)
			(end 0.299974 0.150114)
			(stroke
				(width 0.1)
				(type default)
			)
			(layer "F.Fab")
		)
		(fp_line
			(start -0.299974 -0.150114)
			(end 0.299974 -0.150114)
			(stroke
				(width 0.1)
				(type default)
			)
			(layer "F.Fab")
		)
		(fp_line
			(start 0.299974 0.150114)
			(end -0.299974 0.150114)
			(stroke
				(width 0.1)
				(type default)
			)
			(layer "F.Fab")
		)
		(fp_line
			(start -0.299974 0.150114)
			(end -0.299974 -0.150114)
			(stroke
				(width 0.1)
				(type default)
			)
			(layer "F.Fab")
		)
		(pad "1" smd rect
			(at -0.2667 0 90)
			(size 0.3048 0.381)
			(layers "F.Cu" "F.Mask" "F.Paste")
			(net "P1V25_SERDES_VDDPLL_PEX1")
		)
		(pad "2" smd rect
			(at 0.2667 0 90)
			(size 0.3048 0.381)
			(layers "F.Cu" "F.Mask" "F.Paste")
			(net "GND")
		)
	)
	(footprint ""
		(layer "F.Cu")
		(at 193.16446 -29.079952 180)
		(property "Reference" "R6204"
			(at 0 0 180)
			(layer "F.SilkS")
			(hide yes)
			(effects
				(font
					(size 1.27 1.27)
				)
			)
		)
		(property "Value" ""
			(at 0 0 180)
			(layer "F.Fab")
			(effects
				(font
					(size 1.27 1.27)
				)
			)
		)
		(duplicate_pad_numbers_are_jumpers no)
		(fp_line
			(start 0.7874 0.4064)
			(end -0.7874 0.4064)
			(stroke
				(width 0.1524)
				(type default)
			)
			(layer "F.SilkS")
		)
		(fp_line
			(start 0.7874 -0.4064)
			(end 0.7874 0.4064)
			(stroke
				(width 0.1524)
				(type default)
			)
			(layer "F.SilkS")
		)
		(fp_line
			(start -0.7874 0.4064)
			(end -0.7874 -0.4064)
			(stroke
				(width 0.1524)
				(type default)
			)
			(layer "F.SilkS")
		)
		(fp_line
			(start -0.7874 -0.4064)
			(end 0.7874 -0.4064)
			(stroke
				(width 0.1524)
				(type default)
			)
			(layer "F.SilkS")
		)
		(fp_line
			(start 0.67945 0.3048)
			(end 0.120396 0.3048)
			(stroke
				(width 0.1)
				(type default)
			)
			(layer "F.Fab")
		)
		(fp_line
			(start 0.67945 -0.3048)
			(end 0.67945 0.3048)
			(stroke
				(width 0.1)
				(type default)
			)
			(layer "F.Fab")
		)
		(fp_line
			(start 0.12065 -0.2794)
			(end 0.12065 -0.3048)
			(stroke
				(width 0.1)
				(type default)
			)
			(layer "F.Fab")
		)
		(fp_line
			(start 0.12065 -0.3048)
			(end 0.67945 -0.3048)
			(stroke
				(width 0.1)
				(type default)
			)
			(layer "F.Fab")
		)
		(fp_line
			(start 0.120396 0.3048)
			(end 0.120396 0.2794)
			(stroke
				(width 0.1)
				(type default)
			)
			(layer "F.Fab")
		)
		(fp_line
			(start 0.120396 0.2794)
			(end -0.12065 0.2794)
			(stroke
				(width 0.1)
				(type default)
			)
			(layer "F.Fab")
		)
		(fp_line
			(start -0.12065 0.3048)
			(end -0.67945 0.3048)
			(stroke
				(width 0.1)
				(type default)
			)
			(layer "F.Fab")
		)
		(fp_line
			(start -0.12065 0.2794)
			(end -0.12065 0.3048)
			(stroke
				(width 0.1)
				(type default)
			)
			(layer "F.Fab")
		)
		(fp_line
			(start -0.12065 -0.2794)
			(end 0.12065 -0.2794)
			(stroke
				(width 0.1)
				(type default)
			)
			(layer "F.Fab")
		)
		(fp_line
			(start -0.12065 -0.305054)
			(end -0.12065 -0.2794)
			(stroke
				(width 0.1)
				(type default)
			)
			(layer "F.Fab")
		)
		(fp_line
			(start -0.67945 0.3048)
			(end -0.67945 -0.305054)
			(stroke
				(width 0.1)
				(type default)
			)
			(layer "F.Fab")
		)
		(fp_line
			(start -0.67945 -0.305054)
			(end -0.12065 -0.305054)
			(stroke
				(width 0.1)
				(type default)
			)
			(layer "F.Fab")
		)
		(pad "1" smd circle
			(at -0.40005 0 180)
			(size 0 0)
			(layers "F.Cu" "F.Mask" "F.Paste")
			(net "GND")
		)
		(pad "2" smd circle
			(at 0.40005 0 180)
			(size 0 0)
			(layers "F.Cu" "F.Mask" "F.Paste")
			(net "SSD6_PWRDIS_R")
		)
	)
	(footprint ""
		(layer "F.Cu")
		(at 17.622774 -22.867366 90)
		(property "Reference" "C3878"
			(at 0 0 90)
			(layer "F.SilkS")
			(hide yes)
			(effects
				(font
					(size 1.27 1.27)
				)
			)
		)
		(property "Value" ""
			(at 0 0 90)
			(layer "F.Fab")
			(effects
				(font
					(size 1.27 1.27)
				)
			)
		)
		(duplicate_pad_numbers_are_jumpers no)
		(fp_line
			(start 0.7874 -0.4064)
			(end 0.7874 0.4064)
			(stroke
				(width 0.1524)
				(type default)
			)
			(layer "F.SilkS")
		)
		(fp_line
			(start -0.7874 -0.4064)
			(end 0.7874 -0.4064)
			(stroke
				(width 0.1524)
				(type default)
			)
			(layer "F.SilkS")
		)
		(fp_line
			(start 0.7874 0.4064)
			(end -0.7874 0.4064)
			(stroke
				(width 0.1524)
				(type default)
			)
			(layer "F.SilkS")
		)
		(fp_line
			(start -0.7874 0.4064)
			(end -0.7874 -0.4064)
			(stroke
				(width 0.1524)
				(type default)
			)
			(layer "F.SilkS")
		)
		(fp_line
			(start -0.12065 -0.305054)
			(end -0.12065 -0.2794)
			(stroke
				(width 0.1)
				(type default)
			)
			(layer "F.Fab")
		)
		(fp_line
			(start -0.67945 -0.305054)
			(end -0.12065 -0.305054)
			(stroke
				(width 0.1)
				(type default)
			)
			(layer "F.Fab")
		)
		(fp_line
			(start 0.67945 -0.3048)
			(end 0.67945 0.3048)
			(stroke
				(width 0.1)
				(type default)
			)
			(layer "F.Fab")
		)
		(fp_line
			(start 0.12065 -0.3048)
			(end 0.67945 -0.3048)
			(stroke
				(width 0.1)
				(type default)
			)
			(layer "F.Fab")
		)
		(fp_line
			(start 0.12065 -0.2794)
			(end 0.12065 -0.3048)
			(stroke
				(width 0.1)
				(type default)
			)
			(layer "F.Fab")
		)
		(fp_line
			(start -0.12065 -0.2794)
			(end 0.12065 -0.2794)
			(stroke
				(width 0.1)
				(type default)
			)
			(layer "F.Fab")
		)
		(fp_line
			(start 0.120396 0.2794)
			(end -0.12065 0.2794)
			(stroke
				(width 0.1)
				(type default)
			)
			(layer "F.Fab")
		)
		(fp_line
			(start -0.12065 0.2794)
			(end -0.12065 0.3048)
			(stroke
				(width 0.1)
				(type default)
			)
			(layer "F.Fab")
		)
		(fp_line
			(start 0.67945 0.3048)
			(end 0.120396 0.3048)
			(stroke
				(width 0.1)
				(type default)
			)
			(layer "F.Fab")
		)
		(fp_line
			(start 0.120396 0.3048)
			(end 0.120396 0.2794)
			(stroke
				(width 0.1)
				(type default)
			)
			(layer "F.Fab")
		)
		(fp_line
			(start -0.12065 0.3048)
			(end -0.67945 0.3048)
			(stroke
				(width 0.1)
				(type default)
			)
			(layer "F.Fab")
		)
		(fp_line
			(start -0.67945 0.3048)
			(end -0.67945 -0.305054)
			(stroke
				(width 0.1)
				(type default)
			)
			(layer "F.Fab")
		)
		(pad "1" smd circle
			(at -0.40005 0 90)
			(size 0 0)
			(layers "F.Cu" "F.Mask" "F.Paste")
			(net "P12V_SSD0")
		)
		(pad "2" smd circle
			(at 0.40005 0 90)
			(size 0 0)
			(layers "F.Cu" "F.Mask" "F.Paste")
			(net "GND")
		)
	)
	(footprint ""
		(layer "F.Cu")
		(at 238.919512 -234.728004 -90)
		(property "Reference" "R6182"
			(at 0 0 270)
			(layer "F.SilkS")
			(hide yes)
			(effects
				(font
					(size 1.27 1.27)
				)
			)
		)
		(property "Value" ""
			(at 0 0 270)
			(layer "F.Fab")
			(effects
				(font
					(size 1.27 1.27)
				)
			)
		)
		(duplicate_pad_numbers_are_jumpers no)
		(fp_line
			(start -0.7874 0.4064)
			(end -0.7874 -0.4064)
			(stroke
				(width 0.1524)
				(type default)
			)
			(layer "F.SilkS")
		)
		(fp_line
			(start 0.7874 0.4064)
			(end -0.7874 0.4064)
			(stroke
				(width 0.1524)
				(type default)
			)
			(layer "F.SilkS")
		)
		(fp_line
			(start -0.7874 -0.4064)
			(end 0.7874 -0.4064)
			(stroke
				(width 0.1524)
				(type default)
			)
			(layer "F.SilkS")
		)
		(fp_line
			(start 0.7874 -0.4064)
			(end 0.7874 0.4064)
			(stroke
				(width 0.1524)
				(type default)
			)
			(layer "F.SilkS")
		)
		(fp_line
			(start -0.67945 0.3048)
			(end -0.67945 -0.305054)
			(stroke
				(width 0.1)
				(type default)
			)
			(layer "F.Fab")
		)
		(fp_line
			(start -0.12065 0.3048)
			(end -0.67945 0.3048)
			(stroke
				(width 0.1)
				(type default)
			)
			(layer "F.Fab")
		)
		(fp_line
			(start 0.120396 0.3048)
			(end 0.120396 0.2794)
			(stroke
				(width 0.1)
				(type default)
			)
			(layer "F.Fab")
		)
		(fp_line
			(start 0.67945 0.3048)
			(end 0.120396 0.3048)
			(stroke
				(width 0.1)
				(type default)
			)
			(layer "F.Fab")
		)
		(fp_line
			(start -0.12065 0.2794)
			(end -0.12065 0.3048)
			(stroke
				(width 0.1)
				(type default)
			)
			(layer "F.Fab")
		)
		(fp_line
			(start 0.120396 0.2794)
			(end -0.12065 0.2794)
			(stroke
				(width 0.1)
				(type default)
			)
			(layer "F.Fab")
		)
		(fp_line
			(start -0.12065 -0.2794)
			(end 0.12065 -0.2794)
			(stroke
				(width 0.1)
				(type default)
			)
			(layer "F.Fab")
		)
		(fp_line
			(start 0.12065 -0.2794)
			(end 0.12065 -0.3048)
			(stroke
				(width 0.1)
				(type default)
			)
			(layer "F.Fab")
		)
		(fp_line
			(start 0.12065 -0.3048)
			(end 0.67945 -0.3048)
			(stroke
				(width 0.1)
				(type default)
			)
			(layer "F.Fab")
		)
		(fp_line
			(start 0.67945 -0.3048)
			(end 0.67945 0.3048)
			(stroke
				(width 0.1)
				(type default)
			)
			(layer "F.Fab")
		)
		(fp_line
			(start -0.67945 -0.305054)
			(end -0.12065 -0.305054)
			(stroke
				(width 0.1)
				(type default)
			)
			(layer "F.Fab")
		)
		(fp_line
			(start -0.12065 -0.305054)
			(end -0.12065 -0.2794)
			(stroke
				(width 0.1)
				(type default)
			)
			(layer "F.Fab")
		)
		(pad "1" smd circle
			(at -0.40005 0 270)
			(size 0 0)
			(layers "F.Cu" "F.Mask" "F.Paste")
			(net "GND")
		)
		(pad "2" smd circle
			(at 0.40005 0 270)
			(size 0 0)
			(layers "F.Cu" "F.Mask" "F.Paste")
			(net "SSD0_PWRDIS_BIC_R")
		)
	)
	(footprint ""
		(layer "F.Cu")
		(at 352.320098 -159.465518 180)
		(property "Reference" "R4826"
			(at 0 0 180)
			(layer "F.SilkS")
			(hide yes)
			(effects
				(font
					(size 1.27 1.27)
				)
			)
		)
		(property "Value" ""
			(at 0 0 180)
			(layer "F.Fab")
			(effects
				(font
					(size 1.27 1.27)
				)
			)
		)
		(duplicate_pad_numbers_are_jumpers no)
		(fp_line
			(start 0.7874 0.4064)
			(end -0.7874 0.4064)
			(stroke
				(width 0.1524)
				(type default)
			)
			(layer "F.SilkS")
		)
		(fp_line
			(start 0.7874 -0.4064)
			(end 0.7874 0.4064)
			(stroke
				(width 0.1524)
				(type default)
			)
			(layer "F.SilkS")
		)
		(fp_line
			(start -0.7874 0.4064)
			(end -0.7874 -0.4064)
			(stroke
				(width 0.1524)
				(type default)
			)
			(layer "F.SilkS")
		)
		(fp_line
			(start -0.7874 -0.4064)
			(end 0.7874 -0.4064)
			(stroke
				(width 0.1524)
				(type default)
			)
			(layer "F.SilkS")
		)
		(fp_line
			(start 0.67945 0.3048)
			(end 0.120396 0.3048)
			(stroke
				(width 0.1)
				(type default)
			)
			(layer "F.Fab")
		)
		(fp_line
			(start 0.67945 -0.3048)
			(end 0.67945 0.3048)
			(stroke
				(width 0.1)
				(type default)
			)
			(layer "F.Fab")
		)
		(fp_line
			(start 0.12065 -0.2794)
			(end 0.12065 -0.3048)
			(stroke
				(width 0.1)
				(type default)
			)
			(layer "F.Fab")
		)
		(fp_line
			(start 0.12065 -0.3048)
			(end 0.67945 -0.3048)
			(stroke
				(width 0.1)
				(type default)
			)
			(layer "F.Fab")
		)
		(fp_line
			(start 0.120396 0.3048)
			(end 0.120396 0.2794)
			(stroke
				(width 0.1)
				(type default)
			)
			(layer "F.Fab")
		)
		(fp_line
			(start 0.120396 0.2794)
			(end -0.12065 0.2794)
			(stroke
				(width 0.1)
				(type default)
			)
			(layer "F.Fab")
		)
		(fp_line
			(start -0.12065 0.3048)
			(end -0.67945 0.3048)
			(stroke
				(width 0.1)
				(type default)
			)
			(layer "F.Fab")
		)
		(fp_line
			(start -0.12065 0.2794)
			(end -0.12065 0.3048)
			(stroke
				(width 0.1)
				(type default)
			)
			(layer "F.Fab")
		)
		(fp_line
			(start -0.12065 -0.2794)
			(end 0.12065 -0.2794)
			(stroke
				(width 0.1)
				(type default)
			)
			(layer "F.Fab")
		)
		(fp_line
			(start -0.12065 -0.305054)
			(end -0.12065 -0.2794)
			(stroke
				(width 0.1)
				(type default)
			)
			(layer "F.Fab")
		)
		(fp_line
			(start -0.67945 0.3048)
			(end -0.67945 -0.305054)
			(stroke
				(width 0.1)
				(type default)
			)
			(layer "F.Fab")
		)
		(fp_line
			(start -0.67945 -0.305054)
			(end -0.12065 -0.305054)
			(stroke
				(width 0.1)
				(type default)
			)
			(layer "F.Fab")
		)
		(pad "1" smd circle
			(at -0.40005 0 180)
			(size 0 0)
			(layers "F.Cu" "F.Mask" "F.Paste")
			(net "GND")
		)
		(pad "2" smd circle
			(at 0.40005 0 180)
			(size 0 0)
			(layers "F.Cu" "F.Mask" "F.Paste")
			(net "PCA9555_0_PEX3_A0")
		)
	)
	(footprint ""
		(layer "F.Cu")
		(at 366.979962 -135.62711 90)
		(property "Reference" "PD98"
			(at -3.49631 2.184908 90)
			(unlocked yes)
			(layer "F.SilkS")
			(effects
				(font
					(size 0.7874 0.5842)
					(thickness 0.1524)
				)
				(justify left)
			)
		)
		(property "Value" ""
			(at 0 0 90)
			(layer "F.Fab")
			(effects
				(font
					(size 1.27 1.27)
				)
			)
		)
		(duplicate_pad_numbers_are_jumpers no)
		(fp_line
			(start 4.107942 -1.459992)
			(end 4.107942 1.459992)
			(stroke
				(width 0.1524)
				(type default)
			)
			(layer "F.SilkS")
		)
		(fp_line
			(start -3.400044 -1.459992)
			(end 4.107942 -1.459992)
			(stroke
				(width 0.1524)
				(type default)
			)
			(layer "F.SilkS")
		)
		(fp_line
			(start 4.107942 1.459992)
			(end -3.400044 1.459992)
			(stroke
				(width 0.1524)
				(type default)
			)
			(layer "F.SilkS")
		)
		(fp_line
			(start -3.400044 1.459992)
			(end -3.400044 -1.459992)
			(stroke
				(width 0.1524)
				(type default)
			)
			(layer "F.SilkS")
		)
		(fp_poly
			(pts
				(xy 4.107942 -1.459992) (xy 4.107942 1.459992) (xy 3.308096 1.459992) (xy 3.308096 -1.459992)
			)
			(stroke
				(width 0)
				(type default)
			)
			(fill yes)
			(layer "F.SilkS")
		)
		(fp_line
			(start 2.29997 -1.459992)
			(end 2.29997 1.459992)
			(stroke
				(width 0.1)
				(type default)
			)
			(layer "F.Fab")
		)
		(fp_line
			(start -2.29997 -1.459992)
			(end 2.29997 -1.459992)
			(stroke
				(width 0.1)
				(type default)
			)
			(layer "F.Fab")
		)
		(fp_line
			(start 2.29997 1.459992)
			(end -2.29997 1.459992)
			(stroke
				(width 0.1)
				(type default)
			)
			(layer "F.Fab")
		)
		(fp_line
			(start -2.29997 1.459992)
			(end -2.29997 -1.459992)
			(stroke
				(width 0.1)
				(type default)
			)
			(layer "F.Fab")
		)
		(fp_text user "+"
			(at -4.7752 -0.12065 90)
			(unlocked yes)
			(layer "F.SilkS")
			(effects
				(font
					(size 1.905 1.4224)
					(thickness 0.1524)
				)
				(justify left)
			)
		)
		(fp_text user "-"
			(at 3.631438 2.56032 270)
			(unlocked yes)
			(layer "F.SilkS")
			(effects
				(font
					(size 1.905 1.4224)
					(thickness 0.1524)
				)
				(justify left)
			)
		)
		(fp_text user "+"
			(at -4.7752 -0.12065 90)
			(unlocked yes)
			(layer "F.Fab")
			(effects
				(font
					(size 1.905 1.4224)
					(thickness 0.1524)
				)
				(justify left)
			)
		)
		(fp_text user "-"
			(at 5.4102 0.29845 270)
			(unlocked yes)
			(layer "F.Fab")
			(effects
				(font
					(size 1.905 1.4224)
					(thickness 0.1524)
				)
				(justify left)
			)
		)
		(pad "A" smd rect
			(at -1.999996 0 180)
			(size 1.7018 2.5146)
			(layers "F.Cu" "F.Mask" "F.Paste")
			(net "GND")
		)
		(pad "C" smd rect
			(at 1.999996 0 180)
			(size 1.7018 2.5146)
			(layers "F.Cu" "F.Mask" "F.Paste")
			(net "P12V_NIC6_R")
		)
	)
	(footprint ""
		(layer "F.Cu")
		(at 381.41148 -258.234434)
		(property "Reference" "L141"
			(at 0 0 0)
			(layer "F.SilkS")
			(hide yes)
			(effects
				(font
					(size 1.27 1.27)
				)
			)
		)
		(property "Value" ""
			(at 0 0 0)
			(layer "F.Fab")
			(effects
				(font
					(size 1.27 1.27)
				)
			)
		)
		(duplicate_pad_numbers_are_jumpers no)
		(fp_line
			(start -1.63576 -0.8128)
			(end -1.63576 0.8128)
			(stroke
				(width 0.1524)
				(type default)
			)
			(layer "F.SilkS")
		)
		(fp_line
			(start -1.63576 -0.8128)
			(end 1.63576 -0.8128)
			(stroke
				(width 0.1524)
				(type default)
			)
			(layer "F.SilkS")
		)
		(fp_line
			(start 1.63576 -0.8128)
			(end 1.63576 0.8128)
			(stroke
				(width 0.1524)
				(type default)
			)
			(layer "F.SilkS")
		)
		(fp_line
			(start 1.63576 0.8128)
			(end -1.63576 0.8128)
			(stroke
				(width 0.1524)
				(type default)
			)
			(layer "F.SilkS")
		)
		(fp_line
			(start -1.56083 -0.738632)
			(end -1.56083 0.7366)
			(stroke
				(width 0.1)
				(type default)
			)
			(layer "F.Fab")
		)
		(fp_line
			(start -1.56083 0.7366)
			(end -1.524 0.7366)
			(stroke
				(width 0.1)
				(type default)
			)
			(layer "F.Fab")
		)
		(fp_line
			(start -1.524 0.7366)
			(end 1.524 0.7366)
			(stroke
				(width 0.1)
				(type default)
			)
			(layer "F.Fab")
		)
		(fp_line
			(start 1.524 0.7366)
			(end 1.560576 0.7366)
			(stroke
				(width 0.1)
				(type default)
			)
			(layer "F.Fab")
		)
		(fp_line
			(start 1.560576 -0.738632)
			(end -1.56083 -0.738632)
			(stroke
				(width 0.1)
				(type default)
			)
			(layer "F.Fab")
		)
		(fp_line
			(start 1.560576 0.7366)
			(end 1.560576 -0.738632)
			(stroke
				(width 0.1)
				(type default)
			)
			(layer "F.Fab")
		)
		(pad "1" smd rect
			(at -0.94996 0 180)
			(size 1.1176 1.3716)
			(layers "F.Cu" "F.Mask" "F.Paste")
			(net "P1V8_PLL0_PEX3")
		)
		(pad "2" smd rect
			(at 0.94996 0 180)
			(size 1.1176 1.3716)
			(layers "F.Cu" "F.Mask" "F.Paste")
			(net "PCEPLL5_VDDA18_PEX3")
		)
	)
	(footprint ""
		(layer "F.Cu")
		(at 82.661506 -155.196794 180)
		(property "Reference" "C2"
			(at 0 0 180)
			(layer "F.SilkS")
			(hide yes)
			(effects
				(font
					(size 1.27 1.27)
				)
			)
		)
		(property "Value" ""
			(at 0 0 180)
			(layer "F.Fab")
			(effects
				(font
					(size 1.27 1.27)
				)
			)
		)
		(duplicate_pad_numbers_are_jumpers no)
		(fp_line
			(start 0.299974 0.150114)
			(end -0.299974 0.150114)
			(stroke
				(width 0.1)
				(type default)
			)
			(layer "F.Fab")
		)
		(fp_line
			(start 0.299974 -0.150114)
			(end 0.299974 0.150114)
			(stroke
				(width 0.1)
				(type default)
			)
			(layer "F.Fab")
		)
		(fp_line
			(start -0.299974 0.150114)
			(end -0.299974 -0.150114)
			(stroke
				(width 0.1)
				(type default)
			)
			(layer "F.Fab")
		)
		(fp_line
			(start -0.299974 -0.150114)
			(end 0.299974 -0.150114)
			(stroke
				(width 0.1)
				(type default)
			)
			(layer "F.Fab")
		)
		(pad "1" smd rect
			(at -0.2667 0 180)
			(size 0.3048 0.381)
			(layers "F.Cu" "F.Mask" "F.Paste")
			(net "P5E_PEX0_STN0_TX_DN<15>")
		)
		(pad "2" smd rect
			(at 0.2667 0 180)
			(size 0.3048 0.381)
			(layers "F.Cu" "F.Mask" "F.Paste")
			(net "P5E_PEX0_STN0_TX_C_DN<15>")
		)
	)
	(footprint ""
		(layer "F.Cu")
		(at 310.467756 -52.035456 180)
		(property "Reference" "R873"
			(at 0 0 180)
			(layer "F.SilkS")
			(hide yes)
			(effects
				(font
					(size 1.27 1.27)
				)
			)
		)
		(property "Value" ""
			(at 0 0 180)
			(layer "F.Fab")
			(effects
				(font
					(size 1.27 1.27)
				)
			)
		)
		(duplicate_pad_numbers_are_jumpers no)
		(fp_line
			(start 0.7874 0.4064)
			(end -0.7874 0.4064)
			(stroke
				(width 0.1524)
				(type default)
			)
			(layer "F.SilkS")
		)
		(fp_line
			(start 0.7874 -0.4064)
			(end 0.7874 0.4064)
			(stroke
				(width 0.1524)
				(type default)
			)
			(layer "F.SilkS")
		)
		(fp_line
			(start -0.7874 0.4064)
			(end -0.7874 -0.4064)
			(stroke
				(width 0.1524)
				(type default)
			)
			(layer "F.SilkS")
		)
		(fp_line
			(start -0.7874 -0.4064)
			(end 0.7874 -0.4064)
			(stroke
				(width 0.1524)
				(type default)
			)
			(layer "F.SilkS")
		)
		(fp_line
			(start 0.67945 0.3048)
			(end 0.120396 0.3048)
			(stroke
				(width 0.1)
				(type default)
			)
			(layer "F.Fab")
		)
		(fp_line
			(start 0.67945 -0.3048)
			(end 0.67945 0.3048)
			(stroke
				(width 0.1)
				(type default)
			)
			(layer "F.Fab")
		)
		(fp_line
			(start 0.12065 -0.2794)
			(end 0.12065 -0.3048)
			(stroke
				(width 0.1)
				(type default)
			)
			(layer "F.Fab")
		)
		(fp_line
			(start 0.12065 -0.3048)
			(end 0.67945 -0.3048)
			(stroke
				(width 0.1)
				(type default)
			)
			(layer "F.Fab")
		)
		(fp_line
			(start 0.120396 0.3048)
			(end 0.120396 0.2794)
			(stroke
				(width 0.1)
				(type default)
			)
			(layer "F.Fab")
		)
		(fp_line
			(start 0.120396 0.2794)
			(end -0.12065 0.2794)
			(stroke
				(width 0.1)
				(type default)
			)
			(layer "F.Fab")
		)
		(fp_line
			(start -0.12065 0.3048)
			(end -0.67945 0.3048)
			(stroke
				(width 0.1)
				(type default)
			)
			(layer "F.Fab")
		)
		(fp_line
			(start -0.12065 0.2794)
			(end -0.12065 0.3048)
			(stroke
				(width 0.1)
				(type default)
			)
			(layer "F.Fab")
		)
		(fp_line
			(start -0.12065 -0.2794)
			(end 0.12065 -0.2794)
			(stroke
				(width 0.1)
				(type default)
			)
			(layer "F.Fab")
		)
		(fp_line
			(start -0.12065 -0.305054)
			(end -0.12065 -0.2794)
			(stroke
				(width 0.1)
				(type default)
			)
			(layer "F.Fab")
		)
		(fp_line
			(start -0.67945 0.3048)
			(end -0.67945 -0.305054)
			(stroke
				(width 0.1)
				(type default)
			)
			(layer "F.Fab")
		)
		(fp_line
			(start -0.67945 -0.305054)
			(end -0.12065 -0.305054)
			(stroke
				(width 0.1)
				(type default)
			)
			(layer "F.Fab")
		)
		(pad "1" smd circle
			(at -0.40005 0 180)
			(size 0 0)
			(layers "F.Cu" "F.Mask" "F.Paste")
			(net "P3V3_AUX")
		)
		(pad "2" smd circle
			(at 0.40005 0 180)
			(size 0 0)
			(layers "F.Cu" "F.Mask" "F.Paste")
			(net "PWRGD_P12V_SSD10")
		)
	)
	(footprint ""
		(layer "F.Cu")
		(at 407.295096 -96.702372 180)
		(property "Reference" "R404"
			(at 0 0 180)
			(layer "F.SilkS")
			(hide yes)
			(effects
				(font
					(size 1.27 1.27)
				)
			)
		)
		(property "Value" ""
			(at 0 0 180)
			(layer "F.Fab")
			(effects
				(font
					(size 1.27 1.27)
				)
			)
		)
		(duplicate_pad_numbers_are_jumpers no)
		(fp_line
			(start 0.7874 0.4064)
			(end -0.7874 0.4064)
			(stroke
				(width 0.1524)
				(type default)
			)
			(layer "F.SilkS")
		)
		(fp_line
			(start 0.7874 -0.4064)
			(end 0.7874 0.4064)
			(stroke
				(width 0.1524)
				(type default)
			)
			(layer "F.SilkS")
		)
		(fp_line
			(start -0.7874 0.4064)
			(end -0.7874 -0.4064)
			(stroke
				(width 0.1524)
				(type default)
			)
			(layer "F.SilkS")
		)
		(fp_line
			(start -0.7874 -0.4064)
			(end 0.7874 -0.4064)
			(stroke
				(width 0.1524)
				(type default)
			)
			(layer "F.SilkS")
		)
		(fp_line
			(start 0.67945 0.3048)
			(end 0.120396 0.3048)
			(stroke
				(width 0.1)
				(type default)
			)
			(layer "F.Fab")
		)
		(fp_line
			(start 0.67945 -0.3048)
			(end 0.67945 0.3048)
			(stroke
				(width 0.1)
				(type default)
			)
			(layer "F.Fab")
		)
		(fp_line
			(start 0.12065 -0.2794)
			(end 0.12065 -0.3048)
			(stroke
				(width 0.1)
				(type default)
			)
			(layer "F.Fab")
		)
		(fp_line
			(start 0.12065 -0.3048)
			(end 0.67945 -0.3048)
			(stroke
				(width 0.1)
				(type default)
			)
			(layer "F.Fab")
		)
		(fp_line
			(start 0.120396 0.3048)
			(end 0.120396 0.2794)
			(stroke
				(width 0.1)
				(type default)
			)
			(layer "F.Fab")
		)
		(fp_line
			(start 0.120396 0.2794)
			(end -0.12065 0.2794)
			(stroke
				(width 0.1)
				(type default)
			)
			(layer "F.Fab")
		)
		(fp_line
			(start -0.12065 0.3048)
			(end -0.67945 0.3048)
			(stroke
				(width 0.1)
				(type default)
			)
			(layer "F.Fab")
		)
		(fp_line
			(start -0.12065 0.2794)
			(end -0.12065 0.3048)
			(stroke
				(width 0.1)
				(type default)
			)
			(layer "F.Fab")
		)
		(fp_line
			(start -0.12065 -0.2794)
			(end 0.12065 -0.2794)
			(stroke
				(width 0.1)
				(type default)
			)
			(layer "F.Fab")
		)
		(fp_line
			(start -0.12065 -0.305054)
			(end -0.12065 -0.2794)
			(stroke
				(width 0.1)
				(type default)
			)
			(layer "F.Fab")
		)
		(fp_line
			(start -0.67945 0.3048)
			(end -0.67945 -0.305054)
			(stroke
				(width 0.1)
				(type default)
			)
			(layer "F.Fab")
		)
		(fp_line
			(start -0.67945 -0.305054)
			(end -0.12065 -0.305054)
			(stroke
				(width 0.1)
				(type default)
			)
			(layer "F.Fab")
		)
		(pad "1" smd circle
			(at -0.40005 0 180)
			(size 0 0)
			(layers "F.Cu" "F.Mask" "F.Paste")
			(net "RST_NIC7_PERST2_R_N")
		)
		(pad "2" smd circle
			(at 0.40005 0 180)
			(size 0 0)
			(layers "F.Cu" "F.Mask" "F.Paste")
			(net "RST_HP_NIC7_BUF_N")
		)
	)
	(footprint ""
		(layer "F.Cu")
		(at 218.503754 -102.241604 90)
		(property "Reference" "U82"
			(at 0.983996 -2.399284 90)
			(unlocked yes)
			(layer "F.SilkS")
			(effects
				(font
					(size 0.7874 0.5842)
					(thickness 0.1524)
				)
			)
		)
		(property "Value" ""
			(at 0 0 90)
			(layer "F.Fab")
			(effects
				(font
					(size 1.27 1.27)
				)
			)
		)
		(duplicate_pad_numbers_are_jumpers no)
		(fp_line
			(start 1.500124 -1.500124)
			(end 1.500124 -1.004062)
			(stroke
				(width 0.1524)
				(type default)
			)
			(layer "F.SilkS")
		)
		(fp_line
			(start 1.004062 -1.500124)
			(end 1.500124 -1.500124)
			(stroke
				(width 0.1524)
				(type default)
			)
			(layer "F.SilkS")
		)
		(fp_line
			(start -1.500124 -1.500124)
			(end -1.004062 -1.500124)
			(stroke
				(width 0.1524)
				(type default)
			)
			(layer "F.SilkS")
		)
		(fp_line
			(start -1.500124 -1.004062)
			(end -1.500124 -1.500124)
			(stroke
				(width 0.1524)
				(type default)
			)
			(layer "F.SilkS")
		)
		(fp_line
			(start 1.500124 1.004062)
			(end 1.500124 1.500124)
			(stroke
				(width 0.1524)
				(type default)
			)
			(layer "F.SilkS")
		)
		(fp_line
			(start 1.500124 1.500124)
			(end 1.004062 1.500124)
			(stroke
				(width 0.1524)
				(type default)
			)
			(layer "F.SilkS")
		)
		(fp_line
			(start -1.004062 1.500124)
			(end -1.500124 1.500124)
			(stroke
				(width 0.1524)
				(type default)
			)
			(layer "F.SilkS")
		)
		(fp_line
			(start -1.500124 1.500124)
			(end -1.500124 1.004062)
			(stroke
				(width 0.1524)
				(type default)
			)
			(layer "F.SilkS")
		)
		(fp_poly
			(pts
				(xy -2.554986 -0.388366) (xy -1.831848 -0.750062) (xy -2.554986 -1.111504)
			)
			(stroke
				(width 0)
				(type default)
			)
			(fill yes)
			(layer "F.SilkS")
		)
		(fp_line
			(start 1.500124 -1.500124)
			(end 1.500124 1.500124)
			(stroke
				(width 0.1)
				(type default)
			)
			(layer "F.Fab")
		)
		(fp_line
			(start -1.500124 -1.500124)
			(end 1.500124 -1.500124)
			(stroke
				(width 0.1)
				(type default)
			)
			(layer "F.Fab")
		)
		(fp_line
			(start 1.500124 1.500124)
			(end -1.500124 1.500124)
			(stroke
				(width 0.1)
				(type default)
			)
			(layer "F.Fab")
		)
		(fp_line
			(start -1.500124 1.500124)
			(end -1.500124 -1.500124)
			(stroke
				(width 0.1)
				(type default)
			)
			(layer "F.Fab")
		)
		(fp_poly
			(pts
				(xy -2.847848 -1.258062) (xy -2.847848 -0.242062) (xy -1.831848 -0.750062)
			)
			(stroke
				(width 0)
				(type default)
			)
			(fill yes)
			(layer "F.Fab")
		)
		(pad "1" smd rect
			(at -1.400048 -0.750062)
			(size 0.2286 0.6096)
			(layers "F.Cu" "F.Mask" "F.Paste")
			(net "NIC3_ADC_A1")
		)
		(pad "2" smd rect
			(at -1.400048 -0.249936)
			(size 0.2286 0.6096)
			(layers "F.Cu" "F.Mask" "F.Paste")
			(net "NIC3_ADC_A0")
		)
		(pad "3" smd rect
			(at -1.400048 0.249936)
			(size 0.2286 0.6096)
			(layers "F.Cu" "F.Mask" "F.Paste")
			(net "NIC3_ADC_ALERT_N")
		)
		(pad "4" smd rect
			(at -1.400048 0.750062)
			(size 0.2286 0.6096)
			(layers "F.Cu" "F.Mask" "F.Paste")
			(net "SMB_NIC3_ADC_SDA")
		)
		(pad "5" smd rect
			(at -0.750062 1.400048 90)
			(size 0.2286 0.6096)
			(layers "F.Cu" "F.Mask" "F.Paste")
			(net "SMB_NIC3_ADC_SCL")
		)
		(pad "6" smd rect
			(at -0.249936 1.400048 90)
			(size 0.2286 0.6096)
			(layers "F.Cu" "F.Mask" "F.Paste")
			(net "Net_8648")
		)
		(pad "7" smd rect
			(at 0.249936 1.400048 90)
			(size 0.2286 0.6096)
			(layers "F.Cu" "F.Mask" "F.Paste")
			(net "Net_8647")
		)
		(pad "8" smd rect
			(at 0.750062 1.400048 90)
			(size 0.2286 0.6096)
			(layers "F.Cu" "F.Mask" "F.Paste")
			(net "Net_8646")
		)
		(pad "9" smd rect
			(at 1.400048 0.750062)
			(size 0.2286 0.6096)
			(layers "F.Cu" "F.Mask" "F.Paste")
			(net "P3V3_AUX")
		)
		(pad "10" smd rect
			(at 1.400048 0.249936)
			(size 0.2286 0.6096)
			(layers "F.Cu" "F.Mask" "F.Paste")
			(net "GND")
		)
		(pad "11" smd rect
			(at 1.400048 -0.249936)
			(size 0.2286 0.6096)
			(layers "F.Cu" "F.Mask" "F.Paste")
			(net "P12V_NIC3_R")
		)
		(pad "12" smd rect
			(at 1.400048 -0.750062)
			(size 0.2286 0.6096)
			(layers "F.Cu" "F.Mask" "F.Paste")
			(net "P12V_NIC3_VIN_N")
		)
		(pad "13" smd rect
			(at 0.750062 -1.400048 90)
			(size 0.2286 0.6096)
			(layers "F.Cu" "F.Mask" "F.Paste")
			(net "P12V_NIC3_VIN_P")
		)
		(pad "14" smd rect
			(at 0.249936 -1.400048 90)
			(size 0.2286 0.6096)
			(layers "F.Cu" "F.Mask" "F.Paste")
			(net "Net_8645")
		)
		(pad "15" smd rect
			(at -0.249936 -1.400048 90)
			(size 0.2286 0.6096)
			(layers "F.Cu" "F.Mask" "F.Paste")
			(net "Net_8644")
		)
		(pad "16" smd rect
			(at -0.750062 -1.400048 90)
			(size 0.2286 0.6096)
			(layers "F.Cu" "F.Mask" "F.Paste")
			(net "Net_8643")
		)
		(pad "TH" smd rect
			(at 0 0 90)
			(size 1.7018 1.7018)
			(layers "F.Cu" "F.Mask" "F.Paste")
			(net "GND")
		)
		(zone
			(layer "F.Cu")
			(hatch none 0.5)
			(connect_pads
				(clearance 0)
			)
			(min_thickness 0.25)
			(keepout
				(tracks not_allowed)
				(vias allowed)
				(pads allowed)
				(copperpour not_allowed)
				(footprints allowed)
			)
			(placement
				(enabled no)
				(sheetname "")
			)
			(fill
				(thermal_gap 0.5)
				(thermal_bridge_width 0.5)
				(island_removal_mode 0)
			)
			(polygon
				(pts
					(xy 218.478354 -101.197156) (xy 217.459306 -101.197156) (xy 217.459306 -103.286052) (xy 219.548202 -103.286052)
					(xy 219.548202 -101.197156) (xy 218.503754 -101.197156) (xy 218.503754 -101.339904) (xy 219.405454 -101.339904)
					(xy 219.405454 -103.143304) (xy 217.602054 -103.143304) (xy 217.602054 -101.339904) (xy 218.478354 -101.339904)
				)
			)
		)
	)
	(footprint ""
		(layer "F.Cu")
		(at 152.738328 -119.198898)
		(property "Reference" "C258"
			(at 0 0 0)
			(layer "F.SilkS")
			(hide yes)
			(effects
				(font
					(size 1.27 1.27)
				)
			)
		)
		(property "Value" ""
			(at 0 0 0)
			(layer "F.Fab")
			(effects
				(font
					(size 1.27 1.27)
				)
			)
		)
		(duplicate_pad_numbers_are_jumpers no)
		(fp_line
			(start -0.299974 -0.150114)
			(end 0.299974 -0.150114)
			(stroke
				(width 0.1)
				(type default)
			)
			(layer "F.Fab")
		)
		(fp_line
			(start -0.299974 0.150114)
			(end -0.299974 -0.150114)
			(stroke
				(width 0.1)
				(type default)
			)
			(layer "F.Fab")
		)
		(fp_line
			(start 0.299974 -0.150114)
			(end 0.299974 0.150114)
			(stroke
				(width 0.1)
				(type default)
			)
			(layer "F.Fab")
		)
		(fp_line
			(start 0.299974 0.150114)
			(end -0.299974 0.150114)
			(stroke
				(width 0.1)
				(type default)
			)
			(layer "F.Fab")
		)
		(pad "1" smd rect
			(at -0.2667 0)
			(size 0.3048 0.381)
			(layers "F.Cu" "F.Mask" "F.Paste")
			(net "P5E_PEX1_STN1_TX_DP<24>")
		)
		(pad "2" smd rect
			(at 0.2667 0)
			(size 0.3048 0.381)
			(layers "F.Cu" "F.Mask" "F.Paste")
			(net "P5E_PEX1_STN1_TX_C_DP<24>")
		)
	)
	(footprint ""
		(layer "F.Cu")
		(at 278.646382 -58.323734)
		(property "Reference" "PC415"
			(at 0 0 0)
			(layer "F.SilkS")
			(hide yes)
			(effects
				(font
					(size 1.27 1.27)
				)
			)
		)
		(property "Value" ""
			(at 0 0 0)
			(layer "F.Fab")
			(effects
				(font
					(size 1.27 1.27)
				)
			)
		)
		(duplicate_pad_numbers_are_jumpers no)
		(fp_line
			(start -1.524 -0.762)
			(end 1.524 -0.762)
			(stroke
				(width 0.1524)
				(type default)
			)
			(layer "F.SilkS")
		)
		(fp_line
			(start -1.524 0.762)
			(end -1.524 -0.762)
			(stroke
				(width 0.1524)
				(type default)
			)
			(layer "F.SilkS")
		)
		(fp_line
			(start 1.524 -0.762)
			(end 1.524 0.762)
			(stroke
				(width 0.1524)
				(type default)
			)
			(layer "F.SilkS")
		)
		(fp_line
			(start 1.524 0.762)
			(end -1.524 0.762)
			(stroke
				(width 0.1524)
				(type default)
			)
			(layer "F.SilkS")
		)
		(fp_line
			(start -1.1049 -0.724916)
			(end -1.1049 0.724916)
			(stroke
				(width 0.1)
				(type default)
			)
			(layer "F.Fab")
		)
		(fp_line
			(start -1.1049 0.724916)
			(end 1.1049 0.724916)
			(stroke
				(width 0.1)
				(type default)
			)
			(layer "F.Fab")
		)
		(fp_line
			(start 1.1049 -0.724916)
			(end -1.1049 -0.724916)
			(stroke
				(width 0.1)
				(type default)
			)
			(layer "F.Fab")
		)
		(fp_line
			(start 1.1049 0.724916)
			(end 1.1049 -0.724916)
			(stroke
				(width 0.1)
				(type default)
			)
			(layer "F.Fab")
		)
		(pad "1" smd rect
			(at -0.889 0 180)
			(size 1.016 1.27)
			(layers "F.Cu" "F.Mask" "F.Paste")
			(net "GND")
		)
		(pad "2" smd rect
			(at 0.889 0 180)
			(size 1.016 1.27)
			(layers "F.Cu" "F.Mask" "F.Paste")
			(net "P12V_AUX")
		)
	)
	(footprint ""
		(layer "F.Cu")
		(at 196.119242 -150.70455 180)
		(property "Reference" "C218"
			(at 0 0 180)
			(layer "F.SilkS")
			(hide yes)
			(effects
				(font
					(size 1.27 1.27)
				)
			)
		)
		(property "Value" ""
			(at 0 0 180)
			(layer "F.Fab")
			(effects
				(font
					(size 1.27 1.27)
				)
			)
		)
		(duplicate_pad_numbers_are_jumpers no)
		(fp_line
			(start 0.299974 0.150114)
			(end -0.299974 0.150114)
			(stroke
				(width 0.1)
				(type default)
			)
			(layer "F.Fab")
		)
		(fp_line
			(start 0.299974 -0.150114)
			(end 0.299974 0.150114)
			(stroke
				(width 0.1)
				(type default)
			)
			(layer "F.Fab")
		)
		(fp_line
			(start -0.299974 0.150114)
			(end -0.299974 -0.150114)
			(stroke
				(width 0.1)
				(type default)
			)
			(layer "F.Fab")
		)
		(fp_line
			(start -0.299974 -0.150114)
			(end 0.299974 -0.150114)
			(stroke
				(width 0.1)
				(type default)
			)
			(layer "F.Fab")
		)
		(pad "1" smd rect
			(at -0.2667 0 180)
			(size 0.3048 0.381)
			(layers "F.Cu" "F.Mask" "F.Paste")
			(net "P5E_PEX1_STN0_TX_DN<12>")
		)
		(pad "2" smd rect
			(at 0.2667 0 180)
			(size 0.3048 0.381)
			(layers "F.Cu" "F.Mask" "F.Paste")
			(net "P5E_PEX1_STN0_TX_C_DN<12>")
		)
	)
	(footprint ""
		(layer "F.Cu")
		(at 375.632218 -32.848042 90)
		(property "Reference" "PC967"
			(at 0 0 90)
			(layer "F.SilkS")
			(hide yes)
			(effects
				(font
					(size 1.27 1.27)
				)
			)
		)
		(property "Value" ""
			(at 0 0 90)
			(layer "F.Fab")
			(effects
				(font
					(size 1.27 1.27)
				)
			)
		)
		(duplicate_pad_numbers_are_jumpers no)
		(fp_line
			(start 0.7874 -0.4064)
			(end 0.7874 0.4064)
			(stroke
				(width 0.1524)
				(type default)
			)
			(layer "F.SilkS")
		)
		(fp_line
			(start -0.7874 -0.4064)
			(end 0.7874 -0.4064)
			(stroke
				(width 0.1524)
				(type default)
			)
			(layer "F.SilkS")
		)
		(fp_line
			(start 0.7874 0.4064)
			(end -0.7874 0.4064)
			(stroke
				(width 0.1524)
				(type default)
			)
			(layer "F.SilkS")
		)
		(fp_line
			(start -0.7874 0.4064)
			(end -0.7874 -0.4064)
			(stroke
				(width 0.1524)
				(type default)
			)
			(layer "F.SilkS")
		)
		(fp_line
			(start -0.12065 -0.305054)
			(end -0.12065 -0.2794)
			(stroke
				(width 0.1)
				(type default)
			)
			(layer "F.Fab")
		)
		(fp_line
			(start -0.67945 -0.305054)
			(end -0.12065 -0.305054)
			(stroke
				(width 0.1)
				(type default)
			)
			(layer "F.Fab")
		)
		(fp_line
			(start 0.67945 -0.3048)
			(end 0.67945 0.3048)
			(stroke
				(width 0.1)
				(type default)
			)
			(layer "F.Fab")
		)
		(fp_line
			(start 0.12065 -0.3048)
			(end 0.67945 -0.3048)
			(stroke
				(width 0.1)
				(type default)
			)
			(layer "F.Fab")
		)
		(fp_line
			(start 0.12065 -0.2794)
			(end 0.12065 -0.3048)
			(stroke
				(width 0.1)
				(type default)
			)
			(layer "F.Fab")
		)
		(fp_line
			(start -0.12065 -0.2794)
			(end 0.12065 -0.2794)
			(stroke
				(width 0.1)
				(type default)
			)
			(layer "F.Fab")
		)
		(fp_line
			(start 0.120396 0.2794)
			(end -0.12065 0.2794)
			(stroke
				(width 0.1)
				(type default)
			)
			(layer "F.Fab")
		)
		(fp_line
			(start -0.12065 0.2794)
			(end -0.12065 0.3048)
			(stroke
				(width 0.1)
				(type default)
			)
			(layer "F.Fab")
		)
		(fp_line
			(start 0.67945 0.3048)
			(end 0.120396 0.3048)
			(stroke
				(width 0.1)
				(type default)
			)
			(layer "F.Fab")
		)
		(fp_line
			(start 0.120396 0.3048)
			(end 0.120396 0.2794)
			(stroke
				(width 0.1)
				(type default)
			)
			(layer "F.Fab")
		)
		(fp_line
			(start -0.12065 0.3048)
			(end -0.67945 0.3048)
			(stroke
				(width 0.1)
				(type default)
			)
			(layer "F.Fab")
		)
		(fp_line
			(start -0.67945 0.3048)
			(end -0.67945 -0.305054)
			(stroke
				(width 0.1)
				(type default)
			)
			(layer "F.Fab")
		)
		(pad "1" smd circle
			(at -0.40005 0 90)
			(size 0 0)
			(layers "F.Cu" "F.Mask" "F.Paste")
			(net "P3V3_SSD13_CO_DV_DT")
		)
		(pad "2" smd circle
			(at 0.40005 0 90)
			(size 0 0)
			(layers "F.Cu" "F.Mask" "F.Paste")
			(net "GND")
		)
	)
	(footprint ""
		(layer "F.Cu")
		(at 310.224932 -14.735302 180)
		(property "Reference" "C2732"
			(at 0 0 180)
			(layer "F.SilkS")
			(hide yes)
			(effects
				(font
					(size 1.27 1.27)
				)
			)
		)
		(property "Value" ""
			(at 0 0 180)
			(layer "F.Fab")
			(effects
				(font
					(size 1.27 1.27)
				)
			)
		)
		(duplicate_pad_numbers_are_jumpers no)
		(fp_line
			(start 0.7874 0.4064)
			(end -0.7874 0.4064)
			(stroke
				(width 0.1524)
				(type default)
			)
			(layer "F.SilkS")
		)
		(fp_line
			(start 0.7874 -0.4064)
			(end 0.7874 0.4064)
			(stroke
				(width 0.1524)
				(type default)
			)
			(layer "F.SilkS")
		)
		(fp_line
			(start -0.7874 0.4064)
			(end -0.7874 -0.4064)
			(stroke
				(width 0.1524)
				(type default)
			)
			(layer "F.SilkS")
		)
		(fp_line
			(start -0.7874 -0.4064)
			(end 0.7874 -0.4064)
			(stroke
				(width 0.1524)
				(type default)
			)
			(layer "F.SilkS")
		)
		(fp_line
			(start 0.67945 0.3048)
			(end 0.120396 0.3048)
			(stroke
				(width 0.1)
				(type default)
			)
			(layer "F.Fab")
		)
		(fp_line
			(start 0.67945 -0.3048)
			(end 0.67945 0.3048)
			(stroke
				(width 0.1)
				(type default)
			)
			(layer "F.Fab")
		)
		(fp_line
			(start 0.12065 -0.2794)
			(end 0.12065 -0.3048)
			(stroke
				(width 0.1)
				(type default)
			)
			(layer "F.Fab")
		)
		(fp_line
			(start 0.12065 -0.3048)
			(end 0.67945 -0.3048)
			(stroke
				(width 0.1)
				(type default)
			)
			(layer "F.Fab")
		)
		(fp_line
			(start 0.120396 0.3048)
			(end 0.120396 0.2794)
			(stroke
				(width 0.1)
				(type default)
			)
			(layer "F.Fab")
		)
		(fp_line
			(start 0.120396 0.2794)
			(end -0.12065 0.2794)
			(stroke
				(width 0.1)
				(type default)
			)
			(layer "F.Fab")
		)
		(fp_line
			(start -0.12065 0.3048)
			(end -0.67945 0.3048)
			(stroke
				(width 0.1)
				(type default)
			)
			(layer "F.Fab")
		)
		(fp_line
			(start -0.12065 0.2794)
			(end -0.12065 0.3048)
			(stroke
				(width 0.1)
				(type default)
			)
			(layer "F.Fab")
		)
		(fp_line
			(start -0.12065 -0.2794)
			(end 0.12065 -0.2794)
			(stroke
				(width 0.1)
				(type default)
			)
			(layer "F.Fab")
		)
		(fp_line
			(start -0.12065 -0.305054)
			(end -0.12065 -0.2794)
			(stroke
				(width 0.1)
				(type default)
			)
			(layer "F.Fab")
		)
		(fp_line
			(start -0.67945 0.3048)
			(end -0.67945 -0.305054)
			(stroke
				(width 0.1)
				(type default)
			)
			(layer "F.Fab")
		)
		(fp_line
			(start -0.67945 -0.305054)
			(end -0.12065 -0.305054)
			(stroke
				(width 0.1)
				(type default)
			)
			(layer "F.Fab")
		)
		(pad "1" smd circle
			(at -0.40005 0 180)
			(size 0 0)
			(layers "F.Cu" "F.Mask" "F.Paste")
			(net "GND")
		)
		(pad "2" smd circle
			(at 0.40005 0 180)
			(size 0 0)
			(layers "F.Cu" "F.Mask" "F.Paste")
			(net "P3V3_SSD10")
		)
	)
	(footprint ""
		(layer "F.Cu")
		(at 447.676778 -208.504282)
		(property "Reference" "R1000"
			(at 0 0 0)
			(layer "F.SilkS")
			(hide yes)
			(effects
				(font
					(size 1.27 1.27)
				)
			)
		)
		(property "Value" ""
			(at 0 0 0)
			(layer "F.Fab")
			(effects
				(font
					(size 1.27 1.27)
				)
			)
		)
		(duplicate_pad_numbers_are_jumpers no)
		(fp_line
			(start 0.7874 0.4064)
			(end -0.7874 0.4064)
			(stroke
				(width 0.1524)
				(type default)
			)
			(layer "F.SilkS")
		)
		(fp_line
			(start -0.67945 -0.305054)
			(end -0.12065 -0.305054)
			(stroke
				(width 0.1)
				(type default)
			)
			(layer "F.Fab")
		)
		(fp_line
			(start -0.67945 0.3048)
			(end -0.67945 -0.305054)
			(stroke
				(width 0.1)
				(type default)
			)
			(layer "F.Fab")
		)
		(fp_line
			(start -0.12065 -0.305054)
			(end -0.12065 -0.2794)
			(stroke
				(width 0.1)
				(type default)
			)
			(layer "F.Fab")
		)
		(fp_line
			(start -0.12065 -0.2794)
			(end 0.12065 -0.2794)
			(stroke
				(width 0.1)
				(type default)
			)
			(layer "F.Fab")
		)
		(fp_line
			(start -0.12065 0.2794)
			(end -0.12065 0.3048)
			(stroke
				(width 0.1)
				(type default)
			)
			(layer "F.Fab")
		)
		(fp_line
			(start -0.12065 0.3048)
			(end -0.67945 0.3048)
			(stroke
				(width 0.1)
				(type default)
			)
			(layer "F.Fab")
		)
		(fp_line
			(start 0.120396 0.2794)
			(end -0.12065 0.2794)
			(stroke
				(width 0.1)
				(type default)
			)
			(layer "F.Fab")
		)
		(fp_line
			(start 0.120396 0.3048)
			(end 0.120396 0.2794)
			(stroke
				(width 0.1)
				(type default)
			)
			(layer "F.Fab")
		)
		(fp_line
			(start 0.12065 -0.3048)
			(end 0.67945 -0.3048)
			(stroke
				(width 0.1)
				(type default)
			)
			(layer "F.Fab")
		)
		(fp_line
			(start 0.12065 -0.2794)
			(end 0.12065 -0.3048)
			(stroke
				(width 0.1)
				(type default)
			)
			(layer "F.Fab")
		)
		(fp_line
			(start 0.67945 -0.3048)
			(end 0.67945 0.3048)
			(stroke
				(width 0.1)
				(type default)
			)
			(layer "F.Fab")
		)
		(fp_line
			(start 0.67945 0.3048)
			(end 0.120396 0.3048)
			(stroke
				(width 0.1)
				(type default)
			)
			(layer "F.Fab")
		)
		(pad "1" smd circle
			(at -0.40005 0)
			(size 0 0)
			(layers "F.Cu" "F.Mask" "F.Paste")
			(net "USB2_MICRO_DN")
		)
		(pad "2" smd circle
			(at 0.40005 0)
			(size 0 0)
			(layers "F.Cu" "F.Mask" "F.Paste")
			(net "USB2_FT4232_MUX_D_DN")
		)
	)
	(footprint ""
		(layer "F.Cu")
		(at 211.892388 -32.739584 180)
		(property "Reference" "C302"
			(at 0 0 180)
			(layer "F.SilkS")
			(hide yes)
			(effects
				(font
					(size 1.27 1.27)
				)
			)
		)
		(property "Value" ""
			(at 0 0 180)
			(layer "F.Fab")
			(effects
				(font
					(size 1.27 1.27)
				)
			)
		)
		(duplicate_pad_numbers_are_jumpers no)
		(fp_line
			(start 0.299974 0.150114)
			(end -0.299974 0.150114)
			(stroke
				(width 0.1)
				(type default)
			)
			(layer "F.Fab")
		)
		(fp_line
			(start 0.299974 -0.150114)
			(end 0.299974 0.150114)
			(stroke
				(width 0.1)
				(type default)
			)
			(layer "F.Fab")
		)
		(fp_line
			(start -0.299974 0.150114)
			(end -0.299974 -0.150114)
			(stroke
				(width 0.1)
				(type default)
			)
			(layer "F.Fab")
		)
		(fp_line
			(start -0.299974 -0.150114)
			(end 0.299974 -0.150114)
			(stroke
				(width 0.1)
				(type default)
			)
			(layer "F.Fab")
		)
		(pad "1" smd rect
			(at -0.2667 0 180)
			(size 0.3048 0.381)
			(layers "F.Cu" "F.Mask" "F.Paste")
			(net "P5E_PEX1_STN2_TX_DP<34>")
		)
		(pad "2" smd rect
			(at 0.2667 0 180)
			(size 0.3048 0.381)
			(layers "F.Cu" "F.Mask" "F.Paste")
			(net "P5E_PEX1_STN2_TX_C_DP<34>")
		)
	)
	(footprint ""
		(layer "F.Cu")
		(at 271.895062 -343.952322 90)
		(property "Reference" "C612"
			(at 0 0 90)
			(layer "F.SilkS")
			(hide yes)
			(effects
				(font
					(size 1.27 1.27)
				)
			)
		)
		(property "Value" ""
			(at 0 0 90)
			(layer "F.Fab")
			(effects
				(font
					(size 1.27 1.27)
				)
			)
		)
		(duplicate_pad_numbers_are_jumpers no)
		(fp_line
			(start 0.299974 -0.150114)
			(end 0.299974 0.150114)
			(stroke
				(width 0.1)
				(type default)
			)
			(layer "F.Fab")
		)
		(fp_line
			(start -0.299974 -0.150114)
			(end 0.299974 -0.150114)
			(stroke
				(width 0.1)
				(type default)
			)
			(layer "F.Fab")
		)
		(fp_line
			(start 0.299974 0.150114)
			(end -0.299974 0.150114)
			(stroke
				(width 0.1)
				(type default)
			)
			(layer "F.Fab")
		)
		(fp_line
			(start -0.299974 0.150114)
			(end -0.299974 -0.150114)
			(stroke
				(width 0.1)
				(type default)
			)
			(layer "F.Fab")
		)
		(pad "1" smd rect
			(at -0.2667 0 90)
			(size 0.3048 0.381)
			(layers "F.Cu" "F.Mask" "F.Paste")
			(net "P5E_PEX2_STN7_TX_DN<113>")
		)
		(pad "2" smd rect
			(at 0.2667 0 90)
			(size 0.3048 0.381)
			(layers "F.Cu" "F.Mask" "F.Paste")
			(net "P5E_PEX2_STN7_TX_C_DN<113>")
		)
	)
	(footprint ""
		(layer "F.Cu")
		(at 291.090858 -55.663846 90)
		(property "Reference" "PU66"
			(at -1.23063 2.755392 90)
			(unlocked yes)
			(layer "F.SilkS")
			(effects
				(font
					(size 0.7874 0.5842)
					(thickness 0.1524)
				)
				(justify left)
			)
		)
		(property "Value" ""
			(at 0 0 90)
			(layer "F.Fab")
			(effects
				(font
					(size 1.27 1.27)
				)
			)
		)
		(duplicate_pad_numbers_are_jumpers no)
		(fp_line
			(start 1.943608 -1.549908)
			(end 1.943608 1.549908)
			(stroke
				(width 0.1524)
				(type default)
			)
			(layer "F.SilkS")
		)
		(fp_line
			(start -1.943608 -1.549908)
			(end 1.943608 -1.549908)
			(stroke
				(width 0.1524)
				(type default)
			)
			(layer "F.SilkS")
		)
		(fp_line
			(start 1.943608 1.549908)
			(end -1.943608 1.549908)
			(stroke
				(width 0.1524)
				(type default)
			)
			(layer "F.SilkS")
		)
		(fp_line
			(start -1.943608 1.549908)
			(end -1.943608 -1.549908)
			(stroke
				(width 0.1524)
				(type default)
			)
			(layer "F.SilkS")
		)
		(fp_poly
			(pts
				(xy -2.019808 -1.549908) (xy -1.257808 -1.549908) (xy -1.257808 -1.880108) (xy -2.019808 -1.880108)
			)
			(stroke
				(width 0)
				(type default)
			)
			(fill yes)
			(layer "F.SilkS")
		)
		(fp_line
			(start 1.549908 -1.549908)
			(end 1.549908 1.549908)
			(stroke
				(width 0.1)
				(type default)
			)
			(layer "F.Fab")
		)
		(fp_line
			(start -1.549908 -1.549908)
			(end 1.549908 -1.549908)
			(stroke
				(width 0.1)
				(type default)
			)
			(layer "F.Fab")
		)
		(fp_line
			(start 1.549908 1.549908)
			(end -1.549908 1.549908)
			(stroke
				(width 0.1)
				(type default)
			)
			(layer "F.Fab")
		)
		(fp_line
			(start -1.549908 1.549908)
			(end -1.549908 -1.549908)
			(stroke
				(width 0.1)
				(type default)
			)
			(layer "F.Fab")
		)
		(fp_poly
			(pts
				(xy -2.019808 -1.549908) (xy -1.257808 -1.549908) (xy -1.257808 -1.880108) (xy -2.019808 -1.880108)
			)
			(stroke
				(width 0)
				(type default)
			)
			(fill yes)
			(layer "F.Fab")
		)
		(pad "1" smd rect
			(at -1.500124 -1.249934)
			(size 0.2794 0.6096)
			(layers "F.Cu" "F.Mask" "F.Paste")
			(net "P3V3_SSD10")
		)
		(pad "2" smd rect
			(at -1.500124 -0.750062)
			(size 0.2794 0.6096)
			(layers "F.Cu" "F.Mask" "F.Paste")
			(net "P3V3_SSD10")
		)
		(pad "3" smd rect
			(at -1.500124 -0.249936)
			(size 0.2794 0.6096)
			(layers "F.Cu" "F.Mask" "F.Paste")
			(net "P3V3_SSD10")
		)
		(pad "4" smd rect
			(at -1.500124 0.249936)
			(size 0.2794 0.6096)
			(layers "F.Cu" "F.Mask" "F.Paste")
			(net "P3V3_SSD10")
		)
		(pad "5" smd rect
			(at -1.500124 0.750062)
			(size 0.2794 0.6096)
			(layers "F.Cu" "F.Mask" "F.Paste")
			(net "P3V3_SSD10")
		)
		(pad "6" smd rect
			(at -1.500124 1.249934)
			(size 0.2794 0.6096)
			(layers "F.Cu" "F.Mask" "F.Paste")
			(net "GND")
		)
		(pad "7" smd rect
			(at 1.500124 1.249934)
			(size 0.2794 0.6096)
			(layers "F.Cu" "F.Mask" "F.Paste")
			(net "P3V3_SSD10_SS")
		)
		(pad "8" smd rect
			(at 1.500124 0.750062)
			(size 0.2794 0.6096)
			(layers "F.Cu" "F.Mask" "F.Paste")
			(net "PWRGD_P3V3_SSD10")
		)
		(pad "9" smd rect
			(at 1.500124 0.249936)
			(size 0.2794 0.6096)
			(layers "F.Cu" "F.Mask" "F.Paste")
			(net "P3V3_SSD10_OCP")
		)
		(pad "10" smd rect
			(at 1.500124 -0.249936)
			(size 0.2794 0.6096)
			(layers "F.Cu" "F.Mask" "F.Paste")
			(net "P5V_AUX")
		)
		(pad "11" smd rect
			(at 1.500124 -0.750062)
			(size 0.2794 0.6096)
			(layers "F.Cu" "F.Mask" "F.Paste")
			(net "SSD10_AUX_P3V3_EN_R")
		)
		(pad "12" smd rect
			(at 1.500124 -1.249934)
			(size 0.2794 0.6096)
			(layers "F.Cu" "F.Mask" "F.Paste")
			(net "P3V3_AUX")
		)
		(pad "13" smd rect
			(at 0 0 90)
			(size 1.9812 2.7178)
			(layers "F.Cu" "F.Mask" "F.Paste")
			(net "P3V3_AUX")
		)
		(zone
			(layer "F.Cu")
			(hatch none 0.5)
			(connect_pads
				(clearance 0)
			)
			(min_thickness 0.25)
			(keepout
				(tracks not_allowed)
				(vias allowed)
				(pads allowed)
				(copperpour not_allowed)
				(footprints allowed)
			)
			(placement
				(enabled no)
				(sheetname "")
			)
			(fill
				(thermal_gap 0.5)
				(thermal_bridge_width 0.5)
				(island_removal_mode 0)
			)
			(polygon
				(pts
					(xy 289.541458 -56.806846) (xy 289.668458 -56.806846) (xy 292.640258 -56.806846) (xy 292.640766 -56.806846)
					(xy 292.640766 -54.520846) (xy 292.640258 -54.520846) (xy 292.513258 -54.520846) (xy 291.090858 -54.520846)
					(xy 291.090858 -54.622446) (xy 292.513258 -54.622446) (xy 292.513258 -56.705246) (xy 289.668458 -56.705246)
					(xy 289.668458 -54.622446) (xy 291.065458 -54.622446) (xy 291.065458 -54.520846) (xy 289.668458 -54.520846)
					(xy 289.541458 -54.520846) (xy 289.54095 -54.520846) (xy 289.54095 -56.806846)
				)
			)
		)
	)
	(footprint ""
		(layer "F.Cu")
		(at 259.6769 -84.30641)
		(property "Reference" "U113"
			(at 2.6035 -4.74472 0)
			(unlocked yes)
			(layer "F.SilkS")
			(effects
				(font
					(size 0.7874 0.5842)
					(thickness 0.1524)
				)
				(justify left)
			)
		)
		(property "Value" ""
			(at 0 0 0)
			(layer "F.Fab")
			(effects
				(font
					(size 1.27 1.27)
				)
			)
		)
		(duplicate_pad_numbers_are_jumpers no)
		(fp_line
			(start -3.999992 -3.999992)
			(end -3.999992 -3.4798)
			(stroke
				(width 0.1524)
				(type default)
			)
			(layer "F.SilkS")
		)
		(fp_line
			(start -3.999992 3.4798)
			(end -3.999992 3.999992)
			(stroke
				(width 0.1524)
				(type default)
			)
			(layer "F.SilkS")
		)
		(fp_line
			(start -3.999992 3.999992)
			(end -3.4798 3.999992)
			(stroke
				(width 0.1524)
				(type default)
			)
			(layer "F.SilkS")
		)
		(fp_line
			(start -3.4798 -3.999992)
			(end -3.999992 -3.999992)
			(stroke
				(width 0.1524)
				(type default)
			)
			(layer "F.SilkS")
		)
		(fp_line
			(start 3.4798 3.999992)
			(end 3.999992 3.999992)
			(stroke
				(width 0.1524)
				(type default)
			)
			(layer "F.SilkS")
		)
		(fp_line
			(start 3.999992 -3.999992)
			(end 3.4798 -3.999992)
			(stroke
				(width 0.1524)
				(type default)
			)
			(layer "F.SilkS")
		)
		(fp_line
			(start 3.999992 -3.4798)
			(end 3.999992 -3.999992)
			(stroke
				(width 0.1524)
				(type default)
			)
			(layer "F.SilkS")
		)
		(fp_line
			(start 3.999992 3.999992)
			(end 3.999992 3.4798)
			(stroke
				(width 0.1524)
				(type default)
			)
			(layer "F.SilkS")
		)
		(fp_poly
			(pts
				(xy -5.4102 -3.75793) (xy -5.4102 -2.74193) (xy -4.3942 -3.24993)
			)
			(stroke
				(width 0)
				(type default)
			)
			(fill yes)
			(layer "F.SilkS")
		)
		(fp_line
			(start -3.999992 -3.999992)
			(end -3.999992 3.999992)
			(stroke
				(width 0.1)
				(type default)
			)
			(layer "F.Fab")
		)
		(fp_line
			(start -3.999992 3.999992)
			(end 3.999992 3.999992)
			(stroke
				(width 0.1)
				(type default)
			)
			(layer "F.Fab")
		)
		(fp_line
			(start 3.999992 -3.999992)
			(end -3.999992 -3.999992)
			(stroke
				(width 0.1)
				(type default)
			)
			(layer "F.Fab")
		)
		(fp_line
			(start 3.999992 3.999992)
			(end 3.999992 -3.999992)
			(stroke
				(width 0.1)
				(type default)
			)
			(layer "F.Fab")
		)
		(fp_poly
			(pts
				(xy -5.4102 -3.75793) (xy -5.4102 -2.74193) (xy -4.3942 -3.24993)
			)
			(stroke
				(width 0)
				(type default)
			)
			(fill yes)
			(layer "F.Fab")
		)
		(pad "A1" smd rect
			(at -3.875024 -3.24993 90)
			(size 0.1778 0.5588)
			(layers "F.Cu" "F.Mask" "F.Paste")
			(net "FM_CK440Q_DEV_25M_EN")
		)
		(pad "A2" smd rect
			(at -3.875024 -2.750058 90)
			(size 0.1778 0.5588)
			(layers "F.Cu" "F.Mask" "F.Paste")
			(net "Net_4267")
		)
		(pad "A3" smd rect
			(at -3.875024 -2.249932 90)
			(size 0.1778 0.5588)
			(layers "F.Cu" "F.Mask" "F.Paste")
			(net "Net_4266")
		)
		(pad "A4" smd rect
			(at -3.875024 -1.75006 90)
			(size 0.1778 0.5588)
			(layers "F.Cu" "F.Mask" "F.Paste")
			(net "Net_4265")
		)
		(pad "A5" smd rect
			(at -3.875024 -1.249934 90)
			(size 0.1778 0.5588)
			(layers "F.Cu" "F.Mask" "F.Paste")
			(net "Net_4264")
		)
		(pad "A6" smd rect
			(at -3.875024 -0.750062 90)
			(size 0.1778 0.5588)
			(layers "F.Cu" "F.Mask" "F.Paste")
			(net "TP_CLK_CK440_PFT_OUT_DP")
		)
		(pad "A7" smd rect
			(at -3.875024 -0.249936 90)
			(size 0.1778 0.5588)
			(layers "F.Cu" "F.Mask" "F.Paste")
			(net "TP_CLK_CK440_PFT_OUT_DN")
		)
		(pad "A8" smd rect
			(at -3.875024 0.249936 90)
			(size 0.1778 0.5588)
			(layers "F.Cu" "F.Mask" "F.Paste")
			(net "TP_CLK_PFT_IN_DP")
		)
		(pad "A9" smd rect
			(at -3.875024 0.750062 90)
			(size 0.1778 0.5588)
			(layers "F.Cu" "F.Mask" "F.Paste")
			(net "TP_CLK_PFT_IN_DN")
		)
		(pad "A10" smd rect
			(at -3.875024 1.249934 90)
			(size 0.1778 0.5588)
			(layers "F.Cu" "F.Mask" "F.Paste")
			(net "SMB_CK440_CLK_SCL")
		)
		(pad "A11" smd rect
			(at -3.875024 1.75006 90)
			(size 0.1778 0.5588)
			(layers "F.Cu" "F.Mask" "F.Paste")
			(net "CLK_CK440_SMB_ADDR0")
		)
		(pad "A12" smd rect
			(at -3.875024 2.249932 90)
			(size 0.1778 0.5588)
			(layers "F.Cu" "F.Mask" "F.Paste")
			(net "P3V3_CLK_GEN_VDDXTAL_CK440")
		)
		(pad "A13" smd rect
			(at -3.875024 2.750058 90)
			(size 0.1778 0.5588)
			(layers "F.Cu" "F.Mask" "F.Paste")
			(net "XTAL_CK440_25M_XIN")
		)
		(pad "A14" smd rect
			(at -3.875024 3.24993 90)
			(size 0.1778 0.5588)
			(layers "F.Cu" "F.Mask" "F.Paste")
			(net "GND")
		)
		(pad "A15" smd rect
			(at -3.24993 3.875024)
			(size 0.1778 0.5588)
			(layers "F.Cu" "F.Mask" "F.Paste")
			(net "Net_4288")
		)
		(pad "A16" smd rect
			(at -2.750058 3.875024)
			(size 0.1778 0.5588)
			(layers "F.Cu" "F.Mask" "F.Paste")
			(net "FM_CLK_CK440_SS_EN")
		)
		(pad "A17" smd rect
			(at -2.249932 3.875024)
			(size 0.1778 0.5588)
			(layers "F.Cu" "F.Mask" "F.Paste")
			(net "FM_CLK_EN_R")
		)
		(pad "A18" smd rect
			(at -1.75006 3.875024)
			(size 0.1778 0.5588)
			(layers "F.Cu" "F.Mask" "F.Paste")
			(net "Net_4263")
		)
		(pad "A19" smd rect
			(at -1.249934 3.875024)
			(size 0.1778 0.5588)
			(layers "F.Cu" "F.Mask" "F.Paste")
			(net "Net_4262")
		)
		(pad "A20" smd rect
			(at -0.750062 3.875024)
			(size 0.1778 0.5588)
			(layers "F.Cu" "F.Mask" "F.Paste")
			(net "Net_4261")
		)
		(pad "A21" smd rect
			(at -0.249936 3.875024)
			(size 0.1778 0.5588)
			(layers "F.Cu" "F.Mask" "F.Paste")
			(net "Net_4260")
		)
		(pad "A22" smd rect
			(at 0.249936 3.875024)
			(size 0.1778 0.5588)
			(layers "F.Cu" "F.Mask" "F.Paste")
			(net "Net_4259")
		)
		(pad "A23" smd rect
			(at 0.750062 3.875024)
			(size 0.1778 0.5588)
			(layers "F.Cu" "F.Mask" "F.Paste")
			(net "Net_4258")
		)
		(pad "A24" smd rect
			(at 1.249934 3.875024)
			(size 0.1778 0.5588)
			(layers "F.Cu" "F.Mask" "F.Paste")
			(net "Net_4257")
		)
		(pad "A25" smd rect
			(at 1.75006 3.875024)
			(size 0.1778 0.5588)
			(layers "F.Cu" "F.Mask" "F.Paste")
			(net "Net_4256")
		)
		(pad "A26" smd rect
			(at 2.249932 3.875024)
			(size 0.1778 0.5588)
			(layers "F.Cu" "F.Mask" "F.Paste")
			(net "CLK_GEN_CK440_OE3_N")
		)
		(pad "A27" smd rect
			(at 2.750058 3.875024)
			(size 0.1778 0.5588)
			(layers "F.Cu" "F.Mask" "F.Paste")
			(net "CLK_100M_CK440Q_2_DB800ZL_DN")
		)
		(pad "A28" smd rect
			(at 3.24993 3.875024)
			(size 0.1778 0.5588)
			(layers "F.Cu" "F.Mask" "F.Paste")
			(net "CLK_100M_CK440Q_2_DB800ZL_DP")
		)
		(pad "A29" smd rect
			(at 3.875024 3.24993 270)
			(size 0.1778 0.5588)
			(layers "F.Cu" "F.Mask" "F.Paste")
			(net "CLK_BUFFER_9ZXL0851E_8_15_OE2_N")
		)
		(pad "A30" smd rect
			(at 3.875024 2.750058 270)
			(size 0.1778 0.5588)
			(layers "F.Cu" "F.Mask" "F.Paste")
			(net "CLK_BUFFER_9ZXL0851E_0_7_OE1_N")
		)
		(pad "A31" smd rect
			(at 3.875024 2.249932 270)
			(size 0.1778 0.5588)
			(layers "F.Cu" "F.Mask" "F.Paste")
			(net "CLK_100M_CK440Q_1_DB800ZL_DN")
		)
		(pad "A32" smd rect
			(at 3.875024 1.75006 270)
			(size 0.1778 0.5588)
			(layers "F.Cu" "F.Mask" "F.Paste")
			(net "CLK_100M_CK440Q_1_DB800ZL_DP")
		)
		(pad "A33" smd rect
			(at 3.875024 1.249934 270)
			(size 0.1778 0.5588)
			(layers "F.Cu" "F.Mask" "F.Paste")
			(net "CLK_100M_CK440Q_0_DB2000QL_DN")
		)
		(pad "A34" smd rect
			(at 3.875024 0.750062 270)
			(size 0.1778 0.5588)
			(layers "F.Cu" "F.Mask" "F.Paste")
			(net "CLK_100M_CK440Q_0_DB2000QL_DP")
		)
		(pad "A35" smd rect
			(at 3.875024 0.249936 270)
			(size 0.1778 0.5588)
			(layers "F.Cu" "F.Mask" "F.Paste")
			(net "Net_4287")
		)
		(pad "A36" smd rect
			(at 3.875024 -0.249936 270)
			(size 0.1778 0.5588)
			(layers "F.Cu" "F.Mask" "F.Paste")
			(net "Net_4286")
		)
		(pad "A37" smd rect
			(at 3.875024 -0.750062 270)
			(size 0.1778 0.5588)
			(layers "F.Cu" "F.Mask" "F.Paste")
			(net "Net_4285")
		)
		(pad "A38" smd rect
			(at 3.875024 -1.249934 270)
			(size 0.1778 0.5588)
			(layers "F.Cu" "F.Mask" "F.Paste")
			(net "Net_4284")
		)
		(pad "A39" smd rect
			(at 3.875024 -1.75006 270)
			(size 0.1778 0.5588)
			(layers "F.Cu" "F.Mask" "F.Paste")
			(net "Net_4283")
		)
		(pad "A40" smd rect
			(at 3.875024 -2.249932 270)
			(size 0.1778 0.5588)
			(layers "F.Cu" "F.Mask" "F.Paste")
			(net "Net_4282")
		)
		(pad "A41" smd rect
			(at 3.875024 -2.750058 270)
			(size 0.1778 0.5588)
			(layers "F.Cu" "F.Mask" "F.Paste")
			(net "Net_4281")
		)
		(pad "A42" smd rect
			(at 3.875024 -3.24993 270)
			(size 0.1778 0.5588)
			(layers "F.Cu" "F.Mask" "F.Paste")
			(net "Net_4280")
		)
		(pad "A43" smd rect
			(at 3.24993 -3.875024)
			(size 0.1778 0.5588)
			(layers "F.Cu" "F.Mask" "F.Paste")
			(net "Net_4279")
		)
		(pad "A44" smd rect
			(at 2.750058 -3.875024)
			(size 0.1778 0.5588)
			(layers "F.Cu" "F.Mask" "F.Paste")
			(net "Net_4278")
		)
		(pad "A45" smd rect
			(at 2.249932 -3.875024)
			(size 0.1778 0.5588)
			(layers "F.Cu" "F.Mask" "F.Paste")
			(net "Net_4277")
		)
		(pad "A46" smd rect
			(at 1.75006 -3.875024)
			(size 0.1778 0.5588)
			(layers "F.Cu" "F.Mask" "F.Paste")
			(net "Net_4276")
		)
		(pad "A47" smd rect
			(at 1.249934 -3.875024)
			(size 0.1778 0.5588)
			(layers "F.Cu" "F.Mask" "F.Paste")
			(net "Net_4275")
		)
		(pad "A48" smd rect
			(at 0.750062 -3.875024)
			(size 0.1778 0.5588)
			(layers "F.Cu" "F.Mask" "F.Paste")
			(net "Net_4274")
		)
		(pad "A49" smd rect
			(at 0.249936 -3.875024)
			(size 0.1778 0.5588)
			(layers "F.Cu" "F.Mask" "F.Paste")
			(net "Net_4273")
		)
		(pad "A50" smd rect
			(at -0.249936 -3.875024)
			(size 0.1778 0.5588)
			(layers "F.Cu" "F.Mask" "F.Paste")
			(net "Net_4272")
		)
		(pad "A51" smd rect
			(at -0.750062 -3.875024)
			(size 0.1778 0.5588)
			(layers "F.Cu" "F.Mask" "F.Paste")
			(net "Net_4271")
		)
		(pad "A52" smd rect
			(at -1.249934 -3.875024)
			(size 0.1778 0.5588)
			(layers "F.Cu" "F.Mask" "F.Paste")
			(net "Net_4270")
		)
		(pad "A53" smd rect
			(at -1.75006 -3.875024)
			(size 0.1778 0.5588)
			(layers "F.Cu" "F.Mask" "F.Paste")
			(net "TP_CK440_SBI_DATA_OUT")
		)
		(pad "A54" smd rect
			(at -2.249932 -3.875024)
			(size 0.1778 0.5588)
			(layers "F.Cu" "F.Mask" "F.Paste")
			(net "PD_CK440_SBI_CLK")
		)
		(pad "A55" smd rect
			(at -2.750058 -3.875024)
			(size 0.1778 0.5588)
			(layers "F.Cu" "F.Mask" "F.Paste")
			(net "Net_4269")
		)
		(pad "A56" smd rect
			(at -3.24993 -3.875024)
			(size 0.1778 0.5588)
			(layers "F.Cu" "F.Mask" "F.Paste")
			(net "Net_4268")
		)
		(pad "B1" smd rect
			(at -3.124962 -2.500122 90)
			(size 0.2794 0.4572)
			(layers "F.Cu" "F.Mask" "F.Paste")
			(net "P3V3_CLK_GEN_VDDA25M_CK440")
		)
		(pad "B2" smd rect
			(at -3.124962 -1.999996 90)
			(size 0.2794 0.4572)
			(layers "F.Cu" "F.Mask" "F.Paste")
			(net "Net_4292")
		)
		(pad "B3" smd rect
			(at -3.124962 -1.500124 90)
			(size 0.2794 0.4572)
			(layers "F.Cu" "F.Mask" "F.Paste")
			(net "Net_4299")
		)
		(pad "B4" smd rect
			(at -3.124962 -0.999998 90)
			(size 0.2794 0.4572)
			(layers "F.Cu" "F.Mask" "F.Paste")
			(net "PU_CLK_PFT_LOST_N")
		)
		(pad "B5" smd rect
			(at -3.124962 -0.499872 90)
			(size 0.2794 0.4572)
			(layers "F.Cu" "F.Mask" "F.Paste")
			(net "Net_4309")
		)
		(pad "B6" smd rect
			(at -3.124962 0 90)
			(size 0.2794 0.4572)
			(layers "F.Cu" "F.Mask" "F.Paste")
			(net "P3V3_CLK_GEN_VDDPT_CK440")
		)
		(pad "B7" smd rect
			(at -3.124962 0.499872 90)
			(size 0.2794 0.4572)
			(layers "F.Cu" "F.Mask" "F.Paste")
			(net "Net_4310")
		)
		(pad "B8" smd rect
			(at -3.124962 0.999998 90)
			(size 0.2794 0.4572)
			(layers "F.Cu" "F.Mask" "F.Paste")
			(net "SMB_CK440_CLK_SDA")
		)
		(pad "B9" smd rect
			(at -3.124962 1.500124 90)
			(size 0.2794 0.4572)
			(layers "F.Cu" "F.Mask" "F.Paste")
			(net "CLK_CK440_SMB_ADDR1")
		)
		(pad "B10" smd rect
			(at -3.124962 1.999996 90)
			(size 0.2794 0.4572)
			(layers "F.Cu" "F.Mask" "F.Paste")
			(net "GND")
		)
		(pad "B11" smd rect
			(at -3.124962 2.500122 90)
			(size 0.2794 0.4572)
			(layers "F.Cu" "F.Mask" "F.Paste")
			(net "XTAL_CK440_25M_XOUT")
		)
		(pad "B12" smd rect
			(at -2.500122 3.124962)
			(size 0.2794 0.4572)
			(layers "F.Cu" "F.Mask" "F.Paste")
			(net "GND")
		)
		(pad "B13" smd rect
			(at -1.999996 3.124962)
			(size 0.2794 0.4572)
			(layers "F.Cu" "F.Mask" "F.Paste")
			(net "Net_4289")
		)
		(pad "B14" smd rect
			(at -1.500124 3.124962)
			(size 0.2794 0.4572)
			(layers "F.Cu" "F.Mask" "F.Paste")
			(net "CLK_GEN_CK440_OE6_N")
		)
		(pad "B15" smd rect
			(at -0.999998 3.124962)
			(size 0.2794 0.4572)
			(layers "F.Cu" "F.Mask" "F.Paste")
			(net "CLK_GEN_CK440_OE5_N")
		)
		(pad "B16" smd rect
			(at -0.499872 3.124962)
			(size 0.2794 0.4572)
			(layers "F.Cu" "F.Mask" "F.Paste")
			(net "Net_4290")
		)
		(pad "B17" smd rect
			(at 0 3.124962)
			(size 0.2794 0.4572)
			(layers "F.Cu" "F.Mask" "F.Paste")
			(net "P3V3_CLK_GEN_VDDA100M_CK440")
		)
		(pad "B18" smd rect
			(at 0.499872 3.124962)
			(size 0.2794 0.4572)
			(layers "F.Cu" "F.Mask" "F.Paste")
			(net "Net_4291")
		)
		(pad "B19" smd rect
			(at 0.999998 3.124962)
			(size 0.2794 0.4572)
			(layers "F.Cu" "F.Mask" "F.Paste")
			(net "CLK_GEN_CK440_OE4_N")
		)
		(pad "B20" smd rect
			(at 1.500124 3.124962)
			(size 0.2794 0.4572)
			(layers "F.Cu" "F.Mask" "F.Paste")
			(net "Net_4293")
		)
		(pad "B21" smd rect
			(at 1.999996 3.124962)
			(size 0.2794 0.4572)
			(layers "F.Cu" "F.Mask" "F.Paste")
			(net "P3V3_CLK_GEN_VDD_CK440")
		)
		(pad "B22" smd rect
			(at 2.500122 3.124962)
			(size 0.2794 0.4572)
			(layers "F.Cu" "F.Mask" "F.Paste")
			(net "Net_4294")
		)
		(pad "B23" smd rect
			(at 3.124962 2.500122 270)
			(size 0.2794 0.4572)
			(layers "F.Cu" "F.Mask" "F.Paste")
			(net "P3V3_CLK_GEN_VDD_CK440")
		)
		(pad "B24" smd rect
			(at 3.124962 1.999996 270)
			(size 0.2794 0.4572)
			(layers "F.Cu" "F.Mask" "F.Paste")
			(net "Net_4295")
		)
		(pad "B25" smd rect
			(at 3.124962 1.500124 270)
			(size 0.2794 0.4572)
			(layers "F.Cu" "F.Mask" "F.Paste")
			(net "Net_4296")
		)
		(pad "B26" smd rect
			(at 3.124962 0.999998 270)
			(size 0.2794 0.4572)
			(layers "F.Cu" "F.Mask" "F.Paste")
			(net "Net_4297")
		)
		(pad "B27" smd rect
			(at 3.124962 0.499872 270)
			(size 0.2794 0.4572)
			(layers "F.Cu" "F.Mask" "F.Paste")
			(net "CLK_BUFFER_DB2000QL_OE0_N")
		)
		(pad "B28" smd rect
			(at 3.124962 0 270)
			(size 0.2794 0.4572)
			(layers "F.Cu" "F.Mask" "F.Paste")
			(net "Net_4298")
		)
		(pad "B29" smd rect
			(at 3.124962 -0.499872 270)
			(size 0.2794 0.4572)
			(layers "F.Cu" "F.Mask" "F.Paste")
			(net "P3V3_CLK_GEN_VDDMXCK_CK440")
		)
		(pad "B30" smd rect
			(at 3.124962 -0.999998 270)
			(size 0.2794 0.4572)
			(layers "F.Cu" "F.Mask" "F.Paste")
			(net "Net_4300")
		)
		(pad "B31" smd rect
			(at 3.124962 -1.500124 270)
			(size 0.2794 0.4572)
			(layers "F.Cu" "F.Mask" "F.Paste")
			(net "Net_4301")
		)
		(pad "B32" smd rect
			(at 3.124962 -1.999996 270)
			(size 0.2794 0.4572)
			(layers "F.Cu" "F.Mask" "F.Paste")
			(net "P3V3_CLK_GEN_VDDMXCK_CK440")
		)
		(pad "B33" smd rect
			(at 3.124962 -2.500122 270)
			(size 0.2794 0.4572)
			(layers "F.Cu" "F.Mask" "F.Paste")
			(net "Net_4302")
		)
		(pad "B34" smd rect
			(at 2.500122 -3.124962)
			(size 0.2794 0.4572)
			(layers "F.Cu" "F.Mask" "F.Paste")
			(net "Net_4303")
		)
		(pad "B35" smd rect
			(at 1.999996 -3.124962)
			(size 0.2794 0.4572)
			(layers "F.Cu" "F.Mask" "F.Paste")
			(net "P3V3_CLK_GEN_VDDMXCK_CK440")
		)
		(pad "B36" smd rect
			(at 1.500124 -3.124962)
			(size 0.2794 0.4572)
			(layers "F.Cu" "F.Mask" "F.Paste")
			(net "Net_4304")
		)
		(pad "B37" smd rect
			(at 0.999998 -3.124962)
			(size 0.2794 0.4572)
			(layers "F.Cu" "F.Mask" "F.Paste")
			(net "Net_4305")
		)
		(pad "B38" smd rect
			(at 0.499872 -3.124962)
			(size 0.2794 0.4572)
			(layers "F.Cu" "F.Mask" "F.Paste")
			(net "FM_CK440_MXCK_25M_100M")
		)
		(pad "B39" smd rect
			(at 0 -3.124962)
			(size 0.2794 0.4572)
			(layers "F.Cu" "F.Mask" "F.Paste")
			(net "Net_4306")
		)
		(pad "B40" smd rect
			(at -0.499872 -3.124962)
			(size 0.2794 0.4572)
			(layers "F.Cu" "F.Mask" "F.Paste")
			(net "P3V3_CLK_GEN_VDDMXCK_CK440")
		)
		(pad "B41" smd rect
			(at -0.999998 -3.124962)
			(size 0.2794 0.4572)
			(layers "F.Cu" "F.Mask" "F.Paste")
			(net "Net_4307")
		)
		(pad "B42" smd rect
			(at -1.500124 -3.124962)
			(size 0.2794 0.4572)
			(layers "F.Cu" "F.Mask" "F.Paste")
			(net "PU_CK440_SHFT_LD_N")
		)
		(pad "B43" smd rect
			(at -1.999996 -3.124962)
			(size 0.2794 0.4572)
			(layers "F.Cu" "F.Mask" "F.Paste")
			(net "PD_CK440_SBI_DATA_IN")
		)
		(pad "B44" smd rect
			(at -2.500122 -3.124962)
			(size 0.2794 0.4572)
			(layers "F.Cu" "F.Mask" "F.Paste")
			(net "Net_4308")
		)
		(pad "C1" smd circle
			(at 0 0)
			(size 0 0)
			(layers "F.Cu" "F.Mask" "F.Paste")
			(net "GND")
		)
		(zone
			(layer "F.Cu")
			(hatch none 0.5)
			(connect_pads
				(clearance 0)
			)
			(min_thickness 0.25)
			(keepout
				(tracks not_allowed)
				(vias allowed)
				(pads allowed)
				(copperpour not_allowed)
				(footprints allowed)
			)
			(placement
				(enabled no)
				(sheetname "")
			)
			(fill
				(thermal_gap 0.5)
				(thermal_bridge_width 0.5)
				(island_removal_mode 0)
			)
			(polygon
				(pts
					(xy 256.831338 -86.08441) (xy 257.0734 -86.08441) (xy 257.0734 -86.59241) (xy 257.3909 -86.90991)
					(xy 262.2804 -86.90991) (xy 262.2804 -81.70291) (xy 257.0734 -81.70291) (xy 257.0734 -86.05901)
					(xy 256.831338 -86.05901) (xy 256.831338 -81.460848) (xy 262.522462 -81.460848) (xy 262.522462 -87.151972)
					(xy 256.831338 -87.151972)
				)
			)
		)
	)
	(footprint ""
		(layer "F.Cu")
		(at 400.543776 -42.84091)
		(property "Reference" "R648"
			(at 0 0 0)
			(layer "F.SilkS")
			(hide yes)
			(effects
				(font
					(size 1.27 1.27)
				)
			)
		)
		(property "Value" ""
			(at 0 0 0)
			(layer "F.Fab")
			(effects
				(font
					(size 1.27 1.27)
				)
			)
		)
		(duplicate_pad_numbers_are_jumpers no)
		(fp_line
			(start -0.7874 -0.4064)
			(end 0.7874 -0.4064)
			(stroke
				(width 0.1524)
				(type default)
			)
			(layer "F.SilkS")
		)
		(fp_line
			(start -0.7874 0.4064)
			(end -0.7874 -0.4064)
			(stroke
				(width 0.1524)
				(type default)
			)
			(layer "F.SilkS")
		)
		(fp_line
			(start 0.7874 -0.4064)
			(end 0.7874 0.4064)
			(stroke
				(width 0.1524)
				(type default)
			)
			(layer "F.SilkS")
		)
		(fp_line
			(start 0.7874 0.4064)
			(end -0.7874 0.4064)
			(stroke
				(width 0.1524)
				(type default)
			)
			(layer "F.SilkS")
		)
		(fp_line
			(start -0.67945 -0.305054)
			(end -0.12065 -0.305054)
			(stroke
				(width 0.1)
				(type default)
			)
			(layer "F.Fab")
		)
		(fp_line
			(start -0.67945 0.3048)
			(end -0.67945 -0.305054)
			(stroke
				(width 0.1)
				(type default)
			)
			(layer "F.Fab")
		)
		(fp_line
			(start -0.12065 -0.305054)
			(end -0.12065 -0.2794)
			(stroke
				(width 0.1)
				(type default)
			)
			(layer "F.Fab")
		)
		(fp_line
			(start -0.12065 -0.2794)
			(end 0.12065 -0.2794)
			(stroke
				(width 0.1)
				(type default)
			)
			(layer "F.Fab")
		)
		(fp_line
			(start -0.12065 0.2794)
			(end -0.12065 0.3048)
			(stroke
				(width 0.1)
				(type default)
			)
			(layer "F.Fab")
		)
		(fp_line
			(start -0.12065 0.3048)
			(end -0.67945 0.3048)
			(stroke
				(width 0.1)
				(type default)
			)
			(layer "F.Fab")
		)
		(fp_line
			(start 0.120396 0.2794)
			(end -0.12065 0.2794)
			(stroke
				(width 0.1)
				(type default)
			)
			(layer "F.Fab")
		)
		(fp_line
			(start 0.120396 0.3048)
			(end 0.120396 0.2794)
			(stroke
				(width 0.1)
				(type default)
			)
			(layer "F.Fab")
		)
		(fp_line
			(start 0.12065 -0.3048)
			(end 0.67945 -0.3048)
			(stroke
				(width 0.1)
				(type default)
			)
			(layer "F.Fab")
		)
		(fp_line
			(start 0.12065 -0.2794)
			(end 0.12065 -0.3048)
			(stroke
				(width 0.1)
				(type default)
			)
			(layer "F.Fab")
		)
		(fp_line
			(start 0.67945 -0.3048)
			(end 0.67945 0.3048)
			(stroke
				(width 0.1)
				(type default)
			)
			(layer "F.Fab")
		)
		(fp_line
			(start 0.67945 0.3048)
			(end 0.120396 0.3048)
			(stroke
				(width 0.1)
				(type default)
			)
			(layer "F.Fab")
		)
		(pad "1" smd circle
			(at -0.40005 0)
			(size 0 0)
			(layers "F.Cu" "F.Mask" "F.Paste")
			(net "SSD13_ADC_A1")
		)
		(pad "2" smd circle
			(at 0.40005 0)
			(size 0 0)
			(layers "F.Cu" "F.Mask" "F.Paste")
			(net "P3V3_AUX")
		)
	)
	(footprint ""
		(layer "F.Cu")
		(at 5.888736 -37.795962 -90)
		(property "Reference" "PC674"
			(at 0 0 270)
			(layer "F.SilkS")
			(hide yes)
			(effects
				(font
					(size 1.27 1.27)
				)
			)
		)
		(property "Value" ""
			(at 0 0 270)
			(layer "F.Fab")
			(effects
				(font
					(size 1.27 1.27)
				)
			)
		)
		(duplicate_pad_numbers_are_jumpers no)
		(fp_line
			(start -0.7874 0.4064)
			(end -0.7874 -0.4064)
			(stroke
				(width 0.1524)
				(type default)
			)
			(layer "F.SilkS")
		)
		(fp_line
			(start 0.7874 0.4064)
			(end -0.7874 0.4064)
			(stroke
				(width 0.1524)
				(type default)
			)
			(layer "F.SilkS")
		)
		(fp_line
			(start -0.7874 -0.4064)
			(end 0.7874 -0.4064)
			(stroke
				(width 0.1524)
				(type default)
			)
			(layer "F.SilkS")
		)
		(fp_line
			(start 0.7874 -0.4064)
			(end 0.7874 0.4064)
			(stroke
				(width 0.1524)
				(type default)
			)
			(layer "F.SilkS")
		)
		(fp_line
			(start -0.67945 0.3048)
			(end -0.67945 -0.305054)
			(stroke
				(width 0.1)
				(type default)
			)
			(layer "F.Fab")
		)
		(fp_line
			(start -0.12065 0.3048)
			(end -0.67945 0.3048)
			(stroke
				(width 0.1)
				(type default)
			)
			(layer "F.Fab")
		)
		(fp_line
			(start 0.120396 0.3048)
			(end 0.120396 0.2794)
			(stroke
				(width 0.1)
				(type default)
			)
			(layer "F.Fab")
		)
		(fp_line
			(start 0.67945 0.3048)
			(end 0.120396 0.3048)
			(stroke
				(width 0.1)
				(type default)
			)
			(layer "F.Fab")
		)
		(fp_line
			(start -0.12065 0.2794)
			(end -0.12065 0.3048)
			(stroke
				(width 0.1)
				(type default)
			)
			(layer "F.Fab")
		)
		(fp_line
			(start 0.120396 0.2794)
			(end -0.12065 0.2794)
			(stroke
				(width 0.1)
				(type default)
			)
			(layer "F.Fab")
		)
		(fp_line
			(start -0.12065 -0.2794)
			(end 0.12065 -0.2794)
			(stroke
				(width 0.1)
				(type default)
			)
			(layer "F.Fab")
		)
		(fp_line
			(start 0.12065 -0.2794)
			(end 0.12065 -0.3048)
			(stroke
				(width 0.1)
				(type default)
			)
			(layer "F.Fab")
		)
		(fp_line
			(start 0.12065 -0.3048)
			(end 0.67945 -0.3048)
			(stroke
				(width 0.1)
				(type default)
			)
			(layer "F.Fab")
		)
		(fp_line
			(start 0.67945 -0.3048)
			(end 0.67945 0.3048)
			(stroke
				(width 0.1)
				(type default)
			)
			(layer "F.Fab")
		)
		(fp_line
			(start -0.67945 -0.305054)
			(end -0.12065 -0.305054)
			(stroke
				(width 0.1)
				(type default)
			)
			(layer "F.Fab")
		)
		(fp_line
			(start -0.12065 -0.305054)
			(end -0.12065 -0.2794)
			(stroke
				(width 0.1)
				(type default)
			)
			(layer "F.Fab")
		)
		(pad "1" smd circle
			(at -0.40005 0 270)
			(size 0 0)
			(layers "F.Cu" "F.Mask" "F.Paste")
			(net "P3V3_SSD0_CO_MODE")
		)
		(pad "2" smd circle
			(at 0.40005 0 270)
			(size 0 0)
			(layers "F.Cu" "F.Mask" "F.Paste")
			(net "GND")
		)
	)
	(footprint ""
		(layer "F.Cu")
		(at 153.104596 -141.87297 180)
		(property "Reference" "R133"
			(at 0 0 180)
			(layer "F.SilkS")
			(hide yes)
			(effects
				(font
					(size 1.27 1.27)
				)
			)
		)
		(property "Value" ""
			(at 0 0 180)
			(layer "F.Fab")
			(effects
				(font
					(size 1.27 1.27)
				)
			)
		)
		(duplicate_pad_numbers_are_jumpers no)
		(fp_line
			(start 0.7874 0.4064)
			(end -0.7874 0.4064)
			(stroke
				(width 0.1524)
				(type default)
			)
			(layer "F.SilkS")
		)
		(fp_line
			(start 0.7874 -0.4064)
			(end 0.7874 0.4064)
			(stroke
				(width 0.1524)
				(type default)
			)
			(layer "F.SilkS")
		)
		(fp_line
			(start -0.7874 0.4064)
			(end -0.7874 -0.4064)
			(stroke
				(width 0.1524)
				(type default)
			)
			(layer "F.SilkS")
		)
		(fp_line
			(start -0.7874 -0.4064)
			(end 0.7874 -0.4064)
			(stroke
				(width 0.1524)
				(type default)
			)
			(layer "F.SilkS")
		)
		(fp_line
			(start 0.67945 0.3048)
			(end 0.120396 0.3048)
			(stroke
				(width 0.1)
				(type default)
			)
			(layer "F.Fab")
		)
		(fp_line
			(start 0.67945 -0.3048)
			(end 0.67945 0.3048)
			(stroke
				(width 0.1)
				(type default)
			)
			(layer "F.Fab")
		)
		(fp_line
			(start 0.12065 -0.2794)
			(end 0.12065 -0.3048)
			(stroke
				(width 0.1)
				(type default)
			)
			(layer "F.Fab")
		)
		(fp_line
			(start 0.12065 -0.3048)
			(end 0.67945 -0.3048)
			(stroke
				(width 0.1)
				(type default)
			)
			(layer "F.Fab")
		)
		(fp_line
			(start 0.120396 0.3048)
			(end 0.120396 0.2794)
			(stroke
				(width 0.1)
				(type default)
			)
			(layer "F.Fab")
		)
		(fp_line
			(start 0.120396 0.2794)
			(end -0.12065 0.2794)
			(stroke
				(width 0.1)
				(type default)
			)
			(layer "F.Fab")
		)
		(fp_line
			(start -0.12065 0.3048)
			(end -0.67945 0.3048)
			(stroke
				(width 0.1)
				(type default)
			)
			(layer "F.Fab")
		)
		(fp_line
			(start -0.12065 0.2794)
			(end -0.12065 0.3048)
			(stroke
				(width 0.1)
				(type default)
			)
			(layer "F.Fab")
		)
		(fp_line
			(start -0.12065 -0.2794)
			(end 0.12065 -0.2794)
			(stroke
				(width 0.1)
				(type default)
			)
			(layer "F.Fab")
		)
		(fp_line
			(start -0.12065 -0.305054)
			(end -0.12065 -0.2794)
			(stroke
				(width 0.1)
				(type default)
			)
			(layer "F.Fab")
		)
		(fp_line
			(start -0.67945 0.3048)
			(end -0.67945 -0.305054)
			(stroke
				(width 0.1)
				(type default)
			)
			(layer "F.Fab")
		)
		(fp_line
			(start -0.67945 -0.305054)
			(end -0.12065 -0.305054)
			(stroke
				(width 0.1)
				(type default)
			)
			(layer "F.Fab")
		)
		(pad "1" smd circle
			(at -0.40005 0 180)
			(size 0 0)
			(layers "F.Cu" "F.Mask" "F.Paste")
			(net "NIC2_BIF1_N")
		)
		(pad "2" smd circle
			(at 0.40005 0 180)
			(size 0 0)
			(layers "F.Cu" "F.Mask" "F.Paste")
			(net "P3V3_AUX")
		)
	)
	(footprint ""
		(layer "F.Cu")
		(at 221.251272 -144.958562)
		(property "Reference" "R4207"
			(at 0 0 0)
			(layer "F.SilkS")
			(hide yes)
			(effects
				(font
					(size 1.27 1.27)
				)
			)
		)
		(property "Value" ""
			(at 0 0 0)
			(layer "F.Fab")
			(effects
				(font
					(size 1.27 1.27)
				)
			)
		)
		(duplicate_pad_numbers_are_jumpers no)
		(fp_line
			(start -0.7874 -0.4064)
			(end 0.7874 -0.4064)
			(stroke
				(width 0.1524)
				(type default)
			)
			(layer "F.SilkS")
		)
		(fp_line
			(start -0.7874 0.4064)
			(end -0.7874 -0.4064)
			(stroke
				(width 0.1524)
				(type default)
			)
			(layer "F.SilkS")
		)
		(fp_line
			(start 0.7874 -0.4064)
			(end 0.7874 0.4064)
			(stroke
				(width 0.1524)
				(type default)
			)
			(layer "F.SilkS")
		)
		(fp_line
			(start 0.7874 0.4064)
			(end -0.7874 0.4064)
			(stroke
				(width 0.1524)
				(type default)
			)
			(layer "F.SilkS")
		)
		(fp_line
			(start -0.67945 -0.305054)
			(end -0.12065 -0.305054)
			(stroke
				(width 0.1)
				(type default)
			)
			(layer "F.Fab")
		)
		(fp_line
			(start -0.67945 0.3048)
			(end -0.67945 -0.305054)
			(stroke
				(width 0.1)
				(type default)
			)
			(layer "F.Fab")
		)
		(fp_line
			(start -0.12065 -0.305054)
			(end -0.12065 -0.2794)
			(stroke
				(width 0.1)
				(type default)
			)
			(layer "F.Fab")
		)
		(fp_line
			(start -0.12065 -0.2794)
			(end 0.12065 -0.2794)
			(stroke
				(width 0.1)
				(type default)
			)
			(layer "F.Fab")
		)
		(fp_line
			(start -0.12065 0.2794)
			(end -0.12065 0.3048)
			(stroke
				(width 0.1)
				(type default)
			)
			(layer "F.Fab")
		)
		(fp_line
			(start -0.12065 0.3048)
			(end -0.67945 0.3048)
			(stroke
				(width 0.1)
				(type default)
			)
			(layer "F.Fab")
		)
		(fp_line
			(start 0.120396 0.2794)
			(end -0.12065 0.2794)
			(stroke
				(width 0.1)
				(type default)
			)
			(layer "F.Fab")
		)
		(fp_line
			(start 0.120396 0.3048)
			(end 0.120396 0.2794)
			(stroke
				(width 0.1)
				(type default)
			)
			(layer "F.Fab")
		)
		(fp_line
			(start 0.12065 -0.3048)
			(end 0.67945 -0.3048)
			(stroke
				(width 0.1)
				(type default)
			)
			(layer "F.Fab")
		)
		(fp_line
			(start 0.12065 -0.2794)
			(end 0.12065 -0.3048)
			(stroke
				(width 0.1)
				(type default)
			)
			(layer "F.Fab")
		)
		(fp_line
			(start 0.67945 -0.3048)
			(end 0.67945 0.3048)
			(stroke
				(width 0.1)
				(type default)
			)
			(layer "F.Fab")
		)
		(fp_line
			(start 0.67945 0.3048)
			(end 0.120396 0.3048)
			(stroke
				(width 0.1)
				(type default)
			)
			(layer "F.Fab")
		)
		(pad "1" smd circle
			(at -0.40005 0)
			(size 0 0)
			(layers "F.Cu" "F.Mask" "F.Paste")
			(net "GND")
		)
		(pad "2" smd circle
			(at 0.40005 0)
			(size 0 0)
			(layers "F.Cu" "F.Mask" "F.Paste")
			(net "PD_CK440_PEX_SBI_DATA_IN")
		)
	)
	(footprint ""
		(layer "F.Cu")
		(at 312.982356 -29.875734)
		(property "Reference" "PU130"
			(at -3.328924 -2.221992 90)
			(unlocked yes)
			(layer "F.SilkS")
			(effects
				(font
					(size 0.7874 0.5842)
					(thickness 0.1524)
				)
			)
		)
		(property "Value" ""
			(at 0 0 0)
			(layer "F.Fab")
			(effects
				(font
					(size 1.27 1.27)
				)
			)
		)
		(duplicate_pad_numbers_are_jumpers no)
		(fp_line
			(start -1.239774 -1.495298)
			(end 1.239774 -1.495298)
			(stroke
				(width 0.1524)
				(type default)
			)
			(layer "F.SilkS")
		)
		(fp_line
			(start -1.239774 1.495298)
			(end -1.239774 -1.495298)
			(stroke
				(width 0.1524)
				(type default)
			)
			(layer "F.SilkS")
		)
		(fp_line
			(start 1.239774 -1.495298)
			(end 1.239774 1.495298)
			(stroke
				(width 0.1524)
				(type default)
			)
			(layer "F.SilkS")
		)
		(fp_line
			(start 1.239774 1.495298)
			(end -1.239774 1.495298)
			(stroke
				(width 0.1524)
				(type default)
			)
			(layer "F.SilkS")
		)
		(fp_poly
			(pts
				(xy -1.986788 -1.275842) (xy -2.705354 -0.557276) (xy -1.627632 -0.19812)
			)
			(stroke
				(width 0)
				(type default)
			)
			(fill yes)
			(layer "F.SilkS")
		)
		(fp_line
			(start -0.8001 -1.050036)
			(end 0.8001 -1.050036)
			(stroke
				(width 0.1)
				(type default)
			)
			(layer "F.Fab")
		)
		(fp_line
			(start -0.8001 1.050036)
			(end -0.8001 -1.050036)
			(stroke
				(width 0.1)
				(type default)
			)
			(layer "F.Fab")
		)
		(fp_line
			(start 0.8001 -1.050036)
			(end 0.8001 1.050036)
			(stroke
				(width 0.1)
				(type default)
			)
			(layer "F.Fab")
		)
		(fp_line
			(start 0.8001 1.050036)
			(end -0.8001 1.050036)
			(stroke
				(width 0.1)
				(type default)
			)
			(layer "F.Fab")
		)
		(fp_poly
			(pts
				(xy -2.458974 -0.508) (xy -2.458974 0.508) (xy -1.442974 0)
			)
			(stroke
				(width 0)
				(type default)
			)
			(fill yes)
			(layer "F.Fab")
		)
		(pad "1_2" smd circle
			(at -0.374904 0 90)
			(size 0 0)
			(layers "F.Cu" "F.Mask" "F.Paste")
			(net "P3V3_AUX")
		)
		(pad "3" smd rect
			(at -0.499872 0.999998)
			(size 0.254 0.7112)
			(layers "F.Cu" "F.Mask" "F.Paste")
			(net "GND")
		)
		(pad "4" smd rect
			(at 0 0.999998)
			(size 0.254 0.7112)
			(layers "F.Cu" "F.Mask" "F.Paste")
			(net "P3V3_SSD11_CO_ILIMIT")
		)
		(pad "5" smd rect
			(at 0.499872 0.999998)
			(size 0.254 0.7112)
			(layers "F.Cu" "F.Mask" "F.Paste")
			(net "P3V3_SSD11_CO_MODE")
		)
		(pad "6_7" smd circle
			(at 0.374904 0 270)
			(size 0 0)
			(layers "F.Cu" "F.Mask" "F.Paste")
			(net "P3V3_SSD11")
		)
		(pad "8" smd rect
			(at 0.499872 -0.999998)
			(size 0.254 0.7112)
			(layers "F.Cu" "F.Mask" "F.Paste")
			(net "P3V3_SSD11_CO_GATE")
		)
		(pad "9" smd rect
			(at 0 -0.999998)
			(size 0.254 0.7112)
			(layers "F.Cu" "F.Mask" "F.Paste")
			(net "P3V3_SSD11_CO_EN")
		)
		(pad "10" smd rect
			(at -0.499872 -0.999998)
			(size 0.254 0.7112)
			(layers "F.Cu" "F.Mask" "F.Paste")
			(net "P3V3_SSD11_CO_DV_DT")
		)
	)
	(footprint ""
		(layer "F.Cu")
		(at 280.307542 -356.244906 90)
		(property "Reference" "C2353"
			(at 0 0 90)
			(layer "F.SilkS")
			(hide yes)
			(effects
				(font
					(size 1.27 1.27)
				)
			)
		)
		(property "Value" ""
			(at 0 0 90)
			(layer "F.Fab")
			(effects
				(font
					(size 1.27 1.27)
				)
			)
		)
		(duplicate_pad_numbers_are_jumpers no)
		(fp_line
			(start 0.299974 -0.150114)
			(end 0.299974 0.150114)
			(stroke
				(width 0.1)
				(type default)
			)
			(layer "F.Fab")
		)
		(fp_line
			(start -0.299974 -0.150114)
			(end 0.299974 -0.150114)
			(stroke
				(width 0.1)
				(type default)
			)
			(layer "F.Fab")
		)
		(fp_line
			(start 0.299974 0.150114)
			(end -0.299974 0.150114)
			(stroke
				(width 0.1)
				(type default)
			)
			(layer "F.Fab")
		)
		(fp_line
			(start -0.299974 0.150114)
			(end -0.299974 -0.150114)
			(stroke
				(width 0.1)
				(type default)
			)
			(layer "F.Fab")
		)
		(pad "1" smd rect
			(at -0.2667 0 90)
			(size 0.3048 0.381)
			(layers "F.Cu" "F.Mask" "F.Paste")
			(net "P5E_PEX2_STN4_TX_DP<73>")
		)
		(pad "2" smd rect
			(at 0.2667 0 90)
			(size 0.3048 0.381)
			(layers "F.Cu" "F.Mask" "F.Paste")
			(net "P5E_PEX2_STN4_TX_C_DP<73>")
		)
	)
	(footprint ""
		(layer "F.Cu")
		(at 243.476018 -236.682026 -90)
		(property "Reference" "R6241"
			(at 0 0 270)
			(layer "F.SilkS")
			(hide yes)
			(effects
				(font
					(size 1.27 1.27)
				)
			)
		)
		(property "Value" ""
			(at 0 0 270)
			(layer "F.Fab")
			(effects
				(font
					(size 1.27 1.27)
				)
			)
		)
		(duplicate_pad_numbers_are_jumpers no)
		(fp_line
			(start -0.7874 0.4064)
			(end -0.7874 -0.4064)
			(stroke
				(width 0.1524)
				(type default)
			)
			(layer "F.SilkS")
		)
		(fp_line
			(start 0.7874 0.4064)
			(end -0.7874 0.4064)
			(stroke
				(width 0.1524)
				(type default)
			)
			(layer "F.SilkS")
		)
		(fp_line
			(start -0.7874 -0.4064)
			(end 0.7874 -0.4064)
			(stroke
				(width 0.1524)
				(type default)
			)
			(layer "F.SilkS")
		)
		(fp_line
			(start 0.7874 -0.4064)
			(end 0.7874 0.4064)
			(stroke
				(width 0.1524)
				(type default)
			)
			(layer "F.SilkS")
		)
		(fp_line
			(start -0.67945 0.3048)
			(end -0.67945 -0.305054)
			(stroke
				(width 0.1)
				(type default)
			)
			(layer "F.Fab")
		)
		(fp_line
			(start -0.12065 0.3048)
			(end -0.67945 0.3048)
			(stroke
				(width 0.1)
				(type default)
			)
			(layer "F.Fab")
		)
		(fp_line
			(start 0.120396 0.3048)
			(end 0.120396 0.2794)
			(stroke
				(width 0.1)
				(type default)
			)
			(layer "F.Fab")
		)
		(fp_line
			(start 0.67945 0.3048)
			(end 0.120396 0.3048)
			(stroke
				(width 0.1)
				(type default)
			)
			(layer "F.Fab")
		)
		(fp_line
			(start -0.12065 0.2794)
			(end -0.12065 0.3048)
			(stroke
				(width 0.1)
				(type default)
			)
			(layer "F.Fab")
		)
		(fp_line
			(start 0.120396 0.2794)
			(end -0.12065 0.2794)
			(stroke
				(width 0.1)
				(type default)
			)
			(layer "F.Fab")
		)
		(fp_line
			(start -0.12065 -0.2794)
			(end 0.12065 -0.2794)
			(stroke
				(width 0.1)
				(type default)
			)
			(layer "F.Fab")
		)
		(fp_line
			(start 0.12065 -0.2794)
			(end 0.12065 -0.3048)
			(stroke
				(width 0.1)
				(type default)
			)
			(layer "F.Fab")
		)
		(fp_line
			(start 0.12065 -0.3048)
			(end 0.67945 -0.3048)
			(stroke
				(width 0.1)
				(type default)
			)
			(layer "F.Fab")
		)
		(fp_line
			(start 0.67945 -0.3048)
			(end 0.67945 0.3048)
			(stroke
				(width 0.1)
				(type default)
			)
			(layer "F.Fab")
		)
		(fp_line
			(start -0.67945 -0.305054)
			(end -0.12065 -0.305054)
			(stroke
				(width 0.1)
				(type default)
			)
			(layer "F.Fab")
		)
		(fp_line
			(start -0.12065 -0.305054)
			(end -0.12065 -0.2794)
			(stroke
				(width 0.1)
				(type default)
			)
			(layer "F.Fab")
		)
		(pad "1" smd circle
			(at -0.40005 0 270)
			(size 0 0)
			(layers "F.Cu" "F.Mask" "F.Paste")
			(net "SMB_BIC_RECOVER_IOEXP_SCL")
		)
		(pad "2" smd circle
			(at 0.40005 0 270)
			(size 0 0)
			(layers "F.Cu" "F.Mask" "F.Paste")
			(net "SMB_MB_R_SCL")
		)
	)
	(footprint ""
		(layer "F.Cu")
		(at 244.583458 -160.327848 180)
		(property "Reference" "PR7027"
			(at 0 0 180)
			(layer "F.SilkS")
			(hide yes)
			(effects
				(font
					(size 1.27 1.27)
				)
			)
		)
		(property "Value" ""
			(at 0 0 180)
			(layer "F.Fab")
			(effects
				(font
					(size 1.27 1.27)
				)
			)
		)
		(duplicate_pad_numbers_are_jumpers no)
		(fp_line
			(start 0.7874 0.4064)
			(end -0.7874 0.4064)
			(stroke
				(width 0.1524)
				(type default)
			)
			(layer "F.SilkS")
		)
		(fp_line
			(start 0.7874 -0.4064)
			(end 0.7874 0.4064)
			(stroke
				(width 0.1524)
				(type default)
			)
			(layer "F.SilkS")
		)
		(fp_line
			(start -0.7874 0.4064)
			(end -0.7874 -0.4064)
			(stroke
				(width 0.1524)
				(type default)
			)
			(layer "F.SilkS")
		)
		(fp_line
			(start -0.7874 -0.4064)
			(end 0.7874 -0.4064)
			(stroke
				(width 0.1524)
				(type default)
			)
			(layer "F.SilkS")
		)
		(fp_line
			(start 0.67945 0.3048)
			(end 0.120396 0.3048)
			(stroke
				(width 0.1)
				(type default)
			)
			(layer "F.Fab")
		)
		(fp_line
			(start 0.67945 -0.3048)
			(end 0.67945 0.3048)
			(stroke
				(width 0.1)
				(type default)
			)
			(layer "F.Fab")
		)
		(fp_line
			(start 0.12065 -0.2794)
			(end 0.12065 -0.3048)
			(stroke
				(width 0.1)
				(type default)
			)
			(layer "F.Fab")
		)
		(fp_line
			(start 0.12065 -0.3048)
			(end 0.67945 -0.3048)
			(stroke
				(width 0.1)
				(type default)
			)
			(layer "F.Fab")
		)
		(fp_line
			(start 0.120396 0.3048)
			(end 0.120396 0.2794)
			(stroke
				(width 0.1)
				(type default)
			)
			(layer "F.Fab")
		)
		(fp_line
			(start 0.120396 0.2794)
			(end -0.12065 0.2794)
			(stroke
				(width 0.1)
				(type default)
			)
			(layer "F.Fab")
		)
		(fp_line
			(start -0.12065 0.3048)
			(end -0.67945 0.3048)
			(stroke
				(width 0.1)
				(type default)
			)
			(layer "F.Fab")
		)
		(fp_line
			(start -0.12065 0.2794)
			(end -0.12065 0.3048)
			(stroke
				(width 0.1)
				(type default)
			)
			(layer "F.Fab")
		)
		(fp_line
			(start -0.12065 -0.2794)
			(end 0.12065 -0.2794)
			(stroke
				(width 0.1)
				(type default)
			)
			(layer "F.Fab")
		)
		(fp_line
			(start -0.12065 -0.305054)
			(end -0.12065 -0.2794)
			(stroke
				(width 0.1)
				(type default)
			)
			(layer "F.Fab")
		)
		(fp_line
			(start -0.67945 0.3048)
			(end -0.67945 -0.305054)
			(stroke
				(width 0.1)
				(type default)
			)
			(layer "F.Fab")
		)
		(fp_line
			(start -0.67945 -0.305054)
			(end -0.12065 -0.305054)
			(stroke
				(width 0.1)
				(type default)
			)
			(layer "F.Fab")
		)
		(pad "1" smd circle
			(at -0.40005 0 180)
			(size 0 0)
			(layers "F.Cu" "F.Mask" "F.Paste")
			(net "P12V_NIC4_CO_ISET")
		)
		(pad "2" smd circle
			(at 0.40005 0 180)
			(size 0 0)
			(layers "F.Cu" "F.Mask" "F.Paste")
			(net "P12V_NIC4_CO_ISET_R")
		)
	)
	(footprint ""
		(layer "F.Cu")
		(at 370.708428 -257.102102)
		(property "Reference" "Q20"
			(at -2.243836 0.85725 90)
			(unlocked yes)
			(layer "F.SilkS")
			(effects
				(font
					(size 0.7874 0.5842)
					(thickness 0.1524)
				)
			)
		)
		(property "Value" ""
			(at 0 0 0)
			(layer "F.Fab")
			(effects
				(font
					(size 1.27 1.27)
				)
			)
		)
		(duplicate_pad_numbers_are_jumpers no)
		(fp_line
			(start -1.376172 -1.199896)
			(end -0.508 -1.199896)
			(stroke
				(width 0.1524)
				(type default)
			)
			(layer "F.SilkS")
		)
		(fp_line
			(start -1.376172 1.199896)
			(end -1.376172 -1.199896)
			(stroke
				(width 0.1524)
				(type default)
			)
			(layer "F.SilkS")
		)
		(fp_line
			(start -0.508 -1.199896)
			(end 0 -0.762)
			(stroke
				(width 0.1524)
				(type default)
			)
			(layer "F.SilkS")
		)
		(fp_line
			(start 0 -0.762)
			(end 0.508 -1.199896)
			(stroke
				(width 0.1524)
				(type default)
			)
			(layer "F.SilkS")
		)
		(fp_line
			(start 0.508 -1.199896)
			(end 1.376172 -1.199896)
			(stroke
				(width 0.1524)
				(type default)
			)
			(layer "F.SilkS")
		)
		(fp_line
			(start 1.376172 -1.199896)
			(end 1.376172 1.199896)
			(stroke
				(width 0.1524)
				(type default)
			)
			(layer "F.SilkS")
		)
		(fp_line
			(start 1.376172 1.199896)
			(end -1.376172 1.199896)
			(stroke
				(width 0.1524)
				(type default)
			)
			(layer "F.SilkS")
		)
		(fp_poly
			(pts
				(xy -1.4605 -0.7493) (xy -2.2225 -1.1303) (xy -2.2225 -0.3683)
			)
			(stroke
				(width 0)
				(type default)
			)
			(fill yes)
			(layer "F.SilkS")
		)
		(fp_line
			(start -0.674878 -1.100074)
			(end 0.674878 -1.100074)
			(stroke
				(width 0.1)
				(type default)
			)
			(layer "F.Fab")
		)
		(fp_line
			(start -0.674878 1.100074)
			(end -0.674878 -1.100074)
			(stroke
				(width 0.1)
				(type default)
			)
			(layer "F.Fab")
		)
		(fp_line
			(start 0.674878 -1.100074)
			(end 0.674878 1.100074)
			(stroke
				(width 0.1)
				(type default)
			)
			(layer "F.Fab")
		)
		(fp_line
			(start 0.674878 1.100074)
			(end -0.674878 1.100074)
			(stroke
				(width 0.1)
				(type default)
			)
			(layer "F.Fab")
		)
		(fp_poly
			(pts
				(xy -1.4605 -0.7493) (xy -2.2225 -1.1303) (xy -2.2225 -0.3683)
			)
			(stroke
				(width 0)
				(type default)
			)
			(fill yes)
			(layer "F.Fab")
		)
		(pad "1" smd rect
			(at -0.899922 -0.750062 270)
			(size 0.6096 0.6096)
			(layers "F.Cu" "F.Mask" "F.Paste")
			(net "GND")
		)
		(pad "2" smd rect
			(at -0.899922 0 270)
			(size 0.4064 0.6096)
			(layers "F.Cu" "F.Mask" "F.Paste")
			(net "PEX3_SYS_ERR_R_N")
		)
		(pad "3" smd rect
			(at -0.899922 0.750062 270)
			(size 0.6096 0.6096)
			(layers "F.Cu" "F.Mask" "F.Paste")
			(net "PEX3_SYS_ERR_3V3_N")
		)
		(pad "4" smd rect
			(at 0.899922 0.750062 270)
			(size 0.6096 0.6096)
			(layers "F.Cu" "F.Mask" "F.Paste")
			(net "GND")
		)
		(pad "5" smd rect
			(at 0.899922 0 270)
			(size 0.4064 0.6096)
			(layers "F.Cu" "F.Mask" "F.Paste")
			(net "PEX3_SYS_ERR_N_G")
		)
		(pad "6" smd rect
			(at 0.899922 -0.750062 270)
			(size 0.6096 0.6096)
			(layers "F.Cu" "F.Mask" "F.Paste")
			(net "PEX3_SYS_ERR_N_G")
		)
	)
	(footprint ""
		(layer "F.Cu")
		(at 464.381088 -281.323034 -90)
		(property "Reference" "R1746"
			(at 0 0 270)
			(layer "F.SilkS")
			(hide yes)
			(effects
				(font
					(size 1.27 1.27)
				)
			)
		)
		(property "Value" ""
			(at 0 0 270)
			(layer "F.Fab")
			(effects
				(font
					(size 1.27 1.27)
				)
			)
		)
		(duplicate_pad_numbers_are_jumpers no)
		(fp_line
			(start -0.7874 0.4064)
			(end -0.7874 -0.4064)
			(stroke
				(width 0.1524)
				(type default)
			)
			(layer "F.SilkS")
		)
		(fp_line
			(start 0.7874 0.4064)
			(end -0.7874 0.4064)
			(stroke
				(width 0.1524)
				(type default)
			)
			(layer "F.SilkS")
		)
		(fp_line
			(start -0.7874 -0.4064)
			(end 0.7874 -0.4064)
			(stroke
				(width 0.1524)
				(type default)
			)
			(layer "F.SilkS")
		)
		(fp_line
			(start 0.7874 -0.4064)
			(end 0.7874 0.4064)
			(stroke
				(width 0.1524)
				(type default)
			)
			(layer "F.SilkS")
		)
		(fp_line
			(start -0.67945 0.3048)
			(end -0.67945 -0.305054)
			(stroke
				(width 0.1)
				(type default)
			)
			(layer "F.Fab")
		)
		(fp_line
			(start -0.12065 0.3048)
			(end -0.67945 0.3048)
			(stroke
				(width 0.1)
				(type default)
			)
			(layer "F.Fab")
		)
		(fp_line
			(start 0.120396 0.3048)
			(end 0.120396 0.2794)
			(stroke
				(width 0.1)
				(type default)
			)
			(layer "F.Fab")
		)
		(fp_line
			(start 0.67945 0.3048)
			(end 0.120396 0.3048)
			(stroke
				(width 0.1)
				(type default)
			)
			(layer "F.Fab")
		)
		(fp_line
			(start -0.12065 0.2794)
			(end -0.12065 0.3048)
			(stroke
				(width 0.1)
				(type default)
			)
			(layer "F.Fab")
		)
		(fp_line
			(start 0.120396 0.2794)
			(end -0.12065 0.2794)
			(stroke
				(width 0.1)
				(type default)
			)
			(layer "F.Fab")
		)
		(fp_line
			(start -0.12065 -0.2794)
			(end 0.12065 -0.2794)
			(stroke
				(width 0.1)
				(type default)
			)
			(layer "F.Fab")
		)
		(fp_line
			(start 0.12065 -0.2794)
			(end 0.12065 -0.3048)
			(stroke
				(width 0.1)
				(type default)
			)
			(layer "F.Fab")
		)
		(fp_line
			(start 0.12065 -0.3048)
			(end 0.67945 -0.3048)
			(stroke
				(width 0.1)
				(type default)
			)
			(layer "F.Fab")
		)
		(fp_line
			(start 0.67945 -0.3048)
			(end 0.67945 0.3048)
			(stroke
				(width 0.1)
				(type default)
			)
			(layer "F.Fab")
		)
		(fp_line
			(start -0.67945 -0.305054)
			(end -0.12065 -0.305054)
			(stroke
				(width 0.1)
				(type default)
			)
			(layer "F.Fab")
		)
		(fp_line
			(start -0.12065 -0.305054)
			(end -0.12065 -0.2794)
			(stroke
				(width 0.1)
				(type default)
			)
			(layer "F.Fab")
		)
		(pad "1" smd circle
			(at -0.40005 0 270)
			(size 0 0)
			(layers "F.Cu" "F.Mask" "F.Paste")
			(net "P3V3_AUX")
		)
		(pad "2" smd circle
			(at 0.40005 0 270)
			(size 0 0)
			(layers "F.Cu" "F.Mask" "F.Paste")
			(net "SMB_BIC_I2C6_MUX_PEX_ADC_R_SCL")
		)
	)
	(footprint ""
		(layer "F.Cu")
		(at 235.690664 -204.44206 90)
		(property "Reference" "R5480"
			(at 0 0 90)
			(layer "F.SilkS")
			(hide yes)
			(effects
				(font
					(size 1.27 1.27)
				)
			)
		)
		(property "Value" ""
			(at 0 0 90)
			(layer "F.Fab")
			(effects
				(font
					(size 1.27 1.27)
				)
			)
		)
		(duplicate_pad_numbers_are_jumpers no)
		(fp_line
			(start 0.7874 -0.4064)
			(end 0.7874 0.4064)
			(stroke
				(width 0.1524)
				(type default)
			)
			(layer "F.SilkS")
		)
		(fp_line
			(start -0.7874 -0.4064)
			(end 0.7874 -0.4064)
			(stroke
				(width 0.1524)
				(type default)
			)
			(layer "F.SilkS")
		)
		(fp_line
			(start 0.7874 0.4064)
			(end -0.7874 0.4064)
			(stroke
				(width 0.1524)
				(type default)
			)
			(layer "F.SilkS")
		)
		(fp_line
			(start -0.7874 0.4064)
			(end -0.7874 -0.4064)
			(stroke
				(width 0.1524)
				(type default)
			)
			(layer "F.SilkS")
		)
		(fp_line
			(start -0.12065 -0.305054)
			(end -0.12065 -0.2794)
			(stroke
				(width 0.1)
				(type default)
			)
			(layer "F.Fab")
		)
		(fp_line
			(start -0.67945 -0.305054)
			(end -0.12065 -0.305054)
			(stroke
				(width 0.1)
				(type default)
			)
			(layer "F.Fab")
		)
		(fp_line
			(start 0.67945 -0.3048)
			(end 0.67945 0.3048)
			(stroke
				(width 0.1)
				(type default)
			)
			(layer "F.Fab")
		)
		(fp_line
			(start 0.12065 -0.3048)
			(end 0.67945 -0.3048)
			(stroke
				(width 0.1)
				(type default)
			)
			(layer "F.Fab")
		)
		(fp_line
			(start 0.12065 -0.2794)
			(end 0.12065 -0.3048)
			(stroke
				(width 0.1)
				(type default)
			)
			(layer "F.Fab")
		)
		(fp_line
			(start -0.12065 -0.2794)
			(end 0.12065 -0.2794)
			(stroke
				(width 0.1)
				(type default)
			)
			(layer "F.Fab")
		)
		(fp_line
			(start 0.120396 0.2794)
			(end -0.12065 0.2794)
			(stroke
				(width 0.1)
				(type default)
			)
			(layer "F.Fab")
		)
		(fp_line
			(start -0.12065 0.2794)
			(end -0.12065 0.3048)
			(stroke
				(width 0.1)
				(type default)
			)
			(layer "F.Fab")
		)
		(fp_line
			(start 0.67945 0.3048)
			(end 0.120396 0.3048)
			(stroke
				(width 0.1)
				(type default)
			)
			(layer "F.Fab")
		)
		(fp_line
			(start 0.120396 0.3048)
			(end 0.120396 0.2794)
			(stroke
				(width 0.1)
				(type default)
			)
			(layer "F.Fab")
		)
		(fp_line
			(start -0.12065 0.3048)
			(end -0.67945 0.3048)
			(stroke
				(width 0.1)
				(type default)
			)
			(layer "F.Fab")
		)
		(fp_line
			(start -0.67945 0.3048)
			(end -0.67945 -0.305054)
			(stroke
				(width 0.1)
				(type default)
			)
			(layer "F.Fab")
		)
		(pad "1" smd circle
			(at -0.40005 0 90)
			(size 0 0)
			(layers "F.Cu" "F.Mask" "F.Paste")
			(net "RST_BIC_SRST_R_N")
		)
		(pad "2" smd circle
			(at 0.40005 0 90)
			(size 0 0)
			(layers "F.Cu" "F.Mask" "F.Paste")
			(net "RST_BIC_SRST_BIC_N")
		)
	)
	(footprint ""
		(layer "F.Cu")
		(at 237.924848 -85.551518 180)
		(property "Reference" "R6285"
			(at 0 0 180)
			(layer "F.SilkS")
			(hide yes)
			(effects
				(font
					(size 1.27 1.27)
				)
			)
		)
		(property "Value" ""
			(at 0 0 180)
			(layer "F.Fab")
			(effects
				(font
					(size 1.27 1.27)
				)
			)
		)
		(duplicate_pad_numbers_are_jumpers no)
		(fp_line
			(start 0.7874 0.4064)
			(end 0.004318 0.4064)
			(stroke
				(width 0.1524)
				(type default)
			)
			(layer "F.SilkS")
		)
		(fp_line
			(start 0.7874 -0.4064)
			(end 0.7874 0.4064)
			(stroke
				(width 0.1524)
				(type default)
			)
			(layer "F.SilkS")
		)
		(fp_line
			(start -0.7874 -0.4064)
			(end 0.7874 -0.4064)
			(stroke
				(width 0.1524)
				(type default)
			)
			(layer "F.SilkS")
		)
		(fp_line
			(start 0.67945 0.3048)
			(end 0.120396 0.3048)
			(stroke
				(width 0.1)
				(type default)
			)
			(layer "F.Fab")
		)
		(fp_line
			(start 0.67945 -0.3048)
			(end 0.67945 0.3048)
			(stroke
				(width 0.1)
				(type default)
			)
			(layer "F.Fab")
		)
		(fp_line
			(start 0.12065 -0.2794)
			(end 0.12065 -0.3048)
			(stroke
				(width 0.1)
				(type default)
			)
			(layer "F.Fab")
		)
		(fp_line
			(start 0.12065 -0.3048)
			(end 0.67945 -0.3048)
			(stroke
				(width 0.1)
				(type default)
			)
			(layer "F.Fab")
		)
		(fp_line
			(start 0.120396 0.3048)
			(end 0.120396 0.2794)
			(stroke
				(width 0.1)
				(type default)
			)
			(layer "F.Fab")
		)
		(fp_line
			(start 0.120396 0.2794)
			(end -0.12065 0.2794)
			(stroke
				(width 0.1)
				(type default)
			)
			(layer "F.Fab")
		)
		(fp_line
			(start -0.12065 0.3048)
			(end -0.67945 0.3048)
			(stroke
				(width 0.1)
				(type default)
			)
			(layer "F.Fab")
		)
		(fp_line
			(start -0.12065 0.2794)
			(end -0.12065 0.3048)
			(stroke
				(width 0.1)
				(type default)
			)
			(layer "F.Fab")
		)
		(fp_line
			(start -0.12065 -0.2794)
			(end 0.12065 -0.2794)
			(stroke
				(width 0.1)
				(type default)
			)
			(layer "F.Fab")
		)
		(fp_line
			(start -0.12065 -0.305054)
			(end -0.12065 -0.2794)
			(stroke
				(width 0.1)
				(type default)
			)
			(layer "F.Fab")
		)
		(fp_line
			(start -0.67945 0.3048)
			(end -0.67945 -0.305054)
			(stroke
				(width 0.1)
				(type default)
			)
			(layer "F.Fab")
		)
		(fp_line
			(start -0.67945 -0.305054)
			(end -0.12065 -0.305054)
			(stroke
				(width 0.1)
				(type default)
			)
			(layer "F.Fab")
		)
		(pad "1" smd rect
			(at -0.40005 0)
			(size 0.4572 0.508)
			(layers "F.Cu" "F.Mask" "F.Paste")
			(net "USB2_FT4232_CLI_DN")
		)
		(pad "2" smd rect
			(at 0.40005 0)
			(size 0.4572 0.508)
			(layers "F.Cu" "F.Mask" "F.Paste")
			(net "GND")
		)
	)
	(footprint ""
		(layer "F.Cu")
		(at 174.596552 -343.952322 90)
		(property "Reference" "C390"
			(at 0 0 90)
			(layer "F.SilkS")
			(hide yes)
			(effects
				(font
					(size 1.27 1.27)
				)
			)
		)
		(property "Value" ""
			(at 0 0 90)
			(layer "F.Fab")
			(effects
				(font
					(size 1.27 1.27)
				)
			)
		)
		(duplicate_pad_numbers_are_jumpers no)
		(fp_line
			(start 0.299974 -0.150114)
			(end 0.299974 0.150114)
			(stroke
				(width 0.1)
				(type default)
			)
			(layer "F.Fab")
		)
		(fp_line
			(start -0.299974 -0.150114)
			(end 0.299974 -0.150114)
			(stroke
				(width 0.1)
				(type default)
			)
			(layer "F.Fab")
		)
		(fp_line
			(start 0.299974 0.150114)
			(end -0.299974 0.150114)
			(stroke
				(width 0.1)
				(type default)
			)
			(layer "F.Fab")
		)
		(fp_line
			(start -0.299974 0.150114)
			(end -0.299974 -0.150114)
			(stroke
				(width 0.1)
				(type default)
			)
			(layer "F.Fab")
		)
		(pad "1" smd rect
			(at -0.2667 0 90)
			(size 0.3048 0.381)
			(layers "F.Cu" "F.Mask" "F.Paste")
			(net "P5E_PEX1_STN7_TX_DP<118>")
		)
		(pad "2" smd rect
			(at 0.2667 0 90)
			(size 0.3048 0.381)
			(layers "F.Cu" "F.Mask" "F.Paste")
			(net "P5E_PEX1_STN7_TX_C_DP<118>")
		)
	)
	(footprint ""
		(layer "F.Cu")
		(at 392.092434 -29.139642 180)
		(property "Reference" "C712"
			(at 0 0 180)
			(layer "F.SilkS")
			(hide yes)
			(effects
				(font
					(size 1.27 1.27)
				)
			)
		)
		(property "Value" ""
			(at 0 0 180)
			(layer "F.Fab")
			(effects
				(font
					(size 1.27 1.27)
				)
			)
		)
		(duplicate_pad_numbers_are_jumpers no)
		(fp_line
			(start 0.299974 0.150114)
			(end -0.299974 0.150114)
			(stroke
				(width 0.1)
				(type default)
			)
			(layer "F.Fab")
		)
		(fp_line
			(start 0.299974 -0.150114)
			(end 0.299974 0.150114)
			(stroke
				(width 0.1)
				(type default)
			)
			(layer "F.Fab")
		)
		(fp_line
			(start -0.299974 0.150114)
			(end -0.299974 -0.150114)
			(stroke
				(width 0.1)
				(type default)
			)
			(layer "F.Fab")
		)
		(fp_line
			(start -0.299974 -0.150114)
			(end 0.299974 -0.150114)
			(stroke
				(width 0.1)
				(type default)
			)
			(layer "F.Fab")
		)
		(pad "1" smd rect
			(at -0.2667 0 180)
			(size 0.3048 0.381)
			(layers "F.Cu" "F.Mask" "F.Paste")
			(net "P5E_PEX3_STN2_TX_DP<40>")
		)
		(pad "2" smd rect
			(at 0.2667 0 180)
			(size 0.3048 0.381)
			(layers "F.Cu" "F.Mask" "F.Paste")
			(net "P5E_PEX3_STN2_TX_C_DP<40>")
		)
	)
	(footprint ""
		(layer "F.Cu")
		(at 257.262376 -22.955504 -90)
		(property "Reference" "C2727"
			(at 0 0 270)
			(layer "F.SilkS")
			(hide yes)
			(effects
				(font
					(size 1.27 1.27)
				)
			)
		)
		(property "Value" ""
			(at 0 0 270)
			(layer "F.Fab")
			(effects
				(font
					(size 1.27 1.27)
				)
			)
		)
		(duplicate_pad_numbers_are_jumpers no)
		(fp_line
			(start -0.7874 0.4064)
			(end -0.7874 -0.4064)
			(stroke
				(width 0.1524)
				(type default)
			)
			(layer "F.SilkS")
		)
		(fp_line
			(start 0.7874 0.4064)
			(end -0.7874 0.4064)
			(stroke
				(width 0.1524)
				(type default)
			)
			(layer "F.SilkS")
		)
		(fp_line
			(start -0.7874 -0.4064)
			(end 0.7874 -0.4064)
			(stroke
				(width 0.1524)
				(type default)
			)
			(layer "F.SilkS")
		)
		(fp_line
			(start 0.7874 -0.4064)
			(end 0.7874 0.4064)
			(stroke
				(width 0.1524)
				(type default)
			)
			(layer "F.SilkS")
		)
		(fp_line
			(start -0.67945 0.3048)
			(end -0.67945 -0.305054)
			(stroke
				(width 0.1)
				(type default)
			)
			(layer "F.Fab")
		)
		(fp_line
			(start -0.12065 0.3048)
			(end -0.67945 0.3048)
			(stroke
				(width 0.1)
				(type default)
			)
			(layer "F.Fab")
		)
		(fp_line
			(start 0.120396 0.3048)
			(end 0.120396 0.2794)
			(stroke
				(width 0.1)
				(type default)
			)
			(layer "F.Fab")
		)
		(fp_line
			(start 0.67945 0.3048)
			(end 0.120396 0.3048)
			(stroke
				(width 0.1)
				(type default)
			)
			(layer "F.Fab")
		)
		(fp_line
			(start -0.12065 0.2794)
			(end -0.12065 0.3048)
			(stroke
				(width 0.1)
				(type default)
			)
			(layer "F.Fab")
		)
		(fp_line
			(start 0.120396 0.2794)
			(end -0.12065 0.2794)
			(stroke
				(width 0.1)
				(type default)
			)
			(layer "F.Fab")
		)
		(fp_line
			(start -0.12065 -0.2794)
			(end 0.12065 -0.2794)
			(stroke
				(width 0.1)
				(type default)
			)
			(layer "F.Fab")
		)
		(fp_line
			(start 0.12065 -0.2794)
			(end 0.12065 -0.3048)
			(stroke
				(width 0.1)
				(type default)
			)
			(layer "F.Fab")
		)
		(fp_line
			(start 0.12065 -0.3048)
			(end 0.67945 -0.3048)
			(stroke
				(width 0.1)
				(type default)
			)
			(layer "F.Fab")
		)
		(fp_line
			(start 0.67945 -0.3048)
			(end 0.67945 0.3048)
			(stroke
				(width 0.1)
				(type default)
			)
			(layer "F.Fab")
		)
		(fp_line
			(start -0.67945 -0.305054)
			(end -0.12065 -0.305054)
			(stroke
				(width 0.1)
				(type default)
			)
			(layer "F.Fab")
		)
		(fp_line
			(start -0.12065 -0.305054)
			(end -0.12065 -0.2794)
			(stroke
				(width 0.1)
				(type default)
			)
			(layer "F.Fab")
		)
		(pad "1" smd circle
			(at -0.40005 0 270)
			(size 0 0)
			(layers "F.Cu" "F.Mask" "F.Paste")
			(net "GND")
		)
		(pad "2" smd circle
			(at 0.40005 0 270)
			(size 0 0)
			(layers "F.Cu" "F.Mask" "F.Paste")
			(net "P3V3_AUX")
		)
	)
	(footprint ""
		(layer "F.Cu")
		(at 353.168966 -280.44902 -90)
		(property "Reference" "PC179"
			(at 0 0 270)
			(layer "F.SilkS")
			(hide yes)
			(effects
				(font
					(size 1.27 1.27)
				)
			)
		)
		(property "Value" ""
			(at 0 0 270)
			(layer "F.Fab")
			(effects
				(font
					(size 1.27 1.27)
				)
			)
		)
		(duplicate_pad_numbers_are_jumpers no)
		(fp_line
			(start -0.7874 0.4064)
			(end -0.7874 -0.4064)
			(stroke
				(width 0.1524)
				(type default)
			)
			(layer "F.SilkS")
		)
		(fp_line
			(start 0.7874 0.4064)
			(end -0.7874 0.4064)
			(stroke
				(width 0.1524)
				(type default)
			)
			(layer "F.SilkS")
		)
		(fp_line
			(start -0.7874 -0.4064)
			(end 0.7874 -0.4064)
			(stroke
				(width 0.1524)
				(type default)
			)
			(layer "F.SilkS")
		)
		(fp_line
			(start 0.7874 -0.4064)
			(end 0.7874 0.4064)
			(stroke
				(width 0.1524)
				(type default)
			)
			(layer "F.SilkS")
		)
		(fp_line
			(start -0.67945 0.3048)
			(end -0.67945 -0.305054)
			(stroke
				(width 0.1)
				(type default)
			)
			(layer "F.Fab")
		)
		(fp_line
			(start -0.12065 0.3048)
			(end -0.67945 0.3048)
			(stroke
				(width 0.1)
				(type default)
			)
			(layer "F.Fab")
		)
		(fp_line
			(start 0.120396 0.3048)
			(end 0.120396 0.2794)
			(stroke
				(width 0.1)
				(type default)
			)
			(layer "F.Fab")
		)
		(fp_line
			(start 0.67945 0.3048)
			(end 0.120396 0.3048)
			(stroke
				(width 0.1)
				(type default)
			)
			(layer "F.Fab")
		)
		(fp_line
			(start -0.12065 0.2794)
			(end -0.12065 0.3048)
			(stroke
				(width 0.1)
				(type default)
			)
			(layer "F.Fab")
		)
		(fp_line
			(start 0.120396 0.2794)
			(end -0.12065 0.2794)
			(stroke
				(width 0.1)
				(type default)
			)
			(layer "F.Fab")
		)
		(fp_line
			(start -0.12065 -0.2794)
			(end 0.12065 -0.2794)
			(stroke
				(width 0.1)
				(type default)
			)
			(layer "F.Fab")
		)
		(fp_line
			(start 0.12065 -0.2794)
			(end 0.12065 -0.3048)
			(stroke
				(width 0.1)
				(type default)
			)
			(layer "F.Fab")
		)
		(fp_line
			(start 0.12065 -0.3048)
			(end 0.67945 -0.3048)
			(stroke
				(width 0.1)
				(type default)
			)
			(layer "F.Fab")
		)
		(fp_line
			(start 0.67945 -0.3048)
			(end 0.67945 0.3048)
			(stroke
				(width 0.1)
				(type default)
			)
			(layer "F.Fab")
		)
		(fp_line
			(start -0.67945 -0.305054)
			(end -0.12065 -0.305054)
			(stroke
				(width 0.1)
				(type default)
			)
			(layer "F.Fab")
		)
		(fp_line
			(start -0.12065 -0.305054)
			(end -0.12065 -0.2794)
			(stroke
				(width 0.1)
				(type default)
			)
			(layer "F.Fab")
		)
		(pad "1" smd circle
			(at -0.40005 0 270)
			(size 0 0)
			(layers "F.Cu" "F.Mask" "F.Paste")
			(net "SW_P0V8_PEX3_PHASE1")
		)
		(pad "2" smd circle
			(at 0.40005 0 270)
			(size 0 0)
			(layers "F.Cu" "F.Mask" "F.Paste")
			(net "SW_P0V8_PEX3_BOOT1_R")
		)
	)
	(footprint ""
		(layer "F.Cu")
		(at 187.896246 -47.20082 90)
		(property "Reference" "C316"
			(at 0 0 90)
			(layer "F.SilkS")
			(hide yes)
			(effects
				(font
					(size 1.27 1.27)
				)
			)
		)
		(property "Value" ""
			(at 0 0 90)
			(layer "F.Fab")
			(effects
				(font
					(size 1.27 1.27)
				)
			)
		)
		(duplicate_pad_numbers_are_jumpers no)
		(fp_line
			(start 0.7874 -0.4064)
			(end 0.7874 0.4064)
			(stroke
				(width 0.1524)
				(type default)
			)
			(layer "F.SilkS")
		)
		(fp_line
			(start -0.7874 -0.4064)
			(end 0.7874 -0.4064)
			(stroke
				(width 0.1524)
				(type default)
			)
			(layer "F.SilkS")
		)
		(fp_line
			(start 0.7874 0.4064)
			(end -0.7874 0.4064)
			(stroke
				(width 0.1524)
				(type default)
			)
			(layer "F.SilkS")
		)
		(fp_line
			(start -0.7874 0.4064)
			(end -0.7874 -0.4064)
			(stroke
				(width 0.1524)
				(type default)
			)
			(layer "F.SilkS")
		)
		(fp_line
			(start -0.12065 -0.305054)
			(end -0.12065 -0.2794)
			(stroke
				(width 0.1)
				(type default)
			)
			(layer "F.Fab")
		)
		(fp_line
			(start -0.67945 -0.305054)
			(end -0.12065 -0.305054)
			(stroke
				(width 0.1)
				(type default)
			)
			(layer "F.Fab")
		)
		(fp_line
			(start 0.67945 -0.3048)
			(end 0.67945 0.3048)
			(stroke
				(width 0.1)
				(type default)
			)
			(layer "F.Fab")
		)
		(fp_line
			(start 0.12065 -0.3048)
			(end 0.67945 -0.3048)
			(stroke
				(width 0.1)
				(type default)
			)
			(layer "F.Fab")
		)
		(fp_line
			(start 0.12065 -0.2794)
			(end 0.12065 -0.3048)
			(stroke
				(width 0.1)
				(type default)
			)
			(layer "F.Fab")
		)
		(fp_line
			(start -0.12065 -0.2794)
			(end 0.12065 -0.2794)
			(stroke
				(width 0.1)
				(type default)
			)
			(layer "F.Fab")
		)
		(fp_line
			(start 0.120396 0.2794)
			(end -0.12065 0.2794)
			(stroke
				(width 0.1)
				(type default)
			)
			(layer "F.Fab")
		)
		(fp_line
			(start -0.12065 0.2794)
			(end -0.12065 0.3048)
			(stroke
				(width 0.1)
				(type default)
			)
			(layer "F.Fab")
		)
		(fp_line
			(start 0.67945 0.3048)
			(end 0.120396 0.3048)
			(stroke
				(width 0.1)
				(type default)
			)
			(layer "F.Fab")
		)
		(fp_line
			(start 0.120396 0.3048)
			(end 0.120396 0.2794)
			(stroke
				(width 0.1)
				(type default)
			)
			(layer "F.Fab")
		)
		(fp_line
			(start -0.12065 0.3048)
			(end -0.67945 0.3048)
			(stroke
				(width 0.1)
				(type default)
			)
			(layer "F.Fab")
		)
		(fp_line
			(start -0.67945 0.3048)
			(end -0.67945 -0.305054)
			(stroke
				(width 0.1)
				(type default)
			)
			(layer "F.Fab")
		)
		(pad "1" smd circle
			(at -0.40005 0 90)
			(size 0 0)
			(layers "F.Cu" "F.Mask" "F.Paste")
			(net "P12V_SSD6_R")
		)
		(pad "2" smd circle
			(at 0.40005 0 90)
			(size 0 0)
			(layers "F.Cu" "F.Mask" "F.Paste")
			(net "GND")
		)
	)
	(footprint ""
		(layer "F.Cu")
		(at 325.827644 -343.952322 90)
		(property "Reference" "C562"
			(at 0 0 90)
			(layer "F.SilkS")
			(hide yes)
			(effects
				(font
					(size 1.27 1.27)
				)
			)
		)
		(property "Value" ""
			(at 0 0 90)
			(layer "F.Fab")
			(effects
				(font
					(size 1.27 1.27)
				)
			)
		)
		(duplicate_pad_numbers_are_jumpers no)
		(fp_line
			(start 0.299974 -0.150114)
			(end 0.299974 0.150114)
			(stroke
				(width 0.1)
				(type default)
			)
			(layer "F.Fab")
		)
		(fp_line
			(start -0.299974 -0.150114)
			(end 0.299974 -0.150114)
			(stroke
				(width 0.1)
				(type default)
			)
			(layer "F.Fab")
		)
		(fp_line
			(start 0.299974 0.150114)
			(end -0.299974 0.150114)
			(stroke
				(width 0.1)
				(type default)
			)
			(layer "F.Fab")
		)
		(fp_line
			(start -0.299974 0.150114)
			(end -0.299974 -0.150114)
			(stroke
				(width 0.1)
				(type default)
			)
			(layer "F.Fab")
		)
		(pad "1" smd rect
			(at -0.2667 0 90)
			(size 0.3048 0.381)
			(layers "F.Cu" "F.Mask" "F.Paste")
			(net "P5E_PEX2_STN6_TX_DN<106>")
		)
		(pad "2" smd rect
			(at 0.2667 0 90)
			(size 0.3048 0.381)
			(layers "F.Cu" "F.Mask" "F.Paste")
			(net "P5E_PEX2_STN6_TX_C_DN<106>")
		)
	)
	(footprint ""
		(layer "F.Cu")
		(at 203.792582 -303.913794 90)
		(property "Reference" "R6717"
			(at 0 0 90)
			(layer "F.SilkS")
			(hide yes)
			(effects
				(font
					(size 1.27 1.27)
				)
			)
		)
		(property "Value" ""
			(at 0 0 90)
			(layer "F.Fab")
			(effects
				(font
					(size 1.27 1.27)
				)
			)
		)
		(duplicate_pad_numbers_are_jumpers no)
		(fp_line
			(start 0.7874 -0.4064)
			(end 0.7874 0.4064)
			(stroke
				(width 0.1524)
				(type default)
			)
			(layer "F.SilkS")
		)
		(fp_line
			(start -0.7874 -0.4064)
			(end 0.7874 -0.4064)
			(stroke
				(width 0.1524)
				(type default)
			)
			(layer "F.SilkS")
		)
		(fp_line
			(start 0.7874 0.4064)
			(end -0.7874 0.4064)
			(stroke
				(width 0.1524)
				(type default)
			)
			(layer "F.SilkS")
		)
		(fp_line
			(start -0.7874 0.4064)
			(end -0.7874 -0.4064)
			(stroke
				(width 0.1524)
				(type default)
			)
			(layer "F.SilkS")
		)
		(fp_line
			(start -0.12065 -0.305054)
			(end -0.12065 -0.2794)
			(stroke
				(width 0.1)
				(type default)
			)
			(layer "F.Fab")
		)
		(fp_line
			(start -0.67945 -0.305054)
			(end -0.12065 -0.305054)
			(stroke
				(width 0.1)
				(type default)
			)
			(layer "F.Fab")
		)
		(fp_line
			(start 0.67945 -0.3048)
			(end 0.67945 0.3048)
			(stroke
				(width 0.1)
				(type default)
			)
			(layer "F.Fab")
		)
		(fp_line
			(start 0.12065 -0.3048)
			(end 0.67945 -0.3048)
			(stroke
				(width 0.1)
				(type default)
			)
			(layer "F.Fab")
		)
		(fp_line
			(start 0.12065 -0.2794)
			(end 0.12065 -0.3048)
			(stroke
				(width 0.1)
				(type default)
			)
			(layer "F.Fab")
		)
		(fp_line
			(start -0.12065 -0.2794)
			(end 0.12065 -0.2794)
			(stroke
				(width 0.1)
				(type default)
			)
			(layer "F.Fab")
		)
		(fp_line
			(start 0.120396 0.2794)
			(end -0.12065 0.2794)
			(stroke
				(width 0.1)
				(type default)
			)
			(layer "F.Fab")
		)
		(fp_line
			(start -0.12065 0.2794)
			(end -0.12065 0.3048)
			(stroke
				(width 0.1)
				(type default)
			)
			(layer "F.Fab")
		)
		(fp_line
			(start 0.67945 0.3048)
			(end 0.120396 0.3048)
			(stroke
				(width 0.1)
				(type default)
			)
			(layer "F.Fab")
		)
		(fp_line
			(start 0.120396 0.3048)
			(end 0.120396 0.2794)
			(stroke
				(width 0.1)
				(type default)
			)
			(layer "F.Fab")
		)
		(fp_line
			(start -0.12065 0.3048)
			(end -0.67945 0.3048)
			(stroke
				(width 0.1)
				(type default)
			)
			(layer "F.Fab")
		)
		(fp_line
			(start -0.67945 0.3048)
			(end -0.67945 -0.305054)
			(stroke
				(width 0.1)
				(type default)
			)
			(layer "F.Fab")
		)
		(pad "1" smd circle
			(at -0.40005 0 90)
			(size 0 0)
			(layers "F.Cu" "F.Mask" "F.Paste")
			(net "SMB_PEX1_SLAVE1_SDA")
		)
		(pad "2" smd circle
			(at 0.40005 0 90)
			(size 0 0)
			(layers "F.Cu" "F.Mask" "F.Paste")
			(net "SMB_PEX1_R_SDA")
		)
	)
	(footprint ""
		(layer "F.Cu")
		(at 257.541776 -261.026402 180)
		(property "Reference" "C3418"
			(at 0 0 180)
			(layer "F.SilkS")
			(hide yes)
			(effects
				(font
					(size 1.27 1.27)
				)
			)
		)
		(property "Value" ""
			(at 0 0 180)
			(layer "F.Fab")
			(effects
				(font
					(size 1.27 1.27)
				)
			)
		)
		(duplicate_pad_numbers_are_jumpers no)
		(fp_line
			(start 1.2954 0.5842)
			(end -1.2954 0.5842)
			(stroke
				(width 0.1524)
				(type default)
			)
			(layer "F.SilkS")
		)
		(fp_line
			(start 1.2954 -0.5842)
			(end 1.2954 0.5842)
			(stroke
				(width 0.1524)
				(type default)
			)
			(layer "F.SilkS")
		)
		(fp_line
			(start -1.2954 0.5842)
			(end -1.2954 -0.5842)
			(stroke
				(width 0.1524)
				(type default)
			)
			(layer "F.SilkS")
		)
		(fp_line
			(start -1.2954 -0.5842)
			(end 1.2954 -0.5842)
			(stroke
				(width 0.1524)
				(type default)
			)
			(layer "F.SilkS")
		)
		(fp_line
			(start 1.1938 0.4064)
			(end 0.8636 0.4064)
			(stroke
				(width 0.1)
				(type default)
			)
			(layer "F.Fab")
		)
		(fp_line
			(start 1.1938 -0.4064)
			(end 1.1938 0.4064)
			(stroke
				(width 0.1)
				(type default)
			)
			(layer "F.Fab")
		)
		(fp_line
			(start 0.8636 0.4572)
			(end -0.8636 0.4572)
			(stroke
				(width 0.1)
				(type default)
			)
			(layer "F.Fab")
		)
		(fp_line
			(start 0.8636 0.4064)
			(end 0.8636 0.4572)
			(stroke
				(width 0.1)
				(type default)
			)
			(layer "F.Fab")
		)
		(fp_line
			(start 0.8636 -0.4064)
			(end 1.1938 -0.4064)
			(stroke
				(width 0.1)
				(type default)
			)
			(layer "F.Fab")
		)
		(fp_line
			(start 0.8636 -0.4572)
			(end 0.8636 -0.4064)
			(stroke
				(width 0.1)
				(type default)
			)
			(layer "F.Fab")
		)
		(fp_line
			(start -0.8636 0.4572)
			(end -0.8636 0.4064)
			(stroke
				(width 0.1)
				(type default)
			)
			(layer "F.Fab")
		)
		(fp_line
			(start -0.8636 0.4064)
			(end -1.1938 0.4064)
			(stroke
				(width 0.1)
				(type default)
			)
			(layer "F.Fab")
		)
		(fp_line
			(start -0.8636 -0.4064)
			(end -0.8636 -0.4572)
			(stroke
				(width 0.1)
				(type default)
			)
			(layer "F.Fab")
		)
		(fp_line
			(start -0.8636 -0.4572)
			(end 0.8636 -0.4572)
			(stroke
				(width 0.1)
				(type default)
			)
			(layer "F.Fab")
		)
		(fp_line
			(start -1.1938 0.4064)
			(end -1.1938 -0.4064)
			(stroke
				(width 0.1)
				(type default)
			)
			(layer "F.Fab")
		)
		(fp_line
			(start -1.1938 -0.4064)
			(end -0.8636 -0.4064)
			(stroke
				(width 0.1)
				(type default)
			)
			(layer "F.Fab")
		)
		(pad "1" smd rect
			(at -0.7366 0 90)
			(size 0.7112 0.8128)
			(layers "F.Cu" "F.Mask" "F.Paste")
			(net "P1V8_VDDA_PEX2")
		)
		(pad "2" smd rect
			(at 0.7366 0 90)
			(size 0.7112 0.8128)
			(layers "F.Cu" "F.Mask" "F.Paste")
			(net "GND")
		)
	)
	(footprint ""
		(layer "F.Cu")
		(at 310.467756 -53.051456)
		(property "Reference" "R4470"
			(at 0 0 0)
			(layer "F.SilkS")
			(hide yes)
			(effects
				(font
					(size 1.27 1.27)
				)
			)
		)
		(property "Value" ""
			(at 0 0 0)
			(layer "F.Fab")
			(effects
				(font
					(size 1.27 1.27)
				)
			)
		)
		(duplicate_pad_numbers_are_jumpers no)
		(fp_line
			(start -0.7874 -0.4064)
			(end 0.7874 -0.4064)
			(stroke
				(width 0.1524)
				(type default)
			)
			(layer "F.SilkS")
		)
		(fp_line
			(start -0.7874 0.4064)
			(end -0.7874 -0.4064)
			(stroke
				(width 0.1524)
				(type default)
			)
			(layer "F.SilkS")
		)
		(fp_line
			(start 0.7874 -0.4064)
			(end 0.7874 0.4064)
			(stroke
				(width 0.1524)
				(type default)
			)
			(layer "F.SilkS")
		)
		(fp_line
			(start 0.7874 0.4064)
			(end -0.7874 0.4064)
			(stroke
				(width 0.1524)
				(type default)
			)
			(layer "F.SilkS")
		)
		(fp_line
			(start -0.67945 -0.305054)
			(end -0.12065 -0.305054)
			(stroke
				(width 0.1)
				(type default)
			)
			(layer "F.Fab")
		)
		(fp_line
			(start -0.67945 0.3048)
			(end -0.67945 -0.305054)
			(stroke
				(width 0.1)
				(type default)
			)
			(layer "F.Fab")
		)
		(fp_line
			(start -0.12065 -0.305054)
			(end -0.12065 -0.2794)
			(stroke
				(width 0.1)
				(type default)
			)
			(layer "F.Fab")
		)
		(fp_line
			(start -0.12065 -0.2794)
			(end 0.12065 -0.2794)
			(stroke
				(width 0.1)
				(type default)
			)
			(layer "F.Fab")
		)
		(fp_line
			(start -0.12065 0.2794)
			(end -0.12065 0.3048)
			(stroke
				(width 0.1)
				(type default)
			)
			(layer "F.Fab")
		)
		(fp_line
			(start -0.12065 0.3048)
			(end -0.67945 0.3048)
			(stroke
				(width 0.1)
				(type default)
			)
			(layer "F.Fab")
		)
		(fp_line
			(start 0.120396 0.2794)
			(end -0.12065 0.2794)
			(stroke
				(width 0.1)
				(type default)
			)
			(layer "F.Fab")
		)
		(fp_line
			(start 0.120396 0.3048)
			(end 0.120396 0.2794)
			(stroke
				(width 0.1)
				(type default)
			)
			(layer "F.Fab")
		)
		(fp_line
			(start 0.12065 -0.3048)
			(end 0.67945 -0.3048)
			(stroke
				(width 0.1)
				(type default)
			)
			(layer "F.Fab")
		)
		(fp_line
			(start 0.12065 -0.2794)
			(end 0.12065 -0.3048)
			(stroke
				(width 0.1)
				(type default)
			)
			(layer "F.Fab")
		)
		(fp_line
			(start 0.67945 -0.3048)
			(end 0.67945 0.3048)
			(stroke
				(width 0.1)
				(type default)
			)
			(layer "F.Fab")
		)
		(fp_line
			(start 0.67945 0.3048)
			(end 0.120396 0.3048)
			(stroke
				(width 0.1)
				(type default)
			)
			(layer "F.Fab")
		)
		(pad "1" smd circle
			(at -0.40005 0)
			(size 0 0)
			(layers "F.Cu" "F.Mask" "F.Paste")
			(net "PWRGD_P12V_SSD10")
		)
		(pad "2" smd circle
			(at 0.40005 0)
			(size 0 0)
			(layers "F.Cu" "F.Mask" "F.Paste")
			(net "PWRGD_P12V_SSD10_R")
		)
	)
	(footprint ""
		(layer "F.Cu")
		(at 171.979844 -141.9352 180)
		(property "Reference" "R112"
			(at 0 0 180)
			(layer "F.SilkS")
			(hide yes)
			(effects
				(font
					(size 1.27 1.27)
				)
			)
		)
		(property "Value" ""
			(at 0 0 180)
			(layer "F.Fab")
			(effects
				(font
					(size 1.27 1.27)
				)
			)
		)
		(duplicate_pad_numbers_are_jumpers no)
		(fp_line
			(start 0.7874 0.4064)
			(end -0.7874 0.4064)
			(stroke
				(width 0.1524)
				(type default)
			)
			(layer "F.SilkS")
		)
		(fp_line
			(start 0.7874 -0.4064)
			(end 0.7874 0.4064)
			(stroke
				(width 0.1524)
				(type default)
			)
			(layer "F.SilkS")
		)
		(fp_line
			(start -0.7874 0.4064)
			(end -0.7874 -0.4064)
			(stroke
				(width 0.1524)
				(type default)
			)
			(layer "F.SilkS")
		)
		(fp_line
			(start -0.7874 -0.4064)
			(end 0.7874 -0.4064)
			(stroke
				(width 0.1524)
				(type default)
			)
			(layer "F.SilkS")
		)
		(fp_line
			(start 0.67945 0.3048)
			(end 0.120396 0.3048)
			(stroke
				(width 0.1)
				(type default)
			)
			(layer "F.Fab")
		)
		(fp_line
			(start 0.67945 -0.3048)
			(end 0.67945 0.3048)
			(stroke
				(width 0.1)
				(type default)
			)
			(layer "F.Fab")
		)
		(fp_line
			(start 0.12065 -0.2794)
			(end 0.12065 -0.3048)
			(stroke
				(width 0.1)
				(type default)
			)
			(layer "F.Fab")
		)
		(fp_line
			(start 0.12065 -0.3048)
			(end 0.67945 -0.3048)
			(stroke
				(width 0.1)
				(type default)
			)
			(layer "F.Fab")
		)
		(fp_line
			(start 0.120396 0.3048)
			(end 0.120396 0.2794)
			(stroke
				(width 0.1)
				(type default)
			)
			(layer "F.Fab")
		)
		(fp_line
			(start 0.120396 0.2794)
			(end -0.12065 0.2794)
			(stroke
				(width 0.1)
				(type default)
			)
			(layer "F.Fab")
		)
		(fp_line
			(start -0.12065 0.3048)
			(end -0.67945 0.3048)
			(stroke
				(width 0.1)
				(type default)
			)
			(layer "F.Fab")
		)
		(fp_line
			(start -0.12065 0.2794)
			(end -0.12065 0.3048)
			(stroke
				(width 0.1)
				(type default)
			)
			(layer "F.Fab")
		)
		(fp_line
			(start -0.12065 -0.2794)
			(end 0.12065 -0.2794)
			(stroke
				(width 0.1)
				(type default)
			)
			(layer "F.Fab")
		)
		(fp_line
			(start -0.12065 -0.305054)
			(end -0.12065 -0.2794)
			(stroke
				(width 0.1)
				(type default)
			)
			(layer "F.Fab")
		)
		(fp_line
			(start -0.67945 0.3048)
			(end -0.67945 -0.305054)
			(stroke
				(width 0.1)
				(type default)
			)
			(layer "F.Fab")
		)
		(fp_line
			(start -0.67945 -0.305054)
			(end -0.12065 -0.305054)
			(stroke
				(width 0.1)
				(type default)
			)
			(layer "F.Fab")
		)
		(pad "1" smd circle
			(at -0.40005 0 180)
			(size 0 0)
			(layers "F.Cu" "F.Mask" "F.Paste")
			(net "P3V3_NIC2")
		)
		(pad "2" smd circle
			(at 0.40005 0 180)
			(size 0 0)
			(layers "F.Cu" "F.Mask" "F.Paste")
			(net "SMB_NIC2_R_SDA")
		)
	)
	(footprint ""
		(layer "F.Cu")
		(at 182.94604 -177.322988 90)
		(property "Reference" "R6672"
			(at 0 0 90)
			(layer "F.SilkS")
			(hide yes)
			(effects
				(font
					(size 1.27 1.27)
				)
			)
		)
		(property "Value" ""
			(at 0 0 90)
			(layer "F.Fab")
			(effects
				(font
					(size 1.27 1.27)
				)
			)
		)
		(duplicate_pad_numbers_are_jumpers no)
		(fp_line
			(start 0.7874 -0.4064)
			(end 0.7874 0.4064)
			(stroke
				(width 0.1524)
				(type default)
			)
			(layer "F.SilkS")
		)
		(fp_line
			(start -0.7874 -0.4064)
			(end 0.7874 -0.4064)
			(stroke
				(width 0.1524)
				(type default)
			)
			(layer "F.SilkS")
		)
		(fp_line
			(start 0.7874 0.4064)
			(end -0.7874 0.4064)
			(stroke
				(width 0.1524)
				(type default)
			)
			(layer "F.SilkS")
		)
		(fp_line
			(start -0.7874 0.4064)
			(end -0.7874 -0.4064)
			(stroke
				(width 0.1524)
				(type default)
			)
			(layer "F.SilkS")
		)
		(fp_line
			(start -0.12065 -0.305054)
			(end -0.12065 -0.2794)
			(stroke
				(width 0.1)
				(type default)
			)
			(layer "F.Fab")
		)
		(fp_line
			(start -0.67945 -0.305054)
			(end -0.12065 -0.305054)
			(stroke
				(width 0.1)
				(type default)
			)
			(layer "F.Fab")
		)
		(fp_line
			(start 0.67945 -0.3048)
			(end 0.67945 0.3048)
			(stroke
				(width 0.1)
				(type default)
			)
			(layer "F.Fab")
		)
		(fp_line
			(start 0.12065 -0.3048)
			(end 0.67945 -0.3048)
			(stroke
				(width 0.1)
				(type default)
			)
			(layer "F.Fab")
		)
		(fp_line
			(start 0.12065 -0.2794)
			(end 0.12065 -0.3048)
			(stroke
				(width 0.1)
				(type default)
			)
			(layer "F.Fab")
		)
		(fp_line
			(start -0.12065 -0.2794)
			(end 0.12065 -0.2794)
			(stroke
				(width 0.1)
				(type default)
			)
			(layer "F.Fab")
		)
		(fp_line
			(start 0.120396 0.2794)
			(end -0.12065 0.2794)
			(stroke
				(width 0.1)
				(type default)
			)
			(layer "F.Fab")
		)
		(fp_line
			(start -0.12065 0.2794)
			(end -0.12065 0.3048)
			(stroke
				(width 0.1)
				(type default)
			)
			(layer "F.Fab")
		)
		(fp_line
			(start 0.67945 0.3048)
			(end 0.120396 0.3048)
			(stroke
				(width 0.1)
				(type default)
			)
			(layer "F.Fab")
		)
		(fp_line
			(start 0.120396 0.3048)
			(end 0.120396 0.2794)
			(stroke
				(width 0.1)
				(type default)
			)
			(layer "F.Fab")
		)
		(fp_line
			(start -0.12065 0.3048)
			(end -0.67945 0.3048)
			(stroke
				(width 0.1)
				(type default)
			)
			(layer "F.Fab")
		)
		(fp_line
			(start -0.67945 0.3048)
			(end -0.67945 -0.305054)
			(stroke
				(width 0.1)
				(type default)
			)
			(layer "F.Fab")
		)
		(pad "1" smd circle
			(at -0.40005 0 90)
			(size 0 0)
			(layers "F.Cu" "F.Mask" "F.Paste")
			(net "NIC3_CLK_EN_BUF_R_N")
		)
		(pad "2" smd circle
			(at 0.40005 0 90)
			(size 0 0)
			(layers "F.Cu" "F.Mask" "F.Paste")
			(net "P3V3")
		)
	)
	(footprint ""
		(layer "F.Cu")
		(at 178.609752 -165.670484 -90)
		(property "Reference" "R2466"
			(at 0 0 270)
			(layer "F.SilkS")
			(hide yes)
			(effects
				(font
					(size 1.27 1.27)
				)
			)
		)
		(property "Value" ""
			(at 0 0 270)
			(layer "F.Fab")
			(effects
				(font
					(size 1.27 1.27)
				)
			)
		)
		(duplicate_pad_numbers_are_jumpers no)
		(fp_line
			(start -0.7874 0.4064)
			(end -0.7874 -0.4064)
			(stroke
				(width 0.1524)
				(type default)
			)
			(layer "F.SilkS")
		)
		(fp_line
			(start 0.7874 0.4064)
			(end -0.7874 0.4064)
			(stroke
				(width 0.1524)
				(type default)
			)
			(layer "F.SilkS")
		)
		(fp_line
			(start -0.7874 -0.4064)
			(end 0.7874 -0.4064)
			(stroke
				(width 0.1524)
				(type default)
			)
			(layer "F.SilkS")
		)
		(fp_line
			(start 0.7874 -0.4064)
			(end 0.7874 0.4064)
			(stroke
				(width 0.1524)
				(type default)
			)
			(layer "F.SilkS")
		)
		(fp_line
			(start -0.67945 0.3048)
			(end -0.67945 -0.305054)
			(stroke
				(width 0.1)
				(type default)
			)
			(layer "F.Fab")
		)
		(fp_line
			(start -0.12065 0.3048)
			(end -0.67945 0.3048)
			(stroke
				(width 0.1)
				(type default)
			)
			(layer "F.Fab")
		)
		(fp_line
			(start 0.120396 0.3048)
			(end 0.120396 0.2794)
			(stroke
				(width 0.1)
				(type default)
			)
			(layer "F.Fab")
		)
		(fp_line
			(start 0.67945 0.3048)
			(end 0.120396 0.3048)
			(stroke
				(width 0.1)
				(type default)
			)
			(layer "F.Fab")
		)
		(fp_line
			(start -0.12065 0.2794)
			(end -0.12065 0.3048)
			(stroke
				(width 0.1)
				(type default)
			)
			(layer "F.Fab")
		)
		(fp_line
			(start 0.120396 0.2794)
			(end -0.12065 0.2794)
			(stroke
				(width 0.1)
				(type default)
			)
			(layer "F.Fab")
		)
		(fp_line
			(start -0.12065 -0.2794)
			(end 0.12065 -0.2794)
			(stroke
				(width 0.1)
				(type default)
			)
			(layer "F.Fab")
		)
		(fp_line
			(start 0.12065 -0.2794)
			(end 0.12065 -0.3048)
			(stroke
				(width 0.1)
				(type default)
			)
			(layer "F.Fab")
		)
		(fp_line
			(start 0.12065 -0.3048)
			(end 0.67945 -0.3048)
			(stroke
				(width 0.1)
				(type default)
			)
			(layer "F.Fab")
		)
		(fp_line
			(start 0.67945 -0.3048)
			(end 0.67945 0.3048)
			(stroke
				(width 0.1)
				(type default)
			)
			(layer "F.Fab")
		)
		(fp_line
			(start -0.67945 -0.305054)
			(end -0.12065 -0.305054)
			(stroke
				(width 0.1)
				(type default)
			)
			(layer "F.Fab")
		)
		(fp_line
			(start -0.12065 -0.305054)
			(end -0.12065 -0.2794)
			(stroke
				(width 0.1)
				(type default)
			)
			(layer "F.Fab")
		)
		(pad "1" smd circle
			(at -0.40005 0 270)
			(size 0 0)
			(layers "F.Cu" "F.Mask" "F.Paste")
			(net "NIC2_PWRBRK_R_N")
		)
		(pad "2" smd circle
			(at 0.40005 0 270)
			(size 0 0)
			(layers "F.Cu" "F.Mask" "F.Paste")
			(net "NIC2_PWRBRK_N")
		)
	)
	(footprint ""
		(layer "F.Cu")
		(at 293.657782 -350.098614 90)
		(property "Reference" "C590"
			(at 0 0 90)
			(layer "F.SilkS")
			(hide yes)
			(effects
				(font
					(size 1.27 1.27)
				)
			)
		)
		(property "Value" ""
			(at 0 0 90)
			(layer "F.Fab")
			(effects
				(font
					(size 1.27 1.27)
				)
			)
		)
		(duplicate_pad_numbers_are_jumpers no)
		(fp_line
			(start 0.299974 -0.150114)
			(end 0.299974 0.150114)
			(stroke
				(width 0.1)
				(type default)
			)
			(layer "F.Fab")
		)
		(fp_line
			(start -0.299974 -0.150114)
			(end 0.299974 -0.150114)
			(stroke
				(width 0.1)
				(type default)
			)
			(layer "F.Fab")
		)
		(fp_line
			(start 0.299974 0.150114)
			(end -0.299974 0.150114)
			(stroke
				(width 0.1)
				(type default)
			)
			(layer "F.Fab")
		)
		(fp_line
			(start -0.299974 0.150114)
			(end -0.299974 -0.150114)
			(stroke
				(width 0.1)
				(type default)
			)
			(layer "F.Fab")
		)
		(pad "1" smd rect
			(at -0.2667 0 90)
			(size 0.3048 0.381)
			(layers "F.Cu" "F.Mask" "F.Paste")
			(net "P5E_PEX2_STN7_TX_DN<124>")
		)
		(pad "2" smd rect
			(at 0.2667 0 90)
			(size 0.3048 0.381)
			(layers "F.Cu" "F.Mask" "F.Paste")
			(net "P5E_PEX2_STN7_TX_C_DN<124>")
		)
	)
	(footprint ""
		(layer "F.Cu")
		(at 411.479492 -200.782682)
		(property "Reference" "Q235"
			(at -0.569214 -1.738884 0)
			(unlocked yes)
			(layer "F.SilkS")
			(effects
				(font
					(size 0.7874 0.5842)
					(thickness 0.1524)
				)
			)
		)
		(property "Value" ""
			(at 0 0 0)
			(layer "F.Fab")
			(effects
				(font
					(size 1.27 1.27)
				)
			)
		)
		(duplicate_pad_numbers_are_jumpers no)
		(fp_line
			(start -1.376172 -1.199896)
			(end -0.508 -1.199896)
			(stroke
				(width 0.1524)
				(type default)
			)
			(layer "F.SilkS")
		)
		(fp_line
			(start -1.376172 1.199896)
			(end -1.376172 -1.199896)
			(stroke
				(width 0.1524)
				(type default)
			)
			(layer "F.SilkS")
		)
		(fp_line
			(start -0.508 -1.199896)
			(end 0 -0.762)
			(stroke
				(width 0.1524)
				(type default)
			)
			(layer "F.SilkS")
		)
		(fp_line
			(start 0 -0.762)
			(end 0.508 -1.199896)
			(stroke
				(width 0.1524)
				(type default)
			)
			(layer "F.SilkS")
		)
		(fp_line
			(start 0.508 -1.199896)
			(end 1.376172 -1.199896)
			(stroke
				(width 0.1524)
				(type default)
			)
			(layer "F.SilkS")
		)
		(fp_line
			(start 1.376172 -1.199896)
			(end 1.376172 1.199896)
			(stroke
				(width 0.1524)
				(type default)
			)
			(layer "F.SilkS")
		)
		(fp_line
			(start 1.376172 1.199896)
			(end -1.376172 1.199896)
			(stroke
				(width 0.1524)
				(type default)
			)
			(layer "F.SilkS")
		)
		(fp_poly
			(pts
				(xy -1.4605 -0.7493) (xy -2.2225 -1.1303) (xy -2.2225 -0.3683)
			)
			(stroke
				(width 0)
				(type default)
			)
			(fill yes)
			(layer "F.SilkS")
		)
		(fp_line
			(start -0.674878 -1.100074)
			(end 0.674878 -1.100074)
			(stroke
				(width 0.1)
				(type default)
			)
			(layer "F.Fab")
		)
		(fp_line
			(start -0.674878 1.100074)
			(end -0.674878 -1.100074)
			(stroke
				(width 0.1)
				(type default)
			)
			(layer "F.Fab")
		)
		(fp_line
			(start 0.674878 -1.100074)
			(end 0.674878 1.100074)
			(stroke
				(width 0.1)
				(type default)
			)
			(layer "F.Fab")
		)
		(fp_line
			(start 0.674878 1.100074)
			(end -0.674878 1.100074)
			(stroke
				(width 0.1)
				(type default)
			)
			(layer "F.Fab")
		)
		(fp_poly
			(pts
				(xy -1.4605 -0.7493) (xy -2.2225 -1.1303) (xy -2.2225 -0.3683)
			)
			(stroke
				(width 0)
				(type default)
			)
			(fill yes)
			(layer "F.Fab")
		)
		(pad "1" smd rect
			(at -0.899922 -0.750062 270)
			(size 0.6096 0.6096)
			(layers "F.Cu" "F.Mask" "F.Paste")
			(net "GND")
		)
		(pad "2" smd rect
			(at -0.899922 0 270)
			(size 0.4064 0.6096)
			(layers "F.Cu" "F.Mask" "F.Paste")
			(net "FPGA_PEX1_MODE_SEL2_R")
		)
		(pad "3" smd rect
			(at -0.899922 0.750062 270)
			(size 0.6096 0.6096)
			(layers "F.Cu" "F.Mask" "F.Paste")
			(net "FPGA_PEX1_MODE_SEL2_ISO")
		)
		(pad "4" smd rect
			(at 0.899922 0.750062 270)
			(size 0.6096 0.6096)
			(layers "F.Cu" "F.Mask" "F.Paste")
			(net "GND")
		)
		(pad "5" smd rect
			(at 0.899922 0 270)
			(size 0.4064 0.6096)
			(layers "F.Cu" "F.Mask" "F.Paste")
			(net "FPGA_PEX1_MODE_SEL2_D_N")
		)
		(pad "6" smd rect
			(at 0.899922 -0.750062 270)
			(size 0.6096 0.6096)
			(layers "F.Cu" "F.Mask" "F.Paste")
			(net "FPGA_PEX1_MODE_SEL2_D_N")
		)
	)
	(footprint ""
		(layer "F.Cu")
		(at 453.827134 -366.70361)
		(property "Reference" "Q244"
			(at -0.6604 -1.793748 0)
			(unlocked yes)
			(layer "F.SilkS")
			(effects
				(font
					(size 0.7874 0.5842)
					(thickness 0.1524)
				)
			)
		)
		(property "Value" ""
			(at 0 0 0)
			(layer "F.Fab")
			(effects
				(font
					(size 1.27 1.27)
				)
			)
		)
		(duplicate_pad_numbers_are_jumpers no)
		(fp_line
			(start -1.376172 -1.199896)
			(end -0.508 -1.199896)
			(stroke
				(width 0.1524)
				(type default)
			)
			(layer "F.SilkS")
		)
		(fp_line
			(start -1.376172 1.199896)
			(end -1.376172 -1.199896)
			(stroke
				(width 0.1524)
				(type default)
			)
			(layer "F.SilkS")
		)
		(fp_line
			(start -0.508 -1.199896)
			(end 0 -0.762)
			(stroke
				(width 0.1524)
				(type default)
			)
			(layer "F.SilkS")
		)
		(fp_line
			(start 0 -0.762)
			(end 0.508 -1.199896)
			(stroke
				(width 0.1524)
				(type default)
			)
			(layer "F.SilkS")
		)
		(fp_line
			(start 0.508 -1.199896)
			(end 1.376172 -1.199896)
			(stroke
				(width 0.1524)
				(type default)
			)
			(layer "F.SilkS")
		)
		(fp_line
			(start 1.376172 -1.199896)
			(end 1.376172 1.199896)
			(stroke
				(width 0.1524)
				(type default)
			)
			(layer "F.SilkS")
		)
		(fp_line
			(start 1.376172 1.199896)
			(end -1.376172 1.199896)
			(stroke
				(width 0.1524)
				(type default)
			)
			(layer "F.SilkS")
		)
		(fp_poly
			(pts
				(xy -1.4605 -0.7493) (xy -2.2225 -1.1303) (xy -2.2225 -0.3683)
			)
			(stroke
				(width 0)
				(type default)
			)
			(fill yes)
			(layer "F.SilkS")
		)
		(fp_line
			(start -0.674878 -1.100074)
			(end 0.674878 -1.100074)
			(stroke
				(width 0.1)
				(type default)
			)
			(layer "F.Fab")
		)
		(fp_line
			(start -0.674878 1.100074)
			(end -0.674878 -1.100074)
			(stroke
				(width 0.1)
				(type default)
			)
			(layer "F.Fab")
		)
		(fp_line
			(start 0.674878 -1.100074)
			(end 0.674878 1.100074)
			(stroke
				(width 0.1)
				(type default)
			)
			(layer "F.Fab")
		)
		(fp_line
			(start 0.674878 1.100074)
			(end -0.674878 1.100074)
			(stroke
				(width 0.1)
				(type default)
			)
			(layer "F.Fab")
		)
		(fp_poly
			(pts
				(xy -1.4605 -0.7493) (xy -2.2225 -1.1303) (xy -2.2225 -0.3683)
			)
			(stroke
				(width 0)
				(type default)
			)
			(fill yes)
			(layer "F.Fab")
		)
		(pad "1" smd rect
			(at -0.899922 -0.750062 270)
			(size 0.6096 0.6096)
			(layers "F.Cu" "F.Mask" "F.Paste")
			(net "GND")
		)
		(pad "2" smd rect
			(at -0.899922 0 270)
			(size 0.4064 0.6096)
			(layers "F.Cu" "F.Mask" "F.Paste")
			(net "GPU_3V3IO_RSVD1")
		)
		(pad "3" smd rect
			(at -0.899922 0.750062 270)
			(size 0.6096 0.6096)
			(layers "F.Cu" "F.Mask" "F.Paste")
			(net "GPU_3V3IO_RSVD1_ISO")
		)
		(pad "4" smd rect
			(at 0.899922 0.750062 270)
			(size 0.6096 0.6096)
			(layers "F.Cu" "F.Mask" "F.Paste")
			(net "GND")
		)
		(pad "5" smd rect
			(at 0.899922 0 270)
			(size 0.4064 0.6096)
			(layers "F.Cu" "F.Mask" "F.Paste")
			(net "GPU_3V3IO_RSVD1_N")
		)
		(pad "6" smd rect
			(at 0.899922 -0.750062 270)
			(size 0.6096 0.6096)
			(layers "F.Cu" "F.Mask" "F.Paste")
			(net "GPU_3V3IO_RSVD1_N")
		)
	)
	(footprint ""
		(layer "F.Cu")
		(at 278.634444 -34.546286 180)
		(property "Reference" "C495"
			(at 0 0 180)
			(layer "F.SilkS")
			(hide yes)
			(effects
				(font
					(size 1.27 1.27)
				)
			)
		)
		(property "Value" ""
			(at 0 0 180)
			(layer "F.Fab")
			(effects
				(font
					(size 1.27 1.27)
				)
			)
		)
		(duplicate_pad_numbers_are_jumpers no)
		(fp_line
			(start 0.299974 0.150114)
			(end -0.299974 0.150114)
			(stroke
				(width 0.1)
				(type default)
			)
			(layer "F.Fab")
		)
		(fp_line
			(start 0.299974 -0.150114)
			(end 0.299974 0.150114)
			(stroke
				(width 0.1)
				(type default)
			)
			(layer "F.Fab")
		)
		(fp_line
			(start -0.299974 0.150114)
			(end -0.299974 -0.150114)
			(stroke
				(width 0.1)
				(type default)
			)
			(layer "F.Fab")
		)
		(fp_line
			(start -0.299974 -0.150114)
			(end 0.299974 -0.150114)
			(stroke
				(width 0.1)
				(type default)
			)
			(layer "F.Fab")
		)
		(pad "1" smd rect
			(at -0.2667 0 180)
			(size 0.3048 0.381)
			(layers "F.Cu" "F.Mask" "F.Paste")
			(net "P5E_PEX2_STN2_TX_DP<43>")
		)
		(pad "2" smd rect
			(at 0.2667 0 180)
			(size 0.3048 0.381)
			(layers "F.Cu" "F.Mask" "F.Paste")
			(net "P5E_PEX2_STN2_TX_C_DP<43>")
		)
	)
	(footprint ""
		(layer "F.Cu")
		(at 82.947256 -36.686998 90)
		(property "Reference" "C3664"
			(at 0 0 90)
			(layer "F.SilkS")
			(hide yes)
			(effects
				(font
					(size 1.27 1.27)
				)
			)
		)
		(property "Value" ""
			(at 0 0 90)
			(layer "F.Fab")
			(effects
				(font
					(size 1.27 1.27)
				)
			)
		)
		(duplicate_pad_numbers_are_jumpers no)
		(fp_line
			(start 0.7874 -0.4064)
			(end 0.7874 0.4064)
			(stroke
				(width 0.1524)
				(type default)
			)
			(layer "F.SilkS")
		)
		(fp_line
			(start -0.7874 -0.4064)
			(end 0.7874 -0.4064)
			(stroke
				(width 0.1524)
				(type default)
			)
			(layer "F.SilkS")
		)
		(fp_line
			(start 0.7874 0.4064)
			(end -0.7874 0.4064)
			(stroke
				(width 0.1524)
				(type default)
			)
			(layer "F.SilkS")
		)
		(fp_line
			(start -0.7874 0.4064)
			(end -0.7874 -0.4064)
			(stroke
				(width 0.1524)
				(type default)
			)
			(layer "F.SilkS")
		)
		(fp_line
			(start -0.12065 -0.305054)
			(end -0.12065 -0.2794)
			(stroke
				(width 0.1)
				(type default)
			)
			(layer "F.Fab")
		)
		(fp_line
			(start -0.67945 -0.305054)
			(end -0.12065 -0.305054)
			(stroke
				(width 0.1)
				(type default)
			)
			(layer "F.Fab")
		)
		(fp_line
			(start 0.67945 -0.3048)
			(end 0.67945 0.3048)
			(stroke
				(width 0.1)
				(type default)
			)
			(layer "F.Fab")
		)
		(fp_line
			(start 0.12065 -0.3048)
			(end 0.67945 -0.3048)
			(stroke
				(width 0.1)
				(type default)
			)
			(layer "F.Fab")
		)
		(fp_line
			(start 0.12065 -0.2794)
			(end 0.12065 -0.3048)
			(stroke
				(width 0.1)
				(type default)
			)
			(layer "F.Fab")
		)
		(fp_line
			(start -0.12065 -0.2794)
			(end 0.12065 -0.2794)
			(stroke
				(width 0.1)
				(type default)
			)
			(layer "F.Fab")
		)
		(fp_line
			(start 0.120396 0.2794)
			(end -0.12065 0.2794)
			(stroke
				(width 0.1)
				(type default)
			)
			(layer "F.Fab")
		)
		(fp_line
			(start -0.12065 0.2794)
			(end -0.12065 0.3048)
			(stroke
				(width 0.1)
				(type default)
			)
			(layer "F.Fab")
		)
		(fp_line
			(start 0.67945 0.3048)
			(end 0.120396 0.3048)
			(stroke
				(width 0.1)
				(type default)
			)
			(layer "F.Fab")
		)
		(fp_line
			(start 0.120396 0.3048)
			(end 0.120396 0.2794)
			(stroke
				(width 0.1)
				(type default)
			)
			(layer "F.Fab")
		)
		(fp_line
			(start -0.12065 0.3048)
			(end -0.67945 0.3048)
			(stroke
				(width 0.1)
				(type default)
			)
			(layer "F.Fab")
		)
		(fp_line
			(start -0.67945 0.3048)
			(end -0.67945 -0.305054)
			(stroke
				(width 0.1)
				(type default)
			)
			(layer "F.Fab")
		)
		(pad "1" smd circle
			(at -0.40005 0 90)
			(size 0 0)
			(layers "F.Cu" "F.Mask" "F.Paste")
			(net "P3V3_AUX")
		)
		(pad "2" smd circle
			(at 0.40005 0 90)
			(size 0 0)
			(layers "F.Cu" "F.Mask" "F.Paste")
			(net "GND")
		)
	)
	(footprint ""
		(layer "F.Cu")
		(at 52.243736 -44.87291)
		(property "Reference" "R518"
			(at 0 0 0)
			(layer "F.SilkS")
			(hide yes)
			(effects
				(font
					(size 1.27 1.27)
				)
			)
		)
		(property "Value" ""
			(at 0 0 0)
			(layer "F.Fab")
			(effects
				(font
					(size 1.27 1.27)
				)
			)
		)
		(duplicate_pad_numbers_are_jumpers no)
		(fp_line
			(start -0.7874 -0.4064)
			(end 0.7874 -0.4064)
			(stroke
				(width 0.1524)
				(type default)
			)
			(layer "F.SilkS")
		)
		(fp_line
			(start -0.7874 0.4064)
			(end -0.7874 -0.4064)
			(stroke
				(width 0.1524)
				(type default)
			)
			(layer "F.SilkS")
		)
		(fp_line
			(start 0.7874 -0.4064)
			(end 0.7874 0.4064)
			(stroke
				(width 0.1524)
				(type default)
			)
			(layer "F.SilkS")
		)
		(fp_line
			(start 0.7874 0.4064)
			(end -0.7874 0.4064)
			(stroke
				(width 0.1524)
				(type default)
			)
			(layer "F.SilkS")
		)
		(fp_line
			(start -0.67945 -0.305054)
			(end -0.12065 -0.305054)
			(stroke
				(width 0.1)
				(type default)
			)
			(layer "F.Fab")
		)
		(fp_line
			(start -0.67945 0.3048)
			(end -0.67945 -0.305054)
			(stroke
				(width 0.1)
				(type default)
			)
			(layer "F.Fab")
		)
		(fp_line
			(start -0.12065 -0.305054)
			(end -0.12065 -0.2794)
			(stroke
				(width 0.1)
				(type default)
			)
			(layer "F.Fab")
		)
		(fp_line
			(start -0.12065 -0.2794)
			(end 0.12065 -0.2794)
			(stroke
				(width 0.1)
				(type default)
			)
			(layer "F.Fab")
		)
		(fp_line
			(start -0.12065 0.2794)
			(end -0.12065 0.3048)
			(stroke
				(width 0.1)
				(type default)
			)
			(layer "F.Fab")
		)
		(fp_line
			(start -0.12065 0.3048)
			(end -0.67945 0.3048)
			(stroke
				(width 0.1)
				(type default)
			)
			(layer "F.Fab")
		)
		(fp_line
			(start 0.120396 0.2794)
			(end -0.12065 0.2794)
			(stroke
				(width 0.1)
				(type default)
			)
			(layer "F.Fab")
		)
		(fp_line
			(start 0.120396 0.3048)
			(end 0.120396 0.2794)
			(stroke
				(width 0.1)
				(type default)
			)
			(layer "F.Fab")
		)
		(fp_line
			(start 0.12065 -0.3048)
			(end 0.67945 -0.3048)
			(stroke
				(width 0.1)
				(type default)
			)
			(layer "F.Fab")
		)
		(fp_line
			(start 0.12065 -0.2794)
			(end 0.12065 -0.3048)
			(stroke
				(width 0.1)
				(type default)
			)
			(layer "F.Fab")
		)
		(fp_line
			(start 0.67945 -0.3048)
			(end 0.67945 0.3048)
			(stroke
				(width 0.1)
				(type default)
			)
			(layer "F.Fab")
		)
		(fp_line
			(start 0.67945 0.3048)
			(end 0.120396 0.3048)
			(stroke
				(width 0.1)
				(type default)
			)
			(layer "F.Fab")
		)
		(pad "1" smd circle
			(at -0.40005 0)
			(size 0 0)
			(layers "F.Cu" "F.Mask" "F.Paste")
			(net "SSD1_ADC_A0")
		)
		(pad "2" smd circle
			(at 0.40005 0)
			(size 0 0)
			(layers "F.Cu" "F.Mask" "F.Paste")
			(net "P3V3_AUX")
		)
	)
	(footprint ""
		(layer "F.Cu")
		(at 381.403352 -59.571636 90)
		(property "Reference" "PR278"
			(at 0 0 90)
			(layer "F.SilkS")
			(hide yes)
			(effects
				(font
					(size 1.27 1.27)
				)
			)
		)
		(property "Value" ""
			(at 0 0 90)
			(layer "F.Fab")
			(effects
				(font
					(size 1.27 1.27)
				)
			)
		)
		(duplicate_pad_numbers_are_jumpers no)
		(fp_line
			(start 0.7874 -0.4064)
			(end 0.7874 0.4064)
			(stroke
				(width 0.1524)
				(type default)
			)
			(layer "F.SilkS")
		)
		(fp_line
			(start -0.7874 -0.4064)
			(end 0.7874 -0.4064)
			(stroke
				(width 0.1524)
				(type default)
			)
			(layer "F.SilkS")
		)
		(fp_line
			(start 0.7874 0.4064)
			(end -0.7874 0.4064)
			(stroke
				(width 0.1524)
				(type default)
			)
			(layer "F.SilkS")
		)
		(fp_line
			(start -0.7874 0.4064)
			(end -0.7874 -0.4064)
			(stroke
				(width 0.1524)
				(type default)
			)
			(layer "F.SilkS")
		)
		(fp_line
			(start -0.12065 -0.305054)
			(end -0.12065 -0.2794)
			(stroke
				(width 0.1)
				(type default)
			)
			(layer "F.Fab")
		)
		(fp_line
			(start -0.67945 -0.305054)
			(end -0.12065 -0.305054)
			(stroke
				(width 0.1)
				(type default)
			)
			(layer "F.Fab")
		)
		(fp_line
			(start 0.67945 -0.3048)
			(end 0.67945 0.3048)
			(stroke
				(width 0.1)
				(type default)
			)
			(layer "F.Fab")
		)
		(fp_line
			(start 0.12065 -0.3048)
			(end 0.67945 -0.3048)
			(stroke
				(width 0.1)
				(type default)
			)
			(layer "F.Fab")
		)
		(fp_line
			(start 0.12065 -0.2794)
			(end 0.12065 -0.3048)
			(stroke
				(width 0.1)
				(type default)
			)
			(layer "F.Fab")
		)
		(fp_line
			(start -0.12065 -0.2794)
			(end 0.12065 -0.2794)
			(stroke
				(width 0.1)
				(type default)
			)
			(layer "F.Fab")
		)
		(fp_line
			(start 0.120396 0.2794)
			(end -0.12065 0.2794)
			(stroke
				(width 0.1)
				(type default)
			)
			(layer "F.Fab")
		)
		(fp_line
			(start -0.12065 0.2794)
			(end -0.12065 0.3048)
			(stroke
				(width 0.1)
				(type default)
			)
			(layer "F.Fab")
		)
		(fp_line
			(start 0.67945 0.3048)
			(end 0.120396 0.3048)
			(stroke
				(width 0.1)
				(type default)
			)
			(layer "F.Fab")
		)
		(fp_line
			(start 0.120396 0.3048)
			(end 0.120396 0.2794)
			(stroke
				(width 0.1)
				(type default)
			)
			(layer "F.Fab")
		)
		(fp_line
			(start -0.12065 0.3048)
			(end -0.67945 0.3048)
			(stroke
				(width 0.1)
				(type default)
			)
			(layer "F.Fab")
		)
		(fp_line
			(start -0.67945 0.3048)
			(end -0.67945 -0.305054)
			(stroke
				(width 0.1)
				(type default)
			)
			(layer "F.Fab")
		)
		(pad "1" smd circle
			(at -0.40005 0 90)
			(size 0 0)
			(layers "F.Cu" "F.Mask" "F.Paste")
			(net "P3V3_SSD13_OCP")
		)
		(pad "2" smd circle
			(at 0.40005 0 90)
			(size 0 0)
			(layers "F.Cu" "F.Mask" "F.Paste")
			(net "GND")
		)
	)
	(footprint ""
		(layer "F.Cu")
		(at 239.18799 -91.250262 -90)
		(property "Reference" "C2622"
			(at 0 0 270)
			(layer "F.SilkS")
			(hide yes)
			(effects
				(font
					(size 1.27 1.27)
				)
			)
		)
		(property "Value" ""
			(at 0 0 270)
			(layer "F.Fab")
			(effects
				(font
					(size 1.27 1.27)
				)
			)
		)
		(duplicate_pad_numbers_are_jumpers no)
		(fp_line
			(start -0.7874 0.4064)
			(end -0.7874 -0.4064)
			(stroke
				(width 0.1524)
				(type default)
			)
			(layer "F.SilkS")
		)
		(fp_line
			(start 0.7874 0.4064)
			(end -0.7874 0.4064)
			(stroke
				(width 0.1524)
				(type default)
			)
			(layer "F.SilkS")
		)
		(fp_line
			(start -0.7874 -0.4064)
			(end 0.7874 -0.4064)
			(stroke
				(width 0.1524)
				(type default)
			)
			(layer "F.SilkS")
		)
		(fp_line
			(start 0.7874 -0.4064)
			(end 0.7874 0.4064)
			(stroke
				(width 0.1524)
				(type default)
			)
			(layer "F.SilkS")
		)
		(fp_line
			(start -0.67945 0.3048)
			(end -0.67945 -0.305054)
			(stroke
				(width 0.1)
				(type default)
			)
			(layer "F.Fab")
		)
		(fp_line
			(start -0.12065 0.3048)
			(end -0.67945 0.3048)
			(stroke
				(width 0.1)
				(type default)
			)
			(layer "F.Fab")
		)
		(fp_line
			(start 0.120396 0.3048)
			(end 0.120396 0.2794)
			(stroke
				(width 0.1)
				(type default)
			)
			(layer "F.Fab")
		)
		(fp_line
			(start 0.67945 0.3048)
			(end 0.120396 0.3048)
			(stroke
				(width 0.1)
				(type default)
			)
			(layer "F.Fab")
		)
		(fp_line
			(start -0.12065 0.2794)
			(end -0.12065 0.3048)
			(stroke
				(width 0.1)
				(type default)
			)
			(layer "F.Fab")
		)
		(fp_line
			(start 0.120396 0.2794)
			(end -0.12065 0.2794)
			(stroke
				(width 0.1)
				(type default)
			)
			(layer "F.Fab")
		)
		(fp_line
			(start -0.12065 -0.2794)
			(end 0.12065 -0.2794)
			(stroke
				(width 0.1)
				(type default)
			)
			(layer "F.Fab")
		)
		(fp_line
			(start 0.12065 -0.2794)
			(end 0.12065 -0.3048)
			(stroke
				(width 0.1)
				(type default)
			)
			(layer "F.Fab")
		)
		(fp_line
			(start 0.12065 -0.3048)
			(end 0.67945 -0.3048)
			(stroke
				(width 0.1)
				(type default)
			)
			(layer "F.Fab")
		)
		(fp_line
			(start 0.67945 -0.3048)
			(end 0.67945 0.3048)
			(stroke
				(width 0.1)
				(type default)
			)
			(layer "F.Fab")
		)
		(fp_line
			(start -0.67945 -0.305054)
			(end -0.12065 -0.305054)
			(stroke
				(width 0.1)
				(type default)
			)
			(layer "F.Fab")
		)
		(fp_line
			(start -0.12065 -0.305054)
			(end -0.12065 -0.2794)
			(stroke
				(width 0.1)
				(type default)
			)
			(layer "F.Fab")
		)
		(pad "1" smd circle
			(at -0.40005 0 270)
			(size 0 0)
			(layers "F.Cu" "F.Mask" "F.Paste")
			(net "PEX_USB_HUB_XIN")
		)
		(pad "2" smd circle
			(at 0.40005 0 270)
			(size 0 0)
			(layers "F.Cu" "F.Mask" "F.Paste")
			(net "GND")
		)
	)
	(footprint ""
		(layer "F.Cu")
		(at 129.32156 -129.799334 180)
		(property "Reference" "PD4"
			(at 4.20116 2.685796 0)
			(unlocked yes)
			(layer "F.SilkS")
			(effects
				(font
					(size 0.7874 0.5842)
					(thickness 0.1524)
				)
				(justify left)
			)
		)
		(property "Value" ""
			(at 0 0 180)
			(layer "F.Fab")
			(effects
				(font
					(size 1.27 1.27)
				)
			)
		)
		(duplicate_pad_numbers_are_jumpers no)
		(fp_line
			(start 4.240784 1.970024)
			(end 4.240784 -1.970024)
			(stroke
				(width 0.1524)
				(type default)
			)
			(layer "F.SilkS")
		)
		(fp_line
			(start 4.240784 -1.970024)
			(end -3.656584 -1.970024)
			(stroke
				(width 0.1524)
				(type default)
			)
			(layer "F.SilkS")
		)
		(fp_line
			(start -3.656584 1.970024)
			(end 4.240784 1.970024)
			(stroke
				(width 0.1524)
				(type default)
			)
			(layer "F.SilkS")
		)
		(fp_line
			(start -3.656584 -1.970024)
			(end -3.656584 1.970024)
			(stroke
				(width 0.1524)
				(type default)
			)
			(layer "F.SilkS")
		)
		(fp_poly
			(pts
				(xy 3.580384 1.970024) (xy 3.580384 -1.970024) (xy 4.240784 -1.970024) (xy 4.240784 1.970024)
			)
			(stroke
				(width 0)
				(type default)
			)
			(fill yes)
			(layer "F.SilkS")
		)
		(fp_line
			(start 2.3749 1.970024)
			(end 2.3749 -1.970024)
			(stroke
				(width 0.1)
				(type default)
			)
			(layer "F.Fab")
		)
		(fp_line
			(start 2.3749 -1.970024)
			(end -2.3749 -1.970024)
			(stroke
				(width 0.1)
				(type default)
			)
			(layer "F.Fab")
		)
		(fp_line
			(start -2.3749 1.970024)
			(end 2.3749 1.970024)
			(stroke
				(width 0.1)
				(type default)
			)
			(layer "F.Fab")
		)
		(fp_line
			(start -2.3749 -1.970024)
			(end -2.3749 1.970024)
			(stroke
				(width 0.1)
				(type default)
			)
			(layer "F.Fab")
		)
		(fp_text user "-"
			(at 4.1656 -0.23495 180)
			(unlocked yes)
			(layer "F.Fab")
			(effects
				(font
					(size 1.905 1.4224)
					(thickness 0.1524)
				)
				(justify left)
			)
		)
		(fp_text user "+"
			(at -4.9784 -0.23495 180)
			(unlocked yes)
			(layer "F.Fab")
			(effects
				(font
					(size 1.905 1.4224)
					(thickness 0.1524)
				)
				(justify left)
			)
		)
		(pad "A" smd rect
			(at -2.450084 0 180)
			(size 2.159 2.2606)
			(layers "F.Cu" "F.Mask" "F.Paste")
			(net "GND")
		)
		(pad "C" smd rect
			(at 2.450084 0 180)
			(size 2.159 2.2606)
			(layers "F.Cu" "F.Mask" "F.Paste")
			(net "P12V_AUX")
		)
	)
	(footprint ""
		(layer "F.Cu")
		(at 93.621098 -102.880414 90)
		(property "Reference" "C871"
			(at 0 0 90)
			(layer "F.SilkS")
			(hide yes)
			(effects
				(font
					(size 1.27 1.27)
				)
			)
		)
		(property "Value" ""
			(at 0 0 90)
			(layer "F.Fab")
			(effects
				(font
					(size 1.27 1.27)
				)
			)
		)
		(duplicate_pad_numbers_are_jumpers no)
		(fp_line
			(start 0.7874 -0.4064)
			(end 0.7874 0.4064)
			(stroke
				(width 0.1524)
				(type default)
			)
			(layer "F.SilkS")
		)
		(fp_line
			(start -0.7874 -0.4064)
			(end 0.7874 -0.4064)
			(stroke
				(width 0.1524)
				(type default)
			)
			(layer "F.SilkS")
		)
		(fp_line
			(start 0.7874 0.4064)
			(end -0.7874 0.4064)
			(stroke
				(width 0.1524)
				(type default)
			)
			(layer "F.SilkS")
		)
		(fp_line
			(start -0.7874 0.4064)
			(end -0.7874 -0.4064)
			(stroke
				(width 0.1524)
				(type default)
			)
			(layer "F.SilkS")
		)
		(fp_line
			(start -0.12065 -0.305054)
			(end -0.12065 -0.2794)
			(stroke
				(width 0.1)
				(type default)
			)
			(layer "F.Fab")
		)
		(fp_line
			(start -0.67945 -0.305054)
			(end -0.12065 -0.305054)
			(stroke
				(width 0.1)
				(type default)
			)
			(layer "F.Fab")
		)
		(fp_line
			(start 0.67945 -0.3048)
			(end 0.67945 0.3048)
			(stroke
				(width 0.1)
				(type default)
			)
			(layer "F.Fab")
		)
		(fp_line
			(start 0.12065 -0.3048)
			(end 0.67945 -0.3048)
			(stroke
				(width 0.1)
				(type default)
			)
			(layer "F.Fab")
		)
		(fp_line
			(start 0.12065 -0.2794)
			(end 0.12065 -0.3048)
			(stroke
				(width 0.1)
				(type default)
			)
			(layer "F.Fab")
		)
		(fp_line
			(start -0.12065 -0.2794)
			(end 0.12065 -0.2794)
			(stroke
				(width 0.1)
				(type default)
			)
			(layer "F.Fab")
		)
		(fp_line
			(start 0.120396 0.2794)
			(end -0.12065 0.2794)
			(stroke
				(width 0.1)
				(type default)
			)
			(layer "F.Fab")
		)
		(fp_line
			(start -0.12065 0.2794)
			(end -0.12065 0.3048)
			(stroke
				(width 0.1)
				(type default)
			)
			(layer "F.Fab")
		)
		(fp_line
			(start 0.67945 0.3048)
			(end 0.120396 0.3048)
			(stroke
				(width 0.1)
				(type default)
			)
			(layer "F.Fab")
		)
		(fp_line
			(start 0.120396 0.3048)
			(end 0.120396 0.2794)
			(stroke
				(width 0.1)
				(type default)
			)
			(layer "F.Fab")
		)
		(fp_line
			(start -0.12065 0.3048)
			(end -0.67945 0.3048)
			(stroke
				(width 0.1)
				(type default)
			)
			(layer "F.Fab")
		)
		(fp_line
			(start -0.67945 0.3048)
			(end -0.67945 -0.305054)
			(stroke
				(width 0.1)
				(type default)
			)
			(layer "F.Fab")
		)
		(pad "1" smd circle
			(at -0.40005 0 90)
			(size 0 0)
			(layers "F.Cu" "F.Mask" "F.Paste")
			(net "P3V3_AUX")
		)
		(pad "2" smd circle
			(at 0.40005 0 90)
			(size 0 0)
			(layers "F.Cu" "F.Mask" "F.Paste")
			(net "GND")
		)
	)
	(footprint ""
		(layer "F.Cu")
		(at 14.653768 -162.003994 -90)
		(property "Reference" "R905"
			(at 0 0 270)
			(layer "F.SilkS")
			(hide yes)
			(effects
				(font
					(size 1.27 1.27)
				)
			)
		)
		(property "Value" ""
			(at 0 0 270)
			(layer "F.Fab")
			(effects
				(font
					(size 1.27 1.27)
				)
			)
		)
		(duplicate_pad_numbers_are_jumpers no)
		(fp_line
			(start -0.7874 0.4064)
			(end -0.7874 -0.4064)
			(stroke
				(width 0.1524)
				(type default)
			)
			(layer "F.SilkS")
		)
		(fp_line
			(start 0.7874 0.4064)
			(end -0.7874 0.4064)
			(stroke
				(width 0.1524)
				(type default)
			)
			(layer "F.SilkS")
		)
		(fp_line
			(start -0.7874 -0.4064)
			(end 0.7874 -0.4064)
			(stroke
				(width 0.1524)
				(type default)
			)
			(layer "F.SilkS")
		)
		(fp_line
			(start 0.7874 -0.4064)
			(end 0.7874 0.4064)
			(stroke
				(width 0.1524)
				(type default)
			)
			(layer "F.SilkS")
		)
		(fp_line
			(start -0.67945 0.3048)
			(end -0.67945 -0.305054)
			(stroke
				(width 0.1)
				(type default)
			)
			(layer "F.Fab")
		)
		(fp_line
			(start -0.12065 0.3048)
			(end -0.67945 0.3048)
			(stroke
				(width 0.1)
				(type default)
			)
			(layer "F.Fab")
		)
		(fp_line
			(start 0.120396 0.3048)
			(end 0.120396 0.2794)
			(stroke
				(width 0.1)
				(type default)
			)
			(layer "F.Fab")
		)
		(fp_line
			(start 0.67945 0.3048)
			(end 0.120396 0.3048)
			(stroke
				(width 0.1)
				(type default)
			)
			(layer "F.Fab")
		)
		(fp_line
			(start -0.12065 0.2794)
			(end -0.12065 0.3048)
			(stroke
				(width 0.1)
				(type default)
			)
			(layer "F.Fab")
		)
		(fp_line
			(start 0.120396 0.2794)
			(end -0.12065 0.2794)
			(stroke
				(width 0.1)
				(type default)
			)
			(layer "F.Fab")
		)
		(fp_line
			(start -0.12065 -0.2794)
			(end 0.12065 -0.2794)
			(stroke
				(width 0.1)
				(type default)
			)
			(layer "F.Fab")
		)
		(fp_line
			(start 0.12065 -0.2794)
			(end 0.12065 -0.3048)
			(stroke
				(width 0.1)
				(type default)
			)
			(layer "F.Fab")
		)
		(fp_line
			(start 0.12065 -0.3048)
			(end 0.67945 -0.3048)
			(stroke
				(width 0.1)
				(type default)
			)
			(layer "F.Fab")
		)
		(fp_line
			(start 0.67945 -0.3048)
			(end 0.67945 0.3048)
			(stroke
				(width 0.1)
				(type default)
			)
			(layer "F.Fab")
		)
		(fp_line
			(start -0.67945 -0.305054)
			(end -0.12065 -0.305054)
			(stroke
				(width 0.1)
				(type default)
			)
			(layer "F.Fab")
		)
		(fp_line
			(start -0.12065 -0.305054)
			(end -0.12065 -0.2794)
			(stroke
				(width 0.1)
				(type default)
			)
			(layer "F.Fab")
		)
		(pad "1" smd circle
			(at -0.40005 0 270)
			(size 0 0)
			(layers "F.Cu" "F.Mask" "F.Paste")
			(net "GND")
		)
		(pad "2" smd circle
			(at 0.40005 0 270)
			(size 0 0)
			(layers "F.Cu" "F.Mask" "F.Paste")
			(net "P12V_NIC0_CO_EN")
		)
	)
	(footprint ""
		(layer "F.Cu")
		(at 459.710282 -30.681168)
		(property "Reference" "H44"
			(at -3.729482 -2.540762 0)
			(unlocked yes)
			(layer "F.SilkS")
			(effects
				(font
					(size 0.7874 0.5842)
					(thickness 0.1524)
				)
				(justify left)
			)
		)
		(property "Value" ""
			(at 0 0 0)
			(layer "F.Fab")
			(effects
				(font
					(size 1.27 1.27)
				)
			)
		)
		(duplicate_pad_numbers_are_jumpers no)
		(fp_circle
			(center 0 0)
			(end 2.4003 0)
			(stroke
				(width 0.1524)
				(type default)
			)
			(fill no)
			(layer "F.SilkS")
		)
		(fp_circle
			(center 0 0)
			(end 6.5913 0)
			(stroke
				(width 0.1524)
				(type default)
			)
			(fill no)
			(layer "B.SilkS")
		)
		(fp_circle
			(center 0 0)
			(end 6.5913 0)
			(stroke
				(width 0.1)
				(type default)
			)
			(fill no)
			(layer "B.Fab")
		)
		(fp_circle
			(center 0 0)
			(end 2.4003 0)
			(stroke
				(width 0.1)
				(type default)
			)
			(fill no)
			(layer "F.Fab")
		)
		(pad "" np_thru_hole circle
			(at 0 0)
			(size 3.175 3.175)
			(drill 3.175)
			(layers "*.Cu" "*.Mask")
			(clearance 0.381)
			(thermal_gap 0.381)
		)
		(zone
			(layers "F.Cu" "B.Cu" "In1.Cu" "In2.Cu" "In3.Cu" "In4.Cu" "In5.Cu" "In6.Cu"
				"In7.Cu" "In8.Cu" "In9.Cu" "In10.Cu" "In11.Cu" "In12.Cu" "In13.Cu" "In14.Cu"
				"In15.Cu" "In16.Cu"
			)
			(hatch none 0.5)
			(connect_pads
				(clearance 0)
			)
			(min_thickness 0.25)
			(keepout
				(tracks not_allowed)
				(vias allowed)
				(pads allowed)
				(copperpour not_allowed)
				(footprints allowed)
			)
			(placement
				(enabled no)
				(sheetname "")
			)
			(fill
				(thermal_gap 0.5)
				(thermal_bridge_width 0.5)
				(island_removal_mode 0)
			)
			(polygon
				(pts
					(arc
						(start 461.805782 -30.681168)
						(mid 457.614782 -30.681168)
						(end 461.805782 -30.681168)
					)
				)
			)
		)
	)
	(footprint ""
		(layer "F.Cu")
		(at 203.040234 -143.182848 90)
		(property "Reference" "C4001"
			(at 0 0 90)
			(layer "F.SilkS")
			(hide yes)
			(effects
				(font
					(size 1.27 1.27)
				)
			)
		)
		(property "Value" ""
			(at 0 0 90)
			(layer "F.Fab")
			(effects
				(font
					(size 1.27 1.27)
				)
			)
		)
		(duplicate_pad_numbers_are_jumpers no)
		(fp_line
			(start 0.7874 -0.4064)
			(end 0.7874 0.4064)
			(stroke
				(width 0.1524)
				(type default)
			)
			(layer "F.SilkS")
		)
		(fp_line
			(start -0.7874 -0.4064)
			(end 0.7874 -0.4064)
			(stroke
				(width 0.1524)
				(type default)
			)
			(layer "F.SilkS")
		)
		(fp_line
			(start 0.7874 0.4064)
			(end -0.7874 0.4064)
			(stroke
				(width 0.1524)
				(type default)
			)
			(layer "F.SilkS")
		)
		(fp_line
			(start -0.7874 0.4064)
			(end -0.7874 -0.4064)
			(stroke
				(width 0.1524)
				(type default)
			)
			(layer "F.SilkS")
		)
		(fp_line
			(start -0.12065 -0.305054)
			(end -0.12065 -0.2794)
			(stroke
				(width 0.1)
				(type default)
			)
			(layer "F.Fab")
		)
		(fp_line
			(start -0.67945 -0.305054)
			(end -0.12065 -0.305054)
			(stroke
				(width 0.1)
				(type default)
			)
			(layer "F.Fab")
		)
		(fp_line
			(start 0.67945 -0.3048)
			(end 0.67945 0.3048)
			(stroke
				(width 0.1)
				(type default)
			)
			(layer "F.Fab")
		)
		(fp_line
			(start 0.12065 -0.3048)
			(end 0.67945 -0.3048)
			(stroke
				(width 0.1)
				(type default)
			)
			(layer "F.Fab")
		)
		(fp_line
			(start 0.12065 -0.2794)
			(end 0.12065 -0.3048)
			(stroke
				(width 0.1)
				(type default)
			)
			(layer "F.Fab")
		)
		(fp_line
			(start -0.12065 -0.2794)
			(end 0.12065 -0.2794)
			(stroke
				(width 0.1)
				(type default)
			)
			(layer "F.Fab")
		)
		(fp_line
			(start 0.120396 0.2794)
			(end -0.12065 0.2794)
			(stroke
				(width 0.1)
				(type default)
			)
			(layer "F.Fab")
		)
		(fp_line
			(start -0.12065 0.2794)
			(end -0.12065 0.3048)
			(stroke
				(width 0.1)
				(type default)
			)
			(layer "F.Fab")
		)
		(fp_line
			(start 0.67945 0.3048)
			(end 0.120396 0.3048)
			(stroke
				(width 0.1)
				(type default)
			)
			(layer "F.Fab")
		)
		(fp_line
			(start 0.120396 0.3048)
			(end 0.120396 0.2794)
			(stroke
				(width 0.1)
				(type default)
			)
			(layer "F.Fab")
		)
		(fp_line
			(start -0.12065 0.3048)
			(end -0.67945 0.3048)
			(stroke
				(width 0.1)
				(type default)
			)
			(layer "F.Fab")
		)
		(fp_line
			(start -0.67945 0.3048)
			(end -0.67945 -0.305054)
			(stroke
				(width 0.1)
				(type default)
			)
			(layer "F.Fab")
		)
		(pad "1" smd circle
			(at -0.40005 0 90)
			(size 0 0)
			(layers "F.Cu" "F.Mask" "F.Paste")
			(net "PRSNT_NIC3_R_N")
		)
		(pad "2" smd circle
			(at 0.40005 0 90)
			(size 0 0)
			(layers "F.Cu" "F.Mask" "F.Paste")
			(net "GND")
		)
	)
	(footprint ""
		(layer "F.Cu")
		(at 255.856486 -20.467574 180)
		(property "Reference" "R1689"
			(at 0 0 180)
			(layer "F.SilkS")
			(hide yes)
			(effects
				(font
					(size 1.27 1.27)
				)
			)
		)
		(property "Value" ""
			(at 0 0 180)
			(layer "F.Fab")
			(effects
				(font
					(size 1.27 1.27)
				)
			)
		)
		(duplicate_pad_numbers_are_jumpers no)
		(fp_line
			(start 0.7874 0.4064)
			(end -0.7874 0.4064)
			(stroke
				(width 0.1524)
				(type default)
			)
			(layer "F.SilkS")
		)
		(fp_line
			(start 0.7874 -0.4064)
			(end 0.7874 0.4064)
			(stroke
				(width 0.1524)
				(type default)
			)
			(layer "F.SilkS")
		)
		(fp_line
			(start -0.7874 0.4064)
			(end -0.7874 -0.4064)
			(stroke
				(width 0.1524)
				(type default)
			)
			(layer "F.SilkS")
		)
		(fp_line
			(start -0.7874 -0.4064)
			(end 0.7874 -0.4064)
			(stroke
				(width 0.1524)
				(type default)
			)
			(layer "F.SilkS")
		)
		(fp_line
			(start 0.67945 0.3048)
			(end 0.120396 0.3048)
			(stroke
				(width 0.1)
				(type default)
			)
			(layer "F.Fab")
		)
		(fp_line
			(start 0.67945 -0.3048)
			(end 0.67945 0.3048)
			(stroke
				(width 0.1)
				(type default)
			)
			(layer "F.Fab")
		)
		(fp_line
			(start 0.12065 -0.2794)
			(end 0.12065 -0.3048)
			(stroke
				(width 0.1)
				(type default)
			)
			(layer "F.Fab")
		)
		(fp_line
			(start 0.12065 -0.3048)
			(end 0.67945 -0.3048)
			(stroke
				(width 0.1)
				(type default)
			)
			(layer "F.Fab")
		)
		(fp_line
			(start 0.120396 0.3048)
			(end 0.120396 0.2794)
			(stroke
				(width 0.1)
				(type default)
			)
			(layer "F.Fab")
		)
		(fp_line
			(start 0.120396 0.2794)
			(end -0.12065 0.2794)
			(stroke
				(width 0.1)
				(type default)
			)
			(layer "F.Fab")
		)
		(fp_line
			(start -0.12065 0.3048)
			(end -0.67945 0.3048)
			(stroke
				(width 0.1)
				(type default)
			)
			(layer "F.Fab")
		)
		(fp_line
			(start -0.12065 0.2794)
			(end -0.12065 0.3048)
			(stroke
				(width 0.1)
				(type default)
			)
			(layer "F.Fab")
		)
		(fp_line
			(start -0.12065 -0.2794)
			(end 0.12065 -0.2794)
			(stroke
				(width 0.1)
				(type default)
			)
			(layer "F.Fab")
		)
		(fp_line
			(start -0.12065 -0.305054)
			(end -0.12065 -0.2794)
			(stroke
				(width 0.1)
				(type default)
			)
			(layer "F.Fab")
		)
		(fp_line
			(start -0.67945 0.3048)
			(end -0.67945 -0.305054)
			(stroke
				(width 0.1)
				(type default)
			)
			(layer "F.Fab")
		)
		(fp_line
			(start -0.67945 -0.305054)
			(end -0.12065 -0.305054)
			(stroke
				(width 0.1)
				(type default)
			)
			(layer "F.Fab")
		)
		(pad "1" smd circle
			(at -0.40005 0 180)
			(size 0 0)
			(layers "F.Cu" "F.Mask" "F.Paste")
			(net "P3V3_SSD8")
		)
		(pad "2" smd circle
			(at 0.40005 0 180)
			(size 0 0)
			(layers "F.Cu" "F.Mask" "F.Paste")
			(net "SMB_ISO_SSD8_SDA")
		)
	)
	(footprint ""
		(layer "F.Cu")
		(at 152.738328 -134.008876)
		(property "Reference" "C246"
			(at 0 0 0)
			(layer "F.SilkS")
			(hide yes)
			(effects
				(font
					(size 1.27 1.27)
				)
			)
		)
		(property "Value" ""
			(at 0 0 0)
			(layer "F.Fab")
			(effects
				(font
					(size 1.27 1.27)
				)
			)
		)
		(duplicate_pad_numbers_are_jumpers no)
		(fp_line
			(start -0.299974 -0.150114)
			(end 0.299974 -0.150114)
			(stroke
				(width 0.1)
				(type default)
			)
			(layer "F.Fab")
		)
		(fp_line
			(start -0.299974 0.150114)
			(end -0.299974 -0.150114)
			(stroke
				(width 0.1)
				(type default)
			)
			(layer "F.Fab")
		)
		(fp_line
			(start 0.299974 -0.150114)
			(end 0.299974 0.150114)
			(stroke
				(width 0.1)
				(type default)
			)
			(layer "F.Fab")
		)
		(fp_line
			(start 0.299974 0.150114)
			(end -0.299974 0.150114)
			(stroke
				(width 0.1)
				(type default)
			)
			(layer "F.Fab")
		)
		(pad "1" smd rect
			(at -0.2667 0)
			(size 0.3048 0.381)
			(layers "F.Cu" "F.Mask" "F.Paste")
			(net "P5E_PEX1_STN1_TX_DP<30>")
		)
		(pad "2" smd rect
			(at 0.2667 0)
			(size 0.3048 0.381)
			(layers "F.Cu" "F.Mask" "F.Paste")
			(net "P5E_PEX1_STN1_TX_C_DP<30>")
		)
	)
	(footprint ""
		(layer "F.Cu")
		(at 331.22362 -106.413808 180)
		(property "Reference" "PD11"
			(at 4.12242 2.144522 0)
			(unlocked yes)
			(layer "F.SilkS")
			(effects
				(font
					(size 0.7874 0.5842)
					(thickness 0.1524)
				)
				(justify left)
			)
		)
		(property "Value" ""
			(at 0 0 180)
			(layer "F.Fab")
			(effects
				(font
					(size 1.27 1.27)
				)
			)
		)
		(duplicate_pad_numbers_are_jumpers no)
		(fp_line
			(start 4.107942 1.459992)
			(end -3.400044 1.459992)
			(stroke
				(width 0.1524)
				(type default)
			)
			(layer "F.SilkS")
		)
		(fp_line
			(start 4.107942 -1.459992)
			(end 4.107942 1.459992)
			(stroke
				(width 0.1524)
				(type default)
			)
			(layer "F.SilkS")
		)
		(fp_line
			(start -3.400044 1.459992)
			(end -3.400044 -1.459992)
			(stroke
				(width 0.1524)
				(type default)
			)
			(layer "F.SilkS")
		)
		(fp_line
			(start -3.400044 -1.459992)
			(end 4.107942 -1.459992)
			(stroke
				(width 0.1524)
				(type default)
			)
			(layer "F.SilkS")
		)
		(fp_rect
			(start 4.107942 -1.459992)
			(end 3.308096 1.459992)
			(stroke
				(width 0)
				(type default)
			)
			(fill yes)
			(layer "F.SilkS")
		)
		(fp_line
			(start 2.29997 1.459992)
			(end -2.29997 1.459992)
			(stroke
				(width 0.1)
				(type default)
			)
			(layer "F.Fab")
		)
		(fp_line
			(start 2.29997 -1.459992)
			(end 2.29997 1.459992)
			(stroke
				(width 0.1)
				(type default)
			)
			(layer "F.Fab")
		)
		(fp_line
			(start -2.29997 1.459992)
			(end -2.29997 -1.459992)
			(stroke
				(width 0.1)
				(type default)
			)
			(layer "F.Fab")
		)
		(fp_line
			(start -2.29997 -1.459992)
			(end 2.29997 -1.459992)
			(stroke
				(width 0.1)
				(type default)
			)
			(layer "F.Fab")
		)
		(fp_text user "-"
			(at 4.946904 -1.626108 0)
			(unlocked yes)
			(layer "F.SilkS")
			(effects
				(font
					(size 1.905 1.4224)
					(thickness 0.1524)
				)
				(justify left)
			)
		)
		(fp_text user "+"
			(at -4.619244 1.084072 180)
			(unlocked yes)
			(layer "F.SilkS")
			(effects
				(font
					(size 1.905 1.4224)
					(thickness 0.1524)
				)
				(justify left)
			)
		)
		(fp_text user "-"
			(at 5.4102 0.29845 0)
			(unlocked yes)
			(layer "F.Fab")
			(effects
				(font
					(size 1.905 1.4224)
					(thickness 0.1524)
				)
				(justify left)
			)
		)
		(fp_text user "+"
			(at -4.7752 -0.12065 180)
			(unlocked yes)
			(layer "F.Fab")
			(effects
				(font
					(size 1.905 1.4224)
					(thickness 0.1524)
				)
				(justify left)
			)
		)
		(pad "A" smd rect
			(at -1.999996 0 270)
			(size 1.7018 2.5146)
			(layers "F.Cu" "F.Mask" "F.Paste")
			(net "GND")
		)
		(pad "C" smd rect
			(at 1.999996 0 270)
			(size 1.7018 2.5146)
			(layers "F.Cu" "F.Mask" "F.Paste")
			(net "P12V_NIC5_R")
		)
	)
	(footprint ""
		(layer "F.Cu")
		(at 404.18004 -138.6332 180)
		(property "Reference" "R347"
			(at 0 0 180)
			(layer "F.SilkS")
			(hide yes)
			(effects
				(font
					(size 1.27 1.27)
				)
			)
		)
		(property "Value" ""
			(at 0 0 180)
			(layer "F.Fab")
			(effects
				(font
					(size 1.27 1.27)
				)
			)
		)
		(duplicate_pad_numbers_are_jumpers no)
		(fp_line
			(start 0.7874 0.4064)
			(end -0.7874 0.4064)
			(stroke
				(width 0.1524)
				(type default)
			)
			(layer "F.SilkS")
		)
		(fp_line
			(start 0.7874 -0.4064)
			(end 0.7874 0.4064)
			(stroke
				(width 0.1524)
				(type default)
			)
			(layer "F.SilkS")
		)
		(fp_line
			(start -0.7874 0.4064)
			(end -0.7874 -0.4064)
			(stroke
				(width 0.1524)
				(type default)
			)
			(layer "F.SilkS")
		)
		(fp_line
			(start -0.7874 -0.4064)
			(end 0.7874 -0.4064)
			(stroke
				(width 0.1524)
				(type default)
			)
			(layer "F.SilkS")
		)
		(fp_line
			(start 0.67945 0.3048)
			(end 0.120396 0.3048)
			(stroke
				(width 0.1)
				(type default)
			)
			(layer "F.Fab")
		)
		(fp_line
			(start 0.67945 -0.3048)
			(end 0.67945 0.3048)
			(stroke
				(width 0.1)
				(type default)
			)
			(layer "F.Fab")
		)
		(fp_line
			(start 0.12065 -0.2794)
			(end 0.12065 -0.3048)
			(stroke
				(width 0.1)
				(type default)
			)
			(layer "F.Fab")
		)
		(fp_line
			(start 0.12065 -0.3048)
			(end 0.67945 -0.3048)
			(stroke
				(width 0.1)
				(type default)
			)
			(layer "F.Fab")
		)
		(fp_line
			(start 0.120396 0.3048)
			(end 0.120396 0.2794)
			(stroke
				(width 0.1)
				(type default)
			)
			(layer "F.Fab")
		)
		(fp_line
			(start 0.120396 0.2794)
			(end -0.12065 0.2794)
			(stroke
				(width 0.1)
				(type default)
			)
			(layer "F.Fab")
		)
		(fp_line
			(start -0.12065 0.3048)
			(end -0.67945 0.3048)
			(stroke
				(width 0.1)
				(type default)
			)
			(layer "F.Fab")
		)
		(fp_line
			(start -0.12065 0.2794)
			(end -0.12065 0.3048)
			(stroke
				(width 0.1)
				(type default)
			)
			(layer "F.Fab")
		)
		(fp_line
			(start -0.12065 -0.2794)
			(end 0.12065 -0.2794)
			(stroke
				(width 0.1)
				(type default)
			)
			(layer "F.Fab")
		)
		(fp_line
			(start -0.12065 -0.305054)
			(end -0.12065 -0.2794)
			(stroke
				(width 0.1)
				(type default)
			)
			(layer "F.Fab")
		)
		(fp_line
			(start -0.67945 0.3048)
			(end -0.67945 -0.305054)
			(stroke
				(width 0.1)
				(type default)
			)
			(layer "F.Fab")
		)
		(fp_line
			(start -0.67945 -0.305054)
			(end -0.12065 -0.305054)
			(stroke
				(width 0.1)
				(type default)
			)
			(layer "F.Fab")
		)
		(pad "1" smd circle
			(at -0.40005 0 180)
			(size 0 0)
			(layers "F.Cu" "F.Mask" "F.Paste")
			(net "PRSNT_NIC6_N")
		)
		(pad "2" smd circle
			(at 0.40005 0 180)
			(size 0 0)
			(layers "F.Cu" "F.Mask" "F.Paste")
			(net "PRSNTB2_NIC6_N")
		)
	)
	(footprint ""
		(layer "F.Cu")
		(at 12.433046 -210.875372 -90)
		(property "Reference" "C4415"
			(at 0 0 270)
			(layer "F.SilkS")
			(hide yes)
			(effects
				(font
					(size 1.27 1.27)
				)
			)
		)
		(property "Value" ""
			(at 0 0 270)
			(layer "F.Fab")
			(effects
				(font
					(size 1.27 1.27)
				)
			)
		)
		(duplicate_pad_numbers_are_jumpers no)
		(fp_line
			(start -1.524 0.762)
			(end -1.524 -0.762)
			(stroke
				(width 0.1524)
				(type default)
			)
			(layer "F.SilkS")
		)
		(fp_line
			(start 1.524 0.762)
			(end -1.524 0.762)
			(stroke
				(width 0.1524)
				(type default)
			)
			(layer "F.SilkS")
		)
		(fp_line
			(start -1.524 -0.762)
			(end 1.524 -0.762)
			(stroke
				(width 0.1524)
				(type default)
			)
			(layer "F.SilkS")
		)
		(fp_line
			(start 1.524 -0.762)
			(end 1.524 0.762)
			(stroke
				(width 0.1524)
				(type default)
			)
			(layer "F.SilkS")
		)
		(fp_line
			(start -1.1049 0.724916)
			(end 1.1049 0.724916)
			(stroke
				(width 0.1)
				(type default)
			)
			(layer "F.Fab")
		)
		(fp_line
			(start 1.1049 0.724916)
			(end 1.1049 -0.724916)
			(stroke
				(width 0.1)
				(type default)
			)
			(layer "F.Fab")
		)
		(fp_line
			(start -1.1049 -0.724916)
			(end -1.1049 0.724916)
			(stroke
				(width 0.1)
				(type default)
			)
			(layer "F.Fab")
		)
		(fp_line
			(start 1.1049 -0.724916)
			(end -1.1049 -0.724916)
			(stroke
				(width 0.1)
				(type default)
			)
			(layer "F.Fab")
		)
		(pad "1" smd rect
			(at -0.889 0 90)
			(size 1.016 1.27)
			(layers "F.Cu" "F.Mask" "F.Paste")
			(net "P3V3_AUX")
		)
		(pad "2" smd rect
			(at 0.889 0 90)
			(size 1.016 1.27)
			(layers "F.Cu" "F.Mask" "F.Paste")
			(net "GND")
		)
	)
	(footprint ""
		(layer "F.Cu")
		(at 416.402012 -343.952322 90)
		(property "Reference" "C821"
			(at 0 0 90)
			(layer "F.SilkS")
			(hide yes)
			(effects
				(font
					(size 1.27 1.27)
				)
			)
		)
		(property "Value" ""
			(at 0 0 90)
			(layer "F.Fab")
			(effects
				(font
					(size 1.27 1.27)
				)
			)
		)
		(duplicate_pad_numbers_are_jumpers no)
		(fp_line
			(start 0.299974 -0.150114)
			(end 0.299974 0.150114)
			(stroke
				(width 0.1)
				(type default)
			)
			(layer "F.Fab")
		)
		(fp_line
			(start -0.299974 -0.150114)
			(end 0.299974 -0.150114)
			(stroke
				(width 0.1)
				(type default)
			)
			(layer "F.Fab")
		)
		(fp_line
			(start 0.299974 0.150114)
			(end -0.299974 0.150114)
			(stroke
				(width 0.1)
				(type default)
			)
			(layer "F.Fab")
		)
		(fp_line
			(start -0.299974 0.150114)
			(end -0.299974 -0.150114)
			(stroke
				(width 0.1)
				(type default)
			)
			(layer "F.Fab")
		)
		(pad "1" smd rect
			(at -0.2667 0 90)
			(size 0.3048 0.381)
			(layers "F.Cu" "F.Mask" "F.Paste")
			(net "P5E_PEX3_STN7_TX_DN<114>")
		)
		(pad "2" smd rect
			(at 0.2667 0 90)
			(size 0.3048 0.381)
			(layers "F.Cu" "F.Mask" "F.Paste")
			(net "P5E_PEX3_STN7_TX_C_DN<114>")
		)
	)
	(footprint ""
		(layer "F.Cu")
		(at 155.380436 -100.203254)
		(property "Reference" "C275"
			(at 0 0 0)
			(layer "F.SilkS")
			(hide yes)
			(effects
				(font
					(size 1.27 1.27)
				)
			)
		)
		(property "Value" ""
			(at 0 0 0)
			(layer "F.Fab")
			(effects
				(font
					(size 1.27 1.27)
				)
			)
		)
		(duplicate_pad_numbers_are_jumpers no)
		(fp_line
			(start -0.299974 -0.150114)
			(end 0.299974 -0.150114)
			(stroke
				(width 0.1)
				(type default)
			)
			(layer "F.Fab")
		)
		(fp_line
			(start -0.299974 0.150114)
			(end -0.299974 -0.150114)
			(stroke
				(width 0.1)
				(type default)
			)
			(layer "F.Fab")
		)
		(fp_line
			(start 0.299974 -0.150114)
			(end 0.299974 0.150114)
			(stroke
				(width 0.1)
				(type default)
			)
			(layer "F.Fab")
		)
		(fp_line
			(start 0.299974 0.150114)
			(end -0.299974 0.150114)
			(stroke
				(width 0.1)
				(type default)
			)
			(layer "F.Fab")
		)
		(pad "1" smd rect
			(at -0.2667 0)
			(size 0.3048 0.381)
			(layers "F.Cu" "F.Mask" "F.Paste")
			(net "P5E_PEX1_STN1_TX_DN<16>")
		)
		(pad "2" smd rect
			(at 0.2667 0)
			(size 0.3048 0.381)
			(layers "F.Cu" "F.Mask" "F.Paste")
			(net "P5E_PEX1_STN1_TX_C_DN<16>")
		)
	)
	(footprint ""
		(layer "F.Cu")
		(at 64.455802 -350.098614 90)
		(property "Reference" "C131"
			(at 0 0 90)
			(layer "F.SilkS")
			(hide yes)
			(effects
				(font
					(size 1.27 1.27)
				)
			)
		)
		(property "Value" ""
			(at 0 0 90)
			(layer "F.Fab")
			(effects
				(font
					(size 1.27 1.27)
				)
			)
		)
		(duplicate_pad_numbers_are_jumpers no)
		(fp_line
			(start 0.299974 -0.150114)
			(end 0.299974 0.150114)
			(stroke
				(width 0.1)
				(type default)
			)
			(layer "F.Fab")
		)
		(fp_line
			(start -0.299974 -0.150114)
			(end 0.299974 -0.150114)
			(stroke
				(width 0.1)
				(type default)
			)
			(layer "F.Fab")
		)
		(fp_line
			(start 0.299974 0.150114)
			(end -0.299974 0.150114)
			(stroke
				(width 0.1)
				(type default)
			)
			(layer "F.Fab")
		)
		(fp_line
			(start -0.299974 0.150114)
			(end -0.299974 -0.150114)
			(stroke
				(width 0.1)
				(type default)
			)
			(layer "F.Fab")
		)
		(pad "1" smd rect
			(at -0.2667 0 90)
			(size 0.3048 0.381)
			(layers "F.Cu" "F.Mask" "F.Paste")
			(net "P5E_PEX0_STN6_TX_DP<110>")
		)
		(pad "2" smd rect
			(at 0.2667 0 90)
			(size 0.3048 0.381)
			(layers "F.Cu" "F.Mask" "F.Paste")
			(net "P5E_PEX0_STN6_TX_C_DP<110>")
		)
	)
	(footprint ""
		(layer "F.Cu")
		(at 292.410896 -61.386974)
		(property "Reference" "R4507"
			(at 0 0 0)
			(layer "F.SilkS")
			(hide yes)
			(effects
				(font
					(size 1.27 1.27)
				)
			)
		)
		(property "Value" ""
			(at 0 0 0)
			(layer "F.Fab")
			(effects
				(font
					(size 1.27 1.27)
				)
			)
		)
		(duplicate_pad_numbers_are_jumpers no)
		(fp_line
			(start -0.7874 -0.4064)
			(end 0.7874 -0.4064)
			(stroke
				(width 0.1524)
				(type default)
			)
			(layer "F.SilkS")
		)
		(fp_line
			(start -0.7874 0.4064)
			(end -0.7874 -0.4064)
			(stroke
				(width 0.1524)
				(type default)
			)
			(layer "F.SilkS")
		)
		(fp_line
			(start 0.7874 -0.4064)
			(end 0.7874 0.4064)
			(stroke
				(width 0.1524)
				(type default)
			)
			(layer "F.SilkS")
		)
		(fp_line
			(start 0.7874 0.4064)
			(end -0.7874 0.4064)
			(stroke
				(width 0.1524)
				(type default)
			)
			(layer "F.SilkS")
		)
		(fp_line
			(start -0.67945 -0.305054)
			(end -0.12065 -0.305054)
			(stroke
				(width 0.1)
				(type default)
			)
			(layer "F.Fab")
		)
		(fp_line
			(start -0.67945 0.3048)
			(end -0.67945 -0.305054)
			(stroke
				(width 0.1)
				(type default)
			)
			(layer "F.Fab")
		)
		(fp_line
			(start -0.12065 -0.305054)
			(end -0.12065 -0.2794)
			(stroke
				(width 0.1)
				(type default)
			)
			(layer "F.Fab")
		)
		(fp_line
			(start -0.12065 -0.2794)
			(end 0.12065 -0.2794)
			(stroke
				(width 0.1)
				(type default)
			)
			(layer "F.Fab")
		)
		(fp_line
			(start -0.12065 0.2794)
			(end -0.12065 0.3048)
			(stroke
				(width 0.1)
				(type default)
			)
			(layer "F.Fab")
		)
		(fp_line
			(start -0.12065 0.3048)
			(end -0.67945 0.3048)
			(stroke
				(width 0.1)
				(type default)
			)
			(layer "F.Fab")
		)
		(fp_line
			(start 0.120396 0.2794)
			(end -0.12065 0.2794)
			(stroke
				(width 0.1)
				(type default)
			)
			(layer "F.Fab")
		)
		(fp_line
			(start 0.120396 0.3048)
			(end 0.120396 0.2794)
			(stroke
				(width 0.1)
				(type default)
			)
			(layer "F.Fab")
		)
		(fp_line
			(start 0.12065 -0.3048)
			(end 0.67945 -0.3048)
			(stroke
				(width 0.1)
				(type default)
			)
			(layer "F.Fab")
		)
		(fp_line
			(start 0.12065 -0.2794)
			(end 0.12065 -0.3048)
			(stroke
				(width 0.1)
				(type default)
			)
			(layer "F.Fab")
		)
		(fp_line
			(start 0.67945 -0.3048)
			(end 0.67945 0.3048)
			(stroke
				(width 0.1)
				(type default)
			)
			(layer "F.Fab")
		)
		(fp_line
			(start 0.67945 0.3048)
			(end 0.120396 0.3048)
			(stroke
				(width 0.1)
				(type default)
			)
			(layer "F.Fab")
		)
		(pad "1" smd circle
			(at -0.40005 0)
			(size 0 0)
			(layers "F.Cu" "F.Mask" "F.Paste")
			(net "PWRGD_P3V3_SSD10")
		)
		(pad "2" smd circle
			(at 0.40005 0)
			(size 0 0)
			(layers "F.Cu" "F.Mask" "F.Paste")
			(net "PWRGD_P3V3_SSD10_R")
		)
	)
	(footprint ""
		(layer "F.Cu")
		(at 154.707844 -155.3464 180)
		(property "Reference" "R116"
			(at 0 0 180)
			(layer "F.SilkS")
			(hide yes)
			(effects
				(font
					(size 1.27 1.27)
				)
			)
		)
		(property "Value" ""
			(at 0 0 180)
			(layer "F.Fab")
			(effects
				(font
					(size 1.27 1.27)
				)
			)
		)
		(duplicate_pad_numbers_are_jumpers no)
		(fp_line
			(start 0.7874 0.4064)
			(end -0.7874 0.4064)
			(stroke
				(width 0.1524)
				(type default)
			)
			(layer "F.SilkS")
		)
		(fp_line
			(start 0.7874 -0.4064)
			(end 0.7874 0.4064)
			(stroke
				(width 0.1524)
				(type default)
			)
			(layer "F.SilkS")
		)
		(fp_line
			(start -0.7874 0.4064)
			(end -0.7874 -0.4064)
			(stroke
				(width 0.1524)
				(type default)
			)
			(layer "F.SilkS")
		)
		(fp_line
			(start -0.7874 -0.4064)
			(end 0.7874 -0.4064)
			(stroke
				(width 0.1524)
				(type default)
			)
			(layer "F.SilkS")
		)
		(fp_line
			(start 0.67945 0.3048)
			(end 0.120396 0.3048)
			(stroke
				(width 0.1)
				(type default)
			)
			(layer "F.Fab")
		)
		(fp_line
			(start 0.67945 -0.3048)
			(end 0.67945 0.3048)
			(stroke
				(width 0.1)
				(type default)
			)
			(layer "F.Fab")
		)
		(fp_line
			(start 0.12065 -0.2794)
			(end 0.12065 -0.3048)
			(stroke
				(width 0.1)
				(type default)
			)
			(layer "F.Fab")
		)
		(fp_line
			(start 0.12065 -0.3048)
			(end 0.67945 -0.3048)
			(stroke
				(width 0.1)
				(type default)
			)
			(layer "F.Fab")
		)
		(fp_line
			(start 0.120396 0.3048)
			(end 0.120396 0.2794)
			(stroke
				(width 0.1)
				(type default)
			)
			(layer "F.Fab")
		)
		(fp_line
			(start 0.120396 0.2794)
			(end -0.12065 0.2794)
			(stroke
				(width 0.1)
				(type default)
			)
			(layer "F.Fab")
		)
		(fp_line
			(start -0.12065 0.3048)
			(end -0.67945 0.3048)
			(stroke
				(width 0.1)
				(type default)
			)
			(layer "F.Fab")
		)
		(fp_line
			(start -0.12065 0.2794)
			(end -0.12065 0.3048)
			(stroke
				(width 0.1)
				(type default)
			)
			(layer "F.Fab")
		)
		(fp_line
			(start -0.12065 -0.2794)
			(end 0.12065 -0.2794)
			(stroke
				(width 0.1)
				(type default)
			)
			(layer "F.Fab")
		)
		(fp_line
			(start -0.12065 -0.305054)
			(end -0.12065 -0.2794)
			(stroke
				(width 0.1)
				(type default)
			)
			(layer "F.Fab")
		)
		(fp_line
			(start -0.67945 0.3048)
			(end -0.67945 -0.305054)
			(stroke
				(width 0.1)
				(type default)
			)
			(layer "F.Fab")
		)
		(fp_line
			(start -0.67945 -0.305054)
			(end -0.12065 -0.305054)
			(stroke
				(width 0.1)
				(type default)
			)
			(layer "F.Fab")
		)
		(pad "1" smd circle
			(at -0.40005 0 180)
			(size 0 0)
			(layers "F.Cu" "F.Mask" "F.Paste")
			(net "NIC2_CLK")
		)
		(pad "2" smd circle
			(at 0.40005 0 180)
			(size 0 0)
			(layers "F.Cu" "F.Mask" "F.Paste")
			(net "GND")
		)
	)
	(footprint ""
		(layer "F.Cu")
		(at 96.834198 -95.263716 -90)
		(property "Reference" "R4446"
			(at 0 0 270)
			(layer "F.SilkS")
			(hide yes)
			(effects
				(font
					(size 1.27 1.27)
				)
			)
		)
		(property "Value" ""
			(at 0 0 270)
			(layer "F.Fab")
			(effects
				(font
					(size 1.27 1.27)
				)
			)
		)
		(duplicate_pad_numbers_are_jumpers no)
		(fp_line
			(start -0.7874 0.4064)
			(end -0.7874 -0.4064)
			(stroke
				(width 0.1524)
				(type default)
			)
			(layer "F.SilkS")
		)
		(fp_line
			(start 0.7874 0.4064)
			(end -0.7874 0.4064)
			(stroke
				(width 0.1524)
				(type default)
			)
			(layer "F.SilkS")
		)
		(fp_line
			(start -0.7874 -0.4064)
			(end 0.7874 -0.4064)
			(stroke
				(width 0.1524)
				(type default)
			)
			(layer "F.SilkS")
		)
		(fp_line
			(start 0.7874 -0.4064)
			(end 0.7874 0.4064)
			(stroke
				(width 0.1524)
				(type default)
			)
			(layer "F.SilkS")
		)
		(fp_line
			(start -0.67945 0.3048)
			(end -0.67945 -0.305054)
			(stroke
				(width 0.1)
				(type default)
			)
			(layer "F.Fab")
		)
		(fp_line
			(start -0.12065 0.3048)
			(end -0.67945 0.3048)
			(stroke
				(width 0.1)
				(type default)
			)
			(layer "F.Fab")
		)
		(fp_line
			(start 0.120396 0.3048)
			(end 0.120396 0.2794)
			(stroke
				(width 0.1)
				(type default)
			)
			(layer "F.Fab")
		)
		(fp_line
			(start 0.67945 0.3048)
			(end 0.120396 0.3048)
			(stroke
				(width 0.1)
				(type default)
			)
			(layer "F.Fab")
		)
		(fp_line
			(start -0.12065 0.2794)
			(end -0.12065 0.3048)
			(stroke
				(width 0.1)
				(type default)
			)
			(layer "F.Fab")
		)
		(fp_line
			(start 0.120396 0.2794)
			(end -0.12065 0.2794)
			(stroke
				(width 0.1)
				(type default)
			)
			(layer "F.Fab")
		)
		(fp_line
			(start -0.12065 -0.2794)
			(end 0.12065 -0.2794)
			(stroke
				(width 0.1)
				(type default)
			)
			(layer "F.Fab")
		)
		(fp_line
			(start 0.12065 -0.2794)
			(end 0.12065 -0.3048)
			(stroke
				(width 0.1)
				(type default)
			)
			(layer "F.Fab")
		)
		(fp_line
			(start 0.12065 -0.3048)
			(end 0.67945 -0.3048)
			(stroke
				(width 0.1)
				(type default)
			)
			(layer "F.Fab")
		)
		(fp_line
			(start 0.67945 -0.3048)
			(end 0.67945 0.3048)
			(stroke
				(width 0.1)
				(type default)
			)
			(layer "F.Fab")
		)
		(fp_line
			(start -0.67945 -0.305054)
			(end -0.12065 -0.305054)
			(stroke
				(width 0.1)
				(type default)
			)
			(layer "F.Fab")
		)
		(fp_line
			(start -0.12065 -0.305054)
			(end -0.12065 -0.2794)
			(stroke
				(width 0.1)
				(type default)
			)
			(layer "F.Fab")
		)
		(pad "1" smd circle
			(at -0.40005 0 270)
			(size 0 0)
			(layers "F.Cu" "F.Mask" "F.Paste")
			(net "PWRGD_P12V_NIC1")
		)
		(pad "2" smd circle
			(at 0.40005 0 270)
			(size 0 0)
			(layers "F.Cu" "F.Mask" "F.Paste")
			(net "PWRGD_P12V_NIC1_R")
		)
	)
	(footprint ""
		(layer "F.Cu")
		(at 469.009984 -551.319192 180)
		(property "Reference" "SCREW_SSD8_2"
			(at -5.207 -1.402334 0)
			(unlocked yes)
			(layer "B.SilkS")
			(effects
				(font
					(size 0.7874 0.5842)
					(thickness 0.1524)
				)
				(justify mirror)
			)
		)
		(property "Value" ""
			(at 0 0 180)
			(layer "F.Fab")
			(effects
				(font
					(size 1.27 1.27)
				)
			)
		)
		(duplicate_pad_numbers_are_jumpers no)
		(pad "1" thru_hole circle
			(at 0 0 180)
			(size 0.4572 0.4572)
			(drill 0.2032)
			(layers "*.Cu" "*.Mask")
			(remove_unused_layers no)
			(net "Net_9127")
			(clearance 0.127)
			(thermal_gap 0.127)
			(padstack
				(mode front_inner_back)
				(layer "Inner"
					(shape circle)
					(size 0.4572 0.4572)
					(clearance 0.127)
				)
				(layer "B.Cu"
					(shape circle)
					(size 0.508 0.508)
					(clearance 0.1016)
				)
			)
		)
	)
	(footprint ""
		(layer "F.Cu")
		(at 7.613396 -139.376404)
		(property "Reference" "R853"
			(at 0 0 0)
			(layer "F.SilkS")
			(hide yes)
			(effects
				(font
					(size 1.27 1.27)
				)
			)
		)
		(property "Value" ""
			(at 0 0 0)
			(layer "F.Fab")
			(effects
				(font
					(size 1.27 1.27)
				)
			)
		)
		(duplicate_pad_numbers_are_jumpers no)
		(fp_line
			(start -0.7874 -0.4064)
			(end 0.7874 -0.4064)
			(stroke
				(width 0.1524)
				(type default)
			)
			(layer "F.SilkS")
		)
		(fp_line
			(start -0.7874 0.4064)
			(end -0.7874 -0.4064)
			(stroke
				(width 0.1524)
				(type default)
			)
			(layer "F.SilkS")
		)
		(fp_line
			(start 0.7874 -0.4064)
			(end 0.7874 0.4064)
			(stroke
				(width 0.1524)
				(type default)
			)
			(layer "F.SilkS")
		)
		(fp_line
			(start 0.7874 0.4064)
			(end -0.7874 0.4064)
			(stroke
				(width 0.1524)
				(type default)
			)
			(layer "F.SilkS")
		)
		(fp_line
			(start -0.67945 -0.305054)
			(end -0.12065 -0.305054)
			(stroke
				(width 0.1)
				(type default)
			)
			(layer "F.Fab")
		)
		(fp_line
			(start -0.67945 0.3048)
			(end -0.67945 -0.305054)
			(stroke
				(width 0.1)
				(type default)
			)
			(layer "F.Fab")
		)
		(fp_line
			(start -0.12065 -0.305054)
			(end -0.12065 -0.2794)
			(stroke
				(width 0.1)
				(type default)
			)
			(layer "F.Fab")
		)
		(fp_line
			(start -0.12065 -0.2794)
			(end 0.12065 -0.2794)
			(stroke
				(width 0.1)
				(type default)
			)
			(layer "F.Fab")
		)
		(fp_line
			(start -0.12065 0.2794)
			(end -0.12065 0.3048)
			(stroke
				(width 0.1)
				(type default)
			)
			(layer "F.Fab")
		)
		(fp_line
			(start -0.12065 0.3048)
			(end -0.67945 0.3048)
			(stroke
				(width 0.1)
				(type default)
			)
			(layer "F.Fab")
		)
		(fp_line
			(start 0.120396 0.2794)
			(end -0.12065 0.2794)
			(stroke
				(width 0.1)
				(type default)
			)
			(layer "F.Fab")
		)
		(fp_line
			(start 0.120396 0.3048)
			(end 0.120396 0.2794)
			(stroke
				(width 0.1)
				(type default)
			)
			(layer "F.Fab")
		)
		(fp_line
			(start 0.12065 -0.3048)
			(end 0.67945 -0.3048)
			(stroke
				(width 0.1)
				(type default)
			)
			(layer "F.Fab")
		)
		(fp_line
			(start 0.12065 -0.2794)
			(end 0.12065 -0.3048)
			(stroke
				(width 0.1)
				(type default)
			)
			(layer "F.Fab")
		)
		(fp_line
			(start 0.67945 -0.3048)
			(end 0.67945 0.3048)
			(stroke
				(width 0.1)
				(type default)
			)
			(layer "F.Fab")
		)
		(fp_line
			(start 0.67945 0.3048)
			(end 0.120396 0.3048)
			(stroke
				(width 0.1)
				(type default)
			)
			(layer "F.Fab")
		)
		(pad "1" smd circle
			(at -0.40005 0)
			(size 0 0)
			(layers "F.Cu" "F.Mask" "F.Paste")
			(net "P3V3_AUX")
		)
		(pad "2" smd circle
			(at 0.40005 0)
			(size 0 0)
			(layers "F.Cu" "F.Mask" "F.Paste")
			(net "PWRGD_P12V_NIC0")
		)
	)
	(footprint ""
		(layer "F.Cu")
		(at 82.661506 -132.601208 180)
		(property "Reference" "C21"
			(at 0 0 180)
			(layer "F.SilkS")
			(hide yes)
			(effects
				(font
					(size 1.27 1.27)
				)
			)
		)
		(property "Value" ""
			(at 0 0 180)
			(layer "F.Fab")
			(effects
				(font
					(size 1.27 1.27)
				)
			)
		)
		(duplicate_pad_numbers_are_jumpers no)
		(fp_line
			(start 0.299974 0.150114)
			(end -0.299974 0.150114)
			(stroke
				(width 0.1)
				(type default)
			)
			(layer "F.Fab")
		)
		(fp_line
			(start 0.299974 -0.150114)
			(end 0.299974 0.150114)
			(stroke
				(width 0.1)
				(type default)
			)
			(layer "F.Fab")
		)
		(fp_line
			(start -0.299974 0.150114)
			(end -0.299974 -0.150114)
			(stroke
				(width 0.1)
				(type default)
			)
			(layer "F.Fab")
		)
		(fp_line
			(start -0.299974 -0.150114)
			(end 0.299974 -0.150114)
			(stroke
				(width 0.1)
				(type default)
			)
			(layer "F.Fab")
		)
		(pad "1" smd rect
			(at -0.2667 0 180)
			(size 0.3048 0.381)
			(layers "F.Cu" "F.Mask" "F.Paste")
			(net "P5E_PEX0_STN0_TX_DP<5>")
		)
		(pad "2" smd rect
			(at 0.2667 0 180)
			(size 0.3048 0.381)
			(layers "F.Cu" "F.Mask" "F.Paste")
			(net "P5E_PEX0_STN0_TX_C_DP<5>")
		)
	)
	(footprint ""
		(layer "F.Cu")
		(at 7.613396 -136.328404 180)
		(property "Reference" "PC360"
			(at 0 0 180)
			(layer "F.SilkS")
			(hide yes)
			(effects
				(font
					(size 1.27 1.27)
				)
			)
		)
		(property "Value" ""
			(at 0 0 180)
			(layer "F.Fab")
			(effects
				(font
					(size 1.27 1.27)
				)
			)
		)
		(duplicate_pad_numbers_are_jumpers no)
		(fp_line
			(start 0.7874 0.4064)
			(end -0.7874 0.4064)
			(stroke
				(width 0.1524)
				(type default)
			)
			(layer "F.SilkS")
		)
		(fp_line
			(start 0.7874 -0.4064)
			(end 0.7874 0.4064)
			(stroke
				(width 0.1524)
				(type default)
			)
			(layer "F.SilkS")
		)
		(fp_line
			(start -0.7874 0.4064)
			(end -0.7874 -0.4064)
			(stroke
				(width 0.1524)
				(type default)
			)
			(layer "F.SilkS")
		)
		(fp_line
			(start -0.7874 -0.4064)
			(end 0.7874 -0.4064)
			(stroke
				(width 0.1524)
				(type default)
			)
			(layer "F.SilkS")
		)
		(fp_line
			(start 0.67945 0.3048)
			(end 0.120396 0.3048)
			(stroke
				(width 0.1)
				(type default)
			)
			(layer "F.Fab")
		)
		(fp_line
			(start 0.67945 -0.3048)
			(end 0.67945 0.3048)
			(stroke
				(width 0.1)
				(type default)
			)
			(layer "F.Fab")
		)
		(fp_line
			(start 0.12065 -0.2794)
			(end 0.12065 -0.3048)
			(stroke
				(width 0.1)
				(type default)
			)
			(layer "F.Fab")
		)
		(fp_line
			(start 0.12065 -0.3048)
			(end 0.67945 -0.3048)
			(stroke
				(width 0.1)
				(type default)
			)
			(layer "F.Fab")
		)
		(fp_line
			(start 0.120396 0.3048)
			(end 0.120396 0.2794)
			(stroke
				(width 0.1)
				(type default)
			)
			(layer "F.Fab")
		)
		(fp_line
			(start 0.120396 0.2794)
			(end -0.12065 0.2794)
			(stroke
				(width 0.1)
				(type default)
			)
			(layer "F.Fab")
		)
		(fp_line
			(start -0.12065 0.3048)
			(end -0.67945 0.3048)
			(stroke
				(width 0.1)
				(type default)
			)
			(layer "F.Fab")
		)
		(fp_line
			(start -0.12065 0.2794)
			(end -0.12065 0.3048)
			(stroke
				(width 0.1)
				(type default)
			)
			(layer "F.Fab")
		)
		(fp_line
			(start -0.12065 -0.2794)
			(end 0.12065 -0.2794)
			(stroke
				(width 0.1)
				(type default)
			)
			(layer "F.Fab")
		)
		(fp_line
			(start -0.12065 -0.305054)
			(end -0.12065 -0.2794)
			(stroke
				(width 0.1)
				(type default)
			)
			(layer "F.Fab")
		)
		(fp_line
			(start -0.67945 0.3048)
			(end -0.67945 -0.305054)
			(stroke
				(width 0.1)
				(type default)
			)
			(layer "F.Fab")
		)
		(fp_line
			(start -0.67945 -0.305054)
			(end -0.12065 -0.305054)
			(stroke
				(width 0.1)
				(type default)
			)
			(layer "F.Fab")
		)
		(pad "1" smd circle
			(at -0.40005 0 180)
			(size 0 0)
			(layers "F.Cu" "F.Mask" "F.Paste")
			(net "P5V_AUX")
		)
		(pad "2" smd circle
			(at 0.40005 0 180)
			(size 0 0)
			(layers "F.Cu" "F.Mask" "F.Paste")
			(net "GND")
		)
	)
	(footprint ""
		(layer "F.Cu")
		(at 71.246746 -37.47516)
		(property "Reference" "R5887"
			(at 0 0 0)
			(layer "F.SilkS")
			(hide yes)
			(effects
				(font
					(size 1.27 1.27)
				)
			)
		)
		(property "Value" ""
			(at 0 0 0)
			(layer "F.Fab")
			(effects
				(font
					(size 1.27 1.27)
				)
			)
		)
		(duplicate_pad_numbers_are_jumpers no)
		(fp_line
			(start -0.7874 -0.4064)
			(end 0.7874 -0.4064)
			(stroke
				(width 0.1524)
				(type default)
			)
			(layer "F.SilkS")
		)
		(fp_line
			(start -0.7874 0.4064)
			(end -0.7874 -0.4064)
			(stroke
				(width 0.1524)
				(type default)
			)
			(layer "F.SilkS")
		)
		(fp_line
			(start 0.7874 -0.4064)
			(end 0.7874 0.4064)
			(stroke
				(width 0.1524)
				(type default)
			)
			(layer "F.SilkS")
		)
		(fp_line
			(start 0.7874 0.4064)
			(end -0.7874 0.4064)
			(stroke
				(width 0.1524)
				(type default)
			)
			(layer "F.SilkS")
		)
		(fp_line
			(start -0.67945 -0.305054)
			(end -0.12065 -0.305054)
			(stroke
				(width 0.1)
				(type default)
			)
			(layer "F.Fab")
		)
		(fp_line
			(start -0.67945 0.3048)
			(end -0.67945 -0.305054)
			(stroke
				(width 0.1)
				(type default)
			)
			(layer "F.Fab")
		)
		(fp_line
			(start -0.12065 -0.305054)
			(end -0.12065 -0.2794)
			(stroke
				(width 0.1)
				(type default)
			)
			(layer "F.Fab")
		)
		(fp_line
			(start -0.12065 -0.2794)
			(end 0.12065 -0.2794)
			(stroke
				(width 0.1)
				(type default)
			)
			(layer "F.Fab")
		)
		(fp_line
			(start -0.12065 0.2794)
			(end -0.12065 0.3048)
			(stroke
				(width 0.1)
				(type default)
			)
			(layer "F.Fab")
		)
		(fp_line
			(start -0.12065 0.3048)
			(end -0.67945 0.3048)
			(stroke
				(width 0.1)
				(type default)
			)
			(layer "F.Fab")
		)
		(fp_line
			(start 0.120396 0.2794)
			(end -0.12065 0.2794)
			(stroke
				(width 0.1)
				(type default)
			)
			(layer "F.Fab")
		)
		(fp_line
			(start 0.120396 0.3048)
			(end 0.120396 0.2794)
			(stroke
				(width 0.1)
				(type default)
			)
			(layer "F.Fab")
		)
		(fp_line
			(start 0.12065 -0.3048)
			(end 0.67945 -0.3048)
			(stroke
				(width 0.1)
				(type default)
			)
			(layer "F.Fab")
		)
		(fp_line
			(start 0.12065 -0.2794)
			(end 0.12065 -0.3048)
			(stroke
				(width 0.1)
				(type default)
			)
			(layer "F.Fab")
		)
		(fp_line
			(start 0.67945 -0.3048)
			(end 0.67945 0.3048)
			(stroke
				(width 0.1)
				(type default)
			)
			(layer "F.Fab")
		)
		(fp_line
			(start 0.67945 0.3048)
			(end 0.120396 0.3048)
			(stroke
				(width 0.1)
				(type default)
			)
			(layer "F.Fab")
		)
		(pad "1" smd circle
			(at -0.40005 0)
			(size 0 0)
			(layers "F.Cu" "F.Mask" "F.Paste")
			(net "P3V3_SSD3")
		)
		(pad "2" smd circle
			(at 0.40005 0)
			(size 0 0)
			(layers "F.Cu" "F.Mask" "F.Paste")
			(net "P3V3_SSD3_PG_G1")
		)
	)
	(footprint ""
		(layer "F.Cu")
		(at 367.525808 -159.082994 -90)
		(property "Reference" "PD5"
			(at 4.244594 -2.756662 90)
			(unlocked yes)
			(layer "F.SilkS")
			(effects
				(font
					(size 0.7874 0.5842)
					(thickness 0.1524)
				)
				(justify left)
			)
		)
		(property "Value" ""
			(at 0 0 270)
			(layer "F.Fab")
			(effects
				(font
					(size 1.27 1.27)
				)
			)
		)
		(duplicate_pad_numbers_are_jumpers no)
		(fp_line
			(start -3.656584 1.970024)
			(end 4.240784 1.970024)
			(stroke
				(width 0.1524)
				(type default)
			)
			(layer "F.SilkS")
		)
		(fp_line
			(start 4.240784 1.970024)
			(end 4.240784 -1.970024)
			(stroke
				(width 0.1524)
				(type default)
			)
			(layer "F.SilkS")
		)
		(fp_line
			(start -3.656584 -1.970024)
			(end -3.656584 1.970024)
			(stroke
				(width 0.1524)
				(type default)
			)
			(layer "F.SilkS")
		)
		(fp_line
			(start 4.240784 -1.970024)
			(end -3.656584 -1.970024)
			(stroke
				(width 0.1524)
				(type default)
			)
			(layer "F.SilkS")
		)
		(fp_poly
			(pts
				(xy 3.580384 1.970024) (xy 3.580384 -1.970024) (xy 4.240784 -1.970024) (xy 4.240784 1.970024)
			)
			(stroke
				(width 0)
				(type default)
			)
			(fill yes)
			(layer "F.SilkS")
		)
		(fp_line
			(start -2.3749 1.970024)
			(end 2.3749 1.970024)
			(stroke
				(width 0.1)
				(type default)
			)
			(layer "F.Fab")
		)
		(fp_line
			(start 2.3749 1.970024)
			(end 2.3749 -1.970024)
			(stroke
				(width 0.1)
				(type default)
			)
			(layer "F.Fab")
		)
		(fp_line
			(start -2.3749 -1.970024)
			(end -2.3749 1.970024)
			(stroke
				(width 0.1)
				(type default)
			)
			(layer "F.Fab")
		)
		(fp_line
			(start 2.3749 -1.970024)
			(end -2.3749 -1.970024)
			(stroke
				(width 0.1)
				(type default)
			)
			(layer "F.Fab")
		)
		(fp_text user "+"
			(at -4.9784 -0.23495 270)
			(unlocked yes)
			(layer "F.Fab")
			(effects
				(font
					(size 1.905 1.4224)
					(thickness 0.1524)
				)
				(justify left)
			)
		)
		(fp_text user "-"
			(at 4.1656 -0.23495 270)
			(unlocked yes)
			(layer "F.Fab")
			(effects
				(font
					(size 1.905 1.4224)
					(thickness 0.1524)
				)
				(justify left)
			)
		)
		(pad "A" smd rect
			(at -2.450084 0 270)
			(size 2.159 2.2606)
			(layers "F.Cu" "F.Mask" "F.Paste")
			(net "GND")
		)
		(pad "C" smd rect
			(at 2.450084 0 270)
			(size 2.159 2.2606)
			(layers "F.Cu" "F.Mask" "F.Paste")
			(net "P12V_AUX")
		)
	)
	(footprint ""
		(layer "F.Cu")
		(at 170.554904 -22.961346 90)
		(property "Reference" "R1662"
			(at 0 0 90)
			(layer "F.SilkS")
			(hide yes)
			(effects
				(font
					(size 1.27 1.27)
				)
			)
		)
		(property "Value" ""
			(at 0 0 90)
			(layer "F.Fab")
			(effects
				(font
					(size 1.27 1.27)
				)
			)
		)
		(duplicate_pad_numbers_are_jumpers no)
		(fp_line
			(start 0.7874 -0.4064)
			(end 0.7874 0.4064)
			(stroke
				(width 0.1524)
				(type default)
			)
			(layer "F.SilkS")
		)
		(fp_line
			(start -0.7874 -0.4064)
			(end 0.7874 -0.4064)
			(stroke
				(width 0.1524)
				(type default)
			)
			(layer "F.SilkS")
		)
		(fp_line
			(start 0.7874 0.4064)
			(end -0.7874 0.4064)
			(stroke
				(width 0.1524)
				(type default)
			)
			(layer "F.SilkS")
		)
		(fp_line
			(start -0.7874 0.4064)
			(end -0.7874 -0.4064)
			(stroke
				(width 0.1524)
				(type default)
			)
			(layer "F.SilkS")
		)
		(fp_line
			(start -0.12065 -0.305054)
			(end -0.12065 -0.2794)
			(stroke
				(width 0.1)
				(type default)
			)
			(layer "F.Fab")
		)
		(fp_line
			(start -0.67945 -0.305054)
			(end -0.12065 -0.305054)
			(stroke
				(width 0.1)
				(type default)
			)
			(layer "F.Fab")
		)
		(fp_line
			(start 0.67945 -0.3048)
			(end 0.67945 0.3048)
			(stroke
				(width 0.1)
				(type default)
			)
			(layer "F.Fab")
		)
		(fp_line
			(start 0.12065 -0.3048)
			(end 0.67945 -0.3048)
			(stroke
				(width 0.1)
				(type default)
			)
			(layer "F.Fab")
		)
		(fp_line
			(start 0.12065 -0.2794)
			(end 0.12065 -0.3048)
			(stroke
				(width 0.1)
				(type default)
			)
			(layer "F.Fab")
		)
		(fp_line
			(start -0.12065 -0.2794)
			(end 0.12065 -0.2794)
			(stroke
				(width 0.1)
				(type default)
			)
			(layer "F.Fab")
		)
		(fp_line
			(start 0.120396 0.2794)
			(end -0.12065 0.2794)
			(stroke
				(width 0.1)
				(type default)
			)
			(layer "F.Fab")
		)
		(fp_line
			(start -0.12065 0.2794)
			(end -0.12065 0.3048)
			(stroke
				(width 0.1)
				(type default)
			)
			(layer "F.Fab")
		)
		(fp_line
			(start 0.67945 0.3048)
			(end 0.120396 0.3048)
			(stroke
				(width 0.1)
				(type default)
			)
			(layer "F.Fab")
		)
		(fp_line
			(start 0.120396 0.3048)
			(end 0.120396 0.2794)
			(stroke
				(width 0.1)
				(type default)
			)
			(layer "F.Fab")
		)
		(fp_line
			(start -0.12065 0.3048)
			(end -0.67945 0.3048)
			(stroke
				(width 0.1)
				(type default)
			)
			(layer "F.Fab")
		)
		(fp_line
			(start -0.67945 0.3048)
			(end -0.67945 -0.305054)
			(stroke
				(width 0.1)
				(type default)
			)
			(layer "F.Fab")
		)
		(pad "1" smd circle
			(at -0.40005 0 90)
			(size 0 0)
			(layers "F.Cu" "F.Mask" "F.Paste")
			(net "SMB_SSD5_ISO_EN")
		)
		(pad "2" smd circle
			(at 0.40005 0 90)
			(size 0 0)
			(layers "F.Cu" "F.Mask" "F.Paste")
			(net "P3V3_AUX")
		)
	)
	(footprint ""
		(layer "F.Cu")
		(at 99.530408 -66.32194 -90)
		(property "Reference" "PC657"
			(at 0 0 270)
			(layer "F.SilkS")
			(hide yes)
			(effects
				(font
					(size 1.27 1.27)
				)
			)
		)
		(property "Value" ""
			(at 0 0 270)
			(layer "F.Fab")
			(effects
				(font
					(size 1.27 1.27)
				)
			)
		)
		(duplicate_pad_numbers_are_jumpers no)
		(fp_line
			(start -0.7874 0.4064)
			(end -0.7874 -0.4064)
			(stroke
				(width 0.1524)
				(type default)
			)
			(layer "F.SilkS")
		)
		(fp_line
			(start 0.7874 0.4064)
			(end -0.7874 0.4064)
			(stroke
				(width 0.1524)
				(type default)
			)
			(layer "F.SilkS")
		)
		(fp_line
			(start -0.7874 -0.4064)
			(end 0.7874 -0.4064)
			(stroke
				(width 0.1524)
				(type default)
			)
			(layer "F.SilkS")
		)
		(fp_line
			(start 0.7874 -0.4064)
			(end 0.7874 0.4064)
			(stroke
				(width 0.1524)
				(type default)
			)
			(layer "F.SilkS")
		)
		(fp_line
			(start -0.67945 0.3048)
			(end -0.67945 -0.305054)
			(stroke
				(width 0.1)
				(type default)
			)
			(layer "F.Fab")
		)
		(fp_line
			(start -0.12065 0.3048)
			(end -0.67945 0.3048)
			(stroke
				(width 0.1)
				(type default)
			)
			(layer "F.Fab")
		)
		(fp_line
			(start 0.120396 0.3048)
			(end 0.120396 0.2794)
			(stroke
				(width 0.1)
				(type default)
			)
			(layer "F.Fab")
		)
		(fp_line
			(start 0.67945 0.3048)
			(end 0.120396 0.3048)
			(stroke
				(width 0.1)
				(type default)
			)
			(layer "F.Fab")
		)
		(fp_line
			(start -0.12065 0.2794)
			(end -0.12065 0.3048)
			(stroke
				(width 0.1)
				(type default)
			)
			(layer "F.Fab")
		)
		(fp_line
			(start 0.120396 0.2794)
			(end -0.12065 0.2794)
			(stroke
				(width 0.1)
				(type default)
			)
			(layer "F.Fab")
		)
		(fp_line
			(start -0.12065 -0.2794)
			(end 0.12065 -0.2794)
			(stroke
				(width 0.1)
				(type default)
			)
			(layer "F.Fab")
		)
		(fp_line
			(start 0.12065 -0.2794)
			(end 0.12065 -0.3048)
			(stroke
				(width 0.1)
				(type default)
			)
			(layer "F.Fab")
		)
		(fp_line
			(start 0.12065 -0.3048)
			(end 0.67945 -0.3048)
			(stroke
				(width 0.1)
				(type default)
			)
			(layer "F.Fab")
		)
		(fp_line
			(start 0.67945 -0.3048)
			(end 0.67945 0.3048)
			(stroke
				(width 0.1)
				(type default)
			)
			(layer "F.Fab")
		)
		(fp_line
			(start -0.67945 -0.305054)
			(end -0.12065 -0.305054)
			(stroke
				(width 0.1)
				(type default)
			)
			(layer "F.Fab")
		)
		(fp_line
			(start -0.12065 -0.305054)
			(end -0.12065 -0.2794)
			(stroke
				(width 0.1)
				(type default)
			)
			(layer "F.Fab")
		)
		(pad "1" smd circle
			(at -0.40005 0 270)
			(size 0 0)
			(layers "F.Cu" "F.Mask" "F.Paste")
			(net "P12V_SSD3_CO_DV_DT")
		)
		(pad "2" smd circle
			(at 0.40005 0 270)
			(size 0 0)
			(layers "F.Cu" "F.Mask" "F.Paste")
			(net "GND")
		)
	)
	(footprint ""
		(layer "F.Cu")
		(at 373.761 -181.483 90)
		(property "Reference" "C3599"
			(at 0 0 90)
			(layer "F.SilkS")
			(hide yes)
			(effects
				(font
					(size 1.27 1.27)
				)
			)
		)
		(property "Value" ""
			(at 0 0 90)
			(layer "F.Fab")
			(effects
				(font
					(size 1.27 1.27)
				)
			)
		)
		(duplicate_pad_numbers_are_jumpers no)
		(fp_line
			(start 0.7874 -0.4064)
			(end 0.7874 0.4064)
			(stroke
				(width 0.1524)
				(type default)
			)
			(layer "F.SilkS")
		)
		(fp_line
			(start -0.7874 -0.4064)
			(end 0.7874 -0.4064)
			(stroke
				(width 0.1524)
				(type default)
			)
			(layer "F.SilkS")
		)
		(fp_line
			(start 0.7874 0.4064)
			(end -0.7874 0.4064)
			(stroke
				(width 0.1524)
				(type default)
			)
			(layer "F.SilkS")
		)
		(fp_line
			(start -0.7874 0.4064)
			(end -0.7874 -0.4064)
			(stroke
				(width 0.1524)
				(type default)
			)
			(layer "F.SilkS")
		)
		(fp_line
			(start -0.12065 -0.305054)
			(end -0.12065 -0.2794)
			(stroke
				(width 0.1)
				(type default)
			)
			(layer "F.Fab")
		)
		(fp_line
			(start -0.67945 -0.305054)
			(end -0.12065 -0.305054)
			(stroke
				(width 0.1)
				(type default)
			)
			(layer "F.Fab")
		)
		(fp_line
			(start 0.67945 -0.3048)
			(end 0.67945 0.3048)
			(stroke
				(width 0.1)
				(type default)
			)
			(layer "F.Fab")
		)
		(fp_line
			(start 0.12065 -0.3048)
			(end 0.67945 -0.3048)
			(stroke
				(width 0.1)
				(type default)
			)
			(layer "F.Fab")
		)
		(fp_line
			(start 0.12065 -0.2794)
			(end 0.12065 -0.3048)
			(stroke
				(width 0.1)
				(type default)
			)
			(layer "F.Fab")
		)
		(fp_line
			(start -0.12065 -0.2794)
			(end 0.12065 -0.2794)
			(stroke
				(width 0.1)
				(type default)
			)
			(layer "F.Fab")
		)
		(fp_line
			(start 0.120396 0.2794)
			(end -0.12065 0.2794)
			(stroke
				(width 0.1)
				(type default)
			)
			(layer "F.Fab")
		)
		(fp_line
			(start -0.12065 0.2794)
			(end -0.12065 0.3048)
			(stroke
				(width 0.1)
				(type default)
			)
			(layer "F.Fab")
		)
		(fp_line
			(start 0.67945 0.3048)
			(end 0.120396 0.3048)
			(stroke
				(width 0.1)
				(type default)
			)
			(layer "F.Fab")
		)
		(fp_line
			(start 0.120396 0.3048)
			(end 0.120396 0.2794)
			(stroke
				(width 0.1)
				(type default)
			)
			(layer "F.Fab")
		)
		(fp_line
			(start -0.12065 0.3048)
			(end -0.67945 0.3048)
			(stroke
				(width 0.1)
				(type default)
			)
			(layer "F.Fab")
		)
		(fp_line
			(start -0.67945 0.3048)
			(end -0.67945 -0.305054)
			(stroke
				(width 0.1)
				(type default)
			)
			(layer "F.Fab")
		)
		(pad "1" smd circle
			(at -0.40005 0 90)
			(size 0 0)
			(layers "F.Cu" "F.Mask" "F.Paste")
			(net "P3V3_AUX")
		)
		(pad "2" smd circle
			(at 0.40005 0 90)
			(size 0 0)
			(layers "F.Cu" "F.Mask" "F.Paste")
			(net "GND")
		)
	)
	(footprint ""
		(layer "F.Cu")
		(at 56.715152 -59.546236 90)
		(property "Reference" "C2889"
			(at 0 0 90)
			(layer "F.SilkS")
			(hide yes)
			(effects
				(font
					(size 1.27 1.27)
				)
			)
		)
		(property "Value" ""
			(at 0 0 90)
			(layer "F.Fab")
			(effects
				(font
					(size 1.27 1.27)
				)
			)
		)
		(duplicate_pad_numbers_are_jumpers no)
		(fp_line
			(start 0.7874 -0.4064)
			(end 0.7874 0.4064)
			(stroke
				(width 0.1524)
				(type default)
			)
			(layer "F.SilkS")
		)
		(fp_line
			(start -0.7874 -0.4064)
			(end 0.7874 -0.4064)
			(stroke
				(width 0.1524)
				(type default)
			)
			(layer "F.SilkS")
		)
		(fp_line
			(start 0.7874 0.4064)
			(end -0.7874 0.4064)
			(stroke
				(width 0.1524)
				(type default)
			)
			(layer "F.SilkS")
		)
		(fp_line
			(start -0.7874 0.4064)
			(end -0.7874 -0.4064)
			(stroke
				(width 0.1524)
				(type default)
			)
			(layer "F.SilkS")
		)
		(fp_line
			(start -0.12065 -0.305054)
			(end -0.12065 -0.2794)
			(stroke
				(width 0.1)
				(type default)
			)
			(layer "F.Fab")
		)
		(fp_line
			(start -0.67945 -0.305054)
			(end -0.12065 -0.305054)
			(stroke
				(width 0.1)
				(type default)
			)
			(layer "F.Fab")
		)
		(fp_line
			(start 0.67945 -0.3048)
			(end 0.67945 0.3048)
			(stroke
				(width 0.1)
				(type default)
			)
			(layer "F.Fab")
		)
		(fp_line
			(start 0.12065 -0.3048)
			(end 0.67945 -0.3048)
			(stroke
				(width 0.1)
				(type default)
			)
			(layer "F.Fab")
		)
		(fp_line
			(start 0.12065 -0.2794)
			(end 0.12065 -0.3048)
			(stroke
				(width 0.1)
				(type default)
			)
			(layer "F.Fab")
		)
		(fp_line
			(start -0.12065 -0.2794)
			(end 0.12065 -0.2794)
			(stroke
				(width 0.1)
				(type default)
			)
			(layer "F.Fab")
		)
		(fp_line
			(start 0.120396 0.2794)
			(end -0.12065 0.2794)
			(stroke
				(width 0.1)
				(type default)
			)
			(layer "F.Fab")
		)
		(fp_line
			(start -0.12065 0.2794)
			(end -0.12065 0.3048)
			(stroke
				(width 0.1)
				(type default)
			)
			(layer "F.Fab")
		)
		(fp_line
			(start 0.67945 0.3048)
			(end 0.120396 0.3048)
			(stroke
				(width 0.1)
				(type default)
			)
			(layer "F.Fab")
		)
		(fp_line
			(start 0.120396 0.3048)
			(end 0.120396 0.2794)
			(stroke
				(width 0.1)
				(type default)
			)
			(layer "F.Fab")
		)
		(fp_line
			(start -0.12065 0.3048)
			(end -0.67945 0.3048)
			(stroke
				(width 0.1)
				(type default)
			)
			(layer "F.Fab")
		)
		(fp_line
			(start -0.67945 0.3048)
			(end -0.67945 -0.305054)
			(stroke
				(width 0.1)
				(type default)
			)
			(layer "F.Fab")
		)
		(pad "1" smd circle
			(at -0.40005 0 90)
			(size 0 0)
			(layers "F.Cu" "F.Mask" "F.Paste")
			(net "SSD2_AUX_P3V3_EN_R")
		)
		(pad "2" smd circle
			(at 0.40005 0 90)
			(size 0 0)
			(layers "F.Cu" "F.Mask" "F.Paste")
			(net "GND")
		)
	)
	(footprint ""
		(layer "F.Cu")
		(at 239.721898 -84.351368 90)
		(property "Reference" "R6623"
			(at 0 0 90)
			(layer "F.SilkS")
			(hide yes)
			(effects
				(font
					(size 1.27 1.27)
				)
			)
		)
		(property "Value" ""
			(at 0 0 90)
			(layer "F.Fab")
			(effects
				(font
					(size 1.27 1.27)
				)
			)
		)
		(duplicate_pad_numbers_are_jumpers no)
		(fp_line
			(start 0.7874 -0.4064)
			(end 0.7874 0.4064)
			(stroke
				(width 0.1524)
				(type default)
			)
			(layer "F.SilkS")
		)
		(fp_line
			(start -0.7874 -0.4064)
			(end -0.00254 -0.4064)
			(stroke
				(width 0.1524)
				(type default)
			)
			(layer "F.SilkS")
		)
		(fp_line
			(start 0.7874 0.4064)
			(end -0.7874 0.4064)
			(stroke
				(width 0.1524)
				(type default)
			)
			(layer "F.SilkS")
		)
		(fp_line
			(start -0.12065 -0.305054)
			(end -0.12065 -0.2794)
			(stroke
				(width 0.1)
				(type default)
			)
			(layer "F.Fab")
		)
		(fp_line
			(start -0.67945 -0.305054)
			(end -0.12065 -0.305054)
			(stroke
				(width 0.1)
				(type default)
			)
			(layer "F.Fab")
		)
		(fp_line
			(start 0.67945 -0.3048)
			(end 0.67945 0.3048)
			(stroke
				(width 0.1)
				(type default)
			)
			(layer "F.Fab")
		)
		(fp_line
			(start 0.12065 -0.3048)
			(end 0.67945 -0.3048)
			(stroke
				(width 0.1)
				(type default)
			)
			(layer "F.Fab")
		)
		(fp_line
			(start 0.12065 -0.2794)
			(end 0.12065 -0.3048)
			(stroke
				(width 0.1)
				(type default)
			)
			(layer "F.Fab")
		)
		(fp_line
			(start -0.12065 -0.2794)
			(end 0.12065 -0.2794)
			(stroke
				(width 0.1)
				(type default)
			)
			(layer "F.Fab")
		)
		(fp_line
			(start 0.120396 0.2794)
			(end -0.12065 0.2794)
			(stroke
				(width 0.1)
				(type default)
			)
			(layer "F.Fab")
		)
		(fp_line
			(start -0.12065 0.2794)
			(end -0.12065 0.3048)
			(stroke
				(width 0.1)
				(type default)
			)
			(layer "F.Fab")
		)
		(fp_line
			(start 0.67945 0.3048)
			(end 0.120396 0.3048)
			(stroke
				(width 0.1)
				(type default)
			)
			(layer "F.Fab")
		)
		(fp_line
			(start 0.120396 0.3048)
			(end 0.120396 0.2794)
			(stroke
				(width 0.1)
				(type default)
			)
			(layer "F.Fab")
		)
		(fp_line
			(start -0.12065 0.3048)
			(end -0.67945 0.3048)
			(stroke
				(width 0.1)
				(type default)
			)
			(layer "F.Fab")
		)
		(fp_line
			(start -0.67945 0.3048)
			(end -0.67945 -0.305054)
			(stroke
				(width 0.1)
				(type default)
			)
			(layer "F.Fab")
		)
		(pad "1" smd rect
			(at -0.40005 0 270)
			(size 0.4572 0.508)
			(layers "F.Cu" "F.Mask" "F.Paste")
			(net "USB2_CP2108_CLI_DP")
		)
		(pad "2" smd rect
			(at 0.40005 0 270)
			(size 0.4572 0.508)
			(layers "F.Cu" "F.Mask" "F.Paste")
			(net "USB2_FT4232_CLI_R_DP")
		)
	)
	(footprint ""
		(layer "F.Cu")
		(at 235.623608 -151.975566 180)
		(property "Reference" "R1209"
			(at 0 0 180)
			(layer "F.SilkS")
			(hide yes)
			(effects
				(font
					(size 1.27 1.27)
				)
			)
		)
		(property "Value" ""
			(at 0 0 180)
			(layer "F.Fab")
			(effects
				(font
					(size 1.27 1.27)
				)
			)
		)
		(duplicate_pad_numbers_are_jumpers no)
		(fp_line
			(start 0.7874 0.4064)
			(end -0.7874 0.4064)
			(stroke
				(width 0.1524)
				(type default)
			)
			(layer "F.SilkS")
		)
		(fp_line
			(start 0.67945 0.3048)
			(end 0.120396 0.3048)
			(stroke
				(width 0.1)
				(type default)
			)
			(layer "F.Fab")
		)
		(fp_line
			(start 0.67945 -0.3048)
			(end 0.67945 0.3048)
			(stroke
				(width 0.1)
				(type default)
			)
			(layer "F.Fab")
		)
		(fp_line
			(start 0.12065 -0.2794)
			(end 0.12065 -0.3048)
			(stroke
				(width 0.1)
				(type default)
			)
			(layer "F.Fab")
		)
		(fp_line
			(start 0.12065 -0.3048)
			(end 0.67945 -0.3048)
			(stroke
				(width 0.1)
				(type default)
			)
			(layer "F.Fab")
		)
		(fp_line
			(start 0.120396 0.3048)
			(end 0.120396 0.2794)
			(stroke
				(width 0.1)
				(type default)
			)
			(layer "F.Fab")
		)
		(fp_line
			(start 0.120396 0.2794)
			(end -0.12065 0.2794)
			(stroke
				(width 0.1)
				(type default)
			)
			(layer "F.Fab")
		)
		(fp_line
			(start -0.12065 0.3048)
			(end -0.67945 0.3048)
			(stroke
				(width 0.1)
				(type default)
			)
			(layer "F.Fab")
		)
		(fp_line
			(start -0.12065 0.2794)
			(end -0.12065 0.3048)
			(stroke
				(width 0.1)
				(type default)
			)
			(layer "F.Fab")
		)
		(fp_line
			(start -0.12065 -0.2794)
			(end 0.12065 -0.2794)
			(stroke
				(width 0.1)
				(type default)
			)
			(layer "F.Fab")
		)
		(fp_line
			(start -0.12065 -0.305054)
			(end -0.12065 -0.2794)
			(stroke
				(width 0.1)
				(type default)
			)
			(layer "F.Fab")
		)
		(fp_line
			(start -0.67945 0.3048)
			(end -0.67945 -0.305054)
			(stroke
				(width 0.1)
				(type default)
			)
			(layer "F.Fab")
		)
		(fp_line
			(start -0.67945 -0.305054)
			(end -0.12065 -0.305054)
			(stroke
				(width 0.1)
				(type default)
			)
			(layer "F.Fab")
		)
		(pad "1" smd circle
			(at -0.40005 0 180)
			(size 0 0)
			(layers "F.Cu" "F.Mask" "F.Paste")
			(net "CLK_100M_PEX2_REF_R_DP")
		)
		(pad "2" smd circle
			(at 0.40005 0 180)
			(size 0 0)
			(layers "F.Cu" "F.Mask" "F.Paste")
			(net "CLK_100M_PEX2_REF_DP")
		)
	)
	(footprint ""
		(layer "F.Cu")
		(at 20.25523 -35.876738)
		(property "Reference" "R5869"
			(at 0 0 0)
			(layer "F.SilkS")
			(hide yes)
			(effects
				(font
					(size 1.27 1.27)
				)
			)
		)
		(property "Value" ""
			(at 0 0 0)
			(layer "F.Fab")
			(effects
				(font
					(size 1.27 1.27)
				)
			)
		)
		(duplicate_pad_numbers_are_jumpers no)
		(fp_line
			(start -0.7874 -0.4064)
			(end 0.7874 -0.4064)
			(stroke
				(width 0.1524)
				(type default)
			)
			(layer "F.SilkS")
		)
		(fp_line
			(start -0.7874 0.4064)
			(end -0.7874 -0.4064)
			(stroke
				(width 0.1524)
				(type default)
			)
			(layer "F.SilkS")
		)
		(fp_line
			(start 0.7874 -0.4064)
			(end 0.7874 0.4064)
			(stroke
				(width 0.1524)
				(type default)
			)
			(layer "F.SilkS")
		)
		(fp_line
			(start 0.7874 0.4064)
			(end -0.7874 0.4064)
			(stroke
				(width 0.1524)
				(type default)
			)
			(layer "F.SilkS")
		)
		(fp_line
			(start -0.67945 -0.305054)
			(end -0.12065 -0.305054)
			(stroke
				(width 0.1)
				(type default)
			)
			(layer "F.Fab")
		)
		(fp_line
			(start -0.67945 0.3048)
			(end -0.67945 -0.305054)
			(stroke
				(width 0.1)
				(type default)
			)
			(layer "F.Fab")
		)
		(fp_line
			(start -0.12065 -0.305054)
			(end -0.12065 -0.2794)
			(stroke
				(width 0.1)
				(type default)
			)
			(layer "F.Fab")
		)
		(fp_line
			(start -0.12065 -0.2794)
			(end 0.12065 -0.2794)
			(stroke
				(width 0.1)
				(type default)
			)
			(layer "F.Fab")
		)
		(fp_line
			(start -0.12065 0.2794)
			(end -0.12065 0.3048)
			(stroke
				(width 0.1)
				(type default)
			)
			(layer "F.Fab")
		)
		(fp_line
			(start -0.12065 0.3048)
			(end -0.67945 0.3048)
			(stroke
				(width 0.1)
				(type default)
			)
			(layer "F.Fab")
		)
		(fp_line
			(start 0.120396 0.2794)
			(end -0.12065 0.2794)
			(stroke
				(width 0.1)
				(type default)
			)
			(layer "F.Fab")
		)
		(fp_line
			(start 0.120396 0.3048)
			(end 0.120396 0.2794)
			(stroke
				(width 0.1)
				(type default)
			)
			(layer "F.Fab")
		)
		(fp_line
			(start 0.12065 -0.3048)
			(end 0.67945 -0.3048)
			(stroke
				(width 0.1)
				(type default)
			)
			(layer "F.Fab")
		)
		(fp_line
			(start 0.12065 -0.2794)
			(end 0.12065 -0.3048)
			(stroke
				(width 0.1)
				(type default)
			)
			(layer "F.Fab")
		)
		(fp_line
			(start 0.67945 -0.3048)
			(end 0.67945 0.3048)
			(stroke
				(width 0.1)
				(type default)
			)
			(layer "F.Fab")
		)
		(fp_line
			(start 0.67945 0.3048)
			(end 0.120396 0.3048)
			(stroke
				(width 0.1)
				(type default)
			)
			(layer "F.Fab")
		)
		(pad "1" smd circle
			(at -0.40005 0)
			(size 0 0)
			(layers "F.Cu" "F.Mask" "F.Paste")
			(net "P3V3_AUX")
		)
		(pad "2" smd circle
			(at 0.40005 0)
			(size 0 0)
			(layers "F.Cu" "F.Mask" "F.Paste")
			(net "PWRGD_P3V3_SSD1_D")
		)
	)
	(footprint ""
		(layer "F.Cu")
		(at 56.034686 -371.336062 180)
		(property "Reference" "C3987"
			(at 0 0 180)
			(layer "F.SilkS")
			(hide yes)
			(effects
				(font
					(size 1.27 1.27)
				)
			)
		)
		(property "Value" ""
			(at 0 0 180)
			(layer "F.Fab")
			(effects
				(font
					(size 1.27 1.27)
				)
			)
		)
		(duplicate_pad_numbers_are_jumpers no)
		(fp_line
			(start 0.299974 0.150114)
			(end -0.299974 0.150114)
			(stroke
				(width 0.1)
				(type default)
			)
			(layer "F.Fab")
		)
		(fp_line
			(start 0.299974 -0.150114)
			(end 0.299974 0.150114)
			(stroke
				(width 0.1)
				(type default)
			)
			(layer "F.Fab")
		)
		(fp_line
			(start -0.299974 0.150114)
			(end -0.299974 -0.150114)
			(stroke
				(width 0.1)
				(type default)
			)
			(layer "F.Fab")
		)
		(fp_line
			(start -0.299974 -0.150114)
			(end 0.299974 -0.150114)
			(stroke
				(width 0.1)
				(type default)
			)
			(layer "F.Fab")
		)
		(pad "1" smd rect
			(at -0.2667 0 180)
			(size 0.3048 0.381)
			(layers "F.Cu" "F.Mask" "F.Paste")
			(net "P4E_PEX0_STN3_TX_DN<48>")
		)
		(pad "2" smd rect
			(at 0.2667 0 180)
			(size 0.3048 0.381)
			(layers "F.Cu" "F.Mask" "F.Paste")
			(net "P4E_PEX0_STN3_TX_C_DN<48>")
		)
	)
	(footprint ""
		(layer "F.Cu")
		(at 435.291484 -96.811592 -90)
		(property "Reference" "R759"
			(at 0 0 270)
			(layer "F.SilkS")
			(hide yes)
			(effects
				(font
					(size 1.27 1.27)
				)
			)
		)
		(property "Value" ""
			(at 0 0 270)
			(layer "F.Fab")
			(effects
				(font
					(size 1.27 1.27)
				)
			)
		)
		(duplicate_pad_numbers_are_jumpers no)
		(fp_line
			(start -0.7874 0.4064)
			(end -0.7874 -0.4064)
			(stroke
				(width 0.1524)
				(type default)
			)
			(layer "F.SilkS")
		)
		(fp_line
			(start 0.7874 0.4064)
			(end -0.7874 0.4064)
			(stroke
				(width 0.1524)
				(type default)
			)
			(layer "F.SilkS")
		)
		(fp_line
			(start -0.7874 -0.4064)
			(end 0.7874 -0.4064)
			(stroke
				(width 0.1524)
				(type default)
			)
			(layer "F.SilkS")
		)
		(fp_line
			(start 0.7874 -0.4064)
			(end 0.7874 0.4064)
			(stroke
				(width 0.1524)
				(type default)
			)
			(layer "F.SilkS")
		)
		(fp_line
			(start -0.67945 0.3048)
			(end -0.67945 -0.305054)
			(stroke
				(width 0.1)
				(type default)
			)
			(layer "F.Fab")
		)
		(fp_line
			(start -0.12065 0.3048)
			(end -0.67945 0.3048)
			(stroke
				(width 0.1)
				(type default)
			)
			(layer "F.Fab")
		)
		(fp_line
			(start 0.120396 0.3048)
			(end 0.120396 0.2794)
			(stroke
				(width 0.1)
				(type default)
			)
			(layer "F.Fab")
		)
		(fp_line
			(start 0.67945 0.3048)
			(end 0.120396 0.3048)
			(stroke
				(width 0.1)
				(type default)
			)
			(layer "F.Fab")
		)
		(fp_line
			(start -0.12065 0.2794)
			(end -0.12065 0.3048)
			(stroke
				(width 0.1)
				(type default)
			)
			(layer "F.Fab")
		)
		(fp_line
			(start 0.120396 0.2794)
			(end -0.12065 0.2794)
			(stroke
				(width 0.1)
				(type default)
			)
			(layer "F.Fab")
		)
		(fp_line
			(start -0.12065 -0.2794)
			(end 0.12065 -0.2794)
			(stroke
				(width 0.1)
				(type default)
			)
			(layer "F.Fab")
		)
		(fp_line
			(start 0.12065 -0.2794)
			(end 0.12065 -0.3048)
			(stroke
				(width 0.1)
				(type default)
			)
			(layer "F.Fab")
		)
		(fp_line
			(start 0.12065 -0.3048)
			(end 0.67945 -0.3048)
			(stroke
				(width 0.1)
				(type default)
			)
			(layer "F.Fab")
		)
		(fp_line
			(start 0.67945 -0.3048)
			(end 0.67945 0.3048)
			(stroke
				(width 0.1)
				(type default)
			)
			(layer "F.Fab")
		)
		(fp_line
			(start -0.67945 -0.305054)
			(end -0.12065 -0.305054)
			(stroke
				(width 0.1)
				(type default)
			)
			(layer "F.Fab")
		)
		(fp_line
			(start -0.12065 -0.305054)
			(end -0.12065 -0.2794)
			(stroke
				(width 0.1)
				(type default)
			)
			(layer "F.Fab")
		)
		(pad "1" smd circle
			(at -0.40005 0 270)
			(size 0 0)
			(layers "F.Cu" "F.Mask" "F.Paste")
			(net "NIC7_ADC_A1")
		)
		(pad "2" smd circle
			(at 0.40005 0 270)
			(size 0 0)
			(layers "F.Cu" "F.Mask" "F.Paste")
			(net "P3V3_AUX")
		)
	)
	(footprint ""
		(layer "F.Cu")
		(at 6.999224 -255.046734 -90)
		(property "Reference" "R6461"
			(at 0 0 270)
			(layer "F.SilkS")
			(hide yes)
			(effects
				(font
					(size 1.27 1.27)
				)
			)
		)
		(property "Value" ""
			(at 0 0 270)
			(layer "F.Fab")
			(effects
				(font
					(size 1.27 1.27)
				)
			)
		)
		(duplicate_pad_numbers_are_jumpers no)
		(fp_line
			(start -0.7874 0.4064)
			(end -0.7874 -0.4064)
			(stroke
				(width 0.1524)
				(type default)
			)
			(layer "F.SilkS")
		)
		(fp_line
			(start 0.7874 0.4064)
			(end -0.7874 0.4064)
			(stroke
				(width 0.1524)
				(type default)
			)
			(layer "F.SilkS")
		)
		(fp_line
			(start -0.7874 -0.4064)
			(end 0.7874 -0.4064)
			(stroke
				(width 0.1524)
				(type default)
			)
			(layer "F.SilkS")
		)
		(fp_line
			(start 0.7874 -0.4064)
			(end 0.7874 0.4064)
			(stroke
				(width 0.1524)
				(type default)
			)
			(layer "F.SilkS")
		)
		(fp_line
			(start -0.67945 0.3048)
			(end -0.67945 -0.305054)
			(stroke
				(width 0.1)
				(type default)
			)
			(layer "F.Fab")
		)
		(fp_line
			(start -0.12065 0.3048)
			(end -0.67945 0.3048)
			(stroke
				(width 0.1)
				(type default)
			)
			(layer "F.Fab")
		)
		(fp_line
			(start 0.120396 0.3048)
			(end 0.120396 0.2794)
			(stroke
				(width 0.1)
				(type default)
			)
			(layer "F.Fab")
		)
		(fp_line
			(start 0.67945 0.3048)
			(end 0.120396 0.3048)
			(stroke
				(width 0.1)
				(type default)
			)
			(layer "F.Fab")
		)
		(fp_line
			(start -0.12065 0.2794)
			(end -0.12065 0.3048)
			(stroke
				(width 0.1)
				(type default)
			)
			(layer "F.Fab")
		)
		(fp_line
			(start 0.120396 0.2794)
			(end -0.12065 0.2794)
			(stroke
				(width 0.1)
				(type default)
			)
			(layer "F.Fab")
		)
		(fp_line
			(start -0.12065 -0.2794)
			(end 0.12065 -0.2794)
			(stroke
				(width 0.1)
				(type default)
			)
			(layer "F.Fab")
		)
		(fp_line
			(start 0.12065 -0.2794)
			(end 0.12065 -0.3048)
			(stroke
				(width 0.1)
				(type default)
			)
			(layer "F.Fab")
		)
		(fp_line
			(start 0.12065 -0.3048)
			(end 0.67945 -0.3048)
			(stroke
				(width 0.1)
				(type default)
			)
			(layer "F.Fab")
		)
		(fp_line
			(start 0.67945 -0.3048)
			(end 0.67945 0.3048)
			(stroke
				(width 0.1)
				(type default)
			)
			(layer "F.Fab")
		)
		(fp_line
			(start -0.67945 -0.305054)
			(end -0.12065 -0.305054)
			(stroke
				(width 0.1)
				(type default)
			)
			(layer "F.Fab")
		)
		(fp_line
			(start -0.12065 -0.305054)
			(end -0.12065 -0.2794)
			(stroke
				(width 0.1)
				(type default)
			)
			(layer "F.Fab")
		)
		(pad "1" smd circle
			(at -0.40005 0 270)
			(size 0 0)
			(layers "F.Cu" "F.Mask" "F.Paste")
			(net "P1V25_SERDES_VDDPLL_PEX0")
		)
		(pad "2" smd circle
			(at 0.40005 0 270)
			(size 0 0)
			(layers "F.Cu" "F.Mask" "F.Paste")
			(net "P1V25_SERDES_VDDPLL_PEX0_C0")
		)
	)
	(footprint ""
		(layer "F.Cu")
		(at 392.9253 -343.952322 90)
		(property "Reference" "C756"
			(at 0 0 90)
			(layer "F.SilkS")
			(hide yes)
			(effects
				(font
					(size 1.27 1.27)
				)
			)
		)
		(property "Value" ""
			(at 0 0 90)
			(layer "F.Fab")
			(effects
				(font
					(size 1.27 1.27)
				)
			)
		)
		(duplicate_pad_numbers_are_jumpers no)
		(fp_line
			(start 0.299974 -0.150114)
			(end 0.299974 0.150114)
			(stroke
				(width 0.1)
				(type default)
			)
			(layer "F.Fab")
		)
		(fp_line
			(start -0.299974 -0.150114)
			(end 0.299974 -0.150114)
			(stroke
				(width 0.1)
				(type default)
			)
			(layer "F.Fab")
		)
		(fp_line
			(start 0.299974 0.150114)
			(end -0.299974 0.150114)
			(stroke
				(width 0.1)
				(type default)
			)
			(layer "F.Fab")
		)
		(fp_line
			(start -0.299974 0.150114)
			(end -0.299974 -0.150114)
			(stroke
				(width 0.1)
				(type default)
			)
			(layer "F.Fab")
		)
		(pad "1" smd rect
			(at -0.2667 0 90)
			(size 0.3048 0.381)
			(layers "F.Cu" "F.Mask" "F.Paste")
			(net "P5E_PEX3_STN5_TX_DP<82>")
		)
		(pad "2" smd rect
			(at 0.2667 0 90)
			(size 0.3048 0.381)
			(layers "F.Cu" "F.Mask" "F.Paste")
			(net "P5E_PEX3_STN5_TX_C_DP<82>")
		)
	)
	(footprint ""
		(layer "F.Cu")
		(at 361.188 -173.99 180)
		(property "Reference" "R4710"
			(at 0 0 180)
			(layer "F.SilkS")
			(hide yes)
			(effects
				(font
					(size 1.27 1.27)
				)
			)
		)
		(property "Value" ""
			(at 0 0 180)
			(layer "F.Fab")
			(effects
				(font
					(size 1.27 1.27)
				)
			)
		)
		(duplicate_pad_numbers_are_jumpers no)
		(fp_line
			(start 0.7874 0.4064)
			(end -0.7874 0.4064)
			(stroke
				(width 0.1524)
				(type default)
			)
			(layer "F.SilkS")
		)
		(fp_line
			(start 0.7874 -0.4064)
			(end 0.7874 0.4064)
			(stroke
				(width 0.1524)
				(type default)
			)
			(layer "F.SilkS")
		)
		(fp_line
			(start -0.7874 0.4064)
			(end -0.7874 -0.4064)
			(stroke
				(width 0.1524)
				(type default)
			)
			(layer "F.SilkS")
		)
		(fp_line
			(start -0.7874 -0.4064)
			(end 0.7874 -0.4064)
			(stroke
				(width 0.1524)
				(type default)
			)
			(layer "F.SilkS")
		)
		(fp_line
			(start 0.67945 0.3048)
			(end 0.120396 0.3048)
			(stroke
				(width 0.1)
				(type default)
			)
			(layer "F.Fab")
		)
		(fp_line
			(start 0.67945 -0.3048)
			(end 0.67945 0.3048)
			(stroke
				(width 0.1)
				(type default)
			)
			(layer "F.Fab")
		)
		(fp_line
			(start 0.12065 -0.2794)
			(end 0.12065 -0.3048)
			(stroke
				(width 0.1)
				(type default)
			)
			(layer "F.Fab")
		)
		(fp_line
			(start 0.12065 -0.3048)
			(end 0.67945 -0.3048)
			(stroke
				(width 0.1)
				(type default)
			)
			(layer "F.Fab")
		)
		(fp_line
			(start 0.120396 0.3048)
			(end 0.120396 0.2794)
			(stroke
				(width 0.1)
				(type default)
			)
			(layer "F.Fab")
		)
		(fp_line
			(start 0.120396 0.2794)
			(end -0.12065 0.2794)
			(stroke
				(width 0.1)
				(type default)
			)
			(layer "F.Fab")
		)
		(fp_line
			(start -0.12065 0.3048)
			(end -0.67945 0.3048)
			(stroke
				(width 0.1)
				(type default)
			)
			(layer "F.Fab")
		)
		(fp_line
			(start -0.12065 0.2794)
			(end -0.12065 0.3048)
			(stroke
				(width 0.1)
				(type default)
			)
			(layer "F.Fab")
		)
		(fp_line
			(start -0.12065 -0.2794)
			(end 0.12065 -0.2794)
			(stroke
				(width 0.1)
				(type default)
			)
			(layer "F.Fab")
		)
		(fp_line
			(start -0.12065 -0.305054)
			(end -0.12065 -0.2794)
			(stroke
				(width 0.1)
				(type default)
			)
			(layer "F.Fab")
		)
		(fp_line
			(start -0.67945 0.3048)
			(end -0.67945 -0.305054)
			(stroke
				(width 0.1)
				(type default)
			)
			(layer "F.Fab")
		)
		(fp_line
			(start -0.67945 -0.305054)
			(end -0.12065 -0.305054)
			(stroke
				(width 0.1)
				(type default)
			)
			(layer "F.Fab")
		)
		(pad "1" smd circle
			(at -0.40005 0 180)
			(size 0 0)
			(layers "F.Cu" "F.Mask" "F.Paste")
			(net "SSD7_PEX_PWR_EN")
		)
		(pad "2" smd circle
			(at 0.40005 0 180)
			(size 0 0)
			(layers "F.Cu" "F.Mask" "F.Paste")
			(net "SSD7_PEX_PWR_EN_R")
		)
	)
	(footprint ""
		(layer "F.Cu")
		(at 407.295096 -102.798372 180)
		(property "Reference" "R376"
			(at 0 0 180)
			(layer "F.SilkS")
			(hide yes)
			(effects
				(font
					(size 1.27 1.27)
				)
			)
		)
		(property "Value" ""
			(at 0 0 180)
			(layer "F.Fab")
			(effects
				(font
					(size 1.27 1.27)
				)
			)
		)
		(duplicate_pad_numbers_are_jumpers no)
		(fp_line
			(start 0.7874 0.4064)
			(end -0.7874 0.4064)
			(stroke
				(width 0.1524)
				(type default)
			)
			(layer "F.SilkS")
		)
		(fp_line
			(start 0.7874 -0.4064)
			(end 0.7874 0.4064)
			(stroke
				(width 0.1524)
				(type default)
			)
			(layer "F.SilkS")
		)
		(fp_line
			(start -0.7874 0.4064)
			(end -0.7874 -0.4064)
			(stroke
				(width 0.1524)
				(type default)
			)
			(layer "F.SilkS")
		)
		(fp_line
			(start -0.7874 -0.4064)
			(end 0.7874 -0.4064)
			(stroke
				(width 0.1524)
				(type default)
			)
			(layer "F.SilkS")
		)
		(fp_line
			(start 0.67945 0.3048)
			(end 0.120396 0.3048)
			(stroke
				(width 0.1)
				(type default)
			)
			(layer "F.Fab")
		)
		(fp_line
			(start 0.67945 -0.3048)
			(end 0.67945 0.3048)
			(stroke
				(width 0.1)
				(type default)
			)
			(layer "F.Fab")
		)
		(fp_line
			(start 0.12065 -0.2794)
			(end 0.12065 -0.3048)
			(stroke
				(width 0.1)
				(type default)
			)
			(layer "F.Fab")
		)
		(fp_line
			(start 0.12065 -0.3048)
			(end 0.67945 -0.3048)
			(stroke
				(width 0.1)
				(type default)
			)
			(layer "F.Fab")
		)
		(fp_line
			(start 0.120396 0.3048)
			(end 0.120396 0.2794)
			(stroke
				(width 0.1)
				(type default)
			)
			(layer "F.Fab")
		)
		(fp_line
			(start 0.120396 0.2794)
			(end -0.12065 0.2794)
			(stroke
				(width 0.1)
				(type default)
			)
			(layer "F.Fab")
		)
		(fp_line
			(start -0.12065 0.3048)
			(end -0.67945 0.3048)
			(stroke
				(width 0.1)
				(type default)
			)
			(layer "F.Fab")
		)
		(fp_line
			(start -0.12065 0.2794)
			(end -0.12065 0.3048)
			(stroke
				(width 0.1)
				(type default)
			)
			(layer "F.Fab")
		)
		(fp_line
			(start -0.12065 -0.2794)
			(end 0.12065 -0.2794)
			(stroke
				(width 0.1)
				(type default)
			)
			(layer "F.Fab")
		)
		(fp_line
			(start -0.12065 -0.305054)
			(end -0.12065 -0.2794)
			(stroke
				(width 0.1)
				(type default)
			)
			(layer "F.Fab")
		)
		(fp_line
			(start -0.67945 0.3048)
			(end -0.67945 -0.305054)
			(stroke
				(width 0.1)
				(type default)
			)
			(layer "F.Fab")
		)
		(fp_line
			(start -0.67945 -0.305054)
			(end -0.12065 -0.305054)
			(stroke
				(width 0.1)
				(type default)
			)
			(layer "F.Fab")
		)
		(pad "1" smd circle
			(at -0.40005 0 180)
			(size 0 0)
			(layers "F.Cu" "F.Mask" "F.Paste")
			(net "NCSI_NIC7_TXD1")
		)
		(pad "2" smd circle
			(at 0.40005 0 180)
			(size 0 0)
			(layers "F.Cu" "F.Mask" "F.Paste")
			(net "GND")
		)
	)
	(footprint ""
		(layer "F.Cu")
		(at 26.930096 -300.406308 -90)
		(property "Reference" "C3017"
			(at 0 0 270)
			(layer "F.SilkS")
			(hide yes)
			(effects
				(font
					(size 1.27 1.27)
				)
			)
		)
		(property "Value" ""
			(at 0 0 270)
			(layer "F.Fab")
			(effects
				(font
					(size 1.27 1.27)
				)
			)
		)
		(duplicate_pad_numbers_are_jumpers no)
		(fp_line
			(start -1.2954 0.5842)
			(end -1.2954 -0.5842)
			(stroke
				(width 0.1524)
				(type default)
			)
			(layer "F.SilkS")
		)
		(fp_line
			(start 1.2954 0.5842)
			(end -1.2954 0.5842)
			(stroke
				(width 0.1524)
				(type default)
			)
			(layer "F.SilkS")
		)
		(fp_line
			(start -1.2954 -0.5842)
			(end 1.2954 -0.5842)
			(stroke
				(width 0.1524)
				(type default)
			)
			(layer "F.SilkS")
		)
		(fp_line
			(start 1.2954 -0.5842)
			(end 1.2954 0.5842)
			(stroke
				(width 0.1524)
				(type default)
			)
			(layer "F.SilkS")
		)
		(fp_line
			(start -0.8636 0.4572)
			(end -0.8636 0.4064)
			(stroke
				(width 0.1)
				(type default)
			)
			(layer "F.Fab")
		)
		(fp_line
			(start 0.8636 0.4572)
			(end -0.8636 0.4572)
			(stroke
				(width 0.1)
				(type default)
			)
			(layer "F.Fab")
		)
		(fp_line
			(start -1.1938 0.4064)
			(end -1.1938 -0.4064)
			(stroke
				(width 0.1)
				(type default)
			)
			(layer "F.Fab")
		)
		(fp_line
			(start -0.8636 0.4064)
			(end -1.1938 0.4064)
			(stroke
				(width 0.1)
				(type default)
			)
			(layer "F.Fab")
		)
		(fp_line
			(start 0.8636 0.4064)
			(end 0.8636 0.4572)
			(stroke
				(width 0.1)
				(type default)
			)
			(layer "F.Fab")
		)
		(fp_line
			(start 1.1938 0.4064)
			(end 0.8636 0.4064)
			(stroke
				(width 0.1)
				(type default)
			)
			(layer "F.Fab")
		)
		(fp_line
			(start -1.1938 -0.4064)
			(end -0.8636 -0.4064)
			(stroke
				(width 0.1)
				(type default)
			)
			(layer "F.Fab")
		)
		(fp_line
			(start -0.8636 -0.4064)
			(end -0.8636 -0.4572)
			(stroke
				(width 0.1)
				(type default)
			)
			(layer "F.Fab")
		)
		(fp_line
			(start 0.8636 -0.4064)
			(end 1.1938 -0.4064)
			(stroke
				(width 0.1)
				(type default)
			)
			(layer "F.Fab")
		)
		(fp_line
			(start 1.1938 -0.4064)
			(end 1.1938 0.4064)
			(stroke
				(width 0.1)
				(type default)
			)
			(layer "F.Fab")
		)
		(fp_line
			(start -0.8636 -0.4572)
			(end 0.8636 -0.4572)
			(stroke
				(width 0.1)
				(type default)
			)
			(layer "F.Fab")
		)
		(fp_line
			(start 0.8636 -0.4572)
			(end 0.8636 -0.4064)
			(stroke
				(width 0.1)
				(type default)
			)
			(layer "F.Fab")
		)
		(pad "1" smd rect
			(at -0.7366 0 180)
			(size 0.7112 0.8128)
			(layers "F.Cu" "F.Mask" "F.Paste")
			(net "P1V8_PLL0_PEX0")
		)
		(pad "2" smd rect
			(at 0.7366 0 180)
			(size 0.7112 0.8128)
			(layers "F.Cu" "F.Mask" "F.Paste")
			(net "GND")
		)
	)
	(footprint ""
		(layer "F.Cu")
		(at 98.446336 -58.323734)
		(property "Reference" "PC391"
			(at 0 0 0)
			(layer "F.SilkS")
			(hide yes)
			(effects
				(font
					(size 1.27 1.27)
				)
			)
		)
		(property "Value" ""
			(at 0 0 0)
			(layer "F.Fab")
			(effects
				(font
					(size 1.27 1.27)
				)
			)
		)
		(duplicate_pad_numbers_are_jumpers no)
		(fp_line
			(start -1.524 -0.762)
			(end 1.524 -0.762)
			(stroke
				(width 0.1524)
				(type default)
			)
			(layer "F.SilkS")
		)
		(fp_line
			(start -1.524 0.762)
			(end -1.524 -0.762)
			(stroke
				(width 0.1524)
				(type default)
			)
			(layer "F.SilkS")
		)
		(fp_line
			(start 1.524 -0.762)
			(end 1.524 0.762)
			(stroke
				(width 0.1524)
				(type default)
			)
			(layer "F.SilkS")
		)
		(fp_line
			(start 1.524 0.762)
			(end -1.524 0.762)
			(stroke
				(width 0.1524)
				(type default)
			)
			(layer "F.SilkS")
		)
		(fp_line
			(start -1.1049 -0.724916)
			(end -1.1049 0.724916)
			(stroke
				(width 0.1)
				(type default)
			)
			(layer "F.Fab")
		)
		(fp_line
			(start -1.1049 0.724916)
			(end 1.1049 0.724916)
			(stroke
				(width 0.1)
				(type default)
			)
			(layer "F.Fab")
		)
		(fp_line
			(start 1.1049 -0.724916)
			(end -1.1049 -0.724916)
			(stroke
				(width 0.1)
				(type default)
			)
			(layer "F.Fab")
		)
		(fp_line
			(start 1.1049 0.724916)
			(end 1.1049 -0.724916)
			(stroke
				(width 0.1)
				(type default)
			)
			(layer "F.Fab")
		)
		(pad "1" smd rect
			(at -0.889 0 180)
			(size 1.016 1.27)
			(layers "F.Cu" "F.Mask" "F.Paste")
			(net "GND")
		)
		(pad "2" smd rect
			(at 0.889 0 180)
			(size 1.016 1.27)
			(layers "F.Cu" "F.Mask" "F.Paste")
			(net "P12V_AUX")
		)
	)
	(footprint ""
		(layer "F.Cu")
		(at 402.140166 -32.848042 90)
		(property "Reference" "PC973"
			(at 0 0 90)
			(layer "F.SilkS")
			(hide yes)
			(effects
				(font
					(size 1.27 1.27)
				)
			)
		)
		(property "Value" ""
			(at 0 0 90)
			(layer "F.Fab")
			(effects
				(font
					(size 1.27 1.27)
				)
			)
		)
		(duplicate_pad_numbers_are_jumpers no)
		(fp_line
			(start 0.7874 -0.4064)
			(end 0.7874 0.4064)
			(stroke
				(width 0.1524)
				(type default)
			)
			(layer "F.SilkS")
		)
		(fp_line
			(start -0.7874 -0.4064)
			(end 0.7874 -0.4064)
			(stroke
				(width 0.1524)
				(type default)
			)
			(layer "F.SilkS")
		)
		(fp_line
			(start 0.7874 0.4064)
			(end -0.7874 0.4064)
			(stroke
				(width 0.1524)
				(type default)
			)
			(layer "F.SilkS")
		)
		(fp_line
			(start -0.7874 0.4064)
			(end -0.7874 -0.4064)
			(stroke
				(width 0.1524)
				(type default)
			)
			(layer "F.SilkS")
		)
		(fp_line
			(start -0.12065 -0.305054)
			(end -0.12065 -0.2794)
			(stroke
				(width 0.1)
				(type default)
			)
			(layer "F.Fab")
		)
		(fp_line
			(start -0.67945 -0.305054)
			(end -0.12065 -0.305054)
			(stroke
				(width 0.1)
				(type default)
			)
			(layer "F.Fab")
		)
		(fp_line
			(start 0.67945 -0.3048)
			(end 0.67945 0.3048)
			(stroke
				(width 0.1)
				(type default)
			)
			(layer "F.Fab")
		)
		(fp_line
			(start 0.12065 -0.3048)
			(end 0.67945 -0.3048)
			(stroke
				(width 0.1)
				(type default)
			)
			(layer "F.Fab")
		)
		(fp_line
			(start 0.12065 -0.2794)
			(end 0.12065 -0.3048)
			(stroke
				(width 0.1)
				(type default)
			)
			(layer "F.Fab")
		)
		(fp_line
			(start -0.12065 -0.2794)
			(end 0.12065 -0.2794)
			(stroke
				(width 0.1)
				(type default)
			)
			(layer "F.Fab")
		)
		(fp_line
			(start 0.120396 0.2794)
			(end -0.12065 0.2794)
			(stroke
				(width 0.1)
				(type default)
			)
			(layer "F.Fab")
		)
		(fp_line
			(start -0.12065 0.2794)
			(end -0.12065 0.3048)
			(stroke
				(width 0.1)
				(type default)
			)
			(layer "F.Fab")
		)
		(fp_line
			(start 0.67945 0.3048)
			(end 0.120396 0.3048)
			(stroke
				(width 0.1)
				(type default)
			)
			(layer "F.Fab")
		)
		(fp_line
			(start 0.120396 0.3048)
			(end 0.120396 0.2794)
			(stroke
				(width 0.1)
				(type default)
			)
			(layer "F.Fab")
		)
		(fp_line
			(start -0.12065 0.3048)
			(end -0.67945 0.3048)
			(stroke
				(width 0.1)
				(type default)
			)
			(layer "F.Fab")
		)
		(fp_line
			(start -0.67945 0.3048)
			(end -0.67945 -0.305054)
			(stroke
				(width 0.1)
				(type default)
			)
			(layer "F.Fab")
		)
		(pad "1" smd circle
			(at -0.40005 0 90)
			(size 0 0)
			(layers "F.Cu" "F.Mask" "F.Paste")
			(net "P3V3_SSD14_CO_DV_DT")
		)
		(pad "2" smd circle
			(at 0.40005 0 90)
			(size 0 0)
			(layers "F.Cu" "F.Mask" "F.Paste")
			(net "GND")
		)
	)
	(footprint ""
		(layer "F.Cu")
		(at 320.488056 -100.459032 90)
		(property "Reference" "R744"
			(at 0 0 90)
			(layer "F.SilkS")
			(hide yes)
			(effects
				(font
					(size 1.27 1.27)
				)
			)
		)
		(property "Value" ""
			(at 0 0 90)
			(layer "F.Fab")
			(effects
				(font
					(size 1.27 1.27)
				)
			)
		)
		(duplicate_pad_numbers_are_jumpers no)
		(fp_line
			(start 0.7874 -0.4064)
			(end 0.7874 0.4064)
			(stroke
				(width 0.1524)
				(type default)
			)
			(layer "F.SilkS")
		)
		(fp_line
			(start -0.7874 -0.4064)
			(end 0.7874 -0.4064)
			(stroke
				(width 0.1524)
				(type default)
			)
			(layer "F.SilkS")
		)
		(fp_line
			(start 0.7874 0.4064)
			(end -0.7874 0.4064)
			(stroke
				(width 0.1524)
				(type default)
			)
			(layer "F.SilkS")
		)
		(fp_line
			(start -0.7874 0.4064)
			(end -0.7874 -0.4064)
			(stroke
				(width 0.1524)
				(type default)
			)
			(layer "F.SilkS")
		)
		(fp_line
			(start -0.12065 -0.305054)
			(end -0.12065 -0.2794)
			(stroke
				(width 0.1)
				(type default)
			)
			(layer "F.Fab")
		)
		(fp_line
			(start -0.67945 -0.305054)
			(end -0.12065 -0.305054)
			(stroke
				(width 0.1)
				(type default)
			)
			(layer "F.Fab")
		)
		(fp_line
			(start 0.67945 -0.3048)
			(end 0.67945 0.3048)
			(stroke
				(width 0.1)
				(type default)
			)
			(layer "F.Fab")
		)
		(fp_line
			(start 0.12065 -0.3048)
			(end 0.67945 -0.3048)
			(stroke
				(width 0.1)
				(type default)
			)
			(layer "F.Fab")
		)
		(fp_line
			(start 0.12065 -0.2794)
			(end 0.12065 -0.3048)
			(stroke
				(width 0.1)
				(type default)
			)
			(layer "F.Fab")
		)
		(fp_line
			(start -0.12065 -0.2794)
			(end 0.12065 -0.2794)
			(stroke
				(width 0.1)
				(type default)
			)
			(layer "F.Fab")
		)
		(fp_line
			(start 0.120396 0.2794)
			(end -0.12065 0.2794)
			(stroke
				(width 0.1)
				(type default)
			)
			(layer "F.Fab")
		)
		(fp_line
			(start -0.12065 0.2794)
			(end -0.12065 0.3048)
			(stroke
				(width 0.1)
				(type default)
			)
			(layer "F.Fab")
		)
		(fp_line
			(start 0.67945 0.3048)
			(end 0.120396 0.3048)
			(stroke
				(width 0.1)
				(type default)
			)
			(layer "F.Fab")
		)
		(fp_line
			(start 0.120396 0.3048)
			(end 0.120396 0.2794)
			(stroke
				(width 0.1)
				(type default)
			)
			(layer "F.Fab")
		)
		(fp_line
			(start -0.12065 0.3048)
			(end -0.67945 0.3048)
			(stroke
				(width 0.1)
				(type default)
			)
			(layer "F.Fab")
		)
		(fp_line
			(start -0.67945 0.3048)
			(end -0.67945 -0.305054)
			(stroke
				(width 0.1)
				(type default)
			)
			(layer "F.Fab")
		)
		(pad "1" smd circle
			(at -0.40005 0 90)
			(size 0 0)
			(layers "F.Cu" "F.Mask" "F.Paste")
			(net "P12V_NIC5_R")
		)
		(pad "2" smd circle
			(at 0.40005 0 90)
			(size 0 0)
			(layers "F.Cu" "F.Mask" "F.Paste")
			(net "P12V_NIC5_VIN_P")
		)
	)
	(footprint ""
		(layer "F.Cu")
		(at 280.571448 -407.714958 90)
		(property "Reference" "C2747"
			(at 0 0 90)
			(layer "F.SilkS")
			(hide yes)
			(effects
				(font
					(size 1.27 1.27)
				)
			)
		)
		(property "Value" ""
			(at 0 0 90)
			(layer "F.Fab")
			(effects
				(font
					(size 1.27 1.27)
				)
			)
		)
		(duplicate_pad_numbers_are_jumpers no)
		(fp_line
			(start 0.7874 -0.4064)
			(end 0.7874 0.4064)
			(stroke
				(width 0.1524)
				(type default)
			)
			(layer "F.SilkS")
		)
		(fp_line
			(start -0.7874 -0.4064)
			(end 0.7874 -0.4064)
			(stroke
				(width 0.1524)
				(type default)
			)
			(layer "F.SilkS")
		)
		(fp_line
			(start 0.7874 0.4064)
			(end -0.7874 0.4064)
			(stroke
				(width 0.1524)
				(type default)
			)
			(layer "F.SilkS")
		)
		(fp_line
			(start -0.7874 0.4064)
			(end -0.7874 -0.4064)
			(stroke
				(width 0.1524)
				(type default)
			)
			(layer "F.SilkS")
		)
		(fp_line
			(start -0.12065 -0.305054)
			(end -0.12065 -0.2794)
			(stroke
				(width 0.1)
				(type default)
			)
			(layer "F.Fab")
		)
		(fp_line
			(start -0.67945 -0.305054)
			(end -0.12065 -0.305054)
			(stroke
				(width 0.1)
				(type default)
			)
			(layer "F.Fab")
		)
		(fp_line
			(start 0.67945 -0.3048)
			(end 0.67945 0.3048)
			(stroke
				(width 0.1)
				(type default)
			)
			(layer "F.Fab")
		)
		(fp_line
			(start 0.12065 -0.3048)
			(end 0.67945 -0.3048)
			(stroke
				(width 0.1)
				(type default)
			)
			(layer "F.Fab")
		)
		(fp_line
			(start 0.12065 -0.2794)
			(end 0.12065 -0.3048)
			(stroke
				(width 0.1)
				(type default)
			)
			(layer "F.Fab")
		)
		(fp_line
			(start -0.12065 -0.2794)
			(end 0.12065 -0.2794)
			(stroke
				(width 0.1)
				(type default)
			)
			(layer "F.Fab")
		)
		(fp_line
			(start 0.120396 0.2794)
			(end -0.12065 0.2794)
			(stroke
				(width 0.1)
				(type default)
			)
			(layer "F.Fab")
		)
		(fp_line
			(start -0.12065 0.2794)
			(end -0.12065 0.3048)
			(stroke
				(width 0.1)
				(type default)
			)
			(layer "F.Fab")
		)
		(fp_line
			(start 0.67945 0.3048)
			(end 0.120396 0.3048)
			(stroke
				(width 0.1)
				(type default)
			)
			(layer "F.Fab")
		)
		(fp_line
			(start 0.120396 0.3048)
			(end 0.120396 0.2794)
			(stroke
				(width 0.1)
				(type default)
			)
			(layer "F.Fab")
		)
		(fp_line
			(start -0.12065 0.3048)
			(end -0.67945 0.3048)
			(stroke
				(width 0.1)
				(type default)
			)
			(layer "F.Fab")
		)
		(fp_line
			(start -0.67945 0.3048)
			(end -0.67945 -0.305054)
			(stroke
				(width 0.1)
				(type default)
			)
			(layer "F.Fab")
		)
		(pad "1" smd circle
			(at -0.40005 0 90)
			(size 0 0)
			(layers "F.Cu" "F.Mask" "F.Paste")
			(net "P3V3_AUX")
		)
		(pad "2" smd circle
			(at 0.40005 0 90)
			(size 0 0)
			(layers "F.Cu" "F.Mask" "F.Paste")
			(net "GND")
		)
	)
	(footprint ""
		(layer "F.Cu")
		(at 385.308602 -247.32996 180)
		(property "Reference" "C2577"
			(at 0 0 180)
			(layer "F.SilkS")
			(hide yes)
			(effects
				(font
					(size 1.27 1.27)
				)
			)
		)
		(property "Value" ""
			(at 0 0 180)
			(layer "F.Fab")
			(effects
				(font
					(size 1.27 1.27)
				)
			)
		)
		(duplicate_pad_numbers_are_jumpers no)
		(fp_line
			(start 1.2954 0.5842)
			(end -1.2954 0.5842)
			(stroke
				(width 0.1524)
				(type default)
			)
			(layer "F.SilkS")
		)
		(fp_line
			(start 1.2954 -0.5842)
			(end 1.2954 0.5842)
			(stroke
				(width 0.1524)
				(type default)
			)
			(layer "F.SilkS")
		)
		(fp_line
			(start -1.2954 0.5842)
			(end -1.2954 -0.5842)
			(stroke
				(width 0.1524)
				(type default)
			)
			(layer "F.SilkS")
		)
		(fp_line
			(start -1.2954 -0.5842)
			(end 1.2954 -0.5842)
			(stroke
				(width 0.1524)
				(type default)
			)
			(layer "F.SilkS")
		)
		(fp_line
			(start 1.1938 0.4064)
			(end 0.8636 0.4064)
			(stroke
				(width 0.1)
				(type default)
			)
			(layer "F.Fab")
		)
		(fp_line
			(start 1.1938 -0.4064)
			(end 1.1938 0.4064)
			(stroke
				(width 0.1)
				(type default)
			)
			(layer "F.Fab")
		)
		(fp_line
			(start 0.8636 0.4572)
			(end -0.8636 0.4572)
			(stroke
				(width 0.1)
				(type default)
			)
			(layer "F.Fab")
		)
		(fp_line
			(start 0.8636 0.4064)
			(end 0.8636 0.4572)
			(stroke
				(width 0.1)
				(type default)
			)
			(layer "F.Fab")
		)
		(fp_line
			(start 0.8636 -0.4064)
			(end 1.1938 -0.4064)
			(stroke
				(width 0.1)
				(type default)
			)
			(layer "F.Fab")
		)
		(fp_line
			(start 0.8636 -0.4572)
			(end 0.8636 -0.4064)
			(stroke
				(width 0.1)
				(type default)
			)
			(layer "F.Fab")
		)
		(fp_line
			(start -0.8636 0.4572)
			(end -0.8636 0.4064)
			(stroke
				(width 0.1)
				(type default)
			)
			(layer "F.Fab")
		)
		(fp_line
			(start -0.8636 0.4064)
			(end -1.1938 0.4064)
			(stroke
				(width 0.1)
				(type default)
			)
			(layer "F.Fab")
		)
		(fp_line
			(start -0.8636 -0.4064)
			(end -0.8636 -0.4572)
			(stroke
				(width 0.1)
				(type default)
			)
			(layer "F.Fab")
		)
		(fp_line
			(start -0.8636 -0.4572)
			(end 0.8636 -0.4572)
			(stroke
				(width 0.1)
				(type default)
			)
			(layer "F.Fab")
		)
		(fp_line
			(start -1.1938 0.4064)
			(end -1.1938 -0.4064)
			(stroke
				(width 0.1)
				(type default)
			)
			(layer "F.Fab")
		)
		(fp_line
			(start -1.1938 -0.4064)
			(end -0.8636 -0.4064)
			(stroke
				(width 0.1)
				(type default)
			)
			(layer "F.Fab")
		)
		(pad "1" smd rect
			(at -0.7366 0 90)
			(size 0.7112 0.8128)
			(layers "F.Cu" "F.Mask" "F.Paste")
			(net "P1V8_SDB_VCORE")
		)
		(pad "2" smd rect
			(at 0.7366 0 90)
			(size 0.7112 0.8128)
			(layers "F.Cu" "F.Mask" "F.Paste")
			(net "GND")
		)
	)
	(footprint ""
		(layer "F.Cu")
		(at 440.687206 -300.650402 -90)
		(property "Reference" "R3996"
			(at 0 0 270)
			(layer "F.SilkS")
			(hide yes)
			(effects
				(font
					(size 1.27 1.27)
				)
			)
		)
		(property "Value" ""
			(at 0 0 270)
			(layer "F.Fab")
			(effects
				(font
					(size 1.27 1.27)
				)
			)
		)
		(duplicate_pad_numbers_are_jumpers no)
		(fp_line
			(start -0.7874 0.4064)
			(end -0.7874 -0.4064)
			(stroke
				(width 0.1524)
				(type default)
			)
			(layer "F.SilkS")
		)
		(fp_line
			(start 0.7874 0.4064)
			(end -0.7874 0.4064)
			(stroke
				(width 0.1524)
				(type default)
			)
			(layer "F.SilkS")
		)
		(fp_line
			(start -0.7874 -0.4064)
			(end 0.7874 -0.4064)
			(stroke
				(width 0.1524)
				(type default)
			)
			(layer "F.SilkS")
		)
		(fp_line
			(start 0.7874 -0.4064)
			(end 0.7874 0.4064)
			(stroke
				(width 0.1524)
				(type default)
			)
			(layer "F.SilkS")
		)
		(fp_line
			(start -0.67945 0.3048)
			(end -0.67945 -0.305054)
			(stroke
				(width 0.1)
				(type default)
			)
			(layer "F.Fab")
		)
		(fp_line
			(start -0.12065 0.3048)
			(end -0.67945 0.3048)
			(stroke
				(width 0.1)
				(type default)
			)
			(layer "F.Fab")
		)
		(fp_line
			(start 0.120396 0.3048)
			(end 0.120396 0.2794)
			(stroke
				(width 0.1)
				(type default)
			)
			(layer "F.Fab")
		)
		(fp_line
			(start 0.67945 0.3048)
			(end 0.120396 0.3048)
			(stroke
				(width 0.1)
				(type default)
			)
			(layer "F.Fab")
		)
		(fp_line
			(start -0.12065 0.2794)
			(end -0.12065 0.3048)
			(stroke
				(width 0.1)
				(type default)
			)
			(layer "F.Fab")
		)
		(fp_line
			(start 0.120396 0.2794)
			(end -0.12065 0.2794)
			(stroke
				(width 0.1)
				(type default)
			)
			(layer "F.Fab")
		)
		(fp_line
			(start -0.12065 -0.2794)
			(end 0.12065 -0.2794)
			(stroke
				(width 0.1)
				(type default)
			)
			(layer "F.Fab")
		)
		(fp_line
			(start 0.12065 -0.2794)
			(end 0.12065 -0.3048)
			(stroke
				(width 0.1)
				(type default)
			)
			(layer "F.Fab")
		)
		(fp_line
			(start 0.12065 -0.3048)
			(end 0.67945 -0.3048)
			(stroke
				(width 0.1)
				(type default)
			)
			(layer "F.Fab")
		)
		(fp_line
			(start 0.67945 -0.3048)
			(end 0.67945 0.3048)
			(stroke
				(width 0.1)
				(type default)
			)
			(layer "F.Fab")
		)
		(fp_line
			(start -0.67945 -0.305054)
			(end -0.12065 -0.305054)
			(stroke
				(width 0.1)
				(type default)
			)
			(layer "F.Fab")
		)
		(fp_line
			(start -0.12065 -0.305054)
			(end -0.12065 -0.2794)
			(stroke
				(width 0.1)
				(type default)
			)
			(layer "F.Fab")
		)
		(pad "1" smd circle
			(at -0.40005 0 270)
			(size 0 0)
			(layers "F.Cu" "F.Mask" "F.Paste")
			(net "I2C0_PEX3_SHPC_SCL")
		)
		(pad "2" smd circle
			(at 0.40005 0 270)
			(size 0 0)
			(layers "F.Cu" "F.Mask" "F.Paste")
			(net "I2C_PEX3_HOST_SCL")
		)
	)
	(footprint ""
		(layer "F.Cu")
		(at 437.302148 -306.074572 90)
		(property "Reference" "R1439"
			(at 0 0 90)
			(layer "F.SilkS")
			(hide yes)
			(effects
				(font
					(size 1.27 1.27)
				)
			)
		)
		(property "Value" ""
			(at 0 0 90)
			(layer "F.Fab")
			(effects
				(font
					(size 1.27 1.27)
				)
			)
		)
		(duplicate_pad_numbers_are_jumpers no)
		(fp_line
			(start 0.7874 -0.4064)
			(end 0.7874 0.4064)
			(stroke
				(width 0.1524)
				(type default)
			)
			(layer "F.SilkS")
		)
		(fp_line
			(start -0.7874 -0.4064)
			(end 0.7874 -0.4064)
			(stroke
				(width 0.1524)
				(type default)
			)
			(layer "F.SilkS")
		)
		(fp_line
			(start 0.7874 0.4064)
			(end -0.7874 0.4064)
			(stroke
				(width 0.1524)
				(type default)
			)
			(layer "F.SilkS")
		)
		(fp_line
			(start -0.7874 0.4064)
			(end -0.7874 -0.4064)
			(stroke
				(width 0.1524)
				(type default)
			)
			(layer "F.SilkS")
		)
		(fp_line
			(start -0.12065 -0.305054)
			(end -0.12065 -0.2794)
			(stroke
				(width 0.1)
				(type default)
			)
			(layer "F.Fab")
		)
		(fp_line
			(start -0.67945 -0.305054)
			(end -0.12065 -0.305054)
			(stroke
				(width 0.1)
				(type default)
			)
			(layer "F.Fab")
		)
		(fp_line
			(start 0.67945 -0.3048)
			(end 0.67945 0.3048)
			(stroke
				(width 0.1)
				(type default)
			)
			(layer "F.Fab")
		)
		(fp_line
			(start 0.12065 -0.3048)
			(end 0.67945 -0.3048)
			(stroke
				(width 0.1)
				(type default)
			)
			(layer "F.Fab")
		)
		(fp_line
			(start 0.12065 -0.2794)
			(end 0.12065 -0.3048)
			(stroke
				(width 0.1)
				(type default)
			)
			(layer "F.Fab")
		)
		(fp_line
			(start -0.12065 -0.2794)
			(end 0.12065 -0.2794)
			(stroke
				(width 0.1)
				(type default)
			)
			(layer "F.Fab")
		)
		(fp_line
			(start 0.120396 0.2794)
			(end -0.12065 0.2794)
			(stroke
				(width 0.1)
				(type default)
			)
			(layer "F.Fab")
		)
		(fp_line
			(start -0.12065 0.2794)
			(end -0.12065 0.3048)
			(stroke
				(width 0.1)
				(type default)
			)
			(layer "F.Fab")
		)
		(fp_line
			(start 0.67945 0.3048)
			(end 0.120396 0.3048)
			(stroke
				(width 0.1)
				(type default)
			)
			(layer "F.Fab")
		)
		(fp_line
			(start 0.120396 0.3048)
			(end 0.120396 0.2794)
			(stroke
				(width 0.1)
				(type default)
			)
			(layer "F.Fab")
		)
		(fp_line
			(start -0.12065 0.3048)
			(end -0.67945 0.3048)
			(stroke
				(width 0.1)
				(type default)
			)
			(layer "F.Fab")
		)
		(fp_line
			(start -0.67945 0.3048)
			(end -0.67945 -0.305054)
			(stroke
				(width 0.1)
				(type default)
			)
			(layer "F.Fab")
		)
		(pad "1" smd circle
			(at -0.40005 0 90)
			(size 0 0)
			(layers "F.Cu" "F.Mask" "F.Paste")
			(net "PEX3_SPARE4")
		)
		(pad "2" smd circle
			(at 0.40005 0 90)
			(size 0 0)
			(layers "F.Cu" "F.Mask" "F.Paste")
			(net "P1V8_PEX")
		)
	)
	(footprint ""
		(layer "F.Cu")
		(at 277.198582 -350.098614 90)
		(property "Reference" "C2349"
			(at 0 0 90)
			(layer "F.SilkS")
			(hide yes)
			(effects
				(font
					(size 1.27 1.27)
				)
			)
		)
		(property "Value" ""
			(at 0 0 90)
			(layer "F.Fab")
			(effects
				(font
					(size 1.27 1.27)
				)
			)
		)
		(duplicate_pad_numbers_are_jumpers no)
		(fp_line
			(start 0.299974 -0.150114)
			(end 0.299974 0.150114)
			(stroke
				(width 0.1)
				(type default)
			)
			(layer "F.Fab")
		)
		(fp_line
			(start -0.299974 -0.150114)
			(end 0.299974 -0.150114)
			(stroke
				(width 0.1)
				(type default)
			)
			(layer "F.Fab")
		)
		(fp_line
			(start 0.299974 0.150114)
			(end -0.299974 0.150114)
			(stroke
				(width 0.1)
				(type default)
			)
			(layer "F.Fab")
		)
		(fp_line
			(start -0.299974 0.150114)
			(end -0.299974 -0.150114)
			(stroke
				(width 0.1)
				(type default)
			)
			(layer "F.Fab")
		)
		(pad "1" smd rect
			(at -0.2667 0 90)
			(size 0.3048 0.381)
			(layers "F.Cu" "F.Mask" "F.Paste")
			(net "P5E_PEX2_STN4_TX_DP<75>")
		)
		(pad "2" smd rect
			(at 0.2667 0 90)
			(size 0.3048 0.381)
			(layers "F.Cu" "F.Mask" "F.Paste")
			(net "P5E_PEX2_STN4_TX_C_DP<75>")
		)
	)
	(footprint ""
		(layer "F.Cu")
		(at 381.40386 -350.098614 90)
		(property "Reference" "C771"
			(at 0 0 90)
			(layer "F.SilkS")
			(hide yes)
			(effects
				(font
					(size 1.27 1.27)
				)
			)
		)
		(property "Value" ""
			(at 0 0 90)
			(layer "F.Fab")
			(effects
				(font
					(size 1.27 1.27)
				)
			)
		)
		(duplicate_pad_numbers_are_jumpers no)
		(fp_line
			(start 0.299974 -0.150114)
			(end 0.299974 0.150114)
			(stroke
				(width 0.1)
				(type default)
			)
			(layer "F.Fab")
		)
		(fp_line
			(start -0.299974 -0.150114)
			(end 0.299974 -0.150114)
			(stroke
				(width 0.1)
				(type default)
			)
			(layer "F.Fab")
		)
		(fp_line
			(start 0.299974 0.150114)
			(end -0.299974 0.150114)
			(stroke
				(width 0.1)
				(type default)
			)
			(layer "F.Fab")
		)
		(fp_line
			(start -0.299974 0.150114)
			(end -0.299974 -0.150114)
			(stroke
				(width 0.1)
				(type default)
			)
			(layer "F.Fab")
		)
		(pad "1" smd rect
			(at -0.2667 0 90)
			(size 0.3048 0.381)
			(layers "F.Cu" "F.Mask" "F.Paste")
			(net "P5E_PEX3_STN6_TX_DN<107>")
		)
		(pad "2" smd rect
			(at 0.2667 0 90)
			(size 0.3048 0.381)
			(layers "F.Cu" "F.Mask" "F.Paste")
			(net "P5E_PEX3_STN6_TX_C_DN<107>")
		)
	)
	(footprint ""
		(layer "F.Cu")
		(at 87.194644 -439.060082 180)
		(property "Reference" "X14"
			(at -0.1778 -1.92913 180)
			(unlocked yes)
			(layer "F.SilkS")
			(effects
				(font
					(size 0.7874 0.5842)
					(thickness 0.1524)
				)
				(justify left)
			)
		)
		(property "Value" ""
			(at 0 0 180)
			(layer "F.Fab")
			(effects
				(font
					(size 1.27 1.27)
				)
			)
		)
		(property "User Part Number" "TP15"
			(at 1.30175 1.27 270)
			(unlocked yes)
			(layer "Cmts.User")
			(hide yes)
			(effects
				(font
					(size 0.635 0.4064)
					(thickness 0.1524)
				)
			)
		)
		(property "Device Type" "TP_TDR_4P_FTS_MPKT4_H025P0200_IO_TP15_TP_TDR_4P_DIP"
			(at 1.30175 1.27 270)
			(unlocked yes)
			(layer "F.Fab")
			(hide yes)
			(effects
				(font
					(size 0.635 0.4064)
					(thickness 0.1524)
				)
			)
		)
		(duplicate_pad_numbers_are_jumpers no)
		(fp_line
			(start 2.54 3.81)
			(end 2.54 3.6703)
			(stroke
				(width 0.1524)
				(type default)
			)
			(layer "F.SilkS")
		)
		(fp_line
			(start 2.54 1.4097)
			(end 2.54 1.1303)
			(stroke
				(width 0.1524)
				(type default)
			)
			(layer "F.SilkS")
		)
		(fp_line
			(start 2.54 -1.1303)
			(end 2.54 -1.27)
			(stroke
				(width 0.1524)
				(type default)
			)
			(layer "F.SilkS")
		)
		(fp_line
			(start 2.54 -1.27)
			(end 0 -1.27)
			(stroke
				(width 0.1524)
				(type default)
			)
			(layer "F.SilkS")
		)
		(fp_line
			(start 0 3.81)
			(end 2.54 3.81)
			(stroke
				(width 0.1524)
				(type default)
			)
			(layer "F.SilkS")
		)
		(fp_line
			(start 0 3.175)
			(end 0 3.81)
			(stroke
				(width 0.1524)
				(type default)
			)
			(layer "F.SilkS")
		)
		(fp_line
			(start 0 0.635)
			(end 0 1.905)
			(stroke
				(width 0.1524)
				(type default)
			)
			(layer "F.SilkS")
		)
		(fp_line
			(start 0 -1.27)
			(end 0 -0.635)
			(stroke
				(width 0.1524)
				(type default)
			)
			(layer "F.SilkS")
		)
		(fp_poly
			(pts
				(xy -0.761746 0) (xy -2.285746 -0.762) (xy -2.285746 0.762)
			)
			(stroke
				(width 0)
				(type default)
			)
			(fill yes)
			(layer "F.SilkS")
		)
		(fp_line
			(start 2.54 3.81)
			(end 2.54 -1.27)
			(stroke
				(width 0.1)
				(type default)
			)
			(layer "F.Fab")
		)
		(fp_line
			(start 2.54 -1.27)
			(end 0 -1.27)
			(stroke
				(width 0.1)
				(type default)
			)
			(layer "F.Fab")
		)
		(fp_line
			(start 0 3.81)
			(end 2.54 3.81)
			(stroke
				(width 0.1)
				(type default)
			)
			(layer "F.Fab")
		)
		(fp_line
			(start 0 -1.27)
			(end 0 3.81)
			(stroke
				(width 0.1)
				(type default)
			)
			(layer "F.Fab")
		)
		(fp_poly
			(pts
				(xy -0.761746 0) (xy -2.285746 -0.762) (xy -2.285746 0.762)
			)
			(stroke
				(width 0)
				(type default)
			)
			(fill yes)
			(layer "F.Fab")
		)
		(pad "1" thru_hole circle
			(at 0 0 180)
			(size 1.0033 1.0033)
			(drill 0.249936)
			(layers "*.Cu" "*.Mask")
			(remove_unused_layers no)
			(net "TDR_DIFF_85_IN2_DIP")
			(clearance 0.10795)
			(thermal_gap 0.10795)
			(padstack
				(mode front_inner_back)
				(layer "Inner"
					(shape circle)
					(size 0.8001 0.8001)
					(clearance 0.1524)
				)
				(layer "B.Cu"
					(shape circle)
					(size 1.0033 1.0033)
					(clearance 0.10795)
				)
			)
		)
		(pad "2" thru_hole circle
			(at 2.54 0 180)
			(size 1.9939 1.9939)
			(drill 0.249936)
			(layers "*.Cu" "*.Mask")
			(remove_unused_layers no)
			(net "COUPON_GND1")
			(clearance 0.10795)
			(thermal_gap 0.10795)
			(padstack
				(mode front_inner_back)
				(layer "Inner"
					(shape circle)
					(size 0.8001 0.8001)
					(clearance 0.1524)
				)
				(layer "B.Cu"
					(shape circle)
					(size 1.9939 1.9939)
					(clearance 0.10795)
				)
			)
		)
		(pad "3" thru_hole circle
			(at 2.54 2.54 180)
			(size 1.9939 1.9939)
			(drill 0.249936)
			(layers "*.Cu" "*.Mask")
			(remove_unused_layers no)
			(net "COUPON_GND1")
			(clearance 0.10795)
			(thermal_gap 0.10795)
			(padstack
				(mode front_inner_back)
				(layer "Inner"
					(shape circle)
					(size 0.8001 0.8001)
					(clearance 0.1524)
				)
				(layer "B.Cu"
					(shape circle)
					(size 1.9939 1.9939)
					(clearance 0.10795)
				)
			)
		)
		(pad "4" thru_hole circle
			(at 0 2.54 180)
			(size 1.0033 1.0033)
			(drill 0.249936)
			(layers "*.Cu" "*.Mask")
			(remove_unused_layers no)
			(net "TDR_DIFF_85_IN2_DIN")
			(clearance 0.10795)
			(thermal_gap 0.10795)
			(padstack
				(mode front_inner_back)
				(layer "Inner"
					(shape circle)
					(size 0.8001 0.8001)
					(clearance 0.1524)
				)
				(layer "B.Cu"
					(shape circle)
					(size 1.0033 1.0033)
					(clearance 0.10795)
				)
			)
		)
	)
	(footprint ""
		(layer "F.Cu")
		(at 127.33401 -137.01776 180)
		(property "Reference" "PU26"
			(at 2.605024 -2.84226 0)
			(unlocked yes)
			(layer "F.SilkS")
			(effects
				(font
					(size 0.7874 0.5842)
					(thickness 0.1524)
				)
				(justify left)
			)
		)
		(property "Value" ""
			(at 0 0 180)
			(layer "F.Fab")
			(effects
				(font
					(size 1.27 1.27)
				)
			)
		)
		(duplicate_pad_numbers_are_jumpers no)
		(fp_line
			(start 1.943608 1.549908)
			(end -1.943608 1.549908)
			(stroke
				(width 0.1524)
				(type default)
			)
			(layer "F.SilkS")
		)
		(fp_line
			(start 1.943608 -1.549908)
			(end 1.943608 1.549908)
			(stroke
				(width 0.1524)
				(type default)
			)
			(layer "F.SilkS")
		)
		(fp_line
			(start -1.943608 1.549908)
			(end -1.943608 -1.549908)
			(stroke
				(width 0.1524)
				(type default)
			)
			(layer "F.SilkS")
		)
		(fp_line
			(start -1.943608 -1.549908)
			(end 1.943608 -1.549908)
			(stroke
				(width 0.1524)
				(type default)
			)
			(layer "F.SilkS")
		)
		(fp_poly
			(pts
				(xy -2.019808 -1.549908) (xy -1.257808 -1.549908) (xy -1.257808 -1.880108) (xy -2.019808 -1.880108)
			)
			(stroke
				(width 0)
				(type default)
			)
			(fill yes)
			(layer "F.SilkS")
		)
		(fp_line
			(start 1.549908 1.549908)
			(end -1.549908 1.549908)
			(stroke
				(width 0.1)
				(type default)
			)
			(layer "F.Fab")
		)
		(fp_line
			(start 1.549908 -1.549908)
			(end 1.549908 1.549908)
			(stroke
				(width 0.1)
				(type default)
			)
			(layer "F.Fab")
		)
		(fp_line
			(start -1.549908 1.549908)
			(end -1.549908 -1.549908)
			(stroke
				(width 0.1)
				(type default)
			)
			(layer "F.Fab")
		)
		(fp_line
			(start -1.549908 -1.549908)
			(end 1.549908 -1.549908)
			(stroke
				(width 0.1)
				(type default)
			)
			(layer "F.Fab")
		)
		(fp_poly
			(pts
				(xy -2.019808 -1.549908) (xy -1.257808 -1.549908) (xy -1.257808 -1.880108) (xy -2.019808 -1.880108)
			)
			(stroke
				(width 0)
				(type default)
			)
			(fill yes)
			(layer "F.Fab")
		)
		(pad "1" smd rect
			(at -1.500124 -1.249934 90)
			(size 0.2794 0.6096)
			(layers "F.Cu" "F.Mask" "F.Paste")
			(net "P12V_NIC2_R")
		)
		(pad "2" smd rect
			(at -1.500124 -0.750062 90)
			(size 0.2794 0.6096)
			(layers "F.Cu" "F.Mask" "F.Paste")
			(net "P12V_NIC2_R")
		)
		(pad "3" smd rect
			(at -1.500124 -0.249936 90)
			(size 0.2794 0.6096)
			(layers "F.Cu" "F.Mask" "F.Paste")
			(net "P12V_NIC2_R")
		)
		(pad "4" smd rect
			(at -1.500124 0.249936 90)
			(size 0.2794 0.6096)
			(layers "F.Cu" "F.Mask" "F.Paste")
			(net "P12V_NIC2_R")
		)
		(pad "5" smd rect
			(at -1.500124 0.750062 90)
			(size 0.2794 0.6096)
			(layers "F.Cu" "F.Mask" "F.Paste")
			(net "P12V_NIC2_R")
		)
		(pad "6" smd rect
			(at -1.500124 1.249934 90)
			(size 0.2794 0.6096)
			(layers "F.Cu" "F.Mask" "F.Paste")
			(net "GND")
		)
		(pad "7" smd rect
			(at 1.500124 1.249934 90)
			(size 0.2794 0.6096)
			(layers "F.Cu" "F.Mask" "F.Paste")
			(net "P12V_NIC2_SS")
		)
		(pad "8" smd rect
			(at 1.500124 0.750062 90)
			(size 0.2794 0.6096)
			(layers "F.Cu" "F.Mask" "F.Paste")
			(net "PWRGD_P12V_NIC2")
		)
		(pad "9" smd rect
			(at 1.500124 0.249936 90)
			(size 0.2794 0.6096)
			(layers "F.Cu" "F.Mask" "F.Paste")
			(net "P12V_NIC2_OCP")
		)
		(pad "10" smd rect
			(at 1.500124 -0.249936 90)
			(size 0.2794 0.6096)
			(layers "F.Cu" "F.Mask" "F.Paste")
			(net "P5V_AUX")
		)
		(pad "11" smd rect
			(at 1.500124 -0.750062 90)
			(size 0.2794 0.6096)
			(layers "F.Cu" "F.Mask" "F.Paste")
			(net "P12V_NIC2_EN_R")
		)
		(pad "12" smd rect
			(at 1.500124 -1.249934 90)
			(size 0.2794 0.6096)
			(layers "F.Cu" "F.Mask" "F.Paste")
			(net "P12V_AUX")
		)
		(pad "13" smd rect
			(at 0 0 180)
			(size 1.9812 2.7178)
			(layers "F.Cu" "F.Mask" "F.Paste")
			(net "P12V_AUX")
		)
		(zone
			(layer "F.Cu")
			(hatch none 0.5)
			(connect_pads
				(clearance 0)
			)
			(min_thickness 0.25)
			(keepout
				(tracks not_allowed)
				(vias allowed)
				(pads allowed)
				(copperpour not_allowed)
				(footprints allowed)
			)
			(placement
				(enabled no)
				(sheetname "")
			)
			(fill
				(thermal_gap 0.5)
				(thermal_bridge_width 0.5)
				(island_removal_mode 0)
			)
			(polygon
				(pts
					(xy 126.19101 -135.46836) (xy 126.19101 -135.59536) (xy 126.19101 -138.56716) (xy 126.19101 -138.567668)
					(xy 128.47701 -138.567668) (xy 128.47701 -138.56716) (xy 128.47701 -138.44016) (xy 128.47701 -137.01776)
					(xy 128.37541 -137.01776) (xy 128.37541 -138.44016) (xy 126.29261 -138.44016) (xy 126.29261 -135.59536)
					(xy 128.37541 -135.59536) (xy 128.37541 -136.99236) (xy 128.47701 -136.99236) (xy 128.47701 -135.59536)
					(xy 128.47701 -135.46836) (xy 128.47701 -135.467852) (xy 126.19101 -135.467852)
				)
			)
		)
	)
	(footprint ""
		(layer "F.Cu")
		(at 250.1265 -25.432004 -90)
		(property "Reference" "C973"
			(at 0 0 270)
			(layer "F.SilkS")
			(hide yes)
			(effects
				(font
					(size 1.27 1.27)
				)
			)
		)
		(property "Value" ""
			(at 0 0 270)
			(layer "F.Fab")
			(effects
				(font
					(size 1.27 1.27)
				)
			)
		)
		(duplicate_pad_numbers_are_jumpers no)
		(fp_line
			(start -0.7874 0.4064)
			(end -0.7874 -0.4064)
			(stroke
				(width 0.1524)
				(type default)
			)
			(layer "F.SilkS")
		)
		(fp_line
			(start 0.7874 0.4064)
			(end -0.7874 0.4064)
			(stroke
				(width 0.1524)
				(type default)
			)
			(layer "F.SilkS")
		)
		(fp_line
			(start -0.7874 -0.4064)
			(end 0.7874 -0.4064)
			(stroke
				(width 0.1524)
				(type default)
			)
			(layer "F.SilkS")
		)
		(fp_line
			(start 0.7874 -0.4064)
			(end 0.7874 0.4064)
			(stroke
				(width 0.1524)
				(type default)
			)
			(layer "F.SilkS")
		)
		(fp_line
			(start -0.67945 0.3048)
			(end -0.67945 -0.305054)
			(stroke
				(width 0.1)
				(type default)
			)
			(layer "F.Fab")
		)
		(fp_line
			(start -0.12065 0.3048)
			(end -0.67945 0.3048)
			(stroke
				(width 0.1)
				(type default)
			)
			(layer "F.Fab")
		)
		(fp_line
			(start 0.120396 0.3048)
			(end 0.120396 0.2794)
			(stroke
				(width 0.1)
				(type default)
			)
			(layer "F.Fab")
		)
		(fp_line
			(start 0.67945 0.3048)
			(end 0.120396 0.3048)
			(stroke
				(width 0.1)
				(type default)
			)
			(layer "F.Fab")
		)
		(fp_line
			(start -0.12065 0.2794)
			(end -0.12065 0.3048)
			(stroke
				(width 0.1)
				(type default)
			)
			(layer "F.Fab")
		)
		(fp_line
			(start 0.120396 0.2794)
			(end -0.12065 0.2794)
			(stroke
				(width 0.1)
				(type default)
			)
			(layer "F.Fab")
		)
		(fp_line
			(start -0.12065 -0.2794)
			(end 0.12065 -0.2794)
			(stroke
				(width 0.1)
				(type default)
			)
			(layer "F.Fab")
		)
		(fp_line
			(start 0.12065 -0.2794)
			(end 0.12065 -0.3048)
			(stroke
				(width 0.1)
				(type default)
			)
			(layer "F.Fab")
		)
		(fp_line
			(start 0.12065 -0.3048)
			(end 0.67945 -0.3048)
			(stroke
				(width 0.1)
				(type default)
			)
			(layer "F.Fab")
		)
		(fp_line
			(start 0.67945 -0.3048)
			(end 0.67945 0.3048)
			(stroke
				(width 0.1)
				(type default)
			)
			(layer "F.Fab")
		)
		(fp_line
			(start -0.67945 -0.305054)
			(end -0.12065 -0.305054)
			(stroke
				(width 0.1)
				(type default)
			)
			(layer "F.Fab")
		)
		(fp_line
			(start -0.12065 -0.305054)
			(end -0.12065 -0.2794)
			(stroke
				(width 0.1)
				(type default)
			)
			(layer "F.Fab")
		)
		(pad "1" smd circle
			(at -0.40005 0 270)
			(size 0 0)
			(layers "F.Cu" "F.Mask" "F.Paste")
			(net "GND")
		)
		(pad "2" smd circle
			(at 0.40005 0 270)
			(size 0 0)
			(layers "F.Cu" "F.Mask" "F.Paste")
			(net "P3V3_SSD8")
		)
	)
	(footprint ""
		(layer "F.Cu")
		(at 356.182422 -279.486868 -90)
		(property "Reference" "PR159"
			(at 0 0 270)
			(layer "F.SilkS")
			(hide yes)
			(effects
				(font
					(size 1.27 1.27)
				)
			)
		)
		(property "Value" ""
			(at 0 0 270)
			(layer "F.Fab")
			(effects
				(font
					(size 1.27 1.27)
				)
			)
		)
		(duplicate_pad_numbers_are_jumpers no)
		(fp_line
			(start -0.7874 0.4064)
			(end -0.7874 -0.4064)
			(stroke
				(width 0.1524)
				(type default)
			)
			(layer "F.SilkS")
		)
		(fp_line
			(start 0.7874 0.4064)
			(end -0.7874 0.4064)
			(stroke
				(width 0.1524)
				(type default)
			)
			(layer "F.SilkS")
		)
		(fp_line
			(start -0.7874 -0.4064)
			(end 0.7874 -0.4064)
			(stroke
				(width 0.1524)
				(type default)
			)
			(layer "F.SilkS")
		)
		(fp_line
			(start 0.7874 -0.4064)
			(end 0.7874 0.4064)
			(stroke
				(width 0.1524)
				(type default)
			)
			(layer "F.SilkS")
		)
		(fp_line
			(start -0.67945 0.3048)
			(end -0.67945 -0.305054)
			(stroke
				(width 0.1)
				(type default)
			)
			(layer "F.Fab")
		)
		(fp_line
			(start -0.12065 0.3048)
			(end -0.67945 0.3048)
			(stroke
				(width 0.1)
				(type default)
			)
			(layer "F.Fab")
		)
		(fp_line
			(start 0.120396 0.3048)
			(end 0.120396 0.2794)
			(stroke
				(width 0.1)
				(type default)
			)
			(layer "F.Fab")
		)
		(fp_line
			(start 0.67945 0.3048)
			(end 0.120396 0.3048)
			(stroke
				(width 0.1)
				(type default)
			)
			(layer "F.Fab")
		)
		(fp_line
			(start -0.12065 0.2794)
			(end -0.12065 0.3048)
			(stroke
				(width 0.1)
				(type default)
			)
			(layer "F.Fab")
		)
		(fp_line
			(start 0.120396 0.2794)
			(end -0.12065 0.2794)
			(stroke
				(width 0.1)
				(type default)
			)
			(layer "F.Fab")
		)
		(fp_line
			(start -0.12065 -0.2794)
			(end 0.12065 -0.2794)
			(stroke
				(width 0.1)
				(type default)
			)
			(layer "F.Fab")
		)
		(fp_line
			(start 0.12065 -0.2794)
			(end 0.12065 -0.3048)
			(stroke
				(width 0.1)
				(type default)
			)
			(layer "F.Fab")
		)
		(fp_line
			(start 0.12065 -0.3048)
			(end 0.67945 -0.3048)
			(stroke
				(width 0.1)
				(type default)
			)
			(layer "F.Fab")
		)
		(fp_line
			(start 0.67945 -0.3048)
			(end 0.67945 0.3048)
			(stroke
				(width 0.1)
				(type default)
			)
			(layer "F.Fab")
		)
		(fp_line
			(start -0.67945 -0.305054)
			(end -0.12065 -0.305054)
			(stroke
				(width 0.1)
				(type default)
			)
			(layer "F.Fab")
		)
		(fp_line
			(start -0.12065 -0.305054)
			(end -0.12065 -0.2794)
			(stroke
				(width 0.1)
				(type default)
			)
			(layer "F.Fab")
		)
		(pad "1" smd circle
			(at -0.40005 0 270)
			(size 0 0)
			(layers "F.Cu" "F.Mask" "F.Paste")
			(net "P0V8_PEX3_LSET1")
		)
		(pad "2" smd circle
			(at 0.40005 0 270)
			(size 0 0)
			(layers "F.Cu" "F.Mask" "F.Paste")
			(net "GND")
		)
	)
	(footprint ""
		(layer "F.Cu")
		(at 347.481652 -303.649634 90)
		(property "Reference" "PC167"
			(at 0 0 90)
			(layer "F.SilkS")
			(hide yes)
			(effects
				(font
					(size 1.27 1.27)
				)
			)
		)
		(property "Value" ""
			(at 0 0 90)
			(layer "F.Fab")
			(effects
				(font
					(size 1.27 1.27)
				)
			)
		)
		(duplicate_pad_numbers_are_jumpers no)
		(fp_line
			(start 1.524 -0.762)
			(end 1.524 0.762)
			(stroke
				(width 0.1524)
				(type default)
			)
			(layer "F.SilkS")
		)
		(fp_line
			(start -1.524 -0.762)
			(end 1.524 -0.762)
			(stroke
				(width 0.1524)
				(type default)
			)
			(layer "F.SilkS")
		)
		(fp_line
			(start 1.524 0.762)
			(end -1.524 0.762)
			(stroke
				(width 0.1524)
				(type default)
			)
			(layer "F.SilkS")
		)
		(fp_line
			(start -1.524 0.762)
			(end -1.524 -0.762)
			(stroke
				(width 0.1524)
				(type default)
			)
			(layer "F.SilkS")
		)
		(fp_line
			(start 1.1049 -0.724916)
			(end -1.1049 -0.724916)
			(stroke
				(width 0.1)
				(type default)
			)
			(layer "F.Fab")
		)
		(fp_line
			(start -1.1049 -0.724916)
			(end -1.1049 0.724916)
			(stroke
				(width 0.1)
				(type default)
			)
			(layer "F.Fab")
		)
		(fp_line
			(start 1.1049 0.724916)
			(end 1.1049 -0.724916)
			(stroke
				(width 0.1)
				(type default)
			)
			(layer "F.Fab")
		)
		(fp_line
			(start -1.1049 0.724916)
			(end 1.1049 0.724916)
			(stroke
				(width 0.1)
				(type default)
			)
			(layer "F.Fab")
		)
		(pad "1" smd rect
			(at -0.889 0 270)
			(size 1.016 1.27)
			(layers "F.Cu" "F.Mask" "F.Paste")
			(net "P0V8_PEX2")
		)
		(pad "2" smd rect
			(at 0.889 0 270)
			(size 1.016 1.27)
			(layers "F.Cu" "F.Mask" "F.Paste")
			(net "GND")
		)
	)
	(footprint ""
		(layer "F.Cu")
		(at 409.157932 -386.54101 90)
		(property "Reference" "C4162"
			(at 0 0 90)
			(layer "F.SilkS")
			(hide yes)
			(effects
				(font
					(size 1.27 1.27)
				)
			)
		)
		(property "Value" ""
			(at 0 0 90)
			(layer "F.Fab")
			(effects
				(font
					(size 1.27 1.27)
				)
			)
		)
		(duplicate_pad_numbers_are_jumpers no)
		(fp_line
			(start 0.7874 -0.4064)
			(end 0.7874 0.4064)
			(stroke
				(width 0.1524)
				(type default)
			)
			(layer "F.SilkS")
		)
		(fp_line
			(start -0.7874 -0.4064)
			(end 0.7874 -0.4064)
			(stroke
				(width 0.1524)
				(type default)
			)
			(layer "F.SilkS")
		)
		(fp_line
			(start 0.7874 0.4064)
			(end -0.7874 0.4064)
			(stroke
				(width 0.1524)
				(type default)
			)
			(layer "F.SilkS")
		)
		(fp_line
			(start -0.7874 0.4064)
			(end -0.7874 -0.4064)
			(stroke
				(width 0.1524)
				(type default)
			)
			(layer "F.SilkS")
		)
		(fp_line
			(start -0.12065 -0.305054)
			(end -0.12065 -0.2794)
			(stroke
				(width 0.1)
				(type default)
			)
			(layer "F.Fab")
		)
		(fp_line
			(start -0.67945 -0.305054)
			(end -0.12065 -0.305054)
			(stroke
				(width 0.1)
				(type default)
			)
			(layer "F.Fab")
		)
		(fp_line
			(start 0.67945 -0.3048)
			(end 0.67945 0.3048)
			(stroke
				(width 0.1)
				(type default)
			)
			(layer "F.Fab")
		)
		(fp_line
			(start 0.12065 -0.3048)
			(end 0.67945 -0.3048)
			(stroke
				(width 0.1)
				(type default)
			)
			(layer "F.Fab")
		)
		(fp_line
			(start 0.12065 -0.2794)
			(end 0.12065 -0.3048)
			(stroke
				(width 0.1)
				(type default)
			)
			(layer "F.Fab")
		)
		(fp_line
			(start -0.12065 -0.2794)
			(end 0.12065 -0.2794)
			(stroke
				(width 0.1)
				(type default)
			)
			(layer "F.Fab")
		)
		(fp_line
			(start 0.120396 0.2794)
			(end -0.12065 0.2794)
			(stroke
				(width 0.1)
				(type default)
			)
			(layer "F.Fab")
		)
		(fp_line
			(start -0.12065 0.2794)
			(end -0.12065 0.3048)
			(stroke
				(width 0.1)
				(type default)
			)
			(layer "F.Fab")
		)
		(fp_line
			(start 0.67945 0.3048)
			(end 0.120396 0.3048)
			(stroke
				(width 0.1)
				(type default)
			)
			(layer "F.Fab")
		)
		(fp_line
			(start 0.120396 0.3048)
			(end 0.120396 0.2794)
			(stroke
				(width 0.1)
				(type default)
			)
			(layer "F.Fab")
		)
		(fp_line
			(start -0.12065 0.3048)
			(end -0.67945 0.3048)
			(stroke
				(width 0.1)
				(type default)
			)
			(layer "F.Fab")
		)
		(fp_line
			(start -0.67945 0.3048)
			(end -0.67945 -0.305054)
			(stroke
				(width 0.1)
				(type default)
			)
			(layer "F.Fab")
		)
		(pad "1" smd circle
			(at -0.40005 0 90)
			(size 0 0)
			(layers "F.Cu" "F.Mask" "F.Paste")
			(net "GND")
		)
		(pad "2" smd circle
			(at 0.40005 0 90)
			(size 0 0)
			(layers "F.Cu" "F.Mask" "F.Paste")
			(net "GPU_3V3IO_RSVD4")
		)
	)
	(footprint ""
		(layer "F.Cu")
		(at 351.288096 -293.816786 -90)
		(property "Reference" "PC180"
			(at 0 0 270)
			(layer "F.SilkS")
			(hide yes)
			(effects
				(font
					(size 1.27 1.27)
				)
			)
		)
		(property "Value" ""
			(at 0 0 270)
			(layer "F.Fab")
			(effects
				(font
					(size 1.27 1.27)
				)
			)
		)
		(duplicate_pad_numbers_are_jumpers no)
		(fp_line
			(start -0.7874 0.4064)
			(end -0.7874 -0.4064)
			(stroke
				(width 0.1524)
				(type default)
			)
			(layer "F.SilkS")
		)
		(fp_line
			(start 0.7874 0.4064)
			(end -0.7874 0.4064)
			(stroke
				(width 0.1524)
				(type default)
			)
			(layer "F.SilkS")
		)
		(fp_line
			(start -0.7874 -0.4064)
			(end 0.7874 -0.4064)
			(stroke
				(width 0.1524)
				(type default)
			)
			(layer "F.SilkS")
		)
		(fp_line
			(start 0.7874 -0.4064)
			(end 0.7874 0.4064)
			(stroke
				(width 0.1524)
				(type default)
			)
			(layer "F.SilkS")
		)
		(fp_line
			(start -0.67945 0.3048)
			(end -0.67945 -0.305054)
			(stroke
				(width 0.1)
				(type default)
			)
			(layer "F.Fab")
		)
		(fp_line
			(start -0.12065 0.3048)
			(end -0.67945 0.3048)
			(stroke
				(width 0.1)
				(type default)
			)
			(layer "F.Fab")
		)
		(fp_line
			(start 0.120396 0.3048)
			(end 0.120396 0.2794)
			(stroke
				(width 0.1)
				(type default)
			)
			(layer "F.Fab")
		)
		(fp_line
			(start 0.67945 0.3048)
			(end 0.120396 0.3048)
			(stroke
				(width 0.1)
				(type default)
			)
			(layer "F.Fab")
		)
		(fp_line
			(start -0.12065 0.2794)
			(end -0.12065 0.3048)
			(stroke
				(width 0.1)
				(type default)
			)
			(layer "F.Fab")
		)
		(fp_line
			(start 0.120396 0.2794)
			(end -0.12065 0.2794)
			(stroke
				(width 0.1)
				(type default)
			)
			(layer "F.Fab")
		)
		(fp_line
			(start -0.12065 -0.2794)
			(end 0.12065 -0.2794)
			(stroke
				(width 0.1)
				(type default)
			)
			(layer "F.Fab")
		)
		(fp_line
			(start 0.12065 -0.2794)
			(end 0.12065 -0.3048)
			(stroke
				(width 0.1)
				(type default)
			)
			(layer "F.Fab")
		)
		(fp_line
			(start 0.12065 -0.3048)
			(end 0.67945 -0.3048)
			(stroke
				(width 0.1)
				(type default)
			)
			(layer "F.Fab")
		)
		(fp_line
			(start 0.67945 -0.3048)
			(end 0.67945 0.3048)
			(stroke
				(width 0.1)
				(type default)
			)
			(layer "F.Fab")
		)
		(fp_line
			(start -0.67945 -0.305054)
			(end -0.12065 -0.305054)
			(stroke
				(width 0.1)
				(type default)
			)
			(layer "F.Fab")
		)
		(fp_line
			(start -0.12065 -0.305054)
			(end -0.12065 -0.2794)
			(stroke
				(width 0.1)
				(type default)
			)
			(layer "F.Fab")
		)
		(pad "1" smd circle
			(at -0.40005 0 270)
			(size 0 0)
			(layers "F.Cu" "F.Mask" "F.Paste")
			(net "P0V8_PEX3")
		)
		(pad "2" smd circle
			(at 0.40005 0 270)
			(size 0 0)
			(layers "F.Cu" "F.Mask" "F.Paste")
			(net "GND")
		)
	)
	(footprint ""
		(layer "F.Cu")
		(at 17.792446 -28.225242 180)
		(property "Reference" "C72"
			(at 0 0 180)
			(layer "F.SilkS")
			(hide yes)
			(effects
				(font
					(size 1.27 1.27)
				)
			)
		)
		(property "Value" ""
			(at 0 0 180)
			(layer "F.Fab")
			(effects
				(font
					(size 1.27 1.27)
				)
			)
		)
		(duplicate_pad_numbers_are_jumpers no)
		(fp_line
			(start 0.299974 0.150114)
			(end -0.299974 0.150114)
			(stroke
				(width 0.1)
				(type default)
			)
			(layer "F.Fab")
		)
		(fp_line
			(start 0.299974 -0.150114)
			(end 0.299974 0.150114)
			(stroke
				(width 0.1)
				(type default)
			)
			(layer "F.Fab")
		)
		(fp_line
			(start -0.299974 0.150114)
			(end -0.299974 -0.150114)
			(stroke
				(width 0.1)
				(type default)
			)
			(layer "F.Fab")
		)
		(fp_line
			(start -0.299974 -0.150114)
			(end 0.299974 -0.150114)
			(stroke
				(width 0.1)
				(type default)
			)
			(layer "F.Fab")
		)
		(pad "1" smd rect
			(at -0.2667 0 180)
			(size 0.3048 0.381)
			(layers "F.Cu" "F.Mask" "F.Paste")
			(net "P5E_PEX0_STN2_TX_DN<44>")
		)
		(pad "2" smd rect
			(at 0.2667 0 180)
			(size 0.3048 0.381)
			(layers "F.Cu" "F.Mask" "F.Paste")
			(net "P5E_PEX0_STN2_TX_C_DN<44>")
		)
	)
	(footprint ""
		(layer "F.Cu")
		(at 407.295096 -101.782372 180)
		(property "Reference" "R378"
			(at 0 0 180)
			(layer "F.SilkS")
			(hide yes)
			(effects
				(font
					(size 1.27 1.27)
				)
			)
		)
		(property "Value" ""
			(at 0 0 180)
			(layer "F.Fab")
			(effects
				(font
					(size 1.27 1.27)
				)
			)
		)
		(duplicate_pad_numbers_are_jumpers no)
		(fp_line
			(start 0.7874 0.4064)
			(end -0.7874 0.4064)
			(stroke
				(width 0.1524)
				(type default)
			)
			(layer "F.SilkS")
		)
		(fp_line
			(start 0.7874 -0.4064)
			(end 0.7874 0.4064)
			(stroke
				(width 0.1524)
				(type default)
			)
			(layer "F.SilkS")
		)
		(fp_line
			(start -0.7874 0.4064)
			(end -0.7874 -0.4064)
			(stroke
				(width 0.1524)
				(type default)
			)
			(layer "F.SilkS")
		)
		(fp_line
			(start -0.7874 -0.4064)
			(end 0.7874 -0.4064)
			(stroke
				(width 0.1524)
				(type default)
			)
			(layer "F.SilkS")
		)
		(fp_line
			(start 0.67945 0.3048)
			(end 0.120396 0.3048)
			(stroke
				(width 0.1)
				(type default)
			)
			(layer "F.Fab")
		)
		(fp_line
			(start 0.67945 -0.3048)
			(end 0.67945 0.3048)
			(stroke
				(width 0.1)
				(type default)
			)
			(layer "F.Fab")
		)
		(fp_line
			(start 0.12065 -0.2794)
			(end 0.12065 -0.3048)
			(stroke
				(width 0.1)
				(type default)
			)
			(layer "F.Fab")
		)
		(fp_line
			(start 0.12065 -0.3048)
			(end 0.67945 -0.3048)
			(stroke
				(width 0.1)
				(type default)
			)
			(layer "F.Fab")
		)
		(fp_line
			(start 0.120396 0.3048)
			(end 0.120396 0.2794)
			(stroke
				(width 0.1)
				(type default)
			)
			(layer "F.Fab")
		)
		(fp_line
			(start 0.120396 0.2794)
			(end -0.12065 0.2794)
			(stroke
				(width 0.1)
				(type default)
			)
			(layer "F.Fab")
		)
		(fp_line
			(start -0.12065 0.3048)
			(end -0.67945 0.3048)
			(stroke
				(width 0.1)
				(type default)
			)
			(layer "F.Fab")
		)
		(fp_line
			(start -0.12065 0.2794)
			(end -0.12065 0.3048)
			(stroke
				(width 0.1)
				(type default)
			)
			(layer "F.Fab")
		)
		(fp_line
			(start -0.12065 -0.2794)
			(end 0.12065 -0.2794)
			(stroke
				(width 0.1)
				(type default)
			)
			(layer "F.Fab")
		)
		(fp_line
			(start -0.12065 -0.305054)
			(end -0.12065 -0.2794)
			(stroke
				(width 0.1)
				(type default)
			)
			(layer "F.Fab")
		)
		(fp_line
			(start -0.67945 0.3048)
			(end -0.67945 -0.305054)
			(stroke
				(width 0.1)
				(type default)
			)
			(layer "F.Fab")
		)
		(fp_line
			(start -0.67945 -0.305054)
			(end -0.12065 -0.305054)
			(stroke
				(width 0.1)
				(type default)
			)
			(layer "F.Fab")
		)
		(pad "1" smd circle
			(at -0.40005 0 180)
			(size 0 0)
			(layers "F.Cu" "F.Mask" "F.Paste")
			(net "NCSI_NIC7_TX_EN")
		)
		(pad "2" smd circle
			(at 0.40005 0 180)
			(size 0 0)
			(layers "F.Cu" "F.Mask" "F.Paste")
			(net "GND")
		)
	)
	(footprint ""
		(layer "F.Cu")
		(at 428.837852 -356.244906 90)
		(property "Reference" "C806"
			(at 0 0 90)
			(layer "F.SilkS")
			(hide yes)
			(effects
				(font
					(size 1.27 1.27)
				)
			)
		)
		(property "Value" ""
			(at 0 0 90)
			(layer "F.Fab")
			(effects
				(font
					(size 1.27 1.27)
				)
			)
		)
		(duplicate_pad_numbers_are_jumpers no)
		(fp_line
			(start 0.299974 -0.150114)
			(end 0.299974 0.150114)
			(stroke
				(width 0.1)
				(type default)
			)
			(layer "F.Fab")
		)
		(fp_line
			(start -0.299974 -0.150114)
			(end 0.299974 -0.150114)
			(stroke
				(width 0.1)
				(type default)
			)
			(layer "F.Fab")
		)
		(fp_line
			(start 0.299974 0.150114)
			(end -0.299974 0.150114)
			(stroke
				(width 0.1)
				(type default)
			)
			(layer "F.Fab")
		)
		(fp_line
			(start -0.299974 0.150114)
			(end -0.299974 -0.150114)
			(stroke
				(width 0.1)
				(type default)
			)
			(layer "F.Fab")
		)
		(pad "1" smd rect
			(at -0.2667 0 90)
			(size 0.3048 0.381)
			(layers "F.Cu" "F.Mask" "F.Paste")
			(net "P5E_PEX3_STN7_TX_DP<121>")
		)
		(pad "2" smd rect
			(at 0.2667 0 90)
			(size 0.3048 0.381)
			(layers "F.Cu" "F.Mask" "F.Paste")
			(net "P5E_PEX3_STN7_TX_C_DP<121>")
		)
	)
	(footprint ""
		(layer "F.Cu")
		(at 14.286992 -456.423014 180)
		(property "Reference" "X9"
			(at -0.1778 -1.92913 180)
			(unlocked yes)
			(layer "F.SilkS")
			(effects
				(font
					(size 0.7874 0.5842)
					(thickness 0.1524)
				)
				(justify left)
			)
		)
		(property "Value" ""
			(at 0 0 180)
			(layer "F.Fab")
			(effects
				(font
					(size 1.27 1.27)
				)
			)
		)
		(property "Device Type" "TP_TDR_4P_FTS_MPKT4_H025P0200_IO_TP15_TP_TDR_4P_DIP"
			(at 1.30175 1.27 270)
			(unlocked yes)
			(layer "F.Fab")
			(hide yes)
			(effects
				(font
					(size 0.635 0.4064)
					(thickness 0.1524)
				)
			)
		)
		(property "User Part Number" "TP15"
			(at 1.30175 1.27 270)
			(unlocked yes)
			(layer "Cmts.User")
			(hide yes)
			(effects
				(font
					(size 0.635 0.4064)
					(thickness 0.1524)
				)
			)
		)
		(duplicate_pad_numbers_are_jumpers no)
		(fp_line
			(start 2.54 3.81)
			(end 2.54 3.6703)
			(stroke
				(width 0.1524)
				(type default)
			)
			(layer "F.SilkS")
		)
		(fp_line
			(start 2.54 1.4097)
			(end 2.54 1.1303)
			(stroke
				(width 0.1524)
				(type default)
			)
			(layer "F.SilkS")
		)
		(fp_line
			(start 2.54 -1.1303)
			(end 2.54 -1.27)
			(stroke
				(width 0.1524)
				(type default)
			)
			(layer "F.SilkS")
		)
		(fp_line
			(start 2.54 -1.27)
			(end 0 -1.27)
			(stroke
				(width 0.1524)
				(type default)
			)
			(layer "F.SilkS")
		)
		(fp_line
			(start 0 3.81)
			(end 2.54 3.81)
			(stroke
				(width 0.1524)
				(type default)
			)
			(layer "F.SilkS")
		)
		(fp_line
			(start 0 3.175)
			(end 0 3.81)
			(stroke
				(width 0.1524)
				(type default)
			)
			(layer "F.SilkS")
		)
		(fp_line
			(start 0 0.635)
			(end 0 1.905)
			(stroke
				(width 0.1524)
				(type default)
			)
			(layer "F.SilkS")
		)
		(fp_line
			(start 0 -1.27)
			(end 0 -0.635)
			(stroke
				(width 0.1524)
				(type default)
			)
			(layer "F.SilkS")
		)
		(fp_poly
			(pts
				(xy -0.761746 0) (xy -2.285746 -0.762) (xy -2.285746 0.762)
			)
			(stroke
				(width 0)
				(type default)
			)
			(fill yes)
			(layer "F.SilkS")
		)
		(fp_line
			(start 2.54 3.81)
			(end 2.54 -1.27)
			(stroke
				(width 0.1)
				(type default)
			)
			(layer "F.Fab")
		)
		(fp_line
			(start 2.54 -1.27)
			(end 0 -1.27)
			(stroke
				(width 0.1)
				(type default)
			)
			(layer "F.Fab")
		)
		(fp_line
			(start 0 3.81)
			(end 2.54 3.81)
			(stroke
				(width 0.1)
				(type default)
			)
			(layer "F.Fab")
		)
		(fp_line
			(start 0 -1.27)
			(end 0 3.81)
			(stroke
				(width 0.1)
				(type default)
			)
			(layer "F.Fab")
		)
		(fp_poly
			(pts
				(xy -0.761746 0) (xy -2.285746 -0.762) (xy -2.285746 0.762)
			)
			(stroke
				(width 0)
				(type default)
			)
			(fill yes)
			(layer "F.Fab")
		)
		(pad "1" thru_hole circle
			(at 0 0 180)
			(size 1.0033 1.0033)
			(drill 0.249936)
			(layers "*.Cu" "*.Mask")
			(remove_unused_layers no)
			(net "TDR_DIFF_85_IN1_DIN")
			(clearance 0.10795)
			(thermal_gap 0.10795)
			(padstack
				(mode front_inner_back)
				(layer "Inner"
					(shape circle)
					(size 0.8001 0.8001)
					(clearance 0.1524)
				)
				(layer "B.Cu"
					(shape circle)
					(size 1.0033 1.0033)
					(clearance 0.10795)
				)
			)
		)
		(pad "2" thru_hole circle
			(at 2.54 0 180)
			(size 1.9939 1.9939)
			(drill 0.249936)
			(layers "*.Cu" "*.Mask")
			(remove_unused_layers no)
			(net "COUPON_GND1")
			(clearance 0.10795)
			(thermal_gap 0.10795)
			(padstack
				(mode front_inner_back)
				(layer "Inner"
					(shape circle)
					(size 0.8001 0.8001)
					(clearance 0.1524)
				)
				(layer "B.Cu"
					(shape circle)
					(size 1.9939 1.9939)
					(clearance 0.10795)
				)
			)
		)
		(pad "3" thru_hole circle
			(at 2.54 2.54 180)
			(size 1.9939 1.9939)
			(drill 0.249936)
			(layers "*.Cu" "*.Mask")
			(remove_unused_layers no)
			(net "COUPON_GND1")
			(clearance 0.10795)
			(thermal_gap 0.10795)
			(padstack
				(mode front_inner_back)
				(layer "Inner"
					(shape circle)
					(size 0.8001 0.8001)
					(clearance 0.1524)
				)
				(layer "B.Cu"
					(shape circle)
					(size 1.9939 1.9939)
					(clearance 0.10795)
				)
			)
		)
		(pad "4" thru_hole circle
			(at 0 2.54 180)
			(size 1.0033 1.0033)
			(drill 0.249936)
			(layers "*.Cu" "*.Mask")
			(remove_unused_layers no)
			(net "TDR_DIFF_85_IN1_DIP")
			(clearance 0.10795)
			(thermal_gap 0.10795)
			(padstack
				(mode front_inner_back)
				(layer "Inner"
					(shape circle)
					(size 0.8001 0.8001)
					(clearance 0.1524)
				)
				(layer "B.Cu"
					(shape circle)
					(size 1.0033 1.0033)
					(clearance 0.10795)
				)
			)
		)
	)
	(footprint ""
		(layer "F.Cu")
		(at 374.567958 -54.067456)
		(property "Reference" "PR226"
			(at 0 0 0)
			(layer "F.SilkS")
			(hide yes)
			(effects
				(font
					(size 1.27 1.27)
				)
			)
		)
		(property "Value" ""
			(at 0 0 0)
			(layer "F.Fab")
			(effects
				(font
					(size 1.27 1.27)
				)
			)
		)
		(duplicate_pad_numbers_are_jumpers no)
		(fp_line
			(start -0.7874 -0.4064)
			(end 0.7874 -0.4064)
			(stroke
				(width 0.1524)
				(type default)
			)
			(layer "F.SilkS")
		)
		(fp_line
			(start -0.7874 0.4064)
			(end -0.7874 -0.4064)
			(stroke
				(width 0.1524)
				(type default)
			)
			(layer "F.SilkS")
		)
		(fp_line
			(start 0.7874 -0.4064)
			(end 0.7874 0.4064)
			(stroke
				(width 0.1524)
				(type default)
			)
			(layer "F.SilkS")
		)
		(fp_line
			(start 0.7874 0.4064)
			(end -0.7874 0.4064)
			(stroke
				(width 0.1524)
				(type default)
			)
			(layer "F.SilkS")
		)
		(fp_line
			(start -0.67945 -0.305054)
			(end -0.12065 -0.305054)
			(stroke
				(width 0.1)
				(type default)
			)
			(layer "F.Fab")
		)
		(fp_line
			(start -0.67945 0.3048)
			(end -0.67945 -0.305054)
			(stroke
				(width 0.1)
				(type default)
			)
			(layer "F.Fab")
		)
		(fp_line
			(start -0.12065 -0.305054)
			(end -0.12065 -0.2794)
			(stroke
				(width 0.1)
				(type default)
			)
			(layer "F.Fab")
		)
		(fp_line
			(start -0.12065 -0.2794)
			(end 0.12065 -0.2794)
			(stroke
				(width 0.1)
				(type default)
			)
			(layer "F.Fab")
		)
		(fp_line
			(start -0.12065 0.2794)
			(end -0.12065 0.3048)
			(stroke
				(width 0.1)
				(type default)
			)
			(layer "F.Fab")
		)
		(fp_line
			(start -0.12065 0.3048)
			(end -0.67945 0.3048)
			(stroke
				(width 0.1)
				(type default)
			)
			(layer "F.Fab")
		)
		(fp_line
			(start 0.120396 0.2794)
			(end -0.12065 0.2794)
			(stroke
				(width 0.1)
				(type default)
			)
			(layer "F.Fab")
		)
		(fp_line
			(start 0.120396 0.3048)
			(end 0.120396 0.2794)
			(stroke
				(width 0.1)
				(type default)
			)
			(layer "F.Fab")
		)
		(fp_line
			(start 0.12065 -0.3048)
			(end 0.67945 -0.3048)
			(stroke
				(width 0.1)
				(type default)
			)
			(layer "F.Fab")
		)
		(fp_line
			(start 0.12065 -0.2794)
			(end 0.12065 -0.3048)
			(stroke
				(width 0.1)
				(type default)
			)
			(layer "F.Fab")
		)
		(fp_line
			(start 0.67945 -0.3048)
			(end 0.67945 0.3048)
			(stroke
				(width 0.1)
				(type default)
			)
			(layer "F.Fab")
		)
		(fp_line
			(start 0.67945 0.3048)
			(end 0.120396 0.3048)
			(stroke
				(width 0.1)
				(type default)
			)
			(layer "F.Fab")
		)
		(pad "1" smd circle
			(at -0.40005 0)
			(size 0 0)
			(layers "F.Cu" "F.Mask" "F.Paste")
			(net "P12V_SSD12_OCP")
		)
		(pad "2" smd circle
			(at 0.40005 0)
			(size 0 0)
			(layers "F.Cu" "F.Mask" "F.Paste")
			(net "GND")
		)
	)
	(footprint ""
		(layer "F.Cu")
		(at 283.061156 -169.23385 180)
		(property "Reference" "C917"
			(at 0 0 180)
			(layer "F.SilkS")
			(hide yes)
			(effects
				(font
					(size 1.27 1.27)
				)
			)
		)
		(property "Value" ""
			(at 0 0 180)
			(layer "F.Fab")
			(effects
				(font
					(size 1.27 1.27)
				)
			)
		)
		(duplicate_pad_numbers_are_jumpers no)
		(fp_line
			(start 0.7874 0.4064)
			(end -0.7874 0.4064)
			(stroke
				(width 0.1524)
				(type default)
			)
			(layer "F.SilkS")
		)
		(fp_line
			(start 0.7874 -0.4064)
			(end 0.7874 0.4064)
			(stroke
				(width 0.1524)
				(type default)
			)
			(layer "F.SilkS")
		)
		(fp_line
			(start -0.7874 0.4064)
			(end -0.7874 -0.4064)
			(stroke
				(width 0.1524)
				(type default)
			)
			(layer "F.SilkS")
		)
		(fp_line
			(start -0.7874 -0.4064)
			(end 0.7874 -0.4064)
			(stroke
				(width 0.1524)
				(type default)
			)
			(layer "F.SilkS")
		)
		(fp_line
			(start 0.67945 0.3048)
			(end 0.120396 0.3048)
			(stroke
				(width 0.1)
				(type default)
			)
			(layer "F.Fab")
		)
		(fp_line
			(start 0.67945 -0.3048)
			(end 0.67945 0.3048)
			(stroke
				(width 0.1)
				(type default)
			)
			(layer "F.Fab")
		)
		(fp_line
			(start 0.12065 -0.2794)
			(end 0.12065 -0.3048)
			(stroke
				(width 0.1)
				(type default)
			)
			(layer "F.Fab")
		)
		(fp_line
			(start 0.12065 -0.3048)
			(end 0.67945 -0.3048)
			(stroke
				(width 0.1)
				(type default)
			)
			(layer "F.Fab")
		)
		(fp_line
			(start 0.120396 0.3048)
			(end 0.120396 0.2794)
			(stroke
				(width 0.1)
				(type default)
			)
			(layer "F.Fab")
		)
		(fp_line
			(start 0.120396 0.2794)
			(end -0.12065 0.2794)
			(stroke
				(width 0.1)
				(type default)
			)
			(layer "F.Fab")
		)
		(fp_line
			(start -0.12065 0.3048)
			(end -0.67945 0.3048)
			(stroke
				(width 0.1)
				(type default)
			)
			(layer "F.Fab")
		)
		(fp_line
			(start -0.12065 0.2794)
			(end -0.12065 0.3048)
			(stroke
				(width 0.1)
				(type default)
			)
			(layer "F.Fab")
		)
		(fp_line
			(start -0.12065 -0.2794)
			(end 0.12065 -0.2794)
			(stroke
				(width 0.1)
				(type default)
			)
			(layer "F.Fab")
		)
		(fp_line
			(start -0.12065 -0.305054)
			(end -0.12065 -0.2794)
			(stroke
				(width 0.1)
				(type default)
			)
			(layer "F.Fab")
		)
		(fp_line
			(start -0.67945 0.3048)
			(end -0.67945 -0.305054)
			(stroke
				(width 0.1)
				(type default)
			)
			(layer "F.Fab")
		)
		(fp_line
			(start -0.67945 -0.305054)
			(end -0.12065 -0.305054)
			(stroke
				(width 0.1)
				(type default)
			)
			(layer "F.Fab")
		)
		(pad "1" smd circle
			(at -0.40005 0 180)
			(size 0 0)
			(layers "F.Cu" "F.Mask" "F.Paste")
			(net "P3V3_AUX")
		)
		(pad "2" smd circle
			(at 0.40005 0 180)
			(size 0 0)
			(layers "F.Cu" "F.Mask" "F.Paste")
			(net "GND")
		)
	)
	(footprint ""
		(layer "F.Cu")
		(at 39.280592 -121.005346)
		(property "Reference" "C45"
			(at 0 0 0)
			(layer "F.SilkS")
			(hide yes)
			(effects
				(font
					(size 1.27 1.27)
				)
			)
		)
		(property "Value" ""
			(at 0 0 0)
			(layer "F.Fab")
			(effects
				(font
					(size 1.27 1.27)
				)
			)
		)
		(duplicate_pad_numbers_are_jumpers no)
		(fp_line
			(start -0.299974 -0.150114)
			(end 0.299974 -0.150114)
			(stroke
				(width 0.1)
				(type default)
			)
			(layer "F.Fab")
		)
		(fp_line
			(start -0.299974 0.150114)
			(end -0.299974 -0.150114)
			(stroke
				(width 0.1)
				(type default)
			)
			(layer "F.Fab")
		)
		(fp_line
			(start 0.299974 -0.150114)
			(end 0.299974 0.150114)
			(stroke
				(width 0.1)
				(type default)
			)
			(layer "F.Fab")
		)
		(fp_line
			(start 0.299974 0.150114)
			(end -0.299974 0.150114)
			(stroke
				(width 0.1)
				(type default)
			)
			(layer "F.Fab")
		)
		(pad "1" smd rect
			(at -0.2667 0)
			(size 0.3048 0.381)
			(layers "F.Cu" "F.Mask" "F.Paste")
			(net "P5E_PEX0_STN1_TX_DN<25>")
		)
		(pad "2" smd rect
			(at 0.2667 0)
			(size 0.3048 0.381)
			(layers "F.Cu" "F.Mask" "F.Paste")
			(net "P5E_PEX0_STN1_TX_C_DN<25>")
		)
	)
	(footprint ""
		(layer "F.Cu")
		(at 393.546838 -37.47516)
		(property "Reference" "R6122"
			(at 0 0 0)
			(layer "F.SilkS")
			(hide yes)
			(effects
				(font
					(size 1.27 1.27)
				)
			)
		)
		(property "Value" ""
			(at 0 0 0)
			(layer "F.Fab")
			(effects
				(font
					(size 1.27 1.27)
				)
			)
		)
		(duplicate_pad_numbers_are_jumpers no)
		(fp_line
			(start -0.7874 -0.4064)
			(end 0.7874 -0.4064)
			(stroke
				(width 0.1524)
				(type default)
			)
			(layer "F.SilkS")
		)
		(fp_line
			(start -0.7874 0.4064)
			(end -0.7874 -0.4064)
			(stroke
				(width 0.1524)
				(type default)
			)
			(layer "F.SilkS")
		)
		(fp_line
			(start 0.7874 -0.4064)
			(end 0.7874 0.4064)
			(stroke
				(width 0.1524)
				(type default)
			)
			(layer "F.SilkS")
		)
		(fp_line
			(start 0.7874 0.4064)
			(end -0.7874 0.4064)
			(stroke
				(width 0.1524)
				(type default)
			)
			(layer "F.SilkS")
		)
		(fp_line
			(start -0.67945 -0.305054)
			(end -0.12065 -0.305054)
			(stroke
				(width 0.1)
				(type default)
			)
			(layer "F.Fab")
		)
		(fp_line
			(start -0.67945 0.3048)
			(end -0.67945 -0.305054)
			(stroke
				(width 0.1)
				(type default)
			)
			(layer "F.Fab")
		)
		(fp_line
			(start -0.12065 -0.305054)
			(end -0.12065 -0.2794)
			(stroke
				(width 0.1)
				(type default)
			)
			(layer "F.Fab")
		)
		(fp_line
			(start -0.12065 -0.2794)
			(end 0.12065 -0.2794)
			(stroke
				(width 0.1)
				(type default)
			)
			(layer "F.Fab")
		)
		(fp_line
			(start -0.12065 0.2794)
			(end -0.12065 0.3048)
			(stroke
				(width 0.1)
				(type default)
			)
			(layer "F.Fab")
		)
		(fp_line
			(start -0.12065 0.3048)
			(end -0.67945 0.3048)
			(stroke
				(width 0.1)
				(type default)
			)
			(layer "F.Fab")
		)
		(fp_line
			(start 0.120396 0.2794)
			(end -0.12065 0.2794)
			(stroke
				(width 0.1)
				(type default)
			)
			(layer "F.Fab")
		)
		(fp_line
			(start 0.120396 0.3048)
			(end 0.120396 0.2794)
			(stroke
				(width 0.1)
				(type default)
			)
			(layer "F.Fab")
		)
		(fp_line
			(start 0.12065 -0.3048)
			(end 0.67945 -0.3048)
			(stroke
				(width 0.1)
				(type default)
			)
			(layer "F.Fab")
		)
		(fp_line
			(start 0.12065 -0.2794)
			(end 0.12065 -0.3048)
			(stroke
				(width 0.1)
				(type default)
			)
			(layer "F.Fab")
		)
		(fp_line
			(start 0.67945 -0.3048)
			(end 0.67945 0.3048)
			(stroke
				(width 0.1)
				(type default)
			)
			(layer "F.Fab")
		)
		(fp_line
			(start 0.67945 0.3048)
			(end 0.120396 0.3048)
			(stroke
				(width 0.1)
				(type default)
			)
			(layer "F.Fab")
		)
		(pad "1" smd circle
			(at -0.40005 0)
			(size 0 0)
			(layers "F.Cu" "F.Mask" "F.Paste")
			(net "P3V3_SSD14")
		)
		(pad "2" smd circle
			(at 0.40005 0)
			(size 0 0)
			(layers "F.Cu" "F.Mask" "F.Paste")
			(net "P3V3_SSD14_PG_G1")
		)
	)
	(footprint ""
		(layer "F.Cu")
		(at 213.730332 -223.382586 180)
		(property "Reference" "R4882"
			(at 0 0 180)
			(layer "F.SilkS")
			(hide yes)
			(effects
				(font
					(size 1.27 1.27)
				)
			)
		)
		(property "Value" ""
			(at 0 0 180)
			(layer "F.Fab")
			(effects
				(font
					(size 1.27 1.27)
				)
			)
		)
		(duplicate_pad_numbers_are_jumpers no)
		(fp_line
			(start 0.7874 0.4064)
			(end -0.7874 0.4064)
			(stroke
				(width 0.1524)
				(type default)
			)
			(layer "F.SilkS")
		)
		(fp_line
			(start 0.7874 -0.4064)
			(end 0.7874 0.4064)
			(stroke
				(width 0.1524)
				(type default)
			)
			(layer "F.SilkS")
		)
		(fp_line
			(start -0.7874 0.4064)
			(end -0.7874 -0.4064)
			(stroke
				(width 0.1524)
				(type default)
			)
			(layer "F.SilkS")
		)
		(fp_line
			(start -0.7874 -0.4064)
			(end 0.7874 -0.4064)
			(stroke
				(width 0.1524)
				(type default)
			)
			(layer "F.SilkS")
		)
		(fp_line
			(start 0.67945 0.3048)
			(end 0.120396 0.3048)
			(stroke
				(width 0.1)
				(type default)
			)
			(layer "F.Fab")
		)
		(fp_line
			(start 0.67945 -0.3048)
			(end 0.67945 0.3048)
			(stroke
				(width 0.1)
				(type default)
			)
			(layer "F.Fab")
		)
		(fp_line
			(start 0.12065 -0.2794)
			(end 0.12065 -0.3048)
			(stroke
				(width 0.1)
				(type default)
			)
			(layer "F.Fab")
		)
		(fp_line
			(start 0.12065 -0.3048)
			(end 0.67945 -0.3048)
			(stroke
				(width 0.1)
				(type default)
			)
			(layer "F.Fab")
		)
		(fp_line
			(start 0.120396 0.3048)
			(end 0.120396 0.2794)
			(stroke
				(width 0.1)
				(type default)
			)
			(layer "F.Fab")
		)
		(fp_line
			(start 0.120396 0.2794)
			(end -0.12065 0.2794)
			(stroke
				(width 0.1)
				(type default)
			)
			(layer "F.Fab")
		)
		(fp_line
			(start -0.12065 0.3048)
			(end -0.67945 0.3048)
			(stroke
				(width 0.1)
				(type default)
			)
			(layer "F.Fab")
		)
		(fp_line
			(start -0.12065 0.2794)
			(end -0.12065 0.3048)
			(stroke
				(width 0.1)
				(type default)
			)
			(layer "F.Fab")
		)
		(fp_line
			(start -0.12065 -0.2794)
			(end 0.12065 -0.2794)
			(stroke
				(width 0.1)
				(type default)
			)
			(layer "F.Fab")
		)
		(fp_line
			(start -0.12065 -0.305054)
			(end -0.12065 -0.2794)
			(stroke
				(width 0.1)
				(type default)
			)
			(layer "F.Fab")
		)
		(fp_line
			(start -0.67945 0.3048)
			(end -0.67945 -0.305054)
			(stroke
				(width 0.1)
				(type default)
			)
			(layer "F.Fab")
		)
		(fp_line
			(start -0.67945 -0.305054)
			(end -0.12065 -0.305054)
			(stroke
				(width 0.1)
				(type default)
			)
			(layer "F.Fab")
		)
		(pad "1" smd circle
			(at -0.40005 0 180)
			(size 0 0)
			(layers "F.Cu" "F.Mask" "F.Paste")
			(net "SMB_MB_I3C_ISO_SDA")
		)
		(pad "2" smd circle
			(at 0.40005 0 180)
			(size 0 0)
			(layers "F.Cu" "F.Mask" "F.Paste")
			(net "P3V3_AUX")
		)
	)
	(footprint ""
		(layer "F.Cu")
		(at 179.777644 -114.267742)
		(property "Reference" "R191"
			(at 0 0 0)
			(layer "F.SilkS")
			(hide yes)
			(effects
				(font
					(size 1.27 1.27)
				)
			)
		)
		(property "Value" ""
			(at 0 0 0)
			(layer "F.Fab")
			(effects
				(font
					(size 1.27 1.27)
				)
			)
		)
		(duplicate_pad_numbers_are_jumpers no)
		(fp_line
			(start -0.7874 -0.4064)
			(end 0.7874 -0.4064)
			(stroke
				(width 0.1524)
				(type default)
			)
			(layer "F.SilkS")
		)
		(fp_line
			(start -0.7874 0.4064)
			(end -0.7874 -0.4064)
			(stroke
				(width 0.1524)
				(type default)
			)
			(layer "F.SilkS")
		)
		(fp_line
			(start 0.7874 -0.4064)
			(end 0.7874 0.4064)
			(stroke
				(width 0.1524)
				(type default)
			)
			(layer "F.SilkS")
		)
		(fp_line
			(start 0.7874 0.4064)
			(end -0.7874 0.4064)
			(stroke
				(width 0.1524)
				(type default)
			)
			(layer "F.SilkS")
		)
		(fp_line
			(start -0.67945 -0.305054)
			(end -0.12065 -0.305054)
			(stroke
				(width 0.1)
				(type default)
			)
			(layer "F.Fab")
		)
		(fp_line
			(start -0.67945 0.3048)
			(end -0.67945 -0.305054)
			(stroke
				(width 0.1)
				(type default)
			)
			(layer "F.Fab")
		)
		(fp_line
			(start -0.12065 -0.305054)
			(end -0.12065 -0.2794)
			(stroke
				(width 0.1)
				(type default)
			)
			(layer "F.Fab")
		)
		(fp_line
			(start -0.12065 -0.2794)
			(end 0.12065 -0.2794)
			(stroke
				(width 0.1)
				(type default)
			)
			(layer "F.Fab")
		)
		(fp_line
			(start -0.12065 0.2794)
			(end -0.12065 0.3048)
			(stroke
				(width 0.1)
				(type default)
			)
			(layer "F.Fab")
		)
		(fp_line
			(start -0.12065 0.3048)
			(end -0.67945 0.3048)
			(stroke
				(width 0.1)
				(type default)
			)
			(layer "F.Fab")
		)
		(fp_line
			(start 0.120396 0.2794)
			(end -0.12065 0.2794)
			(stroke
				(width 0.1)
				(type default)
			)
			(layer "F.Fab")
		)
		(fp_line
			(start 0.120396 0.3048)
			(end 0.120396 0.2794)
			(stroke
				(width 0.1)
				(type default)
			)
			(layer "F.Fab")
		)
		(fp_line
			(start 0.12065 -0.3048)
			(end 0.67945 -0.3048)
			(stroke
				(width 0.1)
				(type default)
			)
			(layer "F.Fab")
		)
		(fp_line
			(start 0.12065 -0.2794)
			(end 0.12065 -0.3048)
			(stroke
				(width 0.1)
				(type default)
			)
			(layer "F.Fab")
		)
		(fp_line
			(start 0.67945 -0.3048)
			(end 0.67945 0.3048)
			(stroke
				(width 0.1)
				(type default)
			)
			(layer "F.Fab")
		)
		(fp_line
			(start 0.67945 0.3048)
			(end 0.120396 0.3048)
			(stroke
				(width 0.1)
				(type default)
			)
			(layer "F.Fab")
		)
		(pad "1" smd circle
			(at -0.40005 0)
			(size 0 0)
			(layers "F.Cu" "F.Mask" "F.Paste")
			(net "RST_SMB_NIC3_MUX_ISO_N")
		)
		(pad "2" smd circle
			(at 0.40005 0)
			(size 0 0)
			(layers "F.Cu" "F.Mask" "F.Paste")
			(net "GND")
		)
	)
	(footprint ""
		(layer "F.Cu")
		(at 241.64671 -154.256994)
		(property "Reference" "PC810"
			(at 0 0 0)
			(layer "F.SilkS")
			(hide yes)
			(effects
				(font
					(size 1.27 1.27)
				)
			)
		)
		(property "Value" ""
			(at 0 0 0)
			(layer "F.Fab")
			(effects
				(font
					(size 1.27 1.27)
				)
			)
		)
		(duplicate_pad_numbers_are_jumpers no)
		(fp_line
			(start -1.2954 -0.5842)
			(end 1.2954 -0.5842)
			(stroke
				(width 0.1524)
				(type default)
			)
			(layer "F.SilkS")
		)
		(fp_line
			(start -1.2954 0.5842)
			(end -1.2954 -0.5842)
			(stroke
				(width 0.1524)
				(type default)
			)
			(layer "F.SilkS")
		)
		(fp_line
			(start 1.2954 -0.5842)
			(end 1.2954 0.5842)
			(stroke
				(width 0.1524)
				(type default)
			)
			(layer "F.SilkS")
		)
		(fp_line
			(start 1.2954 0.5842)
			(end -1.2954 0.5842)
			(stroke
				(width 0.1524)
				(type default)
			)
			(layer "F.SilkS")
		)
		(fp_line
			(start -1.1938 -0.4064)
			(end -0.8636 -0.4064)
			(stroke
				(width 0.1)
				(type default)
			)
			(layer "F.Fab")
		)
		(fp_line
			(start -1.1938 0.4064)
			(end -1.1938 -0.4064)
			(stroke
				(width 0.1)
				(type default)
			)
			(layer "F.Fab")
		)
		(fp_line
			(start -0.8636 -0.4572)
			(end 0.8636 -0.4572)
			(stroke
				(width 0.1)
				(type default)
			)
			(layer "F.Fab")
		)
		(fp_line
			(start -0.8636 -0.4064)
			(end -0.8636 -0.4572)
			(stroke
				(width 0.1)
				(type default)
			)
			(layer "F.Fab")
		)
		(fp_line
			(start -0.8636 0.4064)
			(end -1.1938 0.4064)
			(stroke
				(width 0.1)
				(type default)
			)
			(layer "F.Fab")
		)
		(fp_line
			(start -0.8636 0.4572)
			(end -0.8636 0.4064)
			(stroke
				(width 0.1)
				(type default)
			)
			(layer "F.Fab")
		)
		(fp_line
			(start 0.8636 -0.4572)
			(end 0.8636 -0.4064)
			(stroke
				(width 0.1)
				(type default)
			)
			(layer "F.Fab")
		)
		(fp_line
			(start 0.8636 -0.4064)
			(end 1.1938 -0.4064)
			(stroke
				(width 0.1)
				(type default)
			)
			(layer "F.Fab")
		)
		(fp_line
			(start 0.8636 0.4064)
			(end 0.8636 0.4572)
			(stroke
				(width 0.1)
				(type default)
			)
			(layer "F.Fab")
		)
		(fp_line
			(start 0.8636 0.4572)
			(end -0.8636 0.4572)
			(stroke
				(width 0.1)
				(type default)
			)
			(layer "F.Fab")
		)
		(fp_line
			(start 1.1938 -0.4064)
			(end 1.1938 0.4064)
			(stroke
				(width 0.1)
				(type default)
			)
			(layer "F.Fab")
		)
		(fp_line
			(start 1.1938 0.4064)
			(end 0.8636 0.4064)
			(stroke
				(width 0.1)
				(type default)
			)
			(layer "F.Fab")
		)
		(pad "1" smd rect
			(at -0.7366 0 270)
			(size 0.7112 0.8128)
			(layers "F.Cu" "F.Mask" "F.Paste")
			(net "GND")
		)
		(pad "2" smd rect
			(at 0.7366 0 270)
			(size 0.7112 0.8128)
			(layers "F.Cu" "F.Mask" "F.Paste")
			(net "P12V_NIC4_CO_AVIN_PD")
		)
	)
	(footprint ""
		(layer "F.Cu")
		(at 264.611358 -283.643832 -90)
		(property "Reference" "R4585"
			(at 0 0 270)
			(layer "F.SilkS")
			(hide yes)
			(effects
				(font
					(size 1.27 1.27)
				)
			)
		)
		(property "Value" ""
			(at 0 0 270)
			(layer "F.Fab")
			(effects
				(font
					(size 1.27 1.27)
				)
			)
		)
		(duplicate_pad_numbers_are_jumpers no)
		(fp_line
			(start -0.7874 0.4064)
			(end -0.7874 -0.4064)
			(stroke
				(width 0.1524)
				(type default)
			)
			(layer "F.SilkS")
		)
		(fp_line
			(start 0.7874 0.4064)
			(end -0.7874 0.4064)
			(stroke
				(width 0.1524)
				(type default)
			)
			(layer "F.SilkS")
		)
		(fp_line
			(start -0.7874 -0.4064)
			(end 0.7874 -0.4064)
			(stroke
				(width 0.1524)
				(type default)
			)
			(layer "F.SilkS")
		)
		(fp_line
			(start 0.7874 -0.4064)
			(end 0.7874 0.4064)
			(stroke
				(width 0.1524)
				(type default)
			)
			(layer "F.SilkS")
		)
		(fp_line
			(start -0.67945 0.3048)
			(end -0.67945 -0.305054)
			(stroke
				(width 0.1)
				(type default)
			)
			(layer "F.Fab")
		)
		(fp_line
			(start -0.12065 0.3048)
			(end -0.67945 0.3048)
			(stroke
				(width 0.1)
				(type default)
			)
			(layer "F.Fab")
		)
		(fp_line
			(start 0.120396 0.3048)
			(end 0.120396 0.2794)
			(stroke
				(width 0.1)
				(type default)
			)
			(layer "F.Fab")
		)
		(fp_line
			(start 0.67945 0.3048)
			(end 0.120396 0.3048)
			(stroke
				(width 0.1)
				(type default)
			)
			(layer "F.Fab")
		)
		(fp_line
			(start -0.12065 0.2794)
			(end -0.12065 0.3048)
			(stroke
				(width 0.1)
				(type default)
			)
			(layer "F.Fab")
		)
		(fp_line
			(start 0.120396 0.2794)
			(end -0.12065 0.2794)
			(stroke
				(width 0.1)
				(type default)
			)
			(layer "F.Fab")
		)
		(fp_line
			(start -0.12065 -0.2794)
			(end 0.12065 -0.2794)
			(stroke
				(width 0.1)
				(type default)
			)
			(layer "F.Fab")
		)
		(fp_line
			(start 0.12065 -0.2794)
			(end 0.12065 -0.3048)
			(stroke
				(width 0.1)
				(type default)
			)
			(layer "F.Fab")
		)
		(fp_line
			(start 0.12065 -0.3048)
			(end 0.67945 -0.3048)
			(stroke
				(width 0.1)
				(type default)
			)
			(layer "F.Fab")
		)
		(fp_line
			(start 0.67945 -0.3048)
			(end 0.67945 0.3048)
			(stroke
				(width 0.1)
				(type default)
			)
			(layer "F.Fab")
		)
		(fp_line
			(start -0.67945 -0.305054)
			(end -0.12065 -0.305054)
			(stroke
				(width 0.1)
				(type default)
			)
			(layer "F.Fab")
		)
		(fp_line
			(start -0.12065 -0.305054)
			(end -0.12065 -0.2794)
			(stroke
				(width 0.1)
				(type default)
			)
			(layer "F.Fab")
		)
		(pad "1" smd circle
			(at -0.40005 0 270)
			(size 0 0)
			(layers "F.Cu" "F.Mask" "F.Paste")
			(net "PCEPLL7_VDDA18_PEX2")
		)
		(pad "2" smd circle
			(at 0.40005 0 270)
			(size 0 0)
			(layers "F.Cu" "F.Mask" "F.Paste")
			(net "PCEPLL7_VDDA18_PEX2_R")
		)
	)
	(footprint ""
		(layer "F.Cu")
		(at 281.221942 -350.098614 90)
		(property "Reference" "C602"
			(at 0 0 90)
			(layer "F.SilkS")
			(hide yes)
			(effects
				(font
					(size 1.27 1.27)
				)
			)
		)
		(property "Value" ""
			(at 0 0 90)
			(layer "F.Fab")
			(effects
				(font
					(size 1.27 1.27)
				)
			)
		)
		(duplicate_pad_numbers_are_jumpers no)
		(fp_line
			(start 0.299974 -0.150114)
			(end 0.299974 0.150114)
			(stroke
				(width 0.1)
				(type default)
			)
			(layer "F.Fab")
		)
		(fp_line
			(start -0.299974 -0.150114)
			(end 0.299974 -0.150114)
			(stroke
				(width 0.1)
				(type default)
			)
			(layer "F.Fab")
		)
		(fp_line
			(start 0.299974 0.150114)
			(end -0.299974 0.150114)
			(stroke
				(width 0.1)
				(type default)
			)
			(layer "F.Fab")
		)
		(fp_line
			(start -0.299974 0.150114)
			(end -0.299974 -0.150114)
			(stroke
				(width 0.1)
				(type default)
			)
			(layer "F.Fab")
		)
		(pad "1" smd rect
			(at -0.2667 0 90)
			(size 0.3048 0.381)
			(layers "F.Cu" "F.Mask" "F.Paste")
			(net "P5E_PEX2_STN7_TX_DN<118>")
		)
		(pad "2" smd rect
			(at 0.2667 0 90)
			(size 0.3048 0.381)
			(layers "F.Cu" "F.Mask" "F.Paste")
			(net "P5E_PEX2_STN7_TX_C_DN<118>")
		)
	)
	(footprint ""
		(layer "F.Cu")
		(at 204.591158 -84.675472)
		(property "Reference" "R4330"
			(at 0 0 0)
			(layer "F.SilkS")
			(hide yes)
			(effects
				(font
					(size 1.27 1.27)
				)
			)
		)
		(property "Value" ""
			(at 0 0 0)
			(layer "F.Fab")
			(effects
				(font
					(size 1.27 1.27)
				)
			)
		)
		(duplicate_pad_numbers_are_jumpers no)
		(fp_line
			(start -0.7874 -0.4064)
			(end 0.7874 -0.4064)
			(stroke
				(width 0.1524)
				(type default)
			)
			(layer "F.SilkS")
		)
		(fp_line
			(start -0.7874 0.4064)
			(end -0.7874 -0.4064)
			(stroke
				(width 0.1524)
				(type default)
			)
			(layer "F.SilkS")
		)
		(fp_line
			(start 0.7874 -0.4064)
			(end 0.7874 0.4064)
			(stroke
				(width 0.1524)
				(type default)
			)
			(layer "F.SilkS")
		)
		(fp_line
			(start 0.7874 0.4064)
			(end -0.7874 0.4064)
			(stroke
				(width 0.1524)
				(type default)
			)
			(layer "F.SilkS")
		)
		(fp_line
			(start -0.67945 -0.305054)
			(end -0.12065 -0.305054)
			(stroke
				(width 0.1)
				(type default)
			)
			(layer "F.Fab")
		)
		(fp_line
			(start -0.67945 0.3048)
			(end -0.67945 -0.305054)
			(stroke
				(width 0.1)
				(type default)
			)
			(layer "F.Fab")
		)
		(fp_line
			(start -0.12065 -0.305054)
			(end -0.12065 -0.2794)
			(stroke
				(width 0.1)
				(type default)
			)
			(layer "F.Fab")
		)
		(fp_line
			(start -0.12065 -0.2794)
			(end 0.12065 -0.2794)
			(stroke
				(width 0.1)
				(type default)
			)
			(layer "F.Fab")
		)
		(fp_line
			(start -0.12065 0.2794)
			(end -0.12065 0.3048)
			(stroke
				(width 0.1)
				(type default)
			)
			(layer "F.Fab")
		)
		(fp_line
			(start -0.12065 0.3048)
			(end -0.67945 0.3048)
			(stroke
				(width 0.1)
				(type default)
			)
			(layer "F.Fab")
		)
		(fp_line
			(start 0.120396 0.2794)
			(end -0.12065 0.2794)
			(stroke
				(width 0.1)
				(type default)
			)
			(layer "F.Fab")
		)
		(fp_line
			(start 0.120396 0.3048)
			(end 0.120396 0.2794)
			(stroke
				(width 0.1)
				(type default)
			)
			(layer "F.Fab")
		)
		(fp_line
			(start 0.12065 -0.3048)
			(end 0.67945 -0.3048)
			(stroke
				(width 0.1)
				(type default)
			)
			(layer "F.Fab")
		)
		(fp_line
			(start 0.12065 -0.2794)
			(end 0.12065 -0.3048)
			(stroke
				(width 0.1)
				(type default)
			)
			(layer "F.Fab")
		)
		(fp_line
			(start 0.67945 -0.3048)
			(end 0.67945 0.3048)
			(stroke
				(width 0.1)
				(type default)
			)
			(layer "F.Fab")
		)
		(fp_line
			(start 0.67945 0.3048)
			(end 0.120396 0.3048)
			(stroke
				(width 0.1)
				(type default)
			)
			(layer "F.Fab")
		)
		(pad "1" smd circle
			(at -0.40005 0)
			(size 0 0)
			(layers "F.Cu" "F.Mask" "F.Paste")
			(net "P3V3_AUX")
		)
		(pad "2" smd circle
			(at 0.40005 0)
			(size 0 0)
			(layers "F.Cu" "F.Mask" "F.Paste")
			(net "SSD0_LED_R")
		)
	)
	(footprint ""
		(layer "F.Cu")
		(at 258.401566 -334.013048 -90)
		(property "Reference" "R6791"
			(at 0 0 270)
			(layer "F.SilkS")
			(hide yes)
			(effects
				(font
					(size 1.27 1.27)
				)
			)
		)
		(property "Value" ""
			(at 0 0 270)
			(layer "F.Fab")
			(effects
				(font
					(size 1.27 1.27)
				)
			)
		)
		(duplicate_pad_numbers_are_jumpers no)
		(fp_line
			(start -0.7874 0.4064)
			(end -0.7874 -0.4064)
			(stroke
				(width 0.1524)
				(type default)
			)
			(layer "F.SilkS")
		)
		(fp_line
			(start 0.7874 0.4064)
			(end -0.7874 0.4064)
			(stroke
				(width 0.1524)
				(type default)
			)
			(layer "F.SilkS")
		)
		(fp_line
			(start -0.7874 -0.4064)
			(end 0.7874 -0.4064)
			(stroke
				(width 0.1524)
				(type default)
			)
			(layer "F.SilkS")
		)
		(fp_line
			(start 0.7874 -0.4064)
			(end 0.7874 0.4064)
			(stroke
				(width 0.1524)
				(type default)
			)
			(layer "F.SilkS")
		)
		(fp_line
			(start -0.67945 0.3048)
			(end -0.67945 -0.305054)
			(stroke
				(width 0.1)
				(type default)
			)
			(layer "F.Fab")
		)
		(fp_line
			(start -0.12065 0.3048)
			(end -0.67945 0.3048)
			(stroke
				(width 0.1)
				(type default)
			)
			(layer "F.Fab")
		)
		(fp_line
			(start 0.120396 0.3048)
			(end 0.120396 0.2794)
			(stroke
				(width 0.1)
				(type default)
			)
			(layer "F.Fab")
		)
		(fp_line
			(start 0.67945 0.3048)
			(end 0.120396 0.3048)
			(stroke
				(width 0.1)
				(type default)
			)
			(layer "F.Fab")
		)
		(fp_line
			(start -0.12065 0.2794)
			(end -0.12065 0.3048)
			(stroke
				(width 0.1)
				(type default)
			)
			(layer "F.Fab")
		)
		(fp_line
			(start 0.120396 0.2794)
			(end -0.12065 0.2794)
			(stroke
				(width 0.1)
				(type default)
			)
			(layer "F.Fab")
		)
		(fp_line
			(start -0.12065 -0.2794)
			(end 0.12065 -0.2794)
			(stroke
				(width 0.1)
				(type default)
			)
			(layer "F.Fab")
		)
		(fp_line
			(start 0.12065 -0.2794)
			(end 0.12065 -0.3048)
			(stroke
				(width 0.1)
				(type default)
			)
			(layer "F.Fab")
		)
		(fp_line
			(start 0.12065 -0.3048)
			(end 0.67945 -0.3048)
			(stroke
				(width 0.1)
				(type default)
			)
			(layer "F.Fab")
		)
		(fp_line
			(start 0.67945 -0.3048)
			(end 0.67945 0.3048)
			(stroke
				(width 0.1)
				(type default)
			)
			(layer "F.Fab")
		)
		(fp_line
			(start -0.67945 -0.305054)
			(end -0.12065 -0.305054)
			(stroke
				(width 0.1)
				(type default)
			)
			(layer "F.Fab")
		)
		(fp_line
			(start -0.12065 -0.305054)
			(end -0.12065 -0.2794)
			(stroke
				(width 0.1)
				(type default)
			)
			(layer "F.Fab")
		)
		(pad "1" smd circle
			(at -0.40005 0 270)
			(size 0 0)
			(layers "F.Cu" "F.Mask" "F.Paste")
			(net "HSC_CSOUT")
		)
		(pad "2" smd circle
			(at 0.40005 0 270)
			(size 0 0)
			(layers "F.Cu" "F.Mask" "F.Paste")
			(net "HSC_OC_VOL")
		)
	)
	(footprint ""
		(layer "F.Cu")
		(at 318.62776 -302.863504 180)
		(property "Reference" "R3975"
			(at 0 0 180)
			(layer "F.SilkS")
			(hide yes)
			(effects
				(font
					(size 1.27 1.27)
				)
			)
		)
		(property "Value" ""
			(at 0 0 180)
			(layer "F.Fab")
			(effects
				(font
					(size 1.27 1.27)
				)
			)
		)
		(duplicate_pad_numbers_are_jumpers no)
		(fp_line
			(start 0.7874 0.4064)
			(end -0.7874 0.4064)
			(stroke
				(width 0.1524)
				(type default)
			)
			(layer "F.SilkS")
		)
		(fp_line
			(start 0.7874 -0.4064)
			(end 0.7874 0.4064)
			(stroke
				(width 0.1524)
				(type default)
			)
			(layer "F.SilkS")
		)
		(fp_line
			(start -0.7874 0.4064)
			(end -0.7874 -0.4064)
			(stroke
				(width 0.1524)
				(type default)
			)
			(layer "F.SilkS")
		)
		(fp_line
			(start -0.7874 -0.4064)
			(end 0.7874 -0.4064)
			(stroke
				(width 0.1524)
				(type default)
			)
			(layer "F.SilkS")
		)
		(fp_line
			(start 0.67945 0.3048)
			(end 0.120396 0.3048)
			(stroke
				(width 0.1)
				(type default)
			)
			(layer "F.Fab")
		)
		(fp_line
			(start 0.67945 -0.3048)
			(end 0.67945 0.3048)
			(stroke
				(width 0.1)
				(type default)
			)
			(layer "F.Fab")
		)
		(fp_line
			(start 0.12065 -0.2794)
			(end 0.12065 -0.3048)
			(stroke
				(width 0.1)
				(type default)
			)
			(layer "F.Fab")
		)
		(fp_line
			(start 0.12065 -0.3048)
			(end 0.67945 -0.3048)
			(stroke
				(width 0.1)
				(type default)
			)
			(layer "F.Fab")
		)
		(fp_line
			(start 0.120396 0.3048)
			(end 0.120396 0.2794)
			(stroke
				(width 0.1)
				(type default)
			)
			(layer "F.Fab")
		)
		(fp_line
			(start 0.120396 0.2794)
			(end -0.12065 0.2794)
			(stroke
				(width 0.1)
				(type default)
			)
			(layer "F.Fab")
		)
		(fp_line
			(start -0.12065 0.3048)
			(end -0.67945 0.3048)
			(stroke
				(width 0.1)
				(type default)
			)
			(layer "F.Fab")
		)
		(fp_line
			(start -0.12065 0.2794)
			(end -0.12065 0.3048)
			(stroke
				(width 0.1)
				(type default)
			)
			(layer "F.Fab")
		)
		(fp_line
			(start -0.12065 -0.2794)
			(end 0.12065 -0.2794)
			(stroke
				(width 0.1)
				(type default)
			)
			(layer "F.Fab")
		)
		(fp_line
			(start -0.12065 -0.305054)
			(end -0.12065 -0.2794)
			(stroke
				(width 0.1)
				(type default)
			)
			(layer "F.Fab")
		)
		(fp_line
			(start -0.67945 0.3048)
			(end -0.67945 -0.305054)
			(stroke
				(width 0.1)
				(type default)
			)
			(layer "F.Fab")
		)
		(fp_line
			(start -0.67945 -0.305054)
			(end -0.12065 -0.305054)
			(stroke
				(width 0.1)
				(type default)
			)
			(layer "F.Fab")
		)
		(pad "1" smd circle
			(at -0.40005 0 180)
			(size 0 0)
			(layers "F.Cu" "F.Mask" "F.Paste")
			(net "SMB_PEX2_SLAVE_SCL")
		)
		(pad "2" smd circle
			(at 0.40005 0 180)
			(size 0 0)
			(layers "F.Cu" "F.Mask" "F.Paste")
			(net "SMB_PEX2_R_SCL")
		)
	)
	(footprint ""
		(layer "F.Cu")
		(at 384.938524 -120.113298)
		(property "Reference" "C681"
			(at 0 0 0)
			(layer "F.SilkS")
			(hide yes)
			(effects
				(font
					(size 1.27 1.27)
				)
			)
		)
		(property "Value" ""
			(at 0 0 0)
			(layer "F.Fab")
			(effects
				(font
					(size 1.27 1.27)
				)
			)
		)
		(duplicate_pad_numbers_are_jumpers no)
		(fp_line
			(start -0.299974 -0.150114)
			(end 0.299974 -0.150114)
			(stroke
				(width 0.1)
				(type default)
			)
			(layer "F.Fab")
		)
		(fp_line
			(start -0.299974 0.150114)
			(end -0.299974 -0.150114)
			(stroke
				(width 0.1)
				(type default)
			)
			(layer "F.Fab")
		)
		(fp_line
			(start 0.299974 -0.150114)
			(end 0.299974 0.150114)
			(stroke
				(width 0.1)
				(type default)
			)
			(layer "F.Fab")
		)
		(fp_line
			(start 0.299974 0.150114)
			(end -0.299974 0.150114)
			(stroke
				(width 0.1)
				(type default)
			)
			(layer "F.Fab")
		)
		(pad "1" smd rect
			(at -0.2667 0)
			(size 0.3048 0.381)
			(layers "F.Cu" "F.Mask" "F.Paste")
			(net "P5E_PEX3_STN1_TX_DN<24>")
		)
		(pad "2" smd rect
			(at 0.2667 0)
			(size 0.3048 0.381)
			(layers "F.Cu" "F.Mask" "F.Paste")
			(net "P5E_PEX3_STN1_TX_C_DN<24>")
		)
	)
	(footprint ""
		(layer "F.Cu")
		(at 431.032412 -343.952322 90)
		(property "Reference" "C2459"
			(at 0 0 90)
			(layer "F.SilkS")
			(hide yes)
			(effects
				(font
					(size 1.27 1.27)
				)
			)
		)
		(property "Value" ""
			(at 0 0 90)
			(layer "F.Fab")
			(effects
				(font
					(size 1.27 1.27)
				)
			)
		)
		(duplicate_pad_numbers_are_jumpers no)
		(fp_line
			(start 0.299974 -0.150114)
			(end 0.299974 0.150114)
			(stroke
				(width 0.1)
				(type default)
			)
			(layer "F.Fab")
		)
		(fp_line
			(start -0.299974 -0.150114)
			(end 0.299974 -0.150114)
			(stroke
				(width 0.1)
				(type default)
			)
			(layer "F.Fab")
		)
		(fp_line
			(start 0.299974 0.150114)
			(end -0.299974 0.150114)
			(stroke
				(width 0.1)
				(type default)
			)
			(layer "F.Fab")
		)
		(fp_line
			(start -0.299974 0.150114)
			(end -0.299974 -0.150114)
			(stroke
				(width 0.1)
				(type default)
			)
			(layer "F.Fab")
		)
		(pad "1" smd rect
			(at -0.2667 0 90)
			(size 0.3048 0.381)
			(layers "F.Cu" "F.Mask" "F.Paste")
			(net "P5E_PEX3_STN4_TX_DP<69>")
		)
		(pad "2" smd rect
			(at 0.2667 0 90)
			(size 0.3048 0.381)
			(layers "F.Cu" "F.Mask" "F.Paste")
			(net "P5E_PEX3_STN4_TX_C_DP<69>")
		)
	)
	(footprint ""
		(layer "F.Cu")
		(at 205.391766 -356.811326)
		(property "Reference" "R493"
			(at 0 0 0)
			(layer "F.SilkS")
			(hide yes)
			(effects
				(font
					(size 1.27 1.27)
				)
			)
		)
		(property "Value" ""
			(at 0 0 0)
			(layer "F.Fab")
			(effects
				(font
					(size 1.27 1.27)
				)
			)
		)
		(duplicate_pad_numbers_are_jumpers no)
		(fp_line
			(start -0.7874 -0.4064)
			(end 0.7874 -0.4064)
			(stroke
				(width 0.1524)
				(type default)
			)
			(layer "F.SilkS")
		)
		(fp_line
			(start -0.7874 0.4064)
			(end -0.7874 -0.4064)
			(stroke
				(width 0.1524)
				(type default)
			)
			(layer "F.SilkS")
		)
		(fp_line
			(start 0.7874 -0.4064)
			(end 0.7874 0.4064)
			(stroke
				(width 0.1524)
				(type default)
			)
			(layer "F.SilkS")
		)
		(fp_line
			(start 0.7874 0.4064)
			(end -0.7874 0.4064)
			(stroke
				(width 0.1524)
				(type default)
			)
			(layer "F.SilkS")
		)
		(fp_line
			(start -0.67945 -0.305054)
			(end -0.12065 -0.305054)
			(stroke
				(width 0.1)
				(type default)
			)
			(layer "F.Fab")
		)
		(fp_line
			(start -0.67945 0.3048)
			(end -0.67945 -0.305054)
			(stroke
				(width 0.1)
				(type default)
			)
			(layer "F.Fab")
		)
		(fp_line
			(start -0.12065 -0.305054)
			(end -0.12065 -0.2794)
			(stroke
				(width 0.1)
				(type default)
			)
			(layer "F.Fab")
		)
		(fp_line
			(start -0.12065 -0.2794)
			(end 0.12065 -0.2794)
			(stroke
				(width 0.1)
				(type default)
			)
			(layer "F.Fab")
		)
		(fp_line
			(start -0.12065 0.2794)
			(end -0.12065 0.3048)
			(stroke
				(width 0.1)
				(type default)
			)
			(layer "F.Fab")
		)
		(fp_line
			(start -0.12065 0.3048)
			(end -0.67945 0.3048)
			(stroke
				(width 0.1)
				(type default)
			)
			(layer "F.Fab")
		)
		(fp_line
			(start 0.120396 0.2794)
			(end -0.12065 0.2794)
			(stroke
				(width 0.1)
				(type default)
			)
			(layer "F.Fab")
		)
		(fp_line
			(start 0.120396 0.3048)
			(end 0.120396 0.2794)
			(stroke
				(width 0.1)
				(type default)
			)
			(layer "F.Fab")
		)
		(fp_line
			(start 0.12065 -0.3048)
			(end 0.67945 -0.3048)
			(stroke
				(width 0.1)
				(type default)
			)
			(layer "F.Fab")
		)
		(fp_line
			(start 0.12065 -0.2794)
			(end 0.12065 -0.3048)
			(stroke
				(width 0.1)
				(type default)
			)
			(layer "F.Fab")
		)
		(fp_line
			(start 0.67945 -0.3048)
			(end 0.67945 0.3048)
			(stroke
				(width 0.1)
				(type default)
			)
			(layer "F.Fab")
		)
		(fp_line
			(start 0.67945 0.3048)
			(end 0.120396 0.3048)
			(stroke
				(width 0.1)
				(type default)
			)
			(layer "F.Fab")
		)
		(pad "1" smd circle
			(at -0.40005 0)
			(size 0 0)
			(layers "F.Cu" "F.Mask" "F.Paste")
			(net "HSC_D_OC")
		)
		(pad "2" smd circle
			(at 0.40005 0)
			(size 0 0)
			(layers "F.Cu" "F.Mask" "F.Paste")
			(net "HSC_D_OC_R")
		)
	)
	(footprint ""
		(layer "F.Cu")
		(at 352.826828 -53.697124 -90)
		(property "Reference" "PC544"
			(at 0 0 270)
			(layer "F.SilkS")
			(hide yes)
			(effects
				(font
					(size 1.27 1.27)
				)
			)
		)
		(property "Value" ""
			(at 0 0 270)
			(layer "F.Fab")
			(effects
				(font
					(size 1.27 1.27)
				)
			)
		)
		(duplicate_pad_numbers_are_jumpers no)
		(fp_line
			(start -0.7874 0.4064)
			(end -0.7874 -0.4064)
			(stroke
				(width 0.1524)
				(type default)
			)
			(layer "F.SilkS")
		)
		(fp_line
			(start 0.7874 0.4064)
			(end -0.7874 0.4064)
			(stroke
				(width 0.1524)
				(type default)
			)
			(layer "F.SilkS")
		)
		(fp_line
			(start -0.7874 -0.4064)
			(end 0.7874 -0.4064)
			(stroke
				(width 0.1524)
				(type default)
			)
			(layer "F.SilkS")
		)
		(fp_line
			(start 0.7874 -0.4064)
			(end 0.7874 0.4064)
			(stroke
				(width 0.1524)
				(type default)
			)
			(layer "F.SilkS")
		)
		(fp_line
			(start -0.67945 0.3048)
			(end -0.67945 -0.305054)
			(stroke
				(width 0.1)
				(type default)
			)
			(layer "F.Fab")
		)
		(fp_line
			(start -0.12065 0.3048)
			(end -0.67945 0.3048)
			(stroke
				(width 0.1)
				(type default)
			)
			(layer "F.Fab")
		)
		(fp_line
			(start 0.120396 0.3048)
			(end 0.120396 0.2794)
			(stroke
				(width 0.1)
				(type default)
			)
			(layer "F.Fab")
		)
		(fp_line
			(start 0.67945 0.3048)
			(end 0.120396 0.3048)
			(stroke
				(width 0.1)
				(type default)
			)
			(layer "F.Fab")
		)
		(fp_line
			(start -0.12065 0.2794)
			(end -0.12065 0.3048)
			(stroke
				(width 0.1)
				(type default)
			)
			(layer "F.Fab")
		)
		(fp_line
			(start 0.120396 0.2794)
			(end -0.12065 0.2794)
			(stroke
				(width 0.1)
				(type default)
			)
			(layer "F.Fab")
		)
		(fp_line
			(start -0.12065 -0.2794)
			(end 0.12065 -0.2794)
			(stroke
				(width 0.1)
				(type default)
			)
			(layer "F.Fab")
		)
		(fp_line
			(start 0.12065 -0.2794)
			(end 0.12065 -0.3048)
			(stroke
				(width 0.1)
				(type default)
			)
			(layer "F.Fab")
		)
		(fp_line
			(start 0.12065 -0.3048)
			(end 0.67945 -0.3048)
			(stroke
				(width 0.1)
				(type default)
			)
			(layer "F.Fab")
		)
		(fp_line
			(start 0.67945 -0.3048)
			(end 0.67945 0.3048)
			(stroke
				(width 0.1)
				(type default)
			)
			(layer "F.Fab")
		)
		(fp_line
			(start -0.67945 -0.305054)
			(end -0.12065 -0.305054)
			(stroke
				(width 0.1)
				(type default)
			)
			(layer "F.Fab")
		)
		(fp_line
			(start -0.12065 -0.305054)
			(end -0.12065 -0.2794)
			(stroke
				(width 0.1)
				(type default)
			)
			(layer "F.Fab")
		)
		(pad "1" smd circle
			(at -0.40005 0 270)
			(size 0 0)
			(layers "F.Cu" "F.Mask" "F.Paste")
			(net "P3V3_AUX")
		)
		(pad "2" smd circle
			(at 0.40005 0 270)
			(size 0 0)
			(layers "F.Cu" "F.Mask" "F.Paste")
			(net "GND")
		)
	)
	(footprint ""
		(layer "F.Cu")
		(at 201.635868 -289.230816 -90)
		(property "Reference" "R6393"
			(at 0 0 270)
			(layer "F.SilkS")
			(hide yes)
			(effects
				(font
					(size 1.27 1.27)
				)
			)
		)
		(property "Value" ""
			(at 0 0 270)
			(layer "F.Fab")
			(effects
				(font
					(size 1.27 1.27)
				)
			)
		)
		(duplicate_pad_numbers_are_jumpers no)
		(fp_line
			(start -0.7874 0.4064)
			(end -0.7874 -0.4064)
			(stroke
				(width 0.1524)
				(type default)
			)
			(layer "F.SilkS")
		)
		(fp_line
			(start 0.7874 0.4064)
			(end -0.7874 0.4064)
			(stroke
				(width 0.1524)
				(type default)
			)
			(layer "F.SilkS")
		)
		(fp_line
			(start -0.7874 -0.4064)
			(end 0.7874 -0.4064)
			(stroke
				(width 0.1524)
				(type default)
			)
			(layer "F.SilkS")
		)
		(fp_line
			(start 0.7874 -0.4064)
			(end 0.7874 0.4064)
			(stroke
				(width 0.1524)
				(type default)
			)
			(layer "F.SilkS")
		)
		(fp_line
			(start -0.67945 0.3048)
			(end -0.67945 -0.305054)
			(stroke
				(width 0.1)
				(type default)
			)
			(layer "F.Fab")
		)
		(fp_line
			(start -0.12065 0.3048)
			(end -0.67945 0.3048)
			(stroke
				(width 0.1)
				(type default)
			)
			(layer "F.Fab")
		)
		(fp_line
			(start 0.120396 0.3048)
			(end 0.120396 0.2794)
			(stroke
				(width 0.1)
				(type default)
			)
			(layer "F.Fab")
		)
		(fp_line
			(start 0.67945 0.3048)
			(end 0.120396 0.3048)
			(stroke
				(width 0.1)
				(type default)
			)
			(layer "F.Fab")
		)
		(fp_line
			(start -0.12065 0.2794)
			(end -0.12065 0.3048)
			(stroke
				(width 0.1)
				(type default)
			)
			(layer "F.Fab")
		)
		(fp_line
			(start 0.120396 0.2794)
			(end -0.12065 0.2794)
			(stroke
				(width 0.1)
				(type default)
			)
			(layer "F.Fab")
		)
		(fp_line
			(start -0.12065 -0.2794)
			(end 0.12065 -0.2794)
			(stroke
				(width 0.1)
				(type default)
			)
			(layer "F.Fab")
		)
		(fp_line
			(start 0.12065 -0.2794)
			(end 0.12065 -0.3048)
			(stroke
				(width 0.1)
				(type default)
			)
			(layer "F.Fab")
		)
		(fp_line
			(start 0.12065 -0.3048)
			(end 0.67945 -0.3048)
			(stroke
				(width 0.1)
				(type default)
			)
			(layer "F.Fab")
		)
		(fp_line
			(start 0.67945 -0.3048)
			(end 0.67945 0.3048)
			(stroke
				(width 0.1)
				(type default)
			)
			(layer "F.Fab")
		)
		(fp_line
			(start -0.67945 -0.305054)
			(end -0.12065 -0.305054)
			(stroke
				(width 0.1)
				(type default)
			)
			(layer "F.Fab")
		)
		(fp_line
			(start -0.12065 -0.305054)
			(end -0.12065 -0.2794)
			(stroke
				(width 0.1)
				(type default)
			)
			(layer "F.Fab")
		)
		(pad "1" smd circle
			(at -0.40005 0 270)
			(size 0 0)
			(layers "F.Cu" "F.Mask" "F.Paste")
			(net "RST_PEX1_S0_PERST_N")
		)
		(pad "2" smd circle
			(at 0.40005 0 270)
			(size 0 0)
			(layers "F.Cu" "F.Mask" "F.Paste")
			(net "RST_PEX1_S0_PERST_R_N")
		)
	)
	(footprint ""
		(layer "F.Cu")
		(at 219.014294 -181.14518 180)
		(property "Reference" "R5497"
			(at 0 0 180)
			(layer "F.SilkS")
			(hide yes)
			(effects
				(font
					(size 1.27 1.27)
				)
			)
		)
		(property "Value" ""
			(at 0 0 180)
			(layer "F.Fab")
			(effects
				(font
					(size 1.27 1.27)
				)
			)
		)
		(duplicate_pad_numbers_are_jumpers no)
		(fp_line
			(start 0.7874 0.4064)
			(end -0.7874 0.4064)
			(stroke
				(width 0.1524)
				(type default)
			)
			(layer "F.SilkS")
		)
		(fp_line
			(start 0.7874 -0.4064)
			(end 0.7874 0.4064)
			(stroke
				(width 0.1524)
				(type default)
			)
			(layer "F.SilkS")
		)
		(fp_line
			(start -0.7874 0.4064)
			(end -0.7874 -0.4064)
			(stroke
				(width 0.1524)
				(type default)
			)
			(layer "F.SilkS")
		)
		(fp_line
			(start -0.7874 -0.4064)
			(end 0.7874 -0.4064)
			(stroke
				(width 0.1524)
				(type default)
			)
			(layer "F.SilkS")
		)
		(fp_line
			(start 0.67945 0.3048)
			(end 0.120396 0.3048)
			(stroke
				(width 0.1)
				(type default)
			)
			(layer "F.Fab")
		)
		(fp_line
			(start 0.67945 -0.3048)
			(end 0.67945 0.3048)
			(stroke
				(width 0.1)
				(type default)
			)
			(layer "F.Fab")
		)
		(fp_line
			(start 0.12065 -0.2794)
			(end 0.12065 -0.3048)
			(stroke
				(width 0.1)
				(type default)
			)
			(layer "F.Fab")
		)
		(fp_line
			(start 0.12065 -0.3048)
			(end 0.67945 -0.3048)
			(stroke
				(width 0.1)
				(type default)
			)
			(layer "F.Fab")
		)
		(fp_line
			(start 0.120396 0.3048)
			(end 0.120396 0.2794)
			(stroke
				(width 0.1)
				(type default)
			)
			(layer "F.Fab")
		)
		(fp_line
			(start 0.120396 0.2794)
			(end -0.12065 0.2794)
			(stroke
				(width 0.1)
				(type default)
			)
			(layer "F.Fab")
		)
		(fp_line
			(start -0.12065 0.3048)
			(end -0.67945 0.3048)
			(stroke
				(width 0.1)
				(type default)
			)
			(layer "F.Fab")
		)
		(fp_line
			(start -0.12065 0.2794)
			(end -0.12065 0.3048)
			(stroke
				(width 0.1)
				(type default)
			)
			(layer "F.Fab")
		)
		(fp_line
			(start -0.12065 -0.2794)
			(end 0.12065 -0.2794)
			(stroke
				(width 0.1)
				(type default)
			)
			(layer "F.Fab")
		)
		(fp_line
			(start -0.12065 -0.305054)
			(end -0.12065 -0.2794)
			(stroke
				(width 0.1)
				(type default)
			)
			(layer "F.Fab")
		)
		(fp_line
			(start -0.67945 0.3048)
			(end -0.67945 -0.305054)
			(stroke
				(width 0.1)
				(type default)
			)
			(layer "F.Fab")
		)
		(fp_line
			(start -0.67945 -0.305054)
			(end -0.12065 -0.305054)
			(stroke
				(width 0.1)
				(type default)
			)
			(layer "F.Fab")
		)
		(pad "1" smd circle
			(at -0.40005 0 180)
			(size 0 0)
			(layers "F.Cu" "F.Mask" "F.Paste")
			(net "RST_FW_BIC_PLTRST_C")
		)
		(pad "2" smd circle
			(at 0.40005 0 180)
			(size 0 0)
			(layers "F.Cu" "F.Mask" "F.Paste")
			(net "GND")
		)
	)
	(footprint ""
		(layer "F.Cu")
		(at 340.561422 -190.41745 180)
		(property "Reference" "R4243"
			(at 0 0 180)
			(layer "F.SilkS")
			(hide yes)
			(effects
				(font
					(size 1.27 1.27)
				)
			)
		)
		(property "Value" ""
			(at 0 0 180)
			(layer "F.Fab")
			(effects
				(font
					(size 1.27 1.27)
				)
			)
		)
		(duplicate_pad_numbers_are_jumpers no)
		(fp_line
			(start 0.7874 0.4064)
			(end -0.7874 0.4064)
			(stroke
				(width 0.1524)
				(type default)
			)
			(layer "F.SilkS")
		)
		(fp_line
			(start 0.7874 -0.4064)
			(end 0.7874 0.4064)
			(stroke
				(width 0.1524)
				(type default)
			)
			(layer "F.SilkS")
		)
		(fp_line
			(start -0.7874 0.4064)
			(end -0.7874 -0.4064)
			(stroke
				(width 0.1524)
				(type default)
			)
			(layer "F.SilkS")
		)
		(fp_line
			(start -0.7874 -0.4064)
			(end 0.7874 -0.4064)
			(stroke
				(width 0.1524)
				(type default)
			)
			(layer "F.SilkS")
		)
		(fp_line
			(start 0.67945 0.3048)
			(end 0.120396 0.3048)
			(stroke
				(width 0.1)
				(type default)
			)
			(layer "F.Fab")
		)
		(fp_line
			(start 0.67945 -0.3048)
			(end 0.67945 0.3048)
			(stroke
				(width 0.1)
				(type default)
			)
			(layer "F.Fab")
		)
		(fp_line
			(start 0.12065 -0.2794)
			(end 0.12065 -0.3048)
			(stroke
				(width 0.1)
				(type default)
			)
			(layer "F.Fab")
		)
		(fp_line
			(start 0.12065 -0.3048)
			(end 0.67945 -0.3048)
			(stroke
				(width 0.1)
				(type default)
			)
			(layer "F.Fab")
		)
		(fp_line
			(start 0.120396 0.3048)
			(end 0.120396 0.2794)
			(stroke
				(width 0.1)
				(type default)
			)
			(layer "F.Fab")
		)
		(fp_line
			(start 0.120396 0.2794)
			(end -0.12065 0.2794)
			(stroke
				(width 0.1)
				(type default)
			)
			(layer "F.Fab")
		)
		(fp_line
			(start -0.12065 0.3048)
			(end -0.67945 0.3048)
			(stroke
				(width 0.1)
				(type default)
			)
			(layer "F.Fab")
		)
		(fp_line
			(start -0.12065 0.2794)
			(end -0.12065 0.3048)
			(stroke
				(width 0.1)
				(type default)
			)
			(layer "F.Fab")
		)
		(fp_line
			(start -0.12065 -0.2794)
			(end 0.12065 -0.2794)
			(stroke
				(width 0.1)
				(type default)
			)
			(layer "F.Fab")
		)
		(fp_line
			(start -0.12065 -0.305054)
			(end -0.12065 -0.2794)
			(stroke
				(width 0.1)
				(type default)
			)
			(layer "F.Fab")
		)
		(fp_line
			(start -0.67945 0.3048)
			(end -0.67945 -0.305054)
			(stroke
				(width 0.1)
				(type default)
			)
			(layer "F.Fab")
		)
		(fp_line
			(start -0.67945 -0.305054)
			(end -0.12065 -0.305054)
			(stroke
				(width 0.1)
				(type default)
			)
			(layer "F.Fab")
		)
		(pad "1" smd circle
			(at -0.40005 0 180)
			(size 0 0)
			(layers "F.Cu" "F.Mask" "F.Paste")
			(net "P3V3_AUX")
		)
		(pad "2" smd circle
			(at 0.40005 0 180)
			(size 0 0)
			(layers "F.Cu" "F.Mask" "F.Paste")
			(net "RST_PLTRST_N")
		)
	)
	(footprint ""
		(layer "F.Cu")
		(at 80.53959 -159.235648 180)
		(property "Reference" "R93"
			(at 0 0 180)
			(layer "F.SilkS")
			(hide yes)
			(effects
				(font
					(size 1.27 1.27)
				)
			)
		)
		(property "Value" ""
			(at 0 0 180)
			(layer "F.Fab")
			(effects
				(font
					(size 1.27 1.27)
				)
			)
		)
		(duplicate_pad_numbers_are_jumpers no)
		(fp_line
			(start 0.7874 0.4064)
			(end -0.7874 0.4064)
			(stroke
				(width 0.1524)
				(type default)
			)
			(layer "F.SilkS")
		)
		(fp_line
			(start 0.7874 -0.4064)
			(end 0.7874 0.4064)
			(stroke
				(width 0.1524)
				(type default)
			)
			(layer "F.SilkS")
		)
		(fp_line
			(start -0.7874 0.4064)
			(end -0.7874 -0.4064)
			(stroke
				(width 0.1524)
				(type default)
			)
			(layer "F.SilkS")
		)
		(fp_line
			(start -0.7874 -0.4064)
			(end 0.7874 -0.4064)
			(stroke
				(width 0.1524)
				(type default)
			)
			(layer "F.SilkS")
		)
		(fp_line
			(start 0.67945 0.3048)
			(end 0.120396 0.3048)
			(stroke
				(width 0.1)
				(type default)
			)
			(layer "F.Fab")
		)
		(fp_line
			(start 0.67945 -0.3048)
			(end 0.67945 0.3048)
			(stroke
				(width 0.1)
				(type default)
			)
			(layer "F.Fab")
		)
		(fp_line
			(start 0.12065 -0.2794)
			(end 0.12065 -0.3048)
			(stroke
				(width 0.1)
				(type default)
			)
			(layer "F.Fab")
		)
		(fp_line
			(start 0.12065 -0.3048)
			(end 0.67945 -0.3048)
			(stroke
				(width 0.1)
				(type default)
			)
			(layer "F.Fab")
		)
		(fp_line
			(start 0.120396 0.3048)
			(end 0.120396 0.2794)
			(stroke
				(width 0.1)
				(type default)
			)
			(layer "F.Fab")
		)
		(fp_line
			(start 0.120396 0.2794)
			(end -0.12065 0.2794)
			(stroke
				(width 0.1)
				(type default)
			)
			(layer "F.Fab")
		)
		(fp_line
			(start -0.12065 0.3048)
			(end -0.67945 0.3048)
			(stroke
				(width 0.1)
				(type default)
			)
			(layer "F.Fab")
		)
		(fp_line
			(start -0.12065 0.2794)
			(end -0.12065 0.3048)
			(stroke
				(width 0.1)
				(type default)
			)
			(layer "F.Fab")
		)
		(fp_line
			(start -0.12065 -0.2794)
			(end 0.12065 -0.2794)
			(stroke
				(width 0.1)
				(type default)
			)
			(layer "F.Fab")
		)
		(fp_line
			(start -0.12065 -0.305054)
			(end -0.12065 -0.2794)
			(stroke
				(width 0.1)
				(type default)
			)
			(layer "F.Fab")
		)
		(fp_line
			(start -0.67945 0.3048)
			(end -0.67945 -0.305054)
			(stroke
				(width 0.1)
				(type default)
			)
			(layer "F.Fab")
		)
		(fp_line
			(start -0.67945 -0.305054)
			(end -0.12065 -0.305054)
			(stroke
				(width 0.1)
				(type default)
			)
			(layer "F.Fab")
		)
		(pad "1" smd circle
			(at -0.40005 0 180)
			(size 0 0)
			(layers "F.Cu" "F.Mask" "F.Paste")
			(net "PRSNT_NIC1_N")
		)
		(pad "2" smd circle
			(at 0.40005 0 180)
			(size 0 0)
			(layers "F.Cu" "F.Mask" "F.Paste")
			(net "PRSNTB3_NIC1_N")
		)
	)
	(footprint ""
		(layer "F.Cu")
		(at 374.543828 -42.84091)
		(property "Reference" "R637"
			(at 0 0 0)
			(layer "F.SilkS")
			(hide yes)
			(effects
				(font
					(size 1.27 1.27)
				)
			)
		)
		(property "Value" ""
			(at 0 0 0)
			(layer "F.Fab")
			(effects
				(font
					(size 1.27 1.27)
				)
			)
		)
		(duplicate_pad_numbers_are_jumpers no)
		(fp_line
			(start -0.7874 -0.4064)
			(end 0.7874 -0.4064)
			(stroke
				(width 0.1524)
				(type default)
			)
			(layer "F.SilkS")
		)
		(fp_line
			(start -0.7874 0.4064)
			(end -0.7874 -0.4064)
			(stroke
				(width 0.1524)
				(type default)
			)
			(layer "F.SilkS")
		)
		(fp_line
			(start 0.7874 -0.4064)
			(end 0.7874 0.4064)
			(stroke
				(width 0.1524)
				(type default)
			)
			(layer "F.SilkS")
		)
		(fp_line
			(start 0.7874 0.4064)
			(end -0.7874 0.4064)
			(stroke
				(width 0.1524)
				(type default)
			)
			(layer "F.SilkS")
		)
		(fp_line
			(start -0.67945 -0.305054)
			(end -0.12065 -0.305054)
			(stroke
				(width 0.1)
				(type default)
			)
			(layer "F.Fab")
		)
		(fp_line
			(start -0.67945 0.3048)
			(end -0.67945 -0.305054)
			(stroke
				(width 0.1)
				(type default)
			)
			(layer "F.Fab")
		)
		(fp_line
			(start -0.12065 -0.305054)
			(end -0.12065 -0.2794)
			(stroke
				(width 0.1)
				(type default)
			)
			(layer "F.Fab")
		)
		(fp_line
			(start -0.12065 -0.2794)
			(end 0.12065 -0.2794)
			(stroke
				(width 0.1)
				(type default)
			)
			(layer "F.Fab")
		)
		(fp_line
			(start -0.12065 0.2794)
			(end -0.12065 0.3048)
			(stroke
				(width 0.1)
				(type default)
			)
			(layer "F.Fab")
		)
		(fp_line
			(start -0.12065 0.3048)
			(end -0.67945 0.3048)
			(stroke
				(width 0.1)
				(type default)
			)
			(layer "F.Fab")
		)
		(fp_line
			(start 0.120396 0.2794)
			(end -0.12065 0.2794)
			(stroke
				(width 0.1)
				(type default)
			)
			(layer "F.Fab")
		)
		(fp_line
			(start 0.120396 0.3048)
			(end 0.120396 0.2794)
			(stroke
				(width 0.1)
				(type default)
			)
			(layer "F.Fab")
		)
		(fp_line
			(start 0.12065 -0.3048)
			(end 0.67945 -0.3048)
			(stroke
				(width 0.1)
				(type default)
			)
			(layer "F.Fab")
		)
		(fp_line
			(start 0.12065 -0.2794)
			(end 0.12065 -0.3048)
			(stroke
				(width 0.1)
				(type default)
			)
			(layer "F.Fab")
		)
		(fp_line
			(start 0.67945 -0.3048)
			(end 0.67945 0.3048)
			(stroke
				(width 0.1)
				(type default)
			)
			(layer "F.Fab")
		)
		(fp_line
			(start 0.67945 0.3048)
			(end 0.120396 0.3048)
			(stroke
				(width 0.1)
				(type default)
			)
			(layer "F.Fab")
		)
		(pad "1" smd circle
			(at -0.40005 0)
			(size 0 0)
			(layers "F.Cu" "F.Mask" "F.Paste")
			(net "SSD12_ADC_A1")
		)
		(pad "2" smd circle
			(at 0.40005 0)
			(size 0 0)
			(layers "F.Cu" "F.Mask" "F.Paste")
			(net "P3V3_AUX")
		)
	)
	(footprint ""
		(layer "F.Cu")
		(at 113.561114 -259.782564 180)
		(property "Reference" "PR92"
			(at 0 0 180)
			(layer "F.SilkS")
			(hide yes)
			(effects
				(font
					(size 1.27 1.27)
				)
			)
		)
		(property "Value" ""
			(at 0 0 180)
			(layer "F.Fab")
			(effects
				(font
					(size 1.27 1.27)
				)
			)
		)
		(duplicate_pad_numbers_are_jumpers no)
		(fp_line
			(start 0.7874 0.4064)
			(end -0.7874 0.4064)
			(stroke
				(width 0.1524)
				(type default)
			)
			(layer "F.SilkS")
		)
		(fp_line
			(start 0.7874 -0.4064)
			(end 0.7874 0.4064)
			(stroke
				(width 0.1524)
				(type default)
			)
			(layer "F.SilkS")
		)
		(fp_line
			(start -0.7874 0.4064)
			(end -0.7874 -0.4064)
			(stroke
				(width 0.1524)
				(type default)
			)
			(layer "F.SilkS")
		)
		(fp_line
			(start -0.7874 -0.4064)
			(end 0.7874 -0.4064)
			(stroke
				(width 0.1524)
				(type default)
			)
			(layer "F.SilkS")
		)
		(fp_line
			(start 0.67945 0.3048)
			(end 0.120396 0.3048)
			(stroke
				(width 0.1)
				(type default)
			)
			(layer "F.Fab")
		)
		(fp_line
			(start 0.67945 -0.3048)
			(end 0.67945 0.3048)
			(stroke
				(width 0.1)
				(type default)
			)
			(layer "F.Fab")
		)
		(fp_line
			(start 0.12065 -0.2794)
			(end 0.12065 -0.3048)
			(stroke
				(width 0.1)
				(type default)
			)
			(layer "F.Fab")
		)
		(fp_line
			(start 0.12065 -0.3048)
			(end 0.67945 -0.3048)
			(stroke
				(width 0.1)
				(type default)
			)
			(layer "F.Fab")
		)
		(fp_line
			(start 0.120396 0.3048)
			(end 0.120396 0.2794)
			(stroke
				(width 0.1)
				(type default)
			)
			(layer "F.Fab")
		)
		(fp_line
			(start 0.120396 0.2794)
			(end -0.12065 0.2794)
			(stroke
				(width 0.1)
				(type default)
			)
			(layer "F.Fab")
		)
		(fp_line
			(start -0.12065 0.3048)
			(end -0.67945 0.3048)
			(stroke
				(width 0.1)
				(type default)
			)
			(layer "F.Fab")
		)
		(fp_line
			(start -0.12065 0.2794)
			(end -0.12065 0.3048)
			(stroke
				(width 0.1)
				(type default)
			)
			(layer "F.Fab")
		)
		(fp_line
			(start -0.12065 -0.2794)
			(end 0.12065 -0.2794)
			(stroke
				(width 0.1)
				(type default)
			)
			(layer "F.Fab")
		)
		(fp_line
			(start -0.12065 -0.305054)
			(end -0.12065 -0.2794)
			(stroke
				(width 0.1)
				(type default)
			)
			(layer "F.Fab")
		)
		(fp_line
			(start -0.67945 0.3048)
			(end -0.67945 -0.305054)
			(stroke
				(width 0.1)
				(type default)
			)
			(layer "F.Fab")
		)
		(fp_line
			(start -0.67945 -0.305054)
			(end -0.12065 -0.305054)
			(stroke
				(width 0.1)
				(type default)
			)
			(layer "F.Fab")
		)
		(pad "1" smd circle
			(at -0.40005 0 180)
			(size 0 0)
			(layers "F.Cu" "F.Mask" "F.Paste")
			(net "P0V8_PEX0_ADDR")
		)
		(pad "2" smd circle
			(at 0.40005 0 180)
			(size 0 0)
			(layers "F.Cu" "F.Mask" "F.Paste")
			(net "GND")
		)
	)
	(footprint ""
		(layer "F.Cu")
		(at 148.26361 -384.566668)
		(property "Reference" "C4082"
			(at 0 0 0)
			(layer "F.SilkS")
			(hide yes)
			(effects
				(font
					(size 1.27 1.27)
				)
			)
		)
		(property "Value" ""
			(at 0 0 0)
			(layer "F.Fab")
			(effects
				(font
					(size 1.27 1.27)
				)
			)
		)
		(duplicate_pad_numbers_are_jumpers no)
		(fp_line
			(start -0.7874 -0.4064)
			(end 0.7874 -0.4064)
			(stroke
				(width 0.1524)
				(type default)
			)
			(layer "F.SilkS")
		)
		(fp_line
			(start -0.7874 0.4064)
			(end -0.7874 -0.4064)
			(stroke
				(width 0.1524)
				(type default)
			)
			(layer "F.SilkS")
		)
		(fp_line
			(start 0.7874 -0.4064)
			(end 0.7874 0.4064)
			(stroke
				(width 0.1524)
				(type default)
			)
			(layer "F.SilkS")
		)
		(fp_line
			(start 0.7874 0.4064)
			(end -0.7874 0.4064)
			(stroke
				(width 0.1524)
				(type default)
			)
			(layer "F.SilkS")
		)
		(fp_line
			(start -0.67945 -0.305054)
			(end -0.12065 -0.305054)
			(stroke
				(width 0.1)
				(type default)
			)
			(layer "F.Fab")
		)
		(fp_line
			(start -0.67945 0.3048)
			(end -0.67945 -0.305054)
			(stroke
				(width 0.1)
				(type default)
			)
			(layer "F.Fab")
		)
		(fp_line
			(start -0.12065 -0.305054)
			(end -0.12065 -0.2794)
			(stroke
				(width 0.1)
				(type default)
			)
			(layer "F.Fab")
		)
		(fp_line
			(start -0.12065 -0.2794)
			(end 0.12065 -0.2794)
			(stroke
				(width 0.1)
				(type default)
			)
			(layer "F.Fab")
		)
		(fp_line
			(start -0.12065 0.2794)
			(end -0.12065 0.3048)
			(stroke
				(width 0.1)
				(type default)
			)
			(layer "F.Fab")
		)
		(fp_line
			(start -0.12065 0.3048)
			(end -0.67945 0.3048)
			(stroke
				(width 0.1)
				(type default)
			)
			(layer "F.Fab")
		)
		(fp_line
			(start 0.120396 0.2794)
			(end -0.12065 0.2794)
			(stroke
				(width 0.1)
				(type default)
			)
			(layer "F.Fab")
		)
		(fp_line
			(start 0.120396 0.3048)
			(end 0.120396 0.2794)
			(stroke
				(width 0.1)
				(type default)
			)
			(layer "F.Fab")
		)
		(fp_line
			(start 0.12065 -0.3048)
			(end 0.67945 -0.3048)
			(stroke
				(width 0.1)
				(type default)
			)
			(layer "F.Fab")
		)
		(fp_line
			(start 0.12065 -0.2794)
			(end 0.12065 -0.3048)
			(stroke
				(width 0.1)
				(type default)
			)
			(layer "F.Fab")
		)
		(fp_line
			(start 0.67945 -0.3048)
			(end 0.67945 0.3048)
			(stroke
				(width 0.1)
				(type default)
			)
			(layer "F.Fab")
		)
		(fp_line
			(start 0.67945 0.3048)
			(end 0.120396 0.3048)
			(stroke
				(width 0.1)
				(type default)
			)
			(layer "F.Fab")
		)
		(pad "1" smd circle
			(at -0.40005 0)
			(size 0 0)
			(layers "F.Cu" "F.Mask" "F.Paste")
			(net "GND")
		)
		(pad "2" smd circle
			(at 0.40005 0)
			(size 0 0)
			(layers "F.Cu" "F.Mask" "F.Paste")
			(net "RST_GPU_FPGA_EROT_N")
		)
	)
	(footprint ""
		(layer "F.Cu")
		(at 454.896982 -115.646454 180)
		(property "Reference" "PR7059"
			(at 0 0 180)
			(layer "F.SilkS")
			(hide yes)
			(effects
				(font
					(size 1.27 1.27)
				)
			)
		)
		(property "Value" ""
			(at 0 0 180)
			(layer "F.Fab")
			(effects
				(font
					(size 1.27 1.27)
				)
			)
		)
		(duplicate_pad_numbers_are_jumpers no)
		(fp_line
			(start 0.7874 0.4064)
			(end -0.7874 0.4064)
			(stroke
				(width 0.1524)
				(type default)
			)
			(layer "F.SilkS")
		)
		(fp_line
			(start 0.7874 -0.4064)
			(end 0.7874 0.4064)
			(stroke
				(width 0.1524)
				(type default)
			)
			(layer "F.SilkS")
		)
		(fp_line
			(start -0.7874 0.4064)
			(end -0.7874 -0.4064)
			(stroke
				(width 0.1524)
				(type default)
			)
			(layer "F.SilkS")
		)
		(fp_line
			(start -0.7874 -0.4064)
			(end 0.7874 -0.4064)
			(stroke
				(width 0.1524)
				(type default)
			)
			(layer "F.SilkS")
		)
		(fp_line
			(start 0.67945 0.3048)
			(end 0.120396 0.3048)
			(stroke
				(width 0.1)
				(type default)
			)
			(layer "F.Fab")
		)
		(fp_line
			(start 0.67945 -0.3048)
			(end 0.67945 0.3048)
			(stroke
				(width 0.1)
				(type default)
			)
			(layer "F.Fab")
		)
		(fp_line
			(start 0.12065 -0.2794)
			(end 0.12065 -0.3048)
			(stroke
				(width 0.1)
				(type default)
			)
			(layer "F.Fab")
		)
		(fp_line
			(start 0.12065 -0.3048)
			(end 0.67945 -0.3048)
			(stroke
				(width 0.1)
				(type default)
			)
			(layer "F.Fab")
		)
		(fp_line
			(start 0.120396 0.3048)
			(end 0.120396 0.2794)
			(stroke
				(width 0.1)
				(type default)
			)
			(layer "F.Fab")
		)
		(fp_line
			(start 0.120396 0.2794)
			(end -0.12065 0.2794)
			(stroke
				(width 0.1)
				(type default)
			)
			(layer "F.Fab")
		)
		(fp_line
			(start -0.12065 0.3048)
			(end -0.67945 0.3048)
			(stroke
				(width 0.1)
				(type default)
			)
			(layer "F.Fab")
		)
		(fp_line
			(start -0.12065 0.2794)
			(end -0.12065 0.3048)
			(stroke
				(width 0.1)
				(type default)
			)
			(layer "F.Fab")
		)
		(fp_line
			(start -0.12065 -0.2794)
			(end 0.12065 -0.2794)
			(stroke
				(width 0.1)
				(type default)
			)
			(layer "F.Fab")
		)
		(fp_line
			(start -0.12065 -0.305054)
			(end -0.12065 -0.2794)
			(stroke
				(width 0.1)
				(type default)
			)
			(layer "F.Fab")
		)
		(fp_line
			(start -0.67945 0.3048)
			(end -0.67945 -0.305054)
			(stroke
				(width 0.1)
				(type default)
			)
			(layer "F.Fab")
		)
		(fp_line
			(start -0.67945 -0.305054)
			(end -0.12065 -0.305054)
			(stroke
				(width 0.1)
				(type default)
			)
			(layer "F.Fab")
		)
		(pad "1" smd circle
			(at -0.40005 0 180)
			(size 0 0)
			(layers "F.Cu" "F.Mask" "F.Paste")
			(net "P12V_NIC7_CO_OV_FB")
		)
		(pad "2" smd circle
			(at 0.40005 0 180)
			(size 0 0)
			(layers "F.Cu" "F.Mask" "F.Paste")
			(net "GND")
		)
	)
	(footprint ""
		(layer "F.Cu")
		(at 250.838716 -22.867366 90)
		(property "Reference" "C3933"
			(at 0 0 90)
			(layer "F.SilkS")
			(hide yes)
			(effects
				(font
					(size 1.27 1.27)
				)
			)
		)
		(property "Value" ""
			(at 0 0 90)
			(layer "F.Fab")
			(effects
				(font
					(size 1.27 1.27)
				)
			)
		)
		(duplicate_pad_numbers_are_jumpers no)
		(fp_line
			(start 0.7874 -0.4064)
			(end 0.7874 0.4064)
			(stroke
				(width 0.1524)
				(type default)
			)
			(layer "F.SilkS")
		)
		(fp_line
			(start -0.7874 -0.4064)
			(end 0.7874 -0.4064)
			(stroke
				(width 0.1524)
				(type default)
			)
			(layer "F.SilkS")
		)
		(fp_line
			(start 0.7874 0.4064)
			(end -0.7874 0.4064)
			(stroke
				(width 0.1524)
				(type default)
			)
			(layer "F.SilkS")
		)
		(fp_line
			(start -0.7874 0.4064)
			(end -0.7874 -0.4064)
			(stroke
				(width 0.1524)
				(type default)
			)
			(layer "F.SilkS")
		)
		(fp_line
			(start -0.12065 -0.305054)
			(end -0.12065 -0.2794)
			(stroke
				(width 0.1)
				(type default)
			)
			(layer "F.Fab")
		)
		(fp_line
			(start -0.67945 -0.305054)
			(end -0.12065 -0.305054)
			(stroke
				(width 0.1)
				(type default)
			)
			(layer "F.Fab")
		)
		(fp_line
			(start 0.67945 -0.3048)
			(end 0.67945 0.3048)
			(stroke
				(width 0.1)
				(type default)
			)
			(layer "F.Fab")
		)
		(fp_line
			(start 0.12065 -0.3048)
			(end 0.67945 -0.3048)
			(stroke
				(width 0.1)
				(type default)
			)
			(layer "F.Fab")
		)
		(fp_line
			(start 0.12065 -0.2794)
			(end 0.12065 -0.3048)
			(stroke
				(width 0.1)
				(type default)
			)
			(layer "F.Fab")
		)
		(fp_line
			(start -0.12065 -0.2794)
			(end 0.12065 -0.2794)
			(stroke
				(width 0.1)
				(type default)
			)
			(layer "F.Fab")
		)
		(fp_line
			(start 0.120396 0.2794)
			(end -0.12065 0.2794)
			(stroke
				(width 0.1)
				(type default)
			)
			(layer "F.Fab")
		)
		(fp_line
			(start -0.12065 0.2794)
			(end -0.12065 0.3048)
			(stroke
				(width 0.1)
				(type default)
			)
			(layer "F.Fab")
		)
		(fp_line
			(start 0.67945 0.3048)
			(end 0.120396 0.3048)
			(stroke
				(width 0.1)
				(type default)
			)
			(layer "F.Fab")
		)
		(fp_line
			(start 0.120396 0.3048)
			(end 0.120396 0.2794)
			(stroke
				(width 0.1)
				(type default)
			)
			(layer "F.Fab")
		)
		(fp_line
			(start -0.12065 0.3048)
			(end -0.67945 0.3048)
			(stroke
				(width 0.1)
				(type default)
			)
			(layer "F.Fab")
		)
		(fp_line
			(start -0.67945 0.3048)
			(end -0.67945 -0.305054)
			(stroke
				(width 0.1)
				(type default)
			)
			(layer "F.Fab")
		)
		(pad "1" smd circle
			(at -0.40005 0 90)
			(size 0 0)
			(layers "F.Cu" "F.Mask" "F.Paste")
			(net "P12V_SSD8")
		)
		(pad "2" smd circle
			(at 0.40005 0 90)
			(size 0 0)
			(layers "F.Cu" "F.Mask" "F.Paste")
			(net "GND")
		)
	)
	(footprint ""
		(layer "F.Cu")
		(at 102.402386 -284.834838 90)
		(property "Reference" "PC59"
			(at 0 0 90)
			(layer "F.SilkS")
			(hide yes)
			(effects
				(font
					(size 1.27 1.27)
				)
			)
		)
		(property "Value" ""
			(at 0 0 90)
			(layer "F.Fab")
			(effects
				(font
					(size 1.27 1.27)
				)
			)
		)
		(duplicate_pad_numbers_are_jumpers no)
		(fp_line
			(start 0.7874 -0.4064)
			(end 0.7874 0.4064)
			(stroke
				(width 0.1524)
				(type default)
			)
			(layer "F.SilkS")
		)
		(fp_line
			(start -0.7874 -0.4064)
			(end 0.7874 -0.4064)
			(stroke
				(width 0.1524)
				(type default)
			)
			(layer "F.SilkS")
		)
		(fp_line
			(start 0.7874 0.4064)
			(end -0.7874 0.4064)
			(stroke
				(width 0.1524)
				(type default)
			)
			(layer "F.SilkS")
		)
		(fp_line
			(start -0.7874 0.4064)
			(end -0.7874 -0.4064)
			(stroke
				(width 0.1524)
				(type default)
			)
			(layer "F.SilkS")
		)
		(fp_line
			(start -0.12065 -0.305054)
			(end -0.12065 -0.2794)
			(stroke
				(width 0.1)
				(type default)
			)
			(layer "F.Fab")
		)
		(fp_line
			(start -0.67945 -0.305054)
			(end -0.12065 -0.305054)
			(stroke
				(width 0.1)
				(type default)
			)
			(layer "F.Fab")
		)
		(fp_line
			(start 0.67945 -0.3048)
			(end 0.67945 0.3048)
			(stroke
				(width 0.1)
				(type default)
			)
			(layer "F.Fab")
		)
		(fp_line
			(start 0.12065 -0.3048)
			(end 0.67945 -0.3048)
			(stroke
				(width 0.1)
				(type default)
			)
			(layer "F.Fab")
		)
		(fp_line
			(start 0.12065 -0.2794)
			(end 0.12065 -0.3048)
			(stroke
				(width 0.1)
				(type default)
			)
			(layer "F.Fab")
		)
		(fp_line
			(start -0.12065 -0.2794)
			(end 0.12065 -0.2794)
			(stroke
				(width 0.1)
				(type default)
			)
			(layer "F.Fab")
		)
		(fp_line
			(start 0.120396 0.2794)
			(end -0.12065 0.2794)
			(stroke
				(width 0.1)
				(type default)
			)
			(layer "F.Fab")
		)
		(fp_line
			(start -0.12065 0.2794)
			(end -0.12065 0.3048)
			(stroke
				(width 0.1)
				(type default)
			)
			(layer "F.Fab")
		)
		(fp_line
			(start 0.67945 0.3048)
			(end 0.120396 0.3048)
			(stroke
				(width 0.1)
				(type default)
			)
			(layer "F.Fab")
		)
		(fp_line
			(start 0.120396 0.3048)
			(end 0.120396 0.2794)
			(stroke
				(width 0.1)
				(type default)
			)
			(layer "F.Fab")
		)
		(fp_line
			(start -0.12065 0.3048)
			(end -0.67945 0.3048)
			(stroke
				(width 0.1)
				(type default)
			)
			(layer "F.Fab")
		)
		(fp_line
			(start -0.67945 0.3048)
			(end -0.67945 -0.305054)
			(stroke
				(width 0.1)
				(type default)
			)
			(layer "F.Fab")
		)
		(pad "1" smd circle
			(at -0.40005 0 90)
			(size 0 0)
			(layers "F.Cu" "F.Mask" "F.Paste")
			(net "SW_P12V_P0V8_PEX0_FLT")
		)
		(pad "2" smd circle
			(at 0.40005 0 90)
			(size 0 0)
			(layers "F.Cu" "F.Mask" "F.Paste")
			(net "GND")
		)
	)
	(footprint ""
		(layer "F.Cu")
		(at 355.727 -183.388)
		(property "Reference" "R4747"
			(at 0 0 0)
			(layer "F.SilkS")
			(hide yes)
			(effects
				(font
					(size 1.27 1.27)
				)
			)
		)
		(property "Value" ""
			(at 0 0 0)
			(layer "F.Fab")
			(effects
				(font
					(size 1.27 1.27)
				)
			)
		)
		(duplicate_pad_numbers_are_jumpers no)
		(fp_line
			(start -0.7874 -0.4064)
			(end 0.7874 -0.4064)
			(stroke
				(width 0.1524)
				(type default)
			)
			(layer "F.SilkS")
		)
		(fp_line
			(start -0.7874 0.4064)
			(end -0.7874 -0.4064)
			(stroke
				(width 0.1524)
				(type default)
			)
			(layer "F.SilkS")
		)
		(fp_line
			(start 0.7874 -0.4064)
			(end 0.7874 0.4064)
			(stroke
				(width 0.1524)
				(type default)
			)
			(layer "F.SilkS")
		)
		(fp_line
			(start 0.7874 0.4064)
			(end -0.7874 0.4064)
			(stroke
				(width 0.1524)
				(type default)
			)
			(layer "F.SilkS")
		)
		(fp_line
			(start -0.67945 -0.305054)
			(end -0.12065 -0.305054)
			(stroke
				(width 0.1)
				(type default)
			)
			(layer "F.Fab")
		)
		(fp_line
			(start -0.67945 0.3048)
			(end -0.67945 -0.305054)
			(stroke
				(width 0.1)
				(type default)
			)
			(layer "F.Fab")
		)
		(fp_line
			(start -0.12065 -0.305054)
			(end -0.12065 -0.2794)
			(stroke
				(width 0.1)
				(type default)
			)
			(layer "F.Fab")
		)
		(fp_line
			(start -0.12065 -0.2794)
			(end 0.12065 -0.2794)
			(stroke
				(width 0.1)
				(type default)
			)
			(layer "F.Fab")
		)
		(fp_line
			(start -0.12065 0.2794)
			(end -0.12065 0.3048)
			(stroke
				(width 0.1)
				(type default)
			)
			(layer "F.Fab")
		)
		(fp_line
			(start -0.12065 0.3048)
			(end -0.67945 0.3048)
			(stroke
				(width 0.1)
				(type default)
			)
			(layer "F.Fab")
		)
		(fp_line
			(start 0.120396 0.2794)
			(end -0.12065 0.2794)
			(stroke
				(width 0.1)
				(type default)
			)
			(layer "F.Fab")
		)
		(fp_line
			(start 0.120396 0.3048)
			(end 0.120396 0.2794)
			(stroke
				(width 0.1)
				(type default)
			)
			(layer "F.Fab")
		)
		(fp_line
			(start 0.12065 -0.3048)
			(end 0.67945 -0.3048)
			(stroke
				(width 0.1)
				(type default)
			)
			(layer "F.Fab")
		)
		(fp_line
			(start 0.12065 -0.2794)
			(end 0.12065 -0.3048)
			(stroke
				(width 0.1)
				(type default)
			)
			(layer "F.Fab")
		)
		(fp_line
			(start 0.67945 -0.3048)
			(end 0.67945 0.3048)
			(stroke
				(width 0.1)
				(type default)
			)
			(layer "F.Fab")
		)
		(fp_line
			(start 0.67945 0.3048)
			(end 0.120396 0.3048)
			(stroke
				(width 0.1)
				(type default)
			)
			(layer "F.Fab")
		)
		(pad "1" smd circle
			(at -0.40005 0)
			(size 0 0)
			(layers "F.Cu" "F.Mask" "F.Paste")
			(net "PCA9555_0_PEX2_A0")
		)
		(pad "2" smd circle
			(at 0.40005 0)
			(size 0 0)
			(layers "F.Cu" "F.Mask" "F.Paste")
			(net "P3V3_AUX")
		)
	)
	(footprint ""
		(layer "F.Cu")
		(at 268.53515 -78.885796)
		(property "Reference" "R1050"
			(at 0 0 0)
			(layer "F.SilkS")
			(hide yes)
			(effects
				(font
					(size 1.27 1.27)
				)
			)
		)
		(property "Value" ""
			(at 0 0 0)
			(layer "F.Fab")
			(effects
				(font
					(size 1.27 1.27)
				)
			)
		)
		(duplicate_pad_numbers_are_jumpers no)
		(fp_line
			(start -0.7874 -0.4064)
			(end 0.7874 -0.4064)
			(stroke
				(width 0.1524)
				(type default)
			)
			(layer "F.SilkS")
		)
		(fp_line
			(start -0.7874 0.4064)
			(end -0.7874 -0.4064)
			(stroke
				(width 0.1524)
				(type default)
			)
			(layer "F.SilkS")
		)
		(fp_line
			(start 0.7874 -0.4064)
			(end 0.7874 0.4064)
			(stroke
				(width 0.1524)
				(type default)
			)
			(layer "F.SilkS")
		)
		(fp_line
			(start 0.7874 0.4064)
			(end -0.7874 0.4064)
			(stroke
				(width 0.1524)
				(type default)
			)
			(layer "F.SilkS")
		)
		(fp_line
			(start -0.67945 -0.305054)
			(end -0.12065 -0.305054)
			(stroke
				(width 0.1)
				(type default)
			)
			(layer "F.Fab")
		)
		(fp_line
			(start -0.67945 0.3048)
			(end -0.67945 -0.305054)
			(stroke
				(width 0.1)
				(type default)
			)
			(layer "F.Fab")
		)
		(fp_line
			(start -0.12065 -0.305054)
			(end -0.12065 -0.2794)
			(stroke
				(width 0.1)
				(type default)
			)
			(layer "F.Fab")
		)
		(fp_line
			(start -0.12065 -0.2794)
			(end 0.12065 -0.2794)
			(stroke
				(width 0.1)
				(type default)
			)
			(layer "F.Fab")
		)
		(fp_line
			(start -0.12065 0.2794)
			(end -0.12065 0.3048)
			(stroke
				(width 0.1)
				(type default)
			)
			(layer "F.Fab")
		)
		(fp_line
			(start -0.12065 0.3048)
			(end -0.67945 0.3048)
			(stroke
				(width 0.1)
				(type default)
			)
			(layer "F.Fab")
		)
		(fp_line
			(start 0.120396 0.2794)
			(end -0.12065 0.2794)
			(stroke
				(width 0.1)
				(type default)
			)
			(layer "F.Fab")
		)
		(fp_line
			(start 0.120396 0.3048)
			(end 0.120396 0.2794)
			(stroke
				(width 0.1)
				(type default)
			)
			(layer "F.Fab")
		)
		(fp_line
			(start 0.12065 -0.3048)
			(end 0.67945 -0.3048)
			(stroke
				(width 0.1)
				(type default)
			)
			(layer "F.Fab")
		)
		(fp_line
			(start 0.12065 -0.2794)
			(end 0.12065 -0.3048)
			(stroke
				(width 0.1)
				(type default)
			)
			(layer "F.Fab")
		)
		(fp_line
			(start 0.67945 -0.3048)
			(end 0.67945 0.3048)
			(stroke
				(width 0.1)
				(type default)
			)
			(layer "F.Fab")
		)
		(fp_line
			(start 0.67945 0.3048)
			(end 0.120396 0.3048)
			(stroke
				(width 0.1)
				(type default)
			)
			(layer "F.Fab")
		)
		(pad "1" smd circle
			(at -0.40005 0)
			(size 0 0)
			(layers "F.Cu" "F.Mask" "F.Paste")
			(net "CLK_BUFFER_9ZXL0851E_0_7_OE1_N")
		)
		(pad "2" smd circle
			(at 0.40005 0)
			(size 0 0)
			(layers "F.Cu" "F.Mask" "F.Paste")
			(net "P3V3")
		)
	)
	(footprint ""
		(layer "F.Cu")
		(at 268.461236 -367.527586 -90)
		(property "Reference" "PQ6606"
			(at -1.826768 -3.552952 0)
			(unlocked yes)
			(layer "F.SilkS")
			(effects
				(font
					(size 0.7874 0.5842)
					(thickness 0.1524)
				)
				(justify left)
			)
		)
		(property "Value" ""
			(at 0 0 270)
			(layer "F.Fab")
			(effects
				(font
					(size 1.27 1.27)
				)
			)
		)
		(duplicate_pad_numbers_are_jumpers no)
		(fp_line
			(start -1.584198 1.53416)
			(end -1.584198 -1.53416)
			(stroke
				(width 0.1524)
				(type default)
			)
			(layer "F.SilkS")
		)
		(fp_line
			(start 1.584198 1.53416)
			(end -1.584198 1.53416)
			(stroke
				(width 0.1524)
				(type default)
			)
			(layer "F.SilkS")
		)
		(fp_line
			(start -1.584198 -1.53416)
			(end 1.584198 -1.53416)
			(stroke
				(width 0.1524)
				(type default)
			)
			(layer "F.SilkS")
		)
		(fp_line
			(start 1.584198 -1.53416)
			(end 1.584198 1.53416)
			(stroke
				(width 0.1524)
				(type default)
			)
			(layer "F.SilkS")
		)
		(fp_line
			(start -0.700024 1.500124)
			(end -0.700024 -1.500124)
			(stroke
				(width 0.1)
				(type default)
			)
			(layer "F.Fab")
		)
		(fp_line
			(start 0.700024 1.500124)
			(end -0.700024 1.500124)
			(stroke
				(width 0.1)
				(type default)
			)
			(layer "F.Fab")
		)
		(fp_line
			(start -0.700024 -1.500124)
			(end 0.700024 -1.500124)
			(stroke
				(width 0.1)
				(type default)
			)
			(layer "F.Fab")
		)
		(fp_line
			(start 0.700024 -1.500124)
			(end 0.700024 1.500124)
			(stroke
				(width 0.1)
				(type default)
			)
			(layer "F.Fab")
		)
		(pad "B" smd rect
			(at -0.999998 -0.94996)
			(size 0.8128 0.9144)
			(layers "F.Cu" "F.Mask" "F.Paste")
			(net "LTC4282_TEMP_R_D+")
		)
		(pad "C" smd rect
			(at 0.999998 0)
			(size 0.8128 0.9144)
			(layers "F.Cu" "F.Mask" "F.Paste")
			(net "LTC4282_TEMP_R_D+")
		)
		(pad "E" smd rect
			(at -0.999998 0.94996)
			(size 0.8128 0.9144)
			(layers "F.Cu" "F.Mask" "F.Paste")
			(net "LTC4282_TEMP_R_D-")
		)
	)
	(footprint ""
		(layer "F.Cu")
		(at 408.529282 -202.362308 -90)
		(property "Reference" "R6441"
			(at 0 0 270)
			(layer "F.SilkS")
			(hide yes)
			(effects
				(font
					(size 1.27 1.27)
				)
			)
		)
		(property "Value" ""
			(at 0 0 270)
			(layer "F.Fab")
			(effects
				(font
					(size 1.27 1.27)
				)
			)
		)
		(duplicate_pad_numbers_are_jumpers no)
		(fp_line
			(start -0.7874 0.4064)
			(end -0.7874 -0.4064)
			(stroke
				(width 0.1524)
				(type default)
			)
			(layer "F.SilkS")
		)
		(fp_line
			(start 0.7874 0.4064)
			(end -0.7874 0.4064)
			(stroke
				(width 0.1524)
				(type default)
			)
			(layer "F.SilkS")
		)
		(fp_line
			(start -0.7874 -0.4064)
			(end 0.7874 -0.4064)
			(stroke
				(width 0.1524)
				(type default)
			)
			(layer "F.SilkS")
		)
		(fp_line
			(start 0.7874 -0.4064)
			(end 0.7874 0.4064)
			(stroke
				(width 0.1524)
				(type default)
			)
			(layer "F.SilkS")
		)
		(fp_line
			(start -0.67945 0.3048)
			(end -0.67945 -0.305054)
			(stroke
				(width 0.1)
				(type default)
			)
			(layer "F.Fab")
		)
		(fp_line
			(start -0.12065 0.3048)
			(end -0.67945 0.3048)
			(stroke
				(width 0.1)
				(type default)
			)
			(layer "F.Fab")
		)
		(fp_line
			(start 0.120396 0.3048)
			(end 0.120396 0.2794)
			(stroke
				(width 0.1)
				(type default)
			)
			(layer "F.Fab")
		)
		(fp_line
			(start 0.67945 0.3048)
			(end 0.120396 0.3048)
			(stroke
				(width 0.1)
				(type default)
			)
			(layer "F.Fab")
		)
		(fp_line
			(start -0.12065 0.2794)
			(end -0.12065 0.3048)
			(stroke
				(width 0.1)
				(type default)
			)
			(layer "F.Fab")
		)
		(fp_line
			(start 0.120396 0.2794)
			(end -0.12065 0.2794)
			(stroke
				(width 0.1)
				(type default)
			)
			(layer "F.Fab")
		)
		(fp_line
			(start -0.12065 -0.2794)
			(end 0.12065 -0.2794)
			(stroke
				(width 0.1)
				(type default)
			)
			(layer "F.Fab")
		)
		(fp_line
			(start 0.12065 -0.2794)
			(end 0.12065 -0.3048)
			(stroke
				(width 0.1)
				(type default)
			)
			(layer "F.Fab")
		)
		(fp_line
			(start 0.12065 -0.3048)
			(end 0.67945 -0.3048)
			(stroke
				(width 0.1)
				(type default)
			)
			(layer "F.Fab")
		)
		(fp_line
			(start 0.67945 -0.3048)
			(end 0.67945 0.3048)
			(stroke
				(width 0.1)
				(type default)
			)
			(layer "F.Fab")
		)
		(fp_line
			(start -0.67945 -0.305054)
			(end -0.12065 -0.305054)
			(stroke
				(width 0.1)
				(type default)
			)
			(layer "F.Fab")
		)
		(fp_line
			(start -0.12065 -0.305054)
			(end -0.12065 -0.2794)
			(stroke
				(width 0.1)
				(type default)
			)
			(layer "F.Fab")
		)
		(pad "1" smd circle
			(at -0.40005 0 270)
			(size 0 0)
			(layers "F.Cu" "F.Mask" "F.Paste")
			(net "FPGA_PEX2_MODE_SEL2_ISO")
		)
		(pad "2" smd circle
			(at 0.40005 0 270)
			(size 0 0)
			(layers "F.Cu" "F.Mask" "F.Paste")
			(net "PEX2_MODE_SEL2")
		)
	)
	(footprint ""
		(layer "F.Cu")
		(at 34.502344 -250.070874 -90)
		(property "Reference" "R1165"
			(at 0 0 270)
			(layer "F.SilkS")
			(hide yes)
			(effects
				(font
					(size 1.27 1.27)
				)
			)
		)
		(property "Value" ""
			(at 0 0 270)
			(layer "F.Fab")
			(effects
				(font
					(size 1.27 1.27)
				)
			)
		)
		(duplicate_pad_numbers_are_jumpers no)
		(fp_line
			(start -0.7874 0.4064)
			(end -0.7874 -0.4064)
			(stroke
				(width 0.1524)
				(type default)
			)
			(layer "F.SilkS")
		)
		(fp_line
			(start 0.7874 0.4064)
			(end -0.7874 0.4064)
			(stroke
				(width 0.1524)
				(type default)
			)
			(layer "F.SilkS")
		)
		(fp_line
			(start -0.7874 -0.4064)
			(end 0.7874 -0.4064)
			(stroke
				(width 0.1524)
				(type default)
			)
			(layer "F.SilkS")
		)
		(fp_line
			(start 0.7874 -0.4064)
			(end 0.7874 0.4064)
			(stroke
				(width 0.1524)
				(type default)
			)
			(layer "F.SilkS")
		)
		(fp_line
			(start -0.67945 0.3048)
			(end -0.67945 -0.305054)
			(stroke
				(width 0.1)
				(type default)
			)
			(layer "F.Fab")
		)
		(fp_line
			(start -0.12065 0.3048)
			(end -0.67945 0.3048)
			(stroke
				(width 0.1)
				(type default)
			)
			(layer "F.Fab")
		)
		(fp_line
			(start 0.120396 0.3048)
			(end 0.120396 0.2794)
			(stroke
				(width 0.1)
				(type default)
			)
			(layer "F.Fab")
		)
		(fp_line
			(start 0.67945 0.3048)
			(end 0.120396 0.3048)
			(stroke
				(width 0.1)
				(type default)
			)
			(layer "F.Fab")
		)
		(fp_line
			(start -0.12065 0.2794)
			(end -0.12065 0.3048)
			(stroke
				(width 0.1)
				(type default)
			)
			(layer "F.Fab")
		)
		(fp_line
			(start 0.120396 0.2794)
			(end -0.12065 0.2794)
			(stroke
				(width 0.1)
				(type default)
			)
			(layer "F.Fab")
		)
		(fp_line
			(start -0.12065 -0.2794)
			(end 0.12065 -0.2794)
			(stroke
				(width 0.1)
				(type default)
			)
			(layer "F.Fab")
		)
		(fp_line
			(start 0.12065 -0.2794)
			(end 0.12065 -0.3048)
			(stroke
				(width 0.1)
				(type default)
			)
			(layer "F.Fab")
		)
		(fp_line
			(start 0.12065 -0.3048)
			(end 0.67945 -0.3048)
			(stroke
				(width 0.1)
				(type default)
			)
			(layer "F.Fab")
		)
		(fp_line
			(start 0.67945 -0.3048)
			(end 0.67945 0.3048)
			(stroke
				(width 0.1)
				(type default)
			)
			(layer "F.Fab")
		)
		(fp_line
			(start -0.67945 -0.305054)
			(end -0.12065 -0.305054)
			(stroke
				(width 0.1)
				(type default)
			)
			(layer "F.Fab")
		)
		(fp_line
			(start -0.12065 -0.305054)
			(end -0.12065 -0.2794)
			(stroke
				(width 0.1)
				(type default)
			)
			(layer "F.Fab")
		)
		(pad "1" smd circle
			(at -0.40005 0 270)
			(size 0 0)
			(layers "F.Cu" "F.Mask" "F.Paste")
			(net "PEX0_MODE_SEL11")
		)
		(pad "2" smd circle
			(at 0.40005 0 270)
			(size 0 0)
			(layers "F.Cu" "F.Mask" "F.Paste")
			(net "P1V8_PEX")
		)
	)
	(footprint ""
		(layer "F.Cu")
		(at 431.20183 -32.849312 90)
		(property "Reference" "R5706"
			(at 0 0 90)
			(layer "F.SilkS")
			(hide yes)
			(effects
				(font
					(size 1.27 1.27)
				)
			)
		)
		(property "Value" ""
			(at 0 0 90)
			(layer "F.Fab")
			(effects
				(font
					(size 1.27 1.27)
				)
			)
		)
		(duplicate_pad_numbers_are_jumpers no)
		(fp_line
			(start 0.7874 -0.4064)
			(end 0.7874 0.4064)
			(stroke
				(width 0.1524)
				(type default)
			)
			(layer "F.SilkS")
		)
		(fp_line
			(start -0.7874 -0.4064)
			(end 0.7874 -0.4064)
			(stroke
				(width 0.1524)
				(type default)
			)
			(layer "F.SilkS")
		)
		(fp_line
			(start 0.7874 0.4064)
			(end -0.7874 0.4064)
			(stroke
				(width 0.1524)
				(type default)
			)
			(layer "F.SilkS")
		)
		(fp_line
			(start -0.7874 0.4064)
			(end -0.7874 -0.4064)
			(stroke
				(width 0.1524)
				(type default)
			)
			(layer "F.SilkS")
		)
		(fp_line
			(start -0.12065 -0.305054)
			(end -0.12065 -0.2794)
			(stroke
				(width 0.1)
				(type default)
			)
			(layer "F.Fab")
		)
		(fp_line
			(start -0.67945 -0.305054)
			(end -0.12065 -0.305054)
			(stroke
				(width 0.1)
				(type default)
			)
			(layer "F.Fab")
		)
		(fp_line
			(start 0.67945 -0.3048)
			(end 0.67945 0.3048)
			(stroke
				(width 0.1)
				(type default)
			)
			(layer "F.Fab")
		)
		(fp_line
			(start 0.12065 -0.3048)
			(end 0.67945 -0.3048)
			(stroke
				(width 0.1)
				(type default)
			)
			(layer "F.Fab")
		)
		(fp_line
			(start 0.12065 -0.2794)
			(end 0.12065 -0.3048)
			(stroke
				(width 0.1)
				(type default)
			)
			(layer "F.Fab")
		)
		(fp_line
			(start -0.12065 -0.2794)
			(end 0.12065 -0.2794)
			(stroke
				(width 0.1)
				(type default)
			)
			(layer "F.Fab")
		)
		(fp_line
			(start 0.120396 0.2794)
			(end -0.12065 0.2794)
			(stroke
				(width 0.1)
				(type default)
			)
			(layer "F.Fab")
		)
		(fp_line
			(start -0.12065 0.2794)
			(end -0.12065 0.3048)
			(stroke
				(width 0.1)
				(type default)
			)
			(layer "F.Fab")
		)
		(fp_line
			(start 0.67945 0.3048)
			(end 0.120396 0.3048)
			(stroke
				(width 0.1)
				(type default)
			)
			(layer "F.Fab")
		)
		(fp_line
			(start 0.120396 0.3048)
			(end 0.120396 0.2794)
			(stroke
				(width 0.1)
				(type default)
			)
			(layer "F.Fab")
		)
		(fp_line
			(start -0.12065 0.3048)
			(end -0.67945 0.3048)
			(stroke
				(width 0.1)
				(type default)
			)
			(layer "F.Fab")
		)
		(fp_line
			(start -0.67945 0.3048)
			(end -0.67945 -0.305054)
			(stroke
				(width 0.1)
				(type default)
			)
			(layer "F.Fab")
		)
		(pad "1" smd circle
			(at -0.40005 0 90)
			(size 0 0)
			(layers "F.Cu" "F.Mask" "F.Paste")
			(net "RST_SMB_SSD15_ISO_R_N")
		)
		(pad "2" smd circle
			(at 0.40005 0 90)
			(size 0 0)
			(layers "F.Cu" "F.Mask" "F.Paste")
			(net "RST_SMB_SSD15_ISO_N")
		)
	)
	(footprint ""
		(layer "F.Cu")
		(at 246.554498 -135.993632 -90)
		(property "Reference" "PC309"
			(at 0 0 270)
			(layer "F.SilkS")
			(hide yes)
			(effects
				(font
					(size 1.27 1.27)
				)
			)
		)
		(property "Value" ""
			(at 0 0 270)
			(layer "F.Fab")
			(effects
				(font
					(size 1.27 1.27)
				)
			)
		)
		(duplicate_pad_numbers_are_jumpers no)
		(fp_line
			(start -0.7874 0.4064)
			(end -0.7874 -0.4064)
			(stroke
				(width 0.1524)
				(type default)
			)
			(layer "F.SilkS")
		)
		(fp_line
			(start 0.7874 0.4064)
			(end -0.7874 0.4064)
			(stroke
				(width 0.1524)
				(type default)
			)
			(layer "F.SilkS")
		)
		(fp_line
			(start -0.7874 -0.4064)
			(end 0.7874 -0.4064)
			(stroke
				(width 0.1524)
				(type default)
			)
			(layer "F.SilkS")
		)
		(fp_line
			(start 0.7874 -0.4064)
			(end 0.7874 0.4064)
			(stroke
				(width 0.1524)
				(type default)
			)
			(layer "F.SilkS")
		)
		(fp_line
			(start -0.67945 0.3048)
			(end -0.67945 -0.305054)
			(stroke
				(width 0.1)
				(type default)
			)
			(layer "F.Fab")
		)
		(fp_line
			(start -0.12065 0.3048)
			(end -0.67945 0.3048)
			(stroke
				(width 0.1)
				(type default)
			)
			(layer "F.Fab")
		)
		(fp_line
			(start 0.120396 0.3048)
			(end 0.120396 0.2794)
			(stroke
				(width 0.1)
				(type default)
			)
			(layer "F.Fab")
		)
		(fp_line
			(start 0.67945 0.3048)
			(end 0.120396 0.3048)
			(stroke
				(width 0.1)
				(type default)
			)
			(layer "F.Fab")
		)
		(fp_line
			(start -0.12065 0.2794)
			(end -0.12065 0.3048)
			(stroke
				(width 0.1)
				(type default)
			)
			(layer "F.Fab")
		)
		(fp_line
			(start 0.120396 0.2794)
			(end -0.12065 0.2794)
			(stroke
				(width 0.1)
				(type default)
			)
			(layer "F.Fab")
		)
		(fp_line
			(start -0.12065 -0.2794)
			(end 0.12065 -0.2794)
			(stroke
				(width 0.1)
				(type default)
			)
			(layer "F.Fab")
		)
		(fp_line
			(start 0.12065 -0.2794)
			(end 0.12065 -0.3048)
			(stroke
				(width 0.1)
				(type default)
			)
			(layer "F.Fab")
		)
		(fp_line
			(start 0.12065 -0.3048)
			(end 0.67945 -0.3048)
			(stroke
				(width 0.1)
				(type default)
			)
			(layer "F.Fab")
		)
		(fp_line
			(start 0.67945 -0.3048)
			(end 0.67945 0.3048)
			(stroke
				(width 0.1)
				(type default)
			)
			(layer "F.Fab")
		)
		(fp_line
			(start -0.67945 -0.305054)
			(end -0.12065 -0.305054)
			(stroke
				(width 0.1)
				(type default)
			)
			(layer "F.Fab")
		)
		(fp_line
			(start -0.12065 -0.305054)
			(end -0.12065 -0.2794)
			(stroke
				(width 0.1)
				(type default)
			)
			(layer "F.Fab")
		)
		(pad "1" smd circle
			(at -0.40005 0 270)
			(size 0 0)
			(layers "F.Cu" "F.Mask" "F.Paste")
			(net "P12V_NIC4_R")
		)
		(pad "2" smd circle
			(at 0.40005 0 270)
			(size 0 0)
			(layers "F.Cu" "F.Mask" "F.Paste")
			(net "GND")
		)
	)
	(footprint ""
		(layer "F.Cu")
		(at 134.513828 -356.244906 90)
		(property "Reference" "C2268"
			(at 0 0 90)
			(layer "F.SilkS")
			(hide yes)
			(effects
				(font
					(size 1.27 1.27)
				)
			)
		)
		(property "Value" ""
			(at 0 0 90)
			(layer "F.Fab")
			(effects
				(font
					(size 1.27 1.27)
				)
			)
		)
		(duplicate_pad_numbers_are_jumpers no)
		(fp_line
			(start 0.299974 -0.150114)
			(end 0.299974 0.150114)
			(stroke
				(width 0.1)
				(type default)
			)
			(layer "F.Fab")
		)
		(fp_line
			(start -0.299974 -0.150114)
			(end 0.299974 -0.150114)
			(stroke
				(width 0.1)
				(type default)
			)
			(layer "F.Fab")
		)
		(fp_line
			(start 0.299974 0.150114)
			(end -0.299974 0.150114)
			(stroke
				(width 0.1)
				(type default)
			)
			(layer "F.Fab")
		)
		(fp_line
			(start -0.299974 0.150114)
			(end -0.299974 -0.150114)
			(stroke
				(width 0.1)
				(type default)
			)
			(layer "F.Fab")
		)
		(pad "1" smd rect
			(at -0.2667 0 90)
			(size 0.3048 0.381)
			(layers "F.Cu" "F.Mask" "F.Paste")
			(net "P5E_PEX1_STN5_TX_DN<83>")
		)
		(pad "2" smd rect
			(at 0.2667 0 90)
			(size 0.3048 0.381)
			(layers "F.Cu" "F.Mask" "F.Paste")
			(net "P5E_PEX1_STN5_TX_C_DN<83>")
		)
	)
	(footprint ""
		(layer "F.Cu")
		(at 117.958362 -126.915926)
		(property "Reference" "R4440"
			(at 0 0 0)
			(layer "F.SilkS")
			(hide yes)
			(effects
				(font
					(size 1.27 1.27)
				)
			)
		)
		(property "Value" ""
			(at 0 0 0)
			(layer "F.Fab")
			(effects
				(font
					(size 1.27 1.27)
				)
			)
		)
		(duplicate_pad_numbers_are_jumpers no)
		(fp_line
			(start -0.7874 -0.4064)
			(end 0.7874 -0.4064)
			(stroke
				(width 0.1524)
				(type default)
			)
			(layer "F.SilkS")
		)
		(fp_line
			(start -0.7874 0.4064)
			(end -0.7874 -0.4064)
			(stroke
				(width 0.1524)
				(type default)
			)
			(layer "F.SilkS")
		)
		(fp_line
			(start 0.7874 -0.4064)
			(end 0.7874 0.4064)
			(stroke
				(width 0.1524)
				(type default)
			)
			(layer "F.SilkS")
		)
		(fp_line
			(start 0.7874 0.4064)
			(end -0.7874 0.4064)
			(stroke
				(width 0.1524)
				(type default)
			)
			(layer "F.SilkS")
		)
		(fp_line
			(start -0.67945 -0.305054)
			(end -0.12065 -0.305054)
			(stroke
				(width 0.1)
				(type default)
			)
			(layer "F.Fab")
		)
		(fp_line
			(start -0.67945 0.3048)
			(end -0.67945 -0.305054)
			(stroke
				(width 0.1)
				(type default)
			)
			(layer "F.Fab")
		)
		(fp_line
			(start -0.12065 -0.305054)
			(end -0.12065 -0.2794)
			(stroke
				(width 0.1)
				(type default)
			)
			(layer "F.Fab")
		)
		(fp_line
			(start -0.12065 -0.2794)
			(end 0.12065 -0.2794)
			(stroke
				(width 0.1)
				(type default)
			)
			(layer "F.Fab")
		)
		(fp_line
			(start -0.12065 0.2794)
			(end -0.12065 0.3048)
			(stroke
				(width 0.1)
				(type default)
			)
			(layer "F.Fab")
		)
		(fp_line
			(start -0.12065 0.3048)
			(end -0.67945 0.3048)
			(stroke
				(width 0.1)
				(type default)
			)
			(layer "F.Fab")
		)
		(fp_line
			(start 0.120396 0.2794)
			(end -0.12065 0.2794)
			(stroke
				(width 0.1)
				(type default)
			)
			(layer "F.Fab")
		)
		(fp_line
			(start 0.120396 0.3048)
			(end 0.120396 0.2794)
			(stroke
				(width 0.1)
				(type default)
			)
			(layer "F.Fab")
		)
		(fp_line
			(start 0.12065 -0.3048)
			(end 0.67945 -0.3048)
			(stroke
				(width 0.1)
				(type default)
			)
			(layer "F.Fab")
		)
		(fp_line
			(start 0.12065 -0.2794)
			(end 0.12065 -0.3048)
			(stroke
				(width 0.1)
				(type default)
			)
			(layer "F.Fab")
		)
		(fp_line
			(start 0.67945 -0.3048)
			(end 0.67945 0.3048)
			(stroke
				(width 0.1)
				(type default)
			)
			(layer "F.Fab")
		)
		(fp_line
			(start 0.67945 0.3048)
			(end 0.120396 0.3048)
			(stroke
				(width 0.1)
				(type default)
			)
			(layer "F.Fab")
		)
		(pad "1" smd circle
			(at -0.40005 0)
			(size 0 0)
			(layers "F.Cu" "F.Mask" "F.Paste")
			(net "PWRGD_P3V3")
		)
		(pad "2" smd circle
			(at 0.40005 0)
			(size 0 0)
			(layers "F.Cu" "F.Mask" "F.Paste")
			(net "PWRGD_P3V3_R")
		)
	)
	(footprint ""
		(layer "F.Cu")
		(at 90.867992 -289.230816 90)
		(property "Reference" "R3879"
			(at 0 0 90)
			(layer "F.SilkS")
			(hide yes)
			(effects
				(font
					(size 1.27 1.27)
				)
			)
		)
		(property "Value" ""
			(at 0 0 90)
			(layer "F.Fab")
			(effects
				(font
					(size 1.27 1.27)
				)
			)
		)
		(duplicate_pad_numbers_are_jumpers no)
		(fp_line
			(start 0.7874 -0.4064)
			(end 0.7874 0.4064)
			(stroke
				(width 0.1524)
				(type default)
			)
			(layer "F.SilkS")
		)
		(fp_line
			(start -0.7874 -0.4064)
			(end 0.7874 -0.4064)
			(stroke
				(width 0.1524)
				(type default)
			)
			(layer "F.SilkS")
		)
		(fp_line
			(start 0.7874 0.4064)
			(end -0.7874 0.4064)
			(stroke
				(width 0.1524)
				(type default)
			)
			(layer "F.SilkS")
		)
		(fp_line
			(start -0.7874 0.4064)
			(end -0.7874 -0.4064)
			(stroke
				(width 0.1524)
				(type default)
			)
			(layer "F.SilkS")
		)
		(fp_line
			(start -0.12065 -0.305054)
			(end -0.12065 -0.2794)
			(stroke
				(width 0.1)
				(type default)
			)
			(layer "F.Fab")
		)
		(fp_line
			(start -0.67945 -0.305054)
			(end -0.12065 -0.305054)
			(stroke
				(width 0.1)
				(type default)
			)
			(layer "F.Fab")
		)
		(fp_line
			(start 0.67945 -0.3048)
			(end 0.67945 0.3048)
			(stroke
				(width 0.1)
				(type default)
			)
			(layer "F.Fab")
		)
		(fp_line
			(start 0.12065 -0.3048)
			(end 0.67945 -0.3048)
			(stroke
				(width 0.1)
				(type default)
			)
			(layer "F.Fab")
		)
		(fp_line
			(start 0.12065 -0.2794)
			(end 0.12065 -0.3048)
			(stroke
				(width 0.1)
				(type default)
			)
			(layer "F.Fab")
		)
		(fp_line
			(start -0.12065 -0.2794)
			(end 0.12065 -0.2794)
			(stroke
				(width 0.1)
				(type default)
			)
			(layer "F.Fab")
		)
		(fp_line
			(start 0.120396 0.2794)
			(end -0.12065 0.2794)
			(stroke
				(width 0.1)
				(type default)
			)
			(layer "F.Fab")
		)
		(fp_line
			(start -0.12065 0.2794)
			(end -0.12065 0.3048)
			(stroke
				(width 0.1)
				(type default)
			)
			(layer "F.Fab")
		)
		(fp_line
			(start 0.67945 0.3048)
			(end 0.120396 0.3048)
			(stroke
				(width 0.1)
				(type default)
			)
			(layer "F.Fab")
		)
		(fp_line
			(start 0.120396 0.3048)
			(end 0.120396 0.2794)
			(stroke
				(width 0.1)
				(type default)
			)
			(layer "F.Fab")
		)
		(fp_line
			(start -0.12065 0.3048)
			(end -0.67945 0.3048)
			(stroke
				(width 0.1)
				(type default)
			)
			(layer "F.Fab")
		)
		(fp_line
			(start -0.67945 0.3048)
			(end -0.67945 -0.305054)
			(stroke
				(width 0.1)
				(type default)
			)
			(layer "F.Fab")
		)
		(pad "1" smd circle
			(at -0.40005 0 90)
			(size 0 0)
			(layers "F.Cu" "F.Mask" "F.Paste")
			(net "SMB_PEX0_PCA9555_SCL")
		)
		(pad "2" smd circle
			(at 0.40005 0 90)
			(size 0 0)
			(layers "F.Cu" "F.Mask" "F.Paste")
			(net "SMB_PEX0_HOST_LS_SCL")
		)
	)
	(footprint ""
		(layer "F.Cu")
		(at 219.202 -192.024)
		(property "Reference" "R1531"
			(at 0 0 0)
			(layer "F.SilkS")
			(hide yes)
			(effects
				(font
					(size 1.27 1.27)
				)
			)
		)
		(property "Value" ""
			(at 0 0 0)
			(layer "F.Fab")
			(effects
				(font
					(size 1.27 1.27)
				)
			)
		)
		(duplicate_pad_numbers_are_jumpers no)
		(fp_line
			(start -0.7874 -0.4064)
			(end 0.7874 -0.4064)
			(stroke
				(width 0.1524)
				(type default)
			)
			(layer "F.SilkS")
		)
		(fp_line
			(start -0.7874 0.4064)
			(end -0.7874 -0.4064)
			(stroke
				(width 0.1524)
				(type default)
			)
			(layer "F.SilkS")
		)
		(fp_line
			(start 0.7874 -0.4064)
			(end 0.7874 0.4064)
			(stroke
				(width 0.1524)
				(type default)
			)
			(layer "F.SilkS")
		)
		(fp_line
			(start 0.7874 0.4064)
			(end -0.7874 0.4064)
			(stroke
				(width 0.1524)
				(type default)
			)
			(layer "F.SilkS")
		)
		(fp_line
			(start -0.67945 -0.305054)
			(end -0.12065 -0.305054)
			(stroke
				(width 0.1)
				(type default)
			)
			(layer "F.Fab")
		)
		(fp_line
			(start -0.67945 0.3048)
			(end -0.67945 -0.305054)
			(stroke
				(width 0.1)
				(type default)
			)
			(layer "F.Fab")
		)
		(fp_line
			(start -0.12065 -0.305054)
			(end -0.12065 -0.2794)
			(stroke
				(width 0.1)
				(type default)
			)
			(layer "F.Fab")
		)
		(fp_line
			(start -0.12065 -0.2794)
			(end 0.12065 -0.2794)
			(stroke
				(width 0.1)
				(type default)
			)
			(layer "F.Fab")
		)
		(fp_line
			(start -0.12065 0.2794)
			(end -0.12065 0.3048)
			(stroke
				(width 0.1)
				(type default)
			)
			(layer "F.Fab")
		)
		(fp_line
			(start -0.12065 0.3048)
			(end -0.67945 0.3048)
			(stroke
				(width 0.1)
				(type default)
			)
			(layer "F.Fab")
		)
		(fp_line
			(start 0.120396 0.2794)
			(end -0.12065 0.2794)
			(stroke
				(width 0.1)
				(type default)
			)
			(layer "F.Fab")
		)
		(fp_line
			(start 0.120396 0.3048)
			(end 0.120396 0.2794)
			(stroke
				(width 0.1)
				(type default)
			)
			(layer "F.Fab")
		)
		(fp_line
			(start 0.12065 -0.3048)
			(end 0.67945 -0.3048)
			(stroke
				(width 0.1)
				(type default)
			)
			(layer "F.Fab")
		)
		(fp_line
			(start 0.12065 -0.2794)
			(end 0.12065 -0.3048)
			(stroke
				(width 0.1)
				(type default)
			)
			(layer "F.Fab")
		)
		(fp_line
			(start 0.67945 -0.3048)
			(end 0.67945 0.3048)
			(stroke
				(width 0.1)
				(type default)
			)
			(layer "F.Fab")
		)
		(fp_line
			(start 0.67945 0.3048)
			(end 0.120396 0.3048)
			(stroke
				(width 0.1)
				(type default)
			)
			(layer "F.Fab")
		)
		(pad "1" smd circle
			(at -0.40005 0)
			(size 0 0)
			(layers "F.Cu" "F.Mask" "F.Paste")
			(net "SMB_NIC7_LS_EN")
		)
		(pad "2" smd circle
			(at 0.40005 0)
			(size 0 0)
			(layers "F.Cu" "F.Mask" "F.Paste")
			(net "P3V3_NIC7")
		)
	)
	(footprint ""
		(layer "F.Cu")
		(at 228.79304 -90.009726)
		(property "Reference" "R1012"
			(at 0 0 0)
			(layer "F.SilkS")
			(hide yes)
			(effects
				(font
					(size 1.27 1.27)
				)
			)
		)
		(property "Value" ""
			(at 0 0 0)
			(layer "F.Fab")
			(effects
				(font
					(size 1.27 1.27)
				)
			)
		)
		(duplicate_pad_numbers_are_jumpers no)
		(fp_line
			(start -0.7874 -0.4064)
			(end 0.7874 -0.4064)
			(stroke
				(width 0.1524)
				(type default)
			)
			(layer "F.SilkS")
		)
		(fp_line
			(start -0.7874 0.4064)
			(end -0.7874 -0.4064)
			(stroke
				(width 0.1524)
				(type default)
			)
			(layer "F.SilkS")
		)
		(fp_line
			(start 0.7874 -0.4064)
			(end 0.7874 0.4064)
			(stroke
				(width 0.1524)
				(type default)
			)
			(layer "F.SilkS")
		)
		(fp_line
			(start 0.7874 0.4064)
			(end -0.7874 0.4064)
			(stroke
				(width 0.1524)
				(type default)
			)
			(layer "F.SilkS")
		)
		(fp_line
			(start -0.67945 -0.305054)
			(end -0.12065 -0.305054)
			(stroke
				(width 0.1)
				(type default)
			)
			(layer "F.Fab")
		)
		(fp_line
			(start -0.67945 0.3048)
			(end -0.67945 -0.305054)
			(stroke
				(width 0.1)
				(type default)
			)
			(layer "F.Fab")
		)
		(fp_line
			(start -0.12065 -0.305054)
			(end -0.12065 -0.2794)
			(stroke
				(width 0.1)
				(type default)
			)
			(layer "F.Fab")
		)
		(fp_line
			(start -0.12065 -0.2794)
			(end 0.12065 -0.2794)
			(stroke
				(width 0.1)
				(type default)
			)
			(layer "F.Fab")
		)
		(fp_line
			(start -0.12065 0.2794)
			(end -0.12065 0.3048)
			(stroke
				(width 0.1)
				(type default)
			)
			(layer "F.Fab")
		)
		(fp_line
			(start -0.12065 0.3048)
			(end -0.67945 0.3048)
			(stroke
				(width 0.1)
				(type default)
			)
			(layer "F.Fab")
		)
		(fp_line
			(start 0.120396 0.2794)
			(end -0.12065 0.2794)
			(stroke
				(width 0.1)
				(type default)
			)
			(layer "F.Fab")
		)
		(fp_line
			(start 0.120396 0.3048)
			(end 0.120396 0.2794)
			(stroke
				(width 0.1)
				(type default)
			)
			(layer "F.Fab")
		)
		(fp_line
			(start 0.12065 -0.3048)
			(end 0.67945 -0.3048)
			(stroke
				(width 0.1)
				(type default)
			)
			(layer "F.Fab")
		)
		(fp_line
			(start 0.12065 -0.2794)
			(end 0.12065 -0.3048)
			(stroke
				(width 0.1)
				(type default)
			)
			(layer "F.Fab")
		)
		(fp_line
			(start 0.67945 -0.3048)
			(end 0.67945 0.3048)
			(stroke
				(width 0.1)
				(type default)
			)
			(layer "F.Fab")
		)
		(fp_line
			(start 0.67945 0.3048)
			(end 0.120396 0.3048)
			(stroke
				(width 0.1)
				(type default)
			)
			(layer "F.Fab")
		)
		(pad "1" smd circle
			(at -0.40005 0)
			(size 0 0)
			(layers "F.Cu" "F.Mask" "F.Paste")
			(net "P3V3_AUX")
		)
		(pad "2" smd circle
			(at 0.40005 0)
			(size 0 0)
			(layers "F.Cu" "F.Mask" "F.Paste")
			(net "PEX_USB_HUB_OVCUR1")
		)
	)
	(footprint ""
		(layer "F.Cu")
		(at 274.089622 -350.098614 90)
		(property "Reference" "C607"
			(at 0 0 90)
			(layer "F.SilkS")
			(hide yes)
			(effects
				(font
					(size 1.27 1.27)
				)
			)
		)
		(property "Value" ""
			(at 0 0 90)
			(layer "F.Fab")
			(effects
				(font
					(size 1.27 1.27)
				)
			)
		)
		(duplicate_pad_numbers_are_jumpers no)
		(fp_line
			(start 0.299974 -0.150114)
			(end 0.299974 0.150114)
			(stroke
				(width 0.1)
				(type default)
			)
			(layer "F.Fab")
		)
		(fp_line
			(start -0.299974 -0.150114)
			(end 0.299974 -0.150114)
			(stroke
				(width 0.1)
				(type default)
			)
			(layer "F.Fab")
		)
		(fp_line
			(start 0.299974 0.150114)
			(end -0.299974 0.150114)
			(stroke
				(width 0.1)
				(type default)
			)
			(layer "F.Fab")
		)
		(fp_line
			(start -0.299974 0.150114)
			(end -0.299974 -0.150114)
			(stroke
				(width 0.1)
				(type default)
			)
			(layer "F.Fab")
		)
		(pad "1" smd rect
			(at -0.2667 0 90)
			(size 0.3048 0.381)
			(layers "F.Cu" "F.Mask" "F.Paste")
			(net "P5E_PEX2_STN7_TX_DP<115>")
		)
		(pad "2" smd rect
			(at 0.2667 0 90)
			(size 0.3048 0.381)
			(layers "F.Cu" "F.Mask" "F.Paste")
			(net "P5E_PEX2_STN7_TX_C_DP<115>")
		)
	)
	(footprint ""
		(layer "F.Cu")
		(at 458.155548 -373.71782 -90)
		(property "Reference" "R6683"
			(at 0 0 270)
			(layer "F.SilkS")
			(hide yes)
			(effects
				(font
					(size 1.27 1.27)
				)
			)
		)
		(property "Value" ""
			(at 0 0 270)
			(layer "F.Fab")
			(effects
				(font
					(size 1.27 1.27)
				)
			)
		)
		(duplicate_pad_numbers_are_jumpers no)
		(fp_line
			(start -0.7874 0.4064)
			(end -0.7874 -0.4064)
			(stroke
				(width 0.1524)
				(type default)
			)
			(layer "F.SilkS")
		)
		(fp_line
			(start 0.7874 0.4064)
			(end -0.7874 0.4064)
			(stroke
				(width 0.1524)
				(type default)
			)
			(layer "F.SilkS")
		)
		(fp_line
			(start -0.7874 -0.4064)
			(end 0.7874 -0.4064)
			(stroke
				(width 0.1524)
				(type default)
			)
			(layer "F.SilkS")
		)
		(fp_line
			(start 0.7874 -0.4064)
			(end 0.7874 0.4064)
			(stroke
				(width 0.1524)
				(type default)
			)
			(layer "F.SilkS")
		)
		(fp_line
			(start -0.67945 0.3048)
			(end -0.67945 -0.305054)
			(stroke
				(width 0.1)
				(type default)
			)
			(layer "F.Fab")
		)
		(fp_line
			(start -0.12065 0.3048)
			(end -0.67945 0.3048)
			(stroke
				(width 0.1)
				(type default)
			)
			(layer "F.Fab")
		)
		(fp_line
			(start 0.120396 0.3048)
			(end 0.120396 0.2794)
			(stroke
				(width 0.1)
				(type default)
			)
			(layer "F.Fab")
		)
		(fp_line
			(start 0.67945 0.3048)
			(end 0.120396 0.3048)
			(stroke
				(width 0.1)
				(type default)
			)
			(layer "F.Fab")
		)
		(fp_line
			(start -0.12065 0.2794)
			(end -0.12065 0.3048)
			(stroke
				(width 0.1)
				(type default)
			)
			(layer "F.Fab")
		)
		(fp_line
			(start 0.120396 0.2794)
			(end -0.12065 0.2794)
			(stroke
				(width 0.1)
				(type default)
			)
			(layer "F.Fab")
		)
		(fp_line
			(start -0.12065 -0.2794)
			(end 0.12065 -0.2794)
			(stroke
				(width 0.1)
				(type default)
			)
			(layer "F.Fab")
		)
		(fp_line
			(start 0.12065 -0.2794)
			(end 0.12065 -0.3048)
			(stroke
				(width 0.1)
				(type default)
			)
			(layer "F.Fab")
		)
		(fp_line
			(start 0.12065 -0.3048)
			(end 0.67945 -0.3048)
			(stroke
				(width 0.1)
				(type default)
			)
			(layer "F.Fab")
		)
		(fp_line
			(start 0.67945 -0.3048)
			(end 0.67945 0.3048)
			(stroke
				(width 0.1)
				(type default)
			)
			(layer "F.Fab")
		)
		(fp_line
			(start -0.67945 -0.305054)
			(end -0.12065 -0.305054)
			(stroke
				(width 0.1)
				(type default)
			)
			(layer "F.Fab")
		)
		(fp_line
			(start -0.12065 -0.305054)
			(end -0.12065 -0.2794)
			(stroke
				(width 0.1)
				(type default)
			)
			(layer "F.Fab")
		)
		(pad "1" smd circle
			(at -0.40005 0 270)
			(size 0 0)
			(layers "F.Cu" "F.Mask" "F.Paste")
			(net "GPU_3V3IO_RSVD3_ISO")
		)
		(pad "2" smd circle
			(at 0.40005 0 270)
			(size 0 0)
			(layers "F.Cu" "F.Mask" "F.Paste")
			(net "P3V3_AUX")
		)
	)
	(footprint ""
		(layer "F.Cu")
		(at 228.915722 -308.162452 90)
		(property "Reference" "PC242"
			(at 0 0 90)
			(layer "F.SilkS")
			(hide yes)
			(effects
				(font
					(size 1.27 1.27)
				)
			)
		)
		(property "Value" ""
			(at 0 0 90)
			(layer "F.Fab")
			(effects
				(font
					(size 1.27 1.27)
				)
			)
		)
		(duplicate_pad_numbers_are_jumpers no)
		(fp_line
			(start 0.7874 -0.4064)
			(end 0.7874 0.4064)
			(stroke
				(width 0.1524)
				(type default)
			)
			(layer "F.SilkS")
		)
		(fp_line
			(start -0.7874 -0.4064)
			(end 0.7874 -0.4064)
			(stroke
				(width 0.1524)
				(type default)
			)
			(layer "F.SilkS")
		)
		(fp_line
			(start 0.7874 0.4064)
			(end -0.7874 0.4064)
			(stroke
				(width 0.1524)
				(type default)
			)
			(layer "F.SilkS")
		)
		(fp_line
			(start -0.7874 0.4064)
			(end -0.7874 -0.4064)
			(stroke
				(width 0.1524)
				(type default)
			)
			(layer "F.SilkS")
		)
		(fp_line
			(start -0.12065 -0.305054)
			(end -0.12065 -0.2794)
			(stroke
				(width 0.1)
				(type default)
			)
			(layer "F.Fab")
		)
		(fp_line
			(start -0.67945 -0.305054)
			(end -0.12065 -0.305054)
			(stroke
				(width 0.1)
				(type default)
			)
			(layer "F.Fab")
		)
		(fp_line
			(start 0.67945 -0.3048)
			(end 0.67945 0.3048)
			(stroke
				(width 0.1)
				(type default)
			)
			(layer "F.Fab")
		)
		(fp_line
			(start 0.12065 -0.3048)
			(end 0.67945 -0.3048)
			(stroke
				(width 0.1)
				(type default)
			)
			(layer "F.Fab")
		)
		(fp_line
			(start 0.12065 -0.2794)
			(end 0.12065 -0.3048)
			(stroke
				(width 0.1)
				(type default)
			)
			(layer "F.Fab")
		)
		(fp_line
			(start -0.12065 -0.2794)
			(end 0.12065 -0.2794)
			(stroke
				(width 0.1)
				(type default)
			)
			(layer "F.Fab")
		)
		(fp_line
			(start 0.120396 0.2794)
			(end -0.12065 0.2794)
			(stroke
				(width 0.1)
				(type default)
			)
			(layer "F.Fab")
		)
		(fp_line
			(start -0.12065 0.2794)
			(end -0.12065 0.3048)
			(stroke
				(width 0.1)
				(type default)
			)
			(layer "F.Fab")
		)
		(fp_line
			(start 0.67945 0.3048)
			(end 0.120396 0.3048)
			(stroke
				(width 0.1)
				(type default)
			)
			(layer "F.Fab")
		)
		(fp_line
			(start 0.120396 0.3048)
			(end 0.120396 0.2794)
			(stroke
				(width 0.1)
				(type default)
			)
			(layer "F.Fab")
		)
		(fp_line
			(start -0.12065 0.3048)
			(end -0.67945 0.3048)
			(stroke
				(width 0.1)
				(type default)
			)
			(layer "F.Fab")
		)
		(fp_line
			(start -0.67945 0.3048)
			(end -0.67945 -0.305054)
			(stroke
				(width 0.1)
				(type default)
			)
			(layer "F.Fab")
		)
		(pad "1" smd circle
			(at -0.40005 0 90)
			(size 0 0)
			(layers "F.Cu" "F.Mask" "F.Paste")
			(net "P1V25_PEX1_REF")
		)
		(pad "2" smd circle
			(at 0.40005 0 90)
			(size 0 0)
			(layers "F.Cu" "F.Mask" "F.Paste")
			(net "SH_P1V25_PEX1_FB_N")
		)
	)
	(footprint ""
		(layer "F.Cu")
		(at 38.782752 -140.85697)
		(property "Reference" "R34"
			(at 0 0 0)
			(layer "F.SilkS")
			(hide yes)
			(effects
				(font
					(size 1.27 1.27)
				)
			)
		)
		(property "Value" ""
			(at 0 0 0)
			(layer "F.Fab")
			(effects
				(font
					(size 1.27 1.27)
				)
			)
		)
		(duplicate_pad_numbers_are_jumpers no)
		(fp_line
			(start -0.7874 -0.4064)
			(end 0.7874 -0.4064)
			(stroke
				(width 0.1524)
				(type default)
			)
			(layer "F.SilkS")
		)
		(fp_line
			(start -0.7874 0.4064)
			(end -0.7874 -0.4064)
			(stroke
				(width 0.1524)
				(type default)
			)
			(layer "F.SilkS")
		)
		(fp_line
			(start 0.7874 -0.4064)
			(end 0.7874 0.4064)
			(stroke
				(width 0.1524)
				(type default)
			)
			(layer "F.SilkS")
		)
		(fp_line
			(start 0.7874 0.4064)
			(end -0.7874 0.4064)
			(stroke
				(width 0.1524)
				(type default)
			)
			(layer "F.SilkS")
		)
		(fp_line
			(start -0.67945 -0.305054)
			(end -0.12065 -0.305054)
			(stroke
				(width 0.1)
				(type default)
			)
			(layer "F.Fab")
		)
		(fp_line
			(start -0.67945 0.3048)
			(end -0.67945 -0.305054)
			(stroke
				(width 0.1)
				(type default)
			)
			(layer "F.Fab")
		)
		(fp_line
			(start -0.12065 -0.305054)
			(end -0.12065 -0.2794)
			(stroke
				(width 0.1)
				(type default)
			)
			(layer "F.Fab")
		)
		(fp_line
			(start -0.12065 -0.2794)
			(end 0.12065 -0.2794)
			(stroke
				(width 0.1)
				(type default)
			)
			(layer "F.Fab")
		)
		(fp_line
			(start -0.12065 0.2794)
			(end -0.12065 0.3048)
			(stroke
				(width 0.1)
				(type default)
			)
			(layer "F.Fab")
		)
		(fp_line
			(start -0.12065 0.3048)
			(end -0.67945 0.3048)
			(stroke
				(width 0.1)
				(type default)
			)
			(layer "F.Fab")
		)
		(fp_line
			(start 0.120396 0.2794)
			(end -0.12065 0.2794)
			(stroke
				(width 0.1)
				(type default)
			)
			(layer "F.Fab")
		)
		(fp_line
			(start 0.120396 0.3048)
			(end 0.120396 0.2794)
			(stroke
				(width 0.1)
				(type default)
			)
			(layer "F.Fab")
		)
		(fp_line
			(start 0.12065 -0.3048)
			(end 0.67945 -0.3048)
			(stroke
				(width 0.1)
				(type default)
			)
			(layer "F.Fab")
		)
		(fp_line
			(start 0.12065 -0.2794)
			(end 0.12065 -0.3048)
			(stroke
				(width 0.1)
				(type default)
			)
			(layer "F.Fab")
		)
		(fp_line
			(start 0.67945 -0.3048)
			(end 0.67945 0.3048)
			(stroke
				(width 0.1)
				(type default)
			)
			(layer "F.Fab")
		)
		(fp_line
			(start 0.67945 0.3048)
			(end 0.120396 0.3048)
			(stroke
				(width 0.1)
				(type default)
			)
			(layer "F.Fab")
		)
		(pad "1" smd circle
			(at -0.40005 0)
			(size 0 0)
			(layers "F.Cu" "F.Mask" "F.Paste")
			(net "NIC0_BIF2_N")
		)
		(pad "2" smd circle
			(at 0.40005 0)
			(size 0 0)
			(layers "F.Cu" "F.Mask" "F.Paste")
			(net "GND")
		)
	)
	(footprint ""
		(layer "F.Cu")
		(at 241.567208 -305.338988)
		(property "Reference" "PC248"
			(at 0 0 0)
			(layer "F.SilkS")
			(hide yes)
			(effects
				(font
					(size 1.27 1.27)
				)
			)
		)
		(property "Value" ""
			(at 0 0 0)
			(layer "F.Fab")
			(effects
				(font
					(size 1.27 1.27)
				)
			)
		)
		(duplicate_pad_numbers_are_jumpers no)
		(fp_line
			(start -0.7874 -0.4064)
			(end 0.7874 -0.4064)
			(stroke
				(width 0.1524)
				(type default)
			)
			(layer "F.SilkS")
		)
		(fp_line
			(start -0.7874 0.4064)
			(end -0.7874 -0.4064)
			(stroke
				(width 0.1524)
				(type default)
			)
			(layer "F.SilkS")
		)
		(fp_line
			(start 0.7874 -0.4064)
			(end 0.7874 0.4064)
			(stroke
				(width 0.1524)
				(type default)
			)
			(layer "F.SilkS")
		)
		(fp_line
			(start 0.7874 0.4064)
			(end -0.7874 0.4064)
			(stroke
				(width 0.1524)
				(type default)
			)
			(layer "F.SilkS")
		)
		(fp_line
			(start -0.67945 -0.305054)
			(end -0.12065 -0.305054)
			(stroke
				(width 0.1)
				(type default)
			)
			(layer "F.Fab")
		)
		(fp_line
			(start -0.67945 0.3048)
			(end -0.67945 -0.305054)
			(stroke
				(width 0.1)
				(type default)
			)
			(layer "F.Fab")
		)
		(fp_line
			(start -0.12065 -0.305054)
			(end -0.12065 -0.2794)
			(stroke
				(width 0.1)
				(type default)
			)
			(layer "F.Fab")
		)
		(fp_line
			(start -0.12065 -0.2794)
			(end 0.12065 -0.2794)
			(stroke
				(width 0.1)
				(type default)
			)
			(layer "F.Fab")
		)
		(fp_line
			(start -0.12065 0.2794)
			(end -0.12065 0.3048)
			(stroke
				(width 0.1)
				(type default)
			)
			(layer "F.Fab")
		)
		(fp_line
			(start -0.12065 0.3048)
			(end -0.67945 0.3048)
			(stroke
				(width 0.1)
				(type default)
			)
			(layer "F.Fab")
		)
		(fp_line
			(start 0.120396 0.2794)
			(end -0.12065 0.2794)
			(stroke
				(width 0.1)
				(type default)
			)
			(layer "F.Fab")
		)
		(fp_line
			(start 0.120396 0.3048)
			(end 0.120396 0.2794)
			(stroke
				(width 0.1)
				(type default)
			)
			(layer "F.Fab")
		)
		(fp_line
			(start 0.12065 -0.3048)
			(end 0.67945 -0.3048)
			(stroke
				(width 0.1)
				(type default)
			)
			(layer "F.Fab")
		)
		(fp_line
			(start 0.12065 -0.2794)
			(end 0.12065 -0.3048)
			(stroke
				(width 0.1)
				(type default)
			)
			(layer "F.Fab")
		)
		(fp_line
			(start 0.67945 -0.3048)
			(end 0.67945 0.3048)
			(stroke
				(width 0.1)
				(type default)
			)
			(layer "F.Fab")
		)
		(fp_line
			(start 0.67945 0.3048)
			(end 0.120396 0.3048)
			(stroke
				(width 0.1)
				(type default)
			)
			(layer "F.Fab")
		)
		(pad "1" smd circle
			(at -0.40005 0)
			(size 0 0)
			(layers "F.Cu" "F.Mask" "F.Paste")
			(net "SW_P12V_P1V25_PEX2_FLT")
		)
		(pad "2" smd circle
			(at 0.40005 0)
			(size 0 0)
			(layers "F.Cu" "F.Mask" "F.Paste")
			(net "GND")
		)
	)
	(footprint ""
		(layer "F.Cu")
		(at 369.24742 -20.35556)
		(property "Reference" "C3960"
			(at 0 0 0)
			(layer "F.SilkS")
			(hide yes)
			(effects
				(font
					(size 1.27 1.27)
				)
			)
		)
		(property "Value" ""
			(at 0 0 0)
			(layer "F.Fab")
			(effects
				(font
					(size 1.27 1.27)
				)
			)
		)
		(duplicate_pad_numbers_are_jumpers no)
		(fp_line
			(start -0.7874 -0.4064)
			(end 0.7874 -0.4064)
			(stroke
				(width 0.1524)
				(type default)
			)
			(layer "F.SilkS")
		)
		(fp_line
			(start -0.7874 0.4064)
			(end -0.7874 -0.4064)
			(stroke
				(width 0.1524)
				(type default)
			)
			(layer "F.SilkS")
		)
		(fp_line
			(start 0.7874 -0.4064)
			(end 0.7874 0.4064)
			(stroke
				(width 0.1524)
				(type default)
			)
			(layer "F.SilkS")
		)
		(fp_line
			(start 0.7874 0.4064)
			(end -0.7874 0.4064)
			(stroke
				(width 0.1524)
				(type default)
			)
			(layer "F.SilkS")
		)
		(fp_line
			(start -0.67945 -0.305054)
			(end -0.12065 -0.305054)
			(stroke
				(width 0.1)
				(type default)
			)
			(layer "F.Fab")
		)
		(fp_line
			(start -0.67945 0.3048)
			(end -0.67945 -0.305054)
			(stroke
				(width 0.1)
				(type default)
			)
			(layer "F.Fab")
		)
		(fp_line
			(start -0.12065 -0.305054)
			(end -0.12065 -0.2794)
			(stroke
				(width 0.1)
				(type default)
			)
			(layer "F.Fab")
		)
		(fp_line
			(start -0.12065 -0.2794)
			(end 0.12065 -0.2794)
			(stroke
				(width 0.1)
				(type default)
			)
			(layer "F.Fab")
		)
		(fp_line
			(start -0.12065 0.2794)
			(end -0.12065 0.3048)
			(stroke
				(width 0.1)
				(type default)
			)
			(layer "F.Fab")
		)
		(fp_line
			(start -0.12065 0.3048)
			(end -0.67945 0.3048)
			(stroke
				(width 0.1)
				(type default)
			)
			(layer "F.Fab")
		)
		(fp_line
			(start 0.120396 0.2794)
			(end -0.12065 0.2794)
			(stroke
				(width 0.1)
				(type default)
			)
			(layer "F.Fab")
		)
		(fp_line
			(start 0.120396 0.3048)
			(end 0.120396 0.2794)
			(stroke
				(width 0.1)
				(type default)
			)
			(layer "F.Fab")
		)
		(fp_line
			(start 0.12065 -0.3048)
			(end 0.67945 -0.3048)
			(stroke
				(width 0.1)
				(type default)
			)
			(layer "F.Fab")
		)
		(fp_line
			(start 0.12065 -0.2794)
			(end 0.12065 -0.3048)
			(stroke
				(width 0.1)
				(type default)
			)
			(layer "F.Fab")
		)
		(fp_line
			(start 0.67945 -0.3048)
			(end 0.67945 0.3048)
			(stroke
				(width 0.1)
				(type default)
			)
			(layer "F.Fab")
		)
		(fp_line
			(start 0.67945 0.3048)
			(end 0.120396 0.3048)
			(stroke
				(width 0.1)
				(type default)
			)
			(layer "F.Fab")
		)
		(pad "1" smd circle
			(at -0.40005 0)
			(size 0 0)
			(layers "F.Cu" "F.Mask" "F.Paste")
			(net "P12V_SSD12")
		)
		(pad "2" smd circle
			(at 0.40005 0)
			(size 0 0)
			(layers "F.Cu" "F.Mask" "F.Paste")
			(net "GND")
		)
	)
	(footprint ""
		(layer "F.Cu")
		(at 127.658114 -258.131564)
		(property "Reference" "C833"
			(at 0 0 0)
			(layer "F.SilkS")
			(hide yes)
			(effects
				(font
					(size 1.27 1.27)
				)
			)
		)
		(property "Value" ""
			(at 0 0 0)
			(layer "F.Fab")
			(effects
				(font
					(size 1.27 1.27)
				)
			)
		)
		(duplicate_pad_numbers_are_jumpers no)
		(fp_line
			(start -0.7874 -0.4064)
			(end 0.7874 -0.4064)
			(stroke
				(width 0.1524)
				(type default)
			)
			(layer "F.SilkS")
		)
		(fp_line
			(start -0.7874 0.4064)
			(end -0.7874 -0.4064)
			(stroke
				(width 0.1524)
				(type default)
			)
			(layer "F.SilkS")
		)
		(fp_line
			(start 0.7874 -0.4064)
			(end 0.7874 0.4064)
			(stroke
				(width 0.1524)
				(type default)
			)
			(layer "F.SilkS")
		)
		(fp_line
			(start 0.7874 0.4064)
			(end -0.7874 0.4064)
			(stroke
				(width 0.1524)
				(type default)
			)
			(layer "F.SilkS")
		)
		(fp_line
			(start -0.67945 -0.305054)
			(end -0.12065 -0.305054)
			(stroke
				(width 0.1)
				(type default)
			)
			(layer "F.Fab")
		)
		(fp_line
			(start -0.67945 0.3048)
			(end -0.67945 -0.305054)
			(stroke
				(width 0.1)
				(type default)
			)
			(layer "F.Fab")
		)
		(fp_line
			(start -0.12065 -0.305054)
			(end -0.12065 -0.2794)
			(stroke
				(width 0.1)
				(type default)
			)
			(layer "F.Fab")
		)
		(fp_line
			(start -0.12065 -0.2794)
			(end 0.12065 -0.2794)
			(stroke
				(width 0.1)
				(type default)
			)
			(layer "F.Fab")
		)
		(fp_line
			(start -0.12065 0.2794)
			(end -0.12065 0.3048)
			(stroke
				(width 0.1)
				(type default)
			)
			(layer "F.Fab")
		)
		(fp_line
			(start -0.12065 0.3048)
			(end -0.67945 0.3048)
			(stroke
				(width 0.1)
				(type default)
			)
			(layer "F.Fab")
		)
		(fp_line
			(start 0.120396 0.2794)
			(end -0.12065 0.2794)
			(stroke
				(width 0.1)
				(type default)
			)
			(layer "F.Fab")
		)
		(fp_line
			(start 0.120396 0.3048)
			(end 0.120396 0.2794)
			(stroke
				(width 0.1)
				(type default)
			)
			(layer "F.Fab")
		)
		(fp_line
			(start 0.12065 -0.3048)
			(end 0.67945 -0.3048)
			(stroke
				(width 0.1)
				(type default)
			)
			(layer "F.Fab")
		)
		(fp_line
			(start 0.12065 -0.2794)
			(end 0.12065 -0.3048)
			(stroke
				(width 0.1)
				(type default)
			)
			(layer "F.Fab")
		)
		(fp_line
			(start 0.67945 -0.3048)
			(end 0.67945 0.3048)
			(stroke
				(width 0.1)
				(type default)
			)
			(layer "F.Fab")
		)
		(fp_line
			(start 0.67945 0.3048)
			(end 0.120396 0.3048)
			(stroke
				(width 0.1)
				(type default)
			)
			(layer "F.Fab")
		)
		(pad "1" smd circle
			(at -0.40005 0)
			(size 0 0)
			(layers "F.Cu" "F.Mask" "F.Paste")
			(net "P0V8_PEX1_BVRRDY")
		)
		(pad "2" smd circle
			(at 0.40005 0)
			(size 0 0)
			(layers "F.Cu" "F.Mask" "F.Paste")
			(net "GND")
		)
	)
	(footprint ""
		(layer "F.Cu")
		(at 125.186948 -356.244906 90)
		(property "Reference" "C353"
			(at 0 0 90)
			(layer "F.SilkS")
			(hide yes)
			(effects
				(font
					(size 1.27 1.27)
				)
			)
		)
		(property "Value" ""
			(at 0 0 90)
			(layer "F.Fab")
			(effects
				(font
					(size 1.27 1.27)
				)
			)
		)
		(duplicate_pad_numbers_are_jumpers no)
		(fp_line
			(start 0.299974 -0.150114)
			(end 0.299974 0.150114)
			(stroke
				(width 0.1)
				(type default)
			)
			(layer "F.Fab")
		)
		(fp_line
			(start -0.299974 -0.150114)
			(end 0.299974 -0.150114)
			(stroke
				(width 0.1)
				(type default)
			)
			(layer "F.Fab")
		)
		(fp_line
			(start 0.299974 0.150114)
			(end -0.299974 0.150114)
			(stroke
				(width 0.1)
				(type default)
			)
			(layer "F.Fab")
		)
		(fp_line
			(start -0.299974 0.150114)
			(end -0.299974 -0.150114)
			(stroke
				(width 0.1)
				(type default)
			)
			(layer "F.Fab")
		)
		(pad "1" smd rect
			(at -0.2667 0 90)
			(size 0.3048 0.381)
			(layers "F.Cu" "F.Mask" "F.Paste")
			(net "P5E_PEX1_STN6_TX_DN<105>")
		)
		(pad "2" smd rect
			(at 0.2667 0 90)
			(size 0.3048 0.381)
			(layers "F.Cu" "F.Mask" "F.Paste")
			(net "P5E_PEX1_STN6_TX_C_DN<105>")
		)
	)
	(footprint ""
		(layer "F.Cu")
		(at 90.964766 -26.785062 180)
		(property "Reference" "J33"
			(at 3.892296 -11.037062 90)
			(unlocked yes)
			(layer "F.SilkS")
			(effects
				(font
					(size 0.7874 0.5842)
					(thickness 0.1524)
				)
			)
		)
		(property "Value" ""
			(at 0 0 180)
			(layer "F.Fab")
			(effects
				(font
					(size 1.27 1.27)
				)
			)
		)
		(duplicate_pad_numbers_are_jumpers no)
		(fp_line
			(start 3.150108 12.115038)
			(end 1.529334 12.115038)
			(stroke
				(width 0.1524)
				(type default)
			)
			(layer "F.SilkS")
		)
		(fp_line
			(start 3.074924 12.014962)
			(end 1.632204 12.014962)
			(stroke
				(width 0.1524)
				(type default)
			)
			(layer "F.SilkS")
		)
		(fp_line
			(start 1.632204 -12.014962)
			(end 3.074924 -12.014962)
			(stroke
				(width 0.1524)
				(type default)
			)
			(layer "F.SilkS")
		)
		(fp_line
			(start 1.529334 -12.115038)
			(end 3.150108 -12.115038)
			(stroke
				(width 0.1524)
				(type default)
			)
			(layer "F.SilkS")
		)
		(fp_line
			(start -1.529334 12.115038)
			(end -3.150108 12.115038)
			(stroke
				(width 0.1524)
				(type default)
			)
			(layer "F.SilkS")
		)
		(fp_line
			(start -1.632204 12.014962)
			(end -3.074924 12.014962)
			(stroke
				(width 0.1524)
				(type default)
			)
			(layer "F.SilkS")
		)
		(fp_line
			(start -3.074924 -12.014962)
			(end -1.632204 -12.014962)
			(stroke
				(width 0.1524)
				(type default)
			)
			(layer "F.SilkS")
		)
		(fp_line
			(start -3.150108 -12.115038)
			(end -1.529334 -12.115038)
			(stroke
				(width 0.1524)
				(type default)
			)
			(layer "F.SilkS")
		)
		(fp_poly
			(pts
				(xy 3.341116 -8.698738) (xy 3.763518 -9.966452) (xy 4.608576 -9.121394)
			)
			(stroke
				(width 0)
				(type default)
			)
			(fill yes)
			(layer "F.SilkS")
		)
		(fp_line
			(start 3.074924 12.014962)
			(end -3.074924 12.014962)
			(stroke
				(width 0.1)
				(type default)
			)
			(layer "F.Fab")
		)
		(fp_line
			(start 3.074924 -12.014962)
			(end 3.074924 12.014962)
			(stroke
				(width 0.1)
				(type default)
			)
			(layer "F.Fab")
		)
		(fp_line
			(start -3.074924 12.014962)
			(end -3.074924 -12.014962)
			(stroke
				(width 0.1)
				(type default)
			)
			(layer "F.Fab")
		)
		(fp_line
			(start -3.074924 -12.014962)
			(end 3.074924 -12.014962)
			(stroke
				(width 0.1)
				(type default)
			)
			(layer "F.Fab")
		)
		(fp_poly
			(pts
				(xy 3.348736 -7.994904) (xy 4.543806 -8.592566) (xy 4.543806 -7.397496)
			)
			(stroke
				(width 0)
				(type default)
			)
			(fill yes)
			(layer "F.Fab")
		)
		(pad "" np_thru_hole circle
			(at -1.75006 -9.815068 90)
			(size 1.1176 1.1176)
			(drill 1.1176)
			(layers "*.Cu" "*.Mask")
			(clearance 0.381)
			(thermal_gap 0.381)
		)
		(pad "" np_thru_hole circle
			(at 0 9.815068 90)
			(size 1.1176 1.1176)
			(drill 1.1176)
			(layers "*.Cu" "*.Mask")
			(clearance 0.381)
			(thermal_gap 0.381)
		)
		(pad "A1" smd rect
			(at 2.29997 -7.994904 90)
			(size 0.381 1.27)
			(layers "F.Cu" "F.Mask" "F.Paste")
			(net "GND")
		)
		(pad "A2" smd rect
			(at 2.29997 -7.394956 90)
			(size 0.381 1.27)
			(layers "F.Cu" "F.Mask" "F.Paste")
			(net "GND")
		)
		(pad "A3" smd rect
			(at 2.29997 -6.795008 90)
			(size 0.381 1.27)
			(layers "F.Cu" "F.Mask" "F.Paste")
			(net "GND")
		)
		(pad "A4" smd rect
			(at 2.29997 -6.19506 90)
			(size 0.381 1.27)
			(layers "F.Cu" "F.Mask" "F.Paste")
			(net "GND")
		)
		(pad "A5" smd rect
			(at 2.29997 -5.595112 90)
			(size 0.381 1.27)
			(layers "F.Cu" "F.Mask" "F.Paste")
			(net "GND")
		)
		(pad "A6" smd rect
			(at 2.29997 -4.99491 90)
			(size 0.381 1.27)
			(layers "F.Cu" "F.Mask" "F.Paste")
			(net "GND")
		)
		(pad "A7" smd rect
			(at 2.29997 -4.394962 90)
			(size 0.381 1.27)
			(layers "F.Cu" "F.Mask" "F.Paste")
			(net "SMB_ISO_SSD3_R_SCL")
		)
		(pad "A8" smd rect
			(at 2.29997 -3.795014 90)
			(size 0.381 1.27)
			(layers "F.Cu" "F.Mask" "F.Paste")
			(net "SMB_ISO_SSD3_R_SDA")
		)
		(pad "A9" smd rect
			(at 2.29997 -3.195066 90)
			(size 0.381 1.27)
			(layers "F.Cu" "F.Mask" "F.Paste")
			(net "RST_SMB_SSD3_ISO_R_N")
		)
		(pad "A10" smd rect
			(at 2.29997 -2.595118 90)
			(size 0.381 1.27)
			(layers "F.Cu" "F.Mask" "F.Paste")
			(net "SSD3_LED_ISO_R_N")
		)
		(pad "A11" smd rect
			(at 2.29997 -1.994916 90)
			(size 0.381 1.27)
			(layers "F.Cu" "F.Mask" "F.Paste")
			(net "PU_CLKREQ3")
		)
		(pad "A12" smd rect
			(at 2.29997 -1.394968 90)
			(size 0.381 1.27)
			(layers "F.Cu" "F.Mask" "F.Paste")
			(net "PRSNT_SSD3_N")
		)
		(pad "A13" smd rect
			(at 2.29997 -0.79502 90)
			(size 0.381 1.27)
			(layers "F.Cu" "F.Mask" "F.Paste")
			(net "GND")
		)
		(pad "A14" smd rect
			(at 2.29997 -0.195072 90)
			(size 0.381 1.27)
			(layers "F.Cu" "F.Mask" "F.Paste")
			(net "Net_8567")
		)
		(pad "A15" smd rect
			(at 2.29997 0.404876 90)
			(size 0.381 1.27)
			(layers "F.Cu" "F.Mask" "F.Paste")
			(net "Net_8566")
		)
		(pad "A16" smd rect
			(at 2.29997 1.005078 90)
			(size 0.381 1.27)
			(layers "F.Cu" "F.Mask" "F.Paste")
			(net "GND")
		)
		(pad "A17" smd rect
			(at 2.29997 1.605026 90)
			(size 0.381 1.27)
			(layers "F.Cu" "F.Mask" "F.Paste")
			(net "P5E_PEX0_STN2_RX_DN<32>")
		)
		(pad "A18" smd rect
			(at 2.29997 2.204974 90)
			(size 0.381 1.27)
			(layers "F.Cu" "F.Mask" "F.Paste")
			(net "P5E_PEX0_STN2_RX_DP<32>")
		)
		(pad "A19" smd rect
			(at 2.29997 2.804922 90)
			(size 0.381 1.27)
			(layers "F.Cu" "F.Mask" "F.Paste")
			(net "GND")
		)
		(pad "A20" smd rect
			(at 2.29997 3.405124 90)
			(size 0.381 1.27)
			(layers "F.Cu" "F.Mask" "F.Paste")
			(net "P5E_PEX0_STN2_RX_DN<33>")
		)
		(pad "A21" smd rect
			(at 2.29997 4.005072 90)
			(size 0.381 1.27)
			(layers "F.Cu" "F.Mask" "F.Paste")
			(net "P5E_PEX0_STN2_RX_DP<33>")
		)
		(pad "A22" smd rect
			(at 2.29997 4.60502 90)
			(size 0.381 1.27)
			(layers "F.Cu" "F.Mask" "F.Paste")
			(net "GND")
		)
		(pad "A23" smd rect
			(at 2.29997 5.204968 90)
			(size 0.381 1.27)
			(layers "F.Cu" "F.Mask" "F.Paste")
			(net "P5E_PEX0_STN2_RX_DN<34>")
		)
		(pad "A24" smd rect
			(at 2.29997 5.804916 90)
			(size 0.381 1.27)
			(layers "F.Cu" "F.Mask" "F.Paste")
			(net "P5E_PEX0_STN2_RX_DP<34>")
		)
		(pad "A25" smd rect
			(at 2.29997 6.405118 90)
			(size 0.381 1.27)
			(layers "F.Cu" "F.Mask" "F.Paste")
			(net "GND")
		)
		(pad "A26" smd rect
			(at 2.29997 7.005066 90)
			(size 0.381 1.27)
			(layers "F.Cu" "F.Mask" "F.Paste")
			(net "P5E_PEX0_STN2_RX_DN<35>")
		)
		(pad "A27" smd rect
			(at 2.29997 7.605014 90)
			(size 0.381 1.27)
			(layers "F.Cu" "F.Mask" "F.Paste")
			(net "P5E_PEX0_STN2_RX_DP<35>")
		)
		(pad "A28" smd rect
			(at 2.29997 8.204962 90)
			(size 0.381 1.27)
			(layers "F.Cu" "F.Mask" "F.Paste")
			(net "GND")
		)
		(pad "B1" smd rect
			(at -2.29997 -7.994904 90)
			(size 0.381 1.27)
			(layers "F.Cu" "F.Mask" "F.Paste")
			(net "P12V_SSD3")
		)
		(pad "B2" smd rect
			(at -2.29997 -7.394956 90)
			(size 0.381 1.27)
			(layers "F.Cu" "F.Mask" "F.Paste")
			(net "P12V_SSD3")
		)
		(pad "B3" smd rect
			(at -2.29997 -6.795008 90)
			(size 0.381 1.27)
			(layers "F.Cu" "F.Mask" "F.Paste")
			(net "P12V_SSD3")
		)
		(pad "B4" smd rect
			(at -2.29997 -6.19506 90)
			(size 0.381 1.27)
			(layers "F.Cu" "F.Mask" "F.Paste")
			(net "P12V_SSD3")
		)
		(pad "B5" smd rect
			(at -2.29997 -5.595112 90)
			(size 0.381 1.27)
			(layers "F.Cu" "F.Mask" "F.Paste")
			(net "P12V_SSD3")
		)
		(pad "B6" smd rect
			(at -2.29997 -4.99491 90)
			(size 0.381 1.27)
			(layers "F.Cu" "F.Mask" "F.Paste")
			(net "P12V_SSD3")
		)
		(pad "B7" smd rect
			(at -2.29997 -4.394962 90)
			(size 0.381 1.27)
			(layers "F.Cu" "F.Mask" "F.Paste")
			(net "Net_8568")
		)
		(pad "B8" smd rect
			(at -2.29997 -3.795014 90)
			(size 0.381 1.27)
			(layers "F.Cu" "F.Mask" "F.Paste")
			(net "Net_8565")
		)
		(pad "B9" smd rect
			(at -2.29997 -3.195066 90)
			(size 0.381 1.27)
			(layers "F.Cu" "F.Mask" "F.Paste")
			(net "DUALPORT_N_SSD3")
		)
		(pad "B10" smd rect
			(at -2.29997 -2.595118 90)
			(size 0.381 1.27)
			(layers "F.Cu" "F.Mask" "F.Paste")
			(net "RST_SSD3_PERST_R_N")
		)
		(pad "B11" smd rect
			(at -2.29997 -1.994916 90)
			(size 0.381 1.27)
			(layers "F.Cu" "F.Mask" "F.Paste")
			(net "P3V3_SSD3")
		)
		(pad "B12" smd rect
			(at -2.29997 -1.394968 90)
			(size 0.381 1.27)
			(layers "F.Cu" "F.Mask" "F.Paste")
			(net "SSD3_PWRDIS_R")
		)
		(pad "B13" smd rect
			(at -2.29997 -0.79502 90)
			(size 0.381 1.27)
			(layers "F.Cu" "F.Mask" "F.Paste")
			(net "GND")
		)
		(pad "B14" smd rect
			(at -2.29997 -0.195072 90)
			(size 0.381 1.27)
			(layers "F.Cu" "F.Mask" "F.Paste")
			(net "CLK_100M_DB800ZL_SSD3_R_DN")
		)
		(pad "B15" smd rect
			(at -2.29997 0.404876 90)
			(size 0.381 1.27)
			(layers "F.Cu" "F.Mask" "F.Paste")
			(net "CLK_100M_DB800ZL_SSD3_R_DP")
		)
		(pad "B16" smd rect
			(at -2.29997 1.005078 90)
			(size 0.381 1.27)
			(layers "F.Cu" "F.Mask" "F.Paste")
			(net "GND")
		)
		(pad "B17" smd rect
			(at -2.29997 1.605026 90)
			(size 0.381 1.27)
			(layers "F.Cu" "F.Mask" "F.Paste")
			(net "P5E_PEX0_STN2_TX_C_DN<32>")
		)
		(pad "B18" smd rect
			(at -2.29997 2.204974 90)
			(size 0.381 1.27)
			(layers "F.Cu" "F.Mask" "F.Paste")
			(net "P5E_PEX0_STN2_TX_C_DP<32>")
		)
		(pad "B19" smd rect
			(at -2.29997 2.804922 90)
			(size 0.381 1.27)
			(layers "F.Cu" "F.Mask" "F.Paste")
			(net "GND")
		)
		(pad "B20" smd rect
			(at -2.29997 3.405124 90)
			(size 0.381 1.27)
			(layers "F.Cu" "F.Mask" "F.Paste")
			(net "P5E_PEX0_STN2_TX_C_DN<33>")
		)
		(pad "B21" smd rect
			(at -2.29997 4.005072 90)
			(size 0.381 1.27)
			(layers "F.Cu" "F.Mask" "F.Paste")
			(net "P5E_PEX0_STN2_TX_C_DP<33>")
		)
		(pad "B22" smd rect
			(at -2.29997 4.60502 90)
			(size 0.381 1.27)
			(layers "F.Cu" "F.Mask" "F.Paste")
			(net "GND")
		)
		(pad "B23" smd rect
			(at -2.29997 5.204968 90)
			(size 0.381 1.27)
			(layers "F.Cu" "F.Mask" "F.Paste")
			(net "P5E_PEX0_STN2_TX_C_DN<34>")
		)
		(pad "B24" smd rect
			(at -2.29997 5.804916 90)
			(size 0.381 1.27)
			(layers "F.Cu" "F.Mask" "F.Paste")
			(net "P5E_PEX0_STN2_TX_C_DP<34>")
		)
		(pad "B25" smd rect
			(at -2.29997 6.405118 90)
			(size 0.381 1.27)
			(layers "F.Cu" "F.Mask" "F.Paste")
			(net "GND")
		)
		(pad "B26" smd rect
			(at -2.29997 7.005066 90)
			(size 0.381 1.27)
			(layers "F.Cu" "F.Mask" "F.Paste")
			(net "P5E_PEX0_STN2_TX_C_DN<35>")
		)
		(pad "B27" smd rect
			(at -2.29997 7.605014 90)
			(size 0.381 1.27)
			(layers "F.Cu" "F.Mask" "F.Paste")
			(net "P5E_PEX0_STN2_TX_C_DP<35>")
		)
		(pad "B28" smd rect
			(at -2.29997 8.204962 90)
			(size 0.381 1.27)
			(layers "F.Cu" "F.Mask" "F.Paste")
			(net "GND")
		)
		(pad "G1" thru_hole oval
			(at 0 -11.364976 90)
			(size 1.6256 3.4798)
			(drill oval 1.1176 2.4638)
			(layers "*.Cu" "*.Mask")
			(remove_unused_layers no)
			(net "GND")
			(clearance 0.127)
			(thermal_gap 0.127)
		)
		(pad "G2" thru_hole oval
			(at 0 11.364976 90)
			(size 1.6256 3.4798)
			(drill oval 1.1176 2.4638)
			(layers "*.Cu" "*.Mask")
			(remove_unused_layers no)
			(net "GND")
			(clearance 0.127)
			(thermal_gap 0.127)
		)
		(zone
			(layer "F.Cu")
			(hatch none 0.5)
			(connect_pads
				(clearance 0)
			)
			(min_thickness 0.25)
			(keepout
				(tracks not_allowed)
				(vias allowed)
				(pads allowed)
				(copperpour not_allowed)
				(footprints allowed)
			)
			(placement
				(enabled no)
				(sheetname "")
			)
			(fill
				(thermal_gap 0.5)
				(thermal_bridge_width 0.5)
				(island_removal_mode 0)
			)
			(polygon
				(pts
					(xy 92.344748 -38.850062) (xy 89.59469 -38.850062) (xy 89.59469 -35.900106) (xy 92.344748 -35.900106)
				)
			)
		)
		(zone
			(layer "F.Cu")
			(hatch none 0.5)
			(connect_pads
				(clearance 0)
			)
			(min_thickness 0.25)
			(keepout
				(tracks not_allowed)
				(vias allowed)
				(pads allowed)
				(copperpour not_allowed)
				(footprints allowed)
			)
			(placement
				(enabled no)
				(sheetname "")
			)
			(fill
				(thermal_gap 0.5)
				(thermal_bridge_width 0.5)
				(island_removal_mode 0)
			)
			(polygon
				(pts
					(xy 93.41485 -17.670018) (xy 89.584784 -17.670018) (xy 89.584784 -14.720062) (xy 93.41485 -14.720062)
				)
			)
		)
		(zone
			(layers "F.Cu" "B.Cu" "In1.Cu" "In2.Cu" "In3.Cu" "In4.Cu" "In5.Cu" "In6.Cu"
				"In7.Cu" "In8.Cu" "In9.Cu" "In10.Cu" "In11.Cu" "In12.Cu" "In13.Cu" "In14.Cu"
				"In15.Cu" "In16.Cu"
			)
			(hatch none 0.5)
			(connect_pads
				(clearance 0)
			)
			(min_thickness 0.25)
			(keepout
				(tracks not_allowed)
				(vias allowed)
				(pads allowed)
				(copperpour not_allowed)
				(footprints allowed)
			)
			(placement
				(enabled no)
				(sheetname "")
			)
			(fill
				(thermal_gap 0.5)
				(thermal_bridge_width 0.5)
				(island_removal_mode 0)
			)
			(polygon
				(pts
					(arc
						(start 91.929966 -36.60013)
						(mid 89.999566 -36.60013)
						(end 91.929966 -36.60013)
					)
				)
			)
		)
		(zone
			(layers "F.Cu" "B.Cu" "In1.Cu" "In2.Cu" "In3.Cu" "In4.Cu" "In5.Cu" "In6.Cu"
				"In7.Cu" "In8.Cu" "In9.Cu" "In10.Cu" "In11.Cu" "In12.Cu" "In13.Cu" "In14.Cu"
				"In15.Cu" "In16.Cu"
			)
			(hatch none 0.5)
			(connect_pads
				(clearance 0)
			)
			(min_thickness 0.25)
			(keepout
				(tracks not_allowed)
				(vias allowed)
				(pads allowed)
				(copperpour not_allowed)
				(footprints allowed)
			)
			(placement
				(enabled no)
				(sheetname "")
			)
			(fill
				(thermal_gap 0.5)
				(thermal_bridge_width 0.5)
				(island_removal_mode 0)
			)
			(polygon
				(pts
					(arc
						(start 93.680026 -16.969994)
						(mid 91.749626 -16.969994)
						(end 93.680026 -16.969994)
					)
				)
			)
		)
	)
	(footprint ""
		(layer "F.Cu")
		(at 233.839512 -234.728004 -90)
		(property "Reference" "R6191"
			(at 0 0 270)
			(layer "F.SilkS")
			(hide yes)
			(effects
				(font
					(size 1.27 1.27)
				)
			)
		)
		(property "Value" ""
			(at 0 0 270)
			(layer "F.Fab")
			(effects
				(font
					(size 1.27 1.27)
				)
			)
		)
		(duplicate_pad_numbers_are_jumpers no)
		(fp_line
			(start -0.7874 0.4064)
			(end -0.7874 -0.4064)
			(stroke
				(width 0.1524)
				(type default)
			)
			(layer "F.SilkS")
		)
		(fp_line
			(start 0.7874 0.4064)
			(end -0.7874 0.4064)
			(stroke
				(width 0.1524)
				(type default)
			)
			(layer "F.SilkS")
		)
		(fp_line
			(start -0.7874 -0.4064)
			(end 0.7874 -0.4064)
			(stroke
				(width 0.1524)
				(type default)
			)
			(layer "F.SilkS")
		)
		(fp_line
			(start 0.7874 -0.4064)
			(end 0.7874 0.4064)
			(stroke
				(width 0.1524)
				(type default)
			)
			(layer "F.SilkS")
		)
		(fp_line
			(start -0.67945 0.3048)
			(end -0.67945 -0.305054)
			(stroke
				(width 0.1)
				(type default)
			)
			(layer "F.Fab")
		)
		(fp_line
			(start -0.12065 0.3048)
			(end -0.67945 0.3048)
			(stroke
				(width 0.1)
				(type default)
			)
			(layer "F.Fab")
		)
		(fp_line
			(start 0.120396 0.3048)
			(end 0.120396 0.2794)
			(stroke
				(width 0.1)
				(type default)
			)
			(layer "F.Fab")
		)
		(fp_line
			(start 0.67945 0.3048)
			(end 0.120396 0.3048)
			(stroke
				(width 0.1)
				(type default)
			)
			(layer "F.Fab")
		)
		(fp_line
			(start -0.12065 0.2794)
			(end -0.12065 0.3048)
			(stroke
				(width 0.1)
				(type default)
			)
			(layer "F.Fab")
		)
		(fp_line
			(start 0.120396 0.2794)
			(end -0.12065 0.2794)
			(stroke
				(width 0.1)
				(type default)
			)
			(layer "F.Fab")
		)
		(fp_line
			(start -0.12065 -0.2794)
			(end 0.12065 -0.2794)
			(stroke
				(width 0.1)
				(type default)
			)
			(layer "F.Fab")
		)
		(fp_line
			(start 0.12065 -0.2794)
			(end 0.12065 -0.3048)
			(stroke
				(width 0.1)
				(type default)
			)
			(layer "F.Fab")
		)
		(fp_line
			(start 0.12065 -0.3048)
			(end 0.67945 -0.3048)
			(stroke
				(width 0.1)
				(type default)
			)
			(layer "F.Fab")
		)
		(fp_line
			(start 0.67945 -0.3048)
			(end 0.67945 0.3048)
			(stroke
				(width 0.1)
				(type default)
			)
			(layer "F.Fab")
		)
		(fp_line
			(start -0.67945 -0.305054)
			(end -0.12065 -0.305054)
			(stroke
				(width 0.1)
				(type default)
			)
			(layer "F.Fab")
		)
		(fp_line
			(start -0.12065 -0.305054)
			(end -0.12065 -0.2794)
			(stroke
				(width 0.1)
				(type default)
			)
			(layer "F.Fab")
		)
		(pad "1" smd circle
			(at -0.40005 0 270)
			(size 0 0)
			(layers "F.Cu" "F.Mask" "F.Paste")
			(net "GND")
		)
		(pad "2" smd circle
			(at 0.40005 0 270)
			(size 0 0)
			(layers "F.Cu" "F.Mask" "F.Paste")
			(net "SSD9_PWRDIS_BIC_R")
		)
	)
	(footprint ""
		(layer "F.Cu")
		(at 112.311942 -113.563654)
		(property "Reference" "PC613"
			(at 0 0 0)
			(layer "F.SilkS")
			(hide yes)
			(effects
				(font
					(size 1.27 1.27)
				)
			)
		)
		(property "Value" ""
			(at 0 0 0)
			(layer "F.Fab")
			(effects
				(font
					(size 1.27 1.27)
				)
			)
		)
		(duplicate_pad_numbers_are_jumpers no)
		(fp_line
			(start -0.7874 -0.4064)
			(end 0.7874 -0.4064)
			(stroke
				(width 0.1524)
				(type default)
			)
			(layer "F.SilkS")
		)
		(fp_line
			(start -0.7874 0.4064)
			(end -0.7874 -0.4064)
			(stroke
				(width 0.1524)
				(type default)
			)
			(layer "F.SilkS")
		)
		(fp_line
			(start 0.7874 -0.4064)
			(end 0.7874 0.4064)
			(stroke
				(width 0.1524)
				(type default)
			)
			(layer "F.SilkS")
		)
		(fp_line
			(start 0.7874 0.4064)
			(end -0.7874 0.4064)
			(stroke
				(width 0.1524)
				(type default)
			)
			(layer "F.SilkS")
		)
		(fp_line
			(start -0.67945 -0.305054)
			(end -0.12065 -0.305054)
			(stroke
				(width 0.1)
				(type default)
			)
			(layer "F.Fab")
		)
		(fp_line
			(start -0.67945 0.3048)
			(end -0.67945 -0.305054)
			(stroke
				(width 0.1)
				(type default)
			)
			(layer "F.Fab")
		)
		(fp_line
			(start -0.12065 -0.305054)
			(end -0.12065 -0.2794)
			(stroke
				(width 0.1)
				(type default)
			)
			(layer "F.Fab")
		)
		(fp_line
			(start -0.12065 -0.2794)
			(end 0.12065 -0.2794)
			(stroke
				(width 0.1)
				(type default)
			)
			(layer "F.Fab")
		)
		(fp_line
			(start -0.12065 0.2794)
			(end -0.12065 0.3048)
			(stroke
				(width 0.1)
				(type default)
			)
			(layer "F.Fab")
		)
		(fp_line
			(start -0.12065 0.3048)
			(end -0.67945 0.3048)
			(stroke
				(width 0.1)
				(type default)
			)
			(layer "F.Fab")
		)
		(fp_line
			(start 0.120396 0.2794)
			(end -0.12065 0.2794)
			(stroke
				(width 0.1)
				(type default)
			)
			(layer "F.Fab")
		)
		(fp_line
			(start 0.120396 0.3048)
			(end 0.120396 0.2794)
			(stroke
				(width 0.1)
				(type default)
			)
			(layer "F.Fab")
		)
		(fp_line
			(start 0.12065 -0.3048)
			(end 0.67945 -0.3048)
			(stroke
				(width 0.1)
				(type default)
			)
			(layer "F.Fab")
		)
		(fp_line
			(start 0.12065 -0.2794)
			(end 0.12065 -0.3048)
			(stroke
				(width 0.1)
				(type default)
			)
			(layer "F.Fab")
		)
		(fp_line
			(start 0.67945 -0.3048)
			(end 0.67945 0.3048)
			(stroke
				(width 0.1)
				(type default)
			)
			(layer "F.Fab")
		)
		(fp_line
			(start 0.67945 0.3048)
			(end 0.120396 0.3048)
			(stroke
				(width 0.1)
				(type default)
			)
			(layer "F.Fab")
		)
		(pad "1" smd circle
			(at -0.40005 0)
			(size 0 0)
			(layers "F.Cu" "F.Mask" "F.Paste")
			(net "P12V_NIC1_CO_SS")
		)
		(pad "2" smd circle
			(at 0.40005 0)
			(size 0 0)
			(layers "F.Cu" "F.Mask" "F.Paste")
			(net "GND")
		)
	)
	(footprint ""
		(layer "F.Cu")
		(at 466.308948 -538.74416 180)
		(property "Reference" "J45_OTH"
			(at -3.2385 -1.402334 0)
			(unlocked yes)
			(layer "B.SilkS")
			(effects
				(font
					(size 0.7874 0.5842)
					(thickness 0.1524)
				)
				(justify mirror)
			)
		)
		(property "Value" ""
			(at 0 0 180)
			(layer "F.Fab")
			(effects
				(font
					(size 1.27 1.27)
				)
			)
		)
		(duplicate_pad_numbers_are_jumpers no)
		(pad "1" thru_hole circle
			(at 0 0 180)
			(size 0.4572 0.4572)
			(drill 0.2032)
			(layers "*.Cu" "*.Mask")
			(remove_unused_layers no)
			(net "Net_9091")
			(clearance 0.127)
			(thermal_gap 0.127)
			(padstack
				(mode front_inner_back)
				(layer "Inner"
					(shape circle)
					(size 0.4572 0.4572)
					(clearance 0.127)
				)
				(layer "B.Cu"
					(shape circle)
					(size 0.508 0.508)
					(clearance 0.1016)
				)
			)
		)
	)
	(footprint ""
		(layer "F.Cu")
		(at 194.367912 -52.035456 180)
		(property "Reference" "R866"
			(at 0 0 180)
			(layer "F.SilkS")
			(hide yes)
			(effects
				(font
					(size 1.27 1.27)
				)
			)
		)
		(property "Value" ""
			(at 0 0 180)
			(layer "F.Fab")
			(effects
				(font
					(size 1.27 1.27)
				)
			)
		)
		(duplicate_pad_numbers_are_jumpers no)
		(fp_line
			(start 0.7874 0.4064)
			(end -0.7874 0.4064)
			(stroke
				(width 0.1524)
				(type default)
			)
			(layer "F.SilkS")
		)
		(fp_line
			(start 0.7874 -0.4064)
			(end 0.7874 0.4064)
			(stroke
				(width 0.1524)
				(type default)
			)
			(layer "F.SilkS")
		)
		(fp_line
			(start -0.7874 0.4064)
			(end -0.7874 -0.4064)
			(stroke
				(width 0.1524)
				(type default)
			)
			(layer "F.SilkS")
		)
		(fp_line
			(start -0.7874 -0.4064)
			(end 0.7874 -0.4064)
			(stroke
				(width 0.1524)
				(type default)
			)
			(layer "F.SilkS")
		)
		(fp_line
			(start 0.67945 0.3048)
			(end 0.120396 0.3048)
			(stroke
				(width 0.1)
				(type default)
			)
			(layer "F.Fab")
		)
		(fp_line
			(start 0.67945 -0.3048)
			(end 0.67945 0.3048)
			(stroke
				(width 0.1)
				(type default)
			)
			(layer "F.Fab")
		)
		(fp_line
			(start 0.12065 -0.2794)
			(end 0.12065 -0.3048)
			(stroke
				(width 0.1)
				(type default)
			)
			(layer "F.Fab")
		)
		(fp_line
			(start 0.12065 -0.3048)
			(end 0.67945 -0.3048)
			(stroke
				(width 0.1)
				(type default)
			)
			(layer "F.Fab")
		)
		(fp_line
			(start 0.120396 0.3048)
			(end 0.120396 0.2794)
			(stroke
				(width 0.1)
				(type default)
			)
			(layer "F.Fab")
		)
		(fp_line
			(start 0.120396 0.2794)
			(end -0.12065 0.2794)
			(stroke
				(width 0.1)
				(type default)
			)
			(layer "F.Fab")
		)
		(fp_line
			(start -0.12065 0.3048)
			(end -0.67945 0.3048)
			(stroke
				(width 0.1)
				(type default)
			)
			(layer "F.Fab")
		)
		(fp_line
			(start -0.12065 0.2794)
			(end -0.12065 0.3048)
			(stroke
				(width 0.1)
				(type default)
			)
			(layer "F.Fab")
		)
		(fp_line
			(start -0.12065 -0.2794)
			(end 0.12065 -0.2794)
			(stroke
				(width 0.1)
				(type default)
			)
			(layer "F.Fab")
		)
		(fp_line
			(start -0.12065 -0.305054)
			(end -0.12065 -0.2794)
			(stroke
				(width 0.1)
				(type default)
			)
			(layer "F.Fab")
		)
		(fp_line
			(start -0.67945 0.3048)
			(end -0.67945 -0.305054)
			(stroke
				(width 0.1)
				(type default)
			)
			(layer "F.Fab")
		)
		(fp_line
			(start -0.67945 -0.305054)
			(end -0.12065 -0.305054)
			(stroke
				(width 0.1)
				(type default)
			)
			(layer "F.Fab")
		)
		(pad "1" smd circle
			(at -0.40005 0 180)
			(size 0 0)
			(layers "F.Cu" "F.Mask" "F.Paste")
			(net "P3V3_AUX")
		)
		(pad "2" smd circle
			(at 0.40005 0 180)
			(size 0 0)
			(layers "F.Cu" "F.Mask" "F.Paste")
			(net "PWRGD_P12V_SSD6")
		)
	)
	(footprint ""
		(layer "F.Cu")
		(at 123.67514 -93.748606)
		(property "Reference" "R1581"
			(at 0 0 0)
			(layer "F.SilkS")
			(hide yes)
			(effects
				(font
					(size 1.27 1.27)
				)
			)
		)
		(property "Value" ""
			(at 0 0 0)
			(layer "F.Fab")
			(effects
				(font
					(size 1.27 1.27)
				)
			)
		)
		(duplicate_pad_numbers_are_jumpers no)
		(fp_line
			(start -0.7874 -0.4064)
			(end 0.7874 -0.4064)
			(stroke
				(width 0.1524)
				(type default)
			)
			(layer "F.SilkS")
		)
		(fp_line
			(start -0.7874 0.4064)
			(end -0.7874 -0.4064)
			(stroke
				(width 0.1524)
				(type default)
			)
			(layer "F.SilkS")
		)
		(fp_line
			(start 0.7874 -0.4064)
			(end 0.7874 0.4064)
			(stroke
				(width 0.1524)
				(type default)
			)
			(layer "F.SilkS")
		)
		(fp_line
			(start 0.7874 0.4064)
			(end -0.7874 0.4064)
			(stroke
				(width 0.1524)
				(type default)
			)
			(layer "F.SilkS")
		)
		(fp_line
			(start -0.67945 -0.305054)
			(end -0.12065 -0.305054)
			(stroke
				(width 0.1)
				(type default)
			)
			(layer "F.Fab")
		)
		(fp_line
			(start -0.67945 0.3048)
			(end -0.67945 -0.305054)
			(stroke
				(width 0.1)
				(type default)
			)
			(layer "F.Fab")
		)
		(fp_line
			(start -0.12065 -0.305054)
			(end -0.12065 -0.2794)
			(stroke
				(width 0.1)
				(type default)
			)
			(layer "F.Fab")
		)
		(fp_line
			(start -0.12065 -0.2794)
			(end 0.12065 -0.2794)
			(stroke
				(width 0.1)
				(type default)
			)
			(layer "F.Fab")
		)
		(fp_line
			(start -0.12065 0.2794)
			(end -0.12065 0.3048)
			(stroke
				(width 0.1)
				(type default)
			)
			(layer "F.Fab")
		)
		(fp_line
			(start -0.12065 0.3048)
			(end -0.67945 0.3048)
			(stroke
				(width 0.1)
				(type default)
			)
			(layer "F.Fab")
		)
		(fp_line
			(start 0.120396 0.2794)
			(end -0.12065 0.2794)
			(stroke
				(width 0.1)
				(type default)
			)
			(layer "F.Fab")
		)
		(fp_line
			(start 0.120396 0.3048)
			(end 0.120396 0.2794)
			(stroke
				(width 0.1)
				(type default)
			)
			(layer "F.Fab")
		)
		(fp_line
			(start 0.12065 -0.3048)
			(end 0.67945 -0.3048)
			(stroke
				(width 0.1)
				(type default)
			)
			(layer "F.Fab")
		)
		(fp_line
			(start 0.12065 -0.2794)
			(end 0.12065 -0.3048)
			(stroke
				(width 0.1)
				(type default)
			)
			(layer "F.Fab")
		)
		(fp_line
			(start 0.67945 -0.3048)
			(end 0.67945 0.3048)
			(stroke
				(width 0.1)
				(type default)
			)
			(layer "F.Fab")
		)
		(fp_line
			(start 0.67945 0.3048)
			(end 0.120396 0.3048)
			(stroke
				(width 0.1)
				(type default)
			)
			(layer "F.Fab")
		)
		(pad "1" smd circle
			(at -0.40005 0)
			(size 0 0)
			(layers "F.Cu" "F.Mask" "F.Paste")
			(net "SMB_BIC_I2C9_MUX0_SSD1_R_SCL")
		)
		(pad "2" smd circle
			(at 0.40005 0)
			(size 0 0)
			(layers "F.Cu" "F.Mask" "F.Paste")
			(net "SMB_BIC_I2C9_MUX0_SSD1_SCL")
		)
	)
	(footprint ""
		(layer "F.Cu")
		(at 231.686862 -139.026392 180)
		(property "Reference" "C2792"
			(at 0 0 180)
			(layer "F.SilkS")
			(hide yes)
			(effects
				(font
					(size 1.27 1.27)
				)
			)
		)
		(property "Value" ""
			(at 0 0 180)
			(layer "F.Fab")
			(effects
				(font
					(size 1.27 1.27)
				)
			)
		)
		(duplicate_pad_numbers_are_jumpers no)
		(fp_line
			(start 0.7874 0.4064)
			(end -0.7874 0.4064)
			(stroke
				(width 0.1524)
				(type default)
			)
			(layer "F.SilkS")
		)
		(fp_line
			(start 0.7874 -0.4064)
			(end 0.7874 0.4064)
			(stroke
				(width 0.1524)
				(type default)
			)
			(layer "F.SilkS")
		)
		(fp_line
			(start -0.7874 0.4064)
			(end -0.7874 -0.4064)
			(stroke
				(width 0.1524)
				(type default)
			)
			(layer "F.SilkS")
		)
		(fp_line
			(start -0.7874 -0.4064)
			(end 0.7874 -0.4064)
			(stroke
				(width 0.1524)
				(type default)
			)
			(layer "F.SilkS")
		)
		(fp_line
			(start 0.67945 0.3048)
			(end 0.120396 0.3048)
			(stroke
				(width 0.1)
				(type default)
			)
			(layer "F.Fab")
		)
		(fp_line
			(start 0.67945 -0.3048)
			(end 0.67945 0.3048)
			(stroke
				(width 0.1)
				(type default)
			)
			(layer "F.Fab")
		)
		(fp_line
			(start 0.12065 -0.2794)
			(end 0.12065 -0.3048)
			(stroke
				(width 0.1)
				(type default)
			)
			(layer "F.Fab")
		)
		(fp_line
			(start 0.12065 -0.3048)
			(end 0.67945 -0.3048)
			(stroke
				(width 0.1)
				(type default)
			)
			(layer "F.Fab")
		)
		(fp_line
			(start 0.120396 0.3048)
			(end 0.120396 0.2794)
			(stroke
				(width 0.1)
				(type default)
			)
			(layer "F.Fab")
		)
		(fp_line
			(start 0.120396 0.2794)
			(end -0.12065 0.2794)
			(stroke
				(width 0.1)
				(type default)
			)
			(layer "F.Fab")
		)
		(fp_line
			(start -0.12065 0.3048)
			(end -0.67945 0.3048)
			(stroke
				(width 0.1)
				(type default)
			)
			(layer "F.Fab")
		)
		(fp_line
			(start -0.12065 0.2794)
			(end -0.12065 0.3048)
			(stroke
				(width 0.1)
				(type default)
			)
			(layer "F.Fab")
		)
		(fp_line
			(start -0.12065 -0.2794)
			(end 0.12065 -0.2794)
			(stroke
				(width 0.1)
				(type default)
			)
			(layer "F.Fab")
		)
		(fp_line
			(start -0.12065 -0.305054)
			(end -0.12065 -0.2794)
			(stroke
				(width 0.1)
				(type default)
			)
			(layer "F.Fab")
		)
		(fp_line
			(start -0.67945 0.3048)
			(end -0.67945 -0.305054)
			(stroke
				(width 0.1)
				(type default)
			)
			(layer "F.Fab")
		)
		(fp_line
			(start -0.67945 -0.305054)
			(end -0.12065 -0.305054)
			(stroke
				(width 0.1)
				(type default)
			)
			(layer "F.Fab")
		)
		(pad "1" smd circle
			(at -0.40005 0 180)
			(size 0 0)
			(layers "F.Cu" "F.Mask" "F.Paste")
			(net "XTAL_CK440_PEX_25M_XOUT")
		)
		(pad "2" smd circle
			(at 0.40005 0 180)
			(size 0 0)
			(layers "F.Cu" "F.Mask" "F.Paste")
			(net "GND")
		)
	)
	(footprint ""
		(layer "F.Cu")
		(at 232.409746 -120.762268 180)
		(property "Reference" "PR6892"
			(at 0 0 180)
			(layer "F.SilkS")
			(hide yes)
			(effects
				(font
					(size 1.27 1.27)
				)
			)
		)
		(property "Value" ""
			(at 0 0 180)
			(layer "F.Fab")
			(effects
				(font
					(size 1.27 1.27)
				)
			)
		)
		(duplicate_pad_numbers_are_jumpers no)
		(fp_line
			(start 0.7874 0.4064)
			(end -0.7874 0.4064)
			(stroke
				(width 0.1524)
				(type default)
			)
			(layer "F.SilkS")
		)
		(fp_line
			(start 0.7874 -0.4064)
			(end 0.7874 0.4064)
			(stroke
				(width 0.1524)
				(type default)
			)
			(layer "F.SilkS")
		)
		(fp_line
			(start -0.7874 0.4064)
			(end -0.7874 -0.4064)
			(stroke
				(width 0.1524)
				(type default)
			)
			(layer "F.SilkS")
		)
		(fp_line
			(start -0.7874 -0.4064)
			(end 0.7874 -0.4064)
			(stroke
				(width 0.1524)
				(type default)
			)
			(layer "F.SilkS")
		)
		(fp_line
			(start 0.67945 0.3048)
			(end 0.120396 0.3048)
			(stroke
				(width 0.1)
				(type default)
			)
			(layer "F.Fab")
		)
		(fp_line
			(start 0.67945 -0.3048)
			(end 0.67945 0.3048)
			(stroke
				(width 0.1)
				(type default)
			)
			(layer "F.Fab")
		)
		(fp_line
			(start 0.12065 -0.2794)
			(end 0.12065 -0.3048)
			(stroke
				(width 0.1)
				(type default)
			)
			(layer "F.Fab")
		)
		(fp_line
			(start 0.12065 -0.3048)
			(end 0.67945 -0.3048)
			(stroke
				(width 0.1)
				(type default)
			)
			(layer "F.Fab")
		)
		(fp_line
			(start 0.120396 0.3048)
			(end 0.120396 0.2794)
			(stroke
				(width 0.1)
				(type default)
			)
			(layer "F.Fab")
		)
		(fp_line
			(start 0.120396 0.2794)
			(end -0.12065 0.2794)
			(stroke
				(width 0.1)
				(type default)
			)
			(layer "F.Fab")
		)
		(fp_line
			(start -0.12065 0.3048)
			(end -0.67945 0.3048)
			(stroke
				(width 0.1)
				(type default)
			)
			(layer "F.Fab")
		)
		(fp_line
			(start -0.12065 0.2794)
			(end -0.12065 0.3048)
			(stroke
				(width 0.1)
				(type default)
			)
			(layer "F.Fab")
		)
		(fp_line
			(start -0.12065 -0.2794)
			(end 0.12065 -0.2794)
			(stroke
				(width 0.1)
				(type default)
			)
			(layer "F.Fab")
		)
		(fp_line
			(start -0.12065 -0.305054)
			(end -0.12065 -0.2794)
			(stroke
				(width 0.1)
				(type default)
			)
			(layer "F.Fab")
		)
		(fp_line
			(start -0.67945 0.3048)
			(end -0.67945 -0.305054)
			(stroke
				(width 0.1)
				(type default)
			)
			(layer "F.Fab")
		)
		(fp_line
			(start -0.67945 -0.305054)
			(end -0.12065 -0.305054)
			(stroke
				(width 0.1)
				(type default)
			)
			(layer "F.Fab")
		)
		(pad "1" smd circle
			(at -0.40005 0 180)
			(size 0 0)
			(layers "F.Cu" "F.Mask" "F.Paste")
			(net "P12V_NIC3_CO_OV_FB")
		)
		(pad "2" smd circle
			(at 0.40005 0 180)
			(size 0 0)
			(layers "F.Cu" "F.Mask" "F.Paste")
			(net "P12V_AUX")
		)
	)
	(footprint ""
		(layer "F.Cu")
		(at 275.822664 -22.867366 90)
		(property "Reference" "C3940"
			(at 0 0 90)
			(layer "F.SilkS")
			(hide yes)
			(effects
				(font
					(size 1.27 1.27)
				)
			)
		)
		(property "Value" ""
			(at 0 0 90)
			(layer "F.Fab")
			(effects
				(font
					(size 1.27 1.27)
				)
			)
		)
		(duplicate_pad_numbers_are_jumpers no)
		(fp_line
			(start 0.7874 -0.4064)
			(end 0.7874 0.4064)
			(stroke
				(width 0.1524)
				(type default)
			)
			(layer "F.SilkS")
		)
		(fp_line
			(start -0.7874 -0.4064)
			(end 0.7874 -0.4064)
			(stroke
				(width 0.1524)
				(type default)
			)
			(layer "F.SilkS")
		)
		(fp_line
			(start 0.7874 0.4064)
			(end -0.7874 0.4064)
			(stroke
				(width 0.1524)
				(type default)
			)
			(layer "F.SilkS")
		)
		(fp_line
			(start -0.7874 0.4064)
			(end -0.7874 -0.4064)
			(stroke
				(width 0.1524)
				(type default)
			)
			(layer "F.SilkS")
		)
		(fp_line
			(start -0.12065 -0.305054)
			(end -0.12065 -0.2794)
			(stroke
				(width 0.1)
				(type default)
			)
			(layer "F.Fab")
		)
		(fp_line
			(start -0.67945 -0.305054)
			(end -0.12065 -0.305054)
			(stroke
				(width 0.1)
				(type default)
			)
			(layer "F.Fab")
		)
		(fp_line
			(start 0.67945 -0.3048)
			(end 0.67945 0.3048)
			(stroke
				(width 0.1)
				(type default)
			)
			(layer "F.Fab")
		)
		(fp_line
			(start 0.12065 -0.3048)
			(end 0.67945 -0.3048)
			(stroke
				(width 0.1)
				(type default)
			)
			(layer "F.Fab")
		)
		(fp_line
			(start 0.12065 -0.2794)
			(end 0.12065 -0.3048)
			(stroke
				(width 0.1)
				(type default)
			)
			(layer "F.Fab")
		)
		(fp_line
			(start -0.12065 -0.2794)
			(end 0.12065 -0.2794)
			(stroke
				(width 0.1)
				(type default)
			)
			(layer "F.Fab")
		)
		(fp_line
			(start 0.120396 0.2794)
			(end -0.12065 0.2794)
			(stroke
				(width 0.1)
				(type default)
			)
			(layer "F.Fab")
		)
		(fp_line
			(start -0.12065 0.2794)
			(end -0.12065 0.3048)
			(stroke
				(width 0.1)
				(type default)
			)
			(layer "F.Fab")
		)
		(fp_line
			(start 0.67945 0.3048)
			(end 0.120396 0.3048)
			(stroke
				(width 0.1)
				(type default)
			)
			(layer "F.Fab")
		)
		(fp_line
			(start 0.120396 0.3048)
			(end 0.120396 0.2794)
			(stroke
				(width 0.1)
				(type default)
			)
			(layer "F.Fab")
		)
		(fp_line
			(start -0.12065 0.3048)
			(end -0.67945 0.3048)
			(stroke
				(width 0.1)
				(type default)
			)
			(layer "F.Fab")
		)
		(fp_line
			(start -0.67945 0.3048)
			(end -0.67945 -0.305054)
			(stroke
				(width 0.1)
				(type default)
			)
			(layer "F.Fab")
		)
		(pad "1" smd circle
			(at -0.40005 0 90)
			(size 0 0)
			(layers "F.Cu" "F.Mask" "F.Paste")
			(net "P12V_SSD9")
		)
		(pad "2" smd circle
			(at 0.40005 0 90)
			(size 0 0)
			(layers "F.Cu" "F.Mask" "F.Paste")
			(net "GND")
		)
	)
	(footprint ""
		(layer "F.Cu")
		(at 284.226 -86.106 180)
		(property "Reference" "R484"
			(at 0 0 180)
			(layer "F.SilkS")
			(hide yes)
			(effects
				(font
					(size 1.27 1.27)
				)
			)
		)
		(property "Value" ""
			(at 0 0 180)
			(layer "F.Fab")
			(effects
				(font
					(size 1.27 1.27)
				)
			)
		)
		(duplicate_pad_numbers_are_jumpers no)
		(fp_line
			(start 0.7874 0.4064)
			(end -0.7874 0.4064)
			(stroke
				(width 0.1524)
				(type default)
			)
			(layer "F.SilkS")
		)
		(fp_line
			(start 0.7874 -0.4064)
			(end 0.7874 0.4064)
			(stroke
				(width 0.1524)
				(type default)
			)
			(layer "F.SilkS")
		)
		(fp_line
			(start -0.7874 0.4064)
			(end -0.7874 -0.4064)
			(stroke
				(width 0.1524)
				(type default)
			)
			(layer "F.SilkS")
		)
		(fp_line
			(start -0.7874 -0.4064)
			(end 0.7874 -0.4064)
			(stroke
				(width 0.1524)
				(type default)
			)
			(layer "F.SilkS")
		)
		(fp_line
			(start 0.67945 0.3048)
			(end 0.120396 0.3048)
			(stroke
				(width 0.1)
				(type default)
			)
			(layer "F.Fab")
		)
		(fp_line
			(start 0.67945 -0.3048)
			(end 0.67945 0.3048)
			(stroke
				(width 0.1)
				(type default)
			)
			(layer "F.Fab")
		)
		(fp_line
			(start 0.12065 -0.2794)
			(end 0.12065 -0.3048)
			(stroke
				(width 0.1)
				(type default)
			)
			(layer "F.Fab")
		)
		(fp_line
			(start 0.12065 -0.3048)
			(end 0.67945 -0.3048)
			(stroke
				(width 0.1)
				(type default)
			)
			(layer "F.Fab")
		)
		(fp_line
			(start 0.120396 0.3048)
			(end 0.120396 0.2794)
			(stroke
				(width 0.1)
				(type default)
			)
			(layer "F.Fab")
		)
		(fp_line
			(start 0.120396 0.2794)
			(end -0.12065 0.2794)
			(stroke
				(width 0.1)
				(type default)
			)
			(layer "F.Fab")
		)
		(fp_line
			(start -0.12065 0.3048)
			(end -0.67945 0.3048)
			(stroke
				(width 0.1)
				(type default)
			)
			(layer "F.Fab")
		)
		(fp_line
			(start -0.12065 0.2794)
			(end -0.12065 0.3048)
			(stroke
				(width 0.1)
				(type default)
			)
			(layer "F.Fab")
		)
		(fp_line
			(start -0.12065 -0.2794)
			(end 0.12065 -0.2794)
			(stroke
				(width 0.1)
				(type default)
			)
			(layer "F.Fab")
		)
		(fp_line
			(start -0.12065 -0.305054)
			(end -0.12065 -0.2794)
			(stroke
				(width 0.1)
				(type default)
			)
			(layer "F.Fab")
		)
		(fp_line
			(start -0.67945 0.3048)
			(end -0.67945 -0.305054)
			(stroke
				(width 0.1)
				(type default)
			)
			(layer "F.Fab")
		)
		(fp_line
			(start -0.67945 -0.305054)
			(end -0.12065 -0.305054)
			(stroke
				(width 0.1)
				(type default)
			)
			(layer "F.Fab")
		)
		(pad "1" smd circle
			(at -0.40005 0 180)
			(size 0 0)
			(layers "F.Cu" "F.Mask" "F.Paste")
			(net "BB_FRU_A0")
		)
		(pad "2" smd circle
			(at 0.40005 0 180)
			(size 0 0)
			(layers "F.Cu" "F.Mask" "F.Paste")
			(net "P3V3_AUX")
		)
	)
	(footprint ""
		(layer "F.Cu")
		(at 134.794244 -213.5378 180)
		(property "Reference" "R6644"
			(at 0 0 180)
			(layer "F.SilkS")
			(hide yes)
			(effects
				(font
					(size 1.27 1.27)
				)
			)
		)
		(property "Value" ""
			(at 0 0 180)
			(layer "F.Fab")
			(effects
				(font
					(size 1.27 1.27)
				)
			)
		)
		(duplicate_pad_numbers_are_jumpers no)
		(fp_line
			(start 0.7874 0.4064)
			(end -0.7874 0.4064)
			(stroke
				(width 0.1524)
				(type default)
			)
			(layer "F.SilkS")
		)
		(fp_line
			(start 0.7874 -0.4064)
			(end 0.7874 0.4064)
			(stroke
				(width 0.1524)
				(type default)
			)
			(layer "F.SilkS")
		)
		(fp_line
			(start -0.7874 0.4064)
			(end -0.7874 -0.4064)
			(stroke
				(width 0.1524)
				(type default)
			)
			(layer "F.SilkS")
		)
		(fp_line
			(start -0.7874 -0.4064)
			(end 0.7874 -0.4064)
			(stroke
				(width 0.1524)
				(type default)
			)
			(layer "F.SilkS")
		)
		(fp_line
			(start 0.67945 0.3048)
			(end 0.120396 0.3048)
			(stroke
				(width 0.1)
				(type default)
			)
			(layer "F.Fab")
		)
		(fp_line
			(start 0.67945 -0.3048)
			(end 0.67945 0.3048)
			(stroke
				(width 0.1)
				(type default)
			)
			(layer "F.Fab")
		)
		(fp_line
			(start 0.12065 -0.2794)
			(end 0.12065 -0.3048)
			(stroke
				(width 0.1)
				(type default)
			)
			(layer "F.Fab")
		)
		(fp_line
			(start 0.12065 -0.3048)
			(end 0.67945 -0.3048)
			(stroke
				(width 0.1)
				(type default)
			)
			(layer "F.Fab")
		)
		(fp_line
			(start 0.120396 0.3048)
			(end 0.120396 0.2794)
			(stroke
				(width 0.1)
				(type default)
			)
			(layer "F.Fab")
		)
		(fp_line
			(start 0.120396 0.2794)
			(end -0.12065 0.2794)
			(stroke
				(width 0.1)
				(type default)
			)
			(layer "F.Fab")
		)
		(fp_line
			(start -0.12065 0.3048)
			(end -0.67945 0.3048)
			(stroke
				(width 0.1)
				(type default)
			)
			(layer "F.Fab")
		)
		(fp_line
			(start -0.12065 0.2794)
			(end -0.12065 0.3048)
			(stroke
				(width 0.1)
				(type default)
			)
			(layer "F.Fab")
		)
		(fp_line
			(start -0.12065 -0.2794)
			(end 0.12065 -0.2794)
			(stroke
				(width 0.1)
				(type default)
			)
			(layer "F.Fab")
		)
		(fp_line
			(start -0.12065 -0.305054)
			(end -0.12065 -0.2794)
			(stroke
				(width 0.1)
				(type default)
			)
			(layer "F.Fab")
		)
		(fp_line
			(start -0.67945 0.3048)
			(end -0.67945 -0.305054)
			(stroke
				(width 0.1)
				(type default)
			)
			(layer "F.Fab")
		)
		(fp_line
			(start -0.67945 -0.305054)
			(end -0.12065 -0.305054)
			(stroke
				(width 0.1)
				(type default)
			)
			(layer "F.Fab")
		)
		(pad "1" smd circle
			(at -0.40005 0 180)
			(size 0 0)
			(layers "F.Cu" "F.Mask" "F.Paste")
			(net "UART_PEX3_CLI_RX")
		)
		(pad "2" smd circle
			(at 0.40005 0 180)
			(size 0 0)
			(layers "F.Cu" "F.Mask" "F.Paste")
			(net "UART_PEX3_CLI_R_RX")
		)
	)
	(footprint ""
		(layer "F.Cu")
		(at 271.480534 -107.403138)
		(property "Reference" "C478"
			(at 0 0 0)
			(layer "F.SilkS")
			(hide yes)
			(effects
				(font
					(size 1.27 1.27)
				)
			)
		)
		(property "Value" ""
			(at 0 0 0)
			(layer "F.Fab")
			(effects
				(font
					(size 1.27 1.27)
				)
			)
		)
		(duplicate_pad_numbers_are_jumpers no)
		(fp_line
			(start -0.299974 -0.150114)
			(end 0.299974 -0.150114)
			(stroke
				(width 0.1)
				(type default)
			)
			(layer "F.Fab")
		)
		(fp_line
			(start -0.299974 0.150114)
			(end -0.299974 -0.150114)
			(stroke
				(width 0.1)
				(type default)
			)
			(layer "F.Fab")
		)
		(fp_line
			(start 0.299974 -0.150114)
			(end 0.299974 0.150114)
			(stroke
				(width 0.1)
				(type default)
			)
			(layer "F.Fab")
		)
		(fp_line
			(start 0.299974 0.150114)
			(end -0.299974 0.150114)
			(stroke
				(width 0.1)
				(type default)
			)
			(layer "F.Fab")
		)
		(pad "1" smd rect
			(at -0.2667 0)
			(size 0.3048 0.381)
			(layers "F.Cu" "F.Mask" "F.Paste")
			(net "P5E_PEX2_STN1_TX_DN<20>")
		)
		(pad "2" smd rect
			(at 0.2667 0)
			(size 0.3048 0.381)
			(layers "F.Cu" "F.Mask" "F.Paste")
			(net "P5E_PEX2_STN1_TX_C_DN<20>")
		)
	)
	(footprint ""
		(layer "F.Cu")
		(at 87.194898 -59.577986 90)
		(property "Reference" "PC543"
			(at 0 0 90)
			(layer "F.SilkS")
			(hide yes)
			(effects
				(font
					(size 1.27 1.27)
				)
			)
		)
		(property "Value" ""
			(at 0 0 90)
			(layer "F.Fab")
			(effects
				(font
					(size 1.27 1.27)
				)
			)
		)
		(duplicate_pad_numbers_are_jumpers no)
		(fp_line
			(start 0.7874 -0.4064)
			(end 0.7874 0.4064)
			(stroke
				(width 0.1524)
				(type default)
			)
			(layer "F.SilkS")
		)
		(fp_line
			(start -0.7874 -0.4064)
			(end 0.7874 -0.4064)
			(stroke
				(width 0.1524)
				(type default)
			)
			(layer "F.SilkS")
		)
		(fp_line
			(start 0.7874 0.4064)
			(end -0.7874 0.4064)
			(stroke
				(width 0.1524)
				(type default)
			)
			(layer "F.SilkS")
		)
		(fp_line
			(start -0.7874 0.4064)
			(end -0.7874 -0.4064)
			(stroke
				(width 0.1524)
				(type default)
			)
			(layer "F.SilkS")
		)
		(fp_line
			(start -0.12065 -0.305054)
			(end -0.12065 -0.2794)
			(stroke
				(width 0.1)
				(type default)
			)
			(layer "F.Fab")
		)
		(fp_line
			(start -0.67945 -0.305054)
			(end -0.12065 -0.305054)
			(stroke
				(width 0.1)
				(type default)
			)
			(layer "F.Fab")
		)
		(fp_line
			(start 0.67945 -0.3048)
			(end 0.67945 0.3048)
			(stroke
				(width 0.1)
				(type default)
			)
			(layer "F.Fab")
		)
		(fp_line
			(start 0.12065 -0.3048)
			(end 0.67945 -0.3048)
			(stroke
				(width 0.1)
				(type default)
			)
			(layer "F.Fab")
		)
		(fp_line
			(start 0.12065 -0.2794)
			(end 0.12065 -0.3048)
			(stroke
				(width 0.1)
				(type default)
			)
			(layer "F.Fab")
		)
		(fp_line
			(start -0.12065 -0.2794)
			(end 0.12065 -0.2794)
			(stroke
				(width 0.1)
				(type default)
			)
			(layer "F.Fab")
		)
		(fp_line
			(start 0.120396 0.2794)
			(end -0.12065 0.2794)
			(stroke
				(width 0.1)
				(type default)
			)
			(layer "F.Fab")
		)
		(fp_line
			(start -0.12065 0.2794)
			(end -0.12065 0.3048)
			(stroke
				(width 0.1)
				(type default)
			)
			(layer "F.Fab")
		)
		(fp_line
			(start 0.67945 0.3048)
			(end 0.120396 0.3048)
			(stroke
				(width 0.1)
				(type default)
			)
			(layer "F.Fab")
		)
		(fp_line
			(start 0.120396 0.3048)
			(end 0.120396 0.2794)
			(stroke
				(width 0.1)
				(type default)
			)
			(layer "F.Fab")
		)
		(fp_line
			(start -0.12065 0.3048)
			(end -0.67945 0.3048)
			(stroke
				(width 0.1)
				(type default)
			)
			(layer "F.Fab")
		)
		(fp_line
			(start -0.67945 0.3048)
			(end -0.67945 -0.305054)
			(stroke
				(width 0.1)
				(type default)
			)
			(layer "F.Fab")
		)
		(pad "1" smd circle
			(at -0.40005 0 90)
			(size 0 0)
			(layers "F.Cu" "F.Mask" "F.Paste")
			(net "P3V3_SSD3_SS")
		)
		(pad "2" smd circle
			(at 0.40005 0 90)
			(size 0 0)
			(layers "F.Cu" "F.Mask" "F.Paste")
			(net "GND")
		)
	)
	(footprint ""
		(layer "F.Cu")
		(at 52.267866 -53.051456)
		(property "Reference" "R4460"
			(at 0 0 0)
			(layer "F.SilkS")
			(hide yes)
			(effects
				(font
					(size 1.27 1.27)
				)
			)
		)
		(property "Value" ""
			(at 0 0 0)
			(layer "F.Fab")
			(effects
				(font
					(size 1.27 1.27)
				)
			)
		)
		(duplicate_pad_numbers_are_jumpers no)
		(fp_line
			(start -0.7874 -0.4064)
			(end 0.7874 -0.4064)
			(stroke
				(width 0.1524)
				(type default)
			)
			(layer "F.SilkS")
		)
		(fp_line
			(start -0.7874 0.4064)
			(end -0.7874 -0.4064)
			(stroke
				(width 0.1524)
				(type default)
			)
			(layer "F.SilkS")
		)
		(fp_line
			(start 0.7874 -0.4064)
			(end 0.7874 0.4064)
			(stroke
				(width 0.1524)
				(type default)
			)
			(layer "F.SilkS")
		)
		(fp_line
			(start 0.7874 0.4064)
			(end -0.7874 0.4064)
			(stroke
				(width 0.1524)
				(type default)
			)
			(layer "F.SilkS")
		)
		(fp_line
			(start -0.67945 -0.305054)
			(end -0.12065 -0.305054)
			(stroke
				(width 0.1)
				(type default)
			)
			(layer "F.Fab")
		)
		(fp_line
			(start -0.67945 0.3048)
			(end -0.67945 -0.305054)
			(stroke
				(width 0.1)
				(type default)
			)
			(layer "F.Fab")
		)
		(fp_line
			(start -0.12065 -0.305054)
			(end -0.12065 -0.2794)
			(stroke
				(width 0.1)
				(type default)
			)
			(layer "F.Fab")
		)
		(fp_line
			(start -0.12065 -0.2794)
			(end 0.12065 -0.2794)
			(stroke
				(width 0.1)
				(type default)
			)
			(layer "F.Fab")
		)
		(fp_line
			(start -0.12065 0.2794)
			(end -0.12065 0.3048)
			(stroke
				(width 0.1)
				(type default)
			)
			(layer "F.Fab")
		)
		(fp_line
			(start -0.12065 0.3048)
			(end -0.67945 0.3048)
			(stroke
				(width 0.1)
				(type default)
			)
			(layer "F.Fab")
		)
		(fp_line
			(start 0.120396 0.2794)
			(end -0.12065 0.2794)
			(stroke
				(width 0.1)
				(type default)
			)
			(layer "F.Fab")
		)
		(fp_line
			(start 0.120396 0.3048)
			(end 0.120396 0.2794)
			(stroke
				(width 0.1)
				(type default)
			)
			(layer "F.Fab")
		)
		(fp_line
			(start 0.12065 -0.3048)
			(end 0.67945 -0.3048)
			(stroke
				(width 0.1)
				(type default)
			)
			(layer "F.Fab")
		)
		(fp_line
			(start 0.12065 -0.2794)
			(end 0.12065 -0.3048)
			(stroke
				(width 0.1)
				(type default)
			)
			(layer "F.Fab")
		)
		(fp_line
			(start 0.67945 -0.3048)
			(end 0.67945 0.3048)
			(stroke
				(width 0.1)
				(type default)
			)
			(layer "F.Fab")
		)
		(fp_line
			(start 0.67945 0.3048)
			(end 0.120396 0.3048)
			(stroke
				(width 0.1)
				(type default)
			)
			(layer "F.Fab")
		)
		(pad "1" smd circle
			(at -0.40005 0)
			(size 0 0)
			(layers "F.Cu" "F.Mask" "F.Paste")
			(net "PWRGD_P12V_SSD1")
		)
		(pad "2" smd circle
			(at 0.40005 0)
			(size 0 0)
			(layers "F.Cu" "F.Mask" "F.Paste")
			(net "PWRGD_P12V_SSD1_R")
		)
	)
	(footprint ""
		(layer "F.Cu")
		(at 23.502112 -254.850646 180)
		(property "Reference" "D1"
			(at 1.109726 -1.44526 0)
			(unlocked yes)
			(layer "F.SilkS")
			(effects
				(font
					(size 0.7874 0.5842)
					(thickness 0.1524)
				)
				(justify left)
			)
		)
		(property "Value" ""
			(at 0 0 180)
			(layer "F.Fab")
			(effects
				(font
					(size 1.27 1.27)
				)
			)
		)
		(duplicate_pad_numbers_are_jumpers no)
		(fp_line
			(start 1.16078 0.4826)
			(end -0.64008 0.4826)
			(stroke
				(width 0.1524)
				(type default)
			)
			(layer "F.SilkS")
		)
		(fp_line
			(start 1.16078 -0.4826)
			(end 1.16078 0.4826)
			(stroke
				(width 0.1524)
				(type default)
			)
			(layer "F.SilkS")
		)
		(fp_line
			(start 1.03378 0.4826)
			(end -0.79248 0.4826)
			(stroke
				(width 0.1524)
				(type default)
			)
			(layer "F.SilkS")
		)
		(fp_line
			(start 1.03378 -0.4826)
			(end 1.03378 0.4826)
			(stroke
				(width 0.1524)
				(type default)
			)
			(layer "F.SilkS")
		)
		(fp_line
			(start 0.90678 0.4826)
			(end -0.90678 0.4826)
			(stroke
				(width 0.1524)
				(type default)
			)
			(layer "F.SilkS")
		)
		(fp_line
			(start 0.90678 -0.4826)
			(end 0.90678 0.4826)
			(stroke
				(width 0.1524)
				(type default)
			)
			(layer "F.SilkS")
		)
		(fp_line
			(start -0.64008 -0.4826)
			(end 1.16078 -0.4826)
			(stroke
				(width 0.1524)
				(type default)
			)
			(layer "F.SilkS")
		)
		(fp_line
			(start -0.79248 -0.4826)
			(end 1.03378 -0.4826)
			(stroke
				(width 0.1524)
				(type default)
			)
			(layer "F.SilkS")
		)
		(fp_line
			(start -0.89408 -0.4826)
			(end 0.90678 -0.4826)
			(stroke
				(width 0.1524)
				(type default)
			)
			(layer "F.SilkS")
		)
		(fp_line
			(start -0.90678 0.4826)
			(end -0.90678 -0.4699)
			(stroke
				(width 0.1524)
				(type default)
			)
			(layer "F.SilkS")
		)
		(fp_line
			(start 0.499872 0.249936)
			(end -0.499872 0.249936)
			(stroke
				(width 0.1)
				(type default)
			)
			(layer "F.Fab")
		)
		(fp_line
			(start 0.499872 -0.249936)
			(end 0.499872 0.249936)
			(stroke
				(width 0.1)
				(type default)
			)
			(layer "F.Fab")
		)
		(fp_line
			(start -0.499872 0.249936)
			(end -0.499872 -0.249936)
			(stroke
				(width 0.1)
				(type default)
			)
			(layer "F.Fab")
		)
		(fp_line
			(start -0.499872 -0.249936)
			(end 0.499872 -0.249936)
			(stroke
				(width 0.1)
				(type default)
			)
			(layer "F.Fab")
		)
		(pad "A" smd rect
			(at -0.47498 0 180)
			(size 0.6096 0.7112)
			(layers "F.Cu" "F.Mask" "F.Paste")
			(net "LED_PEX0_SYS_ERR_N")
		)
		(pad "C" smd rect
			(at 0.47498 0 180)
			(size 0.6096 0.7112)
			(layers "F.Cu" "F.Mask" "F.Paste")
			(net "PEX0_SYS_ERR_3V3_N")
		)
	)
	(footprint ""
		(layer "F.Cu")
		(at 222.130874 -50.52695 -90)
		(property "Reference" "R1753"
			(at 0 0 270)
			(layer "F.SilkS")
			(hide yes)
			(effects
				(font
					(size 1.27 1.27)
				)
			)
		)
		(property "Value" ""
			(at 0 0 270)
			(layer "F.Fab")
			(effects
				(font
					(size 1.27 1.27)
				)
			)
		)
		(duplicate_pad_numbers_are_jumpers no)
		(fp_line
			(start -0.7874 0.4064)
			(end -0.7874 -0.4064)
			(stroke
				(width 0.1524)
				(type default)
			)
			(layer "F.SilkS")
		)
		(fp_line
			(start 0.7874 0.4064)
			(end -0.7874 0.4064)
			(stroke
				(width 0.1524)
				(type default)
			)
			(layer "F.SilkS")
		)
		(fp_line
			(start -0.7874 -0.4064)
			(end 0.7874 -0.4064)
			(stroke
				(width 0.1524)
				(type default)
			)
			(layer "F.SilkS")
		)
		(fp_line
			(start 0.7874 -0.4064)
			(end 0.7874 0.4064)
			(stroke
				(width 0.1524)
				(type default)
			)
			(layer "F.SilkS")
		)
		(fp_line
			(start -0.67945 0.3048)
			(end -0.67945 -0.305054)
			(stroke
				(width 0.1)
				(type default)
			)
			(layer "F.Fab")
		)
		(fp_line
			(start -0.12065 0.3048)
			(end -0.67945 0.3048)
			(stroke
				(width 0.1)
				(type default)
			)
			(layer "F.Fab")
		)
		(fp_line
			(start 0.120396 0.3048)
			(end 0.120396 0.2794)
			(stroke
				(width 0.1)
				(type default)
			)
			(layer "F.Fab")
		)
		(fp_line
			(start 0.67945 0.3048)
			(end 0.120396 0.3048)
			(stroke
				(width 0.1)
				(type default)
			)
			(layer "F.Fab")
		)
		(fp_line
			(start -0.12065 0.2794)
			(end -0.12065 0.3048)
			(stroke
				(width 0.1)
				(type default)
			)
			(layer "F.Fab")
		)
		(fp_line
			(start 0.120396 0.2794)
			(end -0.12065 0.2794)
			(stroke
				(width 0.1)
				(type default)
			)
			(layer "F.Fab")
		)
		(fp_line
			(start -0.12065 -0.2794)
			(end 0.12065 -0.2794)
			(stroke
				(width 0.1)
				(type default)
			)
			(layer "F.Fab")
		)
		(fp_line
			(start 0.12065 -0.2794)
			(end 0.12065 -0.3048)
			(stroke
				(width 0.1)
				(type default)
			)
			(layer "F.Fab")
		)
		(fp_line
			(start 0.12065 -0.3048)
			(end 0.67945 -0.3048)
			(stroke
				(width 0.1)
				(type default)
			)
			(layer "F.Fab")
		)
		(fp_line
			(start 0.67945 -0.3048)
			(end 0.67945 0.3048)
			(stroke
				(width 0.1)
				(type default)
			)
			(layer "F.Fab")
		)
		(fp_line
			(start -0.67945 -0.305054)
			(end -0.12065 -0.305054)
			(stroke
				(width 0.1)
				(type default)
			)
			(layer "F.Fab")
		)
		(fp_line
			(start -0.12065 -0.305054)
			(end -0.12065 -0.2794)
			(stroke
				(width 0.1)
				(type default)
			)
			(layer "F.Fab")
		)
		(pad "1" smd circle
			(at -0.40005 0 270)
			(size 0 0)
			(layers "F.Cu" "F.Mask" "F.Paste")
			(net "P3V3_AUX")
		)
		(pad "2" smd circle
			(at 0.40005 0 270)
			(size 0 0)
			(layers "F.Cu" "F.Mask" "F.Paste")
			(net "SMB_BIC_I2C6_MUX_SSD_0_7_ADC_R_SCL")
		)
	)
	(footprint ""
		(layer "F.Cu")
		(at 217.235786 -221.350586 180)
		(property "Reference" "R1493"
			(at 0 0 180)
			(layer "F.SilkS")
			(hide yes)
			(effects
				(font
					(size 1.27 1.27)
				)
			)
		)
		(property "Value" ""
			(at 0 0 180)
			(layer "F.Fab")
			(effects
				(font
					(size 1.27 1.27)
				)
			)
		)
		(duplicate_pad_numbers_are_jumpers no)
		(fp_line
			(start 0.7874 0.4064)
			(end -0.7874 0.4064)
			(stroke
				(width 0.1524)
				(type default)
			)
			(layer "F.SilkS")
		)
		(fp_line
			(start 0.7874 -0.4064)
			(end 0.7874 0.4064)
			(stroke
				(width 0.1524)
				(type default)
			)
			(layer "F.SilkS")
		)
		(fp_line
			(start -0.7874 0.4064)
			(end -0.7874 -0.4064)
			(stroke
				(width 0.1524)
				(type default)
			)
			(layer "F.SilkS")
		)
		(fp_line
			(start -0.7874 -0.4064)
			(end 0.7874 -0.4064)
			(stroke
				(width 0.1524)
				(type default)
			)
			(layer "F.SilkS")
		)
		(fp_line
			(start 0.67945 0.3048)
			(end 0.120396 0.3048)
			(stroke
				(width 0.1)
				(type default)
			)
			(layer "F.Fab")
		)
		(fp_line
			(start 0.67945 -0.3048)
			(end 0.67945 0.3048)
			(stroke
				(width 0.1)
				(type default)
			)
			(layer "F.Fab")
		)
		(fp_line
			(start 0.12065 -0.2794)
			(end 0.12065 -0.3048)
			(stroke
				(width 0.1)
				(type default)
			)
			(layer "F.Fab")
		)
		(fp_line
			(start 0.12065 -0.3048)
			(end 0.67945 -0.3048)
			(stroke
				(width 0.1)
				(type default)
			)
			(layer "F.Fab")
		)
		(fp_line
			(start 0.120396 0.3048)
			(end 0.120396 0.2794)
			(stroke
				(width 0.1)
				(type default)
			)
			(layer "F.Fab")
		)
		(fp_line
			(start 0.120396 0.2794)
			(end -0.12065 0.2794)
			(stroke
				(width 0.1)
				(type default)
			)
			(layer "F.Fab")
		)
		(fp_line
			(start -0.12065 0.3048)
			(end -0.67945 0.3048)
			(stroke
				(width 0.1)
				(type default)
			)
			(layer "F.Fab")
		)
		(fp_line
			(start -0.12065 0.2794)
			(end -0.12065 0.3048)
			(stroke
				(width 0.1)
				(type default)
			)
			(layer "F.Fab")
		)
		(fp_line
			(start -0.12065 -0.2794)
			(end 0.12065 -0.2794)
			(stroke
				(width 0.1)
				(type default)
			)
			(layer "F.Fab")
		)
		(fp_line
			(start -0.12065 -0.305054)
			(end -0.12065 -0.2794)
			(stroke
				(width 0.1)
				(type default)
			)
			(layer "F.Fab")
		)
		(fp_line
			(start -0.67945 0.3048)
			(end -0.67945 -0.305054)
			(stroke
				(width 0.1)
				(type default)
			)
			(layer "F.Fab")
		)
		(fp_line
			(start -0.67945 -0.305054)
			(end -0.12065 -0.305054)
			(stroke
				(width 0.1)
				(type default)
			)
			(layer "F.Fab")
		)
		(pad "1" smd circle
			(at -0.40005 0 180)
			(size 0 0)
			(layers "F.Cu" "F.Mask" "F.Paste")
			(net "SMB_BIC_I2C9_SSD_MUX_SDA")
		)
		(pad "2" smd circle
			(at 0.40005 0 180)
			(size 0 0)
			(layers "F.Cu" "F.Mask" "F.Paste")
			(net "SMB_BIC_I2C9_SSD_MUX_R_SDA")
		)
	)
	(footprint ""
		(layer "F.Cu")
		(at 115.600226 -120.093486 180)
		(property "Reference" "PC594"
			(at 0 0 180)
			(layer "F.SilkS")
			(hide yes)
			(effects
				(font
					(size 1.27 1.27)
				)
			)
		)
		(property "Value" ""
			(at 0 0 180)
			(layer "F.Fab")
			(effects
				(font
					(size 1.27 1.27)
				)
			)
		)
		(duplicate_pad_numbers_are_jumpers no)
		(fp_line
			(start 0.7874 0.4064)
			(end -0.7874 0.4064)
			(stroke
				(width 0.1524)
				(type default)
			)
			(layer "F.SilkS")
		)
		(fp_line
			(start 0.7874 -0.4064)
			(end 0.7874 0.4064)
			(stroke
				(width 0.1524)
				(type default)
			)
			(layer "F.SilkS")
		)
		(fp_line
			(start -0.7874 0.4064)
			(end -0.7874 -0.4064)
			(stroke
				(width 0.1524)
				(type default)
			)
			(layer "F.SilkS")
		)
		(fp_line
			(start -0.7874 -0.4064)
			(end 0.7874 -0.4064)
			(stroke
				(width 0.1524)
				(type default)
			)
			(layer "F.SilkS")
		)
		(fp_line
			(start 0.67945 0.3048)
			(end 0.120396 0.3048)
			(stroke
				(width 0.1)
				(type default)
			)
			(layer "F.Fab")
		)
		(fp_line
			(start 0.67945 -0.3048)
			(end 0.67945 0.3048)
			(stroke
				(width 0.1)
				(type default)
			)
			(layer "F.Fab")
		)
		(fp_line
			(start 0.12065 -0.2794)
			(end 0.12065 -0.3048)
			(stroke
				(width 0.1)
				(type default)
			)
			(layer "F.Fab")
		)
		(fp_line
			(start 0.12065 -0.3048)
			(end 0.67945 -0.3048)
			(stroke
				(width 0.1)
				(type default)
			)
			(layer "F.Fab")
		)
		(fp_line
			(start 0.120396 0.3048)
			(end 0.120396 0.2794)
			(stroke
				(width 0.1)
				(type default)
			)
			(layer "F.Fab")
		)
		(fp_line
			(start 0.120396 0.2794)
			(end -0.12065 0.2794)
			(stroke
				(width 0.1)
				(type default)
			)
			(layer "F.Fab")
		)
		(fp_line
			(start -0.12065 0.3048)
			(end -0.67945 0.3048)
			(stroke
				(width 0.1)
				(type default)
			)
			(layer "F.Fab")
		)
		(fp_line
			(start -0.12065 0.2794)
			(end -0.12065 0.3048)
			(stroke
				(width 0.1)
				(type default)
			)
			(layer "F.Fab")
		)
		(fp_line
			(start -0.12065 -0.2794)
			(end 0.12065 -0.2794)
			(stroke
				(width 0.1)
				(type default)
			)
			(layer "F.Fab")
		)
		(fp_line
			(start -0.12065 -0.305054)
			(end -0.12065 -0.2794)
			(stroke
				(width 0.1)
				(type default)
			)
			(layer "F.Fab")
		)
		(fp_line
			(start -0.67945 0.3048)
			(end -0.67945 -0.305054)
			(stroke
				(width 0.1)
				(type default)
			)
			(layer "F.Fab")
		)
		(fp_line
			(start -0.67945 -0.305054)
			(end -0.12065 -0.305054)
			(stroke
				(width 0.1)
				(type default)
			)
			(layer "F.Fab")
		)
		(pad "1" smd circle
			(at -0.40005 0 180)
			(size 0 0)
			(layers "F.Cu" "F.Mask" "F.Paste")
			(net "P3V3_CO_GATE")
		)
		(pad "2" smd circle
			(at 0.40005 0 180)
			(size 0 0)
			(layers "F.Cu" "F.Mask" "F.Paste")
			(net "GND")
		)
	)
	(footprint ""
		(layer "F.Cu")
		(at 128.594612 -157.304994 -90)
		(property "Reference" "PU73"
			(at -3.221736 -1.554988 0)
			(unlocked yes)
			(layer "F.SilkS")
			(effects
				(font
					(size 0.7874 0.5842)
					(thickness 0.1524)
				)
				(justify left)
			)
		)
		(property "Value" ""
			(at 0 0 270)
			(layer "F.Fab")
			(effects
				(font
					(size 1.27 1.27)
				)
			)
		)
		(duplicate_pad_numbers_are_jumpers no)
		(fp_line
			(start -1.549908 2.549906)
			(end -0.753872 2.549906)
			(stroke
				(width 0.1524)
				(type default)
			)
			(layer "F.SilkS")
		)
		(fp_line
			(start -0.245872 2.549906)
			(end 0.245872 2.549906)
			(stroke
				(width 0.1524)
				(type default)
			)
			(layer "F.SilkS")
		)
		(fp_line
			(start 0.753872 2.549906)
			(end 1.549908 2.549906)
			(stroke
				(width 0.1524)
				(type default)
			)
			(layer "F.SilkS")
		)
		(fp_line
			(start 1.549908 2.549906)
			(end 1.549908 2.253996)
			(stroke
				(width 0.1524)
				(type default)
			)
			(layer "F.SilkS")
		)
		(fp_line
			(start -1.549908 2.253996)
			(end -1.549908 2.549906)
			(stroke
				(width 0.1524)
				(type default)
			)
			(layer "F.SilkS")
		)
		(fp_line
			(start 1.549908 -2.253996)
			(end 1.549908 -2.549906)
			(stroke
				(width 0.1524)
				(type default)
			)
			(layer "F.SilkS")
		)
		(fp_line
			(start -1.549908 -2.549906)
			(end -1.549908 -2.251964)
			(stroke
				(width 0.1524)
				(type default)
			)
			(layer "F.SilkS")
		)
		(fp_line
			(start -0.752094 -2.549906)
			(end -1.549908 -2.549906)
			(stroke
				(width 0.1524)
				(type default)
			)
			(layer "F.SilkS")
		)
		(fp_line
			(start 0.2413 -2.549906)
			(end -0.2413 -2.549906)
			(stroke
				(width 0.1524)
				(type default)
			)
			(layer "F.SilkS")
		)
		(fp_line
			(start 1.549908 -2.549906)
			(end 0.752094 -2.549906)
			(stroke
				(width 0.1524)
				(type default)
			)
			(layer "F.SilkS")
		)
		(fp_poly
			(pts
				(xy -1.688084 -2.346198) (xy -2.591308 -2.647442) (xy -1.989074 -3.249422)
			)
			(stroke
				(width 0)
				(type default)
			)
			(fill yes)
			(layer "F.SilkS")
		)
		(fp_line
			(start -1.549908 2.549906)
			(end 1.549908 2.549906)
			(stroke
				(width 0.1)
				(type default)
			)
			(layer "F.Fab")
		)
		(fp_line
			(start 1.549908 2.549906)
			(end 1.549908 -2.549906)
			(stroke
				(width 0.1)
				(type default)
			)
			(layer "F.Fab")
		)
		(fp_line
			(start -1.549908 -2.549906)
			(end -1.549908 2.549906)
			(stroke
				(width 0.1)
				(type default)
			)
			(layer "F.Fab")
		)
		(fp_line
			(start 1.549908 -2.549906)
			(end -1.549908 -2.549906)
			(stroke
				(width 0.1)
				(type default)
			)
			(layer "F.Fab")
		)
		(fp_poly
			(pts
				(xy -1.891538 -1.999996) (xy -2.7432 -1.574292) (xy -2.7432 -2.4257)
			)
			(stroke
				(width 0)
				(type default)
			)
			(fill yes)
			(layer "F.Fab")
		)
		(fp_text user "10"
			(at -1.411478 3.132328 270)
			(unlocked yes)
			(layer "F.SilkS")
			(effects
				(font
					(size 0.635 0.4064)
					(thickness 0.1524)
				)
			)
		)
		(fp_text user "11"
			(at 1.830578 2.879344 270)
			(unlocked yes)
			(layer "F.SilkS")
			(effects
				(font
					(size 0.635 0.4064)
					(thickness 0.1524)
				)
			)
		)
		(fp_text user "9"
			(at -2.338832 2.5908 180)
			(unlocked yes)
			(layer "F.SilkS")
			(effects
				(font
					(size 0.635 0.4064)
					(thickness 0.1524)
				)
			)
		)
		(fp_text user "12"
			(at 2.5019 1.055624 180)
			(unlocked yes)
			(layer "F.SilkS")
			(effects
				(font
					(size 0.635 0.4064)
					(thickness 0.1524)
				)
			)
		)
		(fp_text user "21_22"
			(at 0.41783 -3.434588 270)
			(unlocked yes)
			(layer "F.SilkS")
			(effects
				(font
					(size 0.635 0.4064)
					(thickness 0.1524)
				)
			)
		)
		(fp_text user "20"
			(at 2.17551 -3.919728 180)
			(unlocked yes)
			(layer "F.SilkS")
			(effects
				(font
					(size 0.635 0.4064)
					(thickness 0.1524)
				)
			)
		)
		(fp_text user "11"
			(at 1.1938 3.329432 270)
			(unlocked yes)
			(layer "F.Fab")
			(effects
				(font
					(size 0.635 0.4064)
					(thickness 0.1524)
				)
			)
		)
		(fp_text user "10"
			(at -1.4224 3.253232 270)
			(unlocked yes)
			(layer "F.Fab")
			(effects
				(font
					(size 0.635 0.4064)
					(thickness 0.1524)
				)
			)
		)
		(fp_text user "12"
			(at 2.207768 2.7178 180)
			(unlocked yes)
			(layer "F.Fab")
			(effects
				(font
					(size 0.635 0.4064)
					(thickness 0.1524)
				)
			)
		)
		(fp_text user "9"
			(at -2.338832 2.5908 180)
			(unlocked yes)
			(layer "F.Fab")
			(effects
				(font
					(size 0.635 0.4064)
					(thickness 0.1524)
				)
			)
		)
		(fp_text user "20"
			(at 2.055368 -2.7686 180)
			(unlocked yes)
			(layer "F.Fab")
			(effects
				(font
					(size 0.635 0.4064)
					(thickness 0.1524)
				)
			)
		)
		(fp_text user "21_22"
			(at -0.0762 -3.401568 270)
			(unlocked yes)
			(layer "F.Fab")
			(effects
				(font
					(size 0.635 0.4064)
					(thickness 0.1524)
				)
			)
		)
		(pad "1" smd circle
			(at -1.374902 -1.999996 180)
			(size 0 0)
			(layers "F.Cu" "F.Mask" "F.Paste")
			(net "P12V_NIC2_CO_EN")
		)
		(pad "2" smd rect
			(at -1.400048 -1.500124 180)
			(size 0.254 0.8128)
			(layers "F.Cu" "F.Mask" "F.Paste")
			(net "GND")
		)
		(pad "3" smd rect
			(at -1.400048 -0.999998 180)
			(size 0.254 0.8128)
			(layers "F.Cu" "F.Mask" "F.Paste")
			(net "GND")
		)
		(pad "4" smd rect
			(at -1.400048 -0.499872 180)
			(size 0.254 0.8128)
			(layers "F.Cu" "F.Mask" "F.Paste")
			(net "P12V_NIC2_CO_TIMER")
		)
		(pad "5" smd rect
			(at -1.400048 0 180)
			(size 0.254 0.8128)
			(layers "F.Cu" "F.Mask" "F.Paste")
			(net "P12V_NIC2_CO_ISET")
		)
		(pad "6" smd rect
			(at -1.400048 0.499872 180)
			(size 0.254 0.8128)
			(layers "F.Cu" "F.Mask" "F.Paste")
			(net "P12V_NIC2_CO_SS")
		)
		(pad "7" smd rect
			(at -1.400048 0.999998 180)
			(size 0.254 0.8128)
			(layers "F.Cu" "F.Mask" "F.Paste")
			(net "GND")
		)
		(pad "8" smd rect
			(at -1.400048 1.500124 180)
			(size 0.254 0.8128)
			(layers "F.Cu" "F.Mask" "F.Paste")
			(net "P12V_NIC2_CO_IMON_VR")
		)
		(pad "9" smd rect
			(at -1.400048 1.999996 180)
			(size 0.254 0.8128)
			(layers "F.Cu" "F.Mask" "F.Paste")
			(net "P12V_NIC2_CO_FLTB")
		)
		(pad "10" smd rect
			(at -0.499872 2.400046 270)
			(size 0.254 0.8128)
			(layers "F.Cu" "F.Mask" "F.Paste")
			(net "PWRGD_P12V_NIC2_CO")
		)
		(pad "11" smd rect
			(at 0.499872 2.400046 270)
			(size 0.254 0.8128)
			(layers "F.Cu" "F.Mask" "F.Paste")
			(net "P12V_NIC2_CO_OV_FB")
		)
		(pad "12" smd rect
			(at 1.400048 1.999996 180)
			(size 0.254 0.8128)
			(layers "F.Cu" "F.Mask" "F.Paste")
			(net "P12V_NIC2_CO_AVIN_PD")
		)
		(pad "13" smd rect
			(at 1.400048 1.500124 180)
			(size 0.254 0.8128)
			(layers "F.Cu" "F.Mask" "F.Paste")
			(net "P12V_NIC2_R")
		)
		(pad "14" smd rect
			(at 1.400048 0.999998 180)
			(size 0.254 0.8128)
			(layers "F.Cu" "F.Mask" "F.Paste")
			(net "P12V_NIC2_R")
		)
		(pad "15" smd rect
			(at 1.400048 0.499872 180)
			(size 0.254 0.8128)
			(layers "F.Cu" "F.Mask" "F.Paste")
			(net "P12V_NIC2_R")
		)
		(pad "16" smd rect
			(at 1.400048 0 180)
			(size 0.254 0.8128)
			(layers "F.Cu" "F.Mask" "F.Paste")
			(net "P12V_NIC2_R")
		)
		(pad "17" smd rect
			(at 1.400048 -0.499872 180)
			(size 0.254 0.8128)
			(layers "F.Cu" "F.Mask" "F.Paste")
			(net "P12V_NIC2_R")
		)
		(pad "18" smd rect
			(at 1.400048 -0.999998 180)
			(size 0.254 0.8128)
			(layers "F.Cu" "F.Mask" "F.Paste")
			(net "P12V_NIC2_R")
		)
		(pad "19" smd rect
			(at 1.400048 -1.500124 180)
			(size 0.254 0.8128)
			(layers "F.Cu" "F.Mask" "F.Paste")
			(net "P12V_NIC2_R")
		)
		(pad "20" smd rect
			(at 1.400048 -1.999996 180)
			(size 0.254 0.8128)
			(layers "F.Cu" "F.Mask" "F.Paste")
			(net "P12V_NIC2_R")
		)
		(pad "21_22" smd circle
			(at 0.499872 -2.337562 180)
			(size 0 0)
			(layers "F.Cu" "F.Mask" "F.Paste")
			(net "P12V_AUX")
		)
		(pad "23" smd rect
			(at 0 -1.100074 180)
			(size 0.254 1.27)
			(layers "F.Cu" "F.Mask" "F.Paste")
			(net "P12V_AUX")
		)
		(pad "24" smd rect
			(at 0 -0.199898 180)
			(size 0.254 1.27)
			(layers "F.Cu" "F.Mask" "F.Paste")
			(net "P12V_AUX")
		)
		(pad "25" smd rect
			(at 0 0.700024 180)
			(size 0.254 1.27)
			(layers "F.Cu" "F.Mask" "F.Paste")
			(net "P12V_AUX")
		)
		(pad "26" smd rect
			(at 0 1.599946 180)
			(size 0.254 1.27)
			(layers "F.Cu" "F.Mask" "F.Paste")
			(net "P12V_AUX")
		)
	)
	(footprint ""
		(layer "F.Cu")
		(at 214.497158 -82.135472)
		(property "Reference" "U330"
			(at -2.2606 -4.663948 0)
			(unlocked yes)
			(layer "F.SilkS")
			(effects
				(font
					(size 0.7874 0.5842)
					(thickness 0.1524)
				)
				(justify left)
			)
		)
		(property "Value" ""
			(at 0 0 0)
			(layer "F.Fab")
			(effects
				(font
					(size 1.27 1.27)
				)
			)
		)
		(duplicate_pad_numbers_are_jumpers no)
		(fp_line
			(start -2.097532 -3.949954)
			(end -2.097532 3.949954)
			(stroke
				(width 0.1524)
				(type default)
			)
			(layer "F.SilkS")
		)
		(fp_line
			(start -2.097532 3.949954)
			(end 2.097532 3.949954)
			(stroke
				(width 0.1524)
				(type default)
			)
			(layer "F.SilkS")
		)
		(fp_line
			(start -1.409954 -3.949954)
			(end -2.097532 -3.949954)
			(stroke
				(width 0.1524)
				(type default)
			)
			(layer "F.SilkS")
		)
		(fp_line
			(start 0 -2.54)
			(end -1.409954 -3.949954)
			(stroke
				(width 0.1524)
				(type default)
			)
			(layer "F.SilkS")
		)
		(fp_line
			(start 1.409954 -3.949954)
			(end 0 -2.54)
			(stroke
				(width 0.1524)
				(type default)
			)
			(layer "F.SilkS")
		)
		(fp_line
			(start 2.097532 -3.949954)
			(end 1.409954 -3.949954)
			(stroke
				(width 0.1524)
				(type default)
			)
			(layer "F.SilkS")
		)
		(fp_line
			(start 2.097532 3.949954)
			(end 2.097532 -3.949954)
			(stroke
				(width 0.1524)
				(type default)
			)
			(layer "F.SilkS")
		)
		(fp_poly
			(pts
				(xy -4.7498 -4.182872) (xy -4.7498 -3.166872) (xy -3.7338 -3.674872)
			)
			(stroke
				(width 0)
				(type default)
			)
			(fill yes)
			(layer "F.SilkS")
		)
		(fp_line
			(start -2.249932 -3.949954)
			(end -2.249932 3.949954)
			(stroke
				(width 0.1)
				(type default)
			)
			(layer "F.Fab")
		)
		(fp_line
			(start -2.249932 3.949954)
			(end 2.249932 3.949954)
			(stroke
				(width 0.1)
				(type default)
			)
			(layer "F.Fab")
		)
		(fp_line
			(start 2.249932 -3.949954)
			(end -2.249932 -3.949954)
			(stroke
				(width 0.1)
				(type default)
			)
			(layer "F.Fab")
		)
		(fp_line
			(start 2.249932 3.949954)
			(end 2.249932 -3.949954)
			(stroke
				(width 0.1)
				(type default)
			)
			(layer "F.Fab")
		)
		(fp_poly
			(pts
				(xy -4.7498 -4.182872) (xy -4.7498 -3.166872) (xy -3.7338 -3.674872)
			)
			(stroke
				(width 0)
				(type default)
			)
			(fill yes)
			(layer "F.Fab")
		)
		(pad "1" smd rect
			(at -2.925064 -3.674872 270)
			(size 0.6096 1.3716)
			(layers "F.Cu" "F.Mask" "F.Paste")
			(net "IRQ_SSD_LED_IOEXP_N")
		)
		(pad "2" smd rect
			(at -2.925064 -2.925064 270)
			(size 0.4064 1.3716)
			(layers "F.Cu" "F.Mask" "F.Paste")
			(net "SSD_LED_IOEXP_A1")
		)
		(pad "3" smd rect
			(at -2.925064 -2.275078 270)
			(size 0.4064 1.3716)
			(layers "F.Cu" "F.Mask" "F.Paste")
			(net "RST_SSD_LED_IOEXP_R_N")
		)
		(pad "4" smd rect
			(at -2.925064 -1.625092 270)
			(size 0.4064 1.3716)
			(layers "F.Cu" "F.Mask" "F.Paste")
			(net "SSD0_LED")
		)
		(pad "5" smd rect
			(at -2.925064 -0.975106 270)
			(size 0.4064 1.3716)
			(layers "F.Cu" "F.Mask" "F.Paste")
			(net "SSD1_LED")
		)
		(pad "6" smd rect
			(at -2.925064 -0.32512 270)
			(size 0.4064 1.3716)
			(layers "F.Cu" "F.Mask" "F.Paste")
			(net "SSD2_LED")
		)
		(pad "7" smd rect
			(at -2.925064 0.32512 270)
			(size 0.4064 1.3716)
			(layers "F.Cu" "F.Mask" "F.Paste")
			(net "SSD3_LED")
		)
		(pad "8" smd rect
			(at -2.925064 0.975106 270)
			(size 0.4064 1.3716)
			(layers "F.Cu" "F.Mask" "F.Paste")
			(net "SSD4_LED")
		)
		(pad "9" smd rect
			(at -2.925064 1.625092 270)
			(size 0.4064 1.3716)
			(layers "F.Cu" "F.Mask" "F.Paste")
			(net "SSD5_LED")
		)
		(pad "10" smd rect
			(at -2.925064 2.275078 270)
			(size 0.4064 1.3716)
			(layers "F.Cu" "F.Mask" "F.Paste")
			(net "SSD6_LED")
		)
		(pad "11" smd rect
			(at -2.925064 2.925064 270)
			(size 0.4064 1.3716)
			(layers "F.Cu" "F.Mask" "F.Paste")
			(net "SSD7_LED")
		)
		(pad "12" smd rect
			(at -2.925064 3.674872 270)
			(size 0.6096 1.3716)
			(layers "F.Cu" "F.Mask" "F.Paste")
			(net "GND")
		)
		(pad "13" smd rect
			(at 2.925064 3.674872 270)
			(size 0.6096 1.3716)
			(layers "F.Cu" "F.Mask" "F.Paste")
			(net "SSD8_LED")
		)
		(pad "14" smd rect
			(at 2.925064 2.925064 270)
			(size 0.4064 1.3716)
			(layers "F.Cu" "F.Mask" "F.Paste")
			(net "SSD9_LED")
		)
		(pad "15" smd rect
			(at 2.925064 2.275078 270)
			(size 0.4064 1.3716)
			(layers "F.Cu" "F.Mask" "F.Paste")
			(net "SSD10_LED")
		)
		(pad "16" smd rect
			(at 2.925064 1.625092 270)
			(size 0.4064 1.3716)
			(layers "F.Cu" "F.Mask" "F.Paste")
			(net "SSD11_LED")
		)
		(pad "17" smd rect
			(at 2.925064 0.975106 270)
			(size 0.4064 1.3716)
			(layers "F.Cu" "F.Mask" "F.Paste")
			(net "SSD12_LED")
		)
		(pad "18" smd rect
			(at 2.925064 0.32512 270)
			(size 0.4064 1.3716)
			(layers "F.Cu" "F.Mask" "F.Paste")
			(net "SSD13_LED")
		)
		(pad "19" smd rect
			(at 2.925064 -0.32512 270)
			(size 0.4064 1.3716)
			(layers "F.Cu" "F.Mask" "F.Paste")
			(net "SSD14_LED")
		)
		(pad "20" smd rect
			(at 2.925064 -0.975106 270)
			(size 0.4064 1.3716)
			(layers "F.Cu" "F.Mask" "F.Paste")
			(net "SSD15_LED")
		)
		(pad "21" smd rect
			(at 2.925064 -1.625092 270)
			(size 0.4064 1.3716)
			(layers "F.Cu" "F.Mask" "F.Paste")
			(net "SSD_LED_IOEXP_A0")
		)
		(pad "22" smd rect
			(at 2.925064 -2.275078 270)
			(size 0.4064 1.3716)
			(layers "F.Cu" "F.Mask" "F.Paste")
			(net "SMB_SSD_LED_IOEXP_SCL")
		)
		(pad "23" smd rect
			(at 2.925064 -2.925064 270)
			(size 0.4064 1.3716)
			(layers "F.Cu" "F.Mask" "F.Paste")
			(net "SMB_SSD_LED_IOEXP_SDA")
		)
		(pad "24" smd rect
			(at 2.925064 -3.674872 270)
			(size 0.6096 1.3716)
			(layers "F.Cu" "F.Mask" "F.Paste")
			(net "P3V3_AUX")
		)
	)
	(footprint ""
		(layer "F.Cu")
		(at 383.818384 -252.356874 -90)
		(property "Reference" "R1437"
			(at 0 0 270)
			(layer "F.SilkS")
			(hide yes)
			(effects
				(font
					(size 1.27 1.27)
				)
			)
		)
		(property "Value" ""
			(at 0 0 270)
			(layer "F.Fab")
			(effects
				(font
					(size 1.27 1.27)
				)
			)
		)
		(duplicate_pad_numbers_are_jumpers no)
		(fp_line
			(start -0.7874 0.4064)
			(end -0.7874 -0.4064)
			(stroke
				(width 0.1524)
				(type default)
			)
			(layer "F.SilkS")
		)
		(fp_line
			(start 0.7874 0.4064)
			(end -0.7874 0.4064)
			(stroke
				(width 0.1524)
				(type default)
			)
			(layer "F.SilkS")
		)
		(fp_line
			(start -0.7874 -0.4064)
			(end 0.7874 -0.4064)
			(stroke
				(width 0.1524)
				(type default)
			)
			(layer "F.SilkS")
		)
		(fp_line
			(start 0.7874 -0.4064)
			(end 0.7874 0.4064)
			(stroke
				(width 0.1524)
				(type default)
			)
			(layer "F.SilkS")
		)
		(fp_line
			(start -0.67945 0.3048)
			(end -0.67945 -0.305054)
			(stroke
				(width 0.1)
				(type default)
			)
			(layer "F.Fab")
		)
		(fp_line
			(start -0.12065 0.3048)
			(end -0.67945 0.3048)
			(stroke
				(width 0.1)
				(type default)
			)
			(layer "F.Fab")
		)
		(fp_line
			(start 0.120396 0.3048)
			(end 0.120396 0.2794)
			(stroke
				(width 0.1)
				(type default)
			)
			(layer "F.Fab")
		)
		(fp_line
			(start 0.67945 0.3048)
			(end 0.120396 0.3048)
			(stroke
				(width 0.1)
				(type default)
			)
			(layer "F.Fab")
		)
		(fp_line
			(start -0.12065 0.2794)
			(end -0.12065 0.3048)
			(stroke
				(width 0.1)
				(type default)
			)
			(layer "F.Fab")
		)
		(fp_line
			(start 0.120396 0.2794)
			(end -0.12065 0.2794)
			(stroke
				(width 0.1)
				(type default)
			)
			(layer "F.Fab")
		)
		(fp_line
			(start -0.12065 -0.2794)
			(end 0.12065 -0.2794)
			(stroke
				(width 0.1)
				(type default)
			)
			(layer "F.Fab")
		)
		(fp_line
			(start 0.12065 -0.2794)
			(end 0.12065 -0.3048)
			(stroke
				(width 0.1)
				(type default)
			)
			(layer "F.Fab")
		)
		(fp_line
			(start 0.12065 -0.3048)
			(end 0.67945 -0.3048)
			(stroke
				(width 0.1)
				(type default)
			)
			(layer "F.Fab")
		)
		(fp_line
			(start 0.67945 -0.3048)
			(end 0.67945 0.3048)
			(stroke
				(width 0.1)
				(type default)
			)
			(layer "F.Fab")
		)
		(fp_line
			(start -0.67945 -0.305054)
			(end -0.12065 -0.305054)
			(stroke
				(width 0.1)
				(type default)
			)
			(layer "F.Fab")
		)
		(fp_line
			(start -0.12065 -0.305054)
			(end -0.12065 -0.2794)
			(stroke
				(width 0.1)
				(type default)
			)
			(layer "F.Fab")
		)
		(pad "1" smd circle
			(at -0.40005 0 270)
			(size 0 0)
			(layers "F.Cu" "F.Mask" "F.Paste")
			(net "GND")
		)
		(pad "2" smd circle
			(at 0.40005 0 270)
			(size 0 0)
			(layers "F.Cu" "F.Mask" "F.Paste")
			(net "PEX3_MODE_SEL12")
		)
	)
	(footprint ""
		(layer "F.Cu")
		(at 400.543776 -47.92091)
		(property "Reference" "R647"
			(at 0 0 0)
			(layer "F.SilkS")
			(hide yes)
			(effects
				(font
					(size 1.27 1.27)
				)
			)
		)
		(property "Value" ""
			(at 0 0 0)
			(layer "F.Fab")
			(effects
				(font
					(size 1.27 1.27)
				)
			)
		)
		(duplicate_pad_numbers_are_jumpers no)
		(fp_line
			(start -0.7874 -0.4064)
			(end 0.7874 -0.4064)
			(stroke
				(width 0.1524)
				(type default)
			)
			(layer "F.SilkS")
		)
		(fp_line
			(start -0.7874 0.4064)
			(end -0.7874 -0.4064)
			(stroke
				(width 0.1524)
				(type default)
			)
			(layer "F.SilkS")
		)
		(fp_line
			(start 0.7874 -0.4064)
			(end 0.7874 0.4064)
			(stroke
				(width 0.1524)
				(type default)
			)
			(layer "F.SilkS")
		)
		(fp_line
			(start 0.7874 0.4064)
			(end -0.7874 0.4064)
			(stroke
				(width 0.1524)
				(type default)
			)
			(layer "F.SilkS")
		)
		(fp_line
			(start -0.67945 -0.305054)
			(end -0.12065 -0.305054)
			(stroke
				(width 0.1)
				(type default)
			)
			(layer "F.Fab")
		)
		(fp_line
			(start -0.67945 0.3048)
			(end -0.67945 -0.305054)
			(stroke
				(width 0.1)
				(type default)
			)
			(layer "F.Fab")
		)
		(fp_line
			(start -0.12065 -0.305054)
			(end -0.12065 -0.2794)
			(stroke
				(width 0.1)
				(type default)
			)
			(layer "F.Fab")
		)
		(fp_line
			(start -0.12065 -0.2794)
			(end 0.12065 -0.2794)
			(stroke
				(width 0.1)
				(type default)
			)
			(layer "F.Fab")
		)
		(fp_line
			(start -0.12065 0.2794)
			(end -0.12065 0.3048)
			(stroke
				(width 0.1)
				(type default)
			)
			(layer "F.Fab")
		)
		(fp_line
			(start -0.12065 0.3048)
			(end -0.67945 0.3048)
			(stroke
				(width 0.1)
				(type default)
			)
			(layer "F.Fab")
		)
		(fp_line
			(start 0.120396 0.2794)
			(end -0.12065 0.2794)
			(stroke
				(width 0.1)
				(type default)
			)
			(layer "F.Fab")
		)
		(fp_line
			(start 0.120396 0.3048)
			(end 0.120396 0.2794)
			(stroke
				(width 0.1)
				(type default)
			)
			(layer "F.Fab")
		)
		(fp_line
			(start 0.12065 -0.3048)
			(end 0.67945 -0.3048)
			(stroke
				(width 0.1)
				(type default)
			)
			(layer "F.Fab")
		)
		(fp_line
			(start 0.12065 -0.2794)
			(end 0.12065 -0.3048)
			(stroke
				(width 0.1)
				(type default)
			)
			(layer "F.Fab")
		)
		(fp_line
			(start 0.67945 -0.3048)
			(end 0.67945 0.3048)
			(stroke
				(width 0.1)
				(type default)
			)
			(layer "F.Fab")
		)
		(fp_line
			(start 0.67945 0.3048)
			(end 0.120396 0.3048)
			(stroke
				(width 0.1)
				(type default)
			)
			(layer "F.Fab")
		)
		(pad "1" smd circle
			(at -0.40005 0)
			(size 0 0)
			(layers "F.Cu" "F.Mask" "F.Paste")
			(net "P3V3_AUX")
		)
		(pad "2" smd circle
			(at 0.40005 0)
			(size 0 0)
			(layers "F.Cu" "F.Mask" "F.Paste")
			(net "SSD_8_15_ADC_ALERT_N")
		)
	)
	(footprint ""
		(layer "F.Cu")
		(at 135.325612 -159.082994 -90)
		(property "Reference" "PD81"
			(at 4.295394 -2.750058 90)
			(unlocked yes)
			(layer "F.SilkS")
			(effects
				(font
					(size 0.7874 0.5842)
					(thickness 0.1524)
				)
				(justify left)
			)
		)
		(property "Value" ""
			(at 0 0 270)
			(layer "F.Fab")
			(effects
				(font
					(size 1.27 1.27)
				)
			)
		)
		(duplicate_pad_numbers_are_jumpers no)
		(fp_line
			(start -3.656584 1.970024)
			(end 4.240784 1.970024)
			(stroke
				(width 0.1524)
				(type default)
			)
			(layer "F.SilkS")
		)
		(fp_line
			(start 4.240784 1.970024)
			(end 4.240784 -1.970024)
			(stroke
				(width 0.1524)
				(type default)
			)
			(layer "F.SilkS")
		)
		(fp_line
			(start -3.656584 -1.970024)
			(end -3.656584 1.970024)
			(stroke
				(width 0.1524)
				(type default)
			)
			(layer "F.SilkS")
		)
		(fp_line
			(start 4.240784 -1.970024)
			(end -3.656584 -1.970024)
			(stroke
				(width 0.1524)
				(type default)
			)
			(layer "F.SilkS")
		)
		(fp_poly
			(pts
				(xy 3.580384 1.970024) (xy 3.580384 -1.970024) (xy 4.240784 -1.970024) (xy 4.240784 1.970024)
			)
			(stroke
				(width 0)
				(type default)
			)
			(fill yes)
			(layer "F.SilkS")
		)
		(fp_line
			(start -2.3749 1.970024)
			(end 2.3749 1.970024)
			(stroke
				(width 0.1)
				(type default)
			)
			(layer "F.Fab")
		)
		(fp_line
			(start 2.3749 1.970024)
			(end 2.3749 -1.970024)
			(stroke
				(width 0.1)
				(type default)
			)
			(layer "F.Fab")
		)
		(fp_line
			(start -2.3749 -1.970024)
			(end -2.3749 1.970024)
			(stroke
				(width 0.1)
				(type default)
			)
			(layer "F.Fab")
		)
		(fp_line
			(start 2.3749 -1.970024)
			(end -2.3749 -1.970024)
			(stroke
				(width 0.1)
				(type default)
			)
			(layer "F.Fab")
		)
		(fp_text user "+"
			(at -4.9784 -0.23495 270)
			(unlocked yes)
			(layer "F.Fab")
			(effects
				(font
					(size 1.905 1.4224)
					(thickness 0.1524)
				)
				(justify left)
			)
		)
		(fp_text user "-"
			(at 4.1656 -0.23495 270)
			(unlocked yes)
			(layer "F.Fab")
			(effects
				(font
					(size 1.905 1.4224)
					(thickness 0.1524)
				)
				(justify left)
			)
		)
		(pad "A" smd rect
			(at -2.450084 0 270)
			(size 2.159 2.2606)
			(layers "F.Cu" "F.Mask" "F.Paste")
			(net "GND")
		)
		(pad "C" smd rect
			(at 2.450084 0 270)
			(size 2.159 2.2606)
			(layers "F.Cu" "F.Mask" "F.Paste")
			(net "P12V_AUX")
		)
	)
	(footprint ""
		(layer "F.Cu")
		(at 259.130038 -281.203908 -90)
		(property "Reference" "C3383"
			(at 0 0 270)
			(layer "F.SilkS")
			(hide yes)
			(effects
				(font
					(size 1.27 1.27)
				)
			)
		)
		(property "Value" ""
			(at 0 0 270)
			(layer "F.Fab")
			(effects
				(font
					(size 1.27 1.27)
				)
			)
		)
		(duplicate_pad_numbers_are_jumpers no)
		(fp_line
			(start -1.2954 0.5842)
			(end -1.2954 -0.5842)
			(stroke
				(width 0.1524)
				(type default)
			)
			(layer "F.SilkS")
		)
		(fp_line
			(start 1.2954 0.5842)
			(end -1.2954 0.5842)
			(stroke
				(width 0.1524)
				(type default)
			)
			(layer "F.SilkS")
		)
		(fp_line
			(start -1.2954 -0.5842)
			(end 1.2954 -0.5842)
			(stroke
				(width 0.1524)
				(type default)
			)
			(layer "F.SilkS")
		)
		(fp_line
			(start 1.2954 -0.5842)
			(end 1.2954 0.5842)
			(stroke
				(width 0.1524)
				(type default)
			)
			(layer "F.SilkS")
		)
		(fp_line
			(start -0.8636 0.4572)
			(end -0.8636 0.4064)
			(stroke
				(width 0.1)
				(type default)
			)
			(layer "F.Fab")
		)
		(fp_line
			(start 0.8636 0.4572)
			(end -0.8636 0.4572)
			(stroke
				(width 0.1)
				(type default)
			)
			(layer "F.Fab")
		)
		(fp_line
			(start -1.1938 0.4064)
			(end -1.1938 -0.4064)
			(stroke
				(width 0.1)
				(type default)
			)
			(layer "F.Fab")
		)
		(fp_line
			(start -0.8636 0.4064)
			(end -1.1938 0.4064)
			(stroke
				(width 0.1)
				(type default)
			)
			(layer "F.Fab")
		)
		(fp_line
			(start 0.8636 0.4064)
			(end 0.8636 0.4572)
			(stroke
				(width 0.1)
				(type default)
			)
			(layer "F.Fab")
		)
		(fp_line
			(start 1.1938 0.4064)
			(end 0.8636 0.4064)
			(stroke
				(width 0.1)
				(type default)
			)
			(layer "F.Fab")
		)
		(fp_line
			(start -1.1938 -0.4064)
			(end -0.8636 -0.4064)
			(stroke
				(width 0.1)
				(type default)
			)
			(layer "F.Fab")
		)
		(fp_line
			(start -0.8636 -0.4064)
			(end -0.8636 -0.4572)
			(stroke
				(width 0.1)
				(type default)
			)
			(layer "F.Fab")
		)
		(fp_line
			(start 0.8636 -0.4064)
			(end 1.1938 -0.4064)
			(stroke
				(width 0.1)
				(type default)
			)
			(layer "F.Fab")
		)
		(fp_line
			(start 1.1938 -0.4064)
			(end 1.1938 0.4064)
			(stroke
				(width 0.1)
				(type default)
			)
			(layer "F.Fab")
		)
		(fp_line
			(start -0.8636 -0.4572)
			(end 0.8636 -0.4572)
			(stroke
				(width 0.1)
				(type default)
			)
			(layer "F.Fab")
		)
		(fp_line
			(start 0.8636 -0.4572)
			(end 0.8636 -0.4064)
			(stroke
				(width 0.1)
				(type default)
			)
			(layer "F.Fab")
		)
		(pad "1" smd rect
			(at -0.7366 0 180)
			(size 0.7112 0.8128)
			(layers "F.Cu" "F.Mask" "F.Paste")
			(net "P1V8_PLL0_PEX2")
		)
		(pad "2" smd rect
			(at 0.7366 0 180)
			(size 0.7112 0.8128)
			(layers "F.Cu" "F.Mask" "F.Paste")
			(net "GND")
		)
	)
	(footprint ""
		(layer "F.Cu")
		(at 254.227838 -35.876738)
		(property "Reference" "R6083"
			(at 0 0 0)
			(layer "F.SilkS")
			(hide yes)
			(effects
				(font
					(size 1.27 1.27)
				)
			)
		)
		(property "Value" ""
			(at 0 0 0)
			(layer "F.Fab")
			(effects
				(font
					(size 1.27 1.27)
				)
			)
		)
		(duplicate_pad_numbers_are_jumpers no)
		(fp_line
			(start -0.7874 -0.4064)
			(end 0.7874 -0.4064)
			(stroke
				(width 0.1524)
				(type default)
			)
			(layer "F.SilkS")
		)
		(fp_line
			(start -0.7874 0.4064)
			(end -0.7874 -0.4064)
			(stroke
				(width 0.1524)
				(type default)
			)
			(layer "F.SilkS")
		)
		(fp_line
			(start 0.7874 -0.4064)
			(end 0.7874 0.4064)
			(stroke
				(width 0.1524)
				(type default)
			)
			(layer "F.SilkS")
		)
		(fp_line
			(start 0.7874 0.4064)
			(end -0.7874 0.4064)
			(stroke
				(width 0.1524)
				(type default)
			)
			(layer "F.SilkS")
		)
		(fp_line
			(start -0.67945 -0.305054)
			(end -0.12065 -0.305054)
			(stroke
				(width 0.1)
				(type default)
			)
			(layer "F.Fab")
		)
		(fp_line
			(start -0.67945 0.3048)
			(end -0.67945 -0.305054)
			(stroke
				(width 0.1)
				(type default)
			)
			(layer "F.Fab")
		)
		(fp_line
			(start -0.12065 -0.305054)
			(end -0.12065 -0.2794)
			(stroke
				(width 0.1)
				(type default)
			)
			(layer "F.Fab")
		)
		(fp_line
			(start -0.12065 -0.2794)
			(end 0.12065 -0.2794)
			(stroke
				(width 0.1)
				(type default)
			)
			(layer "F.Fab")
		)
		(fp_line
			(start -0.12065 0.2794)
			(end -0.12065 0.3048)
			(stroke
				(width 0.1)
				(type default)
			)
			(layer "F.Fab")
		)
		(fp_line
			(start -0.12065 0.3048)
			(end -0.67945 0.3048)
			(stroke
				(width 0.1)
				(type default)
			)
			(layer "F.Fab")
		)
		(fp_line
			(start 0.120396 0.2794)
			(end -0.12065 0.2794)
			(stroke
				(width 0.1)
				(type default)
			)
			(layer "F.Fab")
		)
		(fp_line
			(start 0.120396 0.3048)
			(end 0.120396 0.2794)
			(stroke
				(width 0.1)
				(type default)
			)
			(layer "F.Fab")
		)
		(fp_line
			(start 0.12065 -0.3048)
			(end 0.67945 -0.3048)
			(stroke
				(width 0.1)
				(type default)
			)
			(layer "F.Fab")
		)
		(fp_line
			(start 0.12065 -0.2794)
			(end 0.12065 -0.3048)
			(stroke
				(width 0.1)
				(type default)
			)
			(layer "F.Fab")
		)
		(fp_line
			(start 0.67945 -0.3048)
			(end 0.67945 0.3048)
			(stroke
				(width 0.1)
				(type default)
			)
			(layer "F.Fab")
		)
		(fp_line
			(start 0.67945 0.3048)
			(end 0.120396 0.3048)
			(stroke
				(width 0.1)
				(type default)
			)
			(layer "F.Fab")
		)
		(pad "1" smd circle
			(at -0.40005 0)
			(size 0 0)
			(layers "F.Cu" "F.Mask" "F.Paste")
			(net "PWRGD_P3V3_SSD9_D")
		)
		(pad "2" smd circle
			(at 0.40005 0)
			(size 0 0)
			(layers "F.Cu" "F.Mask" "F.Paste")
			(net "PWRGD_P3V3_SSD9_R")
		)
	)
	(footprint ""
		(layer "F.Cu")
		(at 60.210954 -61.386974)
		(property "Reference" "R4491"
			(at 0 0 0)
			(layer "F.SilkS")
			(hide yes)
			(effects
				(font
					(size 1.27 1.27)
				)
			)
		)
		(property "Value" ""
			(at 0 0 0)
			(layer "F.Fab")
			(effects
				(font
					(size 1.27 1.27)
				)
			)
		)
		(duplicate_pad_numbers_are_jumpers no)
		(fp_line
			(start -0.7874 -0.4064)
			(end 0.7874 -0.4064)
			(stroke
				(width 0.1524)
				(type default)
			)
			(layer "F.SilkS")
		)
		(fp_line
			(start -0.7874 0.4064)
			(end -0.7874 -0.4064)
			(stroke
				(width 0.1524)
				(type default)
			)
			(layer "F.SilkS")
		)
		(fp_line
			(start 0.7874 -0.4064)
			(end 0.7874 0.4064)
			(stroke
				(width 0.1524)
				(type default)
			)
			(layer "F.SilkS")
		)
		(fp_line
			(start 0.7874 0.4064)
			(end -0.7874 0.4064)
			(stroke
				(width 0.1524)
				(type default)
			)
			(layer "F.SilkS")
		)
		(fp_line
			(start -0.67945 -0.305054)
			(end -0.12065 -0.305054)
			(stroke
				(width 0.1)
				(type default)
			)
			(layer "F.Fab")
		)
		(fp_line
			(start -0.67945 0.3048)
			(end -0.67945 -0.305054)
			(stroke
				(width 0.1)
				(type default)
			)
			(layer "F.Fab")
		)
		(fp_line
			(start -0.12065 -0.305054)
			(end -0.12065 -0.2794)
			(stroke
				(width 0.1)
				(type default)
			)
			(layer "F.Fab")
		)
		(fp_line
			(start -0.12065 -0.2794)
			(end 0.12065 -0.2794)
			(stroke
				(width 0.1)
				(type default)
			)
			(layer "F.Fab")
		)
		(fp_line
			(start -0.12065 0.2794)
			(end -0.12065 0.3048)
			(stroke
				(width 0.1)
				(type default)
			)
			(layer "F.Fab")
		)
		(fp_line
			(start -0.12065 0.3048)
			(end -0.67945 0.3048)
			(stroke
				(width 0.1)
				(type default)
			)
			(layer "F.Fab")
		)
		(fp_line
			(start 0.120396 0.2794)
			(end -0.12065 0.2794)
			(stroke
				(width 0.1)
				(type default)
			)
			(layer "F.Fab")
		)
		(fp_line
			(start 0.120396 0.3048)
			(end 0.120396 0.2794)
			(stroke
				(width 0.1)
				(type default)
			)
			(layer "F.Fab")
		)
		(fp_line
			(start 0.12065 -0.3048)
			(end 0.67945 -0.3048)
			(stroke
				(width 0.1)
				(type default)
			)
			(layer "F.Fab")
		)
		(fp_line
			(start 0.12065 -0.2794)
			(end 0.12065 -0.3048)
			(stroke
				(width 0.1)
				(type default)
			)
			(layer "F.Fab")
		)
		(fp_line
			(start 0.67945 -0.3048)
			(end 0.67945 0.3048)
			(stroke
				(width 0.1)
				(type default)
			)
			(layer "F.Fab")
		)
		(fp_line
			(start 0.67945 0.3048)
			(end 0.120396 0.3048)
			(stroke
				(width 0.1)
				(type default)
			)
			(layer "F.Fab")
		)
		(pad "1" smd circle
			(at -0.40005 0)
			(size 0 0)
			(layers "F.Cu" "F.Mask" "F.Paste")
			(net "PWRGD_P3V3_SSD2")
		)
		(pad "2" smd circle
			(at 0.40005 0)
			(size 0 0)
			(layers "F.Cu" "F.Mask" "F.Paste")
			(net "PWRGD_P3V3_SSD2_R")
		)
	)
	(footprint ""
		(layer "F.Cu")
		(at 98.17481 -48.753014 180)
		(property "Reference" "C207"
			(at 0 0 180)
			(layer "F.SilkS")
			(hide yes)
			(effects
				(font
					(size 1.27 1.27)
				)
			)
		)
		(property "Value" ""
			(at 0 0 180)
			(layer "F.Fab")
			(effects
				(font
					(size 1.27 1.27)
				)
			)
		)
		(duplicate_pad_numbers_are_jumpers no)
		(fp_line
			(start 0.7874 0.4064)
			(end -0.7874 0.4064)
			(stroke
				(width 0.1524)
				(type default)
			)
			(layer "F.SilkS")
		)
		(fp_line
			(start 0.7874 -0.4064)
			(end 0.7874 0.4064)
			(stroke
				(width 0.1524)
				(type default)
			)
			(layer "F.SilkS")
		)
		(fp_line
			(start -0.7874 0.4064)
			(end -0.7874 -0.4064)
			(stroke
				(width 0.1524)
				(type default)
			)
			(layer "F.SilkS")
		)
		(fp_line
			(start -0.7874 -0.4064)
			(end 0.7874 -0.4064)
			(stroke
				(width 0.1524)
				(type default)
			)
			(layer "F.SilkS")
		)
		(fp_line
			(start 0.67945 0.3048)
			(end 0.120396 0.3048)
			(stroke
				(width 0.1)
				(type default)
			)
			(layer "F.Fab")
		)
		(fp_line
			(start 0.67945 -0.3048)
			(end 0.67945 0.3048)
			(stroke
				(width 0.1)
				(type default)
			)
			(layer "F.Fab")
		)
		(fp_line
			(start 0.12065 -0.2794)
			(end 0.12065 -0.3048)
			(stroke
				(width 0.1)
				(type default)
			)
			(layer "F.Fab")
		)
		(fp_line
			(start 0.12065 -0.3048)
			(end 0.67945 -0.3048)
			(stroke
				(width 0.1)
				(type default)
			)
			(layer "F.Fab")
		)
		(fp_line
			(start 0.120396 0.3048)
			(end 0.120396 0.2794)
			(stroke
				(width 0.1)
				(type default)
			)
			(layer "F.Fab")
		)
		(fp_line
			(start 0.120396 0.2794)
			(end -0.12065 0.2794)
			(stroke
				(width 0.1)
				(type default)
			)
			(layer "F.Fab")
		)
		(fp_line
			(start -0.12065 0.3048)
			(end -0.67945 0.3048)
			(stroke
				(width 0.1)
				(type default)
			)
			(layer "F.Fab")
		)
		(fp_line
			(start -0.12065 0.2794)
			(end -0.12065 0.3048)
			(stroke
				(width 0.1)
				(type default)
			)
			(layer "F.Fab")
		)
		(fp_line
			(start -0.12065 -0.2794)
			(end 0.12065 -0.2794)
			(stroke
				(width 0.1)
				(type default)
			)
			(layer "F.Fab")
		)
		(fp_line
			(start -0.12065 -0.305054)
			(end -0.12065 -0.2794)
			(stroke
				(width 0.1)
				(type default)
			)
			(layer "F.Fab")
		)
		(fp_line
			(start -0.67945 0.3048)
			(end -0.67945 -0.305054)
			(stroke
				(width 0.1)
				(type default)
			)
			(layer "F.Fab")
		)
		(fp_line
			(start -0.67945 -0.305054)
			(end -0.12065 -0.305054)
			(stroke
				(width 0.1)
				(type default)
			)
			(layer "F.Fab")
		)
		(pad "1" smd circle
			(at -0.40005 0 180)
			(size 0 0)
			(layers "F.Cu" "F.Mask" "F.Paste")
			(net "P3V3_AUX")
		)
		(pad "2" smd circle
			(at 0.40005 0 180)
			(size 0 0)
			(layers "F.Cu" "F.Mask" "F.Paste")
			(net "GND")
		)
	)
	(footprint ""
		(layer "F.Cu")
		(at 374.543828 -45.88891)
		(property "Reference" "R641"
			(at 0 0 0)
			(layer "F.SilkS")
			(hide yes)
			(effects
				(font
					(size 1.27 1.27)
				)
			)
		)
		(property "Value" ""
			(at 0 0 0)
			(layer "F.Fab")
			(effects
				(font
					(size 1.27 1.27)
				)
			)
		)
		(duplicate_pad_numbers_are_jumpers no)
		(fp_line
			(start -0.7874 -0.4064)
			(end 0.7874 -0.4064)
			(stroke
				(width 0.1524)
				(type default)
			)
			(layer "F.SilkS")
		)
		(fp_line
			(start -0.7874 0.4064)
			(end -0.7874 -0.4064)
			(stroke
				(width 0.1524)
				(type default)
			)
			(layer "F.SilkS")
		)
		(fp_line
			(start 0.7874 -0.4064)
			(end 0.7874 0.4064)
			(stroke
				(width 0.1524)
				(type default)
			)
			(layer "F.SilkS")
		)
		(fp_line
			(start 0.7874 0.4064)
			(end -0.7874 0.4064)
			(stroke
				(width 0.1524)
				(type default)
			)
			(layer "F.SilkS")
		)
		(fp_line
			(start -0.67945 -0.305054)
			(end -0.12065 -0.305054)
			(stroke
				(width 0.1)
				(type default)
			)
			(layer "F.Fab")
		)
		(fp_line
			(start -0.67945 0.3048)
			(end -0.67945 -0.305054)
			(stroke
				(width 0.1)
				(type default)
			)
			(layer "F.Fab")
		)
		(fp_line
			(start -0.12065 -0.305054)
			(end -0.12065 -0.2794)
			(stroke
				(width 0.1)
				(type default)
			)
			(layer "F.Fab")
		)
		(fp_line
			(start -0.12065 -0.2794)
			(end 0.12065 -0.2794)
			(stroke
				(width 0.1)
				(type default)
			)
			(layer "F.Fab")
		)
		(fp_line
			(start -0.12065 0.2794)
			(end -0.12065 0.3048)
			(stroke
				(width 0.1)
				(type default)
			)
			(layer "F.Fab")
		)
		(fp_line
			(start -0.12065 0.3048)
			(end -0.67945 0.3048)
			(stroke
				(width 0.1)
				(type default)
			)
			(layer "F.Fab")
		)
		(fp_line
			(start 0.120396 0.2794)
			(end -0.12065 0.2794)
			(stroke
				(width 0.1)
				(type default)
			)
			(layer "F.Fab")
		)
		(fp_line
			(start 0.120396 0.3048)
			(end 0.120396 0.2794)
			(stroke
				(width 0.1)
				(type default)
			)
			(layer "F.Fab")
		)
		(fp_line
			(start 0.12065 -0.3048)
			(end 0.67945 -0.3048)
			(stroke
				(width 0.1)
				(type default)
			)
			(layer "F.Fab")
		)
		(fp_line
			(start 0.12065 -0.2794)
			(end 0.12065 -0.3048)
			(stroke
				(width 0.1)
				(type default)
			)
			(layer "F.Fab")
		)
		(fp_line
			(start 0.67945 -0.3048)
			(end 0.67945 0.3048)
			(stroke
				(width 0.1)
				(type default)
			)
			(layer "F.Fab")
		)
		(fp_line
			(start 0.67945 0.3048)
			(end 0.120396 0.3048)
			(stroke
				(width 0.1)
				(type default)
			)
			(layer "F.Fab")
		)
		(pad "1" smd circle
			(at -0.40005 0)
			(size 0 0)
			(layers "F.Cu" "F.Mask" "F.Paste")
			(net "SSD12_ADC_A0")
		)
		(pad "2" smd circle
			(at 0.40005 0)
			(size 0 0)
			(layers "F.Cu" "F.Mask" "F.Paste")
			(net "GND")
		)
	)
	(footprint ""
		(layer "F.Cu")
		(at 198.564246 -363.583728 180)
		(property "Reference" "PR33"
			(at 0 0 180)
			(layer "F.SilkS")
			(hide yes)
			(effects
				(font
					(size 1.27 1.27)
				)
			)
		)
		(property "Value" ""
			(at 0 0 180)
			(layer "F.Fab")
			(effects
				(font
					(size 1.27 1.27)
				)
			)
		)
		(duplicate_pad_numbers_are_jumpers no)
		(fp_line
			(start 0.7874 0.4064)
			(end -0.7874 0.4064)
			(stroke
				(width 0.1524)
				(type default)
			)
			(layer "F.SilkS")
		)
		(fp_line
			(start 0.7874 -0.4064)
			(end 0.7874 0.4064)
			(stroke
				(width 0.1524)
				(type default)
			)
			(layer "F.SilkS")
		)
		(fp_line
			(start -0.7874 0.4064)
			(end -0.7874 -0.4064)
			(stroke
				(width 0.1524)
				(type default)
			)
			(layer "F.SilkS")
		)
		(fp_line
			(start -0.7874 -0.4064)
			(end 0.7874 -0.4064)
			(stroke
				(width 0.1524)
				(type default)
			)
			(layer "F.SilkS")
		)
		(fp_line
			(start 0.67945 0.3048)
			(end 0.120396 0.3048)
			(stroke
				(width 0.1)
				(type default)
			)
			(layer "F.Fab")
		)
		(fp_line
			(start 0.67945 -0.3048)
			(end 0.67945 0.3048)
			(stroke
				(width 0.1)
				(type default)
			)
			(layer "F.Fab")
		)
		(fp_line
			(start 0.12065 -0.2794)
			(end 0.12065 -0.3048)
			(stroke
				(width 0.1)
				(type default)
			)
			(layer "F.Fab")
		)
		(fp_line
			(start 0.12065 -0.3048)
			(end 0.67945 -0.3048)
			(stroke
				(width 0.1)
				(type default)
			)
			(layer "F.Fab")
		)
		(fp_line
			(start 0.120396 0.3048)
			(end 0.120396 0.2794)
			(stroke
				(width 0.1)
				(type default)
			)
			(layer "F.Fab")
		)
		(fp_line
			(start 0.120396 0.2794)
			(end -0.12065 0.2794)
			(stroke
				(width 0.1)
				(type default)
			)
			(layer "F.Fab")
		)
		(fp_line
			(start -0.12065 0.3048)
			(end -0.67945 0.3048)
			(stroke
				(width 0.1)
				(type default)
			)
			(layer "F.Fab")
		)
		(fp_line
			(start -0.12065 0.2794)
			(end -0.12065 0.3048)
			(stroke
				(width 0.1)
				(type default)
			)
			(layer "F.Fab")
		)
		(fp_line
			(start -0.12065 -0.2794)
			(end 0.12065 -0.2794)
			(stroke
				(width 0.1)
				(type default)
			)
			(layer "F.Fab")
		)
		(fp_line
			(start -0.12065 -0.305054)
			(end -0.12065 -0.2794)
			(stroke
				(width 0.1)
				(type default)
			)
			(layer "F.Fab")
		)
		(fp_line
			(start -0.67945 0.3048)
			(end -0.67945 -0.305054)
			(stroke
				(width 0.1)
				(type default)
			)
			(layer "F.Fab")
		)
		(fp_line
			(start -0.67945 -0.305054)
			(end -0.12065 -0.305054)
			(stroke
				(width 0.1)
				(type default)
			)
			(layer "F.Fab")
		)
		(pad "1" smd circle
			(at -0.40005 0 180)
			(size 0 0)
			(layers "F.Cu" "F.Mask" "F.Paste")
			(net "HSC_IMON")
		)
		(pad "2" smd circle
			(at 0.40005 0 180)
			(size 0 0)
			(layers "F.Cu" "F.Mask" "F.Paste")
			(net "AGND_HSC")
		)
	)
	(footprint ""
		(layer "F.Cu")
		(at 14.907768 -154.510994)
		(property "Reference" "PC603"
			(at 0 0 0)
			(layer "F.SilkS")
			(hide yes)
			(effects
				(font
					(size 1.27 1.27)
				)
			)
		)
		(property "Value" ""
			(at 0 0 0)
			(layer "F.Fab")
			(effects
				(font
					(size 1.27 1.27)
				)
			)
		)
		(duplicate_pad_numbers_are_jumpers no)
		(fp_line
			(start -0.7874 -0.4064)
			(end 0.7874 -0.4064)
			(stroke
				(width 0.1524)
				(type default)
			)
			(layer "F.SilkS")
		)
		(fp_line
			(start -0.7874 0.4064)
			(end -0.7874 -0.4064)
			(stroke
				(width 0.1524)
				(type default)
			)
			(layer "F.SilkS")
		)
		(fp_line
			(start 0.7874 -0.4064)
			(end 0.7874 0.4064)
			(stroke
				(width 0.1524)
				(type default)
			)
			(layer "F.SilkS")
		)
		(fp_line
			(start 0.7874 0.4064)
			(end -0.7874 0.4064)
			(stroke
				(width 0.1524)
				(type default)
			)
			(layer "F.SilkS")
		)
		(fp_line
			(start -0.67945 -0.305054)
			(end -0.12065 -0.305054)
			(stroke
				(width 0.1)
				(type default)
			)
			(layer "F.Fab")
		)
		(fp_line
			(start -0.67945 0.3048)
			(end -0.67945 -0.305054)
			(stroke
				(width 0.1)
				(type default)
			)
			(layer "F.Fab")
		)
		(fp_line
			(start -0.12065 -0.305054)
			(end -0.12065 -0.2794)
			(stroke
				(width 0.1)
				(type default)
			)
			(layer "F.Fab")
		)
		(fp_line
			(start -0.12065 -0.2794)
			(end 0.12065 -0.2794)
			(stroke
				(width 0.1)
				(type default)
			)
			(layer "F.Fab")
		)
		(fp_line
			(start -0.12065 0.2794)
			(end -0.12065 0.3048)
			(stroke
				(width 0.1)
				(type default)
			)
			(layer "F.Fab")
		)
		(fp_line
			(start -0.12065 0.3048)
			(end -0.67945 0.3048)
			(stroke
				(width 0.1)
				(type default)
			)
			(layer "F.Fab")
		)
		(fp_line
			(start 0.120396 0.2794)
			(end -0.12065 0.2794)
			(stroke
				(width 0.1)
				(type default)
			)
			(layer "F.Fab")
		)
		(fp_line
			(start 0.120396 0.3048)
			(end 0.120396 0.2794)
			(stroke
				(width 0.1)
				(type default)
			)
			(layer "F.Fab")
		)
		(fp_line
			(start 0.12065 -0.3048)
			(end 0.67945 -0.3048)
			(stroke
				(width 0.1)
				(type default)
			)
			(layer "F.Fab")
		)
		(fp_line
			(start 0.12065 -0.2794)
			(end 0.12065 -0.3048)
			(stroke
				(width 0.1)
				(type default)
			)
			(layer "F.Fab")
		)
		(fp_line
			(start 0.67945 -0.3048)
			(end 0.67945 0.3048)
			(stroke
				(width 0.1)
				(type default)
			)
			(layer "F.Fab")
		)
		(fp_line
			(start 0.67945 0.3048)
			(end 0.120396 0.3048)
			(stroke
				(width 0.1)
				(type default)
			)
			(layer "F.Fab")
		)
		(pad "1" smd circle
			(at -0.40005 0)
			(size 0 0)
			(layers "F.Cu" "F.Mask" "F.Paste")
			(net "P12V_NIC0_R")
		)
		(pad "2" smd circle
			(at 0.40005 0)
			(size 0 0)
			(layers "F.Cu" "F.Mask" "F.Paste")
			(net "GND")
		)
	)
	(footprint ""
		(layer "F.Cu")
		(at 210.130136 -181.613556 -90)
		(property "Reference" "R5300"
			(at 0 0 270)
			(layer "F.SilkS")
			(hide yes)
			(effects
				(font
					(size 1.27 1.27)
				)
			)
		)
		(property "Value" ""
			(at 0 0 270)
			(layer "F.Fab")
			(effects
				(font
					(size 1.27 1.27)
				)
			)
		)
		(duplicate_pad_numbers_are_jumpers no)
		(fp_line
			(start -0.7874 0.4064)
			(end -0.7874 -0.4064)
			(stroke
				(width 0.1524)
				(type default)
			)
			(layer "F.SilkS")
		)
		(fp_line
			(start 0.7874 0.4064)
			(end -0.7874 0.4064)
			(stroke
				(width 0.1524)
				(type default)
			)
			(layer "F.SilkS")
		)
		(fp_line
			(start -0.7874 -0.4064)
			(end 0.7874 -0.4064)
			(stroke
				(width 0.1524)
				(type default)
			)
			(layer "F.SilkS")
		)
		(fp_line
			(start 0.7874 -0.4064)
			(end 0.7874 0.4064)
			(stroke
				(width 0.1524)
				(type default)
			)
			(layer "F.SilkS")
		)
		(fp_line
			(start -0.67945 0.3048)
			(end -0.67945 -0.305054)
			(stroke
				(width 0.1)
				(type default)
			)
			(layer "F.Fab")
		)
		(fp_line
			(start -0.12065 0.3048)
			(end -0.67945 0.3048)
			(stroke
				(width 0.1)
				(type default)
			)
			(layer "F.Fab")
		)
		(fp_line
			(start 0.120396 0.3048)
			(end 0.120396 0.2794)
			(stroke
				(width 0.1)
				(type default)
			)
			(layer "F.Fab")
		)
		(fp_line
			(start 0.67945 0.3048)
			(end 0.120396 0.3048)
			(stroke
				(width 0.1)
				(type default)
			)
			(layer "F.Fab")
		)
		(fp_line
			(start -0.12065 0.2794)
			(end -0.12065 0.3048)
			(stroke
				(width 0.1)
				(type default)
			)
			(layer "F.Fab")
		)
		(fp_line
			(start 0.120396 0.2794)
			(end -0.12065 0.2794)
			(stroke
				(width 0.1)
				(type default)
			)
			(layer "F.Fab")
		)
		(fp_line
			(start -0.12065 -0.2794)
			(end 0.12065 -0.2794)
			(stroke
				(width 0.1)
				(type default)
			)
			(layer "F.Fab")
		)
		(fp_line
			(start 0.12065 -0.2794)
			(end 0.12065 -0.3048)
			(stroke
				(width 0.1)
				(type default)
			)
			(layer "F.Fab")
		)
		(fp_line
			(start 0.12065 -0.3048)
			(end 0.67945 -0.3048)
			(stroke
				(width 0.1)
				(type default)
			)
			(layer "F.Fab")
		)
		(fp_line
			(start 0.67945 -0.3048)
			(end 0.67945 0.3048)
			(stroke
				(width 0.1)
				(type default)
			)
			(layer "F.Fab")
		)
		(fp_line
			(start -0.67945 -0.305054)
			(end -0.12065 -0.305054)
			(stroke
				(width 0.1)
				(type default)
			)
			(layer "F.Fab")
		)
		(fp_line
			(start -0.12065 -0.305054)
			(end -0.12065 -0.2794)
			(stroke
				(width 0.1)
				(type default)
			)
			(layer "F.Fab")
		)
		(pad "1" smd circle
			(at -0.40005 0 270)
			(size 0 0)
			(layers "F.Cu" "F.Mask" "F.Paste")
			(net "SEL_FLASH_PEX3_BUF")
		)
		(pad "2" smd circle
			(at 0.40005 0 270)
			(size 0 0)
			(layers "F.Cu" "F.Mask" "F.Paste")
			(net "SEL_FLASH_PEX3_BUF_R")
		)
	)
	(footprint ""
		(layer "F.Cu")
		(at 374.567958 -56.353456)
		(property "Reference" "C2870"
			(at 0 0 0)
			(layer "F.SilkS")
			(hide yes)
			(effects
				(font
					(size 1.27 1.27)
				)
			)
		)
		(property "Value" ""
			(at 0 0 0)
			(layer "F.Fab")
			(effects
				(font
					(size 1.27 1.27)
				)
			)
		)
		(duplicate_pad_numbers_are_jumpers no)
		(fp_line
			(start -0.7874 -0.4064)
			(end 0.7874 -0.4064)
			(stroke
				(width 0.1524)
				(type default)
			)
			(layer "F.SilkS")
		)
		(fp_line
			(start -0.7874 0.4064)
			(end -0.7874 -0.4064)
			(stroke
				(width 0.1524)
				(type default)
			)
			(layer "F.SilkS")
		)
		(fp_line
			(start 0.7874 -0.4064)
			(end 0.7874 0.4064)
			(stroke
				(width 0.1524)
				(type default)
			)
			(layer "F.SilkS")
		)
		(fp_line
			(start 0.7874 0.4064)
			(end -0.7874 0.4064)
			(stroke
				(width 0.1524)
				(type default)
			)
			(layer "F.SilkS")
		)
		(fp_line
			(start -0.67945 -0.305054)
			(end -0.12065 -0.305054)
			(stroke
				(width 0.1)
				(type default)
			)
			(layer "F.Fab")
		)
		(fp_line
			(start -0.67945 0.3048)
			(end -0.67945 -0.305054)
			(stroke
				(width 0.1)
				(type default)
			)
			(layer "F.Fab")
		)
		(fp_line
			(start -0.12065 -0.305054)
			(end -0.12065 -0.2794)
			(stroke
				(width 0.1)
				(type default)
			)
			(layer "F.Fab")
		)
		(fp_line
			(start -0.12065 -0.2794)
			(end 0.12065 -0.2794)
			(stroke
				(width 0.1)
				(type default)
			)
			(layer "F.Fab")
		)
		(fp_line
			(start -0.12065 0.2794)
			(end -0.12065 0.3048)
			(stroke
				(width 0.1)
				(type default)
			)
			(layer "F.Fab")
		)
		(fp_line
			(start -0.12065 0.3048)
			(end -0.67945 0.3048)
			(stroke
				(width 0.1)
				(type default)
			)
			(layer "F.Fab")
		)
		(fp_line
			(start 0.120396 0.2794)
			(end -0.12065 0.2794)
			(stroke
				(width 0.1)
				(type default)
			)
			(layer "F.Fab")
		)
		(fp_line
			(start 0.120396 0.3048)
			(end 0.120396 0.2794)
			(stroke
				(width 0.1)
				(type default)
			)
			(layer "F.Fab")
		)
		(fp_line
			(start 0.12065 -0.3048)
			(end 0.67945 -0.3048)
			(stroke
				(width 0.1)
				(type default)
			)
			(layer "F.Fab")
		)
		(fp_line
			(start 0.12065 -0.2794)
			(end 0.12065 -0.3048)
			(stroke
				(width 0.1)
				(type default)
			)
			(layer "F.Fab")
		)
		(fp_line
			(start 0.67945 -0.3048)
			(end 0.67945 0.3048)
			(stroke
				(width 0.1)
				(type default)
			)
			(layer "F.Fab")
		)
		(fp_line
			(start 0.67945 0.3048)
			(end 0.120396 0.3048)
			(stroke
				(width 0.1)
				(type default)
			)
			(layer "F.Fab")
		)
		(pad "1" smd circle
			(at -0.40005 0)
			(size 0 0)
			(layers "F.Cu" "F.Mask" "F.Paste")
			(net "SSD12_PWR_EN_R")
		)
		(pad "2" smd circle
			(at 0.40005 0)
			(size 0 0)
			(layers "F.Cu" "F.Mask" "F.Paste")
			(net "GND")
		)
	)
	(footprint ""
		(layer "F.Cu")
		(at 70.620128 -15.649956 180)
		(property "Reference" "H116"
			(at -3.849624 -2.709418 0)
			(unlocked yes)
			(layer "B.SilkS")
			(effects
				(font
					(size 0.7874 0.5842)
					(thickness 0.1524)
				)
				(justify left mirror)
			)
		)
		(property "Value" ""
			(at 0 0 180)
			(layer "F.Fab")
			(effects
				(font
					(size 1.27 1.27)
				)
			)
		)
		(duplicate_pad_numbers_are_jumpers no)
		(pad "1" thru_hole rect
			(at 0 0 180)
			(size 4.2164 5.0038)
			(drill 2.0066
				(offset 0.099822 0)
			)
			(layers "*.Cu" "*.Mask")
			(remove_unused_layers no)
			(net "Net_8547")
			(clearance -0.8509)
			(padstack
				(mode front_inner_back)
				(layer "Inner"
					(shape circle)
					(size 4.0132 4.0132)
					(clearance -0.7493)
				)
				(layer "B.Cu"
					(shape circle)
					(size 4.0132 4.0132)
					(clearance -0.7493)
				)
			)
		)
	)
	(footprint ""
		(layer "F.Cu")
		(at 168.378632 -343.952322 90)
		(property "Reference" "C396"
			(at 0 0 90)
			(layer "F.SilkS")
			(hide yes)
			(effects
				(font
					(size 1.27 1.27)
				)
			)
		)
		(property "Value" ""
			(at 0 0 90)
			(layer "F.Fab")
			(effects
				(font
					(size 1.27 1.27)
				)
			)
		)
		(duplicate_pad_numbers_are_jumpers no)
		(fp_line
			(start 0.299974 -0.150114)
			(end 0.299974 0.150114)
			(stroke
				(width 0.1)
				(type default)
			)
			(layer "F.Fab")
		)
		(fp_line
			(start -0.299974 -0.150114)
			(end 0.299974 -0.150114)
			(stroke
				(width 0.1)
				(type default)
			)
			(layer "F.Fab")
		)
		(fp_line
			(start 0.299974 0.150114)
			(end -0.299974 0.150114)
			(stroke
				(width 0.1)
				(type default)
			)
			(layer "F.Fab")
		)
		(fp_line
			(start -0.299974 0.150114)
			(end -0.299974 -0.150114)
			(stroke
				(width 0.1)
				(type default)
			)
			(layer "F.Fab")
		)
		(pad "1" smd rect
			(at -0.2667 0 90)
			(size 0.3048 0.381)
			(layers "F.Cu" "F.Mask" "F.Paste")
			(net "P5E_PEX1_STN7_TX_DP<115>")
		)
		(pad "2" smd rect
			(at 0.2667 0 90)
			(size 0.3048 0.381)
			(layers "F.Cu" "F.Mask" "F.Paste")
			(net "P5E_PEX1_STN7_TX_C_DP<115>")
		)
	)
	(footprint ""
		(layer "F.Cu")
		(at 237.494064 -35.264852)
		(property "Reference" "R5687"
			(at 0 0 0)
			(layer "F.SilkS")
			(hide yes)
			(effects
				(font
					(size 1.27 1.27)
				)
			)
		)
		(property "Value" ""
			(at 0 0 0)
			(layer "F.Fab")
			(effects
				(font
					(size 1.27 1.27)
				)
			)
		)
		(duplicate_pad_numbers_are_jumpers no)
		(fp_line
			(start -0.7874 -0.4064)
			(end 0.7874 -0.4064)
			(stroke
				(width 0.1524)
				(type default)
			)
			(layer "F.SilkS")
		)
		(fp_line
			(start -0.7874 0.4064)
			(end -0.7874 -0.4064)
			(stroke
				(width 0.1524)
				(type default)
			)
			(layer "F.SilkS")
		)
		(fp_line
			(start 0.7874 -0.4064)
			(end 0.7874 0.4064)
			(stroke
				(width 0.1524)
				(type default)
			)
			(layer "F.SilkS")
		)
		(fp_line
			(start 0.7874 0.4064)
			(end -0.7874 0.4064)
			(stroke
				(width 0.1524)
				(type default)
			)
			(layer "F.SilkS")
		)
		(fp_line
			(start -0.67945 -0.305054)
			(end -0.12065 -0.305054)
			(stroke
				(width 0.1)
				(type default)
			)
			(layer "F.Fab")
		)
		(fp_line
			(start -0.67945 0.3048)
			(end -0.67945 -0.305054)
			(stroke
				(width 0.1)
				(type default)
			)
			(layer "F.Fab")
		)
		(fp_line
			(start -0.12065 -0.305054)
			(end -0.12065 -0.2794)
			(stroke
				(width 0.1)
				(type default)
			)
			(layer "F.Fab")
		)
		(fp_line
			(start -0.12065 -0.2794)
			(end 0.12065 -0.2794)
			(stroke
				(width 0.1)
				(type default)
			)
			(layer "F.Fab")
		)
		(fp_line
			(start -0.12065 0.2794)
			(end -0.12065 0.3048)
			(stroke
				(width 0.1)
				(type default)
			)
			(layer "F.Fab")
		)
		(fp_line
			(start -0.12065 0.3048)
			(end -0.67945 0.3048)
			(stroke
				(width 0.1)
				(type default)
			)
			(layer "F.Fab")
		)
		(fp_line
			(start 0.120396 0.2794)
			(end -0.12065 0.2794)
			(stroke
				(width 0.1)
				(type default)
			)
			(layer "F.Fab")
		)
		(fp_line
			(start 0.120396 0.3048)
			(end 0.120396 0.2794)
			(stroke
				(width 0.1)
				(type default)
			)
			(layer "F.Fab")
		)
		(fp_line
			(start 0.12065 -0.3048)
			(end 0.67945 -0.3048)
			(stroke
				(width 0.1)
				(type default)
			)
			(layer "F.Fab")
		)
		(fp_line
			(start 0.12065 -0.2794)
			(end 0.12065 -0.3048)
			(stroke
				(width 0.1)
				(type default)
			)
			(layer "F.Fab")
		)
		(fp_line
			(start 0.67945 -0.3048)
			(end 0.67945 0.3048)
			(stroke
				(width 0.1)
				(type default)
			)
			(layer "F.Fab")
		)
		(fp_line
			(start 0.67945 0.3048)
			(end 0.120396 0.3048)
			(stroke
				(width 0.1)
				(type default)
			)
			(layer "F.Fab")
		)
		(pad "1" smd circle
			(at -0.40005 0)
			(size 0 0)
			(layers "F.Cu" "F.Mask" "F.Paste")
			(net "RST_SMB_SSD8_ISO_N")
		)
		(pad "2" smd circle
			(at 0.40005 0)
			(size 0 0)
			(layers "F.Cu" "F.Mask" "F.Paste")
			(net "GND")
		)
	)
	(footprint ""
		(layer "F.Cu")
		(at 90.241882 -356.244906 90)
		(property "Reference" "C100"
			(at 0 0 90)
			(layer "F.SilkS")
			(hide yes)
			(effects
				(font
					(size 1.27 1.27)
				)
			)
		)
		(property "Value" ""
			(at 0 0 90)
			(layer "F.Fab")
			(effects
				(font
					(size 1.27 1.27)
				)
			)
		)
		(duplicate_pad_numbers_are_jumpers no)
		(fp_line
			(start 0.299974 -0.150114)
			(end 0.299974 0.150114)
			(stroke
				(width 0.1)
				(type default)
			)
			(layer "F.Fab")
		)
		(fp_line
			(start -0.299974 -0.150114)
			(end 0.299974 -0.150114)
			(stroke
				(width 0.1)
				(type default)
			)
			(layer "F.Fab")
		)
		(fp_line
			(start 0.299974 0.150114)
			(end -0.299974 0.150114)
			(stroke
				(width 0.1)
				(type default)
			)
			(layer "F.Fab")
		)
		(fp_line
			(start -0.299974 0.150114)
			(end -0.299974 -0.150114)
			(stroke
				(width 0.1)
				(type default)
			)
			(layer "F.Fab")
		)
		(pad "1" smd rect
			(at -0.2667 0 90)
			(size 0.3048 0.381)
			(layers "F.Cu" "F.Mask" "F.Paste")
			(net "P5E_PEX0_STN5_TX_DN<94>")
		)
		(pad "2" smd rect
			(at 0.2667 0 90)
			(size 0.3048 0.381)
			(layers "F.Cu" "F.Mask" "F.Paste")
			(net "P5E_PEX0_STN5_TX_C_DN<94>")
		)
	)
	(footprint ""
		(layer "F.Cu")
		(at 173.494192 -29.507688 -90)
		(property "Reference" "PC931"
			(at 0 0 270)
			(layer "F.SilkS")
			(hide yes)
			(effects
				(font
					(size 1.27 1.27)
				)
			)
		)
		(property "Value" ""
			(at 0 0 270)
			(layer "F.Fab")
			(effects
				(font
					(size 1.27 1.27)
				)
			)
		)
		(duplicate_pad_numbers_are_jumpers no)
		(fp_line
			(start -1.524 0.762)
			(end -1.524 -0.762)
			(stroke
				(width 0.1524)
				(type default)
			)
			(layer "F.SilkS")
		)
		(fp_line
			(start 1.524 0.762)
			(end -1.524 0.762)
			(stroke
				(width 0.1524)
				(type default)
			)
			(layer "F.SilkS")
		)
		(fp_line
			(start -1.524 -0.762)
			(end 1.524 -0.762)
			(stroke
				(width 0.1524)
				(type default)
			)
			(layer "F.SilkS")
		)
		(fp_line
			(start 1.524 -0.762)
			(end 1.524 0.762)
			(stroke
				(width 0.1524)
				(type default)
			)
			(layer "F.SilkS")
		)
		(fp_line
			(start -1.1049 0.724916)
			(end 1.1049 0.724916)
			(stroke
				(width 0.1)
				(type default)
			)
			(layer "F.Fab")
		)
		(fp_line
			(start 1.1049 0.724916)
			(end 1.1049 -0.724916)
			(stroke
				(width 0.1)
				(type default)
			)
			(layer "F.Fab")
		)
		(fp_line
			(start -1.1049 -0.724916)
			(end -1.1049 0.724916)
			(stroke
				(width 0.1)
				(type default)
			)
			(layer "F.Fab")
		)
		(fp_line
			(start 1.1049 -0.724916)
			(end -1.1049 -0.724916)
			(stroke
				(width 0.1)
				(type default)
			)
			(layer "F.Fab")
		)
		(pad "1" smd rect
			(at -0.889 0 90)
			(size 1.016 1.27)
			(layers "F.Cu" "F.Mask" "F.Paste")
			(net "P3V3_SSD6")
		)
		(pad "2" smd rect
			(at 0.889 0 90)
			(size 1.016 1.27)
			(layers "F.Cu" "F.Mask" "F.Paste")
			(net "GND")
		)
	)
	(footprint ""
		(layer "F.Cu")
		(at 278.758396 -414.88995 90)
		(property "Reference" "R1820"
			(at 0 0 90)
			(layer "F.SilkS")
			(hide yes)
			(effects
				(font
					(size 1.27 1.27)
				)
			)
		)
		(property "Value" ""
			(at 0 0 90)
			(layer "F.Fab")
			(effects
				(font
					(size 1.27 1.27)
				)
			)
		)
		(duplicate_pad_numbers_are_jumpers no)
		(fp_line
			(start 0.7874 -0.4064)
			(end 0.7874 0.4064)
			(stroke
				(width 0.1524)
				(type default)
			)
			(layer "F.SilkS")
		)
		(fp_line
			(start -0.7874 -0.4064)
			(end 0.7874 -0.4064)
			(stroke
				(width 0.1524)
				(type default)
			)
			(layer "F.SilkS")
		)
		(fp_line
			(start 0.7874 0.4064)
			(end -0.7874 0.4064)
			(stroke
				(width 0.1524)
				(type default)
			)
			(layer "F.SilkS")
		)
		(fp_line
			(start -0.7874 0.4064)
			(end -0.7874 -0.4064)
			(stroke
				(width 0.1524)
				(type default)
			)
			(layer "F.SilkS")
		)
		(fp_line
			(start -0.12065 -0.305054)
			(end -0.12065 -0.2794)
			(stroke
				(width 0.1)
				(type default)
			)
			(layer "F.Fab")
		)
		(fp_line
			(start -0.67945 -0.305054)
			(end -0.12065 -0.305054)
			(stroke
				(width 0.1)
				(type default)
			)
			(layer "F.Fab")
		)
		(fp_line
			(start 0.67945 -0.3048)
			(end 0.67945 0.3048)
			(stroke
				(width 0.1)
				(type default)
			)
			(layer "F.Fab")
		)
		(fp_line
			(start 0.12065 -0.3048)
			(end 0.67945 -0.3048)
			(stroke
				(width 0.1)
				(type default)
			)
			(layer "F.Fab")
		)
		(fp_line
			(start 0.12065 -0.2794)
			(end 0.12065 -0.3048)
			(stroke
				(width 0.1)
				(type default)
			)
			(layer "F.Fab")
		)
		(fp_line
			(start -0.12065 -0.2794)
			(end 0.12065 -0.2794)
			(stroke
				(width 0.1)
				(type default)
			)
			(layer "F.Fab")
		)
		(fp_line
			(start 0.120396 0.2794)
			(end -0.12065 0.2794)
			(stroke
				(width 0.1)
				(type default)
			)
			(layer "F.Fab")
		)
		(fp_line
			(start -0.12065 0.2794)
			(end -0.12065 0.3048)
			(stroke
				(width 0.1)
				(type default)
			)
			(layer "F.Fab")
		)
		(fp_line
			(start 0.67945 0.3048)
			(end 0.120396 0.3048)
			(stroke
				(width 0.1)
				(type default)
			)
			(layer "F.Fab")
		)
		(fp_line
			(start 0.120396 0.3048)
			(end 0.120396 0.2794)
			(stroke
				(width 0.1)
				(type default)
			)
			(layer "F.Fab")
		)
		(fp_line
			(start -0.12065 0.3048)
			(end -0.67945 0.3048)
			(stroke
				(width 0.1)
				(type default)
			)
			(layer "F.Fab")
		)
		(fp_line
			(start -0.67945 0.3048)
			(end -0.67945 -0.305054)
			(stroke
				(width 0.1)
				(type default)
			)
			(layer "F.Fab")
		)
		(pad "1" smd circle
			(at -0.40005 0 90)
			(size 0 0)
			(layers "F.Cu" "F.Mask" "F.Paste")
			(net "MB_BIC_READY_BUF_N")
		)
		(pad "2" smd circle
			(at 0.40005 0 90)
			(size 0 0)
			(layers "F.Cu" "F.Mask" "F.Paste")
			(net "MB_BIC_READY_BUF_R_N")
		)
	)
	(footprint ""
		(layer "F.Cu")
		(at 203.294996 -59.577986 90)
		(property "Reference" "PC542"
			(at 0 0 90)
			(layer "F.SilkS")
			(hide yes)
			(effects
				(font
					(size 1.27 1.27)
				)
			)
		)
		(property "Value" ""
			(at 0 0 90)
			(layer "F.Fab")
			(effects
				(font
					(size 1.27 1.27)
				)
			)
		)
		(duplicate_pad_numbers_are_jumpers no)
		(fp_line
			(start 0.7874 -0.4064)
			(end 0.7874 0.4064)
			(stroke
				(width 0.1524)
				(type default)
			)
			(layer "F.SilkS")
		)
		(fp_line
			(start -0.7874 -0.4064)
			(end 0.7874 -0.4064)
			(stroke
				(width 0.1524)
				(type default)
			)
			(layer "F.SilkS")
		)
		(fp_line
			(start 0.7874 0.4064)
			(end -0.7874 0.4064)
			(stroke
				(width 0.1524)
				(type default)
			)
			(layer "F.SilkS")
		)
		(fp_line
			(start -0.7874 0.4064)
			(end -0.7874 -0.4064)
			(stroke
				(width 0.1524)
				(type default)
			)
			(layer "F.SilkS")
		)
		(fp_line
			(start -0.12065 -0.305054)
			(end -0.12065 -0.2794)
			(stroke
				(width 0.1)
				(type default)
			)
			(layer "F.Fab")
		)
		(fp_line
			(start -0.67945 -0.305054)
			(end -0.12065 -0.305054)
			(stroke
				(width 0.1)
				(type default)
			)
			(layer "F.Fab")
		)
		(fp_line
			(start 0.67945 -0.3048)
			(end 0.67945 0.3048)
			(stroke
				(width 0.1)
				(type default)
			)
			(layer "F.Fab")
		)
		(fp_line
			(start 0.12065 -0.3048)
			(end 0.67945 -0.3048)
			(stroke
				(width 0.1)
				(type default)
			)
			(layer "F.Fab")
		)
		(fp_line
			(start 0.12065 -0.2794)
			(end 0.12065 -0.3048)
			(stroke
				(width 0.1)
				(type default)
			)
			(layer "F.Fab")
		)
		(fp_line
			(start -0.12065 -0.2794)
			(end 0.12065 -0.2794)
			(stroke
				(width 0.1)
				(type default)
			)
			(layer "F.Fab")
		)
		(fp_line
			(start 0.120396 0.2794)
			(end -0.12065 0.2794)
			(stroke
				(width 0.1)
				(type default)
			)
			(layer "F.Fab")
		)
		(fp_line
			(start -0.12065 0.2794)
			(end -0.12065 0.3048)
			(stroke
				(width 0.1)
				(type default)
			)
			(layer "F.Fab")
		)
		(fp_line
			(start 0.67945 0.3048)
			(end 0.120396 0.3048)
			(stroke
				(width 0.1)
				(type default)
			)
			(layer "F.Fab")
		)
		(fp_line
			(start 0.120396 0.3048)
			(end 0.120396 0.2794)
			(stroke
				(width 0.1)
				(type default)
			)
			(layer "F.Fab")
		)
		(fp_line
			(start -0.12065 0.3048)
			(end -0.67945 0.3048)
			(stroke
				(width 0.1)
				(type default)
			)
			(layer "F.Fab")
		)
		(fp_line
			(start -0.67945 0.3048)
			(end -0.67945 -0.305054)
			(stroke
				(width 0.1)
				(type default)
			)
			(layer "F.Fab")
		)
		(pad "1" smd circle
			(at -0.40005 0 90)
			(size 0 0)
			(layers "F.Cu" "F.Mask" "F.Paste")
			(net "P3V3_SSD7_SS")
		)
		(pad "2" smd circle
			(at 0.40005 0 90)
			(size 0 0)
			(layers "F.Cu" "F.Mask" "F.Paste")
			(net "GND")
		)
	)
	(footprint ""
		(layer "F.Cu")
		(at 376.051572 -260.840982)
		(property "Reference" "R4597"
			(at 0 0 0)
			(layer "F.SilkS")
			(hide yes)
			(effects
				(font
					(size 1.27 1.27)
				)
			)
		)
		(property "Value" ""
			(at 0 0 0)
			(layer "F.Fab")
			(effects
				(font
					(size 1.27 1.27)
				)
			)
		)
		(duplicate_pad_numbers_are_jumpers no)
		(fp_line
			(start -0.7874 -0.4064)
			(end 0.7874 -0.4064)
			(stroke
				(width 0.1524)
				(type default)
			)
			(layer "F.SilkS")
		)
		(fp_line
			(start -0.7874 0.4064)
			(end -0.7874 -0.4064)
			(stroke
				(width 0.1524)
				(type default)
			)
			(layer "F.SilkS")
		)
		(fp_line
			(start 0.7874 -0.4064)
			(end 0.7874 0.4064)
			(stroke
				(width 0.1524)
				(type default)
			)
			(layer "F.SilkS")
		)
		(fp_line
			(start 0.7874 0.4064)
			(end -0.7874 0.4064)
			(stroke
				(width 0.1524)
				(type default)
			)
			(layer "F.SilkS")
		)
		(fp_line
			(start -0.67945 -0.305054)
			(end -0.12065 -0.305054)
			(stroke
				(width 0.1)
				(type default)
			)
			(layer "F.Fab")
		)
		(fp_line
			(start -0.67945 0.3048)
			(end -0.67945 -0.305054)
			(stroke
				(width 0.1)
				(type default)
			)
			(layer "F.Fab")
		)
		(fp_line
			(start -0.12065 -0.305054)
			(end -0.12065 -0.2794)
			(stroke
				(width 0.1)
				(type default)
			)
			(layer "F.Fab")
		)
		(fp_line
			(start -0.12065 -0.2794)
			(end 0.12065 -0.2794)
			(stroke
				(width 0.1)
				(type default)
			)
			(layer "F.Fab")
		)
		(fp_line
			(start -0.12065 0.2794)
			(end -0.12065 0.3048)
			(stroke
				(width 0.1)
				(type default)
			)
			(layer "F.Fab")
		)
		(fp_line
			(start -0.12065 0.3048)
			(end -0.67945 0.3048)
			(stroke
				(width 0.1)
				(type default)
			)
			(layer "F.Fab")
		)
		(fp_line
			(start 0.120396 0.2794)
			(end -0.12065 0.2794)
			(stroke
				(width 0.1)
				(type default)
			)
			(layer "F.Fab")
		)
		(fp_line
			(start 0.120396 0.3048)
			(end 0.120396 0.2794)
			(stroke
				(width 0.1)
				(type default)
			)
			(layer "F.Fab")
		)
		(fp_line
			(start 0.12065 -0.3048)
			(end 0.67945 -0.3048)
			(stroke
				(width 0.1)
				(type default)
			)
			(layer "F.Fab")
		)
		(fp_line
			(start 0.12065 -0.2794)
			(end 0.12065 -0.3048)
			(stroke
				(width 0.1)
				(type default)
			)
			(layer "F.Fab")
		)
		(fp_line
			(start 0.67945 -0.3048)
			(end 0.67945 0.3048)
			(stroke
				(width 0.1)
				(type default)
			)
			(layer "F.Fab")
		)
		(fp_line
			(start 0.67945 0.3048)
			(end 0.120396 0.3048)
			(stroke
				(width 0.1)
				(type default)
			)
			(layer "F.Fab")
		)
		(pad "1" smd circle
			(at -0.40005 0)
			(size 0 0)
			(layers "F.Cu" "F.Mask" "F.Paste")
			(net "P1V8_VDDA_PEX3")
		)
		(pad "2" smd circle
			(at 0.40005 0)
			(size 0 0)
			(layers "F.Cu" "F.Mask" "F.Paste")
			(net "P1V8_VDDA_PEX3_R")
		)
	)
	(footprint ""
		(layer "F.Cu")
		(at 80.019398 -119.584724 180)
		(property "Reference" "C31"
			(at 0 0 180)
			(layer "F.SilkS")
			(hide yes)
			(effects
				(font
					(size 1.27 1.27)
				)
			)
		)
		(property "Value" ""
			(at 0 0 180)
			(layer "F.Fab")
			(effects
				(font
					(size 1.27 1.27)
				)
			)
		)
		(duplicate_pad_numbers_are_jumpers no)
		(fp_line
			(start 0.299974 0.150114)
			(end -0.299974 0.150114)
			(stroke
				(width 0.1)
				(type default)
			)
			(layer "F.Fab")
		)
		(fp_line
			(start 0.299974 -0.150114)
			(end 0.299974 0.150114)
			(stroke
				(width 0.1)
				(type default)
			)
			(layer "F.Fab")
		)
		(fp_line
			(start -0.299974 0.150114)
			(end -0.299974 -0.150114)
			(stroke
				(width 0.1)
				(type default)
			)
			(layer "F.Fab")
		)
		(fp_line
			(start -0.299974 -0.150114)
			(end 0.299974 -0.150114)
			(stroke
				(width 0.1)
				(type default)
			)
			(layer "F.Fab")
		)
		(pad "1" smd rect
			(at -0.2667 0 180)
			(size 0.3048 0.381)
			(layers "F.Cu" "F.Mask" "F.Paste")
			(net "P5E_PEX0_STN0_TX_DP<0>")
		)
		(pad "2" smd rect
			(at 0.2667 0 180)
			(size 0.3048 0.381)
			(layers "F.Cu" "F.Mask" "F.Paste")
			(net "P5E_PEX0_STN0_TX_C_DP<0>")
		)
	)
	(footprint ""
		(layer "F.Cu")
		(at 400.567906 -55.083456)
		(property "Reference" "PC445"
			(at 0 0 0)
			(layer "F.SilkS")
			(hide yes)
			(effects
				(font
					(size 1.27 1.27)
				)
			)
		)
		(property "Value" ""
			(at 0 0 0)
			(layer "F.Fab")
			(effects
				(font
					(size 1.27 1.27)
				)
			)
		)
		(duplicate_pad_numbers_are_jumpers no)
		(fp_line
			(start -0.7874 -0.4064)
			(end 0.7874 -0.4064)
			(stroke
				(width 0.1524)
				(type default)
			)
			(layer "F.SilkS")
		)
		(fp_line
			(start -0.7874 0.4064)
			(end -0.7874 -0.4064)
			(stroke
				(width 0.1524)
				(type default)
			)
			(layer "F.SilkS")
		)
		(fp_line
			(start 0.7874 -0.4064)
			(end 0.7874 0.4064)
			(stroke
				(width 0.1524)
				(type default)
			)
			(layer "F.SilkS")
		)
		(fp_line
			(start 0.7874 0.4064)
			(end -0.7874 0.4064)
			(stroke
				(width 0.1524)
				(type default)
			)
			(layer "F.SilkS")
		)
		(fp_line
			(start -0.67945 -0.305054)
			(end -0.12065 -0.305054)
			(stroke
				(width 0.1)
				(type default)
			)
			(layer "F.Fab")
		)
		(fp_line
			(start -0.67945 0.3048)
			(end -0.67945 -0.305054)
			(stroke
				(width 0.1)
				(type default)
			)
			(layer "F.Fab")
		)
		(fp_line
			(start -0.12065 -0.305054)
			(end -0.12065 -0.2794)
			(stroke
				(width 0.1)
				(type default)
			)
			(layer "F.Fab")
		)
		(fp_line
			(start -0.12065 -0.2794)
			(end 0.12065 -0.2794)
			(stroke
				(width 0.1)
				(type default)
			)
			(layer "F.Fab")
		)
		(fp_line
			(start -0.12065 0.2794)
			(end -0.12065 0.3048)
			(stroke
				(width 0.1)
				(type default)
			)
			(layer "F.Fab")
		)
		(fp_line
			(start -0.12065 0.3048)
			(end -0.67945 0.3048)
			(stroke
				(width 0.1)
				(type default)
			)
			(layer "F.Fab")
		)
		(fp_line
			(start 0.120396 0.2794)
			(end -0.12065 0.2794)
			(stroke
				(width 0.1)
				(type default)
			)
			(layer "F.Fab")
		)
		(fp_line
			(start 0.120396 0.3048)
			(end 0.120396 0.2794)
			(stroke
				(width 0.1)
				(type default)
			)
			(layer "F.Fab")
		)
		(fp_line
			(start 0.12065 -0.3048)
			(end 0.67945 -0.3048)
			(stroke
				(width 0.1)
				(type default)
			)
			(layer "F.Fab")
		)
		(fp_line
			(start 0.12065 -0.2794)
			(end 0.12065 -0.3048)
			(stroke
				(width 0.1)
				(type default)
			)
			(layer "F.Fab")
		)
		(fp_line
			(start 0.67945 -0.3048)
			(end 0.67945 0.3048)
			(stroke
				(width 0.1)
				(type default)
			)
			(layer "F.Fab")
		)
		(fp_line
			(start 0.67945 0.3048)
			(end 0.120396 0.3048)
			(stroke
				(width 0.1)
				(type default)
			)
			(layer "F.Fab")
		)
		(pad "1" smd circle
			(at -0.40005 0)
			(size 0 0)
			(layers "F.Cu" "F.Mask" "F.Paste")
			(net "P5V_AUX")
		)
		(pad "2" smd circle
			(at 0.40005 0)
			(size 0 0)
			(layers "F.Cu" "F.Mask" "F.Paste")
			(net "GND")
		)
	)
	(footprint ""
		(layer "F.Cu")
		(at 452.567802 -54.067456)
		(property "Reference" "PR238"
			(at 0 0 0)
			(layer "F.SilkS")
			(hide yes)
			(effects
				(font
					(size 1.27 1.27)
				)
			)
		)
		(property "Value" ""
			(at 0 0 0)
			(layer "F.Fab")
			(effects
				(font
					(size 1.27 1.27)
				)
			)
		)
		(duplicate_pad_numbers_are_jumpers no)
		(fp_line
			(start -0.7874 -0.4064)
			(end 0.7874 -0.4064)
			(stroke
				(width 0.1524)
				(type default)
			)
			(layer "F.SilkS")
		)
		(fp_line
			(start -0.7874 0.4064)
			(end -0.7874 -0.4064)
			(stroke
				(width 0.1524)
				(type default)
			)
			(layer "F.SilkS")
		)
		(fp_line
			(start 0.7874 -0.4064)
			(end 0.7874 0.4064)
			(stroke
				(width 0.1524)
				(type default)
			)
			(layer "F.SilkS")
		)
		(fp_line
			(start 0.7874 0.4064)
			(end -0.7874 0.4064)
			(stroke
				(width 0.1524)
				(type default)
			)
			(layer "F.SilkS")
		)
		(fp_line
			(start -0.67945 -0.305054)
			(end -0.12065 -0.305054)
			(stroke
				(width 0.1)
				(type default)
			)
			(layer "F.Fab")
		)
		(fp_line
			(start -0.67945 0.3048)
			(end -0.67945 -0.305054)
			(stroke
				(width 0.1)
				(type default)
			)
			(layer "F.Fab")
		)
		(fp_line
			(start -0.12065 -0.305054)
			(end -0.12065 -0.2794)
			(stroke
				(width 0.1)
				(type default)
			)
			(layer "F.Fab")
		)
		(fp_line
			(start -0.12065 -0.2794)
			(end 0.12065 -0.2794)
			(stroke
				(width 0.1)
				(type default)
			)
			(layer "F.Fab")
		)
		(fp_line
			(start -0.12065 0.2794)
			(end -0.12065 0.3048)
			(stroke
				(width 0.1)
				(type default)
			)
			(layer "F.Fab")
		)
		(fp_line
			(start -0.12065 0.3048)
			(end -0.67945 0.3048)
			(stroke
				(width 0.1)
				(type default)
			)
			(layer "F.Fab")
		)
		(fp_line
			(start 0.120396 0.2794)
			(end -0.12065 0.2794)
			(stroke
				(width 0.1)
				(type default)
			)
			(layer "F.Fab")
		)
		(fp_line
			(start 0.120396 0.3048)
			(end 0.120396 0.2794)
			(stroke
				(width 0.1)
				(type default)
			)
			(layer "F.Fab")
		)
		(fp_line
			(start 0.12065 -0.3048)
			(end 0.67945 -0.3048)
			(stroke
				(width 0.1)
				(type default)
			)
			(layer "F.Fab")
		)
		(fp_line
			(start 0.12065 -0.2794)
			(end 0.12065 -0.3048)
			(stroke
				(width 0.1)
				(type default)
			)
			(layer "F.Fab")
		)
		(fp_line
			(start 0.67945 -0.3048)
			(end 0.67945 0.3048)
			(stroke
				(width 0.1)
				(type default)
			)
			(layer "F.Fab")
		)
		(fp_line
			(start 0.67945 0.3048)
			(end 0.120396 0.3048)
			(stroke
				(width 0.1)
				(type default)
			)
			(layer "F.Fab")
		)
		(pad "1" smd circle
			(at -0.40005 0)
			(size 0 0)
			(layers "F.Cu" "F.Mask" "F.Paste")
			(net "P12V_SSD15_OCP")
		)
		(pad "2" smd circle
			(at 0.40005 0)
			(size 0 0)
			(layers "F.Cu" "F.Mask" "F.Paste")
			(net "GND")
		)
	)
	(footprint ""
		(layer "F.Cu")
		(at 317.30442 -302.493934 -90)
		(property "Reference" "R6810"
			(at 0 0 270)
			(layer "F.SilkS")
			(hide yes)
			(effects
				(font
					(size 1.27 1.27)
				)
			)
		)
		(property "Value" ""
			(at 0 0 270)
			(layer "F.Fab")
			(effects
				(font
					(size 1.27 1.27)
				)
			)
		)
		(duplicate_pad_numbers_are_jumpers no)
		(fp_line
			(start -0.7874 0.4064)
			(end -0.7874 -0.4064)
			(stroke
				(width 0.1524)
				(type default)
			)
			(layer "F.SilkS")
		)
		(fp_line
			(start 0.7874 0.4064)
			(end -0.7874 0.4064)
			(stroke
				(width 0.1524)
				(type default)
			)
			(layer "F.SilkS")
		)
		(fp_line
			(start -0.7874 -0.4064)
			(end 0.7874 -0.4064)
			(stroke
				(width 0.1524)
				(type default)
			)
			(layer "F.SilkS")
		)
		(fp_line
			(start 0.7874 -0.4064)
			(end 0.7874 0.4064)
			(stroke
				(width 0.1524)
				(type default)
			)
			(layer "F.SilkS")
		)
		(fp_line
			(start -0.67945 0.3048)
			(end -0.67945 -0.305054)
			(stroke
				(width 0.1)
				(type default)
			)
			(layer "F.Fab")
		)
		(fp_line
			(start -0.12065 0.3048)
			(end -0.67945 0.3048)
			(stroke
				(width 0.1)
				(type default)
			)
			(layer "F.Fab")
		)
		(fp_line
			(start 0.120396 0.3048)
			(end 0.120396 0.2794)
			(stroke
				(width 0.1)
				(type default)
			)
			(layer "F.Fab")
		)
		(fp_line
			(start 0.67945 0.3048)
			(end 0.120396 0.3048)
			(stroke
				(width 0.1)
				(type default)
			)
			(layer "F.Fab")
		)
		(fp_line
			(start -0.12065 0.2794)
			(end -0.12065 0.3048)
			(stroke
				(width 0.1)
				(type default)
			)
			(layer "F.Fab")
		)
		(fp_line
			(start 0.120396 0.2794)
			(end -0.12065 0.2794)
			(stroke
				(width 0.1)
				(type default)
			)
			(layer "F.Fab")
		)
		(fp_line
			(start -0.12065 -0.2794)
			(end 0.12065 -0.2794)
			(stroke
				(width 0.1)
				(type default)
			)
			(layer "F.Fab")
		)
		(fp_line
			(start 0.12065 -0.2794)
			(end 0.12065 -0.3048)
			(stroke
				(width 0.1)
				(type default)
			)
			(layer "F.Fab")
		)
		(fp_line
			(start 0.12065 -0.3048)
			(end 0.67945 -0.3048)
			(stroke
				(width 0.1)
				(type default)
			)
			(layer "F.Fab")
		)
		(fp_line
			(start 0.67945 -0.3048)
			(end 0.67945 0.3048)
			(stroke
				(width 0.1)
				(type default)
			)
			(layer "F.Fab")
		)
		(fp_line
			(start -0.67945 -0.305054)
			(end -0.12065 -0.305054)
			(stroke
				(width 0.1)
				(type default)
			)
			(layer "F.Fab")
		)
		(fp_line
			(start -0.12065 -0.305054)
			(end -0.12065 -0.2794)
			(stroke
				(width 0.1)
				(type default)
			)
			(layer "F.Fab")
		)
		(pad "1" smd circle
			(at -0.40005 0 270)
			(size 0 0)
			(layers "F.Cu" "F.Mask" "F.Paste")
			(net "SMB_PEX2_R_SCL")
		)
		(pad "2" smd circle
			(at 0.40005 0 270)
			(size 0 0)
			(layers "F.Cu" "F.Mask" "F.Paste")
			(net "SMB_PEX2_SCL")
		)
	)
	(footprint ""
		(layer "F.Cu")
		(at 92.899992 -289.230816 -90)
		(property "Reference" "R3877"
			(at 0 0 270)
			(layer "F.SilkS")
			(hide yes)
			(effects
				(font
					(size 1.27 1.27)
				)
			)
		)
		(property "Value" ""
			(at 0 0 270)
			(layer "F.Fab")
			(effects
				(font
					(size 1.27 1.27)
				)
			)
		)
		(duplicate_pad_numbers_are_jumpers no)
		(fp_line
			(start -0.7874 0.4064)
			(end -0.7874 -0.4064)
			(stroke
				(width 0.1524)
				(type default)
			)
			(layer "F.SilkS")
		)
		(fp_line
			(start 0.7874 0.4064)
			(end -0.7874 0.4064)
			(stroke
				(width 0.1524)
				(type default)
			)
			(layer "F.SilkS")
		)
		(fp_line
			(start -0.7874 -0.4064)
			(end 0.7874 -0.4064)
			(stroke
				(width 0.1524)
				(type default)
			)
			(layer "F.SilkS")
		)
		(fp_line
			(start 0.7874 -0.4064)
			(end 0.7874 0.4064)
			(stroke
				(width 0.1524)
				(type default)
			)
			(layer "F.SilkS")
		)
		(fp_line
			(start -0.67945 0.3048)
			(end -0.67945 -0.305054)
			(stroke
				(width 0.1)
				(type default)
			)
			(layer "F.Fab")
		)
		(fp_line
			(start -0.12065 0.3048)
			(end -0.67945 0.3048)
			(stroke
				(width 0.1)
				(type default)
			)
			(layer "F.Fab")
		)
		(fp_line
			(start 0.120396 0.3048)
			(end 0.120396 0.2794)
			(stroke
				(width 0.1)
				(type default)
			)
			(layer "F.Fab")
		)
		(fp_line
			(start 0.67945 0.3048)
			(end 0.120396 0.3048)
			(stroke
				(width 0.1)
				(type default)
			)
			(layer "F.Fab")
		)
		(fp_line
			(start -0.12065 0.2794)
			(end -0.12065 0.3048)
			(stroke
				(width 0.1)
				(type default)
			)
			(layer "F.Fab")
		)
		(fp_line
			(start 0.120396 0.2794)
			(end -0.12065 0.2794)
			(stroke
				(width 0.1)
				(type default)
			)
			(layer "F.Fab")
		)
		(fp_line
			(start -0.12065 -0.2794)
			(end 0.12065 -0.2794)
			(stroke
				(width 0.1)
				(type default)
			)
			(layer "F.Fab")
		)
		(fp_line
			(start 0.12065 -0.2794)
			(end 0.12065 -0.3048)
			(stroke
				(width 0.1)
				(type default)
			)
			(layer "F.Fab")
		)
		(fp_line
			(start 0.12065 -0.3048)
			(end 0.67945 -0.3048)
			(stroke
				(width 0.1)
				(type default)
			)
			(layer "F.Fab")
		)
		(fp_line
			(start 0.67945 -0.3048)
			(end 0.67945 0.3048)
			(stroke
				(width 0.1)
				(type default)
			)
			(layer "F.Fab")
		)
		(fp_line
			(start -0.67945 -0.305054)
			(end -0.12065 -0.305054)
			(stroke
				(width 0.1)
				(type default)
			)
			(layer "F.Fab")
		)
		(fp_line
			(start -0.12065 -0.305054)
			(end -0.12065 -0.2794)
			(stroke
				(width 0.1)
				(type default)
			)
			(layer "F.Fab")
		)
		(pad "1" smd circle
			(at -0.40005 0 270)
			(size 0 0)
			(layers "F.Cu" "F.Mask" "F.Paste")
			(net "SMB_PEX0_HOST_LS_SCL")
		)
		(pad "2" smd circle
			(at 0.40005 0 270)
			(size 0 0)
			(layers "F.Cu" "F.Mask" "F.Paste")
			(net "P3V3_AUX")
		)
	)
	(footprint ""
		(layer "F.Cu")
		(at 441.273692 -356.244906 90)
		(property "Reference" "C795"
			(at 0 0 90)
			(layer "F.SilkS")
			(hide yes)
			(effects
				(font
					(size 1.27 1.27)
				)
			)
		)
		(property "Value" ""
			(at 0 0 90)
			(layer "F.Fab")
			(effects
				(font
					(size 1.27 1.27)
				)
			)
		)
		(duplicate_pad_numbers_are_jumpers no)
		(fp_line
			(start 0.299974 -0.150114)
			(end 0.299974 0.150114)
			(stroke
				(width 0.1)
				(type default)
			)
			(layer "F.Fab")
		)
		(fp_line
			(start -0.299974 -0.150114)
			(end 0.299974 -0.150114)
			(stroke
				(width 0.1)
				(type default)
			)
			(layer "F.Fab")
		)
		(fp_line
			(start 0.299974 0.150114)
			(end -0.299974 0.150114)
			(stroke
				(width 0.1)
				(type default)
			)
			(layer "F.Fab")
		)
		(fp_line
			(start -0.299974 0.150114)
			(end -0.299974 -0.150114)
			(stroke
				(width 0.1)
				(type default)
			)
			(layer "F.Fab")
		)
		(pad "1" smd rect
			(at -0.2667 0 90)
			(size 0.3048 0.381)
			(layers "F.Cu" "F.Mask" "F.Paste")
			(net "P5E_PEX3_STN7_TX_DN<127>")
		)
		(pad "2" smd rect
			(at 0.2667 0 90)
			(size 0.3048 0.381)
			(layers "F.Cu" "F.Mask" "F.Paste")
			(net "P5E_PEX3_STN7_TX_C_DN<127>")
		)
	)
	(footprint ""
		(layer "F.Cu")
		(at 56.26481 -384.973068)
		(property "Reference" "C4025"
			(at 0 0 0)
			(layer "F.SilkS")
			(hide yes)
			(effects
				(font
					(size 1.27 1.27)
				)
			)
		)
		(property "Value" ""
			(at 0 0 0)
			(layer "F.Fab")
			(effects
				(font
					(size 1.27 1.27)
				)
			)
		)
		(duplicate_pad_numbers_are_jumpers no)
		(fp_line
			(start -0.7874 -0.4064)
			(end 0.7874 -0.4064)
			(stroke
				(width 0.1524)
				(type default)
			)
			(layer "F.SilkS")
		)
		(fp_line
			(start -0.7874 0.4064)
			(end -0.7874 -0.4064)
			(stroke
				(width 0.1524)
				(type default)
			)
			(layer "F.SilkS")
		)
		(fp_line
			(start 0.7874 -0.4064)
			(end 0.7874 0.4064)
			(stroke
				(width 0.1524)
				(type default)
			)
			(layer "F.SilkS")
		)
		(fp_line
			(start 0.7874 0.4064)
			(end -0.7874 0.4064)
			(stroke
				(width 0.1524)
				(type default)
			)
			(layer "F.SilkS")
		)
		(fp_line
			(start -0.67945 -0.305054)
			(end -0.12065 -0.305054)
			(stroke
				(width 0.1)
				(type default)
			)
			(layer "F.Fab")
		)
		(fp_line
			(start -0.67945 0.3048)
			(end -0.67945 -0.305054)
			(stroke
				(width 0.1)
				(type default)
			)
			(layer "F.Fab")
		)
		(fp_line
			(start -0.12065 -0.305054)
			(end -0.12065 -0.2794)
			(stroke
				(width 0.1)
				(type default)
			)
			(layer "F.Fab")
		)
		(fp_line
			(start -0.12065 -0.2794)
			(end 0.12065 -0.2794)
			(stroke
				(width 0.1)
				(type default)
			)
			(layer "F.Fab")
		)
		(fp_line
			(start -0.12065 0.2794)
			(end -0.12065 0.3048)
			(stroke
				(width 0.1)
				(type default)
			)
			(layer "F.Fab")
		)
		(fp_line
			(start -0.12065 0.3048)
			(end -0.67945 0.3048)
			(stroke
				(width 0.1)
				(type default)
			)
			(layer "F.Fab")
		)
		(fp_line
			(start 0.120396 0.2794)
			(end -0.12065 0.2794)
			(stroke
				(width 0.1)
				(type default)
			)
			(layer "F.Fab")
		)
		(fp_line
			(start 0.120396 0.3048)
			(end 0.120396 0.2794)
			(stroke
				(width 0.1)
				(type default)
			)
			(layer "F.Fab")
		)
		(fp_line
			(start 0.12065 -0.3048)
			(end 0.67945 -0.3048)
			(stroke
				(width 0.1)
				(type default)
			)
			(layer "F.Fab")
		)
		(fp_line
			(start 0.12065 -0.2794)
			(end 0.12065 -0.3048)
			(stroke
				(width 0.1)
				(type default)
			)
			(layer "F.Fab")
		)
		(fp_line
			(start 0.67945 -0.3048)
			(end 0.67945 0.3048)
			(stroke
				(width 0.1)
				(type default)
			)
			(layer "F.Fab")
		)
		(fp_line
			(start 0.67945 0.3048)
			(end 0.120396 0.3048)
			(stroke
				(width 0.1)
				(type default)
			)
			(layer "F.Fab")
		)
		(pad "1" smd circle
			(at -0.40005 0)
			(size 0 0)
			(layers "F.Cu" "F.Mask" "F.Paste")
			(net "GND")
		)
		(pad "2" smd circle
			(at 0.40005 0)
			(size 0 0)
			(layers "F.Cu" "F.Mask" "F.Paste")
			(net "GPU_BASE_FPGA_READY")
		)
	)
	(footprint ""
		(layer "F.Cu")
		(at 288.079942 -139.6492)
		(property "Reference" "R211"
			(at 0 0 0)
			(layer "F.SilkS")
			(hide yes)
			(effects
				(font
					(size 1.27 1.27)
				)
			)
		)
		(property "Value" ""
			(at 0 0 0)
			(layer "F.Fab")
			(effects
				(font
					(size 1.27 1.27)
				)
			)
		)
		(duplicate_pad_numbers_are_jumpers no)
		(fp_line
			(start -0.7874 -0.4064)
			(end 0.7874 -0.4064)
			(stroke
				(width 0.1524)
				(type default)
			)
			(layer "F.SilkS")
		)
		(fp_line
			(start -0.7874 0.4064)
			(end -0.7874 -0.4064)
			(stroke
				(width 0.1524)
				(type default)
			)
			(layer "F.SilkS")
		)
		(fp_line
			(start 0.7874 -0.4064)
			(end 0.7874 0.4064)
			(stroke
				(width 0.1524)
				(type default)
			)
			(layer "F.SilkS")
		)
		(fp_line
			(start 0.7874 0.4064)
			(end -0.7874 0.4064)
			(stroke
				(width 0.1524)
				(type default)
			)
			(layer "F.SilkS")
		)
		(fp_line
			(start -0.67945 -0.305054)
			(end -0.12065 -0.305054)
			(stroke
				(width 0.1)
				(type default)
			)
			(layer "F.Fab")
		)
		(fp_line
			(start -0.67945 0.3048)
			(end -0.67945 -0.305054)
			(stroke
				(width 0.1)
				(type default)
			)
			(layer "F.Fab")
		)
		(fp_line
			(start -0.12065 -0.305054)
			(end -0.12065 -0.2794)
			(stroke
				(width 0.1)
				(type default)
			)
			(layer "F.Fab")
		)
		(fp_line
			(start -0.12065 -0.2794)
			(end 0.12065 -0.2794)
			(stroke
				(width 0.1)
				(type default)
			)
			(layer "F.Fab")
		)
		(fp_line
			(start -0.12065 0.2794)
			(end -0.12065 0.3048)
			(stroke
				(width 0.1)
				(type default)
			)
			(layer "F.Fab")
		)
		(fp_line
			(start -0.12065 0.3048)
			(end -0.67945 0.3048)
			(stroke
				(width 0.1)
				(type default)
			)
			(layer "F.Fab")
		)
		(fp_line
			(start 0.120396 0.2794)
			(end -0.12065 0.2794)
			(stroke
				(width 0.1)
				(type default)
			)
			(layer "F.Fab")
		)
		(fp_line
			(start 0.120396 0.3048)
			(end 0.120396 0.2794)
			(stroke
				(width 0.1)
				(type default)
			)
			(layer "F.Fab")
		)
		(fp_line
			(start 0.12065 -0.3048)
			(end 0.67945 -0.3048)
			(stroke
				(width 0.1)
				(type default)
			)
			(layer "F.Fab")
		)
		(fp_line
			(start 0.12065 -0.2794)
			(end 0.12065 -0.3048)
			(stroke
				(width 0.1)
				(type default)
			)
			(layer "F.Fab")
		)
		(fp_line
			(start 0.67945 -0.3048)
			(end 0.67945 0.3048)
			(stroke
				(width 0.1)
				(type default)
			)
			(layer "F.Fab")
		)
		(fp_line
			(start 0.67945 0.3048)
			(end 0.120396 0.3048)
			(stroke
				(width 0.1)
				(type default)
			)
			(layer "F.Fab")
		)
		(pad "1" smd circle
			(at -0.40005 0)
			(size 0 0)
			(layers "F.Cu" "F.Mask" "F.Paste")
			(net "PRSNTB2_NIC4_N")
		)
		(pad "2" smd circle
			(at 0.40005 0)
			(size 0 0)
			(layers "F.Cu" "F.Mask" "F.Paste")
			(net "P3V3_AUX")
		)
	)
	(footprint ""
		(layer "F.Cu")
		(at 26.267918 -52.035456 180)
		(property "Reference" "R861"
			(at 0 0 180)
			(layer "F.SilkS")
			(hide yes)
			(effects
				(font
					(size 1.27 1.27)
				)
			)
		)
		(property "Value" ""
			(at 0 0 180)
			(layer "F.Fab")
			(effects
				(font
					(size 1.27 1.27)
				)
			)
		)
		(duplicate_pad_numbers_are_jumpers no)
		(fp_line
			(start 0.7874 0.4064)
			(end -0.7874 0.4064)
			(stroke
				(width 0.1524)
				(type default)
			)
			(layer "F.SilkS")
		)
		(fp_line
			(start 0.7874 -0.4064)
			(end 0.7874 0.4064)
			(stroke
				(width 0.1524)
				(type default)
			)
			(layer "F.SilkS")
		)
		(fp_line
			(start -0.7874 0.4064)
			(end -0.7874 -0.4064)
			(stroke
				(width 0.1524)
				(type default)
			)
			(layer "F.SilkS")
		)
		(fp_line
			(start -0.7874 -0.4064)
			(end 0.7874 -0.4064)
			(stroke
				(width 0.1524)
				(type default)
			)
			(layer "F.SilkS")
		)
		(fp_line
			(start 0.67945 0.3048)
			(end 0.120396 0.3048)
			(stroke
				(width 0.1)
				(type default)
			)
			(layer "F.Fab")
		)
		(fp_line
			(start 0.67945 -0.3048)
			(end 0.67945 0.3048)
			(stroke
				(width 0.1)
				(type default)
			)
			(layer "F.Fab")
		)
		(fp_line
			(start 0.12065 -0.2794)
			(end 0.12065 -0.3048)
			(stroke
				(width 0.1)
				(type default)
			)
			(layer "F.Fab")
		)
		(fp_line
			(start 0.12065 -0.3048)
			(end 0.67945 -0.3048)
			(stroke
				(width 0.1)
				(type default)
			)
			(layer "F.Fab")
		)
		(fp_line
			(start 0.120396 0.3048)
			(end 0.120396 0.2794)
			(stroke
				(width 0.1)
				(type default)
			)
			(layer "F.Fab")
		)
		(fp_line
			(start 0.120396 0.2794)
			(end -0.12065 0.2794)
			(stroke
				(width 0.1)
				(type default)
			)
			(layer "F.Fab")
		)
		(fp_line
			(start -0.12065 0.3048)
			(end -0.67945 0.3048)
			(stroke
				(width 0.1)
				(type default)
			)
			(layer "F.Fab")
		)
		(fp_line
			(start -0.12065 0.2794)
			(end -0.12065 0.3048)
			(stroke
				(width 0.1)
				(type default)
			)
			(layer "F.Fab")
		)
		(fp_line
			(start -0.12065 -0.2794)
			(end 0.12065 -0.2794)
			(stroke
				(width 0.1)
				(type default)
			)
			(layer "F.Fab")
		)
		(fp_line
			(start -0.12065 -0.305054)
			(end -0.12065 -0.2794)
			(stroke
				(width 0.1)
				(type default)
			)
			(layer "F.Fab")
		)
		(fp_line
			(start -0.67945 0.3048)
			(end -0.67945 -0.305054)
			(stroke
				(width 0.1)
				(type default)
			)
			(layer "F.Fab")
		)
		(fp_line
			(start -0.67945 -0.305054)
			(end -0.12065 -0.305054)
			(stroke
				(width 0.1)
				(type default)
			)
			(layer "F.Fab")
		)
		(pad "1" smd circle
			(at -0.40005 0 180)
			(size 0 0)
			(layers "F.Cu" "F.Mask" "F.Paste")
			(net "P3V3_AUX")
		)
		(pad "2" smd circle
			(at 0.40005 0 180)
			(size 0 0)
			(layers "F.Cu" "F.Mask" "F.Paste")
			(net "PWRGD_P12V_SSD0")
		)
	)
	(footprint ""
		(layer "F.Cu")
		(at 58.995056 -104.830372 180)
		(property "Reference" "R71"
			(at 0 0 180)
			(layer "F.SilkS")
			(hide yes)
			(effects
				(font
					(size 1.27 1.27)
				)
			)
		)
		(property "Value" ""
			(at 0 0 180)
			(layer "F.Fab")
			(effects
				(font
					(size 1.27 1.27)
				)
			)
		)
		(duplicate_pad_numbers_are_jumpers no)
		(fp_line
			(start 0.7874 0.4064)
			(end -0.7874 0.4064)
			(stroke
				(width 0.1524)
				(type default)
			)
			(layer "F.SilkS")
		)
		(fp_line
			(start 0.7874 -0.4064)
			(end 0.7874 0.4064)
			(stroke
				(width 0.1524)
				(type default)
			)
			(layer "F.SilkS")
		)
		(fp_line
			(start -0.7874 0.4064)
			(end -0.7874 -0.4064)
			(stroke
				(width 0.1524)
				(type default)
			)
			(layer "F.SilkS")
		)
		(fp_line
			(start -0.7874 -0.4064)
			(end 0.7874 -0.4064)
			(stroke
				(width 0.1524)
				(type default)
			)
			(layer "F.SilkS")
		)
		(fp_line
			(start 0.67945 0.3048)
			(end 0.120396 0.3048)
			(stroke
				(width 0.1)
				(type default)
			)
			(layer "F.Fab")
		)
		(fp_line
			(start 0.67945 -0.3048)
			(end 0.67945 0.3048)
			(stroke
				(width 0.1)
				(type default)
			)
			(layer "F.Fab")
		)
		(fp_line
			(start 0.12065 -0.2794)
			(end 0.12065 -0.3048)
			(stroke
				(width 0.1)
				(type default)
			)
			(layer "F.Fab")
		)
		(fp_line
			(start 0.12065 -0.3048)
			(end 0.67945 -0.3048)
			(stroke
				(width 0.1)
				(type default)
			)
			(layer "F.Fab")
		)
		(fp_line
			(start 0.120396 0.3048)
			(end 0.120396 0.2794)
			(stroke
				(width 0.1)
				(type default)
			)
			(layer "F.Fab")
		)
		(fp_line
			(start 0.120396 0.2794)
			(end -0.12065 0.2794)
			(stroke
				(width 0.1)
				(type default)
			)
			(layer "F.Fab")
		)
		(fp_line
			(start -0.12065 0.3048)
			(end -0.67945 0.3048)
			(stroke
				(width 0.1)
				(type default)
			)
			(layer "F.Fab")
		)
		(fp_line
			(start -0.12065 0.2794)
			(end -0.12065 0.3048)
			(stroke
				(width 0.1)
				(type default)
			)
			(layer "F.Fab")
		)
		(fp_line
			(start -0.12065 -0.2794)
			(end 0.12065 -0.2794)
			(stroke
				(width 0.1)
				(type default)
			)
			(layer "F.Fab")
		)
		(fp_line
			(start -0.12065 -0.305054)
			(end -0.12065 -0.2794)
			(stroke
				(width 0.1)
				(type default)
			)
			(layer "F.Fab")
		)
		(fp_line
			(start -0.67945 0.3048)
			(end -0.67945 -0.305054)
			(stroke
				(width 0.1)
				(type default)
			)
			(layer "F.Fab")
		)
		(fp_line
			(start -0.67945 -0.305054)
			(end -0.12065 -0.305054)
			(stroke
				(width 0.1)
				(type default)
			)
			(layer "F.Fab")
		)
		(pad "1" smd circle
			(at -0.40005 0 180)
			(size 0 0)
			(layers "F.Cu" "F.Mask" "F.Paste")
			(net "CLK_50M_NIC1_RBT_REF")
		)
		(pad "2" smd circle
			(at 0.40005 0 180)
			(size 0 0)
			(layers "F.Cu" "F.Mask" "F.Paste")
			(net "GND")
		)
	)
	(footprint ""
		(layer "F.Cu")
		(at 264.066782 -52.543456 180)
		(property "Reference" "PC560"
			(at 0 0 180)
			(layer "F.SilkS")
			(hide yes)
			(effects
				(font
					(size 1.27 1.27)
				)
			)
		)
		(property "Value" ""
			(at 0 0 180)
			(layer "F.Fab")
			(effects
				(font
					(size 1.27 1.27)
				)
			)
		)
		(duplicate_pad_numbers_are_jumpers no)
		(fp_line
			(start 0.7874 0.4064)
			(end -0.7874 0.4064)
			(stroke
				(width 0.1524)
				(type default)
			)
			(layer "F.SilkS")
		)
		(fp_line
			(start 0.7874 -0.4064)
			(end 0.7874 0.4064)
			(stroke
				(width 0.1524)
				(type default)
			)
			(layer "F.SilkS")
		)
		(fp_line
			(start -0.7874 0.4064)
			(end -0.7874 -0.4064)
			(stroke
				(width 0.1524)
				(type default)
			)
			(layer "F.SilkS")
		)
		(fp_line
			(start -0.7874 -0.4064)
			(end 0.7874 -0.4064)
			(stroke
				(width 0.1524)
				(type default)
			)
			(layer "F.SilkS")
		)
		(fp_line
			(start 0.67945 0.3048)
			(end 0.120396 0.3048)
			(stroke
				(width 0.1)
				(type default)
			)
			(layer "F.Fab")
		)
		(fp_line
			(start 0.67945 -0.3048)
			(end 0.67945 0.3048)
			(stroke
				(width 0.1)
				(type default)
			)
			(layer "F.Fab")
		)
		(fp_line
			(start 0.12065 -0.2794)
			(end 0.12065 -0.3048)
			(stroke
				(width 0.1)
				(type default)
			)
			(layer "F.Fab")
		)
		(fp_line
			(start 0.12065 -0.3048)
			(end 0.67945 -0.3048)
			(stroke
				(width 0.1)
				(type default)
			)
			(layer "F.Fab")
		)
		(fp_line
			(start 0.120396 0.3048)
			(end 0.120396 0.2794)
			(stroke
				(width 0.1)
				(type default)
			)
			(layer "F.Fab")
		)
		(fp_line
			(start 0.120396 0.2794)
			(end -0.12065 0.2794)
			(stroke
				(width 0.1)
				(type default)
			)
			(layer "F.Fab")
		)
		(fp_line
			(start -0.12065 0.3048)
			(end -0.67945 0.3048)
			(stroke
				(width 0.1)
				(type default)
			)
			(layer "F.Fab")
		)
		(fp_line
			(start -0.12065 0.2794)
			(end -0.12065 0.3048)
			(stroke
				(width 0.1)
				(type default)
			)
			(layer "F.Fab")
		)
		(fp_line
			(start -0.12065 -0.2794)
			(end 0.12065 -0.2794)
			(stroke
				(width 0.1)
				(type default)
			)
			(layer "F.Fab")
		)
		(fp_line
			(start -0.12065 -0.305054)
			(end -0.12065 -0.2794)
			(stroke
				(width 0.1)
				(type default)
			)
			(layer "F.Fab")
		)
		(fp_line
			(start -0.67945 0.3048)
			(end -0.67945 -0.305054)
			(stroke
				(width 0.1)
				(type default)
			)
			(layer "F.Fab")
		)
		(fp_line
			(start -0.67945 -0.305054)
			(end -0.12065 -0.305054)
			(stroke
				(width 0.1)
				(type default)
			)
			(layer "F.Fab")
		)
		(pad "1" smd circle
			(at -0.40005 0 180)
			(size 0 0)
			(layers "F.Cu" "F.Mask" "F.Paste")
			(net "P3V3_SSD9")
		)
		(pad "2" smd circle
			(at 0.40005 0 180)
			(size 0 0)
			(layers "F.Cu" "F.Mask" "F.Paste")
			(net "GND")
		)
	)
	(footprint ""
		(layer "F.Cu")
		(at 52.267866 -54.067456)
		(property "Reference" "PR213"
			(at 0 0 0)
			(layer "F.SilkS")
			(hide yes)
			(effects
				(font
					(size 1.27 1.27)
				)
			)
		)
		(property "Value" ""
			(at 0 0 0)
			(layer "F.Fab")
			(effects
				(font
					(size 1.27 1.27)
				)
			)
		)
		(duplicate_pad_numbers_are_jumpers no)
		(fp_line
			(start -0.7874 -0.4064)
			(end 0.7874 -0.4064)
			(stroke
				(width 0.1524)
				(type default)
			)
			(layer "F.SilkS")
		)
		(fp_line
			(start -0.7874 0.4064)
			(end -0.7874 -0.4064)
			(stroke
				(width 0.1524)
				(type default)
			)
			(layer "F.SilkS")
		)
		(fp_line
			(start 0.7874 -0.4064)
			(end 0.7874 0.4064)
			(stroke
				(width 0.1524)
				(type default)
			)
			(layer "F.SilkS")
		)
		(fp_line
			(start 0.7874 0.4064)
			(end -0.7874 0.4064)
			(stroke
				(width 0.1524)
				(type default)
			)
			(layer "F.SilkS")
		)
		(fp_line
			(start -0.67945 -0.305054)
			(end -0.12065 -0.305054)
			(stroke
				(width 0.1)
				(type default)
			)
			(layer "F.Fab")
		)
		(fp_line
			(start -0.67945 0.3048)
			(end -0.67945 -0.305054)
			(stroke
				(width 0.1)
				(type default)
			)
			(layer "F.Fab")
		)
		(fp_line
			(start -0.12065 -0.305054)
			(end -0.12065 -0.2794)
			(stroke
				(width 0.1)
				(type default)
			)
			(layer "F.Fab")
		)
		(fp_line
			(start -0.12065 -0.2794)
			(end 0.12065 -0.2794)
			(stroke
				(width 0.1)
				(type default)
			)
			(layer "F.Fab")
		)
		(fp_line
			(start -0.12065 0.2794)
			(end -0.12065 0.3048)
			(stroke
				(width 0.1)
				(type default)
			)
			(layer "F.Fab")
		)
		(fp_line
			(start -0.12065 0.3048)
			(end -0.67945 0.3048)
			(stroke
				(width 0.1)
				(type default)
			)
			(layer "F.Fab")
		)
		(fp_line
			(start 0.120396 0.2794)
			(end -0.12065 0.2794)
			(stroke
				(width 0.1)
				(type default)
			)
			(layer "F.Fab")
		)
		(fp_line
			(start 0.120396 0.3048)
			(end 0.120396 0.2794)
			(stroke
				(width 0.1)
				(type default)
			)
			(layer "F.Fab")
		)
		(fp_line
			(start 0.12065 -0.3048)
			(end 0.67945 -0.3048)
			(stroke
				(width 0.1)
				(type default)
			)
			(layer "F.Fab")
		)
		(fp_line
			(start 0.12065 -0.2794)
			(end 0.12065 -0.3048)
			(stroke
				(width 0.1)
				(type default)
			)
			(layer "F.Fab")
		)
		(fp_line
			(start 0.67945 -0.3048)
			(end 0.67945 0.3048)
			(stroke
				(width 0.1)
				(type default)
			)
			(layer "F.Fab")
		)
		(fp_line
			(start 0.67945 0.3048)
			(end 0.120396 0.3048)
			(stroke
				(width 0.1)
				(type default)
			)
			(layer "F.Fab")
		)
		(pad "1" smd circle
			(at -0.40005 0)
			(size 0 0)
			(layers "F.Cu" "F.Mask" "F.Paste")
			(net "P12V_SSD1_OCP")
		)
		(pad "2" smd circle
			(at 0.40005 0)
			(size 0 0)
			(layers "F.Cu" "F.Mask" "F.Paste")
			(net "GND")
		)
	)
	(footprint ""
		(layer "F.Cu")
		(at 369.24742 -21.37156)
		(property "Reference" "C3961"
			(at 0 0 0)
			(layer "F.SilkS")
			(hide yes)
			(effects
				(font
					(size 1.27 1.27)
				)
			)
		)
		(property "Value" ""
			(at 0 0 0)
			(layer "F.Fab")
			(effects
				(font
					(size 1.27 1.27)
				)
			)
		)
		(duplicate_pad_numbers_are_jumpers no)
		(fp_line
			(start -0.7874 -0.4064)
			(end 0.7874 -0.4064)
			(stroke
				(width 0.1524)
				(type default)
			)
			(layer "F.SilkS")
		)
		(fp_line
			(start -0.7874 0.4064)
			(end -0.7874 -0.4064)
			(stroke
				(width 0.1524)
				(type default)
			)
			(layer "F.SilkS")
		)
		(fp_line
			(start 0.7874 -0.4064)
			(end 0.7874 0.4064)
			(stroke
				(width 0.1524)
				(type default)
			)
			(layer "F.SilkS")
		)
		(fp_line
			(start 0.7874 0.4064)
			(end -0.7874 0.4064)
			(stroke
				(width 0.1524)
				(type default)
			)
			(layer "F.SilkS")
		)
		(fp_line
			(start -0.67945 -0.305054)
			(end -0.12065 -0.305054)
			(stroke
				(width 0.1)
				(type default)
			)
			(layer "F.Fab")
		)
		(fp_line
			(start -0.67945 0.3048)
			(end -0.67945 -0.305054)
			(stroke
				(width 0.1)
				(type default)
			)
			(layer "F.Fab")
		)
		(fp_line
			(start -0.12065 -0.305054)
			(end -0.12065 -0.2794)
			(stroke
				(width 0.1)
				(type default)
			)
			(layer "F.Fab")
		)
		(fp_line
			(start -0.12065 -0.2794)
			(end 0.12065 -0.2794)
			(stroke
				(width 0.1)
				(type default)
			)
			(layer "F.Fab")
		)
		(fp_line
			(start -0.12065 0.2794)
			(end -0.12065 0.3048)
			(stroke
				(width 0.1)
				(type default)
			)
			(layer "F.Fab")
		)
		(fp_line
			(start -0.12065 0.3048)
			(end -0.67945 0.3048)
			(stroke
				(width 0.1)
				(type default)
			)
			(layer "F.Fab")
		)
		(fp_line
			(start 0.120396 0.2794)
			(end -0.12065 0.2794)
			(stroke
				(width 0.1)
				(type default)
			)
			(layer "F.Fab")
		)
		(fp_line
			(start 0.120396 0.3048)
			(end 0.120396 0.2794)
			(stroke
				(width 0.1)
				(type default)
			)
			(layer "F.Fab")
		)
		(fp_line
			(start 0.12065 -0.3048)
			(end 0.67945 -0.3048)
			(stroke
				(width 0.1)
				(type default)
			)
			(layer "F.Fab")
		)
		(fp_line
			(start 0.12065 -0.2794)
			(end 0.12065 -0.3048)
			(stroke
				(width 0.1)
				(type default)
			)
			(layer "F.Fab")
		)
		(fp_line
			(start 0.67945 -0.3048)
			(end 0.67945 0.3048)
			(stroke
				(width 0.1)
				(type default)
			)
			(layer "F.Fab")
		)
		(fp_line
			(start 0.67945 0.3048)
			(end 0.120396 0.3048)
			(stroke
				(width 0.1)
				(type default)
			)
			(layer "F.Fab")
		)
		(pad "1" smd circle
			(at -0.40005 0)
			(size 0 0)
			(layers "F.Cu" "F.Mask" "F.Paste")
			(net "P12V_SSD12")
		)
		(pad "2" smd circle
			(at 0.40005 0)
			(size 0 0)
			(layers "F.Cu" "F.Mask" "F.Paste")
			(net "GND")
		)
	)
	(footprint ""
		(layer "F.Cu")
		(at 210.595972 -216.907364 -90)
		(property "Reference" "U89"
			(at 3.997706 0.131318 90)
			(unlocked yes)
			(layer "F.SilkS")
			(effects
				(font
					(size 0.7874 0.5842)
					(thickness 0.1524)
				)
				(justify left)
			)
		)
		(property "Value" ""
			(at 0 0 270)
			(layer "F.Fab")
			(effects
				(font
					(size 1.27 1.27)
				)
			)
		)
		(duplicate_pad_numbers_are_jumpers no)
		(fp_line
			(start -0.8636 1.050036)
			(end 0.8636 1.050036)
			(stroke
				(width 0.1524)
				(type default)
			)
			(layer "F.SilkS")
		)
		(fp_line
			(start 0.8636 1.050036)
			(end 0.8636 -1.050036)
			(stroke
				(width 0.1524)
				(type default)
			)
			(layer "F.SilkS")
		)
		(fp_line
			(start 0 -0.508)
			(end -0.542036 -1.050036)
			(stroke
				(width 0.1524)
				(type default)
			)
			(layer "F.SilkS")
		)
		(fp_line
			(start -0.8636 -1.050036)
			(end -0.8636 1.050036)
			(stroke
				(width 0.1524)
				(type default)
			)
			(layer "F.SilkS")
		)
		(fp_line
			(start -0.542036 -1.050036)
			(end -0.8636 -1.050036)
			(stroke
				(width 0.1524)
				(type default)
			)
			(layer "F.SilkS")
		)
		(fp_line
			(start 0.542036 -1.050036)
			(end 0 -0.508)
			(stroke
				(width 0.1524)
				(type default)
			)
			(layer "F.SilkS")
		)
		(fp_line
			(start 0.8636 -1.050036)
			(end 0.542036 -1.050036)
			(stroke
				(width 0.1524)
				(type default)
			)
			(layer "F.SilkS")
		)
		(fp_poly
			(pts
				(xy -2.794 -1.258062) (xy -2.794 -0.242062) (xy -1.778 -0.750062)
			)
			(stroke
				(width 0)
				(type default)
			)
			(fill yes)
			(layer "F.SilkS")
		)
		(fp_line
			(start -1.199896 1.050036)
			(end 1.199896 1.050036)
			(stroke
				(width 0.1)
				(type default)
			)
			(layer "F.Fab")
		)
		(fp_line
			(start 1.199896 1.050036)
			(end 1.199896 -1.050036)
			(stroke
				(width 0.1)
				(type default)
			)
			(layer "F.Fab")
		)
		(fp_line
			(start -1.199896 -1.050036)
			(end -1.199896 1.050036)
			(stroke
				(width 0.1)
				(type default)
			)
			(layer "F.Fab")
		)
		(fp_line
			(start 1.199896 -1.050036)
			(end -1.199896 -1.050036)
			(stroke
				(width 0.1)
				(type default)
			)
			(layer "F.Fab")
		)
		(fp_poly
			(pts
				(xy -2.794 -1.258062) (xy -2.794 -0.242062) (xy -1.778 -0.750062)
			)
			(stroke
				(width 0)
				(type default)
			)
			(fill yes)
			(layer "F.Fab")
		)
		(pad "1" smd rect
			(at -1.35001 -0.750062 180)
			(size 0.2794 0.7112)
			(layers "F.Cu" "F.Mask" "F.Paste")
			(net "TP_FSA3357K8X_B2_TX")
		)
		(pad "2" smd rect
			(at -1.35001 -0.249936 180)
			(size 0.2794 0.7112)
			(layers "F.Cu" "F.Mask" "F.Paste")
			(net "UART_MB_BIC_TX")
		)
		(pad "3" smd rect
			(at -1.35001 0.249936 180)
			(size 0.2794 0.7112)
			(layers "F.Cu" "F.Mask" "F.Paste")
			(net "UART_FIO_DEBUG_R_TX")
		)
		(pad "4" smd rect
			(at -1.35001 0.750062 180)
			(size 0.2794 0.7112)
			(layers "F.Cu" "F.Mask" "F.Paste")
			(net "GND")
		)
		(pad "5" smd rect
			(at 1.35001 0.750062 180)
			(size 0.2794 0.7112)
			(layers "F.Cu" "F.Mask" "F.Paste")
			(net "BIC_UART_SEL2")
		)
		(pad "6" smd rect
			(at 1.35001 0.249936 180)
			(size 0.2794 0.7112)
			(layers "F.Cu" "F.Mask" "F.Paste")
			(net "BIC_UART_SEL1")
		)
		(pad "7" smd rect
			(at 1.35001 -0.249936 180)
			(size 0.2794 0.7112)
			(layers "F.Cu" "F.Mask" "F.Paste")
			(net "UART_BIC_DEBUG_R_TX")
		)
		(pad "8" smd rect
			(at 1.35001 -0.750062 180)
			(size 0.2794 0.7112)
			(layers "F.Cu" "F.Mask" "F.Paste")
			(net "P3V3_AUX")
		)
	)
	(footprint ""
		(layer "F.Cu")
		(at 81.872074 -32.848042 90)
		(property "Reference" "PC682"
			(at 0 0 90)
			(layer "F.SilkS")
			(hide yes)
			(effects
				(font
					(size 1.27 1.27)
				)
			)
		)
		(property "Value" ""
			(at 0 0 90)
			(layer "F.Fab")
			(effects
				(font
					(size 1.27 1.27)
				)
			)
		)
		(duplicate_pad_numbers_are_jumpers no)
		(fp_line
			(start 0.7874 -0.4064)
			(end 0.7874 0.4064)
			(stroke
				(width 0.1524)
				(type default)
			)
			(layer "F.SilkS")
		)
		(fp_line
			(start -0.7874 -0.4064)
			(end 0.7874 -0.4064)
			(stroke
				(width 0.1524)
				(type default)
			)
			(layer "F.SilkS")
		)
		(fp_line
			(start 0.7874 0.4064)
			(end -0.7874 0.4064)
			(stroke
				(width 0.1524)
				(type default)
			)
			(layer "F.SilkS")
		)
		(fp_line
			(start -0.7874 0.4064)
			(end -0.7874 -0.4064)
			(stroke
				(width 0.1524)
				(type default)
			)
			(layer "F.SilkS")
		)
		(fp_line
			(start -0.12065 -0.305054)
			(end -0.12065 -0.2794)
			(stroke
				(width 0.1)
				(type default)
			)
			(layer "F.Fab")
		)
		(fp_line
			(start -0.67945 -0.305054)
			(end -0.12065 -0.305054)
			(stroke
				(width 0.1)
				(type default)
			)
			(layer "F.Fab")
		)
		(fp_line
			(start 0.67945 -0.3048)
			(end 0.67945 0.3048)
			(stroke
				(width 0.1)
				(type default)
			)
			(layer "F.Fab")
		)
		(fp_line
			(start 0.12065 -0.3048)
			(end 0.67945 -0.3048)
			(stroke
				(width 0.1)
				(type default)
			)
			(layer "F.Fab")
		)
		(fp_line
			(start 0.12065 -0.2794)
			(end 0.12065 -0.3048)
			(stroke
				(width 0.1)
				(type default)
			)
			(layer "F.Fab")
		)
		(fp_line
			(start -0.12065 -0.2794)
			(end 0.12065 -0.2794)
			(stroke
				(width 0.1)
				(type default)
			)
			(layer "F.Fab")
		)
		(fp_line
			(start 0.120396 0.2794)
			(end -0.12065 0.2794)
			(stroke
				(width 0.1)
				(type default)
			)
			(layer "F.Fab")
		)
		(fp_line
			(start -0.12065 0.2794)
			(end -0.12065 0.3048)
			(stroke
				(width 0.1)
				(type default)
			)
			(layer "F.Fab")
		)
		(fp_line
			(start 0.67945 0.3048)
			(end 0.120396 0.3048)
			(stroke
				(width 0.1)
				(type default)
			)
			(layer "F.Fab")
		)
		(fp_line
			(start 0.120396 0.3048)
			(end 0.120396 0.2794)
			(stroke
				(width 0.1)
				(type default)
			)
			(layer "F.Fab")
		)
		(fp_line
			(start -0.12065 0.3048)
			(end -0.67945 0.3048)
			(stroke
				(width 0.1)
				(type default)
			)
			(layer "F.Fab")
		)
		(fp_line
			(start -0.67945 0.3048)
			(end -0.67945 -0.305054)
			(stroke
				(width 0.1)
				(type default)
			)
			(layer "F.Fab")
		)
		(pad "1" smd circle
			(at -0.40005 0 90)
			(size 0 0)
			(layers "F.Cu" "F.Mask" "F.Paste")
			(net "P3V3_SSD3_CO_GATE")
		)
		(pad "2" smd circle
			(at 0.40005 0 90)
			(size 0 0)
			(layers "F.Cu" "F.Mask" "F.Paste")
			(net "GND")
		)
	)
	(footprint ""
		(layer "F.Cu")
		(at 213.598506 -66.32194 -90)
		(property "Reference" "PC851"
			(at 0 0 270)
			(layer "F.SilkS")
			(hide yes)
			(effects
				(font
					(size 1.27 1.27)
				)
			)
		)
		(property "Value" ""
			(at 0 0 270)
			(layer "F.Fab")
			(effects
				(font
					(size 1.27 1.27)
				)
			)
		)
		(duplicate_pad_numbers_are_jumpers no)
		(fp_line
			(start -0.7874 0.4064)
			(end -0.7874 -0.4064)
			(stroke
				(width 0.1524)
				(type default)
			)
			(layer "F.SilkS")
		)
		(fp_line
			(start 0.7874 0.4064)
			(end -0.7874 0.4064)
			(stroke
				(width 0.1524)
				(type default)
			)
			(layer "F.SilkS")
		)
		(fp_line
			(start -0.7874 -0.4064)
			(end 0.7874 -0.4064)
			(stroke
				(width 0.1524)
				(type default)
			)
			(layer "F.SilkS")
		)
		(fp_line
			(start 0.7874 -0.4064)
			(end 0.7874 0.4064)
			(stroke
				(width 0.1524)
				(type default)
			)
			(layer "F.SilkS")
		)
		(fp_line
			(start -0.67945 0.3048)
			(end -0.67945 -0.305054)
			(stroke
				(width 0.1)
				(type default)
			)
			(layer "F.Fab")
		)
		(fp_line
			(start -0.12065 0.3048)
			(end -0.67945 0.3048)
			(stroke
				(width 0.1)
				(type default)
			)
			(layer "F.Fab")
		)
		(fp_line
			(start 0.120396 0.3048)
			(end 0.120396 0.2794)
			(stroke
				(width 0.1)
				(type default)
			)
			(layer "F.Fab")
		)
		(fp_line
			(start 0.67945 0.3048)
			(end 0.120396 0.3048)
			(stroke
				(width 0.1)
				(type default)
			)
			(layer "F.Fab")
		)
		(fp_line
			(start -0.12065 0.2794)
			(end -0.12065 0.3048)
			(stroke
				(width 0.1)
				(type default)
			)
			(layer "F.Fab")
		)
		(fp_line
			(start 0.120396 0.2794)
			(end -0.12065 0.2794)
			(stroke
				(width 0.1)
				(type default)
			)
			(layer "F.Fab")
		)
		(fp_line
			(start -0.12065 -0.2794)
			(end 0.12065 -0.2794)
			(stroke
				(width 0.1)
				(type default)
			)
			(layer "F.Fab")
		)
		(fp_line
			(start 0.12065 -0.2794)
			(end 0.12065 -0.3048)
			(stroke
				(width 0.1)
				(type default)
			)
			(layer "F.Fab")
		)
		(fp_line
			(start 0.12065 -0.3048)
			(end 0.67945 -0.3048)
			(stroke
				(width 0.1)
				(type default)
			)
			(layer "F.Fab")
		)
		(fp_line
			(start 0.67945 -0.3048)
			(end 0.67945 0.3048)
			(stroke
				(width 0.1)
				(type default)
			)
			(layer "F.Fab")
		)
		(fp_line
			(start -0.67945 -0.305054)
			(end -0.12065 -0.305054)
			(stroke
				(width 0.1)
				(type default)
			)
			(layer "F.Fab")
		)
		(fp_line
			(start -0.12065 -0.305054)
			(end -0.12065 -0.2794)
			(stroke
				(width 0.1)
				(type default)
			)
			(layer "F.Fab")
		)
		(pad "1" smd circle
			(at -0.40005 0 270)
			(size 0 0)
			(layers "F.Cu" "F.Mask" "F.Paste")
			(net "P12V_SSD7_CO_GATE")
		)
		(pad "2" smd circle
			(at 0.40005 0 270)
			(size 0 0)
			(layers "F.Cu" "F.Mask" "F.Paste")
			(net "GND")
		)
	)
	(footprint ""
		(layer "F.Cu")
		(at 396.947136 -54.3941)
		(property "Reference" "PU41"
			(at -1.670812 3.085592 0)
			(unlocked yes)
			(layer "F.SilkS")
			(effects
				(font
					(size 0.7874 0.5842)
					(thickness 0.1524)
				)
				(justify left)
			)
		)
		(property "Value" ""
			(at 0 0 0)
			(layer "F.Fab")
			(effects
				(font
					(size 1.27 1.27)
				)
			)
		)
		(duplicate_pad_numbers_are_jumpers no)
		(fp_line
			(start -1.943608 -1.549908)
			(end 1.943608 -1.549908)
			(stroke
				(width 0.1524)
				(type default)
			)
			(layer "F.SilkS")
		)
		(fp_line
			(start -1.943608 1.549908)
			(end -1.943608 -1.549908)
			(stroke
				(width 0.1524)
				(type default)
			)
			(layer "F.SilkS")
		)
		(fp_line
			(start 1.943608 -1.549908)
			(end 1.943608 1.549908)
			(stroke
				(width 0.1524)
				(type default)
			)
			(layer "F.SilkS")
		)
		(fp_line
			(start 1.943608 1.549908)
			(end -1.943608 1.549908)
			(stroke
				(width 0.1524)
				(type default)
			)
			(layer "F.SilkS")
		)
		(fp_poly
			(pts
				(xy -2.019808 -1.549908) (xy -1.257808 -1.549908) (xy -1.257808 -1.880108) (xy -2.019808 -1.880108)
			)
			(stroke
				(width 0)
				(type default)
			)
			(fill yes)
			(layer "F.SilkS")
		)
		(fp_line
			(start -1.549908 -1.549908)
			(end 1.549908 -1.549908)
			(stroke
				(width 0.1)
				(type default)
			)
			(layer "F.Fab")
		)
		(fp_line
			(start -1.549908 1.549908)
			(end -1.549908 -1.549908)
			(stroke
				(width 0.1)
				(type default)
			)
			(layer "F.Fab")
		)
		(fp_line
			(start 1.549908 -1.549908)
			(end 1.549908 1.549908)
			(stroke
				(width 0.1)
				(type default)
			)
			(layer "F.Fab")
		)
		(fp_line
			(start 1.549908 1.549908)
			(end -1.549908 1.549908)
			(stroke
				(width 0.1)
				(type default)
			)
			(layer "F.Fab")
		)
		(fp_poly
			(pts
				(xy -2.019808 -1.549908) (xy -1.257808 -1.549908) (xy -1.257808 -1.880108) (xy -2.019808 -1.880108)
			)
			(stroke
				(width 0)
				(type default)
			)
			(fill yes)
			(layer "F.Fab")
		)
		(pad "1" smd rect
			(at -1.500124 -1.249934 270)
			(size 0.2794 0.6096)
			(layers "F.Cu" "F.Mask" "F.Paste")
			(net "P12V_SSD13_R")
		)
		(pad "2" smd rect
			(at -1.500124 -0.750062 270)
			(size 0.2794 0.6096)
			(layers "F.Cu" "F.Mask" "F.Paste")
			(net "P12V_SSD13_R")
		)
		(pad "3" smd rect
			(at -1.500124 -0.249936 270)
			(size 0.2794 0.6096)
			(layers "F.Cu" "F.Mask" "F.Paste")
			(net "P12V_SSD13_R")
		)
		(pad "4" smd rect
			(at -1.500124 0.249936 270)
			(size 0.2794 0.6096)
			(layers "F.Cu" "F.Mask" "F.Paste")
			(net "P12V_SSD13_R")
		)
		(pad "5" smd rect
			(at -1.500124 0.750062 270)
			(size 0.2794 0.6096)
			(layers "F.Cu" "F.Mask" "F.Paste")
			(net "P12V_SSD13_R")
		)
		(pad "6" smd rect
			(at -1.500124 1.249934 270)
			(size 0.2794 0.6096)
			(layers "F.Cu" "F.Mask" "F.Paste")
			(net "GND")
		)
		(pad "7" smd rect
			(at 1.500124 1.249934 270)
			(size 0.2794 0.6096)
			(layers "F.Cu" "F.Mask" "F.Paste")
			(net "P12V_SSD13_SS")
		)
		(pad "8" smd rect
			(at 1.500124 0.750062 270)
			(size 0.2794 0.6096)
			(layers "F.Cu" "F.Mask" "F.Paste")
			(net "PWRGD_P12V_SSD13")
		)
		(pad "9" smd rect
			(at 1.500124 0.249936 270)
			(size 0.2794 0.6096)
			(layers "F.Cu" "F.Mask" "F.Paste")
			(net "P12V_SSD13_OCP")
		)
		(pad "10" smd rect
			(at 1.500124 -0.249936 270)
			(size 0.2794 0.6096)
			(layers "F.Cu" "F.Mask" "F.Paste")
			(net "P5V_AUX")
		)
		(pad "11" smd rect
			(at 1.500124 -0.750062 270)
			(size 0.2794 0.6096)
			(layers "F.Cu" "F.Mask" "F.Paste")
			(net "SSD13_PWR_EN_R")
		)
		(pad "12" smd rect
			(at 1.500124 -1.249934 270)
			(size 0.2794 0.6096)
			(layers "F.Cu" "F.Mask" "F.Paste")
			(net "P12V_AUX")
		)
		(pad "13" smd rect
			(at 0 0)
			(size 1.9812 2.7178)
			(layers "F.Cu" "F.Mask" "F.Paste")
			(net "P12V_AUX")
		)
		(zone
			(layer "F.Cu")
			(hatch none 0.5)
			(connect_pads
				(clearance 0)
			)
			(min_thickness 0.25)
			(keepout
				(tracks not_allowed)
				(vias allowed)
				(pads allowed)
				(copperpour not_allowed)
				(footprints allowed)
			)
			(placement
				(enabled no)
				(sheetname "")
			)
			(fill
				(thermal_gap 0.5)
				(thermal_bridge_width 0.5)
				(island_removal_mode 0)
			)
			(polygon
				(pts
					(xy 398.090136 -55.9435) (xy 398.090136 -55.8165) (xy 398.090136 -52.8447) (xy 398.090136 -52.844192)
					(xy 395.804136 -52.844192) (xy 395.804136 -52.8447) (xy 395.804136 -52.9717) (xy 395.804136 -54.3941)
					(xy 395.905736 -54.3941) (xy 395.905736 -52.9717) (xy 397.988536 -52.9717) (xy 397.988536 -55.8165)
					(xy 395.905736 -55.8165) (xy 395.905736 -54.4195) (xy 395.804136 -54.4195) (xy 395.804136 -55.8165)
					(xy 395.804136 -55.9435) (xy 395.804136 -55.944008) (xy 398.090136 -55.944008)
				)
			)
		)
	)
	(footprint ""
		(layer "F.Cu")
		(at 262.353298 -300.992032)
		(property "Reference" "L121"
			(at 0 0 0)
			(layer "F.SilkS")
			(hide yes)
			(effects
				(font
					(size 1.27 1.27)
				)
			)
		)
		(property "Value" ""
			(at 0 0 0)
			(layer "F.Fab")
			(effects
				(font
					(size 1.27 1.27)
				)
			)
		)
		(duplicate_pad_numbers_are_jumpers no)
		(fp_line
			(start -1.63576 -0.8128)
			(end -1.63576 0.8128)
			(stroke
				(width 0.1524)
				(type default)
			)
			(layer "F.SilkS")
		)
		(fp_line
			(start -1.63576 -0.8128)
			(end 1.63576 -0.8128)
			(stroke
				(width 0.1524)
				(type default)
			)
			(layer "F.SilkS")
		)
		(fp_line
			(start 1.63576 -0.8128)
			(end 1.63576 0.8128)
			(stroke
				(width 0.1524)
				(type default)
			)
			(layer "F.SilkS")
		)
		(fp_line
			(start 1.63576 0.8128)
			(end -1.63576 0.8128)
			(stroke
				(width 0.1524)
				(type default)
			)
			(layer "F.SilkS")
		)
		(fp_line
			(start -1.56083 -0.738632)
			(end -1.56083 0.7366)
			(stroke
				(width 0.1)
				(type default)
			)
			(layer "F.Fab")
		)
		(fp_line
			(start -1.56083 0.7366)
			(end -1.524 0.7366)
			(stroke
				(width 0.1)
				(type default)
			)
			(layer "F.Fab")
		)
		(fp_line
			(start -1.524 0.7366)
			(end 1.524 0.7366)
			(stroke
				(width 0.1)
				(type default)
			)
			(layer "F.Fab")
		)
		(fp_line
			(start 1.524 0.7366)
			(end 1.560576 0.7366)
			(stroke
				(width 0.1)
				(type default)
			)
			(layer "F.Fab")
		)
		(fp_line
			(start 1.560576 -0.738632)
			(end -1.56083 -0.738632)
			(stroke
				(width 0.1)
				(type default)
			)
			(layer "F.Fab")
		)
		(fp_line
			(start 1.560576 0.7366)
			(end 1.560576 -0.738632)
			(stroke
				(width 0.1)
				(type default)
			)
			(layer "F.Fab")
		)
		(pad "1" smd rect
			(at -0.94996 0 180)
			(size 1.1176 1.3716)
			(layers "F.Cu" "F.Mask" "F.Paste")
			(net "P1V8_PLL0_PEX2")
		)
		(pad "2" smd rect
			(at 0.94996 0 180)
			(size 1.1176 1.3716)
			(layers "F.Cu" "F.Mask" "F.Paste")
			(net "PCEPLL1_VDDA18_PEX2")
		)
	)
	(footprint ""
		(layer "F.Cu")
		(at 169.759884 -197.900798)
		(property "Reference" "R3288"
			(at 0 0 0)
			(layer "F.SilkS")
			(hide yes)
			(effects
				(font
					(size 1.27 1.27)
				)
			)
		)
		(property "Value" ""
			(at 0 0 0)
			(layer "F.Fab")
			(effects
				(font
					(size 1.27 1.27)
				)
			)
		)
		(duplicate_pad_numbers_are_jumpers no)
		(fp_line
			(start -0.7874 -0.4064)
			(end 0.7874 -0.4064)
			(stroke
				(width 0.1524)
				(type default)
			)
			(layer "F.SilkS")
		)
		(fp_line
			(start -0.7874 0.4064)
			(end -0.7874 -0.4064)
			(stroke
				(width 0.1524)
				(type default)
			)
			(layer "F.SilkS")
		)
		(fp_line
			(start 0.7874 -0.4064)
			(end 0.7874 0.4064)
			(stroke
				(width 0.1524)
				(type default)
			)
			(layer "F.SilkS")
		)
		(fp_line
			(start 0.7874 0.4064)
			(end -0.7874 0.4064)
			(stroke
				(width 0.1524)
				(type default)
			)
			(layer "F.SilkS")
		)
		(fp_line
			(start -0.67945 -0.305054)
			(end -0.12065 -0.305054)
			(stroke
				(width 0.1)
				(type default)
			)
			(layer "F.Fab")
		)
		(fp_line
			(start -0.67945 0.3048)
			(end -0.67945 -0.305054)
			(stroke
				(width 0.1)
				(type default)
			)
			(layer "F.Fab")
		)
		(fp_line
			(start -0.12065 -0.305054)
			(end -0.12065 -0.2794)
			(stroke
				(width 0.1)
				(type default)
			)
			(layer "F.Fab")
		)
		(fp_line
			(start -0.12065 -0.2794)
			(end 0.12065 -0.2794)
			(stroke
				(width 0.1)
				(type default)
			)
			(layer "F.Fab")
		)
		(fp_line
			(start -0.12065 0.2794)
			(end -0.12065 0.3048)
			(stroke
				(width 0.1)
				(type default)
			)
			(layer "F.Fab")
		)
		(fp_line
			(start -0.12065 0.3048)
			(end -0.67945 0.3048)
			(stroke
				(width 0.1)
				(type default)
			)
			(layer "F.Fab")
		)
		(fp_line
			(start 0.120396 0.2794)
			(end -0.12065 0.2794)
			(stroke
				(width 0.1)
				(type default)
			)
			(layer "F.Fab")
		)
		(fp_line
			(start 0.120396 0.3048)
			(end 0.120396 0.2794)
			(stroke
				(width 0.1)
				(type default)
			)
			(layer "F.Fab")
		)
		(fp_line
			(start 0.12065 -0.3048)
			(end 0.67945 -0.3048)
			(stroke
				(width 0.1)
				(type default)
			)
			(layer "F.Fab")
		)
		(fp_line
			(start 0.12065 -0.2794)
			(end 0.12065 -0.3048)
			(stroke
				(width 0.1)
				(type default)
			)
			(layer "F.Fab")
		)
		(fp_line
			(start 0.67945 -0.3048)
			(end 0.67945 0.3048)
			(stroke
				(width 0.1)
				(type default)
			)
			(layer "F.Fab")
		)
		(fp_line
			(start 0.67945 0.3048)
			(end 0.120396 0.3048)
			(stroke
				(width 0.1)
				(type default)
			)
			(layer "F.Fab")
		)
		(pad "1" smd circle
			(at -0.40005 0)
			(size 0 0)
			(layers "F.Cu" "F.Mask" "F.Paste")
			(net "SPI_BIC1_CLK_LS01_R")
		)
		(pad "2" smd circle
			(at 0.40005 0)
			(size 0 0)
			(layers "F.Cu" "F.Mask" "F.Paste")
			(net "SPI_BIC1_CLK_LS01")
		)
	)
	(footprint ""
		(layer "F.Cu")
		(at 296.766742 -356.244906 90)
		(property "Reference" "C586"
			(at 0 0 90)
			(layer "F.SilkS")
			(hide yes)
			(effects
				(font
					(size 1.27 1.27)
				)
			)
		)
		(property "Value" ""
			(at 0 0 90)
			(layer "F.Fab")
			(effects
				(font
					(size 1.27 1.27)
				)
			)
		)
		(duplicate_pad_numbers_are_jumpers no)
		(fp_line
			(start 0.299974 -0.150114)
			(end 0.299974 0.150114)
			(stroke
				(width 0.1)
				(type default)
			)
			(layer "F.Fab")
		)
		(fp_line
			(start -0.299974 -0.150114)
			(end 0.299974 -0.150114)
			(stroke
				(width 0.1)
				(type default)
			)
			(layer "F.Fab")
		)
		(fp_line
			(start 0.299974 0.150114)
			(end -0.299974 0.150114)
			(stroke
				(width 0.1)
				(type default)
			)
			(layer "F.Fab")
		)
		(fp_line
			(start -0.299974 0.150114)
			(end -0.299974 -0.150114)
			(stroke
				(width 0.1)
				(type default)
			)
			(layer "F.Fab")
		)
		(pad "1" smd rect
			(at -0.2667 0 90)
			(size 0.3048 0.381)
			(layers "F.Cu" "F.Mask" "F.Paste")
			(net "P5E_PEX2_STN7_TX_DN<126>")
		)
		(pad "2" smd rect
			(at 0.2667 0 90)
			(size 0.3048 0.381)
			(layers "F.Cu" "F.Mask" "F.Paste")
			(net "P5E_PEX2_STN7_TX_C_DN<126>")
		)
	)
	(footprint ""
		(layer "F.Cu")
		(at 105.27157 -280.44902 -90)
		(property "Reference" "PR100"
			(at 0 0 270)
			(layer "F.SilkS")
			(hide yes)
			(effects
				(font
					(size 1.27 1.27)
				)
			)
		)
		(property "Value" ""
			(at 0 0 270)
			(layer "F.Fab")
			(effects
				(font
					(size 1.27 1.27)
				)
			)
		)
		(duplicate_pad_numbers_are_jumpers no)
		(fp_line
			(start -0.7874 0.4064)
			(end -0.7874 -0.4064)
			(stroke
				(width 0.1524)
				(type default)
			)
			(layer "F.SilkS")
		)
		(fp_line
			(start 0.7874 0.4064)
			(end -0.7874 0.4064)
			(stroke
				(width 0.1524)
				(type default)
			)
			(layer "F.SilkS")
		)
		(fp_line
			(start -0.7874 -0.4064)
			(end 0.7874 -0.4064)
			(stroke
				(width 0.1524)
				(type default)
			)
			(layer "F.SilkS")
		)
		(fp_line
			(start 0.7874 -0.4064)
			(end 0.7874 0.4064)
			(stroke
				(width 0.1524)
				(type default)
			)
			(layer "F.SilkS")
		)
		(fp_line
			(start -0.67945 0.3048)
			(end -0.67945 -0.305054)
			(stroke
				(width 0.1)
				(type default)
			)
			(layer "F.Fab")
		)
		(fp_line
			(start -0.12065 0.3048)
			(end -0.67945 0.3048)
			(stroke
				(width 0.1)
				(type default)
			)
			(layer "F.Fab")
		)
		(fp_line
			(start 0.120396 0.3048)
			(end 0.120396 0.2794)
			(stroke
				(width 0.1)
				(type default)
			)
			(layer "F.Fab")
		)
		(fp_line
			(start 0.67945 0.3048)
			(end 0.120396 0.3048)
			(stroke
				(width 0.1)
				(type default)
			)
			(layer "F.Fab")
		)
		(fp_line
			(start -0.12065 0.2794)
			(end -0.12065 0.3048)
			(stroke
				(width 0.1)
				(type default)
			)
			(layer "F.Fab")
		)
		(fp_line
			(start 0.120396 0.2794)
			(end -0.12065 0.2794)
			(stroke
				(width 0.1)
				(type default)
			)
			(layer "F.Fab")
		)
		(fp_line
			(start -0.12065 -0.2794)
			(end 0.12065 -0.2794)
			(stroke
				(width 0.1)
				(type default)
			)
			(layer "F.Fab")
		)
		(fp_line
			(start 0.12065 -0.2794)
			(end 0.12065 -0.3048)
			(stroke
				(width 0.1)
				(type default)
			)
			(layer "F.Fab")
		)
		(fp_line
			(start 0.12065 -0.3048)
			(end 0.67945 -0.3048)
			(stroke
				(width 0.1)
				(type default)
			)
			(layer "F.Fab")
		)
		(fp_line
			(start 0.67945 -0.3048)
			(end 0.67945 0.3048)
			(stroke
				(width 0.1)
				(type default)
			)
			(layer "F.Fab")
		)
		(fp_line
			(start -0.67945 -0.305054)
			(end -0.12065 -0.305054)
			(stroke
				(width 0.1)
				(type default)
			)
			(layer "F.Fab")
		)
		(fp_line
			(start -0.12065 -0.305054)
			(end -0.12065 -0.2794)
			(stroke
				(width 0.1)
				(type default)
			)
			(layer "F.Fab")
		)
		(pad "1" smd circle
			(at -0.40005 0 270)
			(size 0 0)
			(layers "F.Cu" "F.Mask" "F.Paste")
			(net "SW_P0V8_PEX0_BOOT1")
		)
		(pad "2" smd circle
			(at 0.40005 0 270)
			(size 0 0)
			(layers "F.Cu" "F.Mask" "F.Paste")
			(net "SW_P0V8_PEX0_BOOT1_R")
		)
	)
	(footprint ""
		(layer "F.Cu")
		(at 264.517632 -113.558574 -90)
		(property "Reference" "C4002"
			(at 0 0 270)
			(layer "F.SilkS")
			(hide yes)
			(effects
				(font
					(size 1.27 1.27)
				)
			)
		)
		(property "Value" ""
			(at 0 0 270)
			(layer "F.Fab")
			(effects
				(font
					(size 1.27 1.27)
				)
			)
		)
		(duplicate_pad_numbers_are_jumpers no)
		(fp_line
			(start -0.7874 0.4064)
			(end -0.7874 -0.4064)
			(stroke
				(width 0.1524)
				(type default)
			)
			(layer "F.SilkS")
		)
		(fp_line
			(start 0.7874 0.4064)
			(end -0.7874 0.4064)
			(stroke
				(width 0.1524)
				(type default)
			)
			(layer "F.SilkS")
		)
		(fp_line
			(start -0.7874 -0.4064)
			(end 0.7874 -0.4064)
			(stroke
				(width 0.1524)
				(type default)
			)
			(layer "F.SilkS")
		)
		(fp_line
			(start 0.7874 -0.4064)
			(end 0.7874 0.4064)
			(stroke
				(width 0.1524)
				(type default)
			)
			(layer "F.SilkS")
		)
		(fp_line
			(start -0.67945 0.3048)
			(end -0.67945 -0.305054)
			(stroke
				(width 0.1)
				(type default)
			)
			(layer "F.Fab")
		)
		(fp_line
			(start -0.12065 0.3048)
			(end -0.67945 0.3048)
			(stroke
				(width 0.1)
				(type default)
			)
			(layer "F.Fab")
		)
		(fp_line
			(start 0.120396 0.3048)
			(end 0.120396 0.2794)
			(stroke
				(width 0.1)
				(type default)
			)
			(layer "F.Fab")
		)
		(fp_line
			(start 0.67945 0.3048)
			(end 0.120396 0.3048)
			(stroke
				(width 0.1)
				(type default)
			)
			(layer "F.Fab")
		)
		(fp_line
			(start -0.12065 0.2794)
			(end -0.12065 0.3048)
			(stroke
				(width 0.1)
				(type default)
			)
			(layer "F.Fab")
		)
		(fp_line
			(start 0.120396 0.2794)
			(end -0.12065 0.2794)
			(stroke
				(width 0.1)
				(type default)
			)
			(layer "F.Fab")
		)
		(fp_line
			(start -0.12065 -0.2794)
			(end 0.12065 -0.2794)
			(stroke
				(width 0.1)
				(type default)
			)
			(layer "F.Fab")
		)
		(fp_line
			(start 0.12065 -0.2794)
			(end 0.12065 -0.3048)
			(stroke
				(width 0.1)
				(type default)
			)
			(layer "F.Fab")
		)
		(fp_line
			(start 0.12065 -0.3048)
			(end 0.67945 -0.3048)
			(stroke
				(width 0.1)
				(type default)
			)
			(layer "F.Fab")
		)
		(fp_line
			(start 0.67945 -0.3048)
			(end 0.67945 0.3048)
			(stroke
				(width 0.1)
				(type default)
			)
			(layer "F.Fab")
		)
		(fp_line
			(start -0.67945 -0.305054)
			(end -0.12065 -0.305054)
			(stroke
				(width 0.1)
				(type default)
			)
			(layer "F.Fab")
		)
		(fp_line
			(start -0.12065 -0.305054)
			(end -0.12065 -0.2794)
			(stroke
				(width 0.1)
				(type default)
			)
			(layer "F.Fab")
		)
		(pad "1" smd circle
			(at -0.40005 0 270)
			(size 0 0)
			(layers "F.Cu" "F.Mask" "F.Paste")
			(net "PRSNT_NIC4_R_N")
		)
		(pad "2" smd circle
			(at 0.40005 0 270)
			(size 0 0)
			(layers "F.Cu" "F.Mask" "F.Paste")
			(net "GND")
		)
	)
	(footprint ""
		(layer "F.Cu")
		(at 366.955578 -88.356694 180)
		(property "Reference" "R1628"
			(at 0 0 180)
			(layer "F.SilkS")
			(hide yes)
			(effects
				(font
					(size 1.27 1.27)
				)
			)
		)
		(property "Value" ""
			(at 0 0 180)
			(layer "F.Fab")
			(effects
				(font
					(size 1.27 1.27)
				)
			)
		)
		(duplicate_pad_numbers_are_jumpers no)
		(fp_line
			(start 0.7874 0.4064)
			(end -0.7874 0.4064)
			(stroke
				(width 0.1524)
				(type default)
			)
			(layer "F.SilkS")
		)
		(fp_line
			(start 0.7874 -0.4064)
			(end 0.7874 0.4064)
			(stroke
				(width 0.1524)
				(type default)
			)
			(layer "F.SilkS")
		)
		(fp_line
			(start -0.7874 0.4064)
			(end -0.7874 -0.4064)
			(stroke
				(width 0.1524)
				(type default)
			)
			(layer "F.SilkS")
		)
		(fp_line
			(start -0.7874 -0.4064)
			(end 0.7874 -0.4064)
			(stroke
				(width 0.1524)
				(type default)
			)
			(layer "F.SilkS")
		)
		(fp_line
			(start 0.67945 0.3048)
			(end 0.120396 0.3048)
			(stroke
				(width 0.1)
				(type default)
			)
			(layer "F.Fab")
		)
		(fp_line
			(start 0.67945 -0.3048)
			(end 0.67945 0.3048)
			(stroke
				(width 0.1)
				(type default)
			)
			(layer "F.Fab")
		)
		(fp_line
			(start 0.12065 -0.2794)
			(end 0.12065 -0.3048)
			(stroke
				(width 0.1)
				(type default)
			)
			(layer "F.Fab")
		)
		(fp_line
			(start 0.12065 -0.3048)
			(end 0.67945 -0.3048)
			(stroke
				(width 0.1)
				(type default)
			)
			(layer "F.Fab")
		)
		(fp_line
			(start 0.120396 0.3048)
			(end 0.120396 0.2794)
			(stroke
				(width 0.1)
				(type default)
			)
			(layer "F.Fab")
		)
		(fp_line
			(start 0.120396 0.2794)
			(end -0.12065 0.2794)
			(stroke
				(width 0.1)
				(type default)
			)
			(layer "F.Fab")
		)
		(fp_line
			(start -0.12065 0.3048)
			(end -0.67945 0.3048)
			(stroke
				(width 0.1)
				(type default)
			)
			(layer "F.Fab")
		)
		(fp_line
			(start -0.12065 0.2794)
			(end -0.12065 0.3048)
			(stroke
				(width 0.1)
				(type default)
			)
			(layer "F.Fab")
		)
		(fp_line
			(start -0.12065 -0.2794)
			(end 0.12065 -0.2794)
			(stroke
				(width 0.1)
				(type default)
			)
			(layer "F.Fab")
		)
		(fp_line
			(start -0.12065 -0.305054)
			(end -0.12065 -0.2794)
			(stroke
				(width 0.1)
				(type default)
			)
			(layer "F.Fab")
		)
		(fp_line
			(start -0.67945 0.3048)
			(end -0.67945 -0.305054)
			(stroke
				(width 0.1)
				(type default)
			)
			(layer "F.Fab")
		)
		(fp_line
			(start -0.67945 -0.305054)
			(end -0.12065 -0.305054)
			(stroke
				(width 0.1)
				(type default)
			)
			(layer "F.Fab")
		)
		(pad "1" smd circle
			(at -0.40005 0 180)
			(size 0 0)
			(layers "F.Cu" "F.Mask" "F.Paste")
			(net "SMB_BIC_I2C9_MUX1_SSD15_R_SDA")
		)
		(pad "2" smd circle
			(at 0.40005 0 180)
			(size 0 0)
			(layers "F.Cu" "F.Mask" "F.Paste")
			(net "SMB_BIC_I2C9_MUX1_SSD15_SDA")
		)
	)
	(footprint ""
		(layer "F.Cu")
		(at 225.530664 -207.02016 90)
		(property "Reference" "R5278"
			(at 0 0 90)
			(layer "F.SilkS")
			(hide yes)
			(effects
				(font
					(size 1.27 1.27)
				)
			)
		)
		(property "Value" ""
			(at 0 0 90)
			(layer "F.Fab")
			(effects
				(font
					(size 1.27 1.27)
				)
			)
		)
		(duplicate_pad_numbers_are_jumpers no)
		(fp_line
			(start 0.7874 -0.4064)
			(end 0.7874 0.4064)
			(stroke
				(width 0.1524)
				(type default)
			)
			(layer "F.SilkS")
		)
		(fp_line
			(start -0.7874 -0.4064)
			(end 0.7874 -0.4064)
			(stroke
				(width 0.1524)
				(type default)
			)
			(layer "F.SilkS")
		)
		(fp_line
			(start 0.7874 0.4064)
			(end -0.7874 0.4064)
			(stroke
				(width 0.1524)
				(type default)
			)
			(layer "F.SilkS")
		)
		(fp_line
			(start -0.7874 0.4064)
			(end -0.7874 -0.4064)
			(stroke
				(width 0.1524)
				(type default)
			)
			(layer "F.SilkS")
		)
		(fp_line
			(start -0.12065 -0.305054)
			(end -0.12065 -0.2794)
			(stroke
				(width 0.1)
				(type default)
			)
			(layer "F.Fab")
		)
		(fp_line
			(start -0.67945 -0.305054)
			(end -0.12065 -0.305054)
			(stroke
				(width 0.1)
				(type default)
			)
			(layer "F.Fab")
		)
		(fp_line
			(start 0.67945 -0.3048)
			(end 0.67945 0.3048)
			(stroke
				(width 0.1)
				(type default)
			)
			(layer "F.Fab")
		)
		(fp_line
			(start 0.12065 -0.3048)
			(end 0.67945 -0.3048)
			(stroke
				(width 0.1)
				(type default)
			)
			(layer "F.Fab")
		)
		(fp_line
			(start 0.12065 -0.2794)
			(end 0.12065 -0.3048)
			(stroke
				(width 0.1)
				(type default)
			)
			(layer "F.Fab")
		)
		(fp_line
			(start -0.12065 -0.2794)
			(end 0.12065 -0.2794)
			(stroke
				(width 0.1)
				(type default)
			)
			(layer "F.Fab")
		)
		(fp_line
			(start 0.120396 0.2794)
			(end -0.12065 0.2794)
			(stroke
				(width 0.1)
				(type default)
			)
			(layer "F.Fab")
		)
		(fp_line
			(start -0.12065 0.2794)
			(end -0.12065 0.3048)
			(stroke
				(width 0.1)
				(type default)
			)
			(layer "F.Fab")
		)
		(fp_line
			(start 0.67945 0.3048)
			(end 0.120396 0.3048)
			(stroke
				(width 0.1)
				(type default)
			)
			(layer "F.Fab")
		)
		(fp_line
			(start 0.120396 0.3048)
			(end 0.120396 0.2794)
			(stroke
				(width 0.1)
				(type default)
			)
			(layer "F.Fab")
		)
		(fp_line
			(start -0.12065 0.3048)
			(end -0.67945 0.3048)
			(stroke
				(width 0.1)
				(type default)
			)
			(layer "F.Fab")
		)
		(fp_line
			(start -0.67945 0.3048)
			(end -0.67945 -0.305054)
			(stroke
				(width 0.1)
				(type default)
			)
			(layer "F.Fab")
		)
		(pad "1" smd circle
			(at -0.40005 0 90)
			(size 0 0)
			(layers "F.Cu" "F.Mask" "F.Paste")
			(net "JTAG_BIC_NTRST_R_N")
		)
		(pad "2" smd circle
			(at 0.40005 0 90)
			(size 0 0)
			(layers "F.Cu" "F.Mask" "F.Paste")
			(net "JTAG_BIC_NTRST_N")
		)
	)
	(footprint ""
		(layer "F.Cu")
		(at 178.619912 -343.952322 90)
		(property "Reference" "C2527"
			(at 0 0 90)
			(layer "F.SilkS")
			(hide yes)
			(effects
				(font
					(size 1.27 1.27)
				)
			)
		)
		(property "Value" ""
			(at 0 0 90)
			(layer "F.Fab")
			(effects
				(font
					(size 1.27 1.27)
				)
			)
		)
		(duplicate_pad_numbers_are_jumpers no)
		(fp_line
			(start 0.299974 -0.150114)
			(end 0.299974 0.150114)
			(stroke
				(width 0.1)
				(type default)
			)
			(layer "F.Fab")
		)
		(fp_line
			(start -0.299974 -0.150114)
			(end 0.299974 -0.150114)
			(stroke
				(width 0.1)
				(type default)
			)
			(layer "F.Fab")
		)
		(fp_line
			(start 0.299974 0.150114)
			(end -0.299974 0.150114)
			(stroke
				(width 0.1)
				(type default)
			)
			(layer "F.Fab")
		)
		(fp_line
			(start -0.299974 0.150114)
			(end -0.299974 -0.150114)
			(stroke
				(width 0.1)
				(type default)
			)
			(layer "F.Fab")
		)
		(pad "1" smd rect
			(at -0.2667 0 90)
			(size 0.3048 0.381)
			(layers "F.Cu" "F.Mask" "F.Paste")
			(net "P5E_PEX1_STN4_TX_DN<72>")
		)
		(pad "2" smd rect
			(at 0.2667 0 90)
			(size 0.3048 0.381)
			(layers "F.Cu" "F.Mask" "F.Paste")
			(net "P5E_PEX1_STN4_TX_C_DN<72>")
		)
	)
	(footprint ""
		(layer "F.Cu")
		(at 135.358124 -72.766682 90)
		(property "Reference" "PC845"
			(at 0 0 90)
			(layer "F.SilkS")
			(hide yes)
			(effects
				(font
					(size 1.27 1.27)
				)
			)
		)
		(property "Value" ""
			(at 0 0 90)
			(layer "F.Fab")
			(effects
				(font
					(size 1.27 1.27)
				)
			)
		)
		(duplicate_pad_numbers_are_jumpers no)
		(fp_line
			(start 0.7874 -0.4064)
			(end 0.7874 0.4064)
			(stroke
				(width 0.1524)
				(type default)
			)
			(layer "F.SilkS")
		)
		(fp_line
			(start -0.7874 -0.4064)
			(end 0.7874 -0.4064)
			(stroke
				(width 0.1524)
				(type default)
			)
			(layer "F.SilkS")
		)
		(fp_line
			(start 0.7874 0.4064)
			(end -0.7874 0.4064)
			(stroke
				(width 0.1524)
				(type default)
			)
			(layer "F.SilkS")
		)
		(fp_line
			(start -0.7874 0.4064)
			(end -0.7874 -0.4064)
			(stroke
				(width 0.1524)
				(type default)
			)
			(layer "F.SilkS")
		)
		(fp_line
			(start -0.12065 -0.305054)
			(end -0.12065 -0.2794)
			(stroke
				(width 0.1)
				(type default)
			)
			(layer "F.Fab")
		)
		(fp_line
			(start -0.67945 -0.305054)
			(end -0.12065 -0.305054)
			(stroke
				(width 0.1)
				(type default)
			)
			(layer "F.Fab")
		)
		(fp_line
			(start 0.67945 -0.3048)
			(end 0.67945 0.3048)
			(stroke
				(width 0.1)
				(type default)
			)
			(layer "F.Fab")
		)
		(fp_line
			(start 0.12065 -0.3048)
			(end 0.67945 -0.3048)
			(stroke
				(width 0.1)
				(type default)
			)
			(layer "F.Fab")
		)
		(fp_line
			(start 0.12065 -0.2794)
			(end 0.12065 -0.3048)
			(stroke
				(width 0.1)
				(type default)
			)
			(layer "F.Fab")
		)
		(fp_line
			(start -0.12065 -0.2794)
			(end 0.12065 -0.2794)
			(stroke
				(width 0.1)
				(type default)
			)
			(layer "F.Fab")
		)
		(fp_line
			(start 0.120396 0.2794)
			(end -0.12065 0.2794)
			(stroke
				(width 0.1)
				(type default)
			)
			(layer "F.Fab")
		)
		(fp_line
			(start -0.12065 0.2794)
			(end -0.12065 0.3048)
			(stroke
				(width 0.1)
				(type default)
			)
			(layer "F.Fab")
		)
		(fp_line
			(start 0.67945 0.3048)
			(end 0.120396 0.3048)
			(stroke
				(width 0.1)
				(type default)
			)
			(layer "F.Fab")
		)
		(fp_line
			(start 0.120396 0.3048)
			(end 0.120396 0.2794)
			(stroke
				(width 0.1)
				(type default)
			)
			(layer "F.Fab")
		)
		(fp_line
			(start -0.12065 0.3048)
			(end -0.67945 0.3048)
			(stroke
				(width 0.1)
				(type default)
			)
			(layer "F.Fab")
		)
		(fp_line
			(start -0.67945 0.3048)
			(end -0.67945 -0.305054)
			(stroke
				(width 0.1)
				(type default)
			)
			(layer "F.Fab")
		)
		(pad "1" smd circle
			(at -0.40005 0 90)
			(size 0 0)
			(layers "F.Cu" "F.Mask" "F.Paste")
			(net "P12V_SSD4_CO_MODE")
		)
		(pad "2" smd circle
			(at 0.40005 0 90)
			(size 0 0)
			(layers "F.Cu" "F.Mask" "F.Paste")
			(net "GND")
		)
	)
	(footprint ""
		(layer "F.Cu")
		(at 126.221236 -173.991524)
		(property "Reference" "R1089"
			(at 0 0 0)
			(layer "F.SilkS")
			(hide yes)
			(effects
				(font
					(size 1.27 1.27)
				)
			)
		)
		(property "Value" ""
			(at 0 0 0)
			(layer "F.Fab")
			(effects
				(font
					(size 1.27 1.27)
				)
			)
		)
		(duplicate_pad_numbers_are_jumpers no)
		(fp_line
			(start 0.7874 0.4064)
			(end -0.7874 0.4064)
			(stroke
				(width 0.1524)
				(type default)
			)
			(layer "F.SilkS")
		)
		(fp_line
			(start -0.67945 -0.305054)
			(end -0.12065 -0.305054)
			(stroke
				(width 0.1)
				(type default)
			)
			(layer "F.Fab")
		)
		(fp_line
			(start -0.67945 0.3048)
			(end -0.67945 -0.305054)
			(stroke
				(width 0.1)
				(type default)
			)
			(layer "F.Fab")
		)
		(fp_line
			(start -0.12065 -0.305054)
			(end -0.12065 -0.2794)
			(stroke
				(width 0.1)
				(type default)
			)
			(layer "F.Fab")
		)
		(fp_line
			(start -0.12065 -0.2794)
			(end 0.12065 -0.2794)
			(stroke
				(width 0.1)
				(type default)
			)
			(layer "F.Fab")
		)
		(fp_line
			(start -0.12065 0.2794)
			(end -0.12065 0.3048)
			(stroke
				(width 0.1)
				(type default)
			)
			(layer "F.Fab")
		)
		(fp_line
			(start -0.12065 0.3048)
			(end -0.67945 0.3048)
			(stroke
				(width 0.1)
				(type default)
			)
			(layer "F.Fab")
		)
		(fp_line
			(start 0.120396 0.2794)
			(end -0.12065 0.2794)
			(stroke
				(width 0.1)
				(type default)
			)
			(layer "F.Fab")
		)
		(fp_line
			(start 0.120396 0.3048)
			(end 0.120396 0.2794)
			(stroke
				(width 0.1)
				(type default)
			)
			(layer "F.Fab")
		)
		(fp_line
			(start 0.12065 -0.3048)
			(end 0.67945 -0.3048)
			(stroke
				(width 0.1)
				(type default)
			)
			(layer "F.Fab")
		)
		(fp_line
			(start 0.12065 -0.2794)
			(end 0.12065 -0.3048)
			(stroke
				(width 0.1)
				(type default)
			)
			(layer "F.Fab")
		)
		(fp_line
			(start 0.67945 -0.3048)
			(end 0.67945 0.3048)
			(stroke
				(width 0.1)
				(type default)
			)
			(layer "F.Fab")
		)
		(fp_line
			(start 0.67945 0.3048)
			(end 0.120396 0.3048)
			(stroke
				(width 0.1)
				(type default)
			)
			(layer "F.Fab")
		)
		(pad "1" smd circle
			(at -0.40005 0)
			(size 0 0)
			(layers "F.Cu" "F.Mask" "F.Paste")
			(net "CLK_100M_DB2000QL_PEX1_S1_R_DN")
		)
		(pad "2" smd circle
			(at 0.40005 0)
			(size 0 0)
			(layers "F.Cu" "F.Mask" "F.Paste")
			(net "CLK_100M_DB2000QL_PEX1_S1_DN")
		)
	)
	(footprint ""
		(layer "F.Cu")
		(at 32.119062 -59.574684 90)
		(property "Reference" "PC516"
			(at 0 0 90)
			(layer "F.SilkS")
			(hide yes)
			(effects
				(font
					(size 1.27 1.27)
				)
			)
		)
		(property "Value" ""
			(at 0 0 90)
			(layer "F.Fab")
			(effects
				(font
					(size 1.27 1.27)
				)
			)
		)
		(duplicate_pad_numbers_are_jumpers no)
		(fp_line
			(start 0.7874 -0.4064)
			(end 0.7874 0.4064)
			(stroke
				(width 0.1524)
				(type default)
			)
			(layer "F.SilkS")
		)
		(fp_line
			(start -0.7874 -0.4064)
			(end 0.7874 -0.4064)
			(stroke
				(width 0.1524)
				(type default)
			)
			(layer "F.SilkS")
		)
		(fp_line
			(start 0.7874 0.4064)
			(end -0.7874 0.4064)
			(stroke
				(width 0.1524)
				(type default)
			)
			(layer "F.SilkS")
		)
		(fp_line
			(start -0.7874 0.4064)
			(end -0.7874 -0.4064)
			(stroke
				(width 0.1524)
				(type default)
			)
			(layer "F.SilkS")
		)
		(fp_line
			(start -0.12065 -0.305054)
			(end -0.12065 -0.2794)
			(stroke
				(width 0.1)
				(type default)
			)
			(layer "F.Fab")
		)
		(fp_line
			(start -0.67945 -0.305054)
			(end -0.12065 -0.305054)
			(stroke
				(width 0.1)
				(type default)
			)
			(layer "F.Fab")
		)
		(fp_line
			(start 0.67945 -0.3048)
			(end 0.67945 0.3048)
			(stroke
				(width 0.1)
				(type default)
			)
			(layer "F.Fab")
		)
		(fp_line
			(start 0.12065 -0.3048)
			(end 0.67945 -0.3048)
			(stroke
				(width 0.1)
				(type default)
			)
			(layer "F.Fab")
		)
		(fp_line
			(start 0.12065 -0.2794)
			(end 0.12065 -0.3048)
			(stroke
				(width 0.1)
				(type default)
			)
			(layer "F.Fab")
		)
		(fp_line
			(start -0.12065 -0.2794)
			(end 0.12065 -0.2794)
			(stroke
				(width 0.1)
				(type default)
			)
			(layer "F.Fab")
		)
		(fp_line
			(start 0.120396 0.2794)
			(end -0.12065 0.2794)
			(stroke
				(width 0.1)
				(type default)
			)
			(layer "F.Fab")
		)
		(fp_line
			(start -0.12065 0.2794)
			(end -0.12065 0.3048)
			(stroke
				(width 0.1)
				(type default)
			)
			(layer "F.Fab")
		)
		(fp_line
			(start 0.67945 0.3048)
			(end 0.120396 0.3048)
			(stroke
				(width 0.1)
				(type default)
			)
			(layer "F.Fab")
		)
		(fp_line
			(start 0.120396 0.3048)
			(end 0.120396 0.2794)
			(stroke
				(width 0.1)
				(type default)
			)
			(layer "F.Fab")
		)
		(fp_line
			(start -0.12065 0.3048)
			(end -0.67945 0.3048)
			(stroke
				(width 0.1)
				(type default)
			)
			(layer "F.Fab")
		)
		(fp_line
			(start -0.67945 0.3048)
			(end -0.67945 -0.305054)
			(stroke
				(width 0.1)
				(type default)
			)
			(layer "F.Fab")
		)
		(pad "1" smd circle
			(at -0.40005 0 90)
			(size 0 0)
			(layers "F.Cu" "F.Mask" "F.Paste")
			(net "P5V_AUX")
		)
		(pad "2" smd circle
			(at 0.40005 0 90)
			(size 0 0)
			(layers "F.Cu" "F.Mask" "F.Paste")
			(net "GND")
		)
	)
	(footprint ""
		(layer "F.Cu")
		(at 338.074 -146.939 180)
		(property "Reference" "R4832"
			(at 0 0 180)
			(layer "F.SilkS")
			(hide yes)
			(effects
				(font
					(size 1.27 1.27)
				)
			)
		)
		(property "Value" ""
			(at 0 0 180)
			(layer "F.Fab")
			(effects
				(font
					(size 1.27 1.27)
				)
			)
		)
		(duplicate_pad_numbers_are_jumpers no)
		(fp_line
			(start 0.7874 0.4064)
			(end -0.7874 0.4064)
			(stroke
				(width 0.1524)
				(type default)
			)
			(layer "F.SilkS")
		)
		(fp_line
			(start 0.7874 -0.4064)
			(end 0.7874 0.4064)
			(stroke
				(width 0.1524)
				(type default)
			)
			(layer "F.SilkS")
		)
		(fp_line
			(start -0.7874 0.4064)
			(end -0.7874 -0.4064)
			(stroke
				(width 0.1524)
				(type default)
			)
			(layer "F.SilkS")
		)
		(fp_line
			(start -0.7874 -0.4064)
			(end 0.7874 -0.4064)
			(stroke
				(width 0.1524)
				(type default)
			)
			(layer "F.SilkS")
		)
		(fp_line
			(start 0.67945 0.3048)
			(end 0.120396 0.3048)
			(stroke
				(width 0.1)
				(type default)
			)
			(layer "F.Fab")
		)
		(fp_line
			(start 0.67945 -0.3048)
			(end 0.67945 0.3048)
			(stroke
				(width 0.1)
				(type default)
			)
			(layer "F.Fab")
		)
		(fp_line
			(start 0.12065 -0.2794)
			(end 0.12065 -0.3048)
			(stroke
				(width 0.1)
				(type default)
			)
			(layer "F.Fab")
		)
		(fp_line
			(start 0.12065 -0.3048)
			(end 0.67945 -0.3048)
			(stroke
				(width 0.1)
				(type default)
			)
			(layer "F.Fab")
		)
		(fp_line
			(start 0.120396 0.3048)
			(end 0.120396 0.2794)
			(stroke
				(width 0.1)
				(type default)
			)
			(layer "F.Fab")
		)
		(fp_line
			(start 0.120396 0.2794)
			(end -0.12065 0.2794)
			(stroke
				(width 0.1)
				(type default)
			)
			(layer "F.Fab")
		)
		(fp_line
			(start -0.12065 0.3048)
			(end -0.67945 0.3048)
			(stroke
				(width 0.1)
				(type default)
			)
			(layer "F.Fab")
		)
		(fp_line
			(start -0.12065 0.2794)
			(end -0.12065 0.3048)
			(stroke
				(width 0.1)
				(type default)
			)
			(layer "F.Fab")
		)
		(fp_line
			(start -0.12065 -0.2794)
			(end 0.12065 -0.2794)
			(stroke
				(width 0.1)
				(type default)
			)
			(layer "F.Fab")
		)
		(fp_line
			(start -0.12065 -0.305054)
			(end -0.12065 -0.2794)
			(stroke
				(width 0.1)
				(type default)
			)
			(layer "F.Fab")
		)
		(fp_line
			(start -0.67945 0.3048)
			(end -0.67945 -0.305054)
			(stroke
				(width 0.1)
				(type default)
			)
			(layer "F.Fab")
		)
		(fp_line
			(start -0.67945 -0.305054)
			(end -0.12065 -0.305054)
			(stroke
				(width 0.1)
				(type default)
			)
			(layer "F.Fab")
		)
		(pad "1" smd circle
			(at -0.40005 0 180)
			(size 0 0)
			(layers "F.Cu" "F.Mask" "F.Paste")
			(net "SSD14_PEX_PWR_EN")
		)
		(pad "2" smd circle
			(at 0.40005 0 180)
			(size 0 0)
			(layers "F.Cu" "F.Mask" "F.Paste")
			(net "SSD14_PEX_PWR_EN_R")
		)
	)
	(footprint ""
		(layer "F.Cu")
		(at 275.992336 -31.825184 180)
		(property "Reference" "C498"
			(at 0 0 180)
			(layer "F.SilkS")
			(hide yes)
			(effects
				(font
					(size 1.27 1.27)
				)
			)
		)
		(property "Value" ""
			(at 0 0 180)
			(layer "F.Fab")
			(effects
				(font
					(size 1.27 1.27)
				)
			)
		)
		(duplicate_pad_numbers_are_jumpers no)
		(fp_line
			(start 0.299974 0.150114)
			(end -0.299974 0.150114)
			(stroke
				(width 0.1)
				(type default)
			)
			(layer "F.Fab")
		)
		(fp_line
			(start 0.299974 -0.150114)
			(end 0.299974 0.150114)
			(stroke
				(width 0.1)
				(type default)
			)
			(layer "F.Fab")
		)
		(fp_line
			(start -0.299974 0.150114)
			(end -0.299974 -0.150114)
			(stroke
				(width 0.1)
				(type default)
			)
			(layer "F.Fab")
		)
		(fp_line
			(start -0.299974 -0.150114)
			(end 0.299974 -0.150114)
			(stroke
				(width 0.1)
				(type default)
			)
			(layer "F.Fab")
		)
		(pad "1" smd rect
			(at -0.2667 0 180)
			(size 0.3048 0.381)
			(layers "F.Cu" "F.Mask" "F.Paste")
			(net "P5E_PEX2_STN2_TX_DN<42>")
		)
		(pad "2" smd rect
			(at 0.2667 0 180)
			(size 0.3048 0.381)
			(layers "F.Cu" "F.Mask" "F.Paste")
			(net "P5E_PEX2_STN2_TX_C_DN<42>")
		)
	)
	(footprint ""
		(layer "F.Cu")
		(at 20.434554 -34.546286 180)
		(property "Reference" "C65"
			(at 0 0 180)
			(layer "F.SilkS")
			(hide yes)
			(effects
				(font
					(size 1.27 1.27)
				)
			)
		)
		(property "Value" ""
			(at 0 0 180)
			(layer "F.Fab")
			(effects
				(font
					(size 1.27 1.27)
				)
			)
		)
		(duplicate_pad_numbers_are_jumpers no)
		(fp_line
			(start 0.299974 0.150114)
			(end -0.299974 0.150114)
			(stroke
				(width 0.1)
				(type default)
			)
			(layer "F.Fab")
		)
		(fp_line
			(start 0.299974 -0.150114)
			(end 0.299974 0.150114)
			(stroke
				(width 0.1)
				(type default)
			)
			(layer "F.Fab")
		)
		(fp_line
			(start -0.299974 0.150114)
			(end -0.299974 -0.150114)
			(stroke
				(width 0.1)
				(type default)
			)
			(layer "F.Fab")
		)
		(fp_line
			(start -0.299974 -0.150114)
			(end 0.299974 -0.150114)
			(stroke
				(width 0.1)
				(type default)
			)
			(layer "F.Fab")
		)
		(pad "1" smd rect
			(at -0.2667 0 180)
			(size 0.3048 0.381)
			(layers "F.Cu" "F.Mask" "F.Paste")
			(net "P5E_PEX0_STN2_TX_DP<47>")
		)
		(pad "2" smd rect
			(at 0.2667 0 180)
			(size 0.3048 0.381)
			(layers "F.Cu" "F.Mask" "F.Paste")
			(net "P5E_PEX0_STN2_TX_C_DP<47>")
		)
	)
	(footprint ""
		(layer "F.Cu")
		(at 354.889562 -313.620404 180)
		(property "Reference" "R5795"
			(at 0 0 180)
			(layer "F.SilkS")
			(hide yes)
			(effects
				(font
					(size 1.27 1.27)
				)
			)
		)
		(property "Value" ""
			(at 0 0 180)
			(layer "F.Fab")
			(effects
				(font
					(size 1.27 1.27)
				)
			)
		)
		(duplicate_pad_numbers_are_jumpers no)
		(fp_line
			(start 2.576322 1.1303)
			(end -2.576322 1.1303)
			(stroke
				(width 0.1524)
				(type default)
			)
			(layer "F.SilkS")
		)
		(fp_line
			(start 2.576322 -1.1303)
			(end 2.576322 1.1303)
			(stroke
				(width 0.1524)
				(type default)
			)
			(layer "F.SilkS")
		)
		(fp_line
			(start -2.576322 1.1303)
			(end -2.576322 -1.1303)
			(stroke
				(width 0.1524)
				(type default)
			)
			(layer "F.SilkS")
		)
		(fp_line
			(start -2.576322 -1.1303)
			(end 2.576322 -1.1303)
			(stroke
				(width 0.1524)
				(type default)
			)
			(layer "F.SilkS")
		)
		(fp_line
			(start 1.649984 0.899922)
			(end 1.649984 -0.899922)
			(stroke
				(width 0.1)
				(type default)
			)
			(layer "F.Fab")
		)
		(fp_line
			(start 1.649984 -0.899922)
			(end -1.649984 -0.899922)
			(stroke
				(width 0.1)
				(type default)
			)
			(layer "F.Fab")
		)
		(fp_line
			(start -1.649984 0.899922)
			(end 1.649984 0.899922)
			(stroke
				(width 0.1)
				(type default)
			)
			(layer "F.Fab")
		)
		(fp_line
			(start -1.649984 -0.899922)
			(end -1.649984 0.899922)
			(stroke
				(width 0.1)
				(type default)
			)
			(layer "F.Fab")
		)
		(pad "1A" smd rect
			(at -1.700022 0 180)
			(size 1.4986 2.0066)
			(layers "F.Cu" "F.Mask" "F.Paste")
			(net "P0V8_PEX3")
		)
		(pad "1B" smd rect
			(at -1.077722 0 180)
			(size 0.254 0.508)
			(layers "F.Cu" "F.Mask" "F.Paste")
			(net "P0V8_PEX3")
		)
		(pad "2A" smd rect
			(at 1.700022 0 180)
			(size 1.4986 2.0066)
			(layers "F.Cu" "F.Mask" "F.Paste")
			(net "P0V8_SERDES_VDDA_PEX3")
		)
		(pad "2B" smd rect
			(at 1.077722 0 180)
			(size 0.254 0.508)
			(layers "F.Cu" "F.Mask" "F.Paste")
			(net "P0V8_SERDES_VDDA_PEX3")
		)
	)
	(footprint ""
		(layer "F.Cu")
		(at 143.840708 -350.098614 90)
		(property "Reference" "C2260"
			(at 0 0 90)
			(layer "F.SilkS")
			(hide yes)
			(effects
				(font
					(size 1.27 1.27)
				)
			)
		)
		(property "Value" ""
			(at 0 0 90)
			(layer "F.Fab")
			(effects
				(font
					(size 1.27 1.27)
				)
			)
		)
		(duplicate_pad_numbers_are_jumpers no)
		(fp_line
			(start 0.299974 -0.150114)
			(end 0.299974 0.150114)
			(stroke
				(width 0.1)
				(type default)
			)
			(layer "F.Fab")
		)
		(fp_line
			(start -0.299974 -0.150114)
			(end 0.299974 -0.150114)
			(stroke
				(width 0.1)
				(type default)
			)
			(layer "F.Fab")
		)
		(fp_line
			(start 0.299974 0.150114)
			(end -0.299974 0.150114)
			(stroke
				(width 0.1)
				(type default)
			)
			(layer "F.Fab")
		)
		(fp_line
			(start -0.299974 0.150114)
			(end -0.299974 -0.150114)
			(stroke
				(width 0.1)
				(type default)
			)
			(layer "F.Fab")
		)
		(pad "1" smd rect
			(at -0.2667 0 90)
			(size 0.3048 0.381)
			(layers "F.Cu" "F.Mask" "F.Paste")
			(net "P5E_PEX1_STN5_TX_DN<87>")
		)
		(pad "2" smd rect
			(at 0.2667 0 90)
			(size 0.3048 0.381)
			(layers "F.Cu" "F.Mask" "F.Paste")
			(net "P5E_PEX1_STN5_TX_C_DN<87>")
		)
	)
	(footprint ""
		(layer "F.Cu")
		(at 352.232214 -154.305)
		(property "Reference" "R4820"
			(at 0 0 0)
			(layer "F.SilkS")
			(hide yes)
			(effects
				(font
					(size 1.27 1.27)
				)
			)
		)
		(property "Value" ""
			(at 0 0 0)
			(layer "F.Fab")
			(effects
				(font
					(size 1.27 1.27)
				)
			)
		)
		(duplicate_pad_numbers_are_jumpers no)
		(fp_line
			(start -0.7874 -0.4064)
			(end 0.7874 -0.4064)
			(stroke
				(width 0.1524)
				(type default)
			)
			(layer "F.SilkS")
		)
		(fp_line
			(start -0.7874 0.4064)
			(end -0.7874 -0.4064)
			(stroke
				(width 0.1524)
				(type default)
			)
			(layer "F.SilkS")
		)
		(fp_line
			(start 0.7874 -0.4064)
			(end 0.7874 0.4064)
			(stroke
				(width 0.1524)
				(type default)
			)
			(layer "F.SilkS")
		)
		(fp_line
			(start 0.7874 0.4064)
			(end -0.7874 0.4064)
			(stroke
				(width 0.1524)
				(type default)
			)
			(layer "F.SilkS")
		)
		(fp_line
			(start -0.67945 -0.305054)
			(end -0.12065 -0.305054)
			(stroke
				(width 0.1)
				(type default)
			)
			(layer "F.Fab")
		)
		(fp_line
			(start -0.67945 0.3048)
			(end -0.67945 -0.305054)
			(stroke
				(width 0.1)
				(type default)
			)
			(layer "F.Fab")
		)
		(fp_line
			(start -0.12065 -0.305054)
			(end -0.12065 -0.2794)
			(stroke
				(width 0.1)
				(type default)
			)
			(layer "F.Fab")
		)
		(fp_line
			(start -0.12065 -0.2794)
			(end 0.12065 -0.2794)
			(stroke
				(width 0.1)
				(type default)
			)
			(layer "F.Fab")
		)
		(fp_line
			(start -0.12065 0.2794)
			(end -0.12065 0.3048)
			(stroke
				(width 0.1)
				(type default)
			)
			(layer "F.Fab")
		)
		(fp_line
			(start -0.12065 0.3048)
			(end -0.67945 0.3048)
			(stroke
				(width 0.1)
				(type default)
			)
			(layer "F.Fab")
		)
		(fp_line
			(start 0.120396 0.2794)
			(end -0.12065 0.2794)
			(stroke
				(width 0.1)
				(type default)
			)
			(layer "F.Fab")
		)
		(fp_line
			(start 0.120396 0.3048)
			(end 0.120396 0.2794)
			(stroke
				(width 0.1)
				(type default)
			)
			(layer "F.Fab")
		)
		(fp_line
			(start 0.12065 -0.3048)
			(end 0.67945 -0.3048)
			(stroke
				(width 0.1)
				(type default)
			)
			(layer "F.Fab")
		)
		(fp_line
			(start 0.12065 -0.2794)
			(end 0.12065 -0.3048)
			(stroke
				(width 0.1)
				(type default)
			)
			(layer "F.Fab")
		)
		(fp_line
			(start 0.67945 -0.3048)
			(end 0.67945 0.3048)
			(stroke
				(width 0.1)
				(type default)
			)
			(layer "F.Fab")
		)
		(fp_line
			(start 0.67945 0.3048)
			(end 0.120396 0.3048)
			(stroke
				(width 0.1)
				(type default)
			)
			(layer "F.Fab")
		)
		(pad "1" smd circle
			(at -0.40005 0)
			(size 0 0)
			(layers "F.Cu" "F.Mask" "F.Paste")
			(net "PRSNT_NIC6_FPGA_PCA9555_N")
		)
		(pad "2" smd circle
			(at 0.40005 0)
			(size 0 0)
			(layers "F.Cu" "F.Mask" "F.Paste")
			(net "PRSNT_NIC6_FPGA_R_N")
		)
	)
	(footprint ""
		(layer "F.Cu")
		(at 35.195002 -59.577986 90)
		(property "Reference" "PC518"
			(at 0 0 90)
			(layer "F.SilkS")
			(hide yes)
			(effects
				(font
					(size 1.27 1.27)
				)
			)
		)
		(property "Value" ""
			(at 0 0 90)
			(layer "F.Fab")
			(effects
				(font
					(size 1.27 1.27)
				)
			)
		)
		(duplicate_pad_numbers_are_jumpers no)
		(fp_line
			(start 0.7874 -0.4064)
			(end 0.7874 0.4064)
			(stroke
				(width 0.1524)
				(type default)
			)
			(layer "F.SilkS")
		)
		(fp_line
			(start -0.7874 -0.4064)
			(end 0.7874 -0.4064)
			(stroke
				(width 0.1524)
				(type default)
			)
			(layer "F.SilkS")
		)
		(fp_line
			(start 0.7874 0.4064)
			(end -0.7874 0.4064)
			(stroke
				(width 0.1524)
				(type default)
			)
			(layer "F.SilkS")
		)
		(fp_line
			(start -0.7874 0.4064)
			(end -0.7874 -0.4064)
			(stroke
				(width 0.1524)
				(type default)
			)
			(layer "F.SilkS")
		)
		(fp_line
			(start -0.12065 -0.305054)
			(end -0.12065 -0.2794)
			(stroke
				(width 0.1)
				(type default)
			)
			(layer "F.Fab")
		)
		(fp_line
			(start -0.67945 -0.305054)
			(end -0.12065 -0.305054)
			(stroke
				(width 0.1)
				(type default)
			)
			(layer "F.Fab")
		)
		(fp_line
			(start 0.67945 -0.3048)
			(end 0.67945 0.3048)
			(stroke
				(width 0.1)
				(type default)
			)
			(layer "F.Fab")
		)
		(fp_line
			(start 0.12065 -0.3048)
			(end 0.67945 -0.3048)
			(stroke
				(width 0.1)
				(type default)
			)
			(layer "F.Fab")
		)
		(fp_line
			(start 0.12065 -0.2794)
			(end 0.12065 -0.3048)
			(stroke
				(width 0.1)
				(type default)
			)
			(layer "F.Fab")
		)
		(fp_line
			(start -0.12065 -0.2794)
			(end 0.12065 -0.2794)
			(stroke
				(width 0.1)
				(type default)
			)
			(layer "F.Fab")
		)
		(fp_line
			(start 0.120396 0.2794)
			(end -0.12065 0.2794)
			(stroke
				(width 0.1)
				(type default)
			)
			(layer "F.Fab")
		)
		(fp_line
			(start -0.12065 0.2794)
			(end -0.12065 0.3048)
			(stroke
				(width 0.1)
				(type default)
			)
			(layer "F.Fab")
		)
		(fp_line
			(start 0.67945 0.3048)
			(end 0.120396 0.3048)
			(stroke
				(width 0.1)
				(type default)
			)
			(layer "F.Fab")
		)
		(fp_line
			(start 0.120396 0.3048)
			(end 0.120396 0.2794)
			(stroke
				(width 0.1)
				(type default)
			)
			(layer "F.Fab")
		)
		(fp_line
			(start -0.12065 0.3048)
			(end -0.67945 0.3048)
			(stroke
				(width 0.1)
				(type default)
			)
			(layer "F.Fab")
		)
		(fp_line
			(start -0.67945 0.3048)
			(end -0.67945 -0.305054)
			(stroke
				(width 0.1)
				(type default)
			)
			(layer "F.Fab")
		)
		(pad "1" smd circle
			(at -0.40005 0 90)
			(size 0 0)
			(layers "F.Cu" "F.Mask" "F.Paste")
			(net "P3V3_SSD1_SS")
		)
		(pad "2" smd circle
			(at 0.40005 0 90)
			(size 0 0)
			(layers "F.Cu" "F.Mask" "F.Paste")
			(net "GND")
		)
	)
	(footprint ""
		(layer "F.Cu")
		(at 436.775606 -122.931682 -90)
		(property "Reference" "PD59"
			(at 4.059682 2.129536 90)
			(unlocked yes)
			(layer "F.SilkS")
			(effects
				(font
					(size 0.7874 0.5842)
					(thickness 0.1524)
				)
				(justify left)
			)
		)
		(property "Value" ""
			(at 0 0 270)
			(layer "F.Fab")
			(effects
				(font
					(size 1.27 1.27)
				)
			)
		)
		(duplicate_pad_numbers_are_jumpers no)
		(fp_line
			(start -3.400044 1.459992)
			(end -3.400044 -1.459992)
			(stroke
				(width 0.1524)
				(type default)
			)
			(layer "F.SilkS")
		)
		(fp_line
			(start 4.107942 1.459992)
			(end -3.400044 1.459992)
			(stroke
				(width 0.1524)
				(type default)
			)
			(layer "F.SilkS")
		)
		(fp_line
			(start -3.400044 -1.459992)
			(end 4.107942 -1.459992)
			(stroke
				(width 0.1524)
				(type default)
			)
			(layer "F.SilkS")
		)
		(fp_line
			(start 4.107942 -1.459992)
			(end 4.107942 1.459992)
			(stroke
				(width 0.1524)
				(type default)
			)
			(layer "F.SilkS")
		)
		(fp_rect
			(start 4.107942 1.459992)
			(end 3.308096 -1.459992)
			(stroke
				(width 0)
				(type default)
			)
			(fill yes)
			(layer "F.SilkS")
		)
		(fp_line
			(start -2.29997 1.459992)
			(end -2.29997 -1.459992)
			(stroke
				(width 0.1)
				(type default)
			)
			(layer "F.Fab")
		)
		(fp_line
			(start 2.29997 1.459992)
			(end -2.29997 1.459992)
			(stroke
				(width 0.1)
				(type default)
			)
			(layer "F.Fab")
		)
		(fp_line
			(start -2.29997 -1.459992)
			(end 2.29997 -1.459992)
			(stroke
				(width 0.1)
				(type default)
			)
			(layer "F.Fab")
		)
		(fp_line
			(start 2.29997 -1.459992)
			(end 2.29997 1.459992)
			(stroke
				(width 0.1)
				(type default)
			)
			(layer "F.Fab")
		)
		(fp_text user "-"
			(at 5.4102 0.29845 90)
			(unlocked yes)
			(layer "F.SilkS")
			(effects
				(font
					(size 1.905 1.4224)
					(thickness 0.1524)
				)
				(justify left)
			)
		)
		(fp_text user "+"
			(at -4.7752 -0.12065 270)
			(unlocked yes)
			(layer "F.SilkS")
			(effects
				(font
					(size 1.905 1.4224)
					(thickness 0.1524)
				)
				(justify left)
			)
		)
		(fp_text user "-"
			(at 5.4102 0.29845 90)
			(unlocked yes)
			(layer "F.Fab")
			(effects
				(font
					(size 1.905 1.4224)
					(thickness 0.1524)
				)
				(justify left)
			)
		)
		(fp_text user "+"
			(at -4.7752 -0.12065 270)
			(unlocked yes)
			(layer "F.Fab")
			(effects
				(font
					(size 1.905 1.4224)
					(thickness 0.1524)
				)
				(justify left)
			)
		)
		(pad "A" smd rect
			(at -1.999996 0)
			(size 1.7018 2.5146)
			(layers "F.Cu" "F.Mask" "F.Paste")
			(net "GND")
		)
		(pad "C" smd rect
			(at 1.999996 0)
			(size 1.7018 2.5146)
			(layers "F.Cu" "F.Mask" "F.Paste")
			(net "P3V3_NIC7")
		)
	)
	(footprint ""
		(layer "F.Cu")
		(at 121.13514 -93.748606)
		(property "Reference" "R1554"
			(at 0 0 0)
			(layer "F.SilkS")
			(hide yes)
			(effects
				(font
					(size 1.27 1.27)
				)
			)
		)
		(property "Value" ""
			(at 0 0 0)
			(layer "F.Fab")
			(effects
				(font
					(size 1.27 1.27)
				)
			)
		)
		(duplicate_pad_numbers_are_jumpers no)
		(fp_line
			(start -0.7874 -0.4064)
			(end 0.7874 -0.4064)
			(stroke
				(width 0.1524)
				(type default)
			)
			(layer "F.SilkS")
		)
		(fp_line
			(start -0.7874 0.4064)
			(end -0.7874 -0.4064)
			(stroke
				(width 0.1524)
				(type default)
			)
			(layer "F.SilkS")
		)
		(fp_line
			(start 0.7874 -0.4064)
			(end 0.7874 0.4064)
			(stroke
				(width 0.1524)
				(type default)
			)
			(layer "F.SilkS")
		)
		(fp_line
			(start 0.7874 0.4064)
			(end -0.7874 0.4064)
			(stroke
				(width 0.1524)
				(type default)
			)
			(layer "F.SilkS")
		)
		(fp_line
			(start -0.67945 -0.305054)
			(end -0.12065 -0.305054)
			(stroke
				(width 0.1)
				(type default)
			)
			(layer "F.Fab")
		)
		(fp_line
			(start -0.67945 0.3048)
			(end -0.67945 -0.305054)
			(stroke
				(width 0.1)
				(type default)
			)
			(layer "F.Fab")
		)
		(fp_line
			(start -0.12065 -0.305054)
			(end -0.12065 -0.2794)
			(stroke
				(width 0.1)
				(type default)
			)
			(layer "F.Fab")
		)
		(fp_line
			(start -0.12065 -0.2794)
			(end 0.12065 -0.2794)
			(stroke
				(width 0.1)
				(type default)
			)
			(layer "F.Fab")
		)
		(fp_line
			(start -0.12065 0.2794)
			(end -0.12065 0.3048)
			(stroke
				(width 0.1)
				(type default)
			)
			(layer "F.Fab")
		)
		(fp_line
			(start -0.12065 0.3048)
			(end -0.67945 0.3048)
			(stroke
				(width 0.1)
				(type default)
			)
			(layer "F.Fab")
		)
		(fp_line
			(start 0.120396 0.2794)
			(end -0.12065 0.2794)
			(stroke
				(width 0.1)
				(type default)
			)
			(layer "F.Fab")
		)
		(fp_line
			(start 0.120396 0.3048)
			(end 0.120396 0.2794)
			(stroke
				(width 0.1)
				(type default)
			)
			(layer "F.Fab")
		)
		(fp_line
			(start 0.12065 -0.3048)
			(end 0.67945 -0.3048)
			(stroke
				(width 0.1)
				(type default)
			)
			(layer "F.Fab")
		)
		(fp_line
			(start 0.12065 -0.2794)
			(end 0.12065 -0.3048)
			(stroke
				(width 0.1)
				(type default)
			)
			(layer "F.Fab")
		)
		(fp_line
			(start 0.67945 -0.3048)
			(end 0.67945 0.3048)
			(stroke
				(width 0.1)
				(type default)
			)
			(layer "F.Fab")
		)
		(fp_line
			(start 0.67945 0.3048)
			(end 0.120396 0.3048)
			(stroke
				(width 0.1)
				(type default)
			)
			(layer "F.Fab")
		)
		(pad "1" smd circle
			(at -0.40005 0)
			(size 0 0)
			(layers "F.Cu" "F.Mask" "F.Paste")
			(net "P3V3_AUX")
		)
		(pad "2" smd circle
			(at 0.40005 0)
			(size 0 0)
			(layers "F.Cu" "F.Mask" "F.Paste")
			(net "SMB_BIC_I2C9_MUX0_SSD1_R_SCL")
		)
	)
	(footprint ""
		(layer "F.Cu")
		(at 240.580164 -57.620408)
		(property "Reference" "R4498"
			(at 0 0 0)
			(layer "F.SilkS")
			(hide yes)
			(effects
				(font
					(size 1.27 1.27)
				)
			)
		)
		(property "Value" ""
			(at 0 0 0)
			(layer "F.Fab")
			(effects
				(font
					(size 1.27 1.27)
				)
			)
		)
		(duplicate_pad_numbers_are_jumpers no)
		(fp_line
			(start -0.7874 -0.4064)
			(end 0.7874 -0.4064)
			(stroke
				(width 0.1524)
				(type default)
			)
			(layer "F.SilkS")
		)
		(fp_line
			(start -0.7874 0.4064)
			(end -0.7874 -0.4064)
			(stroke
				(width 0.1524)
				(type default)
			)
			(layer "F.SilkS")
		)
		(fp_line
			(start 0.7874 -0.4064)
			(end 0.7874 0.4064)
			(stroke
				(width 0.1524)
				(type default)
			)
			(layer "F.SilkS")
		)
		(fp_line
			(start 0.7874 0.4064)
			(end -0.7874 0.4064)
			(stroke
				(width 0.1524)
				(type default)
			)
			(layer "F.SilkS")
		)
		(fp_line
			(start -0.67945 -0.305054)
			(end -0.12065 -0.305054)
			(stroke
				(width 0.1)
				(type default)
			)
			(layer "F.Fab")
		)
		(fp_line
			(start -0.67945 0.3048)
			(end -0.67945 -0.305054)
			(stroke
				(width 0.1)
				(type default)
			)
			(layer "F.Fab")
		)
		(fp_line
			(start -0.12065 -0.305054)
			(end -0.12065 -0.2794)
			(stroke
				(width 0.1)
				(type default)
			)
			(layer "F.Fab")
		)
		(fp_line
			(start -0.12065 -0.2794)
			(end 0.12065 -0.2794)
			(stroke
				(width 0.1)
				(type default)
			)
			(layer "F.Fab")
		)
		(fp_line
			(start -0.12065 0.2794)
			(end -0.12065 0.3048)
			(stroke
				(width 0.1)
				(type default)
			)
			(layer "F.Fab")
		)
		(fp_line
			(start -0.12065 0.3048)
			(end -0.67945 0.3048)
			(stroke
				(width 0.1)
				(type default)
			)
			(layer "F.Fab")
		)
		(fp_line
			(start 0.120396 0.2794)
			(end -0.12065 0.2794)
			(stroke
				(width 0.1)
				(type default)
			)
			(layer "F.Fab")
		)
		(fp_line
			(start 0.120396 0.3048)
			(end 0.120396 0.2794)
			(stroke
				(width 0.1)
				(type default)
			)
			(layer "F.Fab")
		)
		(fp_line
			(start 0.12065 -0.3048)
			(end 0.67945 -0.3048)
			(stroke
				(width 0.1)
				(type default)
			)
			(layer "F.Fab")
		)
		(fp_line
			(start 0.12065 -0.2794)
			(end 0.12065 -0.3048)
			(stroke
				(width 0.1)
				(type default)
			)
			(layer "F.Fab")
		)
		(fp_line
			(start 0.67945 -0.3048)
			(end 0.67945 0.3048)
			(stroke
				(width 0.1)
				(type default)
			)
			(layer "F.Fab")
		)
		(fp_line
			(start 0.67945 0.3048)
			(end 0.120396 0.3048)
			(stroke
				(width 0.1)
				(type default)
			)
			(layer "F.Fab")
		)
		(pad "1" smd circle
			(at -0.40005 0)
			(size 0 0)
			(layers "F.Cu" "F.Mask" "F.Paste")
			(net "PWRGD_P3V3_SSD8")
		)
		(pad "2" smd circle
			(at 0.40005 0)
			(size 0 0)
			(layers "F.Cu" "F.Mask" "F.Paste")
			(net "PWRGD_P3V3_SSD8_R")
		)
	)
	(footprint ""
		(layer "F.Cu")
		(at 386.866384 -252.356874 -90)
		(property "Reference" "R1424"
			(at 0 0 270)
			(layer "F.SilkS")
			(hide yes)
			(effects
				(font
					(size 1.27 1.27)
				)
			)
		)
		(property "Value" ""
			(at 0 0 270)
			(layer "F.Fab")
			(effects
				(font
					(size 1.27 1.27)
				)
			)
		)
		(duplicate_pad_numbers_are_jumpers no)
		(fp_line
			(start -0.7874 0.4064)
			(end -0.7874 -0.4064)
			(stroke
				(width 0.1524)
				(type default)
			)
			(layer "F.SilkS")
		)
		(fp_line
			(start 0.7874 0.4064)
			(end -0.7874 0.4064)
			(stroke
				(width 0.1524)
				(type default)
			)
			(layer "F.SilkS")
		)
		(fp_line
			(start -0.7874 -0.4064)
			(end 0.7874 -0.4064)
			(stroke
				(width 0.1524)
				(type default)
			)
			(layer "F.SilkS")
		)
		(fp_line
			(start 0.7874 -0.4064)
			(end 0.7874 0.4064)
			(stroke
				(width 0.1524)
				(type default)
			)
			(layer "F.SilkS")
		)
		(fp_line
			(start -0.67945 0.3048)
			(end -0.67945 -0.305054)
			(stroke
				(width 0.1)
				(type default)
			)
			(layer "F.Fab")
		)
		(fp_line
			(start -0.12065 0.3048)
			(end -0.67945 0.3048)
			(stroke
				(width 0.1)
				(type default)
			)
			(layer "F.Fab")
		)
		(fp_line
			(start 0.120396 0.3048)
			(end 0.120396 0.2794)
			(stroke
				(width 0.1)
				(type default)
			)
			(layer "F.Fab")
		)
		(fp_line
			(start 0.67945 0.3048)
			(end 0.120396 0.3048)
			(stroke
				(width 0.1)
				(type default)
			)
			(layer "F.Fab")
		)
		(fp_line
			(start -0.12065 0.2794)
			(end -0.12065 0.3048)
			(stroke
				(width 0.1)
				(type default)
			)
			(layer "F.Fab")
		)
		(fp_line
			(start 0.120396 0.2794)
			(end -0.12065 0.2794)
			(stroke
				(width 0.1)
				(type default)
			)
			(layer "F.Fab")
		)
		(fp_line
			(start -0.12065 -0.2794)
			(end 0.12065 -0.2794)
			(stroke
				(width 0.1)
				(type default)
			)
			(layer "F.Fab")
		)
		(fp_line
			(start 0.12065 -0.2794)
			(end 0.12065 -0.3048)
			(stroke
				(width 0.1)
				(type default)
			)
			(layer "F.Fab")
		)
		(fp_line
			(start 0.12065 -0.3048)
			(end 0.67945 -0.3048)
			(stroke
				(width 0.1)
				(type default)
			)
			(layer "F.Fab")
		)
		(fp_line
			(start 0.67945 -0.3048)
			(end 0.67945 0.3048)
			(stroke
				(width 0.1)
				(type default)
			)
			(layer "F.Fab")
		)
		(fp_line
			(start -0.67945 -0.305054)
			(end -0.12065 -0.305054)
			(stroke
				(width 0.1)
				(type default)
			)
			(layer "F.Fab")
		)
		(fp_line
			(start -0.12065 -0.305054)
			(end -0.12065 -0.2794)
			(stroke
				(width 0.1)
				(type default)
			)
			(layer "F.Fab")
		)
		(pad "1" smd circle
			(at -0.40005 0 270)
			(size 0 0)
			(layers "F.Cu" "F.Mask" "F.Paste")
			(net "GND")
		)
		(pad "2" smd circle
			(at 0.40005 0 270)
			(size 0 0)
			(layers "F.Cu" "F.Mask" "F.Paste")
			(net "PEX3_DBG_MODE4")
		)
	)
	(footprint ""
		(layer "F.Cu")
		(at 154.707844 -153.3144 180)
		(property "Reference" "R127"
			(at 0 0 180)
			(layer "F.SilkS")
			(hide yes)
			(effects
				(font
					(size 1.27 1.27)
				)
			)
		)
		(property "Value" ""
			(at 0 0 180)
			(layer "F.Fab")
			(effects
				(font
					(size 1.27 1.27)
				)
			)
		)
		(duplicate_pad_numbers_are_jumpers no)
		(fp_line
			(start 0.7874 0.4064)
			(end -0.7874 0.4064)
			(stroke
				(width 0.1524)
				(type default)
			)
			(layer "F.SilkS")
		)
		(fp_line
			(start 0.7874 -0.4064)
			(end 0.7874 0.4064)
			(stroke
				(width 0.1524)
				(type default)
			)
			(layer "F.SilkS")
		)
		(fp_line
			(start -0.7874 0.4064)
			(end -0.7874 -0.4064)
			(stroke
				(width 0.1524)
				(type default)
			)
			(layer "F.SilkS")
		)
		(fp_line
			(start -0.7874 -0.4064)
			(end 0.7874 -0.4064)
			(stroke
				(width 0.1524)
				(type default)
			)
			(layer "F.SilkS")
		)
		(fp_line
			(start 0.67945 0.3048)
			(end 0.120396 0.3048)
			(stroke
				(width 0.1)
				(type default)
			)
			(layer "F.Fab")
		)
		(fp_line
			(start 0.67945 -0.3048)
			(end 0.67945 0.3048)
			(stroke
				(width 0.1)
				(type default)
			)
			(layer "F.Fab")
		)
		(fp_line
			(start 0.12065 -0.2794)
			(end 0.12065 -0.3048)
			(stroke
				(width 0.1)
				(type default)
			)
			(layer "F.Fab")
		)
		(fp_line
			(start 0.12065 -0.3048)
			(end 0.67945 -0.3048)
			(stroke
				(width 0.1)
				(type default)
			)
			(layer "F.Fab")
		)
		(fp_line
			(start 0.120396 0.3048)
			(end 0.120396 0.2794)
			(stroke
				(width 0.1)
				(type default)
			)
			(layer "F.Fab")
		)
		(fp_line
			(start 0.120396 0.2794)
			(end -0.12065 0.2794)
			(stroke
				(width 0.1)
				(type default)
			)
			(layer "F.Fab")
		)
		(fp_line
			(start -0.12065 0.3048)
			(end -0.67945 0.3048)
			(stroke
				(width 0.1)
				(type default)
			)
			(layer "F.Fab")
		)
		(fp_line
			(start -0.12065 0.2794)
			(end -0.12065 0.3048)
			(stroke
				(width 0.1)
				(type default)
			)
			(layer "F.Fab")
		)
		(fp_line
			(start -0.12065 -0.2794)
			(end 0.12065 -0.2794)
			(stroke
				(width 0.1)
				(type default)
			)
			(layer "F.Fab")
		)
		(fp_line
			(start -0.12065 -0.305054)
			(end -0.12065 -0.2794)
			(stroke
				(width 0.1)
				(type default)
			)
			(layer "F.Fab")
		)
		(fp_line
			(start -0.67945 0.3048)
			(end -0.67945 -0.305054)
			(stroke
				(width 0.1)
				(type default)
			)
			(layer "F.Fab")
		)
		(fp_line
			(start -0.67945 -0.305054)
			(end -0.12065 -0.305054)
			(stroke
				(width 0.1)
				(type default)
			)
			(layer "F.Fab")
		)
		(pad "1" smd circle
			(at -0.40005 0 180)
			(size 0 0)
			(layers "F.Cu" "F.Mask" "F.Paste")
			(net "NIC2_SLOT_ID0")
		)
		(pad "2" smd circle
			(at 0.40005 0 180)
			(size 0 0)
			(layers "F.Cu" "F.Mask" "F.Paste")
			(net "P3V3_NIC2")
		)
	)
	(footprint ""
		(layer "F.Cu")
		(at 35.298634 -137.259314 -90)
		(property "Reference" "C855"
			(at 0 0 270)
			(layer "F.SilkS")
			(hide yes)
			(effects
				(font
					(size 1.27 1.27)
				)
			)
		)
		(property "Value" ""
			(at 0 0 270)
			(layer "F.Fab")
			(effects
				(font
					(size 1.27 1.27)
				)
			)
		)
		(duplicate_pad_numbers_are_jumpers no)
		(fp_line
			(start -0.7874 0.4064)
			(end -0.7874 -0.4064)
			(stroke
				(width 0.1524)
				(type default)
			)
			(layer "F.SilkS")
		)
		(fp_line
			(start 0.7874 0.4064)
			(end -0.7874 0.4064)
			(stroke
				(width 0.1524)
				(type default)
			)
			(layer "F.SilkS")
		)
		(fp_line
			(start -0.7874 -0.4064)
			(end 0.7874 -0.4064)
			(stroke
				(width 0.1524)
				(type default)
			)
			(layer "F.SilkS")
		)
		(fp_line
			(start 0.7874 -0.4064)
			(end 0.7874 0.4064)
			(stroke
				(width 0.1524)
				(type default)
			)
			(layer "F.SilkS")
		)
		(fp_line
			(start -0.67945 0.3048)
			(end -0.67945 -0.305054)
			(stroke
				(width 0.1)
				(type default)
			)
			(layer "F.Fab")
		)
		(fp_line
			(start -0.12065 0.3048)
			(end -0.67945 0.3048)
			(stroke
				(width 0.1)
				(type default)
			)
			(layer "F.Fab")
		)
		(fp_line
			(start 0.120396 0.3048)
			(end 0.120396 0.2794)
			(stroke
				(width 0.1)
				(type default)
			)
			(layer "F.Fab")
		)
		(fp_line
			(start 0.67945 0.3048)
			(end 0.120396 0.3048)
			(stroke
				(width 0.1)
				(type default)
			)
			(layer "F.Fab")
		)
		(fp_line
			(start -0.12065 0.2794)
			(end -0.12065 0.3048)
			(stroke
				(width 0.1)
				(type default)
			)
			(layer "F.Fab")
		)
		(fp_line
			(start 0.120396 0.2794)
			(end -0.12065 0.2794)
			(stroke
				(width 0.1)
				(type default)
			)
			(layer "F.Fab")
		)
		(fp_line
			(start -0.12065 -0.2794)
			(end 0.12065 -0.2794)
			(stroke
				(width 0.1)
				(type default)
			)
			(layer "F.Fab")
		)
		(fp_line
			(start 0.12065 -0.2794)
			(end 0.12065 -0.3048)
			(stroke
				(width 0.1)
				(type default)
			)
			(layer "F.Fab")
		)
		(fp_line
			(start 0.12065 -0.3048)
			(end 0.67945 -0.3048)
			(stroke
				(width 0.1)
				(type default)
			)
			(layer "F.Fab")
		)
		(fp_line
			(start 0.67945 -0.3048)
			(end 0.67945 0.3048)
			(stroke
				(width 0.1)
				(type default)
			)
			(layer "F.Fab")
		)
		(fp_line
			(start -0.67945 -0.305054)
			(end -0.12065 -0.305054)
			(stroke
				(width 0.1)
				(type default)
			)
			(layer "F.Fab")
		)
		(fp_line
			(start -0.12065 -0.305054)
			(end -0.12065 -0.2794)
			(stroke
				(width 0.1)
				(type default)
			)
			(layer "F.Fab")
		)
		(pad "1" smd circle
			(at -0.40005 0 270)
			(size 0 0)
			(layers "F.Cu" "F.Mask" "F.Paste")
			(net "P3V3_NIC0")
		)
		(pad "2" smd circle
			(at 0.40005 0 270)
			(size 0 0)
			(layers "F.Cu" "F.Mask" "F.Paste")
			(net "GND")
		)
	)
	(footprint ""
		(layer "F.Cu")
		(at 235.619544 -148.736812 180)
		(property "Reference" "R1212"
			(at 0 0 180)
			(layer "F.SilkS")
			(hide yes)
			(effects
				(font
					(size 1.27 1.27)
				)
			)
		)
		(property "Value" ""
			(at 0 0 180)
			(layer "F.Fab")
			(effects
				(font
					(size 1.27 1.27)
				)
			)
		)
		(duplicate_pad_numbers_are_jumpers no)
		(fp_line
			(start -0.7874 -0.4064)
			(end 0.7874 -0.4064)
			(stroke
				(width 0.1524)
				(type default)
			)
			(layer "F.SilkS")
		)
		(fp_line
			(start 0.67945 0.3048)
			(end 0.120396 0.3048)
			(stroke
				(width 0.1)
				(type default)
			)
			(layer "F.Fab")
		)
		(fp_line
			(start 0.67945 -0.3048)
			(end 0.67945 0.3048)
			(stroke
				(width 0.1)
				(type default)
			)
			(layer "F.Fab")
		)
		(fp_line
			(start 0.12065 -0.2794)
			(end 0.12065 -0.3048)
			(stroke
				(width 0.1)
				(type default)
			)
			(layer "F.Fab")
		)
		(fp_line
			(start 0.12065 -0.3048)
			(end 0.67945 -0.3048)
			(stroke
				(width 0.1)
				(type default)
			)
			(layer "F.Fab")
		)
		(fp_line
			(start 0.120396 0.3048)
			(end 0.120396 0.2794)
			(stroke
				(width 0.1)
				(type default)
			)
			(layer "F.Fab")
		)
		(fp_line
			(start 0.120396 0.2794)
			(end -0.12065 0.2794)
			(stroke
				(width 0.1)
				(type default)
			)
			(layer "F.Fab")
		)
		(fp_line
			(start -0.12065 0.3048)
			(end -0.67945 0.3048)
			(stroke
				(width 0.1)
				(type default)
			)
			(layer "F.Fab")
		)
		(fp_line
			(start -0.12065 0.2794)
			(end -0.12065 0.3048)
			(stroke
				(width 0.1)
				(type default)
			)
			(layer "F.Fab")
		)
		(fp_line
			(start -0.12065 -0.2794)
			(end 0.12065 -0.2794)
			(stroke
				(width 0.1)
				(type default)
			)
			(layer "F.Fab")
		)
		(fp_line
			(start -0.12065 -0.305054)
			(end -0.12065 -0.2794)
			(stroke
				(width 0.1)
				(type default)
			)
			(layer "F.Fab")
		)
		(fp_line
			(start -0.67945 0.3048)
			(end -0.67945 -0.305054)
			(stroke
				(width 0.1)
				(type default)
			)
			(layer "F.Fab")
		)
		(fp_line
			(start -0.67945 -0.305054)
			(end -0.12065 -0.305054)
			(stroke
				(width 0.1)
				(type default)
			)
			(layer "F.Fab")
		)
		(pad "1" smd circle
			(at -0.40005 0 180)
			(size 0 0)
			(layers "F.Cu" "F.Mask" "F.Paste")
			(net "CLK_100M_PEX3_REF_R_DN")
		)
		(pad "2" smd circle
			(at 0.40005 0 180)
			(size 0 0)
			(layers "F.Cu" "F.Mask" "F.Paste")
			(net "CLK_100M_PEX3_REF_DN")
		)
	)
	(footprint ""
		(layer "F.Cu")
		(at 406.36444 -141.6558 180)
		(property "Reference" "R341"
			(at 0 0 180)
			(layer "F.SilkS")
			(hide yes)
			(effects
				(font
					(size 1.27 1.27)
				)
			)
		)
		(property "Value" ""
			(at 0 0 180)
			(layer "F.Fab")
			(effects
				(font
					(size 1.27 1.27)
				)
			)
		)
		(duplicate_pad_numbers_are_jumpers no)
		(fp_line
			(start 0.7874 0.4064)
			(end -0.7874 0.4064)
			(stroke
				(width 0.1524)
				(type default)
			)
			(layer "F.SilkS")
		)
		(fp_line
			(start 0.7874 -0.4064)
			(end 0.7874 0.4064)
			(stroke
				(width 0.1524)
				(type default)
			)
			(layer "F.SilkS")
		)
		(fp_line
			(start -0.7874 0.4064)
			(end -0.7874 -0.4064)
			(stroke
				(width 0.1524)
				(type default)
			)
			(layer "F.SilkS")
		)
		(fp_line
			(start -0.7874 -0.4064)
			(end 0.7874 -0.4064)
			(stroke
				(width 0.1524)
				(type default)
			)
			(layer "F.SilkS")
		)
		(fp_line
			(start 0.67945 0.3048)
			(end 0.120396 0.3048)
			(stroke
				(width 0.1)
				(type default)
			)
			(layer "F.Fab")
		)
		(fp_line
			(start 0.67945 -0.3048)
			(end 0.67945 0.3048)
			(stroke
				(width 0.1)
				(type default)
			)
			(layer "F.Fab")
		)
		(fp_line
			(start 0.12065 -0.2794)
			(end 0.12065 -0.3048)
			(stroke
				(width 0.1)
				(type default)
			)
			(layer "F.Fab")
		)
		(fp_line
			(start 0.12065 -0.3048)
			(end 0.67945 -0.3048)
			(stroke
				(width 0.1)
				(type default)
			)
			(layer "F.Fab")
		)
		(fp_line
			(start 0.120396 0.3048)
			(end 0.120396 0.2794)
			(stroke
				(width 0.1)
				(type default)
			)
			(layer "F.Fab")
		)
		(fp_line
			(start 0.120396 0.2794)
			(end -0.12065 0.2794)
			(stroke
				(width 0.1)
				(type default)
			)
			(layer "F.Fab")
		)
		(fp_line
			(start -0.12065 0.3048)
			(end -0.67945 0.3048)
			(stroke
				(width 0.1)
				(type default)
			)
			(layer "F.Fab")
		)
		(fp_line
			(start -0.12065 0.2794)
			(end -0.12065 0.3048)
			(stroke
				(width 0.1)
				(type default)
			)
			(layer "F.Fab")
		)
		(fp_line
			(start -0.12065 -0.2794)
			(end 0.12065 -0.2794)
			(stroke
				(width 0.1)
				(type default)
			)
			(layer "F.Fab")
		)
		(fp_line
			(start -0.12065 -0.305054)
			(end -0.12065 -0.2794)
			(stroke
				(width 0.1)
				(type default)
			)
			(layer "F.Fab")
		)
		(fp_line
			(start -0.67945 0.3048)
			(end -0.67945 -0.305054)
			(stroke
				(width 0.1)
				(type default)
			)
			(layer "F.Fab")
		)
		(fp_line
			(start -0.67945 -0.305054)
			(end -0.12065 -0.305054)
			(stroke
				(width 0.1)
				(type default)
			)
			(layer "F.Fab")
		)
		(pad "1" smd circle
			(at -0.40005 0 180)
			(size 0 0)
			(layers "F.Cu" "F.Mask" "F.Paste")
			(net "RST_SMB_NIC6_MUX_ISO_N")
		)
		(pad "2" smd circle
			(at 0.40005 0 180)
			(size 0 0)
			(layers "F.Cu" "F.Mask" "F.Paste")
			(net "P3V3_NIC6")
		)
	)
	(footprint ""
		(layer "F.Cu")
		(at 4.541266 -372.011448)
		(property "Reference" "R6759"
			(at 0 0 0)
			(layer "F.SilkS")
			(hide yes)
			(effects
				(font
					(size 1.27 1.27)
				)
			)
		)
		(property "Value" ""
			(at 0 0 0)
			(layer "F.Fab")
			(effects
				(font
					(size 1.27 1.27)
				)
			)
		)
		(duplicate_pad_numbers_are_jumpers no)
		(fp_line
			(start -0.7874 -0.4064)
			(end 0.7874 -0.4064)
			(stroke
				(width 0.1524)
				(type default)
			)
			(layer "F.SilkS")
		)
		(fp_line
			(start -0.7874 0.4064)
			(end -0.7874 -0.4064)
			(stroke
				(width 0.1524)
				(type default)
			)
			(layer "F.SilkS")
		)
		(fp_line
			(start 0.7874 -0.4064)
			(end 0.7874 0.4064)
			(stroke
				(width 0.1524)
				(type default)
			)
			(layer "F.SilkS")
		)
		(fp_line
			(start 0.7874 0.4064)
			(end -0.7874 0.4064)
			(stroke
				(width 0.1524)
				(type default)
			)
			(layer "F.SilkS")
		)
		(fp_line
			(start -0.67945 -0.305054)
			(end -0.12065 -0.305054)
			(stroke
				(width 0.1)
				(type default)
			)
			(layer "F.Fab")
		)
		(fp_line
			(start -0.67945 0.3048)
			(end -0.67945 -0.305054)
			(stroke
				(width 0.1)
				(type default)
			)
			(layer "F.Fab")
		)
		(fp_line
			(start -0.12065 -0.305054)
			(end -0.12065 -0.2794)
			(stroke
				(width 0.1)
				(type default)
			)
			(layer "F.Fab")
		)
		(fp_line
			(start -0.12065 -0.2794)
			(end 0.12065 -0.2794)
			(stroke
				(width 0.1)
				(type default)
			)
			(layer "F.Fab")
		)
		(fp_line
			(start -0.12065 0.2794)
			(end -0.12065 0.3048)
			(stroke
				(width 0.1)
				(type default)
			)
			(layer "F.Fab")
		)
		(fp_line
			(start -0.12065 0.3048)
			(end -0.67945 0.3048)
			(stroke
				(width 0.1)
				(type default)
			)
			(layer "F.Fab")
		)
		(fp_line
			(start 0.120396 0.2794)
			(end -0.12065 0.2794)
			(stroke
				(width 0.1)
				(type default)
			)
			(layer "F.Fab")
		)
		(fp_line
			(start 0.120396 0.3048)
			(end 0.120396 0.2794)
			(stroke
				(width 0.1)
				(type default)
			)
			(layer "F.Fab")
		)
		(fp_line
			(start 0.12065 -0.3048)
			(end 0.67945 -0.3048)
			(stroke
				(width 0.1)
				(type default)
			)
			(layer "F.Fab")
		)
		(fp_line
			(start 0.12065 -0.2794)
			(end 0.12065 -0.3048)
			(stroke
				(width 0.1)
				(type default)
			)
			(layer "F.Fab")
		)
		(fp_line
			(start 0.67945 -0.3048)
			(end 0.67945 0.3048)
			(stroke
				(width 0.1)
				(type default)
			)
			(layer "F.Fab")
		)
		(fp_line
			(start 0.67945 0.3048)
			(end 0.120396 0.3048)
			(stroke
				(width 0.1)
				(type default)
			)
			(layer "F.Fab")
		)
		(pad "1" smd circle
			(at -0.40005 0)
			(size 0 0)
			(layers "F.Cu" "F.Mask" "F.Paste")
			(net "P3V3_USB_HUB")
		)
		(pad "2" smd circle
			(at 0.40005 0)
			(size 0 0)
			(layers "F.Cu" "F.Mask" "F.Paste")
			(net "GND")
		)
	)
	(footprint ""
		(layer "F.Cu")
		(at 147.756372 -61.487812 180)
		(property "Reference" "R5973"
			(at 0 0 180)
			(layer "F.SilkS")
			(hide yes)
			(effects
				(font
					(size 1.27 1.27)
				)
			)
		)
		(property "Value" ""
			(at 0 0 180)
			(layer "F.Fab")
			(effects
				(font
					(size 1.27 1.27)
				)
			)
		)
		(duplicate_pad_numbers_are_jumpers no)
		(fp_line
			(start 0.7874 0.4064)
			(end -0.7874 0.4064)
			(stroke
				(width 0.1524)
				(type default)
			)
			(layer "F.SilkS")
		)
		(fp_line
			(start 0.7874 -0.4064)
			(end 0.7874 0.4064)
			(stroke
				(width 0.1524)
				(type default)
			)
			(layer "F.SilkS")
		)
		(fp_line
			(start -0.7874 0.4064)
			(end -0.7874 -0.4064)
			(stroke
				(width 0.1524)
				(type default)
			)
			(layer "F.SilkS")
		)
		(fp_line
			(start -0.7874 -0.4064)
			(end 0.7874 -0.4064)
			(stroke
				(width 0.1524)
				(type default)
			)
			(layer "F.SilkS")
		)
		(fp_line
			(start 0.67945 0.3048)
			(end 0.120396 0.3048)
			(stroke
				(width 0.1)
				(type default)
			)
			(layer "F.Fab")
		)
		(fp_line
			(start 0.67945 -0.3048)
			(end 0.67945 0.3048)
			(stroke
				(width 0.1)
				(type default)
			)
			(layer "F.Fab")
		)
		(fp_line
			(start 0.12065 -0.2794)
			(end 0.12065 -0.3048)
			(stroke
				(width 0.1)
				(type default)
			)
			(layer "F.Fab")
		)
		(fp_line
			(start 0.12065 -0.3048)
			(end 0.67945 -0.3048)
			(stroke
				(width 0.1)
				(type default)
			)
			(layer "F.Fab")
		)
		(fp_line
			(start 0.120396 0.3048)
			(end 0.120396 0.2794)
			(stroke
				(width 0.1)
				(type default)
			)
			(layer "F.Fab")
		)
		(fp_line
			(start 0.120396 0.2794)
			(end -0.12065 0.2794)
			(stroke
				(width 0.1)
				(type default)
			)
			(layer "F.Fab")
		)
		(fp_line
			(start -0.12065 0.3048)
			(end -0.67945 0.3048)
			(stroke
				(width 0.1)
				(type default)
			)
			(layer "F.Fab")
		)
		(fp_line
			(start -0.12065 0.2794)
			(end -0.12065 0.3048)
			(stroke
				(width 0.1)
				(type default)
			)
			(layer "F.Fab")
		)
		(fp_line
			(start -0.12065 -0.2794)
			(end 0.12065 -0.2794)
			(stroke
				(width 0.1)
				(type default)
			)
			(layer "F.Fab")
		)
		(fp_line
			(start -0.12065 -0.305054)
			(end -0.12065 -0.2794)
			(stroke
				(width 0.1)
				(type default)
			)
			(layer "F.Fab")
		)
		(fp_line
			(start -0.67945 0.3048)
			(end -0.67945 -0.305054)
			(stroke
				(width 0.1)
				(type default)
			)
			(layer "F.Fab")
		)
		(fp_line
			(start -0.67945 -0.305054)
			(end -0.12065 -0.305054)
			(stroke
				(width 0.1)
				(type default)
			)
			(layer "F.Fab")
		)
		(pad "1" smd circle
			(at -0.40005 0 180)
			(size 0 0)
			(layers "F.Cu" "F.Mask" "F.Paste")
			(net "P3V3_AUX")
		)
		(pad "2" smd circle
			(at 0.40005 0 180)
			(size 0 0)
			(layers "F.Cu" "F.Mask" "F.Paste")
			(net "PWRGD_P12V_SSD5_D")
		)
	)
	(footprint ""
		(layer "F.Cu")
		(at 80.019398 -123.184666 180)
		(property "Reference" "C27"
			(at 0 0 180)
			(layer "F.SilkS")
			(hide yes)
			(effects
				(font
					(size 1.27 1.27)
				)
			)
		)
		(property "Value" ""
			(at 0 0 180)
			(layer "F.Fab")
			(effects
				(font
					(size 1.27 1.27)
				)
			)
		)
		(duplicate_pad_numbers_are_jumpers no)
		(fp_line
			(start 0.299974 0.150114)
			(end -0.299974 0.150114)
			(stroke
				(width 0.1)
				(type default)
			)
			(layer "F.Fab")
		)
		(fp_line
			(start 0.299974 -0.150114)
			(end 0.299974 0.150114)
			(stroke
				(width 0.1)
				(type default)
			)
			(layer "F.Fab")
		)
		(fp_line
			(start -0.299974 0.150114)
			(end -0.299974 -0.150114)
			(stroke
				(width 0.1)
				(type default)
			)
			(layer "F.Fab")
		)
		(fp_line
			(start -0.299974 -0.150114)
			(end 0.299974 -0.150114)
			(stroke
				(width 0.1)
				(type default)
			)
			(layer "F.Fab")
		)
		(pad "1" smd rect
			(at -0.2667 0 180)
			(size 0.3048 0.381)
			(layers "F.Cu" "F.Mask" "F.Paste")
			(net "P5E_PEX0_STN0_TX_DP<2>")
		)
		(pad "2" smd rect
			(at 0.2667 0 180)
			(size 0.3048 0.381)
			(layers "F.Cu" "F.Mask" "F.Paste")
			(net "P5E_PEX0_STN0_TX_C_DP<2>")
		)
	)
	(footprint ""
		(layer "F.Cu")
		(at 431.01514 -59.546236 90)
		(property "Reference" "C2899"
			(at 0 0 90)
			(layer "F.SilkS")
			(hide yes)
			(effects
				(font
					(size 1.27 1.27)
				)
			)
		)
		(property "Value" ""
			(at 0 0 90)
			(layer "F.Fab")
			(effects
				(font
					(size 1.27 1.27)
				)
			)
		)
		(duplicate_pad_numbers_are_jumpers no)
		(fp_line
			(start 0.7874 -0.4064)
			(end 0.7874 0.4064)
			(stroke
				(width 0.1524)
				(type default)
			)
			(layer "F.SilkS")
		)
		(fp_line
			(start -0.7874 -0.4064)
			(end 0.7874 -0.4064)
			(stroke
				(width 0.1524)
				(type default)
			)
			(layer "F.SilkS")
		)
		(fp_line
			(start 0.7874 0.4064)
			(end -0.7874 0.4064)
			(stroke
				(width 0.1524)
				(type default)
			)
			(layer "F.SilkS")
		)
		(fp_line
			(start -0.7874 0.4064)
			(end -0.7874 -0.4064)
			(stroke
				(width 0.1524)
				(type default)
			)
			(layer "F.SilkS")
		)
		(fp_line
			(start -0.12065 -0.305054)
			(end -0.12065 -0.2794)
			(stroke
				(width 0.1)
				(type default)
			)
			(layer "F.Fab")
		)
		(fp_line
			(start -0.67945 -0.305054)
			(end -0.12065 -0.305054)
			(stroke
				(width 0.1)
				(type default)
			)
			(layer "F.Fab")
		)
		(fp_line
			(start 0.67945 -0.3048)
			(end 0.67945 0.3048)
			(stroke
				(width 0.1)
				(type default)
			)
			(layer "F.Fab")
		)
		(fp_line
			(start 0.12065 -0.3048)
			(end 0.67945 -0.3048)
			(stroke
				(width 0.1)
				(type default)
			)
			(layer "F.Fab")
		)
		(fp_line
			(start 0.12065 -0.2794)
			(end 0.12065 -0.3048)
			(stroke
				(width 0.1)
				(type default)
			)
			(layer "F.Fab")
		)
		(fp_line
			(start -0.12065 -0.2794)
			(end 0.12065 -0.2794)
			(stroke
				(width 0.1)
				(type default)
			)
			(layer "F.Fab")
		)
		(fp_line
			(start 0.120396 0.2794)
			(end -0.12065 0.2794)
			(stroke
				(width 0.1)
				(type default)
			)
			(layer "F.Fab")
		)
		(fp_line
			(start -0.12065 0.2794)
			(end -0.12065 0.3048)
			(stroke
				(width 0.1)
				(type default)
			)
			(layer "F.Fab")
		)
		(fp_line
			(start 0.67945 0.3048)
			(end 0.120396 0.3048)
			(stroke
				(width 0.1)
				(type default)
			)
			(layer "F.Fab")
		)
		(fp_line
			(start 0.120396 0.3048)
			(end 0.120396 0.2794)
			(stroke
				(width 0.1)
				(type default)
			)
			(layer "F.Fab")
		)
		(fp_line
			(start -0.12065 0.3048)
			(end -0.67945 0.3048)
			(stroke
				(width 0.1)
				(type default)
			)
			(layer "F.Fab")
		)
		(fp_line
			(start -0.67945 0.3048)
			(end -0.67945 -0.305054)
			(stroke
				(width 0.1)
				(type default)
			)
			(layer "F.Fab")
		)
		(pad "1" smd circle
			(at -0.40005 0 90)
			(size 0 0)
			(layers "F.Cu" "F.Mask" "F.Paste")
			(net "SSD15_AUX_P3V3_EN_R")
		)
		(pad "2" smd circle
			(at 0.40005 0 90)
			(size 0 0)
			(layers "F.Cu" "F.Mask" "F.Paste")
			(net "GND")
		)
	)
	(footprint ""
		(layer "F.Cu")
		(at 10.716768 -162.003994 90)
		(property "Reference" "PC612"
			(at 0 0 90)
			(layer "F.SilkS")
			(hide yes)
			(effects
				(font
					(size 1.27 1.27)
				)
			)
		)
		(property "Value" ""
			(at 0 0 90)
			(layer "F.Fab")
			(effects
				(font
					(size 1.27 1.27)
				)
			)
		)
		(duplicate_pad_numbers_are_jumpers no)
		(fp_line
			(start 0.7874 -0.4064)
			(end 0.7874 0.4064)
			(stroke
				(width 0.1524)
				(type default)
			)
			(layer "F.SilkS")
		)
		(fp_line
			(start -0.7874 -0.4064)
			(end 0.7874 -0.4064)
			(stroke
				(width 0.1524)
				(type default)
			)
			(layer "F.SilkS")
		)
		(fp_line
			(start 0.7874 0.4064)
			(end -0.7874 0.4064)
			(stroke
				(width 0.1524)
				(type default)
			)
			(layer "F.SilkS")
		)
		(fp_line
			(start -0.7874 0.4064)
			(end -0.7874 -0.4064)
			(stroke
				(width 0.1524)
				(type default)
			)
			(layer "F.SilkS")
		)
		(fp_line
			(start -0.12065 -0.305054)
			(end -0.12065 -0.2794)
			(stroke
				(width 0.1)
				(type default)
			)
			(layer "F.Fab")
		)
		(fp_line
			(start -0.67945 -0.305054)
			(end -0.12065 -0.305054)
			(stroke
				(width 0.1)
				(type default)
			)
			(layer "F.Fab")
		)
		(fp_line
			(start 0.67945 -0.3048)
			(end 0.67945 0.3048)
			(stroke
				(width 0.1)
				(type default)
			)
			(layer "F.Fab")
		)
		(fp_line
			(start 0.12065 -0.3048)
			(end 0.67945 -0.3048)
			(stroke
				(width 0.1)
				(type default)
			)
			(layer "F.Fab")
		)
		(fp_line
			(start 0.12065 -0.2794)
			(end 0.12065 -0.3048)
			(stroke
				(width 0.1)
				(type default)
			)
			(layer "F.Fab")
		)
		(fp_line
			(start -0.12065 -0.2794)
			(end 0.12065 -0.2794)
			(stroke
				(width 0.1)
				(type default)
			)
			(layer "F.Fab")
		)
		(fp_line
			(start 0.120396 0.2794)
			(end -0.12065 0.2794)
			(stroke
				(width 0.1)
				(type default)
			)
			(layer "F.Fab")
		)
		(fp_line
			(start -0.12065 0.2794)
			(end -0.12065 0.3048)
			(stroke
				(width 0.1)
				(type default)
			)
			(layer "F.Fab")
		)
		(fp_line
			(start 0.67945 0.3048)
			(end 0.120396 0.3048)
			(stroke
				(width 0.1)
				(type default)
			)
			(layer "F.Fab")
		)
		(fp_line
			(start 0.120396 0.3048)
			(end 0.120396 0.2794)
			(stroke
				(width 0.1)
				(type default)
			)
			(layer "F.Fab")
		)
		(fp_line
			(start -0.12065 0.3048)
			(end -0.67945 0.3048)
			(stroke
				(width 0.1)
				(type default)
			)
			(layer "F.Fab")
		)
		(fp_line
			(start -0.67945 0.3048)
			(end -0.67945 -0.305054)
			(stroke
				(width 0.1)
				(type default)
			)
			(layer "F.Fab")
		)
		(pad "1" smd circle
			(at -0.40005 0 90)
			(size 0 0)
			(layers "F.Cu" "F.Mask" "F.Paste")
			(net "P12V_NIC0_CO_SS")
		)
		(pad "2" smd circle
			(at 0.40005 0 90)
			(size 0 0)
			(layers "F.Cu" "F.Mask" "F.Paste")
			(net "GND")
		)
	)
	(footprint ""
		(layer "F.Cu")
		(at 118.975378 -64.102234 180)
		(property "Reference" "PR7067"
			(at 0 0 180)
			(layer "F.SilkS")
			(hide yes)
			(effects
				(font
					(size 1.27 1.27)
				)
			)
		)
		(property "Value" ""
			(at 0 0 180)
			(layer "F.Fab")
			(effects
				(font
					(size 1.27 1.27)
				)
			)
		)
		(duplicate_pad_numbers_are_jumpers no)
		(fp_line
			(start 0.7874 0.4064)
			(end -0.7874 0.4064)
			(stroke
				(width 0.1524)
				(type default)
			)
			(layer "F.SilkS")
		)
		(fp_line
			(start 0.7874 -0.4064)
			(end 0.7874 0.4064)
			(stroke
				(width 0.1524)
				(type default)
			)
			(layer "F.SilkS")
		)
		(fp_line
			(start -0.7874 0.4064)
			(end -0.7874 -0.4064)
			(stroke
				(width 0.1524)
				(type default)
			)
			(layer "F.SilkS")
		)
		(fp_line
			(start -0.7874 -0.4064)
			(end 0.7874 -0.4064)
			(stroke
				(width 0.1524)
				(type default)
			)
			(layer "F.SilkS")
		)
		(fp_line
			(start 0.67945 0.3048)
			(end 0.120396 0.3048)
			(stroke
				(width 0.1)
				(type default)
			)
			(layer "F.Fab")
		)
		(fp_line
			(start 0.67945 -0.3048)
			(end 0.67945 0.3048)
			(stroke
				(width 0.1)
				(type default)
			)
			(layer "F.Fab")
		)
		(fp_line
			(start 0.12065 -0.2794)
			(end 0.12065 -0.3048)
			(stroke
				(width 0.1)
				(type default)
			)
			(layer "F.Fab")
		)
		(fp_line
			(start 0.12065 -0.3048)
			(end 0.67945 -0.3048)
			(stroke
				(width 0.1)
				(type default)
			)
			(layer "F.Fab")
		)
		(fp_line
			(start 0.120396 0.3048)
			(end 0.120396 0.2794)
			(stroke
				(width 0.1)
				(type default)
			)
			(layer "F.Fab")
		)
		(fp_line
			(start 0.120396 0.2794)
			(end -0.12065 0.2794)
			(stroke
				(width 0.1)
				(type default)
			)
			(layer "F.Fab")
		)
		(fp_line
			(start -0.12065 0.3048)
			(end -0.67945 0.3048)
			(stroke
				(width 0.1)
				(type default)
			)
			(layer "F.Fab")
		)
		(fp_line
			(start -0.12065 0.2794)
			(end -0.12065 0.3048)
			(stroke
				(width 0.1)
				(type default)
			)
			(layer "F.Fab")
		)
		(fp_line
			(start -0.12065 -0.2794)
			(end 0.12065 -0.2794)
			(stroke
				(width 0.1)
				(type default)
			)
			(layer "F.Fab")
		)
		(fp_line
			(start -0.12065 -0.305054)
			(end -0.12065 -0.2794)
			(stroke
				(width 0.1)
				(type default)
			)
			(layer "F.Fab")
		)
		(fp_line
			(start -0.67945 0.3048)
			(end -0.67945 -0.305054)
			(stroke
				(width 0.1)
				(type default)
			)
			(layer "F.Fab")
		)
		(fp_line
			(start -0.67945 -0.305054)
			(end -0.12065 -0.305054)
			(stroke
				(width 0.1)
				(type default)
			)
			(layer "F.Fab")
		)
		(pad "1" smd circle
			(at -0.40005 0 180)
			(size 0 0)
			(layers "F.Cu" "F.Mask" "F.Paste")
			(net "P12V_SSD4_PG_G1")
		)
		(pad "2" smd circle
			(at 0.40005 0 180)
			(size 0 0)
			(layers "F.Cu" "F.Mask" "F.Paste")
			(net "GND")
		)
	)
	(footprint ""
		(layer "F.Cu")
		(at 20.274026 -72.766682 90)
		(property "Reference" "PR6904"
			(at 0 0 90)
			(layer "F.SilkS")
			(hide yes)
			(effects
				(font
					(size 1.27 1.27)
				)
			)
		)
		(property "Value" ""
			(at 0 0 90)
			(layer "F.Fab")
			(effects
				(font
					(size 1.27 1.27)
				)
			)
		)
		(duplicate_pad_numbers_are_jumpers no)
		(fp_line
			(start 0.7874 -0.4064)
			(end 0.7874 0.4064)
			(stroke
				(width 0.1524)
				(type default)
			)
			(layer "F.SilkS")
		)
		(fp_line
			(start -0.7874 -0.4064)
			(end 0.7874 -0.4064)
			(stroke
				(width 0.1524)
				(type default)
			)
			(layer "F.SilkS")
		)
		(fp_line
			(start 0.7874 0.4064)
			(end -0.7874 0.4064)
			(stroke
				(width 0.1524)
				(type default)
			)
			(layer "F.SilkS")
		)
		(fp_line
			(start -0.7874 0.4064)
			(end -0.7874 -0.4064)
			(stroke
				(width 0.1524)
				(type default)
			)
			(layer "F.SilkS")
		)
		(fp_line
			(start -0.12065 -0.305054)
			(end -0.12065 -0.2794)
			(stroke
				(width 0.1)
				(type default)
			)
			(layer "F.Fab")
		)
		(fp_line
			(start -0.67945 -0.305054)
			(end -0.12065 -0.305054)
			(stroke
				(width 0.1)
				(type default)
			)
			(layer "F.Fab")
		)
		(fp_line
			(start 0.67945 -0.3048)
			(end 0.67945 0.3048)
			(stroke
				(width 0.1)
				(type default)
			)
			(layer "F.Fab")
		)
		(fp_line
			(start 0.12065 -0.3048)
			(end 0.67945 -0.3048)
			(stroke
				(width 0.1)
				(type default)
			)
			(layer "F.Fab")
		)
		(fp_line
			(start 0.12065 -0.2794)
			(end 0.12065 -0.3048)
			(stroke
				(width 0.1)
				(type default)
			)
			(layer "F.Fab")
		)
		(fp_line
			(start -0.12065 -0.2794)
			(end 0.12065 -0.2794)
			(stroke
				(width 0.1)
				(type default)
			)
			(layer "F.Fab")
		)
		(fp_line
			(start 0.120396 0.2794)
			(end -0.12065 0.2794)
			(stroke
				(width 0.1)
				(type default)
			)
			(layer "F.Fab")
		)
		(fp_line
			(start -0.12065 0.2794)
			(end -0.12065 0.3048)
			(stroke
				(width 0.1)
				(type default)
			)
			(layer "F.Fab")
		)
		(fp_line
			(start 0.67945 0.3048)
			(end 0.120396 0.3048)
			(stroke
				(width 0.1)
				(type default)
			)
			(layer "F.Fab")
		)
		(fp_line
			(start 0.120396 0.3048)
			(end 0.120396 0.2794)
			(stroke
				(width 0.1)
				(type default)
			)
			(layer "F.Fab")
		)
		(fp_line
			(start -0.12065 0.3048)
			(end -0.67945 0.3048)
			(stroke
				(width 0.1)
				(type default)
			)
			(layer "F.Fab")
		)
		(fp_line
			(start -0.67945 0.3048)
			(end -0.67945 -0.305054)
			(stroke
				(width 0.1)
				(type default)
			)
			(layer "F.Fab")
		)
		(pad "1" smd circle
			(at -0.40005 0 90)
			(size 0 0)
			(layers "F.Cu" "F.Mask" "F.Paste")
			(net "P12V_SSD0_CO_MODE")
		)
		(pad "2" smd circle
			(at 0.40005 0 90)
			(size 0 0)
			(layers "F.Cu" "F.Mask" "F.Paste")
			(net "GND")
		)
	)
	(footprint ""
		(layer "F.Cu")
		(at 336.042 -161.798 180)
		(property "Reference" "R4808"
			(at 0 0 180)
			(layer "F.SilkS")
			(hide yes)
			(effects
				(font
					(size 1.27 1.27)
				)
			)
		)
		(property "Value" ""
			(at 0 0 180)
			(layer "F.Fab")
			(effects
				(font
					(size 1.27 1.27)
				)
			)
		)
		(duplicate_pad_numbers_are_jumpers no)
		(fp_line
			(start 0.7874 0.4064)
			(end -0.7874 0.4064)
			(stroke
				(width 0.1524)
				(type default)
			)
			(layer "F.SilkS")
		)
		(fp_line
			(start 0.7874 -0.4064)
			(end 0.7874 0.4064)
			(stroke
				(width 0.1524)
				(type default)
			)
			(layer "F.SilkS")
		)
		(fp_line
			(start -0.7874 0.4064)
			(end -0.7874 -0.4064)
			(stroke
				(width 0.1524)
				(type default)
			)
			(layer "F.SilkS")
		)
		(fp_line
			(start -0.7874 -0.4064)
			(end 0.7874 -0.4064)
			(stroke
				(width 0.1524)
				(type default)
			)
			(layer "F.SilkS")
		)
		(fp_line
			(start 0.67945 0.3048)
			(end 0.120396 0.3048)
			(stroke
				(width 0.1)
				(type default)
			)
			(layer "F.Fab")
		)
		(fp_line
			(start 0.67945 -0.3048)
			(end 0.67945 0.3048)
			(stroke
				(width 0.1)
				(type default)
			)
			(layer "F.Fab")
		)
		(fp_line
			(start 0.12065 -0.2794)
			(end 0.12065 -0.3048)
			(stroke
				(width 0.1)
				(type default)
			)
			(layer "F.Fab")
		)
		(fp_line
			(start 0.12065 -0.3048)
			(end 0.67945 -0.3048)
			(stroke
				(width 0.1)
				(type default)
			)
			(layer "F.Fab")
		)
		(fp_line
			(start 0.120396 0.3048)
			(end 0.120396 0.2794)
			(stroke
				(width 0.1)
				(type default)
			)
			(layer "F.Fab")
		)
		(fp_line
			(start 0.120396 0.2794)
			(end -0.12065 0.2794)
			(stroke
				(width 0.1)
				(type default)
			)
			(layer "F.Fab")
		)
		(fp_line
			(start -0.12065 0.3048)
			(end -0.67945 0.3048)
			(stroke
				(width 0.1)
				(type default)
			)
			(layer "F.Fab")
		)
		(fp_line
			(start -0.12065 0.2794)
			(end -0.12065 0.3048)
			(stroke
				(width 0.1)
				(type default)
			)
			(layer "F.Fab")
		)
		(fp_line
			(start -0.12065 -0.2794)
			(end 0.12065 -0.2794)
			(stroke
				(width 0.1)
				(type default)
			)
			(layer "F.Fab")
		)
		(fp_line
			(start -0.12065 -0.305054)
			(end -0.12065 -0.2794)
			(stroke
				(width 0.1)
				(type default)
			)
			(layer "F.Fab")
		)
		(fp_line
			(start -0.67945 0.3048)
			(end -0.67945 -0.305054)
			(stroke
				(width 0.1)
				(type default)
			)
			(layer "F.Fab")
		)
		(fp_line
			(start -0.67945 -0.305054)
			(end -0.12065 -0.305054)
			(stroke
				(width 0.1)
				(type default)
			)
			(layer "F.Fab")
		)
		(pad "1" smd circle
			(at -0.40005 0 180)
			(size 0 0)
			(layers "F.Cu" "F.Mask" "F.Paste")
			(net "PCA9555_0_PEX3_A1")
		)
		(pad "2" smd circle
			(at 0.40005 0 180)
			(size 0 0)
			(layers "F.Cu" "F.Mask" "F.Paste")
			(net "P3V3_AUX")
		)
	)
	(footprint ""
		(layer "F.Cu")
		(at 172.81525 -59.546236 90)
		(property "Reference" "C2890"
			(at 0 0 90)
			(layer "F.SilkS")
			(hide yes)
			(effects
				(font
					(size 1.27 1.27)
				)
			)
		)
		(property "Value" ""
			(at 0 0 90)
			(layer "F.Fab")
			(effects
				(font
					(size 1.27 1.27)
				)
			)
		)
		(duplicate_pad_numbers_are_jumpers no)
		(fp_line
			(start 0.7874 -0.4064)
			(end 0.7874 0.4064)
			(stroke
				(width 0.1524)
				(type default)
			)
			(layer "F.SilkS")
		)
		(fp_line
			(start -0.7874 -0.4064)
			(end 0.7874 -0.4064)
			(stroke
				(width 0.1524)
				(type default)
			)
			(layer "F.SilkS")
		)
		(fp_line
			(start 0.7874 0.4064)
			(end -0.7874 0.4064)
			(stroke
				(width 0.1524)
				(type default)
			)
			(layer "F.SilkS")
		)
		(fp_line
			(start -0.7874 0.4064)
			(end -0.7874 -0.4064)
			(stroke
				(width 0.1524)
				(type default)
			)
			(layer "F.SilkS")
		)
		(fp_line
			(start -0.12065 -0.305054)
			(end -0.12065 -0.2794)
			(stroke
				(width 0.1)
				(type default)
			)
			(layer "F.Fab")
		)
		(fp_line
			(start -0.67945 -0.305054)
			(end -0.12065 -0.305054)
			(stroke
				(width 0.1)
				(type default)
			)
			(layer "F.Fab")
		)
		(fp_line
			(start 0.67945 -0.3048)
			(end 0.67945 0.3048)
			(stroke
				(width 0.1)
				(type default)
			)
			(layer "F.Fab")
		)
		(fp_line
			(start 0.12065 -0.3048)
			(end 0.67945 -0.3048)
			(stroke
				(width 0.1)
				(type default)
			)
			(layer "F.Fab")
		)
		(fp_line
			(start 0.12065 -0.2794)
			(end 0.12065 -0.3048)
			(stroke
				(width 0.1)
				(type default)
			)
			(layer "F.Fab")
		)
		(fp_line
			(start -0.12065 -0.2794)
			(end 0.12065 -0.2794)
			(stroke
				(width 0.1)
				(type default)
			)
			(layer "F.Fab")
		)
		(fp_line
			(start 0.120396 0.2794)
			(end -0.12065 0.2794)
			(stroke
				(width 0.1)
				(type default)
			)
			(layer "F.Fab")
		)
		(fp_line
			(start -0.12065 0.2794)
			(end -0.12065 0.3048)
			(stroke
				(width 0.1)
				(type default)
			)
			(layer "F.Fab")
		)
		(fp_line
			(start 0.67945 0.3048)
			(end 0.120396 0.3048)
			(stroke
				(width 0.1)
				(type default)
			)
			(layer "F.Fab")
		)
		(fp_line
			(start 0.120396 0.3048)
			(end 0.120396 0.2794)
			(stroke
				(width 0.1)
				(type default)
			)
			(layer "F.Fab")
		)
		(fp_line
			(start -0.12065 0.3048)
			(end -0.67945 0.3048)
			(stroke
				(width 0.1)
				(type default)
			)
			(layer "F.Fab")
		)
		(fp_line
			(start -0.67945 0.3048)
			(end -0.67945 -0.305054)
			(stroke
				(width 0.1)
				(type default)
			)
			(layer "F.Fab")
		)
		(pad "1" smd circle
			(at -0.40005 0 90)
			(size 0 0)
			(layers "F.Cu" "F.Mask" "F.Paste")
			(net "SSD6_AUX_P3V3_EN_R")
		)
		(pad "2" smd circle
			(at 0.40005 0 90)
			(size 0 0)
			(layers "F.Cu" "F.Mask" "F.Paste")
			(net "GND")
		)
	)
	(footprint ""
		(layer "F.Cu")
		(at 8.45058 -73.475088)
		(property "Reference" "R5652"
			(at 0 0 0)
			(layer "F.SilkS")
			(hide yes)
			(effects
				(font
					(size 1.27 1.27)
				)
			)
		)
		(property "Value" ""
			(at 0 0 0)
			(layer "F.Fab")
			(effects
				(font
					(size 1.27 1.27)
				)
			)
		)
		(duplicate_pad_numbers_are_jumpers no)
		(fp_line
			(start -0.7874 -0.4064)
			(end 0.7874 -0.4064)
			(stroke
				(width 0.1524)
				(type default)
			)
			(layer "F.SilkS")
		)
		(fp_line
			(start -0.7874 0.4064)
			(end -0.7874 -0.4064)
			(stroke
				(width 0.1524)
				(type default)
			)
			(layer "F.SilkS")
		)
		(fp_line
			(start 0.7874 -0.4064)
			(end 0.7874 0.4064)
			(stroke
				(width 0.1524)
				(type default)
			)
			(layer "F.SilkS")
		)
		(fp_line
			(start 0.7874 0.4064)
			(end -0.7874 0.4064)
			(stroke
				(width 0.1524)
				(type default)
			)
			(layer "F.SilkS")
		)
		(fp_line
			(start -0.67945 -0.305054)
			(end -0.12065 -0.305054)
			(stroke
				(width 0.1)
				(type default)
			)
			(layer "F.Fab")
		)
		(fp_line
			(start -0.67945 0.3048)
			(end -0.67945 -0.305054)
			(stroke
				(width 0.1)
				(type default)
			)
			(layer "F.Fab")
		)
		(fp_line
			(start -0.12065 -0.305054)
			(end -0.12065 -0.2794)
			(stroke
				(width 0.1)
				(type default)
			)
			(layer "F.Fab")
		)
		(fp_line
			(start -0.12065 -0.2794)
			(end 0.12065 -0.2794)
			(stroke
				(width 0.1)
				(type default)
			)
			(layer "F.Fab")
		)
		(fp_line
			(start -0.12065 0.2794)
			(end -0.12065 0.3048)
			(stroke
				(width 0.1)
				(type default)
			)
			(layer "F.Fab")
		)
		(fp_line
			(start -0.12065 0.3048)
			(end -0.67945 0.3048)
			(stroke
				(width 0.1)
				(type default)
			)
			(layer "F.Fab")
		)
		(fp_line
			(start 0.120396 0.2794)
			(end -0.12065 0.2794)
			(stroke
				(width 0.1)
				(type default)
			)
			(layer "F.Fab")
		)
		(fp_line
			(start 0.120396 0.3048)
			(end 0.120396 0.2794)
			(stroke
				(width 0.1)
				(type default)
			)
			(layer "F.Fab")
		)
		(fp_line
			(start 0.12065 -0.3048)
			(end 0.67945 -0.3048)
			(stroke
				(width 0.1)
				(type default)
			)
			(layer "F.Fab")
		)
		(fp_line
			(start 0.12065 -0.2794)
			(end 0.12065 -0.3048)
			(stroke
				(width 0.1)
				(type default)
			)
			(layer "F.Fab")
		)
		(fp_line
			(start 0.67945 -0.3048)
			(end 0.67945 0.3048)
			(stroke
				(width 0.1)
				(type default)
			)
			(layer "F.Fab")
		)
		(fp_line
			(start 0.67945 0.3048)
			(end 0.120396 0.3048)
			(stroke
				(width 0.1)
				(type default)
			)
			(layer "F.Fab")
		)
		(pad "1" smd circle
			(at -0.40005 0)
			(size 0 0)
			(layers "F.Cu" "F.Mask" "F.Paste")
			(net "RST_SMB_SSD0_ISO_N")
		)
		(pad "2" smd circle
			(at 0.40005 0)
			(size 0 0)
			(layers "F.Cu" "F.Mask" "F.Paste")
			(net "P3V3_SSD0")
		)
	)
	(footprint ""
		(layer "F.Cu")
		(at 133.892544 -29.139642 180)
		(property "Reference" "C282"
			(at 0 0 180)
			(layer "F.SilkS")
			(hide yes)
			(effects
				(font
					(size 1.27 1.27)
				)
			)
		)
		(property "Value" ""
			(at 0 0 180)
			(layer "F.Fab")
			(effects
				(font
					(size 1.27 1.27)
				)
			)
		)
		(duplicate_pad_numbers_are_jumpers no)
		(fp_line
			(start 0.299974 0.150114)
			(end -0.299974 0.150114)
			(stroke
				(width 0.1)
				(type default)
			)
			(layer "F.Fab")
		)
		(fp_line
			(start 0.299974 -0.150114)
			(end 0.299974 0.150114)
			(stroke
				(width 0.1)
				(type default)
			)
			(layer "F.Fab")
		)
		(fp_line
			(start -0.299974 0.150114)
			(end -0.299974 -0.150114)
			(stroke
				(width 0.1)
				(type default)
			)
			(layer "F.Fab")
		)
		(fp_line
			(start -0.299974 -0.150114)
			(end 0.299974 -0.150114)
			(stroke
				(width 0.1)
				(type default)
			)
			(layer "F.Fab")
		)
		(pad "1" smd rect
			(at -0.2667 0 180)
			(size 0.3048 0.381)
			(layers "F.Cu" "F.Mask" "F.Paste")
			(net "P5E_PEX1_STN2_TX_DP<44>")
		)
		(pad "2" smd rect
			(at 0.2667 0 180)
			(size 0.3048 0.381)
			(layers "F.Cu" "F.Mask" "F.Paste")
			(net "P5E_PEX1_STN2_TX_C_DP<44>")
		)
	)
	(footprint ""
		(layer "F.Cu")
		(at 26.439368 -356.244906 90)
		(property "Reference" "C2159"
			(at 0 0 90)
			(layer "F.SilkS")
			(hide yes)
			(effects
				(font
					(size 1.27 1.27)
				)
			)
		)
		(property "Value" ""
			(at 0 0 90)
			(layer "F.Fab")
			(effects
				(font
					(size 1.27 1.27)
				)
			)
		)
		(duplicate_pad_numbers_are_jumpers no)
		(fp_line
			(start 0.299974 -0.150114)
			(end 0.299974 0.150114)
			(stroke
				(width 0.1)
				(type default)
			)
			(layer "F.Fab")
		)
		(fp_line
			(start -0.299974 -0.150114)
			(end 0.299974 -0.150114)
			(stroke
				(width 0.1)
				(type default)
			)
			(layer "F.Fab")
		)
		(fp_line
			(start 0.299974 0.150114)
			(end -0.299974 0.150114)
			(stroke
				(width 0.1)
				(type default)
			)
			(layer "F.Fab")
		)
		(fp_line
			(start -0.299974 0.150114)
			(end -0.299974 -0.150114)
			(stroke
				(width 0.1)
				(type default)
			)
			(layer "F.Fab")
		)
		(pad "1" smd rect
			(at -0.2667 0 90)
			(size 0.3048 0.381)
			(layers "F.Cu" "F.Mask" "F.Paste")
			(net "P5E_PEX0_STN4_TX_DN<76>")
		)
		(pad "2" smd rect
			(at 0.2667 0 90)
			(size 0.3048 0.381)
			(layers "F.Cu" "F.Mask" "F.Paste")
			(net "P5E_PEX0_STN4_TX_C_DN<76>")
		)
	)
	(footprint ""
		(layer "F.Cu")
		(at 455.93254 -5.999988)
		(property "Reference" "H48"
			(at -5.198618 -5.53593 0)
			(unlocked yes)
			(layer "F.SilkS")
			(effects
				(font
					(size 0.7874 0.5842)
					(thickness 0.1524)
				)
				(justify left)
			)
		)
		(property "Value" ""
			(at 0 0 0)
			(layer "F.Fab")
			(effects
				(font
					(size 1.27 1.27)
				)
			)
		)
		(duplicate_pad_numbers_are_jumpers no)
		(pad "1" thru_hole circle
			(at 0 0)
			(size 10.0076 10.0076)
			(drill 5.6134)
			(layers "*.Cu" "*.Mask")
			(remove_unused_layers no)
			(net "GND")
			(clearance -1.9431)
		)
	)
	(footprint ""
		(layer "F.Cu")
		(at 30.153356 -300.992032)
		(property "Reference" "L89"
			(at 0 0 0)
			(layer "F.SilkS")
			(hide yes)
			(effects
				(font
					(size 1.27 1.27)
				)
			)
		)
		(property "Value" ""
			(at 0 0 0)
			(layer "F.Fab")
			(effects
				(font
					(size 1.27 1.27)
				)
			)
		)
		(duplicate_pad_numbers_are_jumpers no)
		(fp_line
			(start -1.63576 -0.8128)
			(end -1.63576 0.8128)
			(stroke
				(width 0.1524)
				(type default)
			)
			(layer "F.SilkS")
		)
		(fp_line
			(start -1.63576 -0.8128)
			(end 1.63576 -0.8128)
			(stroke
				(width 0.1524)
				(type default)
			)
			(layer "F.SilkS")
		)
		(fp_line
			(start 1.63576 -0.8128)
			(end 1.63576 0.8128)
			(stroke
				(width 0.1524)
				(type default)
			)
			(layer "F.SilkS")
		)
		(fp_line
			(start 1.63576 0.8128)
			(end -1.63576 0.8128)
			(stroke
				(width 0.1524)
				(type default)
			)
			(layer "F.SilkS")
		)
		(fp_line
			(start -1.56083 -0.738632)
			(end -1.56083 0.7366)
			(stroke
				(width 0.1)
				(type default)
			)
			(layer "F.Fab")
		)
		(fp_line
			(start -1.56083 0.7366)
			(end -1.524 0.7366)
			(stroke
				(width 0.1)
				(type default)
			)
			(layer "F.Fab")
		)
		(fp_line
			(start -1.524 0.7366)
			(end 1.524 0.7366)
			(stroke
				(width 0.1)
				(type default)
			)
			(layer "F.Fab")
		)
		(fp_line
			(start 1.524 0.7366)
			(end 1.560576 0.7366)
			(stroke
				(width 0.1)
				(type default)
			)
			(layer "F.Fab")
		)
		(fp_line
			(start 1.560576 -0.738632)
			(end -1.56083 -0.738632)
			(stroke
				(width 0.1)
				(type default)
			)
			(layer "F.Fab")
		)
		(fp_line
			(start 1.560576 0.7366)
			(end 1.560576 -0.738632)
			(stroke
				(width 0.1)
				(type default)
			)
			(layer "F.Fab")
		)
		(pad "1" smd rect
			(at -0.94996 0 180)
			(size 1.1176 1.3716)
			(layers "F.Cu" "F.Mask" "F.Paste")
			(net "P1V8_PLL0_PEX0")
		)
		(pad "2" smd rect
			(at 0.94996 0 180)
			(size 1.1176 1.3716)
			(layers "F.Cu" "F.Mask" "F.Paste")
			(net "PCEPLL1_VDDA18_PEX0")
		)
	)
	(footprint ""
		(layer "F.Cu")
		(at 2.633218 -393.46632 -90)
		(property "Reference" "R6744"
			(at 0 0 270)
			(layer "F.SilkS")
			(hide yes)
			(effects
				(font
					(size 1.27 1.27)
				)
			)
		)
		(property "Value" ""
			(at 0 0 270)
			(layer "F.Fab")
			(effects
				(font
					(size 1.27 1.27)
				)
			)
		)
		(duplicate_pad_numbers_are_jumpers no)
		(fp_line
			(start -0.7874 0.4064)
			(end -0.7874 -0.4064)
			(stroke
				(width 0.1524)
				(type default)
			)
			(layer "F.SilkS")
		)
		(fp_line
			(start 0.7874 0.4064)
			(end -0.7874 0.4064)
			(stroke
				(width 0.1524)
				(type default)
			)
			(layer "F.SilkS")
		)
		(fp_line
			(start -0.7874 -0.4064)
			(end 0.7874 -0.4064)
			(stroke
				(width 0.1524)
				(type default)
			)
			(layer "F.SilkS")
		)
		(fp_line
			(start 0.7874 -0.4064)
			(end 0.7874 0.4064)
			(stroke
				(width 0.1524)
				(type default)
			)
			(layer "F.SilkS")
		)
		(fp_line
			(start -0.67945 0.3048)
			(end -0.67945 -0.305054)
			(stroke
				(width 0.1)
				(type default)
			)
			(layer "F.Fab")
		)
		(fp_line
			(start -0.12065 0.3048)
			(end -0.67945 0.3048)
			(stroke
				(width 0.1)
				(type default)
			)
			(layer "F.Fab")
		)
		(fp_line
			(start 0.120396 0.3048)
			(end 0.120396 0.2794)
			(stroke
				(width 0.1)
				(type default)
			)
			(layer "F.Fab")
		)
		(fp_line
			(start 0.67945 0.3048)
			(end 0.120396 0.3048)
			(stroke
				(width 0.1)
				(type default)
			)
			(layer "F.Fab")
		)
		(fp_line
			(start -0.12065 0.2794)
			(end -0.12065 0.3048)
			(stroke
				(width 0.1)
				(type default)
			)
			(layer "F.Fab")
		)
		(fp_line
			(start 0.120396 0.2794)
			(end -0.12065 0.2794)
			(stroke
				(width 0.1)
				(type default)
			)
			(layer "F.Fab")
		)
		(fp_line
			(start -0.12065 -0.2794)
			(end 0.12065 -0.2794)
			(stroke
				(width 0.1)
				(type default)
			)
			(layer "F.Fab")
		)
		(fp_line
			(start 0.12065 -0.2794)
			(end 0.12065 -0.3048)
			(stroke
				(width 0.1)
				(type default)
			)
			(layer "F.Fab")
		)
		(fp_line
			(start 0.12065 -0.3048)
			(end 0.67945 -0.3048)
			(stroke
				(width 0.1)
				(type default)
			)
			(layer "F.Fab")
		)
		(fp_line
			(start 0.67945 -0.3048)
			(end 0.67945 0.3048)
			(stroke
				(width 0.1)
				(type default)
			)
			(layer "F.Fab")
		)
		(fp_line
			(start -0.67945 -0.305054)
			(end -0.12065 -0.305054)
			(stroke
				(width 0.1)
				(type default)
			)
			(layer "F.Fab")
		)
		(fp_line
			(start -0.12065 -0.305054)
			(end -0.12065 -0.2794)
			(stroke
				(width 0.1)
				(type default)
			)
			(layer "F.Fab")
		)
		(pad "1" smd circle
			(at -0.40005 0 270)
			(size 0 0)
			(layers "F.Cu" "F.Mask" "F.Paste")
			(net "P3V3_USB_8042")
		)
		(pad "2" smd circle
			(at 0.40005 0 270)
			(size 0 0)
			(layers "F.Cu" "F.Mask" "F.Paste")
			(net "BIC_USB_8042_HUB_GRSTZ")
		)
	)
	(footprint ""
		(layer "F.Cu")
		(at 199.689466 -63.56223)
		(property "Reference" "Q203"
			(at 0.42291 -2.23901 0)
			(unlocked yes)
			(layer "F.SilkS")
			(effects
				(font
					(size 0.7874 0.5842)
					(thickness 0.1524)
				)
			)
		)
		(property "Value" ""
			(at 0 0 0)
			(layer "F.Fab")
			(effects
				(font
					(size 1.27 1.27)
				)
			)
		)
		(duplicate_pad_numbers_are_jumpers no)
		(fp_line
			(start -1.376172 -1.199896)
			(end -0.508 -1.199896)
			(stroke
				(width 0.1524)
				(type default)
			)
			(layer "F.SilkS")
		)
		(fp_line
			(start -1.376172 1.199896)
			(end -1.376172 -1.199896)
			(stroke
				(width 0.1524)
				(type default)
			)
			(layer "F.SilkS")
		)
		(fp_line
			(start -0.508 -1.199896)
			(end 0 -0.762)
			(stroke
				(width 0.1524)
				(type default)
			)
			(layer "F.SilkS")
		)
		(fp_line
			(start 0 -0.762)
			(end 0.508 -1.199896)
			(stroke
				(width 0.1524)
				(type default)
			)
			(layer "F.SilkS")
		)
		(fp_line
			(start 0.508 -1.199896)
			(end 1.376172 -1.199896)
			(stroke
				(width 0.1524)
				(type default)
			)
			(layer "F.SilkS")
		)
		(fp_line
			(start 1.376172 -1.199896)
			(end 1.376172 1.199896)
			(stroke
				(width 0.1524)
				(type default)
			)
			(layer "F.SilkS")
		)
		(fp_line
			(start 1.376172 1.199896)
			(end -1.376172 1.199896)
			(stroke
				(width 0.1524)
				(type default)
			)
			(layer "F.SilkS")
		)
		(fp_poly
			(pts
				(xy -1.382014 -1.13665) (xy -1.651254 -1.944878) (xy -2.190242 -1.40589)
			)
			(stroke
				(width 0)
				(type default)
			)
			(fill yes)
			(layer "F.SilkS")
		)
		(fp_line
			(start -0.674878 -1.100074)
			(end 0.674878 -1.100074)
			(stroke
				(width 0.1)
				(type default)
			)
			(layer "F.Fab")
		)
		(fp_line
			(start -0.674878 1.100074)
			(end -0.674878 -1.100074)
			(stroke
				(width 0.1)
				(type default)
			)
			(layer "F.Fab")
		)
		(fp_line
			(start 0.674878 -1.100074)
			(end 0.674878 1.100074)
			(stroke
				(width 0.1)
				(type default)
			)
			(layer "F.Fab")
		)
		(fp_line
			(start 0.674878 1.100074)
			(end -0.674878 1.100074)
			(stroke
				(width 0.1)
				(type default)
			)
			(layer "F.Fab")
		)
		(fp_poly
			(pts
				(xy -1.4605 -0.7493) (xy -2.2225 -1.1303) (xy -2.2225 -0.3683)
			)
			(stroke
				(width 0)
				(type default)
			)
			(fill yes)
			(layer "F.Fab")
		)
		(pad "1" smd rect
			(at -0.899922 -0.750062 270)
			(size 0.6096 0.6096)
			(layers "F.Cu" "F.Mask" "F.Paste")
			(net "GND")
		)
		(pad "2" smd rect
			(at -0.899922 0 270)
			(size 0.4064 0.6096)
			(layers "F.Cu" "F.Mask" "F.Paste")
			(net "P12V_SSD7_PG_G1")
		)
		(pad "3" smd rect
			(at -0.899922 0.750062 270)
			(size 0.6096 0.6096)
			(layers "F.Cu" "F.Mask" "F.Paste")
			(net "PWRGD_P12V_SSD7_D")
		)
		(pad "4" smd rect
			(at 0.899922 0.750062 270)
			(size 0.6096 0.6096)
			(layers "F.Cu" "F.Mask" "F.Paste")
			(net "GND")
		)
		(pad "5" smd rect
			(at 0.899922 0 270)
			(size 0.4064 0.6096)
			(layers "F.Cu" "F.Mask" "F.Paste")
			(net "P12V_SSD7_PG_G2")
		)
		(pad "6" smd rect
			(at 0.899922 -0.750062 270)
			(size 0.6096 0.6096)
			(layers "F.Cu" "F.Mask" "F.Paste")
			(net "P12V_SSD7_PG_G2")
		)
	)
	(footprint ""
		(layer "F.Cu")
		(at 259.389626 -239.958372 180)
		(property "Reference" "U432"
			(at 1.700784 -4.67487 0)
			(unlocked yes)
			(layer "F.SilkS")
			(effects
				(font
					(size 0.7874 0.5842)
					(thickness 0.1524)
				)
				(justify left)
			)
		)
		(property "Value" ""
			(at 0 0 180)
			(layer "F.Fab")
			(effects
				(font
					(size 1.27 1.27)
				)
			)
		)
		(duplicate_pad_numbers_are_jumpers no)
		(fp_line
			(start 1.525016 1.525016)
			(end 1.525016 1.3208)
			(stroke
				(width 0.1524)
				(type default)
			)
			(layer "F.SilkS")
		)
		(fp_line
			(start 1.525016 1.525016)
			(end -1.525016 1.525016)
			(stroke
				(width 0.1524)
				(type default)
			)
			(layer "F.SilkS")
		)
		(fp_line
			(start 1.525016 -1.3208)
			(end 1.525016 -1.525016)
			(stroke
				(width 0.1524)
				(type default)
			)
			(layer "F.SilkS")
		)
		(fp_line
			(start 1.525016 -1.525016)
			(end 0.9398 -1.525016)
			(stroke
				(width 0.1524)
				(type default)
			)
			(layer "F.SilkS")
		)
		(fp_line
			(start 1.525016 -1.525016)
			(end -1.525016 -1.525016)
			(stroke
				(width 0.1524)
				(type default)
			)
			(layer "F.SilkS")
		)
		(fp_line
			(start 0.9906 1.525016)
			(end 1.525016 1.525016)
			(stroke
				(width 0.1524)
				(type default)
			)
			(layer "F.SilkS")
		)
		(fp_line
			(start -0.8636 -1.525016)
			(end -1.525016 -1.525016)
			(stroke
				(width 0.1524)
				(type default)
			)
			(layer "F.SilkS")
		)
		(fp_line
			(start -1.525016 1.525016)
			(end -0.889 1.525016)
			(stroke
				(width 0.1524)
				(type default)
			)
			(layer "F.SilkS")
		)
		(fp_line
			(start -1.525016 1.3208)
			(end -1.525016 1.525016)
			(stroke
				(width 0.1524)
				(type default)
			)
			(layer "F.SilkS")
		)
		(fp_line
			(start -1.525016 -1.525016)
			(end -1.525016 -1.3208)
			(stroke
				(width 0.1524)
				(type default)
			)
			(layer "F.SilkS")
		)
		(fp_poly
			(pts
				(xy -2.0701 -0.999998) (xy -2.970276 -1.299972) (xy -2.970276 -0.700024)
			)
			(stroke
				(width 0)
				(type default)
			)
			(fill yes)
			(layer "F.SilkS")
		)
		(fp_line
			(start 1.525016 1.525016)
			(end -1.525016 1.525016)
			(stroke
				(width 0.1)
				(type default)
			)
			(layer "F.Fab")
		)
		(fp_line
			(start 1.525016 -1.525016)
			(end 1.525016 1.525016)
			(stroke
				(width 0.1)
				(type default)
			)
			(layer "F.Fab")
		)
		(fp_line
			(start -1.525016 1.525016)
			(end -1.525016 -1.525016)
			(stroke
				(width 0.1)
				(type default)
			)
			(layer "F.Fab")
		)
		(fp_line
			(start -1.525016 -1.525016)
			(end 1.525016 -1.525016)
			(stroke
				(width 0.1)
				(type default)
			)
			(layer "F.Fab")
		)
		(fp_poly
			(pts
				(xy -2.0701 -0.999998) (xy -2.977896 -1.302512) (xy -2.977896 -0.697484)
			)
			(stroke
				(width 0)
				(type default)
			)
			(fill yes)
			(layer "F.Fab")
		)
		(pad "1" smd rect
			(at -1.550162 -0.999998 90)
			(size 0.2794 0.9144)
			(layers "F.Cu" "F.Mask" "F.Paste")
			(net "P1V8_PLL0_PEX2")
		)
		(pad "2" smd rect
			(at -1.550162 -0.500126 90)
			(size 0.2794 0.9144)
			(layers "F.Cu" "F.Mask" "F.Paste")
			(net "P1V8_PLL0_PEX2")
		)
		(pad "3" smd rect
			(at -1.550162 0 90)
			(size 0.2794 0.9144)
			(layers "F.Cu" "F.Mask" "F.Paste")
			(net "P1V8_PLL0_PEX2")
		)
		(pad "4" smd rect
			(at -1.550162 0.500126 90)
			(size 0.2794 0.9144)
			(layers "F.Cu" "F.Mask" "F.Paste")
			(net "P1V8_PLL_PEX2_ADJ")
		)
		(pad "5" smd rect
			(at -1.550162 0.999998 270)
			(size 0.2794 0.9144)
			(layers "F.Cu" "F.Mask" "F.Paste")
			(net "PWRGD_PEX2_P1V8_PLL")
		)
		(pad "6" smd rect
			(at 1.550162 0.999998 270)
			(size 0.2794 0.9144)
			(layers "F.Cu" "F.Mask" "F.Paste")
			(net "PEX2_P1V8_PLL_EN")
		)
		(pad "7" smd rect
			(at 1.550162 0.500126 90)
			(size 0.2794 0.9144)
			(layers "F.Cu" "F.Mask" "F.Paste")
			(net "P3V3_AUX")
		)
		(pad "8" smd rect
			(at 1.550162 0 90)
			(size 0.2794 0.9144)
			(layers "F.Cu" "F.Mask" "F.Paste")
			(net "P3V3_AUX")
		)
		(pad "9" smd rect
			(at 1.550162 -0.500126 90)
			(size 0.2794 0.9144)
			(layers "F.Cu" "F.Mask" "F.Paste")
			(net "P3V3_AUX")
		)
		(pad "10" smd rect
			(at 1.550162 -0.999998 90)
			(size 0.2794 0.9144)
			(layers "F.Cu" "F.Mask" "F.Paste")
			(net "P5V_AUX")
		)
		(pad "TH" smd rect
			(at 0 0 180)
			(size 1.7526 2.667)
			(layers "F.Cu" "F.Mask" "F.Paste")
			(net "GND")
		)
		(zone
			(layer "F.Cu")
			(hatch none 0.5)
			(connect_pads
				(clearance 0)
			)
			(min_thickness 0.25)
			(keepout
				(tracks not_allowed)
				(vias allowed)
				(pads allowed)
				(copperpour not_allowed)
				(footprints allowed)
			)
			(placement
				(enabled no)
				(sheetname "")
			)
			(fill
				(thermal_gap 0.5)
				(thermal_bridge_width 0.5)
				(island_removal_mode 0)
			)
			(polygon
				(pts
					(xy 260.406388 -238.424974) (xy 260.406388 -241.472974) (xy 258.374388 -241.472974) (xy 258.374388 -238.424974)
					(xy 260.304788 -238.424974) (xy 260.304788 -238.551974) (xy 258.450588 -238.551974) (xy 258.450588 -241.371374)
					(xy 260.330188 -241.371374) (xy 260.330188 -238.424974)
				)
			)
		)
	)
	(footprint ""
		(layer "F.Cu")
		(at 26.267918 -55.083456)
		(property "Reference" "PC385"
			(at 0 0 0)
			(layer "F.SilkS")
			(hide yes)
			(effects
				(font
					(size 1.27 1.27)
				)
			)
		)
		(property "Value" ""
			(at 0 0 0)
			(layer "F.Fab")
			(effects
				(font
					(size 1.27 1.27)
				)
			)
		)
		(duplicate_pad_numbers_are_jumpers no)
		(fp_line
			(start -0.7874 -0.4064)
			(end 0.7874 -0.4064)
			(stroke
				(width 0.1524)
				(type default)
			)
			(layer "F.SilkS")
		)
		(fp_line
			(start -0.7874 0.4064)
			(end -0.7874 -0.4064)
			(stroke
				(width 0.1524)
				(type default)
			)
			(layer "F.SilkS")
		)
		(fp_line
			(start 0.7874 -0.4064)
			(end 0.7874 0.4064)
			(stroke
				(width 0.1524)
				(type default)
			)
			(layer "F.SilkS")
		)
		(fp_line
			(start 0.7874 0.4064)
			(end -0.7874 0.4064)
			(stroke
				(width 0.1524)
				(type default)
			)
			(layer "F.SilkS")
		)
		(fp_line
			(start -0.67945 -0.305054)
			(end -0.12065 -0.305054)
			(stroke
				(width 0.1)
				(type default)
			)
			(layer "F.Fab")
		)
		(fp_line
			(start -0.67945 0.3048)
			(end -0.67945 -0.305054)
			(stroke
				(width 0.1)
				(type default)
			)
			(layer "F.Fab")
		)
		(fp_line
			(start -0.12065 -0.305054)
			(end -0.12065 -0.2794)
			(stroke
				(width 0.1)
				(type default)
			)
			(layer "F.Fab")
		)
		(fp_line
			(start -0.12065 -0.2794)
			(end 0.12065 -0.2794)
			(stroke
				(width 0.1)
				(type default)
			)
			(layer "F.Fab")
		)
		(fp_line
			(start -0.12065 0.2794)
			(end -0.12065 0.3048)
			(stroke
				(width 0.1)
				(type default)
			)
			(layer "F.Fab")
		)
		(fp_line
			(start -0.12065 0.3048)
			(end -0.67945 0.3048)
			(stroke
				(width 0.1)
				(type default)
			)
			(layer "F.Fab")
		)
		(fp_line
			(start 0.120396 0.2794)
			(end -0.12065 0.2794)
			(stroke
				(width 0.1)
				(type default)
			)
			(layer "F.Fab")
		)
		(fp_line
			(start 0.120396 0.3048)
			(end 0.120396 0.2794)
			(stroke
				(width 0.1)
				(type default)
			)
			(layer "F.Fab")
		)
		(fp_line
			(start 0.12065 -0.3048)
			(end 0.67945 -0.3048)
			(stroke
				(width 0.1)
				(type default)
			)
			(layer "F.Fab")
		)
		(fp_line
			(start 0.12065 -0.2794)
			(end 0.12065 -0.3048)
			(stroke
				(width 0.1)
				(type default)
			)
			(layer "F.Fab")
		)
		(fp_line
			(start 0.67945 -0.3048)
			(end 0.67945 0.3048)
			(stroke
				(width 0.1)
				(type default)
			)
			(layer "F.Fab")
		)
		(fp_line
			(start 0.67945 0.3048)
			(end 0.120396 0.3048)
			(stroke
				(width 0.1)
				(type default)
			)
			(layer "F.Fab")
		)
		(pad "1" smd circle
			(at -0.40005 0)
			(size 0 0)
			(layers "F.Cu" "F.Mask" "F.Paste")
			(net "P5V_AUX")
		)
		(pad "2" smd circle
			(at 0.40005 0)
			(size 0 0)
			(layers "F.Cu" "F.Mask" "F.Paste")
			(net "GND")
		)
	)
	(footprint ""
		(layer "F.Cu")
		(at 262.281924 -296.191432 180)
		(property "Reference" "C3378"
			(at 0 0 180)
			(layer "F.SilkS")
			(hide yes)
			(effects
				(font
					(size 1.27 1.27)
				)
			)
		)
		(property "Value" ""
			(at 0 0 180)
			(layer "F.Fab")
			(effects
				(font
					(size 1.27 1.27)
				)
			)
		)
		(duplicate_pad_numbers_are_jumpers no)
		(fp_line
			(start 1.2954 0.5842)
			(end -1.2954 0.5842)
			(stroke
				(width 0.1524)
				(type default)
			)
			(layer "F.SilkS")
		)
		(fp_line
			(start 1.2954 -0.5842)
			(end 1.2954 0.5842)
			(stroke
				(width 0.1524)
				(type default)
			)
			(layer "F.SilkS")
		)
		(fp_line
			(start -1.2954 0.5842)
			(end -1.2954 -0.5842)
			(stroke
				(width 0.1524)
				(type default)
			)
			(layer "F.SilkS")
		)
		(fp_line
			(start -1.2954 -0.5842)
			(end 1.2954 -0.5842)
			(stroke
				(width 0.1524)
				(type default)
			)
			(layer "F.SilkS")
		)
		(fp_line
			(start 1.1938 0.4064)
			(end 0.8636 0.4064)
			(stroke
				(width 0.1)
				(type default)
			)
			(layer "F.Fab")
		)
		(fp_line
			(start 1.1938 -0.4064)
			(end 1.1938 0.4064)
			(stroke
				(width 0.1)
				(type default)
			)
			(layer "F.Fab")
		)
		(fp_line
			(start 0.8636 0.4572)
			(end -0.8636 0.4572)
			(stroke
				(width 0.1)
				(type default)
			)
			(layer "F.Fab")
		)
		(fp_line
			(start 0.8636 0.4064)
			(end 0.8636 0.4572)
			(stroke
				(width 0.1)
				(type default)
			)
			(layer "F.Fab")
		)
		(fp_line
			(start 0.8636 -0.4064)
			(end 1.1938 -0.4064)
			(stroke
				(width 0.1)
				(type default)
			)
			(layer "F.Fab")
		)
		(fp_line
			(start 0.8636 -0.4572)
			(end 0.8636 -0.4064)
			(stroke
				(width 0.1)
				(type default)
			)
			(layer "F.Fab")
		)
		(fp_line
			(start -0.8636 0.4572)
			(end -0.8636 0.4064)
			(stroke
				(width 0.1)
				(type default)
			)
			(layer "F.Fab")
		)
		(fp_line
			(start -0.8636 0.4064)
			(end -1.1938 0.4064)
			(stroke
				(width 0.1)
				(type default)
			)
			(layer "F.Fab")
		)
		(fp_line
			(start -0.8636 -0.4064)
			(end -0.8636 -0.4572)
			(stroke
				(width 0.1)
				(type default)
			)
			(layer "F.Fab")
		)
		(fp_line
			(start -0.8636 -0.4572)
			(end 0.8636 -0.4572)
			(stroke
				(width 0.1)
				(type default)
			)
			(layer "F.Fab")
		)
		(fp_line
			(start -1.1938 0.4064)
			(end -1.1938 -0.4064)
			(stroke
				(width 0.1)
				(type default)
			)
			(layer "F.Fab")
		)
		(fp_line
			(start -1.1938 -0.4064)
			(end -0.8636 -0.4064)
			(stroke
				(width 0.1)
				(type default)
			)
			(layer "F.Fab")
		)
		(pad "1" smd rect
			(at -0.7366 0 90)
			(size 0.7112 0.8128)
			(layers "F.Cu" "F.Mask" "F.Paste")
			(net "PCEPLL0_VDDA18_PEX2_R")
		)
		(pad "2" smd rect
			(at 0.7366 0 90)
			(size 0.7112 0.8128)
			(layers "F.Cu" "F.Mask" "F.Paste")
			(net "GND")
		)
	)
	(footprint ""
		(layer "F.Cu")
		(at 483.480364 -528.154392 180)
		(property "Reference" "PEX2_HS"
			(at 0.127 -0.593598 0)
			(unlocked yes)
			(layer "F.SilkS")
			(effects
				(font
					(size 0.254 0.127)
					(thickness 0.000001)
				)
			)
		)
		(property "Value" ""
			(at 0 0 180)
			(layer "F.Fab")
			(effects
				(font
					(size 1.27 1.27)
				)
			)
		)
		(duplicate_pad_numbers_are_jumpers no)
		(pad "1" smd circle
			(at 0 0 180)
			(size 0.762 0.762)
			(layers "F.Cu" "F.Mask" "F.Paste")
			(net "Net_9122")
		)
	)
	(footprint ""
		(layer "F.Cu")
		(at 358.830626 -144.067276 180)
		(property "Reference" "PC823"
			(at 0 0 180)
			(layer "F.SilkS")
			(hide yes)
			(effects
				(font
					(size 1.27 1.27)
				)
			)
		)
		(property "Value" ""
			(at 0 0 180)
			(layer "F.Fab")
			(effects
				(font
					(size 1.27 1.27)
				)
			)
		)
		(duplicate_pad_numbers_are_jumpers no)
		(fp_line
			(start 1.524 0.762)
			(end -1.524 0.762)
			(stroke
				(width 0.1524)
				(type default)
			)
			(layer "F.SilkS")
		)
		(fp_line
			(start 1.524 -0.762)
			(end 1.524 0.762)
			(stroke
				(width 0.1524)
				(type default)
			)
			(layer "F.SilkS")
		)
		(fp_line
			(start -1.524 0.762)
			(end -1.524 -0.762)
			(stroke
				(width 0.1524)
				(type default)
			)
			(layer "F.SilkS")
		)
		(fp_line
			(start -1.524 -0.762)
			(end 1.524 -0.762)
			(stroke
				(width 0.1524)
				(type default)
			)
			(layer "F.SilkS")
		)
		(fp_line
			(start 1.1049 0.724916)
			(end 1.1049 -0.724916)
			(stroke
				(width 0.1)
				(type default)
			)
			(layer "F.Fab")
		)
		(fp_line
			(start 1.1049 -0.724916)
			(end -1.1049 -0.724916)
			(stroke
				(width 0.1)
				(type default)
			)
			(layer "F.Fab")
		)
		(fp_line
			(start -1.1049 0.724916)
			(end 1.1049 0.724916)
			(stroke
				(width 0.1)
				(type default)
			)
			(layer "F.Fab")
		)
		(fp_line
			(start -1.1049 -0.724916)
			(end -1.1049 0.724916)
			(stroke
				(width 0.1)
				(type default)
			)
			(layer "F.Fab")
		)
		(pad "1" smd rect
			(at -0.889 0)
			(size 1.016 1.27)
			(layers "F.Cu" "F.Mask" "F.Paste")
			(net "P12V_NIC6_R")
		)
		(pad "2" smd rect
			(at 0.889 0)
			(size 1.016 1.27)
			(layers "F.Cu" "F.Mask" "F.Paste")
			(net "GND")
		)
	)
	(footprint ""
		(layer "F.Cu")
		(at 338.09559 -86.764368)
		(property "Reference" "U116"
			(at 2.136648 -4.159504 0)
			(unlocked yes)
			(layer "F.SilkS")
			(effects
				(font
					(size 0.7874 0.5842)
					(thickness 0.1524)
				)
				(justify left)
			)
		)
		(property "Value" ""
			(at 0 0 0)
			(layer "F.Fab")
			(effects
				(font
					(size 1.27 1.27)
				)
			)
		)
		(duplicate_pad_numbers_are_jumpers no)
		(fp_line
			(start -2.999994 -2.999994)
			(end -2.999994 -2.4384)
			(stroke
				(width 0.1524)
				(type default)
			)
			(layer "F.SilkS")
		)
		(fp_line
			(start -2.999994 2.4384)
			(end -2.999994 2.999994)
			(stroke
				(width 0.1524)
				(type default)
			)
			(layer "F.SilkS")
		)
		(fp_line
			(start -2.999994 2.999994)
			(end -2.4384 2.999994)
			(stroke
				(width 0.1524)
				(type default)
			)
			(layer "F.SilkS")
		)
		(fp_line
			(start -2.4384 -2.999994)
			(end -2.999994 -2.999994)
			(stroke
				(width 0.1524)
				(type default)
			)
			(layer "F.SilkS")
		)
		(fp_line
			(start 2.4384 2.999994)
			(end 2.999994 2.999994)
			(stroke
				(width 0.1524)
				(type default)
			)
			(layer "F.SilkS")
		)
		(fp_line
			(start 2.999994 -2.999994)
			(end 2.4384 -2.999994)
			(stroke
				(width 0.1524)
				(type default)
			)
			(layer "F.SilkS")
		)
		(fp_line
			(start 2.999994 -2.4384)
			(end 2.999994 -2.999994)
			(stroke
				(width 0.1524)
				(type default)
			)
			(layer "F.SilkS")
		)
		(fp_line
			(start 2.999994 2.999994)
			(end 2.999994 2.4384)
			(stroke
				(width 0.1524)
				(type default)
			)
			(layer "F.SilkS")
		)
		(fp_poly
			(pts
				(xy -4.674362 -2.064766) (xy -4.674362 -2.834132) (xy -3.904996 -2.449322)
			)
			(stroke
				(width 0)
				(type default)
			)
			(fill yes)
			(layer "F.SilkS")
		)
		(fp_line
			(start -2.999994 -2.999994)
			(end -2.999994 2.999994)
			(stroke
				(width 0.1)
				(type default)
			)
			(layer "F.Fab")
		)
		(fp_line
			(start -2.999994 2.999994)
			(end 2.999994 2.999994)
			(stroke
				(width 0.1)
				(type default)
			)
			(layer "F.Fab")
		)
		(fp_line
			(start 2.999994 -2.999994)
			(end -2.999994 -2.999994)
			(stroke
				(width 0.1)
				(type default)
			)
			(layer "F.Fab")
		)
		(fp_line
			(start 2.999994 2.999994)
			(end 2.999994 -2.999994)
			(stroke
				(width 0.1)
				(type default)
			)
			(layer "F.Fab")
		)
		(fp_poly
			(pts
				(xy -4.318 -1.815338) (xy -4.318 -2.584704) (xy -3.548634 -2.199894)
			)
			(stroke
				(width 0)
				(type default)
			)
			(fill yes)
			(layer "F.Fab")
		)
		(pad "1" smd circle
			(at -2.949956 -2.199894 270)
			(size 0 0)
			(layers "F.Cu" "F.Mask" "F.Paste")
			(net "FM_CLK_EN_R")
		)
		(pad "2" smd circle
			(at -2.949956 -1.800098 270)
			(size 0 0)
			(layers "F.Cu" "F.Mask" "F.Paste")
			(net "GND")
		)
		(pad "3" smd circle
			(at -2.949956 -1.400048 270)
			(size 0 0)
			(layers "F.Cu" "F.Mask" "F.Paste")
			(net "P3V3_VDDAR_9ZXL0851_8_15")
		)
		(pad "4" smd circle
			(at -2.949956 -0.999998 270)
			(size 0 0)
			(layers "F.Cu" "F.Mask" "F.Paste")
			(net "CLK_100M_CK440Q_2_DB800ZL_R_DP")
		)
		(pad "5" smd circle
			(at -2.949956 -0.599948 270)
			(size 0 0)
			(layers "F.Cu" "F.Mask" "F.Paste")
			(net "CLK_100M_CK440Q_2_DB800ZL_R_DN")
		)
		(pad "6" smd circle
			(at -2.949956 -0.199898 270)
			(size 0 0)
			(layers "F.Cu" "F.Mask" "F.Paste")
			(net "SMB_BMC_9ZXL0851_8_15_SDA")
		)
		(pad "7" smd circle
			(at -2.949956 0.199898 270)
			(size 0 0)
			(layers "F.Cu" "F.Mask" "F.Paste")
			(net "SMB_BMC_9ZXL0851_8_15_SCL")
		)
		(pad "8" smd circle
			(at -2.949956 0.599948 270)
			(size 0 0)
			(layers "F.Cu" "F.Mask" "F.Paste")
			(net "Net_4347")
		)
		(pad "9" smd circle
			(at -2.949956 0.999998 270)
			(size 0 0)
			(layers "F.Cu" "F.Mask" "F.Paste")
			(net "Net_4346")
		)
		(pad "10" smd circle
			(at -2.949956 1.400048 270)
			(size 0 0)
			(layers "F.Cu" "F.Mask" "F.Paste")
			(net "P3V3_VDD_9ZXL0851_8_15")
		)
		(pad "11" smd circle
			(at -2.949956 1.800098 270)
			(size 0 0)
			(layers "F.Cu" "F.Mask" "F.Paste")
			(net "SSD8_CLK_EN_R_N")
		)
		(pad "12" smd circle
			(at -2.949956 2.199894 270)
			(size 0 0)
			(layers "F.Cu" "F.Mask" "F.Paste")
			(net "Net_4348")
		)
		(pad "13" smd circle
			(at -2.199894 2.949956)
			(size 0 0)
			(layers "F.Cu" "F.Mask" "F.Paste")
			(net "CLK_100M_DB800ZL_SSD8_DP")
		)
		(pad "14" smd circle
			(at -1.800098 2.949956)
			(size 0 0)
			(layers "F.Cu" "F.Mask" "F.Paste")
			(net "CLK_100M_DB800ZL_SSD8_DN")
		)
		(pad "15" smd circle
			(at -1.400048 2.949956)
			(size 0 0)
			(layers "F.Cu" "F.Mask" "F.Paste")
			(net "P3V3_VDD_9ZXL0851_8_15")
		)
		(pad "16" smd circle
			(at -0.999998 2.949956)
			(size 0 0)
			(layers "F.Cu" "F.Mask" "F.Paste")
			(net "CLK_100M_DB800ZL_SSD9_DP")
		)
		(pad "17" smd circle
			(at -0.599948 2.949956)
			(size 0 0)
			(layers "F.Cu" "F.Mask" "F.Paste")
			(net "CLK_100M_DB800ZL_SSD9_DN")
		)
		(pad "18" smd circle
			(at -0.199898 2.949956)
			(size 0 0)
			(layers "F.Cu" "F.Mask" "F.Paste")
			(net "SSD9_CLK_EN_R_N")
		)
		(pad "19" smd circle
			(at 0.199898 2.949956)
			(size 0 0)
			(layers "F.Cu" "F.Mask" "F.Paste")
			(net "P3V3_VDD_9ZXL0851_8_15")
		)
		(pad "20" smd circle
			(at 0.599948 2.949956)
			(size 0 0)
			(layers "F.Cu" "F.Mask" "F.Paste")
			(net "Net_4349")
		)
		(pad "21" smd circle
			(at 0.999998 2.949956)
			(size 0 0)
			(layers "F.Cu" "F.Mask" "F.Paste")
			(net "CLK_100M_DB800ZL_SSD10_DP")
		)
		(pad "22" smd circle
			(at 1.400048 2.949956)
			(size 0 0)
			(layers "F.Cu" "F.Mask" "F.Paste")
			(net "CLK_100M_DB800ZL_SSD10_DN")
		)
		(pad "23" smd circle
			(at 1.800098 2.949956)
			(size 0 0)
			(layers "F.Cu" "F.Mask" "F.Paste")
			(net "SSD10_CLK_EN_R_N")
		)
		(pad "24" smd circle
			(at 2.199894 2.949956)
			(size 0 0)
			(layers "F.Cu" "F.Mask" "F.Paste")
			(net "SSD11_CLK_EN_R_N")
		)
		(pad "25" smd circle
			(at 2.949956 2.199894 90)
			(size 0 0)
			(layers "F.Cu" "F.Mask" "F.Paste")
			(net "CLK_100M_DB800ZL_SSD11_DP")
		)
		(pad "26" smd circle
			(at 2.949956 1.800098 90)
			(size 0 0)
			(layers "F.Cu" "F.Mask" "F.Paste")
			(net "CLK_100M_DB800ZL_SSD11_DN")
		)
		(pad "27" smd circle
			(at 2.949956 1.400048 90)
			(size 0 0)
			(layers "F.Cu" "F.Mask" "F.Paste")
			(net "P3V3_VDD_9ZXL0851_8_15")
		)
		(pad "28" smd circle
			(at 2.949956 0.999998 90)
			(size 0 0)
			(layers "F.Cu" "F.Mask" "F.Paste")
			(net "CLK_100M_DB800ZL_SSD12_DP")
		)
		(pad "29" smd circle
			(at 2.949956 0.599948 90)
			(size 0 0)
			(layers "F.Cu" "F.Mask" "F.Paste")
			(net "CLK_100M_DB800ZL_SSD12_DN")
		)
		(pad "30" smd circle
			(at 2.949956 0.199898 90)
			(size 0 0)
			(layers "F.Cu" "F.Mask" "F.Paste")
			(net "SSD12_CLK_EN_R_N")
		)
		(pad "31" smd circle
			(at 2.949956 -0.199898 90)
			(size 0 0)
			(layers "F.Cu" "F.Mask" "F.Paste")
			(net "SSD13_CLK_EN_R_N")
		)
		(pad "32" smd circle
			(at 2.949956 -0.599948 90)
			(size 0 0)
			(layers "F.Cu" "F.Mask" "F.Paste")
			(net "CLK_100M_DB800ZL_SSD13_DP")
		)
		(pad "33" smd circle
			(at 2.949956 -0.999998 90)
			(size 0 0)
			(layers "F.Cu" "F.Mask" "F.Paste")
			(net "CLK_100M_DB800ZL_SSD13_DN")
		)
		(pad "34" smd circle
			(at 2.949956 -1.400048 90)
			(size 0 0)
			(layers "F.Cu" "F.Mask" "F.Paste")
			(net "P3V3_VDD_9ZXL0851_8_15")
		)
		(pad "35" smd circle
			(at 2.949956 -1.800098 90)
			(size 0 0)
			(layers "F.Cu" "F.Mask" "F.Paste")
			(net "CLK_100M_DB800ZL_SSD14_DP")
		)
		(pad "36" smd circle
			(at 2.949956 -2.199894 90)
			(size 0 0)
			(layers "F.Cu" "F.Mask" "F.Paste")
			(net "CLK_100M_DB800ZL_SSD14_DN")
		)
		(pad "37" smd circle
			(at 2.199894 -2.949956 180)
			(size 0 0)
			(layers "F.Cu" "F.Mask" "F.Paste")
			(net "SSD14_CLK_EN_R_N")
		)
		(pad "38" smd circle
			(at 1.800098 -2.949956 180)
			(size 0 0)
			(layers "F.Cu" "F.Mask" "F.Paste")
			(net "P3V3_VDD_9ZXL0851_8_15")
		)
		(pad "39" smd circle
			(at 1.400048 -2.949956 180)
			(size 0 0)
			(layers "F.Cu" "F.Mask" "F.Paste")
			(net "CLK_100M_DB800ZL_SSD15_DP")
		)
		(pad "40" smd circle
			(at 0.999998 -2.949956 180)
			(size 0 0)
			(layers "F.Cu" "F.Mask" "F.Paste")
			(net "CLK_100M_DB800ZL_SSD15_DN")
		)
		(pad "41" smd circle
			(at 0.599948 -2.949956 180)
			(size 0 0)
			(layers "F.Cu" "F.Mask" "F.Paste")
			(net "SSD15_CLK_EN_R_N")
		)
		(pad "42" smd circle
			(at 0.199898 -2.949956 180)
			(size 0 0)
			(layers "F.Cu" "F.Mask" "F.Paste")
			(net "P3V3_VDD_9ZXL0851_8_15")
		)
		(pad "43" smd circle
			(at -0.199898 -2.949956 180)
			(size 0 0)
			(layers "F.Cu" "F.Mask" "F.Paste")
			(net "Net_4350")
		)
		(pad "44" smd circle
			(at -0.599948 -2.949956 180)
			(size 0 0)
			(layers "F.Cu" "F.Mask" "F.Paste")
			(net "P3V3_VDDAR_9ZXL0851_8_15")
		)
		(pad "45" smd circle
			(at -0.999998 -2.949956 180)
			(size 0 0)
			(layers "F.Cu" "F.Mask" "F.Paste")
			(net "Net_4351")
		)
		(pad "46" smd circle
			(at -1.400048 -2.949956 180)
			(size 0 0)
			(layers "F.Cu" "F.Mask" "F.Paste")
			(net "Net_4352")
		)
		(pad "47" smd circle
			(at -1.800098 -2.949956 180)
			(size 0 0)
			(layers "F.Cu" "F.Mask" "F.Paste")
			(net "PU_9ZXL0851_8_15_100M")
		)
		(pad "48" smd circle
			(at -2.199894 -2.949956 180)
			(size 0 0)
			(layers "F.Cu" "F.Mask" "F.Paste")
			(net "PU_9ZXL0851_8_15_HBW")
		)
		(pad "49" smd rect
			(at 0 0)
			(size 4.2164 4.2164)
			(layers "F.Cu" "F.Mask" "F.Paste")
			(net "GND")
		)
		(zone
			(layer "F.Cu")
			(hatch none 0.5)
			(connect_pads
				(clearance 0)
			)
			(min_thickness 0.25)
			(keepout
				(tracks not_allowed)
				(vias allowed)
				(pads allowed)
				(copperpour not_allowed)
				(footprints allowed)
			)
			(placement
				(enabled no)
				(sheetname "")
			)
			(fill
				(thermal_gap 0.5)
				(thermal_bridge_width 0.5)
				(island_removal_mode 0)
			)
			(polygon
				(pts
					(xy 335.63179 -87.729568) (xy 335.63179 -84.300568) (xy 340.55939 -84.300568) (xy 340.55939 -89.228168)
					(xy 335.63179 -89.228168) (xy 335.63179 -87.754968) (xy 335.93659 -87.754968) (xy 335.93659 -88.923368)
					(xy 340.25459 -88.923368) (xy 340.25459 -84.605368) (xy 335.93659 -84.605368) (xy 335.93659 -87.729568)
				)
			)
		)
	)
	(footprint ""
		(layer "F.Cu")
		(at 331.175614 -120.493028)
		(property "Reference" "R4477"
			(at 0 0 0)
			(layer "F.SilkS")
			(hide yes)
			(effects
				(font
					(size 1.27 1.27)
				)
			)
		)
		(property "Value" ""
			(at 0 0 0)
			(layer "F.Fab")
			(effects
				(font
					(size 1.27 1.27)
				)
			)
		)
		(duplicate_pad_numbers_are_jumpers no)
		(fp_line
			(start -0.7874 -0.4064)
			(end 0.7874 -0.4064)
			(stroke
				(width 0.1524)
				(type default)
			)
			(layer "F.SilkS")
		)
		(fp_line
			(start -0.7874 0.4064)
			(end -0.7874 -0.4064)
			(stroke
				(width 0.1524)
				(type default)
			)
			(layer "F.SilkS")
		)
		(fp_line
			(start 0.7874 -0.4064)
			(end 0.7874 0.4064)
			(stroke
				(width 0.1524)
				(type default)
			)
			(layer "F.SilkS")
		)
		(fp_line
			(start 0.7874 0.4064)
			(end -0.7874 0.4064)
			(stroke
				(width 0.1524)
				(type default)
			)
			(layer "F.SilkS")
		)
		(fp_line
			(start -0.67945 -0.305054)
			(end -0.12065 -0.305054)
			(stroke
				(width 0.1)
				(type default)
			)
			(layer "F.Fab")
		)
		(fp_line
			(start -0.67945 0.3048)
			(end -0.67945 -0.305054)
			(stroke
				(width 0.1)
				(type default)
			)
			(layer "F.Fab")
		)
		(fp_line
			(start -0.12065 -0.305054)
			(end -0.12065 -0.2794)
			(stroke
				(width 0.1)
				(type default)
			)
			(layer "F.Fab")
		)
		(fp_line
			(start -0.12065 -0.2794)
			(end 0.12065 -0.2794)
			(stroke
				(width 0.1)
				(type default)
			)
			(layer "F.Fab")
		)
		(fp_line
			(start -0.12065 0.2794)
			(end -0.12065 0.3048)
			(stroke
				(width 0.1)
				(type default)
			)
			(layer "F.Fab")
		)
		(fp_line
			(start -0.12065 0.3048)
			(end -0.67945 0.3048)
			(stroke
				(width 0.1)
				(type default)
			)
			(layer "F.Fab")
		)
		(fp_line
			(start 0.120396 0.2794)
			(end -0.12065 0.2794)
			(stroke
				(width 0.1)
				(type default)
			)
			(layer "F.Fab")
		)
		(fp_line
			(start 0.120396 0.3048)
			(end 0.120396 0.2794)
			(stroke
				(width 0.1)
				(type default)
			)
			(layer "F.Fab")
		)
		(fp_line
			(start 0.12065 -0.3048)
			(end 0.67945 -0.3048)
			(stroke
				(width 0.1)
				(type default)
			)
			(layer "F.Fab")
		)
		(fp_line
			(start 0.12065 -0.2794)
			(end 0.12065 -0.3048)
			(stroke
				(width 0.1)
				(type default)
			)
			(layer "F.Fab")
		)
		(fp_line
			(start 0.67945 -0.3048)
			(end 0.67945 0.3048)
			(stroke
				(width 0.1)
				(type default)
			)
			(layer "F.Fab")
		)
		(fp_line
			(start 0.67945 0.3048)
			(end 0.120396 0.3048)
			(stroke
				(width 0.1)
				(type default)
			)
			(layer "F.Fab")
		)
		(pad "1" smd circle
			(at -0.40005 0)
			(size 0 0)
			(layers "F.Cu" "F.Mask" "F.Paste")
			(net "PWRGD_P3V3_NIC5")
		)
		(pad "2" smd circle
			(at 0.40005 0)
			(size 0 0)
			(layers "F.Cu" "F.Mask" "F.Paste")
			(net "PWRGD_P3V3_NIC5_R")
		)
	)
	(footprint ""
		(layer "F.Cu")
		(at 224.022158 -78.579472 180)
		(property "Reference" "R4347"
			(at 0 0 180)
			(layer "F.SilkS")
			(hide yes)
			(effects
				(font
					(size 1.27 1.27)
				)
			)
		)
		(property "Value" ""
			(at 0 0 180)
			(layer "F.Fab")
			(effects
				(font
					(size 1.27 1.27)
				)
			)
		)
		(duplicate_pad_numbers_are_jumpers no)
		(fp_line
			(start 0.7874 0.4064)
			(end -0.7874 0.4064)
			(stroke
				(width 0.1524)
				(type default)
			)
			(layer "F.SilkS")
		)
		(fp_line
			(start 0.7874 -0.4064)
			(end 0.7874 0.4064)
			(stroke
				(width 0.1524)
				(type default)
			)
			(layer "F.SilkS")
		)
		(fp_line
			(start -0.7874 0.4064)
			(end -0.7874 -0.4064)
			(stroke
				(width 0.1524)
				(type default)
			)
			(layer "F.SilkS")
		)
		(fp_line
			(start -0.7874 -0.4064)
			(end 0.7874 -0.4064)
			(stroke
				(width 0.1524)
				(type default)
			)
			(layer "F.SilkS")
		)
		(fp_line
			(start 0.67945 0.3048)
			(end 0.120396 0.3048)
			(stroke
				(width 0.1)
				(type default)
			)
			(layer "F.Fab")
		)
		(fp_line
			(start 0.67945 -0.3048)
			(end 0.67945 0.3048)
			(stroke
				(width 0.1)
				(type default)
			)
			(layer "F.Fab")
		)
		(fp_line
			(start 0.12065 -0.2794)
			(end 0.12065 -0.3048)
			(stroke
				(width 0.1)
				(type default)
			)
			(layer "F.Fab")
		)
		(fp_line
			(start 0.12065 -0.3048)
			(end 0.67945 -0.3048)
			(stroke
				(width 0.1)
				(type default)
			)
			(layer "F.Fab")
		)
		(fp_line
			(start 0.120396 0.3048)
			(end 0.120396 0.2794)
			(stroke
				(width 0.1)
				(type default)
			)
			(layer "F.Fab")
		)
		(fp_line
			(start 0.120396 0.2794)
			(end -0.12065 0.2794)
			(stroke
				(width 0.1)
				(type default)
			)
			(layer "F.Fab")
		)
		(fp_line
			(start -0.12065 0.3048)
			(end -0.67945 0.3048)
			(stroke
				(width 0.1)
				(type default)
			)
			(layer "F.Fab")
		)
		(fp_line
			(start -0.12065 0.2794)
			(end -0.12065 0.3048)
			(stroke
				(width 0.1)
				(type default)
			)
			(layer "F.Fab")
		)
		(fp_line
			(start -0.12065 -0.2794)
			(end 0.12065 -0.2794)
			(stroke
				(width 0.1)
				(type default)
			)
			(layer "F.Fab")
		)
		(fp_line
			(start -0.12065 -0.305054)
			(end -0.12065 -0.2794)
			(stroke
				(width 0.1)
				(type default)
			)
			(layer "F.Fab")
		)
		(fp_line
			(start -0.67945 0.3048)
			(end -0.67945 -0.305054)
			(stroke
				(width 0.1)
				(type default)
			)
			(layer "F.Fab")
		)
		(fp_line
			(start -0.67945 -0.305054)
			(end -0.12065 -0.305054)
			(stroke
				(width 0.1)
				(type default)
			)
			(layer "F.Fab")
		)
		(pad "1" smd circle
			(at -0.40005 0 180)
			(size 0 0)
			(layers "F.Cu" "F.Mask" "F.Paste")
			(net "P3V3_AUX")
		)
		(pad "2" smd circle
			(at 0.40005 0 180)
			(size 0 0)
			(layers "F.Cu" "F.Mask" "F.Paste")
			(net "SSD9_LED_R")
		)
	)
	(footprint ""
		(layer "F.Cu")
		(at 391.922762 -22.867366 90)
		(property "Reference" "C3964"
			(at 0 0 90)
			(layer "F.SilkS")
			(hide yes)
			(effects
				(font
					(size 1.27 1.27)
				)
			)
		)
		(property "Value" ""
			(at 0 0 90)
			(layer "F.Fab")
			(effects
				(font
					(size 1.27 1.27)
				)
			)
		)
		(duplicate_pad_numbers_are_jumpers no)
		(fp_line
			(start 0.7874 -0.4064)
			(end 0.7874 0.4064)
			(stroke
				(width 0.1524)
				(type default)
			)
			(layer "F.SilkS")
		)
		(fp_line
			(start -0.7874 -0.4064)
			(end 0.7874 -0.4064)
			(stroke
				(width 0.1524)
				(type default)
			)
			(layer "F.SilkS")
		)
		(fp_line
			(start 0.7874 0.4064)
			(end -0.7874 0.4064)
			(stroke
				(width 0.1524)
				(type default)
			)
			(layer "F.SilkS")
		)
		(fp_line
			(start -0.7874 0.4064)
			(end -0.7874 -0.4064)
			(stroke
				(width 0.1524)
				(type default)
			)
			(layer "F.SilkS")
		)
		(fp_line
			(start -0.12065 -0.305054)
			(end -0.12065 -0.2794)
			(stroke
				(width 0.1)
				(type default)
			)
			(layer "F.Fab")
		)
		(fp_line
			(start -0.67945 -0.305054)
			(end -0.12065 -0.305054)
			(stroke
				(width 0.1)
				(type default)
			)
			(layer "F.Fab")
		)
		(fp_line
			(start 0.67945 -0.3048)
			(end 0.67945 0.3048)
			(stroke
				(width 0.1)
				(type default)
			)
			(layer "F.Fab")
		)
		(fp_line
			(start 0.12065 -0.3048)
			(end 0.67945 -0.3048)
			(stroke
				(width 0.1)
				(type default)
			)
			(layer "F.Fab")
		)
		(fp_line
			(start 0.12065 -0.2794)
			(end 0.12065 -0.3048)
			(stroke
				(width 0.1)
				(type default)
			)
			(layer "F.Fab")
		)
		(fp_line
			(start -0.12065 -0.2794)
			(end 0.12065 -0.2794)
			(stroke
				(width 0.1)
				(type default)
			)
			(layer "F.Fab")
		)
		(fp_line
			(start 0.120396 0.2794)
			(end -0.12065 0.2794)
			(stroke
				(width 0.1)
				(type default)
			)
			(layer "F.Fab")
		)
		(fp_line
			(start -0.12065 0.2794)
			(end -0.12065 0.3048)
			(stroke
				(width 0.1)
				(type default)
			)
			(layer "F.Fab")
		)
		(fp_line
			(start 0.67945 0.3048)
			(end 0.120396 0.3048)
			(stroke
				(width 0.1)
				(type default)
			)
			(layer "F.Fab")
		)
		(fp_line
			(start 0.120396 0.3048)
			(end 0.120396 0.2794)
			(stroke
				(width 0.1)
				(type default)
			)
			(layer "F.Fab")
		)
		(fp_line
			(start -0.12065 0.3048)
			(end -0.67945 0.3048)
			(stroke
				(width 0.1)
				(type default)
			)
			(layer "F.Fab")
		)
		(fp_line
			(start -0.67945 0.3048)
			(end -0.67945 -0.305054)
			(stroke
				(width 0.1)
				(type default)
			)
			(layer "F.Fab")
		)
		(pad "1" smd circle
			(at -0.40005 0 90)
			(size 0 0)
			(layers "F.Cu" "F.Mask" "F.Paste")
			(net "P12V_SSD13")
		)
		(pad "2" smd circle
			(at 0.40005 0 90)
			(size 0 0)
			(layers "F.Cu" "F.Mask" "F.Paste")
			(net "GND")
		)
	)
	(footprint ""
		(layer "F.Cu")
		(at 242.134136 -394.98143)
		(property "Reference" "FS1"
			(at -6.4262 -2.64033 0)
			(unlocked yes)
			(layer "F.SilkS")
			(effects
				(font
					(size 0.7874 0.5842)
					(thickness 0.1524)
				)
				(justify left)
			)
		)
		(property "Value" ""
			(at 0 0 0)
			(layer "F.Fab")
			(effects
				(font
					(size 1.27 1.27)
				)
			)
		)
		(duplicate_pad_numbers_are_jumpers no)
		(fp_line
			(start -6.427724 -1.8415)
			(end -6.427724 1.8415)
			(stroke
				(width 0.1524)
				(type default)
			)
			(layer "F.SilkS")
		)
		(fp_line
			(start -6.427724 1.8415)
			(end 6.427724 1.8415)
			(stroke
				(width 0.1524)
				(type default)
			)
			(layer "F.SilkS")
		)
		(fp_line
			(start 6.427724 -1.8415)
			(end -6.427724 -1.8415)
			(stroke
				(width 0.1524)
				(type default)
			)
			(layer "F.SilkS")
		)
		(fp_line
			(start 6.427724 1.8415)
			(end 6.427724 -1.8415)
			(stroke
				(width 0.1524)
				(type default)
			)
			(layer "F.SilkS")
		)
		(fp_line
			(start -5.225034 -1.610106)
			(end 5.225034 -1.610106)
			(stroke
				(width 0.1)
				(type default)
			)
			(layer "F.Fab")
		)
		(fp_line
			(start -5.225034 1.610106)
			(end -5.225034 -1.610106)
			(stroke
				(width 0.1)
				(type default)
			)
			(layer "F.Fab")
		)
		(fp_line
			(start 5.225034 -1.610106)
			(end 5.225034 1.610106)
			(stroke
				(width 0.1)
				(type default)
			)
			(layer "F.Fab")
		)
		(fp_line
			(start 5.225034 1.610106)
			(end -5.225034 1.610106)
			(stroke
				(width 0.1)
				(type default)
			)
			(layer "F.Fab")
		)
		(pad "1" smd rect
			(at -4.675124 0)
			(size 3.2512 3.429)
			(layers "F.Cu" "F.Mask" "F.Paste")
			(net "P12V_STBY")
		)
		(pad "2" smd rect
			(at 4.675124 0)
			(size 3.2512 3.429)
			(layers "F.Cu" "F.Mask" "F.Paste")
			(net "P12V_STBY_FUSE")
		)
	)
	(footprint ""
		(layer "F.Cu")
		(at 206.121254 -298.87291 -90)
		(property "Reference" "R4016"
			(at 0 0 270)
			(layer "F.SilkS")
			(hide yes)
			(effects
				(font
					(size 1.27 1.27)
				)
			)
		)
		(property "Value" ""
			(at 0 0 270)
			(layer "F.Fab")
			(effects
				(font
					(size 1.27 1.27)
				)
			)
		)
		(duplicate_pad_numbers_are_jumpers no)
		(fp_line
			(start -0.7874 0.4064)
			(end -0.7874 -0.4064)
			(stroke
				(width 0.1524)
				(type default)
			)
			(layer "F.SilkS")
		)
		(fp_line
			(start 0.7874 0.4064)
			(end -0.7874 0.4064)
			(stroke
				(width 0.1524)
				(type default)
			)
			(layer "F.SilkS")
		)
		(fp_line
			(start -0.7874 -0.4064)
			(end 0.7874 -0.4064)
			(stroke
				(width 0.1524)
				(type default)
			)
			(layer "F.SilkS")
		)
		(fp_line
			(start 0.7874 -0.4064)
			(end 0.7874 0.4064)
			(stroke
				(width 0.1524)
				(type default)
			)
			(layer "F.SilkS")
		)
		(fp_line
			(start -0.67945 0.3048)
			(end -0.67945 -0.305054)
			(stroke
				(width 0.1)
				(type default)
			)
			(layer "F.Fab")
		)
		(fp_line
			(start -0.12065 0.3048)
			(end -0.67945 0.3048)
			(stroke
				(width 0.1)
				(type default)
			)
			(layer "F.Fab")
		)
		(fp_line
			(start 0.120396 0.3048)
			(end 0.120396 0.2794)
			(stroke
				(width 0.1)
				(type default)
			)
			(layer "F.Fab")
		)
		(fp_line
			(start 0.67945 0.3048)
			(end 0.120396 0.3048)
			(stroke
				(width 0.1)
				(type default)
			)
			(layer "F.Fab")
		)
		(fp_line
			(start -0.12065 0.2794)
			(end -0.12065 0.3048)
			(stroke
				(width 0.1)
				(type default)
			)
			(layer "F.Fab")
		)
		(fp_line
			(start 0.120396 0.2794)
			(end -0.12065 0.2794)
			(stroke
				(width 0.1)
				(type default)
			)
			(layer "F.Fab")
		)
		(fp_line
			(start -0.12065 -0.2794)
			(end 0.12065 -0.2794)
			(stroke
				(width 0.1)
				(type default)
			)
			(layer "F.Fab")
		)
		(fp_line
			(start 0.12065 -0.2794)
			(end 0.12065 -0.3048)
			(stroke
				(width 0.1)
				(type default)
			)
			(layer "F.Fab")
		)
		(fp_line
			(start 0.12065 -0.3048)
			(end 0.67945 -0.3048)
			(stroke
				(width 0.1)
				(type default)
			)
			(layer "F.Fab")
		)
		(fp_line
			(start 0.67945 -0.3048)
			(end 0.67945 0.3048)
			(stroke
				(width 0.1)
				(type default)
			)
			(layer "F.Fab")
		)
		(fp_line
			(start -0.67945 -0.305054)
			(end -0.12065 -0.305054)
			(stroke
				(width 0.1)
				(type default)
			)
			(layer "F.Fab")
		)
		(fp_line
			(start -0.12065 -0.305054)
			(end -0.12065 -0.2794)
			(stroke
				(width 0.1)
				(type default)
			)
			(layer "F.Fab")
		)
		(pad "1" smd circle
			(at -0.40005 0 270)
			(size 0 0)
			(layers "F.Cu" "F.Mask" "F.Paste")
			(net "P1V8_PEX")
		)
		(pad "2" smd circle
			(at 0.40005 0 270)
			(size 0 0)
			(layers "F.Cu" "F.Mask" "F.Paste")
			(net "I2C_PEX1_HOST_R_SDA")
		)
	)
	(footprint ""
		(layer "F.Cu")
		(at 111.861346 -303.698402 90)
		(property "Reference" "PC72"
			(at 0 0 90)
			(layer "F.SilkS")
			(hide yes)
			(effects
				(font
					(size 1.27 1.27)
				)
			)
		)
		(property "Value" ""
			(at 0 0 90)
			(layer "F.Fab")
			(effects
				(font
					(size 1.27 1.27)
				)
			)
		)
		(duplicate_pad_numbers_are_jumpers no)
		(fp_line
			(start -4.53898 -2.150618)
			(end -4.539742 2.152142)
			(stroke
				(width 0.1524)
				(type default)
			)
			(layer "F.SilkS")
		)
		(fp_line
			(start -4.69138 -2.150618)
			(end -4.692396 2.161032)
			(stroke
				(width 0.1524)
				(type default)
			)
			(layer "F.SilkS")
		)
		(fp_line
			(start -4.84378 -2.150618)
			(end -4.53898 -2.150618)
			(stroke
				(width 0.1524)
				(type default)
			)
			(layer "F.SilkS")
		)
		(fp_line
			(start -4.84378 -2.150618)
			(end -4.842256 2.163064)
			(stroke
				(width 0.1524)
				(type default)
			)
			(layer "F.SilkS")
		)
		(fp_line
			(start 4.53898 -2.15011)
			(end 4.53898 2.15011)
			(stroke
				(width 0.1524)
				(type default)
			)
			(layer "F.SilkS")
		)
		(fp_line
			(start -4.53898 -2.15011)
			(end 4.53898 -2.15011)
			(stroke
				(width 0.1524)
				(type default)
			)
			(layer "F.SilkS")
		)
		(fp_line
			(start 4.53898 2.15011)
			(end -4.53898 2.15011)
			(stroke
				(width 0.1524)
				(type default)
			)
			(layer "F.SilkS")
		)
		(fp_line
			(start -4.53898 2.15011)
			(end -4.53898 -2.15011)
			(stroke
				(width 0.1524)
				(type default)
			)
			(layer "F.SilkS")
		)
		(fp_line
			(start -4.83108 2.150364)
			(end -4.447794 2.149348)
			(stroke
				(width 0.1524)
				(type default)
			)
			(layer "F.SilkS")
		)
		(fp_line
			(start 3.64998 -2.15011)
			(end 3.64998 2.15011)
			(stroke
				(width 0.1)
				(type default)
			)
			(layer "F.Fab")
		)
		(fp_line
			(start -3.64998 -2.15011)
			(end 3.64998 -2.15011)
			(stroke
				(width 0.1)
				(type default)
			)
			(layer "F.Fab")
		)
		(fp_line
			(start 3.64998 2.15011)
			(end -3.64998 2.15011)
			(stroke
				(width 0.1)
				(type default)
			)
			(layer "F.Fab")
		)
		(fp_line
			(start -3.64998 2.15011)
			(end -3.64998 -2.15011)
			(stroke
				(width 0.1)
				(type default)
			)
			(layer "F.Fab")
		)
		(fp_text user "+"
			(at -4.933442 -3.126232 90)
			(unlocked yes)
			(layer "F.SilkS")
			(effects
				(font
					(size 1.905 1.4224)
					(thickness 0.1524)
				)
				(justify left)
			)
		)
		(fp_text user "-"
			(at 4.731512 -2.260346 90)
			(unlocked yes)
			(layer "F.SilkS")
			(effects
				(font
					(size 1.905 1.4224)
					(thickness 0.1524)
				)
				(justify left)
			)
		)
		(fp_text user "+"
			(at -6.214872 -0.337058 90)
			(unlocked yes)
			(layer "F.Fab")
			(effects
				(font
					(size 1.905 1.4224)
					(thickness 0.1524)
				)
				(justify left)
			)
		)
		(fp_text user "-"
			(at 4.313174 -0.094488 90)
			(unlocked yes)
			(layer "F.Fab")
			(effects
				(font
					(size 1.905 1.4224)
					(thickness 0.1524)
				)
				(justify left)
			)
		)
		(pad "1" smd rect
			(at -3.199892 0 90)
			(size 2.413 2.8194)
			(layers "F.Cu" "F.Mask" "F.Paste")
			(net "P0V8_PEX0")
		)
		(pad "2" smd rect
			(at 3.199892 0 90)
			(size 2.413 2.8194)
			(layers "F.Cu" "F.Mask" "F.Paste")
			(net "GND")
		)
	)
	(footprint ""
		(layer "F.Cu")
		(at 198.564246 -364.599728)
		(property "Reference" "PR15"
			(at 0 0 0)
			(layer "F.SilkS")
			(hide yes)
			(effects
				(font
					(size 1.27 1.27)
				)
			)
		)
		(property "Value" ""
			(at 0 0 0)
			(layer "F.Fab")
			(effects
				(font
					(size 1.27 1.27)
				)
			)
		)
		(duplicate_pad_numbers_are_jumpers no)
		(fp_line
			(start -0.7874 -0.4064)
			(end 0.7874 -0.4064)
			(stroke
				(width 0.1524)
				(type default)
			)
			(layer "F.SilkS")
		)
		(fp_line
			(start -0.7874 0.4064)
			(end -0.7874 -0.4064)
			(stroke
				(width 0.1524)
				(type default)
			)
			(layer "F.SilkS")
		)
		(fp_line
			(start 0.7874 -0.4064)
			(end 0.7874 0.4064)
			(stroke
				(width 0.1524)
				(type default)
			)
			(layer "F.SilkS")
		)
		(fp_line
			(start 0.7874 0.4064)
			(end -0.7874 0.4064)
			(stroke
				(width 0.1524)
				(type default)
			)
			(layer "F.SilkS")
		)
		(fp_line
			(start -0.67945 -0.305054)
			(end -0.12065 -0.305054)
			(stroke
				(width 0.1)
				(type default)
			)
			(layer "F.Fab")
		)
		(fp_line
			(start -0.67945 0.3048)
			(end -0.67945 -0.305054)
			(stroke
				(width 0.1)
				(type default)
			)
			(layer "F.Fab")
		)
		(fp_line
			(start -0.12065 -0.305054)
			(end -0.12065 -0.2794)
			(stroke
				(width 0.1)
				(type default)
			)
			(layer "F.Fab")
		)
		(fp_line
			(start -0.12065 -0.2794)
			(end 0.12065 -0.2794)
			(stroke
				(width 0.1)
				(type default)
			)
			(layer "F.Fab")
		)
		(fp_line
			(start -0.12065 0.2794)
			(end -0.12065 0.3048)
			(stroke
				(width 0.1)
				(type default)
			)
			(layer "F.Fab")
		)
		(fp_line
			(start -0.12065 0.3048)
			(end -0.67945 0.3048)
			(stroke
				(width 0.1)
				(type default)
			)
			(layer "F.Fab")
		)
		(fp_line
			(start 0.120396 0.2794)
			(end -0.12065 0.2794)
			(stroke
				(width 0.1)
				(type default)
			)
			(layer "F.Fab")
		)
		(fp_line
			(start 0.120396 0.3048)
			(end 0.120396 0.2794)
			(stroke
				(width 0.1)
				(type default)
			)
			(layer "F.Fab")
		)
		(fp_line
			(start 0.12065 -0.3048)
			(end 0.67945 -0.3048)
			(stroke
				(width 0.1)
				(type default)
			)
			(layer "F.Fab")
		)
		(fp_line
			(start 0.12065 -0.2794)
			(end 0.12065 -0.3048)
			(stroke
				(width 0.1)
				(type default)
			)
			(layer "F.Fab")
		)
		(fp_line
			(start 0.67945 -0.3048)
			(end 0.67945 0.3048)
			(stroke
				(width 0.1)
				(type default)
			)
			(layer "F.Fab")
		)
		(fp_line
			(start 0.67945 0.3048)
			(end 0.120396 0.3048)
			(stroke
				(width 0.1)
				(type default)
			)
			(layer "F.Fab")
		)
		(pad "1" smd circle
			(at -0.40005 0)
			(size 0 0)
			(layers "F.Cu" "F.Mask" "F.Paste")
			(net "AGND_HSC")
		)
		(pad "2" smd circle
			(at 0.40005 0)
			(size 0 0)
			(layers "F.Cu" "F.Mask" "F.Paste")
			(net "HSC_CS")
		)
	)
	(footprint ""
		(layer "F.Cu")
		(at 104.267762 -53.051456)
		(property "Reference" "R4464"
			(at 0 0 0)
			(layer "F.SilkS")
			(hide yes)
			(effects
				(font
					(size 1.27 1.27)
				)
			)
		)
		(property "Value" ""
			(at 0 0 0)
			(layer "F.Fab")
			(effects
				(font
					(size 1.27 1.27)
				)
			)
		)
		(duplicate_pad_numbers_are_jumpers no)
		(fp_line
			(start -0.7874 -0.4064)
			(end 0.7874 -0.4064)
			(stroke
				(width 0.1524)
				(type default)
			)
			(layer "F.SilkS")
		)
		(fp_line
			(start -0.7874 0.4064)
			(end -0.7874 -0.4064)
			(stroke
				(width 0.1524)
				(type default)
			)
			(layer "F.SilkS")
		)
		(fp_line
			(start 0.7874 -0.4064)
			(end 0.7874 0.4064)
			(stroke
				(width 0.1524)
				(type default)
			)
			(layer "F.SilkS")
		)
		(fp_line
			(start 0.7874 0.4064)
			(end -0.7874 0.4064)
			(stroke
				(width 0.1524)
				(type default)
			)
			(layer "F.SilkS")
		)
		(fp_line
			(start -0.67945 -0.305054)
			(end -0.12065 -0.305054)
			(stroke
				(width 0.1)
				(type default)
			)
			(layer "F.Fab")
		)
		(fp_line
			(start -0.67945 0.3048)
			(end -0.67945 -0.305054)
			(stroke
				(width 0.1)
				(type default)
			)
			(layer "F.Fab")
		)
		(fp_line
			(start -0.12065 -0.305054)
			(end -0.12065 -0.2794)
			(stroke
				(width 0.1)
				(type default)
			)
			(layer "F.Fab")
		)
		(fp_line
			(start -0.12065 -0.2794)
			(end 0.12065 -0.2794)
			(stroke
				(width 0.1)
				(type default)
			)
			(layer "F.Fab")
		)
		(fp_line
			(start -0.12065 0.2794)
			(end -0.12065 0.3048)
			(stroke
				(width 0.1)
				(type default)
			)
			(layer "F.Fab")
		)
		(fp_line
			(start -0.12065 0.3048)
			(end -0.67945 0.3048)
			(stroke
				(width 0.1)
				(type default)
			)
			(layer "F.Fab")
		)
		(fp_line
			(start 0.120396 0.2794)
			(end -0.12065 0.2794)
			(stroke
				(width 0.1)
				(type default)
			)
			(layer "F.Fab")
		)
		(fp_line
			(start 0.120396 0.3048)
			(end 0.120396 0.2794)
			(stroke
				(width 0.1)
				(type default)
			)
			(layer "F.Fab")
		)
		(fp_line
			(start 0.12065 -0.3048)
			(end 0.67945 -0.3048)
			(stroke
				(width 0.1)
				(type default)
			)
			(layer "F.Fab")
		)
		(fp_line
			(start 0.12065 -0.2794)
			(end 0.12065 -0.3048)
			(stroke
				(width 0.1)
				(type default)
			)
			(layer "F.Fab")
		)
		(fp_line
			(start 0.67945 -0.3048)
			(end 0.67945 0.3048)
			(stroke
				(width 0.1)
				(type default)
			)
			(layer "F.Fab")
		)
		(fp_line
			(start 0.67945 0.3048)
			(end 0.120396 0.3048)
			(stroke
				(width 0.1)
				(type default)
			)
			(layer "F.Fab")
		)
		(pad "1" smd circle
			(at -0.40005 0)
			(size 0 0)
			(layers "F.Cu" "F.Mask" "F.Paste")
			(net "PWRGD_P12V_SSD3")
		)
		(pad "2" smd circle
			(at 0.40005 0)
			(size 0 0)
			(layers "F.Cu" "F.Mask" "F.Paste")
			(net "PWRGD_P12V_SSD3_R")
		)
	)
	(footprint ""
		(layer "F.Cu")
		(at 8.45058 -71.443088 180)
		(property "Reference" "R5654"
			(at 0 0 180)
			(layer "F.SilkS")
			(hide yes)
			(effects
				(font
					(size 1.27 1.27)
				)
			)
		)
		(property "Value" ""
			(at 0 0 180)
			(layer "F.Fab")
			(effects
				(font
					(size 1.27 1.27)
				)
			)
		)
		(duplicate_pad_numbers_are_jumpers no)
		(fp_line
			(start 0.7874 0.4064)
			(end -0.7874 0.4064)
			(stroke
				(width 0.1524)
				(type default)
			)
			(layer "F.SilkS")
		)
		(fp_line
			(start 0.7874 -0.4064)
			(end 0.7874 0.4064)
			(stroke
				(width 0.1524)
				(type default)
			)
			(layer "F.SilkS")
		)
		(fp_line
			(start -0.7874 0.4064)
			(end -0.7874 -0.4064)
			(stroke
				(width 0.1524)
				(type default)
			)
			(layer "F.SilkS")
		)
		(fp_line
			(start -0.7874 -0.4064)
			(end 0.7874 -0.4064)
			(stroke
				(width 0.1524)
				(type default)
			)
			(layer "F.SilkS")
		)
		(fp_line
			(start 0.67945 0.3048)
			(end 0.120396 0.3048)
			(stroke
				(width 0.1)
				(type default)
			)
			(layer "F.Fab")
		)
		(fp_line
			(start 0.67945 -0.3048)
			(end 0.67945 0.3048)
			(stroke
				(width 0.1)
				(type default)
			)
			(layer "F.Fab")
		)
		(fp_line
			(start 0.12065 -0.2794)
			(end 0.12065 -0.3048)
			(stroke
				(width 0.1)
				(type default)
			)
			(layer "F.Fab")
		)
		(fp_line
			(start 0.12065 -0.3048)
			(end 0.67945 -0.3048)
			(stroke
				(width 0.1)
				(type default)
			)
			(layer "F.Fab")
		)
		(fp_line
			(start 0.120396 0.3048)
			(end 0.120396 0.2794)
			(stroke
				(width 0.1)
				(type default)
			)
			(layer "F.Fab")
		)
		(fp_line
			(start 0.120396 0.2794)
			(end -0.12065 0.2794)
			(stroke
				(width 0.1)
				(type default)
			)
			(layer "F.Fab")
		)
		(fp_line
			(start -0.12065 0.3048)
			(end -0.67945 0.3048)
			(stroke
				(width 0.1)
				(type default)
			)
			(layer "F.Fab")
		)
		(fp_line
			(start -0.12065 0.2794)
			(end -0.12065 0.3048)
			(stroke
				(width 0.1)
				(type default)
			)
			(layer "F.Fab")
		)
		(fp_line
			(start -0.12065 -0.2794)
			(end 0.12065 -0.2794)
			(stroke
				(width 0.1)
				(type default)
			)
			(layer "F.Fab")
		)
		(fp_line
			(start -0.12065 -0.305054)
			(end -0.12065 -0.2794)
			(stroke
				(width 0.1)
				(type default)
			)
			(layer "F.Fab")
		)
		(fp_line
			(start -0.67945 0.3048)
			(end -0.67945 -0.305054)
			(stroke
				(width 0.1)
				(type default)
			)
			(layer "F.Fab")
		)
		(fp_line
			(start -0.67945 -0.305054)
			(end -0.12065 -0.305054)
			(stroke
				(width 0.1)
				(type default)
			)
			(layer "F.Fab")
		)
		(pad "1" smd circle
			(at -0.40005 0 180)
			(size 0 0)
			(layers "F.Cu" "F.Mask" "F.Paste")
			(net "RST_SMB_SSD0_ISO_R_N")
		)
		(pad "2" smd circle
			(at 0.40005 0 180)
			(size 0 0)
			(layers "F.Cu" "F.Mask" "F.Paste")
			(net "RST_SMB_SSD0_ISO_N")
		)
	)
	(footprint ""
		(layer "F.Cu")
		(at 428.83963 -138.661648 180)
		(property "Reference" "R396"
			(at 0 0 180)
			(layer "F.SilkS")
			(hide yes)
			(effects
				(font
					(size 1.27 1.27)
				)
			)
		)
		(property "Value" ""
			(at 0 0 180)
			(layer "F.Fab")
			(effects
				(font
					(size 1.27 1.27)
				)
			)
		)
		(duplicate_pad_numbers_are_jumpers no)
		(fp_line
			(start 0.7874 0.4064)
			(end -0.7874 0.4064)
			(stroke
				(width 0.1524)
				(type default)
			)
			(layer "F.SilkS")
		)
		(fp_line
			(start 0.7874 -0.4064)
			(end 0.7874 0.4064)
			(stroke
				(width 0.1524)
				(type default)
			)
			(layer "F.SilkS")
		)
		(fp_line
			(start -0.7874 0.4064)
			(end -0.7874 -0.4064)
			(stroke
				(width 0.1524)
				(type default)
			)
			(layer "F.SilkS")
		)
		(fp_line
			(start -0.7874 -0.4064)
			(end 0.7874 -0.4064)
			(stroke
				(width 0.1524)
				(type default)
			)
			(layer "F.SilkS")
		)
		(fp_line
			(start 0.67945 0.3048)
			(end 0.120396 0.3048)
			(stroke
				(width 0.1)
				(type default)
			)
			(layer "F.Fab")
		)
		(fp_line
			(start 0.67945 -0.3048)
			(end 0.67945 0.3048)
			(stroke
				(width 0.1)
				(type default)
			)
			(layer "F.Fab")
		)
		(fp_line
			(start 0.12065 -0.2794)
			(end 0.12065 -0.3048)
			(stroke
				(width 0.1)
				(type default)
			)
			(layer "F.Fab")
		)
		(fp_line
			(start 0.12065 -0.3048)
			(end 0.67945 -0.3048)
			(stroke
				(width 0.1)
				(type default)
			)
			(layer "F.Fab")
		)
		(fp_line
			(start 0.120396 0.3048)
			(end 0.120396 0.2794)
			(stroke
				(width 0.1)
				(type default)
			)
			(layer "F.Fab")
		)
		(fp_line
			(start 0.120396 0.2794)
			(end -0.12065 0.2794)
			(stroke
				(width 0.1)
				(type default)
			)
			(layer "F.Fab")
		)
		(fp_line
			(start -0.12065 0.3048)
			(end -0.67945 0.3048)
			(stroke
				(width 0.1)
				(type default)
			)
			(layer "F.Fab")
		)
		(fp_line
			(start -0.12065 0.2794)
			(end -0.12065 0.3048)
			(stroke
				(width 0.1)
				(type default)
			)
			(layer "F.Fab")
		)
		(fp_line
			(start -0.12065 -0.2794)
			(end 0.12065 -0.2794)
			(stroke
				(width 0.1)
				(type default)
			)
			(layer "F.Fab")
		)
		(fp_line
			(start -0.12065 -0.305054)
			(end -0.12065 -0.2794)
			(stroke
				(width 0.1)
				(type default)
			)
			(layer "F.Fab")
		)
		(fp_line
			(start -0.67945 0.3048)
			(end -0.67945 -0.305054)
			(stroke
				(width 0.1)
				(type default)
			)
			(layer "F.Fab")
		)
		(fp_line
			(start -0.67945 -0.305054)
			(end -0.12065 -0.305054)
			(stroke
				(width 0.1)
				(type default)
			)
			(layer "F.Fab")
		)
		(pad "1" smd circle
			(at -0.40005 0 180)
			(size 0 0)
			(layers "F.Cu" "F.Mask" "F.Paste")
			(net "PRSNT_NIC7_N")
		)
		(pad "2" smd circle
			(at 0.40005 0 180)
			(size 0 0)
			(layers "F.Cu" "F.Mask" "F.Paste")
			(net "PRSNTB0_NIC7_N")
		)
	)
	(footprint ""
		(layer "F.Cu")
		(at 311.514744 -79.58201 90)
		(property "Reference" "R304"
			(at 0 0 90)
			(layer "F.SilkS")
			(hide yes)
			(effects
				(font
					(size 1.27 1.27)
				)
			)
		)
		(property "Value" ""
			(at 0 0 90)
			(layer "F.Fab")
			(effects
				(font
					(size 1.27 1.27)
				)
			)
		)
		(duplicate_pad_numbers_are_jumpers no)
		(fp_line
			(start 0.7874 -0.4064)
			(end 0.7874 0.4064)
			(stroke
				(width 0.1524)
				(type default)
			)
			(layer "F.SilkS")
		)
		(fp_line
			(start -0.7874 -0.4064)
			(end 0.7874 -0.4064)
			(stroke
				(width 0.1524)
				(type default)
			)
			(layer "F.SilkS")
		)
		(fp_line
			(start 0.7874 0.4064)
			(end -0.7874 0.4064)
			(stroke
				(width 0.1524)
				(type default)
			)
			(layer "F.SilkS")
		)
		(fp_line
			(start -0.7874 0.4064)
			(end -0.7874 -0.4064)
			(stroke
				(width 0.1524)
				(type default)
			)
			(layer "F.SilkS")
		)
		(fp_line
			(start -0.12065 -0.305054)
			(end -0.12065 -0.2794)
			(stroke
				(width 0.1)
				(type default)
			)
			(layer "F.Fab")
		)
		(fp_line
			(start -0.67945 -0.305054)
			(end -0.12065 -0.305054)
			(stroke
				(width 0.1)
				(type default)
			)
			(layer "F.Fab")
		)
		(fp_line
			(start 0.67945 -0.3048)
			(end 0.67945 0.3048)
			(stroke
				(width 0.1)
				(type default)
			)
			(layer "F.Fab")
		)
		(fp_line
			(start 0.12065 -0.3048)
			(end 0.67945 -0.3048)
			(stroke
				(width 0.1)
				(type default)
			)
			(layer "F.Fab")
		)
		(fp_line
			(start 0.12065 -0.2794)
			(end 0.12065 -0.3048)
			(stroke
				(width 0.1)
				(type default)
			)
			(layer "F.Fab")
		)
		(fp_line
			(start -0.12065 -0.2794)
			(end 0.12065 -0.2794)
			(stroke
				(width 0.1)
				(type default)
			)
			(layer "F.Fab")
		)
		(fp_line
			(start 0.120396 0.2794)
			(end -0.12065 0.2794)
			(stroke
				(width 0.1)
				(type default)
			)
			(layer "F.Fab")
		)
		(fp_line
			(start -0.12065 0.2794)
			(end -0.12065 0.3048)
			(stroke
				(width 0.1)
				(type default)
			)
			(layer "F.Fab")
		)
		(fp_line
			(start 0.67945 0.3048)
			(end 0.120396 0.3048)
			(stroke
				(width 0.1)
				(type default)
			)
			(layer "F.Fab")
		)
		(fp_line
			(start 0.120396 0.3048)
			(end 0.120396 0.2794)
			(stroke
				(width 0.1)
				(type default)
			)
			(layer "F.Fab")
		)
		(fp_line
			(start -0.12065 0.3048)
			(end -0.67945 0.3048)
			(stroke
				(width 0.1)
				(type default)
			)
			(layer "F.Fab")
		)
		(fp_line
			(start -0.67945 0.3048)
			(end -0.67945 -0.305054)
			(stroke
				(width 0.1)
				(type default)
			)
			(layer "F.Fab")
		)
		(pad "1" smd circle
			(at -0.40005 0 90)
			(size 0 0)
			(layers "F.Cu" "F.Mask" "F.Paste")
			(net "P3V3_NIC5")
		)
		(pad "2" smd circle
			(at 0.40005 0 90)
			(size 0 0)
			(layers "F.Cu" "F.Mask" "F.Paste")
			(net "HP_NIC5_PWRGD")
		)
	)
	(footprint ""
		(layer "F.Cu")
		(at 219.260674 -105.291382)
		(property "Reference" "C419"
			(at 0 0 0)
			(layer "F.SilkS")
			(hide yes)
			(effects
				(font
					(size 1.27 1.27)
				)
			)
		)
		(property "Value" ""
			(at 0 0 0)
			(layer "F.Fab")
			(effects
				(font
					(size 1.27 1.27)
				)
			)
		)
		(duplicate_pad_numbers_are_jumpers no)
		(fp_line
			(start -0.7874 -0.4064)
			(end 0.7874 -0.4064)
			(stroke
				(width 0.1524)
				(type default)
			)
			(layer "F.SilkS")
		)
		(fp_line
			(start -0.7874 0.4064)
			(end -0.7874 -0.4064)
			(stroke
				(width 0.1524)
				(type default)
			)
			(layer "F.SilkS")
		)
		(fp_line
			(start 0.7874 -0.4064)
			(end 0.7874 0.4064)
			(stroke
				(width 0.1524)
				(type default)
			)
			(layer "F.SilkS")
		)
		(fp_line
			(start 0.7874 0.4064)
			(end -0.7874 0.4064)
			(stroke
				(width 0.1524)
				(type default)
			)
			(layer "F.SilkS")
		)
		(fp_line
			(start -0.67945 -0.305054)
			(end -0.12065 -0.305054)
			(stroke
				(width 0.1)
				(type default)
			)
			(layer "F.Fab")
		)
		(fp_line
			(start -0.67945 0.3048)
			(end -0.67945 -0.305054)
			(stroke
				(width 0.1)
				(type default)
			)
			(layer "F.Fab")
		)
		(fp_line
			(start -0.12065 -0.305054)
			(end -0.12065 -0.2794)
			(stroke
				(width 0.1)
				(type default)
			)
			(layer "F.Fab")
		)
		(fp_line
			(start -0.12065 -0.2794)
			(end 0.12065 -0.2794)
			(stroke
				(width 0.1)
				(type default)
			)
			(layer "F.Fab")
		)
		(fp_line
			(start -0.12065 0.2794)
			(end -0.12065 0.3048)
			(stroke
				(width 0.1)
				(type default)
			)
			(layer "F.Fab")
		)
		(fp_line
			(start -0.12065 0.3048)
			(end -0.67945 0.3048)
			(stroke
				(width 0.1)
				(type default)
			)
			(layer "F.Fab")
		)
		(fp_line
			(start 0.120396 0.2794)
			(end -0.12065 0.2794)
			(stroke
				(width 0.1)
				(type default)
			)
			(layer "F.Fab")
		)
		(fp_line
			(start 0.120396 0.3048)
			(end 0.120396 0.2794)
			(stroke
				(width 0.1)
				(type default)
			)
			(layer "F.Fab")
		)
		(fp_line
			(start 0.12065 -0.3048)
			(end 0.67945 -0.3048)
			(stroke
				(width 0.1)
				(type default)
			)
			(layer "F.Fab")
		)
		(fp_line
			(start 0.12065 -0.2794)
			(end 0.12065 -0.3048)
			(stroke
				(width 0.1)
				(type default)
			)
			(layer "F.Fab")
		)
		(fp_line
			(start 0.67945 -0.3048)
			(end 0.67945 0.3048)
			(stroke
				(width 0.1)
				(type default)
			)
			(layer "F.Fab")
		)
		(fp_line
			(start 0.67945 0.3048)
			(end 0.120396 0.3048)
			(stroke
				(width 0.1)
				(type default)
			)
			(layer "F.Fab")
		)
		(pad "1" smd circle
			(at -0.40005 0)
			(size 0 0)
			(layers "F.Cu" "F.Mask" "F.Paste")
			(net "P12V_NIC3_R")
		)
		(pad "2" smd circle
			(at 0.40005 0)
			(size 0 0)
			(layers "F.Cu" "F.Mask" "F.Paste")
			(net "GND")
		)
	)
	(footprint ""
		(layer "F.Cu")
		(at 237.101888 -32.849312 90)
		(property "Reference" "R5686"
			(at 0 0 90)
			(layer "F.SilkS")
			(hide yes)
			(effects
				(font
					(size 1.27 1.27)
				)
			)
		)
		(property "Value" ""
			(at 0 0 90)
			(layer "F.Fab")
			(effects
				(font
					(size 1.27 1.27)
				)
			)
		)
		(duplicate_pad_numbers_are_jumpers no)
		(fp_line
			(start 0.7874 -0.4064)
			(end 0.7874 0.4064)
			(stroke
				(width 0.1524)
				(type default)
			)
			(layer "F.SilkS")
		)
		(fp_line
			(start -0.7874 -0.4064)
			(end 0.7874 -0.4064)
			(stroke
				(width 0.1524)
				(type default)
			)
			(layer "F.SilkS")
		)
		(fp_line
			(start 0.7874 0.4064)
			(end -0.7874 0.4064)
			(stroke
				(width 0.1524)
				(type default)
			)
			(layer "F.SilkS")
		)
		(fp_line
			(start -0.7874 0.4064)
			(end -0.7874 -0.4064)
			(stroke
				(width 0.1524)
				(type default)
			)
			(layer "F.SilkS")
		)
		(fp_line
			(start -0.12065 -0.305054)
			(end -0.12065 -0.2794)
			(stroke
				(width 0.1)
				(type default)
			)
			(layer "F.Fab")
		)
		(fp_line
			(start -0.67945 -0.305054)
			(end -0.12065 -0.305054)
			(stroke
				(width 0.1)
				(type default)
			)
			(layer "F.Fab")
		)
		(fp_line
			(start 0.67945 -0.3048)
			(end 0.67945 0.3048)
			(stroke
				(width 0.1)
				(type default)
			)
			(layer "F.Fab")
		)
		(fp_line
			(start 0.12065 -0.3048)
			(end 0.67945 -0.3048)
			(stroke
				(width 0.1)
				(type default)
			)
			(layer "F.Fab")
		)
		(fp_line
			(start 0.12065 -0.2794)
			(end 0.12065 -0.3048)
			(stroke
				(width 0.1)
				(type default)
			)
			(layer "F.Fab")
		)
		(fp_line
			(start -0.12065 -0.2794)
			(end 0.12065 -0.2794)
			(stroke
				(width 0.1)
				(type default)
			)
			(layer "F.Fab")
		)
		(fp_line
			(start 0.120396 0.2794)
			(end -0.12065 0.2794)
			(stroke
				(width 0.1)
				(type default)
			)
			(layer "F.Fab")
		)
		(fp_line
			(start -0.12065 0.2794)
			(end -0.12065 0.3048)
			(stroke
				(width 0.1)
				(type default)
			)
			(layer "F.Fab")
		)
		(fp_line
			(start 0.67945 0.3048)
			(end 0.120396 0.3048)
			(stroke
				(width 0.1)
				(type default)
			)
			(layer "F.Fab")
		)
		(fp_line
			(start 0.120396 0.3048)
			(end 0.120396 0.2794)
			(stroke
				(width 0.1)
				(type default)
			)
			(layer "F.Fab")
		)
		(fp_line
			(start -0.12065 0.3048)
			(end -0.67945 0.3048)
			(stroke
				(width 0.1)
				(type default)
			)
			(layer "F.Fab")
		)
		(fp_line
			(start -0.67945 0.3048)
			(end -0.67945 -0.305054)
			(stroke
				(width 0.1)
				(type default)
			)
			(layer "F.Fab")
		)
		(pad "1" smd circle
			(at -0.40005 0 90)
			(size 0 0)
			(layers "F.Cu" "F.Mask" "F.Paste")
			(net "RST_SMB_SSD8_ISO_R_N")
		)
		(pad "2" smd circle
			(at 0.40005 0 90)
			(size 0 0)
			(layers "F.Cu" "F.Mask" "F.Paste")
			(net "RST_SMB_SSD8_ISO_N")
		)
	)
	(footprint ""
		(layer "F.Cu")
		(at 261.023608 -306.366418 45)
		(property "Reference" "R1388"
			(at 0 0 45)
			(layer "F.SilkS")
			(hide yes)
			(effects
				(font
					(size 1.27 1.27)
				)
			)
		)
		(property "Value" ""
			(at 0 0 45)
			(layer "F.Fab")
			(effects
				(font
					(size 1.27 1.27)
				)
			)
		)
		(duplicate_pad_numbers_are_jumpers no)
		(fp_line
			(start -0.787389 -0.406267)
			(end 0.787389 -0.406267)
			(stroke
				(width 0.1524)
				(type default)
			)
			(layer "F.SilkS")
		)
		(fp_line
			(start -0.787389 0.406267)
			(end -0.787389 -0.406267)
			(stroke
				(width 0.1524)
				(type default)
			)
			(layer "F.SilkS")
		)
		(fp_line
			(start 0.787389 -0.406267)
			(end 0.787389 0.406267)
			(stroke
				(width 0.1524)
				(type default)
			)
			(layer "F.SilkS")
		)
		(fp_line
			(start 0.787389 0.406267)
			(end -0.787389 0.406267)
			(stroke
				(width 0.1524)
				(type default)
			)
			(layer "F.SilkS")
		)
		(fp_line
			(start -0.679446 -0.305149)
			(end -0.120695 -0.304969)
			(stroke
				(width 0.1)
				(type default)
			)
			(layer "F.Fab")
		)
		(fp_line
			(start -0.120695 -0.304969)
			(end -0.120695 -0.279466)
			(stroke
				(width 0.1)
				(type default)
			)
			(layer "F.Fab")
		)
		(fp_line
			(start -0.120695 -0.279466)
			(end 0.120695 -0.279466)
			(stroke
				(width 0.1)
				(type default)
			)
			(layer "F.Fab")
		)
		(fp_line
			(start -0.679446 0.30479)
			(end -0.679446 -0.305149)
			(stroke
				(width 0.1)
				(type default)
			)
			(layer "F.Fab")
		)
		(fp_line
			(start 0.120515 -0.30479)
			(end 0.679446 -0.30479)
			(stroke
				(width 0.1)
				(type default)
			)
			(layer "F.Fab")
		)
		(fp_line
			(start 0.120695 -0.279466)
			(end 0.120515 -0.30479)
			(stroke
				(width 0.1)
				(type default)
			)
			(layer "F.Fab")
		)
		(fp_line
			(start -0.120695 0.279466)
			(end -0.120515 0.30479)
			(stroke
				(width 0.1)
				(type default)
			)
			(layer "F.Fab")
		)
		(fp_line
			(start -0.120515 0.30479)
			(end -0.679446 0.30479)
			(stroke
				(width 0.1)
				(type default)
			)
			(layer "F.Fab")
		)
		(fp_line
			(start 0.679446 -0.30479)
			(end 0.679446 0.30479)
			(stroke
				(width 0.1)
				(type default)
			)
			(layer "F.Fab")
		)
		(fp_line
			(start 0.120335 0.279466)
			(end -0.120695 0.279466)
			(stroke
				(width 0.1)
				(type default)
			)
			(layer "F.Fab")
		)
		(fp_line
			(start 0.120515 0.30479)
			(end 0.120335 0.279466)
			(stroke
				(width 0.1)
				(type default)
			)
			(layer "F.Fab")
		)
		(fp_line
			(start 0.679446 0.30479)
			(end 0.120515 0.30479)
			(stroke
				(width 0.1)
				(type default)
			)
			(layer "F.Fab")
		)
		(pad "1" smd circle
			(at -0.40005 0 45)
			(size 0 0)
			(layers "F.Cu" "F.Mask" "F.Paste")
			(net "GND")
		)
		(pad "2" smd circle
			(at 0.40005 0 45)
			(size 0 0)
			(layers "F.Cu" "F.Mask" "F.Paste")
			(net "PEX2_DFT_IDDT")
		)
	)
	(footprint ""
		(layer "F.Cu")
		(at 315.586364 -350.098614 90)
		(property "Reference" "C553"
			(at 0 0 90)
			(layer "F.SilkS")
			(hide yes)
			(effects
				(font
					(size 1.27 1.27)
				)
			)
		)
		(property "Value" ""
			(at 0 0 90)
			(layer "F.Fab")
			(effects
				(font
					(size 1.27 1.27)
				)
			)
		)
		(duplicate_pad_numbers_are_jumpers no)
		(fp_line
			(start 0.299974 -0.150114)
			(end 0.299974 0.150114)
			(stroke
				(width 0.1)
				(type default)
			)
			(layer "F.Fab")
		)
		(fp_line
			(start -0.299974 -0.150114)
			(end 0.299974 -0.150114)
			(stroke
				(width 0.1)
				(type default)
			)
			(layer "F.Fab")
		)
		(fp_line
			(start 0.299974 0.150114)
			(end -0.299974 0.150114)
			(stroke
				(width 0.1)
				(type default)
			)
			(layer "F.Fab")
		)
		(fp_line
			(start -0.299974 0.150114)
			(end -0.299974 -0.150114)
			(stroke
				(width 0.1)
				(type default)
			)
			(layer "F.Fab")
		)
		(pad "1" smd rect
			(at -0.2667 0 90)
			(size 0.3048 0.381)
			(layers "F.Cu" "F.Mask" "F.Paste")
			(net "P5E_PEX2_STN6_TX_DP<110>")
		)
		(pad "2" smd rect
			(at 0.2667 0 90)
			(size 0.3048 0.381)
			(layers "F.Cu" "F.Mask" "F.Paste")
			(net "P5E_PEX2_STN6_TX_C_DP<110>")
		)
	)
	(footprint ""
		(layer "F.Cu")
		(at 78.243684 -45.88891)
		(property "Reference" "R532"
			(at 0 0 0)
			(layer "F.SilkS")
			(hide yes)
			(effects
				(font
					(size 1.27 1.27)
				)
			)
		)
		(property "Value" ""
			(at 0 0 0)
			(layer "F.Fab")
			(effects
				(font
					(size 1.27 1.27)
				)
			)
		)
		(duplicate_pad_numbers_are_jumpers no)
		(fp_line
			(start -0.7874 -0.4064)
			(end 0.7874 -0.4064)
			(stroke
				(width 0.1524)
				(type default)
			)
			(layer "F.SilkS")
		)
		(fp_line
			(start -0.7874 0.4064)
			(end -0.7874 -0.4064)
			(stroke
				(width 0.1524)
				(type default)
			)
			(layer "F.SilkS")
		)
		(fp_line
			(start 0.7874 -0.4064)
			(end 0.7874 0.4064)
			(stroke
				(width 0.1524)
				(type default)
			)
			(layer "F.SilkS")
		)
		(fp_line
			(start 0.7874 0.4064)
			(end -0.7874 0.4064)
			(stroke
				(width 0.1524)
				(type default)
			)
			(layer "F.SilkS")
		)
		(fp_line
			(start -0.67945 -0.305054)
			(end -0.12065 -0.305054)
			(stroke
				(width 0.1)
				(type default)
			)
			(layer "F.Fab")
		)
		(fp_line
			(start -0.67945 0.3048)
			(end -0.67945 -0.305054)
			(stroke
				(width 0.1)
				(type default)
			)
			(layer "F.Fab")
		)
		(fp_line
			(start -0.12065 -0.305054)
			(end -0.12065 -0.2794)
			(stroke
				(width 0.1)
				(type default)
			)
			(layer "F.Fab")
		)
		(fp_line
			(start -0.12065 -0.2794)
			(end 0.12065 -0.2794)
			(stroke
				(width 0.1)
				(type default)
			)
			(layer "F.Fab")
		)
		(fp_line
			(start -0.12065 0.2794)
			(end -0.12065 0.3048)
			(stroke
				(width 0.1)
				(type default)
			)
			(layer "F.Fab")
		)
		(fp_line
			(start -0.12065 0.3048)
			(end -0.67945 0.3048)
			(stroke
				(width 0.1)
				(type default)
			)
			(layer "F.Fab")
		)
		(fp_line
			(start 0.120396 0.2794)
			(end -0.12065 0.2794)
			(stroke
				(width 0.1)
				(type default)
			)
			(layer "F.Fab")
		)
		(fp_line
			(start 0.120396 0.3048)
			(end 0.120396 0.2794)
			(stroke
				(width 0.1)
				(type default)
			)
			(layer "F.Fab")
		)
		(fp_line
			(start 0.12065 -0.3048)
			(end 0.67945 -0.3048)
			(stroke
				(width 0.1)
				(type default)
			)
			(layer "F.Fab")
		)
		(fp_line
			(start 0.12065 -0.2794)
			(end 0.12065 -0.3048)
			(stroke
				(width 0.1)
				(type default)
			)
			(layer "F.Fab")
		)
		(fp_line
			(start 0.67945 -0.3048)
			(end 0.67945 0.3048)
			(stroke
				(width 0.1)
				(type default)
			)
			(layer "F.Fab")
		)
		(fp_line
			(start 0.67945 0.3048)
			(end 0.120396 0.3048)
			(stroke
				(width 0.1)
				(type default)
			)
			(layer "F.Fab")
		)
		(pad "1" smd circle
			(at -0.40005 0)
			(size 0 0)
			(layers "F.Cu" "F.Mask" "F.Paste")
			(net "SSD2_ADC_A0")
		)
		(pad "2" smd circle
			(at 0.40005 0)
			(size 0 0)
			(layers "F.Cu" "F.Mask" "F.Paste")
			(net "GND")
		)
	)
	(footprint ""
		(layer "F.Cu")
		(at 359.85831 -257.115564)
		(property "Reference" "PR132"
			(at 0 0 0)
			(layer "F.SilkS")
			(hide yes)
			(effects
				(font
					(size 1.27 1.27)
				)
			)
		)
		(property "Value" ""
			(at 0 0 0)
			(layer "F.Fab")
			(effects
				(font
					(size 1.27 1.27)
				)
			)
		)
		(duplicate_pad_numbers_are_jumpers no)
		(fp_line
			(start -0.7874 -0.4064)
			(end 0.7874 -0.4064)
			(stroke
				(width 0.1524)
				(type default)
			)
			(layer "F.SilkS")
		)
		(fp_line
			(start -0.7874 0.4064)
			(end -0.7874 -0.4064)
			(stroke
				(width 0.1524)
				(type default)
			)
			(layer "F.SilkS")
		)
		(fp_line
			(start 0.7874 -0.4064)
			(end 0.7874 0.4064)
			(stroke
				(width 0.1524)
				(type default)
			)
			(layer "F.SilkS")
		)
		(fp_line
			(start 0.7874 0.4064)
			(end -0.7874 0.4064)
			(stroke
				(width 0.1524)
				(type default)
			)
			(layer "F.SilkS")
		)
		(fp_line
			(start -0.67945 -0.305054)
			(end -0.12065 -0.305054)
			(stroke
				(width 0.1)
				(type default)
			)
			(layer "F.Fab")
		)
		(fp_line
			(start -0.67945 0.3048)
			(end -0.67945 -0.305054)
			(stroke
				(width 0.1)
				(type default)
			)
			(layer "F.Fab")
		)
		(fp_line
			(start -0.12065 -0.305054)
			(end -0.12065 -0.2794)
			(stroke
				(width 0.1)
				(type default)
			)
			(layer "F.Fab")
		)
		(fp_line
			(start -0.12065 -0.2794)
			(end 0.12065 -0.2794)
			(stroke
				(width 0.1)
				(type default)
			)
			(layer "F.Fab")
		)
		(fp_line
			(start -0.12065 0.2794)
			(end -0.12065 0.3048)
			(stroke
				(width 0.1)
				(type default)
			)
			(layer "F.Fab")
		)
		(fp_line
			(start -0.12065 0.3048)
			(end -0.67945 0.3048)
			(stroke
				(width 0.1)
				(type default)
			)
			(layer "F.Fab")
		)
		(fp_line
			(start 0.120396 0.2794)
			(end -0.12065 0.2794)
			(stroke
				(width 0.1)
				(type default)
			)
			(layer "F.Fab")
		)
		(fp_line
			(start 0.120396 0.3048)
			(end 0.120396 0.2794)
			(stroke
				(width 0.1)
				(type default)
			)
			(layer "F.Fab")
		)
		(fp_line
			(start 0.12065 -0.3048)
			(end 0.67945 -0.3048)
			(stroke
				(width 0.1)
				(type default)
			)
			(layer "F.Fab")
		)
		(fp_line
			(start 0.12065 -0.2794)
			(end 0.12065 -0.3048)
			(stroke
				(width 0.1)
				(type default)
			)
			(layer "F.Fab")
		)
		(fp_line
			(start 0.67945 -0.3048)
			(end 0.67945 0.3048)
			(stroke
				(width 0.1)
				(type default)
			)
			(layer "F.Fab")
		)
		(fp_line
			(start 0.67945 0.3048)
			(end 0.120396 0.3048)
			(stroke
				(width 0.1)
				(type default)
			)
			(layer "F.Fab")
		)
		(pad "1" smd circle
			(at -0.40005 0)
			(size 0 0)
			(layers "F.Cu" "F.Mask" "F.Paste")
			(net "P0V8_PEX2_PINALRT")
		)
		(pad "2" smd circle
			(at 0.40005 0)
			(size 0 0)
			(layers "F.Cu" "F.Mask" "F.Paste")
			(net "P3V3_AUX")
		)
	)
	(footprint ""
		(layer "F.Cu")
		(at 155.380436 -135.815324)
		(property "Reference" "C244"
			(at 0 0 0)
			(layer "F.SilkS")
			(hide yes)
			(effects
				(font
					(size 1.27 1.27)
				)
			)
		)
		(property "Value" ""
			(at 0 0 0)
			(layer "F.Fab")
			(effects
				(font
					(size 1.27 1.27)
				)
			)
		)
		(duplicate_pad_numbers_are_jumpers no)
		(fp_line
			(start -0.299974 -0.150114)
			(end 0.299974 -0.150114)
			(stroke
				(width 0.1)
				(type default)
			)
			(layer "F.Fab")
		)
		(fp_line
			(start -0.299974 0.150114)
			(end -0.299974 -0.150114)
			(stroke
				(width 0.1)
				(type default)
			)
			(layer "F.Fab")
		)
		(fp_line
			(start 0.299974 -0.150114)
			(end 0.299974 0.150114)
			(stroke
				(width 0.1)
				(type default)
			)
			(layer "F.Fab")
		)
		(fp_line
			(start 0.299974 0.150114)
			(end -0.299974 0.150114)
			(stroke
				(width 0.1)
				(type default)
			)
			(layer "F.Fab")
		)
		(pad "1" smd rect
			(at -0.2667 0)
			(size 0.3048 0.381)
			(layers "F.Cu" "F.Mask" "F.Paste")
			(net "P5E_PEX1_STN1_TX_DN<31>")
		)
		(pad "2" smd rect
			(at 0.2667 0)
			(size 0.3048 0.381)
			(layers "F.Cu" "F.Mask" "F.Paste")
			(net "P5E_PEX1_STN1_TX_C_DN<31>")
		)
	)
	(footprint ""
		(layer "F.Cu")
		(at 257.169412 -349.695008 180)
		(property "Reference" "R6654"
			(at 0 0 180)
			(layer "F.SilkS")
			(hide yes)
			(effects
				(font
					(size 1.27 1.27)
				)
			)
		)
		(property "Value" ""
			(at 0 0 180)
			(layer "F.Fab")
			(effects
				(font
					(size 1.27 1.27)
				)
			)
		)
		(duplicate_pad_numbers_are_jumpers no)
		(fp_line
			(start 0.7874 0.4064)
			(end -0.7874 0.4064)
			(stroke
				(width 0.1524)
				(type default)
			)
			(layer "F.SilkS")
		)
		(fp_line
			(start 0.7874 -0.4064)
			(end 0.7874 0.4064)
			(stroke
				(width 0.1524)
				(type default)
			)
			(layer "F.SilkS")
		)
		(fp_line
			(start -0.7874 0.4064)
			(end -0.7874 -0.4064)
			(stroke
				(width 0.1524)
				(type default)
			)
			(layer "F.SilkS")
		)
		(fp_line
			(start -0.7874 -0.4064)
			(end 0.7874 -0.4064)
			(stroke
				(width 0.1524)
				(type default)
			)
			(layer "F.SilkS")
		)
		(fp_line
			(start 0.67945 0.3048)
			(end 0.120396 0.3048)
			(stroke
				(width 0.1)
				(type default)
			)
			(layer "F.Fab")
		)
		(fp_line
			(start 0.67945 -0.3048)
			(end 0.67945 0.3048)
			(stroke
				(width 0.1)
				(type default)
			)
			(layer "F.Fab")
		)
		(fp_line
			(start 0.12065 -0.2794)
			(end 0.12065 -0.3048)
			(stroke
				(width 0.1)
				(type default)
			)
			(layer "F.Fab")
		)
		(fp_line
			(start 0.12065 -0.3048)
			(end 0.67945 -0.3048)
			(stroke
				(width 0.1)
				(type default)
			)
			(layer "F.Fab")
		)
		(fp_line
			(start 0.120396 0.3048)
			(end 0.120396 0.2794)
			(stroke
				(width 0.1)
				(type default)
			)
			(layer "F.Fab")
		)
		(fp_line
			(start 0.120396 0.2794)
			(end -0.12065 0.2794)
			(stroke
				(width 0.1)
				(type default)
			)
			(layer "F.Fab")
		)
		(fp_line
			(start -0.12065 0.3048)
			(end -0.67945 0.3048)
			(stroke
				(width 0.1)
				(type default)
			)
			(layer "F.Fab")
		)
		(fp_line
			(start -0.12065 0.2794)
			(end -0.12065 0.3048)
			(stroke
				(width 0.1)
				(type default)
			)
			(layer "F.Fab")
		)
		(fp_line
			(start -0.12065 -0.2794)
			(end 0.12065 -0.2794)
			(stroke
				(width 0.1)
				(type default)
			)
			(layer "F.Fab")
		)
		(fp_line
			(start -0.12065 -0.305054)
			(end -0.12065 -0.2794)
			(stroke
				(width 0.1)
				(type default)
			)
			(layer "F.Fab")
		)
		(fp_line
			(start -0.67945 0.3048)
			(end -0.67945 -0.305054)
			(stroke
				(width 0.1)
				(type default)
			)
			(layer "F.Fab")
		)
		(fp_line
			(start -0.67945 -0.305054)
			(end -0.12065 -0.305054)
			(stroke
				(width 0.1)
				(type default)
			)
			(layer "F.Fab")
		)
		(pad "1" smd circle
			(at -0.40005 0 180)
			(size 0 0)
			(layers "F.Cu" "F.Mask" "F.Paste")
			(net "A_HSC_LOW_GATE")
		)
		(pad "2" smd circle
			(at 0.40005 0 180)
			(size 0 0)
			(layers "F.Cu" "F.Mask" "F.Paste")
			(net "GND")
		)
	)
	(footprint ""
		(layer "F.Cu")
		(at 224.82683 -296.764202 -90)
		(property "Reference" "PL20"
			(at -3.59664 -7.405624 90)
			(unlocked yes)
			(layer "F.SilkS")
			(effects
				(font
					(size 0.7874 0.5842)
					(thickness 0.1524)
				)
				(justify left)
			)
		)
		(property "Value" ""
			(at 0 0 270)
			(layer "F.Fab")
			(effects
				(font
					(size 1.27 1.27)
				)
			)
		)
		(duplicate_pad_numbers_are_jumpers no)
		(fp_line
			(start -6.849872 6.450076)
			(end -6.849872 1.9812)
			(stroke
				(width 0.1524)
				(type default)
			)
			(layer "F.SilkS")
		)
		(fp_line
			(start 6.849872 6.450076)
			(end -6.849872 6.450076)
			(stroke
				(width 0.1524)
				(type default)
			)
			(layer "F.SilkS")
		)
		(fp_line
			(start 6.849872 1.9812)
			(end 6.849872 6.450076)
			(stroke
				(width 0.1524)
				(type default)
			)
			(layer "F.SilkS")
		)
		(fp_line
			(start -6.849872 -1.9812)
			(end -6.849872 -6.450076)
			(stroke
				(width 0.1524)
				(type default)
			)
			(layer "F.SilkS")
		)
		(fp_line
			(start -6.849872 -6.450076)
			(end 6.849872 -6.450076)
			(stroke
				(width 0.1524)
				(type default)
			)
			(layer "F.SilkS")
		)
		(fp_line
			(start 6.849872 -6.450076)
			(end 6.849872 -1.9812)
			(stroke
				(width 0.1524)
				(type default)
			)
			(layer "F.SilkS")
		)
		(fp_line
			(start -6.849872 6.450076)
			(end -6.849872 -6.450076)
			(stroke
				(width 0.1)
				(type default)
			)
			(layer "F.Fab")
		)
		(fp_line
			(start 6.849872 6.450076)
			(end -6.849872 6.450076)
			(stroke
				(width 0.1)
				(type default)
			)
			(layer "F.Fab")
		)
		(fp_line
			(start -6.849872 -6.450076)
			(end 6.849872 -6.450076)
			(stroke
				(width 0.1)
				(type default)
			)
			(layer "F.Fab")
		)
		(fp_line
			(start 6.849872 -6.450076)
			(end 6.849872 6.450076)
			(stroke
				(width 0.1)
				(type default)
			)
			(layer "F.Fab")
		)
		(pad "1" smd rect
			(at -5.407406 0 270)
			(size 2.9464 3.7084)
			(layers "F.Cu" "F.Mask" "F.Paste")
			(net "SW_P1V25_PEX1_PH")
		)
		(pad "2" smd rect
			(at 5.407406 0 270)
			(size 2.9464 3.7084)
			(layers "F.Cu" "F.Mask" "F.Paste")
			(net "P1V25_PEX1_R")
		)
	)
	(footprint ""
		(layer "F.Cu")
		(at 250.94946 -195.573396 90)
		(property "Reference" "R5645"
			(at 0 0 90)
			(layer "F.SilkS")
			(hide yes)
			(effects
				(font
					(size 1.27 1.27)
				)
			)
		)
		(property "Value" ""
			(at 0 0 90)
			(layer "F.Fab")
			(effects
				(font
					(size 1.27 1.27)
				)
			)
		)
		(duplicate_pad_numbers_are_jumpers no)
		(fp_line
			(start 0.7874 -0.4064)
			(end 0.7874 0.4064)
			(stroke
				(width 0.1524)
				(type default)
			)
			(layer "F.SilkS")
		)
		(fp_line
			(start -0.7874 -0.4064)
			(end 0.7874 -0.4064)
			(stroke
				(width 0.1524)
				(type default)
			)
			(layer "F.SilkS")
		)
		(fp_line
			(start 0.7874 0.4064)
			(end -0.7874 0.4064)
			(stroke
				(width 0.1524)
				(type default)
			)
			(layer "F.SilkS")
		)
		(fp_line
			(start -0.7874 0.4064)
			(end -0.7874 -0.4064)
			(stroke
				(width 0.1524)
				(type default)
			)
			(layer "F.SilkS")
		)
		(fp_line
			(start -0.12065 -0.305054)
			(end -0.12065 -0.2794)
			(stroke
				(width 0.1)
				(type default)
			)
			(layer "F.Fab")
		)
		(fp_line
			(start -0.67945 -0.305054)
			(end -0.12065 -0.305054)
			(stroke
				(width 0.1)
				(type default)
			)
			(layer "F.Fab")
		)
		(fp_line
			(start 0.67945 -0.3048)
			(end 0.67945 0.3048)
			(stroke
				(width 0.1)
				(type default)
			)
			(layer "F.Fab")
		)
		(fp_line
			(start 0.12065 -0.3048)
			(end 0.67945 -0.3048)
			(stroke
				(width 0.1)
				(type default)
			)
			(layer "F.Fab")
		)
		(fp_line
			(start 0.12065 -0.2794)
			(end 0.12065 -0.3048)
			(stroke
				(width 0.1)
				(type default)
			)
			(layer "F.Fab")
		)
		(fp_line
			(start -0.12065 -0.2794)
			(end 0.12065 -0.2794)
			(stroke
				(width 0.1)
				(type default)
			)
			(layer "F.Fab")
		)
		(fp_line
			(start 0.120396 0.2794)
			(end -0.12065 0.2794)
			(stroke
				(width 0.1)
				(type default)
			)
			(layer "F.Fab")
		)
		(fp_line
			(start -0.12065 0.2794)
			(end -0.12065 0.3048)
			(stroke
				(width 0.1)
				(type default)
			)
			(layer "F.Fab")
		)
		(fp_line
			(start 0.67945 0.3048)
			(end 0.120396 0.3048)
			(stroke
				(width 0.1)
				(type default)
			)
			(layer "F.Fab")
		)
		(fp_line
			(start 0.120396 0.3048)
			(end 0.120396 0.2794)
			(stroke
				(width 0.1)
				(type default)
			)
			(layer "F.Fab")
		)
		(fp_line
			(start -0.12065 0.3048)
			(end -0.67945 0.3048)
			(stroke
				(width 0.1)
				(type default)
			)
			(layer "F.Fab")
		)
		(fp_line
			(start -0.67945 0.3048)
			(end -0.67945 -0.305054)
			(stroke
				(width 0.1)
				(type default)
			)
			(layer "F.Fab")
		)
		(pad "1" smd circle
			(at -0.40005 0 90)
			(size 0 0)
			(layers "F.Cu" "F.Mask" "F.Paste")
			(net "JTAG_BIC_TCK_R")
		)
		(pad "2" smd circle
			(at 0.40005 0 90)
			(size 0 0)
			(layers "F.Cu" "F.Mask" "F.Paste")
			(net "JTAG_BIC_TCK_R1")
		)
	)
	(footprint ""
		(layer "F.Cu")
		(at 226.819714 -173.838362 180)
		(property "Reference" "D23"
			(at 1.826514 -1.424432 0)
			(unlocked yes)
			(layer "F.SilkS")
			(effects
				(font
					(size 0.7874 0.5842)
					(thickness 0.1524)
				)
				(justify left)
			)
		)
		(property "Value" ""
			(at 0 0 180)
			(layer "F.Fab")
			(effects
				(font
					(size 1.27 1.27)
				)
			)
		)
		(duplicate_pad_numbers_are_jumpers no)
		(fp_line
			(start 2.032 0.7112)
			(end -1.651 0.7112)
			(stroke
				(width 0.1524)
				(type default)
			)
			(layer "F.SilkS")
		)
		(fp_line
			(start 2.032 -0.7112)
			(end 2.032 0.7112)
			(stroke
				(width 0.1524)
				(type default)
			)
			(layer "F.SilkS")
		)
		(fp_line
			(start 1.905 -0.6858)
			(end 1.905 0.6858)
			(stroke
				(width 0.1524)
				(type default)
			)
			(layer "F.SilkS")
		)
		(fp_line
			(start 1.778 0.6858)
			(end 1.778 -0.6858)
			(stroke
				(width 0.1524)
				(type default)
			)
			(layer "F.SilkS")
		)
		(fp_line
			(start 1.651 -0.6858)
			(end 1.651 0.6858)
			(stroke
				(width 0.1524)
				(type default)
			)
			(layer "F.SilkS")
		)
		(fp_line
			(start 0.299974 -0.500126)
			(end 0.299974 0.500126)
			(stroke
				(width 0.1524)
				(type default)
			)
			(layer "F.SilkS")
		)
		(fp_line
			(start 0.199898 0)
			(end -0.299974 -0.500126)
			(stroke
				(width 0.1524)
				(type default)
			)
			(layer "F.SilkS")
		)
		(fp_line
			(start -0.299974 0.500126)
			(end 0.199898 0)
			(stroke
				(width 0.1524)
				(type default)
			)
			(layer "F.SilkS")
		)
		(fp_line
			(start -0.299974 -0.500126)
			(end -0.299974 0.500126)
			(stroke
				(width 0.1524)
				(type default)
			)
			(layer "F.SilkS")
		)
		(fp_line
			(start -1.651 0.7112)
			(end -1.651 -0.7112)
			(stroke
				(width 0.1524)
				(type default)
			)
			(layer "F.SilkS")
		)
		(fp_line
			(start -1.651 -0.7112)
			(end 2.032 -0.7112)
			(stroke
				(width 0.1524)
				(type default)
			)
			(layer "F.SilkS")
		)
		(fp_line
			(start 1.35001 0.175006)
			(end 0.899922 0.175006)
			(stroke
				(width 0.1)
				(type default)
			)
			(layer "F.Fab")
		)
		(fp_line
			(start 1.35001 -0.225044)
			(end 1.35001 0.175006)
			(stroke
				(width 0.1)
				(type default)
			)
			(layer "F.Fab")
		)
		(fp_line
			(start 0.899922 0.700024)
			(end -0.899922 0.700024)
			(stroke
				(width 0.1)
				(type default)
			)
			(layer "F.Fab")
		)
		(fp_line
			(start 0.899922 0.175006)
			(end 0.899922 0.700024)
			(stroke
				(width 0.1)
				(type default)
			)
			(layer "F.Fab")
		)
		(fp_line
			(start 0.899922 -0.225044)
			(end 1.35001 -0.225044)
			(stroke
				(width 0.1)
				(type default)
			)
			(layer "F.Fab")
		)
		(fp_line
			(start 0.899922 -0.700024)
			(end 0.899922 -0.225044)
			(stroke
				(width 0.1)
				(type default)
			)
			(layer "F.Fab")
		)
		(fp_line
			(start 0.299974 -0.500126)
			(end 0.299974 0.500126)
			(stroke
				(width 0.1)
				(type default)
			)
			(layer "F.Fab")
		)
		(fp_line
			(start 0.199898 0)
			(end -0.299974 -0.500126)
			(stroke
				(width 0.1)
				(type default)
			)
			(layer "F.Fab")
		)
		(fp_line
			(start -0.299974 0.500126)
			(end 0.199898 0)
			(stroke
				(width 0.1)
				(type default)
			)
			(layer "F.Fab")
		)
		(fp_line
			(start -0.299974 -0.500126)
			(end -0.299974 0.500126)
			(stroke
				(width 0.1)
				(type default)
			)
			(layer "F.Fab")
		)
		(fp_line
			(start -0.899922 0.700024)
			(end -0.899922 0.175006)
			(stroke
				(width 0.1)
				(type default)
			)
			(layer "F.Fab")
		)
		(fp_line
			(start -0.899922 0.175006)
			(end -1.35001 0.175006)
			(stroke
				(width 0.1)
				(type default)
			)
			(layer "F.Fab")
		)
		(fp_line
			(start -0.899922 -0.225044)
			(end -0.899922 -0.700024)
			(stroke
				(width 0.1)
				(type default)
			)
			(layer "F.Fab")
		)
		(fp_line
			(start -0.899922 -0.700024)
			(end 0.899922 -0.700024)
			(stroke
				(width 0.1)
				(type default)
			)
			(layer "F.Fab")
		)
		(fp_line
			(start -1.35001 0.175006)
			(end -1.35001 -0.225044)
			(stroke
				(width 0.1)
				(type default)
			)
			(layer "F.Fab")
		)
		(fp_line
			(start -1.35001 -0.225044)
			(end -0.899922 -0.225044)
			(stroke
				(width 0.1)
				(type default)
			)
			(layer "F.Fab")
		)
		(fp_text user "-"
			(at 2.261616 -2.594102 180)
			(unlocked yes)
			(layer "F.SilkS")
			(effects
				(font
					(size 1.905 1.4224)
					(thickness 0.1524)
				)
				(justify left)
			)
		)
		(fp_text user "+"
			(at -2.794 -0.19685 180)
			(unlocked yes)
			(layer "F.SilkS")
			(effects
				(font
					(size 1.905 1.4224)
					(thickness 0.1524)
				)
				(justify left)
			)
		)
		(fp_text user "-"
			(at 1.8288 -0.24765 180)
			(unlocked yes)
			(layer "F.Fab")
			(effects
				(font
					(size 1.905 1.4224)
					(thickness 0.1524)
				)
				(justify left)
			)
		)
		(fp_text user "+"
			(at -2.794 -0.19685 180)
			(unlocked yes)
			(layer "F.Fab")
			(effects
				(font
					(size 1.905 1.4224)
					(thickness 0.1524)
				)
				(justify left)
			)
		)
		(pad "1" smd rect
			(at -1.0922 0)
			(size 0.8128 0.8636)
			(layers "F.Cu" "F.Mask" "F.Paste")
			(net "ADM1085_ENOUT")
		)
		(pad "2" smd rect
			(at 1.0922 0 180)
			(size 0.8128 0.8636)
			(layers "F.Cu" "F.Mask" "F.Paste")
			(net "ADM1085_CEXT")
		)
	)
	(footprint ""
		(layer "F.Cu")
		(at 374.567196 -57.332626)
		(property "Reference" "R6829"
			(at 0 0 0)
			(layer "F.SilkS")
			(hide yes)
			(effects
				(font
					(size 1.27 1.27)
				)
			)
		)
		(property "Value" ""
			(at 0 0 0)
			(layer "F.Fab")
			(effects
				(font
					(size 1.27 1.27)
				)
			)
		)
		(duplicate_pad_numbers_are_jumpers no)
		(fp_line
			(start -0.7874 -0.4064)
			(end 0.7874 -0.4064)
			(stroke
				(width 0.1524)
				(type default)
			)
			(layer "F.SilkS")
		)
		(fp_line
			(start -0.7874 0.4064)
			(end -0.7874 -0.4064)
			(stroke
				(width 0.1524)
				(type default)
			)
			(layer "F.SilkS")
		)
		(fp_line
			(start 0.7874 -0.4064)
			(end 0.7874 0.4064)
			(stroke
				(width 0.1524)
				(type default)
			)
			(layer "F.SilkS")
		)
		(fp_line
			(start 0.7874 0.4064)
			(end -0.7874 0.4064)
			(stroke
				(width 0.1524)
				(type default)
			)
			(layer "F.SilkS")
		)
		(fp_line
			(start -0.67945 -0.305054)
			(end -0.12065 -0.305054)
			(stroke
				(width 0.1)
				(type default)
			)
			(layer "F.Fab")
		)
		(fp_line
			(start -0.67945 0.3048)
			(end -0.67945 -0.305054)
			(stroke
				(width 0.1)
				(type default)
			)
			(layer "F.Fab")
		)
		(fp_line
			(start -0.12065 -0.305054)
			(end -0.12065 -0.2794)
			(stroke
				(width 0.1)
				(type default)
			)
			(layer "F.Fab")
		)
		(fp_line
			(start -0.12065 -0.2794)
			(end 0.12065 -0.2794)
			(stroke
				(width 0.1)
				(type default)
			)
			(layer "F.Fab")
		)
		(fp_line
			(start -0.12065 0.2794)
			(end -0.12065 0.3048)
			(stroke
				(width 0.1)
				(type default)
			)
			(layer "F.Fab")
		)
		(fp_line
			(start -0.12065 0.3048)
			(end -0.67945 0.3048)
			(stroke
				(width 0.1)
				(type default)
			)
			(layer "F.Fab")
		)
		(fp_line
			(start 0.120396 0.2794)
			(end -0.12065 0.2794)
			(stroke
				(width 0.1)
				(type default)
			)
			(layer "F.Fab")
		)
		(fp_line
			(start 0.120396 0.3048)
			(end 0.120396 0.2794)
			(stroke
				(width 0.1)
				(type default)
			)
			(layer "F.Fab")
		)
		(fp_line
			(start 0.12065 -0.3048)
			(end 0.67945 -0.3048)
			(stroke
				(width 0.1)
				(type default)
			)
			(layer "F.Fab")
		)
		(fp_line
			(start 0.12065 -0.2794)
			(end 0.12065 -0.3048)
			(stroke
				(width 0.1)
				(type default)
			)
			(layer "F.Fab")
		)
		(fp_line
			(start 0.67945 -0.3048)
			(end 0.67945 0.3048)
			(stroke
				(width 0.1)
				(type default)
			)
			(layer "F.Fab")
		)
		(fp_line
			(start 0.67945 0.3048)
			(end 0.120396 0.3048)
			(stroke
				(width 0.1)
				(type default)
			)
			(layer "F.Fab")
		)
		(pad "1" smd circle
			(at -0.40005 0)
			(size 0 0)
			(layers "F.Cu" "F.Mask" "F.Paste")
			(net "SSD12_PWR_EN_R")
		)
		(pad "2" smd circle
			(at 0.40005 0)
			(size 0 0)
			(layers "F.Cu" "F.Mask" "F.Paste")
			(net "GND")
		)
	)
	(footprint ""
		(layer "F.Cu")
		(at 302.126396 -25.432004 -90)
		(property "Reference" "C975"
			(at 0 0 270)
			(layer "F.SilkS")
			(hide yes)
			(effects
				(font
					(size 1.27 1.27)
				)
			)
		)
		(property "Value" ""
			(at 0 0 270)
			(layer "F.Fab")
			(effects
				(font
					(size 1.27 1.27)
				)
			)
		)
		(duplicate_pad_numbers_are_jumpers no)
		(fp_line
			(start -0.7874 0.4064)
			(end -0.7874 -0.4064)
			(stroke
				(width 0.1524)
				(type default)
			)
			(layer "F.SilkS")
		)
		(fp_line
			(start 0.7874 0.4064)
			(end -0.7874 0.4064)
			(stroke
				(width 0.1524)
				(type default)
			)
			(layer "F.SilkS")
		)
		(fp_line
			(start -0.7874 -0.4064)
			(end 0.7874 -0.4064)
			(stroke
				(width 0.1524)
				(type default)
			)
			(layer "F.SilkS")
		)
		(fp_line
			(start 0.7874 -0.4064)
			(end 0.7874 0.4064)
			(stroke
				(width 0.1524)
				(type default)
			)
			(layer "F.SilkS")
		)
		(fp_line
			(start -0.67945 0.3048)
			(end -0.67945 -0.305054)
			(stroke
				(width 0.1)
				(type default)
			)
			(layer "F.Fab")
		)
		(fp_line
			(start -0.12065 0.3048)
			(end -0.67945 0.3048)
			(stroke
				(width 0.1)
				(type default)
			)
			(layer "F.Fab")
		)
		(fp_line
			(start 0.120396 0.3048)
			(end 0.120396 0.2794)
			(stroke
				(width 0.1)
				(type default)
			)
			(layer "F.Fab")
		)
		(fp_line
			(start 0.67945 0.3048)
			(end 0.120396 0.3048)
			(stroke
				(width 0.1)
				(type default)
			)
			(layer "F.Fab")
		)
		(fp_line
			(start -0.12065 0.2794)
			(end -0.12065 0.3048)
			(stroke
				(width 0.1)
				(type default)
			)
			(layer "F.Fab")
		)
		(fp_line
			(start 0.120396 0.2794)
			(end -0.12065 0.2794)
			(stroke
				(width 0.1)
				(type default)
			)
			(layer "F.Fab")
		)
		(fp_line
			(start -0.12065 -0.2794)
			(end 0.12065 -0.2794)
			(stroke
				(width 0.1)
				(type default)
			)
			(layer "F.Fab")
		)
		(fp_line
			(start 0.12065 -0.2794)
			(end 0.12065 -0.3048)
			(stroke
				(width 0.1)
				(type default)
			)
			(layer "F.Fab")
		)
		(fp_line
			(start 0.12065 -0.3048)
			(end 0.67945 -0.3048)
			(stroke
				(width 0.1)
				(type default)
			)
			(layer "F.Fab")
		)
		(fp_line
			(start 0.67945 -0.3048)
			(end 0.67945 0.3048)
			(stroke
				(width 0.1)
				(type default)
			)
			(layer "F.Fab")
		)
		(fp_line
			(start -0.67945 -0.305054)
			(end -0.12065 -0.305054)
			(stroke
				(width 0.1)
				(type default)
			)
			(layer "F.Fab")
		)
		(fp_line
			(start -0.12065 -0.305054)
			(end -0.12065 -0.2794)
			(stroke
				(width 0.1)
				(type default)
			)
			(layer "F.Fab")
		)
		(pad "1" smd circle
			(at -0.40005 0 270)
			(size 0 0)
			(layers "F.Cu" "F.Mask" "F.Paste")
			(net "GND")
		)
		(pad "2" smd circle
			(at 0.40005 0 270)
			(size 0 0)
			(layers "F.Cu" "F.Mask" "F.Paste")
			(net "P3V3_SSD10")
		)
	)
	(footprint ""
		(layer "F.Cu")
		(at 208.45272 -311.197244 135)
		(property "Reference" "R1313"
			(at 0 0 135)
			(layer "F.SilkS")
			(hide yes)
			(effects
				(font
					(size 1.27 1.27)
				)
			)
		)
		(property "Value" ""
			(at 0 0 135)
			(layer "F.Fab")
			(effects
				(font
					(size 1.27 1.27)
				)
			)
		)
		(duplicate_pad_numbers_are_jumpers no)
		(fp_line
			(start 0.787389 -0.406267)
			(end 0.787389 0.406267)
			(stroke
				(width 0.1524)
				(type default)
			)
			(layer "F.SilkS")
		)
		(fp_line
			(start 0.787389 0.406267)
			(end -0.787389 0.406267)
			(stroke
				(width 0.1524)
				(type default)
			)
			(layer "F.SilkS")
		)
		(fp_line
			(start -0.787389 -0.406267)
			(end 0.787389 -0.406267)
			(stroke
				(width 0.1524)
				(type default)
			)
			(layer "F.SilkS")
		)
		(fp_line
			(start -0.787389 0.406267)
			(end -0.787389 -0.406267)
			(stroke
				(width 0.1524)
				(type default)
			)
			(layer "F.SilkS")
		)
		(fp_line
			(start 0.679446 -0.30479)
			(end 0.679446 0.30479)
			(stroke
				(width 0.1)
				(type default)
			)
			(layer "F.Fab")
		)
		(fp_line
			(start 0.120515 -0.30479)
			(end 0.679446 -0.30479)
			(stroke
				(width 0.1)
				(type default)
			)
			(layer "F.Fab")
		)
		(fp_line
			(start 0.120695 -0.279466)
			(end 0.120515 -0.30479)
			(stroke
				(width 0.1)
				(type default)
			)
			(layer "F.Fab")
		)
		(fp_line
			(start 0.679446 0.30479)
			(end 0.120515 0.30479)
			(stroke
				(width 0.1)
				(type default)
			)
			(layer "F.Fab")
		)
		(fp_line
			(start -0.120695 -0.304969)
			(end -0.120695 -0.279466)
			(stroke
				(width 0.1)
				(type default)
			)
			(layer "F.Fab")
		)
		(fp_line
			(start -0.120695 -0.279466)
			(end 0.120695 -0.279466)
			(stroke
				(width 0.1)
				(type default)
			)
			(layer "F.Fab")
		)
		(fp_line
			(start 0.120335 0.279466)
			(end -0.120695 0.279466)
			(stroke
				(width 0.1)
				(type default)
			)
			(layer "F.Fab")
		)
		(fp_line
			(start 0.120515 0.30479)
			(end 0.120335 0.279466)
			(stroke
				(width 0.1)
				(type default)
			)
			(layer "F.Fab")
		)
		(fp_line
			(start -0.679446 -0.305149)
			(end -0.120695 -0.304969)
			(stroke
				(width 0.1)
				(type default)
			)
			(layer "F.Fab")
		)
		(fp_line
			(start -0.120695 0.279466)
			(end -0.120515 0.30479)
			(stroke
				(width 0.1)
				(type default)
			)
			(layer "F.Fab")
		)
		(fp_line
			(start -0.120515 0.30479)
			(end -0.679446 0.30479)
			(stroke
				(width 0.1)
				(type default)
			)
			(layer "F.Fab")
		)
		(fp_line
			(start -0.679446 0.30479)
			(end -0.679446 -0.305149)
			(stroke
				(width 0.1)
				(type default)
			)
			(layer "F.Fab")
		)
		(pad "1" smd circle
			(at -0.40005 0 135)
			(size 0 0)
			(layers "F.Cu" "F.Mask" "F.Paste")
			(net "GND")
		)
		(pad "2" smd circle
			(at 0.40005 0 135)
			(size 0 0)
			(layers "F.Cu" "F.Mask" "F.Paste")
			(net "PEX1_SPARE5")
		)
	)
	(footprint ""
		(layer "F.Cu")
		(at 38.7604 -117.7544 180)
		(property "Reference" "R5"
			(at 0 0 180)
			(layer "F.SilkS")
			(hide yes)
			(effects
				(font
					(size 1.27 1.27)
				)
			)
		)
		(property "Value" ""
			(at 0 0 180)
			(layer "F.Fab")
			(effects
				(font
					(size 1.27 1.27)
				)
			)
		)
		(duplicate_pad_numbers_are_jumpers no)
		(fp_line
			(start 0.7874 0.4064)
			(end -0.7874 0.4064)
			(stroke
				(width 0.1524)
				(type default)
			)
			(layer "F.SilkS")
		)
		(fp_line
			(start 0.7874 -0.4064)
			(end 0.7874 0.4064)
			(stroke
				(width 0.1524)
				(type default)
			)
			(layer "F.SilkS")
		)
		(fp_line
			(start -0.7874 0.4064)
			(end -0.7874 -0.4064)
			(stroke
				(width 0.1524)
				(type default)
			)
			(layer "F.SilkS")
		)
		(fp_line
			(start -0.7874 -0.4064)
			(end 0.7874 -0.4064)
			(stroke
				(width 0.1524)
				(type default)
			)
			(layer "F.SilkS")
		)
		(fp_line
			(start 0.67945 0.3048)
			(end 0.120396 0.3048)
			(stroke
				(width 0.1)
				(type default)
			)
			(layer "F.Fab")
		)
		(fp_line
			(start 0.67945 -0.3048)
			(end 0.67945 0.3048)
			(stroke
				(width 0.1)
				(type default)
			)
			(layer "F.Fab")
		)
		(fp_line
			(start 0.12065 -0.2794)
			(end 0.12065 -0.3048)
			(stroke
				(width 0.1)
				(type default)
			)
			(layer "F.Fab")
		)
		(fp_line
			(start 0.12065 -0.3048)
			(end 0.67945 -0.3048)
			(stroke
				(width 0.1)
				(type default)
			)
			(layer "F.Fab")
		)
		(fp_line
			(start 0.120396 0.3048)
			(end 0.120396 0.2794)
			(stroke
				(width 0.1)
				(type default)
			)
			(layer "F.Fab")
		)
		(fp_line
			(start 0.120396 0.2794)
			(end -0.12065 0.2794)
			(stroke
				(width 0.1)
				(type default)
			)
			(layer "F.Fab")
		)
		(fp_line
			(start -0.12065 0.3048)
			(end -0.67945 0.3048)
			(stroke
				(width 0.1)
				(type default)
			)
			(layer "F.Fab")
		)
		(fp_line
			(start -0.12065 0.2794)
			(end -0.12065 0.3048)
			(stroke
				(width 0.1)
				(type default)
			)
			(layer "F.Fab")
		)
		(fp_line
			(start -0.12065 -0.2794)
			(end 0.12065 -0.2794)
			(stroke
				(width 0.1)
				(type default)
			)
			(layer "F.Fab")
		)
		(fp_line
			(start -0.12065 -0.305054)
			(end -0.12065 -0.2794)
			(stroke
				(width 0.1)
				(type default)
			)
			(layer "F.Fab")
		)
		(fp_line
			(start -0.67945 0.3048)
			(end -0.67945 -0.305054)
			(stroke
				(width 0.1)
				(type default)
			)
			(layer "F.Fab")
		)
		(fp_line
			(start -0.67945 -0.305054)
			(end -0.12065 -0.305054)
			(stroke
				(width 0.1)
				(type default)
			)
			(layer "F.Fab")
		)
		(pad "1" smd circle
			(at -0.40005 0 180)
			(size 0 0)
			(layers "F.Cu" "F.Mask" "F.Paste")
			(net "PRSNTB0_NIC0_N")
		)
		(pad "2" smd circle
			(at 0.40005 0 180)
			(size 0 0)
			(layers "F.Cu" "F.Mask" "F.Paste")
			(net "P3V3_AUX")
		)
	)
	(footprint ""
		(layer "F.Cu")
		(at 234.541822 -27.006296 -90)
		(property "Reference" "PR7116"
			(at 0 0 270)
			(layer "F.SilkS")
			(hide yes)
			(effects
				(font
					(size 1.27 1.27)
				)
			)
		)
		(property "Value" ""
			(at 0 0 270)
			(layer "F.Fab")
			(effects
				(font
					(size 1.27 1.27)
				)
			)
		)
		(duplicate_pad_numbers_are_jumpers no)
		(fp_line
			(start -0.7874 0.4064)
			(end -0.7874 -0.4064)
			(stroke
				(width 0.1524)
				(type default)
			)
			(layer "F.SilkS")
		)
		(fp_line
			(start 0.7874 0.4064)
			(end -0.7874 0.4064)
			(stroke
				(width 0.1524)
				(type default)
			)
			(layer "F.SilkS")
		)
		(fp_line
			(start -0.7874 -0.4064)
			(end 0.7874 -0.4064)
			(stroke
				(width 0.1524)
				(type default)
			)
			(layer "F.SilkS")
		)
		(fp_line
			(start 0.7874 -0.4064)
			(end 0.7874 0.4064)
			(stroke
				(width 0.1524)
				(type default)
			)
			(layer "F.SilkS")
		)
		(fp_line
			(start -0.67945 0.3048)
			(end -0.67945 -0.305054)
			(stroke
				(width 0.1)
				(type default)
			)
			(layer "F.Fab")
		)
		(fp_line
			(start -0.12065 0.3048)
			(end -0.67945 0.3048)
			(stroke
				(width 0.1)
				(type default)
			)
			(layer "F.Fab")
		)
		(fp_line
			(start 0.120396 0.3048)
			(end 0.120396 0.2794)
			(stroke
				(width 0.1)
				(type default)
			)
			(layer "F.Fab")
		)
		(fp_line
			(start 0.67945 0.3048)
			(end 0.120396 0.3048)
			(stroke
				(width 0.1)
				(type default)
			)
			(layer "F.Fab")
		)
		(fp_line
			(start -0.12065 0.2794)
			(end -0.12065 0.3048)
			(stroke
				(width 0.1)
				(type default)
			)
			(layer "F.Fab")
		)
		(fp_line
			(start 0.120396 0.2794)
			(end -0.12065 0.2794)
			(stroke
				(width 0.1)
				(type default)
			)
			(layer "F.Fab")
		)
		(fp_line
			(start -0.12065 -0.2794)
			(end 0.12065 -0.2794)
			(stroke
				(width 0.1)
				(type default)
			)
			(layer "F.Fab")
		)
		(fp_line
			(start 0.12065 -0.2794)
			(end 0.12065 -0.3048)
			(stroke
				(width 0.1)
				(type default)
			)
			(layer "F.Fab")
		)
		(fp_line
			(start 0.12065 -0.3048)
			(end 0.67945 -0.3048)
			(stroke
				(width 0.1)
				(type default)
			)
			(layer "F.Fab")
		)
		(fp_line
			(start 0.67945 -0.3048)
			(end 0.67945 0.3048)
			(stroke
				(width 0.1)
				(type default)
			)
			(layer "F.Fab")
		)
		(fp_line
			(start -0.67945 -0.305054)
			(end -0.12065 -0.305054)
			(stroke
				(width 0.1)
				(type default)
			)
			(layer "F.Fab")
		)
		(fp_line
			(start -0.12065 -0.305054)
			(end -0.12065 -0.2794)
			(stroke
				(width 0.1)
				(type default)
			)
			(layer "F.Fab")
		)
		(pad "1" smd circle
			(at -0.40005 0 270)
			(size 0 0)
			(layers "F.Cu" "F.Mask" "F.Paste")
			(net "P3V3_SSD8_CO_ILIMIT")
		)
		(pad "2" smd circle
			(at 0.40005 0 270)
			(size 0 0)
			(layers "F.Cu" "F.Mask" "F.Paste")
			(net "GND")
		)
	)
	(footprint ""
		(layer "F.Cu")
		(at 115.356386 -89.384378 180)
		(property "Reference" "R1149"
			(at 0 0 180)
			(layer "F.SilkS")
			(hide yes)
			(effects
				(font
					(size 1.27 1.27)
				)
			)
		)
		(property "Value" ""
			(at 0 0 180)
			(layer "F.Fab")
			(effects
				(font
					(size 1.27 1.27)
				)
			)
		)
		(duplicate_pad_numbers_are_jumpers no)
		(fp_line
			(start 0.7874 0.4064)
			(end -0.7874 0.4064)
			(stroke
				(width 0.1524)
				(type default)
			)
			(layer "F.SilkS")
		)
		(fp_line
			(start 0.67945 0.3048)
			(end 0.120396 0.3048)
			(stroke
				(width 0.1)
				(type default)
			)
			(layer "F.Fab")
		)
		(fp_line
			(start 0.67945 -0.3048)
			(end 0.67945 0.3048)
			(stroke
				(width 0.1)
				(type default)
			)
			(layer "F.Fab")
		)
		(fp_line
			(start 0.12065 -0.2794)
			(end 0.12065 -0.3048)
			(stroke
				(width 0.1)
				(type default)
			)
			(layer "F.Fab")
		)
		(fp_line
			(start 0.12065 -0.3048)
			(end 0.67945 -0.3048)
			(stroke
				(width 0.1)
				(type default)
			)
			(layer "F.Fab")
		)
		(fp_line
			(start 0.120396 0.3048)
			(end 0.120396 0.2794)
			(stroke
				(width 0.1)
				(type default)
			)
			(layer "F.Fab")
		)
		(fp_line
			(start 0.120396 0.2794)
			(end -0.12065 0.2794)
			(stroke
				(width 0.1)
				(type default)
			)
			(layer "F.Fab")
		)
		(fp_line
			(start -0.12065 0.3048)
			(end -0.67945 0.3048)
			(stroke
				(width 0.1)
				(type default)
			)
			(layer "F.Fab")
		)
		(fp_line
			(start -0.12065 0.2794)
			(end -0.12065 0.3048)
			(stroke
				(width 0.1)
				(type default)
			)
			(layer "F.Fab")
		)
		(fp_line
			(start -0.12065 -0.2794)
			(end 0.12065 -0.2794)
			(stroke
				(width 0.1)
				(type default)
			)
			(layer "F.Fab")
		)
		(fp_line
			(start -0.12065 -0.305054)
			(end -0.12065 -0.2794)
			(stroke
				(width 0.1)
				(type default)
			)
			(layer "F.Fab")
		)
		(fp_line
			(start -0.67945 0.3048)
			(end -0.67945 -0.305054)
			(stroke
				(width 0.1)
				(type default)
			)
			(layer "F.Fab")
		)
		(fp_line
			(start -0.67945 -0.305054)
			(end -0.12065 -0.305054)
			(stroke
				(width 0.1)
				(type default)
			)
			(layer "F.Fab")
		)
		(pad "1" smd circle
			(at -0.40005 0 180)
			(size 0 0)
			(layers "F.Cu" "F.Mask" "F.Paste")
			(net "CLK_100M_DB800ZL_SSD6_R_DN")
		)
		(pad "2" smd circle
			(at 0.40005 0 180)
			(size 0 0)
			(layers "F.Cu" "F.Mask" "F.Paste")
			(net "CLK_100M_DB800ZL_SSD6_DN")
		)
	)
	(footprint ""
		(layer "F.Cu")
		(at 249.204734 -215.543638 180)
		(property "Reference" "C2851"
			(at 0 0 180)
			(layer "F.SilkS")
			(hide yes)
			(effects
				(font
					(size 1.27 1.27)
				)
			)
		)
		(property "Value" ""
			(at 0 0 180)
			(layer "F.Fab")
			(effects
				(font
					(size 1.27 1.27)
				)
			)
		)
		(duplicate_pad_numbers_are_jumpers no)
		(fp_line
			(start 0.7874 0.4064)
			(end -0.7874 0.4064)
			(stroke
				(width 0.1524)
				(type default)
			)
			(layer "F.SilkS")
		)
		(fp_line
			(start 0.7874 -0.4064)
			(end 0.7874 0.4064)
			(stroke
				(width 0.1524)
				(type default)
			)
			(layer "F.SilkS")
		)
		(fp_line
			(start -0.7874 0.4064)
			(end -0.7874 -0.4064)
			(stroke
				(width 0.1524)
				(type default)
			)
			(layer "F.SilkS")
		)
		(fp_line
			(start -0.7874 -0.4064)
			(end 0.7874 -0.4064)
			(stroke
				(width 0.1524)
				(type default)
			)
			(layer "F.SilkS")
		)
		(fp_line
			(start 0.67945 0.3048)
			(end 0.120396 0.3048)
			(stroke
				(width 0.1)
				(type default)
			)
			(layer "F.Fab")
		)
		(fp_line
			(start 0.67945 -0.3048)
			(end 0.67945 0.3048)
			(stroke
				(width 0.1)
				(type default)
			)
			(layer "F.Fab")
		)
		(fp_line
			(start 0.12065 -0.2794)
			(end 0.12065 -0.3048)
			(stroke
				(width 0.1)
				(type default)
			)
			(layer "F.Fab")
		)
		(fp_line
			(start 0.12065 -0.3048)
			(end 0.67945 -0.3048)
			(stroke
				(width 0.1)
				(type default)
			)
			(layer "F.Fab")
		)
		(fp_line
			(start 0.120396 0.3048)
			(end 0.120396 0.2794)
			(stroke
				(width 0.1)
				(type default)
			)
			(layer "F.Fab")
		)
		(fp_line
			(start 0.120396 0.2794)
			(end -0.12065 0.2794)
			(stroke
				(width 0.1)
				(type default)
			)
			(layer "F.Fab")
		)
		(fp_line
			(start -0.12065 0.3048)
			(end -0.67945 0.3048)
			(stroke
				(width 0.1)
				(type default)
			)
			(layer "F.Fab")
		)
		(fp_line
			(start -0.12065 0.2794)
			(end -0.12065 0.3048)
			(stroke
				(width 0.1)
				(type default)
			)
			(layer "F.Fab")
		)
		(fp_line
			(start -0.12065 -0.2794)
			(end 0.12065 -0.2794)
			(stroke
				(width 0.1)
				(type default)
			)
			(layer "F.Fab")
		)
		(fp_line
			(start -0.12065 -0.305054)
			(end -0.12065 -0.2794)
			(stroke
				(width 0.1)
				(type default)
			)
			(layer "F.Fab")
		)
		(fp_line
			(start -0.67945 0.3048)
			(end -0.67945 -0.305054)
			(stroke
				(width 0.1)
				(type default)
			)
			(layer "F.Fab")
		)
		(fp_line
			(start -0.67945 -0.305054)
			(end -0.12065 -0.305054)
			(stroke
				(width 0.1)
				(type default)
			)
			(layer "F.Fab")
		)
		(pad "1" smd circle
			(at -0.40005 0 180)
			(size 0 0)
			(layers "F.Cu" "F.Mask" "F.Paste")
			(net "P1V2_AUX")
		)
		(pad "2" smd circle
			(at 0.40005 0 180)
			(size 0 0)
			(layers "F.Cu" "F.Mask" "F.Paste")
			(net "GND")
		)
	)
	(footprint ""
		(layer "F.Cu")
		(at 239.703864 -218.29776 90)
		(property "Reference" "C3615"
			(at 0 0 90)
			(layer "F.SilkS")
			(hide yes)
			(effects
				(font
					(size 1.27 1.27)
				)
			)
		)
		(property "Value" ""
			(at 0 0 90)
			(layer "F.Fab")
			(effects
				(font
					(size 1.27 1.27)
				)
			)
		)
		(duplicate_pad_numbers_are_jumpers no)
		(fp_line
			(start 0.69215 -0.2921)
			(end 0.69215 0.2921)
			(stroke
				(width 0.1524)
				(type default)
			)
			(layer "F.SilkS")
		)
		(fp_line
			(start -0.69215 -0.2921)
			(end 0.69215 -0.2921)
			(stroke
				(width 0.1524)
				(type default)
			)
			(layer "F.SilkS")
		)
		(fp_line
			(start 0.69215 0.2921)
			(end -0.69215 0.2921)
			(stroke
				(width 0.1524)
				(type default)
			)
			(layer "F.SilkS")
		)
		(fp_line
			(start -0.69215 0.2921)
			(end -0.69215 -0.2921)
			(stroke
				(width 0.1524)
				(type default)
			)
			(layer "F.SilkS")
		)
		(fp_line
			(start 0.51435 -0.2794)
			(end 0.51435 0.2794)
			(stroke
				(width 0.1)
				(type default)
			)
			(layer "F.Fab")
		)
		(fp_line
			(start -0.51435 -0.2794)
			(end 0.51435 -0.2794)
			(stroke
				(width 0.1)
				(type default)
			)
			(layer "F.Fab")
		)
		(fp_line
			(start 0.51435 0.2794)
			(end -0.51435 0.2794)
			(stroke
				(width 0.1)
				(type default)
			)
			(layer "F.Fab")
		)
		(fp_line
			(start -0.51435 0.2794)
			(end -0.51435 -0.2794)
			(stroke
				(width 0.1)
				(type default)
			)
			(layer "F.Fab")
		)
		(pad "1" smd circle
			(at -0.40005 0 90)
			(size 0 0)
			(layers "F.Cu" "F.Mask" "F.Paste")
			(net "BIC_ADCVREFP0")
		)
		(pad "2" smd circle
			(at 0.40005 0 90)
			(size 0 0)
			(layers "F.Cu" "F.Mask" "F.Paste")
			(net "BIC_ADCVREFN0")
		)
		(zone
			(layer "F.Cu")
			(hatch none 0.5)
			(connect_pads
				(clearance 0)
			)
			(min_thickness 0.25)
			(keepout
				(tracks not_allowed)
				(vias allowed)
				(pads allowed)
				(copperpour not_allowed)
				(footprints allowed)
			)
			(placement
				(enabled no)
				(sheetname "")
			)
			(fill
				(thermal_gap 0.5)
				(thermal_bridge_width 0.5)
				(island_removal_mode 0)
			)
			(polygon
				(pts
					(xy 239.791494 -218.10726) (xy 239.84966 -218.1987) (xy 239.84966 -218.39809) (xy 239.791494 -218.48826)
					(xy 239.616234 -218.48826) (xy 239.557814 -218.39809) (xy 239.557814 -218.1987) (xy 239.61598 -218.10726)
				)
			)
		)
	)
	(footprint ""
		(layer "F.Cu")
		(at 170.975274 -64.102234 180)
		(property "Reference" "PR7073"
			(at 0 0 180)
			(layer "F.SilkS")
			(hide yes)
			(effects
				(font
					(size 1.27 1.27)
				)
			)
		)
		(property "Value" ""
			(at 0 0 180)
			(layer "F.Fab")
			(effects
				(font
					(size 1.27 1.27)
				)
			)
		)
		(duplicate_pad_numbers_are_jumpers no)
		(fp_line
			(start 0.7874 0.4064)
			(end -0.7874 0.4064)
			(stroke
				(width 0.1524)
				(type default)
			)
			(layer "F.SilkS")
		)
		(fp_line
			(start 0.7874 -0.4064)
			(end 0.7874 0.4064)
			(stroke
				(width 0.1524)
				(type default)
			)
			(layer "F.SilkS")
		)
		(fp_line
			(start -0.7874 0.4064)
			(end -0.7874 -0.4064)
			(stroke
				(width 0.1524)
				(type default)
			)
			(layer "F.SilkS")
		)
		(fp_line
			(start -0.7874 -0.4064)
			(end 0.7874 -0.4064)
			(stroke
				(width 0.1524)
				(type default)
			)
			(layer "F.SilkS")
		)
		(fp_line
			(start 0.67945 0.3048)
			(end 0.120396 0.3048)
			(stroke
				(width 0.1)
				(type default)
			)
			(layer "F.Fab")
		)
		(fp_line
			(start 0.67945 -0.3048)
			(end 0.67945 0.3048)
			(stroke
				(width 0.1)
				(type default)
			)
			(layer "F.Fab")
		)
		(fp_line
			(start 0.12065 -0.2794)
			(end 0.12065 -0.3048)
			(stroke
				(width 0.1)
				(type default)
			)
			(layer "F.Fab")
		)
		(fp_line
			(start 0.12065 -0.3048)
			(end 0.67945 -0.3048)
			(stroke
				(width 0.1)
				(type default)
			)
			(layer "F.Fab")
		)
		(fp_line
			(start 0.120396 0.3048)
			(end 0.120396 0.2794)
			(stroke
				(width 0.1)
				(type default)
			)
			(layer "F.Fab")
		)
		(fp_line
			(start 0.120396 0.2794)
			(end -0.12065 0.2794)
			(stroke
				(width 0.1)
				(type default)
			)
			(layer "F.Fab")
		)
		(fp_line
			(start -0.12065 0.3048)
			(end -0.67945 0.3048)
			(stroke
				(width 0.1)
				(type default)
			)
			(layer "F.Fab")
		)
		(fp_line
			(start -0.12065 0.2794)
			(end -0.12065 0.3048)
			(stroke
				(width 0.1)
				(type default)
			)
			(layer "F.Fab")
		)
		(fp_line
			(start -0.12065 -0.2794)
			(end 0.12065 -0.2794)
			(stroke
				(width 0.1)
				(type default)
			)
			(layer "F.Fab")
		)
		(fp_line
			(start -0.12065 -0.305054)
			(end -0.12065 -0.2794)
			(stroke
				(width 0.1)
				(type default)
			)
			(layer "F.Fab")
		)
		(fp_line
			(start -0.67945 0.3048)
			(end -0.67945 -0.305054)
			(stroke
				(width 0.1)
				(type default)
			)
			(layer "F.Fab")
		)
		(fp_line
			(start -0.67945 -0.305054)
			(end -0.12065 -0.305054)
			(stroke
				(width 0.1)
				(type default)
			)
			(layer "F.Fab")
		)
		(pad "1" smd circle
			(at -0.40005 0 180)
			(size 0 0)
			(layers "F.Cu" "F.Mask" "F.Paste")
			(net "P12V_SSD6_PG_G1")
		)
		(pad "2" smd circle
			(at 0.40005 0 180)
			(size 0 0)
			(layers "F.Cu" "F.Mask" "F.Paste")
			(net "GND")
		)
	)
	(footprint ""
		(layer "F.Cu")
		(at 147.001992 -32.849312 90)
		(property "Reference" "R5666"
			(at 0 0 90)
			(layer "F.SilkS")
			(hide yes)
			(effects
				(font
					(size 1.27 1.27)
				)
			)
		)
		(property "Value" ""
			(at 0 0 90)
			(layer "F.Fab")
			(effects
				(font
					(size 1.27 1.27)
				)
			)
		)
		(duplicate_pad_numbers_are_jumpers no)
		(fp_line
			(start 0.7874 -0.4064)
			(end 0.7874 0.4064)
			(stroke
				(width 0.1524)
				(type default)
			)
			(layer "F.SilkS")
		)
		(fp_line
			(start -0.7874 -0.4064)
			(end 0.7874 -0.4064)
			(stroke
				(width 0.1524)
				(type default)
			)
			(layer "F.SilkS")
		)
		(fp_line
			(start 0.7874 0.4064)
			(end -0.7874 0.4064)
			(stroke
				(width 0.1524)
				(type default)
			)
			(layer "F.SilkS")
		)
		(fp_line
			(start -0.7874 0.4064)
			(end -0.7874 -0.4064)
			(stroke
				(width 0.1524)
				(type default)
			)
			(layer "F.SilkS")
		)
		(fp_line
			(start -0.12065 -0.305054)
			(end -0.12065 -0.2794)
			(stroke
				(width 0.1)
				(type default)
			)
			(layer "F.Fab")
		)
		(fp_line
			(start -0.67945 -0.305054)
			(end -0.12065 -0.305054)
			(stroke
				(width 0.1)
				(type default)
			)
			(layer "F.Fab")
		)
		(fp_line
			(start 0.67945 -0.3048)
			(end 0.67945 0.3048)
			(stroke
				(width 0.1)
				(type default)
			)
			(layer "F.Fab")
		)
		(fp_line
			(start 0.12065 -0.3048)
			(end 0.67945 -0.3048)
			(stroke
				(width 0.1)
				(type default)
			)
			(layer "F.Fab")
		)
		(fp_line
			(start 0.12065 -0.2794)
			(end 0.12065 -0.3048)
			(stroke
				(width 0.1)
				(type default)
			)
			(layer "F.Fab")
		)
		(fp_line
			(start -0.12065 -0.2794)
			(end 0.12065 -0.2794)
			(stroke
				(width 0.1)
				(type default)
			)
			(layer "F.Fab")
		)
		(fp_line
			(start 0.120396 0.2794)
			(end -0.12065 0.2794)
			(stroke
				(width 0.1)
				(type default)
			)
			(layer "F.Fab")
		)
		(fp_line
			(start -0.12065 0.2794)
			(end -0.12065 0.3048)
			(stroke
				(width 0.1)
				(type default)
			)
			(layer "F.Fab")
		)
		(fp_line
			(start 0.67945 0.3048)
			(end 0.120396 0.3048)
			(stroke
				(width 0.1)
				(type default)
			)
			(layer "F.Fab")
		)
		(fp_line
			(start 0.120396 0.3048)
			(end 0.120396 0.2794)
			(stroke
				(width 0.1)
				(type default)
			)
			(layer "F.Fab")
		)
		(fp_line
			(start -0.12065 0.3048)
			(end -0.67945 0.3048)
			(stroke
				(width 0.1)
				(type default)
			)
			(layer "F.Fab")
		)
		(fp_line
			(start -0.67945 0.3048)
			(end -0.67945 -0.305054)
			(stroke
				(width 0.1)
				(type default)
			)
			(layer "F.Fab")
		)
		(pad "1" smd circle
			(at -0.40005 0 90)
			(size 0 0)
			(layers "F.Cu" "F.Mask" "F.Paste")
			(net "RST_SMB_SSD5_ISO_R_N")
		)
		(pad "2" smd circle
			(at 0.40005 0 90)
			(size 0 0)
			(layers "F.Cu" "F.Mask" "F.Paste")
			(net "RST_SMB_SSD5_ISO_N")
		)
	)
	(footprint ""
		(layer "F.Cu")
		(at 384.51282 -350.098614 90)
		(property "Reference" "C791"
			(at 0 0 90)
			(layer "F.SilkS")
			(hide yes)
			(effects
				(font
					(size 1.27 1.27)
				)
			)
		)
		(property "Value" ""
			(at 0 0 90)
			(layer "F.Fab")
			(effects
				(font
					(size 1.27 1.27)
				)
			)
		)
		(duplicate_pad_numbers_are_jumpers no)
		(fp_line
			(start 0.299974 -0.150114)
			(end 0.299974 0.150114)
			(stroke
				(width 0.1)
				(type default)
			)
			(layer "F.Fab")
		)
		(fp_line
			(start -0.299974 -0.150114)
			(end 0.299974 -0.150114)
			(stroke
				(width 0.1)
				(type default)
			)
			(layer "F.Fab")
		)
		(fp_line
			(start 0.299974 0.150114)
			(end -0.299974 0.150114)
			(stroke
				(width 0.1)
				(type default)
			)
			(layer "F.Fab")
		)
		(fp_line
			(start -0.299974 0.150114)
			(end -0.299974 -0.150114)
			(stroke
				(width 0.1)
				(type default)
			)
			(layer "F.Fab")
		)
		(pad "1" smd rect
			(at -0.2667 0 90)
			(size 0.3048 0.381)
			(layers "F.Cu" "F.Mask" "F.Paste")
			(net "P5E_PEX3_STN6_TX_DN<97>")
		)
		(pad "2" smd rect
			(at 0.2667 0 90)
			(size 0.3048 0.381)
			(layers "F.Cu" "F.Mask" "F.Paste")
			(net "P5E_PEX3_STN6_TX_C_DN<97>")
		)
	)
	(footprint ""
		(layer "F.Cu")
		(at 441.442602 -70.844918 -90)
		(property "Reference" "PD51"
			(at 4.093718 2.173732 90)
			(unlocked yes)
			(layer "F.SilkS")
			(effects
				(font
					(size 0.7874 0.5842)
					(thickness 0.1524)
				)
				(justify left)
			)
		)
		(property "Value" ""
			(at 0 0 270)
			(layer "F.Fab")
			(effects
				(font
					(size 1.27 1.27)
				)
			)
		)
		(duplicate_pad_numbers_are_jumpers no)
		(fp_line
			(start -3.400044 1.459992)
			(end -3.400044 -1.459992)
			(stroke
				(width 0.1524)
				(type default)
			)
			(layer "F.SilkS")
		)
		(fp_line
			(start 4.107942 1.459992)
			(end -3.400044 1.459992)
			(stroke
				(width 0.1524)
				(type default)
			)
			(layer "F.SilkS")
		)
		(fp_line
			(start -3.400044 -1.459992)
			(end 4.107942 -1.459992)
			(stroke
				(width 0.1524)
				(type default)
			)
			(layer "F.SilkS")
		)
		(fp_line
			(start 4.107942 -1.459992)
			(end 4.107942 1.459992)
			(stroke
				(width 0.1524)
				(type default)
			)
			(layer "F.SilkS")
		)
		(fp_poly
			(pts
				(xy 4.107942 -1.459992) (xy 4.107942 1.459992) (xy 3.308096 1.459992) (xy 3.308096 -1.459992)
			)
			(stroke
				(width 0)
				(type default)
			)
			(fill yes)
			(layer "F.SilkS")
		)
		(fp_line
			(start -2.29997 1.459992)
			(end -2.29997 -1.459992)
			(stroke
				(width 0.1)
				(type default)
			)
			(layer "F.Fab")
		)
		(fp_line
			(start 2.29997 1.459992)
			(end -2.29997 1.459992)
			(stroke
				(width 0.1)
				(type default)
			)
			(layer "F.Fab")
		)
		(fp_line
			(start -2.29997 -1.459992)
			(end 2.29997 -1.459992)
			(stroke
				(width 0.1)
				(type default)
			)
			(layer "F.Fab")
		)
		(fp_line
			(start 2.29997 -1.459992)
			(end 2.29997 1.459992)
			(stroke
				(width 0.1)
				(type default)
			)
			(layer "F.Fab")
		)
		(fp_text user "-"
			(at 5.4102 0.29845 90)
			(unlocked yes)
			(layer "F.SilkS")
			(effects
				(font
					(size 1.905 1.4224)
					(thickness 0.1524)
				)
				(justify left)
			)
		)
		(fp_text user "+"
			(at -5.148326 -0.183134 270)
			(unlocked yes)
			(layer "F.SilkS")
			(effects
				(font
					(size 1.905 1.4224)
					(thickness 0.1524)
				)
				(justify left)
			)
		)
		(fp_text user "-"
			(at 5.4102 0.29845 90)
			(unlocked yes)
			(layer "F.Fab")
			(effects
				(font
					(size 1.905 1.4224)
					(thickness 0.1524)
				)
				(justify left)
			)
		)
		(fp_text user "+"
			(at -4.7752 -0.12065 270)
			(unlocked yes)
			(layer "F.Fab")
			(effects
				(font
					(size 1.905 1.4224)
					(thickness 0.1524)
				)
				(justify left)
			)
		)
		(pad "A" smd rect
			(at -1.999996 0)
			(size 1.7018 2.5146)
			(layers "F.Cu" "F.Mask" "F.Paste")
			(net "GND")
		)
		(pad "C" smd rect
			(at 1.999996 0)
			(size 1.7018 2.5146)
			(layers "F.Cu" "F.Mask" "F.Paste")
			(net "P12V_SSD15_R")
		)
	)
	(footprint ""
		(layer "F.Cu")
		(at 198.76135 -121.391172 180)
		(property "Reference" "C240"
			(at 0 0 180)
			(layer "F.SilkS")
			(hide yes)
			(effects
				(font
					(size 1.27 1.27)
				)
			)
		)
		(property "Value" ""
			(at 0 0 180)
			(layer "F.Fab")
			(effects
				(font
					(size 1.27 1.27)
				)
			)
		)
		(duplicate_pad_numbers_are_jumpers no)
		(fp_line
			(start 0.299974 0.150114)
			(end -0.299974 0.150114)
			(stroke
				(width 0.1)
				(type default)
			)
			(layer "F.Fab")
		)
		(fp_line
			(start 0.299974 -0.150114)
			(end 0.299974 0.150114)
			(stroke
				(width 0.1)
				(type default)
			)
			(layer "F.Fab")
		)
		(fp_line
			(start -0.299974 0.150114)
			(end -0.299974 -0.150114)
			(stroke
				(width 0.1)
				(type default)
			)
			(layer "F.Fab")
		)
		(fp_line
			(start -0.299974 -0.150114)
			(end 0.299974 -0.150114)
			(stroke
				(width 0.1)
				(type default)
			)
			(layer "F.Fab")
		)
		(pad "1" smd rect
			(at -0.2667 0 180)
			(size 0.3048 0.381)
			(layers "F.Cu" "F.Mask" "F.Paste")
			(net "P5E_PEX1_STN0_TX_DP<1>")
		)
		(pad "2" smd rect
			(at 0.2667 0 180)
			(size 0.3048 0.381)
			(layers "F.Cu" "F.Mask" "F.Paste")
			(net "P5E_PEX1_STN0_TX_C_DP<1>")
		)
	)
	(footprint ""
		(layer "F.Cu")
		(at 28.633928 -356.244906 90)
		(property "Reference" "C181"
			(at 0 0 90)
			(layer "F.SilkS")
			(hide yes)
			(effects
				(font
					(size 1.27 1.27)
				)
			)
		)
		(property "Value" ""
			(at 0 0 90)
			(layer "F.Fab")
			(effects
				(font
					(size 1.27 1.27)
				)
			)
		)
		(duplicate_pad_numbers_are_jumpers no)
		(fp_line
			(start 0.299974 -0.150114)
			(end 0.299974 0.150114)
			(stroke
				(width 0.1)
				(type default)
			)
			(layer "F.Fab")
		)
		(fp_line
			(start -0.299974 -0.150114)
			(end 0.299974 -0.150114)
			(stroke
				(width 0.1)
				(type default)
			)
			(layer "F.Fab")
		)
		(fp_line
			(start 0.299974 0.150114)
			(end -0.299974 0.150114)
			(stroke
				(width 0.1)
				(type default)
			)
			(layer "F.Fab")
		)
		(fp_line
			(start -0.299974 0.150114)
			(end -0.299974 -0.150114)
			(stroke
				(width 0.1)
				(type default)
			)
			(layer "F.Fab")
		)
		(pad "1" smd rect
			(at -0.2667 0 90)
			(size 0.3048 0.381)
			(layers "F.Cu" "F.Mask" "F.Paste")
			(net "P5E_PEX0_STN7_TX_DP<117>")
		)
		(pad "2" smd rect
			(at 0.2667 0 90)
			(size 0.3048 0.381)
			(layers "F.Cu" "F.Mask" "F.Paste")
			(net "P5E_PEX0_STN7_TX_C_DP<117>")
		)
	)
	(footprint ""
		(layer "F.Cu")
		(at 419.95471 -22.867366 90)
		(property "Reference" "C3972"
			(at 0 0 90)
			(layer "F.SilkS")
			(hide yes)
			(effects
				(font
					(size 1.27 1.27)
				)
			)
		)
		(property "Value" ""
			(at 0 0 90)
			(layer "F.Fab")
			(effects
				(font
					(size 1.27 1.27)
				)
			)
		)
		(duplicate_pad_numbers_are_jumpers no)
		(fp_line
			(start 0.7874 -0.4064)
			(end 0.7874 0.4064)
			(stroke
				(width 0.1524)
				(type default)
			)
			(layer "F.SilkS")
		)
		(fp_line
			(start -0.7874 -0.4064)
			(end 0.7874 -0.4064)
			(stroke
				(width 0.1524)
				(type default)
			)
			(layer "F.SilkS")
		)
		(fp_line
			(start 0.7874 0.4064)
			(end -0.7874 0.4064)
			(stroke
				(width 0.1524)
				(type default)
			)
			(layer "F.SilkS")
		)
		(fp_line
			(start -0.7874 0.4064)
			(end -0.7874 -0.4064)
			(stroke
				(width 0.1524)
				(type default)
			)
			(layer "F.SilkS")
		)
		(fp_line
			(start -0.12065 -0.305054)
			(end -0.12065 -0.2794)
			(stroke
				(width 0.1)
				(type default)
			)
			(layer "F.Fab")
		)
		(fp_line
			(start -0.67945 -0.305054)
			(end -0.12065 -0.305054)
			(stroke
				(width 0.1)
				(type default)
			)
			(layer "F.Fab")
		)
		(fp_line
			(start 0.67945 -0.3048)
			(end 0.67945 0.3048)
			(stroke
				(width 0.1)
				(type default)
			)
			(layer "F.Fab")
		)
		(fp_line
			(start 0.12065 -0.3048)
			(end 0.67945 -0.3048)
			(stroke
				(width 0.1)
				(type default)
			)
			(layer "F.Fab")
		)
		(fp_line
			(start 0.12065 -0.2794)
			(end 0.12065 -0.3048)
			(stroke
				(width 0.1)
				(type default)
			)
			(layer "F.Fab")
		)
		(fp_line
			(start -0.12065 -0.2794)
			(end 0.12065 -0.2794)
			(stroke
				(width 0.1)
				(type default)
			)
			(layer "F.Fab")
		)
		(fp_line
			(start 0.120396 0.2794)
			(end -0.12065 0.2794)
			(stroke
				(width 0.1)
				(type default)
			)
			(layer "F.Fab")
		)
		(fp_line
			(start -0.12065 0.2794)
			(end -0.12065 0.3048)
			(stroke
				(width 0.1)
				(type default)
			)
			(layer "F.Fab")
		)
		(fp_line
			(start 0.67945 0.3048)
			(end 0.120396 0.3048)
			(stroke
				(width 0.1)
				(type default)
			)
			(layer "F.Fab")
		)
		(fp_line
			(start 0.120396 0.3048)
			(end 0.120396 0.2794)
			(stroke
				(width 0.1)
				(type default)
			)
			(layer "F.Fab")
		)
		(fp_line
			(start -0.12065 0.3048)
			(end -0.67945 0.3048)
			(stroke
				(width 0.1)
				(type default)
			)
			(layer "F.Fab")
		)
		(fp_line
			(start -0.67945 0.3048)
			(end -0.67945 -0.305054)
			(stroke
				(width 0.1)
				(type default)
			)
			(layer "F.Fab")
		)
		(pad "1" smd circle
			(at -0.40005 0 90)
			(size 0 0)
			(layers "F.Cu" "F.Mask" "F.Paste")
			(net "P12V_SSD14")
		)
		(pad "2" smd circle
			(at 0.40005 0 90)
			(size 0 0)
			(layers "F.Cu" "F.Mask" "F.Paste")
			(net "GND")
		)
	)
	(footprint ""
		(layer "F.Cu")
		(at 145.999962 -244.298978 180)
		(property "Reference" "R6572"
			(at 0 0 180)
			(layer "F.SilkS")
			(hide yes)
			(effects
				(font
					(size 1.27 1.27)
				)
			)
		)
		(property "Value" ""
			(at 0 0 180)
			(layer "F.Fab")
			(effects
				(font
					(size 1.27 1.27)
				)
			)
		)
		(duplicate_pad_numbers_are_jumpers no)
		(fp_line
			(start 0.7874 0.4064)
			(end -0.7874 0.4064)
			(stroke
				(width 0.1524)
				(type default)
			)
			(layer "F.SilkS")
		)
		(fp_line
			(start 0.7874 -0.4064)
			(end 0.7874 0.4064)
			(stroke
				(width 0.1524)
				(type default)
			)
			(layer "F.SilkS")
		)
		(fp_line
			(start -0.7874 0.4064)
			(end -0.7874 -0.4064)
			(stroke
				(width 0.1524)
				(type default)
			)
			(layer "F.SilkS")
		)
		(fp_line
			(start -0.7874 -0.4064)
			(end 0.7874 -0.4064)
			(stroke
				(width 0.1524)
				(type default)
			)
			(layer "F.SilkS")
		)
		(fp_line
			(start 0.67945 0.3048)
			(end 0.120396 0.3048)
			(stroke
				(width 0.1)
				(type default)
			)
			(layer "F.Fab")
		)
		(fp_line
			(start 0.67945 -0.3048)
			(end 0.67945 0.3048)
			(stroke
				(width 0.1)
				(type default)
			)
			(layer "F.Fab")
		)
		(fp_line
			(start 0.12065 -0.2794)
			(end 0.12065 -0.3048)
			(stroke
				(width 0.1)
				(type default)
			)
			(layer "F.Fab")
		)
		(fp_line
			(start 0.12065 -0.3048)
			(end 0.67945 -0.3048)
			(stroke
				(width 0.1)
				(type default)
			)
			(layer "F.Fab")
		)
		(fp_line
			(start 0.120396 0.3048)
			(end 0.120396 0.2794)
			(stroke
				(width 0.1)
				(type default)
			)
			(layer "F.Fab")
		)
		(fp_line
			(start 0.120396 0.2794)
			(end -0.12065 0.2794)
			(stroke
				(width 0.1)
				(type default)
			)
			(layer "F.Fab")
		)
		(fp_line
			(start -0.12065 0.3048)
			(end -0.67945 0.3048)
			(stroke
				(width 0.1)
				(type default)
			)
			(layer "F.Fab")
		)
		(fp_line
			(start -0.12065 0.2794)
			(end -0.12065 0.3048)
			(stroke
				(width 0.1)
				(type default)
			)
			(layer "F.Fab")
		)
		(fp_line
			(start -0.12065 -0.2794)
			(end 0.12065 -0.2794)
			(stroke
				(width 0.1)
				(type default)
			)
			(layer "F.Fab")
		)
		(fp_line
			(start -0.12065 -0.305054)
			(end -0.12065 -0.2794)
			(stroke
				(width 0.1)
				(type default)
			)
			(layer "F.Fab")
		)
		(fp_line
			(start -0.67945 0.3048)
			(end -0.67945 -0.305054)
			(stroke
				(width 0.1)
				(type default)
			)
			(layer "F.Fab")
		)
		(fp_line
			(start -0.67945 -0.305054)
			(end -0.12065 -0.305054)
			(stroke
				(width 0.1)
				(type default)
			)
			(layer "F.Fab")
		)
		(pad "1" smd circle
			(at -0.40005 0 180)
			(size 0 0)
			(layers "F.Cu" "F.Mask" "F.Paste")
			(net "PWR_EN_PEX_R")
		)
		(pad "2" smd circle
			(at 0.40005 0 180)
			(size 0 0)
			(layers "F.Cu" "F.Mask" "F.Paste")
			(net "PEX1_P1V8_PLL_EN")
		)
	)
	(footprint ""
		(layer "F.Cu")
		(at 325.82104 -102.880414 90)
		(property "Reference" "C622"
			(at 0 0 90)
			(layer "F.SilkS")
			(hide yes)
			(effects
				(font
					(size 1.27 1.27)
				)
			)
		)
		(property "Value" ""
			(at 0 0 90)
			(layer "F.Fab")
			(effects
				(font
					(size 1.27 1.27)
				)
			)
		)
		(duplicate_pad_numbers_are_jumpers no)
		(fp_line
			(start 0.7874 -0.4064)
			(end 0.7874 0.4064)
			(stroke
				(width 0.1524)
				(type default)
			)
			(layer "F.SilkS")
		)
		(fp_line
			(start -0.7874 -0.4064)
			(end 0.7874 -0.4064)
			(stroke
				(width 0.1524)
				(type default)
			)
			(layer "F.SilkS")
		)
		(fp_line
			(start 0.7874 0.4064)
			(end -0.7874 0.4064)
			(stroke
				(width 0.1524)
				(type default)
			)
			(layer "F.SilkS")
		)
		(fp_line
			(start -0.7874 0.4064)
			(end -0.7874 -0.4064)
			(stroke
				(width 0.1524)
				(type default)
			)
			(layer "F.SilkS")
		)
		(fp_line
			(start -0.12065 -0.305054)
			(end -0.12065 -0.2794)
			(stroke
				(width 0.1)
				(type default)
			)
			(layer "F.Fab")
		)
		(fp_line
			(start -0.67945 -0.305054)
			(end -0.12065 -0.305054)
			(stroke
				(width 0.1)
				(type default)
			)
			(layer "F.Fab")
		)
		(fp_line
			(start 0.67945 -0.3048)
			(end 0.67945 0.3048)
			(stroke
				(width 0.1)
				(type default)
			)
			(layer "F.Fab")
		)
		(fp_line
			(start 0.12065 -0.3048)
			(end 0.67945 -0.3048)
			(stroke
				(width 0.1)
				(type default)
			)
			(layer "F.Fab")
		)
		(fp_line
			(start 0.12065 -0.2794)
			(end 0.12065 -0.3048)
			(stroke
				(width 0.1)
				(type default)
			)
			(layer "F.Fab")
		)
		(fp_line
			(start -0.12065 -0.2794)
			(end 0.12065 -0.2794)
			(stroke
				(width 0.1)
				(type default)
			)
			(layer "F.Fab")
		)
		(fp_line
			(start 0.120396 0.2794)
			(end -0.12065 0.2794)
			(stroke
				(width 0.1)
				(type default)
			)
			(layer "F.Fab")
		)
		(fp_line
			(start -0.12065 0.2794)
			(end -0.12065 0.3048)
			(stroke
				(width 0.1)
				(type default)
			)
			(layer "F.Fab")
		)
		(fp_line
			(start 0.67945 0.3048)
			(end 0.120396 0.3048)
			(stroke
				(width 0.1)
				(type default)
			)
			(layer "F.Fab")
		)
		(fp_line
			(start 0.120396 0.3048)
			(end 0.120396 0.2794)
			(stroke
				(width 0.1)
				(type default)
			)
			(layer "F.Fab")
		)
		(fp_line
			(start -0.12065 0.3048)
			(end -0.67945 0.3048)
			(stroke
				(width 0.1)
				(type default)
			)
			(layer "F.Fab")
		)
		(fp_line
			(start -0.67945 0.3048)
			(end -0.67945 -0.305054)
			(stroke
				(width 0.1)
				(type default)
			)
			(layer "F.Fab")
		)
		(pad "1" smd circle
			(at -0.40005 0 90)
			(size 0 0)
			(layers "F.Cu" "F.Mask" "F.Paste")
			(net "P3V3_AUX")
		)
		(pad "2" smd circle
			(at 0.40005 0 90)
			(size 0 0)
			(layers "F.Cu" "F.Mask" "F.Paste")
			(net "GND")
		)
	)
	(footprint ""
		(layer "F.Cu")
		(at 226.031298 -86.750398)
		(property "Reference" "R4110"
			(at 0 0 0)
			(layer "F.SilkS")
			(hide yes)
			(effects
				(font
					(size 1.27 1.27)
				)
			)
		)
		(property "Value" ""
			(at 0 0 0)
			(layer "F.Fab")
			(effects
				(font
					(size 1.27 1.27)
				)
			)
		)
		(duplicate_pad_numbers_are_jumpers no)
		(fp_line
			(start -0.7874 -0.4064)
			(end 0.7874 -0.4064)
			(stroke
				(width 0.1524)
				(type default)
			)
			(layer "F.SilkS")
		)
		(fp_line
			(start -0.7874 0.4064)
			(end -0.7874 -0.4064)
			(stroke
				(width 0.1524)
				(type default)
			)
			(layer "F.SilkS")
		)
		(fp_line
			(start 0.7874 -0.4064)
			(end 0.7874 0.4064)
			(stroke
				(width 0.1524)
				(type default)
			)
			(layer "F.SilkS")
		)
		(fp_line
			(start 0.7874 0.4064)
			(end -0.7874 0.4064)
			(stroke
				(width 0.1524)
				(type default)
			)
			(layer "F.SilkS")
		)
		(fp_line
			(start -0.67945 -0.305054)
			(end -0.12065 -0.305054)
			(stroke
				(width 0.1)
				(type default)
			)
			(layer "F.Fab")
		)
		(fp_line
			(start -0.67945 0.3048)
			(end -0.67945 -0.305054)
			(stroke
				(width 0.1)
				(type default)
			)
			(layer "F.Fab")
		)
		(fp_line
			(start -0.12065 -0.305054)
			(end -0.12065 -0.2794)
			(stroke
				(width 0.1)
				(type default)
			)
			(layer "F.Fab")
		)
		(fp_line
			(start -0.12065 -0.2794)
			(end 0.12065 -0.2794)
			(stroke
				(width 0.1)
				(type default)
			)
			(layer "F.Fab")
		)
		(fp_line
			(start -0.12065 0.2794)
			(end -0.12065 0.3048)
			(stroke
				(width 0.1)
				(type default)
			)
			(layer "F.Fab")
		)
		(fp_line
			(start -0.12065 0.3048)
			(end -0.67945 0.3048)
			(stroke
				(width 0.1)
				(type default)
			)
			(layer "F.Fab")
		)
		(fp_line
			(start 0.120396 0.2794)
			(end -0.12065 0.2794)
			(stroke
				(width 0.1)
				(type default)
			)
			(layer "F.Fab")
		)
		(fp_line
			(start 0.120396 0.3048)
			(end 0.120396 0.2794)
			(stroke
				(width 0.1)
				(type default)
			)
			(layer "F.Fab")
		)
		(fp_line
			(start 0.12065 -0.3048)
			(end 0.67945 -0.3048)
			(stroke
				(width 0.1)
				(type default)
			)
			(layer "F.Fab")
		)
		(fp_line
			(start 0.12065 -0.2794)
			(end 0.12065 -0.3048)
			(stroke
				(width 0.1)
				(type default)
			)
			(layer "F.Fab")
		)
		(fp_line
			(start 0.67945 -0.3048)
			(end 0.67945 0.3048)
			(stroke
				(width 0.1)
				(type default)
			)
			(layer "F.Fab")
		)
		(fp_line
			(start 0.67945 0.3048)
			(end 0.120396 0.3048)
			(stroke
				(width 0.1)
				(type default)
			)
			(layer "F.Fab")
		)
		(pad "1" smd circle
			(at -0.40005 0)
			(size 0 0)
			(layers "F.Cu" "F.Mask" "F.Paste")
			(net "SMB_BIC_I2C6_R_SCL")
		)
		(pad "2" smd circle
			(at 0.40005 0)
			(size 0 0)
			(layers "F.Cu" "F.Mask" "F.Paste")
			(net "SMB_BIC_I2C6_SENEOR_SCL")
		)
	)
	(footprint ""
		(layer "F.Cu")
		(at 191.055752 -350.098614 90)
		(property "Reference" "C375"
			(at 0 0 90)
			(layer "F.SilkS")
			(hide yes)
			(effects
				(font
					(size 1.27 1.27)
				)
			)
		)
		(property "Value" ""
			(at 0 0 90)
			(layer "F.Fab")
			(effects
				(font
					(size 1.27 1.27)
				)
			)
		)
		(duplicate_pad_numbers_are_jumpers no)
		(fp_line
			(start 0.299974 -0.150114)
			(end 0.299974 0.150114)
			(stroke
				(width 0.1)
				(type default)
			)
			(layer "F.Fab")
		)
		(fp_line
			(start -0.299974 -0.150114)
			(end 0.299974 -0.150114)
			(stroke
				(width 0.1)
				(type default)
			)
			(layer "F.Fab")
		)
		(fp_line
			(start 0.299974 0.150114)
			(end -0.299974 0.150114)
			(stroke
				(width 0.1)
				(type default)
			)
			(layer "F.Fab")
		)
		(fp_line
			(start -0.299974 0.150114)
			(end -0.299974 -0.150114)
			(stroke
				(width 0.1)
				(type default)
			)
			(layer "F.Fab")
		)
		(pad "1" smd rect
			(at -0.2667 0 90)
			(size 0.3048 0.381)
			(layers "F.Cu" "F.Mask" "F.Paste")
			(net "P5E_PEX1_STN7_TX_DN<126>")
		)
		(pad "2" smd rect
			(at 0.2667 0 90)
			(size 0.3048 0.381)
			(layers "F.Cu" "F.Mask" "F.Paste")
			(net "P5E_PEX1_STN7_TX_C_DN<126>")
		)
	)
	(footprint ""
		(layer "F.Cu")
		(at 10.615168 -251.312426 -90)
		(property "Reference" "C4228"
			(at 0 0 270)
			(layer "F.SilkS")
			(hide yes)
			(effects
				(font
					(size 1.27 1.27)
				)
			)
		)
		(property "Value" ""
			(at 0 0 270)
			(layer "F.Fab")
			(effects
				(font
					(size 1.27 1.27)
				)
			)
		)
		(duplicate_pad_numbers_are_jumpers no)
		(fp_line
			(start -1.2954 0.5842)
			(end -1.2954 -0.5842)
			(stroke
				(width 0.1524)
				(type default)
			)
			(layer "F.SilkS")
		)
		(fp_line
			(start 1.2954 0.5842)
			(end -1.2954 0.5842)
			(stroke
				(width 0.1524)
				(type default)
			)
			(layer "F.SilkS")
		)
		(fp_line
			(start -1.2954 -0.5842)
			(end 1.2954 -0.5842)
			(stroke
				(width 0.1524)
				(type default)
			)
			(layer "F.SilkS")
		)
		(fp_line
			(start 1.2954 -0.5842)
			(end 1.2954 0.5842)
			(stroke
				(width 0.1524)
				(type default)
			)
			(layer "F.SilkS")
		)
		(fp_line
			(start -0.8636 0.4572)
			(end -0.8636 0.4064)
			(stroke
				(width 0.1)
				(type default)
			)
			(layer "F.Fab")
		)
		(fp_line
			(start 0.8636 0.4572)
			(end -0.8636 0.4572)
			(stroke
				(width 0.1)
				(type default)
			)
			(layer "F.Fab")
		)
		(fp_line
			(start -1.1938 0.4064)
			(end -1.1938 -0.4064)
			(stroke
				(width 0.1)
				(type default)
			)
			(layer "F.Fab")
		)
		(fp_line
			(start -0.8636 0.4064)
			(end -1.1938 0.4064)
			(stroke
				(width 0.1)
				(type default)
			)
			(layer "F.Fab")
		)
		(fp_line
			(start 0.8636 0.4064)
			(end 0.8636 0.4572)
			(stroke
				(width 0.1)
				(type default)
			)
			(layer "F.Fab")
		)
		(fp_line
			(start 1.1938 0.4064)
			(end 0.8636 0.4064)
			(stroke
				(width 0.1)
				(type default)
			)
			(layer "F.Fab")
		)
		(fp_line
			(start -1.1938 -0.4064)
			(end -0.8636 -0.4064)
			(stroke
				(width 0.1)
				(type default)
			)
			(layer "F.Fab")
		)
		(fp_line
			(start -0.8636 -0.4064)
			(end -0.8636 -0.4572)
			(stroke
				(width 0.1)
				(type default)
			)
			(layer "F.Fab")
		)
		(fp_line
			(start 0.8636 -0.4064)
			(end 1.1938 -0.4064)
			(stroke
				(width 0.1)
				(type default)
			)
			(layer "F.Fab")
		)
		(fp_line
			(start 1.1938 -0.4064)
			(end 1.1938 0.4064)
			(stroke
				(width 0.1)
				(type default)
			)
			(layer "F.Fab")
		)
		(fp_line
			(start -0.8636 -0.4572)
			(end 0.8636 -0.4572)
			(stroke
				(width 0.1)
				(type default)
			)
			(layer "F.Fab")
		)
		(fp_line
			(start 0.8636 -0.4572)
			(end 0.8636 -0.4064)
			(stroke
				(width 0.1)
				(type default)
			)
			(layer "F.Fab")
		)
		(pad "1" smd rect
			(at -0.7366 0 180)
			(size 0.7112 0.8128)
			(layers "F.Cu" "F.Mask" "F.Paste")
			(net "P1V25_SERDES_VDDPLL_PEX0_C2")
		)
		(pad "2" smd rect
			(at 0.7366 0 180)
			(size 0.7112 0.8128)
			(layers "F.Cu" "F.Mask" "F.Paste")
			(net "GND")
		)
	)
	(footprint ""
		(layer "F.Cu")
		(at 338.838286 -93.11894 -90)
		(property "Reference" "R1185"
			(at 0 0 270)
			(layer "F.SilkS")
			(hide yes)
			(effects
				(font
					(size 1.27 1.27)
				)
			)
		)
		(property "Value" ""
			(at 0 0 270)
			(layer "F.Fab")
			(effects
				(font
					(size 1.27 1.27)
				)
			)
		)
		(duplicate_pad_numbers_are_jumpers no)
		(fp_line
			(start 0.7874 0.4064)
			(end -0.7874 0.4064)
			(stroke
				(width 0.1524)
				(type default)
			)
			(layer "F.SilkS")
		)
		(fp_line
			(start -0.67945 0.3048)
			(end -0.67945 -0.305054)
			(stroke
				(width 0.1)
				(type default)
			)
			(layer "F.Fab")
		)
		(fp_line
			(start -0.12065 0.3048)
			(end -0.67945 0.3048)
			(stroke
				(width 0.1)
				(type default)
			)
			(layer "F.Fab")
		)
		(fp_line
			(start 0.120396 0.3048)
			(end 0.120396 0.2794)
			(stroke
				(width 0.1)
				(type default)
			)
			(layer "F.Fab")
		)
		(fp_line
			(start 0.67945 0.3048)
			(end 0.120396 0.3048)
			(stroke
				(width 0.1)
				(type default)
			)
			(layer "F.Fab")
		)
		(fp_line
			(start -0.12065 0.2794)
			(end -0.12065 0.3048)
			(stroke
				(width 0.1)
				(type default)
			)
			(layer "F.Fab")
		)
		(fp_line
			(start 0.120396 0.2794)
			(end -0.12065 0.2794)
			(stroke
				(width 0.1)
				(type default)
			)
			(layer "F.Fab")
		)
		(fp_line
			(start -0.12065 -0.2794)
			(end 0.12065 -0.2794)
			(stroke
				(width 0.1)
				(type default)
			)
			(layer "F.Fab")
		)
		(fp_line
			(start 0.12065 -0.2794)
			(end 0.12065 -0.3048)
			(stroke
				(width 0.1)
				(type default)
			)
			(layer "F.Fab")
		)
		(fp_line
			(start 0.12065 -0.3048)
			(end 0.67945 -0.3048)
			(stroke
				(width 0.1)
				(type default)
			)
			(layer "F.Fab")
		)
		(fp_line
			(start 0.67945 -0.3048)
			(end 0.67945 0.3048)
			(stroke
				(width 0.1)
				(type default)
			)
			(layer "F.Fab")
		)
		(fp_line
			(start -0.67945 -0.305054)
			(end -0.12065 -0.305054)
			(stroke
				(width 0.1)
				(type default)
			)
			(layer "F.Fab")
		)
		(fp_line
			(start -0.12065 -0.305054)
			(end -0.12065 -0.2794)
			(stroke
				(width 0.1)
				(type default)
			)
			(layer "F.Fab")
		)
		(pad "1" smd circle
			(at -0.40005 0 270)
			(size 0 0)
			(layers "F.Cu" "F.Mask" "F.Paste")
			(net "CLK_100M_DB800ZL_SSD15_R_DN")
		)
		(pad "2" smd circle
			(at 0.40005 0 270)
			(size 0 0)
			(layers "F.Cu" "F.Mask" "F.Paste")
			(net "CLK_100M_DB800ZL_SSD15_DN")
		)
	)
	(footprint ""
		(layer "F.Cu")
		(at 168.367964 -52.035456 180)
		(property "Reference" "R864"
			(at 0 0 180)
			(layer "F.SilkS")
			(hide yes)
			(effects
				(font
					(size 1.27 1.27)
				)
			)
		)
		(property "Value" ""
			(at 0 0 180)
			(layer "F.Fab")
			(effects
				(font
					(size 1.27 1.27)
				)
			)
		)
		(duplicate_pad_numbers_are_jumpers no)
		(fp_line
			(start 0.7874 0.4064)
			(end -0.7874 0.4064)
			(stroke
				(width 0.1524)
				(type default)
			)
			(layer "F.SilkS")
		)
		(fp_line
			(start 0.7874 -0.4064)
			(end 0.7874 0.4064)
			(stroke
				(width 0.1524)
				(type default)
			)
			(layer "F.SilkS")
		)
		(fp_line
			(start -0.7874 0.4064)
			(end -0.7874 -0.4064)
			(stroke
				(width 0.1524)
				(type default)
			)
			(layer "F.SilkS")
		)
		(fp_line
			(start -0.7874 -0.4064)
			(end 0.7874 -0.4064)
			(stroke
				(width 0.1524)
				(type default)
			)
			(layer "F.SilkS")
		)
		(fp_line
			(start 0.67945 0.3048)
			(end 0.120396 0.3048)
			(stroke
				(width 0.1)
				(type default)
			)
			(layer "F.Fab")
		)
		(fp_line
			(start 0.67945 -0.3048)
			(end 0.67945 0.3048)
			(stroke
				(width 0.1)
				(type default)
			)
			(layer "F.Fab")
		)
		(fp_line
			(start 0.12065 -0.2794)
			(end 0.12065 -0.3048)
			(stroke
				(width 0.1)
				(type default)
			)
			(layer "F.Fab")
		)
		(fp_line
			(start 0.12065 -0.3048)
			(end 0.67945 -0.3048)
			(stroke
				(width 0.1)
				(type default)
			)
			(layer "F.Fab")
		)
		(fp_line
			(start 0.120396 0.3048)
			(end 0.120396 0.2794)
			(stroke
				(width 0.1)
				(type default)
			)
			(layer "F.Fab")
		)
		(fp_line
			(start 0.120396 0.2794)
			(end -0.12065 0.2794)
			(stroke
				(width 0.1)
				(type default)
			)
			(layer "F.Fab")
		)
		(fp_line
			(start -0.12065 0.3048)
			(end -0.67945 0.3048)
			(stroke
				(width 0.1)
				(type default)
			)
			(layer "F.Fab")
		)
		(fp_line
			(start -0.12065 0.2794)
			(end -0.12065 0.3048)
			(stroke
				(width 0.1)
				(type default)
			)
			(layer "F.Fab")
		)
		(fp_line
			(start -0.12065 -0.2794)
			(end 0.12065 -0.2794)
			(stroke
				(width 0.1)
				(type default)
			)
			(layer "F.Fab")
		)
		(fp_line
			(start -0.12065 -0.305054)
			(end -0.12065 -0.2794)
			(stroke
				(width 0.1)
				(type default)
			)
			(layer "F.Fab")
		)
		(fp_line
			(start -0.67945 0.3048)
			(end -0.67945 -0.305054)
			(stroke
				(width 0.1)
				(type default)
			)
			(layer "F.Fab")
		)
		(fp_line
			(start -0.67945 -0.305054)
			(end -0.12065 -0.305054)
			(stroke
				(width 0.1)
				(type default)
			)
			(layer "F.Fab")
		)
		(pad "1" smd circle
			(at -0.40005 0 180)
			(size 0 0)
			(layers "F.Cu" "F.Mask" "F.Paste")
			(net "P3V3_AUX")
		)
		(pad "2" smd circle
			(at 0.40005 0 180)
			(size 0 0)
			(layers "F.Cu" "F.Mask" "F.Paste")
			(net "PWRGD_P12V_SSD5")
		)
	)
	(footprint ""
		(layer "F.Cu")
		(at 11.01979 -303.088802)
		(property "Reference" "PC210"
			(at 0 0 0)
			(layer "F.SilkS")
			(hide yes)
			(effects
				(font
					(size 1.27 1.27)
				)
			)
		)
		(property "Value" ""
			(at 0 0 0)
			(layer "F.Fab")
			(effects
				(font
					(size 1.27 1.27)
				)
			)
		)
		(duplicate_pad_numbers_are_jumpers no)
		(fp_line
			(start -0.7874 -0.4064)
			(end 0.7874 -0.4064)
			(stroke
				(width 0.1524)
				(type default)
			)
			(layer "F.SilkS")
		)
		(fp_line
			(start -0.7874 0.4064)
			(end -0.7874 -0.4064)
			(stroke
				(width 0.1524)
				(type default)
			)
			(layer "F.SilkS")
		)
		(fp_line
			(start 0.7874 -0.4064)
			(end 0.7874 0.4064)
			(stroke
				(width 0.1524)
				(type default)
			)
			(layer "F.SilkS")
		)
		(fp_line
			(start 0.7874 0.4064)
			(end -0.7874 0.4064)
			(stroke
				(width 0.1524)
				(type default)
			)
			(layer "F.SilkS")
		)
		(fp_line
			(start -0.67945 -0.305054)
			(end -0.12065 -0.305054)
			(stroke
				(width 0.1)
				(type default)
			)
			(layer "F.Fab")
		)
		(fp_line
			(start -0.67945 0.3048)
			(end -0.67945 -0.305054)
			(stroke
				(width 0.1)
				(type default)
			)
			(layer "F.Fab")
		)
		(fp_line
			(start -0.12065 -0.305054)
			(end -0.12065 -0.2794)
			(stroke
				(width 0.1)
				(type default)
			)
			(layer "F.Fab")
		)
		(fp_line
			(start -0.12065 -0.2794)
			(end 0.12065 -0.2794)
			(stroke
				(width 0.1)
				(type default)
			)
			(layer "F.Fab")
		)
		(fp_line
			(start -0.12065 0.2794)
			(end -0.12065 0.3048)
			(stroke
				(width 0.1)
				(type default)
			)
			(layer "F.Fab")
		)
		(fp_line
			(start -0.12065 0.3048)
			(end -0.67945 0.3048)
			(stroke
				(width 0.1)
				(type default)
			)
			(layer "F.Fab")
		)
		(fp_line
			(start 0.120396 0.2794)
			(end -0.12065 0.2794)
			(stroke
				(width 0.1)
				(type default)
			)
			(layer "F.Fab")
		)
		(fp_line
			(start 0.120396 0.3048)
			(end 0.120396 0.2794)
			(stroke
				(width 0.1)
				(type default)
			)
			(layer "F.Fab")
		)
		(fp_line
			(start 0.12065 -0.3048)
			(end 0.67945 -0.3048)
			(stroke
				(width 0.1)
				(type default)
			)
			(layer "F.Fab")
		)
		(fp_line
			(start 0.12065 -0.2794)
			(end 0.12065 -0.3048)
			(stroke
				(width 0.1)
				(type default)
			)
			(layer "F.Fab")
		)
		(fp_line
			(start 0.67945 -0.3048)
			(end 0.67945 0.3048)
			(stroke
				(width 0.1)
				(type default)
			)
			(layer "F.Fab")
		)
		(fp_line
			(start 0.67945 0.3048)
			(end 0.120396 0.3048)
			(stroke
				(width 0.1)
				(type default)
			)
			(layer "F.Fab")
		)
		(pad "1" smd circle
			(at -0.40005 0)
			(size 0 0)
			(layers "F.Cu" "F.Mask" "F.Paste")
			(net "SW_P12V_P1V25_PEX0_FLT")
		)
		(pad "2" smd circle
			(at 0.40005 0)
			(size 0 0)
			(layers "F.Cu" "F.Mask" "F.Paste")
			(net "GND")
		)
	)
	(footprint ""
		(layer "F.Cu")
		(at 129.06502 -26.785062 180)
		(property "Reference" "J34"
			(at 3.89255 -10.986262 90)
			(unlocked yes)
			(layer "F.SilkS")
			(effects
				(font
					(size 0.7874 0.5842)
					(thickness 0.1524)
				)
			)
		)
		(property "Value" ""
			(at 0 0 180)
			(layer "F.Fab")
			(effects
				(font
					(size 1.27 1.27)
				)
			)
		)
		(duplicate_pad_numbers_are_jumpers no)
		(fp_line
			(start 3.150108 12.115038)
			(end 1.529334 12.115038)
			(stroke
				(width 0.1524)
				(type default)
			)
			(layer "F.SilkS")
		)
		(fp_line
			(start 3.074924 12.014962)
			(end 1.632204 12.014962)
			(stroke
				(width 0.1524)
				(type default)
			)
			(layer "F.SilkS")
		)
		(fp_line
			(start 1.632204 -12.014962)
			(end 3.074924 -12.014962)
			(stroke
				(width 0.1524)
				(type default)
			)
			(layer "F.SilkS")
		)
		(fp_line
			(start 1.529334 -12.115038)
			(end 3.150108 -12.115038)
			(stroke
				(width 0.1524)
				(type default)
			)
			(layer "F.SilkS")
		)
		(fp_line
			(start -1.529334 12.115038)
			(end -3.150108 12.115038)
			(stroke
				(width 0.1524)
				(type default)
			)
			(layer "F.SilkS")
		)
		(fp_line
			(start -1.632204 12.014962)
			(end -3.074924 12.014962)
			(stroke
				(width 0.1524)
				(type default)
			)
			(layer "F.SilkS")
		)
		(fp_line
			(start -3.074924 -12.014962)
			(end -1.632204 -12.014962)
			(stroke
				(width 0.1524)
				(type default)
			)
			(layer "F.SilkS")
		)
		(fp_line
			(start -3.150108 -12.115038)
			(end -1.529334 -12.115038)
			(stroke
				(width 0.1524)
				(type default)
			)
			(layer "F.SilkS")
		)
		(fp_poly
			(pts
				(xy 4.00812 -8.835136) (xy 4.430522 -10.10285) (xy 5.27558 -9.257792)
			)
			(stroke
				(width 0)
				(type default)
			)
			(fill yes)
			(layer "F.SilkS")
		)
		(fp_line
			(start 3.074924 12.014962)
			(end -3.074924 12.014962)
			(stroke
				(width 0.1)
				(type default)
			)
			(layer "F.Fab")
		)
		(fp_line
			(start 3.074924 -12.014962)
			(end 3.074924 12.014962)
			(stroke
				(width 0.1)
				(type default)
			)
			(layer "F.Fab")
		)
		(fp_line
			(start -3.074924 12.014962)
			(end -3.074924 -12.014962)
			(stroke
				(width 0.1)
				(type default)
			)
			(layer "F.Fab")
		)
		(fp_line
			(start -3.074924 -12.014962)
			(end 3.074924 -12.014962)
			(stroke
				(width 0.1)
				(type default)
			)
			(layer "F.Fab")
		)
		(fp_poly
			(pts
				(xy 3.348736 -7.994904) (xy 4.543806 -8.592566) (xy 4.543806 -7.397496)
			)
			(stroke
				(width 0)
				(type default)
			)
			(fill yes)
			(layer "F.Fab")
		)
		(pad "" np_thru_hole circle
			(at -1.75006 -9.815068 90)
			(size 1.1176 1.1176)
			(drill 1.1176)
			(layers "*.Cu" "*.Mask")
			(clearance 0.381)
			(thermal_gap 0.381)
		)
		(pad "" np_thru_hole circle
			(at 0 9.815068 90)
			(size 1.1176 1.1176)
			(drill 1.1176)
			(layers "*.Cu" "*.Mask")
			(clearance 0.381)
			(thermal_gap 0.381)
		)
		(pad "A1" smd rect
			(at 2.29997 -7.994904 90)
			(size 0.381 1.27)
			(layers "F.Cu" "F.Mask" "F.Paste")
			(net "GND")
		)
		(pad "A2" smd rect
			(at 2.29997 -7.394956 90)
			(size 0.381 1.27)
			(layers "F.Cu" "F.Mask" "F.Paste")
			(net "GND")
		)
		(pad "A3" smd rect
			(at 2.29997 -6.795008 90)
			(size 0.381 1.27)
			(layers "F.Cu" "F.Mask" "F.Paste")
			(net "GND")
		)
		(pad "A4" smd rect
			(at 2.29997 -6.19506 90)
			(size 0.381 1.27)
			(layers "F.Cu" "F.Mask" "F.Paste")
			(net "GND")
		)
		(pad "A5" smd rect
			(at 2.29997 -5.595112 90)
			(size 0.381 1.27)
			(layers "F.Cu" "F.Mask" "F.Paste")
			(net "GND")
		)
		(pad "A6" smd rect
			(at 2.29997 -4.99491 90)
			(size 0.381 1.27)
			(layers "F.Cu" "F.Mask" "F.Paste")
			(net "GND")
		)
		(pad "A7" smd rect
			(at 2.29997 -4.394962 90)
			(size 0.381 1.27)
			(layers "F.Cu" "F.Mask" "F.Paste")
			(net "SMB_ISO_SSD4_R_SCL")
		)
		(pad "A8" smd rect
			(at 2.29997 -3.795014 90)
			(size 0.381 1.27)
			(layers "F.Cu" "F.Mask" "F.Paste")
			(net "SMB_ISO_SSD4_R_SDA")
		)
		(pad "A9" smd rect
			(at 2.29997 -3.195066 90)
			(size 0.381 1.27)
			(layers "F.Cu" "F.Mask" "F.Paste")
			(net "RST_SMB_SSD4_ISO_R_N")
		)
		(pad "A10" smd rect
			(at 2.29997 -2.595118 90)
			(size 0.381 1.27)
			(layers "F.Cu" "F.Mask" "F.Paste")
			(net "SSD4_LED_ISO_R_N")
		)
		(pad "A11" smd rect
			(at 2.29997 -1.994916 90)
			(size 0.381 1.27)
			(layers "F.Cu" "F.Mask" "F.Paste")
			(net "PU_CLKREQ4")
		)
		(pad "A12" smd rect
			(at 2.29997 -1.394968 90)
			(size 0.381 1.27)
			(layers "F.Cu" "F.Mask" "F.Paste")
			(net "PRSNT_SSD4_N")
		)
		(pad "A13" smd rect
			(at 2.29997 -0.79502 90)
			(size 0.381 1.27)
			(layers "F.Cu" "F.Mask" "F.Paste")
			(net "GND")
		)
		(pad "A14" smd rect
			(at 2.29997 -0.195072 90)
			(size 0.381 1.27)
			(layers "F.Cu" "F.Mask" "F.Paste")
			(net "Net_8525")
		)
		(pad "A15" smd rect
			(at 2.29997 0.404876 90)
			(size 0.381 1.27)
			(layers "F.Cu" "F.Mask" "F.Paste")
			(net "Net_8524")
		)
		(pad "A16" smd rect
			(at 2.29997 1.005078 90)
			(size 0.381 1.27)
			(layers "F.Cu" "F.Mask" "F.Paste")
			(net "GND")
		)
		(pad "A17" smd rect
			(at 2.29997 1.605026 90)
			(size 0.381 1.27)
			(layers "F.Cu" "F.Mask" "F.Paste")
			(net "P5E_PEX1_STN2_RX_DN<44>")
		)
		(pad "A18" smd rect
			(at 2.29997 2.204974 90)
			(size 0.381 1.27)
			(layers "F.Cu" "F.Mask" "F.Paste")
			(net "P5E_PEX1_STN2_RX_DP<44>")
		)
		(pad "A19" smd rect
			(at 2.29997 2.804922 90)
			(size 0.381 1.27)
			(layers "F.Cu" "F.Mask" "F.Paste")
			(net "GND")
		)
		(pad "A20" smd rect
			(at 2.29997 3.405124 90)
			(size 0.381 1.27)
			(layers "F.Cu" "F.Mask" "F.Paste")
			(net "P5E_PEX1_STN2_RX_DN<45>")
		)
		(pad "A21" smd rect
			(at 2.29997 4.005072 90)
			(size 0.381 1.27)
			(layers "F.Cu" "F.Mask" "F.Paste")
			(net "P5E_PEX1_STN2_RX_DP<45>")
		)
		(pad "A22" smd rect
			(at 2.29997 4.60502 90)
			(size 0.381 1.27)
			(layers "F.Cu" "F.Mask" "F.Paste")
			(net "GND")
		)
		(pad "A23" smd rect
			(at 2.29997 5.204968 90)
			(size 0.381 1.27)
			(layers "F.Cu" "F.Mask" "F.Paste")
			(net "P5E_PEX1_STN2_RX_DN<46>")
		)
		(pad "A24" smd rect
			(at 2.29997 5.804916 90)
			(size 0.381 1.27)
			(layers "F.Cu" "F.Mask" "F.Paste")
			(net "P5E_PEX1_STN2_RX_DP<46>")
		)
		(pad "A25" smd rect
			(at 2.29997 6.405118 90)
			(size 0.381 1.27)
			(layers "F.Cu" "F.Mask" "F.Paste")
			(net "GND")
		)
		(pad "A26" smd rect
			(at 2.29997 7.005066 90)
			(size 0.381 1.27)
			(layers "F.Cu" "F.Mask" "F.Paste")
			(net "P5E_PEX1_STN2_RX_DN<47>")
		)
		(pad "A27" smd rect
			(at 2.29997 7.605014 90)
			(size 0.381 1.27)
			(layers "F.Cu" "F.Mask" "F.Paste")
			(net "P5E_PEX1_STN2_RX_DP<47>")
		)
		(pad "A28" smd rect
			(at 2.29997 8.204962 90)
			(size 0.381 1.27)
			(layers "F.Cu" "F.Mask" "F.Paste")
			(net "GND")
		)
		(pad "B1" smd rect
			(at -2.29997 -7.994904 90)
			(size 0.381 1.27)
			(layers "F.Cu" "F.Mask" "F.Paste")
			(net "P12V_SSD4")
		)
		(pad "B2" smd rect
			(at -2.29997 -7.394956 90)
			(size 0.381 1.27)
			(layers "F.Cu" "F.Mask" "F.Paste")
			(net "P12V_SSD4")
		)
		(pad "B3" smd rect
			(at -2.29997 -6.795008 90)
			(size 0.381 1.27)
			(layers "F.Cu" "F.Mask" "F.Paste")
			(net "P12V_SSD4")
		)
		(pad "B4" smd rect
			(at -2.29997 -6.19506 90)
			(size 0.381 1.27)
			(layers "F.Cu" "F.Mask" "F.Paste")
			(net "P12V_SSD4")
		)
		(pad "B5" smd rect
			(at -2.29997 -5.595112 90)
			(size 0.381 1.27)
			(layers "F.Cu" "F.Mask" "F.Paste")
			(net "P12V_SSD4")
		)
		(pad "B6" smd rect
			(at -2.29997 -4.99491 90)
			(size 0.381 1.27)
			(layers "F.Cu" "F.Mask" "F.Paste")
			(net "P12V_SSD4")
		)
		(pad "B7" smd rect
			(at -2.29997 -4.394962 90)
			(size 0.381 1.27)
			(layers "F.Cu" "F.Mask" "F.Paste")
			(net "Net_8526")
		)
		(pad "B8" smd rect
			(at -2.29997 -3.795014 90)
			(size 0.381 1.27)
			(layers "F.Cu" "F.Mask" "F.Paste")
			(net "Net_8523")
		)
		(pad "B9" smd rect
			(at -2.29997 -3.195066 90)
			(size 0.381 1.27)
			(layers "F.Cu" "F.Mask" "F.Paste")
			(net "DUALPORT_N_SSD4")
		)
		(pad "B10" smd rect
			(at -2.29997 -2.595118 90)
			(size 0.381 1.27)
			(layers "F.Cu" "F.Mask" "F.Paste")
			(net "RST_SSD4_PERST_R_N")
		)
		(pad "B11" smd rect
			(at -2.29997 -1.994916 90)
			(size 0.381 1.27)
			(layers "F.Cu" "F.Mask" "F.Paste")
			(net "P3V3_SSD4")
		)
		(pad "B12" smd rect
			(at -2.29997 -1.394968 90)
			(size 0.381 1.27)
			(layers "F.Cu" "F.Mask" "F.Paste")
			(net "SSD4_PWRDIS_R")
		)
		(pad "B13" smd rect
			(at -2.29997 -0.79502 90)
			(size 0.381 1.27)
			(layers "F.Cu" "F.Mask" "F.Paste")
			(net "GND")
		)
		(pad "B14" smd rect
			(at -2.29997 -0.195072 90)
			(size 0.381 1.27)
			(layers "F.Cu" "F.Mask" "F.Paste")
			(net "CLK_100M_DB800ZL_SSD4_R_DN")
		)
		(pad "B15" smd rect
			(at -2.29997 0.404876 90)
			(size 0.381 1.27)
			(layers "F.Cu" "F.Mask" "F.Paste")
			(net "CLK_100M_DB800ZL_SSD4_R_DP")
		)
		(pad "B16" smd rect
			(at -2.29997 1.005078 90)
			(size 0.381 1.27)
			(layers "F.Cu" "F.Mask" "F.Paste")
			(net "GND")
		)
		(pad "B17" smd rect
			(at -2.29997 1.605026 90)
			(size 0.381 1.27)
			(layers "F.Cu" "F.Mask" "F.Paste")
			(net "P5E_PEX1_STN2_TX_C_DN<44>")
		)
		(pad "B18" smd rect
			(at -2.29997 2.204974 90)
			(size 0.381 1.27)
			(layers "F.Cu" "F.Mask" "F.Paste")
			(net "P5E_PEX1_STN2_TX_C_DP<44>")
		)
		(pad "B19" smd rect
			(at -2.29997 2.804922 90)
			(size 0.381 1.27)
			(layers "F.Cu" "F.Mask" "F.Paste")
			(net "GND")
		)
		(pad "B20" smd rect
			(at -2.29997 3.405124 90)
			(size 0.381 1.27)
			(layers "F.Cu" "F.Mask" "F.Paste")
			(net "P5E_PEX1_STN2_TX_C_DN<45>")
		)
		(pad "B21" smd rect
			(at -2.29997 4.005072 90)
			(size 0.381 1.27)
			(layers "F.Cu" "F.Mask" "F.Paste")
			(net "P5E_PEX1_STN2_TX_C_DP<45>")
		)
		(pad "B22" smd rect
			(at -2.29997 4.60502 90)
			(size 0.381 1.27)
			(layers "F.Cu" "F.Mask" "F.Paste")
			(net "GND")
		)
		(pad "B23" smd rect
			(at -2.29997 5.204968 90)
			(size 0.381 1.27)
			(layers "F.Cu" "F.Mask" "F.Paste")
			(net "P5E_PEX1_STN2_TX_C_DN<46>")
		)
		(pad "B24" smd rect
			(at -2.29997 5.804916 90)
			(size 0.381 1.27)
			(layers "F.Cu" "F.Mask" "F.Paste")
			(net "P5E_PEX1_STN2_TX_C_DP<46>")
		)
		(pad "B25" smd rect
			(at -2.29997 6.405118 90)
			(size 0.381 1.27)
			(layers "F.Cu" "F.Mask" "F.Paste")
			(net "GND")
		)
		(pad "B26" smd rect
			(at -2.29997 7.005066 90)
			(size 0.381 1.27)
			(layers "F.Cu" "F.Mask" "F.Paste")
			(net "P5E_PEX1_STN2_TX_C_DN<47>")
		)
		(pad "B27" smd rect
			(at -2.29997 7.605014 90)
			(size 0.381 1.27)
			(layers "F.Cu" "F.Mask" "F.Paste")
			(net "P5E_PEX1_STN2_TX_C_DP<47>")
		)
		(pad "B28" smd rect
			(at -2.29997 8.204962 90)
			(size 0.381 1.27)
			(layers "F.Cu" "F.Mask" "F.Paste")
			(net "GND")
		)
		(pad "G1" thru_hole oval
			(at 0 -11.364976 90)
			(size 1.6256 3.4798)
			(drill oval 1.1176 2.4638)
			(layers "*.Cu" "*.Mask")
			(remove_unused_layers no)
			(net "GND")
			(clearance 0.127)
			(thermal_gap 0.127)
		)
		(pad "G2" thru_hole oval
			(at 0 11.364976 90)
			(size 1.6256 3.4798)
			(drill oval 1.1176 2.4638)
			(layers "*.Cu" "*.Mask")
			(remove_unused_layers no)
			(net "GND")
			(clearance 0.127)
			(thermal_gap 0.127)
		)
		(zone
			(layer "F.Cu")
			(hatch none 0.5)
			(connect_pads
				(clearance 0)
			)
			(min_thickness 0.25)
			(keepout
				(tracks not_allowed)
				(vias allowed)
				(pads allowed)
				(copperpour not_allowed)
				(footprints allowed)
			)
			(placement
				(enabled no)
				(sheetname "")
			)
			(fill
				(thermal_gap 0.5)
				(thermal_bridge_width 0.5)
				(island_removal_mode 0)
			)
			(polygon
				(pts
					(xy 130.445002 -38.850062) (xy 127.694944 -38.850062) (xy 127.694944 -35.900106) (xy 130.445002 -35.900106)
				)
			)
		)
		(zone
			(layer "F.Cu")
			(hatch none 0.5)
			(connect_pads
				(clearance 0)
			)
			(min_thickness 0.25)
			(keepout
				(tracks not_allowed)
				(vias allowed)
				(pads allowed)
				(copperpour not_allowed)
				(footprints allowed)
			)
			(placement
				(enabled no)
				(sheetname "")
			)
			(fill
				(thermal_gap 0.5)
				(thermal_bridge_width 0.5)
				(island_removal_mode 0)
			)
			(polygon
				(pts
					(xy 131.515104 -17.670018) (xy 127.685038 -17.670018) (xy 127.685038 -14.720062) (xy 131.515104 -14.720062)
				)
			)
		)
		(zone
			(layers "F.Cu" "B.Cu" "In1.Cu" "In2.Cu" "In3.Cu" "In4.Cu" "In5.Cu" "In6.Cu"
				"In7.Cu" "In8.Cu" "In9.Cu" "In10.Cu" "In11.Cu" "In12.Cu" "In13.Cu" "In14.Cu"
				"In15.Cu" "In16.Cu"
			)
			(hatch none 0.5)
			(connect_pads
				(clearance 0)
			)
			(min_thickness 0.25)
			(keepout
				(tracks not_allowed)
				(vias allowed)
				(pads allowed)
				(copperpour not_allowed)
				(footprints allowed)
			)
			(placement
				(enabled no)
				(sheetname "")
			)
			(fill
				(thermal_gap 0.5)
				(thermal_bridge_width 0.5)
				(island_removal_mode 0)
			)
			(polygon
				(pts
					(arc
						(start 130.03022 -36.60013)
						(mid 128.09982 -36.60013)
						(end 130.03022 -36.60013)
					)
				)
			)
		)
		(zone
			(layers "F.Cu" "B.Cu" "In1.Cu" "In2.Cu" "In3.Cu" "In4.Cu" "In5.Cu" "In6.Cu"
				"In7.Cu" "In8.Cu" "In9.Cu" "In10.Cu" "In11.Cu" "In12.Cu" "In13.Cu" "In14.Cu"
				"In15.Cu" "In16.Cu"
			)
			(hatch none 0.5)
			(connect_pads
				(clearance 0)
			)
			(min_thickness 0.25)
			(keepout
				(tracks not_allowed)
				(vias allowed)
				(pads allowed)
				(copperpour not_allowed)
				(footprints allowed)
			)
			(placement
				(enabled no)
				(sheetname "")
			)
			(fill
				(thermal_gap 0.5)
				(thermal_bridge_width 0.5)
				(island_removal_mode 0)
			)
			(polygon
				(pts
					(arc
						(start 131.78028 -16.969994)
						(mid 129.84988 -16.969994)
						(end 131.78028 -16.969994)
					)
				)
			)
		)
	)
	(footprint ""
		(layer "F.Cu")
		(at 338.074 -181.991 180)
		(property "Reference" "R4750"
			(at 0 0 180)
			(layer "F.SilkS")
			(hide yes)
			(effects
				(font
					(size 1.27 1.27)
				)
			)
		)
		(property "Value" ""
			(at 0 0 180)
			(layer "F.Fab")
			(effects
				(font
					(size 1.27 1.27)
				)
			)
		)
		(duplicate_pad_numbers_are_jumpers no)
		(fp_line
			(start 0.7874 0.4064)
			(end -0.7874 0.4064)
			(stroke
				(width 0.1524)
				(type default)
			)
			(layer "F.SilkS")
		)
		(fp_line
			(start 0.7874 -0.4064)
			(end 0.7874 0.4064)
			(stroke
				(width 0.1524)
				(type default)
			)
			(layer "F.SilkS")
		)
		(fp_line
			(start -0.7874 0.4064)
			(end -0.7874 -0.4064)
			(stroke
				(width 0.1524)
				(type default)
			)
			(layer "F.SilkS")
		)
		(fp_line
			(start -0.7874 -0.4064)
			(end 0.7874 -0.4064)
			(stroke
				(width 0.1524)
				(type default)
			)
			(layer "F.SilkS")
		)
		(fp_line
			(start 0.67945 0.3048)
			(end 0.120396 0.3048)
			(stroke
				(width 0.1)
				(type default)
			)
			(layer "F.Fab")
		)
		(fp_line
			(start 0.67945 -0.3048)
			(end 0.67945 0.3048)
			(stroke
				(width 0.1)
				(type default)
			)
			(layer "F.Fab")
		)
		(fp_line
			(start 0.12065 -0.2794)
			(end 0.12065 -0.3048)
			(stroke
				(width 0.1)
				(type default)
			)
			(layer "F.Fab")
		)
		(fp_line
			(start 0.12065 -0.3048)
			(end 0.67945 -0.3048)
			(stroke
				(width 0.1)
				(type default)
			)
			(layer "F.Fab")
		)
		(fp_line
			(start 0.120396 0.3048)
			(end 0.120396 0.2794)
			(stroke
				(width 0.1)
				(type default)
			)
			(layer "F.Fab")
		)
		(fp_line
			(start 0.120396 0.2794)
			(end -0.12065 0.2794)
			(stroke
				(width 0.1)
				(type default)
			)
			(layer "F.Fab")
		)
		(fp_line
			(start -0.12065 0.3048)
			(end -0.67945 0.3048)
			(stroke
				(width 0.1)
				(type default)
			)
			(layer "F.Fab")
		)
		(fp_line
			(start -0.12065 0.2794)
			(end -0.12065 0.3048)
			(stroke
				(width 0.1)
				(type default)
			)
			(layer "F.Fab")
		)
		(fp_line
			(start -0.12065 -0.2794)
			(end 0.12065 -0.2794)
			(stroke
				(width 0.1)
				(type default)
			)
			(layer "F.Fab")
		)
		(fp_line
			(start -0.12065 -0.305054)
			(end -0.12065 -0.2794)
			(stroke
				(width 0.1)
				(type default)
			)
			(layer "F.Fab")
		)
		(fp_line
			(start -0.67945 0.3048)
			(end -0.67945 -0.305054)
			(stroke
				(width 0.1)
				(type default)
			)
			(layer "F.Fab")
		)
		(fp_line
			(start -0.67945 -0.305054)
			(end -0.12065 -0.305054)
			(stroke
				(width 0.1)
				(type default)
			)
			(layer "F.Fab")
		)
		(pad "1" smd circle
			(at -0.40005 0 180)
			(size 0 0)
			(layers "F.Cu" "F.Mask" "F.Paste")
			(net "SSD8_PEX_PWR_EN")
		)
		(pad "2" smd circle
			(at 0.40005 0 180)
			(size 0 0)
			(layers "F.Cu" "F.Mask" "F.Paste")
			(net "SSD8_PEX_PWR_EN_R")
		)
	)
	(footprint ""
		(layer "F.Cu")
		(at 444.226442 -25.432004 -90)
		(property "Reference" "C980"
			(at 0 0 270)
			(layer "F.SilkS")
			(hide yes)
			(effects
				(font
					(size 1.27 1.27)
				)
			)
		)
		(property "Value" ""
			(at 0 0 270)
			(layer "F.Fab")
			(effects
				(font
					(size 1.27 1.27)
				)
			)
		)
		(duplicate_pad_numbers_are_jumpers no)
		(fp_line
			(start -0.7874 0.4064)
			(end -0.7874 -0.4064)
			(stroke
				(width 0.1524)
				(type default)
			)
			(layer "F.SilkS")
		)
		(fp_line
			(start 0.7874 0.4064)
			(end -0.7874 0.4064)
			(stroke
				(width 0.1524)
				(type default)
			)
			(layer "F.SilkS")
		)
		(fp_line
			(start -0.7874 -0.4064)
			(end 0.7874 -0.4064)
			(stroke
				(width 0.1524)
				(type default)
			)
			(layer "F.SilkS")
		)
		(fp_line
			(start 0.7874 -0.4064)
			(end 0.7874 0.4064)
			(stroke
				(width 0.1524)
				(type default)
			)
			(layer "F.SilkS")
		)
		(fp_line
			(start -0.67945 0.3048)
			(end -0.67945 -0.305054)
			(stroke
				(width 0.1)
				(type default)
			)
			(layer "F.Fab")
		)
		(fp_line
			(start -0.12065 0.3048)
			(end -0.67945 0.3048)
			(stroke
				(width 0.1)
				(type default)
			)
			(layer "F.Fab")
		)
		(fp_line
			(start 0.120396 0.3048)
			(end 0.120396 0.2794)
			(stroke
				(width 0.1)
				(type default)
			)
			(layer "F.Fab")
		)
		(fp_line
			(start 0.67945 0.3048)
			(end 0.120396 0.3048)
			(stroke
				(width 0.1)
				(type default)
			)
			(layer "F.Fab")
		)
		(fp_line
			(start -0.12065 0.2794)
			(end -0.12065 0.3048)
			(stroke
				(width 0.1)
				(type default)
			)
			(layer "F.Fab")
		)
		(fp_line
			(start 0.120396 0.2794)
			(end -0.12065 0.2794)
			(stroke
				(width 0.1)
				(type default)
			)
			(layer "F.Fab")
		)
		(fp_line
			(start -0.12065 -0.2794)
			(end 0.12065 -0.2794)
			(stroke
				(width 0.1)
				(type default)
			)
			(layer "F.Fab")
		)
		(fp_line
			(start 0.12065 -0.2794)
			(end 0.12065 -0.3048)
			(stroke
				(width 0.1)
				(type default)
			)
			(layer "F.Fab")
		)
		(fp_line
			(start 0.12065 -0.3048)
			(end 0.67945 -0.3048)
			(stroke
				(width 0.1)
				(type default)
			)
			(layer "F.Fab")
		)
		(fp_line
			(start 0.67945 -0.3048)
			(end 0.67945 0.3048)
			(stroke
				(width 0.1)
				(type default)
			)
			(layer "F.Fab")
		)
		(fp_line
			(start -0.67945 -0.305054)
			(end -0.12065 -0.305054)
			(stroke
				(width 0.1)
				(type default)
			)
			(layer "F.Fab")
		)
		(fp_line
			(start -0.12065 -0.305054)
			(end -0.12065 -0.2794)
			(stroke
				(width 0.1)
				(type default)
			)
			(layer "F.Fab")
		)
		(pad "1" smd circle
			(at -0.40005 0 270)
			(size 0 0)
			(layers "F.Cu" "F.Mask" "F.Paste")
			(net "GND")
		)
		(pad "2" smd circle
			(at 0.40005 0 270)
			(size 0 0)
			(layers "F.Cu" "F.Mask" "F.Paste")
			(net "P3V3_SSD15")
		)
	)
	(footprint ""
		(layer "F.Cu")
		(at 210.439 -194.691)
		(property "Reference" "C2628"
			(at 0 0 0)
			(layer "F.SilkS")
			(hide yes)
			(effects
				(font
					(size 1.27 1.27)
				)
			)
		)
		(property "Value" ""
			(at 0 0 0)
			(layer "F.Fab")
			(effects
				(font
					(size 1.27 1.27)
				)
			)
		)
		(duplicate_pad_numbers_are_jumpers no)
		(fp_line
			(start -0.7874 -0.4064)
			(end 0.7874 -0.4064)
			(stroke
				(width 0.1524)
				(type default)
			)
			(layer "F.SilkS")
		)
		(fp_line
			(start -0.7874 0.4064)
			(end -0.7874 -0.4064)
			(stroke
				(width 0.1524)
				(type default)
			)
			(layer "F.SilkS")
		)
		(fp_line
			(start 0.7874 -0.4064)
			(end 0.7874 0.4064)
			(stroke
				(width 0.1524)
				(type default)
			)
			(layer "F.SilkS")
		)
		(fp_line
			(start 0.7874 0.4064)
			(end -0.7874 0.4064)
			(stroke
				(width 0.1524)
				(type default)
			)
			(layer "F.SilkS")
		)
		(fp_line
			(start -0.67945 -0.305054)
			(end -0.12065 -0.305054)
			(stroke
				(width 0.1)
				(type default)
			)
			(layer "F.Fab")
		)
		(fp_line
			(start -0.67945 0.3048)
			(end -0.67945 -0.305054)
			(stroke
				(width 0.1)
				(type default)
			)
			(layer "F.Fab")
		)
		(fp_line
			(start -0.12065 -0.305054)
			(end -0.12065 -0.2794)
			(stroke
				(width 0.1)
				(type default)
			)
			(layer "F.Fab")
		)
		(fp_line
			(start -0.12065 -0.2794)
			(end 0.12065 -0.2794)
			(stroke
				(width 0.1)
				(type default)
			)
			(layer "F.Fab")
		)
		(fp_line
			(start -0.12065 0.2794)
			(end -0.12065 0.3048)
			(stroke
				(width 0.1)
				(type default)
			)
			(layer "F.Fab")
		)
		(fp_line
			(start -0.12065 0.3048)
			(end -0.67945 0.3048)
			(stroke
				(width 0.1)
				(type default)
			)
			(layer "F.Fab")
		)
		(fp_line
			(start 0.120396 0.2794)
			(end -0.12065 0.2794)
			(stroke
				(width 0.1)
				(type default)
			)
			(layer "F.Fab")
		)
		(fp_line
			(start 0.120396 0.3048)
			(end 0.120396 0.2794)
			(stroke
				(width 0.1)
				(type default)
			)
			(layer "F.Fab")
		)
		(fp_line
			(start 0.12065 -0.3048)
			(end 0.67945 -0.3048)
			(stroke
				(width 0.1)
				(type default)
			)
			(layer "F.Fab")
		)
		(fp_line
			(start 0.12065 -0.2794)
			(end 0.12065 -0.3048)
			(stroke
				(width 0.1)
				(type default)
			)
			(layer "F.Fab")
		)
		(fp_line
			(start 0.67945 -0.3048)
			(end 0.67945 0.3048)
			(stroke
				(width 0.1)
				(type default)
			)
			(layer "F.Fab")
		)
		(fp_line
			(start 0.67945 0.3048)
			(end 0.120396 0.3048)
			(stroke
				(width 0.1)
				(type default)
			)
			(layer "F.Fab")
		)
		(pad "1" smd circle
			(at -0.40005 0)
			(size 0 0)
			(layers "F.Cu" "F.Mask" "F.Paste")
			(net "GND")
		)
		(pad "2" smd circle
			(at 0.40005 0)
			(size 0 0)
			(layers "F.Cu" "F.Mask" "F.Paste")
			(net "P1V2_AUX")
		)
	)
	(footprint ""
		(layer "F.Cu")
		(at 24.482044 -38.041072 180)
		(property "Reference" "R5873"
			(at 0 0 180)
			(layer "F.SilkS")
			(hide yes)
			(effects
				(font
					(size 1.27 1.27)
				)
			)
		)
		(property "Value" ""
			(at 0 0 180)
			(layer "F.Fab")
			(effects
				(font
					(size 1.27 1.27)
				)
			)
		)
		(duplicate_pad_numbers_are_jumpers no)
		(fp_line
			(start 0.7874 0.4064)
			(end -0.7874 0.4064)
			(stroke
				(width 0.1524)
				(type default)
			)
			(layer "F.SilkS")
		)
		(fp_line
			(start 0.7874 -0.4064)
			(end 0.7874 0.4064)
			(stroke
				(width 0.1524)
				(type default)
			)
			(layer "F.SilkS")
		)
		(fp_line
			(start -0.7874 0.4064)
			(end -0.7874 -0.4064)
			(stroke
				(width 0.1524)
				(type default)
			)
			(layer "F.SilkS")
		)
		(fp_line
			(start -0.7874 -0.4064)
			(end 0.7874 -0.4064)
			(stroke
				(width 0.1524)
				(type default)
			)
			(layer "F.SilkS")
		)
		(fp_line
			(start 0.67945 0.3048)
			(end 0.120396 0.3048)
			(stroke
				(width 0.1)
				(type default)
			)
			(layer "F.Fab")
		)
		(fp_line
			(start 0.67945 -0.3048)
			(end 0.67945 0.3048)
			(stroke
				(width 0.1)
				(type default)
			)
			(layer "F.Fab")
		)
		(fp_line
			(start 0.12065 -0.2794)
			(end 0.12065 -0.3048)
			(stroke
				(width 0.1)
				(type default)
			)
			(layer "F.Fab")
		)
		(fp_line
			(start 0.12065 -0.3048)
			(end 0.67945 -0.3048)
			(stroke
				(width 0.1)
				(type default)
			)
			(layer "F.Fab")
		)
		(fp_line
			(start 0.120396 0.3048)
			(end 0.120396 0.2794)
			(stroke
				(width 0.1)
				(type default)
			)
			(layer "F.Fab")
		)
		(fp_line
			(start 0.120396 0.2794)
			(end -0.12065 0.2794)
			(stroke
				(width 0.1)
				(type default)
			)
			(layer "F.Fab")
		)
		(fp_line
			(start -0.12065 0.3048)
			(end -0.67945 0.3048)
			(stroke
				(width 0.1)
				(type default)
			)
			(layer "F.Fab")
		)
		(fp_line
			(start -0.12065 0.2794)
			(end -0.12065 0.3048)
			(stroke
				(width 0.1)
				(type default)
			)
			(layer "F.Fab")
		)
		(fp_line
			(start -0.12065 -0.2794)
			(end 0.12065 -0.2794)
			(stroke
				(width 0.1)
				(type default)
			)
			(layer "F.Fab")
		)
		(fp_line
			(start -0.12065 -0.305054)
			(end -0.12065 -0.2794)
			(stroke
				(width 0.1)
				(type default)
			)
			(layer "F.Fab")
		)
		(fp_line
			(start -0.67945 0.3048)
			(end -0.67945 -0.305054)
			(stroke
				(width 0.1)
				(type default)
			)
			(layer "F.Fab")
		)
		(fp_line
			(start -0.67945 -0.305054)
			(end -0.12065 -0.305054)
			(stroke
				(width 0.1)
				(type default)
			)
			(layer "F.Fab")
		)
		(pad "1" smd circle
			(at -0.40005 0 180)
			(size 0 0)
			(layers "F.Cu" "F.Mask" "F.Paste")
			(net "P5V_AUX")
		)
		(pad "2" smd circle
			(at 0.40005 0 180)
			(size 0 0)
			(layers "F.Cu" "F.Mask" "F.Paste")
			(net "P3V3_SSD1_PG_G2")
		)
	)
	(footprint ""
		(layer "F.Cu")
		(at 291.194998 -99.750372 180)
		(property "Reference" "R283"
			(at 0 0 180)
			(layer "F.SilkS")
			(hide yes)
			(effects
				(font
					(size 1.27 1.27)
				)
			)
		)
		(property "Value" ""
			(at 0 0 180)
			(layer "F.Fab")
			(effects
				(font
					(size 1.27 1.27)
				)
			)
		)
		(duplicate_pad_numbers_are_jumpers no)
		(fp_line
			(start 0.7874 0.4064)
			(end -0.7874 0.4064)
			(stroke
				(width 0.1524)
				(type default)
			)
			(layer "F.SilkS")
		)
		(fp_line
			(start 0.7874 -0.4064)
			(end 0.7874 0.4064)
			(stroke
				(width 0.1524)
				(type default)
			)
			(layer "F.SilkS")
		)
		(fp_line
			(start -0.7874 0.4064)
			(end -0.7874 -0.4064)
			(stroke
				(width 0.1524)
				(type default)
			)
			(layer "F.SilkS")
		)
		(fp_line
			(start -0.7874 -0.4064)
			(end 0.7874 -0.4064)
			(stroke
				(width 0.1524)
				(type default)
			)
			(layer "F.SilkS")
		)
		(fp_line
			(start 0.67945 0.3048)
			(end 0.120396 0.3048)
			(stroke
				(width 0.1)
				(type default)
			)
			(layer "F.Fab")
		)
		(fp_line
			(start 0.67945 -0.3048)
			(end 0.67945 0.3048)
			(stroke
				(width 0.1)
				(type default)
			)
			(layer "F.Fab")
		)
		(fp_line
			(start 0.12065 -0.2794)
			(end 0.12065 -0.3048)
			(stroke
				(width 0.1)
				(type default)
			)
			(layer "F.Fab")
		)
		(fp_line
			(start 0.12065 -0.3048)
			(end 0.67945 -0.3048)
			(stroke
				(width 0.1)
				(type default)
			)
			(layer "F.Fab")
		)
		(fp_line
			(start 0.120396 0.3048)
			(end 0.120396 0.2794)
			(stroke
				(width 0.1)
				(type default)
			)
			(layer "F.Fab")
		)
		(fp_line
			(start 0.120396 0.2794)
			(end -0.12065 0.2794)
			(stroke
				(width 0.1)
				(type default)
			)
			(layer "F.Fab")
		)
		(fp_line
			(start -0.12065 0.3048)
			(end -0.67945 0.3048)
			(stroke
				(width 0.1)
				(type default)
			)
			(layer "F.Fab")
		)
		(fp_line
			(start -0.12065 0.2794)
			(end -0.12065 0.3048)
			(stroke
				(width 0.1)
				(type default)
			)
			(layer "F.Fab")
		)
		(fp_line
			(start -0.12065 -0.2794)
			(end 0.12065 -0.2794)
			(stroke
				(width 0.1)
				(type default)
			)
			(layer "F.Fab")
		)
		(fp_line
			(start -0.12065 -0.305054)
			(end -0.12065 -0.2794)
			(stroke
				(width 0.1)
				(type default)
			)
			(layer "F.Fab")
		)
		(fp_line
			(start -0.67945 0.3048)
			(end -0.67945 -0.305054)
			(stroke
				(width 0.1)
				(type default)
			)
			(layer "F.Fab")
		)
		(fp_line
			(start -0.67945 -0.305054)
			(end -0.12065 -0.305054)
			(stroke
				(width 0.1)
				(type default)
			)
			(layer "F.Fab")
		)
		(pad "1" smd circle
			(at -0.40005 0 180)
			(size 0 0)
			(layers "F.Cu" "F.Mask" "F.Paste")
			(net "NIC5_SLOT_ID1")
		)
		(pad "2" smd circle
			(at 0.40005 0 180)
			(size 0 0)
			(layers "F.Cu" "F.Mask" "F.Paste")
			(net "GND")
		)
	)
	(footprint ""
		(layer "F.Cu")
		(at 94.494096 -115.394486)
		(property "Reference" "PR6918"
			(at 0 0 0)
			(layer "F.SilkS")
			(hide yes)
			(effects
				(font
					(size 1.27 1.27)
				)
			)
		)
		(property "Value" ""
			(at 0 0 0)
			(layer "F.Fab")
			(effects
				(font
					(size 1.27 1.27)
				)
			)
		)
		(duplicate_pad_numbers_are_jumpers no)
		(fp_line
			(start -0.7874 -0.4064)
			(end 0.7874 -0.4064)
			(stroke
				(width 0.1524)
				(type default)
			)
			(layer "F.SilkS")
		)
		(fp_line
			(start -0.7874 0.4064)
			(end -0.7874 -0.4064)
			(stroke
				(width 0.1524)
				(type default)
			)
			(layer "F.SilkS")
		)
		(fp_line
			(start 0.7874 -0.4064)
			(end 0.7874 0.4064)
			(stroke
				(width 0.1524)
				(type default)
			)
			(layer "F.SilkS")
		)
		(fp_line
			(start 0.7874 0.4064)
			(end -0.7874 0.4064)
			(stroke
				(width 0.1524)
				(type default)
			)
			(layer "F.SilkS")
		)
		(fp_line
			(start -0.67945 -0.305054)
			(end -0.12065 -0.305054)
			(stroke
				(width 0.1)
				(type default)
			)
			(layer "F.Fab")
		)
		(fp_line
			(start -0.67945 0.3048)
			(end -0.67945 -0.305054)
			(stroke
				(width 0.1)
				(type default)
			)
			(layer "F.Fab")
		)
		(fp_line
			(start -0.12065 -0.305054)
			(end -0.12065 -0.2794)
			(stroke
				(width 0.1)
				(type default)
			)
			(layer "F.Fab")
		)
		(fp_line
			(start -0.12065 -0.2794)
			(end 0.12065 -0.2794)
			(stroke
				(width 0.1)
				(type default)
			)
			(layer "F.Fab")
		)
		(fp_line
			(start -0.12065 0.2794)
			(end -0.12065 0.3048)
			(stroke
				(width 0.1)
				(type default)
			)
			(layer "F.Fab")
		)
		(fp_line
			(start -0.12065 0.3048)
			(end -0.67945 0.3048)
			(stroke
				(width 0.1)
				(type default)
			)
			(layer "F.Fab")
		)
		(fp_line
			(start 0.120396 0.2794)
			(end -0.12065 0.2794)
			(stroke
				(width 0.1)
				(type default)
			)
			(layer "F.Fab")
		)
		(fp_line
			(start 0.120396 0.3048)
			(end 0.120396 0.2794)
			(stroke
				(width 0.1)
				(type default)
			)
			(layer "F.Fab")
		)
		(fp_line
			(start 0.12065 -0.3048)
			(end 0.67945 -0.3048)
			(stroke
				(width 0.1)
				(type default)
			)
			(layer "F.Fab")
		)
		(fp_line
			(start 0.12065 -0.2794)
			(end 0.12065 -0.3048)
			(stroke
				(width 0.1)
				(type default)
			)
			(layer "F.Fab")
		)
		(fp_line
			(start 0.67945 -0.3048)
			(end 0.67945 0.3048)
			(stroke
				(width 0.1)
				(type default)
			)
			(layer "F.Fab")
		)
		(fp_line
			(start 0.67945 0.3048)
			(end 0.120396 0.3048)
			(stroke
				(width 0.1)
				(type default)
			)
			(layer "F.Fab")
		)
		(pad "1" smd circle
			(at -0.40005 0)
			(size 0 0)
			(layers "F.Cu" "F.Mask" "F.Paste")
			(net "P3V3_NIC1_CO_ILIMIT")
		)
		(pad "2" smd circle
			(at 0.40005 0)
			(size 0 0)
			(layers "F.Cu" "F.Mask" "F.Paste")
			(net "GND")
		)
	)
	(footprint ""
		(layer "F.Cu")
		(at 326.012556 -198.266304 180)
		(property "Reference" "R4235"
			(at 0 0 180)
			(layer "F.SilkS")
			(hide yes)
			(effects
				(font
					(size 1.27 1.27)
				)
			)
		)
		(property "Value" ""
			(at 0 0 180)
			(layer "F.Fab")
			(effects
				(font
					(size 1.27 1.27)
				)
			)
		)
		(duplicate_pad_numbers_are_jumpers no)
		(fp_line
			(start 0.7874 0.4064)
			(end -0.7874 0.4064)
			(stroke
				(width 0.1524)
				(type default)
			)
			(layer "F.SilkS")
		)
		(fp_line
			(start 0.7874 -0.4064)
			(end 0.7874 0.4064)
			(stroke
				(width 0.1524)
				(type default)
			)
			(layer "F.SilkS")
		)
		(fp_line
			(start -0.7874 0.4064)
			(end -0.7874 -0.4064)
			(stroke
				(width 0.1524)
				(type default)
			)
			(layer "F.SilkS")
		)
		(fp_line
			(start -0.7874 -0.4064)
			(end 0.7874 -0.4064)
			(stroke
				(width 0.1524)
				(type default)
			)
			(layer "F.SilkS")
		)
		(fp_line
			(start 0.67945 0.3048)
			(end 0.120396 0.3048)
			(stroke
				(width 0.1)
				(type default)
			)
			(layer "F.Fab")
		)
		(fp_line
			(start 0.67945 -0.3048)
			(end 0.67945 0.3048)
			(stroke
				(width 0.1)
				(type default)
			)
			(layer "F.Fab")
		)
		(fp_line
			(start 0.12065 -0.2794)
			(end 0.12065 -0.3048)
			(stroke
				(width 0.1)
				(type default)
			)
			(layer "F.Fab")
		)
		(fp_line
			(start 0.12065 -0.3048)
			(end 0.67945 -0.3048)
			(stroke
				(width 0.1)
				(type default)
			)
			(layer "F.Fab")
		)
		(fp_line
			(start 0.120396 0.3048)
			(end 0.120396 0.2794)
			(stroke
				(width 0.1)
				(type default)
			)
			(layer "F.Fab")
		)
		(fp_line
			(start 0.120396 0.2794)
			(end -0.12065 0.2794)
			(stroke
				(width 0.1)
				(type default)
			)
			(layer "F.Fab")
		)
		(fp_line
			(start -0.12065 0.3048)
			(end -0.67945 0.3048)
			(stroke
				(width 0.1)
				(type default)
			)
			(layer "F.Fab")
		)
		(fp_line
			(start -0.12065 0.2794)
			(end -0.12065 0.3048)
			(stroke
				(width 0.1)
				(type default)
			)
			(layer "F.Fab")
		)
		(fp_line
			(start -0.12065 -0.2794)
			(end 0.12065 -0.2794)
			(stroke
				(width 0.1)
				(type default)
			)
			(layer "F.Fab")
		)
		(fp_line
			(start -0.12065 -0.305054)
			(end -0.12065 -0.2794)
			(stroke
				(width 0.1)
				(type default)
			)
			(layer "F.Fab")
		)
		(fp_line
			(start -0.67945 0.3048)
			(end -0.67945 -0.305054)
			(stroke
				(width 0.1)
				(type default)
			)
			(layer "F.Fab")
		)
		(fp_line
			(start -0.67945 -0.305054)
			(end -0.12065 -0.305054)
			(stroke
				(width 0.1)
				(type default)
			)
			(layer "F.Fab")
		)
		(pad "1" smd circle
			(at -0.40005 0 180)
			(size 0 0)
			(layers "F.Cu" "F.Mask" "F.Paste")
			(net "IOEXP_DBV2_A1")
		)
		(pad "2" smd circle
			(at 0.40005 0 180)
			(size 0 0)
			(layers "F.Cu" "F.Mask" "F.Paste")
			(net "P3V3_AUX")
		)
	)
	(footprint ""
		(layer "F.Cu")
		(at 221.990158 -84.675472)
		(property "Reference" "R5769"
			(at 0 0 0)
			(layer "F.SilkS")
			(hide yes)
			(effects
				(font
					(size 1.27 1.27)
				)
			)
		)
		(property "Value" ""
			(at 0 0 0)
			(layer "F.Fab")
			(effects
				(font
					(size 1.27 1.27)
				)
			)
		)
		(duplicate_pad_numbers_are_jumpers no)
		(fp_line
			(start -0.7874 -0.4064)
			(end 0.7874 -0.4064)
			(stroke
				(width 0.1524)
				(type default)
			)
			(layer "F.SilkS")
		)
		(fp_line
			(start -0.7874 0.4064)
			(end -0.7874 -0.4064)
			(stroke
				(width 0.1524)
				(type default)
			)
			(layer "F.SilkS")
		)
		(fp_line
			(start 0.7874 -0.4064)
			(end 0.7874 0.4064)
			(stroke
				(width 0.1524)
				(type default)
			)
			(layer "F.SilkS")
		)
		(fp_line
			(start 0.7874 0.4064)
			(end -0.7874 0.4064)
			(stroke
				(width 0.1524)
				(type default)
			)
			(layer "F.SilkS")
		)
		(fp_line
			(start -0.67945 -0.305054)
			(end -0.12065 -0.305054)
			(stroke
				(width 0.1)
				(type default)
			)
			(layer "F.Fab")
		)
		(fp_line
			(start -0.67945 0.3048)
			(end -0.67945 -0.305054)
			(stroke
				(width 0.1)
				(type default)
			)
			(layer "F.Fab")
		)
		(fp_line
			(start -0.12065 -0.305054)
			(end -0.12065 -0.2794)
			(stroke
				(width 0.1)
				(type default)
			)
			(layer "F.Fab")
		)
		(fp_line
			(start -0.12065 -0.2794)
			(end 0.12065 -0.2794)
			(stroke
				(width 0.1)
				(type default)
			)
			(layer "F.Fab")
		)
		(fp_line
			(start -0.12065 0.2794)
			(end -0.12065 0.3048)
			(stroke
				(width 0.1)
				(type default)
			)
			(layer "F.Fab")
		)
		(fp_line
			(start -0.12065 0.3048)
			(end -0.67945 0.3048)
			(stroke
				(width 0.1)
				(type default)
			)
			(layer "F.Fab")
		)
		(fp_line
			(start 0.120396 0.2794)
			(end -0.12065 0.2794)
			(stroke
				(width 0.1)
				(type default)
			)
			(layer "F.Fab")
		)
		(fp_line
			(start 0.120396 0.3048)
			(end 0.120396 0.2794)
			(stroke
				(width 0.1)
				(type default)
			)
			(layer "F.Fab")
		)
		(fp_line
			(start 0.12065 -0.3048)
			(end 0.67945 -0.3048)
			(stroke
				(width 0.1)
				(type default)
			)
			(layer "F.Fab")
		)
		(fp_line
			(start 0.12065 -0.2794)
			(end 0.12065 -0.3048)
			(stroke
				(width 0.1)
				(type default)
			)
			(layer "F.Fab")
		)
		(fp_line
			(start 0.67945 -0.3048)
			(end 0.67945 0.3048)
			(stroke
				(width 0.1)
				(type default)
			)
			(layer "F.Fab")
		)
		(fp_line
			(start 0.67945 0.3048)
			(end 0.120396 0.3048)
			(stroke
				(width 0.1)
				(type default)
			)
			(layer "F.Fab")
		)
		(pad "1" smd circle
			(at -0.40005 0)
			(size 0 0)
			(layers "F.Cu" "F.Mask" "F.Paste")
			(net "SSD15_LED")
		)
		(pad "2" smd circle
			(at 0.40005 0)
			(size 0 0)
			(layers "F.Cu" "F.Mask" "F.Paste")
			(net "SSD15_LED_R")
		)
	)
	(footprint ""
		(layer "F.Cu")
		(at 293.74719 -195.362068 -90)
		(property "Reference" "R3393"
			(at 0 0 270)
			(layer "F.SilkS")
			(hide yes)
			(effects
				(font
					(size 1.27 1.27)
				)
			)
		)
		(property "Value" ""
			(at 0 0 270)
			(layer "F.Fab")
			(effects
				(font
					(size 1.27 1.27)
				)
			)
		)
		(duplicate_pad_numbers_are_jumpers no)
		(fp_line
			(start -0.7874 0.4064)
			(end -0.7874 -0.4064)
			(stroke
				(width 0.1524)
				(type default)
			)
			(layer "F.SilkS")
		)
		(fp_line
			(start 0.7874 0.4064)
			(end -0.7874 0.4064)
			(stroke
				(width 0.1524)
				(type default)
			)
			(layer "F.SilkS")
		)
		(fp_line
			(start -0.7874 -0.4064)
			(end 0.7874 -0.4064)
			(stroke
				(width 0.1524)
				(type default)
			)
			(layer "F.SilkS")
		)
		(fp_line
			(start 0.7874 -0.4064)
			(end 0.7874 0.4064)
			(stroke
				(width 0.1524)
				(type default)
			)
			(layer "F.SilkS")
		)
		(fp_line
			(start -0.67945 0.3048)
			(end -0.67945 -0.305054)
			(stroke
				(width 0.1)
				(type default)
			)
			(layer "F.Fab")
		)
		(fp_line
			(start -0.12065 0.3048)
			(end -0.67945 0.3048)
			(stroke
				(width 0.1)
				(type default)
			)
			(layer "F.Fab")
		)
		(fp_line
			(start 0.120396 0.3048)
			(end 0.120396 0.2794)
			(stroke
				(width 0.1)
				(type default)
			)
			(layer "F.Fab")
		)
		(fp_line
			(start 0.67945 0.3048)
			(end 0.120396 0.3048)
			(stroke
				(width 0.1)
				(type default)
			)
			(layer "F.Fab")
		)
		(fp_line
			(start -0.12065 0.2794)
			(end -0.12065 0.3048)
			(stroke
				(width 0.1)
				(type default)
			)
			(layer "F.Fab")
		)
		(fp_line
			(start 0.120396 0.2794)
			(end -0.12065 0.2794)
			(stroke
				(width 0.1)
				(type default)
			)
			(layer "F.Fab")
		)
		(fp_line
			(start -0.12065 -0.2794)
			(end 0.12065 -0.2794)
			(stroke
				(width 0.1)
				(type default)
			)
			(layer "F.Fab")
		)
		(fp_line
			(start 0.12065 -0.2794)
			(end 0.12065 -0.3048)
			(stroke
				(width 0.1)
				(type default)
			)
			(layer "F.Fab")
		)
		(fp_line
			(start 0.12065 -0.3048)
			(end 0.67945 -0.3048)
			(stroke
				(width 0.1)
				(type default)
			)
			(layer "F.Fab")
		)
		(fp_line
			(start 0.67945 -0.3048)
			(end 0.67945 0.3048)
			(stroke
				(width 0.1)
				(type default)
			)
			(layer "F.Fab")
		)
		(fp_line
			(start -0.67945 -0.305054)
			(end -0.12065 -0.305054)
			(stroke
				(width 0.1)
				(type default)
			)
			(layer "F.Fab")
		)
		(fp_line
			(start -0.12065 -0.305054)
			(end -0.12065 -0.2794)
			(stroke
				(width 0.1)
				(type default)
			)
			(layer "F.Fab")
		)
		(pad "1" smd circle
			(at -0.40005 0 270)
			(size 0 0)
			(layers "F.Cu" "F.Mask" "F.Paste")
			(net "SPI_BIC1_MISO_R4")
		)
		(pad "2" smd circle
			(at 0.40005 0 270)
			(size 0 0)
			(layers "F.Cu" "F.Mask" "F.Paste")
			(net "SPI_BIC1_MISO_R2")
		)
	)
	(footprint ""
		(layer "F.Cu")
		(at 233.25963 -77.36459 180)
		(property "Reference" "R1005"
			(at 0 0 180)
			(layer "F.SilkS")
			(hide yes)
			(effects
				(font
					(size 1.27 1.27)
				)
			)
		)
		(property "Value" ""
			(at 0 0 180)
			(layer "F.Fab")
			(effects
				(font
					(size 1.27 1.27)
				)
			)
		)
		(duplicate_pad_numbers_are_jumpers no)
		(fp_line
			(start 0.7874 0.4064)
			(end -0.7874 0.4064)
			(stroke
				(width 0.1524)
				(type default)
			)
			(layer "F.SilkS")
		)
		(fp_line
			(start 0.7874 -0.4064)
			(end 0.7874 0.4064)
			(stroke
				(width 0.1524)
				(type default)
			)
			(layer "F.SilkS")
		)
		(fp_line
			(start -0.7874 0.4064)
			(end -0.7874 -0.4064)
			(stroke
				(width 0.1524)
				(type default)
			)
			(layer "F.SilkS")
		)
		(fp_line
			(start -0.7874 -0.4064)
			(end 0.7874 -0.4064)
			(stroke
				(width 0.1524)
				(type default)
			)
			(layer "F.SilkS")
		)
		(fp_line
			(start 0.67945 0.3048)
			(end 0.120396 0.3048)
			(stroke
				(width 0.1)
				(type default)
			)
			(layer "F.Fab")
		)
		(fp_line
			(start 0.67945 -0.3048)
			(end 0.67945 0.3048)
			(stroke
				(width 0.1)
				(type default)
			)
			(layer "F.Fab")
		)
		(fp_line
			(start 0.12065 -0.2794)
			(end 0.12065 -0.3048)
			(stroke
				(width 0.1)
				(type default)
			)
			(layer "F.Fab")
		)
		(fp_line
			(start 0.12065 -0.3048)
			(end 0.67945 -0.3048)
			(stroke
				(width 0.1)
				(type default)
			)
			(layer "F.Fab")
		)
		(fp_line
			(start 0.120396 0.3048)
			(end 0.120396 0.2794)
			(stroke
				(width 0.1)
				(type default)
			)
			(layer "F.Fab")
		)
		(fp_line
			(start 0.120396 0.2794)
			(end -0.12065 0.2794)
			(stroke
				(width 0.1)
				(type default)
			)
			(layer "F.Fab")
		)
		(fp_line
			(start -0.12065 0.3048)
			(end -0.67945 0.3048)
			(stroke
				(width 0.1)
				(type default)
			)
			(layer "F.Fab")
		)
		(fp_line
			(start -0.12065 0.2794)
			(end -0.12065 0.3048)
			(stroke
				(width 0.1)
				(type default)
			)
			(layer "F.Fab")
		)
		(fp_line
			(start -0.12065 -0.2794)
			(end 0.12065 -0.2794)
			(stroke
				(width 0.1)
				(type default)
			)
			(layer "F.Fab")
		)
		(fp_line
			(start -0.12065 -0.305054)
			(end -0.12065 -0.2794)
			(stroke
				(width 0.1)
				(type default)
			)
			(layer "F.Fab")
		)
		(fp_line
			(start -0.67945 0.3048)
			(end -0.67945 -0.305054)
			(stroke
				(width 0.1)
				(type default)
			)
			(layer "F.Fab")
		)
		(fp_line
			(start -0.67945 -0.305054)
			(end -0.12065 -0.305054)
			(stroke
				(width 0.1)
				(type default)
			)
			(layer "F.Fab")
		)
		(pad "1" smd circle
			(at -0.40005 0 180)
			(size 0 0)
			(layers "F.Cu" "F.Mask" "F.Paste")
			(net "PWRGD_P3V3_AUX_MUX_N")
		)
		(pad "2" smd circle
			(at 0.40005 0 180)
			(size 0 0)
			(layers "F.Cu" "F.Mask" "F.Paste")
			(net "PWRGD_P3V3_AUX_MUX_R_N")
		)
	)
	(footprint ""
		(layer "F.Cu")
		(at 258.605274 -258.582922 90)
		(property "Reference" "L129"
			(at 0 0 90)
			(layer "F.SilkS")
			(hide yes)
			(effects
				(font
					(size 1.27 1.27)
				)
			)
		)
		(property "Value" ""
			(at 0 0 90)
			(layer "F.Fab")
			(effects
				(font
					(size 1.27 1.27)
				)
			)
		)
		(duplicate_pad_numbers_are_jumpers no)
		(fp_line
			(start 1.63576 -0.8128)
			(end 1.63576 0.8128)
			(stroke
				(width 0.1524)
				(type default)
			)
			(layer "F.SilkS")
		)
		(fp_line
			(start -1.63576 -0.8128)
			(end 1.63576 -0.8128)
			(stroke
				(width 0.1524)
				(type default)
			)
			(layer "F.SilkS")
		)
		(fp_line
			(start -1.63576 -0.8128)
			(end -1.63576 0.8128)
			(stroke
				(width 0.1524)
				(type default)
			)
			(layer "F.SilkS")
		)
		(fp_line
			(start 1.63576 0.8128)
			(end -1.63576 0.8128)
			(stroke
				(width 0.1524)
				(type default)
			)
			(layer "F.SilkS")
		)
		(fp_line
			(start 1.560576 -0.738632)
			(end -1.56083 -0.738632)
			(stroke
				(width 0.1)
				(type default)
			)
			(layer "F.Fab")
		)
		(fp_line
			(start -1.56083 -0.738632)
			(end -1.56083 0.7366)
			(stroke
				(width 0.1)
				(type default)
			)
			(layer "F.Fab")
		)
		(fp_line
			(start 1.560576 0.7366)
			(end 1.560576 -0.738632)
			(stroke
				(width 0.1)
				(type default)
			)
			(layer "F.Fab")
		)
		(fp_line
			(start 1.524 0.7366)
			(end 1.560576 0.7366)
			(stroke
				(width 0.1)
				(type default)
			)
			(layer "F.Fab")
		)
		(fp_line
			(start -1.524 0.7366)
			(end 1.524 0.7366)
			(stroke
				(width 0.1)
				(type default)
			)
			(layer "F.Fab")
		)
		(fp_line
			(start -1.56083 0.7366)
			(end -1.524 0.7366)
			(stroke
				(width 0.1)
				(type default)
			)
			(layer "F.Fab")
		)
		(pad "1" smd rect
			(at -0.94996 0 270)
			(size 1.1176 1.3716)
			(layers "F.Cu" "F.Mask" "F.Paste")
			(net "P1V8_PLL0_PEX2")
		)
		(pad "2" smd rect
			(at 0.94996 0 270)
			(size 1.1176 1.3716)
			(layers "F.Cu" "F.Mask" "F.Paste")
			(net "P1V8_VDDA_PEX2")
		)
	)
	(footprint ""
		(layer "F.Cu")
		(at 248.004838 -119.140986 -90)
		(property "Reference" "R6030"
			(at 0 0 270)
			(layer "F.SilkS")
			(hide yes)
			(effects
				(font
					(size 1.27 1.27)
				)
			)
		)
		(property "Value" ""
			(at 0 0 270)
			(layer "F.Fab")
			(effects
				(font
					(size 1.27 1.27)
				)
			)
		)
		(duplicate_pad_numbers_are_jumpers no)
		(fp_line
			(start -0.7874 0.4064)
			(end -0.7874 -0.4064)
			(stroke
				(width 0.1524)
				(type default)
			)
			(layer "F.SilkS")
		)
		(fp_line
			(start 0.7874 0.4064)
			(end -0.7874 0.4064)
			(stroke
				(width 0.1524)
				(type default)
			)
			(layer "F.SilkS")
		)
		(fp_line
			(start -0.7874 -0.4064)
			(end 0.7874 -0.4064)
			(stroke
				(width 0.1524)
				(type default)
			)
			(layer "F.SilkS")
		)
		(fp_line
			(start 0.7874 -0.4064)
			(end 0.7874 0.4064)
			(stroke
				(width 0.1524)
				(type default)
			)
			(layer "F.SilkS")
		)
		(fp_line
			(start -0.67945 0.3048)
			(end -0.67945 -0.305054)
			(stroke
				(width 0.1)
				(type default)
			)
			(layer "F.Fab")
		)
		(fp_line
			(start -0.12065 0.3048)
			(end -0.67945 0.3048)
			(stroke
				(width 0.1)
				(type default)
			)
			(layer "F.Fab")
		)
		(fp_line
			(start 0.120396 0.3048)
			(end 0.120396 0.2794)
			(stroke
				(width 0.1)
				(type default)
			)
			(layer "F.Fab")
		)
		(fp_line
			(start 0.67945 0.3048)
			(end 0.120396 0.3048)
			(stroke
				(width 0.1)
				(type default)
			)
			(layer "F.Fab")
		)
		(fp_line
			(start -0.12065 0.2794)
			(end -0.12065 0.3048)
			(stroke
				(width 0.1)
				(type default)
			)
			(layer "F.Fab")
		)
		(fp_line
			(start 0.120396 0.2794)
			(end -0.12065 0.2794)
			(stroke
				(width 0.1)
				(type default)
			)
			(layer "F.Fab")
		)
		(fp_line
			(start -0.12065 -0.2794)
			(end 0.12065 -0.2794)
			(stroke
				(width 0.1)
				(type default)
			)
			(layer "F.Fab")
		)
		(fp_line
			(start 0.12065 -0.2794)
			(end 0.12065 -0.3048)
			(stroke
				(width 0.1)
				(type default)
			)
			(layer "F.Fab")
		)
		(fp_line
			(start 0.12065 -0.3048)
			(end 0.67945 -0.3048)
			(stroke
				(width 0.1)
				(type default)
			)
			(layer "F.Fab")
		)
		(fp_line
			(start 0.67945 -0.3048)
			(end 0.67945 0.3048)
			(stroke
				(width 0.1)
				(type default)
			)
			(layer "F.Fab")
		)
		(fp_line
			(start -0.67945 -0.305054)
			(end -0.12065 -0.305054)
			(stroke
				(width 0.1)
				(type default)
			)
			(layer "F.Fab")
		)
		(fp_line
			(start -0.12065 -0.305054)
			(end -0.12065 -0.2794)
			(stroke
				(width 0.1)
				(type default)
			)
			(layer "F.Fab")
		)
		(pad "1" smd circle
			(at -0.40005 0 270)
			(size 0 0)
			(layers "F.Cu" "F.Mask" "F.Paste")
			(net "HP_NIC4_EN")
		)
		(pad "2" smd circle
			(at 0.40005 0 270)
			(size 0 0)
			(layers "F.Cu" "F.Mask" "F.Paste")
			(net "P3V3_NIC4_CO_EN")
		)
	)
	(footprint ""
		(layer "F.Cu")
		(at 125.546612 -154.256994)
		(property "Reference" "PC630"
			(at 0 0 0)
			(layer "F.SilkS")
			(hide yes)
			(effects
				(font
					(size 1.27 1.27)
				)
			)
		)
		(property "Value" ""
			(at 0 0 0)
			(layer "F.Fab")
			(effects
				(font
					(size 1.27 1.27)
				)
			)
		)
		(duplicate_pad_numbers_are_jumpers no)
		(fp_line
			(start -1.2954 -0.5842)
			(end 1.2954 -0.5842)
			(stroke
				(width 0.1524)
				(type default)
			)
			(layer "F.SilkS")
		)
		(fp_line
			(start -1.2954 0.5842)
			(end -1.2954 -0.5842)
			(stroke
				(width 0.1524)
				(type default)
			)
			(layer "F.SilkS")
		)
		(fp_line
			(start 1.2954 -0.5842)
			(end 1.2954 0.5842)
			(stroke
				(width 0.1524)
				(type default)
			)
			(layer "F.SilkS")
		)
		(fp_line
			(start 1.2954 0.5842)
			(end -1.2954 0.5842)
			(stroke
				(width 0.1524)
				(type default)
			)
			(layer "F.SilkS")
		)
		(fp_line
			(start -1.1938 -0.4064)
			(end -0.8636 -0.4064)
			(stroke
				(width 0.1)
				(type default)
			)
			(layer "F.Fab")
		)
		(fp_line
			(start -1.1938 0.4064)
			(end -1.1938 -0.4064)
			(stroke
				(width 0.1)
				(type default)
			)
			(layer "F.Fab")
		)
		(fp_line
			(start -0.8636 -0.4572)
			(end 0.8636 -0.4572)
			(stroke
				(width 0.1)
				(type default)
			)
			(layer "F.Fab")
		)
		(fp_line
			(start -0.8636 -0.4064)
			(end -0.8636 -0.4572)
			(stroke
				(width 0.1)
				(type default)
			)
			(layer "F.Fab")
		)
		(fp_line
			(start -0.8636 0.4064)
			(end -1.1938 0.4064)
			(stroke
				(width 0.1)
				(type default)
			)
			(layer "F.Fab")
		)
		(fp_line
			(start -0.8636 0.4572)
			(end -0.8636 0.4064)
			(stroke
				(width 0.1)
				(type default)
			)
			(layer "F.Fab")
		)
		(fp_line
			(start 0.8636 -0.4572)
			(end 0.8636 -0.4064)
			(stroke
				(width 0.1)
				(type default)
			)
			(layer "F.Fab")
		)
		(fp_line
			(start 0.8636 -0.4064)
			(end 1.1938 -0.4064)
			(stroke
				(width 0.1)
				(type default)
			)
			(layer "F.Fab")
		)
		(fp_line
			(start 0.8636 0.4064)
			(end 0.8636 0.4572)
			(stroke
				(width 0.1)
				(type default)
			)
			(layer "F.Fab")
		)
		(fp_line
			(start 0.8636 0.4572)
			(end -0.8636 0.4572)
			(stroke
				(width 0.1)
				(type default)
			)
			(layer "F.Fab")
		)
		(fp_line
			(start 1.1938 -0.4064)
			(end 1.1938 0.4064)
			(stroke
				(width 0.1)
				(type default)
			)
			(layer "F.Fab")
		)
		(fp_line
			(start 1.1938 0.4064)
			(end 0.8636 0.4064)
			(stroke
				(width 0.1)
				(type default)
			)
			(layer "F.Fab")
		)
		(pad "1" smd rect
			(at -0.7366 0 270)
			(size 0.7112 0.8128)
			(layers "F.Cu" "F.Mask" "F.Paste")
			(net "GND")
		)
		(pad "2" smd rect
			(at 0.7366 0 270)
			(size 0.7112 0.8128)
			(layers "F.Cu" "F.Mask" "F.Paste")
			(net "P12V_NIC2_CO_AVIN_PD")
		)
	)
	(footprint ""
		(layer "F.Cu")
		(at 105.971594 -284.8991 180)
		(property "Reference" "PU7"
			(at -30.236922 -1.54813 90)
			(unlocked yes)
			(layer "F.SilkS")
			(effects
				(font
					(size 0.7874 0.5842)
					(thickness 0.1524)
				)
			)
		)
		(property "Value" ""
			(at 0 0 180)
			(layer "F.Fab")
			(effects
				(font
					(size 1.27 1.27)
				)
			)
		)
		(duplicate_pad_numbers_are_jumpers no)
		(fp_line
			(start 2.500122 2.999994)
			(end 2.2987 2.999994)
			(stroke
				(width 0.1524)
				(type default)
			)
			(layer "F.SilkS")
		)
		(fp_line
			(start 2.500122 2.339594)
			(end 2.500122 2.999994)
			(stroke
				(width 0.1524)
				(type default)
			)
			(layer "F.SilkS")
		)
		(fp_line
			(start 2.500122 -2.999994)
			(end 2.500122 -2.44348)
			(stroke
				(width 0.1524)
				(type default)
			)
			(layer "F.SilkS")
		)
		(fp_line
			(start 2.31394 -2.999994)
			(end 2.500122 -2.999994)
			(stroke
				(width 0.1524)
				(type default)
			)
			(layer "F.SilkS")
		)
		(fp_line
			(start -2.2987 2.999994)
			(end -2.500122 2.999994)
			(stroke
				(width 0.1524)
				(type default)
			)
			(layer "F.SilkS")
		)
		(fp_line
			(start -2.500122 2.999994)
			(end -2.500122 2.339594)
			(stroke
				(width 0.1524)
				(type default)
			)
			(layer "F.SilkS")
		)
		(fp_line
			(start -2.500122 0.6604)
			(end -2.500122 0.229108)
			(stroke
				(width 0.1524)
				(type default)
			)
			(layer "F.SilkS")
		)
		(fp_line
			(start -2.500122 -2.529078)
			(end -2.500122 -2.999994)
			(stroke
				(width 0.1524)
				(type default)
			)
			(layer "F.SilkS")
		)
		(fp_line
			(start -2.500122 -2.999994)
			(end -2.24409 -2.999994)
			(stroke
				(width 0.1524)
				(type default)
			)
			(layer "F.SilkS")
		)
		(fp_poly
			(pts
				(xy -2.118106 -4.109466) (xy -3.134106 -4.109466) (xy -2.626106 -3.093466)
			)
			(stroke
				(width 0)
				(type default)
			)
			(fill yes)
			(layer "F.SilkS")
		)
		(fp_line
			(start 2.500122 2.999994)
			(end -2.500122 2.999994)
			(stroke
				(width 0.1)
				(type default)
			)
			(layer "F.Fab")
		)
		(fp_line
			(start 2.500122 -2.999994)
			(end 2.500122 2.999994)
			(stroke
				(width 0.1)
				(type default)
			)
			(layer "F.Fab")
		)
		(fp_line
			(start -2.500122 2.999994)
			(end -2.500122 -2.999994)
			(stroke
				(width 0.1)
				(type default)
			)
			(layer "F.Fab")
		)
		(fp_line
			(start -2.500122 -2.999994)
			(end 2.500122 -2.999994)
			(stroke
				(width 0.1)
				(type default)
			)
			(layer "F.Fab")
		)
		(fp_poly
			(pts
				(xy -4.218432 -2.783078) (xy -4.218432 -1.767078) (xy -3.202432 -2.275078)
			)
			(stroke
				(width 0)
				(type default)
			)
			(fill yes)
			(layer "F.Fab")
		)
		(pad "1" smd rect
			(at -2.400046 -2.275078 270)
			(size 0.2286 0.6096)
			(layers "F.Cu" "F.Mask" "F.Paste")
			(net "SW_P0V8_PEX0_VOS1")
		)
		(pad "2" smd rect
			(at -2.400046 -1.82499 270)
			(size 0.2286 0.6096)
			(layers "F.Cu" "F.Mask" "F.Paste")
			(net "GND")
		)
		(pad "3" smd rect
			(at -2.400046 -1.374902 270)
			(size 0.2286 0.6096)
			(layers "F.Cu" "F.Mask" "F.Paste")
			(net "P0V8_PEX0_VCC1")
		)
		(pad "4" smd rect
			(at -2.400046 -0.925068 270)
			(size 0.2286 0.6096)
			(layers "F.Cu" "F.Mask" "F.Paste")
			(net "P0V8_PEX0_PVCC")
		)
		(pad "5" smd rect
			(at -2.400046 -0.47498 270)
			(size 0.2286 0.6096)
			(layers "F.Cu" "F.Mask" "F.Paste")
			(net "GND")
		)
		(pad "6" smd rect
			(at -2.400046 -0.024892 270)
			(size 0.2286 0.6096)
			(layers "F.Cu" "F.Mask" "F.Paste")
			(net "NC_P0V8_PEX0_PH1_NC1")
		)
		(pad "7_9-20_24" smd circle
			(at 0 1.150112 270)
			(size 0 0)
			(layers "F.Cu" "F.Mask" "F.Paste")
			(net "GND")
		)
		(pad "10_19" smd rect
			(at 0 2.899918 270)
			(size 0.6096 4.318)
			(layers "F.Cu" "F.Mask" "F.Paste")
			(net "SW_P0V8_PEX0_PH1")
		)
		(pad "25_29" smd rect
			(at 1.549908 -1.279906 90)
			(size 2.0574 2.3114)
			(layers "F.Cu" "F.Mask" "F.Paste")
			(net "SW_P12V_P0V8_PEX0_FLT")
		)
		(pad "30" smd rect
			(at 2.05994 -2.899918 180)
			(size 0.2286 0.6096)
			(layers "F.Cu" "F.Mask" "F.Paste")
			(net "SW_P12V_P0V8_PEX0_FLT")
		)
		(pad "31" smd rect
			(at 1.610106 -2.899918 180)
			(size 0.2286 0.6096)
			(layers "F.Cu" "F.Mask" "F.Paste")
			(net "NC_P0V8_PEX0_PH1_NC3")
		)
		(pad "32" smd rect
			(at 1.160018 -2.899918 180)
			(size 0.2286 0.6096)
			(layers "F.Cu" "F.Mask" "F.Paste")
			(net "SW_P0V8_PEX0_PHASE1")
		)
		(pad "33" smd rect
			(at 0.70993 -2.899918 180)
			(size 0.2286 0.6096)
			(layers "F.Cu" "F.Mask" "F.Paste")
			(net "SW_P0V8_PEX0_BOOT1")
		)
		(pad "34" smd rect
			(at 0.260096 -2.899918 180)
			(size 0.2286 0.6096)
			(layers "F.Cu" "F.Mask" "F.Paste")
			(net "P0V8_PEX0_PWM1")
		)
		(pad "35" smd rect
			(at -0.189992 -2.899918 180)
			(size 0.2286 0.6096)
			(layers "F.Cu" "F.Mask" "F.Paste")
			(net "P0V8_PEX0_EN1")
		)
		(pad "36" smd rect
			(at -0.64008 -2.899918 180)
			(size 0.2286 0.6096)
			(layers "F.Cu" "F.Mask" "F.Paste")
			(net "P0V8_PEX0_TSEN")
		)
		(pad "37" smd rect
			(at -1.089914 -2.899918 180)
			(size 0.2286 0.6096)
			(layers "F.Cu" "F.Mask" "F.Paste")
			(net "P0V8_PEX0_LSET1")
		)
		(pad "38" smd rect
			(at -1.540002 -2.899918 180)
			(size 0.2286 0.6096)
			(layers "F.Cu" "F.Mask" "F.Paste")
			(net "P0V8_PEX0_ISEN1")
		)
		(pad "39" smd rect
			(at -1.99009 -2.899918 180)
			(size 0.2286 0.6096)
			(layers "F.Cu" "F.Mask" "F.Paste")
			(net "P0V8_PEX0_VREF")
		)
		(pad "40" smd rect
			(at -0.87503 -1.27508 180)
			(size 1.7526 1.9558)
			(layers "F.Cu" "F.Mask" "F.Paste")
			(net "GND")
		)
		(pad "41" smd rect
			(at -1.525016 0.249936 90)
			(size 0.3048 0.4572)
			(layers "F.Cu" "F.Mask" "F.Paste")
			(net "NC_P0V8_PEX0_PH1_NC2")
		)
		(zone
			(layer "F.Cu")
			(hatch none 0.5)
			(connect_pads
				(clearance 0)
			)
			(min_thickness 0.25)
			(keepout
				(tracks not_allowed)
				(vias allowed)
				(pads allowed)
				(copperpour not_allowed)
				(footprints allowed)
			)
			(placement
				(enabled no)
				(sheetname "")
			)
			(fill
				(thermal_gap 0.5)
				(thermal_bridge_width 0.5)
				(island_removal_mode 0)
			)
			(polygon
				(pts
					(xy 108.471716 -287.899094) (xy 108.471716 -287.149794) (xy 103.471472 -287.149794) (xy 103.471472 -287.899094)
					(xy 103.761794 -287.899094) (xy 103.761794 -287.443418) (xy 108.181394 -287.443418) (xy 108.181394 -287.899094)
				)
			)
		)
	)
	(footprint ""
		(layer "F.Cu")
		(at 387.580632 -135.815324)
		(property "Reference" "C666"
			(at 0 0 0)
			(layer "F.SilkS")
			(hide yes)
			(effects
				(font
					(size 1.27 1.27)
				)
			)
		)
		(property "Value" ""
			(at 0 0 0)
			(layer "F.Fab")
			(effects
				(font
					(size 1.27 1.27)
				)
			)
		)
		(duplicate_pad_numbers_are_jumpers no)
		(fp_line
			(start -0.299974 -0.150114)
			(end 0.299974 -0.150114)
			(stroke
				(width 0.1)
				(type default)
			)
			(layer "F.Fab")
		)
		(fp_line
			(start -0.299974 0.150114)
			(end -0.299974 -0.150114)
			(stroke
				(width 0.1)
				(type default)
			)
			(layer "F.Fab")
		)
		(fp_line
			(start 0.299974 -0.150114)
			(end 0.299974 0.150114)
			(stroke
				(width 0.1)
				(type default)
			)
			(layer "F.Fab")
		)
		(fp_line
			(start 0.299974 0.150114)
			(end -0.299974 0.150114)
			(stroke
				(width 0.1)
				(type default)
			)
			(layer "F.Fab")
		)
		(pad "1" smd rect
			(at -0.2667 0)
			(size 0.3048 0.381)
			(layers "F.Cu" "F.Mask" "F.Paste")
			(net "P5E_PEX3_STN1_TX_DN<31>")
		)
		(pad "2" smd rect
			(at 0.2667 0)
			(size 0.3048 0.381)
			(layers "F.Cu" "F.Mask" "F.Paste")
			(net "P5E_PEX3_STN1_TX_C_DN<31>")
		)
	)
	(footprint ""
		(layer "F.Cu")
		(at 39.280592 -100.203254)
		(property "Reference" "C64"
			(at 0 0 0)
			(layer "F.SilkS")
			(hide yes)
			(effects
				(font
					(size 1.27 1.27)
				)
			)
		)
		(property "Value" ""
			(at 0 0 0)
			(layer "F.Fab")
			(effects
				(font
					(size 1.27 1.27)
				)
			)
		)
		(duplicate_pad_numbers_are_jumpers no)
		(fp_line
			(start -0.299974 -0.150114)
			(end 0.299974 -0.150114)
			(stroke
				(width 0.1)
				(type default)
			)
			(layer "F.Fab")
		)
		(fp_line
			(start -0.299974 0.150114)
			(end -0.299974 -0.150114)
			(stroke
				(width 0.1)
				(type default)
			)
			(layer "F.Fab")
		)
		(fp_line
			(start 0.299974 -0.150114)
			(end 0.299974 0.150114)
			(stroke
				(width 0.1)
				(type default)
			)
			(layer "F.Fab")
		)
		(fp_line
			(start 0.299974 0.150114)
			(end -0.299974 0.150114)
			(stroke
				(width 0.1)
				(type default)
			)
			(layer "F.Fab")
		)
		(pad "1" smd rect
			(at -0.2667 0)
			(size 0.3048 0.381)
			(layers "F.Cu" "F.Mask" "F.Paste")
			(net "P5E_PEX0_STN1_TX_DN<16>")
		)
		(pad "2" smd rect
			(at 0.2667 0)
			(size 0.3048 0.381)
			(layers "F.Cu" "F.Mask" "F.Paste")
			(net "P5E_PEX0_STN1_TX_C_DN<16>")
		)
	)
	(footprint ""
		(layer "F.Cu")
		(at 408.559 -383.667 90)
		(property "Reference" "R6272"
			(at 0 0 90)
			(layer "F.SilkS")
			(hide yes)
			(effects
				(font
					(size 1.27 1.27)
				)
			)
		)
		(property "Value" ""
			(at 0 0 90)
			(layer "F.Fab")
			(effects
				(font
					(size 1.27 1.27)
				)
			)
		)
		(duplicate_pad_numbers_are_jumpers no)
		(fp_line
			(start 0.7874 -0.4064)
			(end 0.7874 0.4064)
			(stroke
				(width 0.1524)
				(type default)
			)
			(layer "F.SilkS")
		)
		(fp_line
			(start -0.7874 -0.4064)
			(end 0.7874 -0.4064)
			(stroke
				(width 0.1524)
				(type default)
			)
			(layer "F.SilkS")
		)
		(fp_line
			(start 0.7874 0.4064)
			(end -0.7874 0.4064)
			(stroke
				(width 0.1524)
				(type default)
			)
			(layer "F.SilkS")
		)
		(fp_line
			(start -0.7874 0.4064)
			(end -0.7874 -0.4064)
			(stroke
				(width 0.1524)
				(type default)
			)
			(layer "F.SilkS")
		)
		(fp_line
			(start -0.12065 -0.305054)
			(end -0.12065 -0.2794)
			(stroke
				(width 0.1)
				(type default)
			)
			(layer "F.Fab")
		)
		(fp_line
			(start -0.67945 -0.305054)
			(end -0.12065 -0.305054)
			(stroke
				(width 0.1)
				(type default)
			)
			(layer "F.Fab")
		)
		(fp_line
			(start 0.67945 -0.3048)
			(end 0.67945 0.3048)
			(stroke
				(width 0.1)
				(type default)
			)
			(layer "F.Fab")
		)
		(fp_line
			(start 0.12065 -0.3048)
			(end 0.67945 -0.3048)
			(stroke
				(width 0.1)
				(type default)
			)
			(layer "F.Fab")
		)
		(fp_line
			(start 0.12065 -0.2794)
			(end 0.12065 -0.3048)
			(stroke
				(width 0.1)
				(type default)
			)
			(layer "F.Fab")
		)
		(fp_line
			(start -0.12065 -0.2794)
			(end 0.12065 -0.2794)
			(stroke
				(width 0.1)
				(type default)
			)
			(layer "F.Fab")
		)
		(fp_line
			(start 0.120396 0.2794)
			(end -0.12065 0.2794)
			(stroke
				(width 0.1)
				(type default)
			)
			(layer "F.Fab")
		)
		(fp_line
			(start -0.12065 0.2794)
			(end -0.12065 0.3048)
			(stroke
				(width 0.1)
				(type default)
			)
			(layer "F.Fab")
		)
		(fp_line
			(start 0.67945 0.3048)
			(end 0.120396 0.3048)
			(stroke
				(width 0.1)
				(type default)
			)
			(layer "F.Fab")
		)
		(fp_line
			(start 0.120396 0.3048)
			(end 0.120396 0.2794)
			(stroke
				(width 0.1)
				(type default)
			)
			(layer "F.Fab")
		)
		(fp_line
			(start -0.12065 0.3048)
			(end -0.67945 0.3048)
			(stroke
				(width 0.1)
				(type default)
			)
			(layer "F.Fab")
		)
		(fp_line
			(start -0.67945 0.3048)
			(end -0.67945 -0.305054)
			(stroke
				(width 0.1)
				(type default)
			)
			(layer "F.Fab")
		)
		(pad "1" smd circle
			(at -0.40005 0 90)
			(size 0 0)
			(layers "F.Cu" "F.Mask" "F.Paste")
			(net "MB_I3C_ISO_EN")
		)
		(pad "2" smd circle
			(at 0.40005 0 90)
			(size 0 0)
			(layers "F.Cu" "F.Mask" "F.Paste")
			(net "P3V3_AUX")
		)
	)
	(footprint ""
		(layer "F.Cu")
		(at 313.391804 -343.952322 90)
		(property "Reference" "C552"
			(at 0 0 90)
			(layer "F.SilkS")
			(hide yes)
			(effects
				(font
					(size 1.27 1.27)
				)
			)
		)
		(property "Value" ""
			(at 0 0 90)
			(layer "F.Fab")
			(effects
				(font
					(size 1.27 1.27)
				)
			)
		)
		(duplicate_pad_numbers_are_jumpers no)
		(fp_line
			(start 0.299974 -0.150114)
			(end 0.299974 0.150114)
			(stroke
				(width 0.1)
				(type default)
			)
			(layer "F.Fab")
		)
		(fp_line
			(start -0.299974 -0.150114)
			(end 0.299974 -0.150114)
			(stroke
				(width 0.1)
				(type default)
			)
			(layer "F.Fab")
		)
		(fp_line
			(start 0.299974 0.150114)
			(end -0.299974 0.150114)
			(stroke
				(width 0.1)
				(type default)
			)
			(layer "F.Fab")
		)
		(fp_line
			(start -0.299974 0.150114)
			(end -0.299974 -0.150114)
			(stroke
				(width 0.1)
				(type default)
			)
			(layer "F.Fab")
		)
		(pad "1" smd rect
			(at -0.2667 0 90)
			(size 0.3048 0.381)
			(layers "F.Cu" "F.Mask" "F.Paste")
			(net "P5E_PEX2_STN6_TX_DN<111>")
		)
		(pad "2" smd rect
			(at 0.2667 0 90)
			(size 0.3048 0.381)
			(layers "F.Cu" "F.Mask" "F.Paste")
			(net "P5E_PEX2_STN6_TX_C_DN<111>")
		)
	)
	(footprint ""
		(layer "F.Cu")
		(at 305.482752 -80.739742)
		(property "Reference" "R305"
			(at 0 0 0)
			(layer "F.SilkS")
			(hide yes)
			(effects
				(font
					(size 1.27 1.27)
				)
			)
		)
		(property "Value" ""
			(at 0 0 0)
			(layer "F.Fab")
			(effects
				(font
					(size 1.27 1.27)
				)
			)
		)
		(duplicate_pad_numbers_are_jumpers no)
		(fp_line
			(start -0.7874 -0.4064)
			(end 0.7874 -0.4064)
			(stroke
				(width 0.1524)
				(type default)
			)
			(layer "F.SilkS")
		)
		(fp_line
			(start -0.7874 0.4064)
			(end -0.7874 -0.4064)
			(stroke
				(width 0.1524)
				(type default)
			)
			(layer "F.SilkS")
		)
		(fp_line
			(start 0.7874 -0.4064)
			(end 0.7874 0.4064)
			(stroke
				(width 0.1524)
				(type default)
			)
			(layer "F.SilkS")
		)
		(fp_line
			(start 0.7874 0.4064)
			(end -0.7874 0.4064)
			(stroke
				(width 0.1524)
				(type default)
			)
			(layer "F.SilkS")
		)
		(fp_line
			(start -0.67945 -0.305054)
			(end -0.12065 -0.305054)
			(stroke
				(width 0.1)
				(type default)
			)
			(layer "F.Fab")
		)
		(fp_line
			(start -0.67945 0.3048)
			(end -0.67945 -0.305054)
			(stroke
				(width 0.1)
				(type default)
			)
			(layer "F.Fab")
		)
		(fp_line
			(start -0.12065 -0.305054)
			(end -0.12065 -0.2794)
			(stroke
				(width 0.1)
				(type default)
			)
			(layer "F.Fab")
		)
		(fp_line
			(start -0.12065 -0.2794)
			(end 0.12065 -0.2794)
			(stroke
				(width 0.1)
				(type default)
			)
			(layer "F.Fab")
		)
		(fp_line
			(start -0.12065 0.2794)
			(end -0.12065 0.3048)
			(stroke
				(width 0.1)
				(type default)
			)
			(layer "F.Fab")
		)
		(fp_line
			(start -0.12065 0.3048)
			(end -0.67945 0.3048)
			(stroke
				(width 0.1)
				(type default)
			)
			(layer "F.Fab")
		)
		(fp_line
			(start 0.120396 0.2794)
			(end -0.12065 0.2794)
			(stroke
				(width 0.1)
				(type default)
			)
			(layer "F.Fab")
		)
		(fp_line
			(start 0.120396 0.3048)
			(end 0.120396 0.2794)
			(stroke
				(width 0.1)
				(type default)
			)
			(layer "F.Fab")
		)
		(fp_line
			(start 0.12065 -0.3048)
			(end 0.67945 -0.3048)
			(stroke
				(width 0.1)
				(type default)
			)
			(layer "F.Fab")
		)
		(fp_line
			(start 0.12065 -0.2794)
			(end 0.12065 -0.3048)
			(stroke
				(width 0.1)
				(type default)
			)
			(layer "F.Fab")
		)
		(fp_line
			(start 0.67945 -0.3048)
			(end 0.67945 0.3048)
			(stroke
				(width 0.1)
				(type default)
			)
			(layer "F.Fab")
		)
		(fp_line
			(start 0.67945 0.3048)
			(end 0.120396 0.3048)
			(stroke
				(width 0.1)
				(type default)
			)
			(layer "F.Fab")
		)
		(pad "1" smd circle
			(at -0.40005 0)
			(size 0 0)
			(layers "F.Cu" "F.Mask" "F.Paste")
			(net "P3V3_AUX")
		)
		(pad "2" smd circle
			(at 0.40005 0)
			(size 0 0)
			(layers "F.Cu" "F.Mask" "F.Paste")
			(net "HP_NIC5_HSC_PWRGD_N")
		)
	)
	(footprint ""
		(layer "F.Cu")
		(at 106.29265 -9.139682 180)
		(property "Reference" "C2717"
			(at 0 0 180)
			(layer "F.SilkS")
			(hide yes)
			(effects
				(font
					(size 1.27 1.27)
				)
			)
		)
		(property "Value" ""
			(at 0 0 180)
			(layer "F.Fab")
			(effects
				(font
					(size 1.27 1.27)
				)
			)
		)
		(duplicate_pad_numbers_are_jumpers no)
		(fp_line
			(start 0.7874 0.4064)
			(end -0.7874 0.4064)
			(stroke
				(width 0.1524)
				(type default)
			)
			(layer "F.SilkS")
		)
		(fp_line
			(start 0.7874 -0.4064)
			(end 0.7874 0.4064)
			(stroke
				(width 0.1524)
				(type default)
			)
			(layer "F.SilkS")
		)
		(fp_line
			(start -0.7874 0.4064)
			(end -0.7874 -0.4064)
			(stroke
				(width 0.1524)
				(type default)
			)
			(layer "F.SilkS")
		)
		(fp_line
			(start -0.7874 -0.4064)
			(end 0.7874 -0.4064)
			(stroke
				(width 0.1524)
				(type default)
			)
			(layer "F.SilkS")
		)
		(fp_line
			(start 0.67945 0.3048)
			(end 0.120396 0.3048)
			(stroke
				(width 0.1)
				(type default)
			)
			(layer "F.Fab")
		)
		(fp_line
			(start 0.67945 -0.3048)
			(end 0.67945 0.3048)
			(stroke
				(width 0.1)
				(type default)
			)
			(layer "F.Fab")
		)
		(fp_line
			(start 0.12065 -0.2794)
			(end 0.12065 -0.3048)
			(stroke
				(width 0.1)
				(type default)
			)
			(layer "F.Fab")
		)
		(fp_line
			(start 0.12065 -0.3048)
			(end 0.67945 -0.3048)
			(stroke
				(width 0.1)
				(type default)
			)
			(layer "F.Fab")
		)
		(fp_line
			(start 0.120396 0.3048)
			(end 0.120396 0.2794)
			(stroke
				(width 0.1)
				(type default)
			)
			(layer "F.Fab")
		)
		(fp_line
			(start 0.120396 0.2794)
			(end -0.12065 0.2794)
			(stroke
				(width 0.1)
				(type default)
			)
			(layer "F.Fab")
		)
		(fp_line
			(start -0.12065 0.3048)
			(end -0.67945 0.3048)
			(stroke
				(width 0.1)
				(type default)
			)
			(layer "F.Fab")
		)
		(fp_line
			(start -0.12065 0.2794)
			(end -0.12065 0.3048)
			(stroke
				(width 0.1)
				(type default)
			)
			(layer "F.Fab")
		)
		(fp_line
			(start -0.12065 -0.2794)
			(end 0.12065 -0.2794)
			(stroke
				(width 0.1)
				(type default)
			)
			(layer "F.Fab")
		)
		(fp_line
			(start -0.12065 -0.305054)
			(end -0.12065 -0.2794)
			(stroke
				(width 0.1)
				(type default)
			)
			(layer "F.Fab")
		)
		(fp_line
			(start -0.67945 0.3048)
			(end -0.67945 -0.305054)
			(stroke
				(width 0.1)
				(type default)
			)
			(layer "F.Fab")
		)
		(fp_line
			(start -0.67945 -0.305054)
			(end -0.12065 -0.305054)
			(stroke
				(width 0.1)
				(type default)
			)
			(layer "F.Fab")
		)
		(pad "1" smd circle
			(at -0.40005 0 180)
			(size 0 0)
			(layers "F.Cu" "F.Mask" "F.Paste")
			(net "GND")
		)
		(pad "2" smd circle
			(at 0.40005 0 180)
			(size 0 0)
			(layers "F.Cu" "F.Mask" "F.Paste")
			(net "P3V3_AUX")
		)
	)
	(footprint ""
		(layer "F.Cu")
		(at 207.268826 -121.797318 90)
		(property "Reference" "PC489"
			(at 0 0 90)
			(layer "F.SilkS")
			(hide yes)
			(effects
				(font
					(size 1.27 1.27)
				)
			)
		)
		(property "Value" ""
			(at 0 0 90)
			(layer "F.Fab")
			(effects
				(font
					(size 1.27 1.27)
				)
			)
		)
		(duplicate_pad_numbers_are_jumpers no)
		(fp_line
			(start 1.524 -0.762)
			(end 1.524 0.762)
			(stroke
				(width 0.1524)
				(type default)
			)
			(layer "F.SilkS")
		)
		(fp_line
			(start -1.524 -0.762)
			(end 1.524 -0.762)
			(stroke
				(width 0.1524)
				(type default)
			)
			(layer "F.SilkS")
		)
		(fp_line
			(start 1.524 0.762)
			(end -1.524 0.762)
			(stroke
				(width 0.1524)
				(type default)
			)
			(layer "F.SilkS")
		)
		(fp_line
			(start -1.524 0.762)
			(end -1.524 -0.762)
			(stroke
				(width 0.1524)
				(type default)
			)
			(layer "F.SilkS")
		)
		(fp_line
			(start 1.1049 -0.724916)
			(end -1.1049 -0.724916)
			(stroke
				(width 0.1)
				(type default)
			)
			(layer "F.Fab")
		)
		(fp_line
			(start -1.1049 -0.724916)
			(end -1.1049 0.724916)
			(stroke
				(width 0.1)
				(type default)
			)
			(layer "F.Fab")
		)
		(fp_line
			(start 1.1049 0.724916)
			(end 1.1049 -0.724916)
			(stroke
				(width 0.1)
				(type default)
			)
			(layer "F.Fab")
		)
		(fp_line
			(start -1.1049 0.724916)
			(end 1.1049 0.724916)
			(stroke
				(width 0.1)
				(type default)
			)
			(layer "F.Fab")
		)
		(pad "1" smd rect
			(at -0.889 0 270)
			(size 1.016 1.27)
			(layers "F.Cu" "F.Mask" "F.Paste")
			(net "P3V3_NIC3")
		)
		(pad "2" smd rect
			(at 0.889 0 270)
			(size 1.016 1.27)
			(layers "F.Cu" "F.Mask" "F.Paste")
			(net "GND")
		)
	)
	(footprint ""
		(layer "F.Cu")
		(at 115.358926 -264.95756 180)
		(property "Reference" "PR7133"
			(at 0 0 180)
			(layer "F.SilkS")
			(hide yes)
			(effects
				(font
					(size 1.27 1.27)
				)
			)
		)
		(property "Value" ""
			(at 0 0 180)
			(layer "F.Fab")
			(effects
				(font
					(size 1.27 1.27)
				)
			)
		)
		(duplicate_pad_numbers_are_jumpers no)
		(fp_line
			(start 0.7874 0.4064)
			(end -0.7874 0.4064)
			(stroke
				(width 0.1524)
				(type default)
			)
			(layer "F.SilkS")
		)
		(fp_line
			(start 0.7874 -0.4064)
			(end 0.7874 0.4064)
			(stroke
				(width 0.1524)
				(type default)
			)
			(layer "F.SilkS")
		)
		(fp_line
			(start -0.7874 0.4064)
			(end -0.7874 -0.4064)
			(stroke
				(width 0.1524)
				(type default)
			)
			(layer "F.SilkS")
		)
		(fp_line
			(start -0.7874 -0.4064)
			(end 0.7874 -0.4064)
			(stroke
				(width 0.1524)
				(type default)
			)
			(layer "F.SilkS")
		)
		(fp_line
			(start 0.67945 0.3048)
			(end 0.120396 0.3048)
			(stroke
				(width 0.1)
				(type default)
			)
			(layer "F.Fab")
		)
		(fp_line
			(start 0.67945 -0.3048)
			(end 0.67945 0.3048)
			(stroke
				(width 0.1)
				(type default)
			)
			(layer "F.Fab")
		)
		(fp_line
			(start 0.12065 -0.2794)
			(end 0.12065 -0.3048)
			(stroke
				(width 0.1)
				(type default)
			)
			(layer "F.Fab")
		)
		(fp_line
			(start 0.12065 -0.3048)
			(end 0.67945 -0.3048)
			(stroke
				(width 0.1)
				(type default)
			)
			(layer "F.Fab")
		)
		(fp_line
			(start 0.120396 0.3048)
			(end 0.120396 0.2794)
			(stroke
				(width 0.1)
				(type default)
			)
			(layer "F.Fab")
		)
		(fp_line
			(start 0.120396 0.2794)
			(end -0.12065 0.2794)
			(stroke
				(width 0.1)
				(type default)
			)
			(layer "F.Fab")
		)
		(fp_line
			(start -0.12065 0.3048)
			(end -0.67945 0.3048)
			(stroke
				(width 0.1)
				(type default)
			)
			(layer "F.Fab")
		)
		(fp_line
			(start -0.12065 0.2794)
			(end -0.12065 0.3048)
			(stroke
				(width 0.1)
				(type default)
			)
			(layer "F.Fab")
		)
		(fp_line
			(start -0.12065 -0.2794)
			(end 0.12065 -0.2794)
			(stroke
				(width 0.1)
				(type default)
			)
			(layer "F.Fab")
		)
		(fp_line
			(start -0.12065 -0.305054)
			(end -0.12065 -0.2794)
			(stroke
				(width 0.1)
				(type default)
			)
			(layer "F.Fab")
		)
		(fp_line
			(start -0.67945 0.3048)
			(end -0.67945 -0.305054)
			(stroke
				(width 0.1)
				(type default)
			)
			(layer "F.Fab")
		)
		(fp_line
			(start -0.67945 -0.305054)
			(end -0.12065 -0.305054)
			(stroke
				(width 0.1)
				(type default)
			)
			(layer "F.Fab")
		)
		(pad "1" smd circle
			(at -0.40005 0 180)
			(size 0 0)
			(layers "F.Cu" "F.Mask" "F.Paste")
			(net "NC_P0V8_PEX0_ISEN4")
		)
		(pad "2" smd circle
			(at 0.40005 0 180)
			(size 0 0)
			(layers "F.Cu" "F.Mask" "F.Paste")
			(net "GND")
		)
	)
	(footprint ""
		(layer "F.Cu")
		(at 215.758014 -347.400118 90)
		(property "Reference" "H143"
			(at -4.11861 2.428494 0)
			(unlocked yes)
			(layer "F.SilkS")
			(effects
				(font
					(size 0.7874 0.5842)
					(thickness 0.1524)
				)
				(justify left)
			)
		)
		(property "Value" ""
			(at 0 0 90)
			(layer "F.Fab")
			(effects
				(font
					(size 1.27 1.27)
				)
			)
		)
		(duplicate_pad_numbers_are_jumpers no)
		(pad "1" thru_hole circle
			(at 0 0 90)
			(size 8.001 8.001)
			(drill 4.2164)
			(layers "*.Cu" "*.Mask")
			(remove_unused_layers no)
			(net "GND")
			(clearance -1.6383)
		)
	)
	(footprint ""
		(layer "F.Cu")
		(at 15.80007 -194.360038)
		(property "Reference" "H67"
			(at -4.464812 -5.059172 0)
			(unlocked yes)
			(layer "F.SilkS")
			(effects
				(font
					(size 0.7874 0.5842)
					(thickness 0.1524)
				)
				(justify left)
			)
		)
		(property "Value" ""
			(at 0 0 0)
			(layer "F.Fab")
			(effects
				(font
					(size 1.27 1.27)
				)
			)
		)
		(duplicate_pad_numbers_are_jumpers no)
		(pad "1" thru_hole circle
			(at 0 0)
			(size 10.0076 10.0076)
			(drill 5.6134)
			(layers "*.Cu" "*.Mask")
			(remove_unused_layers no)
			(net "GND")
			(clearance -1.9431)
		)
	)
	(footprint ""
		(layer "F.Cu")
		(at 389.442706 -70.844918 -90)
		(property "Reference" "PD119"
			(at 4.195318 2.142236 90)
			(unlocked yes)
			(layer "F.SilkS")
			(effects
				(font
					(size 0.7874 0.5842)
					(thickness 0.1524)
				)
				(justify left)
			)
		)
		(property "Value" ""
			(at 0 0 270)
			(layer "F.Fab")
			(effects
				(font
					(size 1.27 1.27)
				)
			)
		)
		(duplicate_pad_numbers_are_jumpers no)
		(fp_line
			(start -3.400044 1.459992)
			(end -3.400044 -1.459992)
			(stroke
				(width 0.1524)
				(type default)
			)
			(layer "F.SilkS")
		)
		(fp_line
			(start 4.107942 1.459992)
			(end -3.400044 1.459992)
			(stroke
				(width 0.1524)
				(type default)
			)
			(layer "F.SilkS")
		)
		(fp_line
			(start -3.400044 -1.459992)
			(end 4.107942 -1.459992)
			(stroke
				(width 0.1524)
				(type default)
			)
			(layer "F.SilkS")
		)
		(fp_line
			(start 4.107942 -1.459992)
			(end 4.107942 1.459992)
			(stroke
				(width 0.1524)
				(type default)
			)
			(layer "F.SilkS")
		)
		(fp_poly
			(pts
				(xy 4.107942 -1.459992) (xy 4.107942 1.459992) (xy 3.308096 1.459992) (xy 3.308096 -1.459992)
			)
			(stroke
				(width 0)
				(type default)
			)
			(fill yes)
			(layer "F.SilkS")
		)
		(fp_line
			(start -2.29997 1.459992)
			(end -2.29997 -1.459992)
			(stroke
				(width 0.1)
				(type default)
			)
			(layer "F.Fab")
		)
		(fp_line
			(start 2.29997 1.459992)
			(end -2.29997 1.459992)
			(stroke
				(width 0.1)
				(type default)
			)
			(layer "F.Fab")
		)
		(fp_line
			(start -2.29997 -1.459992)
			(end 2.29997 -1.459992)
			(stroke
				(width 0.1)
				(type default)
			)
			(layer "F.Fab")
		)
		(fp_line
			(start 2.29997 -1.459992)
			(end 2.29997 1.459992)
			(stroke
				(width 0.1)
				(type default)
			)
			(layer "F.Fab")
		)
		(fp_text user "-"
			(at 5.4102 0.29845 90)
			(unlocked yes)
			(layer "F.SilkS")
			(effects
				(font
					(size 1.905 1.4224)
					(thickness 0.1524)
				)
				(justify left)
			)
		)
		(fp_text user "+"
			(at -5.38099 0.057404 270)
			(unlocked yes)
			(layer "F.SilkS")
			(effects
				(font
					(size 1.905 1.4224)
					(thickness 0.1524)
				)
				(justify left)
			)
		)
		(fp_text user "-"
			(at 5.4102 0.29845 90)
			(unlocked yes)
			(layer "F.Fab")
			(effects
				(font
					(size 1.905 1.4224)
					(thickness 0.1524)
				)
				(justify left)
			)
		)
		(fp_text user "+"
			(at -4.7752 -0.12065 270)
			(unlocked yes)
			(layer "F.Fab")
			(effects
				(font
					(size 1.905 1.4224)
					(thickness 0.1524)
				)
				(justify left)
			)
		)
		(pad "A" smd rect
			(at -1.999996 0)
			(size 1.7018 2.5146)
			(layers "F.Cu" "F.Mask" "F.Paste")
			(net "GND")
		)
		(pad "C" smd rect
			(at 1.999996 0)
			(size 1.7018 2.5146)
			(layers "F.Cu" "F.Mask" "F.Paste")
			(net "P12V_SSD13_R")
		)
	)
	(footprint ""
		(layer "F.Cu")
		(at 461.728312 -264.5537)
		(property "Reference" "C4407"
			(at 0 0 0)
			(layer "F.SilkS")
			(hide yes)
			(effects
				(font
					(size 1.27 1.27)
				)
			)
		)
		(property "Value" ""
			(at 0 0 0)
			(layer "F.Fab")
			(effects
				(font
					(size 1.27 1.27)
				)
			)
		)
		(duplicate_pad_numbers_are_jumpers no)
		(fp_line
			(start -0.299974 -0.150114)
			(end 0.299974 -0.150114)
			(stroke
				(width 0.1)
				(type default)
			)
			(layer "F.Fab")
		)
		(fp_line
			(start -0.299974 0.150114)
			(end -0.299974 -0.150114)
			(stroke
				(width 0.1)
				(type default)
			)
			(layer "F.Fab")
		)
		(fp_line
			(start 0.299974 -0.150114)
			(end 0.299974 0.150114)
			(stroke
				(width 0.1)
				(type default)
			)
			(layer "F.Fab")
		)
		(fp_line
			(start 0.299974 0.150114)
			(end -0.299974 0.150114)
			(stroke
				(width 0.1)
				(type default)
			)
			(layer "F.Fab")
		)
		(pad "1" smd rect
			(at -0.2667 0)
			(size 0.3048 0.381)
			(layers "F.Cu" "F.Mask" "F.Paste")
			(net "P1V25_SERDES_VDDPLL_PEX3")
		)
		(pad "2" smd rect
			(at 0.2667 0)
			(size 0.3048 0.381)
			(layers "F.Cu" "F.Mask" "F.Paste")
			(net "GND")
		)
	)
	(footprint ""
		(layer "F.Cu")
		(at 358.013 -227.584 180)
		(property "Reference" "R3616"
			(at 0 0 180)
			(layer "F.SilkS")
			(hide yes)
			(effects
				(font
					(size 1.27 1.27)
				)
			)
		)
		(property "Value" ""
			(at 0 0 180)
			(layer "F.Fab")
			(effects
				(font
					(size 1.27 1.27)
				)
			)
		)
		(duplicate_pad_numbers_are_jumpers no)
		(fp_line
			(start 0.7874 0.4064)
			(end -0.7874 0.4064)
			(stroke
				(width 0.1524)
				(type default)
			)
			(layer "F.SilkS")
		)
		(fp_line
			(start 0.7874 -0.4064)
			(end 0.7874 0.4064)
			(stroke
				(width 0.1524)
				(type default)
			)
			(layer "F.SilkS")
		)
		(fp_line
			(start -0.7874 0.4064)
			(end -0.7874 -0.4064)
			(stroke
				(width 0.1524)
				(type default)
			)
			(layer "F.SilkS")
		)
		(fp_line
			(start -0.7874 -0.4064)
			(end 0.7874 -0.4064)
			(stroke
				(width 0.1524)
				(type default)
			)
			(layer "F.SilkS")
		)
		(fp_line
			(start 0.67945 0.3048)
			(end 0.120396 0.3048)
			(stroke
				(width 0.1)
				(type default)
			)
			(layer "F.Fab")
		)
		(fp_line
			(start 0.67945 -0.3048)
			(end 0.67945 0.3048)
			(stroke
				(width 0.1)
				(type default)
			)
			(layer "F.Fab")
		)
		(fp_line
			(start 0.12065 -0.2794)
			(end 0.12065 -0.3048)
			(stroke
				(width 0.1)
				(type default)
			)
			(layer "F.Fab")
		)
		(fp_line
			(start 0.12065 -0.3048)
			(end 0.67945 -0.3048)
			(stroke
				(width 0.1)
				(type default)
			)
			(layer "F.Fab")
		)
		(fp_line
			(start 0.120396 0.3048)
			(end 0.120396 0.2794)
			(stroke
				(width 0.1)
				(type default)
			)
			(layer "F.Fab")
		)
		(fp_line
			(start 0.120396 0.2794)
			(end -0.12065 0.2794)
			(stroke
				(width 0.1)
				(type default)
			)
			(layer "F.Fab")
		)
		(fp_line
			(start -0.12065 0.3048)
			(end -0.67945 0.3048)
			(stroke
				(width 0.1)
				(type default)
			)
			(layer "F.Fab")
		)
		(fp_line
			(start -0.12065 0.2794)
			(end -0.12065 0.3048)
			(stroke
				(width 0.1)
				(type default)
			)
			(layer "F.Fab")
		)
		(fp_line
			(start -0.12065 -0.2794)
			(end 0.12065 -0.2794)
			(stroke
				(width 0.1)
				(type default)
			)
			(layer "F.Fab")
		)
		(fp_line
			(start -0.12065 -0.305054)
			(end -0.12065 -0.2794)
			(stroke
				(width 0.1)
				(type default)
			)
			(layer "F.Fab")
		)
		(fp_line
			(start -0.67945 0.3048)
			(end -0.67945 -0.305054)
			(stroke
				(width 0.1)
				(type default)
			)
			(layer "F.Fab")
		)
		(fp_line
			(start -0.67945 -0.305054)
			(end -0.12065 -0.305054)
			(stroke
				(width 0.1)
				(type default)
			)
			(layer "F.Fab")
		)
		(pad "1" smd circle
			(at -0.40005 0 180)
			(size 0 0)
			(layers "F.Cu" "F.Mask" "F.Paste")
			(net "NIC1_CLK_EN_R_N")
		)
		(pad "2" smd circle
			(at 0.40005 0 180)
			(size 0 0)
			(layers "F.Cu" "F.Mask" "F.Paste")
			(net "NIC1_CLK_EN_N")
		)
	)
	(footprint ""
		(layer "F.Cu")
		(at 16.785336 -274.232624)
		(property "Reference" "R774"
			(at 0 0 0)
			(layer "F.SilkS")
			(hide yes)
			(effects
				(font
					(size 1.27 1.27)
				)
			)
		)
		(property "Value" ""
			(at 0 0 0)
			(layer "F.Fab")
			(effects
				(font
					(size 1.27 1.27)
				)
			)
		)
		(duplicate_pad_numbers_are_jumpers no)
		(fp_line
			(start -0.7874 -0.4064)
			(end 0.7874 -0.4064)
			(stroke
				(width 0.1524)
				(type default)
			)
			(layer "F.SilkS")
		)
		(fp_line
			(start -0.7874 0.4064)
			(end -0.7874 -0.4064)
			(stroke
				(width 0.1524)
				(type default)
			)
			(layer "F.SilkS")
		)
		(fp_line
			(start 0.7874 -0.4064)
			(end 0.7874 0.4064)
			(stroke
				(width 0.1524)
				(type default)
			)
			(layer "F.SilkS")
		)
		(fp_line
			(start 0.7874 0.4064)
			(end -0.7874 0.4064)
			(stroke
				(width 0.1524)
				(type default)
			)
			(layer "F.SilkS")
		)
		(fp_line
			(start -0.67945 -0.305054)
			(end -0.12065 -0.305054)
			(stroke
				(width 0.1)
				(type default)
			)
			(layer "F.Fab")
		)
		(fp_line
			(start -0.67945 0.3048)
			(end -0.67945 -0.305054)
			(stroke
				(width 0.1)
				(type default)
			)
			(layer "F.Fab")
		)
		(fp_line
			(start -0.12065 -0.305054)
			(end -0.12065 -0.2794)
			(stroke
				(width 0.1)
				(type default)
			)
			(layer "F.Fab")
		)
		(fp_line
			(start -0.12065 -0.2794)
			(end 0.12065 -0.2794)
			(stroke
				(width 0.1)
				(type default)
			)
			(layer "F.Fab")
		)
		(fp_line
			(start -0.12065 0.2794)
			(end -0.12065 0.3048)
			(stroke
				(width 0.1)
				(type default)
			)
			(layer "F.Fab")
		)
		(fp_line
			(start -0.12065 0.3048)
			(end -0.67945 0.3048)
			(stroke
				(width 0.1)
				(type default)
			)
			(layer "F.Fab")
		)
		(fp_line
			(start 0.120396 0.2794)
			(end -0.12065 0.2794)
			(stroke
				(width 0.1)
				(type default)
			)
			(layer "F.Fab")
		)
		(fp_line
			(start 0.120396 0.3048)
			(end 0.120396 0.2794)
			(stroke
				(width 0.1)
				(type default)
			)
			(layer "F.Fab")
		)
		(fp_line
			(start 0.12065 -0.3048)
			(end 0.67945 -0.3048)
			(stroke
				(width 0.1)
				(type default)
			)
			(layer "F.Fab")
		)
		(fp_line
			(start 0.12065 -0.2794)
			(end 0.12065 -0.3048)
			(stroke
				(width 0.1)
				(type default)
			)
			(layer "F.Fab")
		)
		(fp_line
			(start 0.67945 -0.3048)
			(end 0.67945 0.3048)
			(stroke
				(width 0.1)
				(type default)
			)
			(layer "F.Fab")
		)
		(fp_line
			(start 0.67945 0.3048)
			(end 0.120396 0.3048)
			(stroke
				(width 0.1)
				(type default)
			)
			(layer "F.Fab")
		)
		(pad "1" smd circle
			(at -0.40005 0)
			(size 0 0)
			(layers "F.Cu" "F.Mask" "F.Paste")
			(net "PEX0_P1V25_ADC_A0")
		)
		(pad "2" smd circle
			(at 0.40005 0)
			(size 0 0)
			(layers "F.Cu" "F.Mask" "F.Paste")
			(net "GND")
		)
	)
	(footprint ""
		(layer "F.Cu")
		(at 4.682236 -393.746228 90)
		(property "Reference" "R6754"
			(at 0 0 90)
			(layer "F.SilkS")
			(hide yes)
			(effects
				(font
					(size 1.27 1.27)
				)
			)
		)
		(property "Value" ""
			(at 0 0 90)
			(layer "F.Fab")
			(effects
				(font
					(size 1.27 1.27)
				)
			)
		)
		(duplicate_pad_numbers_are_jumpers no)
		(fp_line
			(start 0.7874 -0.4064)
			(end 0.7874 0.4064)
			(stroke
				(width 0.1524)
				(type default)
			)
			(layer "F.SilkS")
		)
		(fp_line
			(start -0.7874 -0.4064)
			(end 0.7874 -0.4064)
			(stroke
				(width 0.1524)
				(type default)
			)
			(layer "F.SilkS")
		)
		(fp_line
			(start 0.7874 0.4064)
			(end -0.7874 0.4064)
			(stroke
				(width 0.1524)
				(type default)
			)
			(layer "F.SilkS")
		)
		(fp_line
			(start -0.7874 0.4064)
			(end -0.7874 -0.4064)
			(stroke
				(width 0.1524)
				(type default)
			)
			(layer "F.SilkS")
		)
		(fp_line
			(start -0.12065 -0.305054)
			(end -0.12065 -0.2794)
			(stroke
				(width 0.1)
				(type default)
			)
			(layer "F.Fab")
		)
		(fp_line
			(start -0.67945 -0.305054)
			(end -0.12065 -0.305054)
			(stroke
				(width 0.1)
				(type default)
			)
			(layer "F.Fab")
		)
		(fp_line
			(start 0.67945 -0.3048)
			(end 0.67945 0.3048)
			(stroke
				(width 0.1)
				(type default)
			)
			(layer "F.Fab")
		)
		(fp_line
			(start 0.12065 -0.3048)
			(end 0.67945 -0.3048)
			(stroke
				(width 0.1)
				(type default)
			)
			(layer "F.Fab")
		)
		(fp_line
			(start 0.12065 -0.2794)
			(end 0.12065 -0.3048)
			(stroke
				(width 0.1)
				(type default)
			)
			(layer "F.Fab")
		)
		(fp_line
			(start -0.12065 -0.2794)
			(end 0.12065 -0.2794)
			(stroke
				(width 0.1)
				(type default)
			)
			(layer "F.Fab")
		)
		(fp_line
			(start 0.120396 0.2794)
			(end -0.12065 0.2794)
			(stroke
				(width 0.1)
				(type default)
			)
			(layer "F.Fab")
		)
		(fp_line
			(start -0.12065 0.2794)
			(end -0.12065 0.3048)
			(stroke
				(width 0.1)
				(type default)
			)
			(layer "F.Fab")
		)
		(fp_line
			(start 0.67945 0.3048)
			(end 0.120396 0.3048)
			(stroke
				(width 0.1)
				(type default)
			)
			(layer "F.Fab")
		)
		(fp_line
			(start 0.120396 0.3048)
			(end 0.120396 0.2794)
			(stroke
				(width 0.1)
				(type default)
			)
			(layer "F.Fab")
		)
		(fp_line
			(start -0.12065 0.3048)
			(end -0.67945 0.3048)
			(stroke
				(width 0.1)
				(type default)
			)
			(layer "F.Fab")
		)
		(fp_line
			(start -0.67945 0.3048)
			(end -0.67945 -0.305054)
			(stroke
				(width 0.1)
				(type default)
			)
			(layer "F.Fab")
		)
		(pad "1" smd circle
			(at -0.40005 0 90)
			(size 0 0)
			(layers "F.Cu" "F.Mask" "F.Paste")
			(net "BIC_USB_8042_HUB_VBUS")
		)
		(pad "2" smd circle
			(at 0.40005 0 90)
			(size 0 0)
			(layers "F.Cu" "F.Mask" "F.Paste")
			(net "GND")
		)
	)
	(footprint ""
		(layer "F.Cu")
		(at 263.101836 -32.849312 90)
		(property "Reference" "R5682"
			(at 0 0 90)
			(layer "F.SilkS")
			(hide yes)
			(effects
				(font
					(size 1.27 1.27)
				)
			)
		)
		(property "Value" ""
			(at 0 0 90)
			(layer "F.Fab")
			(effects
				(font
					(size 1.27 1.27)
				)
			)
		)
		(duplicate_pad_numbers_are_jumpers no)
		(fp_line
			(start 0.7874 -0.4064)
			(end 0.7874 0.4064)
			(stroke
				(width 0.1524)
				(type default)
			)
			(layer "F.SilkS")
		)
		(fp_line
			(start -0.7874 -0.4064)
			(end 0.7874 -0.4064)
			(stroke
				(width 0.1524)
				(type default)
			)
			(layer "F.SilkS")
		)
		(fp_line
			(start 0.7874 0.4064)
			(end -0.7874 0.4064)
			(stroke
				(width 0.1524)
				(type default)
			)
			(layer "F.SilkS")
		)
		(fp_line
			(start -0.7874 0.4064)
			(end -0.7874 -0.4064)
			(stroke
				(width 0.1524)
				(type default)
			)
			(layer "F.SilkS")
		)
		(fp_line
			(start -0.12065 -0.305054)
			(end -0.12065 -0.2794)
			(stroke
				(width 0.1)
				(type default)
			)
			(layer "F.Fab")
		)
		(fp_line
			(start -0.67945 -0.305054)
			(end -0.12065 -0.305054)
			(stroke
				(width 0.1)
				(type default)
			)
			(layer "F.Fab")
		)
		(fp_line
			(start 0.67945 -0.3048)
			(end 0.67945 0.3048)
			(stroke
				(width 0.1)
				(type default)
			)
			(layer "F.Fab")
		)
		(fp_line
			(start 0.12065 -0.3048)
			(end 0.67945 -0.3048)
			(stroke
				(width 0.1)
				(type default)
			)
			(layer "F.Fab")
		)
		(fp_line
			(start 0.12065 -0.2794)
			(end 0.12065 -0.3048)
			(stroke
				(width 0.1)
				(type default)
			)
			(layer "F.Fab")
		)
		(fp_line
			(start -0.12065 -0.2794)
			(end 0.12065 -0.2794)
			(stroke
				(width 0.1)
				(type default)
			)
			(layer "F.Fab")
		)
		(fp_line
			(start 0.120396 0.2794)
			(end -0.12065 0.2794)
			(stroke
				(width 0.1)
				(type default)
			)
			(layer "F.Fab")
		)
		(fp_line
			(start -0.12065 0.2794)
			(end -0.12065 0.3048)
			(stroke
				(width 0.1)
				(type default)
			)
			(layer "F.Fab")
		)
		(fp_line
			(start 0.67945 0.3048)
			(end 0.120396 0.3048)
			(stroke
				(width 0.1)
				(type default)
			)
			(layer "F.Fab")
		)
		(fp_line
			(start 0.120396 0.3048)
			(end 0.120396 0.2794)
			(stroke
				(width 0.1)
				(type default)
			)
			(layer "F.Fab")
		)
		(fp_line
			(start -0.12065 0.3048)
			(end -0.67945 0.3048)
			(stroke
				(width 0.1)
				(type default)
			)
			(layer "F.Fab")
		)
		(fp_line
			(start -0.67945 0.3048)
			(end -0.67945 -0.305054)
			(stroke
				(width 0.1)
				(type default)
			)
			(layer "F.Fab")
		)
		(pad "1" smd circle
			(at -0.40005 0 90)
			(size 0 0)
			(layers "F.Cu" "F.Mask" "F.Paste")
			(net "RST_SMB_SSD9_ISO_R_N")
		)
		(pad "2" smd circle
			(at 0.40005 0 90)
			(size 0 0)
			(layers "F.Cu" "F.Mask" "F.Paste")
			(net "RST_SMB_SSD9_ISO_N")
		)
	)
	(footprint ""
		(layer "F.Cu")
		(at 93.350842 -356.244906 90)
		(property "Reference" "C160"
			(at 0 0 90)
			(layer "F.SilkS")
			(hide yes)
			(effects
				(font
					(size 1.27 1.27)
				)
			)
		)
		(property "Value" ""
			(at 0 0 90)
			(layer "F.Fab")
			(effects
				(font
					(size 1.27 1.27)
				)
			)
		)
		(duplicate_pad_numbers_are_jumpers no)
		(fp_line
			(start 0.299974 -0.150114)
			(end 0.299974 0.150114)
			(stroke
				(width 0.1)
				(type default)
			)
			(layer "F.Fab")
		)
		(fp_line
			(start -0.299974 -0.150114)
			(end 0.299974 -0.150114)
			(stroke
				(width 0.1)
				(type default)
			)
			(layer "F.Fab")
		)
		(fp_line
			(start 0.299974 0.150114)
			(end -0.299974 0.150114)
			(stroke
				(width 0.1)
				(type default)
			)
			(layer "F.Fab")
		)
		(fp_line
			(start -0.299974 0.150114)
			(end -0.299974 -0.150114)
			(stroke
				(width 0.1)
				(type default)
			)
			(layer "F.Fab")
		)
		(pad "1" smd rect
			(at -0.2667 0 90)
			(size 0.3048 0.381)
			(layers "F.Cu" "F.Mask" "F.Paste")
			(net "P5E_PEX0_STN6_TX_DN<96>")
		)
		(pad "2" smd rect
			(at 0.2667 0 90)
			(size 0.3048 0.381)
			(layers "F.Cu" "F.Mask" "F.Paste")
			(net "P5E_PEX0_STN6_TX_C_DN<96>")
		)
	)
	(footprint ""
		(layer "F.Cu")
		(at 393.798552 -66.32194 -90)
		(property "Reference" "PC881"
			(at 0 0 270)
			(layer "F.SilkS")
			(hide yes)
			(effects
				(font
					(size 1.27 1.27)
				)
			)
		)
		(property "Value" ""
			(at 0 0 270)
			(layer "F.Fab")
			(effects
				(font
					(size 1.27 1.27)
				)
			)
		)
		(duplicate_pad_numbers_are_jumpers no)
		(fp_line
			(start -0.7874 0.4064)
			(end -0.7874 -0.4064)
			(stroke
				(width 0.1524)
				(type default)
			)
			(layer "F.SilkS")
		)
		(fp_line
			(start 0.7874 0.4064)
			(end -0.7874 0.4064)
			(stroke
				(width 0.1524)
				(type default)
			)
			(layer "F.SilkS")
		)
		(fp_line
			(start -0.7874 -0.4064)
			(end 0.7874 -0.4064)
			(stroke
				(width 0.1524)
				(type default)
			)
			(layer "F.SilkS")
		)
		(fp_line
			(start 0.7874 -0.4064)
			(end 0.7874 0.4064)
			(stroke
				(width 0.1524)
				(type default)
			)
			(layer "F.SilkS")
		)
		(fp_line
			(start -0.67945 0.3048)
			(end -0.67945 -0.305054)
			(stroke
				(width 0.1)
				(type default)
			)
			(layer "F.Fab")
		)
		(fp_line
			(start -0.12065 0.3048)
			(end -0.67945 0.3048)
			(stroke
				(width 0.1)
				(type default)
			)
			(layer "F.Fab")
		)
		(fp_line
			(start 0.120396 0.3048)
			(end 0.120396 0.2794)
			(stroke
				(width 0.1)
				(type default)
			)
			(layer "F.Fab")
		)
		(fp_line
			(start 0.67945 0.3048)
			(end 0.120396 0.3048)
			(stroke
				(width 0.1)
				(type default)
			)
			(layer "F.Fab")
		)
		(fp_line
			(start -0.12065 0.2794)
			(end -0.12065 0.3048)
			(stroke
				(width 0.1)
				(type default)
			)
			(layer "F.Fab")
		)
		(fp_line
			(start 0.120396 0.2794)
			(end -0.12065 0.2794)
			(stroke
				(width 0.1)
				(type default)
			)
			(layer "F.Fab")
		)
		(fp_line
			(start -0.12065 -0.2794)
			(end 0.12065 -0.2794)
			(stroke
				(width 0.1)
				(type default)
			)
			(layer "F.Fab")
		)
		(fp_line
			(start 0.12065 -0.2794)
			(end 0.12065 -0.3048)
			(stroke
				(width 0.1)
				(type default)
			)
			(layer "F.Fab")
		)
		(fp_line
			(start 0.12065 -0.3048)
			(end 0.67945 -0.3048)
			(stroke
				(width 0.1)
				(type default)
			)
			(layer "F.Fab")
		)
		(fp_line
			(start 0.67945 -0.3048)
			(end 0.67945 0.3048)
			(stroke
				(width 0.1)
				(type default)
			)
			(layer "F.Fab")
		)
		(fp_line
			(start -0.67945 -0.305054)
			(end -0.12065 -0.305054)
			(stroke
				(width 0.1)
				(type default)
			)
			(layer "F.Fab")
		)
		(fp_line
			(start -0.12065 -0.305054)
			(end -0.12065 -0.2794)
			(stroke
				(width 0.1)
				(type default)
			)
			(layer "F.Fab")
		)
		(pad "1" smd circle
			(at -0.40005 0 270)
			(size 0 0)
			(layers "F.Cu" "F.Mask" "F.Paste")
			(net "P12V_SSD13_CO_GATE")
		)
		(pad "2" smd circle
			(at 0.40005 0 270)
			(size 0 0)
			(layers "F.Cu" "F.Mask" "F.Paste")
			(net "GND")
		)
	)
	(footprint ""
		(layer "F.Cu")
		(at 126.210314 -126.995428 180)
		(property "Reference" "PC482"
			(at 0 0 180)
			(layer "F.SilkS")
			(hide yes)
			(effects
				(font
					(size 1.27 1.27)
				)
			)
		)
		(property "Value" ""
			(at 0 0 180)
			(layer "F.Fab")
			(effects
				(font
					(size 1.27 1.27)
				)
			)
		)
		(duplicate_pad_numbers_are_jumpers no)
		(fp_line
			(start 0.7874 0.4064)
			(end -0.7874 0.4064)
			(stroke
				(width 0.1524)
				(type default)
			)
			(layer "F.SilkS")
		)
		(fp_line
			(start 0.7874 -0.4064)
			(end 0.7874 0.4064)
			(stroke
				(width 0.1524)
				(type default)
			)
			(layer "F.SilkS")
		)
		(fp_line
			(start -0.7874 0.4064)
			(end -0.7874 -0.4064)
			(stroke
				(width 0.1524)
				(type default)
			)
			(layer "F.SilkS")
		)
		(fp_line
			(start -0.7874 -0.4064)
			(end 0.7874 -0.4064)
			(stroke
				(width 0.1524)
				(type default)
			)
			(layer "F.SilkS")
		)
		(fp_line
			(start 0.67945 0.3048)
			(end 0.120396 0.3048)
			(stroke
				(width 0.1)
				(type default)
			)
			(layer "F.Fab")
		)
		(fp_line
			(start 0.67945 -0.3048)
			(end 0.67945 0.3048)
			(stroke
				(width 0.1)
				(type default)
			)
			(layer "F.Fab")
		)
		(fp_line
			(start 0.12065 -0.2794)
			(end 0.12065 -0.3048)
			(stroke
				(width 0.1)
				(type default)
			)
			(layer "F.Fab")
		)
		(fp_line
			(start 0.12065 -0.3048)
			(end 0.67945 -0.3048)
			(stroke
				(width 0.1)
				(type default)
			)
			(layer "F.Fab")
		)
		(fp_line
			(start 0.120396 0.3048)
			(end 0.120396 0.2794)
			(stroke
				(width 0.1)
				(type default)
			)
			(layer "F.Fab")
		)
		(fp_line
			(start 0.120396 0.2794)
			(end -0.12065 0.2794)
			(stroke
				(width 0.1)
				(type default)
			)
			(layer "F.Fab")
		)
		(fp_line
			(start -0.12065 0.3048)
			(end -0.67945 0.3048)
			(stroke
				(width 0.1)
				(type default)
			)
			(layer "F.Fab")
		)
		(fp_line
			(start -0.12065 0.2794)
			(end -0.12065 0.3048)
			(stroke
				(width 0.1)
				(type default)
			)
			(layer "F.Fab")
		)
		(fp_line
			(start -0.12065 -0.2794)
			(end 0.12065 -0.2794)
			(stroke
				(width 0.1)
				(type default)
			)
			(layer "F.Fab")
		)
		(fp_line
			(start -0.12065 -0.305054)
			(end -0.12065 -0.2794)
			(stroke
				(width 0.1)
				(type default)
			)
			(layer "F.Fab")
		)
		(fp_line
			(start -0.67945 0.3048)
			(end -0.67945 -0.305054)
			(stroke
				(width 0.1)
				(type default)
			)
			(layer "F.Fab")
		)
		(fp_line
			(start -0.67945 -0.305054)
			(end -0.12065 -0.305054)
			(stroke
				(width 0.1)
				(type default)
			)
			(layer "F.Fab")
		)
		(pad "1" smd circle
			(at -0.40005 0 180)
			(size 0 0)
			(layers "F.Cu" "F.Mask" "F.Paste")
			(net "P3V3_NIC2_SS")
		)
		(pad "2" smd circle
			(at 0.40005 0 180)
			(size 0 0)
			(layers "F.Cu" "F.Mask" "F.Paste")
			(net "GND")
		)
	)
	(footprint ""
		(layer "F.Cu")
		(at 278.68753 -25.342342 -90)
		(property "Reference" "R437"
			(at 0 0 270)
			(layer "F.SilkS")
			(hide yes)
			(effects
				(font
					(size 1.27 1.27)
				)
			)
		)
		(property "Value" ""
			(at 0 0 270)
			(layer "F.Fab")
			(effects
				(font
					(size 1.27 1.27)
				)
			)
		)
		(duplicate_pad_numbers_are_jumpers no)
		(fp_line
			(start -0.7874 0.4064)
			(end -0.7874 -0.4064)
			(stroke
				(width 0.1524)
				(type default)
			)
			(layer "F.SilkS")
		)
		(fp_line
			(start 0.7874 0.4064)
			(end -0.7874 0.4064)
			(stroke
				(width 0.1524)
				(type default)
			)
			(layer "F.SilkS")
		)
		(fp_line
			(start -0.7874 -0.4064)
			(end 0.7874 -0.4064)
			(stroke
				(width 0.1524)
				(type default)
			)
			(layer "F.SilkS")
		)
		(fp_line
			(start 0.7874 -0.4064)
			(end 0.7874 0.4064)
			(stroke
				(width 0.1524)
				(type default)
			)
			(layer "F.SilkS")
		)
		(fp_line
			(start -0.67945 0.3048)
			(end -0.67945 -0.305054)
			(stroke
				(width 0.1)
				(type default)
			)
			(layer "F.Fab")
		)
		(fp_line
			(start -0.12065 0.3048)
			(end -0.67945 0.3048)
			(stroke
				(width 0.1)
				(type default)
			)
			(layer "F.Fab")
		)
		(fp_line
			(start 0.120396 0.3048)
			(end 0.120396 0.2794)
			(stroke
				(width 0.1)
				(type default)
			)
			(layer "F.Fab")
		)
		(fp_line
			(start 0.67945 0.3048)
			(end 0.120396 0.3048)
			(stroke
				(width 0.1)
				(type default)
			)
			(layer "F.Fab")
		)
		(fp_line
			(start -0.12065 0.2794)
			(end -0.12065 0.3048)
			(stroke
				(width 0.1)
				(type default)
			)
			(layer "F.Fab")
		)
		(fp_line
			(start 0.120396 0.2794)
			(end -0.12065 0.2794)
			(stroke
				(width 0.1)
				(type default)
			)
			(layer "F.Fab")
		)
		(fp_line
			(start -0.12065 -0.2794)
			(end 0.12065 -0.2794)
			(stroke
				(width 0.1)
				(type default)
			)
			(layer "F.Fab")
		)
		(fp_line
			(start 0.12065 -0.2794)
			(end 0.12065 -0.3048)
			(stroke
				(width 0.1)
				(type default)
			)
			(layer "F.Fab")
		)
		(fp_line
			(start 0.12065 -0.3048)
			(end 0.67945 -0.3048)
			(stroke
				(width 0.1)
				(type default)
			)
			(layer "F.Fab")
		)
		(fp_line
			(start 0.67945 -0.3048)
			(end 0.67945 0.3048)
			(stroke
				(width 0.1)
				(type default)
			)
			(layer "F.Fab")
		)
		(fp_line
			(start -0.67945 -0.305054)
			(end -0.12065 -0.305054)
			(stroke
				(width 0.1)
				(type default)
			)
			(layer "F.Fab")
		)
		(fp_line
			(start -0.12065 -0.305054)
			(end -0.12065 -0.2794)
			(stroke
				(width 0.1)
				(type default)
			)
			(layer "F.Fab")
		)
		(pad "1" smd circle
			(at -0.40005 0 270)
			(size 0 0)
			(layers "F.Cu" "F.Mask" "F.Paste")
			(net "GND")
		)
		(pad "2" smd circle
			(at 0.40005 0 270)
			(size 0 0)
			(layers "F.Cu" "F.Mask" "F.Paste")
			(net "DUALPORT_N_SSD9")
		)
	)
	(footprint ""
		(layer "F.Cu")
		(at 457.180442 -373.719344 90)
		(property "Reference" "R6686"
			(at 0 0 90)
			(layer "F.SilkS")
			(hide yes)
			(effects
				(font
					(size 1.27 1.27)
				)
			)
		)
		(property "Value" ""
			(at 0 0 90)
			(layer "F.Fab")
			(effects
				(font
					(size 1.27 1.27)
				)
			)
		)
		(duplicate_pad_numbers_are_jumpers no)
		(fp_line
			(start 0.7874 -0.4064)
			(end 0.7874 0.4064)
			(stroke
				(width 0.1524)
				(type default)
			)
			(layer "F.SilkS")
		)
		(fp_line
			(start -0.7874 -0.4064)
			(end 0.7874 -0.4064)
			(stroke
				(width 0.1524)
				(type default)
			)
			(layer "F.SilkS")
		)
		(fp_line
			(start 0.7874 0.4064)
			(end -0.7874 0.4064)
			(stroke
				(width 0.1524)
				(type default)
			)
			(layer "F.SilkS")
		)
		(fp_line
			(start -0.7874 0.4064)
			(end -0.7874 -0.4064)
			(stroke
				(width 0.1524)
				(type default)
			)
			(layer "F.SilkS")
		)
		(fp_line
			(start -0.12065 -0.305054)
			(end -0.12065 -0.2794)
			(stroke
				(width 0.1)
				(type default)
			)
			(layer "F.Fab")
		)
		(fp_line
			(start -0.67945 -0.305054)
			(end -0.12065 -0.305054)
			(stroke
				(width 0.1)
				(type default)
			)
			(layer "F.Fab")
		)
		(fp_line
			(start 0.67945 -0.3048)
			(end 0.67945 0.3048)
			(stroke
				(width 0.1)
				(type default)
			)
			(layer "F.Fab")
		)
		(fp_line
			(start 0.12065 -0.3048)
			(end 0.67945 -0.3048)
			(stroke
				(width 0.1)
				(type default)
			)
			(layer "F.Fab")
		)
		(fp_line
			(start 0.12065 -0.2794)
			(end 0.12065 -0.3048)
			(stroke
				(width 0.1)
				(type default)
			)
			(layer "F.Fab")
		)
		(fp_line
			(start -0.12065 -0.2794)
			(end 0.12065 -0.2794)
			(stroke
				(width 0.1)
				(type default)
			)
			(layer "F.Fab")
		)
		(fp_line
			(start 0.120396 0.2794)
			(end -0.12065 0.2794)
			(stroke
				(width 0.1)
				(type default)
			)
			(layer "F.Fab")
		)
		(fp_line
			(start -0.12065 0.2794)
			(end -0.12065 0.3048)
			(stroke
				(width 0.1)
				(type default)
			)
			(layer "F.Fab")
		)
		(fp_line
			(start 0.67945 0.3048)
			(end 0.120396 0.3048)
			(stroke
				(width 0.1)
				(type default)
			)
			(layer "F.Fab")
		)
		(fp_line
			(start 0.120396 0.3048)
			(end 0.120396 0.2794)
			(stroke
				(width 0.1)
				(type default)
			)
			(layer "F.Fab")
		)
		(fp_line
			(start -0.12065 0.3048)
			(end -0.67945 0.3048)
			(stroke
				(width 0.1)
				(type default)
			)
			(layer "F.Fab")
		)
		(fp_line
			(start -0.67945 0.3048)
			(end -0.67945 -0.305054)
			(stroke
				(width 0.1)
				(type default)
			)
			(layer "F.Fab")
		)
		(pad "1" smd circle
			(at -0.40005 0 90)
			(size 0 0)
			(layers "F.Cu" "F.Mask" "F.Paste")
			(net "GPU_3V3IO_RSVD3_ISO_R")
		)
		(pad "2" smd circle
			(at 0.40005 0 90)
			(size 0 0)
			(layers "F.Cu" "F.Mask" "F.Paste")
			(net "GPU_3V3IO_RSVD3_ISO")
		)
	)
	(footprint ""
		(layer "F.Cu")
		(at 122.077988 -356.244906 90)
		(property "Reference" "C367"
			(at 0 0 90)
			(layer "F.SilkS")
			(hide yes)
			(effects
				(font
					(size 1.27 1.27)
				)
			)
		)
		(property "Value" ""
			(at 0 0 90)
			(layer "F.Fab")
			(effects
				(font
					(size 1.27 1.27)
				)
			)
		)
		(duplicate_pad_numbers_are_jumpers no)
		(fp_line
			(start 0.299974 -0.150114)
			(end 0.299974 0.150114)
			(stroke
				(width 0.1)
				(type default)
			)
			(layer "F.Fab")
		)
		(fp_line
			(start -0.299974 -0.150114)
			(end 0.299974 -0.150114)
			(stroke
				(width 0.1)
				(type default)
			)
			(layer "F.Fab")
		)
		(fp_line
			(start 0.299974 0.150114)
			(end -0.299974 0.150114)
			(stroke
				(width 0.1)
				(type default)
			)
			(layer "F.Fab")
		)
		(fp_line
			(start -0.299974 0.150114)
			(end -0.299974 -0.150114)
			(stroke
				(width 0.1)
				(type default)
			)
			(layer "F.Fab")
		)
		(pad "1" smd rect
			(at -0.2667 0 90)
			(size 0.3048 0.381)
			(layers "F.Cu" "F.Mask" "F.Paste")
			(net "P5E_PEX1_STN6_TX_DN<98>")
		)
		(pad "2" smd rect
			(at 0.2667 0 90)
			(size 0.3048 0.381)
			(layers "F.Cu" "F.Mask" "F.Paste")
			(net "P5E_PEX1_STN6_TX_C_DN<98>")
		)
	)
	(footprint ""
		(layer "F.Cu")
		(at 361.407202 -275.81606)
		(property "Reference" "PC6622"
			(at 0 0 0)
			(layer "F.SilkS")
			(hide yes)
			(effects
				(font
					(size 1.27 1.27)
				)
			)
		)
		(property "Value" ""
			(at 0 0 0)
			(layer "F.Fab")
			(effects
				(font
					(size 1.27 1.27)
				)
			)
		)
		(duplicate_pad_numbers_are_jumpers no)
		(fp_line
			(start -1.524 -0.762)
			(end 1.524 -0.762)
			(stroke
				(width 0.1524)
				(type default)
			)
			(layer "F.SilkS")
		)
		(fp_line
			(start -1.524 0.762)
			(end -1.524 -0.762)
			(stroke
				(width 0.1524)
				(type default)
			)
			(layer "F.SilkS")
		)
		(fp_line
			(start 1.524 -0.762)
			(end 1.524 0.762)
			(stroke
				(width 0.1524)
				(type default)
			)
			(layer "F.SilkS")
		)
		(fp_line
			(start 1.524 0.762)
			(end -1.524 0.762)
			(stroke
				(width 0.1524)
				(type default)
			)
			(layer "F.SilkS")
		)
		(fp_line
			(start -1.1049 -0.724916)
			(end -1.1049 0.724916)
			(stroke
				(width 0.1)
				(type default)
			)
			(layer "F.Fab")
		)
		(fp_line
			(start -1.1049 0.724916)
			(end 1.1049 0.724916)
			(stroke
				(width 0.1)
				(type default)
			)
			(layer "F.Fab")
		)
		(fp_line
			(start 1.1049 -0.724916)
			(end -1.1049 -0.724916)
			(stroke
				(width 0.1)
				(type default)
			)
			(layer "F.Fab")
		)
		(fp_line
			(start 1.1049 0.724916)
			(end 1.1049 -0.724916)
			(stroke
				(width 0.1)
				(type default)
			)
			(layer "F.Fab")
		)
		(pad "1" smd rect
			(at -0.889 0 180)
			(size 1.016 1.27)
			(layers "F.Cu" "F.Mask" "F.Paste")
			(net "SW_P12V_P0V8_PEX3_FLT")
		)
		(pad "2" smd rect
			(at 0.889 0 180)
			(size 1.016 1.27)
			(layers "F.Cu" "F.Mask" "F.Paste")
			(net "GND")
		)
	)
	(footprint ""
		(layer "F.Cu")
		(at 205.368398 -368.957098 -90)
		(property "Reference" "PU1"
			(at -3.277108 -0.430022 0)
			(unlocked yes)
			(layer "F.SilkS")
			(effects
				(font
					(size 0.7874 0.5842)
					(thickness 0.1524)
				)
			)
		)
		(property "Value" ""
			(at 0 0 270)
			(layer "F.Fab")
			(effects
				(font
					(size 1.27 1.27)
				)
			)
		)
		(duplicate_pad_numbers_are_jumpers no)
		(fp_line
			(start -2.567686 3.567684)
			(end 2.567686 3.567684)
			(stroke
				(width 0.1524)
				(type default)
			)
			(layer "F.SilkS")
		)
		(fp_line
			(start 2.567686 3.567684)
			(end 2.567686 -3.567684)
			(stroke
				(width 0.1524)
				(type default)
			)
			(layer "F.SilkS")
		)
		(fp_line
			(start -2.567686 -3.567684)
			(end -2.567686 3.567684)
			(stroke
				(width 0.1524)
				(type default)
			)
			(layer "F.SilkS")
		)
		(fp_line
			(start 2.567686 -3.567684)
			(end -2.567686 -3.567684)
			(stroke
				(width 0.1524)
				(type default)
			)
			(layer "F.SilkS")
		)
		(fp_poly
			(pts
				(xy -3.02895 -4.209542) (xy -3.747516 -3.49123) (xy -2.669794 -3.13182)
			)
			(stroke
				(width 0)
				(type default)
			)
			(fill yes)
			(layer "F.SilkS")
		)
		(fp_line
			(start -2.549906 3.549904)
			(end 2.549906 3.549904)
			(stroke
				(width 0.1)
				(type default)
			)
			(layer "F.Fab")
		)
		(fp_line
			(start 2.549906 3.549904)
			(end 2.549906 -3.549904)
			(stroke
				(width 0.1)
				(type default)
			)
			(layer "F.Fab")
		)
		(fp_line
			(start -2.549906 -3.549904)
			(end -2.549906 3.549904)
			(stroke
				(width 0.1)
				(type default)
			)
			(layer "F.Fab")
		)
		(fp_line
			(start 2.549906 -3.549904)
			(end -2.549906 -3.549904)
			(stroke
				(width 0.1)
				(type default)
			)
			(layer "F.Fab")
		)
		(fp_poly
			(pts
				(xy -3.7592 -3.20802) (xy -3.7592 -2.19202) (xy -2.7432 -2.70002)
			)
			(stroke
				(width 0)
				(type default)
			)
			(fill yes)
			(layer "F.Fab")
		)
		(pad "1" smd rect
			(at -2.237486 -2.70002)
			(size 0.2286 0.381)
			(layers "F.Cu" "F.Mask" "F.Paste")
			(net "P12V_STBY")
		)
		(pad "2" smd rect
			(at -2.237486 -2.249932)
			(size 0.2286 0.381)
			(layers "F.Cu" "F.Mask" "F.Paste")
			(net "P12V_STBY")
		)
		(pad "3" smd rect
			(at -2.237486 -1.800098)
			(size 0.2286 0.381)
			(layers "F.Cu" "F.Mask" "F.Paste")
			(net "P12V_STBY")
		)
		(pad "4" smd rect
			(at -2.237486 -1.35001)
			(size 0.2286 0.381)
			(layers "F.Cu" "F.Mask" "F.Paste")
			(net "P12V_STBY")
		)
		(pad "5" smd rect
			(at -2.237486 -0.899922)
			(size 0.2286 0.381)
			(layers "F.Cu" "F.Mask" "F.Paste")
			(net "P12V_STBY")
		)
		(pad "6" smd rect
			(at -2.237486 -0.450088)
			(size 0.2286 0.381)
			(layers "F.Cu" "F.Mask" "F.Paste")
			(net "P12V_STBY")
		)
		(pad "7" smd rect
			(at -2.237486 0)
			(size 0.2286 0.381)
			(layers "F.Cu" "F.Mask" "F.Paste")
			(net "P12V_STBY")
		)
		(pad "8" smd rect
			(at -2.237486 0.450088)
			(size 0.2286 0.381)
			(layers "F.Cu" "F.Mask" "F.Paste")
			(net "P12V_STBY")
		)
		(pad "9" smd rect
			(at -2.237486 0.899922)
			(size 0.2286 0.381)
			(layers "F.Cu" "F.Mask" "F.Paste")
			(net "HSC_VINSEN")
		)
		(pad "10" smd rect
			(at -2.237486 1.35001)
			(size 0.2286 0.381)
			(layers "F.Cu" "F.Mask" "F.Paste")
			(net "HSC_ALERT1_N")
		)
		(pad "11" smd rect
			(at -2.237486 1.800098)
			(size 0.2286 0.381)
			(layers "F.Cu" "F.Mask" "F.Paste")
			(net "SMB_HOTSWAP_SCL_R")
		)
		(pad "12" smd rect
			(at -2.237486 2.249932)
			(size 0.2286 0.381)
			(layers "F.Cu" "F.Mask" "F.Paste")
			(net "SMB_HOTSWAP_SDA_R")
		)
		(pad "13" smd rect
			(at -2.237486 2.70002)
			(size 0.2286 0.381)
			(layers "F.Cu" "F.Mask" "F.Paste")
			(net "FM_HSC_PWROK")
		)
		(pad "14" smd rect
			(at -1.575054 3.237484 270)
			(size 0.2286 0.381)
			(layers "F.Cu" "F.Mask" "F.Paste")
			(net "HSC_VIN_UVW_N")
		)
		(pad "15" smd rect
			(at -1.124966 3.237484 270)
			(size 0.2286 0.381)
			(layers "F.Cu" "F.Mask" "F.Paste")
			(net "HSC_VTEMP")
		)
		(pad "16" smd rect
			(at -0.674878 3.237484 270)
			(size 0.2286 0.381)
			(layers "F.Cu" "F.Mask" "F.Paste")
			(net "HSC_SS")
		)
		(pad "17" smd rect
			(at -0.225044 3.237484 270)
			(size 0.2286 0.381)
			(layers "F.Cu" "F.Mask" "F.Paste")
			(net "HSC_VDD_R")
		)
		(pad "18" smd rect
			(at 0.225044 3.237484 270)
			(size 0.2286 0.381)
			(layers "F.Cu" "F.Mask" "F.Paste")
			(net "AGND_HSC")
		)
		(pad "19" smd rect
			(at 0.674878 3.237484 270)
			(size 0.2286 0.381)
			(layers "F.Cu" "F.Mask" "F.Paste")
			(net "HSC_VDD18")
		)
		(pad "20" smd rect
			(at 1.124966 3.237484 270)
			(size 0.2286 0.381)
			(layers "F.Cu" "F.Mask" "F.Paste")
			(net "HSC_CS")
		)
		(pad "21" smd rect
			(at 1.575054 3.237484 270)
			(size 0.2286 0.381)
			(layers "F.Cu" "F.Mask" "F.Paste")
			(net "HSC_IMON")
		)
		(pad "22" smd rect
			(at 2.237486 2.70002)
			(size 0.2286 0.381)
			(layers "F.Cu" "F.Mask" "F.Paste")
			(net "HSC_OCREF")
		)
		(pad "23" smd rect
			(at 2.237486 2.249932)
			(size 0.2286 0.381)
			(layers "F.Cu" "F.Mask" "F.Paste")
			(net "AGND_HSC")
		)
		(pad "24" smd rect
			(at 2.237486 1.800098)
			(size 0.2286 0.381)
			(layers "F.Cu" "F.Mask" "F.Paste")
			(net "HSC_VOSEN")
		)
		(pad "25" smd rect
			(at 2.237486 1.35001)
			(size 0.2286 0.381)
			(layers "F.Cu" "F.Mask" "F.Paste")
			(net "HSC_SCREF")
		)
		(pad "26" smd rect
			(at 2.237486 0.899922)
			(size 0.2286 0.381)
			(layers "F.Cu" "F.Mask" "F.Paste")
			(net "HSC_P12V_MP5990_EN")
		)
		(pad "27" smd rect
			(at 2.237486 0.450088)
			(size 0.2286 0.381)
			(layers "F.Cu" "F.Mask" "F.Paste")
			(net "P12V_AUX")
		)
		(pad "28" smd rect
			(at 2.237486 0)
			(size 0.2286 0.381)
			(layers "F.Cu" "F.Mask" "F.Paste")
			(net "P12V_AUX")
		)
		(pad "29" smd rect
			(at 2.237486 -0.450088)
			(size 0.2286 0.381)
			(layers "F.Cu" "F.Mask" "F.Paste")
			(net "P12V_AUX")
		)
		(pad "30" smd rect
			(at 2.237486 -0.899922)
			(size 0.2286 0.381)
			(layers "F.Cu" "F.Mask" "F.Paste")
			(net "P12V_AUX")
		)
		(pad "31" smd rect
			(at 2.237486 -1.35001)
			(size 0.2286 0.381)
			(layers "F.Cu" "F.Mask" "F.Paste")
			(net "P12V_AUX")
		)
		(pad "32" smd rect
			(at 2.237486 -1.800098)
			(size 0.2286 0.381)
			(layers "F.Cu" "F.Mask" "F.Paste")
			(net "P12V_AUX")
		)
		(pad "33" smd rect
			(at 2.237486 -2.249932)
			(size 0.2286 0.381)
			(layers "F.Cu" "F.Mask" "F.Paste")
			(net "P12V_AUX")
		)
		(pad "34" smd rect
			(at 2.237486 -2.70002)
			(size 0.2286 0.381)
			(layers "F.Cu" "F.Mask" "F.Paste")
			(net "P12V_AUX")
		)
		(pad "35" smd rect
			(at 1.575054 -3.237484 270)
			(size 0.2286 0.381)
			(layers "F.Cu" "F.Mask" "F.Paste")
			(net "P12V_AUX")
		)
		(pad "36" smd rect
			(at 1.124966 -3.237484 270)
			(size 0.2286 0.381)
			(layers "F.Cu" "F.Mask" "F.Paste")
			(net "P12V_AUX")
		)
		(pad "37" smd rect
			(at 0.674878 -3.237484 270)
			(size 0.2286 0.381)
			(layers "F.Cu" "F.Mask" "F.Paste")
			(net "HSC_D_OC")
		)
		(pad "38" smd rect
			(at 0.225044 -3.237484 270)
			(size 0.2286 0.381)
			(layers "F.Cu" "F.Mask" "F.Paste")
			(net "HSC_ON_R")
		)
		(pad "39" smd rect
			(at -0.225044 -3.237484 270)
			(size 0.2286 0.381)
			(layers "F.Cu" "F.Mask" "F.Paste")
			(net "HSC_FAULT_N")
		)
		(pad "40" smd rect
			(at -0.674878 -3.237484 270)
			(size 0.2286 0.381)
			(layers "F.Cu" "F.Mask" "F.Paste")
			(net "HSC_FLT_TYPE")
		)
		(pad "41" smd rect
			(at -1.124966 -3.237484 270)
			(size 0.2286 0.381)
			(layers "F.Cu" "F.Mask" "F.Paste")
			(net "HSC_MODE")
		)
		(pad "42" smd rect
			(at -1.575054 -3.237484 270)
			(size 0.2286 0.381)
			(layers "F.Cu" "F.Mask" "F.Paste")
			(net "P12V_STBY")
		)
		(pad "43" smd rect
			(at 0 -0.999998 270)
			(size 3.4036 3.4036)
			(layers "F.Cu" "F.Mask" "F.Paste")
			(net "P12V_STBY")
		)
		(pad "44" smd rect
			(at -1.124966 1.89992 270)
			(size 1.1684 1.6002)
			(layers "F.Cu" "F.Mask" "F.Paste")
			(net "AGND_HSC")
		)
		(pad "45" smd rect
			(at 1.124966 1.89992 270)
			(size 1.1684 1.6002)
			(layers "F.Cu" "F.Mask" "F.Paste")
			(net "HSC_VDD_R")
		)
	)
	(footprint ""
		(layer "F.Cu")
		(at 146.626834 -53.697124 -90)
		(property "Reference" "PC532"
			(at 0 0 270)
			(layer "F.SilkS")
			(hide yes)
			(effects
				(font
					(size 1.27 1.27)
				)
			)
		)
		(property "Value" ""
			(at 0 0 270)
			(layer "F.Fab")
			(effects
				(font
					(size 1.27 1.27)
				)
			)
		)
		(duplicate_pad_numbers_are_jumpers no)
		(fp_line
			(start -0.7874 0.4064)
			(end -0.7874 -0.4064)
			(stroke
				(width 0.1524)
				(type default)
			)
			(layer "F.SilkS")
		)
		(fp_line
			(start 0.7874 0.4064)
			(end -0.7874 0.4064)
			(stroke
				(width 0.1524)
				(type default)
			)
			(layer "F.SilkS")
		)
		(fp_line
			(start -0.7874 -0.4064)
			(end 0.7874 -0.4064)
			(stroke
				(width 0.1524)
				(type default)
			)
			(layer "F.SilkS")
		)
		(fp_line
			(start 0.7874 -0.4064)
			(end 0.7874 0.4064)
			(stroke
				(width 0.1524)
				(type default)
			)
			(layer "F.SilkS")
		)
		(fp_line
			(start -0.67945 0.3048)
			(end -0.67945 -0.305054)
			(stroke
				(width 0.1)
				(type default)
			)
			(layer "F.Fab")
		)
		(fp_line
			(start -0.12065 0.3048)
			(end -0.67945 0.3048)
			(stroke
				(width 0.1)
				(type default)
			)
			(layer "F.Fab")
		)
		(fp_line
			(start 0.120396 0.3048)
			(end 0.120396 0.2794)
			(stroke
				(width 0.1)
				(type default)
			)
			(layer "F.Fab")
		)
		(fp_line
			(start 0.67945 0.3048)
			(end 0.120396 0.3048)
			(stroke
				(width 0.1)
				(type default)
			)
			(layer "F.Fab")
		)
		(fp_line
			(start -0.12065 0.2794)
			(end -0.12065 0.3048)
			(stroke
				(width 0.1)
				(type default)
			)
			(layer "F.Fab")
		)
		(fp_line
			(start 0.120396 0.2794)
			(end -0.12065 0.2794)
			(stroke
				(width 0.1)
				(type default)
			)
			(layer "F.Fab")
		)
		(fp_line
			(start -0.12065 -0.2794)
			(end 0.12065 -0.2794)
			(stroke
				(width 0.1)
				(type default)
			)
			(layer "F.Fab")
		)
		(fp_line
			(start 0.12065 -0.2794)
			(end 0.12065 -0.3048)
			(stroke
				(width 0.1)
				(type default)
			)
			(layer "F.Fab")
		)
		(fp_line
			(start 0.12065 -0.3048)
			(end 0.67945 -0.3048)
			(stroke
				(width 0.1)
				(type default)
			)
			(layer "F.Fab")
		)
		(fp_line
			(start 0.67945 -0.3048)
			(end 0.67945 0.3048)
			(stroke
				(width 0.1)
				(type default)
			)
			(layer "F.Fab")
		)
		(fp_line
			(start -0.67945 -0.305054)
			(end -0.12065 -0.305054)
			(stroke
				(width 0.1)
				(type default)
			)
			(layer "F.Fab")
		)
		(fp_line
			(start -0.12065 -0.305054)
			(end -0.12065 -0.2794)
			(stroke
				(width 0.1)
				(type default)
			)
			(layer "F.Fab")
		)
		(pad "1" smd circle
			(at -0.40005 0 270)
			(size 0 0)
			(layers "F.Cu" "F.Mask" "F.Paste")
			(net "P3V3_AUX")
		)
		(pad "2" smd circle
			(at 0.40005 0 270)
			(size 0 0)
			(layers "F.Cu" "F.Mask" "F.Paste")
			(net "GND")
		)
	)
	(footprint ""
		(layer "F.Cu")
		(at 143.840708 -356.244906 90)
		(property "Reference" "C2244"
			(at 0 0 90)
			(layer "F.SilkS")
			(hide yes)
			(effects
				(font
					(size 1.27 1.27)
				)
			)
		)
		(property "Value" ""
			(at 0 0 90)
			(layer "F.Fab")
			(effects
				(font
					(size 1.27 1.27)
				)
			)
		)
		(duplicate_pad_numbers_are_jumpers no)
		(fp_line
			(start 0.299974 -0.150114)
			(end 0.299974 0.150114)
			(stroke
				(width 0.1)
				(type default)
			)
			(layer "F.Fab")
		)
		(fp_line
			(start -0.299974 -0.150114)
			(end 0.299974 -0.150114)
			(stroke
				(width 0.1)
				(type default)
			)
			(layer "F.Fab")
		)
		(fp_line
			(start 0.299974 0.150114)
			(end -0.299974 0.150114)
			(stroke
				(width 0.1)
				(type default)
			)
			(layer "F.Fab")
		)
		(fp_line
			(start -0.299974 0.150114)
			(end -0.299974 -0.150114)
			(stroke
				(width 0.1)
				(type default)
			)
			(layer "F.Fab")
		)
		(pad "1" smd rect
			(at -0.2667 0 90)
			(size 0.3048 0.381)
			(layers "F.Cu" "F.Mask" "F.Paste")
			(net "P5E_PEX1_STN5_TX_DN<95>")
		)
		(pad "2" smd rect
			(at 0.2667 0 90)
			(size 0.3048 0.381)
			(layers "F.Cu" "F.Mask" "F.Paste")
			(net "P5E_PEX1_STN5_TX_C_DN<95>")
		)
	)
	(footprint ""
		(layer "F.Cu")
		(at 362.696506 -386.172456)
		(property "Reference" "R6709"
			(at 0 0 0)
			(layer "F.SilkS")
			(hide yes)
			(effects
				(font
					(size 1.27 1.27)
				)
			)
		)
		(property "Value" ""
			(at 0 0 0)
			(layer "F.Fab")
			(effects
				(font
					(size 1.27 1.27)
				)
			)
		)
		(duplicate_pad_numbers_are_jumpers no)
		(fp_line
			(start -0.7874 -0.4064)
			(end 0.7874 -0.4064)
			(stroke
				(width 0.1524)
				(type default)
			)
			(layer "F.SilkS")
		)
		(fp_line
			(start -0.7874 0.4064)
			(end -0.7874 -0.4064)
			(stroke
				(width 0.1524)
				(type default)
			)
			(layer "F.SilkS")
		)
		(fp_line
			(start 0.7874 -0.4064)
			(end 0.7874 0.4064)
			(stroke
				(width 0.1524)
				(type default)
			)
			(layer "F.SilkS")
		)
		(fp_line
			(start 0.7874 0.4064)
			(end -0.7874 0.4064)
			(stroke
				(width 0.1524)
				(type default)
			)
			(layer "F.SilkS")
		)
		(fp_line
			(start -0.67945 -0.305054)
			(end -0.12065 -0.305054)
			(stroke
				(width 0.1)
				(type default)
			)
			(layer "F.Fab")
		)
		(fp_line
			(start -0.67945 0.3048)
			(end -0.67945 -0.305054)
			(stroke
				(width 0.1)
				(type default)
			)
			(layer "F.Fab")
		)
		(fp_line
			(start -0.12065 -0.305054)
			(end -0.12065 -0.2794)
			(stroke
				(width 0.1)
				(type default)
			)
			(layer "F.Fab")
		)
		(fp_line
			(start -0.12065 -0.2794)
			(end 0.12065 -0.2794)
			(stroke
				(width 0.1)
				(type default)
			)
			(layer "F.Fab")
		)
		(fp_line
			(start -0.12065 0.2794)
			(end -0.12065 0.3048)
			(stroke
				(width 0.1)
				(type default)
			)
			(layer "F.Fab")
		)
		(fp_line
			(start -0.12065 0.3048)
			(end -0.67945 0.3048)
			(stroke
				(width 0.1)
				(type default)
			)
			(layer "F.Fab")
		)
		(fp_line
			(start 0.120396 0.2794)
			(end -0.12065 0.2794)
			(stroke
				(width 0.1)
				(type default)
			)
			(layer "F.Fab")
		)
		(fp_line
			(start 0.120396 0.3048)
			(end 0.120396 0.2794)
			(stroke
				(width 0.1)
				(type default)
			)
			(layer "F.Fab")
		)
		(fp_line
			(start 0.12065 -0.3048)
			(end 0.67945 -0.3048)
			(stroke
				(width 0.1)
				(type default)
			)
			(layer "F.Fab")
		)
		(fp_line
			(start 0.12065 -0.2794)
			(end 0.12065 -0.3048)
			(stroke
				(width 0.1)
				(type default)
			)
			(layer "F.Fab")
		)
		(fp_line
			(start 0.67945 -0.3048)
			(end 0.67945 0.3048)
			(stroke
				(width 0.1)
				(type default)
			)
			(layer "F.Fab")
		)
		(fp_line
			(start 0.67945 0.3048)
			(end 0.120396 0.3048)
			(stroke
				(width 0.1)
				(type default)
			)
			(layer "F.Fab")
		)
		(pad "1" smd circle
			(at -0.40005 0)
			(size 0 0)
			(layers "F.Cu" "F.Mask" "F.Paste")
			(net "P3V3_AUX")
		)
		(pad "2" smd circle
			(at 0.40005 0)
			(size 0 0)
			(layers "F.Cu" "F.Mask" "F.Paste")
			(net "MB_3V3IO_RSVD4")
		)
	)
	(footprint ""
		(layer "F.Cu")
		(at 359.156 -192.278 180)
		(property "Reference" "R4640"
			(at 0 0 180)
			(layer "F.SilkS")
			(hide yes)
			(effects
				(font
					(size 1.27 1.27)
				)
			)
		)
		(property "Value" ""
			(at 0 0 180)
			(layer "F.Fab")
			(effects
				(font
					(size 1.27 1.27)
				)
			)
		)
		(duplicate_pad_numbers_are_jumpers no)
		(fp_line
			(start 0.7874 0.4064)
			(end -0.7874 0.4064)
			(stroke
				(width 0.1524)
				(type default)
			)
			(layer "F.SilkS")
		)
		(fp_line
			(start 0.7874 -0.4064)
			(end 0.7874 0.4064)
			(stroke
				(width 0.1524)
				(type default)
			)
			(layer "F.SilkS")
		)
		(fp_line
			(start -0.7874 0.4064)
			(end -0.7874 -0.4064)
			(stroke
				(width 0.1524)
				(type default)
			)
			(layer "F.SilkS")
		)
		(fp_line
			(start -0.7874 -0.4064)
			(end 0.7874 -0.4064)
			(stroke
				(width 0.1524)
				(type default)
			)
			(layer "F.SilkS")
		)
		(fp_line
			(start 0.67945 0.3048)
			(end 0.120396 0.3048)
			(stroke
				(width 0.1)
				(type default)
			)
			(layer "F.Fab")
		)
		(fp_line
			(start 0.67945 -0.3048)
			(end 0.67945 0.3048)
			(stroke
				(width 0.1)
				(type default)
			)
			(layer "F.Fab")
		)
		(fp_line
			(start 0.12065 -0.2794)
			(end 0.12065 -0.3048)
			(stroke
				(width 0.1)
				(type default)
			)
			(layer "F.Fab")
		)
		(fp_line
			(start 0.12065 -0.3048)
			(end 0.67945 -0.3048)
			(stroke
				(width 0.1)
				(type default)
			)
			(layer "F.Fab")
		)
		(fp_line
			(start 0.120396 0.3048)
			(end 0.120396 0.2794)
			(stroke
				(width 0.1)
				(type default)
			)
			(layer "F.Fab")
		)
		(fp_line
			(start 0.120396 0.2794)
			(end -0.12065 0.2794)
			(stroke
				(width 0.1)
				(type default)
			)
			(layer "F.Fab")
		)
		(fp_line
			(start -0.12065 0.3048)
			(end -0.67945 0.3048)
			(stroke
				(width 0.1)
				(type default)
			)
			(layer "F.Fab")
		)
		(fp_line
			(start -0.12065 0.2794)
			(end -0.12065 0.3048)
			(stroke
				(width 0.1)
				(type default)
			)
			(layer "F.Fab")
		)
		(fp_line
			(start -0.12065 -0.2794)
			(end 0.12065 -0.2794)
			(stroke
				(width 0.1)
				(type default)
			)
			(layer "F.Fab")
		)
		(fp_line
			(start -0.12065 -0.305054)
			(end -0.12065 -0.2794)
			(stroke
				(width 0.1)
				(type default)
			)
			(layer "F.Fab")
		)
		(fp_line
			(start -0.67945 0.3048)
			(end -0.67945 -0.305054)
			(stroke
				(width 0.1)
				(type default)
			)
			(layer "F.Fab")
		)
		(fp_line
			(start -0.67945 -0.305054)
			(end -0.12065 -0.305054)
			(stroke
				(width 0.1)
				(type default)
			)
			(layer "F.Fab")
		)
		(pad "1" smd circle
			(at -0.40005 0 180)
			(size 0 0)
			(layers "F.Cu" "F.Mask" "F.Paste")
			(net "PCA9555_1_PEX0_A1")
		)
		(pad "2" smd circle
			(at 0.40005 0 180)
			(size 0 0)
			(layers "F.Cu" "F.Mask" "F.Paste")
			(net "P3V3_AUX")
		)
	)
	(footprint ""
		(layer "F.Cu")
		(at 258.46786 -51.019456)
		(property "Reference" "PC410"
			(at 0 0 0)
			(layer "F.SilkS")
			(hide yes)
			(effects
				(font
					(size 1.27 1.27)
				)
			)
		)
		(property "Value" ""
			(at 0 0 0)
			(layer "F.Fab")
			(effects
				(font
					(size 1.27 1.27)
				)
			)
		)
		(duplicate_pad_numbers_are_jumpers no)
		(fp_line
			(start -0.7874 -0.4064)
			(end 0.7874 -0.4064)
			(stroke
				(width 0.1524)
				(type default)
			)
			(layer "F.SilkS")
		)
		(fp_line
			(start -0.7874 0.4064)
			(end -0.7874 -0.4064)
			(stroke
				(width 0.1524)
				(type default)
			)
			(layer "F.SilkS")
		)
		(fp_line
			(start 0.7874 -0.4064)
			(end 0.7874 0.4064)
			(stroke
				(width 0.1524)
				(type default)
			)
			(layer "F.SilkS")
		)
		(fp_line
			(start 0.7874 0.4064)
			(end -0.7874 0.4064)
			(stroke
				(width 0.1524)
				(type default)
			)
			(layer "F.SilkS")
		)
		(fp_line
			(start -0.67945 -0.305054)
			(end -0.12065 -0.305054)
			(stroke
				(width 0.1)
				(type default)
			)
			(layer "F.Fab")
		)
		(fp_line
			(start -0.67945 0.3048)
			(end -0.67945 -0.305054)
			(stroke
				(width 0.1)
				(type default)
			)
			(layer "F.Fab")
		)
		(fp_line
			(start -0.12065 -0.305054)
			(end -0.12065 -0.2794)
			(stroke
				(width 0.1)
				(type default)
			)
			(layer "F.Fab")
		)
		(fp_line
			(start -0.12065 -0.2794)
			(end 0.12065 -0.2794)
			(stroke
				(width 0.1)
				(type default)
			)
			(layer "F.Fab")
		)
		(fp_line
			(start -0.12065 0.2794)
			(end -0.12065 0.3048)
			(stroke
				(width 0.1)
				(type default)
			)
			(layer "F.Fab")
		)
		(fp_line
			(start -0.12065 0.3048)
			(end -0.67945 0.3048)
			(stroke
				(width 0.1)
				(type default)
			)
			(layer "F.Fab")
		)
		(fp_line
			(start 0.120396 0.2794)
			(end -0.12065 0.2794)
			(stroke
				(width 0.1)
				(type default)
			)
			(layer "F.Fab")
		)
		(fp_line
			(start 0.120396 0.3048)
			(end 0.120396 0.2794)
			(stroke
				(width 0.1)
				(type default)
			)
			(layer "F.Fab")
		)
		(fp_line
			(start 0.12065 -0.3048)
			(end 0.67945 -0.3048)
			(stroke
				(width 0.1)
				(type default)
			)
			(layer "F.Fab")
		)
		(fp_line
			(start 0.12065 -0.2794)
			(end 0.12065 -0.3048)
			(stroke
				(width 0.1)
				(type default)
			)
			(layer "F.Fab")
		)
		(fp_line
			(start 0.67945 -0.3048)
			(end 0.67945 0.3048)
			(stroke
				(width 0.1)
				(type default)
			)
			(layer "F.Fab")
		)
		(fp_line
			(start 0.67945 0.3048)
			(end 0.120396 0.3048)
			(stroke
				(width 0.1)
				(type default)
			)
			(layer "F.Fab")
		)
		(pad "1" smd circle
			(at -0.40005 0)
			(size 0 0)
			(layers "F.Cu" "F.Mask" "F.Paste")
			(net "P12V_SSD8_SS")
		)
		(pad "2" smd circle
			(at 0.40005 0)
			(size 0 0)
			(layers "F.Cu" "F.Mask" "F.Paste")
			(net "GND")
		)
	)
	(footprint ""
		(layer "F.Cu")
		(at 26.243788 -48.93691 180)
		(property "Reference" "R512"
			(at 0 0 180)
			(layer "F.SilkS")
			(hide yes)
			(effects
				(font
					(size 1.27 1.27)
				)
			)
		)
		(property "Value" ""
			(at 0 0 180)
			(layer "F.Fab")
			(effects
				(font
					(size 1.27 1.27)
				)
			)
		)
		(duplicate_pad_numbers_are_jumpers no)
		(fp_line
			(start 0.7874 0.4064)
			(end -0.7874 0.4064)
			(stroke
				(width 0.1524)
				(type default)
			)
			(layer "F.SilkS")
		)
		(fp_line
			(start 0.7874 -0.4064)
			(end 0.7874 0.4064)
			(stroke
				(width 0.1524)
				(type default)
			)
			(layer "F.SilkS")
		)
		(fp_line
			(start -0.7874 0.4064)
			(end -0.7874 -0.4064)
			(stroke
				(width 0.1524)
				(type default)
			)
			(layer "F.SilkS")
		)
		(fp_line
			(start -0.7874 -0.4064)
			(end 0.7874 -0.4064)
			(stroke
				(width 0.1524)
				(type default)
			)
			(layer "F.SilkS")
		)
		(fp_line
			(start 0.67945 0.3048)
			(end 0.120396 0.3048)
			(stroke
				(width 0.1)
				(type default)
			)
			(layer "F.Fab")
		)
		(fp_line
			(start 0.67945 -0.3048)
			(end 0.67945 0.3048)
			(stroke
				(width 0.1)
				(type default)
			)
			(layer "F.Fab")
		)
		(fp_line
			(start 0.12065 -0.2794)
			(end 0.12065 -0.3048)
			(stroke
				(width 0.1)
				(type default)
			)
			(layer "F.Fab")
		)
		(fp_line
			(start 0.12065 -0.3048)
			(end 0.67945 -0.3048)
			(stroke
				(width 0.1)
				(type default)
			)
			(layer "F.Fab")
		)
		(fp_line
			(start 0.120396 0.3048)
			(end 0.120396 0.2794)
			(stroke
				(width 0.1)
				(type default)
			)
			(layer "F.Fab")
		)
		(fp_line
			(start 0.120396 0.2794)
			(end -0.12065 0.2794)
			(stroke
				(width 0.1)
				(type default)
			)
			(layer "F.Fab")
		)
		(fp_line
			(start -0.12065 0.3048)
			(end -0.67945 0.3048)
			(stroke
				(width 0.1)
				(type default)
			)
			(layer "F.Fab")
		)
		(fp_line
			(start -0.12065 0.2794)
			(end -0.12065 0.3048)
			(stroke
				(width 0.1)
				(type default)
			)
			(layer "F.Fab")
		)
		(fp_line
			(start -0.12065 -0.2794)
			(end 0.12065 -0.2794)
			(stroke
				(width 0.1)
				(type default)
			)
			(layer "F.Fab")
		)
		(fp_line
			(start -0.12065 -0.305054)
			(end -0.12065 -0.2794)
			(stroke
				(width 0.1)
				(type default)
			)
			(layer "F.Fab")
		)
		(fp_line
			(start -0.67945 0.3048)
			(end -0.67945 -0.305054)
			(stroke
				(width 0.1)
				(type default)
			)
			(layer "F.Fab")
		)
		(fp_line
			(start -0.67945 -0.305054)
			(end -0.12065 -0.305054)
			(stroke
				(width 0.1)
				(type default)
			)
			(layer "F.Fab")
		)
		(pad "1" smd circle
			(at -0.40005 0 180)
			(size 0 0)
			(layers "F.Cu" "F.Mask" "F.Paste")
			(net "SMB_BIC_I2C6_MUX_SSD_0_7_ADC_R_SDA")
		)
		(pad "2" smd circle
			(at 0.40005 0 180)
			(size 0 0)
			(layers "F.Cu" "F.Mask" "F.Paste")
			(net "SMB_SSD0_ADC_SDA")
		)
	)
	(footprint ""
		(layer "F.Cu")
		(at 287.557718 -27.006296 -90)
		(property "Reference" "PR7119"
			(at 0 0 270)
			(layer "F.SilkS")
			(hide yes)
			(effects
				(font
					(size 1.27 1.27)
				)
			)
		)
		(property "Value" ""
			(at 0 0 270)
			(layer "F.Fab")
			(effects
				(font
					(size 1.27 1.27)
				)
			)
		)
		(duplicate_pad_numbers_are_jumpers no)
		(fp_line
			(start -0.7874 0.4064)
			(end -0.7874 -0.4064)
			(stroke
				(width 0.1524)
				(type default)
			)
			(layer "F.SilkS")
		)
		(fp_line
			(start 0.7874 0.4064)
			(end -0.7874 0.4064)
			(stroke
				(width 0.1524)
				(type default)
			)
			(layer "F.SilkS")
		)
		(fp_line
			(start -0.7874 -0.4064)
			(end 0.7874 -0.4064)
			(stroke
				(width 0.1524)
				(type default)
			)
			(layer "F.SilkS")
		)
		(fp_line
			(start 0.7874 -0.4064)
			(end 0.7874 0.4064)
			(stroke
				(width 0.1524)
				(type default)
			)
			(layer "F.SilkS")
		)
		(fp_line
			(start -0.67945 0.3048)
			(end -0.67945 -0.305054)
			(stroke
				(width 0.1)
				(type default)
			)
			(layer "F.Fab")
		)
		(fp_line
			(start -0.12065 0.3048)
			(end -0.67945 0.3048)
			(stroke
				(width 0.1)
				(type default)
			)
			(layer "F.Fab")
		)
		(fp_line
			(start 0.120396 0.3048)
			(end 0.120396 0.2794)
			(stroke
				(width 0.1)
				(type default)
			)
			(layer "F.Fab")
		)
		(fp_line
			(start 0.67945 0.3048)
			(end 0.120396 0.3048)
			(stroke
				(width 0.1)
				(type default)
			)
			(layer "F.Fab")
		)
		(fp_line
			(start -0.12065 0.2794)
			(end -0.12065 0.3048)
			(stroke
				(width 0.1)
				(type default)
			)
			(layer "F.Fab")
		)
		(fp_line
			(start 0.120396 0.2794)
			(end -0.12065 0.2794)
			(stroke
				(width 0.1)
				(type default)
			)
			(layer "F.Fab")
		)
		(fp_line
			(start -0.12065 -0.2794)
			(end 0.12065 -0.2794)
			(stroke
				(width 0.1)
				(type default)
			)
			(layer "F.Fab")
		)
		(fp_line
			(start 0.12065 -0.2794)
			(end 0.12065 -0.3048)
			(stroke
				(width 0.1)
				(type default)
			)
			(layer "F.Fab")
		)
		(fp_line
			(start 0.12065 -0.3048)
			(end 0.67945 -0.3048)
			(stroke
				(width 0.1)
				(type default)
			)
			(layer "F.Fab")
		)
		(fp_line
			(start 0.67945 -0.3048)
			(end 0.67945 0.3048)
			(stroke
				(width 0.1)
				(type default)
			)
			(layer "F.Fab")
		)
		(fp_line
			(start -0.67945 -0.305054)
			(end -0.12065 -0.305054)
			(stroke
				(width 0.1)
				(type default)
			)
			(layer "F.Fab")
		)
		(fp_line
			(start -0.12065 -0.305054)
			(end -0.12065 -0.2794)
			(stroke
				(width 0.1)
				(type default)
			)
			(layer "F.Fab")
		)
		(pad "1" smd circle
			(at -0.40005 0 270)
			(size 0 0)
			(layers "F.Cu" "F.Mask" "F.Paste")
			(net "P3V3_SSD10_CO_MODE")
		)
		(pad "2" smd circle
			(at 0.40005 0 270)
			(size 0 0)
			(layers "F.Cu" "F.Mask" "F.Paste")
			(net "GND")
		)
	)
	(footprint ""
		(layer "F.Cu")
		(at 244.492018 -236.682026 -90)
		(property "Reference" "R6243"
			(at 0 0 270)
			(layer "F.SilkS")
			(hide yes)
			(effects
				(font
					(size 1.27 1.27)
				)
			)
		)
		(property "Value" ""
			(at 0 0 270)
			(layer "F.Fab")
			(effects
				(font
					(size 1.27 1.27)
				)
			)
		)
		(duplicate_pad_numbers_are_jumpers no)
		(fp_line
			(start -0.7874 0.4064)
			(end -0.7874 -0.4064)
			(stroke
				(width 0.1524)
				(type default)
			)
			(layer "F.SilkS")
		)
		(fp_line
			(start 0.7874 0.4064)
			(end -0.7874 0.4064)
			(stroke
				(width 0.1524)
				(type default)
			)
			(layer "F.SilkS")
		)
		(fp_line
			(start -0.7874 -0.4064)
			(end 0.7874 -0.4064)
			(stroke
				(width 0.1524)
				(type default)
			)
			(layer "F.SilkS")
		)
		(fp_line
			(start 0.7874 -0.4064)
			(end 0.7874 0.4064)
			(stroke
				(width 0.1524)
				(type default)
			)
			(layer "F.SilkS")
		)
		(fp_line
			(start -0.67945 0.3048)
			(end -0.67945 -0.305054)
			(stroke
				(width 0.1)
				(type default)
			)
			(layer "F.Fab")
		)
		(fp_line
			(start -0.12065 0.3048)
			(end -0.67945 0.3048)
			(stroke
				(width 0.1)
				(type default)
			)
			(layer "F.Fab")
		)
		(fp_line
			(start 0.120396 0.3048)
			(end 0.120396 0.2794)
			(stroke
				(width 0.1)
				(type default)
			)
			(layer "F.Fab")
		)
		(fp_line
			(start 0.67945 0.3048)
			(end 0.120396 0.3048)
			(stroke
				(width 0.1)
				(type default)
			)
			(layer "F.Fab")
		)
		(fp_line
			(start -0.12065 0.2794)
			(end -0.12065 0.3048)
			(stroke
				(width 0.1)
				(type default)
			)
			(layer "F.Fab")
		)
		(fp_line
			(start 0.120396 0.2794)
			(end -0.12065 0.2794)
			(stroke
				(width 0.1)
				(type default)
			)
			(layer "F.Fab")
		)
		(fp_line
			(start -0.12065 -0.2794)
			(end 0.12065 -0.2794)
			(stroke
				(width 0.1)
				(type default)
			)
			(layer "F.Fab")
		)
		(fp_line
			(start 0.12065 -0.2794)
			(end 0.12065 -0.3048)
			(stroke
				(width 0.1)
				(type default)
			)
			(layer "F.Fab")
		)
		(fp_line
			(start 0.12065 -0.3048)
			(end 0.67945 -0.3048)
			(stroke
				(width 0.1)
				(type default)
			)
			(layer "F.Fab")
		)
		(fp_line
			(start 0.67945 -0.3048)
			(end 0.67945 0.3048)
			(stroke
				(width 0.1)
				(type default)
			)
			(layer "F.Fab")
		)
		(fp_line
			(start -0.67945 -0.305054)
			(end -0.12065 -0.305054)
			(stroke
				(width 0.1)
				(type default)
			)
			(layer "F.Fab")
		)
		(fp_line
			(start -0.12065 -0.305054)
			(end -0.12065 -0.2794)
			(stroke
				(width 0.1)
				(type default)
			)
			(layer "F.Fab")
		)
		(pad "1" smd circle
			(at -0.40005 0 270)
			(size 0 0)
			(layers "F.Cu" "F.Mask" "F.Paste")
			(net "SMB_BIC_RECOVER_IOEXP_SDA")
		)
		(pad "2" smd circle
			(at 0.40005 0 270)
			(size 0 0)
			(layers "F.Cu" "F.Mask" "F.Paste")
			(net "SMB_MB_R_SDA")
		)
	)
	(footprint ""
		(layer "F.Cu")
		(at 351.15627 -32.848042 -90)
		(property "Reference" "R6102"
			(at 0 0 270)
			(layer "F.SilkS")
			(hide yes)
			(effects
				(font
					(size 1.27 1.27)
				)
			)
		)
		(property "Value" ""
			(at 0 0 270)
			(layer "F.Fab")
			(effects
				(font
					(size 1.27 1.27)
				)
			)
		)
		(duplicate_pad_numbers_are_jumpers no)
		(fp_line
			(start -0.7874 0.4064)
			(end -0.7874 -0.4064)
			(stroke
				(width 0.1524)
				(type default)
			)
			(layer "F.SilkS")
		)
		(fp_line
			(start 0.7874 0.4064)
			(end -0.7874 0.4064)
			(stroke
				(width 0.1524)
				(type default)
			)
			(layer "F.SilkS")
		)
		(fp_line
			(start -0.7874 -0.4064)
			(end 0.7874 -0.4064)
			(stroke
				(width 0.1524)
				(type default)
			)
			(layer "F.SilkS")
		)
		(fp_line
			(start 0.7874 -0.4064)
			(end 0.7874 0.4064)
			(stroke
				(width 0.1524)
				(type default)
			)
			(layer "F.SilkS")
		)
		(fp_line
			(start -0.67945 0.3048)
			(end -0.67945 -0.305054)
			(stroke
				(width 0.1)
				(type default)
			)
			(layer "F.Fab")
		)
		(fp_line
			(start -0.12065 0.3048)
			(end -0.67945 0.3048)
			(stroke
				(width 0.1)
				(type default)
			)
			(layer "F.Fab")
		)
		(fp_line
			(start 0.120396 0.3048)
			(end 0.120396 0.2794)
			(stroke
				(width 0.1)
				(type default)
			)
			(layer "F.Fab")
		)
		(fp_line
			(start 0.67945 0.3048)
			(end 0.120396 0.3048)
			(stroke
				(width 0.1)
				(type default)
			)
			(layer "F.Fab")
		)
		(fp_line
			(start -0.12065 0.2794)
			(end -0.12065 0.3048)
			(stroke
				(width 0.1)
				(type default)
			)
			(layer "F.Fab")
		)
		(fp_line
			(start 0.120396 0.2794)
			(end -0.12065 0.2794)
			(stroke
				(width 0.1)
				(type default)
			)
			(layer "F.Fab")
		)
		(fp_line
			(start -0.12065 -0.2794)
			(end 0.12065 -0.2794)
			(stroke
				(width 0.1)
				(type default)
			)
			(layer "F.Fab")
		)
		(fp_line
			(start 0.12065 -0.2794)
			(end 0.12065 -0.3048)
			(stroke
				(width 0.1)
				(type default)
			)
			(layer "F.Fab")
		)
		(fp_line
			(start 0.12065 -0.3048)
			(end 0.67945 -0.3048)
			(stroke
				(width 0.1)
				(type default)
			)
			(layer "F.Fab")
		)
		(fp_line
			(start 0.67945 -0.3048)
			(end 0.67945 0.3048)
			(stroke
				(width 0.1)
				(type default)
			)
			(layer "F.Fab")
		)
		(fp_line
			(start -0.67945 -0.305054)
			(end -0.12065 -0.305054)
			(stroke
				(width 0.1)
				(type default)
			)
			(layer "F.Fab")
		)
		(fp_line
			(start -0.12065 -0.305054)
			(end -0.12065 -0.2794)
			(stroke
				(width 0.1)
				(type default)
			)
			(layer "F.Fab")
		)
		(pad "1" smd circle
			(at -0.40005 0 270)
			(size 0 0)
			(layers "F.Cu" "F.Mask" "F.Paste")
			(net "SSD12_AUX_P3V3_EN_R")
		)
		(pad "2" smd circle
			(at 0.40005 0 270)
			(size 0 0)
			(layers "F.Cu" "F.Mask" "F.Paste")
			(net "P3V3_SSD12_CO_EN")
		)
	)
	(footprint ""
		(layer "F.Cu")
		(at 358.168194 -391.047478 180)
		(property "Reference" "R6696"
			(at 0 0 180)
			(layer "F.SilkS")
			(hide yes)
			(effects
				(font
					(size 1.27 1.27)
				)
			)
		)
		(property "Value" ""
			(at 0 0 180)
			(layer "F.Fab")
			(effects
				(font
					(size 1.27 1.27)
				)
			)
		)
		(duplicate_pad_numbers_are_jumpers no)
		(fp_line
			(start 0.7874 0.4064)
			(end -0.7874 0.4064)
			(stroke
				(width 0.1524)
				(type default)
			)
			(layer "F.SilkS")
		)
		(fp_line
			(start 0.7874 -0.4064)
			(end 0.7874 0.4064)
			(stroke
				(width 0.1524)
				(type default)
			)
			(layer "F.SilkS")
		)
		(fp_line
			(start -0.7874 0.4064)
			(end -0.7874 -0.4064)
			(stroke
				(width 0.1524)
				(type default)
			)
			(layer "F.SilkS")
		)
		(fp_line
			(start -0.7874 -0.4064)
			(end 0.7874 -0.4064)
			(stroke
				(width 0.1524)
				(type default)
			)
			(layer "F.SilkS")
		)
		(fp_line
			(start 0.67945 0.3048)
			(end 0.120396 0.3048)
			(stroke
				(width 0.1)
				(type default)
			)
			(layer "F.Fab")
		)
		(fp_line
			(start 0.67945 -0.3048)
			(end 0.67945 0.3048)
			(stroke
				(width 0.1)
				(type default)
			)
			(layer "F.Fab")
		)
		(fp_line
			(start 0.12065 -0.2794)
			(end 0.12065 -0.3048)
			(stroke
				(width 0.1)
				(type default)
			)
			(layer "F.Fab")
		)
		(fp_line
			(start 0.12065 -0.3048)
			(end 0.67945 -0.3048)
			(stroke
				(width 0.1)
				(type default)
			)
			(layer "F.Fab")
		)
		(fp_line
			(start 0.120396 0.3048)
			(end 0.120396 0.2794)
			(stroke
				(width 0.1)
				(type default)
			)
			(layer "F.Fab")
		)
		(fp_line
			(start 0.120396 0.2794)
			(end -0.12065 0.2794)
			(stroke
				(width 0.1)
				(type default)
			)
			(layer "F.Fab")
		)
		(fp_line
			(start -0.12065 0.3048)
			(end -0.67945 0.3048)
			(stroke
				(width 0.1)
				(type default)
			)
			(layer "F.Fab")
		)
		(fp_line
			(start -0.12065 0.2794)
			(end -0.12065 0.3048)
			(stroke
				(width 0.1)
				(type default)
			)
			(layer "F.Fab")
		)
		(fp_line
			(start -0.12065 -0.2794)
			(end 0.12065 -0.2794)
			(stroke
				(width 0.1)
				(type default)
			)
			(layer "F.Fab")
		)
		(fp_line
			(start -0.12065 -0.305054)
			(end -0.12065 -0.2794)
			(stroke
				(width 0.1)
				(type default)
			)
			(layer "F.Fab")
		)
		(fp_line
			(start -0.67945 0.3048)
			(end -0.67945 -0.305054)
			(stroke
				(width 0.1)
				(type default)
			)
			(layer "F.Fab")
		)
		(fp_line
			(start -0.67945 -0.305054)
			(end -0.12065 -0.305054)
			(stroke
				(width 0.1)
				(type default)
			)
			(layer "F.Fab")
		)
		(pad "1" smd circle
			(at -0.40005 0 180)
			(size 0 0)
			(layers "F.Cu" "F.Mask" "F.Paste")
			(net "MB_3V3IO_RSVD1_N")
		)
		(pad "2" smd circle
			(at 0.40005 0 180)
			(size 0 0)
			(layers "F.Cu" "F.Mask" "F.Paste")
			(net "P3V3_AUX")
		)
	)
	(footprint ""
		(layer "F.Cu")
		(at 248.698766 -254.192786 -90)
		(property "Reference" "C4357"
			(at 0 0 270)
			(layer "F.SilkS")
			(hide yes)
			(effects
				(font
					(size 1.27 1.27)
				)
			)
		)
		(property "Value" ""
			(at 0 0 270)
			(layer "F.Fab")
			(effects
				(font
					(size 1.27 1.27)
				)
			)
		)
		(duplicate_pad_numbers_are_jumpers no)
		(fp_line
			(start -1.524 0.762)
			(end -1.524 -0.762)
			(stroke
				(width 0.1524)
				(type default)
			)
			(layer "F.SilkS")
		)
		(fp_line
			(start 1.524 0.762)
			(end -1.524 0.762)
			(stroke
				(width 0.1524)
				(type default)
			)
			(layer "F.SilkS")
		)
		(fp_line
			(start -1.524 -0.762)
			(end 1.524 -0.762)
			(stroke
				(width 0.1524)
				(type default)
			)
			(layer "F.SilkS")
		)
		(fp_line
			(start 1.524 -0.762)
			(end 1.524 0.762)
			(stroke
				(width 0.1524)
				(type default)
			)
			(layer "F.SilkS")
		)
		(fp_line
			(start -1.1049 0.724916)
			(end 1.1049 0.724916)
			(stroke
				(width 0.1)
				(type default)
			)
			(layer "F.Fab")
		)
		(fp_line
			(start 1.1049 0.724916)
			(end 1.1049 -0.724916)
			(stroke
				(width 0.1)
				(type default)
			)
			(layer "F.Fab")
		)
		(fp_line
			(start -1.1049 -0.724916)
			(end -1.1049 0.724916)
			(stroke
				(width 0.1)
				(type default)
			)
			(layer "F.Fab")
		)
		(fp_line
			(start 1.1049 -0.724916)
			(end -1.1049 -0.724916)
			(stroke
				(width 0.1)
				(type default)
			)
			(layer "F.Fab")
		)
		(pad "1" smd rect
			(at -0.889 0 90)
			(size 1.016 1.27)
			(layers "F.Cu" "F.Mask" "F.Paste")
			(net "P1V25_SERDES_VDDPLL_PEX2_C11")
		)
		(pad "2" smd rect
			(at 0.889 0 90)
			(size 1.016 1.27)
			(layers "F.Cu" "F.Mask" "F.Paste")
			(net "GND")
		)
		(zone
			(layer "F.Cu")
			(hatch none 0.5)
			(connect_pads
				(clearance 0)
			)
			(min_thickness 0.25)
			(keepout
				(tracks not_allowed)
				(vias allowed)
				(pads allowed)
				(copperpour not_allowed)
				(footprints allowed)
			)
			(placement
				(enabled no)
				(sheetname "")
			)
			(fill
				(thermal_gap 0.5)
				(thermal_bridge_width 0.5)
				(island_removal_mode 0)
			)
			(polygon
				(pts
					(xy 249.423682 -254.522986) (xy 247.97385 -254.522986) (xy 247.97385 -253.862586) (xy 249.423682 -253.862586)
				)
			)
		)
	)
	(footprint ""
		(layer "F.Cu")
		(at 187.346844 -37.47516)
		(property "Reference" "R6075"
			(at 0 0 0)
			(layer "F.SilkS")
			(hide yes)
			(effects
				(font
					(size 1.27 1.27)
				)
			)
		)
		(property "Value" ""
			(at 0 0 0)
			(layer "F.Fab")
			(effects
				(font
					(size 1.27 1.27)
				)
			)
		)
		(duplicate_pad_numbers_are_jumpers no)
		(fp_line
			(start -0.7874 -0.4064)
			(end 0.7874 -0.4064)
			(stroke
				(width 0.1524)
				(type default)
			)
			(layer "F.SilkS")
		)
		(fp_line
			(start -0.7874 0.4064)
			(end -0.7874 -0.4064)
			(stroke
				(width 0.1524)
				(type default)
			)
			(layer "F.SilkS")
		)
		(fp_line
			(start 0.7874 -0.4064)
			(end 0.7874 0.4064)
			(stroke
				(width 0.1524)
				(type default)
			)
			(layer "F.SilkS")
		)
		(fp_line
			(start 0.7874 0.4064)
			(end -0.7874 0.4064)
			(stroke
				(width 0.1524)
				(type default)
			)
			(layer "F.SilkS")
		)
		(fp_line
			(start -0.67945 -0.305054)
			(end -0.12065 -0.305054)
			(stroke
				(width 0.1)
				(type default)
			)
			(layer "F.Fab")
		)
		(fp_line
			(start -0.67945 0.3048)
			(end -0.67945 -0.305054)
			(stroke
				(width 0.1)
				(type default)
			)
			(layer "F.Fab")
		)
		(fp_line
			(start -0.12065 -0.305054)
			(end -0.12065 -0.2794)
			(stroke
				(width 0.1)
				(type default)
			)
			(layer "F.Fab")
		)
		(fp_line
			(start -0.12065 -0.2794)
			(end 0.12065 -0.2794)
			(stroke
				(width 0.1)
				(type default)
			)
			(layer "F.Fab")
		)
		(fp_line
			(start -0.12065 0.2794)
			(end -0.12065 0.3048)
			(stroke
				(width 0.1)
				(type default)
			)
			(layer "F.Fab")
		)
		(fp_line
			(start -0.12065 0.3048)
			(end -0.67945 0.3048)
			(stroke
				(width 0.1)
				(type default)
			)
			(layer "F.Fab")
		)
		(fp_line
			(start 0.120396 0.2794)
			(end -0.12065 0.2794)
			(stroke
				(width 0.1)
				(type default)
			)
			(layer "F.Fab")
		)
		(fp_line
			(start 0.120396 0.3048)
			(end 0.120396 0.2794)
			(stroke
				(width 0.1)
				(type default)
			)
			(layer "F.Fab")
		)
		(fp_line
			(start 0.12065 -0.3048)
			(end 0.67945 -0.3048)
			(stroke
				(width 0.1)
				(type default)
			)
			(layer "F.Fab")
		)
		(fp_line
			(start 0.12065 -0.2794)
			(end 0.12065 -0.3048)
			(stroke
				(width 0.1)
				(type default)
			)
			(layer "F.Fab")
		)
		(fp_line
			(start 0.67945 -0.3048)
			(end 0.67945 0.3048)
			(stroke
				(width 0.1)
				(type default)
			)
			(layer "F.Fab")
		)
		(fp_line
			(start 0.67945 0.3048)
			(end 0.120396 0.3048)
			(stroke
				(width 0.1)
				(type default)
			)
			(layer "F.Fab")
		)
		(pad "1" smd circle
			(at -0.40005 0)
			(size 0 0)
			(layers "F.Cu" "F.Mask" "F.Paste")
			(net "P3V3_SSD7")
		)
		(pad "2" smd circle
			(at 0.40005 0)
			(size 0 0)
			(layers "F.Cu" "F.Mask" "F.Paste")
			(net "P3V3_SSD7_PG_G1")
		)
	)
	(footprint ""
		(layer "F.Cu")
		(at 142.343886 -49.95291 180)
		(property "Reference" "R555"
			(at 0 0 180)
			(layer "F.SilkS")
			(hide yes)
			(effects
				(font
					(size 1.27 1.27)
				)
			)
		)
		(property "Value" ""
			(at 0 0 180)
			(layer "F.Fab")
			(effects
				(font
					(size 1.27 1.27)
				)
			)
		)
		(duplicate_pad_numbers_are_jumpers no)
		(fp_line
			(start 0.7874 0.4064)
			(end -0.7874 0.4064)
			(stroke
				(width 0.1524)
				(type default)
			)
			(layer "F.SilkS")
		)
		(fp_line
			(start 0.7874 -0.4064)
			(end 0.7874 0.4064)
			(stroke
				(width 0.1524)
				(type default)
			)
			(layer "F.SilkS")
		)
		(fp_line
			(start -0.7874 0.4064)
			(end -0.7874 -0.4064)
			(stroke
				(width 0.1524)
				(type default)
			)
			(layer "F.SilkS")
		)
		(fp_line
			(start -0.7874 -0.4064)
			(end 0.7874 -0.4064)
			(stroke
				(width 0.1524)
				(type default)
			)
			(layer "F.SilkS")
		)
		(fp_line
			(start 0.67945 0.3048)
			(end 0.120396 0.3048)
			(stroke
				(width 0.1)
				(type default)
			)
			(layer "F.Fab")
		)
		(fp_line
			(start 0.67945 -0.3048)
			(end 0.67945 0.3048)
			(stroke
				(width 0.1)
				(type default)
			)
			(layer "F.Fab")
		)
		(fp_line
			(start 0.12065 -0.2794)
			(end 0.12065 -0.3048)
			(stroke
				(width 0.1)
				(type default)
			)
			(layer "F.Fab")
		)
		(fp_line
			(start 0.12065 -0.3048)
			(end 0.67945 -0.3048)
			(stroke
				(width 0.1)
				(type default)
			)
			(layer "F.Fab")
		)
		(fp_line
			(start 0.120396 0.3048)
			(end 0.120396 0.2794)
			(stroke
				(width 0.1)
				(type default)
			)
			(layer "F.Fab")
		)
		(fp_line
			(start 0.120396 0.2794)
			(end -0.12065 0.2794)
			(stroke
				(width 0.1)
				(type default)
			)
			(layer "F.Fab")
		)
		(fp_line
			(start -0.12065 0.3048)
			(end -0.67945 0.3048)
			(stroke
				(width 0.1)
				(type default)
			)
			(layer "F.Fab")
		)
		(fp_line
			(start -0.12065 0.2794)
			(end -0.12065 0.3048)
			(stroke
				(width 0.1)
				(type default)
			)
			(layer "F.Fab")
		)
		(fp_line
			(start -0.12065 -0.2794)
			(end 0.12065 -0.2794)
			(stroke
				(width 0.1)
				(type default)
			)
			(layer "F.Fab")
		)
		(fp_line
			(start -0.12065 -0.305054)
			(end -0.12065 -0.2794)
			(stroke
				(width 0.1)
				(type default)
			)
			(layer "F.Fab")
		)
		(fp_line
			(start -0.67945 0.3048)
			(end -0.67945 -0.305054)
			(stroke
				(width 0.1)
				(type default)
			)
			(layer "F.Fab")
		)
		(fp_line
			(start -0.67945 -0.305054)
			(end -0.12065 -0.305054)
			(stroke
				(width 0.1)
				(type default)
			)
			(layer "F.Fab")
		)
		(pad "1" smd circle
			(at -0.40005 0 180)
			(size 0 0)
			(layers "F.Cu" "F.Mask" "F.Paste")
			(net "SMB_BIC_I2C6_MUX_SSD_0_7_ADC_R_SCL")
		)
		(pad "2" smd circle
			(at 0.40005 0 180)
			(size 0 0)
			(layers "F.Cu" "F.Mask" "F.Paste")
			(net "SMB_SSD4_ADC_SCL")
		)
	)
	(footprint ""
		(layer "F.Cu")
		(at 10.530586 -142.035276 180)
		(property "Reference" "PC601"
			(at 0 0 180)
			(layer "F.SilkS")
			(hide yes)
			(effects
				(font
					(size 1.27 1.27)
				)
			)
		)
		(property "Value" ""
			(at 0 0 180)
			(layer "F.Fab")
			(effects
				(font
					(size 1.27 1.27)
				)
			)
		)
		(duplicate_pad_numbers_are_jumpers no)
		(fp_line
			(start 1.524 0.762)
			(end -1.524 0.762)
			(stroke
				(width 0.1524)
				(type default)
			)
			(layer "F.SilkS")
		)
		(fp_line
			(start 1.524 -0.762)
			(end 1.524 0.762)
			(stroke
				(width 0.1524)
				(type default)
			)
			(layer "F.SilkS")
		)
		(fp_line
			(start -1.524 0.762)
			(end -1.524 -0.762)
			(stroke
				(width 0.1524)
				(type default)
			)
			(layer "F.SilkS")
		)
		(fp_line
			(start -1.524 -0.762)
			(end 1.524 -0.762)
			(stroke
				(width 0.1524)
				(type default)
			)
			(layer "F.SilkS")
		)
		(fp_line
			(start 1.1049 0.724916)
			(end 1.1049 -0.724916)
			(stroke
				(width 0.1)
				(type default)
			)
			(layer "F.Fab")
		)
		(fp_line
			(start 1.1049 -0.724916)
			(end -1.1049 -0.724916)
			(stroke
				(width 0.1)
				(type default)
			)
			(layer "F.Fab")
		)
		(fp_line
			(start -1.1049 0.724916)
			(end 1.1049 0.724916)
			(stroke
				(width 0.1)
				(type default)
			)
			(layer "F.Fab")
		)
		(fp_line
			(start -1.1049 -0.724916)
			(end -1.1049 0.724916)
			(stroke
				(width 0.1)
				(type default)
			)
			(layer "F.Fab")
		)
		(pad "1" smd rect
			(at -0.889 0)
			(size 1.016 1.27)
			(layers "F.Cu" "F.Mask" "F.Paste")
			(net "P12V_NIC0_R")
		)
		(pad "2" smd rect
			(at 0.889 0)
			(size 1.016 1.27)
			(layers "F.Cu" "F.Mask" "F.Paste")
			(net "GND")
		)
	)
	(footprint ""
		(layer "F.Cu")
		(at 250.868688 -149.313392 -90)
		(property "Reference" "U83"
			(at 0.012192 -2.472182 90)
			(unlocked yes)
			(layer "F.SilkS")
			(effects
				(font
					(size 0.7874 0.5842)
					(thickness 0.1524)
				)
			)
		)
		(property "Value" ""
			(at 0 0 270)
			(layer "F.Fab")
			(effects
				(font
					(size 1.27 1.27)
				)
			)
		)
		(duplicate_pad_numbers_are_jumpers no)
		(fp_line
			(start -1.500124 1.500124)
			(end -1.500124 1.004062)
			(stroke
				(width 0.1524)
				(type default)
			)
			(layer "F.SilkS")
		)
		(fp_line
			(start -1.004062 1.500124)
			(end -1.500124 1.500124)
			(stroke
				(width 0.1524)
				(type default)
			)
			(layer "F.SilkS")
		)
		(fp_line
			(start 1.500124 1.500124)
			(end 1.004062 1.500124)
			(stroke
				(width 0.1524)
				(type default)
			)
			(layer "F.SilkS")
		)
		(fp_line
			(start 1.500124 1.004062)
			(end 1.500124 1.500124)
			(stroke
				(width 0.1524)
				(type default)
			)
			(layer "F.SilkS")
		)
		(fp_line
			(start -1.500124 -1.004062)
			(end -1.500124 -1.500124)
			(stroke
				(width 0.1524)
				(type default)
			)
			(layer "F.SilkS")
		)
		(fp_line
			(start -1.500124 -1.500124)
			(end -1.004062 -1.500124)
			(stroke
				(width 0.1524)
				(type default)
			)
			(layer "F.SilkS")
		)
		(fp_line
			(start 1.004062 -1.500124)
			(end 1.500124 -1.500124)
			(stroke
				(width 0.1524)
				(type default)
			)
			(layer "F.SilkS")
		)
		(fp_line
			(start 1.500124 -1.500124)
			(end 1.500124 -1.004062)
			(stroke
				(width 0.1524)
				(type default)
			)
			(layer "F.SilkS")
		)
		(fp_poly
			(pts
				(xy -1.975104 -2.088388) (xy -2.693416 -1.369822) (xy -1.615948 -1.010666)
			)
			(stroke
				(width 0)
				(type default)
			)
			(fill yes)
			(layer "F.SilkS")
		)
		(fp_line
			(start -1.500124 1.500124)
			(end -1.500124 -1.500124)
			(stroke
				(width 0.1)
				(type default)
			)
			(layer "F.Fab")
		)
		(fp_line
			(start 1.500124 1.500124)
			(end -1.500124 1.500124)
			(stroke
				(width 0.1)
				(type default)
			)
			(layer "F.Fab")
		)
		(fp_line
			(start -1.500124 -1.500124)
			(end 1.500124 -1.500124)
			(stroke
				(width 0.1)
				(type default)
			)
			(layer "F.Fab")
		)
		(fp_line
			(start 1.500124 -1.500124)
			(end 1.500124 1.500124)
			(stroke
				(width 0.1)
				(type default)
			)
			(layer "F.Fab")
		)
		(fp_poly
			(pts
				(xy -2.847848 -1.258062) (xy -2.847848 -0.242062) (xy -1.831848 -0.750062)
			)
			(stroke
				(width 0)
				(type default)
			)
			(fill yes)
			(layer "F.Fab")
		)
		(pad "1" smd rect
			(at -1.400048 -0.750062 180)
			(size 0.2286 0.6096)
			(layers "F.Cu" "F.Mask" "F.Paste")
			(net "NIC4_ADC_A1")
		)
		(pad "2" smd rect
			(at -1.400048 -0.249936 180)
			(size 0.2286 0.6096)
			(layers "F.Cu" "F.Mask" "F.Paste")
			(net "NIC4_ADC_A0")
		)
		(pad "3" smd rect
			(at -1.400048 0.249936 180)
			(size 0.2286 0.6096)
			(layers "F.Cu" "F.Mask" "F.Paste")
			(net "NIC4_ADC_ALERT_N")
		)
		(pad "4" smd rect
			(at -1.400048 0.750062 180)
			(size 0.2286 0.6096)
			(layers "F.Cu" "F.Mask" "F.Paste")
			(net "SMB_NIC4_ADC_SDA")
		)
		(pad "5" smd rect
			(at -0.750062 1.400048 270)
			(size 0.2286 0.6096)
			(layers "F.Cu" "F.Mask" "F.Paste")
			(net "SMB_NIC4_ADC_SCL")
		)
		(pad "6" smd rect
			(at -0.249936 1.400048 270)
			(size 0.2286 0.6096)
			(layers "F.Cu" "F.Mask" "F.Paste")
			(net "Net_8642")
		)
		(pad "7" smd rect
			(at 0.249936 1.400048 270)
			(size 0.2286 0.6096)
			(layers "F.Cu" "F.Mask" "F.Paste")
			(net "Net_8641")
		)
		(pad "8" smd rect
			(at 0.750062 1.400048 270)
			(size 0.2286 0.6096)
			(layers "F.Cu" "F.Mask" "F.Paste")
			(net "Net_8640")
		)
		(pad "9" smd rect
			(at 1.400048 0.750062 180)
			(size 0.2286 0.6096)
			(layers "F.Cu" "F.Mask" "F.Paste")
			(net "P3V3_AUX")
		)
		(pad "10" smd rect
			(at 1.400048 0.249936 180)
			(size 0.2286 0.6096)
			(layers "F.Cu" "F.Mask" "F.Paste")
			(net "GND")
		)
		(pad "11" smd rect
			(at 1.400048 -0.249936 180)
			(size 0.2286 0.6096)
			(layers "F.Cu" "F.Mask" "F.Paste")
			(net "P12V_NIC4_R")
		)
		(pad "12" smd rect
			(at 1.400048 -0.750062 180)
			(size 0.2286 0.6096)
			(layers "F.Cu" "F.Mask" "F.Paste")
			(net "P12V_NIC4_VIN_N")
		)
		(pad "13" smd rect
			(at 0.750062 -1.400048 270)
			(size 0.2286 0.6096)
			(layers "F.Cu" "F.Mask" "F.Paste")
			(net "P12V_NIC4_VIN_P")
		)
		(pad "14" smd rect
			(at 0.249936 -1.400048 270)
			(size 0.2286 0.6096)
			(layers "F.Cu" "F.Mask" "F.Paste")
			(net "Net_8639")
		)
		(pad "15" smd rect
			(at -0.249936 -1.400048 270)
			(size 0.2286 0.6096)
			(layers "F.Cu" "F.Mask" "F.Paste")
			(net "Net_8638")
		)
		(pad "16" smd rect
			(at -0.750062 -1.400048 270)
			(size 0.2286 0.6096)
			(layers "F.Cu" "F.Mask" "F.Paste")
			(net "Net_8637")
		)
		(pad "TH" smd rect
			(at 0 0 270)
			(size 1.7018 1.7018)
			(layers "F.Cu" "F.Mask" "F.Paste")
			(net "GND")
		)
		(zone
			(layer "F.Cu")
			(hatch none 0.5)
			(connect_pads
				(clearance 0)
			)
			(min_thickness 0.25)
			(keepout
				(tracks not_allowed)
				(vias allowed)
				(pads allowed)
				(copperpour not_allowed)
				(footprints allowed)
			)
			(placement
				(enabled no)
				(sheetname "")
			)
			(fill
				(thermal_gap 0.5)
				(thermal_bridge_width 0.5)
				(island_removal_mode 0)
			)
			(polygon
				(pts
					(xy 250.894088 -150.35784) (xy 251.913136 -150.35784) (xy 251.913136 -148.268944) (xy 249.82424 -148.268944)
					(xy 249.82424 -150.35784) (xy 250.868688 -150.35784) (xy 250.868688 -150.215092) (xy 249.966988 -150.215092)
					(xy 249.966988 -148.411692) (xy 251.770388 -148.411692) (xy 251.770388 -150.215092) (xy 250.894088 -150.215092)
				)
			)
		)
	)
	(footprint ""
		(layer "F.Cu")
		(at 187.626752 -55.418228 90)
		(property "Reference" "PC382"
			(at 0 0 90)
			(layer "F.SilkS")
			(hide yes)
			(effects
				(font
					(size 1.27 1.27)
				)
			)
		)
		(property "Value" ""
			(at 0 0 90)
			(layer "F.Fab")
			(effects
				(font
					(size 1.27 1.27)
				)
			)
		)
		(duplicate_pad_numbers_are_jumpers no)
		(fp_line
			(start 0.7874 -0.4064)
			(end 0.7874 0.4064)
			(stroke
				(width 0.1524)
				(type default)
			)
			(layer "F.SilkS")
		)
		(fp_line
			(start -0.7874 -0.4064)
			(end 0.7874 -0.4064)
			(stroke
				(width 0.1524)
				(type default)
			)
			(layer "F.SilkS")
		)
		(fp_line
			(start 0.7874 0.4064)
			(end -0.7874 0.4064)
			(stroke
				(width 0.1524)
				(type default)
			)
			(layer "F.SilkS")
		)
		(fp_line
			(start -0.7874 0.4064)
			(end -0.7874 -0.4064)
			(stroke
				(width 0.1524)
				(type default)
			)
			(layer "F.SilkS")
		)
		(fp_line
			(start -0.12065 -0.305054)
			(end -0.12065 -0.2794)
			(stroke
				(width 0.1)
				(type default)
			)
			(layer "F.Fab")
		)
		(fp_line
			(start -0.67945 -0.305054)
			(end -0.12065 -0.305054)
			(stroke
				(width 0.1)
				(type default)
			)
			(layer "F.Fab")
		)
		(fp_line
			(start 0.67945 -0.3048)
			(end 0.67945 0.3048)
			(stroke
				(width 0.1)
				(type default)
			)
			(layer "F.Fab")
		)
		(fp_line
			(start 0.12065 -0.3048)
			(end 0.67945 -0.3048)
			(stroke
				(width 0.1)
				(type default)
			)
			(layer "F.Fab")
		)
		(fp_line
			(start 0.12065 -0.2794)
			(end 0.12065 -0.3048)
			(stroke
				(width 0.1)
				(type default)
			)
			(layer "F.Fab")
		)
		(fp_line
			(start -0.12065 -0.2794)
			(end 0.12065 -0.2794)
			(stroke
				(width 0.1)
				(type default)
			)
			(layer "F.Fab")
		)
		(fp_line
			(start 0.120396 0.2794)
			(end -0.12065 0.2794)
			(stroke
				(width 0.1)
				(type default)
			)
			(layer "F.Fab")
		)
		(fp_line
			(start -0.12065 0.2794)
			(end -0.12065 0.3048)
			(stroke
				(width 0.1)
				(type default)
			)
			(layer "F.Fab")
		)
		(fp_line
			(start 0.67945 0.3048)
			(end 0.120396 0.3048)
			(stroke
				(width 0.1)
				(type default)
			)
			(layer "F.Fab")
		)
		(fp_line
			(start 0.120396 0.3048)
			(end 0.120396 0.2794)
			(stroke
				(width 0.1)
				(type default)
			)
			(layer "F.Fab")
		)
		(fp_line
			(start -0.12065 0.3048)
			(end -0.67945 0.3048)
			(stroke
				(width 0.1)
				(type default)
			)
			(layer "F.Fab")
		)
		(fp_line
			(start -0.67945 0.3048)
			(end -0.67945 -0.305054)
			(stroke
				(width 0.1)
				(type default)
			)
			(layer "F.Fab")
		)
		(pad "1" smd circle
			(at -0.40005 0 90)
			(size 0 0)
			(layers "F.Cu" "F.Mask" "F.Paste")
			(net "P12V_SSD6_R")
		)
		(pad "2" smd circle
			(at 0.40005 0 90)
			(size 0 0)
			(layers "F.Cu" "F.Mask" "F.Paste")
			(net "GND")
		)
	)
	(footprint ""
		(layer "F.Cu")
		(at 270.807942 -153.3144 180)
		(property "Reference" "R229"
			(at 0 0 180)
			(layer "F.SilkS")
			(hide yes)
			(effects
				(font
					(size 1.27 1.27)
				)
			)
		)
		(property "Value" ""
			(at 0 0 180)
			(layer "F.Fab")
			(effects
				(font
					(size 1.27 1.27)
				)
			)
		)
		(duplicate_pad_numbers_are_jumpers no)
		(fp_line
			(start 0.7874 0.4064)
			(end -0.7874 0.4064)
			(stroke
				(width 0.1524)
				(type default)
			)
			(layer "F.SilkS")
		)
		(fp_line
			(start 0.7874 -0.4064)
			(end 0.7874 0.4064)
			(stroke
				(width 0.1524)
				(type default)
			)
			(layer "F.SilkS")
		)
		(fp_line
			(start -0.7874 0.4064)
			(end -0.7874 -0.4064)
			(stroke
				(width 0.1524)
				(type default)
			)
			(layer "F.SilkS")
		)
		(fp_line
			(start -0.7874 -0.4064)
			(end 0.7874 -0.4064)
			(stroke
				(width 0.1524)
				(type default)
			)
			(layer "F.SilkS")
		)
		(fp_line
			(start 0.67945 0.3048)
			(end 0.120396 0.3048)
			(stroke
				(width 0.1)
				(type default)
			)
			(layer "F.Fab")
		)
		(fp_line
			(start 0.67945 -0.3048)
			(end 0.67945 0.3048)
			(stroke
				(width 0.1)
				(type default)
			)
			(layer "F.Fab")
		)
		(fp_line
			(start 0.12065 -0.2794)
			(end 0.12065 -0.3048)
			(stroke
				(width 0.1)
				(type default)
			)
			(layer "F.Fab")
		)
		(fp_line
			(start 0.12065 -0.3048)
			(end 0.67945 -0.3048)
			(stroke
				(width 0.1)
				(type default)
			)
			(layer "F.Fab")
		)
		(fp_line
			(start 0.120396 0.3048)
			(end 0.120396 0.2794)
			(stroke
				(width 0.1)
				(type default)
			)
			(layer "F.Fab")
		)
		(fp_line
			(start 0.120396 0.2794)
			(end -0.12065 0.2794)
			(stroke
				(width 0.1)
				(type default)
			)
			(layer "F.Fab")
		)
		(fp_line
			(start -0.12065 0.3048)
			(end -0.67945 0.3048)
			(stroke
				(width 0.1)
				(type default)
			)
			(layer "F.Fab")
		)
		(fp_line
			(start -0.12065 0.2794)
			(end -0.12065 0.3048)
			(stroke
				(width 0.1)
				(type default)
			)
			(layer "F.Fab")
		)
		(fp_line
			(start -0.12065 -0.2794)
			(end 0.12065 -0.2794)
			(stroke
				(width 0.1)
				(type default)
			)
			(layer "F.Fab")
		)
		(fp_line
			(start -0.12065 -0.305054)
			(end -0.12065 -0.2794)
			(stroke
				(width 0.1)
				(type default)
			)
			(layer "F.Fab")
		)
		(fp_line
			(start -0.67945 0.3048)
			(end -0.67945 -0.305054)
			(stroke
				(width 0.1)
				(type default)
			)
			(layer "F.Fab")
		)
		(fp_line
			(start -0.67945 -0.305054)
			(end -0.12065 -0.305054)
			(stroke
				(width 0.1)
				(type default)
			)
			(layer "F.Fab")
		)
		(pad "1" smd circle
			(at -0.40005 0 180)
			(size 0 0)
			(layers "F.Cu" "F.Mask" "F.Paste")
			(net "NIC4_SLOT_ID0")
		)
		(pad "2" smd circle
			(at 0.40005 0 180)
			(size 0 0)
			(layers "F.Cu" "F.Mask" "F.Paste")
			(net "P3V3_NIC4")
		)
	)
	(footprint ""
		(layer "F.Cu")
		(at 292.743382 -343.952322 90)
		(property "Reference" "C2363"
			(at 0 0 90)
			(layer "F.SilkS")
			(hide yes)
			(effects
				(font
					(size 1.27 1.27)
				)
			)
		)
		(property "Value" ""
			(at 0 0 90)
			(layer "F.Fab")
			(effects
				(font
					(size 1.27 1.27)
				)
			)
		)
		(duplicate_pad_numbers_are_jumpers no)
		(fp_line
			(start 0.299974 -0.150114)
			(end 0.299974 0.150114)
			(stroke
				(width 0.1)
				(type default)
			)
			(layer "F.Fab")
		)
		(fp_line
			(start -0.299974 -0.150114)
			(end 0.299974 -0.150114)
			(stroke
				(width 0.1)
				(type default)
			)
			(layer "F.Fab")
		)
		(fp_line
			(start 0.299974 0.150114)
			(end -0.299974 0.150114)
			(stroke
				(width 0.1)
				(type default)
			)
			(layer "F.Fab")
		)
		(fp_line
			(start -0.299974 0.150114)
			(end -0.299974 -0.150114)
			(stroke
				(width 0.1)
				(type default)
			)
			(layer "F.Fab")
		)
		(pad "1" smd rect
			(at -0.2667 0 90)
			(size 0.3048 0.381)
			(layers "F.Cu" "F.Mask" "F.Paste")
			(net "P5E_PEX2_STN4_TX_DP<68>")
		)
		(pad "2" smd rect
			(at 0.2667 0 90)
			(size 0.3048 0.381)
			(layers "F.Cu" "F.Mask" "F.Paste")
			(net "P5E_PEX2_STN4_TX_C_DP<68>")
		)
	)
	(footprint ""
		(layer "F.Cu")
		(at 336.042 -173.101 180)
		(property "Reference" "R4765"
			(at 0 0 180)
			(layer "F.SilkS")
			(hide yes)
			(effects
				(font
					(size 1.27 1.27)
				)
			)
		)
		(property "Value" ""
			(at 0 0 180)
			(layer "F.Fab")
			(effects
				(font
					(size 1.27 1.27)
				)
			)
		)
		(duplicate_pad_numbers_are_jumpers no)
		(fp_line
			(start 0.7874 0.4064)
			(end -0.7874 0.4064)
			(stroke
				(width 0.1524)
				(type default)
			)
			(layer "F.SilkS")
		)
		(fp_line
			(start 0.7874 -0.4064)
			(end 0.7874 0.4064)
			(stroke
				(width 0.1524)
				(type default)
			)
			(layer "F.SilkS")
		)
		(fp_line
			(start -0.7874 0.4064)
			(end -0.7874 -0.4064)
			(stroke
				(width 0.1524)
				(type default)
			)
			(layer "F.SilkS")
		)
		(fp_line
			(start -0.7874 -0.4064)
			(end 0.7874 -0.4064)
			(stroke
				(width 0.1524)
				(type default)
			)
			(layer "F.SilkS")
		)
		(fp_line
			(start 0.67945 0.3048)
			(end 0.120396 0.3048)
			(stroke
				(width 0.1)
				(type default)
			)
			(layer "F.Fab")
		)
		(fp_line
			(start 0.67945 -0.3048)
			(end 0.67945 0.3048)
			(stroke
				(width 0.1)
				(type default)
			)
			(layer "F.Fab")
		)
		(fp_line
			(start 0.12065 -0.2794)
			(end 0.12065 -0.3048)
			(stroke
				(width 0.1)
				(type default)
			)
			(layer "F.Fab")
		)
		(fp_line
			(start 0.12065 -0.3048)
			(end 0.67945 -0.3048)
			(stroke
				(width 0.1)
				(type default)
			)
			(layer "F.Fab")
		)
		(fp_line
			(start 0.120396 0.3048)
			(end 0.120396 0.2794)
			(stroke
				(width 0.1)
				(type default)
			)
			(layer "F.Fab")
		)
		(fp_line
			(start 0.120396 0.2794)
			(end -0.12065 0.2794)
			(stroke
				(width 0.1)
				(type default)
			)
			(layer "F.Fab")
		)
		(fp_line
			(start -0.12065 0.3048)
			(end -0.67945 0.3048)
			(stroke
				(width 0.1)
				(type default)
			)
			(layer "F.Fab")
		)
		(fp_line
			(start -0.12065 0.2794)
			(end -0.12065 0.3048)
			(stroke
				(width 0.1)
				(type default)
			)
			(layer "F.Fab")
		)
		(fp_line
			(start -0.12065 -0.2794)
			(end 0.12065 -0.2794)
			(stroke
				(width 0.1)
				(type default)
			)
			(layer "F.Fab")
		)
		(fp_line
			(start -0.12065 -0.305054)
			(end -0.12065 -0.2794)
			(stroke
				(width 0.1)
				(type default)
			)
			(layer "F.Fab")
		)
		(fp_line
			(start -0.67945 0.3048)
			(end -0.67945 -0.305054)
			(stroke
				(width 0.1)
				(type default)
			)
			(layer "F.Fab")
		)
		(fp_line
			(start -0.67945 -0.305054)
			(end -0.12065 -0.305054)
			(stroke
				(width 0.1)
				(type default)
			)
			(layer "F.Fab")
		)
		(pad "1" smd circle
			(at -0.40005 0 180)
			(size 0 0)
			(layers "F.Cu" "F.Mask" "F.Paste")
			(net "PCA9555_1_PEX2_A1")
		)
		(pad "2" smd circle
			(at 0.40005 0 180)
			(size 0 0)
			(layers "F.Cu" "F.Mask" "F.Paste")
			(net "P3V3_AUX")
		)
	)
	(footprint ""
		(layer "F.Cu")
		(at 349.426276 -39.73576 -90)
		(property "Reference" "R5566"
			(at 0 0 270)
			(layer "F.SilkS")
			(hide yes)
			(effects
				(font
					(size 1.27 1.27)
				)
			)
		)
		(property "Value" ""
			(at 0 0 270)
			(layer "F.Fab")
			(effects
				(font
					(size 1.27 1.27)
				)
			)
		)
		(duplicate_pad_numbers_are_jumpers no)
		(fp_line
			(start -0.7874 0.4064)
			(end -0.7874 -0.4064)
			(stroke
				(width 0.1524)
				(type default)
			)
			(layer "F.SilkS")
		)
		(fp_line
			(start 0.7874 0.4064)
			(end -0.7874 0.4064)
			(stroke
				(width 0.1524)
				(type default)
			)
			(layer "F.SilkS")
		)
		(fp_line
			(start -0.7874 -0.4064)
			(end 0.7874 -0.4064)
			(stroke
				(width 0.1524)
				(type default)
			)
			(layer "F.SilkS")
		)
		(fp_line
			(start 0.7874 -0.4064)
			(end 0.7874 0.4064)
			(stroke
				(width 0.1524)
				(type default)
			)
			(layer "F.SilkS")
		)
		(fp_line
			(start -0.67945 0.3048)
			(end -0.67945 -0.305054)
			(stroke
				(width 0.1)
				(type default)
			)
			(layer "F.Fab")
		)
		(fp_line
			(start -0.12065 0.3048)
			(end -0.67945 0.3048)
			(stroke
				(width 0.1)
				(type default)
			)
			(layer "F.Fab")
		)
		(fp_line
			(start 0.120396 0.3048)
			(end 0.120396 0.2794)
			(stroke
				(width 0.1)
				(type default)
			)
			(layer "F.Fab")
		)
		(fp_line
			(start 0.67945 0.3048)
			(end 0.120396 0.3048)
			(stroke
				(width 0.1)
				(type default)
			)
			(layer "F.Fab")
		)
		(fp_line
			(start -0.12065 0.2794)
			(end -0.12065 0.3048)
			(stroke
				(width 0.1)
				(type default)
			)
			(layer "F.Fab")
		)
		(fp_line
			(start 0.120396 0.2794)
			(end -0.12065 0.2794)
			(stroke
				(width 0.1)
				(type default)
			)
			(layer "F.Fab")
		)
		(fp_line
			(start -0.12065 -0.2794)
			(end 0.12065 -0.2794)
			(stroke
				(width 0.1)
				(type default)
			)
			(layer "F.Fab")
		)
		(fp_line
			(start 0.12065 -0.2794)
			(end 0.12065 -0.3048)
			(stroke
				(width 0.1)
				(type default)
			)
			(layer "F.Fab")
		)
		(fp_line
			(start 0.12065 -0.3048)
			(end 0.67945 -0.3048)
			(stroke
				(width 0.1)
				(type default)
			)
			(layer "F.Fab")
		)
		(fp_line
			(start 0.67945 -0.3048)
			(end 0.67945 0.3048)
			(stroke
				(width 0.1)
				(type default)
			)
			(layer "F.Fab")
		)
		(fp_line
			(start -0.67945 -0.305054)
			(end -0.12065 -0.305054)
			(stroke
				(width 0.1)
				(type default)
			)
			(layer "F.Fab")
		)
		(fp_line
			(start -0.12065 -0.305054)
			(end -0.12065 -0.2794)
			(stroke
				(width 0.1)
				(type default)
			)
			(layer "F.Fab")
		)
		(pad "1" smd circle
			(at -0.40005 0 270)
			(size 0 0)
			(layers "F.Cu" "F.Mask" "F.Paste")
			(net "P3V3_AUX")
		)
		(pad "2" smd circle
			(at 0.40005 0 270)
			(size 0 0)
			(layers "F.Cu" "F.Mask" "F.Paste")
			(net "SSD12_AUX_P3V3_EN")
		)
	)
	(footprint ""
		(layer "F.Cu")
		(at 379.754384 -252.356874 -90)
		(property "Reference" "R1429"
			(at 0 0 270)
			(layer "F.SilkS")
			(hide yes)
			(effects
				(font
					(size 1.27 1.27)
				)
			)
		)
		(property "Value" ""
			(at 0 0 270)
			(layer "F.Fab")
			(effects
				(font
					(size 1.27 1.27)
				)
			)
		)
		(duplicate_pad_numbers_are_jumpers no)
		(fp_line
			(start -0.7874 0.4064)
			(end -0.7874 -0.4064)
			(stroke
				(width 0.1524)
				(type default)
			)
			(layer "F.SilkS")
		)
		(fp_line
			(start 0.7874 0.4064)
			(end -0.7874 0.4064)
			(stroke
				(width 0.1524)
				(type default)
			)
			(layer "F.SilkS")
		)
		(fp_line
			(start -0.7874 -0.4064)
			(end 0.7874 -0.4064)
			(stroke
				(width 0.1524)
				(type default)
			)
			(layer "F.SilkS")
		)
		(fp_line
			(start 0.7874 -0.4064)
			(end 0.7874 0.4064)
			(stroke
				(width 0.1524)
				(type default)
			)
			(layer "F.SilkS")
		)
		(fp_line
			(start -0.67945 0.3048)
			(end -0.67945 -0.305054)
			(stroke
				(width 0.1)
				(type default)
			)
			(layer "F.Fab")
		)
		(fp_line
			(start -0.12065 0.3048)
			(end -0.67945 0.3048)
			(stroke
				(width 0.1)
				(type default)
			)
			(layer "F.Fab")
		)
		(fp_line
			(start 0.120396 0.3048)
			(end 0.120396 0.2794)
			(stroke
				(width 0.1)
				(type default)
			)
			(layer "F.Fab")
		)
		(fp_line
			(start 0.67945 0.3048)
			(end 0.120396 0.3048)
			(stroke
				(width 0.1)
				(type default)
			)
			(layer "F.Fab")
		)
		(fp_line
			(start -0.12065 0.2794)
			(end -0.12065 0.3048)
			(stroke
				(width 0.1)
				(type default)
			)
			(layer "F.Fab")
		)
		(fp_line
			(start 0.120396 0.2794)
			(end -0.12065 0.2794)
			(stroke
				(width 0.1)
				(type default)
			)
			(layer "F.Fab")
		)
		(fp_line
			(start -0.12065 -0.2794)
			(end 0.12065 -0.2794)
			(stroke
				(width 0.1)
				(type default)
			)
			(layer "F.Fab")
		)
		(fp_line
			(start 0.12065 -0.2794)
			(end 0.12065 -0.3048)
			(stroke
				(width 0.1)
				(type default)
			)
			(layer "F.Fab")
		)
		(fp_line
			(start 0.12065 -0.3048)
			(end 0.67945 -0.3048)
			(stroke
				(width 0.1)
				(type default)
			)
			(layer "F.Fab")
		)
		(fp_line
			(start 0.67945 -0.3048)
			(end 0.67945 0.3048)
			(stroke
				(width 0.1)
				(type default)
			)
			(layer "F.Fab")
		)
		(fp_line
			(start -0.67945 -0.305054)
			(end -0.12065 -0.305054)
			(stroke
				(width 0.1)
				(type default)
			)
			(layer "F.Fab")
		)
		(fp_line
			(start -0.12065 -0.305054)
			(end -0.12065 -0.2794)
			(stroke
				(width 0.1)
				(type default)
			)
			(layer "F.Fab")
		)
		(pad "1" smd circle
			(at -0.40005 0 270)
			(size 0 0)
			(layers "F.Cu" "F.Mask" "F.Paste")
			(net "GND")
		)
		(pad "2" smd circle
			(at 0.40005 0 270)
			(size 0 0)
			(layers "F.Cu" "F.Mask" "F.Paste")
			(net "PEX3_MODE_SEL4")
		)
	)
	(footprint ""
		(layer "F.Cu")
		(at 152.738328 -122.79884)
		(property "Reference" "C254"
			(at 0 0 0)
			(layer "F.SilkS")
			(hide yes)
			(effects
				(font
					(size 1.27 1.27)
				)
			)
		)
		(property "Value" ""
			(at 0 0 0)
			(layer "F.Fab")
			(effects
				(font
					(size 1.27 1.27)
				)
			)
		)
		(duplicate_pad_numbers_are_jumpers no)
		(fp_line
			(start -0.299974 -0.150114)
			(end 0.299974 -0.150114)
			(stroke
				(width 0.1)
				(type default)
			)
			(layer "F.Fab")
		)
		(fp_line
			(start -0.299974 0.150114)
			(end -0.299974 -0.150114)
			(stroke
				(width 0.1)
				(type default)
			)
			(layer "F.Fab")
		)
		(fp_line
			(start 0.299974 -0.150114)
			(end 0.299974 0.150114)
			(stroke
				(width 0.1)
				(type default)
			)
			(layer "F.Fab")
		)
		(fp_line
			(start 0.299974 0.150114)
			(end -0.299974 0.150114)
			(stroke
				(width 0.1)
				(type default)
			)
			(layer "F.Fab")
		)
		(pad "1" smd rect
			(at -0.2667 0)
			(size 0.3048 0.381)
			(layers "F.Cu" "F.Mask" "F.Paste")
			(net "P5E_PEX1_STN1_TX_DP<26>")
		)
		(pad "2" smd rect
			(at 0.2667 0)
			(size 0.3048 0.381)
			(layers "F.Cu" "F.Mask" "F.Paste")
			(net "P5E_PEX1_STN1_TX_C_DP<26>")
		)
	)
	(footprint ""
		(layer "F.Cu")
		(at 415.487612 -356.244906 90)
		(property "Reference" "C818"
			(at 0 0 90)
			(layer "F.SilkS")
			(hide yes)
			(effects
				(font
					(size 1.27 1.27)
				)
			)
		)
		(property "Value" ""
			(at 0 0 90)
			(layer "F.Fab")
			(effects
				(font
					(size 1.27 1.27)
				)
			)
		)
		(duplicate_pad_numbers_are_jumpers no)
		(fp_line
			(start 0.299974 -0.150114)
			(end 0.299974 0.150114)
			(stroke
				(width 0.1)
				(type default)
			)
			(layer "F.Fab")
		)
		(fp_line
			(start -0.299974 -0.150114)
			(end 0.299974 -0.150114)
			(stroke
				(width 0.1)
				(type default)
			)
			(layer "F.Fab")
		)
		(fp_line
			(start 0.299974 0.150114)
			(end -0.299974 0.150114)
			(stroke
				(width 0.1)
				(type default)
			)
			(layer "F.Fab")
		)
		(fp_line
			(start -0.299974 0.150114)
			(end -0.299974 -0.150114)
			(stroke
				(width 0.1)
				(type default)
			)
			(layer "F.Fab")
		)
		(pad "1" smd rect
			(at -0.2667 0 90)
			(size 0.3048 0.381)
			(layers "F.Cu" "F.Mask" "F.Paste")
			(net "P5E_PEX3_STN7_TX_DP<115>")
		)
		(pad "2" smd rect
			(at 0.2667 0 90)
			(size 0.3048 0.381)
			(layers "F.Cu" "F.Mask" "F.Paste")
			(net "P5E_PEX3_STN7_TX_C_DP<115>")
		)
	)
	(footprint ""
		(layer "F.Cu")
		(at 284.443678 -47.92091)
		(property "Reference" "R603"
			(at 0 0 0)
			(layer "F.SilkS")
			(hide yes)
			(effects
				(font
					(size 1.27 1.27)
				)
			)
		)
		(property "Value" ""
			(at 0 0 0)
			(layer "F.Fab")
			(effects
				(font
					(size 1.27 1.27)
				)
			)
		)
		(duplicate_pad_numbers_are_jumpers no)
		(fp_line
			(start -0.7874 -0.4064)
			(end 0.7874 -0.4064)
			(stroke
				(width 0.1524)
				(type default)
			)
			(layer "F.SilkS")
		)
		(fp_line
			(start -0.7874 0.4064)
			(end -0.7874 -0.4064)
			(stroke
				(width 0.1524)
				(type default)
			)
			(layer "F.SilkS")
		)
		(fp_line
			(start 0.7874 -0.4064)
			(end 0.7874 0.4064)
			(stroke
				(width 0.1524)
				(type default)
			)
			(layer "F.SilkS")
		)
		(fp_line
			(start 0.7874 0.4064)
			(end -0.7874 0.4064)
			(stroke
				(width 0.1524)
				(type default)
			)
			(layer "F.SilkS")
		)
		(fp_line
			(start -0.67945 -0.305054)
			(end -0.12065 -0.305054)
			(stroke
				(width 0.1)
				(type default)
			)
			(layer "F.Fab")
		)
		(fp_line
			(start -0.67945 0.3048)
			(end -0.67945 -0.305054)
			(stroke
				(width 0.1)
				(type default)
			)
			(layer "F.Fab")
		)
		(fp_line
			(start -0.12065 -0.305054)
			(end -0.12065 -0.2794)
			(stroke
				(width 0.1)
				(type default)
			)
			(layer "F.Fab")
		)
		(fp_line
			(start -0.12065 -0.2794)
			(end 0.12065 -0.2794)
			(stroke
				(width 0.1)
				(type default)
			)
			(layer "F.Fab")
		)
		(fp_line
			(start -0.12065 0.2794)
			(end -0.12065 0.3048)
			(stroke
				(width 0.1)
				(type default)
			)
			(layer "F.Fab")
		)
		(fp_line
			(start -0.12065 0.3048)
			(end -0.67945 0.3048)
			(stroke
				(width 0.1)
				(type default)
			)
			(layer "F.Fab")
		)
		(fp_line
			(start 0.120396 0.2794)
			(end -0.12065 0.2794)
			(stroke
				(width 0.1)
				(type default)
			)
			(layer "F.Fab")
		)
		(fp_line
			(start 0.120396 0.3048)
			(end 0.120396 0.2794)
			(stroke
				(width 0.1)
				(type default)
			)
			(layer "F.Fab")
		)
		(fp_line
			(start 0.12065 -0.3048)
			(end 0.67945 -0.3048)
			(stroke
				(width 0.1)
				(type default)
			)
			(layer "F.Fab")
		)
		(fp_line
			(start 0.12065 -0.2794)
			(end 0.12065 -0.3048)
			(stroke
				(width 0.1)
				(type default)
			)
			(layer "F.Fab")
		)
		(fp_line
			(start 0.67945 -0.3048)
			(end 0.67945 0.3048)
			(stroke
				(width 0.1)
				(type default)
			)
			(layer "F.Fab")
		)
		(fp_line
			(start 0.67945 0.3048)
			(end 0.120396 0.3048)
			(stroke
				(width 0.1)
				(type default)
			)
			(layer "F.Fab")
		)
		(pad "1" smd circle
			(at -0.40005 0)
			(size 0 0)
			(layers "F.Cu" "F.Mask" "F.Paste")
			(net "P3V3_AUX")
		)
		(pad "2" smd circle
			(at 0.40005 0)
			(size 0 0)
			(layers "F.Cu" "F.Mask" "F.Paste")
			(net "SSD_8_15_ADC_ALERT_N")
		)
	)
	(footprint ""
		(layer "F.Cu")
		(at 406.36444 -139.6238)
		(property "Reference" "R343"
			(at 0 0 0)
			(layer "F.SilkS")
			(hide yes)
			(effects
				(font
					(size 1.27 1.27)
				)
			)
		)
		(property "Value" ""
			(at 0 0 0)
			(layer "F.Fab")
			(effects
				(font
					(size 1.27 1.27)
				)
			)
		)
		(duplicate_pad_numbers_are_jumpers no)
		(fp_line
			(start -0.7874 -0.4064)
			(end 0.7874 -0.4064)
			(stroke
				(width 0.1524)
				(type default)
			)
			(layer "F.SilkS")
		)
		(fp_line
			(start -0.7874 0.4064)
			(end -0.7874 -0.4064)
			(stroke
				(width 0.1524)
				(type default)
			)
			(layer "F.SilkS")
		)
		(fp_line
			(start 0.7874 -0.4064)
			(end 0.7874 0.4064)
			(stroke
				(width 0.1524)
				(type default)
			)
			(layer "F.SilkS")
		)
		(fp_line
			(start 0.7874 0.4064)
			(end -0.7874 0.4064)
			(stroke
				(width 0.1524)
				(type default)
			)
			(layer "F.SilkS")
		)
		(fp_line
			(start -0.67945 -0.305054)
			(end -0.12065 -0.305054)
			(stroke
				(width 0.1)
				(type default)
			)
			(layer "F.Fab")
		)
		(fp_line
			(start -0.67945 0.3048)
			(end -0.67945 -0.305054)
			(stroke
				(width 0.1)
				(type default)
			)
			(layer "F.Fab")
		)
		(fp_line
			(start -0.12065 -0.305054)
			(end -0.12065 -0.2794)
			(stroke
				(width 0.1)
				(type default)
			)
			(layer "F.Fab")
		)
		(fp_line
			(start -0.12065 -0.2794)
			(end 0.12065 -0.2794)
			(stroke
				(width 0.1)
				(type default)
			)
			(layer "F.Fab")
		)
		(fp_line
			(start -0.12065 0.2794)
			(end -0.12065 0.3048)
			(stroke
				(width 0.1)
				(type default)
			)
			(layer "F.Fab")
		)
		(fp_line
			(start -0.12065 0.3048)
			(end -0.67945 0.3048)
			(stroke
				(width 0.1)
				(type default)
			)
			(layer "F.Fab")
		)
		(fp_line
			(start 0.120396 0.2794)
			(end -0.12065 0.2794)
			(stroke
				(width 0.1)
				(type default)
			)
			(layer "F.Fab")
		)
		(fp_line
			(start 0.120396 0.3048)
			(end 0.120396 0.2794)
			(stroke
				(width 0.1)
				(type default)
			)
			(layer "F.Fab")
		)
		(fp_line
			(start 0.12065 -0.3048)
			(end 0.67945 -0.3048)
			(stroke
				(width 0.1)
				(type default)
			)
			(layer "F.Fab")
		)
		(fp_line
			(start 0.12065 -0.2794)
			(end 0.12065 -0.3048)
			(stroke
				(width 0.1)
				(type default)
			)
			(layer "F.Fab")
		)
		(fp_line
			(start 0.67945 -0.3048)
			(end 0.67945 0.3048)
			(stroke
				(width 0.1)
				(type default)
			)
			(layer "F.Fab")
		)
		(fp_line
			(start 0.67945 0.3048)
			(end 0.120396 0.3048)
			(stroke
				(width 0.1)
				(type default)
			)
			(layer "F.Fab")
		)
		(pad "1" smd circle
			(at -0.40005 0)
			(size 0 0)
			(layers "F.Cu" "F.Mask" "F.Paste")
			(net "RST_SMB_NIC6_MUX_ISO_R_N")
		)
		(pad "2" smd circle
			(at 0.40005 0)
			(size 0 0)
			(layers "F.Cu" "F.Mask" "F.Paste")
			(net "RST_SMB_NIC6_MUX_ISO_N")
		)
	)
	(footprint ""
		(layer "F.Cu")
		(at 138.37158 -152.71115 90)
		(property "Reference" "R705"
			(at 0 0 90)
			(layer "F.SilkS")
			(hide yes)
			(effects
				(font
					(size 1.27 1.27)
				)
			)
		)
		(property "Value" ""
			(at 0 0 90)
			(layer "F.Fab")
			(effects
				(font
					(size 1.27 1.27)
				)
			)
		)
		(duplicate_pad_numbers_are_jumpers no)
		(fp_line
			(start 0.7874 -0.4064)
			(end 0.7874 0.4064)
			(stroke
				(width 0.1524)
				(type default)
			)
			(layer "F.SilkS")
		)
		(fp_line
			(start -0.7874 -0.4064)
			(end 0.7874 -0.4064)
			(stroke
				(width 0.1524)
				(type default)
			)
			(layer "F.SilkS")
		)
		(fp_line
			(start 0.7874 0.4064)
			(end -0.7874 0.4064)
			(stroke
				(width 0.1524)
				(type default)
			)
			(layer "F.SilkS")
		)
		(fp_line
			(start -0.7874 0.4064)
			(end -0.7874 -0.4064)
			(stroke
				(width 0.1524)
				(type default)
			)
			(layer "F.SilkS")
		)
		(fp_line
			(start -0.12065 -0.305054)
			(end -0.12065 -0.2794)
			(stroke
				(width 0.1)
				(type default)
			)
			(layer "F.Fab")
		)
		(fp_line
			(start -0.67945 -0.305054)
			(end -0.12065 -0.305054)
			(stroke
				(width 0.1)
				(type default)
			)
			(layer "F.Fab")
		)
		(fp_line
			(start 0.67945 -0.3048)
			(end 0.67945 0.3048)
			(stroke
				(width 0.1)
				(type default)
			)
			(layer "F.Fab")
		)
		(fp_line
			(start 0.12065 -0.3048)
			(end 0.67945 -0.3048)
			(stroke
				(width 0.1)
				(type default)
			)
			(layer "F.Fab")
		)
		(fp_line
			(start 0.12065 -0.2794)
			(end 0.12065 -0.3048)
			(stroke
				(width 0.1)
				(type default)
			)
			(layer "F.Fab")
		)
		(fp_line
			(start -0.12065 -0.2794)
			(end 0.12065 -0.2794)
			(stroke
				(width 0.1)
				(type default)
			)
			(layer "F.Fab")
		)
		(fp_line
			(start 0.120396 0.2794)
			(end -0.12065 0.2794)
			(stroke
				(width 0.1)
				(type default)
			)
			(layer "F.Fab")
		)
		(fp_line
			(start -0.12065 0.2794)
			(end -0.12065 0.3048)
			(stroke
				(width 0.1)
				(type default)
			)
			(layer "F.Fab")
		)
		(fp_line
			(start 0.67945 0.3048)
			(end 0.120396 0.3048)
			(stroke
				(width 0.1)
				(type default)
			)
			(layer "F.Fab")
		)
		(fp_line
			(start 0.120396 0.3048)
			(end 0.120396 0.2794)
			(stroke
				(width 0.1)
				(type default)
			)
			(layer "F.Fab")
		)
		(fp_line
			(start -0.12065 0.3048)
			(end -0.67945 0.3048)
			(stroke
				(width 0.1)
				(type default)
			)
			(layer "F.Fab")
		)
		(fp_line
			(start -0.67945 0.3048)
			(end -0.67945 -0.305054)
			(stroke
				(width 0.1)
				(type default)
			)
			(layer "F.Fab")
		)
		(pad "1" smd circle
			(at -0.40005 0 90)
			(size 0 0)
			(layers "F.Cu" "F.Mask" "F.Paste")
			(net "NIC2_ADC_A1")
		)
		(pad "2" smd circle
			(at 0.40005 0 90)
			(size 0 0)
			(layers "F.Cu" "F.Mask" "F.Paste")
			(net "P3V3_AUX")
		)
	)
	(footprint ""
		(layer "F.Cu")
		(at 36.638484 -131.323334)
		(property "Reference" "C40"
			(at 0 0 0)
			(layer "F.SilkS")
			(hide yes)
			(effects
				(font
					(size 1.27 1.27)
				)
			)
		)
		(property "Value" ""
			(at 0 0 0)
			(layer "F.Fab")
			(effects
				(font
					(size 1.27 1.27)
				)
			)
		)
		(duplicate_pad_numbers_are_jumpers no)
		(fp_line
			(start -0.299974 -0.150114)
			(end 0.299974 -0.150114)
			(stroke
				(width 0.1)
				(type default)
			)
			(layer "F.Fab")
		)
		(fp_line
			(start -0.299974 0.150114)
			(end -0.299974 -0.150114)
			(stroke
				(width 0.1)
				(type default)
			)
			(layer "F.Fab")
		)
		(fp_line
			(start 0.299974 -0.150114)
			(end 0.299974 0.150114)
			(stroke
				(width 0.1)
				(type default)
			)
			(layer "F.Fab")
		)
		(fp_line
			(start 0.299974 0.150114)
			(end -0.299974 0.150114)
			(stroke
				(width 0.1)
				(type default)
			)
			(layer "F.Fab")
		)
		(pad "1" smd rect
			(at -0.2667 0)
			(size 0.3048 0.381)
			(layers "F.Cu" "F.Mask" "F.Paste")
			(net "P5E_PEX0_STN1_TX_DN<28>")
		)
		(pad "2" smd rect
			(at 0.2667 0)
			(size 0.3048 0.381)
			(layers "F.Cu" "F.Mask" "F.Paste")
			(net "P5E_PEX0_STN1_TX_C_DN<28>")
		)
	)
	(footprint ""
		(layer "F.Cu")
		(at 327.992232 -31.825184 180)
		(property "Reference" "C514"
			(at 0 0 180)
			(layer "F.SilkS")
			(hide yes)
			(effects
				(font
					(size 1.27 1.27)
				)
			)
		)
		(property "Value" ""
			(at 0 0 180)
			(layer "F.Fab")
			(effects
				(font
					(size 1.27 1.27)
				)
			)
		)
		(duplicate_pad_numbers_are_jumpers no)
		(fp_line
			(start 0.299974 0.150114)
			(end -0.299974 0.150114)
			(stroke
				(width 0.1)
				(type default)
			)
			(layer "F.Fab")
		)
		(fp_line
			(start 0.299974 -0.150114)
			(end 0.299974 0.150114)
			(stroke
				(width 0.1)
				(type default)
			)
			(layer "F.Fab")
		)
		(fp_line
			(start -0.299974 0.150114)
			(end -0.299974 -0.150114)
			(stroke
				(width 0.1)
				(type default)
			)
			(layer "F.Fab")
		)
		(fp_line
			(start -0.299974 -0.150114)
			(end 0.299974 -0.150114)
			(stroke
				(width 0.1)
				(type default)
			)
			(layer "F.Fab")
		)
		(pad "1" smd rect
			(at -0.2667 0 180)
			(size 0.3048 0.381)
			(layers "F.Cu" "F.Mask" "F.Paste")
			(net "P5E_PEX2_STN2_TX_DN<34>")
		)
		(pad "2" smd rect
			(at 0.2667 0 180)
			(size 0.3048 0.381)
			(layers "F.Cu" "F.Mask" "F.Paste")
			(net "P5E_PEX2_STN2_TX_C_DN<34>")
		)
	)
	(footprint ""
		(layer "F.Cu")
		(at 355.913436 -135.058404 180)
		(property "Reference" "C2858"
			(at 0 0 180)
			(layer "F.SilkS")
			(hide yes)
			(effects
				(font
					(size 1.27 1.27)
				)
			)
		)
		(property "Value" ""
			(at 0 0 180)
			(layer "F.Fab")
			(effects
				(font
					(size 1.27 1.27)
				)
			)
		)
		(duplicate_pad_numbers_are_jumpers no)
		(fp_line
			(start 0.7874 0.4064)
			(end -0.7874 0.4064)
			(stroke
				(width 0.1524)
				(type default)
			)
			(layer "F.SilkS")
		)
		(fp_line
			(start 0.7874 -0.4064)
			(end 0.7874 0.4064)
			(stroke
				(width 0.1524)
				(type default)
			)
			(layer "F.SilkS")
		)
		(fp_line
			(start -0.7874 0.4064)
			(end -0.7874 -0.4064)
			(stroke
				(width 0.1524)
				(type default)
			)
			(layer "F.SilkS")
		)
		(fp_line
			(start -0.7874 -0.4064)
			(end 0.7874 -0.4064)
			(stroke
				(width 0.1524)
				(type default)
			)
			(layer "F.SilkS")
		)
		(fp_line
			(start 0.67945 0.3048)
			(end 0.120396 0.3048)
			(stroke
				(width 0.1)
				(type default)
			)
			(layer "F.Fab")
		)
		(fp_line
			(start 0.67945 -0.3048)
			(end 0.67945 0.3048)
			(stroke
				(width 0.1)
				(type default)
			)
			(layer "F.Fab")
		)
		(fp_line
			(start 0.12065 -0.2794)
			(end 0.12065 -0.3048)
			(stroke
				(width 0.1)
				(type default)
			)
			(layer "F.Fab")
		)
		(fp_line
			(start 0.12065 -0.3048)
			(end 0.67945 -0.3048)
			(stroke
				(width 0.1)
				(type default)
			)
			(layer "F.Fab")
		)
		(fp_line
			(start 0.120396 0.3048)
			(end 0.120396 0.2794)
			(stroke
				(width 0.1)
				(type default)
			)
			(layer "F.Fab")
		)
		(fp_line
			(start 0.120396 0.2794)
			(end -0.12065 0.2794)
			(stroke
				(width 0.1)
				(type default)
			)
			(layer "F.Fab")
		)
		(fp_line
			(start -0.12065 0.3048)
			(end -0.67945 0.3048)
			(stroke
				(width 0.1)
				(type default)
			)
			(layer "F.Fab")
		)
		(fp_line
			(start -0.12065 0.2794)
			(end -0.12065 0.3048)
			(stroke
				(width 0.1)
				(type default)
			)
			(layer "F.Fab")
		)
		(fp_line
			(start -0.12065 -0.2794)
			(end 0.12065 -0.2794)
			(stroke
				(width 0.1)
				(type default)
			)
			(layer "F.Fab")
		)
		(fp_line
			(start -0.12065 -0.305054)
			(end -0.12065 -0.2794)
			(stroke
				(width 0.1)
				(type default)
			)
			(layer "F.Fab")
		)
		(fp_line
			(start -0.67945 0.3048)
			(end -0.67945 -0.305054)
			(stroke
				(width 0.1)
				(type default)
			)
			(layer "F.Fab")
		)
		(fp_line
			(start -0.67945 -0.305054)
			(end -0.12065 -0.305054)
			(stroke
				(width 0.1)
				(type default)
			)
			(layer "F.Fab")
		)
		(pad "1" smd circle
			(at -0.40005 0 180)
			(size 0 0)
			(layers "F.Cu" "F.Mask" "F.Paste")
			(net "P12V_NIC6_EN_R")
		)
		(pad "2" smd circle
			(at 0.40005 0 180)
			(size 0 0)
			(layers "F.Cu" "F.Mask" "F.Paste")
			(net "GND")
		)
	)
	(footprint ""
		(layer "F.Cu")
		(at 275.004022 -343.952322 90)
		(property "Reference" "C2346"
			(at 0 0 90)
			(layer "F.SilkS")
			(hide yes)
			(effects
				(font
					(size 1.27 1.27)
				)
			)
		)
		(property "Value" ""
			(at 0 0 90)
			(layer "F.Fab")
			(effects
				(font
					(size 1.27 1.27)
				)
			)
		)
		(duplicate_pad_numbers_are_jumpers no)
		(fp_line
			(start 0.299974 -0.150114)
			(end 0.299974 0.150114)
			(stroke
				(width 0.1)
				(type default)
			)
			(layer "F.Fab")
		)
		(fp_line
			(start -0.299974 -0.150114)
			(end 0.299974 -0.150114)
			(stroke
				(width 0.1)
				(type default)
			)
			(layer "F.Fab")
		)
		(fp_line
			(start 0.299974 0.150114)
			(end -0.299974 0.150114)
			(stroke
				(width 0.1)
				(type default)
			)
			(layer "F.Fab")
		)
		(fp_line
			(start -0.299974 0.150114)
			(end -0.299974 -0.150114)
			(stroke
				(width 0.1)
				(type default)
			)
			(layer "F.Fab")
		)
		(pad "1" smd rect
			(at -0.2667 0 90)
			(size 0.3048 0.381)
			(layers "F.Cu" "F.Mask" "F.Paste")
			(net "P5E_PEX2_STN4_TX_DN<77>")
		)
		(pad "2" smd rect
			(at 0.2667 0 90)
			(size 0.3048 0.381)
			(layers "F.Cu" "F.Mask" "F.Paste")
			(net "P5E_PEX2_STN4_TX_C_DN<77>")
		)
	)
	(footprint ""
		(layer "F.Cu")
		(at 188.49721 -366.181386)
		(property "Reference" "PJ1"
			(at -1.013968 -4.913122 0)
			(unlocked yes)
			(layer "F.SilkS")
			(effects
				(font
					(size 0.7874 0.5842)
					(thickness 0.1524)
				)
				(justify left)
			)
		)
		(property "Value" ""
			(at 0 0 0)
			(layer "F.Fab")
			(effects
				(font
					(size 1.27 1.27)
				)
			)
		)
		(duplicate_pad_numbers_are_jumpers no)
		(fp_line
			(start -1.249934 -3.860038)
			(end -1.249934 -3.1877)
			(stroke
				(width 0.1524)
				(type default)
			)
			(layer "F.SilkS")
		)
		(fp_line
			(start -1.249934 -1.8923)
			(end -1.249934 1.8923)
			(stroke
				(width 0.1524)
				(type default)
			)
			(layer "F.SilkS")
		)
		(fp_line
			(start -1.249934 3.1877)
			(end -1.249934 3.860038)
			(stroke
				(width 0.1524)
				(type default)
			)
			(layer "F.SilkS")
		)
		(fp_line
			(start -1.249934 3.860038)
			(end 1.249934 3.860038)
			(stroke
				(width 0.1524)
				(type default)
			)
			(layer "F.SilkS")
		)
		(fp_line
			(start 1.249934 -3.860038)
			(end -1.249934 -3.860038)
			(stroke
				(width 0.1524)
				(type default)
			)
			(layer "F.SilkS")
		)
		(fp_line
			(start 1.249934 -0.6477)
			(end 1.249934 -3.860038)
			(stroke
				(width 0.1524)
				(type default)
			)
			(layer "F.SilkS")
		)
		(fp_line
			(start 1.249934 3.860038)
			(end 1.249934 0.6477)
			(stroke
				(width 0.1524)
				(type default)
			)
			(layer "F.SilkS")
		)
		(fp_poly
			(pts
				(xy -4.2164 -3.048) (xy -3.2004 -2.54) (xy -4.2164 -2.032)
			)
			(stroke
				(width 0)
				(type default)
			)
			(fill yes)
			(layer "F.SilkS")
		)
		(fp_line
			(start -1.249934 -3.860038)
			(end -1.249934 3.860038)
			(stroke
				(width 0.1)
				(type default)
			)
			(layer "F.Fab")
		)
		(fp_line
			(start -1.249934 3.860038)
			(end 1.249934 3.860038)
			(stroke
				(width 0.1)
				(type default)
			)
			(layer "F.Fab")
		)
		(fp_line
			(start 1.249934 -3.860038)
			(end -1.249934 -3.860038)
			(stroke
				(width 0.1)
				(type default)
			)
			(layer "F.Fab")
		)
		(fp_line
			(start 1.249934 3.860038)
			(end 1.249934 -3.860038)
			(stroke
				(width 0.1)
				(type default)
			)
			(layer "F.Fab")
		)
		(fp_poly
			(pts
				(xy -4.2164 -3.048) (xy -3.2004 -2.54) (xy -4.2164 -2.032)
			)
			(stroke
				(width 0)
				(type default)
			)
			(fill yes)
			(layer "F.Fab")
		)
		(pad "1" smd rect
			(at -1.374902 -2.54 270)
			(size 1.016 2.7686)
			(layers "F.Cu" "F.Mask" "F.Paste")
			(net "GND")
		)
		(pad "2" smd rect
			(at 1.374902 0 270)
			(size 1.016 2.7686)
			(layers "F.Cu" "F.Mask" "F.Paste")
			(net "SMB_HOTSWAP_SDA_R")
		)
		(pad "3" smd rect
			(at -1.374902 2.54 270)
			(size 1.016 2.7686)
			(layers "F.Cu" "F.Mask" "F.Paste")
			(net "SMB_HOTSWAP_SCL_R")
		)
	)
	(footprint ""
		(layer "F.Cu")
		(at 213.935056 -215.26246)
		(property "Reference" "R4880"
			(at 0 0 0)
			(layer "F.SilkS")
			(hide yes)
			(effects
				(font
					(size 1.27 1.27)
				)
			)
		)
		(property "Value" ""
			(at 0 0 0)
			(layer "F.Fab")
			(effects
				(font
					(size 1.27 1.27)
				)
			)
		)
		(duplicate_pad_numbers_are_jumpers no)
		(fp_line
			(start -0.7874 -0.4064)
			(end 0.7874 -0.4064)
			(stroke
				(width 0.1524)
				(type default)
			)
			(layer "F.SilkS")
		)
		(fp_line
			(start -0.7874 0.4064)
			(end -0.7874 -0.4064)
			(stroke
				(width 0.1524)
				(type default)
			)
			(layer "F.SilkS")
		)
		(fp_line
			(start 0.7874 -0.4064)
			(end 0.7874 0.4064)
			(stroke
				(width 0.1524)
				(type default)
			)
			(layer "F.SilkS")
		)
		(fp_line
			(start 0.7874 0.4064)
			(end -0.7874 0.4064)
			(stroke
				(width 0.1524)
				(type default)
			)
			(layer "F.SilkS")
		)
		(fp_line
			(start -0.67945 -0.305054)
			(end -0.12065 -0.305054)
			(stroke
				(width 0.1)
				(type default)
			)
			(layer "F.Fab")
		)
		(fp_line
			(start -0.67945 0.3048)
			(end -0.67945 -0.305054)
			(stroke
				(width 0.1)
				(type default)
			)
			(layer "F.Fab")
		)
		(fp_line
			(start -0.12065 -0.305054)
			(end -0.12065 -0.2794)
			(stroke
				(width 0.1)
				(type default)
			)
			(layer "F.Fab")
		)
		(fp_line
			(start -0.12065 -0.2794)
			(end 0.12065 -0.2794)
			(stroke
				(width 0.1)
				(type default)
			)
			(layer "F.Fab")
		)
		(fp_line
			(start -0.12065 0.2794)
			(end -0.12065 0.3048)
			(stroke
				(width 0.1)
				(type default)
			)
			(layer "F.Fab")
		)
		(fp_line
			(start -0.12065 0.3048)
			(end -0.67945 0.3048)
			(stroke
				(width 0.1)
				(type default)
			)
			(layer "F.Fab")
		)
		(fp_line
			(start 0.120396 0.2794)
			(end -0.12065 0.2794)
			(stroke
				(width 0.1)
				(type default)
			)
			(layer "F.Fab")
		)
		(fp_line
			(start 0.120396 0.3048)
			(end 0.120396 0.2794)
			(stroke
				(width 0.1)
				(type default)
			)
			(layer "F.Fab")
		)
		(fp_line
			(start 0.12065 -0.3048)
			(end 0.67945 -0.3048)
			(stroke
				(width 0.1)
				(type default)
			)
			(layer "F.Fab")
		)
		(fp_line
			(start 0.12065 -0.2794)
			(end 0.12065 -0.3048)
			(stroke
				(width 0.1)
				(type default)
			)
			(layer "F.Fab")
		)
		(fp_line
			(start 0.67945 -0.3048)
			(end 0.67945 0.3048)
			(stroke
				(width 0.1)
				(type default)
			)
			(layer "F.Fab")
		)
		(fp_line
			(start 0.67945 0.3048)
			(end 0.120396 0.3048)
			(stroke
				(width 0.1)
				(type default)
			)
			(layer "F.Fab")
		)
		(pad "1" smd circle
			(at -0.40005 0)
			(size 0 0)
			(layers "F.Cu" "F.Mask" "F.Paste")
			(net "P1V2_AUX")
		)
		(pad "2" smd circle
			(at 0.40005 0)
			(size 0 0)
			(layers "F.Cu" "F.Mask" "F.Paste")
			(net "SMB_NIC7_SDA")
		)
	)
	(footprint ""
		(layer "F.Cu")
		(at 252.842522 -179.167282)
		(property "Reference" "J19"
			(at -1.4224 -4.562348 0)
			(unlocked yes)
			(layer "F.SilkS")
			(effects
				(font
					(size 0.7874 0.5842)
					(thickness 0.1524)
				)
				(justify left)
			)
		)
		(property "Value" ""
			(at 0 0 0)
			(layer "F.Fab")
			(effects
				(font
					(size 1.27 1.27)
				)
			)
		)
		(duplicate_pad_numbers_are_jumpers no)
		(fp_line
			(start -1.27 -3.81)
			(end 1.27 -3.81)
			(stroke
				(width 0.1524)
				(type default)
			)
			(layer "F.SilkS")
		)
		(fp_line
			(start -1.27 -0.7747)
			(end -1.27 -3.81)
			(stroke
				(width 0.1524)
				(type default)
			)
			(layer "F.SilkS")
		)
		(fp_line
			(start -1.27 3.81)
			(end -1.27 0.7747)
			(stroke
				(width 0.1524)
				(type default)
			)
			(layer "F.SilkS")
		)
		(fp_line
			(start 1.27 -3.81)
			(end 1.27 -3.3147)
			(stroke
				(width 0.1524)
				(type default)
			)
			(layer "F.SilkS")
		)
		(fp_line
			(start 1.27 -1.7653)
			(end 1.27 1.7653)
			(stroke
				(width 0.1524)
				(type default)
			)
			(layer "F.SilkS")
		)
		(fp_line
			(start 1.27 3.3147)
			(end 1.27 3.81)
			(stroke
				(width 0.1524)
				(type default)
			)
			(layer "F.SilkS")
		)
		(fp_line
			(start 1.27 3.81)
			(end -1.27 3.81)
			(stroke
				(width 0.1524)
				(type default)
			)
			(layer "F.SilkS")
		)
		(fp_poly
			(pts
				(xy 4.3942 -3.048) (xy 4.3942 -2.032) (xy 3.3782 -2.54)
			)
			(stroke
				(width 0)
				(type default)
			)
			(fill yes)
			(layer "F.SilkS")
		)
		(fp_line
			(start -1.27 -3.81)
			(end -1.27 3.81)
			(stroke
				(width 0.1)
				(type default)
			)
			(layer "F.Fab")
		)
		(fp_line
			(start -1.27 3.81)
			(end 1.27 3.81)
			(stroke
				(width 0.1)
				(type default)
			)
			(layer "F.Fab")
		)
		(fp_line
			(start 1.27 -3.81)
			(end -1.27 -3.81)
			(stroke
				(width 0.1)
				(type default)
			)
			(layer "F.Fab")
		)
		(fp_line
			(start 1.27 3.81)
			(end 1.27 -3.81)
			(stroke
				(width 0.1)
				(type default)
			)
			(layer "F.Fab")
		)
		(fp_poly
			(pts
				(xy 4.3942 -3.048) (xy 4.3942 -2.032) (xy 3.3782 -2.54)
			)
			(stroke
				(width 0)
				(type default)
			)
			(fill yes)
			(layer "F.Fab")
		)
		(fp_text user "3"
			(at 3.921252 2.54 90)
			(unlocked yes)
			(layer "F.SilkS")
			(effects
				(font
					(size 0.7874 0.5842)
					(thickness 0.1524)
				)
			)
		)
		(fp_text user "3"
			(at 3.921252 2.54 90)
			(unlocked yes)
			(layer "F.Fab")
			(effects
				(font
					(size 0.7874 0.5842)
					(thickness 0.1524)
				)
			)
		)
		(pad "1" smd rect
			(at 1.459992 -2.54 90)
			(size 1.27 3.429)
			(layers "F.Cu" "F.Mask" "F.Paste")
			(net "Net_467")
		)
		(pad "2" smd rect
			(at -1.459992 0 90)
			(size 1.27 3.429)
			(layers "F.Cu" "F.Mask" "F.Paste")
			(net "BIC_FWSPICK")
		)
		(pad "3" smd rect
			(at 1.459992 2.54 90)
			(size 1.27 3.429)
			(layers "F.Cu" "F.Mask" "F.Paste")
			(net "BIC_FWSPICK_R")
		)
	)
	(footprint ""
		(layer "F.Cu")
		(at 314.083446 -61.487812 180)
		(property "Reference" "R6005"
			(at 0 0 180)
			(layer "F.SilkS")
			(hide yes)
			(effects
				(font
					(size 1.27 1.27)
				)
			)
		)
		(property "Value" ""
			(at 0 0 180)
			(layer "F.Fab")
			(effects
				(font
					(size 1.27 1.27)
				)
			)
		)
		(duplicate_pad_numbers_are_jumpers no)
		(fp_line
			(start 0.7874 0.4064)
			(end -0.7874 0.4064)
			(stroke
				(width 0.1524)
				(type default)
			)
			(layer "F.SilkS")
		)
		(fp_line
			(start 0.7874 -0.4064)
			(end 0.7874 0.4064)
			(stroke
				(width 0.1524)
				(type default)
			)
			(layer "F.SilkS")
		)
		(fp_line
			(start -0.7874 0.4064)
			(end -0.7874 -0.4064)
			(stroke
				(width 0.1524)
				(type default)
			)
			(layer "F.SilkS")
		)
		(fp_line
			(start -0.7874 -0.4064)
			(end 0.7874 -0.4064)
			(stroke
				(width 0.1524)
				(type default)
			)
			(layer "F.SilkS")
		)
		(fp_line
			(start 0.67945 0.3048)
			(end 0.120396 0.3048)
			(stroke
				(width 0.1)
				(type default)
			)
			(layer "F.Fab")
		)
		(fp_line
			(start 0.67945 -0.3048)
			(end 0.67945 0.3048)
			(stroke
				(width 0.1)
				(type default)
			)
			(layer "F.Fab")
		)
		(fp_line
			(start 0.12065 -0.2794)
			(end 0.12065 -0.3048)
			(stroke
				(width 0.1)
				(type default)
			)
			(layer "F.Fab")
		)
		(fp_line
			(start 0.12065 -0.3048)
			(end 0.67945 -0.3048)
			(stroke
				(width 0.1)
				(type default)
			)
			(layer "F.Fab")
		)
		(fp_line
			(start 0.120396 0.3048)
			(end 0.120396 0.2794)
			(stroke
				(width 0.1)
				(type default)
			)
			(layer "F.Fab")
		)
		(fp_line
			(start 0.120396 0.2794)
			(end -0.12065 0.2794)
			(stroke
				(width 0.1)
				(type default)
			)
			(layer "F.Fab")
		)
		(fp_line
			(start -0.12065 0.3048)
			(end -0.67945 0.3048)
			(stroke
				(width 0.1)
				(type default)
			)
			(layer "F.Fab")
		)
		(fp_line
			(start -0.12065 0.2794)
			(end -0.12065 0.3048)
			(stroke
				(width 0.1)
				(type default)
			)
			(layer "F.Fab")
		)
		(fp_line
			(start -0.12065 -0.2794)
			(end 0.12065 -0.2794)
			(stroke
				(width 0.1)
				(type default)
			)
			(layer "F.Fab")
		)
		(fp_line
			(start -0.12065 -0.305054)
			(end -0.12065 -0.2794)
			(stroke
				(width 0.1)
				(type default)
			)
			(layer "F.Fab")
		)
		(fp_line
			(start -0.67945 0.3048)
			(end -0.67945 -0.305054)
			(stroke
				(width 0.1)
				(type default)
			)
			(layer "F.Fab")
		)
		(fp_line
			(start -0.67945 -0.305054)
			(end -0.12065 -0.305054)
			(stroke
				(width 0.1)
				(type default)
			)
			(layer "F.Fab")
		)
		(pad "1" smd circle
			(at -0.40005 0 180)
			(size 0 0)
			(layers "F.Cu" "F.Mask" "F.Paste")
			(net "PWRGD_P12V_SSD11_D")
		)
		(pad "2" smd circle
			(at 0.40005 0 180)
			(size 0 0)
			(layers "F.Cu" "F.Mask" "F.Paste")
			(net "PWRGD_P12V_SSD11_R")
		)
	)
	(footprint ""
		(layer "F.Cu")
		(at 381.254 -197.358)
		(property "Reference" "R4665"
			(at 0 0 0)
			(layer "F.SilkS")
			(hide yes)
			(effects
				(font
					(size 1.27 1.27)
				)
			)
		)
		(property "Value" ""
			(at 0 0 0)
			(layer "F.Fab")
			(effects
				(font
					(size 1.27 1.27)
				)
			)
		)
		(duplicate_pad_numbers_are_jumpers no)
		(fp_line
			(start -0.7874 -0.4064)
			(end 0.7874 -0.4064)
			(stroke
				(width 0.1524)
				(type default)
			)
			(layer "F.SilkS")
		)
		(fp_line
			(start -0.7874 0.4064)
			(end -0.7874 -0.4064)
			(stroke
				(width 0.1524)
				(type default)
			)
			(layer "F.SilkS")
		)
		(fp_line
			(start 0.7874 -0.4064)
			(end 0.7874 0.4064)
			(stroke
				(width 0.1524)
				(type default)
			)
			(layer "F.SilkS")
		)
		(fp_line
			(start 0.7874 0.4064)
			(end -0.7874 0.4064)
			(stroke
				(width 0.1524)
				(type default)
			)
			(layer "F.SilkS")
		)
		(fp_line
			(start -0.67945 -0.305054)
			(end -0.12065 -0.305054)
			(stroke
				(width 0.1)
				(type default)
			)
			(layer "F.Fab")
		)
		(fp_line
			(start -0.67945 0.3048)
			(end -0.67945 -0.305054)
			(stroke
				(width 0.1)
				(type default)
			)
			(layer "F.Fab")
		)
		(fp_line
			(start -0.12065 -0.305054)
			(end -0.12065 -0.2794)
			(stroke
				(width 0.1)
				(type default)
			)
			(layer "F.Fab")
		)
		(fp_line
			(start -0.12065 -0.2794)
			(end 0.12065 -0.2794)
			(stroke
				(width 0.1)
				(type default)
			)
			(layer "F.Fab")
		)
		(fp_line
			(start -0.12065 0.2794)
			(end -0.12065 0.3048)
			(stroke
				(width 0.1)
				(type default)
			)
			(layer "F.Fab")
		)
		(fp_line
			(start -0.12065 0.3048)
			(end -0.67945 0.3048)
			(stroke
				(width 0.1)
				(type default)
			)
			(layer "F.Fab")
		)
		(fp_line
			(start 0.120396 0.2794)
			(end -0.12065 0.2794)
			(stroke
				(width 0.1)
				(type default)
			)
			(layer "F.Fab")
		)
		(fp_line
			(start 0.120396 0.3048)
			(end 0.120396 0.2794)
			(stroke
				(width 0.1)
				(type default)
			)
			(layer "F.Fab")
		)
		(fp_line
			(start 0.12065 -0.3048)
			(end 0.67945 -0.3048)
			(stroke
				(width 0.1)
				(type default)
			)
			(layer "F.Fab")
		)
		(fp_line
			(start 0.12065 -0.2794)
			(end 0.12065 -0.3048)
			(stroke
				(width 0.1)
				(type default)
			)
			(layer "F.Fab")
		)
		(fp_line
			(start 0.67945 -0.3048)
			(end 0.67945 0.3048)
			(stroke
				(width 0.1)
				(type default)
			)
			(layer "F.Fab")
		)
		(fp_line
			(start 0.67945 0.3048)
			(end 0.120396 0.3048)
			(stroke
				(width 0.1)
				(type default)
			)
			(layer "F.Fab")
		)
		(pad "1" smd circle
			(at -0.40005 0)
			(size 0 0)
			(layers "F.Cu" "F.Mask" "F.Paste")
			(net "P3V3_AUX")
		)
		(pad "2" smd circle
			(at 0.40005 0)
			(size 0 0)
			(layers "F.Cu" "F.Mask" "F.Paste")
			(net "NIC2_PEX_PWR_EN_R")
		)
	)
	(footprint ""
		(layer "F.Cu")
		(at 95.105728 -240.744248)
		(property "Reference" "R820"
			(at 0 0 0)
			(layer "F.SilkS")
			(hide yes)
			(effects
				(font
					(size 1.27 1.27)
				)
			)
		)
		(property "Value" ""
			(at 0 0 0)
			(layer "F.Fab")
			(effects
				(font
					(size 1.27 1.27)
				)
			)
		)
		(duplicate_pad_numbers_are_jumpers no)
		(fp_line
			(start -0.7874 -0.4064)
			(end 0.7874 -0.4064)
			(stroke
				(width 0.1524)
				(type default)
			)
			(layer "F.SilkS")
		)
		(fp_line
			(start -0.7874 0.4064)
			(end -0.7874 -0.4064)
			(stroke
				(width 0.1524)
				(type default)
			)
			(layer "F.SilkS")
		)
		(fp_line
			(start 0.7874 -0.4064)
			(end 0.7874 0.4064)
			(stroke
				(width 0.1524)
				(type default)
			)
			(layer "F.SilkS")
		)
		(fp_line
			(start 0.7874 0.4064)
			(end -0.7874 0.4064)
			(stroke
				(width 0.1524)
				(type default)
			)
			(layer "F.SilkS")
		)
		(fp_line
			(start -0.67945 -0.305054)
			(end -0.12065 -0.305054)
			(stroke
				(width 0.1)
				(type default)
			)
			(layer "F.Fab")
		)
		(fp_line
			(start -0.67945 0.3048)
			(end -0.67945 -0.305054)
			(stroke
				(width 0.1)
				(type default)
			)
			(layer "F.Fab")
		)
		(fp_line
			(start -0.12065 -0.305054)
			(end -0.12065 -0.2794)
			(stroke
				(width 0.1)
				(type default)
			)
			(layer "F.Fab")
		)
		(fp_line
			(start -0.12065 -0.2794)
			(end 0.12065 -0.2794)
			(stroke
				(width 0.1)
				(type default)
			)
			(layer "F.Fab")
		)
		(fp_line
			(start -0.12065 0.2794)
			(end -0.12065 0.3048)
			(stroke
				(width 0.1)
				(type default)
			)
			(layer "F.Fab")
		)
		(fp_line
			(start -0.12065 0.3048)
			(end -0.67945 0.3048)
			(stroke
				(width 0.1)
				(type default)
			)
			(layer "F.Fab")
		)
		(fp_line
			(start 0.120396 0.2794)
			(end -0.12065 0.2794)
			(stroke
				(width 0.1)
				(type default)
			)
			(layer "F.Fab")
		)
		(fp_line
			(start 0.120396 0.3048)
			(end 0.120396 0.2794)
			(stroke
				(width 0.1)
				(type default)
			)
			(layer "F.Fab")
		)
		(fp_line
			(start 0.12065 -0.3048)
			(end 0.67945 -0.3048)
			(stroke
				(width 0.1)
				(type default)
			)
			(layer "F.Fab")
		)
		(fp_line
			(start 0.12065 -0.2794)
			(end 0.12065 -0.3048)
			(stroke
				(width 0.1)
				(type default)
			)
			(layer "F.Fab")
		)
		(fp_line
			(start 0.67945 -0.3048)
			(end 0.67945 0.3048)
			(stroke
				(width 0.1)
				(type default)
			)
			(layer "F.Fab")
		)
		(fp_line
			(start 0.67945 0.3048)
			(end 0.120396 0.3048)
			(stroke
				(width 0.1)
				(type default)
			)
			(layer "F.Fab")
		)
		(pad "1" smd circle
			(at -0.40005 0)
			(size 0 0)
			(layers "F.Cu" "F.Mask" "F.Paste")
			(net "SMB_BIC_I2C6_MUX_PEX_ADC_R_SDA")
		)
		(pad "2" smd circle
			(at 0.40005 0)
			(size 0 0)
			(layers "F.Cu" "F.Mask" "F.Paste")
			(net "SMB_PEX_P1V8_ADC_SDA")
		)
	)
	(footprint ""
		(layer "F.Cu")
		(at 130.168904 -293.5351 90)
		(property "Reference" "PL10"
			(at -4.287774 10.17016 90)
			(unlocked yes)
			(layer "F.SilkS")
			(effects
				(font
					(size 0.7874 0.5842)
					(thickness 0.1524)
				)
				(justify left)
			)
		)
		(property "Value" ""
			(at 0 0 90)
			(layer "F.Fab")
			(effects
				(font
					(size 1.27 1.27)
				)
			)
		)
		(duplicate_pad_numbers_are_jumpers no)
		(fp_line
			(start 4.800092 -3.199892)
			(end 4.800092 -1.6764)
			(stroke
				(width 0.1524)
				(type default)
			)
			(layer "F.SilkS")
		)
		(fp_line
			(start -4.800092 -3.199892)
			(end 4.800092 -3.199892)
			(stroke
				(width 0.1524)
				(type default)
			)
			(layer "F.SilkS")
		)
		(fp_line
			(start -4.800092 -1.6764)
			(end -4.800092 -3.199892)
			(stroke
				(width 0.1524)
				(type default)
			)
			(layer "F.SilkS")
		)
		(fp_line
			(start 4.800092 1.6764)
			(end 4.800092 3.199892)
			(stroke
				(width 0.1524)
				(type default)
			)
			(layer "F.SilkS")
		)
		(fp_line
			(start 4.800092 3.199892)
			(end -4.800092 3.199892)
			(stroke
				(width 0.1524)
				(type default)
			)
			(layer "F.SilkS")
		)
		(fp_line
			(start -4.800092 3.199892)
			(end -4.800092 1.6764)
			(stroke
				(width 0.1524)
				(type default)
			)
			(layer "F.SilkS")
		)
		(fp_line
			(start 4.800092 -3.199892)
			(end 4.800092 3.199892)
			(stroke
				(width 0.1)
				(type default)
			)
			(layer "F.Fab")
		)
		(fp_line
			(start -4.800092 -3.199892)
			(end 4.800092 -3.199892)
			(stroke
				(width 0.1)
				(type default)
			)
			(layer "F.Fab")
		)
		(fp_line
			(start 4.800092 3.199892)
			(end -4.800092 3.199892)
			(stroke
				(width 0.1)
				(type default)
			)
			(layer "F.Fab")
		)
		(fp_line
			(start -4.800092 3.199892)
			(end -4.800092 -3.199892)
			(stroke
				(width 0.1)
				(type default)
			)
			(layer "F.Fab")
		)
		(pad "1" smd rect
			(at -3.074924 0 180)
			(size 3.0988 3.3528)
			(layers "F.Cu" "F.Mask" "F.Paste")
			(net "SW_P0V8_PEX1_PH2")
		)
		(pad "2" smd rect
			(at 3.074924 0 180)
			(size 3.0988 3.3528)
			(layers "F.Cu" "F.Mask" "F.Paste")
			(net "P0V8_PEX1")
		)
	)
	(footprint ""
		(layer "F.Cu")
		(at 98.072448 -8.177022 90)
		(property "Reference" "C2718"
			(at 0 0 90)
			(layer "F.SilkS")
			(hide yes)
			(effects
				(font
					(size 1.27 1.27)
				)
			)
		)
		(property "Value" ""
			(at 0 0 90)
			(layer "F.Fab")
			(effects
				(font
					(size 1.27 1.27)
				)
			)
		)
		(duplicate_pad_numbers_are_jumpers no)
		(fp_line
			(start 0.7874 -0.4064)
			(end 0.7874 0.4064)
			(stroke
				(width 0.1524)
				(type default)
			)
			(layer "F.SilkS")
		)
		(fp_line
			(start -0.7874 -0.4064)
			(end 0.7874 -0.4064)
			(stroke
				(width 0.1524)
				(type default)
			)
			(layer "F.SilkS")
		)
		(fp_line
			(start 0.7874 0.4064)
			(end -0.7874 0.4064)
			(stroke
				(width 0.1524)
				(type default)
			)
			(layer "F.SilkS")
		)
		(fp_line
			(start -0.7874 0.4064)
			(end -0.7874 -0.4064)
			(stroke
				(width 0.1524)
				(type default)
			)
			(layer "F.SilkS")
		)
		(fp_line
			(start -0.12065 -0.305054)
			(end -0.12065 -0.2794)
			(stroke
				(width 0.1)
				(type default)
			)
			(layer "F.Fab")
		)
		(fp_line
			(start -0.67945 -0.305054)
			(end -0.12065 -0.305054)
			(stroke
				(width 0.1)
				(type default)
			)
			(layer "F.Fab")
		)
		(fp_line
			(start 0.67945 -0.3048)
			(end 0.67945 0.3048)
			(stroke
				(width 0.1)
				(type default)
			)
			(layer "F.Fab")
		)
		(fp_line
			(start 0.12065 -0.3048)
			(end 0.67945 -0.3048)
			(stroke
				(width 0.1)
				(type default)
			)
			(layer "F.Fab")
		)
		(fp_line
			(start 0.12065 -0.2794)
			(end 0.12065 -0.3048)
			(stroke
				(width 0.1)
				(type default)
			)
			(layer "F.Fab")
		)
		(fp_line
			(start -0.12065 -0.2794)
			(end 0.12065 -0.2794)
			(stroke
				(width 0.1)
				(type default)
			)
			(layer "F.Fab")
		)
		(fp_line
			(start 0.120396 0.2794)
			(end -0.12065 0.2794)
			(stroke
				(width 0.1)
				(type default)
			)
			(layer "F.Fab")
		)
		(fp_line
			(start -0.12065 0.2794)
			(end -0.12065 0.3048)
			(stroke
				(width 0.1)
				(type default)
			)
			(layer "F.Fab")
		)
		(fp_line
			(start 0.67945 0.3048)
			(end 0.120396 0.3048)
			(stroke
				(width 0.1)
				(type default)
			)
			(layer "F.Fab")
		)
		(fp_line
			(start 0.120396 0.3048)
			(end 0.120396 0.2794)
			(stroke
				(width 0.1)
				(type default)
			)
			(layer "F.Fab")
		)
		(fp_line
			(start -0.12065 0.3048)
			(end -0.67945 0.3048)
			(stroke
				(width 0.1)
				(type default)
			)
			(layer "F.Fab")
		)
		(fp_line
			(start -0.67945 0.3048)
			(end -0.67945 -0.305054)
			(stroke
				(width 0.1)
				(type default)
			)
			(layer "F.Fab")
		)
		(pad "1" smd circle
			(at -0.40005 0 90)
			(size 0 0)
			(layers "F.Cu" "F.Mask" "F.Paste")
			(net "GND")
		)
		(pad "2" smd circle
			(at 0.40005 0 90)
			(size 0 0)
			(layers "F.Cu" "F.Mask" "F.Paste")
			(net "P3V3_SSD3")
		)
	)
	(footprint ""
		(layer "F.Cu")
		(at 104.699054 -386.917184 180)
		(property "Reference" "R6292"
			(at 0 0 180)
			(layer "F.SilkS")
			(hide yes)
			(effects
				(font
					(size 1.27 1.27)
				)
			)
		)
		(property "Value" ""
			(at 0 0 180)
			(layer "F.Fab")
			(effects
				(font
					(size 1.27 1.27)
				)
			)
		)
		(duplicate_pad_numbers_are_jumpers no)
		(fp_line
			(start 0.7874 0.4064)
			(end -0.462026 0.4064)
			(stroke
				(width 0.1524)
				(type default)
			)
			(layer "F.SilkS")
		)
		(fp_line
			(start 0.7874 -0.4064)
			(end 0.7874 0.4064)
			(stroke
				(width 0.1524)
				(type default)
			)
			(layer "F.SilkS")
		)
		(fp_line
			(start -0.483362 -0.4064)
			(end 0.7874 -0.4064)
			(stroke
				(width 0.1524)
				(type default)
			)
			(layer "F.SilkS")
		)
		(fp_line
			(start 0.67945 0.3048)
			(end 0.120396 0.3048)
			(stroke
				(width 0.1)
				(type default)
			)
			(layer "F.Fab")
		)
		(fp_line
			(start 0.67945 -0.3048)
			(end 0.67945 0.3048)
			(stroke
				(width 0.1)
				(type default)
			)
			(layer "F.Fab")
		)
		(fp_line
			(start 0.12065 -0.2794)
			(end 0.12065 -0.3048)
			(stroke
				(width 0.1)
				(type default)
			)
			(layer "F.Fab")
		)
		(fp_line
			(start 0.12065 -0.3048)
			(end 0.67945 -0.3048)
			(stroke
				(width 0.1)
				(type default)
			)
			(layer "F.Fab")
		)
		(fp_line
			(start 0.120396 0.3048)
			(end 0.120396 0.2794)
			(stroke
				(width 0.1)
				(type default)
			)
			(layer "F.Fab")
		)
		(fp_line
			(start 0.120396 0.2794)
			(end -0.12065 0.2794)
			(stroke
				(width 0.1)
				(type default)
			)
			(layer "F.Fab")
		)
		(fp_line
			(start -0.12065 0.3048)
			(end -0.67945 0.3048)
			(stroke
				(width 0.1)
				(type default)
			)
			(layer "F.Fab")
		)
		(fp_line
			(start -0.12065 0.2794)
			(end -0.12065 0.3048)
			(stroke
				(width 0.1)
				(type default)
			)
			(layer "F.Fab")
		)
		(fp_line
			(start -0.12065 -0.2794)
			(end 0.12065 -0.2794)
			(stroke
				(width 0.1)
				(type default)
			)
			(layer "F.Fab")
		)
		(fp_line
			(start -0.12065 -0.305054)
			(end -0.12065 -0.2794)
			(stroke
				(width 0.1)
				(type default)
			)
			(layer "F.Fab")
		)
		(fp_line
			(start -0.67945 0.3048)
			(end -0.67945 -0.305054)
			(stroke
				(width 0.1)
				(type default)
			)
			(layer "F.Fab")
		)
		(fp_line
			(start -0.67945 -0.305054)
			(end -0.12065 -0.305054)
			(stroke
				(width 0.1)
				(type default)
			)
			(layer "F.Fab")
		)
		(pad "1" smd circle
			(at -0.40005 0 180)
			(size 0 0)
			(layers "F.Cu" "F.Mask" "F.Paste")
			(net "USB2_GPU_HMC_R_DN")
		)
		(pad "2" smd circle
			(at 0.40005 0 180)
			(size 0 0)
			(layers "F.Cu" "F.Mask" "F.Paste")
			(net "GND")
		)
	)
	(footprint ""
		(layer "F.Cu")
		(at 324.192646 -118.446804)
		(property "Reference" "PC903"
			(at 0 0 0)
			(layer "F.SilkS")
			(hide yes)
			(effects
				(font
					(size 1.27 1.27)
				)
			)
		)
		(property "Value" ""
			(at 0 0 0)
			(layer "F.Fab")
			(effects
				(font
					(size 1.27 1.27)
				)
			)
		)
		(duplicate_pad_numbers_are_jumpers no)
		(fp_line
			(start -1.524 -0.762)
			(end 1.524 -0.762)
			(stroke
				(width 0.1524)
				(type default)
			)
			(layer "F.SilkS")
		)
		(fp_line
			(start -1.524 0.762)
			(end -1.524 -0.762)
			(stroke
				(width 0.1524)
				(type default)
			)
			(layer "F.SilkS")
		)
		(fp_line
			(start 1.524 -0.762)
			(end 1.524 0.762)
			(stroke
				(width 0.1524)
				(type default)
			)
			(layer "F.SilkS")
		)
		(fp_line
			(start 1.524 0.762)
			(end -1.524 0.762)
			(stroke
				(width 0.1524)
				(type default)
			)
			(layer "F.SilkS")
		)
		(fp_line
			(start -1.1049 -0.724916)
			(end -1.1049 0.724916)
			(stroke
				(width 0.1)
				(type default)
			)
			(layer "F.Fab")
		)
		(fp_line
			(start -1.1049 0.724916)
			(end 1.1049 0.724916)
			(stroke
				(width 0.1)
				(type default)
			)
			(layer "F.Fab")
		)
		(fp_line
			(start 1.1049 -0.724916)
			(end -1.1049 -0.724916)
			(stroke
				(width 0.1)
				(type default)
			)
			(layer "F.Fab")
		)
		(fp_line
			(start 1.1049 0.724916)
			(end 1.1049 -0.724916)
			(stroke
				(width 0.1)
				(type default)
			)
			(layer "F.Fab")
		)
		(pad "1" smd rect
			(at -0.889 0 180)
			(size 1.016 1.27)
			(layers "F.Cu" "F.Mask" "F.Paste")
			(net "P3V3_NIC5")
		)
		(pad "2" smd rect
			(at 0.889 0 180)
			(size 1.016 1.27)
			(layers "F.Cu" "F.Mask" "F.Paste")
			(net "GND")
		)
	)
	(footprint ""
		(layer "F.Cu")
		(at 258.44373 -47.92091)
		(property "Reference" "R592"
			(at 0 0 0)
			(layer "F.SilkS")
			(hide yes)
			(effects
				(font
					(size 1.27 1.27)
				)
			)
		)
		(property "Value" ""
			(at 0 0 0)
			(layer "F.Fab")
			(effects
				(font
					(size 1.27 1.27)
				)
			)
		)
		(duplicate_pad_numbers_are_jumpers no)
		(fp_line
			(start -0.7874 -0.4064)
			(end 0.7874 -0.4064)
			(stroke
				(width 0.1524)
				(type default)
			)
			(layer "F.SilkS")
		)
		(fp_line
			(start -0.7874 0.4064)
			(end -0.7874 -0.4064)
			(stroke
				(width 0.1524)
				(type default)
			)
			(layer "F.SilkS")
		)
		(fp_line
			(start 0.7874 -0.4064)
			(end 0.7874 0.4064)
			(stroke
				(width 0.1524)
				(type default)
			)
			(layer "F.SilkS")
		)
		(fp_line
			(start 0.7874 0.4064)
			(end -0.7874 0.4064)
			(stroke
				(width 0.1524)
				(type default)
			)
			(layer "F.SilkS")
		)
		(fp_line
			(start -0.67945 -0.305054)
			(end -0.12065 -0.305054)
			(stroke
				(width 0.1)
				(type default)
			)
			(layer "F.Fab")
		)
		(fp_line
			(start -0.67945 0.3048)
			(end -0.67945 -0.305054)
			(stroke
				(width 0.1)
				(type default)
			)
			(layer "F.Fab")
		)
		(fp_line
			(start -0.12065 -0.305054)
			(end -0.12065 -0.2794)
			(stroke
				(width 0.1)
				(type default)
			)
			(layer "F.Fab")
		)
		(fp_line
			(start -0.12065 -0.2794)
			(end 0.12065 -0.2794)
			(stroke
				(width 0.1)
				(type default)
			)
			(layer "F.Fab")
		)
		(fp_line
			(start -0.12065 0.2794)
			(end -0.12065 0.3048)
			(stroke
				(width 0.1)
				(type default)
			)
			(layer "F.Fab")
		)
		(fp_line
			(start -0.12065 0.3048)
			(end -0.67945 0.3048)
			(stroke
				(width 0.1)
				(type default)
			)
			(layer "F.Fab")
		)
		(fp_line
			(start 0.120396 0.2794)
			(end -0.12065 0.2794)
			(stroke
				(width 0.1)
				(type default)
			)
			(layer "F.Fab")
		)
		(fp_line
			(start 0.120396 0.3048)
			(end 0.120396 0.2794)
			(stroke
				(width 0.1)
				(type default)
			)
			(layer "F.Fab")
		)
		(fp_line
			(start 0.12065 -0.3048)
			(end 0.67945 -0.3048)
			(stroke
				(width 0.1)
				(type default)
			)
			(layer "F.Fab")
		)
		(fp_line
			(start 0.12065 -0.2794)
			(end 0.12065 -0.3048)
			(stroke
				(width 0.1)
				(type default)
			)
			(layer "F.Fab")
		)
		(fp_line
			(start 0.67945 -0.3048)
			(end 0.67945 0.3048)
			(stroke
				(width 0.1)
				(type default)
			)
			(layer "F.Fab")
		)
		(fp_line
			(start 0.67945 0.3048)
			(end 0.120396 0.3048)
			(stroke
				(width 0.1)
				(type default)
			)
			(layer "F.Fab")
		)
		(pad "1" smd circle
			(at -0.40005 0)
			(size 0 0)
			(layers "F.Cu" "F.Mask" "F.Paste")
			(net "P3V3_AUX")
		)
		(pad "2" smd circle
			(at 0.40005 0)
			(size 0 0)
			(layers "F.Cu" "F.Mask" "F.Paste")
			(net "SSD_8_15_ADC_ALERT_N")
		)
	)
	(footprint ""
		(layer "F.Cu")
		(at 350.380554 -84.930234)
		(property "Reference" "R1595"
			(at 0 0 0)
			(layer "F.SilkS")
			(hide yes)
			(effects
				(font
					(size 1.27 1.27)
				)
			)
		)
		(property "Value" ""
			(at 0 0 0)
			(layer "F.Fab")
			(effects
				(font
					(size 1.27 1.27)
				)
			)
		)
		(duplicate_pad_numbers_are_jumpers no)
		(fp_line
			(start -0.7874 -0.4064)
			(end 0.7874 -0.4064)
			(stroke
				(width 0.1524)
				(type default)
			)
			(layer "F.SilkS")
		)
		(fp_line
			(start -0.7874 0.4064)
			(end -0.7874 -0.4064)
			(stroke
				(width 0.1524)
				(type default)
			)
			(layer "F.SilkS")
		)
		(fp_line
			(start 0.7874 -0.4064)
			(end 0.7874 0.4064)
			(stroke
				(width 0.1524)
				(type default)
			)
			(layer "F.SilkS")
		)
		(fp_line
			(start 0.7874 0.4064)
			(end -0.7874 0.4064)
			(stroke
				(width 0.1524)
				(type default)
			)
			(layer "F.SilkS")
		)
		(fp_line
			(start -0.67945 -0.305054)
			(end -0.12065 -0.305054)
			(stroke
				(width 0.1)
				(type default)
			)
			(layer "F.Fab")
		)
		(fp_line
			(start -0.67945 0.3048)
			(end -0.67945 -0.305054)
			(stroke
				(width 0.1)
				(type default)
			)
			(layer "F.Fab")
		)
		(fp_line
			(start -0.12065 -0.305054)
			(end -0.12065 -0.2794)
			(stroke
				(width 0.1)
				(type default)
			)
			(layer "F.Fab")
		)
		(fp_line
			(start -0.12065 -0.2794)
			(end 0.12065 -0.2794)
			(stroke
				(width 0.1)
				(type default)
			)
			(layer "F.Fab")
		)
		(fp_line
			(start -0.12065 0.2794)
			(end -0.12065 0.3048)
			(stroke
				(width 0.1)
				(type default)
			)
			(layer "F.Fab")
		)
		(fp_line
			(start -0.12065 0.3048)
			(end -0.67945 0.3048)
			(stroke
				(width 0.1)
				(type default)
			)
			(layer "F.Fab")
		)
		(fp_line
			(start 0.120396 0.2794)
			(end -0.12065 0.2794)
			(stroke
				(width 0.1)
				(type default)
			)
			(layer "F.Fab")
		)
		(fp_line
			(start 0.120396 0.3048)
			(end 0.120396 0.2794)
			(stroke
				(width 0.1)
				(type default)
			)
			(layer "F.Fab")
		)
		(fp_line
			(start 0.12065 -0.3048)
			(end 0.67945 -0.3048)
			(stroke
				(width 0.1)
				(type default)
			)
			(layer "F.Fab")
		)
		(fp_line
			(start 0.12065 -0.2794)
			(end 0.12065 -0.3048)
			(stroke
				(width 0.1)
				(type default)
			)
			(layer "F.Fab")
		)
		(fp_line
			(start 0.67945 -0.3048)
			(end 0.67945 0.3048)
			(stroke
				(width 0.1)
				(type default)
			)
			(layer "F.Fab")
		)
		(fp_line
			(start 0.67945 0.3048)
			(end 0.120396 0.3048)
			(stroke
				(width 0.1)
				(type default)
			)
			(layer "F.Fab")
		)
		(pad "1" smd circle
			(at -0.40005 0)
			(size 0 0)
			(layers "F.Cu" "F.Mask" "F.Paste")
			(net "P3V3_AUX")
		)
		(pad "2" smd circle
			(at 0.40005 0)
			(size 0 0)
			(layers "F.Cu" "F.Mask" "F.Paste")
			(net "SMB_BIC_I2C9_MUX1_SSD10_R_SDA")
		)
	)
	(footprint ""
		(layer "F.Cu")
		(at 97.654618 -22.867366 90)
		(property "Reference" "C3898"
			(at 0 0 90)
			(layer "F.SilkS")
			(hide yes)
			(effects
				(font
					(size 1.27 1.27)
				)
			)
		)
		(property "Value" ""
			(at 0 0 90)
			(layer "F.Fab")
			(effects
				(font
					(size 1.27 1.27)
				)
			)
		)
		(duplicate_pad_numbers_are_jumpers no)
		(fp_line
			(start 0.7874 -0.4064)
			(end 0.7874 0.4064)
			(stroke
				(width 0.1524)
				(type default)
			)
			(layer "F.SilkS")
		)
		(fp_line
			(start -0.7874 -0.4064)
			(end 0.7874 -0.4064)
			(stroke
				(width 0.1524)
				(type default)
			)
			(layer "F.SilkS")
		)
		(fp_line
			(start 0.7874 0.4064)
			(end -0.7874 0.4064)
			(stroke
				(width 0.1524)
				(type default)
			)
			(layer "F.SilkS")
		)
		(fp_line
			(start -0.7874 0.4064)
			(end -0.7874 -0.4064)
			(stroke
				(width 0.1524)
				(type default)
			)
			(layer "F.SilkS")
		)
		(fp_line
			(start -0.12065 -0.305054)
			(end -0.12065 -0.2794)
			(stroke
				(width 0.1)
				(type default)
			)
			(layer "F.Fab")
		)
		(fp_line
			(start -0.67945 -0.305054)
			(end -0.12065 -0.305054)
			(stroke
				(width 0.1)
				(type default)
			)
			(layer "F.Fab")
		)
		(fp_line
			(start 0.67945 -0.3048)
			(end 0.67945 0.3048)
			(stroke
				(width 0.1)
				(type default)
			)
			(layer "F.Fab")
		)
		(fp_line
			(start 0.12065 -0.3048)
			(end 0.67945 -0.3048)
			(stroke
				(width 0.1)
				(type default)
			)
			(layer "F.Fab")
		)
		(fp_line
			(start 0.12065 -0.2794)
			(end 0.12065 -0.3048)
			(stroke
				(width 0.1)
				(type default)
			)
			(layer "F.Fab")
		)
		(fp_line
			(start -0.12065 -0.2794)
			(end 0.12065 -0.2794)
			(stroke
				(width 0.1)
				(type default)
			)
			(layer "F.Fab")
		)
		(fp_line
			(start 0.120396 0.2794)
			(end -0.12065 0.2794)
			(stroke
				(width 0.1)
				(type default)
			)
			(layer "F.Fab")
		)
		(fp_line
			(start -0.12065 0.2794)
			(end -0.12065 0.3048)
			(stroke
				(width 0.1)
				(type default)
			)
			(layer "F.Fab")
		)
		(fp_line
			(start 0.67945 0.3048)
			(end 0.120396 0.3048)
			(stroke
				(width 0.1)
				(type default)
			)
			(layer "F.Fab")
		)
		(fp_line
			(start 0.120396 0.3048)
			(end 0.120396 0.2794)
			(stroke
				(width 0.1)
				(type default)
			)
			(layer "F.Fab")
		)
		(fp_line
			(start -0.12065 0.3048)
			(end -0.67945 0.3048)
			(stroke
				(width 0.1)
				(type default)
			)
			(layer "F.Fab")
		)
		(fp_line
			(start -0.67945 0.3048)
			(end -0.67945 -0.305054)
			(stroke
				(width 0.1)
				(type default)
			)
			(layer "F.Fab")
		)
		(pad "1" smd circle
			(at -0.40005 0 90)
			(size 0 0)
			(layers "F.Cu" "F.Mask" "F.Paste")
			(net "P12V_SSD3")
		)
		(pad "2" smd circle
			(at 0.40005 0 90)
			(size 0 0)
			(layers "F.Cu" "F.Mask" "F.Paste")
			(net "GND")
		)
	)
	(footprint ""
		(layer "F.Cu")
		(at 339.812884 -111.785654 180)
		(property "Reference" "PU104"
			(at 3.922014 -2.311654 90)
			(unlocked yes)
			(layer "F.SilkS")
			(effects
				(font
					(size 0.7874 0.5842)
					(thickness 0.1524)
				)
				(justify left)
			)
		)
		(property "Value" ""
			(at 0 0 180)
			(layer "F.Fab")
			(effects
				(font
					(size 1.27 1.27)
				)
			)
		)
		(duplicate_pad_numbers_are_jumpers no)
		(fp_line
			(start 1.549908 2.549906)
			(end 1.549908 2.253996)
			(stroke
				(width 0.1524)
				(type default)
			)
			(layer "F.SilkS")
		)
		(fp_line
			(start 1.549908 -2.253996)
			(end 1.549908 -2.549906)
			(stroke
				(width 0.1524)
				(type default)
			)
			(layer "F.SilkS")
		)
		(fp_line
			(start 1.549908 -2.549906)
			(end 0.752094 -2.549906)
			(stroke
				(width 0.1524)
				(type default)
			)
			(layer "F.SilkS")
		)
		(fp_line
			(start 0.753872 2.549906)
			(end 1.549908 2.549906)
			(stroke
				(width 0.1524)
				(type default)
			)
			(layer "F.SilkS")
		)
		(fp_line
			(start 0.2413 -2.549906)
			(end -0.2413 -2.549906)
			(stroke
				(width 0.1524)
				(type default)
			)
			(layer "F.SilkS")
		)
		(fp_line
			(start -0.245872 2.549906)
			(end 0.245872 2.549906)
			(stroke
				(width 0.1524)
				(type default)
			)
			(layer "F.SilkS")
		)
		(fp_line
			(start -0.752094 -2.549906)
			(end -1.549908 -2.549906)
			(stroke
				(width 0.1524)
				(type default)
			)
			(layer "F.SilkS")
		)
		(fp_line
			(start -1.549908 2.549906)
			(end -0.753872 2.549906)
			(stroke
				(width 0.1524)
				(type default)
			)
			(layer "F.SilkS")
		)
		(fp_line
			(start -1.549908 2.253996)
			(end -1.549908 2.549906)
			(stroke
				(width 0.1524)
				(type default)
			)
			(layer "F.SilkS")
		)
		(fp_line
			(start -1.549908 -2.549906)
			(end -1.549908 -2.251964)
			(stroke
				(width 0.1524)
				(type default)
			)
			(layer "F.SilkS")
		)
		(fp_poly
			(pts
				(xy -2.38506 -1.744218) (xy -3.288284 -2.045462) (xy -2.686304 -2.647442)
			)
			(stroke
				(width 0)
				(type default)
			)
			(fill yes)
			(layer "F.SilkS")
		)
		(fp_line
			(start 1.549908 2.549906)
			(end 1.549908 -2.549906)
			(stroke
				(width 0.1)
				(type default)
			)
			(layer "F.Fab")
		)
		(fp_line
			(start 1.549908 -2.549906)
			(end -1.549908 -2.549906)
			(stroke
				(width 0.1)
				(type default)
			)
			(layer "F.Fab")
		)
		(fp_line
			(start -1.549908 2.549906)
			(end 1.549908 2.549906)
			(stroke
				(width 0.1)
				(type default)
			)
			(layer "F.Fab")
		)
		(fp_line
			(start -1.549908 -2.549906)
			(end -1.549908 2.549906)
			(stroke
				(width 0.1)
				(type default)
			)
			(layer "F.Fab")
		)
		(fp_poly
			(pts
				(xy -1.891538 -1.999996) (xy -2.7432 -1.574292) (xy -2.7432 -2.4257)
			)
			(stroke
				(width 0)
				(type default)
			)
			(fill yes)
			(layer "F.Fab")
		)
		(fp_text user "12"
			(at 2.456434 1.083056 90)
			(unlocked yes)
			(layer "F.SilkS")
			(effects
				(font
					(size 0.635 0.4064)
					(thickness 0.1524)
				)
			)
		)
		(fp_text user "20"
			(at 2.055368 -2.7686 90)
			(unlocked yes)
			(layer "F.SilkS")
			(effects
				(font
					(size 0.635 0.4064)
					(thickness 0.1524)
				)
			)
		)
		(fp_text user "11"
			(at 1.308862 3.031998 0)
			(unlocked yes)
			(layer "F.SilkS")
			(effects
				(font
					(size 0.635 0.4064)
					(thickness 0.1524)
				)
			)
		)
		(fp_text user "21_22"
			(at -1.198372 -3.315208 0)
			(unlocked yes)
			(layer "F.SilkS")
			(effects
				(font
					(size 0.635 0.4064)
					(thickness 0.1524)
				)
			)
		)
		(fp_text user "10"
			(at -1.438148 2.983738 0)
			(unlocked yes)
			(layer "F.SilkS")
			(effects
				(font
					(size 0.635 0.4064)
					(thickness 0.1524)
				)
			)
		)
		(fp_text user "9"
			(at -2.19456 2.16535 0)
			(unlocked yes)
			(layer "F.SilkS")
			(effects
				(font
					(size 0.635 0.4064)
					(thickness 0.1524)
				)
			)
		)
		(fp_text user "12"
			(at 2.207768 2.7178 90)
			(unlocked yes)
			(layer "F.Fab")
			(effects
				(font
					(size 0.635 0.4064)
					(thickness 0.1524)
				)
			)
		)
		(fp_text user "20"
			(at 2.055368 -2.7686 90)
			(unlocked yes)
			(layer "F.Fab")
			(effects
				(font
					(size 0.635 0.4064)
					(thickness 0.1524)
				)
			)
		)
		(fp_text user "11"
			(at 1.1938 3.329432 180)
			(unlocked yes)
			(layer "F.Fab")
			(effects
				(font
					(size 0.635 0.4064)
					(thickness 0.1524)
				)
			)
		)
		(fp_text user "21_22"
			(at -0.0762 -3.401568 180)
			(unlocked yes)
			(layer "F.Fab")
			(effects
				(font
					(size 0.635 0.4064)
					(thickness 0.1524)
				)
			)
		)
		(fp_text user "10"
			(at -1.4224 3.253232 180)
			(unlocked yes)
			(layer "F.Fab")
			(effects
				(font
					(size 0.635 0.4064)
					(thickness 0.1524)
				)
			)
		)
		(fp_text user "9"
			(at -2.338832 2.5908 90)
			(unlocked yes)
			(layer "F.Fab")
			(effects
				(font
					(size 0.635 0.4064)
					(thickness 0.1524)
				)
			)
		)
		(pad "1" smd circle
			(at -1.374902 -1.999996 90)
			(size 0 0)
			(layers "F.Cu" "F.Mask" "F.Paste")
			(net "P12V_NIC5_CO_EN")
		)
		(pad "2" smd rect
			(at -1.400048 -1.500124 90)
			(size 0.254 0.8128)
			(layers "F.Cu" "F.Mask" "F.Paste")
			(net "GND")
		)
		(pad "3" smd rect
			(at -1.400048 -0.999998 90)
			(size 0.254 0.8128)
			(layers "F.Cu" "F.Mask" "F.Paste")
			(net "GND")
		)
		(pad "4" smd rect
			(at -1.400048 -0.499872 90)
			(size 0.254 0.8128)
			(layers "F.Cu" "F.Mask" "F.Paste")
			(net "P12V_NIC5_CO_TIMER")
		)
		(pad "5" smd rect
			(at -1.400048 0 90)
			(size 0.254 0.8128)
			(layers "F.Cu" "F.Mask" "F.Paste")
			(net "P12V_NIC5_CO_ISET")
		)
		(pad "6" smd rect
			(at -1.400048 0.499872 90)
			(size 0.254 0.8128)
			(layers "F.Cu" "F.Mask" "F.Paste")
			(net "P12V_NIC5_CO_SS")
		)
		(pad "7" smd rect
			(at -1.400048 0.999998 90)
			(size 0.254 0.8128)
			(layers "F.Cu" "F.Mask" "F.Paste")
			(net "GND")
		)
		(pad "8" smd rect
			(at -1.400048 1.500124 90)
			(size 0.254 0.8128)
			(layers "F.Cu" "F.Mask" "F.Paste")
			(net "P12V_NIC5_CO_IMON_VR")
		)
		(pad "9" smd rect
			(at -1.400048 1.999996 90)
			(size 0.254 0.8128)
			(layers "F.Cu" "F.Mask" "F.Paste")
			(net "P12V_NIC5_CO_FLTB")
		)
		(pad "10" smd rect
			(at -0.499872 2.400046 180)
			(size 0.254 0.8128)
			(layers "F.Cu" "F.Mask" "F.Paste")
			(net "PWRGD_P12V_NIC5_CO")
		)
		(pad "11" smd rect
			(at 0.499872 2.400046 180)
			(size 0.254 0.8128)
			(layers "F.Cu" "F.Mask" "F.Paste")
			(net "P12V_NIC5_CO_OV_FB")
		)
		(pad "12" smd rect
			(at 1.400048 1.999996 90)
			(size 0.254 0.8128)
			(layers "F.Cu" "F.Mask" "F.Paste")
			(net "P12V_NIC5_CO_AVIN_PD")
		)
		(pad "13" smd rect
			(at 1.400048 1.500124 90)
			(size 0.254 0.8128)
			(layers "F.Cu" "F.Mask" "F.Paste")
			(net "P12V_NIC5_R")
		)
		(pad "14" smd rect
			(at 1.400048 0.999998 90)
			(size 0.254 0.8128)
			(layers "F.Cu" "F.Mask" "F.Paste")
			(net "P12V_NIC5_R")
		)
		(pad "15" smd rect
			(at 1.400048 0.499872 90)
			(size 0.254 0.8128)
			(layers "F.Cu" "F.Mask" "F.Paste")
			(net "P12V_NIC5_R")
		)
		(pad "16" smd rect
			(at 1.400048 0 90)
			(size 0.254 0.8128)
			(layers "F.Cu" "F.Mask" "F.Paste")
			(net "P12V_NIC5_R")
		)
		(pad "17" smd rect
			(at 1.400048 -0.499872 90)
			(size 0.254 0.8128)
			(layers "F.Cu" "F.Mask" "F.Paste")
			(net "P12V_NIC5_R")
		)
		(pad "18" smd rect
			(at 1.400048 -0.999998 90)
			(size 0.254 0.8128)
			(layers "F.Cu" "F.Mask" "F.Paste")
			(net "P12V_NIC5_R")
		)
		(pad "19" smd rect
			(at 1.400048 -1.500124 90)
			(size 0.254 0.8128)
			(layers "F.Cu" "F.Mask" "F.Paste")
			(net "P12V_NIC5_R")
		)
		(pad "20" smd rect
			(at 1.400048 -1.999996 90)
			(size 0.254 0.8128)
			(layers "F.Cu" "F.Mask" "F.Paste")
			(net "P12V_NIC5_R")
		)
		(pad "21_22" smd circle
			(at 0.499872 -2.337562 90)
			(size 0 0)
			(layers "F.Cu" "F.Mask" "F.Paste")
			(net "P12V_AUX")
		)
		(pad "23" smd rect
			(at 0 -1.100074 90)
			(size 0.254 1.27)
			(layers "F.Cu" "F.Mask" "F.Paste")
			(net "P12V_AUX")
		)
		(pad "24" smd rect
			(at 0 -0.199898 90)
			(size 0.254 1.27)
			(layers "F.Cu" "F.Mask" "F.Paste")
			(net "P12V_AUX")
		)
		(pad "25" smd rect
			(at 0 0.700024 90)
			(size 0.254 1.27)
			(layers "F.Cu" "F.Mask" "F.Paste")
			(net "P12V_AUX")
		)
		(pad "26" smd rect
			(at 0 1.599946 90)
			(size 0.254 1.27)
			(layers "F.Cu" "F.Mask" "F.Paste")
			(net "P12V_AUX")
		)
	)
	(footprint ""
		(layer "F.Cu")
		(at 84.118958 -59.574684 90)
		(property "Reference" "PC529"
			(at 0 0 90)
			(layer "F.SilkS")
			(hide yes)
			(effects
				(font
					(size 1.27 1.27)
				)
			)
		)
		(property "Value" ""
			(at 0 0 90)
			(layer "F.Fab")
			(effects
				(font
					(size 1.27 1.27)
				)
			)
		)
		(duplicate_pad_numbers_are_jumpers no)
		(fp_line
			(start 0.7874 -0.4064)
			(end 0.7874 0.4064)
			(stroke
				(width 0.1524)
				(type default)
			)
			(layer "F.SilkS")
		)
		(fp_line
			(start -0.7874 -0.4064)
			(end 0.7874 -0.4064)
			(stroke
				(width 0.1524)
				(type default)
			)
			(layer "F.SilkS")
		)
		(fp_line
			(start 0.7874 0.4064)
			(end -0.7874 0.4064)
			(stroke
				(width 0.1524)
				(type default)
			)
			(layer "F.SilkS")
		)
		(fp_line
			(start -0.7874 0.4064)
			(end -0.7874 -0.4064)
			(stroke
				(width 0.1524)
				(type default)
			)
			(layer "F.SilkS")
		)
		(fp_line
			(start -0.12065 -0.305054)
			(end -0.12065 -0.2794)
			(stroke
				(width 0.1)
				(type default)
			)
			(layer "F.Fab")
		)
		(fp_line
			(start -0.67945 -0.305054)
			(end -0.12065 -0.305054)
			(stroke
				(width 0.1)
				(type default)
			)
			(layer "F.Fab")
		)
		(fp_line
			(start 0.67945 -0.3048)
			(end 0.67945 0.3048)
			(stroke
				(width 0.1)
				(type default)
			)
			(layer "F.Fab")
		)
		(fp_line
			(start 0.12065 -0.3048)
			(end 0.67945 -0.3048)
			(stroke
				(width 0.1)
				(type default)
			)
			(layer "F.Fab")
		)
		(fp_line
			(start 0.12065 -0.2794)
			(end 0.12065 -0.3048)
			(stroke
				(width 0.1)
				(type default)
			)
			(layer "F.Fab")
		)
		(fp_line
			(start -0.12065 -0.2794)
			(end 0.12065 -0.2794)
			(stroke
				(width 0.1)
				(type default)
			)
			(layer "F.Fab")
		)
		(fp_line
			(start 0.120396 0.2794)
			(end -0.12065 0.2794)
			(stroke
				(width 0.1)
				(type default)
			)
			(layer "F.Fab")
		)
		(fp_line
			(start -0.12065 0.2794)
			(end -0.12065 0.3048)
			(stroke
				(width 0.1)
				(type default)
			)
			(layer "F.Fab")
		)
		(fp_line
			(start 0.67945 0.3048)
			(end 0.120396 0.3048)
			(stroke
				(width 0.1)
				(type default)
			)
			(layer "F.Fab")
		)
		(fp_line
			(start 0.120396 0.3048)
			(end 0.120396 0.2794)
			(stroke
				(width 0.1)
				(type default)
			)
			(layer "F.Fab")
		)
		(fp_line
			(start -0.12065 0.3048)
			(end -0.67945 0.3048)
			(stroke
				(width 0.1)
				(type default)
			)
			(layer "F.Fab")
		)
		(fp_line
			(start -0.67945 0.3048)
			(end -0.67945 -0.305054)
			(stroke
				(width 0.1)
				(type default)
			)
			(layer "F.Fab")
		)
		(pad "1" smd circle
			(at -0.40005 0 90)
			(size 0 0)
			(layers "F.Cu" "F.Mask" "F.Paste")
			(net "P5V_AUX")
		)
		(pad "2" smd circle
			(at 0.40005 0 90)
			(size 0 0)
			(layers "F.Cu" "F.Mask" "F.Paste")
			(net "GND")
		)
	)
	(footprint ""
		(layer "F.Cu")
		(at 48.202088 -343.952322 90)
		(property "Reference" "C166"
			(at 0 0 90)
			(layer "F.SilkS")
			(hide yes)
			(effects
				(font
					(size 1.27 1.27)
				)
			)
		)
		(property "Value" ""
			(at 0 0 90)
			(layer "F.Fab")
			(effects
				(font
					(size 1.27 1.27)
				)
			)
		)
		(duplicate_pad_numbers_are_jumpers no)
		(fp_line
			(start 0.299974 -0.150114)
			(end 0.299974 0.150114)
			(stroke
				(width 0.1)
				(type default)
			)
			(layer "F.Fab")
		)
		(fp_line
			(start -0.299974 -0.150114)
			(end 0.299974 -0.150114)
			(stroke
				(width 0.1)
				(type default)
			)
			(layer "F.Fab")
		)
		(fp_line
			(start 0.299974 0.150114)
			(end -0.299974 0.150114)
			(stroke
				(width 0.1)
				(type default)
			)
			(layer "F.Fab")
		)
		(fp_line
			(start -0.299974 0.150114)
			(end -0.299974 -0.150114)
			(stroke
				(width 0.1)
				(type default)
			)
			(layer "F.Fab")
		)
		(pad "1" smd rect
			(at -0.2667 0 90)
			(size 0.3048 0.381)
			(layers "F.Cu" "F.Mask" "F.Paste")
			(net "P5E_PEX0_STN7_TX_DN<125>")
		)
		(pad "2" smd rect
			(at 0.2667 0 90)
			(size 0.3048 0.381)
			(layers "F.Cu" "F.Mask" "F.Paste")
			(net "P5E_PEX0_STN7_TX_C_DN<125>")
		)
	)
	(footprint ""
		(layer "F.Cu")
		(at 194.367912 -55.083456)
		(property "Reference" "PC372"
			(at 0 0 0)
			(layer "F.SilkS")
			(hide yes)
			(effects
				(font
					(size 1.27 1.27)
				)
			)
		)
		(property "Value" ""
			(at 0 0 0)
			(layer "F.Fab")
			(effects
				(font
					(size 1.27 1.27)
				)
			)
		)
		(duplicate_pad_numbers_are_jumpers no)
		(fp_line
			(start -0.7874 -0.4064)
			(end 0.7874 -0.4064)
			(stroke
				(width 0.1524)
				(type default)
			)
			(layer "F.SilkS")
		)
		(fp_line
			(start -0.7874 0.4064)
			(end -0.7874 -0.4064)
			(stroke
				(width 0.1524)
				(type default)
			)
			(layer "F.SilkS")
		)
		(fp_line
			(start 0.7874 -0.4064)
			(end 0.7874 0.4064)
			(stroke
				(width 0.1524)
				(type default)
			)
			(layer "F.SilkS")
		)
		(fp_line
			(start 0.7874 0.4064)
			(end -0.7874 0.4064)
			(stroke
				(width 0.1524)
				(type default)
			)
			(layer "F.SilkS")
		)
		(fp_line
			(start -0.67945 -0.305054)
			(end -0.12065 -0.305054)
			(stroke
				(width 0.1)
				(type default)
			)
			(layer "F.Fab")
		)
		(fp_line
			(start -0.67945 0.3048)
			(end -0.67945 -0.305054)
			(stroke
				(width 0.1)
				(type default)
			)
			(layer "F.Fab")
		)
		(fp_line
			(start -0.12065 -0.305054)
			(end -0.12065 -0.2794)
			(stroke
				(width 0.1)
				(type default)
			)
			(layer "F.Fab")
		)
		(fp_line
			(start -0.12065 -0.2794)
			(end 0.12065 -0.2794)
			(stroke
				(width 0.1)
				(type default)
			)
			(layer "F.Fab")
		)
		(fp_line
			(start -0.12065 0.2794)
			(end -0.12065 0.3048)
			(stroke
				(width 0.1)
				(type default)
			)
			(layer "F.Fab")
		)
		(fp_line
			(start -0.12065 0.3048)
			(end -0.67945 0.3048)
			(stroke
				(width 0.1)
				(type default)
			)
			(layer "F.Fab")
		)
		(fp_line
			(start 0.120396 0.2794)
			(end -0.12065 0.2794)
			(stroke
				(width 0.1)
				(type default)
			)
			(layer "F.Fab")
		)
		(fp_line
			(start 0.120396 0.3048)
			(end 0.120396 0.2794)
			(stroke
				(width 0.1)
				(type default)
			)
			(layer "F.Fab")
		)
		(fp_line
			(start 0.12065 -0.3048)
			(end 0.67945 -0.3048)
			(stroke
				(width 0.1)
				(type default)
			)
			(layer "F.Fab")
		)
		(fp_line
			(start 0.12065 -0.2794)
			(end 0.12065 -0.3048)
			(stroke
				(width 0.1)
				(type default)
			)
			(layer "F.Fab")
		)
		(fp_line
			(start 0.67945 -0.3048)
			(end 0.67945 0.3048)
			(stroke
				(width 0.1)
				(type default)
			)
			(layer "F.Fab")
		)
		(fp_line
			(start 0.67945 0.3048)
			(end 0.120396 0.3048)
			(stroke
				(width 0.1)
				(type default)
			)
			(layer "F.Fab")
		)
		(pad "1" smd circle
			(at -0.40005 0)
			(size 0 0)
			(layers "F.Cu" "F.Mask" "F.Paste")
			(net "P5V_AUX")
		)
		(pad "2" smd circle
			(at 0.40005 0)
			(size 0 0)
			(layers "F.Cu" "F.Mask" "F.Paste")
			(net "GND")
		)
	)
	(footprint ""
		(layer "F.Cu")
		(at 73.885552 -27.092148 -90)
		(property "Reference" "R5735"
			(at 0 0 270)
			(layer "F.SilkS")
			(hide yes)
			(effects
				(font
					(size 1.27 1.27)
				)
			)
		)
		(property "Value" ""
			(at 0 0 270)
			(layer "F.Fab")
			(effects
				(font
					(size 1.27 1.27)
				)
			)
		)
		(duplicate_pad_numbers_are_jumpers no)
		(fp_line
			(start -0.7874 0.4064)
			(end -0.7874 -0.4064)
			(stroke
				(width 0.1524)
				(type default)
			)
			(layer "F.SilkS")
		)
		(fp_line
			(start 0.7874 0.4064)
			(end -0.7874 0.4064)
			(stroke
				(width 0.1524)
				(type default)
			)
			(layer "F.SilkS")
		)
		(fp_line
			(start -0.7874 -0.4064)
			(end 0.7874 -0.4064)
			(stroke
				(width 0.1524)
				(type default)
			)
			(layer "F.SilkS")
		)
		(fp_line
			(start 0.7874 -0.4064)
			(end 0.7874 0.4064)
			(stroke
				(width 0.1524)
				(type default)
			)
			(layer "F.SilkS")
		)
		(fp_line
			(start -0.67945 0.3048)
			(end -0.67945 -0.305054)
			(stroke
				(width 0.1)
				(type default)
			)
			(layer "F.Fab")
		)
		(fp_line
			(start -0.12065 0.3048)
			(end -0.67945 0.3048)
			(stroke
				(width 0.1)
				(type default)
			)
			(layer "F.Fab")
		)
		(fp_line
			(start 0.120396 0.3048)
			(end 0.120396 0.2794)
			(stroke
				(width 0.1)
				(type default)
			)
			(layer "F.Fab")
		)
		(fp_line
			(start 0.67945 0.3048)
			(end 0.120396 0.3048)
			(stroke
				(width 0.1)
				(type default)
			)
			(layer "F.Fab")
		)
		(fp_line
			(start -0.12065 0.2794)
			(end -0.12065 0.3048)
			(stroke
				(width 0.1)
				(type default)
			)
			(layer "F.Fab")
		)
		(fp_line
			(start 0.120396 0.2794)
			(end -0.12065 0.2794)
			(stroke
				(width 0.1)
				(type default)
			)
			(layer "F.Fab")
		)
		(fp_line
			(start -0.12065 -0.2794)
			(end 0.12065 -0.2794)
			(stroke
				(width 0.1)
				(type default)
			)
			(layer "F.Fab")
		)
		(fp_line
			(start 0.12065 -0.2794)
			(end 0.12065 -0.3048)
			(stroke
				(width 0.1)
				(type default)
			)
			(layer "F.Fab")
		)
		(fp_line
			(start 0.12065 -0.3048)
			(end 0.67945 -0.3048)
			(stroke
				(width 0.1)
				(type default)
			)
			(layer "F.Fab")
		)
		(fp_line
			(start 0.67945 -0.3048)
			(end 0.67945 0.3048)
			(stroke
				(width 0.1)
				(type default)
			)
			(layer "F.Fab")
		)
		(fp_line
			(start -0.67945 -0.305054)
			(end -0.12065 -0.305054)
			(stroke
				(width 0.1)
				(type default)
			)
			(layer "F.Fab")
		)
		(fp_line
			(start -0.12065 -0.305054)
			(end -0.12065 -0.2794)
			(stroke
				(width 0.1)
				(type default)
			)
			(layer "F.Fab")
		)
		(pad "1" smd circle
			(at -0.40005 0 270)
			(size 0 0)
			(layers "F.Cu" "F.Mask" "F.Paste")
			(net "P3V3_SSD2")
		)
		(pad "2" smd circle
			(at 0.40005 0 270)
			(size 0 0)
			(layers "F.Cu" "F.Mask" "F.Paste")
			(net "SSD2_LED_ISO_N")
		)
	)
	(footprint ""
		(layer "F.Cu")
		(at 259.590286 -250.070874 -90)
		(property "Reference" "R1341"
			(at 0 0 270)
			(layer "F.SilkS")
			(hide yes)
			(effects
				(font
					(size 1.27 1.27)
				)
			)
		)
		(property "Value" ""
			(at 0 0 270)
			(layer "F.Fab")
			(effects
				(font
					(size 1.27 1.27)
				)
			)
		)
		(duplicate_pad_numbers_are_jumpers no)
		(fp_line
			(start -0.7874 0.4064)
			(end -0.7874 -0.4064)
			(stroke
				(width 0.1524)
				(type default)
			)
			(layer "F.SilkS")
		)
		(fp_line
			(start 0.7874 0.4064)
			(end -0.7874 0.4064)
			(stroke
				(width 0.1524)
				(type default)
			)
			(layer "F.SilkS")
		)
		(fp_line
			(start -0.7874 -0.4064)
			(end 0.7874 -0.4064)
			(stroke
				(width 0.1524)
				(type default)
			)
			(layer "F.SilkS")
		)
		(fp_line
			(start 0.7874 -0.4064)
			(end 0.7874 0.4064)
			(stroke
				(width 0.1524)
				(type default)
			)
			(layer "F.SilkS")
		)
		(fp_line
			(start -0.67945 0.3048)
			(end -0.67945 -0.305054)
			(stroke
				(width 0.1)
				(type default)
			)
			(layer "F.Fab")
		)
		(fp_line
			(start -0.12065 0.3048)
			(end -0.67945 0.3048)
			(stroke
				(width 0.1)
				(type default)
			)
			(layer "F.Fab")
		)
		(fp_line
			(start 0.120396 0.3048)
			(end 0.120396 0.2794)
			(stroke
				(width 0.1)
				(type default)
			)
			(layer "F.Fab")
		)
		(fp_line
			(start 0.67945 0.3048)
			(end 0.120396 0.3048)
			(stroke
				(width 0.1)
				(type default)
			)
			(layer "F.Fab")
		)
		(fp_line
			(start -0.12065 0.2794)
			(end -0.12065 0.3048)
			(stroke
				(width 0.1)
				(type default)
			)
			(layer "F.Fab")
		)
		(fp_line
			(start 0.120396 0.2794)
			(end -0.12065 0.2794)
			(stroke
				(width 0.1)
				(type default)
			)
			(layer "F.Fab")
		)
		(fp_line
			(start -0.12065 -0.2794)
			(end 0.12065 -0.2794)
			(stroke
				(width 0.1)
				(type default)
			)
			(layer "F.Fab")
		)
		(fp_line
			(start 0.12065 -0.2794)
			(end 0.12065 -0.3048)
			(stroke
				(width 0.1)
				(type default)
			)
			(layer "F.Fab")
		)
		(fp_line
			(start 0.12065 -0.3048)
			(end 0.67945 -0.3048)
			(stroke
				(width 0.1)
				(type default)
			)
			(layer "F.Fab")
		)
		(fp_line
			(start 0.67945 -0.3048)
			(end 0.67945 0.3048)
			(stroke
				(width 0.1)
				(type default)
			)
			(layer "F.Fab")
		)
		(fp_line
			(start -0.67945 -0.305054)
			(end -0.12065 -0.305054)
			(stroke
				(width 0.1)
				(type default)
			)
			(layer "F.Fab")
		)
		(fp_line
			(start -0.12065 -0.305054)
			(end -0.12065 -0.2794)
			(stroke
				(width 0.1)
				(type default)
			)
			(layer "F.Fab")
		)
		(pad "1" smd circle
			(at -0.40005 0 270)
			(size 0 0)
			(layers "F.Cu" "F.Mask" "F.Paste")
			(net "PEX2_MODE_SEL5")
		)
		(pad "2" smd circle
			(at 0.40005 0 270)
			(size 0 0)
			(layers "F.Cu" "F.Mask" "F.Paste")
			(net "P1V8_PEX")
		)
	)
	(footprint ""
		(layer "F.Cu")
		(at 331.175614 -118.467886)
		(property "Reference" "PC471"
			(at 0 0 0)
			(layer "F.SilkS")
			(hide yes)
			(effects
				(font
					(size 1.27 1.27)
				)
			)
		)
		(property "Value" ""
			(at 0 0 0)
			(layer "F.Fab")
			(effects
				(font
					(size 1.27 1.27)
				)
			)
		)
		(duplicate_pad_numbers_are_jumpers no)
		(fp_line
			(start -0.7874 -0.4064)
			(end 0.7874 -0.4064)
			(stroke
				(width 0.1524)
				(type default)
			)
			(layer "F.SilkS")
		)
		(fp_line
			(start -0.7874 0.4064)
			(end -0.7874 -0.4064)
			(stroke
				(width 0.1524)
				(type default)
			)
			(layer "F.SilkS")
		)
		(fp_line
			(start 0.7874 -0.4064)
			(end 0.7874 0.4064)
			(stroke
				(width 0.1524)
				(type default)
			)
			(layer "F.SilkS")
		)
		(fp_line
			(start 0.7874 0.4064)
			(end -0.7874 0.4064)
			(stroke
				(width 0.1524)
				(type default)
			)
			(layer "F.SilkS")
		)
		(fp_line
			(start -0.67945 -0.305054)
			(end -0.12065 -0.305054)
			(stroke
				(width 0.1)
				(type default)
			)
			(layer "F.Fab")
		)
		(fp_line
			(start -0.67945 0.3048)
			(end -0.67945 -0.305054)
			(stroke
				(width 0.1)
				(type default)
			)
			(layer "F.Fab")
		)
		(fp_line
			(start -0.12065 -0.305054)
			(end -0.12065 -0.2794)
			(stroke
				(width 0.1)
				(type default)
			)
			(layer "F.Fab")
		)
		(fp_line
			(start -0.12065 -0.2794)
			(end 0.12065 -0.2794)
			(stroke
				(width 0.1)
				(type default)
			)
			(layer "F.Fab")
		)
		(fp_line
			(start -0.12065 0.2794)
			(end -0.12065 0.3048)
			(stroke
				(width 0.1)
				(type default)
			)
			(layer "F.Fab")
		)
		(fp_line
			(start -0.12065 0.3048)
			(end -0.67945 0.3048)
			(stroke
				(width 0.1)
				(type default)
			)
			(layer "F.Fab")
		)
		(fp_line
			(start 0.120396 0.2794)
			(end -0.12065 0.2794)
			(stroke
				(width 0.1)
				(type default)
			)
			(layer "F.Fab")
		)
		(fp_line
			(start 0.120396 0.3048)
			(end 0.120396 0.2794)
			(stroke
				(width 0.1)
				(type default)
			)
			(layer "F.Fab")
		)
		(fp_line
			(start 0.12065 -0.3048)
			(end 0.67945 -0.3048)
			(stroke
				(width 0.1)
				(type default)
			)
			(layer "F.Fab")
		)
		(fp_line
			(start 0.12065 -0.2794)
			(end 0.12065 -0.3048)
			(stroke
				(width 0.1)
				(type default)
			)
			(layer "F.Fab")
		)
		(fp_line
			(start 0.67945 -0.3048)
			(end 0.67945 0.3048)
			(stroke
				(width 0.1)
				(type default)
			)
			(layer "F.Fab")
		)
		(fp_line
			(start 0.67945 0.3048)
			(end 0.120396 0.3048)
			(stroke
				(width 0.1)
				(type default)
			)
			(layer "F.Fab")
		)
		(pad "1" smd circle
			(at -0.40005 0)
			(size 0 0)
			(layers "F.Cu" "F.Mask" "F.Paste")
			(net "P3V3_NIC5_SS")
		)
		(pad "2" smd circle
			(at 0.40005 0)
			(size 0 0)
			(layers "F.Cu" "F.Mask" "F.Paste")
			(net "GND")
		)
	)
	(footprint ""
		(layer "F.Cu")
		(at 99.97948 -385.577842 -90)
		(property "Reference" "R5445"
			(at 0 0 270)
			(layer "F.SilkS")
			(hide yes)
			(effects
				(font
					(size 1.27 1.27)
				)
			)
		)
		(property "Value" ""
			(at 0 0 270)
			(layer "F.Fab")
			(effects
				(font
					(size 1.27 1.27)
				)
			)
		)
		(duplicate_pad_numbers_are_jumpers no)
		(fp_line
			(start 0.7874 0.4064)
			(end -0.7874 0.4064)
			(stroke
				(width 0.1524)
				(type default)
			)
			(layer "F.SilkS")
		)
		(fp_line
			(start -0.7874 -0.4064)
			(end 0.007112 -0.4064)
			(stroke
				(width 0.1524)
				(type default)
			)
			(layer "F.SilkS")
		)
		(fp_line
			(start 0.7874 -0.4064)
			(end 0.7874 0.4064)
			(stroke
				(width 0.1524)
				(type default)
			)
			(layer "F.SilkS")
		)
		(fp_line
			(start -0.67945 0.3048)
			(end -0.67945 -0.305054)
			(stroke
				(width 0.1)
				(type default)
			)
			(layer "F.Fab")
		)
		(fp_line
			(start -0.12065 0.3048)
			(end -0.67945 0.3048)
			(stroke
				(width 0.1)
				(type default)
			)
			(layer "F.Fab")
		)
		(fp_line
			(start 0.120396 0.3048)
			(end 0.120396 0.2794)
			(stroke
				(width 0.1)
				(type default)
			)
			(layer "F.Fab")
		)
		(fp_line
			(start 0.67945 0.3048)
			(end 0.120396 0.3048)
			(stroke
				(width 0.1)
				(type default)
			)
			(layer "F.Fab")
		)
		(fp_line
			(start -0.12065 0.2794)
			(end -0.12065 0.3048)
			(stroke
				(width 0.1)
				(type default)
			)
			(layer "F.Fab")
		)
		(fp_line
			(start 0.120396 0.2794)
			(end -0.12065 0.2794)
			(stroke
				(width 0.1)
				(type default)
			)
			(layer "F.Fab")
		)
		(fp_line
			(start -0.12065 -0.2794)
			(end 0.12065 -0.2794)
			(stroke
				(width 0.1)
				(type default)
			)
			(layer "F.Fab")
		)
		(fp_line
			(start 0.12065 -0.2794)
			(end 0.12065 -0.3048)
			(stroke
				(width 0.1)
				(type default)
			)
			(layer "F.Fab")
		)
		(fp_line
			(start 0.12065 -0.3048)
			(end 0.67945 -0.3048)
			(stroke
				(width 0.1)
				(type default)
			)
			(layer "F.Fab")
		)
		(fp_line
			(start 0.67945 -0.3048)
			(end 0.67945 0.3048)
			(stroke
				(width 0.1)
				(type default)
			)
			(layer "F.Fab")
		)
		(fp_line
			(start -0.67945 -0.305054)
			(end -0.12065 -0.305054)
			(stroke
				(width 0.1)
				(type default)
			)
			(layer "F.Fab")
		)
		(fp_line
			(start -0.12065 -0.305054)
			(end -0.12065 -0.2794)
			(stroke
				(width 0.1)
				(type default)
			)
			(layer "F.Fab")
		)
		(pad "1" smd rect
			(at -0.40005 0 90)
			(size 0.4572 0.508)
			(layers "F.Cu" "F.Mask" "F.Paste")
			(net "USB2_MB_BMC_R_DN")
		)
		(pad "2" smd rect
			(at 0.40005 0 90)
			(size 0.4572 0.508)
			(layers "F.Cu" "F.Mask" "F.Paste")
			(net "USB2_MB_BMC_DN")
		)
	)
	(footprint ""
		(layer "F.Cu")
		(at 163.047426 -20.35556)
		(property "Reference" "C3908"
			(at 0 0 0)
			(layer "F.SilkS")
			(hide yes)
			(effects
				(font
					(size 1.27 1.27)
				)
			)
		)
		(property "Value" ""
			(at 0 0 0)
			(layer "F.Fab")
			(effects
				(font
					(size 1.27 1.27)
				)
			)
		)
		(duplicate_pad_numbers_are_jumpers no)
		(fp_line
			(start -0.7874 -0.4064)
			(end 0.7874 -0.4064)
			(stroke
				(width 0.1524)
				(type default)
			)
			(layer "F.SilkS")
		)
		(fp_line
			(start -0.7874 0.4064)
			(end -0.7874 -0.4064)
			(stroke
				(width 0.1524)
				(type default)
			)
			(layer "F.SilkS")
		)
		(fp_line
			(start 0.7874 -0.4064)
			(end 0.7874 0.4064)
			(stroke
				(width 0.1524)
				(type default)
			)
			(layer "F.SilkS")
		)
		(fp_line
			(start 0.7874 0.4064)
			(end -0.7874 0.4064)
			(stroke
				(width 0.1524)
				(type default)
			)
			(layer "F.SilkS")
		)
		(fp_line
			(start -0.67945 -0.305054)
			(end -0.12065 -0.305054)
			(stroke
				(width 0.1)
				(type default)
			)
			(layer "F.Fab")
		)
		(fp_line
			(start -0.67945 0.3048)
			(end -0.67945 -0.305054)
			(stroke
				(width 0.1)
				(type default)
			)
			(layer "F.Fab")
		)
		(fp_line
			(start -0.12065 -0.305054)
			(end -0.12065 -0.2794)
			(stroke
				(width 0.1)
				(type default)
			)
			(layer "F.Fab")
		)
		(fp_line
			(start -0.12065 -0.2794)
			(end 0.12065 -0.2794)
			(stroke
				(width 0.1)
				(type default)
			)
			(layer "F.Fab")
		)
		(fp_line
			(start -0.12065 0.2794)
			(end -0.12065 0.3048)
			(stroke
				(width 0.1)
				(type default)
			)
			(layer "F.Fab")
		)
		(fp_line
			(start -0.12065 0.3048)
			(end -0.67945 0.3048)
			(stroke
				(width 0.1)
				(type default)
			)
			(layer "F.Fab")
		)
		(fp_line
			(start 0.120396 0.2794)
			(end -0.12065 0.2794)
			(stroke
				(width 0.1)
				(type default)
			)
			(layer "F.Fab")
		)
		(fp_line
			(start 0.120396 0.3048)
			(end 0.120396 0.2794)
			(stroke
				(width 0.1)
				(type default)
			)
			(layer "F.Fab")
		)
		(fp_line
			(start 0.12065 -0.3048)
			(end 0.67945 -0.3048)
			(stroke
				(width 0.1)
				(type default)
			)
			(layer "F.Fab")
		)
		(fp_line
			(start 0.12065 -0.2794)
			(end 0.12065 -0.3048)
			(stroke
				(width 0.1)
				(type default)
			)
			(layer "F.Fab")
		)
		(fp_line
			(start 0.67945 -0.3048)
			(end 0.67945 0.3048)
			(stroke
				(width 0.1)
				(type default)
			)
			(layer "F.Fab")
		)
		(fp_line
			(start 0.67945 0.3048)
			(end 0.120396 0.3048)
			(stroke
				(width 0.1)
				(type default)
			)
			(layer "F.Fab")
		)
		(pad "1" smd circle
			(at -0.40005 0)
			(size 0 0)
			(layers "F.Cu" "F.Mask" "F.Paste")
			(net "P12V_SSD5")
		)
		(pad "2" smd circle
			(at 0.40005 0)
			(size 0 0)
			(layers "F.Cu" "F.Mask" "F.Paste")
			(net "GND")
		)
	)
	(footprint ""
		(layer "F.Cu")
		(at 448.947032 -54.3941)
		(property "Reference" "PU45"
			(at -1.964436 2.902204 0)
			(unlocked yes)
			(layer "F.SilkS")
			(effects
				(font
					(size 0.7874 0.5842)
					(thickness 0.1524)
				)
				(justify left)
			)
		)
		(property "Value" ""
			(at 0 0 0)
			(layer "F.Fab")
			(effects
				(font
					(size 1.27 1.27)
				)
			)
		)
		(duplicate_pad_numbers_are_jumpers no)
		(fp_line
			(start -1.943608 -1.549908)
			(end 1.943608 -1.549908)
			(stroke
				(width 0.1524)
				(type default)
			)
			(layer "F.SilkS")
		)
		(fp_line
			(start -1.943608 1.549908)
			(end -1.943608 -1.549908)
			(stroke
				(width 0.1524)
				(type default)
			)
			(layer "F.SilkS")
		)
		(fp_line
			(start 1.943608 -1.549908)
			(end 1.943608 1.549908)
			(stroke
				(width 0.1524)
				(type default)
			)
			(layer "F.SilkS")
		)
		(fp_line
			(start 1.943608 1.549908)
			(end -1.943608 1.549908)
			(stroke
				(width 0.1524)
				(type default)
			)
			(layer "F.SilkS")
		)
		(fp_poly
			(pts
				(xy -2.019808 -1.549908) (xy -1.257808 -1.549908) (xy -1.257808 -1.880108) (xy -2.019808 -1.880108)
			)
			(stroke
				(width 0)
				(type default)
			)
			(fill yes)
			(layer "F.SilkS")
		)
		(fp_line
			(start -1.549908 -1.549908)
			(end 1.549908 -1.549908)
			(stroke
				(width 0.1)
				(type default)
			)
			(layer "F.Fab")
		)
		(fp_line
			(start -1.549908 1.549908)
			(end -1.549908 -1.549908)
			(stroke
				(width 0.1)
				(type default)
			)
			(layer "F.Fab")
		)
		(fp_line
			(start 1.549908 -1.549908)
			(end 1.549908 1.549908)
			(stroke
				(width 0.1)
				(type default)
			)
			(layer "F.Fab")
		)
		(fp_line
			(start 1.549908 1.549908)
			(end -1.549908 1.549908)
			(stroke
				(width 0.1)
				(type default)
			)
			(layer "F.Fab")
		)
		(fp_poly
			(pts
				(xy -2.019808 -1.549908) (xy -1.257808 -1.549908) (xy -1.257808 -1.880108) (xy -2.019808 -1.880108)
			)
			(stroke
				(width 0)
				(type default)
			)
			(fill yes)
			(layer "F.Fab")
		)
		(pad "1" smd rect
			(at -1.500124 -1.249934 270)
			(size 0.2794 0.6096)
			(layers "F.Cu" "F.Mask" "F.Paste")
			(net "P12V_SSD15_R")
		)
		(pad "2" smd rect
			(at -1.500124 -0.750062 270)
			(size 0.2794 0.6096)
			(layers "F.Cu" "F.Mask" "F.Paste")
			(net "P12V_SSD15_R")
		)
		(pad "3" smd rect
			(at -1.500124 -0.249936 270)
			(size 0.2794 0.6096)
			(layers "F.Cu" "F.Mask" "F.Paste")
			(net "P12V_SSD15_R")
		)
		(pad "4" smd rect
			(at -1.500124 0.249936 270)
			(size 0.2794 0.6096)
			(layers "F.Cu" "F.Mask" "F.Paste")
			(net "P12V_SSD15_R")
		)
		(pad "5" smd rect
			(at -1.500124 0.750062 270)
			(size 0.2794 0.6096)
			(layers "F.Cu" "F.Mask" "F.Paste")
			(net "P12V_SSD15_R")
		)
		(pad "6" smd rect
			(at -1.500124 1.249934 270)
			(size 0.2794 0.6096)
			(layers "F.Cu" "F.Mask" "F.Paste")
			(net "GND")
		)
		(pad "7" smd rect
			(at 1.500124 1.249934 270)
			(size 0.2794 0.6096)
			(layers "F.Cu" "F.Mask" "F.Paste")
			(net "P12V_SSD15_SS")
		)
		(pad "8" smd rect
			(at 1.500124 0.750062 270)
			(size 0.2794 0.6096)
			(layers "F.Cu" "F.Mask" "F.Paste")
			(net "PWRGD_P12V_SSD15")
		)
		(pad "9" smd rect
			(at 1.500124 0.249936 270)
			(size 0.2794 0.6096)
			(layers "F.Cu" "F.Mask" "F.Paste")
			(net "P12V_SSD15_OCP")
		)
		(pad "10" smd rect
			(at 1.500124 -0.249936 270)
			(size 0.2794 0.6096)
			(layers "F.Cu" "F.Mask" "F.Paste")
			(net "P5V_AUX")
		)
		(pad "11" smd rect
			(at 1.500124 -0.750062 270)
			(size 0.2794 0.6096)
			(layers "F.Cu" "F.Mask" "F.Paste")
			(net "SSD15_PWR_EN_R")
		)
		(pad "12" smd rect
			(at 1.500124 -1.249934 270)
			(size 0.2794 0.6096)
			(layers "F.Cu" "F.Mask" "F.Paste")
			(net "P12V_AUX")
		)
		(pad "13" smd rect
			(at 0 0)
			(size 1.9812 2.7178)
			(layers "F.Cu" "F.Mask" "F.Paste")
			(net "P12V_AUX")
		)
		(zone
			(layer "F.Cu")
			(hatch none 0.5)
			(connect_pads
				(clearance 0)
			)
			(min_thickness 0.25)
			(keepout
				(tracks not_allowed)
				(vias allowed)
				(pads allowed)
				(copperpour not_allowed)
				(footprints allowed)
			)
			(placement
				(enabled no)
				(sheetname "")
			)
			(fill
				(thermal_gap 0.5)
				(thermal_bridge_width 0.5)
				(island_removal_mode 0)
			)
			(polygon
				(pts
					(xy 450.090032 -55.9435) (xy 450.090032 -55.8165) (xy 450.090032 -52.8447) (xy 450.090032 -52.844192)
					(xy 447.804032 -52.844192) (xy 447.804032 -52.8447) (xy 447.804032 -52.9717) (xy 447.804032 -54.3941)
					(xy 447.905632 -54.3941) (xy 447.905632 -52.9717) (xy 449.988432 -52.9717) (xy 449.988432 -55.8165)
					(xy 447.905632 -55.8165) (xy 447.905632 -54.4195) (xy 447.804032 -54.4195) (xy 447.804032 -55.8165)
					(xy 447.804032 -55.9435) (xy 447.804032 -55.944008) (xy 450.090032 -55.944008)
				)
			)
		)
	)
	(footprint ""
		(layer "F.Cu")
		(at 271.895062 -356.244906 90)
		(property "Reference" "C610"
			(at 0 0 90)
			(layer "F.SilkS")
			(hide yes)
			(effects
				(font
					(size 1.27 1.27)
				)
			)
		)
		(property "Value" ""
			(at 0 0 90)
			(layer "F.Fab")
			(effects
				(font
					(size 1.27 1.27)
				)
			)
		)
		(duplicate_pad_numbers_are_jumpers no)
		(fp_line
			(start 0.299974 -0.150114)
			(end 0.299974 0.150114)
			(stroke
				(width 0.1)
				(type default)
			)
			(layer "F.Fab")
		)
		(fp_line
			(start -0.299974 -0.150114)
			(end 0.299974 -0.150114)
			(stroke
				(width 0.1)
				(type default)
			)
			(layer "F.Fab")
		)
		(fp_line
			(start 0.299974 0.150114)
			(end -0.299974 0.150114)
			(stroke
				(width 0.1)
				(type default)
			)
			(layer "F.Fab")
		)
		(fp_line
			(start -0.299974 0.150114)
			(end -0.299974 -0.150114)
			(stroke
				(width 0.1)
				(type default)
			)
			(layer "F.Fab")
		)
		(pad "1" smd rect
			(at -0.2667 0 90)
			(size 0.3048 0.381)
			(layers "F.Cu" "F.Mask" "F.Paste")
			(net "P5E_PEX2_STN7_TX_DN<114>")
		)
		(pad "2" smd rect
			(at 0.2667 0 90)
			(size 0.3048 0.381)
			(layers "F.Cu" "F.Mask" "F.Paste")
			(net "P5E_PEX2_STN7_TX_C_DN<114>")
		)
	)
	(footprint ""
		(layer "F.Cu")
		(at 243.564918 -312.671714)
		(property "Reference" "PC250"
			(at 0 0 0)
			(layer "F.SilkS")
			(hide yes)
			(effects
				(font
					(size 1.27 1.27)
				)
			)
		)
		(property "Value" ""
			(at 0 0 0)
			(layer "F.Fab")
			(effects
				(font
					(size 1.27 1.27)
				)
			)
		)
		(duplicate_pad_numbers_are_jumpers no)
		(fp_line
			(start -1.524 -0.762)
			(end 1.524 -0.762)
			(stroke
				(width 0.1524)
				(type default)
			)
			(layer "F.SilkS")
		)
		(fp_line
			(start -1.524 0.762)
			(end -1.524 -0.762)
			(stroke
				(width 0.1524)
				(type default)
			)
			(layer "F.SilkS")
		)
		(fp_line
			(start 1.524 -0.762)
			(end 1.524 0.762)
			(stroke
				(width 0.1524)
				(type default)
			)
			(layer "F.SilkS")
		)
		(fp_line
			(start 1.524 0.762)
			(end -1.524 0.762)
			(stroke
				(width 0.1524)
				(type default)
			)
			(layer "F.SilkS")
		)
		(fp_line
			(start -1.1049 -0.724916)
			(end -1.1049 0.724916)
			(stroke
				(width 0.1)
				(type default)
			)
			(layer "F.Fab")
		)
		(fp_line
			(start -1.1049 0.724916)
			(end 1.1049 0.724916)
			(stroke
				(width 0.1)
				(type default)
			)
			(layer "F.Fab")
		)
		(fp_line
			(start 1.1049 -0.724916)
			(end -1.1049 -0.724916)
			(stroke
				(width 0.1)
				(type default)
			)
			(layer "F.Fab")
		)
		(fp_line
			(start 1.1049 0.724916)
			(end 1.1049 -0.724916)
			(stroke
				(width 0.1)
				(type default)
			)
			(layer "F.Fab")
		)
		(pad "1" smd rect
			(at -0.889 0 180)
			(size 1.016 1.27)
			(layers "F.Cu" "F.Mask" "F.Paste")
			(net "SW_P12V_P1V25_PEX2_FLT")
		)
		(pad "2" smd rect
			(at 0.889 0 180)
			(size 1.016 1.27)
			(layers "F.Cu" "F.Mask" "F.Paste")
			(net "GND")
		)
	)
	(footprint ""
		(layer "F.Cu")
		(at 289.634422 -350.098614 90)
		(property "Reference" "C2361"
			(at 0 0 90)
			(layer "F.SilkS")
			(hide yes)
			(effects
				(font
					(size 1.27 1.27)
				)
			)
		)
		(property "Value" ""
			(at 0 0 90)
			(layer "F.Fab")
			(effects
				(font
					(size 1.27 1.27)
				)
			)
		)
		(duplicate_pad_numbers_are_jumpers no)
		(fp_line
			(start 0.299974 -0.150114)
			(end 0.299974 0.150114)
			(stroke
				(width 0.1)
				(type default)
			)
			(layer "F.Fab")
		)
		(fp_line
			(start -0.299974 -0.150114)
			(end 0.299974 -0.150114)
			(stroke
				(width 0.1)
				(type default)
			)
			(layer "F.Fab")
		)
		(fp_line
			(start 0.299974 0.150114)
			(end -0.299974 0.150114)
			(stroke
				(width 0.1)
				(type default)
			)
			(layer "F.Fab")
		)
		(fp_line
			(start -0.299974 0.150114)
			(end -0.299974 -0.150114)
			(stroke
				(width 0.1)
				(type default)
			)
			(layer "F.Fab")
		)
		(pad "1" smd rect
			(at -0.2667 0 90)
			(size 0.3048 0.381)
			(layers "F.Cu" "F.Mask" "F.Paste")
			(net "P5E_PEX2_STN4_TX_DP<69>")
		)
		(pad "2" smd rect
			(at 0.2667 0 90)
			(size 0.3048 0.381)
			(layers "F.Cu" "F.Mask" "F.Paste")
			(net "P5E_PEX2_STN4_TX_C_DP<69>")
		)
	)
	(footprint ""
		(layer "F.Cu")
		(at 220.077792 -254.18542 -90)
		(property "Reference" "C4282"
			(at 0 0 270)
			(layer "F.SilkS")
			(hide yes)
			(effects
				(font
					(size 1.27 1.27)
				)
			)
		)
		(property "Value" ""
			(at 0 0 270)
			(layer "F.Fab")
			(effects
				(font
					(size 1.27 1.27)
				)
			)
		)
		(duplicate_pad_numbers_are_jumpers no)
		(fp_line
			(start -1.2954 0.5842)
			(end -1.2954 -0.5842)
			(stroke
				(width 0.1524)
				(type default)
			)
			(layer "F.SilkS")
		)
		(fp_line
			(start 1.2954 0.5842)
			(end -1.2954 0.5842)
			(stroke
				(width 0.1524)
				(type default)
			)
			(layer "F.SilkS")
		)
		(fp_line
			(start -1.2954 -0.5842)
			(end 1.2954 -0.5842)
			(stroke
				(width 0.1524)
				(type default)
			)
			(layer "F.SilkS")
		)
		(fp_line
			(start 1.2954 -0.5842)
			(end 1.2954 0.5842)
			(stroke
				(width 0.1524)
				(type default)
			)
			(layer "F.SilkS")
		)
		(fp_line
			(start -0.8636 0.4572)
			(end -0.8636 0.4064)
			(stroke
				(width 0.1)
				(type default)
			)
			(layer "F.Fab")
		)
		(fp_line
			(start 0.8636 0.4572)
			(end -0.8636 0.4572)
			(stroke
				(width 0.1)
				(type default)
			)
			(layer "F.Fab")
		)
		(fp_line
			(start -1.1938 0.4064)
			(end -1.1938 -0.4064)
			(stroke
				(width 0.1)
				(type default)
			)
			(layer "F.Fab")
		)
		(fp_line
			(start -0.8636 0.4064)
			(end -1.1938 0.4064)
			(stroke
				(width 0.1)
				(type default)
			)
			(layer "F.Fab")
		)
		(fp_line
			(start 0.8636 0.4064)
			(end 0.8636 0.4572)
			(stroke
				(width 0.1)
				(type default)
			)
			(layer "F.Fab")
		)
		(fp_line
			(start 1.1938 0.4064)
			(end 0.8636 0.4064)
			(stroke
				(width 0.1)
				(type default)
			)
			(layer "F.Fab")
		)
		(fp_line
			(start -1.1938 -0.4064)
			(end -0.8636 -0.4064)
			(stroke
				(width 0.1)
				(type default)
			)
			(layer "F.Fab")
		)
		(fp_line
			(start -0.8636 -0.4064)
			(end -0.8636 -0.4572)
			(stroke
				(width 0.1)
				(type default)
			)
			(layer "F.Fab")
		)
		(fp_line
			(start 0.8636 -0.4064)
			(end 1.1938 -0.4064)
			(stroke
				(width 0.1)
				(type default)
			)
			(layer "F.Fab")
		)
		(fp_line
			(start 1.1938 -0.4064)
			(end 1.1938 0.4064)
			(stroke
				(width 0.1)
				(type default)
			)
			(layer "F.Fab")
		)
		(fp_line
			(start -0.8636 -0.4572)
			(end 0.8636 -0.4572)
			(stroke
				(width 0.1)
				(type default)
			)
			(layer "F.Fab")
		)
		(fp_line
			(start 0.8636 -0.4572)
			(end 0.8636 -0.4064)
			(stroke
				(width 0.1)
				(type default)
			)
			(layer "F.Fab")
		)
		(pad "1" smd rect
			(at -0.7366 0 180)
			(size 0.7112 0.8128)
			(layers "F.Cu" "F.Mask" "F.Paste")
			(net "P1V25_SERDES_VDDPLL_PEX1_C0")
		)
		(pad "2" smd rect
			(at 0.7366 0 180)
			(size 0.7112 0.8128)
			(layers "F.Cu" "F.Mask" "F.Paste")
			(net "GND")
		)
	)
	(footprint ""
		(layer "F.Cu")
		(at 213.868 -228.6 -90)
		(property "Reference" "R6214"
			(at 0 0 270)
			(layer "F.SilkS")
			(hide yes)
			(effects
				(font
					(size 1.27 1.27)
				)
			)
		)
		(property "Value" ""
			(at 0 0 270)
			(layer "F.Fab")
			(effects
				(font
					(size 1.27 1.27)
				)
			)
		)
		(duplicate_pad_numbers_are_jumpers no)
		(fp_line
			(start -0.7874 0.4064)
			(end -0.7874 -0.4064)
			(stroke
				(width 0.1524)
				(type default)
			)
			(layer "F.SilkS")
		)
		(fp_line
			(start 0.7874 0.4064)
			(end -0.7874 0.4064)
			(stroke
				(width 0.1524)
				(type default)
			)
			(layer "F.SilkS")
		)
		(fp_line
			(start -0.7874 -0.4064)
			(end 0.7874 -0.4064)
			(stroke
				(width 0.1524)
				(type default)
			)
			(layer "F.SilkS")
		)
		(fp_line
			(start 0.7874 -0.4064)
			(end 0.7874 0.4064)
			(stroke
				(width 0.1524)
				(type default)
			)
			(layer "F.SilkS")
		)
		(fp_line
			(start -0.67945 0.3048)
			(end -0.67945 -0.305054)
			(stroke
				(width 0.1)
				(type default)
			)
			(layer "F.Fab")
		)
		(fp_line
			(start -0.12065 0.3048)
			(end -0.67945 0.3048)
			(stroke
				(width 0.1)
				(type default)
			)
			(layer "F.Fab")
		)
		(fp_line
			(start 0.120396 0.3048)
			(end 0.120396 0.2794)
			(stroke
				(width 0.1)
				(type default)
			)
			(layer "F.Fab")
		)
		(fp_line
			(start 0.67945 0.3048)
			(end 0.120396 0.3048)
			(stroke
				(width 0.1)
				(type default)
			)
			(layer "F.Fab")
		)
		(fp_line
			(start -0.12065 0.2794)
			(end -0.12065 0.3048)
			(stroke
				(width 0.1)
				(type default)
			)
			(layer "F.Fab")
		)
		(fp_line
			(start 0.120396 0.2794)
			(end -0.12065 0.2794)
			(stroke
				(width 0.1)
				(type default)
			)
			(layer "F.Fab")
		)
		(fp_line
			(start -0.12065 -0.2794)
			(end 0.12065 -0.2794)
			(stroke
				(width 0.1)
				(type default)
			)
			(layer "F.Fab")
		)
		(fp_line
			(start 0.12065 -0.2794)
			(end 0.12065 -0.3048)
			(stroke
				(width 0.1)
				(type default)
			)
			(layer "F.Fab")
		)
		(fp_line
			(start 0.12065 -0.3048)
			(end 0.67945 -0.3048)
			(stroke
				(width 0.1)
				(type default)
			)
			(layer "F.Fab")
		)
		(fp_line
			(start 0.67945 -0.3048)
			(end 0.67945 0.3048)
			(stroke
				(width 0.1)
				(type default)
			)
			(layer "F.Fab")
		)
		(fp_line
			(start -0.67945 -0.305054)
			(end -0.12065 -0.305054)
			(stroke
				(width 0.1)
				(type default)
			)
			(layer "F.Fab")
		)
		(fp_line
			(start -0.12065 -0.305054)
			(end -0.12065 -0.2794)
			(stroke
				(width 0.1)
				(type default)
			)
			(layer "F.Fab")
		)
		(pad "1" smd circle
			(at -0.40005 0 270)
			(size 0 0)
			(layers "F.Cu" "F.Mask" "F.Paste")
			(net "PRSNT_DBV2_SLIMSAS_R")
		)
		(pad "2" smd circle
			(at 0.40005 0 270)
			(size 0 0)
			(layers "F.Cu" "F.Mask" "F.Paste")
			(net "P3V3_AUX")
		)
	)
	(footprint ""
		(layer "F.Cu")
		(at 381.41148 -261.434834)
		(property "Reference" "L139"
			(at 0 0 0)
			(layer "F.SilkS")
			(hide yes)
			(effects
				(font
					(size 1.27 1.27)
				)
			)
		)
		(property "Value" ""
			(at 0 0 0)
			(layer "F.Fab")
			(effects
				(font
					(size 1.27 1.27)
				)
			)
		)
		(duplicate_pad_numbers_are_jumpers no)
		(fp_line
			(start -1.63576 -0.8128)
			(end -1.63576 0.8128)
			(stroke
				(width 0.1524)
				(type default)
			)
			(layer "F.SilkS")
		)
		(fp_line
			(start -1.63576 -0.8128)
			(end 1.63576 -0.8128)
			(stroke
				(width 0.1524)
				(type default)
			)
			(layer "F.SilkS")
		)
		(fp_line
			(start 1.63576 -0.8128)
			(end 1.63576 0.8128)
			(stroke
				(width 0.1524)
				(type default)
			)
			(layer "F.SilkS")
		)
		(fp_line
			(start 1.63576 0.8128)
			(end -1.63576 0.8128)
			(stroke
				(width 0.1524)
				(type default)
			)
			(layer "F.SilkS")
		)
		(fp_line
			(start -1.56083 -0.738632)
			(end -1.56083 0.7366)
			(stroke
				(width 0.1)
				(type default)
			)
			(layer "F.Fab")
		)
		(fp_line
			(start -1.56083 0.7366)
			(end -1.524 0.7366)
			(stroke
				(width 0.1)
				(type default)
			)
			(layer "F.Fab")
		)
		(fp_line
			(start -1.524 0.7366)
			(end 1.524 0.7366)
			(stroke
				(width 0.1)
				(type default)
			)
			(layer "F.Fab")
		)
		(fp_line
			(start 1.524 0.7366)
			(end 1.560576 0.7366)
			(stroke
				(width 0.1)
				(type default)
			)
			(layer "F.Fab")
		)
		(fp_line
			(start 1.560576 -0.738632)
			(end -1.56083 -0.738632)
			(stroke
				(width 0.1)
				(type default)
			)
			(layer "F.Fab")
		)
		(fp_line
			(start 1.560576 0.7366)
			(end 1.560576 -0.738632)
			(stroke
				(width 0.1)
				(type default)
			)
			(layer "F.Fab")
		)
		(pad "1" smd rect
			(at -0.94996 0 180)
			(size 1.1176 1.3716)
			(layers "F.Cu" "F.Mask" "F.Paste")
			(net "P1V8_PLL0_PEX3")
		)
		(pad "2" smd rect
			(at 0.94996 0 180)
			(size 1.1176 1.3716)
			(layers "F.Cu" "F.Mask" "F.Paste")
			(net "PCEPLL3_VDDA18_PEX3")
		)
	)
	(footprint ""
		(layer "F.Cu")
		(at 286.385 -86.106 180)
		(property "Reference" "R489"
			(at 0 0 180)
			(layer "F.SilkS")
			(hide yes)
			(effects
				(font
					(size 1.27 1.27)
				)
			)
		)
		(property "Value" ""
			(at 0 0 180)
			(layer "F.Fab")
			(effects
				(font
					(size 1.27 1.27)
				)
			)
		)
		(duplicate_pad_numbers_are_jumpers no)
		(fp_line
			(start 0.7874 0.4064)
			(end -0.7874 0.4064)
			(stroke
				(width 0.1524)
				(type default)
			)
			(layer "F.SilkS")
		)
		(fp_line
			(start 0.7874 -0.4064)
			(end 0.7874 0.4064)
			(stroke
				(width 0.1524)
				(type default)
			)
			(layer "F.SilkS")
		)
		(fp_line
			(start -0.7874 0.4064)
			(end -0.7874 -0.4064)
			(stroke
				(width 0.1524)
				(type default)
			)
			(layer "F.SilkS")
		)
		(fp_line
			(start -0.7874 -0.4064)
			(end 0.7874 -0.4064)
			(stroke
				(width 0.1524)
				(type default)
			)
			(layer "F.SilkS")
		)
		(fp_line
			(start 0.67945 0.3048)
			(end 0.120396 0.3048)
			(stroke
				(width 0.1)
				(type default)
			)
			(layer "F.Fab")
		)
		(fp_line
			(start 0.67945 -0.3048)
			(end 0.67945 0.3048)
			(stroke
				(width 0.1)
				(type default)
			)
			(layer "F.Fab")
		)
		(fp_line
			(start 0.12065 -0.2794)
			(end 0.12065 -0.3048)
			(stroke
				(width 0.1)
				(type default)
			)
			(layer "F.Fab")
		)
		(fp_line
			(start 0.12065 -0.3048)
			(end 0.67945 -0.3048)
			(stroke
				(width 0.1)
				(type default)
			)
			(layer "F.Fab")
		)
		(fp_line
			(start 0.120396 0.3048)
			(end 0.120396 0.2794)
			(stroke
				(width 0.1)
				(type default)
			)
			(layer "F.Fab")
		)
		(fp_line
			(start 0.120396 0.2794)
			(end -0.12065 0.2794)
			(stroke
				(width 0.1)
				(type default)
			)
			(layer "F.Fab")
		)
		(fp_line
			(start -0.12065 0.3048)
			(end -0.67945 0.3048)
			(stroke
				(width 0.1)
				(type default)
			)
			(layer "F.Fab")
		)
		(fp_line
			(start -0.12065 0.2794)
			(end -0.12065 0.3048)
			(stroke
				(width 0.1)
				(type default)
			)
			(layer "F.Fab")
		)
		(fp_line
			(start -0.12065 -0.2794)
			(end 0.12065 -0.2794)
			(stroke
				(width 0.1)
				(type default)
			)
			(layer "F.Fab")
		)
		(fp_line
			(start -0.12065 -0.305054)
			(end -0.12065 -0.2794)
			(stroke
				(width 0.1)
				(type default)
			)
			(layer "F.Fab")
		)
		(fp_line
			(start -0.67945 0.3048)
			(end -0.67945 -0.305054)
			(stroke
				(width 0.1)
				(type default)
			)
			(layer "F.Fab")
		)
		(fp_line
			(start -0.67945 -0.305054)
			(end -0.12065 -0.305054)
			(stroke
				(width 0.1)
				(type default)
			)
			(layer "F.Fab")
		)
		(pad "1" smd circle
			(at -0.40005 0 180)
			(size 0 0)
			(layers "F.Cu" "F.Mask" "F.Paste")
			(net "BB_FRU_A0")
		)
		(pad "2" smd circle
			(at 0.40005 0 180)
			(size 0 0)
			(layers "F.Cu" "F.Mask" "F.Paste")
			(net "GND")
		)
	)
	(footprint ""
		(layer "F.Cu")
		(at 368.959638 -61.612526)
		(property "Reference" "PD41"
			(at -3.7084 -2.733548 0)
			(unlocked yes)
			(layer "F.SilkS")
			(effects
				(font
					(size 0.7874 0.5842)
					(thickness 0.1524)
				)
				(justify left)
			)
		)
		(property "Value" ""
			(at 0 0 0)
			(layer "F.Fab")
			(effects
				(font
					(size 1.27 1.27)
				)
			)
		)
		(duplicate_pad_numbers_are_jumpers no)
		(fp_line
			(start -3.656584 -1.970024)
			(end -3.656584 1.970024)
			(stroke
				(width 0.1524)
				(type default)
			)
			(layer "F.SilkS")
		)
		(fp_line
			(start -3.656584 1.970024)
			(end 4.240784 1.970024)
			(stroke
				(width 0.1524)
				(type default)
			)
			(layer "F.SilkS")
		)
		(fp_line
			(start 4.240784 -1.970024)
			(end -3.656584 -1.970024)
			(stroke
				(width 0.1524)
				(type default)
			)
			(layer "F.SilkS")
		)
		(fp_line
			(start 4.240784 1.970024)
			(end 4.240784 -1.970024)
			(stroke
				(width 0.1524)
				(type default)
			)
			(layer "F.SilkS")
		)
		(fp_poly
			(pts
				(xy 3.580384 1.970024) (xy 3.580384 -1.970024) (xy 4.240784 -1.970024) (xy 4.240784 1.970024)
			)
			(stroke
				(width 0)
				(type default)
			)
			(fill yes)
			(layer "F.SilkS")
		)
		(fp_line
			(start -2.3749 -1.970024)
			(end -2.3749 1.970024)
			(stroke
				(width 0.1)
				(type default)
			)
			(layer "F.Fab")
		)
		(fp_line
			(start -2.3749 1.970024)
			(end 2.3749 1.970024)
			(stroke
				(width 0.1)
				(type default)
			)
			(layer "F.Fab")
		)
		(fp_line
			(start 2.3749 -1.970024)
			(end -2.3749 -1.970024)
			(stroke
				(width 0.1)
				(type default)
			)
			(layer "F.Fab")
		)
		(fp_line
			(start 2.3749 1.970024)
			(end 2.3749 -1.970024)
			(stroke
				(width 0.1)
				(type default)
			)
			(layer "F.Fab")
		)
		(fp_text user "+"
			(at -4.9784 -0.23495 0)
			(unlocked yes)
			(layer "F.Fab")
			(effects
				(font
					(size 1.905 1.4224)
					(thickness 0.1524)
				)
				(justify left)
			)
		)
		(fp_text user "-"
			(at 4.1656 -0.23495 0)
			(unlocked yes)
			(layer "F.Fab")
			(effects
				(font
					(size 1.905 1.4224)
					(thickness 0.1524)
				)
				(justify left)
			)
		)
		(pad "A" smd rect
			(at -2.450084 0)
			(size 2.159 2.2606)
			(layers "F.Cu" "F.Mask" "F.Paste")
			(net "GND")
		)
		(pad "C" smd rect
			(at 2.450084 0)
			(size 2.159 2.2606)
			(layers "F.Cu" "F.Mask" "F.Paste")
			(net "P12V_AUX")
		)
	)
	(footprint ""
		(layer "F.Cu")
		(at 171.487592 -356.244906 90)
		(property "Reference" "C2522"
			(at 0 0 90)
			(layer "F.SilkS")
			(hide yes)
			(effects
				(font
					(size 1.27 1.27)
				)
			)
		)
		(property "Value" ""
			(at 0 0 90)
			(layer "F.Fab")
			(effects
				(font
					(size 1.27 1.27)
				)
			)
		)
		(duplicate_pad_numbers_are_jumpers no)
		(fp_line
			(start 0.299974 -0.150114)
			(end 0.299974 0.150114)
			(stroke
				(width 0.1)
				(type default)
			)
			(layer "F.Fab")
		)
		(fp_line
			(start -0.299974 -0.150114)
			(end 0.299974 -0.150114)
			(stroke
				(width 0.1)
				(type default)
			)
			(layer "F.Fab")
		)
		(fp_line
			(start 0.299974 0.150114)
			(end -0.299974 0.150114)
			(stroke
				(width 0.1)
				(type default)
			)
			(layer "F.Fab")
		)
		(fp_line
			(start -0.299974 0.150114)
			(end -0.299974 -0.150114)
			(stroke
				(width 0.1)
				(type default)
			)
			(layer "F.Fab")
		)
		(pad "1" smd rect
			(at -0.2667 0 90)
			(size 0.3048 0.381)
			(layers "F.Cu" "F.Mask" "F.Paste")
			(net "P5E_PEX1_STN4_TX_DP<74>")
		)
		(pad "2" smd rect
			(at 0.2667 0 90)
			(size 0.3048 0.381)
			(layers "F.Cu" "F.Mask" "F.Paste")
			(net "P5E_PEX1_STN4_TX_C_DP<74>")
		)
	)
	(footprint ""
		(layer "F.Cu")
		(at 122.219212 -59.574684 90)
		(property "Reference" "PC540"
			(at 0 0 90)
			(layer "F.SilkS")
			(hide yes)
			(effects
				(font
					(size 1.27 1.27)
				)
			)
		)
		(property "Value" ""
			(at 0 0 90)
			(layer "F.Fab")
			(effects
				(font
					(size 1.27 1.27)
				)
			)
		)
		(duplicate_pad_numbers_are_jumpers no)
		(fp_line
			(start 0.7874 -0.4064)
			(end 0.7874 0.4064)
			(stroke
				(width 0.1524)
				(type default)
			)
			(layer "F.SilkS")
		)
		(fp_line
			(start -0.7874 -0.4064)
			(end 0.7874 -0.4064)
			(stroke
				(width 0.1524)
				(type default)
			)
			(layer "F.SilkS")
		)
		(fp_line
			(start 0.7874 0.4064)
			(end -0.7874 0.4064)
			(stroke
				(width 0.1524)
				(type default)
			)
			(layer "F.SilkS")
		)
		(fp_line
			(start -0.7874 0.4064)
			(end -0.7874 -0.4064)
			(stroke
				(width 0.1524)
				(type default)
			)
			(layer "F.SilkS")
		)
		(fp_line
			(start -0.12065 -0.305054)
			(end -0.12065 -0.2794)
			(stroke
				(width 0.1)
				(type default)
			)
			(layer "F.Fab")
		)
		(fp_line
			(start -0.67945 -0.305054)
			(end -0.12065 -0.305054)
			(stroke
				(width 0.1)
				(type default)
			)
			(layer "F.Fab")
		)
		(fp_line
			(start 0.67945 -0.3048)
			(end 0.67945 0.3048)
			(stroke
				(width 0.1)
				(type default)
			)
			(layer "F.Fab")
		)
		(fp_line
			(start 0.12065 -0.3048)
			(end 0.67945 -0.3048)
			(stroke
				(width 0.1)
				(type default)
			)
			(layer "F.Fab")
		)
		(fp_line
			(start 0.12065 -0.2794)
			(end 0.12065 -0.3048)
			(stroke
				(width 0.1)
				(type default)
			)
			(layer "F.Fab")
		)
		(fp_line
			(start -0.12065 -0.2794)
			(end 0.12065 -0.2794)
			(stroke
				(width 0.1)
				(type default)
			)
			(layer "F.Fab")
		)
		(fp_line
			(start 0.120396 0.2794)
			(end -0.12065 0.2794)
			(stroke
				(width 0.1)
				(type default)
			)
			(layer "F.Fab")
		)
		(fp_line
			(start -0.12065 0.2794)
			(end -0.12065 0.3048)
			(stroke
				(width 0.1)
				(type default)
			)
			(layer "F.Fab")
		)
		(fp_line
			(start 0.67945 0.3048)
			(end 0.120396 0.3048)
			(stroke
				(width 0.1)
				(type default)
			)
			(layer "F.Fab")
		)
		(fp_line
			(start 0.120396 0.3048)
			(end 0.120396 0.2794)
			(stroke
				(width 0.1)
				(type default)
			)
			(layer "F.Fab")
		)
		(fp_line
			(start -0.12065 0.3048)
			(end -0.67945 0.3048)
			(stroke
				(width 0.1)
				(type default)
			)
			(layer "F.Fab")
		)
		(fp_line
			(start -0.67945 0.3048)
			(end -0.67945 -0.305054)
			(stroke
				(width 0.1)
				(type default)
			)
			(layer "F.Fab")
		)
		(pad "1" smd circle
			(at -0.40005 0 90)
			(size 0 0)
			(layers "F.Cu" "F.Mask" "F.Paste")
			(net "P5V_AUX")
		)
		(pad "2" smd circle
			(at 0.40005 0 90)
			(size 0 0)
			(layers "F.Cu" "F.Mask" "F.Paste")
			(net "GND")
		)
	)
	(footprint ""
		(layer "F.Cu")
		(at 349.899986 -72.69988)
		(property "Reference" "H60"
			(at -4.574794 -5.022342 0)
			(unlocked yes)
			(layer "F.SilkS")
			(effects
				(font
					(size 0.7874 0.5842)
					(thickness 0.1524)
				)
				(justify left)
			)
		)
		(property "Value" ""
			(at 0 0 0)
			(layer "F.Fab")
			(effects
				(font
					(size 1.27 1.27)
				)
			)
		)
		(duplicate_pad_numbers_are_jumpers no)
		(pad "1" thru_hole circle
			(at 0 0)
			(size 10.0076 10.0076)
			(drill 5.6134)
			(layers "*.Cu" "*.Mask")
			(remove_unused_layers no)
			(net "GND")
			(clearance -1.9431)
		)
	)
	(footprint ""
		(layer "F.Cu")
		(at 321.201542 -304.036476 90)
		(property "Reference" "R1383"
			(at 0 0 90)
			(layer "F.SilkS")
			(hide yes)
			(effects
				(font
					(size 1.27 1.27)
				)
			)
		)
		(property "Value" ""
			(at 0 0 90)
			(layer "F.Fab")
			(effects
				(font
					(size 1.27 1.27)
				)
			)
		)
		(duplicate_pad_numbers_are_jumpers no)
		(fp_line
			(start 0.7874 -0.4064)
			(end 0.7874 0.4064)
			(stroke
				(width 0.1524)
				(type default)
			)
			(layer "F.SilkS")
		)
		(fp_line
			(start -0.7874 -0.4064)
			(end 0.7874 -0.4064)
			(stroke
				(width 0.1524)
				(type default)
			)
			(layer "F.SilkS")
		)
		(fp_line
			(start 0.7874 0.4064)
			(end -0.7874 0.4064)
			(stroke
				(width 0.1524)
				(type default)
			)
			(layer "F.SilkS")
		)
		(fp_line
			(start -0.7874 0.4064)
			(end -0.7874 -0.4064)
			(stroke
				(width 0.1524)
				(type default)
			)
			(layer "F.SilkS")
		)
		(fp_line
			(start -0.12065 -0.305054)
			(end -0.12065 -0.2794)
			(stroke
				(width 0.1)
				(type default)
			)
			(layer "F.Fab")
		)
		(fp_line
			(start -0.67945 -0.305054)
			(end -0.12065 -0.305054)
			(stroke
				(width 0.1)
				(type default)
			)
			(layer "F.Fab")
		)
		(fp_line
			(start 0.67945 -0.3048)
			(end 0.67945 0.3048)
			(stroke
				(width 0.1)
				(type default)
			)
			(layer "F.Fab")
		)
		(fp_line
			(start 0.12065 -0.3048)
			(end 0.67945 -0.3048)
			(stroke
				(width 0.1)
				(type default)
			)
			(layer "F.Fab")
		)
		(fp_line
			(start 0.12065 -0.2794)
			(end 0.12065 -0.3048)
			(stroke
				(width 0.1)
				(type default)
			)
			(layer "F.Fab")
		)
		(fp_line
			(start -0.12065 -0.2794)
			(end 0.12065 -0.2794)
			(stroke
				(width 0.1)
				(type default)
			)
			(layer "F.Fab")
		)
		(fp_line
			(start 0.120396 0.2794)
			(end -0.12065 0.2794)
			(stroke
				(width 0.1)
				(type default)
			)
			(layer "F.Fab")
		)
		(fp_line
			(start -0.12065 0.2794)
			(end -0.12065 0.3048)
			(stroke
				(width 0.1)
				(type default)
			)
			(layer "F.Fab")
		)
		(fp_line
			(start 0.67945 0.3048)
			(end 0.120396 0.3048)
			(stroke
				(width 0.1)
				(type default)
			)
			(layer "F.Fab")
		)
		(fp_line
			(start 0.120396 0.3048)
			(end 0.120396 0.2794)
			(stroke
				(width 0.1)
				(type default)
			)
			(layer "F.Fab")
		)
		(fp_line
			(start -0.12065 0.3048)
			(end -0.67945 0.3048)
			(stroke
				(width 0.1)
				(type default)
			)
			(layer "F.Fab")
		)
		(fp_line
			(start -0.67945 0.3048)
			(end -0.67945 -0.305054)
			(stroke
				(width 0.1)
				(type default)
			)
			(layer "F.Fab")
		)
		(pad "1" smd circle
			(at -0.40005 0 90)
			(size 0 0)
			(layers "F.Cu" "F.Mask" "F.Paste")
			(net "GND")
		)
		(pad "2" smd circle
			(at 0.40005 0 90)
			(size 0 0)
			(layers "F.Cu" "F.Mask" "F.Paste")
			(net "PEX2_SPARE4")
		)
	)
	(footprint ""
		(layer "F.Cu")
		(at 323.91477 -216.415366 180)
		(property "Reference" "R2985"
			(at 0 0 180)
			(layer "F.SilkS")
			(hide yes)
			(effects
				(font
					(size 1.27 1.27)
				)
			)
		)
		(property "Value" ""
			(at 0 0 180)
			(layer "F.Fab")
			(effects
				(font
					(size 1.27 1.27)
				)
			)
		)
		(duplicate_pad_numbers_are_jumpers no)
		(fp_line
			(start 0.7874 0.4064)
			(end -0.7874 0.4064)
			(stroke
				(width 0.1524)
				(type default)
			)
			(layer "F.SilkS")
		)
		(fp_line
			(start 0.7874 -0.4064)
			(end 0.7874 0.4064)
			(stroke
				(width 0.1524)
				(type default)
			)
			(layer "F.SilkS")
		)
		(fp_line
			(start -0.7874 0.4064)
			(end -0.7874 -0.4064)
			(stroke
				(width 0.1524)
				(type default)
			)
			(layer "F.SilkS")
		)
		(fp_line
			(start -0.7874 -0.4064)
			(end 0.7874 -0.4064)
			(stroke
				(width 0.1524)
				(type default)
			)
			(layer "F.SilkS")
		)
		(fp_line
			(start 0.67945 0.3048)
			(end 0.120396 0.3048)
			(stroke
				(width 0.1)
				(type default)
			)
			(layer "F.Fab")
		)
		(fp_line
			(start 0.67945 -0.3048)
			(end 0.67945 0.3048)
			(stroke
				(width 0.1)
				(type default)
			)
			(layer "F.Fab")
		)
		(fp_line
			(start 0.12065 -0.2794)
			(end 0.12065 -0.3048)
			(stroke
				(width 0.1)
				(type default)
			)
			(layer "F.Fab")
		)
		(fp_line
			(start 0.12065 -0.3048)
			(end 0.67945 -0.3048)
			(stroke
				(width 0.1)
				(type default)
			)
			(layer "F.Fab")
		)
		(fp_line
			(start 0.120396 0.3048)
			(end 0.120396 0.2794)
			(stroke
				(width 0.1)
				(type default)
			)
			(layer "F.Fab")
		)
		(fp_line
			(start 0.120396 0.2794)
			(end -0.12065 0.2794)
			(stroke
				(width 0.1)
				(type default)
			)
			(layer "F.Fab")
		)
		(fp_line
			(start -0.12065 0.3048)
			(end -0.67945 0.3048)
			(stroke
				(width 0.1)
				(type default)
			)
			(layer "F.Fab")
		)
		(fp_line
			(start -0.12065 0.2794)
			(end -0.12065 0.3048)
			(stroke
				(width 0.1)
				(type default)
			)
			(layer "F.Fab")
		)
		(fp_line
			(start -0.12065 -0.2794)
			(end 0.12065 -0.2794)
			(stroke
				(width 0.1)
				(type default)
			)
			(layer "F.Fab")
		)
		(fp_line
			(start -0.12065 -0.305054)
			(end -0.12065 -0.2794)
			(stroke
				(width 0.1)
				(type default)
			)
			(layer "F.Fab")
		)
		(fp_line
			(start -0.67945 0.3048)
			(end -0.67945 -0.305054)
			(stroke
				(width 0.1)
				(type default)
			)
			(layer "F.Fab")
		)
		(fp_line
			(start -0.67945 -0.305054)
			(end -0.12065 -0.305054)
			(stroke
				(width 0.1)
				(type default)
			)
			(layer "F.Fab")
		)
		(pad "1" smd circle
			(at -0.40005 0 180)
			(size 0 0)
			(layers "F.Cu" "F.Mask" "F.Paste")
			(net "LED_POSTCODE_7")
		)
		(pad "2" smd circle
			(at 0.40005 0 180)
			(size 0 0)
			(layers "F.Cu" "F.Mask" "F.Paste")
			(net "LED_POSTCODE_R_7")
		)
	)
	(footprint ""
		(layer "F.Cu")
		(at 214.194136 -181.613556 -90)
		(property "Reference" "R5298"
			(at 0 0 270)
			(layer "F.SilkS")
			(hide yes)
			(effects
				(font
					(size 1.27 1.27)
				)
			)
		)
		(property "Value" ""
			(at 0 0 270)
			(layer "F.Fab")
			(effects
				(font
					(size 1.27 1.27)
				)
			)
		)
		(duplicate_pad_numbers_are_jumpers no)
		(fp_line
			(start -0.7874 0.4064)
			(end -0.7874 -0.4064)
			(stroke
				(width 0.1524)
				(type default)
			)
			(layer "F.SilkS")
		)
		(fp_line
			(start 0.7874 0.4064)
			(end -0.7874 0.4064)
			(stroke
				(width 0.1524)
				(type default)
			)
			(layer "F.SilkS")
		)
		(fp_line
			(start -0.7874 -0.4064)
			(end 0.7874 -0.4064)
			(stroke
				(width 0.1524)
				(type default)
			)
			(layer "F.SilkS")
		)
		(fp_line
			(start 0.7874 -0.4064)
			(end 0.7874 0.4064)
			(stroke
				(width 0.1524)
				(type default)
			)
			(layer "F.SilkS")
		)
		(fp_line
			(start -0.67945 0.3048)
			(end -0.67945 -0.305054)
			(stroke
				(width 0.1)
				(type default)
			)
			(layer "F.Fab")
		)
		(fp_line
			(start -0.12065 0.3048)
			(end -0.67945 0.3048)
			(stroke
				(width 0.1)
				(type default)
			)
			(layer "F.Fab")
		)
		(fp_line
			(start 0.120396 0.3048)
			(end 0.120396 0.2794)
			(stroke
				(width 0.1)
				(type default)
			)
			(layer "F.Fab")
		)
		(fp_line
			(start 0.67945 0.3048)
			(end 0.120396 0.3048)
			(stroke
				(width 0.1)
				(type default)
			)
			(layer "F.Fab")
		)
		(fp_line
			(start -0.12065 0.2794)
			(end -0.12065 0.3048)
			(stroke
				(width 0.1)
				(type default)
			)
			(layer "F.Fab")
		)
		(fp_line
			(start 0.120396 0.2794)
			(end -0.12065 0.2794)
			(stroke
				(width 0.1)
				(type default)
			)
			(layer "F.Fab")
		)
		(fp_line
			(start -0.12065 -0.2794)
			(end 0.12065 -0.2794)
			(stroke
				(width 0.1)
				(type default)
			)
			(layer "F.Fab")
		)
		(fp_line
			(start 0.12065 -0.2794)
			(end 0.12065 -0.3048)
			(stroke
				(width 0.1)
				(type default)
			)
			(layer "F.Fab")
		)
		(fp_line
			(start 0.12065 -0.3048)
			(end 0.67945 -0.3048)
			(stroke
				(width 0.1)
				(type default)
			)
			(layer "F.Fab")
		)
		(fp_line
			(start 0.67945 -0.3048)
			(end 0.67945 0.3048)
			(stroke
				(width 0.1)
				(type default)
			)
			(layer "F.Fab")
		)
		(fp_line
			(start -0.67945 -0.305054)
			(end -0.12065 -0.305054)
			(stroke
				(width 0.1)
				(type default)
			)
			(layer "F.Fab")
		)
		(fp_line
			(start -0.12065 -0.305054)
			(end -0.12065 -0.2794)
			(stroke
				(width 0.1)
				(type default)
			)
			(layer "F.Fab")
		)
		(pad "1" smd circle
			(at -0.40005 0 270)
			(size 0 0)
			(layers "F.Cu" "F.Mask" "F.Paste")
			(net "SEL_FLASH_PEX1_BUF")
		)
		(pad "2" smd circle
			(at 0.40005 0 270)
			(size 0 0)
			(layers "F.Cu" "F.Mask" "F.Paste")
			(net "SEL_FLASH_PEX1_BUF_R")
		)
	)
	(footprint ""
		(layer "F.Cu")
		(at 104.517698 -380.123446 90)
		(property "Reference" "R6732"
			(at 0 0 90)
			(layer "F.SilkS")
			(hide yes)
			(effects
				(font
					(size 1.27 1.27)
				)
			)
		)
		(property "Value" ""
			(at 0 0 90)
			(layer "F.Fab")
			(effects
				(font
					(size 1.27 1.27)
				)
			)
		)
		(duplicate_pad_numbers_are_jumpers no)
		(fp_line
			(start 0.7874 -0.4064)
			(end 0.7874 0.4064)
			(stroke
				(width 0.1524)
				(type default)
			)
			(layer "F.SilkS")
		)
		(fp_line
			(start -0.7874 -0.4064)
			(end 0.7874 -0.4064)
			(stroke
				(width 0.1524)
				(type default)
			)
			(layer "F.SilkS")
		)
		(fp_line
			(start 0.02032 0.4064)
			(end -0.7874 0.4064)
			(stroke
				(width 0.1524)
				(type default)
			)
			(layer "F.SilkS")
		)
		(fp_line
			(start -0.12065 -0.305054)
			(end -0.12065 -0.2794)
			(stroke
				(width 0.1)
				(type default)
			)
			(layer "F.Fab")
		)
		(fp_line
			(start -0.67945 -0.305054)
			(end -0.12065 -0.305054)
			(stroke
				(width 0.1)
				(type default)
			)
			(layer "F.Fab")
		)
		(fp_line
			(start 0.67945 -0.3048)
			(end 0.67945 0.3048)
			(stroke
				(width 0.1)
				(type default)
			)
			(layer "F.Fab")
		)
		(fp_line
			(start 0.12065 -0.3048)
			(end 0.67945 -0.3048)
			(stroke
				(width 0.1)
				(type default)
			)
			(layer "F.Fab")
		)
		(fp_line
			(start 0.12065 -0.2794)
			(end 0.12065 -0.3048)
			(stroke
				(width 0.1)
				(type default)
			)
			(layer "F.Fab")
		)
		(fp_line
			(start -0.12065 -0.2794)
			(end 0.12065 -0.2794)
			(stroke
				(width 0.1)
				(type default)
			)
			(layer "F.Fab")
		)
		(fp_line
			(start 0.120396 0.2794)
			(end -0.12065 0.2794)
			(stroke
				(width 0.1)
				(type default)
			)
			(layer "F.Fab")
		)
		(fp_line
			(start -0.12065 0.2794)
			(end -0.12065 0.3048)
			(stroke
				(width 0.1)
				(type default)
			)
			(layer "F.Fab")
		)
		(fp_line
			(start 0.67945 0.3048)
			(end 0.120396 0.3048)
			(stroke
				(width 0.1)
				(type default)
			)
			(layer "F.Fab")
		)
		(fp_line
			(start 0.120396 0.3048)
			(end 0.120396 0.2794)
			(stroke
				(width 0.1)
				(type default)
			)
			(layer "F.Fab")
		)
		(fp_line
			(start -0.12065 0.3048)
			(end -0.67945 0.3048)
			(stroke
				(width 0.1)
				(type default)
			)
			(layer "F.Fab")
		)
		(fp_line
			(start -0.67945 0.3048)
			(end -0.67945 -0.305054)
			(stroke
				(width 0.1)
				(type default)
			)
			(layer "F.Fab")
		)
		(pad "1" smd rect
			(at -0.40005 0 270)
			(size 0.4572 0.508)
			(layers "F.Cu" "F.Mask" "F.Paste")
			(net "USB2_BIC_USB8042_DN")
		)
		(pad "2" smd rect
			(at 0.40005 0 270)
			(size 0.4572 0.508)
			(layers "F.Cu" "F.Mask" "F.Paste")
			(net "USB2_BIC_DN")
		)
	)
	(footprint ""
		(layer "F.Cu")
		(at 224.856294 -183.58358)
		(property "Reference" "R5495"
			(at 0 0 0)
			(layer "F.SilkS")
			(hide yes)
			(effects
				(font
					(size 1.27 1.27)
				)
			)
		)
		(property "Value" ""
			(at 0 0 0)
			(layer "F.Fab")
			(effects
				(font
					(size 1.27 1.27)
				)
			)
		)
		(duplicate_pad_numbers_are_jumpers no)
		(fp_line
			(start -0.7874 -0.4064)
			(end 0.7874 -0.4064)
			(stroke
				(width 0.1524)
				(type default)
			)
			(layer "F.SilkS")
		)
		(fp_line
			(start -0.7874 0.4064)
			(end -0.7874 -0.4064)
			(stroke
				(width 0.1524)
				(type default)
			)
			(layer "F.SilkS")
		)
		(fp_line
			(start 0.7874 -0.4064)
			(end 0.7874 0.4064)
			(stroke
				(width 0.1524)
				(type default)
			)
			(layer "F.SilkS")
		)
		(fp_line
			(start 0.7874 0.4064)
			(end -0.7874 0.4064)
			(stroke
				(width 0.1524)
				(type default)
			)
			(layer "F.SilkS")
		)
		(fp_line
			(start -0.67945 -0.305054)
			(end -0.12065 -0.305054)
			(stroke
				(width 0.1)
				(type default)
			)
			(layer "F.Fab")
		)
		(fp_line
			(start -0.67945 0.3048)
			(end -0.67945 -0.305054)
			(stroke
				(width 0.1)
				(type default)
			)
			(layer "F.Fab")
		)
		(fp_line
			(start -0.12065 -0.305054)
			(end -0.12065 -0.2794)
			(stroke
				(width 0.1)
				(type default)
			)
			(layer "F.Fab")
		)
		(fp_line
			(start -0.12065 -0.2794)
			(end 0.12065 -0.2794)
			(stroke
				(width 0.1)
				(type default)
			)
			(layer "F.Fab")
		)
		(fp_line
			(start -0.12065 0.2794)
			(end -0.12065 0.3048)
			(stroke
				(width 0.1)
				(type default)
			)
			(layer "F.Fab")
		)
		(fp_line
			(start -0.12065 0.3048)
			(end -0.67945 0.3048)
			(stroke
				(width 0.1)
				(type default)
			)
			(layer "F.Fab")
		)
		(fp_line
			(start 0.120396 0.2794)
			(end -0.12065 0.2794)
			(stroke
				(width 0.1)
				(type default)
			)
			(layer "F.Fab")
		)
		(fp_line
			(start 0.120396 0.3048)
			(end 0.120396 0.2794)
			(stroke
				(width 0.1)
				(type default)
			)
			(layer "F.Fab")
		)
		(fp_line
			(start 0.12065 -0.3048)
			(end 0.67945 -0.3048)
			(stroke
				(width 0.1)
				(type default)
			)
			(layer "F.Fab")
		)
		(fp_line
			(start 0.12065 -0.2794)
			(end 0.12065 -0.3048)
			(stroke
				(width 0.1)
				(type default)
			)
			(layer "F.Fab")
		)
		(fp_line
			(start 0.67945 -0.3048)
			(end 0.67945 0.3048)
			(stroke
				(width 0.1)
				(type default)
			)
			(layer "F.Fab")
		)
		(fp_line
			(start 0.67945 0.3048)
			(end 0.120396 0.3048)
			(stroke
				(width 0.1)
				(type default)
			)
			(layer "F.Fab")
		)
		(pad "1" smd circle
			(at -0.40005 0)
			(size 0 0)
			(layers "F.Cu" "F.Mask" "F.Paste")
			(net "RST_BIC_BUF_RSMRST_N_BUF")
		)
		(pad "2" smd circle
			(at 0.40005 0)
			(size 0 0)
			(layers "F.Cu" "F.Mask" "F.Paste")
			(net "RST_BJT_Q15_B")
		)
	)
	(footprint ""
		(layer "F.Cu")
		(at 236.887512 -231.416606 90)
		(property "Reference" "R4520"
			(at 0 0 90)
			(layer "F.SilkS")
			(hide yes)
			(effects
				(font
					(size 1.27 1.27)
				)
			)
		)
		(property "Value" ""
			(at 0 0 90)
			(layer "F.Fab")
			(effects
				(font
					(size 1.27 1.27)
				)
			)
		)
		(duplicate_pad_numbers_are_jumpers no)
		(fp_line
			(start 0.7874 -0.4064)
			(end 0.7874 0.4064)
			(stroke
				(width 0.1524)
				(type default)
			)
			(layer "F.SilkS")
		)
		(fp_line
			(start -0.7874 -0.4064)
			(end 0.7874 -0.4064)
			(stroke
				(width 0.1524)
				(type default)
			)
			(layer "F.SilkS")
		)
		(fp_line
			(start 0.7874 0.4064)
			(end -0.7874 0.4064)
			(stroke
				(width 0.1524)
				(type default)
			)
			(layer "F.SilkS")
		)
		(fp_line
			(start -0.7874 0.4064)
			(end -0.7874 -0.4064)
			(stroke
				(width 0.1524)
				(type default)
			)
			(layer "F.SilkS")
		)
		(fp_line
			(start -0.12065 -0.305054)
			(end -0.12065 -0.2794)
			(stroke
				(width 0.1)
				(type default)
			)
			(layer "F.Fab")
		)
		(fp_line
			(start -0.67945 -0.305054)
			(end -0.12065 -0.305054)
			(stroke
				(width 0.1)
				(type default)
			)
			(layer "F.Fab")
		)
		(fp_line
			(start 0.67945 -0.3048)
			(end 0.67945 0.3048)
			(stroke
				(width 0.1)
				(type default)
			)
			(layer "F.Fab")
		)
		(fp_line
			(start 0.12065 -0.3048)
			(end 0.67945 -0.3048)
			(stroke
				(width 0.1)
				(type default)
			)
			(layer "F.Fab")
		)
		(fp_line
			(start 0.12065 -0.2794)
			(end 0.12065 -0.3048)
			(stroke
				(width 0.1)
				(type default)
			)
			(layer "F.Fab")
		)
		(fp_line
			(start -0.12065 -0.2794)
			(end 0.12065 -0.2794)
			(stroke
				(width 0.1)
				(type default)
			)
			(layer "F.Fab")
		)
		(fp_line
			(start 0.120396 0.2794)
			(end -0.12065 0.2794)
			(stroke
				(width 0.1)
				(type default)
			)
			(layer "F.Fab")
		)
		(fp_line
			(start -0.12065 0.2794)
			(end -0.12065 0.3048)
			(stroke
				(width 0.1)
				(type default)
			)
			(layer "F.Fab")
		)
		(fp_line
			(start 0.67945 0.3048)
			(end 0.120396 0.3048)
			(stroke
				(width 0.1)
				(type default)
			)
			(layer "F.Fab")
		)
		(fp_line
			(start 0.120396 0.3048)
			(end 0.120396 0.2794)
			(stroke
				(width 0.1)
				(type default)
			)
			(layer "F.Fab")
		)
		(fp_line
			(start -0.12065 0.3048)
			(end -0.67945 0.3048)
			(stroke
				(width 0.1)
				(type default)
			)
			(layer "F.Fab")
		)
		(fp_line
			(start -0.67945 0.3048)
			(end -0.67945 -0.305054)
			(stroke
				(width 0.1)
				(type default)
			)
			(layer "F.Fab")
		)
		(pad "1" smd circle
			(at -0.40005 0 90)
			(size 0 0)
			(layers "F.Cu" "F.Mask" "F.Paste")
			(net "SSD6_PWRDIS_BIC")
		)
		(pad "2" smd circle
			(at 0.40005 0 90)
			(size 0 0)
			(layers "F.Cu" "F.Mask" "F.Paste")
			(net "SSD6_PWRDIS_BIC_R")
		)
	)
	(footprint ""
		(layer "F.Cu")
		(at 80.019398 -122.270266 180)
		(property "Reference" "C28"
			(at 0 0 180)
			(layer "F.SilkS")
			(hide yes)
			(effects
				(font
					(size 1.27 1.27)
				)
			)
		)
		(property "Value" ""
			(at 0 0 180)
			(layer "F.Fab")
			(effects
				(font
					(size 1.27 1.27)
				)
			)
		)
		(duplicate_pad_numbers_are_jumpers no)
		(fp_line
			(start 0.299974 0.150114)
			(end -0.299974 0.150114)
			(stroke
				(width 0.1)
				(type default)
			)
			(layer "F.Fab")
		)
		(fp_line
			(start 0.299974 -0.150114)
			(end 0.299974 0.150114)
			(stroke
				(width 0.1)
				(type default)
			)
			(layer "F.Fab")
		)
		(fp_line
			(start -0.299974 0.150114)
			(end -0.299974 -0.150114)
			(stroke
				(width 0.1)
				(type default)
			)
			(layer "F.Fab")
		)
		(fp_line
			(start -0.299974 -0.150114)
			(end 0.299974 -0.150114)
			(stroke
				(width 0.1)
				(type default)
			)
			(layer "F.Fab")
		)
		(pad "1" smd rect
			(at -0.2667 0 180)
			(size 0.3048 0.381)
			(layers "F.Cu" "F.Mask" "F.Paste")
			(net "P5E_PEX0_STN0_TX_DN<2>")
		)
		(pad "2" smd rect
			(at 0.2667 0 180)
			(size 0.3048 0.381)
			(layers "F.Cu" "F.Mask" "F.Paste")
			(net "P5E_PEX0_STN0_TX_C_DN<2>")
		)
	)
	(footprint ""
		(layer "F.Cu")
		(at 314.726574 -53.697124 -90)
		(property "Reference" "PC546"
			(at 0 0 270)
			(layer "F.SilkS")
			(hide yes)
			(effects
				(font
					(size 1.27 1.27)
				)
			)
		)
		(property "Value" ""
			(at 0 0 270)
			(layer "F.Fab")
			(effects
				(font
					(size 1.27 1.27)
				)
			)
		)
		(duplicate_pad_numbers_are_jumpers no)
		(fp_line
			(start -0.7874 0.4064)
			(end -0.7874 -0.4064)
			(stroke
				(width 0.1524)
				(type default)
			)
			(layer "F.SilkS")
		)
		(fp_line
			(start 0.7874 0.4064)
			(end -0.7874 0.4064)
			(stroke
				(width 0.1524)
				(type default)
			)
			(layer "F.SilkS")
		)
		(fp_line
			(start -0.7874 -0.4064)
			(end 0.7874 -0.4064)
			(stroke
				(width 0.1524)
				(type default)
			)
			(layer "F.SilkS")
		)
		(fp_line
			(start 0.7874 -0.4064)
			(end 0.7874 0.4064)
			(stroke
				(width 0.1524)
				(type default)
			)
			(layer "F.SilkS")
		)
		(fp_line
			(start -0.67945 0.3048)
			(end -0.67945 -0.305054)
			(stroke
				(width 0.1)
				(type default)
			)
			(layer "F.Fab")
		)
		(fp_line
			(start -0.12065 0.3048)
			(end -0.67945 0.3048)
			(stroke
				(width 0.1)
				(type default)
			)
			(layer "F.Fab")
		)
		(fp_line
			(start 0.120396 0.3048)
			(end 0.120396 0.2794)
			(stroke
				(width 0.1)
				(type default)
			)
			(layer "F.Fab")
		)
		(fp_line
			(start 0.67945 0.3048)
			(end 0.120396 0.3048)
			(stroke
				(width 0.1)
				(type default)
			)
			(layer "F.Fab")
		)
		(fp_line
			(start -0.12065 0.2794)
			(end -0.12065 0.3048)
			(stroke
				(width 0.1)
				(type default)
			)
			(layer "F.Fab")
		)
		(fp_line
			(start 0.120396 0.2794)
			(end -0.12065 0.2794)
			(stroke
				(width 0.1)
				(type default)
			)
			(layer "F.Fab")
		)
		(fp_line
			(start -0.12065 -0.2794)
			(end 0.12065 -0.2794)
			(stroke
				(width 0.1)
				(type default)
			)
			(layer "F.Fab")
		)
		(fp_line
			(start 0.12065 -0.2794)
			(end 0.12065 -0.3048)
			(stroke
				(width 0.1)
				(type default)
			)
			(layer "F.Fab")
		)
		(fp_line
			(start 0.12065 -0.3048)
			(end 0.67945 -0.3048)
			(stroke
				(width 0.1)
				(type default)
			)
			(layer "F.Fab")
		)
		(fp_line
			(start 0.67945 -0.3048)
			(end 0.67945 0.3048)
			(stroke
				(width 0.1)
				(type default)
			)
			(layer "F.Fab")
		)
		(fp_line
			(start -0.67945 -0.305054)
			(end -0.12065 -0.305054)
			(stroke
				(width 0.1)
				(type default)
			)
			(layer "F.Fab")
		)
		(fp_line
			(start -0.12065 -0.305054)
			(end -0.12065 -0.2794)
			(stroke
				(width 0.1)
				(type default)
			)
			(layer "F.Fab")
		)
		(pad "1" smd circle
			(at -0.40005 0 270)
			(size 0 0)
			(layers "F.Cu" "F.Mask" "F.Paste")
			(net "P3V3_AUX")
		)
		(pad "2" smd circle
			(at 0.40005 0 270)
			(size 0 0)
			(layers "F.Cu" "F.Mask" "F.Paste")
			(net "GND")
		)
	)
	(footprint ""
		(layer "F.Cu")
		(at 270.980662 -343.952322 90)
		(property "Reference" "C611"
			(at 0 0 90)
			(layer "F.SilkS")
			(hide yes)
			(effects
				(font
					(size 1.27 1.27)
				)
			)
		)
		(property "Value" ""
			(at 0 0 90)
			(layer "F.Fab")
			(effects
				(font
					(size 1.27 1.27)
				)
			)
		)
		(duplicate_pad_numbers_are_jumpers no)
		(fp_line
			(start 0.299974 -0.150114)
			(end 0.299974 0.150114)
			(stroke
				(width 0.1)
				(type default)
			)
			(layer "F.Fab")
		)
		(fp_line
			(start -0.299974 -0.150114)
			(end 0.299974 -0.150114)
			(stroke
				(width 0.1)
				(type default)
			)
			(layer "F.Fab")
		)
		(fp_line
			(start 0.299974 0.150114)
			(end -0.299974 0.150114)
			(stroke
				(width 0.1)
				(type default)
			)
			(layer "F.Fab")
		)
		(fp_line
			(start -0.299974 0.150114)
			(end -0.299974 -0.150114)
			(stroke
				(width 0.1)
				(type default)
			)
			(layer "F.Fab")
		)
		(pad "1" smd rect
			(at -0.2667 0 90)
			(size 0.3048 0.381)
			(layers "F.Cu" "F.Mask" "F.Paste")
			(net "P5E_PEX2_STN7_TX_DP<113>")
		)
		(pad "2" smd rect
			(at 0.2667 0 90)
			(size 0.3048 0.381)
			(layers "F.Cu" "F.Mask" "F.Paste")
			(net "P5E_PEX2_STN7_TX_C_DP<113>")
		)
	)
	(footprint ""
		(layer "F.Cu")
		(at 227.708714 -117.698012 90)
		(property "Reference" "PR6887"
			(at 0 0 90)
			(layer "F.SilkS")
			(hide yes)
			(effects
				(font
					(size 1.27 1.27)
				)
			)
		)
		(property "Value" ""
			(at 0 0 90)
			(layer "F.Fab")
			(effects
				(font
					(size 1.27 1.27)
				)
			)
		)
		(duplicate_pad_numbers_are_jumpers no)
		(fp_line
			(start 0.7874 -0.4064)
			(end 0.7874 0.4064)
			(stroke
				(width 0.1524)
				(type default)
			)
			(layer "F.SilkS")
		)
		(fp_line
			(start -0.7874 -0.4064)
			(end 0.7874 -0.4064)
			(stroke
				(width 0.1524)
				(type default)
			)
			(layer "F.SilkS")
		)
		(fp_line
			(start 0.7874 0.4064)
			(end -0.7874 0.4064)
			(stroke
				(width 0.1524)
				(type default)
			)
			(layer "F.SilkS")
		)
		(fp_line
			(start -0.7874 0.4064)
			(end -0.7874 -0.4064)
			(stroke
				(width 0.1524)
				(type default)
			)
			(layer "F.SilkS")
		)
		(fp_line
			(start -0.12065 -0.305054)
			(end -0.12065 -0.2794)
			(stroke
				(width 0.1)
				(type default)
			)
			(layer "F.Fab")
		)
		(fp_line
			(start -0.67945 -0.305054)
			(end -0.12065 -0.305054)
			(stroke
				(width 0.1)
				(type default)
			)
			(layer "F.Fab")
		)
		(fp_line
			(start 0.67945 -0.3048)
			(end 0.67945 0.3048)
			(stroke
				(width 0.1)
				(type default)
			)
			(layer "F.Fab")
		)
		(fp_line
			(start 0.12065 -0.3048)
			(end 0.67945 -0.3048)
			(stroke
				(width 0.1)
				(type default)
			)
			(layer "F.Fab")
		)
		(fp_line
			(start 0.12065 -0.2794)
			(end 0.12065 -0.3048)
			(stroke
				(width 0.1)
				(type default)
			)
			(layer "F.Fab")
		)
		(fp_line
			(start -0.12065 -0.2794)
			(end 0.12065 -0.2794)
			(stroke
				(width 0.1)
				(type default)
			)
			(layer "F.Fab")
		)
		(fp_line
			(start 0.120396 0.2794)
			(end -0.12065 0.2794)
			(stroke
				(width 0.1)
				(type default)
			)
			(layer "F.Fab")
		)
		(fp_line
			(start -0.12065 0.2794)
			(end -0.12065 0.3048)
			(stroke
				(width 0.1)
				(type default)
			)
			(layer "F.Fab")
		)
		(fp_line
			(start 0.67945 0.3048)
			(end 0.120396 0.3048)
			(stroke
				(width 0.1)
				(type default)
			)
			(layer "F.Fab")
		)
		(fp_line
			(start 0.120396 0.3048)
			(end 0.120396 0.2794)
			(stroke
				(width 0.1)
				(type default)
			)
			(layer "F.Fab")
		)
		(fp_line
			(start -0.12065 0.3048)
			(end -0.67945 0.3048)
			(stroke
				(width 0.1)
				(type default)
			)
			(layer "F.Fab")
		)
		(fp_line
			(start -0.67945 0.3048)
			(end -0.67945 -0.305054)
			(stroke
				(width 0.1)
				(type default)
			)
			(layer "F.Fab")
		)
		(pad "1" smd circle
			(at -0.40005 0 90)
			(size 0 0)
			(layers "F.Cu" "F.Mask" "F.Paste")
			(net "P12V_NIC3_R")
		)
		(pad "2" smd circle
			(at 0.40005 0 90)
			(size 0 0)
			(layers "F.Cu" "F.Mask" "F.Paste")
			(net "P12V_NIC3_CO_AVIN_PD")
		)
	)
	(footprint ""
		(layer "F.Cu")
		(at 461.600042 -398.100042)
		(property "Reference" "H75"
			(at -3.578606 -2.749042 0)
			(unlocked yes)
			(layer "F.SilkS")
			(effects
				(font
					(size 0.7874 0.5842)
					(thickness 0.1524)
				)
				(justify left)
			)
		)
		(property "Value" ""
			(at 0 0 0)
			(layer "F.Fab")
			(effects
				(font
					(size 1.27 1.27)
				)
			)
		)
		(duplicate_pad_numbers_are_jumpers no)
		(fp_circle
			(center 0 0)
			(end 2.6289 0)
			(stroke
				(width 0.1524)
				(type default)
			)
			(fill no)
			(layer "F.SilkS")
		)
		(fp_circle
			(center 0 0)
			(end 2.6289 0)
			(stroke
				(width 0.1524)
				(type default)
			)
			(fill no)
			(layer "B.SilkS")
		)
		(fp_circle
			(center 0 0)
			(end 2.6289 0)
			(stroke
				(width 0.1)
				(type default)
			)
			(fill no)
			(layer "B.Fab")
		)
		(fp_circle
			(center 0 0)
			(end 2.6289 0)
			(stroke
				(width 0.1)
				(type default)
			)
			(fill no)
			(layer "F.Fab")
		)
		(pad "" np_thru_hole circle
			(at 0 0)
			(size 3.0988 3.0988)
			(drill 3.0988)
			(layers "*.Cu" "*.Mask")
			(clearance 0.254)
			(thermal_gap 0.254)
		)
		(zone
			(layers "F.Cu" "B.Cu" "In1.Cu" "In2.Cu" "In3.Cu" "In4.Cu" "In5.Cu" "In6.Cu"
				"In7.Cu" "In8.Cu" "In9.Cu" "In10.Cu" "In11.Cu" "In12.Cu" "In13.Cu" "In14.Cu"
				"In15.Cu" "In16.Cu"
			)
			(hatch none 0.5)
			(connect_pads
				(clearance 0)
			)
			(min_thickness 0.25)
			(keepout
				(tracks not_allowed)
				(vias allowed)
				(pads allowed)
				(copperpour not_allowed)
				(footprints allowed)
			)
			(placement
				(enabled no)
				(sheetname "")
			)
			(fill
				(thermal_gap 0.5)
				(thermal_bridge_width 0.5)
				(island_removal_mode 0)
			)
			(polygon
				(pts
					(arc
						(start 463.657442 -398.100042)
						(mid 459.542642 -398.100042)
						(end 463.657442 -398.100042)
					)
				)
			)
		)
	)
	(footprint ""
		(layer "F.Cu")
		(at 371.802152 -254.850646 180)
		(property "Reference" "D4"
			(at 1.113282 -1.346454 0)
			(unlocked yes)
			(layer "F.SilkS")
			(effects
				(font
					(size 0.7874 0.5842)
					(thickness 0.1524)
				)
				(justify left)
			)
		)
		(property "Value" ""
			(at 0 0 180)
			(layer "F.Fab")
			(effects
				(font
					(size 1.27 1.27)
				)
			)
		)
		(duplicate_pad_numbers_are_jumpers no)
		(fp_line
			(start 1.16078 0.4826)
			(end -0.64008 0.4826)
			(stroke
				(width 0.1524)
				(type default)
			)
			(layer "F.SilkS")
		)
		(fp_line
			(start 1.16078 -0.4826)
			(end 1.16078 0.4826)
			(stroke
				(width 0.1524)
				(type default)
			)
			(layer "F.SilkS")
		)
		(fp_line
			(start 1.03378 0.4826)
			(end -0.79248 0.4826)
			(stroke
				(width 0.1524)
				(type default)
			)
			(layer "F.SilkS")
		)
		(fp_line
			(start 1.03378 -0.4826)
			(end 1.03378 0.4826)
			(stroke
				(width 0.1524)
				(type default)
			)
			(layer "F.SilkS")
		)
		(fp_line
			(start 0.90678 0.4826)
			(end -0.90678 0.4826)
			(stroke
				(width 0.1524)
				(type default)
			)
			(layer "F.SilkS")
		)
		(fp_line
			(start 0.90678 -0.4826)
			(end 0.90678 0.4826)
			(stroke
				(width 0.1524)
				(type default)
			)
			(layer "F.SilkS")
		)
		(fp_line
			(start -0.64008 -0.4826)
			(end 1.16078 -0.4826)
			(stroke
				(width 0.1524)
				(type default)
			)
			(layer "F.SilkS")
		)
		(fp_line
			(start -0.79248 -0.4826)
			(end 1.03378 -0.4826)
			(stroke
				(width 0.1524)
				(type default)
			)
			(layer "F.SilkS")
		)
		(fp_line
			(start -0.89408 -0.4826)
			(end 0.90678 -0.4826)
			(stroke
				(width 0.1524)
				(type default)
			)
			(layer "F.SilkS")
		)
		(fp_line
			(start -0.90678 0.4826)
			(end -0.90678 -0.4699)
			(stroke
				(width 0.1524)
				(type default)
			)
			(layer "F.SilkS")
		)
		(fp_line
			(start 0.499872 0.249936)
			(end -0.499872 0.249936)
			(stroke
				(width 0.1)
				(type default)
			)
			(layer "F.Fab")
		)
		(fp_line
			(start 0.499872 -0.249936)
			(end 0.499872 0.249936)
			(stroke
				(width 0.1)
				(type default)
			)
			(layer "F.Fab")
		)
		(fp_line
			(start -0.499872 0.249936)
			(end -0.499872 -0.249936)
			(stroke
				(width 0.1)
				(type default)
			)
			(layer "F.Fab")
		)
		(fp_line
			(start -0.499872 -0.249936)
			(end 0.499872 -0.249936)
			(stroke
				(width 0.1)
				(type default)
			)
			(layer "F.Fab")
		)
		(pad "A" smd rect
			(at -0.47498 0 180)
			(size 0.6096 0.7112)
			(layers "F.Cu" "F.Mask" "F.Paste")
			(net "LED_PEX3_SYS_ERR_N")
		)
		(pad "C" smd rect
			(at 0.47498 0 180)
			(size 0.6096 0.7112)
			(layers "F.Cu" "F.Mask" "F.Paste")
			(net "PEX3_SYS_ERR_3V3_N")
		)
	)
	(footprint ""
		(layer "F.Cu")
		(at 323.834252 -310.478932 -45)
		(property "Reference" "R3945"
			(at 0 0 315)
			(layer "F.SilkS")
			(hide yes)
			(effects
				(font
					(size 1.27 1.27)
				)
			)
		)
		(property "Value" ""
			(at 0 0 315)
			(layer "F.Fab")
			(effects
				(font
					(size 1.27 1.27)
				)
			)
		)
		(duplicate_pad_numbers_are_jumpers no)
		(fp_line
			(start -0.787389 0.406267)
			(end -0.787389 -0.406267)
			(stroke
				(width 0.1524)
				(type default)
			)
			(layer "F.SilkS")
		)
		(fp_line
			(start -0.787389 -0.406267)
			(end 0.787389 -0.406267)
			(stroke
				(width 0.1524)
				(type default)
			)
			(layer "F.SilkS")
		)
		(fp_line
			(start 0.787389 0.406267)
			(end -0.787389 0.406267)
			(stroke
				(width 0.1524)
				(type default)
			)
			(layer "F.SilkS")
		)
		(fp_line
			(start 0.787389 -0.406267)
			(end 0.787389 0.406267)
			(stroke
				(width 0.1524)
				(type default)
			)
			(layer "F.SilkS")
		)
		(fp_line
			(start -0.679446 0.30479)
			(end -0.679446 -0.305149)
			(stroke
				(width 0.1)
				(type default)
			)
			(layer "F.Fab")
		)
		(fp_line
			(start -0.120515 0.30479)
			(end -0.679446 0.30479)
			(stroke
				(width 0.1)
				(type default)
			)
			(layer "F.Fab")
		)
		(fp_line
			(start -0.120695 0.279466)
			(end -0.120515 0.30479)
			(stroke
				(width 0.1)
				(type default)
			)
			(layer "F.Fab")
		)
		(fp_line
			(start -0.679446 -0.305149)
			(end -0.120695 -0.304969)
			(stroke
				(width 0.1)
				(type default)
			)
			(layer "F.Fab")
		)
		(fp_line
			(start 0.120515 0.30479)
			(end 0.120335 0.279466)
			(stroke
				(width 0.1)
				(type default)
			)
			(layer "F.Fab")
		)
		(fp_line
			(start 0.120335 0.279466)
			(end -0.120695 0.279466)
			(stroke
				(width 0.1)
				(type default)
			)
			(layer "F.Fab")
		)
		(fp_line
			(start -0.120695 -0.279466)
			(end 0.120695 -0.279466)
			(stroke
				(width 0.1)
				(type default)
			)
			(layer "F.Fab")
		)
		(fp_line
			(start -0.120695 -0.304969)
			(end -0.120695 -0.279466)
			(stroke
				(width 0.1)
				(type default)
			)
			(layer "F.Fab")
		)
		(fp_line
			(start 0.679446 0.30479)
			(end 0.120515 0.30479)
			(stroke
				(width 0.1)
				(type default)
			)
			(layer "F.Fab")
		)
		(fp_line
			(start 0.120695 -0.279466)
			(end 0.120515 -0.30479)
			(stroke
				(width 0.1)
				(type default)
			)
			(layer "F.Fab")
		)
		(fp_line
			(start 0.120515 -0.30479)
			(end 0.679446 -0.30479)
			(stroke
				(width 0.1)
				(type default)
			)
			(layer "F.Fab")
		)
		(fp_line
			(start 0.679446 -0.30479)
			(end 0.679446 0.30479)
			(stroke
				(width 0.1)
				(type default)
			)
			(layer "F.Fab")
		)
		(pad "1" smd circle
			(at -0.40005 0 315)
			(size 0 0)
			(layers "F.Cu" "F.Mask" "F.Paste")
			(net "PU_PEX2_SIO_BLINK")
		)
		(pad "2" smd circle
			(at 0.40005 0 315)
			(size 0 0)
			(layers "F.Cu" "F.Mask" "F.Paste")
			(net "P1V8_PEX")
		)
	)
	(footprint ""
		(layer "F.Cu")
		(at 366.955578 -82.641694 180)
		(property "Reference" "R1618"
			(at 0 0 180)
			(layer "F.SilkS")
			(hide yes)
			(effects
				(font
					(size 1.27 1.27)
				)
			)
		)
		(property "Value" ""
			(at 0 0 180)
			(layer "F.Fab")
			(effects
				(font
					(size 1.27 1.27)
				)
			)
		)
		(duplicate_pad_numbers_are_jumpers no)
		(fp_line
			(start 0.7874 0.4064)
			(end -0.7874 0.4064)
			(stroke
				(width 0.1524)
				(type default)
			)
			(layer "F.SilkS")
		)
		(fp_line
			(start 0.7874 -0.4064)
			(end 0.7874 0.4064)
			(stroke
				(width 0.1524)
				(type default)
			)
			(layer "F.SilkS")
		)
		(fp_line
			(start -0.7874 0.4064)
			(end -0.7874 -0.4064)
			(stroke
				(width 0.1524)
				(type default)
			)
			(layer "F.SilkS")
		)
		(fp_line
			(start -0.7874 -0.4064)
			(end 0.7874 -0.4064)
			(stroke
				(width 0.1524)
				(type default)
			)
			(layer "F.SilkS")
		)
		(fp_line
			(start 0.67945 0.3048)
			(end 0.120396 0.3048)
			(stroke
				(width 0.1)
				(type default)
			)
			(layer "F.Fab")
		)
		(fp_line
			(start 0.67945 -0.3048)
			(end 0.67945 0.3048)
			(stroke
				(width 0.1)
				(type default)
			)
			(layer "F.Fab")
		)
		(fp_line
			(start 0.12065 -0.2794)
			(end 0.12065 -0.3048)
			(stroke
				(width 0.1)
				(type default)
			)
			(layer "F.Fab")
		)
		(fp_line
			(start 0.12065 -0.3048)
			(end 0.67945 -0.3048)
			(stroke
				(width 0.1)
				(type default)
			)
			(layer "F.Fab")
		)
		(fp_line
			(start 0.120396 0.3048)
			(end 0.120396 0.2794)
			(stroke
				(width 0.1)
				(type default)
			)
			(layer "F.Fab")
		)
		(fp_line
			(start 0.120396 0.2794)
			(end -0.12065 0.2794)
			(stroke
				(width 0.1)
				(type default)
			)
			(layer "F.Fab")
		)
		(fp_line
			(start -0.12065 0.3048)
			(end -0.67945 0.3048)
			(stroke
				(width 0.1)
				(type default)
			)
			(layer "F.Fab")
		)
		(fp_line
			(start -0.12065 0.2794)
			(end -0.12065 0.3048)
			(stroke
				(width 0.1)
				(type default)
			)
			(layer "F.Fab")
		)
		(fp_line
			(start -0.12065 -0.2794)
			(end 0.12065 -0.2794)
			(stroke
				(width 0.1)
				(type default)
			)
			(layer "F.Fab")
		)
		(fp_line
			(start -0.12065 -0.305054)
			(end -0.12065 -0.2794)
			(stroke
				(width 0.1)
				(type default)
			)
			(layer "F.Fab")
		)
		(fp_line
			(start -0.67945 0.3048)
			(end -0.67945 -0.305054)
			(stroke
				(width 0.1)
				(type default)
			)
			(layer "F.Fab")
		)
		(fp_line
			(start -0.67945 -0.305054)
			(end -0.12065 -0.305054)
			(stroke
				(width 0.1)
				(type default)
			)
			(layer "F.Fab")
		)
		(pad "1" smd circle
			(at -0.40005 0 180)
			(size 0 0)
			(layers "F.Cu" "F.Mask" "F.Paste")
			(net "SMB_BIC_I2C9_MUX1_SSD12_R_SCL")
		)
		(pad "2" smd circle
			(at 0.40005 0 180)
			(size 0 0)
			(layers "F.Cu" "F.Mask" "F.Paste")
			(net "SMB_BIC_I2C9_MUX1_SSD12_SCL")
		)
	)
	(footprint ""
		(layer "F.Cu")
		(at 240.03889 -211.266278 90)
		(property "Reference" "R480"
			(at 0 0 90)
			(layer "F.SilkS")
			(hide yes)
			(effects
				(font
					(size 1.27 1.27)
				)
			)
		)
		(property "Value" ""
			(at 0 0 90)
			(layer "F.Fab")
			(effects
				(font
					(size 1.27 1.27)
				)
			)
		)
		(duplicate_pad_numbers_are_jumpers no)
		(fp_line
			(start 0.7874 -0.4064)
			(end 0.7874 0.4064)
			(stroke
				(width 0.1524)
				(type default)
			)
			(layer "F.SilkS")
		)
		(fp_line
			(start -0.7874 -0.4064)
			(end 0.7874 -0.4064)
			(stroke
				(width 0.1524)
				(type default)
			)
			(layer "F.SilkS")
		)
		(fp_line
			(start 0.7874 0.4064)
			(end -0.7874 0.4064)
			(stroke
				(width 0.1524)
				(type default)
			)
			(layer "F.SilkS")
		)
		(fp_line
			(start -0.7874 0.4064)
			(end -0.7874 -0.4064)
			(stroke
				(width 0.1524)
				(type default)
			)
			(layer "F.SilkS")
		)
		(fp_line
			(start -0.12065 -0.305054)
			(end -0.12065 -0.2794)
			(stroke
				(width 0.1)
				(type default)
			)
			(layer "F.Fab")
		)
		(fp_line
			(start -0.67945 -0.305054)
			(end -0.12065 -0.305054)
			(stroke
				(width 0.1)
				(type default)
			)
			(layer "F.Fab")
		)
		(fp_line
			(start 0.67945 -0.3048)
			(end 0.67945 0.3048)
			(stroke
				(width 0.1)
				(type default)
			)
			(layer "F.Fab")
		)
		(fp_line
			(start 0.12065 -0.3048)
			(end 0.67945 -0.3048)
			(stroke
				(width 0.1)
				(type default)
			)
			(layer "F.Fab")
		)
		(fp_line
			(start 0.12065 -0.2794)
			(end 0.12065 -0.3048)
			(stroke
				(width 0.1)
				(type default)
			)
			(layer "F.Fab")
		)
		(fp_line
			(start -0.12065 -0.2794)
			(end 0.12065 -0.2794)
			(stroke
				(width 0.1)
				(type default)
			)
			(layer "F.Fab")
		)
		(fp_line
			(start 0.120396 0.2794)
			(end -0.12065 0.2794)
			(stroke
				(width 0.1)
				(type default)
			)
			(layer "F.Fab")
		)
		(fp_line
			(start -0.12065 0.2794)
			(end -0.12065 0.3048)
			(stroke
				(width 0.1)
				(type default)
			)
			(layer "F.Fab")
		)
		(fp_line
			(start 0.67945 0.3048)
			(end 0.120396 0.3048)
			(stroke
				(width 0.1)
				(type default)
			)
			(layer "F.Fab")
		)
		(fp_line
			(start 0.120396 0.3048)
			(end 0.120396 0.2794)
			(stroke
				(width 0.1)
				(type default)
			)
			(layer "F.Fab")
		)
		(fp_line
			(start -0.12065 0.3048)
			(end -0.67945 0.3048)
			(stroke
				(width 0.1)
				(type default)
			)
			(layer "F.Fab")
		)
		(fp_line
			(start -0.67945 0.3048)
			(end -0.67945 -0.305054)
			(stroke
				(width 0.1)
				(type default)
			)
			(layer "F.Fab")
		)
		(pad "1" smd circle
			(at -0.40005 0 90)
			(size 0 0)
			(layers "F.Cu" "F.Mask" "F.Paste")
			(net "P3V3_SCALED")
		)
		(pad "2" smd circle
			(at 0.40005 0 90)
			(size 0 0)
			(layers "F.Cu" "F.Mask" "F.Paste")
			(net "GND")
		)
	)
	(footprint ""
		(layer "F.Cu")
		(at 235.623608 -145.688812)
		(property "Reference" "R4223"
			(at 0 0 0)
			(layer "F.SilkS")
			(hide yes)
			(effects
				(font
					(size 1.27 1.27)
				)
			)
		)
		(property "Value" ""
			(at 0 0 0)
			(layer "F.Fab")
			(effects
				(font
					(size 1.27 1.27)
				)
			)
		)
		(duplicate_pad_numbers_are_jumpers no)
		(fp_line
			(start -0.7874 -0.4064)
			(end 0.7874 -0.4064)
			(stroke
				(width 0.1524)
				(type default)
			)
			(layer "F.SilkS")
		)
		(fp_line
			(start -0.7874 0.4064)
			(end -0.7874 -0.4064)
			(stroke
				(width 0.1524)
				(type default)
			)
			(layer "F.SilkS")
		)
		(fp_line
			(start 0.7874 -0.4064)
			(end 0.7874 0.4064)
			(stroke
				(width 0.1524)
				(type default)
			)
			(layer "F.SilkS")
		)
		(fp_line
			(start 0.7874 0.4064)
			(end -0.7874 0.4064)
			(stroke
				(width 0.1524)
				(type default)
			)
			(layer "F.SilkS")
		)
		(fp_line
			(start -0.67945 -0.305054)
			(end -0.12065 -0.305054)
			(stroke
				(width 0.1)
				(type default)
			)
			(layer "F.Fab")
		)
		(fp_line
			(start -0.67945 0.3048)
			(end -0.67945 -0.305054)
			(stroke
				(width 0.1)
				(type default)
			)
			(layer "F.Fab")
		)
		(fp_line
			(start -0.12065 -0.305054)
			(end -0.12065 -0.2794)
			(stroke
				(width 0.1)
				(type default)
			)
			(layer "F.Fab")
		)
		(fp_line
			(start -0.12065 -0.2794)
			(end 0.12065 -0.2794)
			(stroke
				(width 0.1)
				(type default)
			)
			(layer "F.Fab")
		)
		(fp_line
			(start -0.12065 0.2794)
			(end -0.12065 0.3048)
			(stroke
				(width 0.1)
				(type default)
			)
			(layer "F.Fab")
		)
		(fp_line
			(start -0.12065 0.3048)
			(end -0.67945 0.3048)
			(stroke
				(width 0.1)
				(type default)
			)
			(layer "F.Fab")
		)
		(fp_line
			(start 0.120396 0.2794)
			(end -0.12065 0.2794)
			(stroke
				(width 0.1)
				(type default)
			)
			(layer "F.Fab")
		)
		(fp_line
			(start 0.120396 0.3048)
			(end 0.120396 0.2794)
			(stroke
				(width 0.1)
				(type default)
			)
			(layer "F.Fab")
		)
		(fp_line
			(start 0.12065 -0.3048)
			(end 0.67945 -0.3048)
			(stroke
				(width 0.1)
				(type default)
			)
			(layer "F.Fab")
		)
		(fp_line
			(start 0.12065 -0.2794)
			(end 0.12065 -0.3048)
			(stroke
				(width 0.1)
				(type default)
			)
			(layer "F.Fab")
		)
		(fp_line
			(start 0.67945 -0.3048)
			(end 0.67945 0.3048)
			(stroke
				(width 0.1)
				(type default)
			)
			(layer "F.Fab")
		)
		(fp_line
			(start 0.67945 0.3048)
			(end 0.120396 0.3048)
			(stroke
				(width 0.1)
				(type default)
			)
			(layer "F.Fab")
		)
		(pad "1" smd circle
			(at -0.40005 0)
			(size 0 0)
			(layers "F.Cu" "F.Mask" "F.Paste")
			(net "CLK_GEN_CK440_PEX_OE6_N")
		)
		(pad "2" smd circle
			(at 0.40005 0)
			(size 0 0)
			(layers "F.Cu" "F.Mask" "F.Paste")
			(net "P3V3")
		)
	)
	(footprint ""
		(layer "F.Cu")
		(at 478.23247 -528.059142 180)
		(property "Reference" "SCREW_SSD2_1"
			(at -5.207 -1.402334 0)
			(unlocked yes)
			(layer "B.SilkS")
			(effects
				(font
					(size 0.7874 0.5842)
					(thickness 0.1524)
				)
				(justify mirror)
			)
		)
		(property "Value" ""
			(at 0 0 180)
			(layer "F.Fab")
			(effects
				(font
					(size 1.27 1.27)
				)
			)
		)
		(duplicate_pad_numbers_are_jumpers no)
		(pad "1" thru_hole circle
			(at 0 0 180)
			(size 0.4572 0.4572)
			(drill 0.2032)
			(layers "*.Cu" "*.Mask")
			(remove_unused_layers no)
			(net "Net_9140")
			(clearance 0.127)
			(thermal_gap 0.127)
			(padstack
				(mode front_inner_back)
				(layer "Inner"
					(shape circle)
					(size 0.4572 0.4572)
					(clearance 0.127)
				)
				(layer "B.Cu"
					(shape circle)
					(size 0.508 0.508)
					(clearance 0.1016)
				)
			)
		)
	)
	(footprint ""
		(layer "F.Cu")
		(at 252.488954 -207.097122 -90)
		(property "Reference" "R5642"
			(at 0 0 270)
			(layer "F.SilkS")
			(hide yes)
			(effects
				(font
					(size 1.27 1.27)
				)
			)
		)
		(property "Value" ""
			(at 0 0 270)
			(layer "F.Fab")
			(effects
				(font
					(size 1.27 1.27)
				)
			)
		)
		(duplicate_pad_numbers_are_jumpers no)
		(fp_line
			(start -0.7874 0.4064)
			(end -0.7874 -0.4064)
			(stroke
				(width 0.1524)
				(type default)
			)
			(layer "F.SilkS")
		)
		(fp_line
			(start 0.7874 0.4064)
			(end -0.7874 0.4064)
			(stroke
				(width 0.1524)
				(type default)
			)
			(layer "F.SilkS")
		)
		(fp_line
			(start -0.7874 -0.4064)
			(end 0.7874 -0.4064)
			(stroke
				(width 0.1524)
				(type default)
			)
			(layer "F.SilkS")
		)
		(fp_line
			(start 0.7874 -0.4064)
			(end 0.7874 0.4064)
			(stroke
				(width 0.1524)
				(type default)
			)
			(layer "F.SilkS")
		)
		(fp_line
			(start -0.67945 0.3048)
			(end -0.67945 -0.305054)
			(stroke
				(width 0.1)
				(type default)
			)
			(layer "F.Fab")
		)
		(fp_line
			(start -0.12065 0.3048)
			(end -0.67945 0.3048)
			(stroke
				(width 0.1)
				(type default)
			)
			(layer "F.Fab")
		)
		(fp_line
			(start 0.120396 0.3048)
			(end 0.120396 0.2794)
			(stroke
				(width 0.1)
				(type default)
			)
			(layer "F.Fab")
		)
		(fp_line
			(start 0.67945 0.3048)
			(end 0.120396 0.3048)
			(stroke
				(width 0.1)
				(type default)
			)
			(layer "F.Fab")
		)
		(fp_line
			(start -0.12065 0.2794)
			(end -0.12065 0.3048)
			(stroke
				(width 0.1)
				(type default)
			)
			(layer "F.Fab")
		)
		(fp_line
			(start 0.120396 0.2794)
			(end -0.12065 0.2794)
			(stroke
				(width 0.1)
				(type default)
			)
			(layer "F.Fab")
		)
		(fp_line
			(start -0.12065 -0.2794)
			(end 0.12065 -0.2794)
			(stroke
				(width 0.1)
				(type default)
			)
			(layer "F.Fab")
		)
		(fp_line
			(start 0.12065 -0.2794)
			(end 0.12065 -0.3048)
			(stroke
				(width 0.1)
				(type default)
			)
			(layer "F.Fab")
		)
		(fp_line
			(start 0.12065 -0.3048)
			(end 0.67945 -0.3048)
			(stroke
				(width 0.1)
				(type default)
			)
			(layer "F.Fab")
		)
		(fp_line
			(start 0.67945 -0.3048)
			(end 0.67945 0.3048)
			(stroke
				(width 0.1)
				(type default)
			)
			(layer "F.Fab")
		)
		(fp_line
			(start -0.67945 -0.305054)
			(end -0.12065 -0.305054)
			(stroke
				(width 0.1)
				(type default)
			)
			(layer "F.Fab")
		)
		(fp_line
			(start -0.12065 -0.305054)
			(end -0.12065 -0.2794)
			(stroke
				(width 0.1)
				(type default)
			)
			(layer "F.Fab")
		)
		(pad "1" smd circle
			(at -0.40005 0 270)
			(size 0 0)
			(layers "F.Cu" "F.Mask" "F.Paste")
			(net "JTAG_BIC_TDO_R")
		)
		(pad "2" smd circle
			(at 0.40005 0 270)
			(size 0 0)
			(layers "F.Cu" "F.Mask" "F.Paste")
			(net "JTAG_BIC_TDO")
		)
	)
	(footprint ""
		(layer "F.Cu")
		(at 198.815198 -59.546236 90)
		(property "Reference" "C2891"
			(at 0 0 90)
			(layer "F.SilkS")
			(hide yes)
			(effects
				(font
					(size 1.27 1.27)
				)
			)
		)
		(property "Value" ""
			(at 0 0 90)
			(layer "F.Fab")
			(effects
				(font
					(size 1.27 1.27)
				)
			)
		)
		(duplicate_pad_numbers_are_jumpers no)
		(fp_line
			(start 0.7874 -0.4064)
			(end 0.7874 0.4064)
			(stroke
				(width 0.1524)
				(type default)
			)
			(layer "F.SilkS")
		)
		(fp_line
			(start -0.7874 -0.4064)
			(end 0.7874 -0.4064)
			(stroke
				(width 0.1524)
				(type default)
			)
			(layer "F.SilkS")
		)
		(fp_line
			(start 0.7874 0.4064)
			(end -0.7874 0.4064)
			(stroke
				(width 0.1524)
				(type default)
			)
			(layer "F.SilkS")
		)
		(fp_line
			(start -0.7874 0.4064)
			(end -0.7874 -0.4064)
			(stroke
				(width 0.1524)
				(type default)
			)
			(layer "F.SilkS")
		)
		(fp_line
			(start -0.12065 -0.305054)
			(end -0.12065 -0.2794)
			(stroke
				(width 0.1)
				(type default)
			)
			(layer "F.Fab")
		)
		(fp_line
			(start -0.67945 -0.305054)
			(end -0.12065 -0.305054)
			(stroke
				(width 0.1)
				(type default)
			)
			(layer "F.Fab")
		)
		(fp_line
			(start 0.67945 -0.3048)
			(end 0.67945 0.3048)
			(stroke
				(width 0.1)
				(type default)
			)
			(layer "F.Fab")
		)
		(fp_line
			(start 0.12065 -0.3048)
			(end 0.67945 -0.3048)
			(stroke
				(width 0.1)
				(type default)
			)
			(layer "F.Fab")
		)
		(fp_line
			(start 0.12065 -0.2794)
			(end 0.12065 -0.3048)
			(stroke
				(width 0.1)
				(type default)
			)
			(layer "F.Fab")
		)
		(fp_line
			(start -0.12065 -0.2794)
			(end 0.12065 -0.2794)
			(stroke
				(width 0.1)
				(type default)
			)
			(layer "F.Fab")
		)
		(fp_line
			(start 0.120396 0.2794)
			(end -0.12065 0.2794)
			(stroke
				(width 0.1)
				(type default)
			)
			(layer "F.Fab")
		)
		(fp_line
			(start -0.12065 0.2794)
			(end -0.12065 0.3048)
			(stroke
				(width 0.1)
				(type default)
			)
			(layer "F.Fab")
		)
		(fp_line
			(start 0.67945 0.3048)
			(end 0.120396 0.3048)
			(stroke
				(width 0.1)
				(type default)
			)
			(layer "F.Fab")
		)
		(fp_line
			(start 0.120396 0.3048)
			(end 0.120396 0.2794)
			(stroke
				(width 0.1)
				(type default)
			)
			(layer "F.Fab")
		)
		(fp_line
			(start -0.12065 0.3048)
			(end -0.67945 0.3048)
			(stroke
				(width 0.1)
				(type default)
			)
			(layer "F.Fab")
		)
		(fp_line
			(start -0.67945 0.3048)
			(end -0.67945 -0.305054)
			(stroke
				(width 0.1)
				(type default)
			)
			(layer "F.Fab")
		)
		(pad "1" smd circle
			(at -0.40005 0 90)
			(size 0 0)
			(layers "F.Cu" "F.Mask" "F.Paste")
			(net "SSD7_AUX_P3V3_EN_R")
		)
		(pad "2" smd circle
			(at 0.40005 0 90)
			(size 0 0)
			(layers "F.Cu" "F.Mask" "F.Paste")
			(net "GND")
		)
	)
	(footprint ""
		(layer "F.Cu")
		(at 459.153768 8.175752 180)
		(property "Reference" "DE15T_1"
			(at 2.766568 3.145282 0)
			(unlocked yes)
			(layer "F.SilkS")
			(effects
				(font
					(size 0.7874 0.5842)
					(thickness 0.1524)
				)
				(justify left)
			)
		)
		(property "Value" ""
			(at 0 0 180)
			(layer "F.Fab")
			(effects
				(font
					(size 1.27 1.27)
				)
			)
		)
		(duplicate_pad_numbers_are_jumpers no)
		(fp_line
			(start 1.2192 2.1082)
			(end -1.2192 2.1082)
			(stroke
				(width 0.1524)
				(type default)
			)
			(layer "F.SilkS")
		)
		(fp_line
			(start 1.2192 -2.1082)
			(end 1.2192 2.1082)
			(stroke
				(width 0.1524)
				(type default)
			)
			(layer "F.SilkS")
		)
		(fp_line
			(start -1.2192 2.1082)
			(end -1.2192 -2.1082)
			(stroke
				(width 0.1524)
				(type default)
			)
			(layer "F.SilkS")
		)
		(fp_line
			(start -1.2192 -2.1082)
			(end 1.2192 -2.1082)
			(stroke
				(width 0.1524)
				(type default)
			)
			(layer "F.SilkS")
		)
		(pad "" np_thru_hole circle
			(at -2.8829 -1.27 90)
			(size 1.0414 1.0414)
			(drill 1.0414)
			(layers "*.Cu" "*.Mask")
			(clearance 0.381)
			(thermal_gap 0.381)
		)
		(pad "" np_thru_hole circle
			(at -2.8829 1.27 90)
			(size 1.0414 1.0414)
			(drill 1.0414)
			(layers "*.Cu" "*.Mask")
			(clearance 0.381)
			(thermal_gap 0.381)
		)
		(pad "" np_thru_hole circle
			(at 3.4671 -1.27 90)
			(size 1.0414 1.0414)
			(drill 1.0414)
			(layers "*.Cu" "*.Mask")
			(clearance 0.381)
			(thermal_gap 0.381)
		)
		(pad "" np_thru_hole circle
			(at 3.4671 1.27 90)
			(size 1.0414 1.0414)
			(drill 1.0414)
			(layers "*.Cu" "*.Mask")
			(clearance 0.381)
			(thermal_gap 0.381)
		)
		(pad "1" smd rect
			(at 0.8255 -0.249936 90)
			(size 0.3048 0.508)
			(layers "F.Cu" "F.Mask" "F.Paste")
			(net "85_10INCH_IN3_DP")
		)
		(pad "2" smd rect
			(at 0.8255 0.249936 90)
			(size 0.3048 0.508)
			(layers "F.Cu" "F.Mask" "F.Paste")
			(net "85_10INCH_IN3_DN")
		)
		(pad "3" smd circle
			(at 0 0 180)
			(size 0 0)
			(layers "F.Cu" "F.Mask" "F.Paste")
			(net "COUPON_GND2")
		)
		(zone
			(layer "F.Cu")
			(hatch none 0.5)
			(connect_pads
				(clearance 0)
			)
			(min_thickness 0.25)
			(keepout
				(tracks not_allowed)
				(vias allowed)
				(pads allowed)
				(copperpour not_allowed)
				(footprints allowed)
			)
			(placement
				(enabled no)
				(sheetname "")
			)
			(fill
				(thermal_gap 0.5)
				(thermal_bridge_width 0.5)
				(island_removal_mode 0)
			)
			(polygon
				(pts
					(xy 458.036168 8.724392) (xy 458.036168 8.628888) (xy 458.633068 8.628888) (xy 458.633068 8.222488)
					(xy 458.036168 8.222488) (xy 458.036168 8.129016) (xy 458.633068 8.129016) (xy 458.633068 7.722616)
					(xy 458.036168 7.722616) (xy 458.036168 7.627112) (xy 458.734668 7.627112) (xy 458.734668 8.724392)
				)
			)
		)
		(zone
			(layers "F.Cu" "B.Cu" "In1.Cu" "In2.Cu" "In3.Cu" "In4.Cu" "In5.Cu" "In6.Cu"
				"In7.Cu" "In8.Cu" "In9.Cu" "In10.Cu" "In11.Cu" "In12.Cu" "In13.Cu" "In14.Cu"
				"In15.Cu" "In16.Cu"
			)
			(hatch none 0.5)
			(connect_pads
				(clearance 0)
			)
			(min_thickness 0.25)
			(keepout
				(tracks not_allowed)
				(vias allowed)
				(pads allowed)
				(copperpour not_allowed)
				(footprints allowed)
			)
			(placement
				(enabled no)
				(sheetname "")
			)
			(fill
				(thermal_gap 0.5)
				(thermal_bridge_width 0.5)
				(island_removal_mode 0)
			)
			(polygon
				(pts
					(arc
						(start 456.613768 6.905752)
						(mid 454.759568 6.905752)
						(end 456.613768 6.905752)
					)
				)
			)
		)
		(zone
			(layers "F.Cu" "B.Cu" "In1.Cu" "In2.Cu" "In3.Cu" "In4.Cu" "In5.Cu" "In6.Cu"
				"In7.Cu" "In8.Cu" "In9.Cu" "In10.Cu" "In11.Cu" "In12.Cu" "In13.Cu" "In14.Cu"
				"In15.Cu" "In16.Cu"
			)
			(hatch none 0.5)
			(connect_pads
				(clearance 0)
			)
			(min_thickness 0.25)
			(keepout
				(tracks not_allowed)
				(vias allowed)
				(pads allowed)
				(copperpour not_allowed)
				(footprints allowed)
			)
			(placement
				(enabled no)
				(sheetname "")
			)
			(fill
				(thermal_gap 0.5)
				(thermal_bridge_width 0.5)
				(island_removal_mode 0)
			)
			(polygon
				(pts
					(arc
						(start 456.613768 9.445752)
						(mid 454.759568 9.445752)
						(end 456.613768 9.445752)
					)
				)
			)
		)
		(zone
			(layers "F.Cu" "B.Cu" "In1.Cu" "In2.Cu" "In3.Cu" "In4.Cu" "In5.Cu" "In6.Cu"
				"In7.Cu" "In8.Cu" "In9.Cu" "In10.Cu" "In11.Cu" "In12.Cu" "In13.Cu" "In14.Cu"
				"In15.Cu" "In16.Cu"
			)
			(hatch none 0.5)
			(connect_pads
				(clearance 0)
			)
			(min_thickness 0.25)
			(keepout
				(tracks not_allowed)
				(vias allowed)
				(pads allowed)
				(copperpour not_allowed)
				(footprints allowed)
			)
			(placement
				(enabled no)
				(sheetname "")
			)
			(fill
				(thermal_gap 0.5)
				(thermal_bridge_width 0.5)
				(island_removal_mode 0)
			)
			(polygon
				(pts
					(arc
						(start 462.963768 6.905752)
						(mid 461.109568 6.905752)
						(end 462.963768 6.905752)
					)
				)
			)
		)
		(zone
			(layers "F.Cu" "B.Cu" "In1.Cu" "In2.Cu" "In3.Cu" "In4.Cu" "In5.Cu" "In6.Cu"
				"In7.Cu" "In8.Cu" "In9.Cu" "In10.Cu" "In11.Cu" "In12.Cu" "In13.Cu" "In14.Cu"
				"In15.Cu" "In16.Cu"
			)
			(hatch none 0.5)
			(connect_pads
				(clearance 0)
			)
			(min_thickness 0.25)
			(keepout
				(tracks not_allowed)
				(vias allowed)
				(pads allowed)
				(copperpour not_allowed)
				(footprints allowed)
			)
			(placement
				(enabled no)
				(sheetname "")
			)
			(fill
				(thermal_gap 0.5)
				(thermal_bridge_width 0.5)
				(island_removal_mode 0)
			)
			(polygon
				(pts
					(arc
						(start 462.963768 9.445752)
						(mid 461.109568 9.445752)
						(end 462.963768 9.445752)
					)
				)
			)
		)
	)
	(footprint ""
		(layer "F.Cu")
		(at 380.711456 -280.443432 -90)
		(property "Reference" "R4596"
			(at 0 0 270)
			(layer "F.SilkS")
			(hide yes)
			(effects
				(font
					(size 1.27 1.27)
				)
			)
		)
		(property "Value" ""
			(at 0 0 270)
			(layer "F.Fab")
			(effects
				(font
					(size 1.27 1.27)
				)
			)
		)
		(duplicate_pad_numbers_are_jumpers no)
		(fp_line
			(start -0.7874 0.4064)
			(end -0.7874 -0.4064)
			(stroke
				(width 0.1524)
				(type default)
			)
			(layer "F.SilkS")
		)
		(fp_line
			(start 0.7874 0.4064)
			(end -0.7874 0.4064)
			(stroke
				(width 0.1524)
				(type default)
			)
			(layer "F.SilkS")
		)
		(fp_line
			(start -0.7874 -0.4064)
			(end 0.7874 -0.4064)
			(stroke
				(width 0.1524)
				(type default)
			)
			(layer "F.SilkS")
		)
		(fp_line
			(start 0.7874 -0.4064)
			(end 0.7874 0.4064)
			(stroke
				(width 0.1524)
				(type default)
			)
			(layer "F.SilkS")
		)
		(fp_line
			(start -0.67945 0.3048)
			(end -0.67945 -0.305054)
			(stroke
				(width 0.1)
				(type default)
			)
			(layer "F.Fab")
		)
		(fp_line
			(start -0.12065 0.3048)
			(end -0.67945 0.3048)
			(stroke
				(width 0.1)
				(type default)
			)
			(layer "F.Fab")
		)
		(fp_line
			(start 0.120396 0.3048)
			(end 0.120396 0.2794)
			(stroke
				(width 0.1)
				(type default)
			)
			(layer "F.Fab")
		)
		(fp_line
			(start 0.67945 0.3048)
			(end 0.120396 0.3048)
			(stroke
				(width 0.1)
				(type default)
			)
			(layer "F.Fab")
		)
		(fp_line
			(start -0.12065 0.2794)
			(end -0.12065 0.3048)
			(stroke
				(width 0.1)
				(type default)
			)
			(layer "F.Fab")
		)
		(fp_line
			(start 0.120396 0.2794)
			(end -0.12065 0.2794)
			(stroke
				(width 0.1)
				(type default)
			)
			(layer "F.Fab")
		)
		(fp_line
			(start -0.12065 -0.2794)
			(end 0.12065 -0.2794)
			(stroke
				(width 0.1)
				(type default)
			)
			(layer "F.Fab")
		)
		(fp_line
			(start 0.12065 -0.2794)
			(end 0.12065 -0.3048)
			(stroke
				(width 0.1)
				(type default)
			)
			(layer "F.Fab")
		)
		(fp_line
			(start 0.12065 -0.3048)
			(end 0.67945 -0.3048)
			(stroke
				(width 0.1)
				(type default)
			)
			(layer "F.Fab")
		)
		(fp_line
			(start 0.67945 -0.3048)
			(end 0.67945 0.3048)
			(stroke
				(width 0.1)
				(type default)
			)
			(layer "F.Fab")
		)
		(fp_line
			(start -0.67945 -0.305054)
			(end -0.12065 -0.305054)
			(stroke
				(width 0.1)
				(type default)
			)
			(layer "F.Fab")
		)
		(fp_line
			(start -0.12065 -0.305054)
			(end -0.12065 -0.2794)
			(stroke
				(width 0.1)
				(type default)
			)
			(layer "F.Fab")
		)
		(pad "1" smd circle
			(at -0.40005 0 270)
			(size 0 0)
			(layers "F.Cu" "F.Mask" "F.Paste")
			(net "SYSPLL_VDDA18_PEX3")
		)
		(pad "2" smd circle
			(at 0.40005 0 270)
			(size 0 0)
			(layers "F.Cu" "F.Mask" "F.Paste")
			(net "SYSPLL_VDDA18_PEX3_R")
		)
	)
	(footprint ""
		(layer "F.Cu")
		(at 361.506262 -134.434326)
		(property "Reference" "PC304"
			(at 0 0 0)
			(layer "F.SilkS")
			(hide yes)
			(effects
				(font
					(size 1.27 1.27)
				)
			)
		)
		(property "Value" ""
			(at 0 0 0)
			(layer "F.Fab")
			(effects
				(font
					(size 1.27 1.27)
				)
			)
		)
		(duplicate_pad_numbers_are_jumpers no)
		(fp_line
			(start -0.7874 -0.4064)
			(end 0.7874 -0.4064)
			(stroke
				(width 0.1524)
				(type default)
			)
			(layer "F.SilkS")
		)
		(fp_line
			(start -0.7874 0.4064)
			(end -0.7874 -0.4064)
			(stroke
				(width 0.1524)
				(type default)
			)
			(layer "F.SilkS")
		)
		(fp_line
			(start 0.7874 -0.4064)
			(end 0.7874 0.4064)
			(stroke
				(width 0.1524)
				(type default)
			)
			(layer "F.SilkS")
		)
		(fp_line
			(start 0.7874 0.4064)
			(end -0.7874 0.4064)
			(stroke
				(width 0.1524)
				(type default)
			)
			(layer "F.SilkS")
		)
		(fp_line
			(start -0.67945 -0.305054)
			(end -0.12065 -0.305054)
			(stroke
				(width 0.1)
				(type default)
			)
			(layer "F.Fab")
		)
		(fp_line
			(start -0.67945 0.3048)
			(end -0.67945 -0.305054)
			(stroke
				(width 0.1)
				(type default)
			)
			(layer "F.Fab")
		)
		(fp_line
			(start -0.12065 -0.305054)
			(end -0.12065 -0.2794)
			(stroke
				(width 0.1)
				(type default)
			)
			(layer "F.Fab")
		)
		(fp_line
			(start -0.12065 -0.2794)
			(end 0.12065 -0.2794)
			(stroke
				(width 0.1)
				(type default)
			)
			(layer "F.Fab")
		)
		(fp_line
			(start -0.12065 0.2794)
			(end -0.12065 0.3048)
			(stroke
				(width 0.1)
				(type default)
			)
			(layer "F.Fab")
		)
		(fp_line
			(start -0.12065 0.3048)
			(end -0.67945 0.3048)
			(stroke
				(width 0.1)
				(type default)
			)
			(layer "F.Fab")
		)
		(fp_line
			(start 0.120396 0.2794)
			(end -0.12065 0.2794)
			(stroke
				(width 0.1)
				(type default)
			)
			(layer "F.Fab")
		)
		(fp_line
			(start 0.120396 0.3048)
			(end 0.120396 0.2794)
			(stroke
				(width 0.1)
				(type default)
			)
			(layer "F.Fab")
		)
		(fp_line
			(start 0.12065 -0.3048)
			(end 0.67945 -0.3048)
			(stroke
				(width 0.1)
				(type default)
			)
			(layer "F.Fab")
		)
		(fp_line
			(start 0.12065 -0.2794)
			(end 0.12065 -0.3048)
			(stroke
				(width 0.1)
				(type default)
			)
			(layer "F.Fab")
		)
		(fp_line
			(start 0.67945 -0.3048)
			(end 0.67945 0.3048)
			(stroke
				(width 0.1)
				(type default)
			)
			(layer "F.Fab")
		)
		(fp_line
			(start 0.67945 0.3048)
			(end 0.120396 0.3048)
			(stroke
				(width 0.1)
				(type default)
			)
			(layer "F.Fab")
		)
		(pad "1" smd circle
			(at -0.40005 0)
			(size 0 0)
			(layers "F.Cu" "F.Mask" "F.Paste")
			(net "P12V_AUX")
		)
		(pad "2" smd circle
			(at 0.40005 0)
			(size 0 0)
			(layers "F.Cu" "F.Mask" "F.Paste")
			(net "GND")
		)
	)
	(footprint ""
		(layer "F.Cu")
		(at 56.034686 -367.627662 180)
		(property "Reference" "C3984"
			(at 0 0 180)
			(layer "F.SilkS")
			(hide yes)
			(effects
				(font
					(size 1.27 1.27)
				)
			)
		)
		(property "Value" ""
			(at 0 0 180)
			(layer "F.Fab")
			(effects
				(font
					(size 1.27 1.27)
				)
			)
		)
		(duplicate_pad_numbers_are_jumpers no)
		(fp_line
			(start 0.299974 0.150114)
			(end -0.299974 0.150114)
			(stroke
				(width 0.1)
				(type default)
			)
			(layer "F.Fab")
		)
		(fp_line
			(start 0.299974 -0.150114)
			(end 0.299974 0.150114)
			(stroke
				(width 0.1)
				(type default)
			)
			(layer "F.Fab")
		)
		(fp_line
			(start -0.299974 0.150114)
			(end -0.299974 -0.150114)
			(stroke
				(width 0.1)
				(type default)
			)
			(layer "F.Fab")
		)
		(fp_line
			(start -0.299974 -0.150114)
			(end 0.299974 -0.150114)
			(stroke
				(width 0.1)
				(type default)
			)
			(layer "F.Fab")
		)
		(pad "1" smd rect
			(at -0.2667 0 180)
			(size 0.3048 0.381)
			(layers "F.Cu" "F.Mask" "F.Paste")
			(net "P4E_PEX0_STN3_TX_DP<49>")
		)
		(pad "2" smd rect
			(at 0.2667 0 180)
			(size 0.3048 0.381)
			(layers "F.Cu" "F.Mask" "F.Paste")
			(net "P4E_PEX0_STN3_TX_C_DP<49>")
		)
	)
	(footprint ""
		(layer "F.Cu")
		(at 310.334406 -87.599012)
		(property "Reference" "U35"
			(at -1.267206 -1.706118 0)
			(unlocked yes)
			(layer "F.SilkS")
			(effects
				(font
					(size 0.7874 0.5842)
					(thickness 0.1524)
				)
				(justify left)
			)
		)
		(property "Value" ""
			(at 0 0 0)
			(layer "F.Fab")
			(effects
				(font
					(size 1.27 1.27)
				)
			)
		)
		(duplicate_pad_numbers_are_jumpers no)
		(fp_line
			(start -1.684274 -1.074928)
			(end -0.381 -1.074928)
			(stroke
				(width 0.1524)
				(type default)
			)
			(layer "F.SilkS")
		)
		(fp_line
			(start -1.684274 1.074928)
			(end -1.684274 -1.074928)
			(stroke
				(width 0.1524)
				(type default)
			)
			(layer "F.SilkS")
		)
		(fp_line
			(start -0.381 -1.074928)
			(end 0 -0.625094)
			(stroke
				(width 0.1524)
				(type default)
			)
			(layer "F.SilkS")
		)
		(fp_line
			(start 0 -0.625094)
			(end 0.381 -1.074928)
			(stroke
				(width 0.1524)
				(type default)
			)
			(layer "F.SilkS")
		)
		(fp_line
			(start 0.381 -1.074928)
			(end 1.684274 -1.074928)
			(stroke
				(width 0.1524)
				(type default)
			)
			(layer "F.SilkS")
		)
		(fp_line
			(start 1.684274 -1.074928)
			(end 1.684274 1.074928)
			(stroke
				(width 0.1524)
				(type default)
			)
			(layer "F.SilkS")
		)
		(fp_line
			(start 1.684274 1.074928)
			(end -1.684274 1.074928)
			(stroke
				(width 0.1524)
				(type default)
			)
			(layer "F.SilkS")
		)
		(fp_poly
			(pts
				(xy -2.637282 -0.903986) (xy -2.637282 -0.395986) (xy -1.875282 -0.649986)
			)
			(stroke
				(width 0)
				(type default)
			)
			(fill yes)
			(layer "F.SilkS")
		)
		(fp_line
			(start -0.700024 -1.074928)
			(end -0.700024 1.074928)
			(stroke
				(width 0.1)
				(type default)
			)
			(layer "F.Fab")
		)
		(fp_line
			(start -0.700024 1.074928)
			(end 0.700024 1.074928)
			(stroke
				(width 0.1)
				(type default)
			)
			(layer "F.Fab")
		)
		(fp_line
			(start 0.700024 -1.074928)
			(end -0.700024 -1.074928)
			(stroke
				(width 0.1)
				(type default)
			)
			(layer "F.Fab")
		)
		(fp_line
			(start 0.700024 1.074928)
			(end 0.700024 -1.074928)
			(stroke
				(width 0.1)
				(type default)
			)
			(layer "F.Fab")
		)
		(fp_poly
			(pts
				(xy -2.637282 -0.903986) (xy -2.637282 -0.395986) (xy -1.875282 -0.649986)
			)
			(stroke
				(width 0)
				(type default)
			)
			(fill yes)
			(layer "F.Fab")
		)
		(pad "1" smd rect
			(at -1.100074 -0.649986 270)
			(size 0.4064 0.9144)
			(layers "F.Cu" "F.Mask" "F.Paste")
			(net "Net_8451")
		)
		(pad "2" smd rect
			(at -1.100074 0 270)
			(size 0.4064 0.9144)
			(layers "F.Cu" "F.Mask" "F.Paste")
			(net "RST_HP_NIC5_N")
		)
		(pad "3" smd rect
			(at -1.100074 0.649986 270)
			(size 0.4064 0.9144)
			(layers "F.Cu" "F.Mask" "F.Paste")
			(net "GND")
		)
		(pad "4" smd rect
			(at 1.100074 0.649986 270)
			(size 0.4064 0.9144)
			(layers "F.Cu" "F.Mask" "F.Paste")
			(net "RST_HP_NIC5_BUF_N")
		)
		(pad "5" smd rect
			(at 1.100074 -0.649986 270)
			(size 0.4064 0.9144)
			(layers "F.Cu" "F.Mask" "F.Paste")
			(net "P3V3_AUX")
		)
	)
	(footprint ""
		(layer "F.Cu")
		(at 247.322848 -182.394606 90)
		(property "Reference" "R5504"
			(at 0 0 90)
			(layer "F.SilkS")
			(hide yes)
			(effects
				(font
					(size 1.27 1.27)
				)
			)
		)
		(property "Value" ""
			(at 0 0 90)
			(layer "F.Fab")
			(effects
				(font
					(size 1.27 1.27)
				)
			)
		)
		(duplicate_pad_numbers_are_jumpers no)
		(fp_line
			(start 0.7874 -0.4064)
			(end 0.7874 0.4064)
			(stroke
				(width 0.1524)
				(type default)
			)
			(layer "F.SilkS")
		)
		(fp_line
			(start -0.7874 -0.4064)
			(end 0.7874 -0.4064)
			(stroke
				(width 0.1524)
				(type default)
			)
			(layer "F.SilkS")
		)
		(fp_line
			(start 0.7874 0.4064)
			(end -0.7874 0.4064)
			(stroke
				(width 0.1524)
				(type default)
			)
			(layer "F.SilkS")
		)
		(fp_line
			(start -0.7874 0.4064)
			(end -0.7874 -0.4064)
			(stroke
				(width 0.1524)
				(type default)
			)
			(layer "F.SilkS")
		)
		(fp_line
			(start -0.12065 -0.305054)
			(end -0.12065 -0.2794)
			(stroke
				(width 0.1)
				(type default)
			)
			(layer "F.Fab")
		)
		(fp_line
			(start -0.67945 -0.305054)
			(end -0.12065 -0.305054)
			(stroke
				(width 0.1)
				(type default)
			)
			(layer "F.Fab")
		)
		(fp_line
			(start 0.67945 -0.3048)
			(end 0.67945 0.3048)
			(stroke
				(width 0.1)
				(type default)
			)
			(layer "F.Fab")
		)
		(fp_line
			(start 0.12065 -0.3048)
			(end 0.67945 -0.3048)
			(stroke
				(width 0.1)
				(type default)
			)
			(layer "F.Fab")
		)
		(fp_line
			(start 0.12065 -0.2794)
			(end 0.12065 -0.3048)
			(stroke
				(width 0.1)
				(type default)
			)
			(layer "F.Fab")
		)
		(fp_line
			(start -0.12065 -0.2794)
			(end 0.12065 -0.2794)
			(stroke
				(width 0.1)
				(type default)
			)
			(layer "F.Fab")
		)
		(fp_line
			(start 0.120396 0.2794)
			(end -0.12065 0.2794)
			(stroke
				(width 0.1)
				(type default)
			)
			(layer "F.Fab")
		)
		(fp_line
			(start -0.12065 0.2794)
			(end -0.12065 0.3048)
			(stroke
				(width 0.1)
				(type default)
			)
			(layer "F.Fab")
		)
		(fp_line
			(start 0.67945 0.3048)
			(end 0.120396 0.3048)
			(stroke
				(width 0.1)
				(type default)
			)
			(layer "F.Fab")
		)
		(fp_line
			(start 0.120396 0.3048)
			(end 0.120396 0.2794)
			(stroke
				(width 0.1)
				(type default)
			)
			(layer "F.Fab")
		)
		(fp_line
			(start -0.12065 0.3048)
			(end -0.67945 0.3048)
			(stroke
				(width 0.1)
				(type default)
			)
			(layer "F.Fab")
		)
		(fp_line
			(start -0.67945 0.3048)
			(end -0.67945 -0.305054)
			(stroke
				(width 0.1)
				(type default)
			)
			(layer "F.Fab")
		)
		(pad "1" smd circle
			(at -0.40005 0 90)
			(size 0 0)
			(layers "F.Cu" "F.Mask" "F.Paste")
			(net "BIC_FWSPICK_R")
		)
		(pad "2" smd circle
			(at 0.40005 0 90)
			(size 0 0)
			(layers "F.Cu" "F.Mask" "F.Paste")
			(net "P3V3_AUX")
		)
	)
	(footprint ""
		(layer "F.Cu")
		(at 428.837852 -343.952322 90)
		(property "Reference" "C809"
			(at 0 0 90)
			(layer "F.SilkS")
			(hide yes)
			(effects
				(font
					(size 1.27 1.27)
				)
			)
		)
		(property "Value" ""
			(at 0 0 90)
			(layer "F.Fab")
			(effects
				(font
					(size 1.27 1.27)
				)
			)
		)
		(duplicate_pad_numbers_are_jumpers no)
		(fp_line
			(start 0.299974 -0.150114)
			(end 0.299974 0.150114)
			(stroke
				(width 0.1)
				(type default)
			)
			(layer "F.Fab")
		)
		(fp_line
			(start -0.299974 -0.150114)
			(end 0.299974 -0.150114)
			(stroke
				(width 0.1)
				(type default)
			)
			(layer "F.Fab")
		)
		(fp_line
			(start 0.299974 0.150114)
			(end -0.299974 0.150114)
			(stroke
				(width 0.1)
				(type default)
			)
			(layer "F.Fab")
		)
		(fp_line
			(start -0.299974 0.150114)
			(end -0.299974 -0.150114)
			(stroke
				(width 0.1)
				(type default)
			)
			(layer "F.Fab")
		)
		(pad "1" smd rect
			(at -0.2667 0 90)
			(size 0.3048 0.381)
			(layers "F.Cu" "F.Mask" "F.Paste")
			(net "P5E_PEX3_STN7_TX_DN<120>")
		)
		(pad "2" smd rect
			(at 0.2667 0 90)
			(size 0.3048 0.381)
			(layers "F.Cu" "F.Mask" "F.Paste")
			(net "P5E_PEX3_STN7_TX_C_DN<120>")
		)
	)
	(footprint ""
		(layer "F.Cu")
		(at 428.83963 -159.235648 180)
		(property "Reference" "R399"
			(at 0 0 180)
			(layer "F.SilkS")
			(hide yes)
			(effects
				(font
					(size 1.27 1.27)
				)
			)
		)
		(property "Value" ""
			(at 0 0 180)
			(layer "F.Fab")
			(effects
				(font
					(size 1.27 1.27)
				)
			)
		)
		(duplicate_pad_numbers_are_jumpers no)
		(fp_line
			(start 0.7874 0.4064)
			(end -0.7874 0.4064)
			(stroke
				(width 0.1524)
				(type default)
			)
			(layer "F.SilkS")
		)
		(fp_line
			(start 0.7874 -0.4064)
			(end 0.7874 0.4064)
			(stroke
				(width 0.1524)
				(type default)
			)
			(layer "F.SilkS")
		)
		(fp_line
			(start -0.7874 0.4064)
			(end -0.7874 -0.4064)
			(stroke
				(width 0.1524)
				(type default)
			)
			(layer "F.SilkS")
		)
		(fp_line
			(start -0.7874 -0.4064)
			(end 0.7874 -0.4064)
			(stroke
				(width 0.1524)
				(type default)
			)
			(layer "F.SilkS")
		)
		(fp_line
			(start 0.67945 0.3048)
			(end 0.120396 0.3048)
			(stroke
				(width 0.1)
				(type default)
			)
			(layer "F.Fab")
		)
		(fp_line
			(start 0.67945 -0.3048)
			(end 0.67945 0.3048)
			(stroke
				(width 0.1)
				(type default)
			)
			(layer "F.Fab")
		)
		(fp_line
			(start 0.12065 -0.2794)
			(end 0.12065 -0.3048)
			(stroke
				(width 0.1)
				(type default)
			)
			(layer "F.Fab")
		)
		(fp_line
			(start 0.12065 -0.3048)
			(end 0.67945 -0.3048)
			(stroke
				(width 0.1)
				(type default)
			)
			(layer "F.Fab")
		)
		(fp_line
			(start 0.120396 0.3048)
			(end 0.120396 0.2794)
			(stroke
				(width 0.1)
				(type default)
			)
			(layer "F.Fab")
		)
		(fp_line
			(start 0.120396 0.2794)
			(end -0.12065 0.2794)
			(stroke
				(width 0.1)
				(type default)
			)
			(layer "F.Fab")
		)
		(fp_line
			(start -0.12065 0.3048)
			(end -0.67945 0.3048)
			(stroke
				(width 0.1)
				(type default)
			)
			(layer "F.Fab")
		)
		(fp_line
			(start -0.12065 0.2794)
			(end -0.12065 0.3048)
			(stroke
				(width 0.1)
				(type default)
			)
			(layer "F.Fab")
		)
		(fp_line
			(start -0.12065 -0.2794)
			(end 0.12065 -0.2794)
			(stroke
				(width 0.1)
				(type default)
			)
			(layer "F.Fab")
		)
		(fp_line
			(start -0.12065 -0.305054)
			(end -0.12065 -0.2794)
			(stroke
				(width 0.1)
				(type default)
			)
			(layer "F.Fab")
		)
		(fp_line
			(start -0.67945 0.3048)
			(end -0.67945 -0.305054)
			(stroke
				(width 0.1)
				(type default)
			)
			(layer "F.Fab")
		)
		(fp_line
			(start -0.67945 -0.305054)
			(end -0.12065 -0.305054)
			(stroke
				(width 0.1)
				(type default)
			)
			(layer "F.Fab")
		)
		(pad "1" smd circle
			(at -0.40005 0 180)
			(size 0 0)
			(layers "F.Cu" "F.Mask" "F.Paste")
			(net "PRSNT_NIC7_N")
		)
		(pad "2" smd circle
			(at 0.40005 0 180)
			(size 0 0)
			(layers "F.Cu" "F.Mask" "F.Paste")
			(net "PRSNTB3_NIC7_N")
		)
	)
	(footprint ""
		(layer "F.Cu")
		(at 363.959902 -397.42618 -90)
		(property "Reference" "R6703"
			(at 0 0 270)
			(layer "F.SilkS")
			(hide yes)
			(effects
				(font
					(size 1.27 1.27)
				)
			)
		)
		(property "Value" ""
			(at 0 0 270)
			(layer "F.Fab")
			(effects
				(font
					(size 1.27 1.27)
				)
			)
		)
		(duplicate_pad_numbers_are_jumpers no)
		(fp_line
			(start -0.7874 0.4064)
			(end -0.7874 -0.4064)
			(stroke
				(width 0.1524)
				(type default)
			)
			(layer "F.SilkS")
		)
		(fp_line
			(start 0.7874 0.4064)
			(end -0.7874 0.4064)
			(stroke
				(width 0.1524)
				(type default)
			)
			(layer "F.SilkS")
		)
		(fp_line
			(start -0.7874 -0.4064)
			(end 0.7874 -0.4064)
			(stroke
				(width 0.1524)
				(type default)
			)
			(layer "F.SilkS")
		)
		(fp_line
			(start 0.7874 -0.4064)
			(end 0.7874 0.4064)
			(stroke
				(width 0.1524)
				(type default)
			)
			(layer "F.SilkS")
		)
		(fp_line
			(start -0.67945 0.3048)
			(end -0.67945 -0.305054)
			(stroke
				(width 0.1)
				(type default)
			)
			(layer "F.Fab")
		)
		(fp_line
			(start -0.12065 0.3048)
			(end -0.67945 0.3048)
			(stroke
				(width 0.1)
				(type default)
			)
			(layer "F.Fab")
		)
		(fp_line
			(start 0.120396 0.3048)
			(end 0.120396 0.2794)
			(stroke
				(width 0.1)
				(type default)
			)
			(layer "F.Fab")
		)
		(fp_line
			(start 0.67945 0.3048)
			(end 0.120396 0.3048)
			(stroke
				(width 0.1)
				(type default)
			)
			(layer "F.Fab")
		)
		(fp_line
			(start -0.12065 0.2794)
			(end -0.12065 0.3048)
			(stroke
				(width 0.1)
				(type default)
			)
			(layer "F.Fab")
		)
		(fp_line
			(start 0.120396 0.2794)
			(end -0.12065 0.2794)
			(stroke
				(width 0.1)
				(type default)
			)
			(layer "F.Fab")
		)
		(fp_line
			(start -0.12065 -0.2794)
			(end 0.12065 -0.2794)
			(stroke
				(width 0.1)
				(type default)
			)
			(layer "F.Fab")
		)
		(fp_line
			(start 0.12065 -0.2794)
			(end 0.12065 -0.3048)
			(stroke
				(width 0.1)
				(type default)
			)
			(layer "F.Fab")
		)
		(fp_line
			(start 0.12065 -0.3048)
			(end 0.67945 -0.3048)
			(stroke
				(width 0.1)
				(type default)
			)
			(layer "F.Fab")
		)
		(fp_line
			(start 0.67945 -0.3048)
			(end 0.67945 0.3048)
			(stroke
				(width 0.1)
				(type default)
			)
			(layer "F.Fab")
		)
		(fp_line
			(start -0.67945 -0.305054)
			(end -0.12065 -0.305054)
			(stroke
				(width 0.1)
				(type default)
			)
			(layer "F.Fab")
		)
		(fp_line
			(start -0.12065 -0.305054)
			(end -0.12065 -0.2794)
			(stroke
				(width 0.1)
				(type default)
			)
			(layer "F.Fab")
		)
		(pad "1" smd circle
			(at -0.40005 0 270)
			(size 0 0)
			(layers "F.Cu" "F.Mask" "F.Paste")
			(net "P3V3_AUX")
		)
		(pad "2" smd circle
			(at 0.40005 0 270)
			(size 0 0)
			(layers "F.Cu" "F.Mask" "F.Paste")
			(net "MB_3V3IO_RSVD3")
		)
	)
	(footprint ""
		(layer "F.Cu")
		(at 450.683376 -49.94148)
		(property "Reference" "R5909"
			(at 0 0 0)
			(layer "F.SilkS")
			(hide yes)
			(effects
				(font
					(size 1.27 1.27)
				)
			)
		)
		(property "Value" ""
			(at 0 0 0)
			(layer "F.Fab")
			(effects
				(font
					(size 1.27 1.27)
				)
			)
		)
		(duplicate_pad_numbers_are_jumpers no)
		(fp_line
			(start -0.7874 -0.4064)
			(end 0.7874 -0.4064)
			(stroke
				(width 0.1524)
				(type default)
			)
			(layer "F.SilkS")
		)
		(fp_line
			(start -0.7874 0.4064)
			(end -0.7874 -0.4064)
			(stroke
				(width 0.1524)
				(type default)
			)
			(layer "F.SilkS")
		)
		(fp_line
			(start 0.7874 -0.4064)
			(end 0.7874 0.4064)
			(stroke
				(width 0.1524)
				(type default)
			)
			(layer "F.SilkS")
		)
		(fp_line
			(start 0.7874 0.4064)
			(end -0.7874 0.4064)
			(stroke
				(width 0.1524)
				(type default)
			)
			(layer "F.SilkS")
		)
		(fp_line
			(start -0.67945 -0.305054)
			(end -0.12065 -0.305054)
			(stroke
				(width 0.1)
				(type default)
			)
			(layer "F.Fab")
		)
		(fp_line
			(start -0.67945 0.3048)
			(end -0.67945 -0.305054)
			(stroke
				(width 0.1)
				(type default)
			)
			(layer "F.Fab")
		)
		(fp_line
			(start -0.12065 -0.305054)
			(end -0.12065 -0.2794)
			(stroke
				(width 0.1)
				(type default)
			)
			(layer "F.Fab")
		)
		(fp_line
			(start -0.12065 -0.2794)
			(end 0.12065 -0.2794)
			(stroke
				(width 0.1)
				(type default)
			)
			(layer "F.Fab")
		)
		(fp_line
			(start -0.12065 0.2794)
			(end -0.12065 0.3048)
			(stroke
				(width 0.1)
				(type default)
			)
			(layer "F.Fab")
		)
		(fp_line
			(start -0.12065 0.3048)
			(end -0.67945 0.3048)
			(stroke
				(width 0.1)
				(type default)
			)
			(layer "F.Fab")
		)
		(fp_line
			(start 0.120396 0.2794)
			(end -0.12065 0.2794)
			(stroke
				(width 0.1)
				(type default)
			)
			(layer "F.Fab")
		)
		(fp_line
			(start 0.120396 0.3048)
			(end 0.120396 0.2794)
			(stroke
				(width 0.1)
				(type default)
			)
			(layer "F.Fab")
		)
		(fp_line
			(start 0.12065 -0.3048)
			(end 0.67945 -0.3048)
			(stroke
				(width 0.1)
				(type default)
			)
			(layer "F.Fab")
		)
		(fp_line
			(start 0.12065 -0.2794)
			(end 0.12065 -0.3048)
			(stroke
				(width 0.1)
				(type default)
			)
			(layer "F.Fab")
		)
		(fp_line
			(start 0.67945 -0.3048)
			(end 0.67945 0.3048)
			(stroke
				(width 0.1)
				(type default)
			)
			(layer "F.Fab")
		)
		(fp_line
			(start 0.67945 0.3048)
			(end 0.120396 0.3048)
			(stroke
				(width 0.1)
				(type default)
			)
			(layer "F.Fab")
		)
		(pad "1" smd circle
			(at -0.40005 0)
			(size 0 0)
			(layers "F.Cu" "F.Mask" "F.Paste")
			(net "SSD15_ADC_A0")
		)
		(pad "2" smd circle
			(at 0.40005 0)
			(size 0 0)
			(layers "F.Cu" "F.Mask" "F.Paste")
			(net "SMB_SSD15_ADC_SCL")
		)
	)
	(footprint ""
		(layer "F.Cu")
		(at 396.261082 -37.951156)
		(property "Reference" "Q230"
			(at 1.91135 -1.884934 0)
			(unlocked yes)
			(layer "F.SilkS")
			(effects
				(font
					(size 0.7874 0.5842)
					(thickness 0.1524)
				)
			)
		)
		(property "Value" ""
			(at 0 0 0)
			(layer "F.Fab")
			(effects
				(font
					(size 1.27 1.27)
				)
			)
		)
		(duplicate_pad_numbers_are_jumpers no)
		(fp_line
			(start -1.376172 -1.199896)
			(end -0.508 -1.199896)
			(stroke
				(width 0.1524)
				(type default)
			)
			(layer "F.SilkS")
		)
		(fp_line
			(start -1.376172 1.199896)
			(end -1.376172 -1.199896)
			(stroke
				(width 0.1524)
				(type default)
			)
			(layer "F.SilkS")
		)
		(fp_line
			(start -0.508 -1.199896)
			(end 0 -0.762)
			(stroke
				(width 0.1524)
				(type default)
			)
			(layer "F.SilkS")
		)
		(fp_line
			(start 0 -0.762)
			(end 0.508 -1.199896)
			(stroke
				(width 0.1524)
				(type default)
			)
			(layer "F.SilkS")
		)
		(fp_line
			(start 0.508 -1.199896)
			(end 1.376172 -1.199896)
			(stroke
				(width 0.1524)
				(type default)
			)
			(layer "F.SilkS")
		)
		(fp_line
			(start 1.376172 -1.199896)
			(end 1.376172 1.199896)
			(stroke
				(width 0.1524)
				(type default)
			)
			(layer "F.SilkS")
		)
		(fp_line
			(start 1.376172 1.199896)
			(end -1.376172 1.199896)
			(stroke
				(width 0.1524)
				(type default)
			)
			(layer "F.SilkS")
		)
		(fp_poly
			(pts
				(xy -1.526794 -1.189736) (xy -1.796288 -1.997964) (xy -2.335022 -1.45923)
			)
			(stroke
				(width 0)
				(type default)
			)
			(fill yes)
			(layer "F.SilkS")
		)
		(fp_line
			(start -0.674878 -1.100074)
			(end 0.674878 -1.100074)
			(stroke
				(width 0.1)
				(type default)
			)
			(layer "F.Fab")
		)
		(fp_line
			(start -0.674878 1.100074)
			(end -0.674878 -1.100074)
			(stroke
				(width 0.1)
				(type default)
			)
			(layer "F.Fab")
		)
		(fp_line
			(start 0.674878 -1.100074)
			(end 0.674878 1.100074)
			(stroke
				(width 0.1)
				(type default)
			)
			(layer "F.Fab")
		)
		(fp_line
			(start 0.674878 1.100074)
			(end -0.674878 1.100074)
			(stroke
				(width 0.1)
				(type default)
			)
			(layer "F.Fab")
		)
		(fp_poly
			(pts
				(xy -1.4605 -0.7493) (xy -2.2225 -1.1303) (xy -2.2225 -0.3683)
			)
			(stroke
				(width 0)
				(type default)
			)
			(fill yes)
			(layer "F.Fab")
		)
		(pad "1" smd rect
			(at -0.899922 -0.750062 270)
			(size 0.6096 0.6096)
			(layers "F.Cu" "F.Mask" "F.Paste")
			(net "GND")
		)
		(pad "2" smd rect
			(at -0.899922 0 270)
			(size 0.4064 0.6096)
			(layers "F.Cu" "F.Mask" "F.Paste")
			(net "P3V3_SSD14_PG_G1")
		)
		(pad "3" smd rect
			(at -0.899922 0.750062 270)
			(size 0.6096 0.6096)
			(layers "F.Cu" "F.Mask" "F.Paste")
			(net "PWRGD_P3V3_SSD14_D")
		)
		(pad "4" smd rect
			(at 0.899922 0.750062 270)
			(size 0.6096 0.6096)
			(layers "F.Cu" "F.Mask" "F.Paste")
			(net "GND")
		)
		(pad "5" smd rect
			(at 0.899922 0 270)
			(size 0.4064 0.6096)
			(layers "F.Cu" "F.Mask" "F.Paste")
			(net "P3V3_SSD14_PG_G2")
		)
		(pad "6" smd rect
			(at 0.899922 -0.750062 270)
			(size 0.6096 0.6096)
			(layers "F.Cu" "F.Mask" "F.Paste")
			(net "P3V3_SSD14_PG_G2")
		)
	)
	(footprint ""
		(layer "F.Cu")
		(at 102.714552 -226.005644 180)
		(property "Reference" "PC289"
			(at 0 0 180)
			(layer "F.SilkS")
			(hide yes)
			(effects
				(font
					(size 1.27 1.27)
				)
			)
		)
		(property "Value" ""
			(at 0 0 180)
			(layer "F.Fab")
			(effects
				(font
					(size 1.27 1.27)
				)
			)
		)
		(duplicate_pad_numbers_are_jumpers no)
		(fp_line
			(start 0.7874 0.4064)
			(end -0.7874 0.4064)
			(stroke
				(width 0.1524)
				(type default)
			)
			(layer "F.SilkS")
		)
		(fp_line
			(start 0.7874 -0.4064)
			(end 0.7874 0.4064)
			(stroke
				(width 0.1524)
				(type default)
			)
			(layer "F.SilkS")
		)
		(fp_line
			(start -0.7874 0.4064)
			(end -0.7874 -0.4064)
			(stroke
				(width 0.1524)
				(type default)
			)
			(layer "F.SilkS")
		)
		(fp_line
			(start -0.7874 -0.4064)
			(end 0.7874 -0.4064)
			(stroke
				(width 0.1524)
				(type default)
			)
			(layer "F.SilkS")
		)
		(fp_line
			(start 0.67945 0.3048)
			(end 0.120396 0.3048)
			(stroke
				(width 0.1)
				(type default)
			)
			(layer "F.Fab")
		)
		(fp_line
			(start 0.67945 -0.3048)
			(end 0.67945 0.3048)
			(stroke
				(width 0.1)
				(type default)
			)
			(layer "F.Fab")
		)
		(fp_line
			(start 0.12065 -0.2794)
			(end 0.12065 -0.3048)
			(stroke
				(width 0.1)
				(type default)
			)
			(layer "F.Fab")
		)
		(fp_line
			(start 0.12065 -0.3048)
			(end 0.67945 -0.3048)
			(stroke
				(width 0.1)
				(type default)
			)
			(layer "F.Fab")
		)
		(fp_line
			(start 0.120396 0.3048)
			(end 0.120396 0.2794)
			(stroke
				(width 0.1)
				(type default)
			)
			(layer "F.Fab")
		)
		(fp_line
			(start 0.120396 0.2794)
			(end -0.12065 0.2794)
			(stroke
				(width 0.1)
				(type default)
			)
			(layer "F.Fab")
		)
		(fp_line
			(start -0.12065 0.3048)
			(end -0.67945 0.3048)
			(stroke
				(width 0.1)
				(type default)
			)
			(layer "F.Fab")
		)
		(fp_line
			(start -0.12065 0.2794)
			(end -0.12065 0.3048)
			(stroke
				(width 0.1)
				(type default)
			)
			(layer "F.Fab")
		)
		(fp_line
			(start -0.12065 -0.2794)
			(end 0.12065 -0.2794)
			(stroke
				(width 0.1)
				(type default)
			)
			(layer "F.Fab")
		)
		(fp_line
			(start -0.12065 -0.305054)
			(end -0.12065 -0.2794)
			(stroke
				(width 0.1)
				(type default)
			)
			(layer "F.Fab")
		)
		(fp_line
			(start -0.67945 0.3048)
			(end -0.67945 -0.305054)
			(stroke
				(width 0.1)
				(type default)
			)
			(layer "F.Fab")
		)
		(fp_line
			(start -0.67945 -0.305054)
			(end -0.12065 -0.305054)
			(stroke
				(width 0.1)
				(type default)
			)
			(layer "F.Fab")
		)
		(pad "1" smd circle
			(at -0.40005 0 180)
			(size 0 0)
			(layers "F.Cu" "F.Mask" "F.Paste")
			(net "SW_P1V8_PEX_BT")
		)
		(pad "2" smd circle
			(at 0.40005 0 180)
			(size 0 0)
			(layers "F.Cu" "F.Mask" "F.Paste")
			(net "SW_P1V8_PEX_PH")
		)
	)
	(footprint ""
		(layer "F.Cu")
		(at 239.515142 -20.72513)
		(property "Reference" "H124"
			(at 1.678686 -2.583942 0)
			(unlocked yes)
			(layer "B.SilkS")
			(effects
				(font
					(size 0.7874 0.5842)
					(thickness 0.1524)
				)
				(justify left mirror)
			)
		)
		(property "Value" ""
			(at 0 0 0)
			(layer "F.Fab")
			(effects
				(font
					(size 1.27 1.27)
				)
			)
		)
		(duplicate_pad_numbers_are_jumpers no)
		(pad "1" thru_hole rect
			(at 0 0)
			(size 4.2164 5.0038)
			(drill 2.0066
				(offset 0.099822 0)
			)
			(layers "*.Cu" "*.Mask")
			(remove_unused_layers no)
			(net "Net_8539")
			(clearance -0.8509)
			(padstack
				(mode front_inner_back)
				(layer "Inner"
					(shape circle)
					(size 4.0132 4.0132)
					(clearance -0.7493)
				)
				(layer "B.Cu"
					(shape circle)
					(size 4.0132 4.0132)
					(clearance -0.7493)
				)
			)
		)
	)
	(footprint ""
		(layer "F.Cu")
		(at 232.78211 -257.975862 -90)
		(property "Reference" "R6522"
			(at 0 0 270)
			(layer "F.SilkS")
			(hide yes)
			(effects
				(font
					(size 1.27 1.27)
				)
			)
		)
		(property "Value" ""
			(at 0 0 270)
			(layer "F.Fab")
			(effects
				(font
					(size 1.27 1.27)
				)
			)
		)
		(duplicate_pad_numbers_are_jumpers no)
		(fp_line
			(start -0.7874 0.4064)
			(end -0.7874 -0.4064)
			(stroke
				(width 0.1524)
				(type default)
			)
			(layer "F.SilkS")
		)
		(fp_line
			(start 0.7874 0.4064)
			(end -0.7874 0.4064)
			(stroke
				(width 0.1524)
				(type default)
			)
			(layer "F.SilkS")
		)
		(fp_line
			(start -0.7874 -0.4064)
			(end 0.7874 -0.4064)
			(stroke
				(width 0.1524)
				(type default)
			)
			(layer "F.SilkS")
		)
		(fp_line
			(start 0.7874 -0.4064)
			(end 0.7874 0.4064)
			(stroke
				(width 0.1524)
				(type default)
			)
			(layer "F.SilkS")
		)
		(fp_line
			(start -0.67945 0.3048)
			(end -0.67945 -0.305054)
			(stroke
				(width 0.1)
				(type default)
			)
			(layer "F.Fab")
		)
		(fp_line
			(start -0.12065 0.3048)
			(end -0.67945 0.3048)
			(stroke
				(width 0.1)
				(type default)
			)
			(layer "F.Fab")
		)
		(fp_line
			(start 0.120396 0.3048)
			(end 0.120396 0.2794)
			(stroke
				(width 0.1)
				(type default)
			)
			(layer "F.Fab")
		)
		(fp_line
			(start 0.67945 0.3048)
			(end 0.120396 0.3048)
			(stroke
				(width 0.1)
				(type default)
			)
			(layer "F.Fab")
		)
		(fp_line
			(start -0.12065 0.2794)
			(end -0.12065 0.3048)
			(stroke
				(width 0.1)
				(type default)
			)
			(layer "F.Fab")
		)
		(fp_line
			(start 0.120396 0.2794)
			(end -0.12065 0.2794)
			(stroke
				(width 0.1)
				(type default)
			)
			(layer "F.Fab")
		)
		(fp_line
			(start -0.12065 -0.2794)
			(end 0.12065 -0.2794)
			(stroke
				(width 0.1)
				(type default)
			)
			(layer "F.Fab")
		)
		(fp_line
			(start 0.12065 -0.2794)
			(end 0.12065 -0.3048)
			(stroke
				(width 0.1)
				(type default)
			)
			(layer "F.Fab")
		)
		(fp_line
			(start 0.12065 -0.3048)
			(end 0.67945 -0.3048)
			(stroke
				(width 0.1)
				(type default)
			)
			(layer "F.Fab")
		)
		(fp_line
			(start 0.67945 -0.3048)
			(end 0.67945 0.3048)
			(stroke
				(width 0.1)
				(type default)
			)
			(layer "F.Fab")
		)
		(fp_line
			(start -0.67945 -0.305054)
			(end -0.12065 -0.305054)
			(stroke
				(width 0.1)
				(type default)
			)
			(layer "F.Fab")
		)
		(fp_line
			(start -0.12065 -0.305054)
			(end -0.12065 -0.2794)
			(stroke
				(width 0.1)
				(type default)
			)
			(layer "F.Fab")
		)
		(pad "1" smd circle
			(at -0.40005 0 270)
			(size 0 0)
			(layers "F.Cu" "F.Mask" "F.Paste")
			(net "P1V25_SERDES_VDDPLL_PEX2")
		)
		(pad "2" smd circle
			(at 0.40005 0 270)
			(size 0 0)
			(layers "F.Cu" "F.Mask" "F.Paste")
			(net "P1V25_SERDES_VDDPLL_PEX2_C1")
		)
	)
	(footprint ""
		(layer "F.Cu")
		(at 259.130038 -294.005508 -90)
		(property "Reference" "C3411"
			(at 0 0 270)
			(layer "F.SilkS")
			(hide yes)
			(effects
				(font
					(size 1.27 1.27)
				)
			)
		)
		(property "Value" ""
			(at 0 0 270)
			(layer "F.Fab")
			(effects
				(font
					(size 1.27 1.27)
				)
			)
		)
		(duplicate_pad_numbers_are_jumpers no)
		(fp_line
			(start -1.2954 0.5842)
			(end -1.2954 -0.5842)
			(stroke
				(width 0.1524)
				(type default)
			)
			(layer "F.SilkS")
		)
		(fp_line
			(start 1.2954 0.5842)
			(end -1.2954 0.5842)
			(stroke
				(width 0.1524)
				(type default)
			)
			(layer "F.SilkS")
		)
		(fp_line
			(start -1.2954 -0.5842)
			(end 1.2954 -0.5842)
			(stroke
				(width 0.1524)
				(type default)
			)
			(layer "F.SilkS")
		)
		(fp_line
			(start 1.2954 -0.5842)
			(end 1.2954 0.5842)
			(stroke
				(width 0.1524)
				(type default)
			)
			(layer "F.SilkS")
		)
		(fp_line
			(start -0.8636 0.4572)
			(end -0.8636 0.4064)
			(stroke
				(width 0.1)
				(type default)
			)
			(layer "F.Fab")
		)
		(fp_line
			(start 0.8636 0.4572)
			(end -0.8636 0.4572)
			(stroke
				(width 0.1)
				(type default)
			)
			(layer "F.Fab")
		)
		(fp_line
			(start -1.1938 0.4064)
			(end -1.1938 -0.4064)
			(stroke
				(width 0.1)
				(type default)
			)
			(layer "F.Fab")
		)
		(fp_line
			(start -0.8636 0.4064)
			(end -1.1938 0.4064)
			(stroke
				(width 0.1)
				(type default)
			)
			(layer "F.Fab")
		)
		(fp_line
			(start 0.8636 0.4064)
			(end 0.8636 0.4572)
			(stroke
				(width 0.1)
				(type default)
			)
			(layer "F.Fab")
		)
		(fp_line
			(start 1.1938 0.4064)
			(end 0.8636 0.4064)
			(stroke
				(width 0.1)
				(type default)
			)
			(layer "F.Fab")
		)
		(fp_line
			(start -1.1938 -0.4064)
			(end -0.8636 -0.4064)
			(stroke
				(width 0.1)
				(type default)
			)
			(layer "F.Fab")
		)
		(fp_line
			(start -0.8636 -0.4064)
			(end -0.8636 -0.4572)
			(stroke
				(width 0.1)
				(type default)
			)
			(layer "F.Fab")
		)
		(fp_line
			(start 0.8636 -0.4064)
			(end 1.1938 -0.4064)
			(stroke
				(width 0.1)
				(type default)
			)
			(layer "F.Fab")
		)
		(fp_line
			(start 1.1938 -0.4064)
			(end 1.1938 0.4064)
			(stroke
				(width 0.1)
				(type default)
			)
			(layer "F.Fab")
		)
		(fp_line
			(start -0.8636 -0.4572)
			(end 0.8636 -0.4572)
			(stroke
				(width 0.1)
				(type default)
			)
			(layer "F.Fab")
		)
		(fp_line
			(start 0.8636 -0.4572)
			(end 0.8636 -0.4064)
			(stroke
				(width 0.1)
				(type default)
			)
			(layer "F.Fab")
		)
		(pad "1" smd rect
			(at -0.7366 0 180)
			(size 0.7112 0.8128)
			(layers "F.Cu" "F.Mask" "F.Paste")
			(net "P1V8_PLL0_PEX2")
		)
		(pad "2" smd rect
			(at 0.7366 0 180)
			(size 0.7112 0.8128)
			(layers "F.Cu" "F.Mask" "F.Paste")
			(net "GND")
		)
	)
	(footprint ""
		(layer "F.Cu")
		(at 54.495192 -35.48253)
		(property "Reference" "U385"
			(at -2.623312 1.741424 90)
			(unlocked yes)
			(layer "F.SilkS")
			(effects
				(font
					(size 0.7874 0.5842)
					(thickness 0.1524)
				)
				(justify left)
			)
		)
		(property "Value" ""
			(at 0 0 0)
			(layer "F.Fab")
			(effects
				(font
					(size 1.27 1.27)
				)
			)
		)
		(duplicate_pad_numbers_are_jumpers no)
		(fp_line
			(start -1.3462 -1.1938)
			(end -1.3462 1.1684)
			(stroke
				(width 0.1524)
				(type default)
			)
			(layer "F.SilkS")
		)
		(fp_line
			(start -1.3462 1.1938)
			(end 1.3462 1.1938)
			(stroke
				(width 0.1524)
				(type default)
			)
			(layer "F.SilkS")
		)
		(fp_line
			(start 1.3462 -1.1938)
			(end -1.3462 -1.1938)
			(stroke
				(width 0.1524)
				(type default)
			)
			(layer "F.SilkS")
		)
		(fp_line
			(start 1.3462 1.1938)
			(end 1.3462 -1.1938)
			(stroke
				(width 0.1524)
				(type default)
			)
			(layer "F.SilkS")
		)
		(fp_poly
			(pts
				(xy -1.447038 -0.760476) (xy -2.052066 -0.457962) (xy -2.052066 -1.06299)
			)
			(stroke
				(width 0)
				(type default)
			)
			(fill yes)
			(layer "F.SilkS")
		)
		(fp_line
			(start -0.674878 -1.124966)
			(end -0.674878 1.124966)
			(stroke
				(width 0.1)
				(type default)
			)
			(layer "F.Fab")
		)
		(fp_line
			(start -0.674878 1.124966)
			(end 0.674878 1.124966)
			(stroke
				(width 0.1)
				(type default)
			)
			(layer "F.Fab")
		)
		(fp_line
			(start 0.674878 -1.124966)
			(end -0.674878 -1.124966)
			(stroke
				(width 0.1)
				(type default)
			)
			(layer "F.Fab")
		)
		(fp_line
			(start 0.674878 1.124966)
			(end 0.674878 -1.124966)
			(stroke
				(width 0.1)
				(type default)
			)
			(layer "F.Fab")
		)
		(fp_poly
			(pts
				(xy -1.447038 -0.760476) (xy -2.052066 -0.457962) (xy -2.052066 -1.06299)
			)
			(stroke
				(width 0)
				(type default)
			)
			(fill yes)
			(layer "F.Fab")
		)
		(pad "1" smd rect
			(at -0.899922 -0.750062)
			(size 0.6096 0.6096)
			(layers "F.Cu" "F.Mask" "F.Paste")
			(net "PWRGD_P3V3_SSD2_R")
		)
		(pad "2" smd rect
			(at -0.899922 0 90)
			(size 0.4064 0.6096)
			(layers "F.Cu" "F.Mask" "F.Paste")
			(net "RST_SMB_SSD2_N")
		)
		(pad "3" smd rect
			(at -0.899922 0.750062)
			(size 0.6096 0.6096)
			(layers "F.Cu" "F.Mask" "F.Paste")
			(net "GND")
		)
		(pad "4" smd rect
			(at 0.899922 0.750062)
			(size 0.6096 0.6096)
			(layers "F.Cu" "F.Mask" "F.Paste")
			(net "RST_SMB_SSD2_ISO_N")
		)
		(pad "5" smd rect
			(at 0.899922 -0.750062)
			(size 0.6096 0.6096)
			(layers "F.Cu" "F.Mask" "F.Paste")
			(net "P3V3_AUX")
		)
	)
	(footprint ""
		(layer "F.Cu")
		(at 374.462294 -262.645652 90)
		(property "Reference" "C3594"
			(at 0 0 90)
			(layer "F.SilkS")
			(hide yes)
			(effects
				(font
					(size 1.27 1.27)
				)
			)
		)
		(property "Value" ""
			(at 0 0 90)
			(layer "F.Fab")
			(effects
				(font
					(size 1.27 1.27)
				)
			)
		)
		(duplicate_pad_numbers_are_jumpers no)
		(fp_line
			(start 0.299974 -0.150114)
			(end 0.299974 0.150114)
			(stroke
				(width 0.1)
				(type default)
			)
			(layer "F.Fab")
		)
		(fp_line
			(start -0.299974 -0.150114)
			(end 0.299974 -0.150114)
			(stroke
				(width 0.1)
				(type default)
			)
			(layer "F.Fab")
		)
		(fp_line
			(start 0.299974 0.150114)
			(end -0.299974 0.150114)
			(stroke
				(width 0.1)
				(type default)
			)
			(layer "F.Fab")
		)
		(fp_line
			(start -0.299974 0.150114)
			(end -0.299974 -0.150114)
			(stroke
				(width 0.1)
				(type default)
			)
			(layer "F.Fab")
		)
		(pad "1" smd rect
			(at -0.2667 0 90)
			(size 0.3048 0.381)
			(layers "F.Cu" "F.Mask" "F.Paste")
			(net "P1V8_VDDA_PEX3")
		)
		(pad "2" smd rect
			(at 0.2667 0 90)
			(size 0.3048 0.381)
			(layers "F.Cu" "F.Mask" "F.Paste")
			(net "GND")
		)
	)
	(footprint ""
		(layer "F.Cu")
		(at 381.009144 -26.03373)
		(property "Reference" "R4078"
			(at 0 0 0)
			(layer "F.SilkS")
			(hide yes)
			(effects
				(font
					(size 1.27 1.27)
				)
			)
		)
		(property "Value" ""
			(at 0 0 0)
			(layer "F.Fab")
			(effects
				(font
					(size 1.27 1.27)
				)
			)
		)
		(duplicate_pad_numbers_are_jumpers no)
		(fp_line
			(start -0.7874 -0.4064)
			(end 0.7874 -0.4064)
			(stroke
				(width 0.1524)
				(type default)
			)
			(layer "F.SilkS")
		)
		(fp_line
			(start -0.7874 0.4064)
			(end -0.7874 -0.4064)
			(stroke
				(width 0.1524)
				(type default)
			)
			(layer "F.SilkS")
		)
		(fp_line
			(start 0.7874 -0.4064)
			(end 0.7874 0.4064)
			(stroke
				(width 0.1524)
				(type default)
			)
			(layer "F.SilkS")
		)
		(fp_line
			(start 0.7874 0.4064)
			(end -0.7874 0.4064)
			(stroke
				(width 0.1524)
				(type default)
			)
			(layer "F.SilkS")
		)
		(fp_line
			(start -0.67945 -0.305054)
			(end -0.12065 -0.305054)
			(stroke
				(width 0.1)
				(type default)
			)
			(layer "F.Fab")
		)
		(fp_line
			(start -0.67945 0.3048)
			(end -0.67945 -0.305054)
			(stroke
				(width 0.1)
				(type default)
			)
			(layer "F.Fab")
		)
		(fp_line
			(start -0.12065 -0.305054)
			(end -0.12065 -0.2794)
			(stroke
				(width 0.1)
				(type default)
			)
			(layer "F.Fab")
		)
		(fp_line
			(start -0.12065 -0.2794)
			(end 0.12065 -0.2794)
			(stroke
				(width 0.1)
				(type default)
			)
			(layer "F.Fab")
		)
		(fp_line
			(start -0.12065 0.2794)
			(end -0.12065 0.3048)
			(stroke
				(width 0.1)
				(type default)
			)
			(layer "F.Fab")
		)
		(fp_line
			(start -0.12065 0.3048)
			(end -0.67945 0.3048)
			(stroke
				(width 0.1)
				(type default)
			)
			(layer "F.Fab")
		)
		(fp_line
			(start 0.120396 0.2794)
			(end -0.12065 0.2794)
			(stroke
				(width 0.1)
				(type default)
			)
			(layer "F.Fab")
		)
		(fp_line
			(start 0.120396 0.3048)
			(end 0.120396 0.2794)
			(stroke
				(width 0.1)
				(type default)
			)
			(layer "F.Fab")
		)
		(fp_line
			(start 0.12065 -0.3048)
			(end 0.67945 -0.3048)
			(stroke
				(width 0.1)
				(type default)
			)
			(layer "F.Fab")
		)
		(fp_line
			(start 0.12065 -0.2794)
			(end 0.12065 -0.3048)
			(stroke
				(width 0.1)
				(type default)
			)
			(layer "F.Fab")
		)
		(fp_line
			(start 0.67945 -0.3048)
			(end 0.67945 0.3048)
			(stroke
				(width 0.1)
				(type default)
			)
			(layer "F.Fab")
		)
		(fp_line
			(start 0.67945 0.3048)
			(end 0.120396 0.3048)
			(stroke
				(width 0.1)
				(type default)
			)
			(layer "F.Fab")
		)
		(pad "1" smd circle
			(at -0.40005 0)
			(size 0 0)
			(layers "F.Cu" "F.Mask" "F.Paste")
			(net "P3V3_AUX")
		)
		(pad "2" smd circle
			(at 0.40005 0)
			(size 0 0)
			(layers "F.Cu" "F.Mask" "F.Paste")
			(net "PRSNT_SSD13_R_N")
		)
	)
	(footprint ""
		(layer "F.Cu")
		(at 212.080602 -239.862868 90)
		(property "Reference" "U123"
			(at -1.395222 -2.96291 90)
			(unlocked yes)
			(layer "F.SilkS")
			(effects
				(font
					(size 0.7874 0.5842)
					(thickness 0.1524)
				)
				(justify left)
			)
		)
		(property "Value" ""
			(at 0 0 90)
			(layer "F.Fab")
			(effects
				(font
					(size 1.27 1.27)
				)
			)
		)
		(duplicate_pad_numbers_are_jumpers no)
		(fp_line
			(start 1.463548 -1.549908)
			(end 1.463548 1.549908)
			(stroke
				(width 0.1524)
				(type default)
			)
			(layer "F.SilkS")
		)
		(fp_line
			(start 0.762 -1.549908)
			(end 1.463548 -1.549908)
			(stroke
				(width 0.1524)
				(type default)
			)
			(layer "F.SilkS")
		)
		(fp_line
			(start -0.787908 -1.549908)
			(end 0 -0.762)
			(stroke
				(width 0.1524)
				(type default)
			)
			(layer "F.SilkS")
		)
		(fp_line
			(start -1.463548 -1.549908)
			(end -0.787908 -1.549908)
			(stroke
				(width 0.1524)
				(type default)
			)
			(layer "F.SilkS")
		)
		(fp_line
			(start 0 -0.762)
			(end 0.762 -1.549908)
			(stroke
				(width 0.1524)
				(type default)
			)
			(layer "F.SilkS")
		)
		(fp_line
			(start 1.463548 1.549908)
			(end -1.463548 1.549908)
			(stroke
				(width 0.1524)
				(type default)
			)
			(layer "F.SilkS")
		)
		(fp_line
			(start -1.463548 1.549908)
			(end -1.463548 -1.549908)
			(stroke
				(width 0.1524)
				(type default)
			)
			(layer "F.SilkS")
		)
		(fp_poly
			(pts
				(xy -2.227834 -2.2225) (xy -2.537714 -1.60274) (xy -2.847594 -2.2225)
			)
			(stroke
				(width 0)
				(type default)
			)
			(fill yes)
			(layer "F.SilkS")
		)
		(fp_line
			(start 1.549908 -1.549908)
			(end 1.549908 1.549908)
			(stroke
				(width 0.1)
				(type default)
			)
			(layer "F.Fab")
		)
		(fp_line
			(start -1.549908 -1.549908)
			(end 1.549908 -1.549908)
			(stroke
				(width 0.1)
				(type default)
			)
			(layer "F.Fab")
		)
		(fp_line
			(start 1.549908 1.549908)
			(end -1.549908 1.549908)
			(stroke
				(width 0.1)
				(type default)
			)
			(layer "F.Fab")
		)
		(fp_line
			(start -1.549908 1.549908)
			(end -1.549908 -1.549908)
			(stroke
				(width 0.1)
				(type default)
			)
			(layer "F.Fab")
		)
		(fp_poly
			(pts
				(xy -3.4798 -1.359916) (xy -2.86004 -1.050036) (xy -3.4798 -0.740156)
			)
			(stroke
				(width 0)
				(type default)
			)
			(fill yes)
			(layer "F.Fab")
		)
		(pad "1" smd rect
			(at -2.175002 -1.050036 180)
			(size 0.6096 1.1684)
			(layers "F.Cu" "F.Mask" "F.Paste")
			(net "P1V8_PEX")
		)
		(pad "2" smd rect
			(at -2.175002 -0.32512 180)
			(size 0.4318 1.1684)
			(layers "F.Cu" "F.Mask" "F.Paste")
			(net "SMB_PEX_LS_SCL")
		)
		(pad "3" smd rect
			(at -2.175002 0.32512 180)
			(size 0.4318 1.1684)
			(layers "F.Cu" "F.Mask" "F.Paste")
			(net "SMB_PEX_LS_SDA")
		)
		(pad "4" smd rect
			(at -2.175002 1.050036 180)
			(size 0.6096 1.1684)
			(layers "F.Cu" "F.Mask" "F.Paste")
			(net "GND")
		)
		(pad "5" smd rect
			(at 2.175002 1.050036 180)
			(size 0.6096 1.1684)
			(layers "F.Cu" "F.Mask" "F.Paste")
			(net "PWRGD_P1V8_PEX_R1")
		)
		(pad "6" smd rect
			(at 2.175002 0.32512 180)
			(size 0.4318 1.1684)
			(layers "F.Cu" "F.Mask" "F.Paste")
			(net "SMB_PEX_R_SDA")
		)
		(pad "7" smd rect
			(at 2.175002 -0.32512 180)
			(size 0.4318 1.1684)
			(layers "F.Cu" "F.Mask" "F.Paste")
			(net "SMB_PEX_R_SCL")
		)
		(pad "8" smd rect
			(at 2.175002 -1.050036 180)
			(size 0.6096 1.1684)
			(layers "F.Cu" "F.Mask" "F.Paste")
			(net "P3V3_AUX")
		)
	)
	(footprint ""
		(layer "F.Cu")
		(at 4.781804 -59.557158 90)
		(property "Reference" "C2885"
			(at 0 0 90)
			(layer "F.SilkS")
			(hide yes)
			(effects
				(font
					(size 1.27 1.27)
				)
			)
		)
		(property "Value" ""
			(at 0 0 90)
			(layer "F.Fab")
			(effects
				(font
					(size 1.27 1.27)
				)
			)
		)
		(duplicate_pad_numbers_are_jumpers no)
		(fp_line
			(start 0.7874 -0.4064)
			(end 0.7874 0.4064)
			(stroke
				(width 0.1524)
				(type default)
			)
			(layer "F.SilkS")
		)
		(fp_line
			(start -0.7874 -0.4064)
			(end 0.7874 -0.4064)
			(stroke
				(width 0.1524)
				(type default)
			)
			(layer "F.SilkS")
		)
		(fp_line
			(start 0.7874 0.4064)
			(end -0.7874 0.4064)
			(stroke
				(width 0.1524)
				(type default)
			)
			(layer "F.SilkS")
		)
		(fp_line
			(start -0.7874 0.4064)
			(end -0.7874 -0.4064)
			(stroke
				(width 0.1524)
				(type default)
			)
			(layer "F.SilkS")
		)
		(fp_line
			(start -0.12065 -0.305054)
			(end -0.12065 -0.2794)
			(stroke
				(width 0.1)
				(type default)
			)
			(layer "F.Fab")
		)
		(fp_line
			(start -0.67945 -0.305054)
			(end -0.12065 -0.305054)
			(stroke
				(width 0.1)
				(type default)
			)
			(layer "F.Fab")
		)
		(fp_line
			(start 0.67945 -0.3048)
			(end 0.67945 0.3048)
			(stroke
				(width 0.1)
				(type default)
			)
			(layer "F.Fab")
		)
		(fp_line
			(start 0.12065 -0.3048)
			(end 0.67945 -0.3048)
			(stroke
				(width 0.1)
				(type default)
			)
			(layer "F.Fab")
		)
		(fp_line
			(start 0.12065 -0.2794)
			(end 0.12065 -0.3048)
			(stroke
				(width 0.1)
				(type default)
			)
			(layer "F.Fab")
		)
		(fp_line
			(start -0.12065 -0.2794)
			(end 0.12065 -0.2794)
			(stroke
				(width 0.1)
				(type default)
			)
			(layer "F.Fab")
		)
		(fp_line
			(start 0.120396 0.2794)
			(end -0.12065 0.2794)
			(stroke
				(width 0.1)
				(type default)
			)
			(layer "F.Fab")
		)
		(fp_line
			(start -0.12065 0.2794)
			(end -0.12065 0.3048)
			(stroke
				(width 0.1)
				(type default)
			)
			(layer "F.Fab")
		)
		(fp_line
			(start 0.67945 0.3048)
			(end 0.120396 0.3048)
			(stroke
				(width 0.1)
				(type default)
			)
			(layer "F.Fab")
		)
		(fp_line
			(start 0.120396 0.3048)
			(end 0.120396 0.2794)
			(stroke
				(width 0.1)
				(type default)
			)
			(layer "F.Fab")
		)
		(fp_line
			(start -0.12065 0.3048)
			(end -0.67945 0.3048)
			(stroke
				(width 0.1)
				(type default)
			)
			(layer "F.Fab")
		)
		(fp_line
			(start -0.67945 0.3048)
			(end -0.67945 -0.305054)
			(stroke
				(width 0.1)
				(type default)
			)
			(layer "F.Fab")
		)
		(pad "1" smd circle
			(at -0.40005 0 90)
			(size 0 0)
			(layers "F.Cu" "F.Mask" "F.Paste")
			(net "SSD0_AUX_P3V3_EN_R")
		)
		(pad "2" smd circle
			(at 0.40005 0 90)
			(size 0 0)
			(layers "F.Cu" "F.Mask" "F.Paste")
			(net "GND")
		)
	)
	(footprint ""
		(layer "F.Cu")
		(at 219.202 -196.596)
		(property "Reference" "R1524"
			(at 0 0 0)
			(layer "F.SilkS")
			(hide yes)
			(effects
				(font
					(size 1.27 1.27)
				)
			)
		)
		(property "Value" ""
			(at 0 0 0)
			(layer "F.Fab")
			(effects
				(font
					(size 1.27 1.27)
				)
			)
		)
		(duplicate_pad_numbers_are_jumpers no)
		(fp_line
			(start -0.7874 -0.4064)
			(end 0.7874 -0.4064)
			(stroke
				(width 0.1524)
				(type default)
			)
			(layer "F.SilkS")
		)
		(fp_line
			(start -0.7874 0.4064)
			(end -0.7874 -0.4064)
			(stroke
				(width 0.1524)
				(type default)
			)
			(layer "F.SilkS")
		)
		(fp_line
			(start 0.7874 -0.4064)
			(end 0.7874 0.4064)
			(stroke
				(width 0.1524)
				(type default)
			)
			(layer "F.SilkS")
		)
		(fp_line
			(start 0.7874 0.4064)
			(end -0.7874 0.4064)
			(stroke
				(width 0.1524)
				(type default)
			)
			(layer "F.SilkS")
		)
		(fp_line
			(start -0.67945 -0.305054)
			(end -0.12065 -0.305054)
			(stroke
				(width 0.1)
				(type default)
			)
			(layer "F.Fab")
		)
		(fp_line
			(start -0.67945 0.3048)
			(end -0.67945 -0.305054)
			(stroke
				(width 0.1)
				(type default)
			)
			(layer "F.Fab")
		)
		(fp_line
			(start -0.12065 -0.305054)
			(end -0.12065 -0.2794)
			(stroke
				(width 0.1)
				(type default)
			)
			(layer "F.Fab")
		)
		(fp_line
			(start -0.12065 -0.2794)
			(end 0.12065 -0.2794)
			(stroke
				(width 0.1)
				(type default)
			)
			(layer "F.Fab")
		)
		(fp_line
			(start -0.12065 0.2794)
			(end -0.12065 0.3048)
			(stroke
				(width 0.1)
				(type default)
			)
			(layer "F.Fab")
		)
		(fp_line
			(start -0.12065 0.3048)
			(end -0.67945 0.3048)
			(stroke
				(width 0.1)
				(type default)
			)
			(layer "F.Fab")
		)
		(fp_line
			(start 0.120396 0.2794)
			(end -0.12065 0.2794)
			(stroke
				(width 0.1)
				(type default)
			)
			(layer "F.Fab")
		)
		(fp_line
			(start 0.120396 0.3048)
			(end 0.120396 0.2794)
			(stroke
				(width 0.1)
				(type default)
			)
			(layer "F.Fab")
		)
		(fp_line
			(start 0.12065 -0.3048)
			(end 0.67945 -0.3048)
			(stroke
				(width 0.1)
				(type default)
			)
			(layer "F.Fab")
		)
		(fp_line
			(start 0.12065 -0.2794)
			(end 0.12065 -0.3048)
			(stroke
				(width 0.1)
				(type default)
			)
			(layer "F.Fab")
		)
		(fp_line
			(start 0.67945 -0.3048)
			(end 0.67945 0.3048)
			(stroke
				(width 0.1)
				(type default)
			)
			(layer "F.Fab")
		)
		(fp_line
			(start 0.67945 0.3048)
			(end 0.120396 0.3048)
			(stroke
				(width 0.1)
				(type default)
			)
			(layer "F.Fab")
		)
		(pad "1" smd circle
			(at -0.40005 0)
			(size 0 0)
			(layers "F.Cu" "F.Mask" "F.Paste")
			(net "SMB_NIC6_LS_EN")
		)
		(pad "2" smd circle
			(at 0.40005 0)
			(size 0 0)
			(layers "F.Cu" "F.Mask" "F.Paste")
			(net "P3V3_NIC6")
		)
	)
	(footprint ""
		(layer "F.Cu")
		(at 134.01167 -146.263614 180)
		(property "Reference" "C416"
			(at 0 0 180)
			(layer "F.SilkS")
			(hide yes)
			(effects
				(font
					(size 1.27 1.27)
				)
			)
		)
		(property "Value" ""
			(at 0 0 180)
			(layer "F.Fab")
			(effects
				(font
					(size 1.27 1.27)
				)
			)
		)
		(duplicate_pad_numbers_are_jumpers no)
		(fp_line
			(start 0.7874 0.4064)
			(end -0.7874 0.4064)
			(stroke
				(width 0.1524)
				(type default)
			)
			(layer "F.SilkS")
		)
		(fp_line
			(start 0.7874 -0.4064)
			(end 0.7874 0.4064)
			(stroke
				(width 0.1524)
				(type default)
			)
			(layer "F.SilkS")
		)
		(fp_line
			(start -0.7874 0.4064)
			(end -0.7874 -0.4064)
			(stroke
				(width 0.1524)
				(type default)
			)
			(layer "F.SilkS")
		)
		(fp_line
			(start -0.7874 -0.4064)
			(end 0.7874 -0.4064)
			(stroke
				(width 0.1524)
				(type default)
			)
			(layer "F.SilkS")
		)
		(fp_line
			(start 0.67945 0.3048)
			(end 0.120396 0.3048)
			(stroke
				(width 0.1)
				(type default)
			)
			(layer "F.Fab")
		)
		(fp_line
			(start 0.67945 -0.3048)
			(end 0.67945 0.3048)
			(stroke
				(width 0.1)
				(type default)
			)
			(layer "F.Fab")
		)
		(fp_line
			(start 0.12065 -0.2794)
			(end 0.12065 -0.3048)
			(stroke
				(width 0.1)
				(type default)
			)
			(layer "F.Fab")
		)
		(fp_line
			(start 0.12065 -0.3048)
			(end 0.67945 -0.3048)
			(stroke
				(width 0.1)
				(type default)
			)
			(layer "F.Fab")
		)
		(fp_line
			(start 0.120396 0.3048)
			(end 0.120396 0.2794)
			(stroke
				(width 0.1)
				(type default)
			)
			(layer "F.Fab")
		)
		(fp_line
			(start 0.120396 0.2794)
			(end -0.12065 0.2794)
			(stroke
				(width 0.1)
				(type default)
			)
			(layer "F.Fab")
		)
		(fp_line
			(start -0.12065 0.3048)
			(end -0.67945 0.3048)
			(stroke
				(width 0.1)
				(type default)
			)
			(layer "F.Fab")
		)
		(fp_line
			(start -0.12065 0.2794)
			(end -0.12065 0.3048)
			(stroke
				(width 0.1)
				(type default)
			)
			(layer "F.Fab")
		)
		(fp_line
			(start -0.12065 -0.2794)
			(end 0.12065 -0.2794)
			(stroke
				(width 0.1)
				(type default)
			)
			(layer "F.Fab")
		)
		(fp_line
			(start -0.12065 -0.305054)
			(end -0.12065 -0.2794)
			(stroke
				(width 0.1)
				(type default)
			)
			(layer "F.Fab")
		)
		(fp_line
			(start -0.67945 0.3048)
			(end -0.67945 -0.305054)
			(stroke
				(width 0.1)
				(type default)
			)
			(layer "F.Fab")
		)
		(fp_line
			(start -0.67945 -0.305054)
			(end -0.12065 -0.305054)
			(stroke
				(width 0.1)
				(type default)
			)
			(layer "F.Fab")
		)
		(pad "1" smd circle
			(at -0.40005 0 180)
			(size 0 0)
			(layers "F.Cu" "F.Mask" "F.Paste")
			(net "P12V_NIC2_R")
		)
		(pad "2" smd circle
			(at 0.40005 0 180)
			(size 0 0)
			(layers "F.Cu" "F.Mask" "F.Paste")
			(net "GND")
		)
	)
	(footprint ""
		(layer "F.Cu")
		(at 120.194324 -303.649634 90)
		(property "Reference" "PC101"
			(at 0 0 90)
			(layer "F.SilkS")
			(hide yes)
			(effects
				(font
					(size 1.27 1.27)
				)
			)
		)
		(property "Value" ""
			(at 0 0 90)
			(layer "F.Fab")
			(effects
				(font
					(size 1.27 1.27)
				)
			)
		)
		(duplicate_pad_numbers_are_jumpers no)
		(fp_line
			(start 1.524 -0.762)
			(end 1.524 0.762)
			(stroke
				(width 0.1524)
				(type default)
			)
			(layer "F.SilkS")
		)
		(fp_line
			(start -1.524 -0.762)
			(end 1.524 -0.762)
			(stroke
				(width 0.1524)
				(type default)
			)
			(layer "F.SilkS")
		)
		(fp_line
			(start 1.524 0.762)
			(end -1.524 0.762)
			(stroke
				(width 0.1524)
				(type default)
			)
			(layer "F.SilkS")
		)
		(fp_line
			(start -1.524 0.762)
			(end -1.524 -0.762)
			(stroke
				(width 0.1524)
				(type default)
			)
			(layer "F.SilkS")
		)
		(fp_line
			(start 1.1049 -0.724916)
			(end -1.1049 -0.724916)
			(stroke
				(width 0.1)
				(type default)
			)
			(layer "F.Fab")
		)
		(fp_line
			(start -1.1049 -0.724916)
			(end -1.1049 0.724916)
			(stroke
				(width 0.1)
				(type default)
			)
			(layer "F.Fab")
		)
		(fp_line
			(start 1.1049 0.724916)
			(end 1.1049 -0.724916)
			(stroke
				(width 0.1)
				(type default)
			)
			(layer "F.Fab")
		)
		(fp_line
			(start -1.1049 0.724916)
			(end 1.1049 0.724916)
			(stroke
				(width 0.1)
				(type default)
			)
			(layer "F.Fab")
		)
		(pad "1" smd rect
			(at -0.889 0 270)
			(size 1.016 1.27)
			(layers "F.Cu" "F.Mask" "F.Paste")
			(net "P0V8_PEX1")
		)
		(pad "2" smd rect
			(at 0.889 0 270)
			(size 1.016 1.27)
			(layers "F.Cu" "F.Mask" "F.Paste")
			(net "GND")
		)
	)
	(footprint ""
		(layer "F.Cu")
		(at 55.9816 -158.8516)
		(property "Reference" "R47"
			(at 0 0 0)
			(layer "F.SilkS")
			(hide yes)
			(effects
				(font
					(size 1.27 1.27)
				)
			)
		)
		(property "Value" ""
			(at 0 0 0)
			(layer "F.Fab")
			(effects
				(font
					(size 1.27 1.27)
				)
			)
		)
		(duplicate_pad_numbers_are_jumpers no)
		(fp_line
			(start -0.7874 -0.4064)
			(end 0.7874 -0.4064)
			(stroke
				(width 0.1524)
				(type default)
			)
			(layer "F.SilkS")
		)
		(fp_line
			(start -0.7874 0.4064)
			(end -0.7874 -0.4064)
			(stroke
				(width 0.1524)
				(type default)
			)
			(layer "F.SilkS")
		)
		(fp_line
			(start 0.7874 -0.4064)
			(end 0.7874 0.4064)
			(stroke
				(width 0.1524)
				(type default)
			)
			(layer "F.SilkS")
		)
		(fp_line
			(start 0.7874 0.4064)
			(end -0.7874 0.4064)
			(stroke
				(width 0.1524)
				(type default)
			)
			(layer "F.SilkS")
		)
		(fp_line
			(start -0.67945 -0.305054)
			(end -0.12065 -0.305054)
			(stroke
				(width 0.1)
				(type default)
			)
			(layer "F.Fab")
		)
		(fp_line
			(start -0.67945 0.3048)
			(end -0.67945 -0.305054)
			(stroke
				(width 0.1)
				(type default)
			)
			(layer "F.Fab")
		)
		(fp_line
			(start -0.12065 -0.305054)
			(end -0.12065 -0.2794)
			(stroke
				(width 0.1)
				(type default)
			)
			(layer "F.Fab")
		)
		(fp_line
			(start -0.12065 -0.2794)
			(end 0.12065 -0.2794)
			(stroke
				(width 0.1)
				(type default)
			)
			(layer "F.Fab")
		)
		(fp_line
			(start -0.12065 0.2794)
			(end -0.12065 0.3048)
			(stroke
				(width 0.1)
				(type default)
			)
			(layer "F.Fab")
		)
		(fp_line
			(start -0.12065 0.3048)
			(end -0.67945 0.3048)
			(stroke
				(width 0.1)
				(type default)
			)
			(layer "F.Fab")
		)
		(fp_line
			(start 0.120396 0.2794)
			(end -0.12065 0.2794)
			(stroke
				(width 0.1)
				(type default)
			)
			(layer "F.Fab")
		)
		(fp_line
			(start 0.120396 0.3048)
			(end 0.120396 0.2794)
			(stroke
				(width 0.1)
				(type default)
			)
			(layer "F.Fab")
		)
		(fp_line
			(start 0.12065 -0.3048)
			(end 0.67945 -0.3048)
			(stroke
				(width 0.1)
				(type default)
			)
			(layer "F.Fab")
		)
		(fp_line
			(start 0.12065 -0.2794)
			(end 0.12065 -0.3048)
			(stroke
				(width 0.1)
				(type default)
			)
			(layer "F.Fab")
		)
		(fp_line
			(start 0.67945 -0.3048)
			(end 0.67945 0.3048)
			(stroke
				(width 0.1)
				(type default)
			)
			(layer "F.Fab")
		)
		(fp_line
			(start 0.67945 0.3048)
			(end 0.120396 0.3048)
			(stroke
				(width 0.1)
				(type default)
			)
			(layer "F.Fab")
		)
		(pad "1" smd circle
			(at -0.40005 0)
			(size 0 0)
			(layers "F.Cu" "F.Mask" "F.Paste")
			(net "RST_NIC0_PERST2_R_N")
		)
		(pad "2" smd circle
			(at 0.40005 0)
			(size 0 0)
			(layers "F.Cu" "F.Mask" "F.Paste")
			(net "RST_HP_NIC0_BUF_N")
		)
	)
	(footprint ""
		(layer "F.Cu")
		(at 312.21934 -134.394702 180)
		(property "Reference" "C441"
			(at 0 0 180)
			(layer "F.SilkS")
			(hide yes)
			(effects
				(font
					(size 1.27 1.27)
				)
			)
		)
		(property "Value" ""
			(at 0 0 180)
			(layer "F.Fab")
			(effects
				(font
					(size 1.27 1.27)
				)
			)
		)
		(duplicate_pad_numbers_are_jumpers no)
		(fp_line
			(start 0.299974 0.150114)
			(end -0.299974 0.150114)
			(stroke
				(width 0.1)
				(type default)
			)
			(layer "F.Fab")
		)
		(fp_line
			(start 0.299974 -0.150114)
			(end 0.299974 0.150114)
			(stroke
				(width 0.1)
				(type default)
			)
			(layer "F.Fab")
		)
		(fp_line
			(start -0.299974 0.150114)
			(end -0.299974 -0.150114)
			(stroke
				(width 0.1)
				(type default)
			)
			(layer "F.Fab")
		)
		(fp_line
			(start -0.299974 -0.150114)
			(end 0.299974 -0.150114)
			(stroke
				(width 0.1)
				(type default)
			)
			(layer "F.Fab")
		)
		(pad "1" smd rect
			(at -0.2667 0 180)
			(size 0.3048 0.381)
			(layers "F.Cu" "F.Mask" "F.Paste")
			(net "P5E_PEX2_STN0_TX_DP<6>")
		)
		(pad "2" smd rect
			(at 0.2667 0 180)
			(size 0.3048 0.381)
			(layers "F.Cu" "F.Mask" "F.Paste")
			(net "P5E_PEX2_STN0_TX_C_DP<6>")
		)
	)
	(footprint ""
		(layer "F.Cu")
		(at 1.599692 -24.934164 -90)
		(property "Reference" "R1632"
			(at 0 0 270)
			(layer "F.SilkS")
			(hide yes)
			(effects
				(font
					(size 1.27 1.27)
				)
			)
		)
		(property "Value" ""
			(at 0 0 270)
			(layer "F.Fab")
			(effects
				(font
					(size 1.27 1.27)
				)
			)
		)
		(duplicate_pad_numbers_are_jumpers no)
		(fp_line
			(start -0.7874 0.4064)
			(end -0.7874 -0.4064)
			(stroke
				(width 0.1524)
				(type default)
			)
			(layer "F.SilkS")
		)
		(fp_line
			(start 0.7874 0.4064)
			(end -0.7874 0.4064)
			(stroke
				(width 0.1524)
				(type default)
			)
			(layer "F.SilkS")
		)
		(fp_line
			(start -0.7874 -0.4064)
			(end 0.7874 -0.4064)
			(stroke
				(width 0.1524)
				(type default)
			)
			(layer "F.SilkS")
		)
		(fp_line
			(start 0.7874 -0.4064)
			(end 0.7874 0.4064)
			(stroke
				(width 0.1524)
				(type default)
			)
			(layer "F.SilkS")
		)
		(fp_line
			(start -0.67945 0.3048)
			(end -0.67945 -0.305054)
			(stroke
				(width 0.1)
				(type default)
			)
			(layer "F.Fab")
		)
		(fp_line
			(start -0.12065 0.3048)
			(end -0.67945 0.3048)
			(stroke
				(width 0.1)
				(type default)
			)
			(layer "F.Fab")
		)
		(fp_line
			(start 0.120396 0.3048)
			(end 0.120396 0.2794)
			(stroke
				(width 0.1)
				(type default)
			)
			(layer "F.Fab")
		)
		(fp_line
			(start 0.67945 0.3048)
			(end 0.120396 0.3048)
			(stroke
				(width 0.1)
				(type default)
			)
			(layer "F.Fab")
		)
		(fp_line
			(start -0.12065 0.2794)
			(end -0.12065 0.3048)
			(stroke
				(width 0.1)
				(type default)
			)
			(layer "F.Fab")
		)
		(fp_line
			(start 0.120396 0.2794)
			(end -0.12065 0.2794)
			(stroke
				(width 0.1)
				(type default)
			)
			(layer "F.Fab")
		)
		(fp_line
			(start -0.12065 -0.2794)
			(end 0.12065 -0.2794)
			(stroke
				(width 0.1)
				(type default)
			)
			(layer "F.Fab")
		)
		(fp_line
			(start 0.12065 -0.2794)
			(end 0.12065 -0.3048)
			(stroke
				(width 0.1)
				(type default)
			)
			(layer "F.Fab")
		)
		(fp_line
			(start 0.12065 -0.3048)
			(end 0.67945 -0.3048)
			(stroke
				(width 0.1)
				(type default)
			)
			(layer "F.Fab")
		)
		(fp_line
			(start 0.67945 -0.3048)
			(end 0.67945 0.3048)
			(stroke
				(width 0.1)
				(type default)
			)
			(layer "F.Fab")
		)
		(fp_line
			(start -0.67945 -0.305054)
			(end -0.12065 -0.305054)
			(stroke
				(width 0.1)
				(type default)
			)
			(layer "F.Fab")
		)
		(fp_line
			(start -0.12065 -0.305054)
			(end -0.12065 -0.2794)
			(stroke
				(width 0.1)
				(type default)
			)
			(layer "F.Fab")
		)
		(pad "1" smd circle
			(at -0.40005 0 270)
			(size 0 0)
			(layers "F.Cu" "F.Mask" "F.Paste")
			(net "P3V3_SSD0")
		)
		(pad "2" smd circle
			(at 0.40005 0 270)
			(size 0 0)
			(layers "F.Cu" "F.Mask" "F.Paste")
			(net "SMB_ISO_SSD0_SCL")
		)
	)
	(footprint ""
		(layer "F.Cu")
		(at 21.872956 -172.239178)
		(property "Reference" "PR57"
			(at 0 0 0)
			(layer "F.SilkS")
			(hide yes)
			(effects
				(font
					(size 1.27 1.27)
				)
			)
		)
		(property "Value" ""
			(at 0 0 0)
			(layer "F.Fab")
			(effects
				(font
					(size 1.27 1.27)
				)
			)
		)
		(duplicate_pad_numbers_are_jumpers no)
		(fp_line
			(start -0.7874 -0.4064)
			(end 0.7874 -0.4064)
			(stroke
				(width 0.1524)
				(type default)
			)
			(layer "F.SilkS")
		)
		(fp_line
			(start -0.7874 0.4064)
			(end -0.7874 -0.4064)
			(stroke
				(width 0.1524)
				(type default)
			)
			(layer "F.SilkS")
		)
		(fp_line
			(start 0.7874 -0.4064)
			(end 0.7874 0.4064)
			(stroke
				(width 0.1524)
				(type default)
			)
			(layer "F.SilkS")
		)
		(fp_line
			(start 0.7874 0.4064)
			(end -0.7874 0.4064)
			(stroke
				(width 0.1524)
				(type default)
			)
			(layer "F.SilkS")
		)
		(fp_line
			(start -0.67945 -0.305054)
			(end -0.12065 -0.305054)
			(stroke
				(width 0.1)
				(type default)
			)
			(layer "F.Fab")
		)
		(fp_line
			(start -0.67945 0.3048)
			(end -0.67945 -0.305054)
			(stroke
				(width 0.1)
				(type default)
			)
			(layer "F.Fab")
		)
		(fp_line
			(start -0.12065 -0.305054)
			(end -0.12065 -0.2794)
			(stroke
				(width 0.1)
				(type default)
			)
			(layer "F.Fab")
		)
		(fp_line
			(start -0.12065 -0.2794)
			(end 0.12065 -0.2794)
			(stroke
				(width 0.1)
				(type default)
			)
			(layer "F.Fab")
		)
		(fp_line
			(start -0.12065 0.2794)
			(end -0.12065 0.3048)
			(stroke
				(width 0.1)
				(type default)
			)
			(layer "F.Fab")
		)
		(fp_line
			(start -0.12065 0.3048)
			(end -0.67945 0.3048)
			(stroke
				(width 0.1)
				(type default)
			)
			(layer "F.Fab")
		)
		(fp_line
			(start 0.120396 0.2794)
			(end -0.12065 0.2794)
			(stroke
				(width 0.1)
				(type default)
			)
			(layer "F.Fab")
		)
		(fp_line
			(start 0.120396 0.3048)
			(end 0.120396 0.2794)
			(stroke
				(width 0.1)
				(type default)
			)
			(layer "F.Fab")
		)
		(fp_line
			(start 0.12065 -0.3048)
			(end 0.67945 -0.3048)
			(stroke
				(width 0.1)
				(type default)
			)
			(layer "F.Fab")
		)
		(fp_line
			(start 0.12065 -0.2794)
			(end 0.12065 -0.3048)
			(stroke
				(width 0.1)
				(type default)
			)
			(layer "F.Fab")
		)
		(fp_line
			(start 0.67945 -0.3048)
			(end 0.67945 0.3048)
			(stroke
				(width 0.1)
				(type default)
			)
			(layer "F.Fab")
		)
		(fp_line
			(start 0.67945 0.3048)
			(end 0.120396 0.3048)
			(stroke
				(width 0.1)
				(type default)
			)
			(layer "F.Fab")
		)
		(pad "1" smd circle
			(at -0.40005 0)
			(size 0 0)
			(layers "F.Cu" "F.Mask" "F.Paste")
			(net "P5V_AUX_FB")
		)
		(pad "2" smd circle
			(at 0.40005 0)
			(size 0 0)
			(layers "F.Cu" "F.Mask" "F.Paste")
			(net "SH_P5V_AUX_FB")
		)
	)
	(footprint ""
		(layer "F.Cu")
		(at 438.164732 -343.952322 90)
		(property "Reference" "C2466"
			(at 0 0 90)
			(layer "F.SilkS")
			(hide yes)
			(effects
				(font
					(size 1.27 1.27)
				)
			)
		)
		(property "Value" ""
			(at 0 0 90)
			(layer "F.Fab")
			(effects
				(font
					(size 1.27 1.27)
				)
			)
		)
		(duplicate_pad_numbers_are_jumpers no)
		(fp_line
			(start 0.299974 -0.150114)
			(end 0.299974 0.150114)
			(stroke
				(width 0.1)
				(type default)
			)
			(layer "F.Fab")
		)
		(fp_line
			(start -0.299974 -0.150114)
			(end 0.299974 -0.150114)
			(stroke
				(width 0.1)
				(type default)
			)
			(layer "F.Fab")
		)
		(fp_line
			(start 0.299974 0.150114)
			(end -0.299974 0.150114)
			(stroke
				(width 0.1)
				(type default)
			)
			(layer "F.Fab")
		)
		(fp_line
			(start -0.299974 0.150114)
			(end -0.299974 -0.150114)
			(stroke
				(width 0.1)
				(type default)
			)
			(layer "F.Fab")
		)
		(pad "1" smd rect
			(at -0.2667 0 90)
			(size 0.3048 0.381)
			(layers "F.Cu" "F.Mask" "F.Paste")
			(net "P5E_PEX3_STN4_TX_DN<66>")
		)
		(pad "2" smd rect
			(at 0.2667 0 90)
			(size 0.3048 0.381)
			(layers "F.Cu" "F.Mask" "F.Paste")
			(net "P5E_PEX3_STN4_TX_C_DN<66>")
		)
	)
	(footprint ""
		(layer "F.Cu")
		(at 347.091 -234.061 -90)
		(property "Reference" "R3568"
			(at 0 0 270)
			(layer "F.SilkS")
			(hide yes)
			(effects
				(font
					(size 1.27 1.27)
				)
			)
		)
		(property "Value" ""
			(at 0 0 270)
			(layer "F.Fab")
			(effects
				(font
					(size 1.27 1.27)
				)
			)
		)
		(duplicate_pad_numbers_are_jumpers no)
		(fp_line
			(start -0.7874 0.4064)
			(end -0.7874 -0.4064)
			(stroke
				(width 0.1524)
				(type default)
			)
			(layer "F.SilkS")
		)
		(fp_line
			(start 0.7874 0.4064)
			(end -0.7874 0.4064)
			(stroke
				(width 0.1524)
				(type default)
			)
			(layer "F.SilkS")
		)
		(fp_line
			(start -0.7874 -0.4064)
			(end 0.7874 -0.4064)
			(stroke
				(width 0.1524)
				(type default)
			)
			(layer "F.SilkS")
		)
		(fp_line
			(start 0.7874 -0.4064)
			(end 0.7874 0.4064)
			(stroke
				(width 0.1524)
				(type default)
			)
			(layer "F.SilkS")
		)
		(fp_line
			(start -0.67945 0.3048)
			(end -0.67945 -0.305054)
			(stroke
				(width 0.1)
				(type default)
			)
			(layer "F.Fab")
		)
		(fp_line
			(start -0.12065 0.3048)
			(end -0.67945 0.3048)
			(stroke
				(width 0.1)
				(type default)
			)
			(layer "F.Fab")
		)
		(fp_line
			(start 0.120396 0.3048)
			(end 0.120396 0.2794)
			(stroke
				(width 0.1)
				(type default)
			)
			(layer "F.Fab")
		)
		(fp_line
			(start 0.67945 0.3048)
			(end 0.120396 0.3048)
			(stroke
				(width 0.1)
				(type default)
			)
			(layer "F.Fab")
		)
		(fp_line
			(start -0.12065 0.2794)
			(end -0.12065 0.3048)
			(stroke
				(width 0.1)
				(type default)
			)
			(layer "F.Fab")
		)
		(fp_line
			(start 0.120396 0.2794)
			(end -0.12065 0.2794)
			(stroke
				(width 0.1)
				(type default)
			)
			(layer "F.Fab")
		)
		(fp_line
			(start -0.12065 -0.2794)
			(end 0.12065 -0.2794)
			(stroke
				(width 0.1)
				(type default)
			)
			(layer "F.Fab")
		)
		(fp_line
			(start 0.12065 -0.2794)
			(end 0.12065 -0.3048)
			(stroke
				(width 0.1)
				(type default)
			)
			(layer "F.Fab")
		)
		(fp_line
			(start 0.12065 -0.3048)
			(end 0.67945 -0.3048)
			(stroke
				(width 0.1)
				(type default)
			)
			(layer "F.Fab")
		)
		(fp_line
			(start 0.67945 -0.3048)
			(end 0.67945 0.3048)
			(stroke
				(width 0.1)
				(type default)
			)
			(layer "F.Fab")
		)
		(fp_line
			(start -0.67945 -0.305054)
			(end -0.12065 -0.305054)
			(stroke
				(width 0.1)
				(type default)
			)
			(layer "F.Fab")
		)
		(fp_line
			(start -0.12065 -0.305054)
			(end -0.12065 -0.2794)
			(stroke
				(width 0.1)
				(type default)
			)
			(layer "F.Fab")
		)
		(pad "1" smd circle
			(at -0.40005 0 270)
			(size 0 0)
			(layers "F.Cu" "F.Mask" "F.Paste")
			(net "RST_SSD5_PERST_R_N")
		)
		(pad "2" smd circle
			(at 0.40005 0 270)
			(size 0 0)
			(layers "F.Cu" "F.Mask" "F.Paste")
			(net "RST_SSD5_PERST_N")
		)
	)
	(footprint ""
		(layer "F.Cu")
		(at 183.242712 -70.844918 -90)
		(property "Reference" "PD106"
			(at 3.941318 2.088642 90)
			(unlocked yes)
			(layer "F.SilkS")
			(effects
				(font
					(size 0.7874 0.5842)
					(thickness 0.1524)
				)
				(justify left)
			)
		)
		(property "Value" ""
			(at 0 0 270)
			(layer "F.Fab")
			(effects
				(font
					(size 1.27 1.27)
				)
			)
		)
		(duplicate_pad_numbers_are_jumpers no)
		(fp_line
			(start -3.400044 1.459992)
			(end -3.400044 -1.459992)
			(stroke
				(width 0.1524)
				(type default)
			)
			(layer "F.SilkS")
		)
		(fp_line
			(start 4.107942 1.459992)
			(end -3.400044 1.459992)
			(stroke
				(width 0.1524)
				(type default)
			)
			(layer "F.SilkS")
		)
		(fp_line
			(start -3.400044 -1.459992)
			(end 4.107942 -1.459992)
			(stroke
				(width 0.1524)
				(type default)
			)
			(layer "F.SilkS")
		)
		(fp_line
			(start 4.107942 -1.459992)
			(end 4.107942 1.459992)
			(stroke
				(width 0.1524)
				(type default)
			)
			(layer "F.SilkS")
		)
		(fp_poly
			(pts
				(xy 4.107942 -1.459992) (xy 4.107942 1.459992) (xy 3.308096 1.459992) (xy 3.308096 -1.459992)
			)
			(stroke
				(width 0)
				(type default)
			)
			(fill yes)
			(layer "F.SilkS")
		)
		(fp_line
			(start -2.29997 1.459992)
			(end -2.29997 -1.459992)
			(stroke
				(width 0.1)
				(type default)
			)
			(layer "F.Fab")
		)
		(fp_line
			(start 2.29997 1.459992)
			(end -2.29997 1.459992)
			(stroke
				(width 0.1)
				(type default)
			)
			(layer "F.Fab")
		)
		(fp_line
			(start -2.29997 -1.459992)
			(end 2.29997 -1.459992)
			(stroke
				(width 0.1)
				(type default)
			)
			(layer "F.Fab")
		)
		(fp_line
			(start 2.29997 -1.459992)
			(end 2.29997 1.459992)
			(stroke
				(width 0.1)
				(type default)
			)
			(layer "F.Fab")
		)
		(fp_text user "-"
			(at 5.4102 0.29845 90)
			(unlocked yes)
			(layer "F.SilkS")
			(effects
				(font
					(size 1.905 1.4224)
					(thickness 0.1524)
				)
				(justify left)
			)
		)
		(fp_text user "+"
			(at -5.202682 -0.27305 270)
			(unlocked yes)
			(layer "F.SilkS")
			(effects
				(font
					(size 1.905 1.4224)
					(thickness 0.1524)
				)
				(justify left)
			)
		)
		(fp_text user "-"
			(at 5.4102 0.29845 90)
			(unlocked yes)
			(layer "F.Fab")
			(effects
				(font
					(size 1.905 1.4224)
					(thickness 0.1524)
				)
				(justify left)
			)
		)
		(fp_text user "+"
			(at -4.7752 -0.12065 270)
			(unlocked yes)
			(layer "F.Fab")
			(effects
				(font
					(size 1.905 1.4224)
					(thickness 0.1524)
				)
				(justify left)
			)
		)
		(pad "A" smd rect
			(at -1.999996 0)
			(size 1.7018 2.5146)
			(layers "F.Cu" "F.Mask" "F.Paste")
			(net "GND")
		)
		(pad "C" smd rect
			(at 1.999996 0)
			(size 1.7018 2.5146)
			(layers "F.Cu" "F.Mask" "F.Paste")
			(net "P12V_SSD6_R")
		)
	)
	(footprint ""
		(layer "F.Cu")
		(at 312.739532 -159.235648 180)
		(property "Reference" "R297"
			(at 0 0 180)
			(layer "F.SilkS")
			(hide yes)
			(effects
				(font
					(size 1.27 1.27)
				)
			)
		)
		(property "Value" ""
			(at 0 0 180)
			(layer "F.Fab")
			(effects
				(font
					(size 1.27 1.27)
				)
			)
		)
		(duplicate_pad_numbers_are_jumpers no)
		(fp_line
			(start 0.7874 0.4064)
			(end -0.7874 0.4064)
			(stroke
				(width 0.1524)
				(type default)
			)
			(layer "F.SilkS")
		)
		(fp_line
			(start 0.7874 -0.4064)
			(end 0.7874 0.4064)
			(stroke
				(width 0.1524)
				(type default)
			)
			(layer "F.SilkS")
		)
		(fp_line
			(start -0.7874 0.4064)
			(end -0.7874 -0.4064)
			(stroke
				(width 0.1524)
				(type default)
			)
			(layer "F.SilkS")
		)
		(fp_line
			(start -0.7874 -0.4064)
			(end 0.7874 -0.4064)
			(stroke
				(width 0.1524)
				(type default)
			)
			(layer "F.SilkS")
		)
		(fp_line
			(start 0.67945 0.3048)
			(end 0.120396 0.3048)
			(stroke
				(width 0.1)
				(type default)
			)
			(layer "F.Fab")
		)
		(fp_line
			(start 0.67945 -0.3048)
			(end 0.67945 0.3048)
			(stroke
				(width 0.1)
				(type default)
			)
			(layer "F.Fab")
		)
		(fp_line
			(start 0.12065 -0.2794)
			(end 0.12065 -0.3048)
			(stroke
				(width 0.1)
				(type default)
			)
			(layer "F.Fab")
		)
		(fp_line
			(start 0.12065 -0.3048)
			(end 0.67945 -0.3048)
			(stroke
				(width 0.1)
				(type default)
			)
			(layer "F.Fab")
		)
		(fp_line
			(start 0.120396 0.3048)
			(end 0.120396 0.2794)
			(stroke
				(width 0.1)
				(type default)
			)
			(layer "F.Fab")
		)
		(fp_line
			(start 0.120396 0.2794)
			(end -0.12065 0.2794)
			(stroke
				(width 0.1)
				(type default)
			)
			(layer "F.Fab")
		)
		(fp_line
			(start -0.12065 0.3048)
			(end -0.67945 0.3048)
			(stroke
				(width 0.1)
				(type default)
			)
			(layer "F.Fab")
		)
		(fp_line
			(start -0.12065 0.2794)
			(end -0.12065 0.3048)
			(stroke
				(width 0.1)
				(type default)
			)
			(layer "F.Fab")
		)
		(fp_line
			(start -0.12065 -0.2794)
			(end 0.12065 -0.2794)
			(stroke
				(width 0.1)
				(type default)
			)
			(layer "F.Fab")
		)
		(fp_line
			(start -0.12065 -0.305054)
			(end -0.12065 -0.2794)
			(stroke
				(width 0.1)
				(type default)
			)
			(layer "F.Fab")
		)
		(fp_line
			(start -0.67945 0.3048)
			(end -0.67945 -0.305054)
			(stroke
				(width 0.1)
				(type default)
			)
			(layer "F.Fab")
		)
		(fp_line
			(start -0.67945 -0.305054)
			(end -0.12065 -0.305054)
			(stroke
				(width 0.1)
				(type default)
			)
			(layer "F.Fab")
		)
		(pad "1" smd circle
			(at -0.40005 0 180)
			(size 0 0)
			(layers "F.Cu" "F.Mask" "F.Paste")
			(net "PRSNT_NIC5_N")
		)
		(pad "2" smd circle
			(at 0.40005 0 180)
			(size 0 0)
			(layers "F.Cu" "F.Mask" "F.Paste")
			(net "PRSNTB3_NIC5_N")
		)
	)
	(footprint ""
		(layer "F.Cu")
		(at 337.206336 -198.27367 90)
		(property "Reference" "C2146"
			(at 0 0 90)
			(layer "F.SilkS")
			(hide yes)
			(effects
				(font
					(size 1.27 1.27)
				)
			)
		)
		(property "Value" ""
			(at 0 0 90)
			(layer "F.Fab")
			(effects
				(font
					(size 1.27 1.27)
				)
			)
		)
		(duplicate_pad_numbers_are_jumpers no)
		(fp_line
			(start 0.7874 -0.4064)
			(end 0.7874 0.4064)
			(stroke
				(width 0.1524)
				(type default)
			)
			(layer "F.SilkS")
		)
		(fp_line
			(start -0.7874 -0.4064)
			(end 0.7874 -0.4064)
			(stroke
				(width 0.1524)
				(type default)
			)
			(layer "F.SilkS")
		)
		(fp_line
			(start 0.7874 0.4064)
			(end -0.7874 0.4064)
			(stroke
				(width 0.1524)
				(type default)
			)
			(layer "F.SilkS")
		)
		(fp_line
			(start -0.7874 0.4064)
			(end -0.7874 -0.4064)
			(stroke
				(width 0.1524)
				(type default)
			)
			(layer "F.SilkS")
		)
		(fp_line
			(start -0.12065 -0.305054)
			(end -0.12065 -0.2794)
			(stroke
				(width 0.1)
				(type default)
			)
			(layer "F.Fab")
		)
		(fp_line
			(start -0.67945 -0.305054)
			(end -0.12065 -0.305054)
			(stroke
				(width 0.1)
				(type default)
			)
			(layer "F.Fab")
		)
		(fp_line
			(start 0.67945 -0.3048)
			(end 0.67945 0.3048)
			(stroke
				(width 0.1)
				(type default)
			)
			(layer "F.Fab")
		)
		(fp_line
			(start 0.12065 -0.3048)
			(end 0.67945 -0.3048)
			(stroke
				(width 0.1)
				(type default)
			)
			(layer "F.Fab")
		)
		(fp_line
			(start 0.12065 -0.2794)
			(end 0.12065 -0.3048)
			(stroke
				(width 0.1)
				(type default)
			)
			(layer "F.Fab")
		)
		(fp_line
			(start -0.12065 -0.2794)
			(end 0.12065 -0.2794)
			(stroke
				(width 0.1)
				(type default)
			)
			(layer "F.Fab")
		)
		(fp_line
			(start 0.120396 0.2794)
			(end -0.12065 0.2794)
			(stroke
				(width 0.1)
				(type default)
			)
			(layer "F.Fab")
		)
		(fp_line
			(start -0.12065 0.2794)
			(end -0.12065 0.3048)
			(stroke
				(width 0.1)
				(type default)
			)
			(layer "F.Fab")
		)
		(fp_line
			(start 0.67945 0.3048)
			(end 0.120396 0.3048)
			(stroke
				(width 0.1)
				(type default)
			)
			(layer "F.Fab")
		)
		(fp_line
			(start 0.120396 0.3048)
			(end 0.120396 0.2794)
			(stroke
				(width 0.1)
				(type default)
			)
			(layer "F.Fab")
		)
		(fp_line
			(start -0.12065 0.3048)
			(end -0.67945 0.3048)
			(stroke
				(width 0.1)
				(type default)
			)
			(layer "F.Fab")
		)
		(fp_line
			(start -0.67945 0.3048)
			(end -0.67945 -0.305054)
			(stroke
				(width 0.1)
				(type default)
			)
			(layer "F.Fab")
		)
		(pad "1" smd circle
			(at -0.40005 0 90)
			(size 0 0)
			(layers "F.Cu" "F.Mask" "F.Paste")
			(net "P3V3_AUX")
		)
		(pad "2" smd circle
			(at 0.40005 0 90)
			(size 0 0)
			(layers "F.Cu" "F.Mask" "F.Paste")
			(net "GND")
		)
	)
	(footprint ""
		(layer "F.Cu")
		(at 236.382814 -285.911544 180)
		(property "Reference" "PC258"
			(at 0 0 180)
			(layer "F.SilkS")
			(hide yes)
			(effects
				(font
					(size 1.27 1.27)
				)
			)
		)
		(property "Value" ""
			(at 0 0 180)
			(layer "F.Fab")
			(effects
				(font
					(size 1.27 1.27)
				)
			)
		)
		(duplicate_pad_numbers_are_jumpers no)
		(fp_line
			(start 2.750058 2.750058)
			(end 2.750058 0.9398)
			(stroke
				(width 0.1524)
				(type default)
			)
			(layer "F.SilkS")
		)
		(fp_line
			(start 2.750058 -0.9398)
			(end 2.750058 -2.750058)
			(stroke
				(width 0.1524)
				(type default)
			)
			(layer "F.SilkS")
		)
		(fp_line
			(start 2.750058 -2.750058)
			(end -1.988058 -2.750058)
			(stroke
				(width 0.1524)
				(type default)
			)
			(layer "F.SilkS")
		)
		(fp_line
			(start -1.988058 2.750058)
			(end 2.750058 2.750058)
			(stroke
				(width 0.1524)
				(type default)
			)
			(layer "F.SilkS")
		)
		(fp_line
			(start -1.988058 -2.750058)
			(end -2.750058 -1.988058)
			(stroke
				(width 0.1524)
				(type default)
			)
			(layer "F.SilkS")
		)
		(fp_line
			(start -2.750058 1.988058)
			(end -1.988058 2.750058)
			(stroke
				(width 0.1524)
				(type default)
			)
			(layer "F.SilkS")
		)
		(fp_line
			(start -2.750058 0.9398)
			(end -2.750058 1.988058)
			(stroke
				(width 0.1524)
				(type default)
			)
			(layer "F.SilkS")
		)
		(fp_line
			(start -2.750058 -1.988058)
			(end -2.750058 -0.9398)
			(stroke
				(width 0.1524)
				(type default)
			)
			(layer "F.SilkS")
		)
		(fp_line
			(start 2.750058 2.750058)
			(end 2.750058 -2.750058)
			(stroke
				(width 0.1)
				(type default)
			)
			(layer "F.Fab")
		)
		(fp_line
			(start 2.750058 -2.750058)
			(end -2.750058 -2.750058)
			(stroke
				(width 0.1)
				(type default)
			)
			(layer "F.Fab")
		)
		(fp_line
			(start -2.750058 2.750058)
			(end 2.750058 2.750058)
			(stroke
				(width 0.1)
				(type default)
			)
			(layer "F.Fab")
		)
		(fp_line
			(start -2.750058 -2.750058)
			(end -2.750058 2.750058)
			(stroke
				(width 0.1)
				(type default)
			)
			(layer "F.Fab")
		)
		(pad "1" smd rect
			(at -2.199894 0 270)
			(size 1.6002 3.0226)
			(layers "F.Cu" "F.Mask" "F.Paste")
			(net "P1V25_PEX2_R")
		)
		(pad "2" smd rect
			(at 2.199894 0 270)
			(size 1.6002 3.0226)
			(layers "F.Cu" "F.Mask" "F.Paste")
			(net "GND")
		)
	)
	(footprint ""
		(layer "F.Cu")
		(at 242.310412 -124.963428 180)
		(property "Reference" "R4475"
			(at 0 0 180)
			(layer "F.SilkS")
			(hide yes)
			(effects
				(font
					(size 1.27 1.27)
				)
			)
		)
		(property "Value" ""
			(at 0 0 180)
			(layer "F.Fab")
			(effects
				(font
					(size 1.27 1.27)
				)
			)
		)
		(duplicate_pad_numbers_are_jumpers no)
		(fp_line
			(start 0.7874 0.4064)
			(end -0.7874 0.4064)
			(stroke
				(width 0.1524)
				(type default)
			)
			(layer "F.SilkS")
		)
		(fp_line
			(start 0.7874 -0.4064)
			(end 0.7874 0.4064)
			(stroke
				(width 0.1524)
				(type default)
			)
			(layer "F.SilkS")
		)
		(fp_line
			(start -0.7874 0.4064)
			(end -0.7874 -0.4064)
			(stroke
				(width 0.1524)
				(type default)
			)
			(layer "F.SilkS")
		)
		(fp_line
			(start -0.7874 -0.4064)
			(end 0.7874 -0.4064)
			(stroke
				(width 0.1524)
				(type default)
			)
			(layer "F.SilkS")
		)
		(fp_line
			(start 0.67945 0.3048)
			(end 0.120396 0.3048)
			(stroke
				(width 0.1)
				(type default)
			)
			(layer "F.Fab")
		)
		(fp_line
			(start 0.67945 -0.3048)
			(end 0.67945 0.3048)
			(stroke
				(width 0.1)
				(type default)
			)
			(layer "F.Fab")
		)
		(fp_line
			(start 0.12065 -0.2794)
			(end 0.12065 -0.3048)
			(stroke
				(width 0.1)
				(type default)
			)
			(layer "F.Fab")
		)
		(fp_line
			(start 0.12065 -0.3048)
			(end 0.67945 -0.3048)
			(stroke
				(width 0.1)
				(type default)
			)
			(layer "F.Fab")
		)
		(fp_line
			(start 0.120396 0.3048)
			(end 0.120396 0.2794)
			(stroke
				(width 0.1)
				(type default)
			)
			(layer "F.Fab")
		)
		(fp_line
			(start 0.120396 0.2794)
			(end -0.12065 0.2794)
			(stroke
				(width 0.1)
				(type default)
			)
			(layer "F.Fab")
		)
		(fp_line
			(start -0.12065 0.3048)
			(end -0.67945 0.3048)
			(stroke
				(width 0.1)
				(type default)
			)
			(layer "F.Fab")
		)
		(fp_line
			(start -0.12065 0.2794)
			(end -0.12065 0.3048)
			(stroke
				(width 0.1)
				(type default)
			)
			(layer "F.Fab")
		)
		(fp_line
			(start -0.12065 -0.2794)
			(end 0.12065 -0.2794)
			(stroke
				(width 0.1)
				(type default)
			)
			(layer "F.Fab")
		)
		(fp_line
			(start -0.12065 -0.305054)
			(end -0.12065 -0.2794)
			(stroke
				(width 0.1)
				(type default)
			)
			(layer "F.Fab")
		)
		(fp_line
			(start -0.67945 0.3048)
			(end -0.67945 -0.305054)
			(stroke
				(width 0.1)
				(type default)
			)
			(layer "F.Fab")
		)
		(fp_line
			(start -0.67945 -0.305054)
			(end -0.12065 -0.305054)
			(stroke
				(width 0.1)
				(type default)
			)
			(layer "F.Fab")
		)
		(pad "1" smd circle
			(at -0.40005 0 180)
			(size 0 0)
			(layers "F.Cu" "F.Mask" "F.Paste")
			(net "PWRGD_P3V3_NIC4")
		)
		(pad "2" smd circle
			(at 0.40005 0 180)
			(size 0 0)
			(layers "F.Cu" "F.Mask" "F.Paste")
			(net "PWRGD_P3V3_NIC4_R")
		)
	)
	(footprint ""
		(layer "F.Cu")
		(at 115.38966 -159.377126 -90)
		(property "Reference" "PJ3"
			(at 0 0 270)
			(layer "F.SilkS")
			(hide yes)
			(effects
				(font
					(size 1.27 1.27)
				)
			)
		)
		(property "Value" ""
			(at 0 0 270)
			(layer "F.Fab")
			(effects
				(font
					(size 1.27 1.27)
				)
			)
		)
		(duplicate_pad_numbers_are_jumpers no)
		(pad "1" smd circle
			(at -0.40005 0)
			(size 0 0)
			(layers "F.Cu" "F.Mask" "F.Paste")
			(net "SH_P3V3_AUX_FB")
		)
		(pad "2" smd rect
			(at 0.40005 0 90)
			(size 0.4572 0.508)
			(layers "F.Cu" "F.Mask" "F.Paste")
			(net "P3V3_AUX")
		)
		(zone
			(layer "F.Cu")
			(hatch none 0.5)
			(connect_pads
				(clearance 0)
			)
			(min_thickness 0.25)
			(keepout
				(tracks allowed)
				(vias not_allowed)
				(pads allowed)
				(copperpour not_allowed)
				(footprints allowed)
			)
			(placement
				(enabled no)
				(sheetname "")
			)
			(fill
				(thermal_gap 0.5)
				(thermal_bridge_width 0.5)
				(island_removal_mode 0)
			)
			(polygon
				(pts
					(xy 115.08486 -158.691326) (xy 115.69446 -158.691326) (xy 115.69446 -160.062926) (xy 115.08486 -160.062926)
				)
			)
		)
	)
	(footprint ""
		(layer "F.Cu")
		(at 381.254 -195.326 180)
		(property "Reference" "R4678"
			(at 0 0 180)
			(layer "F.SilkS")
			(hide yes)
			(effects
				(font
					(size 1.27 1.27)
				)
			)
		)
		(property "Value" ""
			(at 0 0 180)
			(layer "F.Fab")
			(effects
				(font
					(size 1.27 1.27)
				)
			)
		)
		(duplicate_pad_numbers_are_jumpers no)
		(fp_line
			(start 0.7874 0.4064)
			(end -0.7874 0.4064)
			(stroke
				(width 0.1524)
				(type default)
			)
			(layer "F.SilkS")
		)
		(fp_line
			(start 0.7874 -0.4064)
			(end 0.7874 0.4064)
			(stroke
				(width 0.1524)
				(type default)
			)
			(layer "F.SilkS")
		)
		(fp_line
			(start -0.7874 0.4064)
			(end -0.7874 -0.4064)
			(stroke
				(width 0.1524)
				(type default)
			)
			(layer "F.SilkS")
		)
		(fp_line
			(start -0.7874 -0.4064)
			(end 0.7874 -0.4064)
			(stroke
				(width 0.1524)
				(type default)
			)
			(layer "F.SilkS")
		)
		(fp_line
			(start 0.67945 0.3048)
			(end 0.120396 0.3048)
			(stroke
				(width 0.1)
				(type default)
			)
			(layer "F.Fab")
		)
		(fp_line
			(start 0.67945 -0.3048)
			(end 0.67945 0.3048)
			(stroke
				(width 0.1)
				(type default)
			)
			(layer "F.Fab")
		)
		(fp_line
			(start 0.12065 -0.2794)
			(end 0.12065 -0.3048)
			(stroke
				(width 0.1)
				(type default)
			)
			(layer "F.Fab")
		)
		(fp_line
			(start 0.12065 -0.3048)
			(end 0.67945 -0.3048)
			(stroke
				(width 0.1)
				(type default)
			)
			(layer "F.Fab")
		)
		(fp_line
			(start 0.120396 0.3048)
			(end 0.120396 0.2794)
			(stroke
				(width 0.1)
				(type default)
			)
			(layer "F.Fab")
		)
		(fp_line
			(start 0.120396 0.2794)
			(end -0.12065 0.2794)
			(stroke
				(width 0.1)
				(type default)
			)
			(layer "F.Fab")
		)
		(fp_line
			(start -0.12065 0.3048)
			(end -0.67945 0.3048)
			(stroke
				(width 0.1)
				(type default)
			)
			(layer "F.Fab")
		)
		(fp_line
			(start -0.12065 0.2794)
			(end -0.12065 0.3048)
			(stroke
				(width 0.1)
				(type default)
			)
			(layer "F.Fab")
		)
		(fp_line
			(start -0.12065 -0.2794)
			(end 0.12065 -0.2794)
			(stroke
				(width 0.1)
				(type default)
			)
			(layer "F.Fab")
		)
		(fp_line
			(start -0.12065 -0.305054)
			(end -0.12065 -0.2794)
			(stroke
				(width 0.1)
				(type default)
			)
			(layer "F.Fab")
		)
		(fp_line
			(start -0.67945 0.3048)
			(end -0.67945 -0.305054)
			(stroke
				(width 0.1)
				(type default)
			)
			(layer "F.Fab")
		)
		(fp_line
			(start -0.67945 -0.305054)
			(end -0.12065 -0.305054)
			(stroke
				(width 0.1)
				(type default)
			)
			(layer "F.Fab")
		)
		(pad "1" smd circle
			(at -0.40005 0 180)
			(size 0 0)
			(layers "F.Cu" "F.Mask" "F.Paste")
			(net "NIC2_PEX_PWR_EN_R")
		)
		(pad "2" smd circle
			(at 0.40005 0 180)
			(size 0 0)
			(layers "F.Cu" "F.Mask" "F.Paste")
			(net "GND")
		)
	)
	(footprint ""
		(layer "F.Cu")
		(at 219.223844 -98.806 -90)
		(property "Reference" "R717"
			(at 0 0 270)
			(layer "F.SilkS")
			(hide yes)
			(effects
				(font
					(size 1.27 1.27)
				)
			)
		)
		(property "Value" ""
			(at 0 0 270)
			(layer "F.Fab")
			(effects
				(font
					(size 1.27 1.27)
				)
			)
		)
		(duplicate_pad_numbers_are_jumpers no)
		(fp_line
			(start -0.7874 0.4064)
			(end -0.7874 -0.4064)
			(stroke
				(width 0.1524)
				(type default)
			)
			(layer "F.SilkS")
		)
		(fp_line
			(start 0.7874 0.4064)
			(end -0.7874 0.4064)
			(stroke
				(width 0.1524)
				(type default)
			)
			(layer "F.SilkS")
		)
		(fp_line
			(start -0.7874 -0.4064)
			(end 0.7874 -0.4064)
			(stroke
				(width 0.1524)
				(type default)
			)
			(layer "F.SilkS")
		)
		(fp_line
			(start 0.7874 -0.4064)
			(end 0.7874 0.4064)
			(stroke
				(width 0.1524)
				(type default)
			)
			(layer "F.SilkS")
		)
		(fp_line
			(start -0.67945 0.3048)
			(end -0.67945 -0.305054)
			(stroke
				(width 0.1)
				(type default)
			)
			(layer "F.Fab")
		)
		(fp_line
			(start -0.12065 0.3048)
			(end -0.67945 0.3048)
			(stroke
				(width 0.1)
				(type default)
			)
			(layer "F.Fab")
		)
		(fp_line
			(start 0.120396 0.3048)
			(end 0.120396 0.2794)
			(stroke
				(width 0.1)
				(type default)
			)
			(layer "F.Fab")
		)
		(fp_line
			(start 0.67945 0.3048)
			(end 0.120396 0.3048)
			(stroke
				(width 0.1)
				(type default)
			)
			(layer "F.Fab")
		)
		(fp_line
			(start -0.12065 0.2794)
			(end -0.12065 0.3048)
			(stroke
				(width 0.1)
				(type default)
			)
			(layer "F.Fab")
		)
		(fp_line
			(start 0.120396 0.2794)
			(end -0.12065 0.2794)
			(stroke
				(width 0.1)
				(type default)
			)
			(layer "F.Fab")
		)
		(fp_line
			(start -0.12065 -0.2794)
			(end 0.12065 -0.2794)
			(stroke
				(width 0.1)
				(type default)
			)
			(layer "F.Fab")
		)
		(fp_line
			(start 0.12065 -0.2794)
			(end 0.12065 -0.3048)
			(stroke
				(width 0.1)
				(type default)
			)
			(layer "F.Fab")
		)
		(fp_line
			(start 0.12065 -0.3048)
			(end 0.67945 -0.3048)
			(stroke
				(width 0.1)
				(type default)
			)
			(layer "F.Fab")
		)
		(fp_line
			(start 0.67945 -0.3048)
			(end 0.67945 0.3048)
			(stroke
				(width 0.1)
				(type default)
			)
			(layer "F.Fab")
		)
		(fp_line
			(start -0.67945 -0.305054)
			(end -0.12065 -0.305054)
			(stroke
				(width 0.1)
				(type default)
			)
			(layer "F.Fab")
		)
		(fp_line
			(start -0.12065 -0.305054)
			(end -0.12065 -0.2794)
			(stroke
				(width 0.1)
				(type default)
			)
			(layer "F.Fab")
		)
		(pad "1" smd circle
			(at -0.40005 0 270)
			(size 0 0)
			(layers "F.Cu" "F.Mask" "F.Paste")
			(net "NIC3_ADC_ALERT_N")
		)
		(pad "2" smd circle
			(at 0.40005 0 270)
			(size 0 0)
			(layers "F.Cu" "F.Mask" "F.Paste")
			(net "NIC_ADC_ALERT_N")
		)
	)
	(footprint ""
		(layer "F.Cu")
		(at 430.826672 -53.697124 -90)
		(property "Reference" "PC582"
			(at 0 0 270)
			(layer "F.SilkS")
			(hide yes)
			(effects
				(font
					(size 1.27 1.27)
				)
			)
		)
		(property "Value" ""
			(at 0 0 270)
			(layer "F.Fab")
			(effects
				(font
					(size 1.27 1.27)
				)
			)
		)
		(duplicate_pad_numbers_are_jumpers no)
		(fp_line
			(start -0.7874 0.4064)
			(end -0.7874 -0.4064)
			(stroke
				(width 0.1524)
				(type default)
			)
			(layer "F.SilkS")
		)
		(fp_line
			(start 0.7874 0.4064)
			(end -0.7874 0.4064)
			(stroke
				(width 0.1524)
				(type default)
			)
			(layer "F.SilkS")
		)
		(fp_line
			(start -0.7874 -0.4064)
			(end 0.7874 -0.4064)
			(stroke
				(width 0.1524)
				(type default)
			)
			(layer "F.SilkS")
		)
		(fp_line
			(start 0.7874 -0.4064)
			(end 0.7874 0.4064)
			(stroke
				(width 0.1524)
				(type default)
			)
			(layer "F.SilkS")
		)
		(fp_line
			(start -0.67945 0.3048)
			(end -0.67945 -0.305054)
			(stroke
				(width 0.1)
				(type default)
			)
			(layer "F.Fab")
		)
		(fp_line
			(start -0.12065 0.3048)
			(end -0.67945 0.3048)
			(stroke
				(width 0.1)
				(type default)
			)
			(layer "F.Fab")
		)
		(fp_line
			(start 0.120396 0.3048)
			(end 0.120396 0.2794)
			(stroke
				(width 0.1)
				(type default)
			)
			(layer "F.Fab")
		)
		(fp_line
			(start 0.67945 0.3048)
			(end 0.120396 0.3048)
			(stroke
				(width 0.1)
				(type default)
			)
			(layer "F.Fab")
		)
		(fp_line
			(start -0.12065 0.2794)
			(end -0.12065 0.3048)
			(stroke
				(width 0.1)
				(type default)
			)
			(layer "F.Fab")
		)
		(fp_line
			(start 0.120396 0.2794)
			(end -0.12065 0.2794)
			(stroke
				(width 0.1)
				(type default)
			)
			(layer "F.Fab")
		)
		(fp_line
			(start -0.12065 -0.2794)
			(end 0.12065 -0.2794)
			(stroke
				(width 0.1)
				(type default)
			)
			(layer "F.Fab")
		)
		(fp_line
			(start 0.12065 -0.2794)
			(end 0.12065 -0.3048)
			(stroke
				(width 0.1)
				(type default)
			)
			(layer "F.Fab")
		)
		(fp_line
			(start 0.12065 -0.3048)
			(end 0.67945 -0.3048)
			(stroke
				(width 0.1)
				(type default)
			)
			(layer "F.Fab")
		)
		(fp_line
			(start 0.67945 -0.3048)
			(end 0.67945 0.3048)
			(stroke
				(width 0.1)
				(type default)
			)
			(layer "F.Fab")
		)
		(fp_line
			(start -0.67945 -0.305054)
			(end -0.12065 -0.305054)
			(stroke
				(width 0.1)
				(type default)
			)
			(layer "F.Fab")
		)
		(fp_line
			(start -0.12065 -0.305054)
			(end -0.12065 -0.2794)
			(stroke
				(width 0.1)
				(type default)
			)
			(layer "F.Fab")
		)
		(pad "1" smd circle
			(at -0.40005 0 270)
			(size 0 0)
			(layers "F.Cu" "F.Mask" "F.Paste")
			(net "P3V3_AUX")
		)
		(pad "2" smd circle
			(at 0.40005 0 270)
			(size 0 0)
			(layers "F.Cu" "F.Mask" "F.Paste")
			(net "GND")
		)
	)
	(footprint ""
		(layer "F.Cu")
		(at 102.428802 -293.816786 -90)
		(property "Reference" "PC83"
			(at 0 0 270)
			(layer "F.SilkS")
			(hide yes)
			(effects
				(font
					(size 1.27 1.27)
				)
			)
		)
		(property "Value" ""
			(at 0 0 270)
			(layer "F.Fab")
			(effects
				(font
					(size 1.27 1.27)
				)
			)
		)
		(duplicate_pad_numbers_are_jumpers no)
		(fp_line
			(start -0.7874 0.4064)
			(end -0.7874 -0.4064)
			(stroke
				(width 0.1524)
				(type default)
			)
			(layer "F.SilkS")
		)
		(fp_line
			(start 0.7874 0.4064)
			(end -0.7874 0.4064)
			(stroke
				(width 0.1524)
				(type default)
			)
			(layer "F.SilkS")
		)
		(fp_line
			(start -0.7874 -0.4064)
			(end 0.7874 -0.4064)
			(stroke
				(width 0.1524)
				(type default)
			)
			(layer "F.SilkS")
		)
		(fp_line
			(start 0.7874 -0.4064)
			(end 0.7874 0.4064)
			(stroke
				(width 0.1524)
				(type default)
			)
			(layer "F.SilkS")
		)
		(fp_line
			(start -0.67945 0.3048)
			(end -0.67945 -0.305054)
			(stroke
				(width 0.1)
				(type default)
			)
			(layer "F.Fab")
		)
		(fp_line
			(start -0.12065 0.3048)
			(end -0.67945 0.3048)
			(stroke
				(width 0.1)
				(type default)
			)
			(layer "F.Fab")
		)
		(fp_line
			(start 0.120396 0.3048)
			(end 0.120396 0.2794)
			(stroke
				(width 0.1)
				(type default)
			)
			(layer "F.Fab")
		)
		(fp_line
			(start 0.67945 0.3048)
			(end 0.120396 0.3048)
			(stroke
				(width 0.1)
				(type default)
			)
			(layer "F.Fab")
		)
		(fp_line
			(start -0.12065 0.2794)
			(end -0.12065 0.3048)
			(stroke
				(width 0.1)
				(type default)
			)
			(layer "F.Fab")
		)
		(fp_line
			(start 0.120396 0.2794)
			(end -0.12065 0.2794)
			(stroke
				(width 0.1)
				(type default)
			)
			(layer "F.Fab")
		)
		(fp_line
			(start -0.12065 -0.2794)
			(end 0.12065 -0.2794)
			(stroke
				(width 0.1)
				(type default)
			)
			(layer "F.Fab")
		)
		(fp_line
			(start 0.12065 -0.2794)
			(end 0.12065 -0.3048)
			(stroke
				(width 0.1)
				(type default)
			)
			(layer "F.Fab")
		)
		(fp_line
			(start 0.12065 -0.3048)
			(end 0.67945 -0.3048)
			(stroke
				(width 0.1)
				(type default)
			)
			(layer "F.Fab")
		)
		(fp_line
			(start 0.67945 -0.3048)
			(end 0.67945 0.3048)
			(stroke
				(width 0.1)
				(type default)
			)
			(layer "F.Fab")
		)
		(fp_line
			(start -0.67945 -0.305054)
			(end -0.12065 -0.305054)
			(stroke
				(width 0.1)
				(type default)
			)
			(layer "F.Fab")
		)
		(fp_line
			(start -0.12065 -0.305054)
			(end -0.12065 -0.2794)
			(stroke
				(width 0.1)
				(type default)
			)
			(layer "F.Fab")
		)
		(pad "1" smd circle
			(at -0.40005 0 270)
			(size 0 0)
			(layers "F.Cu" "F.Mask" "F.Paste")
			(net "P0V8_PEX0")
		)
		(pad "2" smd circle
			(at 0.40005 0 270)
			(size 0 0)
			(layers "F.Cu" "F.Mask" "F.Paste")
			(net "GND")
		)
	)
	(footprint ""
		(layer "F.Cu")
		(at 138.985244 -96.957642 180)
		(property "Reference" "R1559"
			(at 0 0 180)
			(layer "F.SilkS")
			(hide yes)
			(effects
				(font
					(size 1.27 1.27)
				)
			)
		)
		(property "Value" ""
			(at 0 0 180)
			(layer "F.Fab")
			(effects
				(font
					(size 1.27 1.27)
				)
			)
		)
		(duplicate_pad_numbers_are_jumpers no)
		(fp_line
			(start 0.7874 0.4064)
			(end -0.7874 0.4064)
			(stroke
				(width 0.1524)
				(type default)
			)
			(layer "F.SilkS")
		)
		(fp_line
			(start 0.7874 -0.4064)
			(end 0.7874 0.4064)
			(stroke
				(width 0.1524)
				(type default)
			)
			(layer "F.SilkS")
		)
		(fp_line
			(start -0.7874 0.4064)
			(end -0.7874 -0.4064)
			(stroke
				(width 0.1524)
				(type default)
			)
			(layer "F.SilkS")
		)
		(fp_line
			(start -0.7874 -0.4064)
			(end 0.7874 -0.4064)
			(stroke
				(width 0.1524)
				(type default)
			)
			(layer "F.SilkS")
		)
		(fp_line
			(start 0.67945 0.3048)
			(end 0.120396 0.3048)
			(stroke
				(width 0.1)
				(type default)
			)
			(layer "F.Fab")
		)
		(fp_line
			(start 0.67945 -0.3048)
			(end 0.67945 0.3048)
			(stroke
				(width 0.1)
				(type default)
			)
			(layer "F.Fab")
		)
		(fp_line
			(start 0.12065 -0.2794)
			(end 0.12065 -0.3048)
			(stroke
				(width 0.1)
				(type default)
			)
			(layer "F.Fab")
		)
		(fp_line
			(start 0.12065 -0.3048)
			(end 0.67945 -0.3048)
			(stroke
				(width 0.1)
				(type default)
			)
			(layer "F.Fab")
		)
		(fp_line
			(start 0.120396 0.3048)
			(end 0.120396 0.2794)
			(stroke
				(width 0.1)
				(type default)
			)
			(layer "F.Fab")
		)
		(fp_line
			(start 0.120396 0.2794)
			(end -0.12065 0.2794)
			(stroke
				(width 0.1)
				(type default)
			)
			(layer "F.Fab")
		)
		(fp_line
			(start -0.12065 0.3048)
			(end -0.67945 0.3048)
			(stroke
				(width 0.1)
				(type default)
			)
			(layer "F.Fab")
		)
		(fp_line
			(start -0.12065 0.2794)
			(end -0.12065 0.3048)
			(stroke
				(width 0.1)
				(type default)
			)
			(layer "F.Fab")
		)
		(fp_line
			(start -0.12065 -0.2794)
			(end 0.12065 -0.2794)
			(stroke
				(width 0.1)
				(type default)
			)
			(layer "F.Fab")
		)
		(fp_line
			(start -0.12065 -0.305054)
			(end -0.12065 -0.2794)
			(stroke
				(width 0.1)
				(type default)
			)
			(layer "F.Fab")
		)
		(fp_line
			(start -0.67945 0.3048)
			(end -0.67945 -0.305054)
			(stroke
				(width 0.1)
				(type default)
			)
			(layer "F.Fab")
		)
		(fp_line
			(start -0.67945 -0.305054)
			(end -0.12065 -0.305054)
			(stroke
				(width 0.1)
				(type default)
			)
			(layer "F.Fab")
		)
		(pad "1" smd circle
			(at -0.40005 0 180)
			(size 0 0)
			(layers "F.Cu" "F.Mask" "F.Paste")
			(net "P3V3_AUX")
		)
		(pad "2" smd circle
			(at 0.40005 0 180)
			(size 0 0)
			(layers "F.Cu" "F.Mask" "F.Paste")
			(net "BIC_I2C9_SSD_MUX0_A2")
		)
	)
	(footprint ""
		(layer "F.Cu")
		(at 366.092486 -32.739584 180)
		(property "Reference" "C700"
			(at 0 0 180)
			(layer "F.SilkS")
			(hide yes)
			(effects
				(font
					(size 1.27 1.27)
				)
			)
		)
		(property "Value" ""
			(at 0 0 180)
			(layer "F.Fab")
			(effects
				(font
					(size 1.27 1.27)
				)
			)
		)
		(duplicate_pad_numbers_are_jumpers no)
		(fp_line
			(start 0.299974 0.150114)
			(end -0.299974 0.150114)
			(stroke
				(width 0.1)
				(type default)
			)
			(layer "F.Fab")
		)
		(fp_line
			(start 0.299974 -0.150114)
			(end 0.299974 0.150114)
			(stroke
				(width 0.1)
				(type default)
			)
			(layer "F.Fab")
		)
		(fp_line
			(start -0.299974 0.150114)
			(end -0.299974 -0.150114)
			(stroke
				(width 0.1)
				(type default)
			)
			(layer "F.Fab")
		)
		(fp_line
			(start -0.299974 -0.150114)
			(end 0.299974 -0.150114)
			(stroke
				(width 0.1)
				(type default)
			)
			(layer "F.Fab")
		)
		(pad "1" smd rect
			(at -0.2667 0 180)
			(size 0.3048 0.381)
			(layers "F.Cu" "F.Mask" "F.Paste")
			(net "P5E_PEX3_STN2_TX_DP<46>")
		)
		(pad "2" smd rect
			(at 0.2667 0 180)
			(size 0.3048 0.381)
			(layers "F.Cu" "F.Mask" "F.Paste")
			(net "P5E_PEX3_STN2_TX_C_DP<46>")
		)
	)
	(footprint ""
		(layer "F.Cu")
		(at 375.230136 -297.205908 -90)
		(property "Reference" "C3537"
			(at 0 0 270)
			(layer "F.SilkS")
			(hide yes)
			(effects
				(font
					(size 1.27 1.27)
				)
			)
		)
		(property "Value" ""
			(at 0 0 270)
			(layer "F.Fab")
			(effects
				(font
					(size 1.27 1.27)
				)
			)
		)
		(duplicate_pad_numbers_are_jumpers no)
		(fp_line
			(start -1.2954 0.5842)
			(end -1.2954 -0.5842)
			(stroke
				(width 0.1524)
				(type default)
			)
			(layer "F.SilkS")
		)
		(fp_line
			(start 1.2954 0.5842)
			(end -1.2954 0.5842)
			(stroke
				(width 0.1524)
				(type default)
			)
			(layer "F.SilkS")
		)
		(fp_line
			(start -1.2954 -0.5842)
			(end 1.2954 -0.5842)
			(stroke
				(width 0.1524)
				(type default)
			)
			(layer "F.SilkS")
		)
		(fp_line
			(start 1.2954 -0.5842)
			(end 1.2954 0.5842)
			(stroke
				(width 0.1524)
				(type default)
			)
			(layer "F.SilkS")
		)
		(fp_line
			(start -0.8636 0.4572)
			(end -0.8636 0.4064)
			(stroke
				(width 0.1)
				(type default)
			)
			(layer "F.Fab")
		)
		(fp_line
			(start 0.8636 0.4572)
			(end -0.8636 0.4572)
			(stroke
				(width 0.1)
				(type default)
			)
			(layer "F.Fab")
		)
		(fp_line
			(start -1.1938 0.4064)
			(end -1.1938 -0.4064)
			(stroke
				(width 0.1)
				(type default)
			)
			(layer "F.Fab")
		)
		(fp_line
			(start -0.8636 0.4064)
			(end -1.1938 0.4064)
			(stroke
				(width 0.1)
				(type default)
			)
			(layer "F.Fab")
		)
		(fp_line
			(start 0.8636 0.4064)
			(end 0.8636 0.4572)
			(stroke
				(width 0.1)
				(type default)
			)
			(layer "F.Fab")
		)
		(fp_line
			(start 1.1938 0.4064)
			(end 0.8636 0.4064)
			(stroke
				(width 0.1)
				(type default)
			)
			(layer "F.Fab")
		)
		(fp_line
			(start -1.1938 -0.4064)
			(end -0.8636 -0.4064)
			(stroke
				(width 0.1)
				(type default)
			)
			(layer "F.Fab")
		)
		(fp_line
			(start -0.8636 -0.4064)
			(end -0.8636 -0.4572)
			(stroke
				(width 0.1)
				(type default)
			)
			(layer "F.Fab")
		)
		(fp_line
			(start 0.8636 -0.4064)
			(end 1.1938 -0.4064)
			(stroke
				(width 0.1)
				(type default)
			)
			(layer "F.Fab")
		)
		(fp_line
			(start 1.1938 -0.4064)
			(end 1.1938 0.4064)
			(stroke
				(width 0.1)
				(type default)
			)
			(layer "F.Fab")
		)
		(fp_line
			(start -0.8636 -0.4572)
			(end 0.8636 -0.4572)
			(stroke
				(width 0.1)
				(type default)
			)
			(layer "F.Fab")
		)
		(fp_line
			(start 0.8636 -0.4572)
			(end 0.8636 -0.4064)
			(stroke
				(width 0.1)
				(type default)
			)
			(layer "F.Fab")
		)
		(pad "1" smd rect
			(at -0.7366 0 180)
			(size 0.7112 0.8128)
			(layers "F.Cu" "F.Mask" "F.Paste")
			(net "P1V8_PLL0_PEX3")
		)
		(pad "2" smd rect
			(at 0.7366 0 180)
			(size 0.7112 0.8128)
			(layers "F.Cu" "F.Mask" "F.Paste")
			(net "GND")
		)
	)
	(footprint ""
		(layer "F.Cu")
		(at 274.18792 -45.704252 90)
		(property "Reference" "R605"
			(at 0 0 90)
			(layer "F.SilkS")
			(hide yes)
			(effects
				(font
					(size 1.27 1.27)
				)
			)
		)
		(property "Value" ""
			(at 0 0 90)
			(layer "F.Fab")
			(effects
				(font
					(size 1.27 1.27)
				)
			)
		)
		(duplicate_pad_numbers_are_jumpers no)
		(fp_line
			(start 3.937508 -1.8796)
			(end -3.937508 -1.8796)
			(stroke
				(width 0.1524)
				(type default)
			)
			(layer "F.SilkS")
		)
		(fp_line
			(start -3.937508 -1.8796)
			(end -3.937508 1.8796)
			(stroke
				(width 0.1524)
				(type default)
			)
			(layer "F.SilkS")
		)
		(fp_line
			(start 3.937508 1.8796)
			(end 3.937508 -1.8796)
			(stroke
				(width 0.1524)
				(type default)
			)
			(layer "F.SilkS")
		)
		(fp_line
			(start -3.937508 1.8796)
			(end 3.937508 1.8796)
			(stroke
				(width 0.1524)
				(type default)
			)
			(layer "F.SilkS")
		)
		(fp_line
			(start 3.275076 -1.674876)
			(end -3.275076 -1.674876)
			(stroke
				(width 0.1)
				(type default)
			)
			(layer "F.Fab")
		)
		(fp_line
			(start -3.275076 -1.674876)
			(end -3.275076 1.674876)
			(stroke
				(width 0.1)
				(type default)
			)
			(layer "F.Fab")
		)
		(fp_line
			(start 3.275076 1.674876)
			(end 3.275076 -1.674876)
			(stroke
				(width 0.1)
				(type default)
			)
			(layer "F.Fab")
		)
		(fp_line
			(start -3.275076 1.674876)
			(end 3.275076 1.674876)
			(stroke
				(width 0.1)
				(type default)
			)
			(layer "F.Fab")
		)
		(pad "1" smd rect
			(at -2.350008 0 90)
			(size 2.921 3.5052)
			(layers "F.Cu" "F.Mask" "F.Paste")
			(net "P12V_SSD9")
		)
		(pad "2" smd rect
			(at 2.350008 0 90)
			(size 2.921 3.5052)
			(layers "F.Cu" "F.Mask" "F.Paste")
			(net "P12V_SSD9_R")
		)
	)
	(footprint ""
		(layer "F.Cu")
		(at 229.88778 -308.095396 -90)
		(property "Reference" "PC979"
			(at 0 0 270)
			(layer "F.SilkS")
			(hide yes)
			(effects
				(font
					(size 1.27 1.27)
				)
			)
		)
		(property "Value" ""
			(at 0 0 270)
			(layer "F.Fab")
			(effects
				(font
					(size 1.27 1.27)
				)
			)
		)
		(duplicate_pad_numbers_are_jumpers no)
		(fp_line
			(start -0.7874 0.4064)
			(end -0.7874 -0.4064)
			(stroke
				(width 0.1524)
				(type default)
			)
			(layer "F.SilkS")
		)
		(fp_line
			(start 0.7874 0.4064)
			(end -0.7874 0.4064)
			(stroke
				(width 0.1524)
				(type default)
			)
			(layer "F.SilkS")
		)
		(fp_line
			(start -0.7874 -0.4064)
			(end 0.7874 -0.4064)
			(stroke
				(width 0.1524)
				(type default)
			)
			(layer "F.SilkS")
		)
		(fp_line
			(start 0.7874 -0.4064)
			(end 0.7874 0.4064)
			(stroke
				(width 0.1524)
				(type default)
			)
			(layer "F.SilkS")
		)
		(fp_line
			(start -0.67945 0.3048)
			(end -0.67945 -0.305054)
			(stroke
				(width 0.1)
				(type default)
			)
			(layer "F.Fab")
		)
		(fp_line
			(start -0.12065 0.3048)
			(end -0.67945 0.3048)
			(stroke
				(width 0.1)
				(type default)
			)
			(layer "F.Fab")
		)
		(fp_line
			(start 0.120396 0.3048)
			(end 0.120396 0.2794)
			(stroke
				(width 0.1)
				(type default)
			)
			(layer "F.Fab")
		)
		(fp_line
			(start 0.67945 0.3048)
			(end 0.120396 0.3048)
			(stroke
				(width 0.1)
				(type default)
			)
			(layer "F.Fab")
		)
		(fp_line
			(start -0.12065 0.2794)
			(end -0.12065 0.3048)
			(stroke
				(width 0.1)
				(type default)
			)
			(layer "F.Fab")
		)
		(fp_line
			(start 0.120396 0.2794)
			(end -0.12065 0.2794)
			(stroke
				(width 0.1)
				(type default)
			)
			(layer "F.Fab")
		)
		(fp_line
			(start -0.12065 -0.2794)
			(end 0.12065 -0.2794)
			(stroke
				(width 0.1)
				(type default)
			)
			(layer "F.Fab")
		)
		(fp_line
			(start 0.12065 -0.2794)
			(end 0.12065 -0.3048)
			(stroke
				(width 0.1)
				(type default)
			)
			(layer "F.Fab")
		)
		(fp_line
			(start 0.12065 -0.3048)
			(end 0.67945 -0.3048)
			(stroke
				(width 0.1)
				(type default)
			)
			(layer "F.Fab")
		)
		(fp_line
			(start 0.67945 -0.3048)
			(end 0.67945 0.3048)
			(stroke
				(width 0.1)
				(type default)
			)
			(layer "F.Fab")
		)
		(fp_line
			(start -0.67945 -0.305054)
			(end -0.12065 -0.305054)
			(stroke
				(width 0.1)
				(type default)
			)
			(layer "F.Fab")
		)
		(fp_line
			(start -0.12065 -0.305054)
			(end -0.12065 -0.2794)
			(stroke
				(width 0.1)
				(type default)
			)
			(layer "F.Fab")
		)
		(pad "1" smd circle
			(at -0.40005 0 270)
			(size 0 0)
			(layers "F.Cu" "F.Mask" "F.Paste")
			(net "SH_P1V25_PEX1_FB_P")
		)
		(pad "2" smd circle
			(at 0.40005 0 270)
			(size 0 0)
			(layers "F.Cu" "F.Mask" "F.Paste")
			(net "SH_P1V25_PEX1_FB_N")
		)
	)
	(footprint ""
		(layer "F.Cu")
		(at 271.480534 -132.215382)
		(property "Reference" "C459"
			(at 0 0 0)
			(layer "F.SilkS")
			(hide yes)
			(effects
				(font
					(size 1.27 1.27)
				)
			)
		)
		(property "Value" ""
			(at 0 0 0)
			(layer "F.Fab")
			(effects
				(font
					(size 1.27 1.27)
				)
			)
		)
		(duplicate_pad_numbers_are_jumpers no)
		(fp_line
			(start -0.299974 -0.150114)
			(end 0.299974 -0.150114)
			(stroke
				(width 0.1)
				(type default)
			)
			(layer "F.Fab")
		)
		(fp_line
			(start -0.299974 0.150114)
			(end -0.299974 -0.150114)
			(stroke
				(width 0.1)
				(type default)
			)
			(layer "F.Fab")
		)
		(fp_line
			(start 0.299974 -0.150114)
			(end 0.299974 0.150114)
			(stroke
				(width 0.1)
				(type default)
			)
			(layer "F.Fab")
		)
		(fp_line
			(start 0.299974 0.150114)
			(end -0.299974 0.150114)
			(stroke
				(width 0.1)
				(type default)
			)
			(layer "F.Fab")
		)
		(pad "1" smd rect
			(at -0.2667 0)
			(size 0.3048 0.381)
			(layers "F.Cu" "F.Mask" "F.Paste")
			(net "P5E_PEX2_STN1_TX_DN<29>")
		)
		(pad "2" smd rect
			(at 0.2667 0)
			(size 0.3048 0.381)
			(layers "F.Cu" "F.Mask" "F.Paste")
			(net "P5E_PEX2_STN1_TX_C_DN<29>")
		)
	)
	(footprint ""
		(layer "F.Cu")
		(at 277.996142 -47.20082 90)
		(property "Reference" "C325"
			(at 0 0 90)
			(layer "F.SilkS")
			(hide yes)
			(effects
				(font
					(size 1.27 1.27)
				)
			)
		)
		(property "Value" ""
			(at 0 0 90)
			(layer "F.Fab")
			(effects
				(font
					(size 1.27 1.27)
				)
			)
		)
		(duplicate_pad_numbers_are_jumpers no)
		(fp_line
			(start 0.7874 -0.4064)
			(end 0.7874 0.4064)
			(stroke
				(width 0.1524)
				(type default)
			)
			(layer "F.SilkS")
		)
		(fp_line
			(start -0.7874 -0.4064)
			(end 0.7874 -0.4064)
			(stroke
				(width 0.1524)
				(type default)
			)
			(layer "F.SilkS")
		)
		(fp_line
			(start 0.7874 0.4064)
			(end -0.7874 0.4064)
			(stroke
				(width 0.1524)
				(type default)
			)
			(layer "F.SilkS")
		)
		(fp_line
			(start -0.7874 0.4064)
			(end -0.7874 -0.4064)
			(stroke
				(width 0.1524)
				(type default)
			)
			(layer "F.SilkS")
		)
		(fp_line
			(start -0.12065 -0.305054)
			(end -0.12065 -0.2794)
			(stroke
				(width 0.1)
				(type default)
			)
			(layer "F.Fab")
		)
		(fp_line
			(start -0.67945 -0.305054)
			(end -0.12065 -0.305054)
			(stroke
				(width 0.1)
				(type default)
			)
			(layer "F.Fab")
		)
		(fp_line
			(start 0.67945 -0.3048)
			(end 0.67945 0.3048)
			(stroke
				(width 0.1)
				(type default)
			)
			(layer "F.Fab")
		)
		(fp_line
			(start 0.12065 -0.3048)
			(end 0.67945 -0.3048)
			(stroke
				(width 0.1)
				(type default)
			)
			(layer "F.Fab")
		)
		(fp_line
			(start 0.12065 -0.2794)
			(end 0.12065 -0.3048)
			(stroke
				(width 0.1)
				(type default)
			)
			(layer "F.Fab")
		)
		(fp_line
			(start -0.12065 -0.2794)
			(end 0.12065 -0.2794)
			(stroke
				(width 0.1)
				(type default)
			)
			(layer "F.Fab")
		)
		(fp_line
			(start 0.120396 0.2794)
			(end -0.12065 0.2794)
			(stroke
				(width 0.1)
				(type default)
			)
			(layer "F.Fab")
		)
		(fp_line
			(start -0.12065 0.2794)
			(end -0.12065 0.3048)
			(stroke
				(width 0.1)
				(type default)
			)
			(layer "F.Fab")
		)
		(fp_line
			(start 0.67945 0.3048)
			(end 0.120396 0.3048)
			(stroke
				(width 0.1)
				(type default)
			)
			(layer "F.Fab")
		)
		(fp_line
			(start 0.120396 0.3048)
			(end 0.120396 0.2794)
			(stroke
				(width 0.1)
				(type default)
			)
			(layer "F.Fab")
		)
		(fp_line
			(start -0.12065 0.3048)
			(end -0.67945 0.3048)
			(stroke
				(width 0.1)
				(type default)
			)
			(layer "F.Fab")
		)
		(fp_line
			(start -0.67945 0.3048)
			(end -0.67945 -0.305054)
			(stroke
				(width 0.1)
				(type default)
			)
			(layer "F.Fab")
		)
		(pad "1" smd circle
			(at -0.40005 0 90)
			(size 0 0)
			(layers "F.Cu" "F.Mask" "F.Paste")
			(net "P12V_SSD9_R")
		)
		(pad "2" smd circle
			(at 0.40005 0 90)
			(size 0 0)
			(layers "F.Cu" "F.Mask" "F.Paste")
			(net "GND")
		)
	)
	(footprint ""
		(layer "F.Cu")
		(at 210.419442 -244.016276 -90)
		(property "Reference" "C2707"
			(at 0 0 270)
			(layer "F.SilkS")
			(hide yes)
			(effects
				(font
					(size 1.27 1.27)
				)
			)
		)
		(property "Value" ""
			(at 0 0 270)
			(layer "F.Fab")
			(effects
				(font
					(size 1.27 1.27)
				)
			)
		)
		(duplicate_pad_numbers_are_jumpers no)
		(fp_line
			(start -0.7874 0.4064)
			(end -0.7874 -0.4064)
			(stroke
				(width 0.1524)
				(type default)
			)
			(layer "F.SilkS")
		)
		(fp_line
			(start 0.7874 0.4064)
			(end -0.7874 0.4064)
			(stroke
				(width 0.1524)
				(type default)
			)
			(layer "F.SilkS")
		)
		(fp_line
			(start -0.7874 -0.4064)
			(end 0.7874 -0.4064)
			(stroke
				(width 0.1524)
				(type default)
			)
			(layer "F.SilkS")
		)
		(fp_line
			(start 0.7874 -0.4064)
			(end 0.7874 0.4064)
			(stroke
				(width 0.1524)
				(type default)
			)
			(layer "F.SilkS")
		)
		(fp_line
			(start -0.67945 0.3048)
			(end -0.67945 -0.305054)
			(stroke
				(width 0.1)
				(type default)
			)
			(layer "F.Fab")
		)
		(fp_line
			(start -0.12065 0.3048)
			(end -0.67945 0.3048)
			(stroke
				(width 0.1)
				(type default)
			)
			(layer "F.Fab")
		)
		(fp_line
			(start 0.120396 0.3048)
			(end 0.120396 0.2794)
			(stroke
				(width 0.1)
				(type default)
			)
			(layer "F.Fab")
		)
		(fp_line
			(start 0.67945 0.3048)
			(end 0.120396 0.3048)
			(stroke
				(width 0.1)
				(type default)
			)
			(layer "F.Fab")
		)
		(fp_line
			(start -0.12065 0.2794)
			(end -0.12065 0.3048)
			(stroke
				(width 0.1)
				(type default)
			)
			(layer "F.Fab")
		)
		(fp_line
			(start 0.120396 0.2794)
			(end -0.12065 0.2794)
			(stroke
				(width 0.1)
				(type default)
			)
			(layer "F.Fab")
		)
		(fp_line
			(start -0.12065 -0.2794)
			(end 0.12065 -0.2794)
			(stroke
				(width 0.1)
				(type default)
			)
			(layer "F.Fab")
		)
		(fp_line
			(start 0.12065 -0.2794)
			(end 0.12065 -0.3048)
			(stroke
				(width 0.1)
				(type default)
			)
			(layer "F.Fab")
		)
		(fp_line
			(start 0.12065 -0.3048)
			(end 0.67945 -0.3048)
			(stroke
				(width 0.1)
				(type default)
			)
			(layer "F.Fab")
		)
		(fp_line
			(start 0.67945 -0.3048)
			(end 0.67945 0.3048)
			(stroke
				(width 0.1)
				(type default)
			)
			(layer "F.Fab")
		)
		(fp_line
			(start -0.67945 -0.305054)
			(end -0.12065 -0.305054)
			(stroke
				(width 0.1)
				(type default)
			)
			(layer "F.Fab")
		)
		(fp_line
			(start -0.12065 -0.305054)
			(end -0.12065 -0.2794)
			(stroke
				(width 0.1)
				(type default)
			)
			(layer "F.Fab")
		)
		(pad "1" smd circle
			(at -0.40005 0 270)
			(size 0 0)
			(layers "F.Cu" "F.Mask" "F.Paste")
			(net "GND")
		)
		(pad "2" smd circle
			(at 0.40005 0 270)
			(size 0 0)
			(layers "F.Cu" "F.Mask" "F.Paste")
			(net "P3V3_AUX")
		)
	)
	(footprint ""
		(layer "F.Cu")
		(at 438.328308 -300.64202 -90)
		(property "Reference" "R3989"
			(at 0 0 270)
			(layer "F.SilkS")
			(hide yes)
			(effects
				(font
					(size 1.27 1.27)
				)
			)
		)
		(property "Value" ""
			(at 0 0 270)
			(layer "F.Fab")
			(effects
				(font
					(size 1.27 1.27)
				)
			)
		)
		(duplicate_pad_numbers_are_jumpers no)
		(fp_line
			(start -0.7874 0.4064)
			(end -0.7874 -0.4064)
			(stroke
				(width 0.1524)
				(type default)
			)
			(layer "F.SilkS")
		)
		(fp_line
			(start 0.7874 0.4064)
			(end -0.7874 0.4064)
			(stroke
				(width 0.1524)
				(type default)
			)
			(layer "F.SilkS")
		)
		(fp_line
			(start -0.7874 -0.4064)
			(end 0.7874 -0.4064)
			(stroke
				(width 0.1524)
				(type default)
			)
			(layer "F.SilkS")
		)
		(fp_line
			(start 0.7874 -0.4064)
			(end 0.7874 0.4064)
			(stroke
				(width 0.1524)
				(type default)
			)
			(layer "F.SilkS")
		)
		(fp_line
			(start -0.67945 0.3048)
			(end -0.67945 -0.305054)
			(stroke
				(width 0.1)
				(type default)
			)
			(layer "F.Fab")
		)
		(fp_line
			(start -0.12065 0.3048)
			(end -0.67945 0.3048)
			(stroke
				(width 0.1)
				(type default)
			)
			(layer "F.Fab")
		)
		(fp_line
			(start 0.120396 0.3048)
			(end 0.120396 0.2794)
			(stroke
				(width 0.1)
				(type default)
			)
			(layer "F.Fab")
		)
		(fp_line
			(start 0.67945 0.3048)
			(end 0.120396 0.3048)
			(stroke
				(width 0.1)
				(type default)
			)
			(layer "F.Fab")
		)
		(fp_line
			(start -0.12065 0.2794)
			(end -0.12065 0.3048)
			(stroke
				(width 0.1)
				(type default)
			)
			(layer "F.Fab")
		)
		(fp_line
			(start 0.120396 0.2794)
			(end -0.12065 0.2794)
			(stroke
				(width 0.1)
				(type default)
			)
			(layer "F.Fab")
		)
		(fp_line
			(start -0.12065 -0.2794)
			(end 0.12065 -0.2794)
			(stroke
				(width 0.1)
				(type default)
			)
			(layer "F.Fab")
		)
		(fp_line
			(start 0.12065 -0.2794)
			(end 0.12065 -0.3048)
			(stroke
				(width 0.1)
				(type default)
			)
			(layer "F.Fab")
		)
		(fp_line
			(start 0.12065 -0.3048)
			(end 0.67945 -0.3048)
			(stroke
				(width 0.1)
				(type default)
			)
			(layer "F.Fab")
		)
		(fp_line
			(start 0.67945 -0.3048)
			(end 0.67945 0.3048)
			(stroke
				(width 0.1)
				(type default)
			)
			(layer "F.Fab")
		)
		(fp_line
			(start -0.67945 -0.305054)
			(end -0.12065 -0.305054)
			(stroke
				(width 0.1)
				(type default)
			)
			(layer "F.Fab")
		)
		(fp_line
			(start -0.12065 -0.305054)
			(end -0.12065 -0.2794)
			(stroke
				(width 0.1)
				(type default)
			)
			(layer "F.Fab")
		)
		(pad "1" smd circle
			(at -0.40005 0 270)
			(size 0 0)
			(layers "F.Cu" "F.Mask" "F.Paste")
			(net "I2C0_PEX3_SDA")
		)
		(pad "2" smd circle
			(at 0.40005 0 270)
			(size 0 0)
			(layers "F.Cu" "F.Mask" "F.Paste")
			(net "I2C_PEX3_HOST_SDA")
		)
	)
	(footprint ""
		(layer "F.Cu")
		(at 99.36353 -220.544644 180)
		(property "Reference" "C838"
			(at 0 0 180)
			(layer "F.SilkS")
			(hide yes)
			(effects
				(font
					(size 1.27 1.27)
				)
			)
		)
		(property "Value" ""
			(at 0 0 180)
			(layer "F.Fab")
			(effects
				(font
					(size 1.27 1.27)
				)
			)
		)
		(duplicate_pad_numbers_are_jumpers no)
		(fp_line
			(start 0.7874 0.4064)
			(end -0.7874 0.4064)
			(stroke
				(width 0.1524)
				(type default)
			)
			(layer "F.SilkS")
		)
		(fp_line
			(start 0.7874 -0.4064)
			(end 0.7874 0.4064)
			(stroke
				(width 0.1524)
				(type default)
			)
			(layer "F.SilkS")
		)
		(fp_line
			(start -0.7874 0.4064)
			(end -0.7874 -0.4064)
			(stroke
				(width 0.1524)
				(type default)
			)
			(layer "F.SilkS")
		)
		(fp_line
			(start -0.7874 -0.4064)
			(end 0.7874 -0.4064)
			(stroke
				(width 0.1524)
				(type default)
			)
			(layer "F.SilkS")
		)
		(fp_line
			(start 0.67945 0.3048)
			(end 0.120396 0.3048)
			(stroke
				(width 0.1)
				(type default)
			)
			(layer "F.Fab")
		)
		(fp_line
			(start 0.67945 -0.3048)
			(end 0.67945 0.3048)
			(stroke
				(width 0.1)
				(type default)
			)
			(layer "F.Fab")
		)
		(fp_line
			(start 0.12065 -0.2794)
			(end 0.12065 -0.3048)
			(stroke
				(width 0.1)
				(type default)
			)
			(layer "F.Fab")
		)
		(fp_line
			(start 0.12065 -0.3048)
			(end 0.67945 -0.3048)
			(stroke
				(width 0.1)
				(type default)
			)
			(layer "F.Fab")
		)
		(fp_line
			(start 0.120396 0.3048)
			(end 0.120396 0.2794)
			(stroke
				(width 0.1)
				(type default)
			)
			(layer "F.Fab")
		)
		(fp_line
			(start 0.120396 0.2794)
			(end -0.12065 0.2794)
			(stroke
				(width 0.1)
				(type default)
			)
			(layer "F.Fab")
		)
		(fp_line
			(start -0.12065 0.3048)
			(end -0.67945 0.3048)
			(stroke
				(width 0.1)
				(type default)
			)
			(layer "F.Fab")
		)
		(fp_line
			(start -0.12065 0.2794)
			(end -0.12065 0.3048)
			(stroke
				(width 0.1)
				(type default)
			)
			(layer "F.Fab")
		)
		(fp_line
			(start -0.12065 -0.2794)
			(end 0.12065 -0.2794)
			(stroke
				(width 0.1)
				(type default)
			)
			(layer "F.Fab")
		)
		(fp_line
			(start -0.12065 -0.305054)
			(end -0.12065 -0.2794)
			(stroke
				(width 0.1)
				(type default)
			)
			(layer "F.Fab")
		)
		(fp_line
			(start -0.67945 0.3048)
			(end -0.67945 -0.305054)
			(stroke
				(width 0.1)
				(type default)
			)
			(layer "F.Fab")
		)
		(fp_line
			(start -0.67945 -0.305054)
			(end -0.12065 -0.305054)
			(stroke
				(width 0.1)
				(type default)
			)
			(layer "F.Fab")
		)
		(pad "1" smd circle
			(at -0.40005 0 180)
			(size 0 0)
			(layers "F.Cu" "F.Mask" "F.Paste")
			(net "PWR_EN_PEX_R")
		)
		(pad "2" smd circle
			(at 0.40005 0 180)
			(size 0 0)
			(layers "F.Cu" "F.Mask" "F.Paste")
			(net "GND")
		)
	)
	(footprint ""
		(layer "F.Cu")
		(at 234.965494 -180.68163 -90)
		(property "Reference" "R5494"
			(at 0 0 270)
			(layer "F.SilkS")
			(hide yes)
			(effects
				(font
					(size 1.27 1.27)
				)
			)
		)
		(property "Value" ""
			(at 0 0 270)
			(layer "F.Fab")
			(effects
				(font
					(size 1.27 1.27)
				)
			)
		)
		(duplicate_pad_numbers_are_jumpers no)
		(fp_line
			(start -0.7874 0.4064)
			(end -0.7874 -0.4064)
			(stroke
				(width 0.1524)
				(type default)
			)
			(layer "F.SilkS")
		)
		(fp_line
			(start 0.7874 0.4064)
			(end -0.7874 0.4064)
			(stroke
				(width 0.1524)
				(type default)
			)
			(layer "F.SilkS")
		)
		(fp_line
			(start -0.7874 -0.4064)
			(end 0.7874 -0.4064)
			(stroke
				(width 0.1524)
				(type default)
			)
			(layer "F.SilkS")
		)
		(fp_line
			(start 0.7874 -0.4064)
			(end 0.7874 0.4064)
			(stroke
				(width 0.1524)
				(type default)
			)
			(layer "F.SilkS")
		)
		(fp_line
			(start -0.67945 0.3048)
			(end -0.67945 -0.305054)
			(stroke
				(width 0.1)
				(type default)
			)
			(layer "F.Fab")
		)
		(fp_line
			(start -0.12065 0.3048)
			(end -0.67945 0.3048)
			(stroke
				(width 0.1)
				(type default)
			)
			(layer "F.Fab")
		)
		(fp_line
			(start 0.120396 0.3048)
			(end 0.120396 0.2794)
			(stroke
				(width 0.1)
				(type default)
			)
			(layer "F.Fab")
		)
		(fp_line
			(start 0.67945 0.3048)
			(end 0.120396 0.3048)
			(stroke
				(width 0.1)
				(type default)
			)
			(layer "F.Fab")
		)
		(fp_line
			(start -0.12065 0.2794)
			(end -0.12065 0.3048)
			(stroke
				(width 0.1)
				(type default)
			)
			(layer "F.Fab")
		)
		(fp_line
			(start 0.120396 0.2794)
			(end -0.12065 0.2794)
			(stroke
				(width 0.1)
				(type default)
			)
			(layer "F.Fab")
		)
		(fp_line
			(start -0.12065 -0.2794)
			(end 0.12065 -0.2794)
			(stroke
				(width 0.1)
				(type default)
			)
			(layer "F.Fab")
		)
		(fp_line
			(start 0.12065 -0.2794)
			(end 0.12065 -0.3048)
			(stroke
				(width 0.1)
				(type default)
			)
			(layer "F.Fab")
		)
		(fp_line
			(start 0.12065 -0.3048)
			(end 0.67945 -0.3048)
			(stroke
				(width 0.1)
				(type default)
			)
			(layer "F.Fab")
		)
		(fp_line
			(start 0.67945 -0.3048)
			(end 0.67945 0.3048)
			(stroke
				(width 0.1)
				(type default)
			)
			(layer "F.Fab")
		)
		(fp_line
			(start -0.67945 -0.305054)
			(end -0.12065 -0.305054)
			(stroke
				(width 0.1)
				(type default)
			)
			(layer "F.Fab")
		)
		(fp_line
			(start -0.12065 -0.305054)
			(end -0.12065 -0.2794)
			(stroke
				(width 0.1)
				(type default)
			)
			(layer "F.Fab")
		)
		(pad "1" smd circle
			(at -0.40005 0 270)
			(size 0 0)
			(layers "F.Cu" "F.Mask" "F.Paste")
			(net "RST_BIC_EXTRST_N")
		)
		(pad "2" smd circle
			(at 0.40005 0 270)
			(size 0 0)
			(layers "F.Cu" "F.Mask" "F.Paste")
			(net "RST_BIC_EXTRST_R_N")
		)
	)
	(footprint ""
		(layer "F.Cu")
		(at 265.971782 -24.807418)
		(property "Reference" "R438"
			(at 0 0 0)
			(layer "F.SilkS")
			(hide yes)
			(effects
				(font
					(size 1.27 1.27)
				)
			)
		)
		(property "Value" ""
			(at 0 0 0)
			(layer "F.Fab")
			(effects
				(font
					(size 1.27 1.27)
				)
			)
		)
		(duplicate_pad_numbers_are_jumpers no)
		(fp_line
			(start -0.7874 -0.4064)
			(end 0.7874 -0.4064)
			(stroke
				(width 0.1524)
				(type default)
			)
			(layer "F.SilkS")
		)
		(fp_line
			(start -0.7874 0.4064)
			(end -0.7874 -0.4064)
			(stroke
				(width 0.1524)
				(type default)
			)
			(layer "F.SilkS")
		)
		(fp_line
			(start 0.7874 -0.4064)
			(end 0.7874 0.4064)
			(stroke
				(width 0.1524)
				(type default)
			)
			(layer "F.SilkS")
		)
		(fp_line
			(start 0.7874 0.4064)
			(end -0.7874 0.4064)
			(stroke
				(width 0.1524)
				(type default)
			)
			(layer "F.SilkS")
		)
		(fp_line
			(start -0.67945 -0.305054)
			(end -0.12065 -0.305054)
			(stroke
				(width 0.1)
				(type default)
			)
			(layer "F.Fab")
		)
		(fp_line
			(start -0.67945 0.3048)
			(end -0.67945 -0.305054)
			(stroke
				(width 0.1)
				(type default)
			)
			(layer "F.Fab")
		)
		(fp_line
			(start -0.12065 -0.305054)
			(end -0.12065 -0.2794)
			(stroke
				(width 0.1)
				(type default)
			)
			(layer "F.Fab")
		)
		(fp_line
			(start -0.12065 -0.2794)
			(end 0.12065 -0.2794)
			(stroke
				(width 0.1)
				(type default)
			)
			(layer "F.Fab")
		)
		(fp_line
			(start -0.12065 0.2794)
			(end -0.12065 0.3048)
			(stroke
				(width 0.1)
				(type default)
			)
			(layer "F.Fab")
		)
		(fp_line
			(start -0.12065 0.3048)
			(end -0.67945 0.3048)
			(stroke
				(width 0.1)
				(type default)
			)
			(layer "F.Fab")
		)
		(fp_line
			(start 0.120396 0.2794)
			(end -0.12065 0.2794)
			(stroke
				(width 0.1)
				(type default)
			)
			(layer "F.Fab")
		)
		(fp_line
			(start 0.120396 0.3048)
			(end 0.120396 0.2794)
			(stroke
				(width 0.1)
				(type default)
			)
			(layer "F.Fab")
		)
		(fp_line
			(start 0.12065 -0.3048)
			(end 0.67945 -0.3048)
			(stroke
				(width 0.1)
				(type default)
			)
			(layer "F.Fab")
		)
		(fp_line
			(start 0.12065 -0.2794)
			(end 0.12065 -0.3048)
			(stroke
				(width 0.1)
				(type default)
			)
			(layer "F.Fab")
		)
		(fp_line
			(start 0.67945 -0.3048)
			(end 0.67945 0.3048)
			(stroke
				(width 0.1)
				(type default)
			)
			(layer "F.Fab")
		)
		(fp_line
			(start 0.67945 0.3048)
			(end 0.120396 0.3048)
			(stroke
				(width 0.1)
				(type default)
			)
			(layer "F.Fab")
		)
		(pad "1" smd circle
			(at -0.40005 0)
			(size 0 0)
			(layers "F.Cu" "F.Mask" "F.Paste")
			(net "P3V3_SSD9")
		)
		(pad "2" smd circle
			(at 0.40005 0)
			(size 0 0)
			(layers "F.Cu" "F.Mask" "F.Paste")
			(net "PU_CLKREQ9")
		)
	)
	(footprint ""
		(layer "F.Cu")
		(at 64.455802 -343.952322 90)
		(property "Reference" "C125"
			(at 0 0 90)
			(layer "F.SilkS")
			(hide yes)
			(effects
				(font
					(size 1.27 1.27)
				)
			)
		)
		(property "Value" ""
			(at 0 0 90)
			(layer "F.Fab")
			(effects
				(font
					(size 1.27 1.27)
				)
			)
		)
		(duplicate_pad_numbers_are_jumpers no)
		(fp_line
			(start 0.299974 -0.150114)
			(end 0.299974 0.150114)
			(stroke
				(width 0.1)
				(type default)
			)
			(layer "F.Fab")
		)
		(fp_line
			(start -0.299974 -0.150114)
			(end 0.299974 -0.150114)
			(stroke
				(width 0.1)
				(type default)
			)
			(layer "F.Fab")
		)
		(fp_line
			(start 0.299974 0.150114)
			(end -0.299974 0.150114)
			(stroke
				(width 0.1)
				(type default)
			)
			(layer "F.Fab")
		)
		(fp_line
			(start -0.299974 0.150114)
			(end -0.299974 -0.150114)
			(stroke
				(width 0.1)
				(type default)
			)
			(layer "F.Fab")
		)
		(pad "1" smd rect
			(at -0.2667 0 90)
			(size 0.3048 0.381)
			(layers "F.Cu" "F.Mask" "F.Paste")
			(net "P5E_PEX0_STN5_TX_DP<81>")
		)
		(pad "2" smd rect
			(at 0.2667 0 90)
			(size 0.3048 0.381)
			(layers "F.Cu" "F.Mask" "F.Paste")
			(net "P5E_PEX0_STN5_TX_C_DP<81>")
		)
	)
	(footprint ""
		(layer "F.Cu")
		(at 336.931 -234.061 -90)
		(property "Reference" "R3546"
			(at 0 0 270)
			(layer "F.SilkS")
			(hide yes)
			(effects
				(font
					(size 1.27 1.27)
				)
			)
		)
		(property "Value" ""
			(at 0 0 270)
			(layer "F.Fab")
			(effects
				(font
					(size 1.27 1.27)
				)
			)
		)
		(duplicate_pad_numbers_are_jumpers no)
		(fp_line
			(start -0.7874 0.4064)
			(end -0.7874 -0.4064)
			(stroke
				(width 0.1524)
				(type default)
			)
			(layer "F.SilkS")
		)
		(fp_line
			(start 0.7874 0.4064)
			(end -0.7874 0.4064)
			(stroke
				(width 0.1524)
				(type default)
			)
			(layer "F.SilkS")
		)
		(fp_line
			(start -0.7874 -0.4064)
			(end 0.7874 -0.4064)
			(stroke
				(width 0.1524)
				(type default)
			)
			(layer "F.SilkS")
		)
		(fp_line
			(start 0.7874 -0.4064)
			(end 0.7874 0.4064)
			(stroke
				(width 0.1524)
				(type default)
			)
			(layer "F.SilkS")
		)
		(fp_line
			(start -0.67945 0.3048)
			(end -0.67945 -0.305054)
			(stroke
				(width 0.1)
				(type default)
			)
			(layer "F.Fab")
		)
		(fp_line
			(start -0.12065 0.3048)
			(end -0.67945 0.3048)
			(stroke
				(width 0.1)
				(type default)
			)
			(layer "F.Fab")
		)
		(fp_line
			(start 0.120396 0.3048)
			(end 0.120396 0.2794)
			(stroke
				(width 0.1)
				(type default)
			)
			(layer "F.Fab")
		)
		(fp_line
			(start 0.67945 0.3048)
			(end 0.120396 0.3048)
			(stroke
				(width 0.1)
				(type default)
			)
			(layer "F.Fab")
		)
		(fp_line
			(start -0.12065 0.2794)
			(end -0.12065 0.3048)
			(stroke
				(width 0.1)
				(type default)
			)
			(layer "F.Fab")
		)
		(fp_line
			(start 0.120396 0.2794)
			(end -0.12065 0.2794)
			(stroke
				(width 0.1)
				(type default)
			)
			(layer "F.Fab")
		)
		(fp_line
			(start -0.12065 -0.2794)
			(end 0.12065 -0.2794)
			(stroke
				(width 0.1)
				(type default)
			)
			(layer "F.Fab")
		)
		(fp_line
			(start 0.12065 -0.2794)
			(end 0.12065 -0.3048)
			(stroke
				(width 0.1)
				(type default)
			)
			(layer "F.Fab")
		)
		(fp_line
			(start 0.12065 -0.3048)
			(end 0.67945 -0.3048)
			(stroke
				(width 0.1)
				(type default)
			)
			(layer "F.Fab")
		)
		(fp_line
			(start 0.67945 -0.3048)
			(end 0.67945 0.3048)
			(stroke
				(width 0.1)
				(type default)
			)
			(layer "F.Fab")
		)
		(fp_line
			(start -0.67945 -0.305054)
			(end -0.12065 -0.305054)
			(stroke
				(width 0.1)
				(type default)
			)
			(layer "F.Fab")
		)
		(fp_line
			(start -0.12065 -0.305054)
			(end -0.12065 -0.2794)
			(stroke
				(width 0.1)
				(type default)
			)
			(layer "F.Fab")
		)
		(pad "1" smd circle
			(at -0.40005 0 270)
			(size 0 0)
			(layers "F.Cu" "F.Mask" "F.Paste")
			(net "SYS_PWR_READY_R_N")
		)
		(pad "2" smd circle
			(at 0.40005 0 270)
			(size 0 0)
			(layers "F.Cu" "F.Mask" "F.Paste")
			(net "SYS_PWR_READY_N")
		)
	)
	(footprint ""
		(layer "F.Cu")
		(at 260.540246 -77.279754 -90)
		(property "Reference" "R1079"
			(at 0 0 270)
			(layer "F.SilkS")
			(hide yes)
			(effects
				(font
					(size 1.27 1.27)
				)
			)
		)
		(property "Value" ""
			(at 0 0 270)
			(layer "F.Fab")
			(effects
				(font
					(size 1.27 1.27)
				)
			)
		)
		(duplicate_pad_numbers_are_jumpers no)
		(fp_line
			(start -0.7874 0.4064)
			(end -0.7874 -0.4064)
			(stroke
				(width 0.1524)
				(type default)
			)
			(layer "F.SilkS")
		)
		(fp_line
			(start 0.7874 0.4064)
			(end -0.7874 0.4064)
			(stroke
				(width 0.1524)
				(type default)
			)
			(layer "F.SilkS")
		)
		(fp_line
			(start -0.7874 -0.4064)
			(end 0.7874 -0.4064)
			(stroke
				(width 0.1524)
				(type default)
			)
			(layer "F.SilkS")
		)
		(fp_line
			(start 0.7874 -0.4064)
			(end 0.7874 0.4064)
			(stroke
				(width 0.1524)
				(type default)
			)
			(layer "F.SilkS")
		)
		(fp_line
			(start -0.67945 0.3048)
			(end -0.67945 -0.305054)
			(stroke
				(width 0.1)
				(type default)
			)
			(layer "F.Fab")
		)
		(fp_line
			(start -0.12065 0.3048)
			(end -0.67945 0.3048)
			(stroke
				(width 0.1)
				(type default)
			)
			(layer "F.Fab")
		)
		(fp_line
			(start 0.120396 0.3048)
			(end 0.120396 0.2794)
			(stroke
				(width 0.1)
				(type default)
			)
			(layer "F.Fab")
		)
		(fp_line
			(start 0.67945 0.3048)
			(end 0.120396 0.3048)
			(stroke
				(width 0.1)
				(type default)
			)
			(layer "F.Fab")
		)
		(fp_line
			(start -0.12065 0.2794)
			(end -0.12065 0.3048)
			(stroke
				(width 0.1)
				(type default)
			)
			(layer "F.Fab")
		)
		(fp_line
			(start 0.120396 0.2794)
			(end -0.12065 0.2794)
			(stroke
				(width 0.1)
				(type default)
			)
			(layer "F.Fab")
		)
		(fp_line
			(start -0.12065 -0.2794)
			(end 0.12065 -0.2794)
			(stroke
				(width 0.1)
				(type default)
			)
			(layer "F.Fab")
		)
		(fp_line
			(start 0.12065 -0.2794)
			(end 0.12065 -0.3048)
			(stroke
				(width 0.1)
				(type default)
			)
			(layer "F.Fab")
		)
		(fp_line
			(start 0.12065 -0.3048)
			(end 0.67945 -0.3048)
			(stroke
				(width 0.1)
				(type default)
			)
			(layer "F.Fab")
		)
		(fp_line
			(start 0.67945 -0.3048)
			(end 0.67945 0.3048)
			(stroke
				(width 0.1)
				(type default)
			)
			(layer "F.Fab")
		)
		(fp_line
			(start -0.67945 -0.305054)
			(end -0.12065 -0.305054)
			(stroke
				(width 0.1)
				(type default)
			)
			(layer "F.Fab")
		)
		(fp_line
			(start -0.12065 -0.305054)
			(end -0.12065 -0.2794)
			(stroke
				(width 0.1)
				(type default)
			)
			(layer "F.Fab")
		)
		(pad "1" smd circle
			(at -0.40005 0 270)
			(size 0 0)
			(layers "F.Cu" "F.Mask" "F.Paste")
			(net "CLK_GEN_CK440_OE4_N")
		)
		(pad "2" smd circle
			(at 0.40005 0 270)
			(size 0 0)
			(layers "F.Cu" "F.Mask" "F.Paste")
			(net "P3V3")
		)
	)
	(footprint ""
		(layer "F.Cu")
		(at 240.35258 -223.066864 180)
		(property "Reference" "R4855"
			(at 0 0 180)
			(layer "F.SilkS")
			(hide yes)
			(effects
				(font
					(size 1.27 1.27)
				)
			)
		)
		(property "Value" ""
			(at 0 0 180)
			(layer "F.Fab")
			(effects
				(font
					(size 1.27 1.27)
				)
			)
		)
		(duplicate_pad_numbers_are_jumpers no)
		(fp_line
			(start 0.7874 0.4064)
			(end -0.7874 0.4064)
			(stroke
				(width 0.1524)
				(type default)
			)
			(layer "F.SilkS")
		)
		(fp_line
			(start 0.7874 -0.4064)
			(end 0.7874 0.4064)
			(stroke
				(width 0.1524)
				(type default)
			)
			(layer "F.SilkS")
		)
		(fp_line
			(start -0.7874 0.4064)
			(end -0.7874 -0.4064)
			(stroke
				(width 0.1524)
				(type default)
			)
			(layer "F.SilkS")
		)
		(fp_line
			(start -0.7874 -0.4064)
			(end 0.7874 -0.4064)
			(stroke
				(width 0.1524)
				(type default)
			)
			(layer "F.SilkS")
		)
		(fp_line
			(start 0.67945 0.3048)
			(end 0.120396 0.3048)
			(stroke
				(width 0.1)
				(type default)
			)
			(layer "F.Fab")
		)
		(fp_line
			(start 0.67945 -0.3048)
			(end 0.67945 0.3048)
			(stroke
				(width 0.1)
				(type default)
			)
			(layer "F.Fab")
		)
		(fp_line
			(start 0.12065 -0.2794)
			(end 0.12065 -0.3048)
			(stroke
				(width 0.1)
				(type default)
			)
			(layer "F.Fab")
		)
		(fp_line
			(start 0.12065 -0.3048)
			(end 0.67945 -0.3048)
			(stroke
				(width 0.1)
				(type default)
			)
			(layer "F.Fab")
		)
		(fp_line
			(start 0.120396 0.3048)
			(end 0.120396 0.2794)
			(stroke
				(width 0.1)
				(type default)
			)
			(layer "F.Fab")
		)
		(fp_line
			(start 0.120396 0.2794)
			(end -0.12065 0.2794)
			(stroke
				(width 0.1)
				(type default)
			)
			(layer "F.Fab")
		)
		(fp_line
			(start -0.12065 0.3048)
			(end -0.67945 0.3048)
			(stroke
				(width 0.1)
				(type default)
			)
			(layer "F.Fab")
		)
		(fp_line
			(start -0.12065 0.2794)
			(end -0.12065 0.3048)
			(stroke
				(width 0.1)
				(type default)
			)
			(layer "F.Fab")
		)
		(fp_line
			(start -0.12065 -0.2794)
			(end 0.12065 -0.2794)
			(stroke
				(width 0.1)
				(type default)
			)
			(layer "F.Fab")
		)
		(fp_line
			(start -0.12065 -0.305054)
			(end -0.12065 -0.2794)
			(stroke
				(width 0.1)
				(type default)
			)
			(layer "F.Fab")
		)
		(fp_line
			(start -0.67945 0.3048)
			(end -0.67945 -0.305054)
			(stroke
				(width 0.1)
				(type default)
			)
			(layer "F.Fab")
		)
		(fp_line
			(start -0.67945 -0.305054)
			(end -0.12065 -0.305054)
			(stroke
				(width 0.1)
				(type default)
			)
			(layer "F.Fab")
		)
		(pad "1" smd circle
			(at -0.40005 0 180)
			(size 0 0)
			(layers "F.Cu" "F.Mask" "F.Paste")
			(net "P1V2_AUX")
		)
		(pad "2" smd circle
			(at 0.40005 0 180)
			(size 0 0)
			(layers "F.Cu" "F.Mask" "F.Paste")
			(net "P1V2_BIC_ADCVREFREXT1")
		)
	)
	(footprint ""
		(layer "F.Cu")
		(at 113.970816 -126.654814)
		(property "Reference" "PU21"
			(at -0.827024 2.31521 0)
			(unlocked yes)
			(layer "F.SilkS")
			(effects
				(font
					(size 0.7874 0.5842)
					(thickness 0.1524)
				)
				(justify left)
			)
		)
		(property "Value" ""
			(at 0 0 0)
			(layer "F.Fab")
			(effects
				(font
					(size 1.27 1.27)
				)
			)
		)
		(duplicate_pad_numbers_are_jumpers no)
		(fp_line
			(start -1.943608 -1.549908)
			(end 1.943608 -1.549908)
			(stroke
				(width 0.1524)
				(type default)
			)
			(layer "F.SilkS")
		)
		(fp_line
			(start -1.943608 1.549908)
			(end -1.943608 -1.549908)
			(stroke
				(width 0.1524)
				(type default)
			)
			(layer "F.SilkS")
		)
		(fp_line
			(start 1.943608 -1.549908)
			(end 1.943608 1.549908)
			(stroke
				(width 0.1524)
				(type default)
			)
			(layer "F.SilkS")
		)
		(fp_line
			(start 1.943608 1.549908)
			(end -1.943608 1.549908)
			(stroke
				(width 0.1524)
				(type default)
			)
			(layer "F.SilkS")
		)
		(fp_poly
			(pts
				(xy -2.019808 -1.549908) (xy -1.257808 -1.549908) (xy -1.257808 -1.880108) (xy -2.019808 -1.880108)
			)
			(stroke
				(width 0)
				(type default)
			)
			(fill yes)
			(layer "F.SilkS")
		)
		(fp_line
			(start -1.549908 -1.549908)
			(end 1.549908 -1.549908)
			(stroke
				(width 0.1)
				(type default)
			)
			(layer "F.Fab")
		)
		(fp_line
			(start -1.549908 1.549908)
			(end -1.549908 -1.549908)
			(stroke
				(width 0.1)
				(type default)
			)
			(layer "F.Fab")
		)
		(fp_line
			(start 1.549908 -1.549908)
			(end 1.549908 1.549908)
			(stroke
				(width 0.1)
				(type default)
			)
			(layer "F.Fab")
		)
		(fp_line
			(start 1.549908 1.549908)
			(end -1.549908 1.549908)
			(stroke
				(width 0.1)
				(type default)
			)
			(layer "F.Fab")
		)
		(fp_poly
			(pts
				(xy -2.019808 -1.549908) (xy -1.257808 -1.549908) (xy -1.257808 -1.880108) (xy -2.019808 -1.880108)
			)
			(stroke
				(width 0)
				(type default)
			)
			(fill yes)
			(layer "F.Fab")
		)
		(pad "1" smd rect
			(at -1.500124 -1.249934 270)
			(size 0.2794 0.6096)
			(layers "F.Cu" "F.Mask" "F.Paste")
			(net "P3V3")
		)
		(pad "2" smd rect
			(at -1.500124 -0.750062 270)
			(size 0.2794 0.6096)
			(layers "F.Cu" "F.Mask" "F.Paste")
			(net "P3V3")
		)
		(pad "3" smd rect
			(at -1.500124 -0.249936 270)
			(size 0.2794 0.6096)
			(layers "F.Cu" "F.Mask" "F.Paste")
			(net "P3V3")
		)
		(pad "4" smd rect
			(at -1.500124 0.249936 270)
			(size 0.2794 0.6096)
			(layers "F.Cu" "F.Mask" "F.Paste")
			(net "P3V3")
		)
		(pad "5" smd rect
			(at -1.500124 0.750062 270)
			(size 0.2794 0.6096)
			(layers "F.Cu" "F.Mask" "F.Paste")
			(net "P3V3")
		)
		(pad "6" smd rect
			(at -1.500124 1.249934 270)
			(size 0.2794 0.6096)
			(layers "F.Cu" "F.Mask" "F.Paste")
			(net "GND")
		)
		(pad "7" smd rect
			(at 1.500124 1.249934 270)
			(size 0.2794 0.6096)
			(layers "F.Cu" "F.Mask" "F.Paste")
			(net "P3V3_SS")
		)
		(pad "8" smd rect
			(at 1.500124 0.750062 270)
			(size 0.2794 0.6096)
			(layers "F.Cu" "F.Mask" "F.Paste")
			(net "PWRGD_P3V3")
		)
		(pad "9" smd rect
			(at 1.500124 0.249936 270)
			(size 0.2794 0.6096)
			(layers "F.Cu" "F.Mask" "F.Paste")
			(net "P3V3_OCP")
		)
		(pad "10" smd rect
			(at 1.500124 -0.249936 270)
			(size 0.2794 0.6096)
			(layers "F.Cu" "F.Mask" "F.Paste")
			(net "P5V_AUX")
		)
		(pad "11" smd rect
			(at 1.500124 -0.750062 270)
			(size 0.2794 0.6096)
			(layers "F.Cu" "F.Mask" "F.Paste")
			(net "PWR_EN_P3V3_R")
		)
		(pad "12" smd rect
			(at 1.500124 -1.249934 270)
			(size 0.2794 0.6096)
			(layers "F.Cu" "F.Mask" "F.Paste")
			(net "P3V3_AUX")
		)
		(pad "13" smd rect
			(at 0 0)
			(size 1.9812 2.7178)
			(layers "F.Cu" "F.Mask" "F.Paste")
			(net "P3V3_AUX")
		)
		(zone
			(layer "F.Cu")
			(hatch none 0.5)
			(connect_pads
				(clearance 0)
			)
			(min_thickness 0.25)
			(keepout
				(tracks not_allowed)
				(vias allowed)
				(pads allowed)
				(copperpour not_allowed)
				(footprints allowed)
			)
			(placement
				(enabled no)
				(sheetname "")
			)
			(fill
				(thermal_gap 0.5)
				(thermal_bridge_width 0.5)
				(island_removal_mode 0)
			)
			(polygon
				(pts
					(xy 115.113816 -128.204214) (xy 115.113816 -128.077214) (xy 115.113816 -125.105414) (xy 115.113816 -125.104906)
					(xy 112.827816 -125.104906) (xy 112.827816 -125.105414) (xy 112.827816 -125.232414) (xy 112.827816 -126.654814)
					(xy 112.929416 -126.654814) (xy 112.929416 -125.232414) (xy 115.012216 -125.232414) (xy 115.012216 -128.077214)
					(xy 112.929416 -128.077214) (xy 112.929416 -126.680214) (xy 112.827816 -126.680214) (xy 112.827816 -128.077214)
					(xy 112.827816 -128.204214) (xy 112.827816 -128.204722) (xy 115.113816 -128.204722)
				)
			)
		)
	)
	(footprint ""
		(layer "F.Cu")
		(at 129.403856 -170.599862 90)
		(property "Reference" "R1091"
			(at 0 0 90)
			(layer "F.SilkS")
			(hide yes)
			(effects
				(font
					(size 1.27 1.27)
				)
			)
		)
		(property "Value" ""
			(at 0 0 90)
			(layer "F.Fab")
			(effects
				(font
					(size 1.27 1.27)
				)
			)
		)
		(duplicate_pad_numbers_are_jumpers no)
		(fp_line
			(start 0.7874 0.4064)
			(end -0.7874 0.4064)
			(stroke
				(width 0.1524)
				(type default)
			)
			(layer "F.SilkS")
		)
		(fp_line
			(start -0.12065 -0.305054)
			(end -0.12065 -0.2794)
			(stroke
				(width 0.1)
				(type default)
			)
			(layer "F.Fab")
		)
		(fp_line
			(start -0.67945 -0.305054)
			(end -0.12065 -0.305054)
			(stroke
				(width 0.1)
				(type default)
			)
			(layer "F.Fab")
		)
		(fp_line
			(start 0.67945 -0.3048)
			(end 0.67945 0.3048)
			(stroke
				(width 0.1)
				(type default)
			)
			(layer "F.Fab")
		)
		(fp_line
			(start 0.12065 -0.3048)
			(end 0.67945 -0.3048)
			(stroke
				(width 0.1)
				(type default)
			)
			(layer "F.Fab")
		)
		(fp_line
			(start 0.12065 -0.2794)
			(end 0.12065 -0.3048)
			(stroke
				(width 0.1)
				(type default)
			)
			(layer "F.Fab")
		)
		(fp_line
			(start -0.12065 -0.2794)
			(end 0.12065 -0.2794)
			(stroke
				(width 0.1)
				(type default)
			)
			(layer "F.Fab")
		)
		(fp_line
			(start 0.120396 0.2794)
			(end -0.12065 0.2794)
			(stroke
				(width 0.1)
				(type default)
			)
			(layer "F.Fab")
		)
		(fp_line
			(start -0.12065 0.2794)
			(end -0.12065 0.3048)
			(stroke
				(width 0.1)
				(type default)
			)
			(layer "F.Fab")
		)
		(fp_line
			(start 0.67945 0.3048)
			(end 0.120396 0.3048)
			(stroke
				(width 0.1)
				(type default)
			)
			(layer "F.Fab")
		)
		(fp_line
			(start 0.120396 0.3048)
			(end 0.120396 0.2794)
			(stroke
				(width 0.1)
				(type default)
			)
			(layer "F.Fab")
		)
		(fp_line
			(start -0.12065 0.3048)
			(end -0.67945 0.3048)
			(stroke
				(width 0.1)
				(type default)
			)
			(layer "F.Fab")
		)
		(fp_line
			(start -0.67945 0.3048)
			(end -0.67945 -0.305054)
			(stroke
				(width 0.1)
				(type default)
			)
			(layer "F.Fab")
		)
		(pad "1" smd circle
			(at -0.40005 0 90)
			(size 0 0)
			(layers "F.Cu" "F.Mask" "F.Paste")
			(net "CLK_100M_DB2000QL_PEX2_S1_R_DN")
		)
		(pad "2" smd circle
			(at 0.40005 0 90)
			(size 0 0)
			(layers "F.Cu" "F.Mask" "F.Paste")
			(net "CLK_100M_DB2000QL_PEX2_S1_DN")
		)
	)
	(footprint ""
		(layer "F.Cu")
		(at 359.156 -179.07 180)
		(property "Reference" "R4676"
			(at 0 0 180)
			(layer "F.SilkS")
			(hide yes)
			(effects
				(font
					(size 1.27 1.27)
				)
			)
		)
		(property "Value" ""
			(at 0 0 180)
			(layer "F.Fab")
			(effects
				(font
					(size 1.27 1.27)
				)
			)
		)
		(duplicate_pad_numbers_are_jumpers no)
		(fp_line
			(start 0.7874 0.4064)
			(end -0.7874 0.4064)
			(stroke
				(width 0.1524)
				(type default)
			)
			(layer "F.SilkS")
		)
		(fp_line
			(start 0.7874 -0.4064)
			(end 0.7874 0.4064)
			(stroke
				(width 0.1524)
				(type default)
			)
			(layer "F.SilkS")
		)
		(fp_line
			(start -0.7874 0.4064)
			(end -0.7874 -0.4064)
			(stroke
				(width 0.1524)
				(type default)
			)
			(layer "F.SilkS")
		)
		(fp_line
			(start -0.7874 -0.4064)
			(end 0.7874 -0.4064)
			(stroke
				(width 0.1524)
				(type default)
			)
			(layer "F.SilkS")
		)
		(fp_line
			(start 0.67945 0.3048)
			(end 0.120396 0.3048)
			(stroke
				(width 0.1)
				(type default)
			)
			(layer "F.Fab")
		)
		(fp_line
			(start 0.67945 -0.3048)
			(end 0.67945 0.3048)
			(stroke
				(width 0.1)
				(type default)
			)
			(layer "F.Fab")
		)
		(fp_line
			(start 0.12065 -0.2794)
			(end 0.12065 -0.3048)
			(stroke
				(width 0.1)
				(type default)
			)
			(layer "F.Fab")
		)
		(fp_line
			(start 0.12065 -0.3048)
			(end 0.67945 -0.3048)
			(stroke
				(width 0.1)
				(type default)
			)
			(layer "F.Fab")
		)
		(fp_line
			(start 0.120396 0.3048)
			(end 0.120396 0.2794)
			(stroke
				(width 0.1)
				(type default)
			)
			(layer "F.Fab")
		)
		(fp_line
			(start 0.120396 0.2794)
			(end -0.12065 0.2794)
			(stroke
				(width 0.1)
				(type default)
			)
			(layer "F.Fab")
		)
		(fp_line
			(start -0.12065 0.3048)
			(end -0.67945 0.3048)
			(stroke
				(width 0.1)
				(type default)
			)
			(layer "F.Fab")
		)
		(fp_line
			(start -0.12065 0.2794)
			(end -0.12065 0.3048)
			(stroke
				(width 0.1)
				(type default)
			)
			(layer "F.Fab")
		)
		(fp_line
			(start -0.12065 -0.2794)
			(end 0.12065 -0.2794)
			(stroke
				(width 0.1)
				(type default)
			)
			(layer "F.Fab")
		)
		(fp_line
			(start -0.12065 -0.305054)
			(end -0.12065 -0.2794)
			(stroke
				(width 0.1)
				(type default)
			)
			(layer "F.Fab")
		)
		(fp_line
			(start -0.67945 0.3048)
			(end -0.67945 -0.305054)
			(stroke
				(width 0.1)
				(type default)
			)
			(layer "F.Fab")
		)
		(fp_line
			(start -0.67945 -0.305054)
			(end -0.12065 -0.305054)
			(stroke
				(width 0.1)
				(type default)
			)
			(layer "F.Fab")
		)
		(pad "1" smd circle
			(at -0.40005 0 180)
			(size 0 0)
			(layers "F.Cu" "F.Mask" "F.Paste")
			(net "SSD6_PEX_PWR_EN_R")
		)
		(pad "2" smd circle
			(at 0.40005 0 180)
			(size 0 0)
			(layers "F.Cu" "F.Mask" "F.Paste")
			(net "GND")
		)
	)
	(footprint ""
		(layer "F.Cu")
		(at 379.950218 -50.96383 180)
		(property "Reference" "PC563"
			(at 0 0 180)
			(layer "F.SilkS")
			(hide yes)
			(effects
				(font
					(size 1.27 1.27)
				)
			)
		)
		(property "Value" ""
			(at 0 0 180)
			(layer "F.Fab")
			(effects
				(font
					(size 1.27 1.27)
				)
			)
		)
		(duplicate_pad_numbers_are_jumpers no)
		(fp_line
			(start 1.524 0.762)
			(end -1.524 0.762)
			(stroke
				(width 0.1524)
				(type default)
			)
			(layer "F.SilkS")
		)
		(fp_line
			(start 1.524 -0.762)
			(end 1.524 0.762)
			(stroke
				(width 0.1524)
				(type default)
			)
			(layer "F.SilkS")
		)
		(fp_line
			(start -1.524 0.762)
			(end -1.524 -0.762)
			(stroke
				(width 0.1524)
				(type default)
			)
			(layer "F.SilkS")
		)
		(fp_line
			(start -1.524 -0.762)
			(end 1.524 -0.762)
			(stroke
				(width 0.1524)
				(type default)
			)
			(layer "F.SilkS")
		)
		(fp_line
			(start 1.1049 0.724916)
			(end 1.1049 -0.724916)
			(stroke
				(width 0.1)
				(type default)
			)
			(layer "F.Fab")
		)
		(fp_line
			(start 1.1049 -0.724916)
			(end -1.1049 -0.724916)
			(stroke
				(width 0.1)
				(type default)
			)
			(layer "F.Fab")
		)
		(fp_line
			(start -1.1049 0.724916)
			(end 1.1049 0.724916)
			(stroke
				(width 0.1)
				(type default)
			)
			(layer "F.Fab")
		)
		(fp_line
			(start -1.1049 -0.724916)
			(end -1.1049 0.724916)
			(stroke
				(width 0.1)
				(type default)
			)
			(layer "F.Fab")
		)
		(pad "1" smd rect
			(at -0.889 0)
			(size 1.016 1.27)
			(layers "F.Cu" "F.Mask" "F.Paste")
			(net "P3V3_SSD13")
		)
		(pad "2" smd rect
			(at 0.889 0)
			(size 1.016 1.27)
			(layers "F.Cu" "F.Mask" "F.Paste")
			(net "GND")
		)
	)
	(footprint ""
		(layer "F.Cu")
		(at 312.21934 -142.590266 180)
		(property "Reference" "C438"
			(at 0 0 180)
			(layer "F.SilkS")
			(hide yes)
			(effects
				(font
					(size 1.27 1.27)
				)
			)
		)
		(property "Value" ""
			(at 0 0 180)
			(layer "F.Fab")
			(effects
				(font
					(size 1.27 1.27)
				)
			)
		)
		(duplicate_pad_numbers_are_jumpers no)
		(fp_line
			(start 0.299974 0.150114)
			(end -0.299974 0.150114)
			(stroke
				(width 0.1)
				(type default)
			)
			(layer "F.Fab")
		)
		(fp_line
			(start 0.299974 -0.150114)
			(end 0.299974 0.150114)
			(stroke
				(width 0.1)
				(type default)
			)
			(layer "F.Fab")
		)
		(fp_line
			(start -0.299974 0.150114)
			(end -0.299974 -0.150114)
			(stroke
				(width 0.1)
				(type default)
			)
			(layer "F.Fab")
		)
		(fp_line
			(start -0.299974 -0.150114)
			(end 0.299974 -0.150114)
			(stroke
				(width 0.1)
				(type default)
			)
			(layer "F.Fab")
		)
		(pad "1" smd rect
			(at -0.2667 0 180)
			(size 0.3048 0.381)
			(layers "F.Cu" "F.Mask" "F.Paste")
			(net "P5E_PEX2_STN0_TX_DN<8>")
		)
		(pad "2" smd rect
			(at 0.2667 0 180)
			(size 0.3048 0.381)
			(layers "F.Cu" "F.Mask" "F.Paste")
			(net "P5E_PEX2_STN0_TX_C_DN<8>")
		)
	)
	(footprint ""
		(layer "F.Cu")
		(at 147.554442 -252.356874 -90)
		(property "Reference" "R1293"
			(at 0 0 270)
			(layer "F.SilkS")
			(hide yes)
			(effects
				(font
					(size 1.27 1.27)
				)
			)
		)
		(property "Value" ""
			(at 0 0 270)
			(layer "F.Fab")
			(effects
				(font
					(size 1.27 1.27)
				)
			)
		)
		(duplicate_pad_numbers_are_jumpers no)
		(fp_line
			(start -0.7874 0.4064)
			(end -0.7874 -0.4064)
			(stroke
				(width 0.1524)
				(type default)
			)
			(layer "F.SilkS")
		)
		(fp_line
			(start 0.7874 0.4064)
			(end -0.7874 0.4064)
			(stroke
				(width 0.1524)
				(type default)
			)
			(layer "F.SilkS")
		)
		(fp_line
			(start -0.7874 -0.4064)
			(end 0.7874 -0.4064)
			(stroke
				(width 0.1524)
				(type default)
			)
			(layer "F.SilkS")
		)
		(fp_line
			(start 0.7874 -0.4064)
			(end 0.7874 0.4064)
			(stroke
				(width 0.1524)
				(type default)
			)
			(layer "F.SilkS")
		)
		(fp_line
			(start -0.67945 0.3048)
			(end -0.67945 -0.305054)
			(stroke
				(width 0.1)
				(type default)
			)
			(layer "F.Fab")
		)
		(fp_line
			(start -0.12065 0.3048)
			(end -0.67945 0.3048)
			(stroke
				(width 0.1)
				(type default)
			)
			(layer "F.Fab")
		)
		(fp_line
			(start 0.120396 0.3048)
			(end 0.120396 0.2794)
			(stroke
				(width 0.1)
				(type default)
			)
			(layer "F.Fab")
		)
		(fp_line
			(start 0.67945 0.3048)
			(end 0.120396 0.3048)
			(stroke
				(width 0.1)
				(type default)
			)
			(layer "F.Fab")
		)
		(fp_line
			(start -0.12065 0.2794)
			(end -0.12065 0.3048)
			(stroke
				(width 0.1)
				(type default)
			)
			(layer "F.Fab")
		)
		(fp_line
			(start 0.120396 0.2794)
			(end -0.12065 0.2794)
			(stroke
				(width 0.1)
				(type default)
			)
			(layer "F.Fab")
		)
		(fp_line
			(start -0.12065 -0.2794)
			(end 0.12065 -0.2794)
			(stroke
				(width 0.1)
				(type default)
			)
			(layer "F.Fab")
		)
		(fp_line
			(start 0.12065 -0.2794)
			(end 0.12065 -0.3048)
			(stroke
				(width 0.1)
				(type default)
			)
			(layer "F.Fab")
		)
		(fp_line
			(start 0.12065 -0.3048)
			(end 0.67945 -0.3048)
			(stroke
				(width 0.1)
				(type default)
			)
			(layer "F.Fab")
		)
		(fp_line
			(start 0.67945 -0.3048)
			(end 0.67945 0.3048)
			(stroke
				(width 0.1)
				(type default)
			)
			(layer "F.Fab")
		)
		(fp_line
			(start -0.67945 -0.305054)
			(end -0.12065 -0.305054)
			(stroke
				(width 0.1)
				(type default)
			)
			(layer "F.Fab")
		)
		(fp_line
			(start -0.12065 -0.305054)
			(end -0.12065 -0.2794)
			(stroke
				(width 0.1)
				(type default)
			)
			(layer "F.Fab")
		)
		(pad "1" smd circle
			(at -0.40005 0 270)
			(size 0 0)
			(layers "F.Cu" "F.Mask" "F.Paste")
			(net "GND")
		)
		(pad "2" smd circle
			(at 0.40005 0 270)
			(size 0 0)
			(layers "F.Cu" "F.Mask" "F.Paste")
			(net "PEX1_MODE_SEL4")
		)
	)
	(footprint ""
		(layer "F.Cu")
		(at 138.985244 -95.814642 180)
		(property "Reference" "R1572"
			(at 0 0 180)
			(layer "F.SilkS")
			(hide yes)
			(effects
				(font
					(size 1.27 1.27)
				)
			)
		)
		(property "Value" ""
			(at 0 0 180)
			(layer "F.Fab")
			(effects
				(font
					(size 1.27 1.27)
				)
			)
		)
		(duplicate_pad_numbers_are_jumpers no)
		(fp_line
			(start 0.7874 0.4064)
			(end -0.7874 0.4064)
			(stroke
				(width 0.1524)
				(type default)
			)
			(layer "F.SilkS")
		)
		(fp_line
			(start 0.7874 -0.4064)
			(end 0.7874 0.4064)
			(stroke
				(width 0.1524)
				(type default)
			)
			(layer "F.SilkS")
		)
		(fp_line
			(start -0.7874 0.4064)
			(end -0.7874 -0.4064)
			(stroke
				(width 0.1524)
				(type default)
			)
			(layer "F.SilkS")
		)
		(fp_line
			(start -0.7874 -0.4064)
			(end 0.7874 -0.4064)
			(stroke
				(width 0.1524)
				(type default)
			)
			(layer "F.SilkS")
		)
		(fp_line
			(start 0.67945 0.3048)
			(end 0.120396 0.3048)
			(stroke
				(width 0.1)
				(type default)
			)
			(layer "F.Fab")
		)
		(fp_line
			(start 0.67945 -0.3048)
			(end 0.67945 0.3048)
			(stroke
				(width 0.1)
				(type default)
			)
			(layer "F.Fab")
		)
		(fp_line
			(start 0.12065 -0.2794)
			(end 0.12065 -0.3048)
			(stroke
				(width 0.1)
				(type default)
			)
			(layer "F.Fab")
		)
		(fp_line
			(start 0.12065 -0.3048)
			(end 0.67945 -0.3048)
			(stroke
				(width 0.1)
				(type default)
			)
			(layer "F.Fab")
		)
		(fp_line
			(start 0.120396 0.3048)
			(end 0.120396 0.2794)
			(stroke
				(width 0.1)
				(type default)
			)
			(layer "F.Fab")
		)
		(fp_line
			(start 0.120396 0.2794)
			(end -0.12065 0.2794)
			(stroke
				(width 0.1)
				(type default)
			)
			(layer "F.Fab")
		)
		(fp_line
			(start -0.12065 0.3048)
			(end -0.67945 0.3048)
			(stroke
				(width 0.1)
				(type default)
			)
			(layer "F.Fab")
		)
		(fp_line
			(start -0.12065 0.2794)
			(end -0.12065 0.3048)
			(stroke
				(width 0.1)
				(type default)
			)
			(layer "F.Fab")
		)
		(fp_line
			(start -0.12065 -0.2794)
			(end 0.12065 -0.2794)
			(stroke
				(width 0.1)
				(type default)
			)
			(layer "F.Fab")
		)
		(fp_line
			(start -0.12065 -0.305054)
			(end -0.12065 -0.2794)
			(stroke
				(width 0.1)
				(type default)
			)
			(layer "F.Fab")
		)
		(fp_line
			(start -0.67945 0.3048)
			(end -0.67945 -0.305054)
			(stroke
				(width 0.1)
				(type default)
			)
			(layer "F.Fab")
		)
		(fp_line
			(start -0.67945 -0.305054)
			(end -0.12065 -0.305054)
			(stroke
				(width 0.1)
				(type default)
			)
			(layer "F.Fab")
		)
		(pad "1" smd circle
			(at -0.40005 0 180)
			(size 0 0)
			(layers "F.Cu" "F.Mask" "F.Paste")
			(net "P3V3_AUX")
		)
		(pad "2" smd circle
			(at 0.40005 0 180)
			(size 0 0)
			(layers "F.Cu" "F.Mask" "F.Paste")
			(net "SMB_BIC_I2C9_MUX0_SSD7_R_SCL")
		)
	)
	(footprint ""
		(layer "F.Cu")
		(at 184.491884 -193.074798)
		(property "Reference" "R472"
			(at 0 0 0)
			(layer "F.SilkS")
			(hide yes)
			(effects
				(font
					(size 1.27 1.27)
				)
			)
		)
		(property "Value" ""
			(at 0 0 0)
			(layer "F.Fab")
			(effects
				(font
					(size 1.27 1.27)
				)
			)
		)
		(duplicate_pad_numbers_are_jumpers no)
		(fp_line
			(start -0.7874 -0.4064)
			(end 0.7874 -0.4064)
			(stroke
				(width 0.1524)
				(type default)
			)
			(layer "F.SilkS")
		)
		(fp_line
			(start -0.7874 0.4064)
			(end -0.7874 -0.4064)
			(stroke
				(width 0.1524)
				(type default)
			)
			(layer "F.SilkS")
		)
		(fp_line
			(start 0.7874 -0.4064)
			(end 0.7874 0.4064)
			(stroke
				(width 0.1524)
				(type default)
			)
			(layer "F.SilkS")
		)
		(fp_line
			(start 0.7874 0.4064)
			(end -0.7874 0.4064)
			(stroke
				(width 0.1524)
				(type default)
			)
			(layer "F.SilkS")
		)
		(fp_line
			(start -0.67945 -0.305054)
			(end -0.12065 -0.305054)
			(stroke
				(width 0.1)
				(type default)
			)
			(layer "F.Fab")
		)
		(fp_line
			(start -0.67945 0.3048)
			(end -0.67945 -0.305054)
			(stroke
				(width 0.1)
				(type default)
			)
			(layer "F.Fab")
		)
		(fp_line
			(start -0.12065 -0.305054)
			(end -0.12065 -0.2794)
			(stroke
				(width 0.1)
				(type default)
			)
			(layer "F.Fab")
		)
		(fp_line
			(start -0.12065 -0.2794)
			(end 0.12065 -0.2794)
			(stroke
				(width 0.1)
				(type default)
			)
			(layer "F.Fab")
		)
		(fp_line
			(start -0.12065 0.2794)
			(end -0.12065 0.3048)
			(stroke
				(width 0.1)
				(type default)
			)
			(layer "F.Fab")
		)
		(fp_line
			(start -0.12065 0.3048)
			(end -0.67945 0.3048)
			(stroke
				(width 0.1)
				(type default)
			)
			(layer "F.Fab")
		)
		(fp_line
			(start 0.120396 0.2794)
			(end -0.12065 0.2794)
			(stroke
				(width 0.1)
				(type default)
			)
			(layer "F.Fab")
		)
		(fp_line
			(start 0.120396 0.3048)
			(end 0.120396 0.2794)
			(stroke
				(width 0.1)
				(type default)
			)
			(layer "F.Fab")
		)
		(fp_line
			(start 0.12065 -0.3048)
			(end 0.67945 -0.3048)
			(stroke
				(width 0.1)
				(type default)
			)
			(layer "F.Fab")
		)
		(fp_line
			(start 0.12065 -0.2794)
			(end 0.12065 -0.3048)
			(stroke
				(width 0.1)
				(type default)
			)
			(layer "F.Fab")
		)
		(fp_line
			(start 0.67945 -0.3048)
			(end 0.67945 0.3048)
			(stroke
				(width 0.1)
				(type default)
			)
			(layer "F.Fab")
		)
		(fp_line
			(start 0.67945 0.3048)
			(end 0.120396 0.3048)
			(stroke
				(width 0.1)
				(type default)
			)
			(layer "F.Fab")
		)
		(pad "1" smd circle
			(at -0.40005 0)
			(size 0 0)
			(layers "F.Cu" "F.Mask" "F.Paste")
			(net "SPI_BIC1_MISO_R3")
		)
		(pad "2" smd circle
			(at 0.40005 0)
			(size 0 0)
			(layers "F.Cu" "F.Mask" "F.Paste")
			(net "SPI_BIC1_MISO_R2")
		)
	)
	(footprint ""
		(layer "F.Cu")
		(at 143.030194 -294.005508 -90)
		(property "Reference" "C3207"
			(at 0 0 270)
			(layer "F.SilkS")
			(hide yes)
			(effects
				(font
					(size 1.27 1.27)
				)
			)
		)
		(property "Value" ""
			(at 0 0 270)
			(layer "F.Fab")
			(effects
				(font
					(size 1.27 1.27)
				)
			)
		)
		(duplicate_pad_numbers_are_jumpers no)
		(fp_line
			(start -1.2954 0.5842)
			(end -1.2954 -0.5842)
			(stroke
				(width 0.1524)
				(type default)
			)
			(layer "F.SilkS")
		)
		(fp_line
			(start 1.2954 0.5842)
			(end -1.2954 0.5842)
			(stroke
				(width 0.1524)
				(type default)
			)
			(layer "F.SilkS")
		)
		(fp_line
			(start -1.2954 -0.5842)
			(end 1.2954 -0.5842)
			(stroke
				(width 0.1524)
				(type default)
			)
			(layer "F.SilkS")
		)
		(fp_line
			(start 1.2954 -0.5842)
			(end 1.2954 0.5842)
			(stroke
				(width 0.1524)
				(type default)
			)
			(layer "F.SilkS")
		)
		(fp_line
			(start -0.8636 0.4572)
			(end -0.8636 0.4064)
			(stroke
				(width 0.1)
				(type default)
			)
			(layer "F.Fab")
		)
		(fp_line
			(start 0.8636 0.4572)
			(end -0.8636 0.4572)
			(stroke
				(width 0.1)
				(type default)
			)
			(layer "F.Fab")
		)
		(fp_line
			(start -1.1938 0.4064)
			(end -1.1938 -0.4064)
			(stroke
				(width 0.1)
				(type default)
			)
			(layer "F.Fab")
		)
		(fp_line
			(start -0.8636 0.4064)
			(end -1.1938 0.4064)
			(stroke
				(width 0.1)
				(type default)
			)
			(layer "F.Fab")
		)
		(fp_line
			(start 0.8636 0.4064)
			(end 0.8636 0.4572)
			(stroke
				(width 0.1)
				(type default)
			)
			(layer "F.Fab")
		)
		(fp_line
			(start 1.1938 0.4064)
			(end 0.8636 0.4064)
			(stroke
				(width 0.1)
				(type default)
			)
			(layer "F.Fab")
		)
		(fp_line
			(start -1.1938 -0.4064)
			(end -0.8636 -0.4064)
			(stroke
				(width 0.1)
				(type default)
			)
			(layer "F.Fab")
		)
		(fp_line
			(start -0.8636 -0.4064)
			(end -0.8636 -0.4572)
			(stroke
				(width 0.1)
				(type default)
			)
			(layer "F.Fab")
		)
		(fp_line
			(start 0.8636 -0.4064)
			(end 1.1938 -0.4064)
			(stroke
				(width 0.1)
				(type default)
			)
			(layer "F.Fab")
		)
		(fp_line
			(start 1.1938 -0.4064)
			(end 1.1938 0.4064)
			(stroke
				(width 0.1)
				(type default)
			)
			(layer "F.Fab")
		)
		(fp_line
			(start -0.8636 -0.4572)
			(end 0.8636 -0.4572)
			(stroke
				(width 0.1)
				(type default)
			)
			(layer "F.Fab")
		)
		(fp_line
			(start 0.8636 -0.4572)
			(end 0.8636 -0.4064)
			(stroke
				(width 0.1)
				(type default)
			)
			(layer "F.Fab")
		)
		(pad "1" smd rect
			(at -0.7366 0 180)
			(size 0.7112 0.8128)
			(layers "F.Cu" "F.Mask" "F.Paste")
			(net "P1V8_PLL0_PEX1")
		)
		(pad "2" smd rect
			(at 0.7366 0 180)
			(size 0.7112 0.8128)
			(layers "F.Cu" "F.Mask" "F.Paste")
			(net "GND")
		)
	)
	(footprint ""
		(layer "F.Cu")
		(at 154.931872 -147.969224 90)
		(property "Reference" "C875"
			(at 0 0 90)
			(layer "F.SilkS")
			(hide yes)
			(effects
				(font
					(size 1.27 1.27)
				)
			)
		)
		(property "Value" ""
			(at 0 0 90)
			(layer "F.Fab")
			(effects
				(font
					(size 1.27 1.27)
				)
			)
		)
		(duplicate_pad_numbers_are_jumpers no)
		(fp_line
			(start 1.524 -0.762)
			(end 1.524 0.762)
			(stroke
				(width 0.1524)
				(type default)
			)
			(layer "F.SilkS")
		)
		(fp_line
			(start -1.524 -0.762)
			(end 1.524 -0.762)
			(stroke
				(width 0.1524)
				(type default)
			)
			(layer "F.SilkS")
		)
		(fp_line
			(start 1.524 0.762)
			(end -1.524 0.762)
			(stroke
				(width 0.1524)
				(type default)
			)
			(layer "F.SilkS")
		)
		(fp_line
			(start -1.524 0.762)
			(end -1.524 -0.762)
			(stroke
				(width 0.1524)
				(type default)
			)
			(layer "F.SilkS")
		)
		(fp_line
			(start 1.1049 -0.724916)
			(end -1.1049 -0.724916)
			(stroke
				(width 0.1)
				(type default)
			)
			(layer "F.Fab")
		)
		(fp_line
			(start -1.1049 -0.724916)
			(end -1.1049 0.724916)
			(stroke
				(width 0.1)
				(type default)
			)
			(layer "F.Fab")
		)
		(fp_line
			(start 1.1049 0.724916)
			(end 1.1049 -0.724916)
			(stroke
				(width 0.1)
				(type default)
			)
			(layer "F.Fab")
		)
		(fp_line
			(start -1.1049 0.724916)
			(end 1.1049 0.724916)
			(stroke
				(width 0.1)
				(type default)
			)
			(layer "F.Fab")
		)
		(pad "1" smd rect
			(at -0.889 0 270)
			(size 1.016 1.27)
			(layers "F.Cu" "F.Mask" "F.Paste")
			(net "P12V_NIC2")
		)
		(pad "2" smd rect
			(at 0.889 0 270)
			(size 1.016 1.27)
			(layers "F.Cu" "F.Mask" "F.Paste")
			(net "GND")
		)
	)
	(footprint ""
		(layer "F.Cu")
		(at 387.09092 -142.892018)
		(property "Reference" "R336"
			(at 0 0 0)
			(layer "F.SilkS")
			(hide yes)
			(effects
				(font
					(size 1.27 1.27)
				)
			)
		)
		(property "Value" ""
			(at 0 0 0)
			(layer "F.Fab")
			(effects
				(font
					(size 1.27 1.27)
				)
			)
		)
		(duplicate_pad_numbers_are_jumpers no)
		(fp_line
			(start -0.7874 -0.4064)
			(end 0.7874 -0.4064)
			(stroke
				(width 0.1524)
				(type default)
			)
			(layer "F.SilkS")
		)
		(fp_line
			(start -0.7874 0.4064)
			(end -0.7874 -0.4064)
			(stroke
				(width 0.1524)
				(type default)
			)
			(layer "F.SilkS")
		)
		(fp_line
			(start 0.7874 -0.4064)
			(end 0.7874 0.4064)
			(stroke
				(width 0.1524)
				(type default)
			)
			(layer "F.SilkS")
		)
		(fp_line
			(start 0.7874 0.4064)
			(end -0.7874 0.4064)
			(stroke
				(width 0.1524)
				(type default)
			)
			(layer "F.SilkS")
		)
		(fp_line
			(start -0.67945 -0.305054)
			(end -0.12065 -0.305054)
			(stroke
				(width 0.1)
				(type default)
			)
			(layer "F.Fab")
		)
		(fp_line
			(start -0.67945 0.3048)
			(end -0.67945 -0.305054)
			(stroke
				(width 0.1)
				(type default)
			)
			(layer "F.Fab")
		)
		(fp_line
			(start -0.12065 -0.305054)
			(end -0.12065 -0.2794)
			(stroke
				(width 0.1)
				(type default)
			)
			(layer "F.Fab")
		)
		(fp_line
			(start -0.12065 -0.2794)
			(end 0.12065 -0.2794)
			(stroke
				(width 0.1)
				(type default)
			)
			(layer "F.Fab")
		)
		(fp_line
			(start -0.12065 0.2794)
			(end -0.12065 0.3048)
			(stroke
				(width 0.1)
				(type default)
			)
			(layer "F.Fab")
		)
		(fp_line
			(start -0.12065 0.3048)
			(end -0.67945 0.3048)
			(stroke
				(width 0.1)
				(type default)
			)
			(layer "F.Fab")
		)
		(fp_line
			(start 0.120396 0.2794)
			(end -0.12065 0.2794)
			(stroke
				(width 0.1)
				(type default)
			)
			(layer "F.Fab")
		)
		(fp_line
			(start 0.120396 0.3048)
			(end 0.120396 0.2794)
			(stroke
				(width 0.1)
				(type default)
			)
			(layer "F.Fab")
		)
		(fp_line
			(start 0.12065 -0.3048)
			(end 0.67945 -0.3048)
			(stroke
				(width 0.1)
				(type default)
			)
			(layer "F.Fab")
		)
		(fp_line
			(start 0.12065 -0.2794)
			(end 0.12065 -0.3048)
			(stroke
				(width 0.1)
				(type default)
			)
			(layer "F.Fab")
		)
		(fp_line
			(start 0.67945 -0.3048)
			(end 0.67945 0.3048)
			(stroke
				(width 0.1)
				(type default)
			)
			(layer "F.Fab")
		)
		(fp_line
			(start 0.67945 0.3048)
			(end 0.120396 0.3048)
			(stroke
				(width 0.1)
				(type default)
			)
			(layer "F.Fab")
		)
		(pad "1" smd circle
			(at -0.40005 0)
			(size 0 0)
			(layers "F.Cu" "F.Mask" "F.Paste")
			(net "NIC6_BIF0_N")
		)
		(pad "2" smd circle
			(at 0.40005 0)
			(size 0 0)
			(layers "F.Cu" "F.Mask" "F.Paste")
			(net "GND")
		)
	)
	(footprint ""
		(layer "F.Cu")
		(at 366.169448 -254.385572)
		(property "Reference" "R3068"
			(at 0 0 0)
			(layer "F.SilkS")
			(hide yes)
			(effects
				(font
					(size 1.27 1.27)
				)
			)
		)
		(property "Value" ""
			(at 0 0 0)
			(layer "F.Fab")
			(effects
				(font
					(size 1.27 1.27)
				)
			)
		)
		(duplicate_pad_numbers_are_jumpers no)
		(fp_line
			(start -0.7874 -0.4064)
			(end 0.7874 -0.4064)
			(stroke
				(width 0.1524)
				(type default)
			)
			(layer "F.SilkS")
		)
		(fp_line
			(start -0.7874 0.4064)
			(end -0.7874 -0.4064)
			(stroke
				(width 0.1524)
				(type default)
			)
			(layer "F.SilkS")
		)
		(fp_line
			(start 0.7874 -0.4064)
			(end 0.7874 0.4064)
			(stroke
				(width 0.1524)
				(type default)
			)
			(layer "F.SilkS")
		)
		(fp_line
			(start 0.7874 0.4064)
			(end -0.7874 0.4064)
			(stroke
				(width 0.1524)
				(type default)
			)
			(layer "F.SilkS")
		)
		(fp_line
			(start -0.67945 -0.305054)
			(end -0.12065 -0.305054)
			(stroke
				(width 0.1)
				(type default)
			)
			(layer "F.Fab")
		)
		(fp_line
			(start -0.67945 0.3048)
			(end -0.67945 -0.305054)
			(stroke
				(width 0.1)
				(type default)
			)
			(layer "F.Fab")
		)
		(fp_line
			(start -0.12065 -0.305054)
			(end -0.12065 -0.2794)
			(stroke
				(width 0.1)
				(type default)
			)
			(layer "F.Fab")
		)
		(fp_line
			(start -0.12065 -0.2794)
			(end 0.12065 -0.2794)
			(stroke
				(width 0.1)
				(type default)
			)
			(layer "F.Fab")
		)
		(fp_line
			(start -0.12065 0.2794)
			(end -0.12065 0.3048)
			(stroke
				(width 0.1)
				(type default)
			)
			(layer "F.Fab")
		)
		(fp_line
			(start -0.12065 0.3048)
			(end -0.67945 0.3048)
			(stroke
				(width 0.1)
				(type default)
			)
			(layer "F.Fab")
		)
		(fp_line
			(start 0.120396 0.2794)
			(end -0.12065 0.2794)
			(stroke
				(width 0.1)
				(type default)
			)
			(layer "F.Fab")
		)
		(fp_line
			(start 0.120396 0.3048)
			(end 0.120396 0.2794)
			(stroke
				(width 0.1)
				(type default)
			)
			(layer "F.Fab")
		)
		(fp_line
			(start 0.12065 -0.3048)
			(end 0.67945 -0.3048)
			(stroke
				(width 0.1)
				(type default)
			)
			(layer "F.Fab")
		)
		(fp_line
			(start 0.12065 -0.2794)
			(end 0.12065 -0.3048)
			(stroke
				(width 0.1)
				(type default)
			)
			(layer "F.Fab")
		)
		(fp_line
			(start 0.67945 -0.3048)
			(end 0.67945 0.3048)
			(stroke
				(width 0.1)
				(type default)
			)
			(layer "F.Fab")
		)
		(fp_line
			(start 0.67945 0.3048)
			(end 0.120396 0.3048)
			(stroke
				(width 0.1)
				(type default)
			)
			(layer "F.Fab")
		)
		(pad "1" smd circle
			(at -0.40005 0)
			(size 0 0)
			(layers "F.Cu" "F.Mask" "F.Paste")
			(net "PWR_EN_PEX")
		)
		(pad "2" smd circle
			(at 0.40005 0)
			(size 0 0)
			(layers "F.Cu" "F.Mask" "F.Paste")
			(net "PWR_EN_PEX_R1")
		)
	)
	(footprint ""
		(layer "F.Cu")
		(at 315.850016 -50.96383 180)
		(property "Reference" "PC586"
			(at 0 0 180)
			(layer "F.SilkS")
			(hide yes)
			(effects
				(font
					(size 1.27 1.27)
				)
			)
		)
		(property "Value" ""
			(at 0 0 180)
			(layer "F.Fab")
			(effects
				(font
					(size 1.27 1.27)
				)
			)
		)
		(duplicate_pad_numbers_are_jumpers no)
		(fp_line
			(start 1.524 0.762)
			(end -1.524 0.762)
			(stroke
				(width 0.1524)
				(type default)
			)
			(layer "F.SilkS")
		)
		(fp_line
			(start 1.524 -0.762)
			(end 1.524 0.762)
			(stroke
				(width 0.1524)
				(type default)
			)
			(layer "F.SilkS")
		)
		(fp_line
			(start -1.524 0.762)
			(end -1.524 -0.762)
			(stroke
				(width 0.1524)
				(type default)
			)
			(layer "F.SilkS")
		)
		(fp_line
			(start -1.524 -0.762)
			(end 1.524 -0.762)
			(stroke
				(width 0.1524)
				(type default)
			)
			(layer "F.SilkS")
		)
		(fp_line
			(start 1.1049 0.724916)
			(end 1.1049 -0.724916)
			(stroke
				(width 0.1)
				(type default)
			)
			(layer "F.Fab")
		)
		(fp_line
			(start 1.1049 -0.724916)
			(end -1.1049 -0.724916)
			(stroke
				(width 0.1)
				(type default)
			)
			(layer "F.Fab")
		)
		(fp_line
			(start -1.1049 0.724916)
			(end 1.1049 0.724916)
			(stroke
				(width 0.1)
				(type default)
			)
			(layer "F.Fab")
		)
		(fp_line
			(start -1.1049 -0.724916)
			(end -1.1049 0.724916)
			(stroke
				(width 0.1)
				(type default)
			)
			(layer "F.Fab")
		)
		(pad "1" smd rect
			(at -0.889 0)
			(size 1.016 1.27)
			(layers "F.Cu" "F.Mask" "F.Paste")
			(net "P3V3_SSD11")
		)
		(pad "2" smd rect
			(at 0.889 0)
			(size 1.016 1.27)
			(layers "F.Cu" "F.Mask" "F.Paste")
			(net "GND")
		)
	)
	(footprint ""
		(layer "F.Cu")
		(at 47.287688 -343.952322 90)
		(property "Reference" "C165"
			(at 0 0 90)
			(layer "F.SilkS")
			(hide yes)
			(effects
				(font
					(size 1.27 1.27)
				)
			)
		)
		(property "Value" ""
			(at 0 0 90)
			(layer "F.Fab")
			(effects
				(font
					(size 1.27 1.27)
				)
			)
		)
		(duplicate_pad_numbers_are_jumpers no)
		(fp_line
			(start 0.299974 -0.150114)
			(end 0.299974 0.150114)
			(stroke
				(width 0.1)
				(type default)
			)
			(layer "F.Fab")
		)
		(fp_line
			(start -0.299974 -0.150114)
			(end 0.299974 -0.150114)
			(stroke
				(width 0.1)
				(type default)
			)
			(layer "F.Fab")
		)
		(fp_line
			(start 0.299974 0.150114)
			(end -0.299974 0.150114)
			(stroke
				(width 0.1)
				(type default)
			)
			(layer "F.Fab")
		)
		(fp_line
			(start -0.299974 0.150114)
			(end -0.299974 -0.150114)
			(stroke
				(width 0.1)
				(type default)
			)
			(layer "F.Fab")
		)
		(pad "1" smd rect
			(at -0.2667 0 90)
			(size 0.3048 0.381)
			(layers "F.Cu" "F.Mask" "F.Paste")
			(net "P5E_PEX0_STN7_TX_DP<125>")
		)
		(pad "2" smd rect
			(at 0.2667 0 90)
			(size 0.3048 0.381)
			(layers "F.Cu" "F.Mask" "F.Paste")
			(net "P5E_PEX0_STN7_TX_C_DP<125>")
		)
	)
	(footprint ""
		(layer "F.Cu")
		(at 394.09624 -47.20082 90)
		(property "Reference" "C337"
			(at 0 0 90)
			(layer "F.SilkS")
			(hide yes)
			(effects
				(font
					(size 1.27 1.27)
				)
			)
		)
		(property "Value" ""
			(at 0 0 90)
			(layer "F.Fab")
			(effects
				(font
					(size 1.27 1.27)
				)
			)
		)
		(duplicate_pad_numbers_are_jumpers no)
		(fp_line
			(start 0.7874 -0.4064)
			(end 0.7874 0.4064)
			(stroke
				(width 0.1524)
				(type default)
			)
			(layer "F.SilkS")
		)
		(fp_line
			(start -0.7874 -0.4064)
			(end 0.7874 -0.4064)
			(stroke
				(width 0.1524)
				(type default)
			)
			(layer "F.SilkS")
		)
		(fp_line
			(start 0.7874 0.4064)
			(end -0.7874 0.4064)
			(stroke
				(width 0.1524)
				(type default)
			)
			(layer "F.SilkS")
		)
		(fp_line
			(start -0.7874 0.4064)
			(end -0.7874 -0.4064)
			(stroke
				(width 0.1524)
				(type default)
			)
			(layer "F.SilkS")
		)
		(fp_line
			(start -0.12065 -0.305054)
			(end -0.12065 -0.2794)
			(stroke
				(width 0.1)
				(type default)
			)
			(layer "F.Fab")
		)
		(fp_line
			(start -0.67945 -0.305054)
			(end -0.12065 -0.305054)
			(stroke
				(width 0.1)
				(type default)
			)
			(layer "F.Fab")
		)
		(fp_line
			(start 0.67945 -0.3048)
			(end 0.67945 0.3048)
			(stroke
				(width 0.1)
				(type default)
			)
			(layer "F.Fab")
		)
		(fp_line
			(start 0.12065 -0.3048)
			(end 0.67945 -0.3048)
			(stroke
				(width 0.1)
				(type default)
			)
			(layer "F.Fab")
		)
		(fp_line
			(start 0.12065 -0.2794)
			(end 0.12065 -0.3048)
			(stroke
				(width 0.1)
				(type default)
			)
			(layer "F.Fab")
		)
		(fp_line
			(start -0.12065 -0.2794)
			(end 0.12065 -0.2794)
			(stroke
				(width 0.1)
				(type default)
			)
			(layer "F.Fab")
		)
		(fp_line
			(start 0.120396 0.2794)
			(end -0.12065 0.2794)
			(stroke
				(width 0.1)
				(type default)
			)
			(layer "F.Fab")
		)
		(fp_line
			(start -0.12065 0.2794)
			(end -0.12065 0.3048)
			(stroke
				(width 0.1)
				(type default)
			)
			(layer "F.Fab")
		)
		(fp_line
			(start 0.67945 0.3048)
			(end 0.120396 0.3048)
			(stroke
				(width 0.1)
				(type default)
			)
			(layer "F.Fab")
		)
		(fp_line
			(start 0.120396 0.3048)
			(end 0.120396 0.2794)
			(stroke
				(width 0.1)
				(type default)
			)
			(layer "F.Fab")
		)
		(fp_line
			(start -0.12065 0.3048)
			(end -0.67945 0.3048)
			(stroke
				(width 0.1)
				(type default)
			)
			(layer "F.Fab")
		)
		(fp_line
			(start -0.67945 0.3048)
			(end -0.67945 -0.305054)
			(stroke
				(width 0.1)
				(type default)
			)
			(layer "F.Fab")
		)
		(pad "1" smd circle
			(at -0.40005 0 90)
			(size 0 0)
			(layers "F.Cu" "F.Mask" "F.Paste")
			(net "P12V_SSD13_R")
		)
		(pad "2" smd circle
			(at 0.40005 0 90)
			(size 0 0)
			(layers "F.Cu" "F.Mask" "F.Paste")
			(net "GND")
		)
	)
	(footprint ""
		(layer "F.Cu")
		(at 115.339368 -265.949938 180)
		(property "Reference" "PR7132"
			(at 0 0 180)
			(layer "F.SilkS")
			(hide yes)
			(effects
				(font
					(size 1.27 1.27)
				)
			)
		)
		(property "Value" ""
			(at 0 0 180)
			(layer "F.Fab")
			(effects
				(font
					(size 1.27 1.27)
				)
			)
		)
		(duplicate_pad_numbers_are_jumpers no)
		(fp_line
			(start 0.7874 0.4064)
			(end -0.7874 0.4064)
			(stroke
				(width 0.1524)
				(type default)
			)
			(layer "F.SilkS")
		)
		(fp_line
			(start 0.7874 -0.4064)
			(end 0.7874 0.4064)
			(stroke
				(width 0.1524)
				(type default)
			)
			(layer "F.SilkS")
		)
		(fp_line
			(start -0.7874 0.4064)
			(end -0.7874 -0.4064)
			(stroke
				(width 0.1524)
				(type default)
			)
			(layer "F.SilkS")
		)
		(fp_line
			(start -0.7874 -0.4064)
			(end 0.7874 -0.4064)
			(stroke
				(width 0.1524)
				(type default)
			)
			(layer "F.SilkS")
		)
		(fp_line
			(start 0.67945 0.3048)
			(end 0.120396 0.3048)
			(stroke
				(width 0.1)
				(type default)
			)
			(layer "F.Fab")
		)
		(fp_line
			(start 0.67945 -0.3048)
			(end 0.67945 0.3048)
			(stroke
				(width 0.1)
				(type default)
			)
			(layer "F.Fab")
		)
		(fp_line
			(start 0.12065 -0.2794)
			(end 0.12065 -0.3048)
			(stroke
				(width 0.1)
				(type default)
			)
			(layer "F.Fab")
		)
		(fp_line
			(start 0.12065 -0.3048)
			(end 0.67945 -0.3048)
			(stroke
				(width 0.1)
				(type default)
			)
			(layer "F.Fab")
		)
		(fp_line
			(start 0.120396 0.3048)
			(end 0.120396 0.2794)
			(stroke
				(width 0.1)
				(type default)
			)
			(layer "F.Fab")
		)
		(fp_line
			(start 0.120396 0.2794)
			(end -0.12065 0.2794)
			(stroke
				(width 0.1)
				(type default)
			)
			(layer "F.Fab")
		)
		(fp_line
			(start -0.12065 0.3048)
			(end -0.67945 0.3048)
			(stroke
				(width 0.1)
				(type default)
			)
			(layer "F.Fab")
		)
		(fp_line
			(start -0.12065 0.2794)
			(end -0.12065 0.3048)
			(stroke
				(width 0.1)
				(type default)
			)
			(layer "F.Fab")
		)
		(fp_line
			(start -0.12065 -0.2794)
			(end 0.12065 -0.2794)
			(stroke
				(width 0.1)
				(type default)
			)
			(layer "F.Fab")
		)
		(fp_line
			(start -0.12065 -0.305054)
			(end -0.12065 -0.2794)
			(stroke
				(width 0.1)
				(type default)
			)
			(layer "F.Fab")
		)
		(fp_line
			(start -0.67945 0.3048)
			(end -0.67945 -0.305054)
			(stroke
				(width 0.1)
				(type default)
			)
			(layer "F.Fab")
		)
		(fp_line
			(start -0.67945 -0.305054)
			(end -0.12065 -0.305054)
			(stroke
				(width 0.1)
				(type default)
			)
			(layer "F.Fab")
		)
		(pad "1" smd circle
			(at -0.40005 0 180)
			(size 0 0)
			(layers "F.Cu" "F.Mask" "F.Paste")
			(net "NC_P0V8_PEX0_ISEN5")
		)
		(pad "2" smd circle
			(at 0.40005 0 180)
			(size 0 0)
			(layers "F.Cu" "F.Mask" "F.Paste")
			(net "GND")
		)
	)
	(footprint ""
		(layer "F.Cu")
		(at 188.534548 -33.631886 180)
		(property "Reference" "C293"
			(at 0 0 180)
			(layer "F.SilkS")
			(hide yes)
			(effects
				(font
					(size 1.27 1.27)
				)
			)
		)
		(property "Value" ""
			(at 0 0 180)
			(layer "F.Fab")
			(effects
				(font
					(size 1.27 1.27)
				)
			)
		)
		(duplicate_pad_numbers_are_jumpers no)
		(fp_line
			(start 0.299974 0.150114)
			(end -0.299974 0.150114)
			(stroke
				(width 0.1)
				(type default)
			)
			(layer "F.Fab")
		)
		(fp_line
			(start 0.299974 -0.150114)
			(end 0.299974 0.150114)
			(stroke
				(width 0.1)
				(type default)
			)
			(layer "F.Fab")
		)
		(fp_line
			(start -0.299974 0.150114)
			(end -0.299974 -0.150114)
			(stroke
				(width 0.1)
				(type default)
			)
			(layer "F.Fab")
		)
		(fp_line
			(start -0.299974 -0.150114)
			(end 0.299974 -0.150114)
			(stroke
				(width 0.1)
				(type default)
			)
			(layer "F.Fab")
		)
		(pad "1" smd rect
			(at -0.2667 0 180)
			(size 0.3048 0.381)
			(layers "F.Cu" "F.Mask" "F.Paste")
			(net "P5E_PEX1_STN2_TX_DN<39>")
		)
		(pad "2" smd rect
			(at 0.2667 0 180)
			(size 0.3048 0.381)
			(layers "F.Cu" "F.Mask" "F.Paste")
			(net "P5E_PEX1_STN2_TX_C_DN<39>")
		)
	)
	(footprint ""
		(layer "F.Cu")
		(at 459.31328 -258.331208 -90)
		(property "Reference" "R6556"
			(at 0 0 270)
			(layer "F.SilkS")
			(hide yes)
			(effects
				(font
					(size 1.27 1.27)
				)
			)
		)
		(property "Value" ""
			(at 0 0 270)
			(layer "F.Fab")
			(effects
				(font
					(size 1.27 1.27)
				)
			)
		)
		(duplicate_pad_numbers_are_jumpers no)
		(fp_line
			(start -0.7874 0.4064)
			(end -0.7874 -0.4064)
			(stroke
				(width 0.1524)
				(type default)
			)
			(layer "F.SilkS")
		)
		(fp_line
			(start 0.7874 0.4064)
			(end -0.7874 0.4064)
			(stroke
				(width 0.1524)
				(type default)
			)
			(layer "F.SilkS")
		)
		(fp_line
			(start -0.7874 -0.4064)
			(end 0.7874 -0.4064)
			(stroke
				(width 0.1524)
				(type default)
			)
			(layer "F.SilkS")
		)
		(fp_line
			(start 0.7874 -0.4064)
			(end 0.7874 0.4064)
			(stroke
				(width 0.1524)
				(type default)
			)
			(layer "F.SilkS")
		)
		(fp_line
			(start -0.67945 0.3048)
			(end -0.67945 -0.305054)
			(stroke
				(width 0.1)
				(type default)
			)
			(layer "F.Fab")
		)
		(fp_line
			(start -0.12065 0.3048)
			(end -0.67945 0.3048)
			(stroke
				(width 0.1)
				(type default)
			)
			(layer "F.Fab")
		)
		(fp_line
			(start 0.120396 0.3048)
			(end 0.120396 0.2794)
			(stroke
				(width 0.1)
				(type default)
			)
			(layer "F.Fab")
		)
		(fp_line
			(start 0.67945 0.3048)
			(end 0.120396 0.3048)
			(stroke
				(width 0.1)
				(type default)
			)
			(layer "F.Fab")
		)
		(fp_line
			(start -0.12065 0.2794)
			(end -0.12065 0.3048)
			(stroke
				(width 0.1)
				(type default)
			)
			(layer "F.Fab")
		)
		(fp_line
			(start 0.120396 0.2794)
			(end -0.12065 0.2794)
			(stroke
				(width 0.1)
				(type default)
			)
			(layer "F.Fab")
		)
		(fp_line
			(start -0.12065 -0.2794)
			(end 0.12065 -0.2794)
			(stroke
				(width 0.1)
				(type default)
			)
			(layer "F.Fab")
		)
		(fp_line
			(start 0.12065 -0.2794)
			(end 0.12065 -0.3048)
			(stroke
				(width 0.1)
				(type default)
			)
			(layer "F.Fab")
		)
		(fp_line
			(start 0.12065 -0.3048)
			(end 0.67945 -0.3048)
			(stroke
				(width 0.1)
				(type default)
			)
			(layer "F.Fab")
		)
		(fp_line
			(start 0.67945 -0.3048)
			(end 0.67945 0.3048)
			(stroke
				(width 0.1)
				(type default)
			)
			(layer "F.Fab")
		)
		(fp_line
			(start -0.67945 -0.305054)
			(end -0.12065 -0.305054)
			(stroke
				(width 0.1)
				(type default)
			)
			(layer "F.Fab")
		)
		(fp_line
			(start -0.12065 -0.305054)
			(end -0.12065 -0.2794)
			(stroke
				(width 0.1)
				(type default)
			)
			(layer "F.Fab")
		)
		(pad "1" smd circle
			(at -0.40005 0 270)
			(size 0 0)
			(layers "F.Cu" "F.Mask" "F.Paste")
			(net "P1V25_SERDES_VDDPLL_PEX3")
		)
		(pad "2" smd circle
			(at 0.40005 0 270)
			(size 0 0)
			(layers "F.Cu" "F.Mask" "F.Paste")
			(net "P1V25_SERDES_VDDPLL_PEX3_C5")
		)
	)
	(footprint ""
		(layer "F.Cu")
		(at 265.240008 -259.834634 180)
		(property "Reference" "C3396"
			(at 0 0 180)
			(layer "F.SilkS")
			(hide yes)
			(effects
				(font
					(size 1.27 1.27)
				)
			)
		)
		(property "Value" ""
			(at 0 0 180)
			(layer "F.Fab")
			(effects
				(font
					(size 1.27 1.27)
				)
			)
		)
		(duplicate_pad_numbers_are_jumpers no)
		(fp_line
			(start 1.2954 0.5842)
			(end -1.2954 0.5842)
			(stroke
				(width 0.1524)
				(type default)
			)
			(layer "F.SilkS")
		)
		(fp_line
			(start 1.2954 -0.5842)
			(end 1.2954 0.5842)
			(stroke
				(width 0.1524)
				(type default)
			)
			(layer "F.SilkS")
		)
		(fp_line
			(start -1.2954 0.5842)
			(end -1.2954 -0.5842)
			(stroke
				(width 0.1524)
				(type default)
			)
			(layer "F.SilkS")
		)
		(fp_line
			(start -1.2954 -0.5842)
			(end 1.2954 -0.5842)
			(stroke
				(width 0.1524)
				(type default)
			)
			(layer "F.SilkS")
		)
		(fp_line
			(start 1.1938 0.4064)
			(end 0.8636 0.4064)
			(stroke
				(width 0.1)
				(type default)
			)
			(layer "F.Fab")
		)
		(fp_line
			(start 1.1938 -0.4064)
			(end 1.1938 0.4064)
			(stroke
				(width 0.1)
				(type default)
			)
			(layer "F.Fab")
		)
		(fp_line
			(start 0.8636 0.4572)
			(end -0.8636 0.4572)
			(stroke
				(width 0.1)
				(type default)
			)
			(layer "F.Fab")
		)
		(fp_line
			(start 0.8636 0.4064)
			(end 0.8636 0.4572)
			(stroke
				(width 0.1)
				(type default)
			)
			(layer "F.Fab")
		)
		(fp_line
			(start 0.8636 -0.4064)
			(end 1.1938 -0.4064)
			(stroke
				(width 0.1)
				(type default)
			)
			(layer "F.Fab")
		)
		(fp_line
			(start 0.8636 -0.4572)
			(end 0.8636 -0.4064)
			(stroke
				(width 0.1)
				(type default)
			)
			(layer "F.Fab")
		)
		(fp_line
			(start -0.8636 0.4572)
			(end -0.8636 0.4064)
			(stroke
				(width 0.1)
				(type default)
			)
			(layer "F.Fab")
		)
		(fp_line
			(start -0.8636 0.4064)
			(end -1.1938 0.4064)
			(stroke
				(width 0.1)
				(type default)
			)
			(layer "F.Fab")
		)
		(fp_line
			(start -0.8636 -0.4064)
			(end -0.8636 -0.4572)
			(stroke
				(width 0.1)
				(type default)
			)
			(layer "F.Fab")
		)
		(fp_line
			(start -0.8636 -0.4572)
			(end 0.8636 -0.4572)
			(stroke
				(width 0.1)
				(type default)
			)
			(layer "F.Fab")
		)
		(fp_line
			(start -1.1938 0.4064)
			(end -1.1938 -0.4064)
			(stroke
				(width 0.1)
				(type default)
			)
			(layer "F.Fab")
		)
		(fp_line
			(start -1.1938 -0.4064)
			(end -0.8636 -0.4064)
			(stroke
				(width 0.1)
				(type default)
			)
			(layer "F.Fab")
		)
		(pad "1" smd rect
			(at -0.7366 0 90)
			(size 0.7112 0.8128)
			(layers "F.Cu" "F.Mask" "F.Paste")
			(net "PCEPLL3_VDDA18_PEX2_R")
		)
		(pad "2" smd rect
			(at 0.7366 0 90)
			(size 0.7112 0.8128)
			(layers "F.Cu" "F.Mask" "F.Paste")
			(net "GND")
		)
	)
	(footprint ""
		(layer "F.Cu")
		(at 447.163698 -258.331208 -90)
		(property "Reference" "R6560"
			(at 0 0 270)
			(layer "F.SilkS")
			(hide yes)
			(effects
				(font
					(size 1.27 1.27)
				)
			)
		)
		(property "Value" ""
			(at 0 0 270)
			(layer "F.Fab")
			(effects
				(font
					(size 1.27 1.27)
				)
			)
		)
		(duplicate_pad_numbers_are_jumpers no)
		(fp_line
			(start -0.7874 0.4064)
			(end -0.7874 -0.4064)
			(stroke
				(width 0.1524)
				(type default)
			)
			(layer "F.SilkS")
		)
		(fp_line
			(start 0.7874 0.4064)
			(end -0.7874 0.4064)
			(stroke
				(width 0.1524)
				(type default)
			)
			(layer "F.SilkS")
		)
		(fp_line
			(start -0.7874 -0.4064)
			(end 0.7874 -0.4064)
			(stroke
				(width 0.1524)
				(type default)
			)
			(layer "F.SilkS")
		)
		(fp_line
			(start 0.7874 -0.4064)
			(end 0.7874 0.4064)
			(stroke
				(width 0.1524)
				(type default)
			)
			(layer "F.SilkS")
		)
		(fp_line
			(start -0.67945 0.3048)
			(end -0.67945 -0.305054)
			(stroke
				(width 0.1)
				(type default)
			)
			(layer "F.Fab")
		)
		(fp_line
			(start -0.12065 0.3048)
			(end -0.67945 0.3048)
			(stroke
				(width 0.1)
				(type default)
			)
			(layer "F.Fab")
		)
		(fp_line
			(start 0.120396 0.3048)
			(end 0.120396 0.2794)
			(stroke
				(width 0.1)
				(type default)
			)
			(layer "F.Fab")
		)
		(fp_line
			(start 0.67945 0.3048)
			(end 0.120396 0.3048)
			(stroke
				(width 0.1)
				(type default)
			)
			(layer "F.Fab")
		)
		(fp_line
			(start -0.12065 0.2794)
			(end -0.12065 0.3048)
			(stroke
				(width 0.1)
				(type default)
			)
			(layer "F.Fab")
		)
		(fp_line
			(start 0.120396 0.2794)
			(end -0.12065 0.2794)
			(stroke
				(width 0.1)
				(type default)
			)
			(layer "F.Fab")
		)
		(fp_line
			(start -0.12065 -0.2794)
			(end 0.12065 -0.2794)
			(stroke
				(width 0.1)
				(type default)
			)
			(layer "F.Fab")
		)
		(fp_line
			(start 0.12065 -0.2794)
			(end 0.12065 -0.3048)
			(stroke
				(width 0.1)
				(type default)
			)
			(layer "F.Fab")
		)
		(fp_line
			(start 0.12065 -0.3048)
			(end 0.67945 -0.3048)
			(stroke
				(width 0.1)
				(type default)
			)
			(layer "F.Fab")
		)
		(fp_line
			(start 0.67945 -0.3048)
			(end 0.67945 0.3048)
			(stroke
				(width 0.1)
				(type default)
			)
			(layer "F.Fab")
		)
		(fp_line
			(start -0.67945 -0.305054)
			(end -0.12065 -0.305054)
			(stroke
				(width 0.1)
				(type default)
			)
			(layer "F.Fab")
		)
		(fp_line
			(start -0.12065 -0.305054)
			(end -0.12065 -0.2794)
			(stroke
				(width 0.1)
				(type default)
			)
			(layer "F.Fab")
		)
		(pad "1" smd circle
			(at -0.40005 0 270)
			(size 0 0)
			(layers "F.Cu" "F.Mask" "F.Paste")
			(net "P1V25_SERDES_VDDPLL_PEX3")
		)
		(pad "2" smd circle
			(at 0.40005 0 270)
			(size 0 0)
			(layers "F.Cu" "F.Mask" "F.Paste")
			(net "P1V25_SERDES_VDDPLL_PEX3_C7")
		)
	)
	(footprint ""
		(layer "F.Cu")
		(at 344.612976 -87.25535 180)
		(property "Reference" "R1180"
			(at 0 0 180)
			(layer "F.SilkS")
			(hide yes)
			(effects
				(font
					(size 1.27 1.27)
				)
			)
		)
		(property "Value" ""
			(at 0 0 180)
			(layer "F.Fab")
			(effects
				(font
					(size 1.27 1.27)
				)
			)
		)
		(duplicate_pad_numbers_are_jumpers no)
		(fp_line
			(start -0.7874 -0.4064)
			(end 0.7874 -0.4064)
			(stroke
				(width 0.1524)
				(type default)
			)
			(layer "F.SilkS")
		)
		(fp_line
			(start 0.67945 0.3048)
			(end 0.120396 0.3048)
			(stroke
				(width 0.1)
				(type default)
			)
			(layer "F.Fab")
		)
		(fp_line
			(start 0.67945 -0.3048)
			(end 0.67945 0.3048)
			(stroke
				(width 0.1)
				(type default)
			)
			(layer "F.Fab")
		)
		(fp_line
			(start 0.12065 -0.2794)
			(end 0.12065 -0.3048)
			(stroke
				(width 0.1)
				(type default)
			)
			(layer "F.Fab")
		)
		(fp_line
			(start 0.12065 -0.3048)
			(end 0.67945 -0.3048)
			(stroke
				(width 0.1)
				(type default)
			)
			(layer "F.Fab")
		)
		(fp_line
			(start 0.120396 0.3048)
			(end 0.120396 0.2794)
			(stroke
				(width 0.1)
				(type default)
			)
			(layer "F.Fab")
		)
		(fp_line
			(start 0.120396 0.2794)
			(end -0.12065 0.2794)
			(stroke
				(width 0.1)
				(type default)
			)
			(layer "F.Fab")
		)
		(fp_line
			(start -0.12065 0.3048)
			(end -0.67945 0.3048)
			(stroke
				(width 0.1)
				(type default)
			)
			(layer "F.Fab")
		)
		(fp_line
			(start -0.12065 0.2794)
			(end -0.12065 0.3048)
			(stroke
				(width 0.1)
				(type default)
			)
			(layer "F.Fab")
		)
		(fp_line
			(start -0.12065 -0.2794)
			(end 0.12065 -0.2794)
			(stroke
				(width 0.1)
				(type default)
			)
			(layer "F.Fab")
		)
		(fp_line
			(start -0.12065 -0.305054)
			(end -0.12065 -0.2794)
			(stroke
				(width 0.1)
				(type default)
			)
			(layer "F.Fab")
		)
		(fp_line
			(start -0.67945 0.3048)
			(end -0.67945 -0.305054)
			(stroke
				(width 0.1)
				(type default)
			)
			(layer "F.Fab")
		)
		(fp_line
			(start -0.67945 -0.305054)
			(end -0.12065 -0.305054)
			(stroke
				(width 0.1)
				(type default)
			)
			(layer "F.Fab")
		)
		(pad "1" smd circle
			(at -0.40005 0 180)
			(size 0 0)
			(layers "F.Cu" "F.Mask" "F.Paste")
			(net "CLK_100M_DB800ZL_SSD13_R_DP")
		)
		(pad "2" smd circle
			(at 0.40005 0 180)
			(size 0 0)
			(layers "F.Cu" "F.Mask" "F.Paste")
			(net "CLK_100M_DB800ZL_SSD13_DP")
		)
	)
	(footprint ""
		(layer "F.Cu")
		(at 472.525852 -526.131536 180)
		(property "Reference" "J40_OTH"
			(at -3.2385 -1.402334 0)
			(unlocked yes)
			(layer "B.SilkS")
			(effects
				(font
					(size 0.7874 0.5842)
					(thickness 0.1524)
				)
				(justify mirror)
			)
		)
		(property "Value" ""
			(at 0 0 180)
			(layer "F.Fab")
			(effects
				(font
					(size 1.27 1.27)
				)
			)
		)
		(duplicate_pad_numbers_are_jumpers no)
		(pad "1" thru_hole circle
			(at 0 0 180)
			(size 0.4572 0.4572)
			(drill 0.2032)
			(layers "*.Cu" "*.Mask")
			(remove_unused_layers no)
			(net "Net_9096")
			(clearance 0.127)
			(thermal_gap 0.127)
			(padstack
				(mode front_inner_back)
				(layer "Inner"
					(shape circle)
					(size 0.4572 0.4572)
					(clearance 0.127)
				)
				(layer "B.Cu"
					(shape circle)
					(size 0.508 0.508)
					(clearance 0.1016)
				)
			)
		)
	)
	(footprint ""
		(layer "F.Cu")
		(at 387.06044 -96.1644)
		(property "Reference" "R348"
			(at 0 0 0)
			(layer "F.SilkS")
			(hide yes)
			(effects
				(font
					(size 1.27 1.27)
				)
			)
		)
		(property "Value" ""
			(at 0 0 0)
			(layer "F.Fab")
			(effects
				(font
					(size 1.27 1.27)
				)
			)
		)
		(duplicate_pad_numbers_are_jumpers no)
		(fp_line
			(start -0.7874 -0.4064)
			(end 0.7874 -0.4064)
			(stroke
				(width 0.1524)
				(type default)
			)
			(layer "F.SilkS")
		)
		(fp_line
			(start -0.7874 0.4064)
			(end -0.7874 -0.4064)
			(stroke
				(width 0.1524)
				(type default)
			)
			(layer "F.SilkS")
		)
		(fp_line
			(start 0.7874 -0.4064)
			(end 0.7874 0.4064)
			(stroke
				(width 0.1524)
				(type default)
			)
			(layer "F.SilkS")
		)
		(fp_line
			(start 0.7874 0.4064)
			(end -0.7874 0.4064)
			(stroke
				(width 0.1524)
				(type default)
			)
			(layer "F.SilkS")
		)
		(fp_line
			(start -0.67945 -0.305054)
			(end -0.12065 -0.305054)
			(stroke
				(width 0.1)
				(type default)
			)
			(layer "F.Fab")
		)
		(fp_line
			(start -0.67945 0.3048)
			(end -0.67945 -0.305054)
			(stroke
				(width 0.1)
				(type default)
			)
			(layer "F.Fab")
		)
		(fp_line
			(start -0.12065 -0.305054)
			(end -0.12065 -0.2794)
			(stroke
				(width 0.1)
				(type default)
			)
			(layer "F.Fab")
		)
		(fp_line
			(start -0.12065 -0.2794)
			(end 0.12065 -0.2794)
			(stroke
				(width 0.1)
				(type default)
			)
			(layer "F.Fab")
		)
		(fp_line
			(start -0.12065 0.2794)
			(end -0.12065 0.3048)
			(stroke
				(width 0.1)
				(type default)
			)
			(layer "F.Fab")
		)
		(fp_line
			(start -0.12065 0.3048)
			(end -0.67945 0.3048)
			(stroke
				(width 0.1)
				(type default)
			)
			(layer "F.Fab")
		)
		(fp_line
			(start 0.120396 0.2794)
			(end -0.12065 0.2794)
			(stroke
				(width 0.1)
				(type default)
			)
			(layer "F.Fab")
		)
		(fp_line
			(start 0.120396 0.3048)
			(end 0.120396 0.2794)
			(stroke
				(width 0.1)
				(type default)
			)
			(layer "F.Fab")
		)
		(fp_line
			(start 0.12065 -0.3048)
			(end 0.67945 -0.3048)
			(stroke
				(width 0.1)
				(type default)
			)
			(layer "F.Fab")
		)
		(fp_line
			(start 0.12065 -0.2794)
			(end 0.12065 -0.3048)
			(stroke
				(width 0.1)
				(type default)
			)
			(layer "F.Fab")
		)
		(fp_line
			(start 0.67945 -0.3048)
			(end 0.67945 0.3048)
			(stroke
				(width 0.1)
				(type default)
			)
			(layer "F.Fab")
		)
		(fp_line
			(start 0.67945 0.3048)
			(end 0.120396 0.3048)
			(stroke
				(width 0.1)
				(type default)
			)
			(layer "F.Fab")
		)
		(pad "1" smd circle
			(at -0.40005 0)
			(size 0 0)
			(layers "F.Cu" "F.Mask" "F.Paste")
			(net "PRSNT_NIC6_N")
		)
		(pad "2" smd circle
			(at 0.40005 0)
			(size 0 0)
			(layers "F.Cu" "F.Mask" "F.Paste")
			(net "PRSNTB3_NIC6_N")
		)
	)
	(footprint ""
		(layer "F.Cu")
		(at 136.642856 -170.599862 90)
		(property "Reference" "R1097"
			(at 0 0 90)
			(layer "F.SilkS")
			(hide yes)
			(effects
				(font
					(size 1.27 1.27)
				)
			)
		)
		(property "Value" ""
			(at 0 0 90)
			(layer "F.Fab")
			(effects
				(font
					(size 1.27 1.27)
				)
			)
		)
		(duplicate_pad_numbers_are_jumpers no)
		(fp_line
			(start 0.7874 0.4064)
			(end -0.7874 0.4064)
			(stroke
				(width 0.1524)
				(type default)
			)
			(layer "F.SilkS")
		)
		(fp_line
			(start -0.12065 -0.305054)
			(end -0.12065 -0.2794)
			(stroke
				(width 0.1)
				(type default)
			)
			(layer "F.Fab")
		)
		(fp_line
			(start -0.67945 -0.305054)
			(end -0.12065 -0.305054)
			(stroke
				(width 0.1)
				(type default)
			)
			(layer "F.Fab")
		)
		(fp_line
			(start 0.67945 -0.3048)
			(end 0.67945 0.3048)
			(stroke
				(width 0.1)
				(type default)
			)
			(layer "F.Fab")
		)
		(fp_line
			(start 0.12065 -0.3048)
			(end 0.67945 -0.3048)
			(stroke
				(width 0.1)
				(type default)
			)
			(layer "F.Fab")
		)
		(fp_line
			(start 0.12065 -0.2794)
			(end 0.12065 -0.3048)
			(stroke
				(width 0.1)
				(type default)
			)
			(layer "F.Fab")
		)
		(fp_line
			(start -0.12065 -0.2794)
			(end 0.12065 -0.2794)
			(stroke
				(width 0.1)
				(type default)
			)
			(layer "F.Fab")
		)
		(fp_line
			(start 0.120396 0.2794)
			(end -0.12065 0.2794)
			(stroke
				(width 0.1)
				(type default)
			)
			(layer "F.Fab")
		)
		(fp_line
			(start -0.12065 0.2794)
			(end -0.12065 0.3048)
			(stroke
				(width 0.1)
				(type default)
			)
			(layer "F.Fab")
		)
		(fp_line
			(start 0.67945 0.3048)
			(end 0.120396 0.3048)
			(stroke
				(width 0.1)
				(type default)
			)
			(layer "F.Fab")
		)
		(fp_line
			(start 0.120396 0.3048)
			(end 0.120396 0.2794)
			(stroke
				(width 0.1)
				(type default)
			)
			(layer "F.Fab")
		)
		(fp_line
			(start -0.12065 0.3048)
			(end -0.67945 0.3048)
			(stroke
				(width 0.1)
				(type default)
			)
			(layer "F.Fab")
		)
		(fp_line
			(start -0.67945 0.3048)
			(end -0.67945 -0.305054)
			(stroke
				(width 0.1)
				(type default)
			)
			(layer "F.Fab")
		)
		(pad "1" smd circle
			(at -0.40005 0 90)
			(size 0 0)
			(layers "F.Cu" "F.Mask" "F.Paste")
			(net "CLK_100M_DB2000QL_NIC1_R_DN")
		)
		(pad "2" smd circle
			(at 0.40005 0 90)
			(size 0 0)
			(layers "F.Cu" "F.Mask" "F.Paste")
			(net "CLK_100M_DB2000QL_NIC1_DN")
		)
	)
	(footprint ""
		(layer "F.Cu")
		(at 80.341724 -27.006296 -90)
		(property "Reference" "PR6926"
			(at 0 0 270)
			(layer "F.SilkS")
			(hide yes)
			(effects
				(font
					(size 1.27 1.27)
				)
			)
		)
		(property "Value" ""
			(at 0 0 270)
			(layer "F.Fab")
			(effects
				(font
					(size 1.27 1.27)
				)
			)
		)
		(duplicate_pad_numbers_are_jumpers no)
		(fp_line
			(start -0.7874 0.4064)
			(end -0.7874 -0.4064)
			(stroke
				(width 0.1524)
				(type default)
			)
			(layer "F.SilkS")
		)
		(fp_line
			(start 0.7874 0.4064)
			(end -0.7874 0.4064)
			(stroke
				(width 0.1524)
				(type default)
			)
			(layer "F.SilkS")
		)
		(fp_line
			(start -0.7874 -0.4064)
			(end 0.7874 -0.4064)
			(stroke
				(width 0.1524)
				(type default)
			)
			(layer "F.SilkS")
		)
		(fp_line
			(start 0.7874 -0.4064)
			(end 0.7874 0.4064)
			(stroke
				(width 0.1524)
				(type default)
			)
			(layer "F.SilkS")
		)
		(fp_line
			(start -0.67945 0.3048)
			(end -0.67945 -0.305054)
			(stroke
				(width 0.1)
				(type default)
			)
			(layer "F.Fab")
		)
		(fp_line
			(start -0.12065 0.3048)
			(end -0.67945 0.3048)
			(stroke
				(width 0.1)
				(type default)
			)
			(layer "F.Fab")
		)
		(fp_line
			(start 0.120396 0.3048)
			(end 0.120396 0.2794)
			(stroke
				(width 0.1)
				(type default)
			)
			(layer "F.Fab")
		)
		(fp_line
			(start 0.67945 0.3048)
			(end 0.120396 0.3048)
			(stroke
				(width 0.1)
				(type default)
			)
			(layer "F.Fab")
		)
		(fp_line
			(start -0.12065 0.2794)
			(end -0.12065 0.3048)
			(stroke
				(width 0.1)
				(type default)
			)
			(layer "F.Fab")
		)
		(fp_line
			(start 0.120396 0.2794)
			(end -0.12065 0.2794)
			(stroke
				(width 0.1)
				(type default)
			)
			(layer "F.Fab")
		)
		(fp_line
			(start -0.12065 -0.2794)
			(end 0.12065 -0.2794)
			(stroke
				(width 0.1)
				(type default)
			)
			(layer "F.Fab")
		)
		(fp_line
			(start 0.12065 -0.2794)
			(end 0.12065 -0.3048)
			(stroke
				(width 0.1)
				(type default)
			)
			(layer "F.Fab")
		)
		(fp_line
			(start 0.12065 -0.3048)
			(end 0.67945 -0.3048)
			(stroke
				(width 0.1)
				(type default)
			)
			(layer "F.Fab")
		)
		(fp_line
			(start 0.67945 -0.3048)
			(end 0.67945 0.3048)
			(stroke
				(width 0.1)
				(type default)
			)
			(layer "F.Fab")
		)
		(fp_line
			(start -0.67945 -0.305054)
			(end -0.12065 -0.305054)
			(stroke
				(width 0.1)
				(type default)
			)
			(layer "F.Fab")
		)
		(fp_line
			(start -0.12065 -0.305054)
			(end -0.12065 -0.2794)
			(stroke
				(width 0.1)
				(type default)
			)
			(layer "F.Fab")
		)
		(pad "1" smd circle
			(at -0.40005 0 270)
			(size 0 0)
			(layers "F.Cu" "F.Mask" "F.Paste")
			(net "P3V3_SSD3_CO_ILIMIT")
		)
		(pad "2" smd circle
			(at 0.40005 0 270)
			(size 0 0)
			(layers "F.Cu" "F.Mask" "F.Paste")
			(net "GND")
		)
	)
	(footprint ""
		(layer "F.Cu")
		(at 255.867916 -19.453098)
		(property "Reference" "R1695"
			(at 0 0 0)
			(layer "F.SilkS")
			(hide yes)
			(effects
				(font
					(size 1.27 1.27)
				)
			)
		)
		(property "Value" ""
			(at 0 0 0)
			(layer "F.Fab")
			(effects
				(font
					(size 1.27 1.27)
				)
			)
		)
		(duplicate_pad_numbers_are_jumpers no)
		(fp_line
			(start -0.7874 -0.4064)
			(end 0.7874 -0.4064)
			(stroke
				(width 0.1524)
				(type default)
			)
			(layer "F.SilkS")
		)
		(fp_line
			(start -0.7874 0.4064)
			(end -0.7874 -0.4064)
			(stroke
				(width 0.1524)
				(type default)
			)
			(layer "F.SilkS")
		)
		(fp_line
			(start 0.7874 -0.4064)
			(end 0.7874 0.4064)
			(stroke
				(width 0.1524)
				(type default)
			)
			(layer "F.SilkS")
		)
		(fp_line
			(start 0.7874 0.4064)
			(end -0.7874 0.4064)
			(stroke
				(width 0.1524)
				(type default)
			)
			(layer "F.SilkS")
		)
		(fp_line
			(start -0.67945 -0.305054)
			(end -0.12065 -0.305054)
			(stroke
				(width 0.1)
				(type default)
			)
			(layer "F.Fab")
		)
		(fp_line
			(start -0.67945 0.3048)
			(end -0.67945 -0.305054)
			(stroke
				(width 0.1)
				(type default)
			)
			(layer "F.Fab")
		)
		(fp_line
			(start -0.12065 -0.305054)
			(end -0.12065 -0.2794)
			(stroke
				(width 0.1)
				(type default)
			)
			(layer "F.Fab")
		)
		(fp_line
			(start -0.12065 -0.2794)
			(end 0.12065 -0.2794)
			(stroke
				(width 0.1)
				(type default)
			)
			(layer "F.Fab")
		)
		(fp_line
			(start -0.12065 0.2794)
			(end -0.12065 0.3048)
			(stroke
				(width 0.1)
				(type default)
			)
			(layer "F.Fab")
		)
		(fp_line
			(start -0.12065 0.3048)
			(end -0.67945 0.3048)
			(stroke
				(width 0.1)
				(type default)
			)
			(layer "F.Fab")
		)
		(fp_line
			(start 0.120396 0.2794)
			(end -0.12065 0.2794)
			(stroke
				(width 0.1)
				(type default)
			)
			(layer "F.Fab")
		)
		(fp_line
			(start 0.120396 0.3048)
			(end 0.120396 0.2794)
			(stroke
				(width 0.1)
				(type default)
			)
			(layer "F.Fab")
		)
		(fp_line
			(start 0.12065 -0.3048)
			(end 0.67945 -0.3048)
			(stroke
				(width 0.1)
				(type default)
			)
			(layer "F.Fab")
		)
		(fp_line
			(start 0.12065 -0.2794)
			(end 0.12065 -0.3048)
			(stroke
				(width 0.1)
				(type default)
			)
			(layer "F.Fab")
		)
		(fp_line
			(start 0.67945 -0.3048)
			(end 0.67945 0.3048)
			(stroke
				(width 0.1)
				(type default)
			)
			(layer "F.Fab")
		)
		(fp_line
			(start 0.67945 0.3048)
			(end 0.120396 0.3048)
			(stroke
				(width 0.1)
				(type default)
			)
			(layer "F.Fab")
		)
		(pad "1" smd circle
			(at -0.40005 0)
			(size 0 0)
			(layers "F.Cu" "F.Mask" "F.Paste")
			(net "SMB_ISO_SSD8_R_SDA")
		)
		(pad "2" smd circle
			(at 0.40005 0)
			(size 0 0)
			(layers "F.Cu" "F.Mask" "F.Paste")
			(net "SMB_ISO_SSD8_SDA")
		)
	)
	(footprint ""
		(layer "F.Cu")
		(at 454.930002 -251.37364 180)
		(property "Reference" "R6584"
			(at 0 0 180)
			(layer "F.SilkS")
			(hide yes)
			(effects
				(font
					(size 1.27 1.27)
				)
			)
		)
		(property "Value" ""
			(at 0 0 180)
			(layer "F.Fab")
			(effects
				(font
					(size 1.27 1.27)
				)
			)
		)
		(duplicate_pad_numbers_are_jumpers no)
		(fp_line
			(start 0.7874 0.4064)
			(end -0.7874 0.4064)
			(stroke
				(width 0.1524)
				(type default)
			)
			(layer "F.SilkS")
		)
		(fp_line
			(start 0.7874 -0.4064)
			(end 0.7874 0.4064)
			(stroke
				(width 0.1524)
				(type default)
			)
			(layer "F.SilkS")
		)
		(fp_line
			(start -0.7874 0.4064)
			(end -0.7874 -0.4064)
			(stroke
				(width 0.1524)
				(type default)
			)
			(layer "F.SilkS")
		)
		(fp_line
			(start -0.7874 -0.4064)
			(end 0.7874 -0.4064)
			(stroke
				(width 0.1524)
				(type default)
			)
			(layer "F.SilkS")
		)
		(fp_line
			(start 0.67945 0.3048)
			(end 0.120396 0.3048)
			(stroke
				(width 0.1)
				(type default)
			)
			(layer "F.Fab")
		)
		(fp_line
			(start 0.67945 -0.3048)
			(end 0.67945 0.3048)
			(stroke
				(width 0.1)
				(type default)
			)
			(layer "F.Fab")
		)
		(fp_line
			(start 0.12065 -0.2794)
			(end 0.12065 -0.3048)
			(stroke
				(width 0.1)
				(type default)
			)
			(layer "F.Fab")
		)
		(fp_line
			(start 0.12065 -0.3048)
			(end 0.67945 -0.3048)
			(stroke
				(width 0.1)
				(type default)
			)
			(layer "F.Fab")
		)
		(fp_line
			(start 0.120396 0.3048)
			(end 0.120396 0.2794)
			(stroke
				(width 0.1)
				(type default)
			)
			(layer "F.Fab")
		)
		(fp_line
			(start 0.120396 0.2794)
			(end -0.12065 0.2794)
			(stroke
				(width 0.1)
				(type default)
			)
			(layer "F.Fab")
		)
		(fp_line
			(start -0.12065 0.3048)
			(end -0.67945 0.3048)
			(stroke
				(width 0.1)
				(type default)
			)
			(layer "F.Fab")
		)
		(fp_line
			(start -0.12065 0.2794)
			(end -0.12065 0.3048)
			(stroke
				(width 0.1)
				(type default)
			)
			(layer "F.Fab")
		)
		(fp_line
			(start -0.12065 -0.2794)
			(end 0.12065 -0.2794)
			(stroke
				(width 0.1)
				(type default)
			)
			(layer "F.Fab")
		)
		(fp_line
			(start -0.12065 -0.305054)
			(end -0.12065 -0.2794)
			(stroke
				(width 0.1)
				(type default)
			)
			(layer "F.Fab")
		)
		(fp_line
			(start -0.67945 0.3048)
			(end -0.67945 -0.305054)
			(stroke
				(width 0.1)
				(type default)
			)
			(layer "F.Fab")
		)
		(fp_line
			(start -0.67945 -0.305054)
			(end -0.12065 -0.305054)
			(stroke
				(width 0.1)
				(type default)
			)
			(layer "F.Fab")
		)
		(pad "1" smd circle
			(at -0.40005 0 180)
			(size 0 0)
			(layers "F.Cu" "F.Mask" "F.Paste")
			(net "PWR_EN_PEX_R")
		)
		(pad "2" smd circle
			(at 0.40005 0 180)
			(size 0 0)
			(layers "F.Cu" "F.Mask" "F.Paste")
			(net "PEX3_P1V8_PLL_EN")
		)
	)
	(footprint ""
		(layer "F.Cu")
		(at 175.0949 -98.734372)
		(property "Reference" "R154"
			(at 0 0 0)
			(layer "F.SilkS")
			(hide yes)
			(effects
				(font
					(size 1.27 1.27)
				)
			)
		)
		(property "Value" ""
			(at 0 0 0)
			(layer "F.Fab")
			(effects
				(font
					(size 1.27 1.27)
				)
			)
		)
		(duplicate_pad_numbers_are_jumpers no)
		(fp_line
			(start -0.7874 -0.4064)
			(end 0.7874 -0.4064)
			(stroke
				(width 0.1524)
				(type default)
			)
			(layer "F.SilkS")
		)
		(fp_line
			(start -0.7874 0.4064)
			(end -0.7874 -0.4064)
			(stroke
				(width 0.1524)
				(type default)
			)
			(layer "F.SilkS")
		)
		(fp_line
			(start 0.7874 -0.4064)
			(end 0.7874 0.4064)
			(stroke
				(width 0.1524)
				(type default)
			)
			(layer "F.SilkS")
		)
		(fp_line
			(start 0.7874 0.4064)
			(end -0.7874 0.4064)
			(stroke
				(width 0.1524)
				(type default)
			)
			(layer "F.SilkS")
		)
		(fp_line
			(start -0.67945 -0.305054)
			(end -0.12065 -0.305054)
			(stroke
				(width 0.1)
				(type default)
			)
			(layer "F.Fab")
		)
		(fp_line
			(start -0.67945 0.3048)
			(end -0.67945 -0.305054)
			(stroke
				(width 0.1)
				(type default)
			)
			(layer "F.Fab")
		)
		(fp_line
			(start -0.12065 -0.305054)
			(end -0.12065 -0.2794)
			(stroke
				(width 0.1)
				(type default)
			)
			(layer "F.Fab")
		)
		(fp_line
			(start -0.12065 -0.2794)
			(end 0.12065 -0.2794)
			(stroke
				(width 0.1)
				(type default)
			)
			(layer "F.Fab")
		)
		(fp_line
			(start -0.12065 0.2794)
			(end -0.12065 0.3048)
			(stroke
				(width 0.1)
				(type default)
			)
			(layer "F.Fab")
		)
		(fp_line
			(start -0.12065 0.3048)
			(end -0.67945 0.3048)
			(stroke
				(width 0.1)
				(type default)
			)
			(layer "F.Fab")
		)
		(fp_line
			(start 0.120396 0.2794)
			(end -0.12065 0.2794)
			(stroke
				(width 0.1)
				(type default)
			)
			(layer "F.Fab")
		)
		(fp_line
			(start 0.120396 0.3048)
			(end 0.120396 0.2794)
			(stroke
				(width 0.1)
				(type default)
			)
			(layer "F.Fab")
		)
		(fp_line
			(start 0.12065 -0.3048)
			(end 0.67945 -0.3048)
			(stroke
				(width 0.1)
				(type default)
			)
			(layer "F.Fab")
		)
		(fp_line
			(start 0.12065 -0.2794)
			(end 0.12065 -0.3048)
			(stroke
				(width 0.1)
				(type default)
			)
			(layer "F.Fab")
		)
		(fp_line
			(start 0.67945 -0.3048)
			(end 0.67945 0.3048)
			(stroke
				(width 0.1)
				(type default)
			)
			(layer "F.Fab")
		)
		(fp_line
			(start 0.67945 0.3048)
			(end 0.120396 0.3048)
			(stroke
				(width 0.1)
				(type default)
			)
			(layer "F.Fab")
		)
		(pad "1" smd circle
			(at -0.40005 0)
			(size 0 0)
			(layers "F.Cu" "F.Mask" "F.Paste")
			(net "NIC3_RBT_ARB_OUT")
		)
		(pad "2" smd circle
			(at 0.40005 0)
			(size 0 0)
			(layers "F.Cu" "F.Mask" "F.Paste")
			(net "NIC3_RBT_ARB_IN")
		)
	)
	(footprint ""
		(layer "F.Cu")
		(at 154.707844 -162.044126 180)
		(property "Reference" "R124"
			(at 0 0 180)
			(layer "F.SilkS")
			(hide yes)
			(effects
				(font
					(size 1.27 1.27)
				)
			)
		)
		(property "Value" ""
			(at 0 0 180)
			(layer "F.Fab")
			(effects
				(font
					(size 1.27 1.27)
				)
			)
		)
		(duplicate_pad_numbers_are_jumpers no)
		(fp_line
			(start 0.7874 0.4064)
			(end -0.7874 0.4064)
			(stroke
				(width 0.1524)
				(type default)
			)
			(layer "F.SilkS")
		)
		(fp_line
			(start 0.7874 -0.4064)
			(end 0.7874 0.4064)
			(stroke
				(width 0.1524)
				(type default)
			)
			(layer "F.SilkS")
		)
		(fp_line
			(start -0.7874 0.4064)
			(end -0.7874 -0.4064)
			(stroke
				(width 0.1524)
				(type default)
			)
			(layer "F.SilkS")
		)
		(fp_line
			(start -0.7874 -0.4064)
			(end 0.7874 -0.4064)
			(stroke
				(width 0.1524)
				(type default)
			)
			(layer "F.SilkS")
		)
		(fp_line
			(start 0.67945 0.3048)
			(end 0.120396 0.3048)
			(stroke
				(width 0.1)
				(type default)
			)
			(layer "F.Fab")
		)
		(fp_line
			(start 0.67945 -0.3048)
			(end 0.67945 0.3048)
			(stroke
				(width 0.1)
				(type default)
			)
			(layer "F.Fab")
		)
		(fp_line
			(start 0.12065 -0.2794)
			(end 0.12065 -0.3048)
			(stroke
				(width 0.1)
				(type default)
			)
			(layer "F.Fab")
		)
		(fp_line
			(start 0.12065 -0.3048)
			(end 0.67945 -0.3048)
			(stroke
				(width 0.1)
				(type default)
			)
			(layer "F.Fab")
		)
		(fp_line
			(start 0.120396 0.3048)
			(end 0.120396 0.2794)
			(stroke
				(width 0.1)
				(type default)
			)
			(layer "F.Fab")
		)
		(fp_line
			(start 0.120396 0.2794)
			(end -0.12065 0.2794)
			(stroke
				(width 0.1)
				(type default)
			)
			(layer "F.Fab")
		)
		(fp_line
			(start -0.12065 0.3048)
			(end -0.67945 0.3048)
			(stroke
				(width 0.1)
				(type default)
			)
			(layer "F.Fab")
		)
		(fp_line
			(start -0.12065 0.2794)
			(end -0.12065 0.3048)
			(stroke
				(width 0.1)
				(type default)
			)
			(layer "F.Fab")
		)
		(fp_line
			(start -0.12065 -0.2794)
			(end 0.12065 -0.2794)
			(stroke
				(width 0.1)
				(type default)
			)
			(layer "F.Fab")
		)
		(fp_line
			(start -0.12065 -0.305054)
			(end -0.12065 -0.2794)
			(stroke
				(width 0.1)
				(type default)
			)
			(layer "F.Fab")
		)
		(fp_line
			(start -0.67945 0.3048)
			(end -0.67945 -0.305054)
			(stroke
				(width 0.1)
				(type default)
			)
			(layer "F.Fab")
		)
		(fp_line
			(start -0.67945 -0.305054)
			(end -0.12065 -0.305054)
			(stroke
				(width 0.1)
				(type default)
			)
			(layer "F.Fab")
		)
		(pad "1" smd circle
			(at -0.40005 0 180)
			(size 0 0)
			(layers "F.Cu" "F.Mask" "F.Paste")
			(net "PWRGD_NIC2_PWR_GOOD")
		)
		(pad "2" smd circle
			(at 0.40005 0 180)
			(size 0 0)
			(layers "F.Cu" "F.Mask" "F.Paste")
			(net "GND")
		)
	)
	(footprint ""
		(layer "F.Cu")
		(at 80.019398 -129.880106 180)
		(property "Reference" "C24"
			(at 0 0 180)
			(layer "F.SilkS")
			(hide yes)
			(effects
				(font
					(size 1.27 1.27)
				)
			)
		)
		(property "Value" ""
			(at 0 0 180)
			(layer "F.Fab")
			(effects
				(font
					(size 1.27 1.27)
				)
			)
		)
		(duplicate_pad_numbers_are_jumpers no)
		(fp_line
			(start 0.299974 0.150114)
			(end -0.299974 0.150114)
			(stroke
				(width 0.1)
				(type default)
			)
			(layer "F.Fab")
		)
		(fp_line
			(start 0.299974 -0.150114)
			(end 0.299974 0.150114)
			(stroke
				(width 0.1)
				(type default)
			)
			(layer "F.Fab")
		)
		(fp_line
			(start -0.299974 0.150114)
			(end -0.299974 -0.150114)
			(stroke
				(width 0.1)
				(type default)
			)
			(layer "F.Fab")
		)
		(fp_line
			(start -0.299974 -0.150114)
			(end 0.299974 -0.150114)
			(stroke
				(width 0.1)
				(type default)
			)
			(layer "F.Fab")
		)
		(pad "1" smd rect
			(at -0.2667 0 180)
			(size 0.3048 0.381)
			(layers "F.Cu" "F.Mask" "F.Paste")
			(net "P5E_PEX0_STN0_TX_DN<4>")
		)
		(pad "2" smd rect
			(at 0.2667 0 180)
			(size 0.3048 0.381)
			(layers "F.Cu" "F.Mask" "F.Paste")
			(net "P5E_PEX0_STN0_TX_C_DN<4>")
		)
	)
	(footprint ""
		(layer "F.Cu")
		(at 463.502756 -254.35433 -90)
		(property "Reference" "C4413"
			(at 0 0 270)
			(layer "F.SilkS")
			(hide yes)
			(effects
				(font
					(size 1.27 1.27)
				)
			)
		)
		(property "Value" ""
			(at 0 0 270)
			(layer "F.Fab")
			(effects
				(font
					(size 1.27 1.27)
				)
			)
		)
		(duplicate_pad_numbers_are_jumpers no)
		(fp_line
			(start -1.524 0.762)
			(end -1.524 -0.762)
			(stroke
				(width 0.1524)
				(type default)
			)
			(layer "F.SilkS")
		)
		(fp_line
			(start 1.524 0.762)
			(end -1.524 0.762)
			(stroke
				(width 0.1524)
				(type default)
			)
			(layer "F.SilkS")
		)
		(fp_line
			(start -1.524 -0.762)
			(end 1.524 -0.762)
			(stroke
				(width 0.1524)
				(type default)
			)
			(layer "F.SilkS")
		)
		(fp_line
			(start 1.524 -0.762)
			(end 1.524 0.762)
			(stroke
				(width 0.1524)
				(type default)
			)
			(layer "F.SilkS")
		)
		(fp_line
			(start -1.1049 0.724916)
			(end 1.1049 0.724916)
			(stroke
				(width 0.1)
				(type default)
			)
			(layer "F.Fab")
		)
		(fp_line
			(start 1.1049 0.724916)
			(end 1.1049 -0.724916)
			(stroke
				(width 0.1)
				(type default)
			)
			(layer "F.Fab")
		)
		(fp_line
			(start -1.1049 -0.724916)
			(end -1.1049 0.724916)
			(stroke
				(width 0.1)
				(type default)
			)
			(layer "F.Fab")
		)
		(fp_line
			(start 1.1049 -0.724916)
			(end -1.1049 -0.724916)
			(stroke
				(width 0.1)
				(type default)
			)
			(layer "F.Fab")
		)
		(pad "1" smd rect
			(at -0.889 0 90)
			(size 1.016 1.27)
			(layers "F.Cu" "F.Mask" "F.Paste")
			(net "P1V25_SERDES_VDDPLL_PEX3_C11")
		)
		(pad "2" smd rect
			(at 0.889 0 90)
			(size 1.016 1.27)
			(layers "F.Cu" "F.Mask" "F.Paste")
			(net "GND")
		)
		(zone
			(layer "F.Cu")
			(hatch none 0.5)
			(connect_pads
				(clearance 0)
			)
			(min_thickness 0.25)
			(keepout
				(tracks not_allowed)
				(vias allowed)
				(pads allowed)
				(copperpour not_allowed)
				(footprints allowed)
			)
			(placement
				(enabled no)
				(sheetname "")
			)
			(fill
				(thermal_gap 0.5)
				(thermal_bridge_width 0.5)
				(island_removal_mode 0)
			)
			(polygon
				(pts
					(xy 464.227672 -254.68453) (xy 462.77784 -254.68453) (xy 462.77784 -254.02413) (xy 464.227672 -254.02413)
				)
			)
		)
	)
	(footprint ""
		(layer "F.Cu")
		(at 459.324202 -246.80164 90)
		(property "Reference" "R6585"
			(at 0 0 90)
			(layer "F.SilkS")
			(hide yes)
			(effects
				(font
					(size 1.27 1.27)
				)
			)
		)
		(property "Value" ""
			(at 0 0 90)
			(layer "F.Fab")
			(effects
				(font
					(size 1.27 1.27)
				)
			)
		)
		(duplicate_pad_numbers_are_jumpers no)
		(fp_line
			(start 0.7874 -0.4064)
			(end 0.7874 0.4064)
			(stroke
				(width 0.1524)
				(type default)
			)
			(layer "F.SilkS")
		)
		(fp_line
			(start -0.7874 -0.4064)
			(end 0.7874 -0.4064)
			(stroke
				(width 0.1524)
				(type default)
			)
			(layer "F.SilkS")
		)
		(fp_line
			(start 0.7874 0.4064)
			(end -0.7874 0.4064)
			(stroke
				(width 0.1524)
				(type default)
			)
			(layer "F.SilkS")
		)
		(fp_line
			(start -0.7874 0.4064)
			(end -0.7874 -0.4064)
			(stroke
				(width 0.1524)
				(type default)
			)
			(layer "F.SilkS")
		)
		(fp_line
			(start -0.12065 -0.305054)
			(end -0.12065 -0.2794)
			(stroke
				(width 0.1)
				(type default)
			)
			(layer "F.Fab")
		)
		(fp_line
			(start -0.67945 -0.305054)
			(end -0.12065 -0.305054)
			(stroke
				(width 0.1)
				(type default)
			)
			(layer "F.Fab")
		)
		(fp_line
			(start 0.67945 -0.3048)
			(end 0.67945 0.3048)
			(stroke
				(width 0.1)
				(type default)
			)
			(layer "F.Fab")
		)
		(fp_line
			(start 0.12065 -0.3048)
			(end 0.67945 -0.3048)
			(stroke
				(width 0.1)
				(type default)
			)
			(layer "F.Fab")
		)
		(fp_line
			(start 0.12065 -0.2794)
			(end 0.12065 -0.3048)
			(stroke
				(width 0.1)
				(type default)
			)
			(layer "F.Fab")
		)
		(fp_line
			(start -0.12065 -0.2794)
			(end 0.12065 -0.2794)
			(stroke
				(width 0.1)
				(type default)
			)
			(layer "F.Fab")
		)
		(fp_line
			(start 0.120396 0.2794)
			(end -0.12065 0.2794)
			(stroke
				(width 0.1)
				(type default)
			)
			(layer "F.Fab")
		)
		(fp_line
			(start -0.12065 0.2794)
			(end -0.12065 0.3048)
			(stroke
				(width 0.1)
				(type default)
			)
			(layer "F.Fab")
		)
		(fp_line
			(start 0.67945 0.3048)
			(end 0.120396 0.3048)
			(stroke
				(width 0.1)
				(type default)
			)
			(layer "F.Fab")
		)
		(fp_line
			(start 0.120396 0.3048)
			(end 0.120396 0.2794)
			(stroke
				(width 0.1)
				(type default)
			)
			(layer "F.Fab")
		)
		(fp_line
			(start -0.12065 0.3048)
			(end -0.67945 0.3048)
			(stroke
				(width 0.1)
				(type default)
			)
			(layer "F.Fab")
		)
		(fp_line
			(start -0.67945 0.3048)
			(end -0.67945 -0.305054)
			(stroke
				(width 0.1)
				(type default)
			)
			(layer "F.Fab")
		)
		(pad "1" smd circle
			(at -0.40005 0 90)
			(size 0 0)
			(layers "F.Cu" "F.Mask" "F.Paste")
			(net "P1V8_PLL0_PEX3")
		)
		(pad "2" smd circle
			(at 0.40005 0 90)
			(size 0 0)
			(layers "F.Cu" "F.Mask" "F.Paste")
			(net "P1V8_PLL_PEX3_ADJ")
		)
	)
	(footprint ""
		(layer "F.Cu")
		(at 225.39706 -278.675846 90)
		(property "Reference" "C629"
			(at 0 0 90)
			(layer "F.SilkS")
			(hide yes)
			(effects
				(font
					(size 1.27 1.27)
				)
			)
		)
		(property "Value" ""
			(at 0 0 90)
			(layer "F.Fab")
			(effects
				(font
					(size 1.27 1.27)
				)
			)
		)
		(duplicate_pad_numbers_are_jumpers no)
		(fp_line
			(start 0.7874 -0.4064)
			(end 0.7874 0.4064)
			(stroke
				(width 0.1524)
				(type default)
			)
			(layer "F.SilkS")
		)
		(fp_line
			(start -0.7874 -0.4064)
			(end 0.7874 -0.4064)
			(stroke
				(width 0.1524)
				(type default)
			)
			(layer "F.SilkS")
		)
		(fp_line
			(start 0.7874 0.4064)
			(end -0.7874 0.4064)
			(stroke
				(width 0.1524)
				(type default)
			)
			(layer "F.SilkS")
		)
		(fp_line
			(start -0.7874 0.4064)
			(end -0.7874 -0.4064)
			(stroke
				(width 0.1524)
				(type default)
			)
			(layer "F.SilkS")
		)
		(fp_line
			(start -0.12065 -0.305054)
			(end -0.12065 -0.2794)
			(stroke
				(width 0.1)
				(type default)
			)
			(layer "F.Fab")
		)
		(fp_line
			(start -0.67945 -0.305054)
			(end -0.12065 -0.305054)
			(stroke
				(width 0.1)
				(type default)
			)
			(layer "F.Fab")
		)
		(fp_line
			(start 0.67945 -0.3048)
			(end 0.67945 0.3048)
			(stroke
				(width 0.1)
				(type default)
			)
			(layer "F.Fab")
		)
		(fp_line
			(start 0.12065 -0.3048)
			(end 0.67945 -0.3048)
			(stroke
				(width 0.1)
				(type default)
			)
			(layer "F.Fab")
		)
		(fp_line
			(start 0.12065 -0.2794)
			(end 0.12065 -0.3048)
			(stroke
				(width 0.1)
				(type default)
			)
			(layer "F.Fab")
		)
		(fp_line
			(start -0.12065 -0.2794)
			(end 0.12065 -0.2794)
			(stroke
				(width 0.1)
				(type default)
			)
			(layer "F.Fab")
		)
		(fp_line
			(start 0.120396 0.2794)
			(end -0.12065 0.2794)
			(stroke
				(width 0.1)
				(type default)
			)
			(layer "F.Fab")
		)
		(fp_line
			(start -0.12065 0.2794)
			(end -0.12065 0.3048)
			(stroke
				(width 0.1)
				(type default)
			)
			(layer "F.Fab")
		)
		(fp_line
			(start 0.67945 0.3048)
			(end 0.120396 0.3048)
			(stroke
				(width 0.1)
				(type default)
			)
			(layer "F.Fab")
		)
		(fp_line
			(start 0.120396 0.3048)
			(end 0.120396 0.2794)
			(stroke
				(width 0.1)
				(type default)
			)
			(layer "F.Fab")
		)
		(fp_line
			(start -0.12065 0.3048)
			(end -0.67945 0.3048)
			(stroke
				(width 0.1)
				(type default)
			)
			(layer "F.Fab")
		)
		(fp_line
			(start -0.67945 0.3048)
			(end -0.67945 -0.305054)
			(stroke
				(width 0.1)
				(type default)
			)
			(layer "F.Fab")
		)
		(pad "1" smd circle
			(at -0.40005 0 90)
			(size 0 0)
			(layers "F.Cu" "F.Mask" "F.Paste")
			(net "P1V25_PEX1_R")
		)
		(pad "2" smd circle
			(at 0.40005 0 90)
			(size 0 0)
			(layers "F.Cu" "F.Mask" "F.Paste")
			(net "GND")
		)
	)
	(footprint ""
		(layer "F.Cu")
		(at 412.378652 -350.098614 90)
		(property "Reference" "C822"
			(at 0 0 90)
			(layer "F.SilkS")
			(hide yes)
			(effects
				(font
					(size 1.27 1.27)
				)
			)
		)
		(property "Value" ""
			(at 0 0 90)
			(layer "F.Fab")
			(effects
				(font
					(size 1.27 1.27)
				)
			)
		)
		(duplicate_pad_numbers_are_jumpers no)
		(fp_line
			(start 0.299974 -0.150114)
			(end 0.299974 0.150114)
			(stroke
				(width 0.1)
				(type default)
			)
			(layer "F.Fab")
		)
		(fp_line
			(start -0.299974 -0.150114)
			(end 0.299974 -0.150114)
			(stroke
				(width 0.1)
				(type default)
			)
			(layer "F.Fab")
		)
		(fp_line
			(start 0.299974 0.150114)
			(end -0.299974 0.150114)
			(stroke
				(width 0.1)
				(type default)
			)
			(layer "F.Fab")
		)
		(fp_line
			(start -0.299974 0.150114)
			(end -0.299974 -0.150114)
			(stroke
				(width 0.1)
				(type default)
			)
			(layer "F.Fab")
		)
		(pad "1" smd rect
			(at -0.2667 0 90)
			(size 0.3048 0.381)
			(layers "F.Cu" "F.Mask" "F.Paste")
			(net "P5E_PEX3_STN7_TX_DP<113>")
		)
		(pad "2" smd rect
			(at 0.2667 0 90)
			(size 0.3048 0.381)
			(layers "F.Cu" "F.Mask" "F.Paste")
			(net "P5E_PEX3_STN7_TX_C_DP<113>")
		)
	)
	(footprint ""
		(layer "F.Cu")
		(at 420.73449 -34.546286 180)
		(property "Reference" "C714"
			(at 0 0 180)
			(layer "F.SilkS")
			(hide yes)
			(effects
				(font
					(size 1.27 1.27)
				)
			)
		)
		(property "Value" ""
			(at 0 0 180)
			(layer "F.Fab")
			(effects
				(font
					(size 1.27 1.27)
				)
			)
		)
		(duplicate_pad_numbers_are_jumpers no)
		(fp_line
			(start 0.299974 0.150114)
			(end -0.299974 0.150114)
			(stroke
				(width 0.1)
				(type default)
			)
			(layer "F.Fab")
		)
		(fp_line
			(start 0.299974 -0.150114)
			(end 0.299974 0.150114)
			(stroke
				(width 0.1)
				(type default)
			)
			(layer "F.Fab")
		)
		(fp_line
			(start -0.299974 0.150114)
			(end -0.299974 -0.150114)
			(stroke
				(width 0.1)
				(type default)
			)
			(layer "F.Fab")
		)
		(fp_line
			(start -0.299974 -0.150114)
			(end 0.299974 -0.150114)
			(stroke
				(width 0.1)
				(type default)
			)
			(layer "F.Fab")
		)
		(pad "1" smd rect
			(at -0.2667 0 180)
			(size 0.3048 0.381)
			(layers "F.Cu" "F.Mask" "F.Paste")
			(net "P5E_PEX3_STN2_TX_DP<39>")
		)
		(pad "2" smd rect
			(at 0.2667 0 180)
			(size 0.3048 0.381)
			(layers "F.Cu" "F.Mask" "F.Paste")
			(net "P5E_PEX3_STN2_TX_C_DP<39>")
		)
	)
	(footprint ""
		(layer "F.Cu")
		(at 92.28328 -113.628678)
		(property "Reference" "PC659"
			(at 0 0 0)
			(layer "F.SilkS")
			(hide yes)
			(effects
				(font
					(size 1.27 1.27)
				)
			)
		)
		(property "Value" ""
			(at 0 0 0)
			(layer "F.Fab")
			(effects
				(font
					(size 1.27 1.27)
				)
			)
		)
		(duplicate_pad_numbers_are_jumpers no)
		(fp_line
			(start -0.7874 -0.4064)
			(end 0.7874 -0.4064)
			(stroke
				(width 0.1524)
				(type default)
			)
			(layer "F.SilkS")
		)
		(fp_line
			(start -0.7874 0.4064)
			(end -0.7874 -0.4064)
			(stroke
				(width 0.1524)
				(type default)
			)
			(layer "F.SilkS")
		)
		(fp_line
			(start 0.7874 -0.4064)
			(end 0.7874 0.4064)
			(stroke
				(width 0.1524)
				(type default)
			)
			(layer "F.SilkS")
		)
		(fp_line
			(start 0.7874 0.4064)
			(end -0.7874 0.4064)
			(stroke
				(width 0.1524)
				(type default)
			)
			(layer "F.SilkS")
		)
		(fp_line
			(start -0.67945 -0.305054)
			(end -0.12065 -0.305054)
			(stroke
				(width 0.1)
				(type default)
			)
			(layer "F.Fab")
		)
		(fp_line
			(start -0.67945 0.3048)
			(end -0.67945 -0.305054)
			(stroke
				(width 0.1)
				(type default)
			)
			(layer "F.Fab")
		)
		(fp_line
			(start -0.12065 -0.305054)
			(end -0.12065 -0.2794)
			(stroke
				(width 0.1)
				(type default)
			)
			(layer "F.Fab")
		)
		(fp_line
			(start -0.12065 -0.2794)
			(end 0.12065 -0.2794)
			(stroke
				(width 0.1)
				(type default)
			)
			(layer "F.Fab")
		)
		(fp_line
			(start -0.12065 0.2794)
			(end -0.12065 0.3048)
			(stroke
				(width 0.1)
				(type default)
			)
			(layer "F.Fab")
		)
		(fp_line
			(start -0.12065 0.3048)
			(end -0.67945 0.3048)
			(stroke
				(width 0.1)
				(type default)
			)
			(layer "F.Fab")
		)
		(fp_line
			(start 0.120396 0.2794)
			(end -0.12065 0.2794)
			(stroke
				(width 0.1)
				(type default)
			)
			(layer "F.Fab")
		)
		(fp_line
			(start 0.120396 0.3048)
			(end 0.120396 0.2794)
			(stroke
				(width 0.1)
				(type default)
			)
			(layer "F.Fab")
		)
		(fp_line
			(start 0.12065 -0.3048)
			(end 0.67945 -0.3048)
			(stroke
				(width 0.1)
				(type default)
			)
			(layer "F.Fab")
		)
		(fp_line
			(start 0.12065 -0.2794)
			(end 0.12065 -0.3048)
			(stroke
				(width 0.1)
				(type default)
			)
			(layer "F.Fab")
		)
		(fp_line
			(start 0.67945 -0.3048)
			(end 0.67945 0.3048)
			(stroke
				(width 0.1)
				(type default)
			)
			(layer "F.Fab")
		)
		(fp_line
			(start 0.67945 0.3048)
			(end 0.120396 0.3048)
			(stroke
				(width 0.1)
				(type default)
			)
			(layer "F.Fab")
		)
		(pad "1" smd circle
			(at -0.40005 0)
			(size 0 0)
			(layers "F.Cu" "F.Mask" "F.Paste")
			(net "P3V3_AUX")
		)
		(pad "2" smd circle
			(at 0.40005 0)
			(size 0 0)
			(layers "F.Cu" "F.Mask" "F.Paste")
			(net "GND")
		)
	)
	(footprint ""
		(layer "F.Cu")
		(at 291.194998 -96.702372 180)
		(property "Reference" "R302"
			(at 0 0 180)
			(layer "F.SilkS")
			(hide yes)
			(effects
				(font
					(size 1.27 1.27)
				)
			)
		)
		(property "Value" ""
			(at 0 0 180)
			(layer "F.Fab")
			(effects
				(font
					(size 1.27 1.27)
				)
			)
		)
		(duplicate_pad_numbers_are_jumpers no)
		(fp_line
			(start 0.7874 0.4064)
			(end -0.7874 0.4064)
			(stroke
				(width 0.1524)
				(type default)
			)
			(layer "F.SilkS")
		)
		(fp_line
			(start 0.7874 -0.4064)
			(end 0.7874 0.4064)
			(stroke
				(width 0.1524)
				(type default)
			)
			(layer "F.SilkS")
		)
		(fp_line
			(start -0.7874 0.4064)
			(end -0.7874 -0.4064)
			(stroke
				(width 0.1524)
				(type default)
			)
			(layer "F.SilkS")
		)
		(fp_line
			(start -0.7874 -0.4064)
			(end 0.7874 -0.4064)
			(stroke
				(width 0.1524)
				(type default)
			)
			(layer "F.SilkS")
		)
		(fp_line
			(start 0.67945 0.3048)
			(end 0.120396 0.3048)
			(stroke
				(width 0.1)
				(type default)
			)
			(layer "F.Fab")
		)
		(fp_line
			(start 0.67945 -0.3048)
			(end 0.67945 0.3048)
			(stroke
				(width 0.1)
				(type default)
			)
			(layer "F.Fab")
		)
		(fp_line
			(start 0.12065 -0.2794)
			(end 0.12065 -0.3048)
			(stroke
				(width 0.1)
				(type default)
			)
			(layer "F.Fab")
		)
		(fp_line
			(start 0.12065 -0.3048)
			(end 0.67945 -0.3048)
			(stroke
				(width 0.1)
				(type default)
			)
			(layer "F.Fab")
		)
		(fp_line
			(start 0.120396 0.3048)
			(end 0.120396 0.2794)
			(stroke
				(width 0.1)
				(type default)
			)
			(layer "F.Fab")
		)
		(fp_line
			(start 0.120396 0.2794)
			(end -0.12065 0.2794)
			(stroke
				(width 0.1)
				(type default)
			)
			(layer "F.Fab")
		)
		(fp_line
			(start -0.12065 0.3048)
			(end -0.67945 0.3048)
			(stroke
				(width 0.1)
				(type default)
			)
			(layer "F.Fab")
		)
		(fp_line
			(start -0.12065 0.2794)
			(end -0.12065 0.3048)
			(stroke
				(width 0.1)
				(type default)
			)
			(layer "F.Fab")
		)
		(fp_line
			(start -0.12065 -0.2794)
			(end 0.12065 -0.2794)
			(stroke
				(width 0.1)
				(type default)
			)
			(layer "F.Fab")
		)
		(fp_line
			(start -0.12065 -0.305054)
			(end -0.12065 -0.2794)
			(stroke
				(width 0.1)
				(type default)
			)
			(layer "F.Fab")
		)
		(fp_line
			(start -0.67945 0.3048)
			(end -0.67945 -0.305054)
			(stroke
				(width 0.1)
				(type default)
			)
			(layer "F.Fab")
		)
		(fp_line
			(start -0.67945 -0.305054)
			(end -0.12065 -0.305054)
			(stroke
				(width 0.1)
				(type default)
			)
			(layer "F.Fab")
		)
		(pad "1" smd circle
			(at -0.40005 0 180)
			(size 0 0)
			(layers "F.Cu" "F.Mask" "F.Paste")
			(net "RST_NIC5_PERST2_R_N")
		)
		(pad "2" smd circle
			(at 0.40005 0 180)
			(size 0 0)
			(layers "F.Cu" "F.Mask" "F.Paste")
			(net "RST_HP_NIC5_BUF_N")
		)
	)
	(footprint ""
		(layer "F.Cu")
		(at 91.287092 -297.27398 180)
		(property "Reference" "R3874"
			(at 0 0 180)
			(layer "F.SilkS")
			(hide yes)
			(effects
				(font
					(size 1.27 1.27)
				)
			)
		)
		(property "Value" ""
			(at 0 0 180)
			(layer "F.Fab")
			(effects
				(font
					(size 1.27 1.27)
				)
			)
		)
		(duplicate_pad_numbers_are_jumpers no)
		(fp_line
			(start 0.7874 0.4064)
			(end -0.7874 0.4064)
			(stroke
				(width 0.1524)
				(type default)
			)
			(layer "F.SilkS")
		)
		(fp_line
			(start 0.7874 -0.4064)
			(end 0.7874 0.4064)
			(stroke
				(width 0.1524)
				(type default)
			)
			(layer "F.SilkS")
		)
		(fp_line
			(start -0.7874 0.4064)
			(end -0.7874 -0.4064)
			(stroke
				(width 0.1524)
				(type default)
			)
			(layer "F.SilkS")
		)
		(fp_line
			(start -0.7874 -0.4064)
			(end 0.7874 -0.4064)
			(stroke
				(width 0.1524)
				(type default)
			)
			(layer "F.SilkS")
		)
		(fp_line
			(start 0.67945 0.3048)
			(end 0.120396 0.3048)
			(stroke
				(width 0.1)
				(type default)
			)
			(layer "F.Fab")
		)
		(fp_line
			(start 0.67945 -0.3048)
			(end 0.67945 0.3048)
			(stroke
				(width 0.1)
				(type default)
			)
			(layer "F.Fab")
		)
		(fp_line
			(start 0.12065 -0.2794)
			(end 0.12065 -0.3048)
			(stroke
				(width 0.1)
				(type default)
			)
			(layer "F.Fab")
		)
		(fp_line
			(start 0.12065 -0.3048)
			(end 0.67945 -0.3048)
			(stroke
				(width 0.1)
				(type default)
			)
			(layer "F.Fab")
		)
		(fp_line
			(start 0.120396 0.3048)
			(end 0.120396 0.2794)
			(stroke
				(width 0.1)
				(type default)
			)
			(layer "F.Fab")
		)
		(fp_line
			(start 0.120396 0.2794)
			(end -0.12065 0.2794)
			(stroke
				(width 0.1)
				(type default)
			)
			(layer "F.Fab")
		)
		(fp_line
			(start -0.12065 0.3048)
			(end -0.67945 0.3048)
			(stroke
				(width 0.1)
				(type default)
			)
			(layer "F.Fab")
		)
		(fp_line
			(start -0.12065 0.2794)
			(end -0.12065 0.3048)
			(stroke
				(width 0.1)
				(type default)
			)
			(layer "F.Fab")
		)
		(fp_line
			(start -0.12065 -0.2794)
			(end 0.12065 -0.2794)
			(stroke
				(width 0.1)
				(type default)
			)
			(layer "F.Fab")
		)
		(fp_line
			(start -0.12065 -0.305054)
			(end -0.12065 -0.2794)
			(stroke
				(width 0.1)
				(type default)
			)
			(layer "F.Fab")
		)
		(fp_line
			(start -0.67945 0.3048)
			(end -0.67945 -0.305054)
			(stroke
				(width 0.1)
				(type default)
			)
			(layer "F.Fab")
		)
		(fp_line
			(start -0.67945 -0.305054)
			(end -0.12065 -0.305054)
			(stroke
				(width 0.1)
				(type default)
			)
			(layer "F.Fab")
		)
		(pad "1" smd circle
			(at -0.40005 0 180)
			(size 0 0)
			(layers "F.Cu" "F.Mask" "F.Paste")
			(net "SMB_PEX0_HOST_LS_SCL")
		)
		(pad "2" smd circle
			(at 0.40005 0 180)
			(size 0 0)
			(layers "F.Cu" "F.Mask" "F.Paste")
			(net "I2C_PEX0_HOST_R_SCL")
		)
	)
	(footprint ""
		(layer "F.Cu")
		(at 123.100592 -293.5351 90)
		(property "Reference" "PL9"
			(at -4.260596 15.498318 90)
			(unlocked yes)
			(layer "F.SilkS")
			(effects
				(font
					(size 0.7874 0.5842)
					(thickness 0.1524)
				)
				(justify left)
			)
		)
		(property "Value" ""
			(at 0 0 90)
			(layer "F.Fab")
			(effects
				(font
					(size 1.27 1.27)
				)
			)
		)
		(duplicate_pad_numbers_are_jumpers no)
		(fp_line
			(start 4.800092 -3.199892)
			(end 4.800092 -1.6764)
			(stroke
				(width 0.1524)
				(type default)
			)
			(layer "F.SilkS")
		)
		(fp_line
			(start -4.800092 -3.199892)
			(end 4.800092 -3.199892)
			(stroke
				(width 0.1524)
				(type default)
			)
			(layer "F.SilkS")
		)
		(fp_line
			(start -4.800092 -1.6764)
			(end -4.800092 -3.199892)
			(stroke
				(width 0.1524)
				(type default)
			)
			(layer "F.SilkS")
		)
		(fp_line
			(start 4.800092 1.6764)
			(end 4.800092 3.199892)
			(stroke
				(width 0.1524)
				(type default)
			)
			(layer "F.SilkS")
		)
		(fp_line
			(start 4.800092 3.199892)
			(end -4.800092 3.199892)
			(stroke
				(width 0.1524)
				(type default)
			)
			(layer "F.SilkS")
		)
		(fp_line
			(start -4.800092 3.199892)
			(end -4.800092 1.6764)
			(stroke
				(width 0.1524)
				(type default)
			)
			(layer "F.SilkS")
		)
		(fp_line
			(start 4.800092 -3.199892)
			(end 4.800092 3.199892)
			(stroke
				(width 0.1)
				(type default)
			)
			(layer "F.Fab")
		)
		(fp_line
			(start -4.800092 -3.199892)
			(end 4.800092 -3.199892)
			(stroke
				(width 0.1)
				(type default)
			)
			(layer "F.Fab")
		)
		(fp_line
			(start 4.800092 3.199892)
			(end -4.800092 3.199892)
			(stroke
				(width 0.1)
				(type default)
			)
			(layer "F.Fab")
		)
		(fp_line
			(start -4.800092 3.199892)
			(end -4.800092 -3.199892)
			(stroke
				(width 0.1)
				(type default)
			)
			(layer "F.Fab")
		)
		(pad "1" smd rect
			(at -3.074924 0 180)
			(size 3.0988 3.3528)
			(layers "F.Cu" "F.Mask" "F.Paste")
			(net "SW_P0V8_PEX1_PH1")
		)
		(pad "2" smd rect
			(at 3.074924 0 180)
			(size 3.0988 3.3528)
			(layers "F.Cu" "F.Mask" "F.Paste")
			(net "P0V8_PEX1")
		)
	)
	(footprint ""
		(layer "F.Cu")
		(at 459.6638 -230.7844 90)
		(property "Reference" "R6607"
			(at 0 0 90)
			(layer "F.SilkS")
			(hide yes)
			(effects
				(font
					(size 1.27 1.27)
				)
			)
		)
		(property "Value" ""
			(at 0 0 90)
			(layer "F.Fab")
			(effects
				(font
					(size 1.27 1.27)
				)
			)
		)
		(duplicate_pad_numbers_are_jumpers no)
		(fp_line
			(start 0.7874 -0.4064)
			(end 0.7874 0.4064)
			(stroke
				(width 0.1524)
				(type default)
			)
			(layer "F.SilkS")
		)
		(fp_line
			(start -0.7874 -0.4064)
			(end 0.7874 -0.4064)
			(stroke
				(width 0.1524)
				(type default)
			)
			(layer "F.SilkS")
		)
		(fp_line
			(start 0.7874 0.4064)
			(end -0.7874 0.4064)
			(stroke
				(width 0.1524)
				(type default)
			)
			(layer "F.SilkS")
		)
		(fp_line
			(start -0.7874 0.4064)
			(end -0.7874 -0.4064)
			(stroke
				(width 0.1524)
				(type default)
			)
			(layer "F.SilkS")
		)
		(fp_line
			(start -0.12065 -0.305054)
			(end -0.12065 -0.2794)
			(stroke
				(width 0.1)
				(type default)
			)
			(layer "F.Fab")
		)
		(fp_line
			(start -0.67945 -0.305054)
			(end -0.12065 -0.305054)
			(stroke
				(width 0.1)
				(type default)
			)
			(layer "F.Fab")
		)
		(fp_line
			(start 0.67945 -0.3048)
			(end 0.67945 0.3048)
			(stroke
				(width 0.1)
				(type default)
			)
			(layer "F.Fab")
		)
		(fp_line
			(start 0.12065 -0.3048)
			(end 0.67945 -0.3048)
			(stroke
				(width 0.1)
				(type default)
			)
			(layer "F.Fab")
		)
		(fp_line
			(start 0.12065 -0.2794)
			(end 0.12065 -0.3048)
			(stroke
				(width 0.1)
				(type default)
			)
			(layer "F.Fab")
		)
		(fp_line
			(start -0.12065 -0.2794)
			(end 0.12065 -0.2794)
			(stroke
				(width 0.1)
				(type default)
			)
			(layer "F.Fab")
		)
		(fp_line
			(start 0.120396 0.2794)
			(end -0.12065 0.2794)
			(stroke
				(width 0.1)
				(type default)
			)
			(layer "F.Fab")
		)
		(fp_line
			(start -0.12065 0.2794)
			(end -0.12065 0.3048)
			(stroke
				(width 0.1)
				(type default)
			)
			(layer "F.Fab")
		)
		(fp_line
			(start 0.67945 0.3048)
			(end 0.120396 0.3048)
			(stroke
				(width 0.1)
				(type default)
			)
			(layer "F.Fab")
		)
		(fp_line
			(start 0.120396 0.3048)
			(end 0.120396 0.2794)
			(stroke
				(width 0.1)
				(type default)
			)
			(layer "F.Fab")
		)
		(fp_line
			(start -0.12065 0.3048)
			(end -0.67945 0.3048)
			(stroke
				(width 0.1)
				(type default)
			)
			(layer "F.Fab")
		)
		(fp_line
			(start -0.67945 0.3048)
			(end -0.67945 -0.305054)
			(stroke
				(width 0.1)
				(type default)
			)
			(layer "F.Fab")
		)
		(pad "1" smd circle
			(at -0.40005 0 90)
			(size 0 0)
			(layers "F.Cu" "F.Mask" "F.Paste")
			(net "UART_PEX1_SDB_BUF_R_TX")
		)
		(pad "2" smd circle
			(at 0.40005 0 90)
			(size 0 0)
			(layers "F.Cu" "F.Mask" "F.Paste")
			(net "UART_PEX1_SDB_CP2108_TX")
		)
	)
	(footprint ""
		(layer "F.Cu")
		(at 366.938814 -22.867366 90)
		(property "Reference" "C3957"
			(at 0 0 90)
			(layer "F.SilkS")
			(hide yes)
			(effects
				(font
					(size 1.27 1.27)
				)
			)
		)
		(property "Value" ""
			(at 0 0 90)
			(layer "F.Fab")
			(effects
				(font
					(size 1.27 1.27)
				)
			)
		)
		(duplicate_pad_numbers_are_jumpers no)
		(fp_line
			(start 0.7874 -0.4064)
			(end 0.7874 0.4064)
			(stroke
				(width 0.1524)
				(type default)
			)
			(layer "F.SilkS")
		)
		(fp_line
			(start -0.7874 -0.4064)
			(end 0.7874 -0.4064)
			(stroke
				(width 0.1524)
				(type default)
			)
			(layer "F.SilkS")
		)
		(fp_line
			(start 0.7874 0.4064)
			(end -0.7874 0.4064)
			(stroke
				(width 0.1524)
				(type default)
			)
			(layer "F.SilkS")
		)
		(fp_line
			(start -0.7874 0.4064)
			(end -0.7874 -0.4064)
			(stroke
				(width 0.1524)
				(type default)
			)
			(layer "F.SilkS")
		)
		(fp_line
			(start -0.12065 -0.305054)
			(end -0.12065 -0.2794)
			(stroke
				(width 0.1)
				(type default)
			)
			(layer "F.Fab")
		)
		(fp_line
			(start -0.67945 -0.305054)
			(end -0.12065 -0.305054)
			(stroke
				(width 0.1)
				(type default)
			)
			(layer "F.Fab")
		)
		(fp_line
			(start 0.67945 -0.3048)
			(end 0.67945 0.3048)
			(stroke
				(width 0.1)
				(type default)
			)
			(layer "F.Fab")
		)
		(fp_line
			(start 0.12065 -0.3048)
			(end 0.67945 -0.3048)
			(stroke
				(width 0.1)
				(type default)
			)
			(layer "F.Fab")
		)
		(fp_line
			(start 0.12065 -0.2794)
			(end 0.12065 -0.3048)
			(stroke
				(width 0.1)
				(type default)
			)
			(layer "F.Fab")
		)
		(fp_line
			(start -0.12065 -0.2794)
			(end 0.12065 -0.2794)
			(stroke
				(width 0.1)
				(type default)
			)
			(layer "F.Fab")
		)
		(fp_line
			(start 0.120396 0.2794)
			(end -0.12065 0.2794)
			(stroke
				(width 0.1)
				(type default)
			)
			(layer "F.Fab")
		)
		(fp_line
			(start -0.12065 0.2794)
			(end -0.12065 0.3048)
			(stroke
				(width 0.1)
				(type default)
			)
			(layer "F.Fab")
		)
		(fp_line
			(start 0.67945 0.3048)
			(end 0.120396 0.3048)
			(stroke
				(width 0.1)
				(type default)
			)
			(layer "F.Fab")
		)
		(fp_line
			(start 0.120396 0.3048)
			(end 0.120396 0.2794)
			(stroke
				(width 0.1)
				(type default)
			)
			(layer "F.Fab")
		)
		(fp_line
			(start -0.12065 0.3048)
			(end -0.67945 0.3048)
			(stroke
				(width 0.1)
				(type default)
			)
			(layer "F.Fab")
		)
		(fp_line
			(start -0.67945 0.3048)
			(end -0.67945 -0.305054)
			(stroke
				(width 0.1)
				(type default)
			)
			(layer "F.Fab")
		)
		(pad "1" smd circle
			(at -0.40005 0 90)
			(size 0 0)
			(layers "F.Cu" "F.Mask" "F.Paste")
			(net "P12V_SSD12")
		)
		(pad "2" smd circle
			(at 0.40005 0 90)
			(size 0 0)
			(layers "F.Cu" "F.Mask" "F.Paste")
			(net "GND")
		)
	)
	(footprint ""
		(layer "F.Cu")
		(at 136.374124 -72.766682 90)
		(property "Reference" "PR7063"
			(at 0 0 90)
			(layer "F.SilkS")
			(hide yes)
			(effects
				(font
					(size 1.27 1.27)
				)
			)
		)
		(property "Value" ""
			(at 0 0 90)
			(layer "F.Fab")
			(effects
				(font
					(size 1.27 1.27)
				)
			)
		)
		(duplicate_pad_numbers_are_jumpers no)
		(fp_line
			(start 0.7874 -0.4064)
			(end 0.7874 0.4064)
			(stroke
				(width 0.1524)
				(type default)
			)
			(layer "F.SilkS")
		)
		(fp_line
			(start -0.7874 -0.4064)
			(end 0.7874 -0.4064)
			(stroke
				(width 0.1524)
				(type default)
			)
			(layer "F.SilkS")
		)
		(fp_line
			(start 0.7874 0.4064)
			(end -0.7874 0.4064)
			(stroke
				(width 0.1524)
				(type default)
			)
			(layer "F.SilkS")
		)
		(fp_line
			(start -0.7874 0.4064)
			(end -0.7874 -0.4064)
			(stroke
				(width 0.1524)
				(type default)
			)
			(layer "F.SilkS")
		)
		(fp_line
			(start -0.12065 -0.305054)
			(end -0.12065 -0.2794)
			(stroke
				(width 0.1)
				(type default)
			)
			(layer "F.Fab")
		)
		(fp_line
			(start -0.67945 -0.305054)
			(end -0.12065 -0.305054)
			(stroke
				(width 0.1)
				(type default)
			)
			(layer "F.Fab")
		)
		(fp_line
			(start 0.67945 -0.3048)
			(end 0.67945 0.3048)
			(stroke
				(width 0.1)
				(type default)
			)
			(layer "F.Fab")
		)
		(fp_line
			(start 0.12065 -0.3048)
			(end 0.67945 -0.3048)
			(stroke
				(width 0.1)
				(type default)
			)
			(layer "F.Fab")
		)
		(fp_line
			(start 0.12065 -0.2794)
			(end 0.12065 -0.3048)
			(stroke
				(width 0.1)
				(type default)
			)
			(layer "F.Fab")
		)
		(fp_line
			(start -0.12065 -0.2794)
			(end 0.12065 -0.2794)
			(stroke
				(width 0.1)
				(type default)
			)
			(layer "F.Fab")
		)
		(fp_line
			(start 0.120396 0.2794)
			(end -0.12065 0.2794)
			(stroke
				(width 0.1)
				(type default)
			)
			(layer "F.Fab")
		)
		(fp_line
			(start -0.12065 0.2794)
			(end -0.12065 0.3048)
			(stroke
				(width 0.1)
				(type default)
			)
			(layer "F.Fab")
		)
		(fp_line
			(start 0.67945 0.3048)
			(end 0.120396 0.3048)
			(stroke
				(width 0.1)
				(type default)
			)
			(layer "F.Fab")
		)
		(fp_line
			(start 0.120396 0.3048)
			(end 0.120396 0.2794)
			(stroke
				(width 0.1)
				(type default)
			)
			(layer "F.Fab")
		)
		(fp_line
			(start -0.12065 0.3048)
			(end -0.67945 0.3048)
			(stroke
				(width 0.1)
				(type default)
			)
			(layer "F.Fab")
		)
		(fp_line
			(start -0.67945 0.3048)
			(end -0.67945 -0.305054)
			(stroke
				(width 0.1)
				(type default)
			)
			(layer "F.Fab")
		)
		(pad "1" smd circle
			(at -0.40005 0 90)
			(size 0 0)
			(layers "F.Cu" "F.Mask" "F.Paste")
			(net "P12V_SSD4_CO_MODE")
		)
		(pad "2" smd circle
			(at 0.40005 0 90)
			(size 0 0)
			(layers "F.Cu" "F.Mask" "F.Paste")
			(net "GND")
		)
	)
	(footprint ""
		(layer "F.Cu")
		(at 224.84334 -257.975862 -90)
		(property "Reference" "R6494"
			(at 0 0 270)
			(layer "F.SilkS")
			(hide yes)
			(effects
				(font
					(size 1.27 1.27)
				)
			)
		)
		(property "Value" ""
			(at 0 0 270)
			(layer "F.Fab")
			(effects
				(font
					(size 1.27 1.27)
				)
			)
		)
		(duplicate_pad_numbers_are_jumpers no)
		(fp_line
			(start -0.7874 0.4064)
			(end -0.7874 -0.4064)
			(stroke
				(width 0.1524)
				(type default)
			)
			(layer "F.SilkS")
		)
		(fp_line
			(start 0.7874 0.4064)
			(end -0.7874 0.4064)
			(stroke
				(width 0.1524)
				(type default)
			)
			(layer "F.SilkS")
		)
		(fp_line
			(start -0.7874 -0.4064)
			(end 0.7874 -0.4064)
			(stroke
				(width 0.1524)
				(type default)
			)
			(layer "F.SilkS")
		)
		(fp_line
			(start 0.7874 -0.4064)
			(end 0.7874 0.4064)
			(stroke
				(width 0.1524)
				(type default)
			)
			(layer "F.SilkS")
		)
		(fp_line
			(start -0.67945 0.3048)
			(end -0.67945 -0.305054)
			(stroke
				(width 0.1)
				(type default)
			)
			(layer "F.Fab")
		)
		(fp_line
			(start -0.12065 0.3048)
			(end -0.67945 0.3048)
			(stroke
				(width 0.1)
				(type default)
			)
			(layer "F.Fab")
		)
		(fp_line
			(start 0.120396 0.3048)
			(end 0.120396 0.2794)
			(stroke
				(width 0.1)
				(type default)
			)
			(layer "F.Fab")
		)
		(fp_line
			(start 0.67945 0.3048)
			(end 0.120396 0.3048)
			(stroke
				(width 0.1)
				(type default)
			)
			(layer "F.Fab")
		)
		(fp_line
			(start -0.12065 0.2794)
			(end -0.12065 0.3048)
			(stroke
				(width 0.1)
				(type default)
			)
			(layer "F.Fab")
		)
		(fp_line
			(start 0.120396 0.2794)
			(end -0.12065 0.2794)
			(stroke
				(width 0.1)
				(type default)
			)
			(layer "F.Fab")
		)
		(fp_line
			(start -0.12065 -0.2794)
			(end 0.12065 -0.2794)
			(stroke
				(width 0.1)
				(type default)
			)
			(layer "F.Fab")
		)
		(fp_line
			(start 0.12065 -0.2794)
			(end 0.12065 -0.3048)
			(stroke
				(width 0.1)
				(type default)
			)
			(layer "F.Fab")
		)
		(fp_line
			(start 0.12065 -0.3048)
			(end 0.67945 -0.3048)
			(stroke
				(width 0.1)
				(type default)
			)
			(layer "F.Fab")
		)
		(fp_line
			(start 0.67945 -0.3048)
			(end 0.67945 0.3048)
			(stroke
				(width 0.1)
				(type default)
			)
			(layer "F.Fab")
		)
		(fp_line
			(start -0.67945 -0.305054)
			(end -0.12065 -0.305054)
			(stroke
				(width 0.1)
				(type default)
			)
			(layer "F.Fab")
		)
		(fp_line
			(start -0.12065 -0.305054)
			(end -0.12065 -0.2794)
			(stroke
				(width 0.1)
				(type default)
			)
			(layer "F.Fab")
		)
		(pad "1" smd circle
			(at -0.40005 0 270)
			(size 0 0)
			(layers "F.Cu" "F.Mask" "F.Paste")
			(net "P1V25_SERDES_VDDPLL_PEX1")
		)
		(pad "2" smd circle
			(at 0.40005 0 270)
			(size 0 0)
			(layers "F.Cu" "F.Mask" "F.Paste")
			(net "P1V25_SERDES_VDDPLL_PEX1_C3")
		)
	)
	(footprint ""
		(layer "F.Cu")
		(at 298.57319 -210.094068 -90)
		(property "Reference" "R3366"
			(at 0 0 270)
			(layer "F.SilkS")
			(hide yes)
			(effects
				(font
					(size 1.27 1.27)
				)
			)
		)
		(property "Value" ""
			(at 0 0 270)
			(layer "F.Fab")
			(effects
				(font
					(size 1.27 1.27)
				)
			)
		)
		(duplicate_pad_numbers_are_jumpers no)
		(fp_line
			(start -0.7874 0.4064)
			(end -0.7874 -0.4064)
			(stroke
				(width 0.1524)
				(type default)
			)
			(layer "F.SilkS")
		)
		(fp_line
			(start 0.7874 0.4064)
			(end -0.7874 0.4064)
			(stroke
				(width 0.1524)
				(type default)
			)
			(layer "F.SilkS")
		)
		(fp_line
			(start -0.7874 -0.4064)
			(end 0.7874 -0.4064)
			(stroke
				(width 0.1524)
				(type default)
			)
			(layer "F.SilkS")
		)
		(fp_line
			(start 0.7874 -0.4064)
			(end 0.7874 0.4064)
			(stroke
				(width 0.1524)
				(type default)
			)
			(layer "F.SilkS")
		)
		(fp_line
			(start -0.67945 0.3048)
			(end -0.67945 -0.305054)
			(stroke
				(width 0.1)
				(type default)
			)
			(layer "F.Fab")
		)
		(fp_line
			(start -0.12065 0.3048)
			(end -0.67945 0.3048)
			(stroke
				(width 0.1)
				(type default)
			)
			(layer "F.Fab")
		)
		(fp_line
			(start 0.120396 0.3048)
			(end 0.120396 0.2794)
			(stroke
				(width 0.1)
				(type default)
			)
			(layer "F.Fab")
		)
		(fp_line
			(start 0.67945 0.3048)
			(end 0.120396 0.3048)
			(stroke
				(width 0.1)
				(type default)
			)
			(layer "F.Fab")
		)
		(fp_line
			(start -0.12065 0.2794)
			(end -0.12065 0.3048)
			(stroke
				(width 0.1)
				(type default)
			)
			(layer "F.Fab")
		)
		(fp_line
			(start 0.120396 0.2794)
			(end -0.12065 0.2794)
			(stroke
				(width 0.1)
				(type default)
			)
			(layer "F.Fab")
		)
		(fp_line
			(start -0.12065 -0.2794)
			(end 0.12065 -0.2794)
			(stroke
				(width 0.1)
				(type default)
			)
			(layer "F.Fab")
		)
		(fp_line
			(start 0.12065 -0.2794)
			(end 0.12065 -0.3048)
			(stroke
				(width 0.1)
				(type default)
			)
			(layer "F.Fab")
		)
		(fp_line
			(start 0.12065 -0.3048)
			(end 0.67945 -0.3048)
			(stroke
				(width 0.1)
				(type default)
			)
			(layer "F.Fab")
		)
		(fp_line
			(start 0.67945 -0.3048)
			(end 0.67945 0.3048)
			(stroke
				(width 0.1)
				(type default)
			)
			(layer "F.Fab")
		)
		(fp_line
			(start -0.67945 -0.305054)
			(end -0.12065 -0.305054)
			(stroke
				(width 0.1)
				(type default)
			)
			(layer "F.Fab")
		)
		(fp_line
			(start -0.12065 -0.305054)
			(end -0.12065 -0.2794)
			(stroke
				(width 0.1)
				(type default)
			)
			(layer "F.Fab")
		)
		(pad "1" smd circle
			(at -0.40005 0 270)
			(size 0 0)
			(layers "F.Cu" "F.Mask" "F.Paste")
			(net "SPI_BIC1_CLK_LS23_R")
		)
		(pad "2" smd circle
			(at 0.40005 0 270)
			(size 0 0)
			(layers "F.Cu" "F.Mask" "F.Paste")
			(net "SPI_BIC1_CLK_LS23")
		)
	)
	(footprint ""
		(layer "F.Cu")
		(at 47.885604 -27.092148 -90)
		(property "Reference" "R5733"
			(at 0 0 270)
			(layer "F.SilkS")
			(hide yes)
			(effects
				(font
					(size 1.27 1.27)
				)
			)
		)
		(property "Value" ""
			(at 0 0 270)
			(layer "F.Fab")
			(effects
				(font
					(size 1.27 1.27)
				)
			)
		)
		(duplicate_pad_numbers_are_jumpers no)
		(fp_line
			(start -0.7874 0.4064)
			(end -0.7874 -0.4064)
			(stroke
				(width 0.1524)
				(type default)
			)
			(layer "F.SilkS")
		)
		(fp_line
			(start 0.7874 0.4064)
			(end -0.7874 0.4064)
			(stroke
				(width 0.1524)
				(type default)
			)
			(layer "F.SilkS")
		)
		(fp_line
			(start -0.7874 -0.4064)
			(end 0.7874 -0.4064)
			(stroke
				(width 0.1524)
				(type default)
			)
			(layer "F.SilkS")
		)
		(fp_line
			(start 0.7874 -0.4064)
			(end 0.7874 0.4064)
			(stroke
				(width 0.1524)
				(type default)
			)
			(layer "F.SilkS")
		)
		(fp_line
			(start -0.67945 0.3048)
			(end -0.67945 -0.305054)
			(stroke
				(width 0.1)
				(type default)
			)
			(layer "F.Fab")
		)
		(fp_line
			(start -0.12065 0.3048)
			(end -0.67945 0.3048)
			(stroke
				(width 0.1)
				(type default)
			)
			(layer "F.Fab")
		)
		(fp_line
			(start 0.120396 0.3048)
			(end 0.120396 0.2794)
			(stroke
				(width 0.1)
				(type default)
			)
			(layer "F.Fab")
		)
		(fp_line
			(start 0.67945 0.3048)
			(end 0.120396 0.3048)
			(stroke
				(width 0.1)
				(type default)
			)
			(layer "F.Fab")
		)
		(fp_line
			(start -0.12065 0.2794)
			(end -0.12065 0.3048)
			(stroke
				(width 0.1)
				(type default)
			)
			(layer "F.Fab")
		)
		(fp_line
			(start 0.120396 0.2794)
			(end -0.12065 0.2794)
			(stroke
				(width 0.1)
				(type default)
			)
			(layer "F.Fab")
		)
		(fp_line
			(start -0.12065 -0.2794)
			(end 0.12065 -0.2794)
			(stroke
				(width 0.1)
				(type default)
			)
			(layer "F.Fab")
		)
		(fp_line
			(start 0.12065 -0.2794)
			(end 0.12065 -0.3048)
			(stroke
				(width 0.1)
				(type default)
			)
			(layer "F.Fab")
		)
		(fp_line
			(start 0.12065 -0.3048)
			(end 0.67945 -0.3048)
			(stroke
				(width 0.1)
				(type default)
			)
			(layer "F.Fab")
		)
		(fp_line
			(start 0.67945 -0.3048)
			(end 0.67945 0.3048)
			(stroke
				(width 0.1)
				(type default)
			)
			(layer "F.Fab")
		)
		(fp_line
			(start -0.67945 -0.305054)
			(end -0.12065 -0.305054)
			(stroke
				(width 0.1)
				(type default)
			)
			(layer "F.Fab")
		)
		(fp_line
			(start -0.12065 -0.305054)
			(end -0.12065 -0.2794)
			(stroke
				(width 0.1)
				(type default)
			)
			(layer "F.Fab")
		)
		(pad "1" smd circle
			(at -0.40005 0 270)
			(size 0 0)
			(layers "F.Cu" "F.Mask" "F.Paste")
			(net "P3V3_SSD1")
		)
		(pad "2" smd circle
			(at 0.40005 0 270)
			(size 0 0)
			(layers "F.Cu" "F.Mask" "F.Paste")
			(net "SSD1_LED_ISO_N")
		)
	)
	(footprint ""
		(layer "F.Cu")
		(at 30.261814 -311.007252 -135)
		(property "Reference" "R1257"
			(at 0 0 225)
			(layer "F.SilkS")
			(hide yes)
			(effects
				(font
					(size 1.27 1.27)
				)
			)
		)
		(property "Value" ""
			(at 0 0 225)
			(layer "F.Fab")
			(effects
				(font
					(size 1.27 1.27)
				)
			)
		)
		(duplicate_pad_numbers_are_jumpers no)
		(fp_line
			(start 0.787389 0.406267)
			(end -0.787389 0.406267)
			(stroke
				(width 0.1524)
				(type default)
			)
			(layer "F.SilkS")
		)
		(fp_line
			(start 0.787389 -0.406267)
			(end 0.787389 0.406267)
			(stroke
				(width 0.1524)
				(type default)
			)
			(layer "F.SilkS")
		)
		(fp_line
			(start -0.787389 0.406267)
			(end -0.787389 -0.406267)
			(stroke
				(width 0.1524)
				(type default)
			)
			(layer "F.SilkS")
		)
		(fp_line
			(start -0.787389 -0.406267)
			(end 0.787389 -0.406267)
			(stroke
				(width 0.1524)
				(type default)
			)
			(layer "F.SilkS")
		)
		(fp_line
			(start 0.679446 0.30479)
			(end 0.120515 0.30479)
			(stroke
				(width 0.1)
				(type default)
			)
			(layer "F.Fab")
		)
		(fp_line
			(start 0.120515 0.30479)
			(end 0.120335 0.279466)
			(stroke
				(width 0.1)
				(type default)
			)
			(layer "F.Fab")
		)
		(fp_line
			(start 0.120335 0.279466)
			(end -0.120695 0.279466)
			(stroke
				(width 0.1)
				(type default)
			)
			(layer "F.Fab")
		)
		(fp_line
			(start 0.679446 -0.30479)
			(end 0.679446 0.30479)
			(stroke
				(width 0.1)
				(type default)
			)
			(layer "F.Fab")
		)
		(fp_line
			(start -0.120515 0.30479)
			(end -0.679446 0.30479)
			(stroke
				(width 0.1)
				(type default)
			)
			(layer "F.Fab")
		)
		(fp_line
			(start -0.120695 0.279466)
			(end -0.120515 0.30479)
			(stroke
				(width 0.1)
				(type default)
			)
			(layer "F.Fab")
		)
		(fp_line
			(start 0.120695 -0.279466)
			(end 0.120515 -0.30479)
			(stroke
				(width 0.1)
				(type default)
			)
			(layer "F.Fab")
		)
		(fp_line
			(start 0.120515 -0.30479)
			(end 0.679446 -0.30479)
			(stroke
				(width 0.1)
				(type default)
			)
			(layer "F.Fab")
		)
		(fp_line
			(start -0.679446 0.30479)
			(end -0.679446 -0.305149)
			(stroke
				(width 0.1)
				(type default)
			)
			(layer "F.Fab")
		)
		(fp_line
			(start -0.120695 -0.279466)
			(end 0.120695 -0.279466)
			(stroke
				(width 0.1)
				(type default)
			)
			(layer "F.Fab")
		)
		(fp_line
			(start -0.120695 -0.304969)
			(end -0.120695 -0.279466)
			(stroke
				(width 0.1)
				(type default)
			)
			(layer "F.Fab")
		)
		(fp_line
			(start -0.679446 -0.305149)
			(end -0.120695 -0.304969)
			(stroke
				(width 0.1)
				(type default)
			)
			(layer "F.Fab")
		)
		(pad "1" smd circle
			(at -0.40005 0 225)
			(size 0 0)
			(layers "F.Cu" "F.Mask" "F.Paste")
			(net "PU_PEX0_PAD_TRI_L")
		)
		(pad "2" smd circle
			(at 0.40005 0 225)
			(size 0 0)
			(layers "F.Cu" "F.Mask" "F.Paste")
			(net "P1V8_PEX")
		)
	)
	(footprint ""
		(layer "F.Cu")
		(at 380.61773 -115.336574 90)
		(property "Reference" "R349"
			(at 0 0 90)
			(layer "F.SilkS")
			(hide yes)
			(effects
				(font
					(size 1.27 1.27)
				)
			)
		)
		(property "Value" ""
			(at 0 0 90)
			(layer "F.Fab")
			(effects
				(font
					(size 1.27 1.27)
				)
			)
		)
		(duplicate_pad_numbers_are_jumpers no)
		(fp_line
			(start 0.7874 -0.4064)
			(end 0.7874 0.4064)
			(stroke
				(width 0.1524)
				(type default)
			)
			(layer "F.SilkS")
		)
		(fp_line
			(start -0.7874 -0.4064)
			(end 0.7874 -0.4064)
			(stroke
				(width 0.1524)
				(type default)
			)
			(layer "F.SilkS")
		)
		(fp_line
			(start 0.7874 0.4064)
			(end -0.7874 0.4064)
			(stroke
				(width 0.1524)
				(type default)
			)
			(layer "F.SilkS")
		)
		(fp_line
			(start -0.7874 0.4064)
			(end -0.7874 -0.4064)
			(stroke
				(width 0.1524)
				(type default)
			)
			(layer "F.SilkS")
		)
		(fp_line
			(start -0.12065 -0.305054)
			(end -0.12065 -0.2794)
			(stroke
				(width 0.1)
				(type default)
			)
			(layer "F.Fab")
		)
		(fp_line
			(start -0.67945 -0.305054)
			(end -0.12065 -0.305054)
			(stroke
				(width 0.1)
				(type default)
			)
			(layer "F.Fab")
		)
		(fp_line
			(start 0.67945 -0.3048)
			(end 0.67945 0.3048)
			(stroke
				(width 0.1)
				(type default)
			)
			(layer "F.Fab")
		)
		(fp_line
			(start 0.12065 -0.3048)
			(end 0.67945 -0.3048)
			(stroke
				(width 0.1)
				(type default)
			)
			(layer "F.Fab")
		)
		(fp_line
			(start 0.12065 -0.2794)
			(end 0.12065 -0.3048)
			(stroke
				(width 0.1)
				(type default)
			)
			(layer "F.Fab")
		)
		(fp_line
			(start -0.12065 -0.2794)
			(end 0.12065 -0.2794)
			(stroke
				(width 0.1)
				(type default)
			)
			(layer "F.Fab")
		)
		(fp_line
			(start 0.120396 0.2794)
			(end -0.12065 0.2794)
			(stroke
				(width 0.1)
				(type default)
			)
			(layer "F.Fab")
		)
		(fp_line
			(start -0.12065 0.2794)
			(end -0.12065 0.3048)
			(stroke
				(width 0.1)
				(type default)
			)
			(layer "F.Fab")
		)
		(fp_line
			(start 0.67945 0.3048)
			(end 0.120396 0.3048)
			(stroke
				(width 0.1)
				(type default)
			)
			(layer "F.Fab")
		)
		(fp_line
			(start 0.120396 0.3048)
			(end 0.120396 0.2794)
			(stroke
				(width 0.1)
				(type default)
			)
			(layer "F.Fab")
		)
		(fp_line
			(start -0.12065 0.3048)
			(end -0.67945 0.3048)
			(stroke
				(width 0.1)
				(type default)
			)
			(layer "F.Fab")
		)
		(fp_line
			(start -0.67945 0.3048)
			(end -0.67945 -0.305054)
			(stroke
				(width 0.1)
				(type default)
			)
			(layer "F.Fab")
		)
		(pad "1" smd circle
			(at -0.40005 0 90)
			(size 0 0)
			(layers "F.Cu" "F.Mask" "F.Paste")
			(net "PRSNT_NIC6_R_N")
		)
		(pad "2" smd circle
			(at 0.40005 0 90)
			(size 0 0)
			(layers "F.Cu" "F.Mask" "F.Paste")
			(net "PRSNT_NIC6_N")
		)
	)
	(footprint ""
		(layer "F.Cu")
		(at 334.518 -238.633 -90)
		(property "Reference" "R1796"
			(at 0 0 270)
			(layer "F.SilkS")
			(hide yes)
			(effects
				(font
					(size 1.27 1.27)
				)
			)
		)
		(property "Value" ""
			(at 0 0 270)
			(layer "F.Fab")
			(effects
				(font
					(size 1.27 1.27)
				)
			)
		)
		(duplicate_pad_numbers_are_jumpers no)
		(fp_line
			(start -0.7874 0.4064)
			(end -0.7874 -0.4064)
			(stroke
				(width 0.1524)
				(type default)
			)
			(layer "F.SilkS")
		)
		(fp_line
			(start 0.7874 0.4064)
			(end -0.7874 0.4064)
			(stroke
				(width 0.1524)
				(type default)
			)
			(layer "F.SilkS")
		)
		(fp_line
			(start -0.7874 -0.4064)
			(end 0.7874 -0.4064)
			(stroke
				(width 0.1524)
				(type default)
			)
			(layer "F.SilkS")
		)
		(fp_line
			(start 0.7874 -0.4064)
			(end 0.7874 0.4064)
			(stroke
				(width 0.1524)
				(type default)
			)
			(layer "F.SilkS")
		)
		(fp_line
			(start -0.67945 0.3048)
			(end -0.67945 -0.305054)
			(stroke
				(width 0.1)
				(type default)
			)
			(layer "F.Fab")
		)
		(fp_line
			(start -0.12065 0.3048)
			(end -0.67945 0.3048)
			(stroke
				(width 0.1)
				(type default)
			)
			(layer "F.Fab")
		)
		(fp_line
			(start 0.120396 0.3048)
			(end 0.120396 0.2794)
			(stroke
				(width 0.1)
				(type default)
			)
			(layer "F.Fab")
		)
		(fp_line
			(start 0.67945 0.3048)
			(end 0.120396 0.3048)
			(stroke
				(width 0.1)
				(type default)
			)
			(layer "F.Fab")
		)
		(fp_line
			(start -0.12065 0.2794)
			(end -0.12065 0.3048)
			(stroke
				(width 0.1)
				(type default)
			)
			(layer "F.Fab")
		)
		(fp_line
			(start 0.120396 0.2794)
			(end -0.12065 0.2794)
			(stroke
				(width 0.1)
				(type default)
			)
			(layer "F.Fab")
		)
		(fp_line
			(start -0.12065 -0.2794)
			(end 0.12065 -0.2794)
			(stroke
				(width 0.1)
				(type default)
			)
			(layer "F.Fab")
		)
		(fp_line
			(start 0.12065 -0.2794)
			(end 0.12065 -0.3048)
			(stroke
				(width 0.1)
				(type default)
			)
			(layer "F.Fab")
		)
		(fp_line
			(start 0.12065 -0.3048)
			(end 0.67945 -0.3048)
			(stroke
				(width 0.1)
				(type default)
			)
			(layer "F.Fab")
		)
		(fp_line
			(start 0.67945 -0.3048)
			(end 0.67945 0.3048)
			(stroke
				(width 0.1)
				(type default)
			)
			(layer "F.Fab")
		)
		(fp_line
			(start -0.67945 -0.305054)
			(end -0.12065 -0.305054)
			(stroke
				(width 0.1)
				(type default)
			)
			(layer "F.Fab")
		)
		(fp_line
			(start -0.12065 -0.305054)
			(end -0.12065 -0.2794)
			(stroke
				(width 0.1)
				(type default)
			)
			(layer "F.Fab")
		)
		(pad "1" smd circle
			(at -0.40005 0 270)
			(size 0 0)
			(layers "F.Cu" "F.Mask" "F.Paste")
			(net "P3V3_AUX")
		)
		(pad "2" smd circle
			(at 0.40005 0 270)
			(size 0 0)
			(layers "F.Cu" "F.Mask" "F.Paste")
			(net "MB_SWB_PWRGD_R")
		)
	)
	(footprint ""
		(layer "F.Cu")
		(at 79.429356 -220.7006)
		(property "Reference" "J70"
			(at -1.4224 -4.562348 0)
			(unlocked yes)
			(layer "F.SilkS")
			(effects
				(font
					(size 0.7874 0.5842)
					(thickness 0.1524)
				)
				(justify left)
			)
		)
		(property "Value" ""
			(at 0 0 0)
			(layer "F.Fab")
			(effects
				(font
					(size 1.27 1.27)
				)
			)
		)
		(duplicate_pad_numbers_are_jumpers no)
		(fp_line
			(start -1.27 -3.81)
			(end 1.27 -3.81)
			(stroke
				(width 0.1524)
				(type default)
			)
			(layer "F.SilkS")
		)
		(fp_line
			(start -1.27 -0.7747)
			(end -1.27 -3.81)
			(stroke
				(width 0.1524)
				(type default)
			)
			(layer "F.SilkS")
		)
		(fp_line
			(start -1.27 3.81)
			(end -1.27 0.7747)
			(stroke
				(width 0.1524)
				(type default)
			)
			(layer "F.SilkS")
		)
		(fp_line
			(start 1.27 -3.81)
			(end 1.27 -3.3147)
			(stroke
				(width 0.1524)
				(type default)
			)
			(layer "F.SilkS")
		)
		(fp_line
			(start 1.27 -1.7653)
			(end 1.27 1.7653)
			(stroke
				(width 0.1524)
				(type default)
			)
			(layer "F.SilkS")
		)
		(fp_line
			(start 1.27 3.3147)
			(end 1.27 3.81)
			(stroke
				(width 0.1524)
				(type default)
			)
			(layer "F.SilkS")
		)
		(fp_line
			(start 1.27 3.81)
			(end -1.27 3.81)
			(stroke
				(width 0.1524)
				(type default)
			)
			(layer "F.SilkS")
		)
		(fp_poly
			(pts
				(xy 4.3942 -3.048) (xy 4.3942 -2.032) (xy 3.3782 -2.54)
			)
			(stroke
				(width 0)
				(type default)
			)
			(fill yes)
			(layer "F.SilkS")
		)
		(fp_line
			(start -1.27 -3.81)
			(end -1.27 3.81)
			(stroke
				(width 0.1)
				(type default)
			)
			(layer "F.Fab")
		)
		(fp_line
			(start -1.27 3.81)
			(end 1.27 3.81)
			(stroke
				(width 0.1)
				(type default)
			)
			(layer "F.Fab")
		)
		(fp_line
			(start 1.27 -3.81)
			(end -1.27 -3.81)
			(stroke
				(width 0.1)
				(type default)
			)
			(layer "F.Fab")
		)
		(fp_line
			(start 1.27 3.81)
			(end 1.27 -3.81)
			(stroke
				(width 0.1)
				(type default)
			)
			(layer "F.Fab")
		)
		(fp_poly
			(pts
				(xy 4.3942 -3.048) (xy 4.3942 -2.032) (xy 3.3782 -2.54)
			)
			(stroke
				(width 0)
				(type default)
			)
			(fill yes)
			(layer "F.Fab")
		)
		(fp_text user "3"
			(at 3.921252 2.54 90)
			(unlocked yes)
			(layer "F.SilkS")
			(effects
				(font
					(size 0.7874 0.5842)
					(thickness 0.1524)
				)
			)
		)
		(fp_text user "3"
			(at 3.921252 2.54 90)
			(unlocked yes)
			(layer "F.Fab")
			(effects
				(font
					(size 0.7874 0.5842)
					(thickness 0.1524)
				)
			)
		)
		(pad "1" smd rect
			(at 1.459992 -2.54 90)
			(size 1.27 3.429)
			(layers "F.Cu" "F.Mask" "F.Paste")
			(net "GND")
		)
		(pad "2" smd rect
			(at -1.459992 0 90)
			(size 1.27 3.429)
			(layers "F.Cu" "F.Mask" "F.Paste")
			(net "UART_PEX3_CLI_BUF_R1_TX")
		)
		(pad "3" smd rect
			(at 1.459992 2.54 90)
			(size 1.27 3.429)
			(layers "F.Cu" "F.Mask" "F.Paste")
			(net "UART_PEX3_CLI_R1_RX")
		)
	)
	(footprint ""
		(layer "F.Cu")
		(at 12.355322 -113.517426 90)
		(property "Reference" "R5860"
			(at 0 0 90)
			(layer "F.SilkS")
			(hide yes)
			(effects
				(font
					(size 1.27 1.27)
				)
			)
		)
		(property "Value" ""
			(at 0 0 90)
			(layer "F.Fab")
			(effects
				(font
					(size 1.27 1.27)
				)
			)
		)
		(duplicate_pad_numbers_are_jumpers no)
		(fp_line
			(start 0.7874 -0.4064)
			(end 0.7874 0.4064)
			(stroke
				(width 0.1524)
				(type default)
			)
			(layer "F.SilkS")
		)
		(fp_line
			(start -0.7874 -0.4064)
			(end 0.7874 -0.4064)
			(stroke
				(width 0.1524)
				(type default)
			)
			(layer "F.SilkS")
		)
		(fp_line
			(start 0.7874 0.4064)
			(end -0.7874 0.4064)
			(stroke
				(width 0.1524)
				(type default)
			)
			(layer "F.SilkS")
		)
		(fp_line
			(start -0.7874 0.4064)
			(end -0.7874 -0.4064)
			(stroke
				(width 0.1524)
				(type default)
			)
			(layer "F.SilkS")
		)
		(fp_line
			(start -0.12065 -0.305054)
			(end -0.12065 -0.2794)
			(stroke
				(width 0.1)
				(type default)
			)
			(layer "F.Fab")
		)
		(fp_line
			(start -0.67945 -0.305054)
			(end -0.12065 -0.305054)
			(stroke
				(width 0.1)
				(type default)
			)
			(layer "F.Fab")
		)
		(fp_line
			(start 0.67945 -0.3048)
			(end 0.67945 0.3048)
			(stroke
				(width 0.1)
				(type default)
			)
			(layer "F.Fab")
		)
		(fp_line
			(start 0.12065 -0.3048)
			(end 0.67945 -0.3048)
			(stroke
				(width 0.1)
				(type default)
			)
			(layer "F.Fab")
		)
		(fp_line
			(start 0.12065 -0.2794)
			(end 0.12065 -0.3048)
			(stroke
				(width 0.1)
				(type default)
			)
			(layer "F.Fab")
		)
		(fp_line
			(start -0.12065 -0.2794)
			(end 0.12065 -0.2794)
			(stroke
				(width 0.1)
				(type default)
			)
			(layer "F.Fab")
		)
		(fp_line
			(start 0.120396 0.2794)
			(end -0.12065 0.2794)
			(stroke
				(width 0.1)
				(type default)
			)
			(layer "F.Fab")
		)
		(fp_line
			(start -0.12065 0.2794)
			(end -0.12065 0.3048)
			(stroke
				(width 0.1)
				(type default)
			)
			(layer "F.Fab")
		)
		(fp_line
			(start 0.67945 0.3048)
			(end 0.120396 0.3048)
			(stroke
				(width 0.1)
				(type default)
			)
			(layer "F.Fab")
		)
		(fp_line
			(start 0.120396 0.3048)
			(end 0.120396 0.2794)
			(stroke
				(width 0.1)
				(type default)
			)
			(layer "F.Fab")
		)
		(fp_line
			(start -0.12065 0.3048)
			(end -0.67945 0.3048)
			(stroke
				(width 0.1)
				(type default)
			)
			(layer "F.Fab")
		)
		(fp_line
			(start -0.67945 0.3048)
			(end -0.67945 -0.305054)
			(stroke
				(width 0.1)
				(type default)
			)
			(layer "F.Fab")
		)
		(pad "1" smd circle
			(at -0.40005 0 90)
			(size 0 0)
			(layers "F.Cu" "F.Mask" "F.Paste")
			(net "P5V_AUX")
		)
		(pad "2" smd circle
			(at 0.40005 0 90)
			(size 0 0)
			(layers "F.Cu" "F.Mask" "F.Paste")
			(net "P3V3_NIC0_PG_G2")
		)
	)
	(footprint ""
		(layer "F.Cu")
		(at 327.533 -218.313)
		(property "Reference" "R4163"
			(at 0 0 0)
			(layer "F.SilkS")
			(hide yes)
			(effects
				(font
					(size 1.27 1.27)
				)
			)
		)
		(property "Value" ""
			(at 0 0 0)
			(layer "F.Fab")
			(effects
				(font
					(size 1.27 1.27)
				)
			)
		)
		(duplicate_pad_numbers_are_jumpers no)
		(fp_line
			(start -0.7874 -0.4064)
			(end 0.7874 -0.4064)
			(stroke
				(width 0.1524)
				(type default)
			)
			(layer "F.SilkS")
		)
		(fp_line
			(start -0.7874 0.4064)
			(end -0.7874 -0.4064)
			(stroke
				(width 0.1524)
				(type default)
			)
			(layer "F.SilkS")
		)
		(fp_line
			(start 0.7874 -0.4064)
			(end 0.7874 0.4064)
			(stroke
				(width 0.1524)
				(type default)
			)
			(layer "F.SilkS")
		)
		(fp_line
			(start 0.7874 0.4064)
			(end -0.7874 0.4064)
			(stroke
				(width 0.1524)
				(type default)
			)
			(layer "F.SilkS")
		)
		(fp_line
			(start -0.67945 -0.305054)
			(end -0.12065 -0.305054)
			(stroke
				(width 0.1)
				(type default)
			)
			(layer "F.Fab")
		)
		(fp_line
			(start -0.67945 0.3048)
			(end -0.67945 -0.305054)
			(stroke
				(width 0.1)
				(type default)
			)
			(layer "F.Fab")
		)
		(fp_line
			(start -0.12065 -0.305054)
			(end -0.12065 -0.2794)
			(stroke
				(width 0.1)
				(type default)
			)
			(layer "F.Fab")
		)
		(fp_line
			(start -0.12065 -0.2794)
			(end 0.12065 -0.2794)
			(stroke
				(width 0.1)
				(type default)
			)
			(layer "F.Fab")
		)
		(fp_line
			(start -0.12065 0.2794)
			(end -0.12065 0.3048)
			(stroke
				(width 0.1)
				(type default)
			)
			(layer "F.Fab")
		)
		(fp_line
			(start -0.12065 0.3048)
			(end -0.67945 0.3048)
			(stroke
				(width 0.1)
				(type default)
			)
			(layer "F.Fab")
		)
		(fp_line
			(start 0.120396 0.2794)
			(end -0.12065 0.2794)
			(stroke
				(width 0.1)
				(type default)
			)
			(layer "F.Fab")
		)
		(fp_line
			(start 0.120396 0.3048)
			(end 0.120396 0.2794)
			(stroke
				(width 0.1)
				(type default)
			)
			(layer "F.Fab")
		)
		(fp_line
			(start 0.12065 -0.3048)
			(end 0.67945 -0.3048)
			(stroke
				(width 0.1)
				(type default)
			)
			(layer "F.Fab")
		)
		(fp_line
			(start 0.12065 -0.2794)
			(end 0.12065 -0.3048)
			(stroke
				(width 0.1)
				(type default)
			)
			(layer "F.Fab")
		)
		(fp_line
			(start 0.67945 -0.3048)
			(end 0.67945 0.3048)
			(stroke
				(width 0.1)
				(type default)
			)
			(layer "F.Fab")
		)
		(fp_line
			(start 0.67945 0.3048)
			(end 0.120396 0.3048)
			(stroke
				(width 0.1)
				(type default)
			)
			(layer "F.Fab")
		)
		(pad "1" smd circle
			(at -0.40005 0)
			(size 0 0)
			(layers "F.Cu" "F.Mask" "F.Paste")
			(net "PRSNT_NIC6_FPGA_R_N")
		)
		(pad "2" smd circle
			(at 0.40005 0)
			(size 0 0)
			(layers "F.Cu" "F.Mask" "F.Paste")
			(net "PRSNT_NIC6_FPGA_N")
		)
	)
	(footprint ""
		(layer "F.Cu")
		(at 229.594664 -207.02016 -90)
		(property "Reference" "R1506"
			(at 0 0 270)
			(layer "F.SilkS")
			(hide yes)
			(effects
				(font
					(size 1.27 1.27)
				)
			)
		)
		(property "Value" ""
			(at 0 0 270)
			(layer "F.Fab")
			(effects
				(font
					(size 1.27 1.27)
				)
			)
		)
		(duplicate_pad_numbers_are_jumpers no)
		(fp_line
			(start -0.7874 0.4064)
			(end -0.7874 -0.4064)
			(stroke
				(width 0.1524)
				(type default)
			)
			(layer "F.SilkS")
		)
		(fp_line
			(start 0.7874 0.4064)
			(end -0.7874 0.4064)
			(stroke
				(width 0.1524)
				(type default)
			)
			(layer "F.SilkS")
		)
		(fp_line
			(start -0.7874 -0.4064)
			(end 0.7874 -0.4064)
			(stroke
				(width 0.1524)
				(type default)
			)
			(layer "F.SilkS")
		)
		(fp_line
			(start 0.7874 -0.4064)
			(end 0.7874 0.4064)
			(stroke
				(width 0.1524)
				(type default)
			)
			(layer "F.SilkS")
		)
		(fp_line
			(start -0.67945 0.3048)
			(end -0.67945 -0.305054)
			(stroke
				(width 0.1)
				(type default)
			)
			(layer "F.Fab")
		)
		(fp_line
			(start -0.12065 0.3048)
			(end -0.67945 0.3048)
			(stroke
				(width 0.1)
				(type default)
			)
			(layer "F.Fab")
		)
		(fp_line
			(start 0.120396 0.3048)
			(end 0.120396 0.2794)
			(stroke
				(width 0.1)
				(type default)
			)
			(layer "F.Fab")
		)
		(fp_line
			(start 0.67945 0.3048)
			(end 0.120396 0.3048)
			(stroke
				(width 0.1)
				(type default)
			)
			(layer "F.Fab")
		)
		(fp_line
			(start -0.12065 0.2794)
			(end -0.12065 0.3048)
			(stroke
				(width 0.1)
				(type default)
			)
			(layer "F.Fab")
		)
		(fp_line
			(start 0.120396 0.2794)
			(end -0.12065 0.2794)
			(stroke
				(width 0.1)
				(type default)
			)
			(layer "F.Fab")
		)
		(fp_line
			(start -0.12065 -0.2794)
			(end 0.12065 -0.2794)
			(stroke
				(width 0.1)
				(type default)
			)
			(layer "F.Fab")
		)
		(fp_line
			(start 0.12065 -0.2794)
			(end 0.12065 -0.3048)
			(stroke
				(width 0.1)
				(type default)
			)
			(layer "F.Fab")
		)
		(fp_line
			(start 0.12065 -0.3048)
			(end 0.67945 -0.3048)
			(stroke
				(width 0.1)
				(type default)
			)
			(layer "F.Fab")
		)
		(fp_line
			(start 0.67945 -0.3048)
			(end 0.67945 0.3048)
			(stroke
				(width 0.1)
				(type default)
			)
			(layer "F.Fab")
		)
		(fp_line
			(start -0.67945 -0.305054)
			(end -0.12065 -0.305054)
			(stroke
				(width 0.1)
				(type default)
			)
			(layer "F.Fab")
		)
		(fp_line
			(start -0.12065 -0.305054)
			(end -0.12065 -0.2794)
			(stroke
				(width 0.1)
				(type default)
			)
			(layer "F.Fab")
		)
		(pad "1" smd circle
			(at -0.40005 0 270)
			(size 0 0)
			(layers "F.Cu" "F.Mask" "F.Paste")
			(net "SPI_BIC1_CS0_N")
		)
		(pad "2" smd circle
			(at 0.40005 0 270)
			(size 0 0)
			(layers "F.Cu" "F.Mask" "F.Paste")
			(net "P3V3_AUX")
		)
	)
	(footprint ""
		(layer "F.Cu")
		(at 28.04922 -300.197012 -90)
		(property "Reference" "C3038"
			(at 0 0 270)
			(layer "F.SilkS")
			(hide yes)
			(effects
				(font
					(size 1.27 1.27)
				)
			)
		)
		(property "Value" ""
			(at 0 0 270)
			(layer "F.Fab")
			(effects
				(font
					(size 1.27 1.27)
				)
			)
		)
		(duplicate_pad_numbers_are_jumpers no)
		(fp_line
			(start -0.299974 0.150114)
			(end -0.299974 -0.150114)
			(stroke
				(width 0.1)
				(type default)
			)
			(layer "F.Fab")
		)
		(fp_line
			(start 0.299974 0.150114)
			(end -0.299974 0.150114)
			(stroke
				(width 0.1)
				(type default)
			)
			(layer "F.Fab")
		)
		(fp_line
			(start -0.299974 -0.150114)
			(end 0.299974 -0.150114)
			(stroke
				(width 0.1)
				(type default)
			)
			(layer "F.Fab")
		)
		(fp_line
			(start 0.299974 -0.150114)
			(end 0.299974 0.150114)
			(stroke
				(width 0.1)
				(type default)
			)
			(layer "F.Fab")
		)
		(pad "1" smd rect
			(at -0.2667 0 270)
			(size 0.3048 0.381)
			(layers "F.Cu" "F.Mask" "F.Paste")
			(net "P1V8_PLL0_PEX0")
		)
		(pad "2" smd rect
			(at 0.2667 0 270)
			(size 0.3048 0.381)
			(layers "F.Cu" "F.Mask" "F.Paste")
			(net "GND")
		)
	)
	(footprint ""
		(layer "F.Cu")
		(at 95.906844 -189.3062 180)
		(property "Reference" "R6628"
			(at 0 0 180)
			(layer "F.SilkS")
			(hide yes)
			(effects
				(font
					(size 1.27 1.27)
				)
			)
		)
		(property "Value" ""
			(at 0 0 180)
			(layer "F.Fab")
			(effects
				(font
					(size 1.27 1.27)
				)
			)
		)
		(duplicate_pad_numbers_are_jumpers no)
		(fp_line
			(start 0.7874 0.4064)
			(end -0.7874 0.4064)
			(stroke
				(width 0.1524)
				(type default)
			)
			(layer "F.SilkS")
		)
		(fp_line
			(start 0.7874 -0.4064)
			(end 0.7874 0.4064)
			(stroke
				(width 0.1524)
				(type default)
			)
			(layer "F.SilkS")
		)
		(fp_line
			(start -0.7874 0.4064)
			(end -0.7874 -0.4064)
			(stroke
				(width 0.1524)
				(type default)
			)
			(layer "F.SilkS")
		)
		(fp_line
			(start -0.7874 -0.4064)
			(end 0.7874 -0.4064)
			(stroke
				(width 0.1524)
				(type default)
			)
			(layer "F.SilkS")
		)
		(fp_line
			(start 0.67945 0.3048)
			(end 0.120396 0.3048)
			(stroke
				(width 0.1)
				(type default)
			)
			(layer "F.Fab")
		)
		(fp_line
			(start 0.67945 -0.3048)
			(end 0.67945 0.3048)
			(stroke
				(width 0.1)
				(type default)
			)
			(layer "F.Fab")
		)
		(fp_line
			(start 0.12065 -0.2794)
			(end 0.12065 -0.3048)
			(stroke
				(width 0.1)
				(type default)
			)
			(layer "F.Fab")
		)
		(fp_line
			(start 0.12065 -0.3048)
			(end 0.67945 -0.3048)
			(stroke
				(width 0.1)
				(type default)
			)
			(layer "F.Fab")
		)
		(fp_line
			(start 0.120396 0.3048)
			(end 0.120396 0.2794)
			(stroke
				(width 0.1)
				(type default)
			)
			(layer "F.Fab")
		)
		(fp_line
			(start 0.120396 0.2794)
			(end -0.12065 0.2794)
			(stroke
				(width 0.1)
				(type default)
			)
			(layer "F.Fab")
		)
		(fp_line
			(start -0.12065 0.3048)
			(end -0.67945 0.3048)
			(stroke
				(width 0.1)
				(type default)
			)
			(layer "F.Fab")
		)
		(fp_line
			(start -0.12065 0.2794)
			(end -0.12065 0.3048)
			(stroke
				(width 0.1)
				(type default)
			)
			(layer "F.Fab")
		)
		(fp_line
			(start -0.12065 -0.2794)
			(end 0.12065 -0.2794)
			(stroke
				(width 0.1)
				(type default)
			)
			(layer "F.Fab")
		)
		(fp_line
			(start -0.12065 -0.305054)
			(end -0.12065 -0.2794)
			(stroke
				(width 0.1)
				(type default)
			)
			(layer "F.Fab")
		)
		(fp_line
			(start -0.67945 0.3048)
			(end -0.67945 -0.305054)
			(stroke
				(width 0.1)
				(type default)
			)
			(layer "F.Fab")
		)
		(fp_line
			(start -0.67945 -0.305054)
			(end -0.12065 -0.305054)
			(stroke
				(width 0.1)
				(type default)
			)
			(layer "F.Fab")
		)
		(pad "1" smd circle
			(at -0.40005 0 180)
			(size 0 0)
			(layers "F.Cu" "F.Mask" "F.Paste")
			(net "UART_PEX2_CLI_CP2108_RX")
		)
		(pad "2" smd circle
			(at 0.40005 0 180)
			(size 0 0)
			(layers "F.Cu" "F.Mask" "F.Paste")
			(net "UART_PEX2_CLI_R_RX")
		)
	)
	(footprint ""
		(layer "F.Cu")
		(at 374.567958 -51.019456)
		(property "Reference" "PC411"
			(at 0 0 0)
			(layer "F.SilkS")
			(hide yes)
			(effects
				(font
					(size 1.27 1.27)
				)
			)
		)
		(property "Value" ""
			(at 0 0 0)
			(layer "F.Fab")
			(effects
				(font
					(size 1.27 1.27)
				)
			)
		)
		(duplicate_pad_numbers_are_jumpers no)
		(fp_line
			(start -0.7874 -0.4064)
			(end 0.7874 -0.4064)
			(stroke
				(width 0.1524)
				(type default)
			)
			(layer "F.SilkS")
		)
		(fp_line
			(start -0.7874 0.4064)
			(end -0.7874 -0.4064)
			(stroke
				(width 0.1524)
				(type default)
			)
			(layer "F.SilkS")
		)
		(fp_line
			(start 0.7874 -0.4064)
			(end 0.7874 0.4064)
			(stroke
				(width 0.1524)
				(type default)
			)
			(layer "F.SilkS")
		)
		(fp_line
			(start 0.7874 0.4064)
			(end -0.7874 0.4064)
			(stroke
				(width 0.1524)
				(type default)
			)
			(layer "F.SilkS")
		)
		(fp_line
			(start -0.67945 -0.305054)
			(end -0.12065 -0.305054)
			(stroke
				(width 0.1)
				(type default)
			)
			(layer "F.Fab")
		)
		(fp_line
			(start -0.67945 0.3048)
			(end -0.67945 -0.305054)
			(stroke
				(width 0.1)
				(type default)
			)
			(layer "F.Fab")
		)
		(fp_line
			(start -0.12065 -0.305054)
			(end -0.12065 -0.2794)
			(stroke
				(width 0.1)
				(type default)
			)
			(layer "F.Fab")
		)
		(fp_line
			(start -0.12065 -0.2794)
			(end 0.12065 -0.2794)
			(stroke
				(width 0.1)
				(type default)
			)
			(layer "F.Fab")
		)
		(fp_line
			(start -0.12065 0.2794)
			(end -0.12065 0.3048)
			(stroke
				(width 0.1)
				(type default)
			)
			(layer "F.Fab")
		)
		(fp_line
			(start -0.12065 0.3048)
			(end -0.67945 0.3048)
			(stroke
				(width 0.1)
				(type default)
			)
			(layer "F.Fab")
		)
		(fp_line
			(start 0.120396 0.2794)
			(end -0.12065 0.2794)
			(stroke
				(width 0.1)
				(type default)
			)
			(layer "F.Fab")
		)
		(fp_line
			(start 0.120396 0.3048)
			(end 0.120396 0.2794)
			(stroke
				(width 0.1)
				(type default)
			)
			(layer "F.Fab")
		)
		(fp_line
			(start 0.12065 -0.3048)
			(end 0.67945 -0.3048)
			(stroke
				(width 0.1)
				(type default)
			)
			(layer "F.Fab")
		)
		(fp_line
			(start 0.12065 -0.2794)
			(end 0.12065 -0.3048)
			(stroke
				(width 0.1)
				(type default)
			)
			(layer "F.Fab")
		)
		(fp_line
			(start 0.67945 -0.3048)
			(end 0.67945 0.3048)
			(stroke
				(width 0.1)
				(type default)
			)
			(layer "F.Fab")
		)
		(fp_line
			(start 0.67945 0.3048)
			(end 0.120396 0.3048)
			(stroke
				(width 0.1)
				(type default)
			)
			(layer "F.Fab")
		)
		(pad "1" smd circle
			(at -0.40005 0)
			(size 0 0)
			(layers "F.Cu" "F.Mask" "F.Paste")
			(net "P12V_SSD12_SS")
		)
		(pad "2" smd circle
			(at 0.40005 0)
			(size 0 0)
			(layers "F.Cu" "F.Mask" "F.Paste")
			(net "GND")
		)
	)
	(footprint ""
		(layer "F.Cu")
		(at 413.723328 -241.83848)
		(property "Reference" "J66"
			(at -7.126986 0.264668 0)
			(unlocked yes)
			(layer "F.SilkS")
			(effects
				(font
					(size 0.7874 0.5842)
					(thickness 0.1524)
				)
				(justify left)
			)
		)
		(property "Value" ""
			(at 0 0 0)
			(layer "F.Fab")
			(effects
				(font
					(size 1.27 1.27)
				)
			)
		)
		(duplicate_pad_numbers_are_jumpers no)
		(fp_line
			(start -1.27 -3.81)
			(end 1.27 -3.81)
			(stroke
				(width 0.1524)
				(type default)
			)
			(layer "F.SilkS")
		)
		(fp_line
			(start -1.27 -0.7747)
			(end -1.27 -3.81)
			(stroke
				(width 0.1524)
				(type default)
			)
			(layer "F.SilkS")
		)
		(fp_line
			(start -1.27 3.81)
			(end -1.27 0.7747)
			(stroke
				(width 0.1524)
				(type default)
			)
			(layer "F.SilkS")
		)
		(fp_line
			(start 1.27 -3.81)
			(end 1.27 -3.3147)
			(stroke
				(width 0.1524)
				(type default)
			)
			(layer "F.SilkS")
		)
		(fp_line
			(start 1.27 -1.7653)
			(end 1.27 1.7653)
			(stroke
				(width 0.1524)
				(type default)
			)
			(layer "F.SilkS")
		)
		(fp_line
			(start 1.27 3.3147)
			(end 1.27 3.81)
			(stroke
				(width 0.1524)
				(type default)
			)
			(layer "F.SilkS")
		)
		(fp_line
			(start 1.27 3.81)
			(end -1.27 3.81)
			(stroke
				(width 0.1524)
				(type default)
			)
			(layer "F.SilkS")
		)
		(fp_poly
			(pts
				(xy 4.3942 -3.048) (xy 4.3942 -2.032) (xy 3.3782 -2.54)
			)
			(stroke
				(width 0)
				(type default)
			)
			(fill yes)
			(layer "F.SilkS")
		)
		(fp_line
			(start -1.27 -3.81)
			(end -1.27 3.81)
			(stroke
				(width 0.1)
				(type default)
			)
			(layer "F.Fab")
		)
		(fp_line
			(start -1.27 3.81)
			(end 1.27 3.81)
			(stroke
				(width 0.1)
				(type default)
			)
			(layer "F.Fab")
		)
		(fp_line
			(start 1.27 -3.81)
			(end -1.27 -3.81)
			(stroke
				(width 0.1)
				(type default)
			)
			(layer "F.Fab")
		)
		(fp_line
			(start 1.27 3.81)
			(end 1.27 -3.81)
			(stroke
				(width 0.1)
				(type default)
			)
			(layer "F.Fab")
		)
		(fp_poly
			(pts
				(xy 4.3942 -3.048) (xy 4.3942 -2.032) (xy 3.3782 -2.54)
			)
			(stroke
				(width 0)
				(type default)
			)
			(fill yes)
			(layer "F.Fab")
		)
		(fp_text user "3"
			(at 3.921252 2.54 90)
			(unlocked yes)
			(layer "F.SilkS")
			(effects
				(font
					(size 0.7874 0.5842)
					(thickness 0.1524)
				)
			)
		)
		(fp_text user "3"
			(at 3.921252 2.54 90)
			(unlocked yes)
			(layer "F.Fab")
			(effects
				(font
					(size 0.7874 0.5842)
					(thickness 0.1524)
				)
			)
		)
		(pad "1" smd rect
			(at 1.459992 -2.54 90)
			(size 1.27 3.429)
			(layers "F.Cu" "F.Mask" "F.Paste")
			(net "GND")
		)
		(pad "2" smd rect
			(at -1.459992 0 90)
			(size 1.27 3.429)
			(layers "F.Cu" "F.Mask" "F.Paste")
			(net "UART_PEX2_SDB_BUF_R1_TX")
		)
		(pad "3" smd rect
			(at 1.459992 2.54 90)
			(size 1.27 3.429)
			(layers "F.Cu" "F.Mask" "F.Paste")
			(net "UART_PEX2_SDB_R1_RX")
		)
	)
	(footprint ""
		(layer "F.Cu")
		(at 154.882596 -140.85697)
		(property "Reference" "R136"
			(at 0 0 0)
			(layer "F.SilkS")
			(hide yes)
			(effects
				(font
					(size 1.27 1.27)
				)
			)
		)
		(property "Value" ""
			(at 0 0 0)
			(layer "F.Fab")
			(effects
				(font
					(size 1.27 1.27)
				)
			)
		)
		(duplicate_pad_numbers_are_jumpers no)
		(fp_line
			(start -0.7874 -0.4064)
			(end 0.7874 -0.4064)
			(stroke
				(width 0.1524)
				(type default)
			)
			(layer "F.SilkS")
		)
		(fp_line
			(start -0.7874 0.4064)
			(end -0.7874 -0.4064)
			(stroke
				(width 0.1524)
				(type default)
			)
			(layer "F.SilkS")
		)
		(fp_line
			(start 0.7874 -0.4064)
			(end 0.7874 0.4064)
			(stroke
				(width 0.1524)
				(type default)
			)
			(layer "F.SilkS")
		)
		(fp_line
			(start 0.7874 0.4064)
			(end -0.7874 0.4064)
			(stroke
				(width 0.1524)
				(type default)
			)
			(layer "F.SilkS")
		)
		(fp_line
			(start -0.67945 -0.305054)
			(end -0.12065 -0.305054)
			(stroke
				(width 0.1)
				(type default)
			)
			(layer "F.Fab")
		)
		(fp_line
			(start -0.67945 0.3048)
			(end -0.67945 -0.305054)
			(stroke
				(width 0.1)
				(type default)
			)
			(layer "F.Fab")
		)
		(fp_line
			(start -0.12065 -0.305054)
			(end -0.12065 -0.2794)
			(stroke
				(width 0.1)
				(type default)
			)
			(layer "F.Fab")
		)
		(fp_line
			(start -0.12065 -0.2794)
			(end 0.12065 -0.2794)
			(stroke
				(width 0.1)
				(type default)
			)
			(layer "F.Fab")
		)
		(fp_line
			(start -0.12065 0.2794)
			(end -0.12065 0.3048)
			(stroke
				(width 0.1)
				(type default)
			)
			(layer "F.Fab")
		)
		(fp_line
			(start -0.12065 0.3048)
			(end -0.67945 0.3048)
			(stroke
				(width 0.1)
				(type default)
			)
			(layer "F.Fab")
		)
		(fp_line
			(start 0.120396 0.2794)
			(end -0.12065 0.2794)
			(stroke
				(width 0.1)
				(type default)
			)
			(layer "F.Fab")
		)
		(fp_line
			(start 0.120396 0.3048)
			(end 0.120396 0.2794)
			(stroke
				(width 0.1)
				(type default)
			)
			(layer "F.Fab")
		)
		(fp_line
			(start 0.12065 -0.3048)
			(end 0.67945 -0.3048)
			(stroke
				(width 0.1)
				(type default)
			)
			(layer "F.Fab")
		)
		(fp_line
			(start 0.12065 -0.2794)
			(end 0.12065 -0.3048)
			(stroke
				(width 0.1)
				(type default)
			)
			(layer "F.Fab")
		)
		(fp_line
			(start 0.67945 -0.3048)
			(end 0.67945 0.3048)
			(stroke
				(width 0.1)
				(type default)
			)
			(layer "F.Fab")
		)
		(fp_line
			(start 0.67945 0.3048)
			(end 0.120396 0.3048)
			(stroke
				(width 0.1)
				(type default)
			)
			(layer "F.Fab")
		)
		(pad "1" smd circle
			(at -0.40005 0)
			(size 0 0)
			(layers "F.Cu" "F.Mask" "F.Paste")
			(net "NIC2_BIF2_N")
		)
		(pad "2" smd circle
			(at 0.40005 0)
			(size 0 0)
			(layers "F.Cu" "F.Mask" "F.Paste")
			(net "GND")
		)
	)
	(footprint ""
		(layer "F.Cu")
		(at 179.667154 -171.675806)
		(property "Reference" "R151"
			(at 0 0 0)
			(layer "F.SilkS")
			(hide yes)
			(effects
				(font
					(size 1.27 1.27)
				)
			)
		)
		(property "Value" ""
			(at 0 0 0)
			(layer "F.Fab")
			(effects
				(font
					(size 1.27 1.27)
				)
			)
		)
		(duplicate_pad_numbers_are_jumpers no)
		(fp_line
			(start -0.7874 -0.4064)
			(end 0.7874 -0.4064)
			(stroke
				(width 0.1524)
				(type default)
			)
			(layer "F.SilkS")
		)
		(fp_line
			(start -0.7874 0.4064)
			(end -0.7874 -0.4064)
			(stroke
				(width 0.1524)
				(type default)
			)
			(layer "F.SilkS")
		)
		(fp_line
			(start 0.7874 -0.4064)
			(end 0.7874 0.4064)
			(stroke
				(width 0.1524)
				(type default)
			)
			(layer "F.SilkS")
		)
		(fp_line
			(start 0.7874 0.4064)
			(end -0.7874 0.4064)
			(stroke
				(width 0.1524)
				(type default)
			)
			(layer "F.SilkS")
		)
		(fp_line
			(start -0.67945 -0.305054)
			(end -0.12065 -0.305054)
			(stroke
				(width 0.1)
				(type default)
			)
			(layer "F.Fab")
		)
		(fp_line
			(start -0.67945 0.3048)
			(end -0.67945 -0.305054)
			(stroke
				(width 0.1)
				(type default)
			)
			(layer "F.Fab")
		)
		(fp_line
			(start -0.12065 -0.305054)
			(end -0.12065 -0.2794)
			(stroke
				(width 0.1)
				(type default)
			)
			(layer "F.Fab")
		)
		(fp_line
			(start -0.12065 -0.2794)
			(end 0.12065 -0.2794)
			(stroke
				(width 0.1)
				(type default)
			)
			(layer "F.Fab")
		)
		(fp_line
			(start -0.12065 0.2794)
			(end -0.12065 0.3048)
			(stroke
				(width 0.1)
				(type default)
			)
			(layer "F.Fab")
		)
		(fp_line
			(start -0.12065 0.3048)
			(end -0.67945 0.3048)
			(stroke
				(width 0.1)
				(type default)
			)
			(layer "F.Fab")
		)
		(fp_line
			(start 0.120396 0.2794)
			(end -0.12065 0.2794)
			(stroke
				(width 0.1)
				(type default)
			)
			(layer "F.Fab")
		)
		(fp_line
			(start 0.120396 0.3048)
			(end 0.120396 0.2794)
			(stroke
				(width 0.1)
				(type default)
			)
			(layer "F.Fab")
		)
		(fp_line
			(start 0.12065 -0.3048)
			(end 0.67945 -0.3048)
			(stroke
				(width 0.1)
				(type default)
			)
			(layer "F.Fab")
		)
		(fp_line
			(start 0.12065 -0.2794)
			(end 0.12065 -0.3048)
			(stroke
				(width 0.1)
				(type default)
			)
			(layer "F.Fab")
		)
		(fp_line
			(start 0.67945 -0.3048)
			(end 0.67945 0.3048)
			(stroke
				(width 0.1)
				(type default)
			)
			(layer "F.Fab")
		)
		(fp_line
			(start 0.67945 0.3048)
			(end 0.120396 0.3048)
			(stroke
				(width 0.1)
				(type default)
			)
			(layer "F.Fab")
		)
		(pad "1" smd circle
			(at -0.40005 0)
			(size 0 0)
			(layers "F.Cu" "F.Mask" "F.Paste")
			(net "P3V3_NIC2")
		)
		(pad "2" smd circle
			(at 0.40005 0)
			(size 0 0)
			(layers "F.Cu" "F.Mask" "F.Paste")
			(net "HP_NIC2_PWRGD")
		)
	)
	(footprint ""
		(layer "F.Cu")
		(at 435.104032 -289.230816 90)
		(property "Reference" "R4003"
			(at 0 0 90)
			(layer "F.SilkS")
			(hide yes)
			(effects
				(font
					(size 1.27 1.27)
				)
			)
		)
		(property "Value" ""
			(at 0 0 90)
			(layer "F.Fab")
			(effects
				(font
					(size 1.27 1.27)
				)
			)
		)
		(duplicate_pad_numbers_are_jumpers no)
		(fp_line
			(start 0.7874 -0.4064)
			(end 0.7874 0.4064)
			(stroke
				(width 0.1524)
				(type default)
			)
			(layer "F.SilkS")
		)
		(fp_line
			(start -0.7874 -0.4064)
			(end 0.7874 -0.4064)
			(stroke
				(width 0.1524)
				(type default)
			)
			(layer "F.SilkS")
		)
		(fp_line
			(start 0.7874 0.4064)
			(end -0.7874 0.4064)
			(stroke
				(width 0.1524)
				(type default)
			)
			(layer "F.SilkS")
		)
		(fp_line
			(start -0.7874 0.4064)
			(end -0.7874 -0.4064)
			(stroke
				(width 0.1524)
				(type default)
			)
			(layer "F.SilkS")
		)
		(fp_line
			(start -0.12065 -0.305054)
			(end -0.12065 -0.2794)
			(stroke
				(width 0.1)
				(type default)
			)
			(layer "F.Fab")
		)
		(fp_line
			(start -0.67945 -0.305054)
			(end -0.12065 -0.305054)
			(stroke
				(width 0.1)
				(type default)
			)
			(layer "F.Fab")
		)
		(fp_line
			(start 0.67945 -0.3048)
			(end 0.67945 0.3048)
			(stroke
				(width 0.1)
				(type default)
			)
			(layer "F.Fab")
		)
		(fp_line
			(start 0.12065 -0.3048)
			(end 0.67945 -0.3048)
			(stroke
				(width 0.1)
				(type default)
			)
			(layer "F.Fab")
		)
		(fp_line
			(start 0.12065 -0.2794)
			(end 0.12065 -0.3048)
			(stroke
				(width 0.1)
				(type default)
			)
			(layer "F.Fab")
		)
		(fp_line
			(start -0.12065 -0.2794)
			(end 0.12065 -0.2794)
			(stroke
				(width 0.1)
				(type default)
			)
			(layer "F.Fab")
		)
		(fp_line
			(start 0.120396 0.2794)
			(end -0.12065 0.2794)
			(stroke
				(width 0.1)
				(type default)
			)
			(layer "F.Fab")
		)
		(fp_line
			(start -0.12065 0.2794)
			(end -0.12065 0.3048)
			(stroke
				(width 0.1)
				(type default)
			)
			(layer "F.Fab")
		)
		(fp_line
			(start 0.67945 0.3048)
			(end 0.120396 0.3048)
			(stroke
				(width 0.1)
				(type default)
			)
			(layer "F.Fab")
		)
		(fp_line
			(start 0.120396 0.3048)
			(end 0.120396 0.2794)
			(stroke
				(width 0.1)
				(type default)
			)
			(layer "F.Fab")
		)
		(fp_line
			(start -0.12065 0.3048)
			(end -0.67945 0.3048)
			(stroke
				(width 0.1)
				(type default)
			)
			(layer "F.Fab")
		)
		(fp_line
			(start -0.67945 0.3048)
			(end -0.67945 -0.305054)
			(stroke
				(width 0.1)
				(type default)
			)
			(layer "F.Fab")
		)
		(pad "1" smd circle
			(at -0.40005 0 90)
			(size 0 0)
			(layers "F.Cu" "F.Mask" "F.Paste")
			(net "PWRGD_P1V8_PEX_R")
		)
		(pad "2" smd circle
			(at 0.40005 0 90)
			(size 0 0)
			(layers "F.Cu" "F.Mask" "F.Paste")
			(net "PWRGD_P1V8_PEX3_R")
		)
	)
	(footprint ""
		(layer "F.Cu")
		(at 161.571686 -25.342342 -90)
		(property "Reference" "R424"
			(at 0 0 270)
			(layer "F.SilkS")
			(hide yes)
			(effects
				(font
					(size 1.27 1.27)
				)
			)
		)
		(property "Value" ""
			(at 0 0 270)
			(layer "F.Fab")
			(effects
				(font
					(size 1.27 1.27)
				)
			)
		)
		(duplicate_pad_numbers_are_jumpers no)
		(fp_line
			(start -0.7874 0.4064)
			(end -0.7874 -0.4064)
			(stroke
				(width 0.1524)
				(type default)
			)
			(layer "F.SilkS")
		)
		(fp_line
			(start 0.7874 0.4064)
			(end -0.7874 0.4064)
			(stroke
				(width 0.1524)
				(type default)
			)
			(layer "F.SilkS")
		)
		(fp_line
			(start -0.7874 -0.4064)
			(end 0.7874 -0.4064)
			(stroke
				(width 0.1524)
				(type default)
			)
			(layer "F.SilkS")
		)
		(fp_line
			(start 0.7874 -0.4064)
			(end 0.7874 0.4064)
			(stroke
				(width 0.1524)
				(type default)
			)
			(layer "F.SilkS")
		)
		(fp_line
			(start -0.67945 0.3048)
			(end -0.67945 -0.305054)
			(stroke
				(width 0.1)
				(type default)
			)
			(layer "F.Fab")
		)
		(fp_line
			(start -0.12065 0.3048)
			(end -0.67945 0.3048)
			(stroke
				(width 0.1)
				(type default)
			)
			(layer "F.Fab")
		)
		(fp_line
			(start 0.120396 0.3048)
			(end 0.120396 0.2794)
			(stroke
				(width 0.1)
				(type default)
			)
			(layer "F.Fab")
		)
		(fp_line
			(start 0.67945 0.3048)
			(end 0.120396 0.3048)
			(stroke
				(width 0.1)
				(type default)
			)
			(layer "F.Fab")
		)
		(fp_line
			(start -0.12065 0.2794)
			(end -0.12065 0.3048)
			(stroke
				(width 0.1)
				(type default)
			)
			(layer "F.Fab")
		)
		(fp_line
			(start 0.120396 0.2794)
			(end -0.12065 0.2794)
			(stroke
				(width 0.1)
				(type default)
			)
			(layer "F.Fab")
		)
		(fp_line
			(start -0.12065 -0.2794)
			(end 0.12065 -0.2794)
			(stroke
				(width 0.1)
				(type default)
			)
			(layer "F.Fab")
		)
		(fp_line
			(start 0.12065 -0.2794)
			(end 0.12065 -0.3048)
			(stroke
				(width 0.1)
				(type default)
			)
			(layer "F.Fab")
		)
		(fp_line
			(start 0.12065 -0.3048)
			(end 0.67945 -0.3048)
			(stroke
				(width 0.1)
				(type default)
			)
			(layer "F.Fab")
		)
		(fp_line
			(start 0.67945 -0.3048)
			(end 0.67945 0.3048)
			(stroke
				(width 0.1)
				(type default)
			)
			(layer "F.Fab")
		)
		(fp_line
			(start -0.67945 -0.305054)
			(end -0.12065 -0.305054)
			(stroke
				(width 0.1)
				(type default)
			)
			(layer "F.Fab")
		)
		(fp_line
			(start -0.12065 -0.305054)
			(end -0.12065 -0.2794)
			(stroke
				(width 0.1)
				(type default)
			)
			(layer "F.Fab")
		)
		(pad "1" smd circle
			(at -0.40005 0 270)
			(size 0 0)
			(layers "F.Cu" "F.Mask" "F.Paste")
			(net "P3V3_SSD5")
		)
		(pad "2" smd circle
			(at 0.40005 0 270)
			(size 0 0)
			(layers "F.Cu" "F.Mask" "F.Paste")
			(net "DUALPORT_N_SSD5")
		)
	)
	(footprint ""
		(layer "F.Cu")
		(at 323.255386 -96.811592 -90)
		(property "Reference" "R740"
			(at 0 0 270)
			(layer "F.SilkS")
			(hide yes)
			(effects
				(font
					(size 1.27 1.27)
				)
			)
		)
		(property "Value" ""
			(at 0 0 270)
			(layer "F.Fab")
			(effects
				(font
					(size 1.27 1.27)
				)
			)
		)
		(duplicate_pad_numbers_are_jumpers no)
		(fp_line
			(start -0.7874 0.4064)
			(end -0.7874 -0.4064)
			(stroke
				(width 0.1524)
				(type default)
			)
			(layer "F.SilkS")
		)
		(fp_line
			(start 0.7874 0.4064)
			(end -0.7874 0.4064)
			(stroke
				(width 0.1524)
				(type default)
			)
			(layer "F.SilkS")
		)
		(fp_line
			(start -0.7874 -0.4064)
			(end 0.7874 -0.4064)
			(stroke
				(width 0.1524)
				(type default)
			)
			(layer "F.SilkS")
		)
		(fp_line
			(start 0.7874 -0.4064)
			(end 0.7874 0.4064)
			(stroke
				(width 0.1524)
				(type default)
			)
			(layer "F.SilkS")
		)
		(fp_line
			(start -0.67945 0.3048)
			(end -0.67945 -0.305054)
			(stroke
				(width 0.1)
				(type default)
			)
			(layer "F.Fab")
		)
		(fp_line
			(start -0.12065 0.3048)
			(end -0.67945 0.3048)
			(stroke
				(width 0.1)
				(type default)
			)
			(layer "F.Fab")
		)
		(fp_line
			(start 0.120396 0.3048)
			(end 0.120396 0.2794)
			(stroke
				(width 0.1)
				(type default)
			)
			(layer "F.Fab")
		)
		(fp_line
			(start 0.67945 0.3048)
			(end 0.120396 0.3048)
			(stroke
				(width 0.1)
				(type default)
			)
			(layer "F.Fab")
		)
		(fp_line
			(start -0.12065 0.2794)
			(end -0.12065 0.3048)
			(stroke
				(width 0.1)
				(type default)
			)
			(layer "F.Fab")
		)
		(fp_line
			(start 0.120396 0.2794)
			(end -0.12065 0.2794)
			(stroke
				(width 0.1)
				(type default)
			)
			(layer "F.Fab")
		)
		(fp_line
			(start -0.12065 -0.2794)
			(end 0.12065 -0.2794)
			(stroke
				(width 0.1)
				(type default)
			)
			(layer "F.Fab")
		)
		(fp_line
			(start 0.12065 -0.2794)
			(end 0.12065 -0.3048)
			(stroke
				(width 0.1)
				(type default)
			)
			(layer "F.Fab")
		)
		(fp_line
			(start 0.12065 -0.3048)
			(end 0.67945 -0.3048)
			(stroke
				(width 0.1)
				(type default)
			)
			(layer "F.Fab")
		)
		(fp_line
			(start 0.67945 -0.3048)
			(end 0.67945 0.3048)
			(stroke
				(width 0.1)
				(type default)
			)
			(layer "F.Fab")
		)
		(fp_line
			(start -0.67945 -0.305054)
			(end -0.12065 -0.305054)
			(stroke
				(width 0.1)
				(type default)
			)
			(layer "F.Fab")
		)
		(fp_line
			(start -0.12065 -0.305054)
			(end -0.12065 -0.2794)
			(stroke
				(width 0.1)
				(type default)
			)
			(layer "F.Fab")
		)
		(pad "1" smd circle
			(at -0.40005 0 270)
			(size 0 0)
			(layers "F.Cu" "F.Mask" "F.Paste")
			(net "NIC5_ADC_ALERT_N")
		)
		(pad "2" smd circle
			(at 0.40005 0 270)
			(size 0 0)
			(layers "F.Cu" "F.Mask" "F.Paste")
			(net "NIC_ADC_ALERT_N")
		)
	)
	(footprint ""
		(layer "F.Cu")
		(at 211.506816 -365.975646)
		(property "Reference" "PR7"
			(at 0 0 0)
			(layer "F.SilkS")
			(hide yes)
			(effects
				(font
					(size 1.27 1.27)
				)
			)
		)
		(property "Value" ""
			(at 0 0 0)
			(layer "F.Fab")
			(effects
				(font
					(size 1.27 1.27)
				)
			)
		)
		(duplicate_pad_numbers_are_jumpers no)
		(fp_line
			(start -0.7874 -0.4064)
			(end 0.7874 -0.4064)
			(stroke
				(width 0.1524)
				(type default)
			)
			(layer "F.SilkS")
		)
		(fp_line
			(start -0.7874 0.4064)
			(end -0.7874 -0.4064)
			(stroke
				(width 0.1524)
				(type default)
			)
			(layer "F.SilkS")
		)
		(fp_line
			(start 0.7874 -0.4064)
			(end 0.7874 0.4064)
			(stroke
				(width 0.1524)
				(type default)
			)
			(layer "F.SilkS")
		)
		(fp_line
			(start 0.7874 0.4064)
			(end -0.7874 0.4064)
			(stroke
				(width 0.1524)
				(type default)
			)
			(layer "F.SilkS")
		)
		(fp_line
			(start -0.67945 -0.305054)
			(end -0.12065 -0.305054)
			(stroke
				(width 0.1)
				(type default)
			)
			(layer "F.Fab")
		)
		(fp_line
			(start -0.67945 0.3048)
			(end -0.67945 -0.305054)
			(stroke
				(width 0.1)
				(type default)
			)
			(layer "F.Fab")
		)
		(fp_line
			(start -0.12065 -0.305054)
			(end -0.12065 -0.2794)
			(stroke
				(width 0.1)
				(type default)
			)
			(layer "F.Fab")
		)
		(fp_line
			(start -0.12065 -0.2794)
			(end 0.12065 -0.2794)
			(stroke
				(width 0.1)
				(type default)
			)
			(layer "F.Fab")
		)
		(fp_line
			(start -0.12065 0.2794)
			(end -0.12065 0.3048)
			(stroke
				(width 0.1)
				(type default)
			)
			(layer "F.Fab")
		)
		(fp_line
			(start -0.12065 0.3048)
			(end -0.67945 0.3048)
			(stroke
				(width 0.1)
				(type default)
			)
			(layer "F.Fab")
		)
		(fp_line
			(start 0.120396 0.2794)
			(end -0.12065 0.2794)
			(stroke
				(width 0.1)
				(type default)
			)
			(layer "F.Fab")
		)
		(fp_line
			(start 0.120396 0.3048)
			(end 0.120396 0.2794)
			(stroke
				(width 0.1)
				(type default)
			)
			(layer "F.Fab")
		)
		(fp_line
			(start 0.12065 -0.3048)
			(end 0.67945 -0.3048)
			(stroke
				(width 0.1)
				(type default)
			)
			(layer "F.Fab")
		)
		(fp_line
			(start 0.12065 -0.2794)
			(end 0.12065 -0.3048)
			(stroke
				(width 0.1)
				(type default)
			)
			(layer "F.Fab")
		)
		(fp_line
			(start 0.67945 -0.3048)
			(end 0.67945 0.3048)
			(stroke
				(width 0.1)
				(type default)
			)
			(layer "F.Fab")
		)
		(fp_line
			(start 0.67945 0.3048)
			(end 0.120396 0.3048)
			(stroke
				(width 0.1)
				(type default)
			)
			(layer "F.Fab")
		)
		(pad "1" smd circle
			(at -0.40005 0)
			(size 0 0)
			(layers "F.Cu" "F.Mask" "F.Paste")
			(net "HSC_D_OC")
		)
		(pad "2" smd circle
			(at 0.40005 0)
			(size 0 0)
			(layers "F.Cu" "F.Mask" "F.Paste")
			(net "HSC_VDD")
		)
	)
	(footprint ""
		(layer "F.Cu")
		(at 346.075 -157.988)
		(property "Reference" "U349"
			(at -1.4478 -4.613148 0)
			(unlocked yes)
			(layer "F.SilkS")
			(effects
				(font
					(size 0.7874 0.5842)
					(thickness 0.1524)
				)
				(justify left)
			)
		)
		(property "Value" ""
			(at 0 0 0)
			(layer "F.Fab")
			(effects
				(font
					(size 1.27 1.27)
				)
			)
		)
		(duplicate_pad_numbers_are_jumpers no)
		(fp_line
			(start -2.097532 -3.949954)
			(end -2.097532 3.949954)
			(stroke
				(width 0.1524)
				(type default)
			)
			(layer "F.SilkS")
		)
		(fp_line
			(start -2.097532 3.949954)
			(end 2.097532 3.949954)
			(stroke
				(width 0.1524)
				(type default)
			)
			(layer "F.SilkS")
		)
		(fp_line
			(start -1.409954 -3.949954)
			(end -2.097532 -3.949954)
			(stroke
				(width 0.1524)
				(type default)
			)
			(layer "F.SilkS")
		)
		(fp_line
			(start 0 -2.54)
			(end -1.409954 -3.949954)
			(stroke
				(width 0.1524)
				(type default)
			)
			(layer "F.SilkS")
		)
		(fp_line
			(start 1.409954 -3.949954)
			(end 0 -2.54)
			(stroke
				(width 0.1524)
				(type default)
			)
			(layer "F.SilkS")
		)
		(fp_line
			(start 2.097532 -3.949954)
			(end 1.409954 -3.949954)
			(stroke
				(width 0.1524)
				(type default)
			)
			(layer "F.SilkS")
		)
		(fp_line
			(start 2.097532 3.949954)
			(end 2.097532 -3.949954)
			(stroke
				(width 0.1524)
				(type default)
			)
			(layer "F.SilkS")
		)
		(fp_poly
			(pts
				(xy -4.7498 -4.182872) (xy -4.7498 -3.166872) (xy -3.7338 -3.674872)
			)
			(stroke
				(width 0)
				(type default)
			)
			(fill yes)
			(layer "F.SilkS")
		)
		(fp_line
			(start -2.249932 -3.949954)
			(end -2.249932 3.949954)
			(stroke
				(width 0.1)
				(type default)
			)
			(layer "F.Fab")
		)
		(fp_line
			(start -2.249932 3.949954)
			(end 2.249932 3.949954)
			(stroke
				(width 0.1)
				(type default)
			)
			(layer "F.Fab")
		)
		(fp_line
			(start 2.249932 -3.949954)
			(end -2.249932 -3.949954)
			(stroke
				(width 0.1)
				(type default)
			)
			(layer "F.Fab")
		)
		(fp_line
			(start 2.249932 3.949954)
			(end 2.249932 -3.949954)
			(stroke
				(width 0.1)
				(type default)
			)
			(layer "F.Fab")
		)
		(fp_poly
			(pts
				(xy -4.7498 -4.182872) (xy -4.7498 -3.166872) (xy -3.7338 -3.674872)
			)
			(stroke
				(width 0)
				(type default)
			)
			(fill yes)
			(layer "F.Fab")
		)
		(pad "1" smd rect
			(at -2.925064 -3.674872 270)
			(size 0.6096 1.3716)
			(layers "F.Cu" "F.Mask" "F.Paste")
			(net "PEX3_PCA9555_0_INT_N")
		)
		(pad "2" smd rect
			(at -2.925064 -2.925064 270)
			(size 0.4064 1.3716)
			(layers "F.Cu" "F.Mask" "F.Paste")
			(net "PCA9555_0_PEX3_A1")
		)
		(pad "3" smd rect
			(at -2.925064 -2.275078 270)
			(size 0.4064 1.3716)
			(layers "F.Cu" "F.Mask" "F.Paste")
			(net "PCA9555_0_PEX3_A2")
		)
		(pad "4" smd rect
			(at -2.925064 -1.625092 270)
			(size 0.4064 1.3716)
			(layers "F.Cu" "F.Mask" "F.Paste")
			(net "PRSNT_SSD12_FPGA_PCA9555_N")
		)
		(pad "5" smd rect
			(at -2.925064 -0.975106 270)
			(size 0.4064 1.3716)
			(layers "F.Cu" "F.Mask" "F.Paste")
			(net "SSD12_PEX_PWR_EN")
		)
		(pad "6" smd rect
			(at -2.925064 -0.32512 270)
			(size 0.4064 1.3716)
			(layers "F.Cu" "F.Mask" "F.Paste")
			(net "RST_PEX_SSD12_PERST_N")
		)
		(pad "7" smd rect
			(at -2.925064 0.32512 270)
			(size 0.4064 1.3716)
			(layers "F.Cu" "F.Mask" "F.Paste")
			(net "Net_1185")
		)
		(pad "8" smd rect
			(at -2.925064 0.975106 270)
			(size 0.4064 1.3716)
			(layers "F.Cu" "F.Mask" "F.Paste")
			(net "PRSNT_SSD13_FPGA_PCA9555_N")
		)
		(pad "9" smd rect
			(at -2.925064 1.625092 270)
			(size 0.4064 1.3716)
			(layers "F.Cu" "F.Mask" "F.Paste")
			(net "SSD13_PEX_PWR_EN")
		)
		(pad "10" smd rect
			(at -2.925064 2.275078 270)
			(size 0.4064 1.3716)
			(layers "F.Cu" "F.Mask" "F.Paste")
			(net "RST_PEX_SSD13_PERST_N")
		)
		(pad "11" smd rect
			(at -2.925064 2.925064 270)
			(size 0.4064 1.3716)
			(layers "F.Cu" "F.Mask" "F.Paste")
			(net "Net_1183")
		)
		(pad "12" smd rect
			(at -2.925064 3.674872 270)
			(size 0.6096 1.3716)
			(layers "F.Cu" "F.Mask" "F.Paste")
			(net "GND")
		)
		(pad "13" smd rect
			(at 2.925064 3.674872 270)
			(size 0.6096 1.3716)
			(layers "F.Cu" "F.Mask" "F.Paste")
			(net "PRSNT_NIC6_FPGA_PCA9555_N")
		)
		(pad "14" smd rect
			(at 2.925064 2.925064 270)
			(size 0.4064 1.3716)
			(layers "F.Cu" "F.Mask" "F.Paste")
			(net "NIC6_PEX_PWR_EN")
		)
		(pad "15" smd rect
			(at 2.925064 2.275078 270)
			(size 0.4064 1.3716)
			(layers "F.Cu" "F.Mask" "F.Paste")
			(net "RST_PEX_NIC6_PERST_N")
		)
		(pad "16" smd rect
			(at 2.925064 1.625092 270)
			(size 0.4064 1.3716)
			(layers "F.Cu" "F.Mask" "F.Paste")
			(net "Net_1182")
		)
		(pad "17" smd rect
			(at 2.925064 0.975106 270)
			(size 0.4064 1.3716)
			(layers "F.Cu" "F.Mask" "F.Paste")
			(net "Net_8968")
		)
		(pad "18" smd rect
			(at 2.925064 0.32512 270)
			(size 0.4064 1.3716)
			(layers "F.Cu" "F.Mask" "F.Paste")
			(net "Net_8967")
		)
		(pad "19" smd rect
			(at 2.925064 -0.32512 270)
			(size 0.4064 1.3716)
			(layers "F.Cu" "F.Mask" "F.Paste")
			(net "Net_8966")
		)
		(pad "20" smd rect
			(at 2.925064 -0.975106 270)
			(size 0.4064 1.3716)
			(layers "F.Cu" "F.Mask" "F.Paste")
			(net "Net_8965")
		)
		(pad "21" smd rect
			(at 2.925064 -1.625092 270)
			(size 0.4064 1.3716)
			(layers "F.Cu" "F.Mask" "F.Paste")
			(net "PCA9555_0_PEX3_A0")
		)
		(pad "22" smd rect
			(at 2.925064 -2.275078 270)
			(size 0.4064 1.3716)
			(layers "F.Cu" "F.Mask" "F.Paste")
			(net "SMB_PEX3_PCA9555_SCL")
		)
		(pad "23" smd rect
			(at 2.925064 -2.925064 270)
			(size 0.4064 1.3716)
			(layers "F.Cu" "F.Mask" "F.Paste")
			(net "SMB_PEX3_PCA9555_SDA")
		)
		(pad "24" smd rect
			(at 2.925064 -3.674872 270)
			(size 0.6096 1.3716)
			(layers "F.Cu" "F.Mask" "F.Paste")
			(net "P3V3_AUX")
		)
	)
	(footprint ""
		(layer "F.Cu")
		(at 230.529892 -79.005684 -90)
		(property "Reference" "U110"
			(at 2.8575 1.565656 0)
			(unlocked yes)
			(layer "F.SilkS")
			(effects
				(font
					(size 0.7874 0.5842)
					(thickness 0.1524)
				)
				(justify left)
			)
		)
		(property "Value" ""
			(at 0 0 270)
			(layer "F.Fab")
			(effects
				(font
					(size 1.27 1.27)
				)
			)
		)
		(duplicate_pad_numbers_are_jumpers no)
		(fp_line
			(start -0.674878 0.824992)
			(end -0.674878 0.403098)
			(stroke
				(width 0.1524)
				(type default)
			)
			(layer "F.SilkS")
		)
		(fp_line
			(start -0.61595 0.824992)
			(end -0.674878 0.824992)
			(stroke
				(width 0.1524)
				(type default)
			)
			(layer "F.SilkS")
		)
		(fp_line
			(start 0.674878 0.824992)
			(end 0.61595 0.824992)
			(stroke
				(width 0.1524)
				(type default)
			)
			(layer "F.SilkS")
		)
		(fp_line
			(start 0.674878 0.403098)
			(end 0.674878 0.824992)
			(stroke
				(width 0.1524)
				(type default)
			)
			(layer "F.SilkS")
		)
		(fp_line
			(start -0.674878 -0.403098)
			(end -0.674878 -0.824992)
			(stroke
				(width 0.1524)
				(type default)
			)
			(layer "F.SilkS")
		)
		(fp_line
			(start -0.674878 -0.824992)
			(end -0.61595 -0.824992)
			(stroke
				(width 0.1524)
				(type default)
			)
			(layer "F.SilkS")
		)
		(fp_line
			(start 0.61595 -0.824992)
			(end 0.674878 -0.824992)
			(stroke
				(width 0.1524)
				(type default)
			)
			(layer "F.SilkS")
		)
		(fp_line
			(start 0.674878 -0.824992)
			(end 0.674878 -0.403098)
			(stroke
				(width 0.1524)
				(type default)
			)
			(layer "F.SilkS")
		)
		(fp_poly
			(pts
				(xy -1.067308 -0.790702) (xy -1.354836 -0.503428) (xy -0.923798 -0.359664)
			)
			(stroke
				(width 0)
				(type default)
			)
			(fill yes)
			(layer "F.SilkS")
		)
		(fp_line
			(start -0.674878 0.824992)
			(end -0.674878 -0.824992)
			(stroke
				(width 0.1)
				(type default)
			)
			(layer "F.Fab")
		)
		(fp_line
			(start 0.674878 0.824992)
			(end -0.674878 0.824992)
			(stroke
				(width 0.1)
				(type default)
			)
			(layer "F.Fab")
		)
		(fp_line
			(start -0.674878 -0.824992)
			(end 0.674878 -0.824992)
			(stroke
				(width 0.1)
				(type default)
			)
			(layer "F.Fab")
		)
		(fp_line
			(start 0.674878 -0.824992)
			(end 0.674878 0.824992)
			(stroke
				(width 0.1)
				(type default)
			)
			(layer "F.Fab")
		)
		(fp_poly
			(pts
				(xy -1.344422 -0.403098) (xy -1.344422 0.003302) (xy -0.938022 -0.199898)
			)
			(stroke
				(width 0)
				(type default)
			)
			(fill yes)
			(layer "F.Fab")
		)
		(fp_text user "3"
			(at -1.12903 1.313688 0)
			(unlocked yes)
			(layer "F.SilkS")
			(effects
				(font
					(size 0.635 0.4064)
					(thickness 0.1524)
				)
				(justify left)
			)
		)
		(fp_text user "5"
			(at 1.437132 1.313688 0)
			(unlocked yes)
			(layer "F.SilkS")
			(effects
				(font
					(size 0.635 0.4064)
					(thickness 0.1524)
				)
				(justify left)
			)
		)
		(fp_text user "10"
			(at -1.247394 -0.408686 0)
			(unlocked yes)
			(layer "F.SilkS")
			(effects
				(font
					(size 0.635 0.4064)
					(thickness 0.1524)
				)
				(justify left)
			)
		)
		(fp_text user "8"
			(at 1.300734 -0.897382 0)
			(unlocked yes)
			(layer "F.SilkS")
			(effects
				(font
					(size 0.635 0.4064)
					(thickness 0.1524)
				)
				(justify left)
			)
		)
		(fp_text user "3"
			(at -1.210056 0.999744 270)
			(unlocked yes)
			(layer "F.Fab")
			(effects
				(font
					(size 0.635 0.4064)
					(thickness 0.1524)
				)
				(justify left)
			)
		)
		(fp_text user "5"
			(at 0.777748 0.940054 270)
			(unlocked yes)
			(layer "F.Fab")
			(effects
				(font
					(size 0.635 0.4064)
					(thickness 0.1524)
				)
				(justify left)
			)
		)
		(fp_text user "10"
			(at -1.505458 -1.33858 270)
			(unlocked yes)
			(layer "F.Fab")
			(effects
				(font
					(size 0.635 0.4064)
					(thickness 0.1524)
				)
				(justify left)
			)
		)
		(fp_text user "8"
			(at 0.582676 -1.368552 270)
			(unlocked yes)
			(layer "F.Fab")
			(effects
				(font
					(size 0.635 0.4064)
					(thickness 0.1524)
				)
				(justify left)
			)
		)
		(pad "1" smd rect
			(at -0.459994 -0.199898)
			(size 0.1524 0.7112)
			(layers "F.Cu" "F.Mask" "F.Paste")
			(net "USB2_PEX_HUB_DP")
		)
		(pad "2" smd rect
			(at -0.459994 0.199898)
			(size 0.1524 0.7112)
			(layers "F.Cu" "F.Mask" "F.Paste")
			(net "USB2_PEX_HUB_DN")
		)
		(pad "3" smd rect
			(at -0.40005 0.735076 270)
			(size 0.1778 0.508)
			(layers "F.Cu" "F.Mask" "F.Paste")
			(net "GND")
		)
		(pad "4" smd rect
			(at 0 0.735076 270)
			(size 0.1778 0.508)
			(layers "F.Cu" "F.Mask" "F.Paste")
			(net "USB2_MICRO_DN")
		)
		(pad "5" smd rect
			(at 0.40005 0.735076 270)
			(size 0.1778 0.508)
			(layers "F.Cu" "F.Mask" "F.Paste")
			(net "USB2_MICRO_DP")
		)
		(pad "6" smd rect
			(at 0.459994 0.199898)
			(size 0.1524 0.7112)
			(layers "F.Cu" "F.Mask" "F.Paste")
			(net "USB2_FIO_DN")
		)
		(pad "7" smd rect
			(at 0.459994 -0.199898)
			(size 0.1524 0.7112)
			(layers "F.Cu" "F.Mask" "F.Paste")
			(net "USB2_FIO_DP")
		)
		(pad "8" smd rect
			(at 0.40005 -0.735076 270)
			(size 0.1778 0.508)
			(layers "F.Cu" "F.Mask" "F.Paste")
			(net "PWRGD_P3V3_AUX_MUX_R_N")
		)
		(pad "9" smd rect
			(at 0 -0.735076 270)
			(size 0.1778 0.508)
			(layers "F.Cu" "F.Mask" "F.Paste")
			(net "P3V3_AUX")
		)
		(pad "10" smd rect
			(at -0.40005 -0.735076 270)
			(size 0.1778 0.508)
			(layers "F.Cu" "F.Mask" "F.Paste")
			(net "PEX_USB2_SEL")
		)
	)
	(footprint ""
		(layer "F.Cu")
		(at 100.216462 -100.178108 90)
		(property "Reference" "PC306"
			(at 0 0 90)
			(layer "F.SilkS")
			(hide yes)
			(effects
				(font
					(size 1.27 1.27)
				)
			)
		)
		(property "Value" ""
			(at 0 0 90)
			(layer "F.Fab")
			(effects
				(font
					(size 1.27 1.27)
				)
			)
		)
		(duplicate_pad_numbers_are_jumpers no)
		(fp_line
			(start 0.7874 -0.4064)
			(end 0.7874 0.4064)
			(stroke
				(width 0.1524)
				(type default)
			)
			(layer "F.SilkS")
		)
		(fp_line
			(start -0.7874 -0.4064)
			(end 0.7874 -0.4064)
			(stroke
				(width 0.1524)
				(type default)
			)
			(layer "F.SilkS")
		)
		(fp_line
			(start 0.7874 0.4064)
			(end -0.7874 0.4064)
			(stroke
				(width 0.1524)
				(type default)
			)
			(layer "F.SilkS")
		)
		(fp_line
			(start -0.7874 0.4064)
			(end -0.7874 -0.4064)
			(stroke
				(width 0.1524)
				(type default)
			)
			(layer "F.SilkS")
		)
		(fp_line
			(start -0.12065 -0.305054)
			(end -0.12065 -0.2794)
			(stroke
				(width 0.1)
				(type default)
			)
			(layer "F.Fab")
		)
		(fp_line
			(start -0.67945 -0.305054)
			(end -0.12065 -0.305054)
			(stroke
				(width 0.1)
				(type default)
			)
			(layer "F.Fab")
		)
		(fp_line
			(start 0.67945 -0.3048)
			(end 0.67945 0.3048)
			(stroke
				(width 0.1)
				(type default)
			)
			(layer "F.Fab")
		)
		(fp_line
			(start 0.12065 -0.3048)
			(end 0.67945 -0.3048)
			(stroke
				(width 0.1)
				(type default)
			)
			(layer "F.Fab")
		)
		(fp_line
			(start 0.12065 -0.2794)
			(end 0.12065 -0.3048)
			(stroke
				(width 0.1)
				(type default)
			)
			(layer "F.Fab")
		)
		(fp_line
			(start -0.12065 -0.2794)
			(end 0.12065 -0.2794)
			(stroke
				(width 0.1)
				(type default)
			)
			(layer "F.Fab")
		)
		(fp_line
			(start 0.120396 0.2794)
			(end -0.12065 0.2794)
			(stroke
				(width 0.1)
				(type default)
			)
			(layer "F.Fab")
		)
		(fp_line
			(start -0.12065 0.2794)
			(end -0.12065 0.3048)
			(stroke
				(width 0.1)
				(type default)
			)
			(layer "F.Fab")
		)
		(fp_line
			(start 0.67945 0.3048)
			(end 0.120396 0.3048)
			(stroke
				(width 0.1)
				(type default)
			)
			(layer "F.Fab")
		)
		(fp_line
			(start 0.120396 0.3048)
			(end 0.120396 0.2794)
			(stroke
				(width 0.1)
				(type default)
			)
			(layer "F.Fab")
		)
		(fp_line
			(start -0.12065 0.3048)
			(end -0.67945 0.3048)
			(stroke
				(width 0.1)
				(type default)
			)
			(layer "F.Fab")
		)
		(fp_line
			(start -0.67945 0.3048)
			(end -0.67945 -0.305054)
			(stroke
				(width 0.1)
				(type default)
			)
			(layer "F.Fab")
		)
		(pad "1" smd circle
			(at -0.40005 0 90)
			(size 0 0)
			(layers "F.Cu" "F.Mask" "F.Paste")
			(net "P12V_AUX")
		)
		(pad "2" smd circle
			(at 0.40005 0 90)
			(size 0 0)
			(layers "F.Cu" "F.Mask" "F.Paste")
			(net "GND")
		)
	)
	(footprint ""
		(layer "F.Cu")
		(at 323.115686 -309.760366 135)
		(property "Reference" "R1387"
			(at 0 0 135)
			(layer "F.SilkS")
			(hide yes)
			(effects
				(font
					(size 1.27 1.27)
				)
			)
		)
		(property "Value" ""
			(at 0 0 135)
			(layer "F.Fab")
			(effects
				(font
					(size 1.27 1.27)
				)
			)
		)
		(duplicate_pad_numbers_are_jumpers no)
		(fp_line
			(start 0.787389 -0.406267)
			(end 0.787389 0.406267)
			(stroke
				(width 0.1524)
				(type default)
			)
			(layer "F.SilkS")
		)
		(fp_line
			(start 0.787389 0.406267)
			(end -0.787389 0.406267)
			(stroke
				(width 0.1524)
				(type default)
			)
			(layer "F.SilkS")
		)
		(fp_line
			(start -0.787389 -0.406267)
			(end 0.787389 -0.406267)
			(stroke
				(width 0.1524)
				(type default)
			)
			(layer "F.SilkS")
		)
		(fp_line
			(start -0.787389 0.406267)
			(end -0.787389 -0.406267)
			(stroke
				(width 0.1524)
				(type default)
			)
			(layer "F.SilkS")
		)
		(fp_line
			(start 0.679446 -0.30479)
			(end 0.679446 0.30479)
			(stroke
				(width 0.1)
				(type default)
			)
			(layer "F.Fab")
		)
		(fp_line
			(start 0.120515 -0.30479)
			(end 0.679446 -0.30479)
			(stroke
				(width 0.1)
				(type default)
			)
			(layer "F.Fab")
		)
		(fp_line
			(start 0.120695 -0.279466)
			(end 0.120515 -0.30479)
			(stroke
				(width 0.1)
				(type default)
			)
			(layer "F.Fab")
		)
		(fp_line
			(start 0.679446 0.30479)
			(end 0.120515 0.30479)
			(stroke
				(width 0.1)
				(type default)
			)
			(layer "F.Fab")
		)
		(fp_line
			(start -0.120695 -0.304969)
			(end -0.120695 -0.279466)
			(stroke
				(width 0.1)
				(type default)
			)
			(layer "F.Fab")
		)
		(fp_line
			(start -0.120695 -0.279466)
			(end 0.120695 -0.279466)
			(stroke
				(width 0.1)
				(type default)
			)
			(layer "F.Fab")
		)
		(fp_line
			(start 0.120335 0.279466)
			(end -0.120695 0.279466)
			(stroke
				(width 0.1)
				(type default)
			)
			(layer "F.Fab")
		)
		(fp_line
			(start 0.120515 0.30479)
			(end 0.120335 0.279466)
			(stroke
				(width 0.1)
				(type default)
			)
			(layer "F.Fab")
		)
		(fp_line
			(start -0.679446 -0.305149)
			(end -0.120695 -0.304969)
			(stroke
				(width 0.1)
				(type default)
			)
			(layer "F.Fab")
		)
		(fp_line
			(start -0.120695 0.279466)
			(end -0.120515 0.30479)
			(stroke
				(width 0.1)
				(type default)
			)
			(layer "F.Fab")
		)
		(fp_line
			(start -0.120515 0.30479)
			(end -0.679446 0.30479)
			(stroke
				(width 0.1)
				(type default)
			)
			(layer "F.Fab")
		)
		(fp_line
			(start -0.679446 0.30479)
			(end -0.679446 -0.305149)
			(stroke
				(width 0.1)
				(type default)
			)
			(layer "F.Fab")
		)
		(pad "1" smd circle
			(at -0.40005 0 135)
			(size 0 0)
			(layers "F.Cu" "F.Mask" "F.Paste")
			(net "GND")
		)
		(pad "2" smd circle
			(at 0.40005 0 135)
			(size 0 0)
			(layers "F.Cu" "F.Mask" "F.Paste")
			(net "PEX2_SPARE0")
		)
	)
	(footprint ""
		(layer "F.Cu")
		(at 360.032808 -162.003994 90)
		(property "Reference" "PC834"
			(at 0 0 90)
			(layer "F.SilkS")
			(hide yes)
			(effects
				(font
					(size 1.27 1.27)
				)
			)
		)
		(property "Value" ""
			(at 0 0 90)
			(layer "F.Fab")
			(effects
				(font
					(size 1.27 1.27)
				)
			)
		)
		(duplicate_pad_numbers_are_jumpers no)
		(fp_line
			(start 0.7874 -0.4064)
			(end 0.7874 0.4064)
			(stroke
				(width 0.1524)
				(type default)
			)
			(layer "F.SilkS")
		)
		(fp_line
			(start -0.7874 -0.4064)
			(end 0.7874 -0.4064)
			(stroke
				(width 0.1524)
				(type default)
			)
			(layer "F.SilkS")
		)
		(fp_line
			(start 0.7874 0.4064)
			(end -0.7874 0.4064)
			(stroke
				(width 0.1524)
				(type default)
			)
			(layer "F.SilkS")
		)
		(fp_line
			(start -0.7874 0.4064)
			(end -0.7874 -0.4064)
			(stroke
				(width 0.1524)
				(type default)
			)
			(layer "F.SilkS")
		)
		(fp_line
			(start -0.12065 -0.305054)
			(end -0.12065 -0.2794)
			(stroke
				(width 0.1)
				(type default)
			)
			(layer "F.Fab")
		)
		(fp_line
			(start -0.67945 -0.305054)
			(end -0.12065 -0.305054)
			(stroke
				(width 0.1)
				(type default)
			)
			(layer "F.Fab")
		)
		(fp_line
			(start 0.67945 -0.3048)
			(end 0.67945 0.3048)
			(stroke
				(width 0.1)
				(type default)
			)
			(layer "F.Fab")
		)
		(fp_line
			(start 0.12065 -0.3048)
			(end 0.67945 -0.3048)
			(stroke
				(width 0.1)
				(type default)
			)
			(layer "F.Fab")
		)
		(fp_line
			(start 0.12065 -0.2794)
			(end 0.12065 -0.3048)
			(stroke
				(width 0.1)
				(type default)
			)
			(layer "F.Fab")
		)
		(fp_line
			(start -0.12065 -0.2794)
			(end 0.12065 -0.2794)
			(stroke
				(width 0.1)
				(type default)
			)
			(layer "F.Fab")
		)
		(fp_line
			(start 0.120396 0.2794)
			(end -0.12065 0.2794)
			(stroke
				(width 0.1)
				(type default)
			)
			(layer "F.Fab")
		)
		(fp_line
			(start -0.12065 0.2794)
			(end -0.12065 0.3048)
			(stroke
				(width 0.1)
				(type default)
			)
			(layer "F.Fab")
		)
		(fp_line
			(start 0.67945 0.3048)
			(end 0.120396 0.3048)
			(stroke
				(width 0.1)
				(type default)
			)
			(layer "F.Fab")
		)
		(fp_line
			(start 0.120396 0.3048)
			(end 0.120396 0.2794)
			(stroke
				(width 0.1)
				(type default)
			)
			(layer "F.Fab")
		)
		(fp_line
			(start -0.12065 0.3048)
			(end -0.67945 0.3048)
			(stroke
				(width 0.1)
				(type default)
			)
			(layer "F.Fab")
		)
		(fp_line
			(start -0.67945 0.3048)
			(end -0.67945 -0.305054)
			(stroke
				(width 0.1)
				(type default)
			)
			(layer "F.Fab")
		)
		(pad "1" smd circle
			(at -0.40005 0 90)
			(size 0 0)
			(layers "F.Cu" "F.Mask" "F.Paste")
			(net "P12V_NIC6_CO_ISET_R")
		)
		(pad "2" smd circle
			(at 0.40005 0 90)
			(size 0 0)
			(layers "F.Cu" "F.Mask" "F.Paste")
			(net "GND")
		)
	)
	(footprint ""
		(layer "F.Cu")
		(at 221.990158 -83.659472)
		(property "Reference" "R5768"
			(at 0 0 0)
			(layer "F.SilkS")
			(hide yes)
			(effects
				(font
					(size 1.27 1.27)
				)
			)
		)
		(property "Value" ""
			(at 0 0 0)
			(layer "F.Fab")
			(effects
				(font
					(size 1.27 1.27)
				)
			)
		)
		(duplicate_pad_numbers_are_jumpers no)
		(fp_line
			(start -0.7874 -0.4064)
			(end 0.7874 -0.4064)
			(stroke
				(width 0.1524)
				(type default)
			)
			(layer "F.SilkS")
		)
		(fp_line
			(start -0.7874 0.4064)
			(end -0.7874 -0.4064)
			(stroke
				(width 0.1524)
				(type default)
			)
			(layer "F.SilkS")
		)
		(fp_line
			(start 0.7874 -0.4064)
			(end 0.7874 0.4064)
			(stroke
				(width 0.1524)
				(type default)
			)
			(layer "F.SilkS")
		)
		(fp_line
			(start 0.7874 0.4064)
			(end -0.7874 0.4064)
			(stroke
				(width 0.1524)
				(type default)
			)
			(layer "F.SilkS")
		)
		(fp_line
			(start -0.67945 -0.305054)
			(end -0.12065 -0.305054)
			(stroke
				(width 0.1)
				(type default)
			)
			(layer "F.Fab")
		)
		(fp_line
			(start -0.67945 0.3048)
			(end -0.67945 -0.305054)
			(stroke
				(width 0.1)
				(type default)
			)
			(layer "F.Fab")
		)
		(fp_line
			(start -0.12065 -0.305054)
			(end -0.12065 -0.2794)
			(stroke
				(width 0.1)
				(type default)
			)
			(layer "F.Fab")
		)
		(fp_line
			(start -0.12065 -0.2794)
			(end 0.12065 -0.2794)
			(stroke
				(width 0.1)
				(type default)
			)
			(layer "F.Fab")
		)
		(fp_line
			(start -0.12065 0.2794)
			(end -0.12065 0.3048)
			(stroke
				(width 0.1)
				(type default)
			)
			(layer "F.Fab")
		)
		(fp_line
			(start -0.12065 0.3048)
			(end -0.67945 0.3048)
			(stroke
				(width 0.1)
				(type default)
			)
			(layer "F.Fab")
		)
		(fp_line
			(start 0.120396 0.2794)
			(end -0.12065 0.2794)
			(stroke
				(width 0.1)
				(type default)
			)
			(layer "F.Fab")
		)
		(fp_line
			(start 0.120396 0.3048)
			(end 0.120396 0.2794)
			(stroke
				(width 0.1)
				(type default)
			)
			(layer "F.Fab")
		)
		(fp_line
			(start 0.12065 -0.3048)
			(end 0.67945 -0.3048)
			(stroke
				(width 0.1)
				(type default)
			)
			(layer "F.Fab")
		)
		(fp_line
			(start 0.12065 -0.2794)
			(end 0.12065 -0.3048)
			(stroke
				(width 0.1)
				(type default)
			)
			(layer "F.Fab")
		)
		(fp_line
			(start 0.67945 -0.3048)
			(end 0.67945 0.3048)
			(stroke
				(width 0.1)
				(type default)
			)
			(layer "F.Fab")
		)
		(fp_line
			(start 0.67945 0.3048)
			(end 0.120396 0.3048)
			(stroke
				(width 0.1)
				(type default)
			)
			(layer "F.Fab")
		)
		(pad "1" smd circle
			(at -0.40005 0)
			(size 0 0)
			(layers "F.Cu" "F.Mask" "F.Paste")
			(net "SSD14_LED")
		)
		(pad "2" smd circle
			(at 0.40005 0)
			(size 0 0)
			(layers "F.Cu" "F.Mask" "F.Paste")
			(net "SSD14_LED_R")
		)
	)
	(footprint ""
		(layer "F.Cu")
		(at 460.340964 -524.207486 180)
		(property "Reference" "HANDLE_0"
			(at -3.6322 -1.402334 0)
			(unlocked yes)
			(layer "B.SilkS")
			(effects
				(font
					(size 0.7874 0.5842)
					(thickness 0.1524)
				)
				(justify mirror)
			)
		)
		(property "Value" ""
			(at 0 0 180)
			(layer "F.Fab")
			(effects
				(font
					(size 1.27 1.27)
				)
			)
		)
		(duplicate_pad_numbers_are_jumpers no)
		(pad "1" thru_hole circle
			(at 0 0 180)
			(size 0.4572 0.4572)
			(drill 0.2032)
			(layers "*.Cu" "*.Mask")
			(remove_unused_layers no)
			(net "Net_9178")
			(clearance 0.127)
			(thermal_gap 0.127)
			(padstack
				(mode front_inner_back)
				(layer "Inner"
					(shape circle)
					(size 0.4572 0.4572)
					(clearance 0.127)
				)
				(layer "B.Cu"
					(shape circle)
					(size 0.508 0.508)
					(clearance 0.1016)
				)
			)
		)
	)
	(footprint ""
		(layer "F.Cu")
		(at 152.345898 -261.663434)
		(property "Reference" "C3213"
			(at 0 0 0)
			(layer "F.SilkS")
			(hide yes)
			(effects
				(font
					(size 1.27 1.27)
				)
			)
		)
		(property "Value" ""
			(at 0 0 0)
			(layer "F.Fab")
			(effects
				(font
					(size 1.27 1.27)
				)
			)
		)
		(duplicate_pad_numbers_are_jumpers no)
		(fp_line
			(start -1.2954 -0.5842)
			(end 1.2954 -0.5842)
			(stroke
				(width 0.1524)
				(type default)
			)
			(layer "F.SilkS")
		)
		(fp_line
			(start -1.2954 0.5842)
			(end -1.2954 -0.5842)
			(stroke
				(width 0.1524)
				(type default)
			)
			(layer "F.SilkS")
		)
		(fp_line
			(start 1.2954 -0.5842)
			(end 1.2954 0.5842)
			(stroke
				(width 0.1524)
				(type default)
			)
			(layer "F.SilkS")
		)
		(fp_line
			(start 1.2954 0.5842)
			(end -1.2954 0.5842)
			(stroke
				(width 0.1524)
				(type default)
			)
			(layer "F.SilkS")
		)
		(fp_line
			(start -1.1938 -0.4064)
			(end -0.8636 -0.4064)
			(stroke
				(width 0.1)
				(type default)
			)
			(layer "F.Fab")
		)
		(fp_line
			(start -1.1938 0.4064)
			(end -1.1938 -0.4064)
			(stroke
				(width 0.1)
				(type default)
			)
			(layer "F.Fab")
		)
		(fp_line
			(start -0.8636 -0.4572)
			(end 0.8636 -0.4572)
			(stroke
				(width 0.1)
				(type default)
			)
			(layer "F.Fab")
		)
		(fp_line
			(start -0.8636 -0.4064)
			(end -0.8636 -0.4572)
			(stroke
				(width 0.1)
				(type default)
			)
			(layer "F.Fab")
		)
		(fp_line
			(start -0.8636 0.4064)
			(end -1.1938 0.4064)
			(stroke
				(width 0.1)
				(type default)
			)
			(layer "F.Fab")
		)
		(fp_line
			(start -0.8636 0.4572)
			(end -0.8636 0.4064)
			(stroke
				(width 0.1)
				(type default)
			)
			(layer "F.Fab")
		)
		(fp_line
			(start 0.8636 -0.4572)
			(end 0.8636 -0.4064)
			(stroke
				(width 0.1)
				(type default)
			)
			(layer "F.Fab")
		)
		(fp_line
			(start 0.8636 -0.4064)
			(end 1.1938 -0.4064)
			(stroke
				(width 0.1)
				(type default)
			)
			(layer "F.Fab")
		)
		(fp_line
			(start 0.8636 0.4064)
			(end 0.8636 0.4572)
			(stroke
				(width 0.1)
				(type default)
			)
			(layer "F.Fab")
		)
		(fp_line
			(start 0.8636 0.4572)
			(end -0.8636 0.4572)
			(stroke
				(width 0.1)
				(type default)
			)
			(layer "F.Fab")
		)
		(fp_line
			(start 1.1938 -0.4064)
			(end 1.1938 0.4064)
			(stroke
				(width 0.1)
				(type default)
			)
			(layer "F.Fab")
		)
		(fp_line
			(start 1.1938 0.4064)
			(end 0.8636 0.4064)
			(stroke
				(width 0.1)
				(type default)
			)
			(layer "F.Fab")
		)
		(pad "1" smd rect
			(at -0.7366 0 270)
			(size 0.7112 0.8128)
			(layers "F.Cu" "F.Mask" "F.Paste")
			(net "PCEPLL3_VDDA18_PEX1")
		)
		(pad "2" smd rect
			(at 0.7366 0 270)
			(size 0.7112 0.8128)
			(layers "F.Cu" "F.Mask" "F.Paste")
			(net "GND")
		)
	)
	(footprint ""
		(layer "F.Cu")
		(at 177.892456 -158.080202 90)
		(property "Reference" "R3306"
			(at 0 0 90)
			(layer "F.SilkS")
			(hide yes)
			(effects
				(font
					(size 1.27 1.27)
				)
			)
		)
		(property "Value" ""
			(at 0 0 90)
			(layer "F.Fab")
			(effects
				(font
					(size 1.27 1.27)
				)
			)
		)
		(duplicate_pad_numbers_are_jumpers no)
		(fp_line
			(start 0.7874 -0.4064)
			(end 0.7874 0.4064)
			(stroke
				(width 0.1524)
				(type default)
			)
			(layer "F.SilkS")
		)
		(fp_line
			(start -0.7874 -0.4064)
			(end 0.7874 -0.4064)
			(stroke
				(width 0.1524)
				(type default)
			)
			(layer "F.SilkS")
		)
		(fp_line
			(start 0.7874 0.4064)
			(end -0.7874 0.4064)
			(stroke
				(width 0.1524)
				(type default)
			)
			(layer "F.SilkS")
		)
		(fp_line
			(start -0.7874 0.4064)
			(end -0.7874 -0.4064)
			(stroke
				(width 0.1524)
				(type default)
			)
			(layer "F.SilkS")
		)
		(fp_line
			(start -0.12065 -0.305054)
			(end -0.12065 -0.2794)
			(stroke
				(width 0.1)
				(type default)
			)
			(layer "F.Fab")
		)
		(fp_line
			(start -0.67945 -0.305054)
			(end -0.12065 -0.305054)
			(stroke
				(width 0.1)
				(type default)
			)
			(layer "F.Fab")
		)
		(fp_line
			(start 0.67945 -0.3048)
			(end 0.67945 0.3048)
			(stroke
				(width 0.1)
				(type default)
			)
			(layer "F.Fab")
		)
		(fp_line
			(start 0.12065 -0.3048)
			(end 0.67945 -0.3048)
			(stroke
				(width 0.1)
				(type default)
			)
			(layer "F.Fab")
		)
		(fp_line
			(start 0.12065 -0.2794)
			(end 0.12065 -0.3048)
			(stroke
				(width 0.1)
				(type default)
			)
			(layer "F.Fab")
		)
		(fp_line
			(start -0.12065 -0.2794)
			(end 0.12065 -0.2794)
			(stroke
				(width 0.1)
				(type default)
			)
			(layer "F.Fab")
		)
		(fp_line
			(start 0.120396 0.2794)
			(end -0.12065 0.2794)
			(stroke
				(width 0.1)
				(type default)
			)
			(layer "F.Fab")
		)
		(fp_line
			(start -0.12065 0.2794)
			(end -0.12065 0.3048)
			(stroke
				(width 0.1)
				(type default)
			)
			(layer "F.Fab")
		)
		(fp_line
			(start 0.67945 0.3048)
			(end 0.120396 0.3048)
			(stroke
				(width 0.1)
				(type default)
			)
			(layer "F.Fab")
		)
		(fp_line
			(start 0.120396 0.3048)
			(end 0.120396 0.2794)
			(stroke
				(width 0.1)
				(type default)
			)
			(layer "F.Fab")
		)
		(fp_line
			(start -0.12065 0.3048)
			(end -0.67945 0.3048)
			(stroke
				(width 0.1)
				(type default)
			)
			(layer "F.Fab")
		)
		(fp_line
			(start -0.67945 0.3048)
			(end -0.67945 -0.305054)
			(stroke
				(width 0.1)
				(type default)
			)
			(layer "F.Fab")
		)
		(pad "1" smd circle
			(at -0.40005 0 90)
			(size 0 0)
			(layers "F.Cu" "F.Mask" "F.Paste")
			(net "FM_SYS_THROTTLE_R")
		)
		(pad "2" smd circle
			(at 0.40005 0 90)
			(size 0 0)
			(layers "F.Cu" "F.Mask" "F.Paste")
			(net "FM_SYS_THROTTLE_NIC2")
		)
	)
	(footprint ""
		(layer "F.Cu")
		(at 465.58073 -524.540988 180)
		(property "Reference" "SCREW_SSD1_2"
			(at -5.207 -1.402334 0)
			(unlocked yes)
			(layer "B.SilkS")
			(effects
				(font
					(size 0.7874 0.5842)
					(thickness 0.1524)
				)
				(justify mirror)
			)
		)
		(property "Value" ""
			(at 0 0 180)
			(layer "F.Fab")
			(effects
				(font
					(size 1.27 1.27)
				)
			)
		)
		(duplicate_pad_numbers_are_jumpers no)
		(pad "1" thru_hole circle
			(at 0 0 180)
			(size 0.4572 0.4572)
			(drill 0.2032)
			(layers "*.Cu" "*.Mask")
			(remove_unused_layers no)
			(net "Net_9141")
			(clearance 0.127)
			(thermal_gap 0.127)
			(padstack
				(mode front_inner_back)
				(layer "Inner"
					(shape circle)
					(size 0.4572 0.4572)
					(clearance 0.127)
				)
				(layer "B.Cu"
					(shape circle)
					(size 0.508 0.508)
					(clearance 0.1016)
				)
			)
		)
	)
	(footprint ""
		(layer "F.Cu")
		(at 329.726544 -55.418228 90)
		(property "Reference" "PC440"
			(at 0 0 90)
			(layer "F.SilkS")
			(hide yes)
			(effects
				(font
					(size 1.27 1.27)
				)
			)
		)
		(property "Value" ""
			(at 0 0 90)
			(layer "F.Fab")
			(effects
				(font
					(size 1.27 1.27)
				)
			)
		)
		(duplicate_pad_numbers_are_jumpers no)
		(fp_line
			(start 0.7874 -0.4064)
			(end 0.7874 0.4064)
			(stroke
				(width 0.1524)
				(type default)
			)
			(layer "F.SilkS")
		)
		(fp_line
			(start -0.7874 -0.4064)
			(end 0.7874 -0.4064)
			(stroke
				(width 0.1524)
				(type default)
			)
			(layer "F.SilkS")
		)
		(fp_line
			(start 0.7874 0.4064)
			(end -0.7874 0.4064)
			(stroke
				(width 0.1524)
				(type default)
			)
			(layer "F.SilkS")
		)
		(fp_line
			(start -0.7874 0.4064)
			(end -0.7874 -0.4064)
			(stroke
				(width 0.1524)
				(type default)
			)
			(layer "F.SilkS")
		)
		(fp_line
			(start -0.12065 -0.305054)
			(end -0.12065 -0.2794)
			(stroke
				(width 0.1)
				(type default)
			)
			(layer "F.Fab")
		)
		(fp_line
			(start -0.67945 -0.305054)
			(end -0.12065 -0.305054)
			(stroke
				(width 0.1)
				(type default)
			)
			(layer "F.Fab")
		)
		(fp_line
			(start 0.67945 -0.3048)
			(end 0.67945 0.3048)
			(stroke
				(width 0.1)
				(type default)
			)
			(layer "F.Fab")
		)
		(fp_line
			(start 0.12065 -0.3048)
			(end 0.67945 -0.3048)
			(stroke
				(width 0.1)
				(type default)
			)
			(layer "F.Fab")
		)
		(fp_line
			(start 0.12065 -0.2794)
			(end 0.12065 -0.3048)
			(stroke
				(width 0.1)
				(type default)
			)
			(layer "F.Fab")
		)
		(fp_line
			(start -0.12065 -0.2794)
			(end 0.12065 -0.2794)
			(stroke
				(width 0.1)
				(type default)
			)
			(layer "F.Fab")
		)
		(fp_line
			(start 0.120396 0.2794)
			(end -0.12065 0.2794)
			(stroke
				(width 0.1)
				(type default)
			)
			(layer "F.Fab")
		)
		(fp_line
			(start -0.12065 0.2794)
			(end -0.12065 0.3048)
			(stroke
				(width 0.1)
				(type default)
			)
			(layer "F.Fab")
		)
		(fp_line
			(start 0.67945 0.3048)
			(end 0.120396 0.3048)
			(stroke
				(width 0.1)
				(type default)
			)
			(layer "F.Fab")
		)
		(fp_line
			(start 0.120396 0.3048)
			(end 0.120396 0.2794)
			(stroke
				(width 0.1)
				(type default)
			)
			(layer "F.Fab")
		)
		(fp_line
			(start -0.12065 0.3048)
			(end -0.67945 0.3048)
			(stroke
				(width 0.1)
				(type default)
			)
			(layer "F.Fab")
		)
		(fp_line
			(start -0.67945 0.3048)
			(end -0.67945 -0.305054)
			(stroke
				(width 0.1)
				(type default)
			)
			(layer "F.Fab")
		)
		(pad "1" smd circle
			(at -0.40005 0 90)
			(size 0 0)
			(layers "F.Cu" "F.Mask" "F.Paste")
			(net "P12V_SSD11_R")
		)
		(pad "2" smd circle
			(at 0.40005 0 90)
			(size 0 0)
			(layers "F.Cu" "F.Mask" "F.Paste")
			(net "GND")
		)
	)
	(footprint ""
		(layer "F.Cu")
		(at 2.87528 -68.166234 180)
		(property "Reference" "R5876"
			(at 0 0 180)
			(layer "F.SilkS")
			(hide yes)
			(effects
				(font
					(size 1.27 1.27)
				)
			)
		)
		(property "Value" ""
			(at 0 0 180)
			(layer "F.Fab")
			(effects
				(font
					(size 1.27 1.27)
				)
			)
		)
		(duplicate_pad_numbers_are_jumpers no)
		(fp_line
			(start 0.7874 0.4064)
			(end -0.7874 0.4064)
			(stroke
				(width 0.1524)
				(type default)
			)
			(layer "F.SilkS")
		)
		(fp_line
			(start 0.7874 -0.4064)
			(end 0.7874 0.4064)
			(stroke
				(width 0.1524)
				(type default)
			)
			(layer "F.SilkS")
		)
		(fp_line
			(start -0.7874 0.4064)
			(end -0.7874 -0.4064)
			(stroke
				(width 0.1524)
				(type default)
			)
			(layer "F.SilkS")
		)
		(fp_line
			(start -0.7874 -0.4064)
			(end 0.7874 -0.4064)
			(stroke
				(width 0.1524)
				(type default)
			)
			(layer "F.SilkS")
		)
		(fp_line
			(start 0.67945 0.3048)
			(end 0.120396 0.3048)
			(stroke
				(width 0.1)
				(type default)
			)
			(layer "F.Fab")
		)
		(fp_line
			(start 0.67945 -0.3048)
			(end 0.67945 0.3048)
			(stroke
				(width 0.1)
				(type default)
			)
			(layer "F.Fab")
		)
		(fp_line
			(start 0.12065 -0.2794)
			(end 0.12065 -0.3048)
			(stroke
				(width 0.1)
				(type default)
			)
			(layer "F.Fab")
		)
		(fp_line
			(start 0.12065 -0.3048)
			(end 0.67945 -0.3048)
			(stroke
				(width 0.1)
				(type default)
			)
			(layer "F.Fab")
		)
		(fp_line
			(start 0.120396 0.3048)
			(end 0.120396 0.2794)
			(stroke
				(width 0.1)
				(type default)
			)
			(layer "F.Fab")
		)
		(fp_line
			(start 0.120396 0.2794)
			(end -0.12065 0.2794)
			(stroke
				(width 0.1)
				(type default)
			)
			(layer "F.Fab")
		)
		(fp_line
			(start -0.12065 0.3048)
			(end -0.67945 0.3048)
			(stroke
				(width 0.1)
				(type default)
			)
			(layer "F.Fab")
		)
		(fp_line
			(start -0.12065 0.2794)
			(end -0.12065 0.3048)
			(stroke
				(width 0.1)
				(type default)
			)
			(layer "F.Fab")
		)
		(fp_line
			(start -0.12065 -0.2794)
			(end 0.12065 -0.2794)
			(stroke
				(width 0.1)
				(type default)
			)
			(layer "F.Fab")
		)
		(fp_line
			(start -0.12065 -0.305054)
			(end -0.12065 -0.2794)
			(stroke
				(width 0.1)
				(type default)
			)
			(layer "F.Fab")
		)
		(fp_line
			(start -0.67945 0.3048)
			(end -0.67945 -0.305054)
			(stroke
				(width 0.1)
				(type default)
			)
			(layer "F.Fab")
		)
		(fp_line
			(start -0.67945 -0.305054)
			(end -0.12065 -0.305054)
			(stroke
				(width 0.1)
				(type default)
			)
			(layer "F.Fab")
		)
		(pad "1" smd circle
			(at -0.40005 0 180)
			(size 0 0)
			(layers "F.Cu" "F.Mask" "F.Paste")
			(net "P3V3_SSD0_PG_G1")
		)
		(pad "2" smd circle
			(at 0.40005 0 180)
			(size 0 0)
			(layers "F.Cu" "F.Mask" "F.Paste")
			(net "GND")
		)
	)
	(footprint ""
		(layer "F.Cu")
		(at 372.07698 -350.098614 90)
		(property "Reference" "C779"
			(at 0 0 90)
			(layer "F.SilkS")
			(hide yes)
			(effects
				(font
					(size 1.27 1.27)
				)
			)
		)
		(property "Value" ""
			(at 0 0 90)
			(layer "F.Fab")
			(effects
				(font
					(size 1.27 1.27)
				)
			)
		)
		(duplicate_pad_numbers_are_jumpers no)
		(fp_line
			(start 0.299974 -0.150114)
			(end 0.299974 0.150114)
			(stroke
				(width 0.1)
				(type default)
			)
			(layer "F.Fab")
		)
		(fp_line
			(start -0.299974 -0.150114)
			(end 0.299974 -0.150114)
			(stroke
				(width 0.1)
				(type default)
			)
			(layer "F.Fab")
		)
		(fp_line
			(start 0.299974 0.150114)
			(end -0.299974 0.150114)
			(stroke
				(width 0.1)
				(type default)
			)
			(layer "F.Fab")
		)
		(fp_line
			(start -0.299974 0.150114)
			(end -0.299974 -0.150114)
			(stroke
				(width 0.1)
				(type default)
			)
			(layer "F.Fab")
		)
		(pad "1" smd rect
			(at -0.2667 0 90)
			(size 0.3048 0.381)
			(layers "F.Cu" "F.Mask" "F.Paste")
			(net "P5E_PEX3_STN6_TX_DN<103>")
		)
		(pad "2" smd rect
			(at 0.2667 0 90)
			(size 0.3048 0.381)
			(layers "F.Cu" "F.Mask" "F.Paste")
			(net "P5E_PEX3_STN6_TX_C_DN<103>")
		)
	)
	(footprint ""
		(layer "F.Cu")
		(at 380.48946 -350.098614 90)
		(property "Reference" "C770"
			(at 0 0 90)
			(layer "F.SilkS")
			(hide yes)
			(effects
				(font
					(size 1.27 1.27)
				)
			)
		)
		(property "Value" ""
			(at 0 0 90)
			(layer "F.Fab")
			(effects
				(font
					(size 1.27 1.27)
				)
			)
		)
		(duplicate_pad_numbers_are_jumpers no)
		(fp_line
			(start 0.299974 -0.150114)
			(end 0.299974 0.150114)
			(stroke
				(width 0.1)
				(type default)
			)
			(layer "F.Fab")
		)
		(fp_line
			(start -0.299974 -0.150114)
			(end 0.299974 -0.150114)
			(stroke
				(width 0.1)
				(type default)
			)
			(layer "F.Fab")
		)
		(fp_line
			(start 0.299974 0.150114)
			(end -0.299974 0.150114)
			(stroke
				(width 0.1)
				(type default)
			)
			(layer "F.Fab")
		)
		(fp_line
			(start -0.299974 0.150114)
			(end -0.299974 -0.150114)
			(stroke
				(width 0.1)
				(type default)
			)
			(layer "F.Fab")
		)
		(pad "1" smd rect
			(at -0.2667 0 90)
			(size 0.3048 0.381)
			(layers "F.Cu" "F.Mask" "F.Paste")
			(net "P5E_PEX3_STN6_TX_DP<107>")
		)
		(pad "2" smd rect
			(at 0.2667 0 90)
			(size 0.3048 0.381)
			(layers "F.Cu" "F.Mask" "F.Paste")
			(net "P5E_PEX3_STN6_TX_C_DP<107>")
		)
	)
	(footprint ""
		(layer "F.Cu")
		(at 462.465674 -277.65883)
		(property "Reference" "R805"
			(at 0 0 0)
			(layer "F.SilkS")
			(hide yes)
			(effects
				(font
					(size 1.27 1.27)
				)
			)
		)
		(property "Value" ""
			(at 0 0 0)
			(layer "F.Fab")
			(effects
				(font
					(size 1.27 1.27)
				)
			)
		)
		(duplicate_pad_numbers_are_jumpers no)
		(fp_line
			(start -0.7874 -0.4064)
			(end 0.7874 -0.4064)
			(stroke
				(width 0.1524)
				(type default)
			)
			(layer "F.SilkS")
		)
		(fp_line
			(start -0.7874 0.4064)
			(end -0.7874 -0.4064)
			(stroke
				(width 0.1524)
				(type default)
			)
			(layer "F.SilkS")
		)
		(fp_line
			(start 0.7874 -0.4064)
			(end 0.7874 0.4064)
			(stroke
				(width 0.1524)
				(type default)
			)
			(layer "F.SilkS")
		)
		(fp_line
			(start 0.7874 0.4064)
			(end -0.7874 0.4064)
			(stroke
				(width 0.1524)
				(type default)
			)
			(layer "F.SilkS")
		)
		(fp_line
			(start -0.67945 -0.305054)
			(end -0.12065 -0.305054)
			(stroke
				(width 0.1)
				(type default)
			)
			(layer "F.Fab")
		)
		(fp_line
			(start -0.67945 0.3048)
			(end -0.67945 -0.305054)
			(stroke
				(width 0.1)
				(type default)
			)
			(layer "F.Fab")
		)
		(fp_line
			(start -0.12065 -0.305054)
			(end -0.12065 -0.2794)
			(stroke
				(width 0.1)
				(type default)
			)
			(layer "F.Fab")
		)
		(fp_line
			(start -0.12065 -0.2794)
			(end 0.12065 -0.2794)
			(stroke
				(width 0.1)
				(type default)
			)
			(layer "F.Fab")
		)
		(fp_line
			(start -0.12065 0.2794)
			(end -0.12065 0.3048)
			(stroke
				(width 0.1)
				(type default)
			)
			(layer "F.Fab")
		)
		(fp_line
			(start -0.12065 0.3048)
			(end -0.67945 0.3048)
			(stroke
				(width 0.1)
				(type default)
			)
			(layer "F.Fab")
		)
		(fp_line
			(start 0.120396 0.2794)
			(end -0.12065 0.2794)
			(stroke
				(width 0.1)
				(type default)
			)
			(layer "F.Fab")
		)
		(fp_line
			(start 0.120396 0.3048)
			(end 0.120396 0.2794)
			(stroke
				(width 0.1)
				(type default)
			)
			(layer "F.Fab")
		)
		(fp_line
			(start 0.12065 -0.3048)
			(end 0.67945 -0.3048)
			(stroke
				(width 0.1)
				(type default)
			)
			(layer "F.Fab")
		)
		(fp_line
			(start 0.12065 -0.2794)
			(end 0.12065 -0.3048)
			(stroke
				(width 0.1)
				(type default)
			)
			(layer "F.Fab")
		)
		(fp_line
			(start 0.67945 -0.3048)
			(end 0.67945 0.3048)
			(stroke
				(width 0.1)
				(type default)
			)
			(layer "F.Fab")
		)
		(fp_line
			(start 0.67945 0.3048)
			(end 0.120396 0.3048)
			(stroke
				(width 0.1)
				(type default)
			)
			(layer "F.Fab")
		)
		(pad "1" smd circle
			(at -0.40005 0)
			(size 0 0)
			(layers "F.Cu" "F.Mask" "F.Paste")
			(net "PEX3_P1V25_ADC_ALERT_N")
		)
		(pad "2" smd circle
			(at 0.40005 0)
			(size 0 0)
			(layers "F.Cu" "F.Mask" "F.Paste")
			(net "PEX_ADC_ALERT_N")
		)
	)
	(footprint ""
		(layer "F.Cu")
		(at 312.21934 -147.104608 180)
		(property "Reference" "C433"
			(at 0 0 180)
			(layer "F.SilkS")
			(hide yes)
			(effects
				(font
					(size 1.27 1.27)
				)
			)
		)
		(property "Value" ""
			(at 0 0 180)
			(layer "F.Fab")
			(effects
				(font
					(size 1.27 1.27)
				)
			)
		)
		(duplicate_pad_numbers_are_jumpers no)
		(fp_line
			(start 0.299974 0.150114)
			(end -0.299974 0.150114)
			(stroke
				(width 0.1)
				(type default)
			)
			(layer "F.Fab")
		)
		(fp_line
			(start 0.299974 -0.150114)
			(end 0.299974 0.150114)
			(stroke
				(width 0.1)
				(type default)
			)
			(layer "F.Fab")
		)
		(fp_line
			(start -0.299974 0.150114)
			(end -0.299974 -0.150114)
			(stroke
				(width 0.1)
				(type default)
			)
			(layer "F.Fab")
		)
		(fp_line
			(start -0.299974 -0.150114)
			(end 0.299974 -0.150114)
			(stroke
				(width 0.1)
				(type default)
			)
			(layer "F.Fab")
		)
		(pad "1" smd rect
			(at -0.2667 0 180)
			(size 0.3048 0.381)
			(layers "F.Cu" "F.Mask" "F.Paste")
			(net "P5E_PEX2_STN0_TX_DP<10>")
		)
		(pad "2" smd rect
			(at 0.2667 0 180)
			(size 0.3048 0.381)
			(layers "F.Cu" "F.Mask" "F.Paste")
			(net "P5E_PEX2_STN0_TX_C_DP<10>")
		)
	)
	(footprint ""
		(layer "F.Cu")
		(at 159.966152 -356.244906 90)
		(property "Reference" "C403"
			(at 0 0 90)
			(layer "F.SilkS")
			(hide yes)
			(effects
				(font
					(size 1.27 1.27)
				)
			)
		)
		(property "Value" ""
			(at 0 0 90)
			(layer "F.Fab")
			(effects
				(font
					(size 1.27 1.27)
				)
			)
		)
		(duplicate_pad_numbers_are_jumpers no)
		(fp_line
			(start 0.299974 -0.150114)
			(end 0.299974 0.150114)
			(stroke
				(width 0.1)
				(type default)
			)
			(layer "F.Fab")
		)
		(fp_line
			(start -0.299974 -0.150114)
			(end 0.299974 -0.150114)
			(stroke
				(width 0.1)
				(type default)
			)
			(layer "F.Fab")
		)
		(fp_line
			(start 0.299974 0.150114)
			(end -0.299974 0.150114)
			(stroke
				(width 0.1)
				(type default)
			)
			(layer "F.Fab")
		)
		(fp_line
			(start -0.299974 0.150114)
			(end -0.299974 -0.150114)
			(stroke
				(width 0.1)
				(type default)
			)
			(layer "F.Fab")
		)
		(pad "1" smd rect
			(at -0.2667 0 90)
			(size 0.3048 0.381)
			(layers "F.Cu" "F.Mask" "F.Paste")
			(net "P5E_PEX1_STN7_TX_DN<112>")
		)
		(pad "2" smd rect
			(at 0.2667 0 90)
			(size 0.3048 0.381)
			(layers "F.Cu" "F.Mask" "F.Paste")
			(net "P5E_PEX1_STN7_TX_C_DN<112>")
		)
	)
	(footprint ""
		(layer "F.Cu")
		(at 377.175268 -64.102234 180)
		(property "Reference" "PR7092"
			(at 0 0 180)
			(layer "F.SilkS")
			(hide yes)
			(effects
				(font
					(size 1.27 1.27)
				)
			)
		)
		(property "Value" ""
			(at 0 0 180)
			(layer "F.Fab")
			(effects
				(font
					(size 1.27 1.27)
				)
			)
		)
		(duplicate_pad_numbers_are_jumpers no)
		(fp_line
			(start 0.7874 0.4064)
			(end -0.7874 0.4064)
			(stroke
				(width 0.1524)
				(type default)
			)
			(layer "F.SilkS")
		)
		(fp_line
			(start 0.7874 -0.4064)
			(end 0.7874 0.4064)
			(stroke
				(width 0.1524)
				(type default)
			)
			(layer "F.SilkS")
		)
		(fp_line
			(start -0.7874 0.4064)
			(end -0.7874 -0.4064)
			(stroke
				(width 0.1524)
				(type default)
			)
			(layer "F.SilkS")
		)
		(fp_line
			(start -0.7874 -0.4064)
			(end 0.7874 -0.4064)
			(stroke
				(width 0.1524)
				(type default)
			)
			(layer "F.SilkS")
		)
		(fp_line
			(start 0.67945 0.3048)
			(end 0.120396 0.3048)
			(stroke
				(width 0.1)
				(type default)
			)
			(layer "F.Fab")
		)
		(fp_line
			(start 0.67945 -0.3048)
			(end 0.67945 0.3048)
			(stroke
				(width 0.1)
				(type default)
			)
			(layer "F.Fab")
		)
		(fp_line
			(start 0.12065 -0.2794)
			(end 0.12065 -0.3048)
			(stroke
				(width 0.1)
				(type default)
			)
			(layer "F.Fab")
		)
		(fp_line
			(start 0.12065 -0.3048)
			(end 0.67945 -0.3048)
			(stroke
				(width 0.1)
				(type default)
			)
			(layer "F.Fab")
		)
		(fp_line
			(start 0.120396 0.3048)
			(end 0.120396 0.2794)
			(stroke
				(width 0.1)
				(type default)
			)
			(layer "F.Fab")
		)
		(fp_line
			(start 0.120396 0.2794)
			(end -0.12065 0.2794)
			(stroke
				(width 0.1)
				(type default)
			)
			(layer "F.Fab")
		)
		(fp_line
			(start -0.12065 0.3048)
			(end -0.67945 0.3048)
			(stroke
				(width 0.1)
				(type default)
			)
			(layer "F.Fab")
		)
		(fp_line
			(start -0.12065 0.2794)
			(end -0.12065 0.3048)
			(stroke
				(width 0.1)
				(type default)
			)
			(layer "F.Fab")
		)
		(fp_line
			(start -0.12065 -0.2794)
			(end 0.12065 -0.2794)
			(stroke
				(width 0.1)
				(type default)
			)
			(layer "F.Fab")
		)
		(fp_line
			(start -0.12065 -0.305054)
			(end -0.12065 -0.2794)
			(stroke
				(width 0.1)
				(type default)
			)
			(layer "F.Fab")
		)
		(fp_line
			(start -0.67945 0.3048)
			(end -0.67945 -0.305054)
			(stroke
				(width 0.1)
				(type default)
			)
			(layer "F.Fab")
		)
		(fp_line
			(start -0.67945 -0.305054)
			(end -0.12065 -0.305054)
			(stroke
				(width 0.1)
				(type default)
			)
			(layer "F.Fab")
		)
		(pad "1" smd circle
			(at -0.40005 0 180)
			(size 0 0)
			(layers "F.Cu" "F.Mask" "F.Paste")
			(net "P12V_SSD13_PG_G1")
		)
		(pad "2" smd circle
			(at 0.40005 0 180)
			(size 0 0)
			(layers "F.Cu" "F.Mask" "F.Paste")
			(net "GND")
		)
	)
	(footprint ""
		(layer "F.Cu")
		(at 202.311 -61.386974)
		(property "Reference" "R4494"
			(at 0 0 0)
			(layer "F.SilkS")
			(hide yes)
			(effects
				(font
					(size 1.27 1.27)
				)
			)
		)
		(property "Value" ""
			(at 0 0 0)
			(layer "F.Fab")
			(effects
				(font
					(size 1.27 1.27)
				)
			)
		)
		(duplicate_pad_numbers_are_jumpers no)
		(fp_line
			(start -0.7874 -0.4064)
			(end 0.7874 -0.4064)
			(stroke
				(width 0.1524)
				(type default)
			)
			(layer "F.SilkS")
		)
		(fp_line
			(start -0.7874 0.4064)
			(end -0.7874 -0.4064)
			(stroke
				(width 0.1524)
				(type default)
			)
			(layer "F.SilkS")
		)
		(fp_line
			(start 0.7874 -0.4064)
			(end 0.7874 0.4064)
			(stroke
				(width 0.1524)
				(type default)
			)
			(layer "F.SilkS")
		)
		(fp_line
			(start 0.7874 0.4064)
			(end -0.7874 0.4064)
			(stroke
				(width 0.1524)
				(type default)
			)
			(layer "F.SilkS")
		)
		(fp_line
			(start -0.67945 -0.305054)
			(end -0.12065 -0.305054)
			(stroke
				(width 0.1)
				(type default)
			)
			(layer "F.Fab")
		)
		(fp_line
			(start -0.67945 0.3048)
			(end -0.67945 -0.305054)
			(stroke
				(width 0.1)
				(type default)
			)
			(layer "F.Fab")
		)
		(fp_line
			(start -0.12065 -0.305054)
			(end -0.12065 -0.2794)
			(stroke
				(width 0.1)
				(type default)
			)
			(layer "F.Fab")
		)
		(fp_line
			(start -0.12065 -0.2794)
			(end 0.12065 -0.2794)
			(stroke
				(width 0.1)
				(type default)
			)
			(layer "F.Fab")
		)
		(fp_line
			(start -0.12065 0.2794)
			(end -0.12065 0.3048)
			(stroke
				(width 0.1)
				(type default)
			)
			(layer "F.Fab")
		)
		(fp_line
			(start -0.12065 0.3048)
			(end -0.67945 0.3048)
			(stroke
				(width 0.1)
				(type default)
			)
			(layer "F.Fab")
		)
		(fp_line
			(start 0.120396 0.2794)
			(end -0.12065 0.2794)
			(stroke
				(width 0.1)
				(type default)
			)
			(layer "F.Fab")
		)
		(fp_line
			(start 0.120396 0.3048)
			(end 0.120396 0.2794)
			(stroke
				(width 0.1)
				(type default)
			)
			(layer "F.Fab")
		)
		(fp_line
			(start 0.12065 -0.3048)
			(end 0.67945 -0.3048)
			(stroke
				(width 0.1)
				(type default)
			)
			(layer "F.Fab")
		)
		(fp_line
			(start 0.12065 -0.2794)
			(end 0.12065 -0.3048)
			(stroke
				(width 0.1)
				(type default)
			)
			(layer "F.Fab")
		)
		(fp_line
			(start 0.67945 -0.3048)
			(end 0.67945 0.3048)
			(stroke
				(width 0.1)
				(type default)
			)
			(layer "F.Fab")
		)
		(fp_line
			(start 0.67945 0.3048)
			(end 0.120396 0.3048)
			(stroke
				(width 0.1)
				(type default)
			)
			(layer "F.Fab")
		)
		(pad "1" smd circle
			(at -0.40005 0)
			(size 0 0)
			(layers "F.Cu" "F.Mask" "F.Paste")
			(net "PWRGD_P3V3_SSD7")
		)
		(pad "2" smd circle
			(at 0.40005 0)
			(size 0 0)
			(layers "F.Cu" "F.Mask" "F.Paste")
			(net "PWRGD_P3V3_SSD7_R")
		)
	)
	(footprint ""
		(layer "F.Cu")
		(at 284.467808 -51.019456)
		(property "Reference" "PC422"
			(at 0 0 0)
			(layer "F.SilkS")
			(hide yes)
			(effects
				(font
					(size 1.27 1.27)
				)
			)
		)
		(property "Value" ""
			(at 0 0 0)
			(layer "F.Fab")
			(effects
				(font
					(size 1.27 1.27)
				)
			)
		)
		(duplicate_pad_numbers_are_jumpers no)
		(fp_line
			(start -0.7874 -0.4064)
			(end 0.7874 -0.4064)
			(stroke
				(width 0.1524)
				(type default)
			)
			(layer "F.SilkS")
		)
		(fp_line
			(start -0.7874 0.4064)
			(end -0.7874 -0.4064)
			(stroke
				(width 0.1524)
				(type default)
			)
			(layer "F.SilkS")
		)
		(fp_line
			(start 0.7874 -0.4064)
			(end 0.7874 0.4064)
			(stroke
				(width 0.1524)
				(type default)
			)
			(layer "F.SilkS")
		)
		(fp_line
			(start 0.7874 0.4064)
			(end -0.7874 0.4064)
			(stroke
				(width 0.1524)
				(type default)
			)
			(layer "F.SilkS")
		)
		(fp_line
			(start -0.67945 -0.305054)
			(end -0.12065 -0.305054)
			(stroke
				(width 0.1)
				(type default)
			)
			(layer "F.Fab")
		)
		(fp_line
			(start -0.67945 0.3048)
			(end -0.67945 -0.305054)
			(stroke
				(width 0.1)
				(type default)
			)
			(layer "F.Fab")
		)
		(fp_line
			(start -0.12065 -0.305054)
			(end -0.12065 -0.2794)
			(stroke
				(width 0.1)
				(type default)
			)
			(layer "F.Fab")
		)
		(fp_line
			(start -0.12065 -0.2794)
			(end 0.12065 -0.2794)
			(stroke
				(width 0.1)
				(type default)
			)
			(layer "F.Fab")
		)
		(fp_line
			(start -0.12065 0.2794)
			(end -0.12065 0.3048)
			(stroke
				(width 0.1)
				(type default)
			)
			(layer "F.Fab")
		)
		(fp_line
			(start -0.12065 0.3048)
			(end -0.67945 0.3048)
			(stroke
				(width 0.1)
				(type default)
			)
			(layer "F.Fab")
		)
		(fp_line
			(start 0.120396 0.2794)
			(end -0.12065 0.2794)
			(stroke
				(width 0.1)
				(type default)
			)
			(layer "F.Fab")
		)
		(fp_line
			(start 0.120396 0.3048)
			(end 0.120396 0.2794)
			(stroke
				(width 0.1)
				(type default)
			)
			(layer "F.Fab")
		)
		(fp_line
			(start 0.12065 -0.3048)
			(end 0.67945 -0.3048)
			(stroke
				(width 0.1)
				(type default)
			)
			(layer "F.Fab")
		)
		(fp_line
			(start 0.12065 -0.2794)
			(end 0.12065 -0.3048)
			(stroke
				(width 0.1)
				(type default)
			)
			(layer "F.Fab")
		)
		(fp_line
			(start 0.67945 -0.3048)
			(end 0.67945 0.3048)
			(stroke
				(width 0.1)
				(type default)
			)
			(layer "F.Fab")
		)
		(fp_line
			(start 0.67945 0.3048)
			(end 0.120396 0.3048)
			(stroke
				(width 0.1)
				(type default)
			)
			(layer "F.Fab")
		)
		(pad "1" smd circle
			(at -0.40005 0)
			(size 0 0)
			(layers "F.Cu" "F.Mask" "F.Paste")
			(net "P12V_SSD9_SS")
		)
		(pad "2" smd circle
			(at 0.40005 0)
			(size 0 0)
			(layers "F.Cu" "F.Mask" "F.Paste")
			(net "GND")
		)
	)
	(footprint ""
		(layer "F.Cu")
		(at 404.114 -86.255606 180)
		(property "Reference" "U421"
			(at 1.3716 -2.284476 0)
			(unlocked yes)
			(layer "F.SilkS")
			(effects
				(font
					(size 0.7874 0.5842)
					(thickness 0.1524)
				)
				(justify left)
			)
		)
		(property "Value" ""
			(at 0 0 180)
			(layer "F.Fab")
			(effects
				(font
					(size 1.27 1.27)
				)
			)
		)
		(duplicate_pad_numbers_are_jumpers no)
		(fp_line
			(start 1.463548 1.549908)
			(end -1.463548 1.549908)
			(stroke
				(width 0.1524)
				(type default)
			)
			(layer "F.SilkS")
		)
		(fp_line
			(start 1.463548 -1.549908)
			(end 1.463548 1.549908)
			(stroke
				(width 0.1524)
				(type default)
			)
			(layer "F.SilkS")
		)
		(fp_line
			(start 0.762 -1.549908)
			(end 1.463548 -1.549908)
			(stroke
				(width 0.1524)
				(type default)
			)
			(layer "F.SilkS")
		)
		(fp_line
			(start 0 -0.762)
			(end 0.762 -1.549908)
			(stroke
				(width 0.1524)
				(type default)
			)
			(layer "F.SilkS")
		)
		(fp_line
			(start -0.787908 -1.549908)
			(end 0 -0.762)
			(stroke
				(width 0.1524)
				(type default)
			)
			(layer "F.SilkS")
		)
		(fp_line
			(start -1.463548 1.549908)
			(end -1.463548 -1.549908)
			(stroke
				(width 0.1524)
				(type default)
			)
			(layer "F.SilkS")
		)
		(fp_line
			(start -1.463548 -1.549908)
			(end -0.787908 -1.549908)
			(stroke
				(width 0.1524)
				(type default)
			)
			(layer "F.SilkS")
		)
		(fp_poly
			(pts
				(xy -3.4798 -1.359916) (xy -2.86004 -1.050036) (xy -3.4798 -0.740156)
			)
			(stroke
				(width 0)
				(type default)
			)
			(fill yes)
			(layer "F.SilkS")
		)
		(fp_line
			(start 1.549908 1.549908)
			(end -1.549908 1.549908)
			(stroke
				(width 0.1)
				(type default)
			)
			(layer "F.Fab")
		)
		(fp_line
			(start 1.549908 -1.549908)
			(end 1.549908 1.549908)
			(stroke
				(width 0.1)
				(type default)
			)
			(layer "F.Fab")
		)
		(fp_line
			(start -1.549908 1.549908)
			(end -1.549908 -1.549908)
			(stroke
				(width 0.1)
				(type default)
			)
			(layer "F.Fab")
		)
		(fp_line
			(start -1.549908 -1.549908)
			(end 1.549908 -1.549908)
			(stroke
				(width 0.1)
				(type default)
			)
			(layer "F.Fab")
		)
		(fp_poly
			(pts
				(xy -3.4798 -1.359916) (xy -2.86004 -1.050036) (xy -3.4798 -0.740156)
			)
			(stroke
				(width 0)
				(type default)
			)
			(fill yes)
			(layer "F.Fab")
		)
		(pad "1" smd rect
			(at -2.175002 -1.050036 270)
			(size 0.6096 1.1684)
			(layers "F.Cu" "F.Mask" "F.Paste")
			(net "P3V3")
		)
		(pad "2" smd rect
			(at -2.175002 -0.32512 270)
			(size 0.4318 1.1684)
			(layers "F.Cu" "F.Mask" "F.Paste")
			(net "SMB_CLK_ISO_SCL")
		)
		(pad "3" smd rect
			(at -2.175002 0.32512 270)
			(size 0.4318 1.1684)
			(layers "F.Cu" "F.Mask" "F.Paste")
			(net "SMB_CLK_ISO_SDA")
		)
		(pad "4" smd rect
			(at -2.175002 1.050036 270)
			(size 0.6096 1.1684)
			(layers "F.Cu" "F.Mask" "F.Paste")
			(net "GND")
		)
		(pad "5" smd rect
			(at 2.175002 1.050036 270)
			(size 0.6096 1.1684)
			(layers "F.Cu" "F.Mask" "F.Paste")
			(net "CLK_ISO_EN")
		)
		(pad "6" smd rect
			(at 2.175002 0.32512 270)
			(size 0.4318 1.1684)
			(layers "F.Cu" "F.Mask" "F.Paste")
			(net "SMB_BIC_I2C6_MUX_CLK_R_SDA")
		)
		(pad "7" smd rect
			(at 2.175002 -0.32512 270)
			(size 0.4318 1.1684)
			(layers "F.Cu" "F.Mask" "F.Paste")
			(net "SMB_BIC_I2C6_MUX_CLK_R_SCL")
		)
		(pad "8" smd rect
			(at 2.175002 -1.050036 270)
			(size 0.6096 1.1684)
			(layers "F.Cu" "F.Mask" "F.Paste")
			(net "P3V3_AUX")
		)
	)
	(footprint ""
		(layer "F.Cu")
		(at 70.63867 -22.867366 90)
		(property "Reference" "C3892"
			(at 0 0 90)
			(layer "F.SilkS")
			(hide yes)
			(effects
				(font
					(size 1.27 1.27)
				)
			)
		)
		(property "Value" ""
			(at 0 0 90)
			(layer "F.Fab")
			(effects
				(font
					(size 1.27 1.27)
				)
			)
		)
		(duplicate_pad_numbers_are_jumpers no)
		(fp_line
			(start 0.7874 -0.4064)
			(end 0.7874 0.4064)
			(stroke
				(width 0.1524)
				(type default)
			)
			(layer "F.SilkS")
		)
		(fp_line
			(start -0.7874 -0.4064)
			(end 0.7874 -0.4064)
			(stroke
				(width 0.1524)
				(type default)
			)
			(layer "F.SilkS")
		)
		(fp_line
			(start 0.7874 0.4064)
			(end -0.7874 0.4064)
			(stroke
				(width 0.1524)
				(type default)
			)
			(layer "F.SilkS")
		)
		(fp_line
			(start -0.7874 0.4064)
			(end -0.7874 -0.4064)
			(stroke
				(width 0.1524)
				(type default)
			)
			(layer "F.SilkS")
		)
		(fp_line
			(start -0.12065 -0.305054)
			(end -0.12065 -0.2794)
			(stroke
				(width 0.1)
				(type default)
			)
			(layer "F.Fab")
		)
		(fp_line
			(start -0.67945 -0.305054)
			(end -0.12065 -0.305054)
			(stroke
				(width 0.1)
				(type default)
			)
			(layer "F.Fab")
		)
		(fp_line
			(start 0.67945 -0.3048)
			(end 0.67945 0.3048)
			(stroke
				(width 0.1)
				(type default)
			)
			(layer "F.Fab")
		)
		(fp_line
			(start 0.12065 -0.3048)
			(end 0.67945 -0.3048)
			(stroke
				(width 0.1)
				(type default)
			)
			(layer "F.Fab")
		)
		(fp_line
			(start 0.12065 -0.2794)
			(end 0.12065 -0.3048)
			(stroke
				(width 0.1)
				(type default)
			)
			(layer "F.Fab")
		)
		(fp_line
			(start -0.12065 -0.2794)
			(end 0.12065 -0.2794)
			(stroke
				(width 0.1)
				(type default)
			)
			(layer "F.Fab")
		)
		(fp_line
			(start 0.120396 0.2794)
			(end -0.12065 0.2794)
			(stroke
				(width 0.1)
				(type default)
			)
			(layer "F.Fab")
		)
		(fp_line
			(start -0.12065 0.2794)
			(end -0.12065 0.3048)
			(stroke
				(width 0.1)
				(type default)
			)
			(layer "F.Fab")
		)
		(fp_line
			(start 0.67945 0.3048)
			(end 0.120396 0.3048)
			(stroke
				(width 0.1)
				(type default)
			)
			(layer "F.Fab")
		)
		(fp_line
			(start 0.120396 0.3048)
			(end 0.120396 0.2794)
			(stroke
				(width 0.1)
				(type default)
			)
			(layer "F.Fab")
		)
		(fp_line
			(start -0.12065 0.3048)
			(end -0.67945 0.3048)
			(stroke
				(width 0.1)
				(type default)
			)
			(layer "F.Fab")
		)
		(fp_line
			(start -0.67945 0.3048)
			(end -0.67945 -0.305054)
			(stroke
				(width 0.1)
				(type default)
			)
			(layer "F.Fab")
		)
		(pad "1" smd circle
			(at -0.40005 0 90)
			(size 0 0)
			(layers "F.Cu" "F.Mask" "F.Paste")
			(net "P12V_SSD2")
		)
		(pad "2" smd circle
			(at 0.40005 0 90)
			(size 0 0)
			(layers "F.Cu" "F.Mask" "F.Paste")
			(net "GND")
		)
	)
	(footprint ""
		(layer "F.Cu")
		(at 258.778502 -308.611524 45)
		(property "Reference" "R4362"
			(at 0 0 45)
			(layer "F.SilkS")
			(hide yes)
			(effects
				(font
					(size 1.27 1.27)
				)
			)
		)
		(property "Value" ""
			(at 0 0 45)
			(layer "F.Fab")
			(effects
				(font
					(size 1.27 1.27)
				)
			)
		)
		(duplicate_pad_numbers_are_jumpers no)
		(fp_line
			(start -0.787389 -0.406267)
			(end 0.787389 -0.406267)
			(stroke
				(width 0.1524)
				(type default)
			)
			(layer "F.SilkS")
		)
		(fp_line
			(start -0.787389 0.406267)
			(end -0.787389 -0.406267)
			(stroke
				(width 0.1524)
				(type default)
			)
			(layer "F.SilkS")
		)
		(fp_line
			(start 0.787389 -0.406267)
			(end 0.787389 0.406267)
			(stroke
				(width 0.1524)
				(type default)
			)
			(layer "F.SilkS")
		)
		(fp_line
			(start 0.787389 0.406267)
			(end -0.787389 0.406267)
			(stroke
				(width 0.1524)
				(type default)
			)
			(layer "F.SilkS")
		)
		(fp_line
			(start -0.679446 -0.305149)
			(end -0.120695 -0.304969)
			(stroke
				(width 0.1)
				(type default)
			)
			(layer "F.Fab")
		)
		(fp_line
			(start -0.120695 -0.304969)
			(end -0.120695 -0.279466)
			(stroke
				(width 0.1)
				(type default)
			)
			(layer "F.Fab")
		)
		(fp_line
			(start -0.120695 -0.279466)
			(end 0.120695 -0.279466)
			(stroke
				(width 0.1)
				(type default)
			)
			(layer "F.Fab")
		)
		(fp_line
			(start -0.679446 0.30479)
			(end -0.679446 -0.305149)
			(stroke
				(width 0.1)
				(type default)
			)
			(layer "F.Fab")
		)
		(fp_line
			(start 0.120515 -0.30479)
			(end 0.679446 -0.30479)
			(stroke
				(width 0.1)
				(type default)
			)
			(layer "F.Fab")
		)
		(fp_line
			(start 0.120695 -0.279466)
			(end 0.120515 -0.30479)
			(stroke
				(width 0.1)
				(type default)
			)
			(layer "F.Fab")
		)
		(fp_line
			(start -0.120695 0.279466)
			(end -0.120515 0.30479)
			(stroke
				(width 0.1)
				(type default)
			)
			(layer "F.Fab")
		)
		(fp_line
			(start -0.120515 0.30479)
			(end -0.679446 0.30479)
			(stroke
				(width 0.1)
				(type default)
			)
			(layer "F.Fab")
		)
		(fp_line
			(start 0.679446 -0.30479)
			(end 0.679446 0.30479)
			(stroke
				(width 0.1)
				(type default)
			)
			(layer "F.Fab")
		)
		(fp_line
			(start 0.120335 0.279466)
			(end -0.120695 0.279466)
			(stroke
				(width 0.1)
				(type default)
			)
			(layer "F.Fab")
		)
		(fp_line
			(start 0.120515 0.30479)
			(end 0.120335 0.279466)
			(stroke
				(width 0.1)
				(type default)
			)
			(layer "F.Fab")
		)
		(fp_line
			(start 0.679446 0.30479)
			(end 0.120515 0.30479)
			(stroke
				(width 0.1)
				(type default)
			)
			(layer "F.Fab")
		)
		(pad "1" smd circle
			(at -0.40005 0 45)
			(size 0 0)
			(layers "F.Cu" "F.Mask" "F.Paste")
			(net "P1V8_PEX")
		)
		(pad "2" smd circle
			(at 0.40005 0 45)
			(size 0 0)
			(layers "F.Cu" "F.Mask" "F.Paste")
			(net "IRQ_PEX2_CLKREQ_INT_N")
		)
	)
	(footprint ""
		(layer "F.Cu")
		(at 376.305572 -258.511548 -90)
		(property "Reference" "C3596"
			(at 0 0 270)
			(layer "F.SilkS")
			(hide yes)
			(effects
				(font
					(size 1.27 1.27)
				)
			)
		)
		(property "Value" ""
			(at 0 0 270)
			(layer "F.Fab")
			(effects
				(font
					(size 1.27 1.27)
				)
			)
		)
		(duplicate_pad_numbers_are_jumpers no)
		(fp_line
			(start -1.2954 0.5842)
			(end -1.2954 -0.5842)
			(stroke
				(width 0.1524)
				(type default)
			)
			(layer "F.SilkS")
		)
		(fp_line
			(start 1.2954 0.5842)
			(end -1.2954 0.5842)
			(stroke
				(width 0.1524)
				(type default)
			)
			(layer "F.SilkS")
		)
		(fp_line
			(start -1.2954 -0.5842)
			(end 1.2954 -0.5842)
			(stroke
				(width 0.1524)
				(type default)
			)
			(layer "F.SilkS")
		)
		(fp_line
			(start 1.2954 -0.5842)
			(end 1.2954 0.5842)
			(stroke
				(width 0.1524)
				(type default)
			)
			(layer "F.SilkS")
		)
		(fp_line
			(start -0.8636 0.4572)
			(end -0.8636 0.4064)
			(stroke
				(width 0.1)
				(type default)
			)
			(layer "F.Fab")
		)
		(fp_line
			(start 0.8636 0.4572)
			(end -0.8636 0.4572)
			(stroke
				(width 0.1)
				(type default)
			)
			(layer "F.Fab")
		)
		(fp_line
			(start -1.1938 0.4064)
			(end -1.1938 -0.4064)
			(stroke
				(width 0.1)
				(type default)
			)
			(layer "F.Fab")
		)
		(fp_line
			(start -0.8636 0.4064)
			(end -1.1938 0.4064)
			(stroke
				(width 0.1)
				(type default)
			)
			(layer "F.Fab")
		)
		(fp_line
			(start 0.8636 0.4064)
			(end 0.8636 0.4572)
			(stroke
				(width 0.1)
				(type default)
			)
			(layer "F.Fab")
		)
		(fp_line
			(start 1.1938 0.4064)
			(end 0.8636 0.4064)
			(stroke
				(width 0.1)
				(type default)
			)
			(layer "F.Fab")
		)
		(fp_line
			(start -1.1938 -0.4064)
			(end -0.8636 -0.4064)
			(stroke
				(width 0.1)
				(type default)
			)
			(layer "F.Fab")
		)
		(fp_line
			(start -0.8636 -0.4064)
			(end -0.8636 -0.4572)
			(stroke
				(width 0.1)
				(type default)
			)
			(layer "F.Fab")
		)
		(fp_line
			(start 0.8636 -0.4064)
			(end 1.1938 -0.4064)
			(stroke
				(width 0.1)
				(type default)
			)
			(layer "F.Fab")
		)
		(fp_line
			(start 1.1938 -0.4064)
			(end 1.1938 0.4064)
			(stroke
				(width 0.1)
				(type default)
			)
			(layer "F.Fab")
		)
		(fp_line
			(start -0.8636 -0.4572)
			(end 0.8636 -0.4572)
			(stroke
				(width 0.1)
				(type default)
			)
			(layer "F.Fab")
		)
		(fp_line
			(start 0.8636 -0.4572)
			(end 0.8636 -0.4064)
			(stroke
				(width 0.1)
				(type default)
			)
			(layer "F.Fab")
		)
		(pad "1" smd rect
			(at -0.7366 0 180)
			(size 0.7112 0.8128)
			(layers "F.Cu" "F.Mask" "F.Paste")
			(net "P1V8_VDDA_PEX3_R")
		)
		(pad "2" smd rect
			(at 0.7366 0 180)
			(size 0.7112 0.8128)
			(layers "F.Cu" "F.Mask" "F.Paste")
			(net "GND")
		)
	)
	(footprint ""
		(layer "F.Cu")
		(at 229.48265 -309.555642)
		(property "Reference" "PC240"
			(at 0 0 0)
			(layer "F.SilkS")
			(hide yes)
			(effects
				(font
					(size 1.27 1.27)
				)
			)
		)
		(property "Value" ""
			(at 0 0 0)
			(layer "F.Fab")
			(effects
				(font
					(size 1.27 1.27)
				)
			)
		)
		(duplicate_pad_numbers_are_jumpers no)
		(fp_line
			(start -0.7874 -0.4064)
			(end 0.7874 -0.4064)
			(stroke
				(width 0.1524)
				(type default)
			)
			(layer "F.SilkS")
		)
		(fp_line
			(start -0.7874 0.4064)
			(end -0.7874 -0.4064)
			(stroke
				(width 0.1524)
				(type default)
			)
			(layer "F.SilkS")
		)
		(fp_line
			(start 0.7874 -0.4064)
			(end 0.7874 0.4064)
			(stroke
				(width 0.1524)
				(type default)
			)
			(layer "F.SilkS")
		)
		(fp_line
			(start 0.7874 0.4064)
			(end -0.7874 0.4064)
			(stroke
				(width 0.1524)
				(type default)
			)
			(layer "F.SilkS")
		)
		(fp_line
			(start -0.67945 -0.305054)
			(end -0.12065 -0.305054)
			(stroke
				(width 0.1)
				(type default)
			)
			(layer "F.Fab")
		)
		(fp_line
			(start -0.67945 0.3048)
			(end -0.67945 -0.305054)
			(stroke
				(width 0.1)
				(type default)
			)
			(layer "F.Fab")
		)
		(fp_line
			(start -0.12065 -0.305054)
			(end -0.12065 -0.2794)
			(stroke
				(width 0.1)
				(type default)
			)
			(layer "F.Fab")
		)
		(fp_line
			(start -0.12065 -0.2794)
			(end 0.12065 -0.2794)
			(stroke
				(width 0.1)
				(type default)
			)
			(layer "F.Fab")
		)
		(fp_line
			(start -0.12065 0.2794)
			(end -0.12065 0.3048)
			(stroke
				(width 0.1)
				(type default)
			)
			(layer "F.Fab")
		)
		(fp_line
			(start -0.12065 0.3048)
			(end -0.67945 0.3048)
			(stroke
				(width 0.1)
				(type default)
			)
			(layer "F.Fab")
		)
		(fp_line
			(start 0.120396 0.2794)
			(end -0.12065 0.2794)
			(stroke
				(width 0.1)
				(type default)
			)
			(layer "F.Fab")
		)
		(fp_line
			(start 0.120396 0.3048)
			(end 0.120396 0.2794)
			(stroke
				(width 0.1)
				(type default)
			)
			(layer "F.Fab")
		)
		(fp_line
			(start 0.12065 -0.3048)
			(end 0.67945 -0.3048)
			(stroke
				(width 0.1)
				(type default)
			)
			(layer "F.Fab")
		)
		(fp_line
			(start 0.12065 -0.2794)
			(end 0.12065 -0.3048)
			(stroke
				(width 0.1)
				(type default)
			)
			(layer "F.Fab")
		)
		(fp_line
			(start 0.67945 -0.3048)
			(end 0.67945 0.3048)
			(stroke
				(width 0.1)
				(type default)
			)
			(layer "F.Fab")
		)
		(fp_line
			(start 0.67945 0.3048)
			(end 0.120396 0.3048)
			(stroke
				(width 0.1)
				(type default)
			)
			(layer "F.Fab")
		)
		(pad "1" smd circle
			(at -0.40005 0)
			(size 0 0)
			(layers "F.Cu" "F.Mask" "F.Paste")
			(net "P1V25_PEX1_FB")
		)
		(pad "2" smd circle
			(at 0.40005 0)
			(size 0 0)
			(layers "F.Cu" "F.Mask" "F.Paste")
			(net "SH_P1V25_PEX1_FB_P")
		)
	)
	(footprint ""
		(layer "F.Cu")
		(at 361.944158 -380.63043)
		(property "Reference" "R6710"
			(at 0 0 0)
			(layer "F.SilkS")
			(hide yes)
			(effects
				(font
					(size 1.27 1.27)
				)
			)
		)
		(property "Value" ""
			(at 0 0 0)
			(layer "F.Fab")
			(effects
				(font
					(size 1.27 1.27)
				)
			)
		)
		(duplicate_pad_numbers_are_jumpers no)
		(fp_line
			(start -0.7874 -0.4064)
			(end 0.7874 -0.4064)
			(stroke
				(width 0.1524)
				(type default)
			)
			(layer "F.SilkS")
		)
		(fp_line
			(start -0.7874 0.4064)
			(end -0.7874 -0.4064)
			(stroke
				(width 0.1524)
				(type default)
			)
			(layer "F.SilkS")
		)
		(fp_line
			(start 0.7874 -0.4064)
			(end 0.7874 0.4064)
			(stroke
				(width 0.1524)
				(type default)
			)
			(layer "F.SilkS")
		)
		(fp_line
			(start 0.7874 0.4064)
			(end -0.7874 0.4064)
			(stroke
				(width 0.1524)
				(type default)
			)
			(layer "F.SilkS")
		)
		(fp_line
			(start -0.67945 -0.305054)
			(end -0.12065 -0.305054)
			(stroke
				(width 0.1)
				(type default)
			)
			(layer "F.Fab")
		)
		(fp_line
			(start -0.67945 0.3048)
			(end -0.67945 -0.305054)
			(stroke
				(width 0.1)
				(type default)
			)
			(layer "F.Fab")
		)
		(fp_line
			(start -0.12065 -0.305054)
			(end -0.12065 -0.2794)
			(stroke
				(width 0.1)
				(type default)
			)
			(layer "F.Fab")
		)
		(fp_line
			(start -0.12065 -0.2794)
			(end 0.12065 -0.2794)
			(stroke
				(width 0.1)
				(type default)
			)
			(layer "F.Fab")
		)
		(fp_line
			(start -0.12065 0.2794)
			(end -0.12065 0.3048)
			(stroke
				(width 0.1)
				(type default)
			)
			(layer "F.Fab")
		)
		(fp_line
			(start -0.12065 0.3048)
			(end -0.67945 0.3048)
			(stroke
				(width 0.1)
				(type default)
			)
			(layer "F.Fab")
		)
		(fp_line
			(start 0.120396 0.2794)
			(end -0.12065 0.2794)
			(stroke
				(width 0.1)
				(type default)
			)
			(layer "F.Fab")
		)
		(fp_line
			(start 0.120396 0.3048)
			(end 0.120396 0.2794)
			(stroke
				(width 0.1)
				(type default)
			)
			(layer "F.Fab")
		)
		(fp_line
			(start 0.12065 -0.3048)
			(end 0.67945 -0.3048)
			(stroke
				(width 0.1)
				(type default)
			)
			(layer "F.Fab")
		)
		(fp_line
			(start 0.12065 -0.2794)
			(end 0.12065 -0.3048)
			(stroke
				(width 0.1)
				(type default)
			)
			(layer "F.Fab")
		)
		(fp_line
			(start 0.67945 -0.3048)
			(end 0.67945 0.3048)
			(stroke
				(width 0.1)
				(type default)
			)
			(layer "F.Fab")
		)
		(fp_line
			(start 0.67945 0.3048)
			(end 0.120396 0.3048)
			(stroke
				(width 0.1)
				(type default)
			)
			(layer "F.Fab")
		)
		(pad "1" smd circle
			(at -0.40005 0)
			(size 0 0)
			(layers "F.Cu" "F.Mask" "F.Paste")
			(net "MB_3V3IO_RSVD4_ISO_R")
		)
		(pad "2" smd circle
			(at 0.40005 0)
			(size 0 0)
			(layers "F.Cu" "F.Mask" "F.Paste")
			(net "MB_3V3IO_RSVD4_ISO")
		)
	)
	(footprint ""
		(layer "F.Cu")
		(at 452.543672 -48.93691 180)
		(property "Reference" "R677"
			(at 0 0 180)
			(layer "F.SilkS")
			(hide yes)
			(effects
				(font
					(size 1.27 1.27)
				)
			)
		)
		(property "Value" ""
			(at 0 0 180)
			(layer "F.Fab")
			(effects
				(font
					(size 1.27 1.27)
				)
			)
		)
		(duplicate_pad_numbers_are_jumpers no)
		(fp_line
			(start 0.7874 0.4064)
			(end -0.7874 0.4064)
			(stroke
				(width 0.1524)
				(type default)
			)
			(layer "F.SilkS")
		)
		(fp_line
			(start 0.7874 -0.4064)
			(end 0.7874 0.4064)
			(stroke
				(width 0.1524)
				(type default)
			)
			(layer "F.SilkS")
		)
		(fp_line
			(start -0.7874 0.4064)
			(end -0.7874 -0.4064)
			(stroke
				(width 0.1524)
				(type default)
			)
			(layer "F.SilkS")
		)
		(fp_line
			(start -0.7874 -0.4064)
			(end 0.7874 -0.4064)
			(stroke
				(width 0.1524)
				(type default)
			)
			(layer "F.SilkS")
		)
		(fp_line
			(start 0.67945 0.3048)
			(end 0.120396 0.3048)
			(stroke
				(width 0.1)
				(type default)
			)
			(layer "F.Fab")
		)
		(fp_line
			(start 0.67945 -0.3048)
			(end 0.67945 0.3048)
			(stroke
				(width 0.1)
				(type default)
			)
			(layer "F.Fab")
		)
		(fp_line
			(start 0.12065 -0.2794)
			(end 0.12065 -0.3048)
			(stroke
				(width 0.1)
				(type default)
			)
			(layer "F.Fab")
		)
		(fp_line
			(start 0.12065 -0.3048)
			(end 0.67945 -0.3048)
			(stroke
				(width 0.1)
				(type default)
			)
			(layer "F.Fab")
		)
		(fp_line
			(start 0.120396 0.3048)
			(end 0.120396 0.2794)
			(stroke
				(width 0.1)
				(type default)
			)
			(layer "F.Fab")
		)
		(fp_line
			(start 0.120396 0.2794)
			(end -0.12065 0.2794)
			(stroke
				(width 0.1)
				(type default)
			)
			(layer "F.Fab")
		)
		(fp_line
			(start -0.12065 0.3048)
			(end -0.67945 0.3048)
			(stroke
				(width 0.1)
				(type default)
			)
			(layer "F.Fab")
		)
		(fp_line
			(start -0.12065 0.2794)
			(end -0.12065 0.3048)
			(stroke
				(width 0.1)
				(type default)
			)
			(layer "F.Fab")
		)
		(fp_line
			(start -0.12065 -0.2794)
			(end 0.12065 -0.2794)
			(stroke
				(width 0.1)
				(type default)
			)
			(layer "F.Fab")
		)
		(fp_line
			(start -0.12065 -0.305054)
			(end -0.12065 -0.2794)
			(stroke
				(width 0.1)
				(type default)
			)
			(layer "F.Fab")
		)
		(fp_line
			(start -0.67945 0.3048)
			(end -0.67945 -0.305054)
			(stroke
				(width 0.1)
				(type default)
			)
			(layer "F.Fab")
		)
		(fp_line
			(start -0.67945 -0.305054)
			(end -0.12065 -0.305054)
			(stroke
				(width 0.1)
				(type default)
			)
			(layer "F.Fab")
		)
		(pad "1" smd circle
			(at -0.40005 0 180)
			(size 0 0)
			(layers "F.Cu" "F.Mask" "F.Paste")
			(net "SMB_BIC_I2C6_MUX_SSD_8_15_ADC_R_SDA")
		)
		(pad "2" smd circle
			(at 0.40005 0 180)
			(size 0 0)
			(layers "F.Cu" "F.Mask" "F.Paste")
			(net "SMB_SSD15_ADC_SDA")
		)
	)
	(footprint ""
		(layer "F.Cu")
		(at 160.047178 -55.63489 90)
		(property "Reference" "PC371"
			(at 0 0 90)
			(layer "F.SilkS")
			(hide yes)
			(effects
				(font
					(size 1.27 1.27)
				)
			)
		)
		(property "Value" ""
			(at 0 0 90)
			(layer "F.Fab")
			(effects
				(font
					(size 1.27 1.27)
				)
			)
		)
		(duplicate_pad_numbers_are_jumpers no)
		(fp_line
			(start 1.524 -0.762)
			(end 1.524 0.762)
			(stroke
				(width 0.1524)
				(type default)
			)
			(layer "F.SilkS")
		)
		(fp_line
			(start -1.524 -0.762)
			(end 1.524 -0.762)
			(stroke
				(width 0.1524)
				(type default)
			)
			(layer "F.SilkS")
		)
		(fp_line
			(start 1.524 0.762)
			(end -1.524 0.762)
			(stroke
				(width 0.1524)
				(type default)
			)
			(layer "F.SilkS")
		)
		(fp_line
			(start -1.524 0.762)
			(end -1.524 -0.762)
			(stroke
				(width 0.1524)
				(type default)
			)
			(layer "F.SilkS")
		)
		(fp_line
			(start 1.1049 -0.724916)
			(end -1.1049 -0.724916)
			(stroke
				(width 0.1)
				(type default)
			)
			(layer "F.Fab")
		)
		(fp_line
			(start -1.1049 -0.724916)
			(end -1.1049 0.724916)
			(stroke
				(width 0.1)
				(type default)
			)
			(layer "F.Fab")
		)
		(fp_line
			(start 1.1049 0.724916)
			(end 1.1049 -0.724916)
			(stroke
				(width 0.1)
				(type default)
			)
			(layer "F.Fab")
		)
		(fp_line
			(start -1.1049 0.724916)
			(end 1.1049 0.724916)
			(stroke
				(width 0.1)
				(type default)
			)
			(layer "F.Fab")
		)
		(pad "1" smd rect
			(at -0.889 0 270)
			(size 1.016 1.27)
			(layers "F.Cu" "F.Mask" "F.Paste")
			(net "P12V_SSD5_R")
		)
		(pad "2" smd rect
			(at 0.889 0 270)
			(size 1.016 1.27)
			(layers "F.Cu" "F.Mask" "F.Paste")
			(net "GND")
		)
	)
	(footprint ""
		(layer "F.Cu")
		(at 340.458044 -343.952322 90)
		(property "Reference" "C523"
			(at 0 0 90)
			(layer "F.SilkS")
			(hide yes)
			(effects
				(font
					(size 1.27 1.27)
				)
			)
		)
		(property "Value" ""
			(at 0 0 90)
			(layer "F.Fab")
			(effects
				(font
					(size 1.27 1.27)
				)
			)
		)
		(duplicate_pad_numbers_are_jumpers no)
		(fp_line
			(start 0.299974 -0.150114)
			(end 0.299974 0.150114)
			(stroke
				(width 0.1)
				(type default)
			)
			(layer "F.Fab")
		)
		(fp_line
			(start -0.299974 -0.150114)
			(end 0.299974 -0.150114)
			(stroke
				(width 0.1)
				(type default)
			)
			(layer "F.Fab")
		)
		(fp_line
			(start 0.299974 0.150114)
			(end -0.299974 0.150114)
			(stroke
				(width 0.1)
				(type default)
			)
			(layer "F.Fab")
		)
		(fp_line
			(start -0.299974 0.150114)
			(end -0.299974 -0.150114)
			(stroke
				(width 0.1)
				(type default)
			)
			(layer "F.Fab")
		)
		(pad "1" smd rect
			(at -0.2667 0 90)
			(size 0.3048 0.381)
			(layers "F.Cu" "F.Mask" "F.Paste")
			(net "P5E_PEX2_STN5_TX_DP<93>")
		)
		(pad "2" smd rect
			(at 0.2667 0 90)
			(size 0.3048 0.381)
			(layers "F.Cu" "F.Mask" "F.Paste")
			(net "P5E_PEX2_STN5_TX_C_DP<93>")
		)
	)
	(footprint ""
		(layer "F.Cu")
		(at 338.83854 -80.607662 90)
		(property "Reference" "R1174"
			(at 0 0 90)
			(layer "F.SilkS")
			(hide yes)
			(effects
				(font
					(size 1.27 1.27)
				)
			)
		)
		(property "Value" ""
			(at 0 0 90)
			(layer "F.Fab")
			(effects
				(font
					(size 1.27 1.27)
				)
			)
		)
		(duplicate_pad_numbers_are_jumpers no)
		(fp_line
			(start -0.7874 -0.4064)
			(end 0.7874 -0.4064)
			(stroke
				(width 0.1524)
				(type default)
			)
			(layer "F.SilkS")
		)
		(fp_line
			(start -0.12065 -0.305054)
			(end -0.12065 -0.2794)
			(stroke
				(width 0.1)
				(type default)
			)
			(layer "F.Fab")
		)
		(fp_line
			(start -0.67945 -0.305054)
			(end -0.12065 -0.305054)
			(stroke
				(width 0.1)
				(type default)
			)
			(layer "F.Fab")
		)
		(fp_line
			(start 0.67945 -0.3048)
			(end 0.67945 0.3048)
			(stroke
				(width 0.1)
				(type default)
			)
			(layer "F.Fab")
		)
		(fp_line
			(start 0.12065 -0.3048)
			(end 0.67945 -0.3048)
			(stroke
				(width 0.1)
				(type default)
			)
			(layer "F.Fab")
		)
		(fp_line
			(start 0.12065 -0.2794)
			(end 0.12065 -0.3048)
			(stroke
				(width 0.1)
				(type default)
			)
			(layer "F.Fab")
		)
		(fp_line
			(start -0.12065 -0.2794)
			(end 0.12065 -0.2794)
			(stroke
				(width 0.1)
				(type default)
			)
			(layer "F.Fab")
		)
		(fp_line
			(start 0.120396 0.2794)
			(end -0.12065 0.2794)
			(stroke
				(width 0.1)
				(type default)
			)
			(layer "F.Fab")
		)
		(fp_line
			(start -0.12065 0.2794)
			(end -0.12065 0.3048)
			(stroke
				(width 0.1)
				(type default)
			)
			(layer "F.Fab")
		)
		(fp_line
			(start 0.67945 0.3048)
			(end 0.120396 0.3048)
			(stroke
				(width 0.1)
				(type default)
			)
			(layer "F.Fab")
		)
		(fp_line
			(start 0.120396 0.3048)
			(end 0.120396 0.2794)
			(stroke
				(width 0.1)
				(type default)
			)
			(layer "F.Fab")
		)
		(fp_line
			(start -0.12065 0.3048)
			(end -0.67945 0.3048)
			(stroke
				(width 0.1)
				(type default)
			)
			(layer "F.Fab")
		)
		(fp_line
			(start -0.67945 0.3048)
			(end -0.67945 -0.305054)
			(stroke
				(width 0.1)
				(type default)
			)
			(layer "F.Fab")
		)
		(pad "1" smd circle
			(at -0.40005 0 90)
			(size 0 0)
			(layers "F.Cu" "F.Mask" "F.Paste")
			(net "CLK_100M_DB800ZL_SSD10_R_DP")
		)
		(pad "2" smd circle
			(at 0.40005 0 90)
			(size 0 0)
			(layers "F.Cu" "F.Mask" "F.Paste")
			(net "CLK_100M_DB800ZL_SSD10_DP")
		)
	)
	(footprint ""
		(layer "F.Cu")
		(at 336.042 -185.039 180)
		(property "Reference" "R4745"
			(at 0 0 180)
			(layer "F.SilkS")
			(hide yes)
			(effects
				(font
					(size 1.27 1.27)
				)
			)
		)
		(property "Value" ""
			(at 0 0 180)
			(layer "F.Fab")
			(effects
				(font
					(size 1.27 1.27)
				)
			)
		)
		(duplicate_pad_numbers_are_jumpers no)
		(fp_line
			(start 0.7874 0.4064)
			(end -0.7874 0.4064)
			(stroke
				(width 0.1524)
				(type default)
			)
			(layer "F.SilkS")
		)
		(fp_line
			(start 0.7874 -0.4064)
			(end 0.7874 0.4064)
			(stroke
				(width 0.1524)
				(type default)
			)
			(layer "F.SilkS")
		)
		(fp_line
			(start -0.7874 0.4064)
			(end -0.7874 -0.4064)
			(stroke
				(width 0.1524)
				(type default)
			)
			(layer "F.SilkS")
		)
		(fp_line
			(start -0.7874 -0.4064)
			(end 0.7874 -0.4064)
			(stroke
				(width 0.1524)
				(type default)
			)
			(layer "F.SilkS")
		)
		(fp_line
			(start 0.67945 0.3048)
			(end 0.120396 0.3048)
			(stroke
				(width 0.1)
				(type default)
			)
			(layer "F.Fab")
		)
		(fp_line
			(start 0.67945 -0.3048)
			(end 0.67945 0.3048)
			(stroke
				(width 0.1)
				(type default)
			)
			(layer "F.Fab")
		)
		(fp_line
			(start 0.12065 -0.2794)
			(end 0.12065 -0.3048)
			(stroke
				(width 0.1)
				(type default)
			)
			(layer "F.Fab")
		)
		(fp_line
			(start 0.12065 -0.3048)
			(end 0.67945 -0.3048)
			(stroke
				(width 0.1)
				(type default)
			)
			(layer "F.Fab")
		)
		(fp_line
			(start 0.120396 0.3048)
			(end 0.120396 0.2794)
			(stroke
				(width 0.1)
				(type default)
			)
			(layer "F.Fab")
		)
		(fp_line
			(start 0.120396 0.2794)
			(end -0.12065 0.2794)
			(stroke
				(width 0.1)
				(type default)
			)
			(layer "F.Fab")
		)
		(fp_line
			(start -0.12065 0.3048)
			(end -0.67945 0.3048)
			(stroke
				(width 0.1)
				(type default)
			)
			(layer "F.Fab")
		)
		(fp_line
			(start -0.12065 0.2794)
			(end -0.12065 0.3048)
			(stroke
				(width 0.1)
				(type default)
			)
			(layer "F.Fab")
		)
		(fp_line
			(start -0.12065 -0.2794)
			(end 0.12065 -0.2794)
			(stroke
				(width 0.1)
				(type default)
			)
			(layer "F.Fab")
		)
		(fp_line
			(start -0.12065 -0.305054)
			(end -0.12065 -0.2794)
			(stroke
				(width 0.1)
				(type default)
			)
			(layer "F.Fab")
		)
		(fp_line
			(start -0.67945 0.3048)
			(end -0.67945 -0.305054)
			(stroke
				(width 0.1)
				(type default)
			)
			(layer "F.Fab")
		)
		(fp_line
			(start -0.67945 -0.305054)
			(end -0.12065 -0.305054)
			(stroke
				(width 0.1)
				(type default)
			)
			(layer "F.Fab")
		)
		(pad "1" smd circle
			(at -0.40005 0 180)
			(size 0 0)
			(layers "F.Cu" "F.Mask" "F.Paste")
			(net "PCA9555_0_PEX2_A1")
		)
		(pad "2" smd circle
			(at 0.40005 0 180)
			(size 0 0)
			(layers "F.Cu" "F.Mask" "F.Paste")
			(net "P3V3_AUX")
		)
	)
	(footprint ""
		(layer "F.Cu")
		(at 166.330884 -197.900798)
		(property "Reference" "R3407"
			(at 0 0 0)
			(layer "F.SilkS")
			(hide yes)
			(effects
				(font
					(size 1.27 1.27)
				)
			)
		)
		(property "Value" ""
			(at 0 0 0)
			(layer "F.Fab")
			(effects
				(font
					(size 1.27 1.27)
				)
			)
		)
		(duplicate_pad_numbers_are_jumpers no)
		(fp_line
			(start -0.7874 -0.4064)
			(end 0.7874 -0.4064)
			(stroke
				(width 0.1524)
				(type default)
			)
			(layer "F.SilkS")
		)
		(fp_line
			(start -0.7874 0.4064)
			(end -0.7874 -0.4064)
			(stroke
				(width 0.1524)
				(type default)
			)
			(layer "F.SilkS")
		)
		(fp_line
			(start 0.7874 -0.4064)
			(end 0.7874 0.4064)
			(stroke
				(width 0.1524)
				(type default)
			)
			(layer "F.SilkS")
		)
		(fp_line
			(start 0.7874 0.4064)
			(end -0.7874 0.4064)
			(stroke
				(width 0.1524)
				(type default)
			)
			(layer "F.SilkS")
		)
		(fp_line
			(start -0.67945 -0.305054)
			(end -0.12065 -0.305054)
			(stroke
				(width 0.1)
				(type default)
			)
			(layer "F.Fab")
		)
		(fp_line
			(start -0.67945 0.3048)
			(end -0.67945 -0.305054)
			(stroke
				(width 0.1)
				(type default)
			)
			(layer "F.Fab")
		)
		(fp_line
			(start -0.12065 -0.305054)
			(end -0.12065 -0.2794)
			(stroke
				(width 0.1)
				(type default)
			)
			(layer "F.Fab")
		)
		(fp_line
			(start -0.12065 -0.2794)
			(end 0.12065 -0.2794)
			(stroke
				(width 0.1)
				(type default)
			)
			(layer "F.Fab")
		)
		(fp_line
			(start -0.12065 0.2794)
			(end -0.12065 0.3048)
			(stroke
				(width 0.1)
				(type default)
			)
			(layer "F.Fab")
		)
		(fp_line
			(start -0.12065 0.3048)
			(end -0.67945 0.3048)
			(stroke
				(width 0.1)
				(type default)
			)
			(layer "F.Fab")
		)
		(fp_line
			(start 0.120396 0.2794)
			(end -0.12065 0.2794)
			(stroke
				(width 0.1)
				(type default)
			)
			(layer "F.Fab")
		)
		(fp_line
			(start 0.120396 0.3048)
			(end 0.120396 0.2794)
			(stroke
				(width 0.1)
				(type default)
			)
			(layer "F.Fab")
		)
		(fp_line
			(start 0.12065 -0.3048)
			(end 0.67945 -0.3048)
			(stroke
				(width 0.1)
				(type default)
			)
			(layer "F.Fab")
		)
		(fp_line
			(start 0.12065 -0.2794)
			(end 0.12065 -0.3048)
			(stroke
				(width 0.1)
				(type default)
			)
			(layer "F.Fab")
		)
		(fp_line
			(start 0.67945 -0.3048)
			(end 0.67945 0.3048)
			(stroke
				(width 0.1)
				(type default)
			)
			(layer "F.Fab")
		)
		(fp_line
			(start 0.67945 0.3048)
			(end 0.120396 0.3048)
			(stroke
				(width 0.1)
				(type default)
			)
			(layer "F.Fab")
		)
		(pad "1" smd circle
			(at -0.40005 0)
			(size 0 0)
			(layers "F.Cu" "F.Mask" "F.Paste")
			(net "SPI_BIC1_CLK_LS01_R2")
		)
		(pad "2" smd circle
			(at 0.40005 0)
			(size 0 0)
			(layers "F.Cu" "F.Mask" "F.Paste")
			(net "SPI_BIC1_CLK_LS01_R")
		)
	)
	(footprint ""
		(layer "F.Cu")
		(at 241.600736 -203.005182)
		(property "Reference" "R6150"
			(at 0 0 0)
			(layer "F.SilkS")
			(hide yes)
			(effects
				(font
					(size 1.27 1.27)
				)
			)
		)
		(property "Value" ""
			(at 0 0 0)
			(layer "F.Fab")
			(effects
				(font
					(size 1.27 1.27)
				)
			)
		)
		(duplicate_pad_numbers_are_jumpers no)
		(fp_line
			(start -0.7874 -0.4064)
			(end 0.7874 -0.4064)
			(stroke
				(width 0.1524)
				(type default)
			)
			(layer "F.SilkS")
		)
		(fp_line
			(start -0.7874 0.4064)
			(end -0.7874 -0.4064)
			(stroke
				(width 0.1524)
				(type default)
			)
			(layer "F.SilkS")
		)
		(fp_line
			(start 0.7874 -0.4064)
			(end 0.7874 0.4064)
			(stroke
				(width 0.1524)
				(type default)
			)
			(layer "F.SilkS")
		)
		(fp_line
			(start 0.7874 0.4064)
			(end -0.7874 0.4064)
			(stroke
				(width 0.1524)
				(type default)
			)
			(layer "F.SilkS")
		)
		(fp_line
			(start -0.67945 -0.305054)
			(end -0.12065 -0.305054)
			(stroke
				(width 0.1)
				(type default)
			)
			(layer "F.Fab")
		)
		(fp_line
			(start -0.67945 0.3048)
			(end -0.67945 -0.305054)
			(stroke
				(width 0.1)
				(type default)
			)
			(layer "F.Fab")
		)
		(fp_line
			(start -0.12065 -0.305054)
			(end -0.12065 -0.2794)
			(stroke
				(width 0.1)
				(type default)
			)
			(layer "F.Fab")
		)
		(fp_line
			(start -0.12065 -0.2794)
			(end 0.12065 -0.2794)
			(stroke
				(width 0.1)
				(type default)
			)
			(layer "F.Fab")
		)
		(fp_line
			(start -0.12065 0.2794)
			(end -0.12065 0.3048)
			(stroke
				(width 0.1)
				(type default)
			)
			(layer "F.Fab")
		)
		(fp_line
			(start -0.12065 0.3048)
			(end -0.67945 0.3048)
			(stroke
				(width 0.1)
				(type default)
			)
			(layer "F.Fab")
		)
		(fp_line
			(start 0.120396 0.2794)
			(end -0.12065 0.2794)
			(stroke
				(width 0.1)
				(type default)
			)
			(layer "F.Fab")
		)
		(fp_line
			(start 0.120396 0.3048)
			(end 0.120396 0.2794)
			(stroke
				(width 0.1)
				(type default)
			)
			(layer "F.Fab")
		)
		(fp_line
			(start 0.12065 -0.3048)
			(end 0.67945 -0.3048)
			(stroke
				(width 0.1)
				(type default)
			)
			(layer "F.Fab")
		)
		(fp_line
			(start 0.12065 -0.2794)
			(end 0.12065 -0.3048)
			(stroke
				(width 0.1)
				(type default)
			)
			(layer "F.Fab")
		)
		(fp_line
			(start 0.67945 -0.3048)
			(end 0.67945 0.3048)
			(stroke
				(width 0.1)
				(type default)
			)
			(layer "F.Fab")
		)
		(fp_line
			(start 0.67945 0.3048)
			(end 0.120396 0.3048)
			(stroke
				(width 0.1)
				(type default)
			)
			(layer "F.Fab")
		)
		(pad "1" smd circle
			(at -0.40005 0)
			(size 0 0)
			(layers "F.Cu" "F.Mask" "F.Paste")
			(net "BIC_FWSPIDQ3")
		)
		(pad "2" smd circle
			(at 0.40005 0)
			(size 0 0)
			(layers "F.Cu" "F.Mask" "F.Paste")
			(net "P3V3_AUX")
		)
	)
	(footprint ""
		(layer "F.Cu")
		(at 452.543672 -46.90491)
		(property "Reference" "R674"
			(at 0 0 0)
			(layer "F.SilkS")
			(hide yes)
			(effects
				(font
					(size 1.27 1.27)
				)
			)
		)
		(property "Value" ""
			(at 0 0 0)
			(layer "F.Fab")
			(effects
				(font
					(size 1.27 1.27)
				)
			)
		)
		(duplicate_pad_numbers_are_jumpers no)
		(fp_line
			(start -0.7874 -0.4064)
			(end 0.7874 -0.4064)
			(stroke
				(width 0.1524)
				(type default)
			)
			(layer "F.SilkS")
		)
		(fp_line
			(start -0.7874 0.4064)
			(end -0.7874 -0.4064)
			(stroke
				(width 0.1524)
				(type default)
			)
			(layer "F.SilkS")
		)
		(fp_line
			(start 0.7874 -0.4064)
			(end 0.7874 0.4064)
			(stroke
				(width 0.1524)
				(type default)
			)
			(layer "F.SilkS")
		)
		(fp_line
			(start 0.7874 0.4064)
			(end -0.7874 0.4064)
			(stroke
				(width 0.1524)
				(type default)
			)
			(layer "F.SilkS")
		)
		(fp_line
			(start -0.67945 -0.305054)
			(end -0.12065 -0.305054)
			(stroke
				(width 0.1)
				(type default)
			)
			(layer "F.Fab")
		)
		(fp_line
			(start -0.67945 0.3048)
			(end -0.67945 -0.305054)
			(stroke
				(width 0.1)
				(type default)
			)
			(layer "F.Fab")
		)
		(fp_line
			(start -0.12065 -0.305054)
			(end -0.12065 -0.2794)
			(stroke
				(width 0.1)
				(type default)
			)
			(layer "F.Fab")
		)
		(fp_line
			(start -0.12065 -0.2794)
			(end 0.12065 -0.2794)
			(stroke
				(width 0.1)
				(type default)
			)
			(layer "F.Fab")
		)
		(fp_line
			(start -0.12065 0.2794)
			(end -0.12065 0.3048)
			(stroke
				(width 0.1)
				(type default)
			)
			(layer "F.Fab")
		)
		(fp_line
			(start -0.12065 0.3048)
			(end -0.67945 0.3048)
			(stroke
				(width 0.1)
				(type default)
			)
			(layer "F.Fab")
		)
		(fp_line
			(start 0.120396 0.2794)
			(end -0.12065 0.2794)
			(stroke
				(width 0.1)
				(type default)
			)
			(layer "F.Fab")
		)
		(fp_line
			(start 0.120396 0.3048)
			(end 0.120396 0.2794)
			(stroke
				(width 0.1)
				(type default)
			)
			(layer "F.Fab")
		)
		(fp_line
			(start 0.12065 -0.3048)
			(end 0.67945 -0.3048)
			(stroke
				(width 0.1)
				(type default)
			)
			(layer "F.Fab")
		)
		(fp_line
			(start 0.12065 -0.2794)
			(end 0.12065 -0.3048)
			(stroke
				(width 0.1)
				(type default)
			)
			(layer "F.Fab")
		)
		(fp_line
			(start 0.67945 -0.3048)
			(end 0.67945 0.3048)
			(stroke
				(width 0.1)
				(type default)
			)
			(layer "F.Fab")
		)
		(fp_line
			(start 0.67945 0.3048)
			(end 0.120396 0.3048)
			(stroke
				(width 0.1)
				(type default)
			)
			(layer "F.Fab")
		)
		(pad "1" smd circle
			(at -0.40005 0)
			(size 0 0)
			(layers "F.Cu" "F.Mask" "F.Paste")
			(net "SSD15_ADC_ALERT_N")
		)
		(pad "2" smd circle
			(at 0.40005 0)
			(size 0 0)
			(layers "F.Cu" "F.Mask" "F.Paste")
			(net "SSD_8_15_ADC_ALERT_N")
		)
	)
	(footprint ""
		(layer "F.Cu")
		(at 454.896982 -117.627654 180)
		(property "Reference" "PR7050"
			(at 0 0 180)
			(layer "F.SilkS")
			(hide yes)
			(effects
				(font
					(size 1.27 1.27)
				)
			)
		)
		(property "Value" ""
			(at 0 0 180)
			(layer "F.Fab")
			(effects
				(font
					(size 1.27 1.27)
				)
			)
		)
		(duplicate_pad_numbers_are_jumpers no)
		(fp_line
			(start 0.7874 0.4064)
			(end -0.7874 0.4064)
			(stroke
				(width 0.1524)
				(type default)
			)
			(layer "F.SilkS")
		)
		(fp_line
			(start 0.7874 -0.4064)
			(end 0.7874 0.4064)
			(stroke
				(width 0.1524)
				(type default)
			)
			(layer "F.SilkS")
		)
		(fp_line
			(start -0.7874 0.4064)
			(end -0.7874 -0.4064)
			(stroke
				(width 0.1524)
				(type default)
			)
			(layer "F.SilkS")
		)
		(fp_line
			(start -0.7874 -0.4064)
			(end 0.7874 -0.4064)
			(stroke
				(width 0.1524)
				(type default)
			)
			(layer "F.SilkS")
		)
		(fp_line
			(start 0.67945 0.3048)
			(end 0.120396 0.3048)
			(stroke
				(width 0.1)
				(type default)
			)
			(layer "F.Fab")
		)
		(fp_line
			(start 0.67945 -0.3048)
			(end 0.67945 0.3048)
			(stroke
				(width 0.1)
				(type default)
			)
			(layer "F.Fab")
		)
		(fp_line
			(start 0.12065 -0.2794)
			(end 0.12065 -0.3048)
			(stroke
				(width 0.1)
				(type default)
			)
			(layer "F.Fab")
		)
		(fp_line
			(start 0.12065 -0.3048)
			(end 0.67945 -0.3048)
			(stroke
				(width 0.1)
				(type default)
			)
			(layer "F.Fab")
		)
		(fp_line
			(start 0.120396 0.3048)
			(end 0.120396 0.2794)
			(stroke
				(width 0.1)
				(type default)
			)
			(layer "F.Fab")
		)
		(fp_line
			(start 0.120396 0.2794)
			(end -0.12065 0.2794)
			(stroke
				(width 0.1)
				(type default)
			)
			(layer "F.Fab")
		)
		(fp_line
			(start -0.12065 0.3048)
			(end -0.67945 0.3048)
			(stroke
				(width 0.1)
				(type default)
			)
			(layer "F.Fab")
		)
		(fp_line
			(start -0.12065 0.2794)
			(end -0.12065 0.3048)
			(stroke
				(width 0.1)
				(type default)
			)
			(layer "F.Fab")
		)
		(fp_line
			(start -0.12065 -0.2794)
			(end 0.12065 -0.2794)
			(stroke
				(width 0.1)
				(type default)
			)
			(layer "F.Fab")
		)
		(fp_line
			(start -0.12065 -0.305054)
			(end -0.12065 -0.2794)
			(stroke
				(width 0.1)
				(type default)
			)
			(layer "F.Fab")
		)
		(fp_line
			(start -0.67945 0.3048)
			(end -0.67945 -0.305054)
			(stroke
				(width 0.1)
				(type default)
			)
			(layer "F.Fab")
		)
		(fp_line
			(start -0.67945 -0.305054)
			(end -0.12065 -0.305054)
			(stroke
				(width 0.1)
				(type default)
			)
			(layer "F.Fab")
		)
		(pad "1" smd circle
			(at -0.40005 0 180)
			(size 0 0)
			(layers "F.Cu" "F.Mask" "F.Paste")
			(net "P12V_NIC7_CO_OV_FB")
		)
		(pad "2" smd circle
			(at 0.40005 0 180)
			(size 0 0)
			(layers "F.Cu" "F.Mask" "F.Paste")
			(net "P12V_NIC7_R")
		)
	)
	(footprint ""
		(layer "F.Cu")
		(at 440.58332 -113.628678)
		(property "Reference" "PC908"
			(at 0 0 0)
			(layer "F.SilkS")
			(hide yes)
			(effects
				(font
					(size 1.27 1.27)
				)
			)
		)
		(property "Value" ""
			(at 0 0 0)
			(layer "F.Fab")
			(effects
				(font
					(size 1.27 1.27)
				)
			)
		)
		(duplicate_pad_numbers_are_jumpers no)
		(fp_line
			(start -0.7874 -0.4064)
			(end 0.7874 -0.4064)
			(stroke
				(width 0.1524)
				(type default)
			)
			(layer "F.SilkS")
		)
		(fp_line
			(start -0.7874 0.4064)
			(end -0.7874 -0.4064)
			(stroke
				(width 0.1524)
				(type default)
			)
			(layer "F.SilkS")
		)
		(fp_line
			(start 0.7874 -0.4064)
			(end 0.7874 0.4064)
			(stroke
				(width 0.1524)
				(type default)
			)
			(layer "F.SilkS")
		)
		(fp_line
			(start 0.7874 0.4064)
			(end -0.7874 0.4064)
			(stroke
				(width 0.1524)
				(type default)
			)
			(layer "F.SilkS")
		)
		(fp_line
			(start -0.67945 -0.305054)
			(end -0.12065 -0.305054)
			(stroke
				(width 0.1)
				(type default)
			)
			(layer "F.Fab")
		)
		(fp_line
			(start -0.67945 0.3048)
			(end -0.67945 -0.305054)
			(stroke
				(width 0.1)
				(type default)
			)
			(layer "F.Fab")
		)
		(fp_line
			(start -0.12065 -0.305054)
			(end -0.12065 -0.2794)
			(stroke
				(width 0.1)
				(type default)
			)
			(layer "F.Fab")
		)
		(fp_line
			(start -0.12065 -0.2794)
			(end 0.12065 -0.2794)
			(stroke
				(width 0.1)
				(type default)
			)
			(layer "F.Fab")
		)
		(fp_line
			(start -0.12065 0.2794)
			(end -0.12065 0.3048)
			(stroke
				(width 0.1)
				(type default)
			)
			(layer "F.Fab")
		)
		(fp_line
			(start -0.12065 0.3048)
			(end -0.67945 0.3048)
			(stroke
				(width 0.1)
				(type default)
			)
			(layer "F.Fab")
		)
		(fp_line
			(start 0.120396 0.2794)
			(end -0.12065 0.2794)
			(stroke
				(width 0.1)
				(type default)
			)
			(layer "F.Fab")
		)
		(fp_line
			(start 0.120396 0.3048)
			(end 0.120396 0.2794)
			(stroke
				(width 0.1)
				(type default)
			)
			(layer "F.Fab")
		)
		(fp_line
			(start 0.12065 -0.3048)
			(end 0.67945 -0.3048)
			(stroke
				(width 0.1)
				(type default)
			)
			(layer "F.Fab")
		)
		(fp_line
			(start 0.12065 -0.2794)
			(end 0.12065 -0.3048)
			(stroke
				(width 0.1)
				(type default)
			)
			(layer "F.Fab")
		)
		(fp_line
			(start 0.67945 -0.3048)
			(end 0.67945 0.3048)
			(stroke
				(width 0.1)
				(type default)
			)
			(layer "F.Fab")
		)
		(fp_line
			(start 0.67945 0.3048)
			(end 0.120396 0.3048)
			(stroke
				(width 0.1)
				(type default)
			)
			(layer "F.Fab")
		)
		(pad "1" smd circle
			(at -0.40005 0)
			(size 0 0)
			(layers "F.Cu" "F.Mask" "F.Paste")
			(net "P3V3_AUX")
		)
		(pad "2" smd circle
			(at 0.40005 0)
			(size 0 0)
			(layers "F.Cu" "F.Mask" "F.Paste")
			(net "GND")
		)
	)
	(footprint ""
		(layer "F.Cu")
		(at 386.90804 -163.061396 180)
		(property "Reference" "R310"
			(at 0 0 180)
			(layer "F.SilkS")
			(hide yes)
			(effects
				(font
					(size 1.27 1.27)
				)
			)
		)
		(property "Value" ""
			(at 0 0 180)
			(layer "F.Fab")
			(effects
				(font
					(size 1.27 1.27)
				)
			)
		)
		(duplicate_pad_numbers_are_jumpers no)
		(fp_line
			(start 0.7874 0.4064)
			(end -0.7874 0.4064)
			(stroke
				(width 0.1524)
				(type default)
			)
			(layer "F.SilkS")
		)
		(fp_line
			(start 0.7874 -0.4064)
			(end 0.7874 0.4064)
			(stroke
				(width 0.1524)
				(type default)
			)
			(layer "F.SilkS")
		)
		(fp_line
			(start -0.7874 0.4064)
			(end -0.7874 -0.4064)
			(stroke
				(width 0.1524)
				(type default)
			)
			(layer "F.SilkS")
		)
		(fp_line
			(start -0.7874 -0.4064)
			(end 0.7874 -0.4064)
			(stroke
				(width 0.1524)
				(type default)
			)
			(layer "F.SilkS")
		)
		(fp_line
			(start 0.67945 0.3048)
			(end 0.120396 0.3048)
			(stroke
				(width 0.1)
				(type default)
			)
			(layer "F.Fab")
		)
		(fp_line
			(start 0.67945 -0.3048)
			(end 0.67945 0.3048)
			(stroke
				(width 0.1)
				(type default)
			)
			(layer "F.Fab")
		)
		(fp_line
			(start 0.12065 -0.2794)
			(end 0.12065 -0.3048)
			(stroke
				(width 0.1)
				(type default)
			)
			(layer "F.Fab")
		)
		(fp_line
			(start 0.12065 -0.3048)
			(end 0.67945 -0.3048)
			(stroke
				(width 0.1)
				(type default)
			)
			(layer "F.Fab")
		)
		(fp_line
			(start 0.120396 0.3048)
			(end 0.120396 0.2794)
			(stroke
				(width 0.1)
				(type default)
			)
			(layer "F.Fab")
		)
		(fp_line
			(start 0.120396 0.2794)
			(end -0.12065 0.2794)
			(stroke
				(width 0.1)
				(type default)
			)
			(layer "F.Fab")
		)
		(fp_line
			(start -0.12065 0.3048)
			(end -0.67945 0.3048)
			(stroke
				(width 0.1)
				(type default)
			)
			(layer "F.Fab")
		)
		(fp_line
			(start -0.12065 0.2794)
			(end -0.12065 0.3048)
			(stroke
				(width 0.1)
				(type default)
			)
			(layer "F.Fab")
		)
		(fp_line
			(start -0.12065 -0.2794)
			(end 0.12065 -0.2794)
			(stroke
				(width 0.1)
				(type default)
			)
			(layer "F.Fab")
		)
		(fp_line
			(start -0.12065 -0.305054)
			(end -0.12065 -0.2794)
			(stroke
				(width 0.1)
				(type default)
			)
			(layer "F.Fab")
		)
		(fp_line
			(start -0.67945 0.3048)
			(end -0.67945 -0.305054)
			(stroke
				(width 0.1)
				(type default)
			)
			(layer "F.Fab")
		)
		(fp_line
			(start -0.67945 -0.305054)
			(end -0.12065 -0.305054)
			(stroke
				(width 0.1)
				(type default)
			)
			(layer "F.Fab")
		)
		(pad "1" smd circle
			(at -0.40005 0 180)
			(size 0 0)
			(layers "F.Cu" "F.Mask" "F.Paste")
			(net "PWRGD_NIC6_PWR_GOOD")
		)
		(pad "2" smd circle
			(at 0.40005 0 180)
			(size 0 0)
			(layers "F.Cu" "F.Mask" "F.Paste")
			(net "PWRGD_NIC6_PWR_GOOD_R")
		)
	)
	(footprint ""
		(layer "F.Cu")
		(at 139.768072 -18.437098)
		(property "Reference" "R1665"
			(at 0 0 0)
			(layer "F.SilkS")
			(hide yes)
			(effects
				(font
					(size 1.27 1.27)
				)
			)
		)
		(property "Value" ""
			(at 0 0 0)
			(layer "F.Fab")
			(effects
				(font
					(size 1.27 1.27)
				)
			)
		)
		(duplicate_pad_numbers_are_jumpers no)
		(fp_line
			(start -0.7874 -0.4064)
			(end 0.7874 -0.4064)
			(stroke
				(width 0.1524)
				(type default)
			)
			(layer "F.SilkS")
		)
		(fp_line
			(start -0.7874 0.4064)
			(end -0.7874 -0.4064)
			(stroke
				(width 0.1524)
				(type default)
			)
			(layer "F.SilkS")
		)
		(fp_line
			(start 0.7874 -0.4064)
			(end 0.7874 0.4064)
			(stroke
				(width 0.1524)
				(type default)
			)
			(layer "F.SilkS")
		)
		(fp_line
			(start 0.7874 0.4064)
			(end -0.7874 0.4064)
			(stroke
				(width 0.1524)
				(type default)
			)
			(layer "F.SilkS")
		)
		(fp_line
			(start -0.67945 -0.305054)
			(end -0.12065 -0.305054)
			(stroke
				(width 0.1)
				(type default)
			)
			(layer "F.Fab")
		)
		(fp_line
			(start -0.67945 0.3048)
			(end -0.67945 -0.305054)
			(stroke
				(width 0.1)
				(type default)
			)
			(layer "F.Fab")
		)
		(fp_line
			(start -0.12065 -0.305054)
			(end -0.12065 -0.2794)
			(stroke
				(width 0.1)
				(type default)
			)
			(layer "F.Fab")
		)
		(fp_line
			(start -0.12065 -0.2794)
			(end 0.12065 -0.2794)
			(stroke
				(width 0.1)
				(type default)
			)
			(layer "F.Fab")
		)
		(fp_line
			(start -0.12065 0.2794)
			(end -0.12065 0.3048)
			(stroke
				(width 0.1)
				(type default)
			)
			(layer "F.Fab")
		)
		(fp_line
			(start -0.12065 0.3048)
			(end -0.67945 0.3048)
			(stroke
				(width 0.1)
				(type default)
			)
			(layer "F.Fab")
		)
		(fp_line
			(start 0.120396 0.2794)
			(end -0.12065 0.2794)
			(stroke
				(width 0.1)
				(type default)
			)
			(layer "F.Fab")
		)
		(fp_line
			(start 0.120396 0.3048)
			(end 0.120396 0.2794)
			(stroke
				(width 0.1)
				(type default)
			)
			(layer "F.Fab")
		)
		(fp_line
			(start 0.12065 -0.3048)
			(end 0.67945 -0.3048)
			(stroke
				(width 0.1)
				(type default)
			)
			(layer "F.Fab")
		)
		(fp_line
			(start 0.12065 -0.2794)
			(end 0.12065 -0.3048)
			(stroke
				(width 0.1)
				(type default)
			)
			(layer "F.Fab")
		)
		(fp_line
			(start 0.67945 -0.3048)
			(end 0.67945 0.3048)
			(stroke
				(width 0.1)
				(type default)
			)
			(layer "F.Fab")
		)
		(fp_line
			(start 0.67945 0.3048)
			(end 0.120396 0.3048)
			(stroke
				(width 0.1)
				(type default)
			)
			(layer "F.Fab")
		)
		(pad "1" smd circle
			(at -0.40005 0)
			(size 0 0)
			(layers "F.Cu" "F.Mask" "F.Paste")
			(net "SMB_ISO_SSD4_R_SCL")
		)
		(pad "2" smd circle
			(at 0.40005 0)
			(size 0 0)
			(layers "F.Cu" "F.Mask" "F.Paste")
			(net "SMB_ISO_SSD4_SCL")
		)
	)
	(footprint ""
		(layer "F.Cu")
		(at 406.005284 -377.889262 90)
		(property "Reference" "U422"
			(at 0.029718 2.129282 0)
			(unlocked yes)
			(layer "F.SilkS")
			(effects
				(font
					(size 0.7874 0.5842)
					(thickness 0.1524)
				)
				(justify left)
			)
		)
		(property "Value" ""
			(at 0 0 90)
			(layer "F.Fab")
			(effects
				(font
					(size 1.27 1.27)
				)
			)
		)
		(duplicate_pad_numbers_are_jumpers no)
		(fp_line
			(start 1.463548 -1.549908)
			(end 1.463548 1.549908)
			(stroke
				(width 0.1524)
				(type default)
			)
			(layer "F.SilkS")
		)
		(fp_line
			(start 0.762 -1.549908)
			(end 1.463548 -1.549908)
			(stroke
				(width 0.1524)
				(type default)
			)
			(layer "F.SilkS")
		)
		(fp_line
			(start -0.787908 -1.549908)
			(end 0 -0.762)
			(stroke
				(width 0.1524)
				(type default)
			)
			(layer "F.SilkS")
		)
		(fp_line
			(start -1.463548 -1.549908)
			(end -0.787908 -1.549908)
			(stroke
				(width 0.1524)
				(type default)
			)
			(layer "F.SilkS")
		)
		(fp_line
			(start 0 -0.762)
			(end 0.762 -1.549908)
			(stroke
				(width 0.1524)
				(type default)
			)
			(layer "F.SilkS")
		)
		(fp_line
			(start 1.463548 1.549908)
			(end -1.463548 1.549908)
			(stroke
				(width 0.1524)
				(type default)
			)
			(layer "F.SilkS")
		)
		(fp_line
			(start -1.463548 1.549908)
			(end -1.463548 -1.549908)
			(stroke
				(width 0.1524)
				(type default)
			)
			(layer "F.SilkS")
		)
		(fp_poly
			(pts
				(xy -2.984754 -2.229612) (xy -2.765806 -1.57226) (xy -3.423158 -1.791462)
			)
			(stroke
				(width 0)
				(type default)
			)
			(fill yes)
			(layer "F.SilkS")
		)
		(fp_line
			(start 1.549908 -1.549908)
			(end 1.549908 1.549908)
			(stroke
				(width 0.1)
				(type default)
			)
			(layer "F.Fab")
		)
		(fp_line
			(start -1.549908 -1.549908)
			(end 1.549908 -1.549908)
			(stroke
				(width 0.1)
				(type default)
			)
			(layer "F.Fab")
		)
		(fp_line
			(start 1.549908 1.549908)
			(end -1.549908 1.549908)
			(stroke
				(width 0.1)
				(type default)
			)
			(layer "F.Fab")
		)
		(fp_line
			(start -1.549908 1.549908)
			(end -1.549908 -1.549908)
			(stroke
				(width 0.1)
				(type default)
			)
			(layer "F.Fab")
		)
		(fp_poly
			(pts
				(xy -3.4798 -1.359916) (xy -2.86004 -1.050036) (xy -3.4798 -0.740156)
			)
			(stroke
				(width 0)
				(type default)
			)
			(fill yes)
			(layer "F.Fab")
		)
		(pad "1" smd rect
			(at -2.175002 -1.050036 180)
			(size 0.6096 1.1684)
			(layers "F.Cu" "F.Mask" "F.Paste")
			(net "P3V3_AUX")
		)
		(pad "2" smd rect
			(at -2.175002 -0.32512 180)
			(size 0.4318 1.1684)
			(layers "F.Cu" "F.Mask" "F.Paste")
			(net "SMB_MB_I3C_ISO_SCL")
		)
		(pad "3" smd rect
			(at -2.175002 0.32512 180)
			(size 0.4318 1.1684)
			(layers "F.Cu" "F.Mask" "F.Paste")
			(net "SMB_MB_I3C_ISO_SDA")
		)
		(pad "4" smd rect
			(at -2.175002 1.050036 180)
			(size 0.6096 1.1684)
			(layers "F.Cu" "F.Mask" "F.Paste")
			(net "GND")
		)
		(pad "5" smd rect
			(at 2.175002 1.050036 180)
			(size 0.6096 1.1684)
			(layers "F.Cu" "F.Mask" "F.Paste")
			(net "MB_I3C_ISO_EN")
		)
		(pad "6" smd rect
			(at 2.175002 0.32512 180)
			(size 0.4318 1.1684)
			(layers "F.Cu" "F.Mask" "F.Paste")
			(net "I3C_MB_BMC_R_SDA")
		)
		(pad "7" smd rect
			(at 2.175002 -0.32512 180)
			(size 0.4318 1.1684)
			(layers "F.Cu" "F.Mask" "F.Paste")
			(net "I3C_MB_BMC_R_SCL")
		)
		(pad "8" smd rect
			(at 2.175002 -1.050036 180)
			(size 0.6096 1.1684)
			(layers "F.Cu" "F.Mask" "F.Paste")
			(net "P3V3_AUX")
		)
	)
	(footprint ""
		(layer "F.Cu")
		(at 210.439 -192.659 180)
		(property "Reference" "R1533"
			(at 0 0 180)
			(layer "F.SilkS")
			(hide yes)
			(effects
				(font
					(size 1.27 1.27)
				)
			)
		)
		(property "Value" ""
			(at 0 0 180)
			(layer "F.Fab")
			(effects
				(font
					(size 1.27 1.27)
				)
			)
		)
		(duplicate_pad_numbers_are_jumpers no)
		(fp_line
			(start 0.7874 0.4064)
			(end -0.7874 0.4064)
			(stroke
				(width 0.1524)
				(type default)
			)
			(layer "F.SilkS")
		)
		(fp_line
			(start 0.7874 -0.4064)
			(end 0.7874 0.4064)
			(stroke
				(width 0.1524)
				(type default)
			)
			(layer "F.SilkS")
		)
		(fp_line
			(start -0.7874 0.4064)
			(end -0.7874 -0.4064)
			(stroke
				(width 0.1524)
				(type default)
			)
			(layer "F.SilkS")
		)
		(fp_line
			(start -0.7874 -0.4064)
			(end 0.7874 -0.4064)
			(stroke
				(width 0.1524)
				(type default)
			)
			(layer "F.SilkS")
		)
		(fp_line
			(start 0.67945 0.3048)
			(end 0.120396 0.3048)
			(stroke
				(width 0.1)
				(type default)
			)
			(layer "F.Fab")
		)
		(fp_line
			(start 0.67945 -0.3048)
			(end 0.67945 0.3048)
			(stroke
				(width 0.1)
				(type default)
			)
			(layer "F.Fab")
		)
		(fp_line
			(start 0.12065 -0.2794)
			(end 0.12065 -0.3048)
			(stroke
				(width 0.1)
				(type default)
			)
			(layer "F.Fab")
		)
		(fp_line
			(start 0.12065 -0.3048)
			(end 0.67945 -0.3048)
			(stroke
				(width 0.1)
				(type default)
			)
			(layer "F.Fab")
		)
		(fp_line
			(start 0.120396 0.3048)
			(end 0.120396 0.2794)
			(stroke
				(width 0.1)
				(type default)
			)
			(layer "F.Fab")
		)
		(fp_line
			(start 0.120396 0.2794)
			(end -0.12065 0.2794)
			(stroke
				(width 0.1)
				(type default)
			)
			(layer "F.Fab")
		)
		(fp_line
			(start -0.12065 0.3048)
			(end -0.67945 0.3048)
			(stroke
				(width 0.1)
				(type default)
			)
			(layer "F.Fab")
		)
		(fp_line
			(start -0.12065 0.2794)
			(end -0.12065 0.3048)
			(stroke
				(width 0.1)
				(type default)
			)
			(layer "F.Fab")
		)
		(fp_line
			(start -0.12065 -0.2794)
			(end 0.12065 -0.2794)
			(stroke
				(width 0.1)
				(type default)
			)
			(layer "F.Fab")
		)
		(fp_line
			(start -0.12065 -0.305054)
			(end -0.12065 -0.2794)
			(stroke
				(width 0.1)
				(type default)
			)
			(layer "F.Fab")
		)
		(fp_line
			(start -0.67945 0.3048)
			(end -0.67945 -0.305054)
			(stroke
				(width 0.1)
				(type default)
			)
			(layer "F.Fab")
		)
		(fp_line
			(start -0.67945 -0.305054)
			(end -0.12065 -0.305054)
			(stroke
				(width 0.1)
				(type default)
			)
			(layer "F.Fab")
		)
		(pad "1" smd circle
			(at -0.40005 0 180)
			(size 0 0)
			(layers "F.Cu" "F.Mask" "F.Paste")
			(net "SMB_NIC7_R_SCL")
		)
		(pad "2" smd circle
			(at 0.40005 0 180)
			(size 0 0)
			(layers "F.Cu" "F.Mask" "F.Paste")
			(net "P1V2_AUX")
		)
	)
	(footprint ""
		(layer "F.Cu")
		(at 45.246798 -38.49116 180)
		(property "Reference" "R5888"
			(at 0 0 180)
			(layer "F.SilkS")
			(hide yes)
			(effects
				(font
					(size 1.27 1.27)
				)
			)
		)
		(property "Value" ""
			(at 0 0 180)
			(layer "F.Fab")
			(effects
				(font
					(size 1.27 1.27)
				)
			)
		)
		(duplicate_pad_numbers_are_jumpers no)
		(fp_line
			(start 0.7874 0.4064)
			(end -0.7874 0.4064)
			(stroke
				(width 0.1524)
				(type default)
			)
			(layer "F.SilkS")
		)
		(fp_line
			(start 0.7874 -0.4064)
			(end 0.7874 0.4064)
			(stroke
				(width 0.1524)
				(type default)
			)
			(layer "F.SilkS")
		)
		(fp_line
			(start -0.7874 0.4064)
			(end -0.7874 -0.4064)
			(stroke
				(width 0.1524)
				(type default)
			)
			(layer "F.SilkS")
		)
		(fp_line
			(start -0.7874 -0.4064)
			(end 0.7874 -0.4064)
			(stroke
				(width 0.1524)
				(type default)
			)
			(layer "F.SilkS")
		)
		(fp_line
			(start 0.67945 0.3048)
			(end 0.120396 0.3048)
			(stroke
				(width 0.1)
				(type default)
			)
			(layer "F.Fab")
		)
		(fp_line
			(start 0.67945 -0.3048)
			(end 0.67945 0.3048)
			(stroke
				(width 0.1)
				(type default)
			)
			(layer "F.Fab")
		)
		(fp_line
			(start 0.12065 -0.2794)
			(end 0.12065 -0.3048)
			(stroke
				(width 0.1)
				(type default)
			)
			(layer "F.Fab")
		)
		(fp_line
			(start 0.12065 -0.3048)
			(end 0.67945 -0.3048)
			(stroke
				(width 0.1)
				(type default)
			)
			(layer "F.Fab")
		)
		(fp_line
			(start 0.120396 0.3048)
			(end 0.120396 0.2794)
			(stroke
				(width 0.1)
				(type default)
			)
			(layer "F.Fab")
		)
		(fp_line
			(start 0.120396 0.2794)
			(end -0.12065 0.2794)
			(stroke
				(width 0.1)
				(type default)
			)
			(layer "F.Fab")
		)
		(fp_line
			(start -0.12065 0.3048)
			(end -0.67945 0.3048)
			(stroke
				(width 0.1)
				(type default)
			)
			(layer "F.Fab")
		)
		(fp_line
			(start -0.12065 0.2794)
			(end -0.12065 0.3048)
			(stroke
				(width 0.1)
				(type default)
			)
			(layer "F.Fab")
		)
		(fp_line
			(start -0.12065 -0.2794)
			(end 0.12065 -0.2794)
			(stroke
				(width 0.1)
				(type default)
			)
			(layer "F.Fab")
		)
		(fp_line
			(start -0.12065 -0.305054)
			(end -0.12065 -0.2794)
			(stroke
				(width 0.1)
				(type default)
			)
			(layer "F.Fab")
		)
		(fp_line
			(start -0.67945 0.3048)
			(end -0.67945 -0.305054)
			(stroke
				(width 0.1)
				(type default)
			)
			(layer "F.Fab")
		)
		(fp_line
			(start -0.67945 -0.305054)
			(end -0.12065 -0.305054)
			(stroke
				(width 0.1)
				(type default)
			)
			(layer "F.Fab")
		)
		(pad "1" smd circle
			(at -0.40005 0 180)
			(size 0 0)
			(layers "F.Cu" "F.Mask" "F.Paste")
			(net "P3V3_SSD2_PG_G1")
		)
		(pad "2" smd circle
			(at 0.40005 0 180)
			(size 0 0)
			(layers "F.Cu" "F.Mask" "F.Paste")
			(net "GND")
		)
	)
	(footprint ""
		(layer "F.Cu")
		(at 20.239736 -152.71115 90)
		(property "Reference" "R683"
			(at 0 0 90)
			(layer "F.SilkS")
			(hide yes)
			(effects
				(font
					(size 1.27 1.27)
				)
			)
		)
		(property "Value" ""
			(at 0 0 90)
			(layer "F.Fab")
			(effects
				(font
					(size 1.27 1.27)
				)
			)
		)
		(duplicate_pad_numbers_are_jumpers no)
		(fp_line
			(start 0.7874 -0.4064)
			(end 0.7874 0.4064)
			(stroke
				(width 0.1524)
				(type default)
			)
			(layer "F.SilkS")
		)
		(fp_line
			(start -0.7874 -0.4064)
			(end 0.7874 -0.4064)
			(stroke
				(width 0.1524)
				(type default)
			)
			(layer "F.SilkS")
		)
		(fp_line
			(start 0.7874 0.4064)
			(end -0.7874 0.4064)
			(stroke
				(width 0.1524)
				(type default)
			)
			(layer "F.SilkS")
		)
		(fp_line
			(start -0.7874 0.4064)
			(end -0.7874 -0.4064)
			(stroke
				(width 0.1524)
				(type default)
			)
			(layer "F.SilkS")
		)
		(fp_line
			(start -0.12065 -0.305054)
			(end -0.12065 -0.2794)
			(stroke
				(width 0.1)
				(type default)
			)
			(layer "F.Fab")
		)
		(fp_line
			(start -0.67945 -0.305054)
			(end -0.12065 -0.305054)
			(stroke
				(width 0.1)
				(type default)
			)
			(layer "F.Fab")
		)
		(fp_line
			(start 0.67945 -0.3048)
			(end 0.67945 0.3048)
			(stroke
				(width 0.1)
				(type default)
			)
			(layer "F.Fab")
		)
		(fp_line
			(start 0.12065 -0.3048)
			(end 0.67945 -0.3048)
			(stroke
				(width 0.1)
				(type default)
			)
			(layer "F.Fab")
		)
		(fp_line
			(start 0.12065 -0.2794)
			(end 0.12065 -0.3048)
			(stroke
				(width 0.1)
				(type default)
			)
			(layer "F.Fab")
		)
		(fp_line
			(start -0.12065 -0.2794)
			(end 0.12065 -0.2794)
			(stroke
				(width 0.1)
				(type default)
			)
			(layer "F.Fab")
		)
		(fp_line
			(start 0.120396 0.2794)
			(end -0.12065 0.2794)
			(stroke
				(width 0.1)
				(type default)
			)
			(layer "F.Fab")
		)
		(fp_line
			(start -0.12065 0.2794)
			(end -0.12065 0.3048)
			(stroke
				(width 0.1)
				(type default)
			)
			(layer "F.Fab")
		)
		(fp_line
			(start 0.67945 0.3048)
			(end 0.120396 0.3048)
			(stroke
				(width 0.1)
				(type default)
			)
			(layer "F.Fab")
		)
		(fp_line
			(start 0.120396 0.3048)
			(end 0.120396 0.2794)
			(stroke
				(width 0.1)
				(type default)
			)
			(layer "F.Fab")
		)
		(fp_line
			(start -0.12065 0.3048)
			(end -0.67945 0.3048)
			(stroke
				(width 0.1)
				(type default)
			)
			(layer "F.Fab")
		)
		(fp_line
			(start -0.67945 0.3048)
			(end -0.67945 -0.305054)
			(stroke
				(width 0.1)
				(type default)
			)
			(layer "F.Fab")
		)
		(pad "1" smd circle
			(at -0.40005 0 90)
			(size 0 0)
			(layers "F.Cu" "F.Mask" "F.Paste")
			(net "NIC0_ADC_A0")
		)
		(pad "2" smd circle
			(at 0.40005 0 90)
			(size 0 0)
			(layers "F.Cu" "F.Mask" "F.Paste")
			(net "P3V3_AUX")
		)
	)
	(footprint ""
		(layer "F.Cu")
		(at 248.094754 -279.567386 180)
		(property "Reference" "R798"
			(at 0 0 180)
			(layer "F.SilkS")
			(hide yes)
			(effects
				(font
					(size 1.27 1.27)
				)
			)
		)
		(property "Value" ""
			(at 0 0 180)
			(layer "F.Fab")
			(effects
				(font
					(size 1.27 1.27)
				)
			)
		)
		(duplicate_pad_numbers_are_jumpers no)
		(fp_line
			(start 0.7874 0.4064)
			(end -0.7874 0.4064)
			(stroke
				(width 0.1524)
				(type default)
			)
			(layer "F.SilkS")
		)
		(fp_line
			(start 0.7874 -0.4064)
			(end 0.7874 0.4064)
			(stroke
				(width 0.1524)
				(type default)
			)
			(layer "F.SilkS")
		)
		(fp_line
			(start -0.7874 0.4064)
			(end -0.7874 -0.4064)
			(stroke
				(width 0.1524)
				(type default)
			)
			(layer "F.SilkS")
		)
		(fp_line
			(start -0.7874 -0.4064)
			(end 0.7874 -0.4064)
			(stroke
				(width 0.1524)
				(type default)
			)
			(layer "F.SilkS")
		)
		(fp_line
			(start 0.67945 0.3048)
			(end 0.120396 0.3048)
			(stroke
				(width 0.1)
				(type default)
			)
			(layer "F.Fab")
		)
		(fp_line
			(start 0.67945 -0.3048)
			(end 0.67945 0.3048)
			(stroke
				(width 0.1)
				(type default)
			)
			(layer "F.Fab")
		)
		(fp_line
			(start 0.12065 -0.2794)
			(end 0.12065 -0.3048)
			(stroke
				(width 0.1)
				(type default)
			)
			(layer "F.Fab")
		)
		(fp_line
			(start 0.12065 -0.3048)
			(end 0.67945 -0.3048)
			(stroke
				(width 0.1)
				(type default)
			)
			(layer "F.Fab")
		)
		(fp_line
			(start 0.120396 0.3048)
			(end 0.120396 0.2794)
			(stroke
				(width 0.1)
				(type default)
			)
			(layer "F.Fab")
		)
		(fp_line
			(start 0.120396 0.2794)
			(end -0.12065 0.2794)
			(stroke
				(width 0.1)
				(type default)
			)
			(layer "F.Fab")
		)
		(fp_line
			(start -0.12065 0.3048)
			(end -0.67945 0.3048)
			(stroke
				(width 0.1)
				(type default)
			)
			(layer "F.Fab")
		)
		(fp_line
			(start -0.12065 0.2794)
			(end -0.12065 0.3048)
			(stroke
				(width 0.1)
				(type default)
			)
			(layer "F.Fab")
		)
		(fp_line
			(start -0.12065 -0.2794)
			(end 0.12065 -0.2794)
			(stroke
				(width 0.1)
				(type default)
			)
			(layer "F.Fab")
		)
		(fp_line
			(start -0.12065 -0.305054)
			(end -0.12065 -0.2794)
			(stroke
				(width 0.1)
				(type default)
			)
			(layer "F.Fab")
		)
		(fp_line
			(start -0.67945 0.3048)
			(end -0.67945 -0.305054)
			(stroke
				(width 0.1)
				(type default)
			)
			(layer "F.Fab")
		)
		(fp_line
			(start -0.67945 -0.305054)
			(end -0.12065 -0.305054)
			(stroke
				(width 0.1)
				(type default)
			)
			(layer "F.Fab")
		)
		(pad "1" smd circle
			(at -0.40005 0 180)
			(size 0 0)
			(layers "F.Cu" "F.Mask" "F.Paste")
			(net "SMB_BIC_I2C6_MUX_PEX_ADC_R_SDA")
		)
		(pad "2" smd circle
			(at 0.40005 0 180)
			(size 0 0)
			(layers "F.Cu" "F.Mask" "F.Paste")
			(net "SMB_PEX2_P1V25_ADC_SDA")
		)
	)
	(footprint ""
		(layer "F.Cu")
		(at 91.311984 -100.20935 90)
		(property "Reference" "U80"
			(at -0.38735 2.364486 90)
			(unlocked yes)
			(layer "F.SilkS")
			(effects
				(font
					(size 0.7874 0.5842)
					(thickness 0.1524)
				)
			)
		)
		(property "Value" ""
			(at 0 0 90)
			(layer "F.Fab")
			(effects
				(font
					(size 1.27 1.27)
				)
			)
		)
		(duplicate_pad_numbers_are_jumpers no)
		(fp_line
			(start 1.500124 -1.500124)
			(end 1.500124 -1.004062)
			(stroke
				(width 0.1524)
				(type default)
			)
			(layer "F.SilkS")
		)
		(fp_line
			(start 1.004062 -1.500124)
			(end 1.500124 -1.500124)
			(stroke
				(width 0.1524)
				(type default)
			)
			(layer "F.SilkS")
		)
		(fp_line
			(start -1.500124 -1.500124)
			(end -1.004062 -1.500124)
			(stroke
				(width 0.1524)
				(type default)
			)
			(layer "F.SilkS")
		)
		(fp_line
			(start -1.500124 -1.004062)
			(end -1.500124 -1.500124)
			(stroke
				(width 0.1524)
				(type default)
			)
			(layer "F.SilkS")
		)
		(fp_line
			(start 1.500124 1.004062)
			(end 1.500124 1.500124)
			(stroke
				(width 0.1524)
				(type default)
			)
			(layer "F.SilkS")
		)
		(fp_line
			(start 1.500124 1.500124)
			(end 1.004062 1.500124)
			(stroke
				(width 0.1524)
				(type default)
			)
			(layer "F.SilkS")
		)
		(fp_line
			(start -1.004062 1.500124)
			(end -1.500124 1.500124)
			(stroke
				(width 0.1524)
				(type default)
			)
			(layer "F.SilkS")
		)
		(fp_line
			(start -1.500124 1.500124)
			(end -1.500124 1.004062)
			(stroke
				(width 0.1524)
				(type default)
			)
			(layer "F.SilkS")
		)
		(fp_poly
			(pts
				(xy -1.972818 -2.316734) (xy -2.69113 -1.598422) (xy -1.613408 -1.239266)
			)
			(stroke
				(width 0)
				(type default)
			)
			(fill yes)
			(layer "F.SilkS")
		)
		(fp_line
			(start 1.500124 -1.500124)
			(end 1.500124 1.500124)
			(stroke
				(width 0.1)
				(type default)
			)
			(layer "F.Fab")
		)
		(fp_line
			(start -1.500124 -1.500124)
			(end 1.500124 -1.500124)
			(stroke
				(width 0.1)
				(type default)
			)
			(layer "F.Fab")
		)
		(fp_line
			(start 1.500124 1.500124)
			(end -1.500124 1.500124)
			(stroke
				(width 0.1)
				(type default)
			)
			(layer "F.Fab")
		)
		(fp_line
			(start -1.500124 1.500124)
			(end -1.500124 -1.500124)
			(stroke
				(width 0.1)
				(type default)
			)
			(layer "F.Fab")
		)
		(fp_poly
			(pts
				(xy -2.847848 -1.258062) (xy -2.847848 -0.242062) (xy -1.831848 -0.750062)
			)
			(stroke
				(width 0)
				(type default)
			)
			(fill yes)
			(layer "F.Fab")
		)
		(pad "1" smd rect
			(at -1.400048 -0.750062)
			(size 0.2286 0.6096)
			(layers "F.Cu" "F.Mask" "F.Paste")
			(net "NIC1_ADC_A1")
		)
		(pad "2" smd rect
			(at -1.400048 -0.249936)
			(size 0.2286 0.6096)
			(layers "F.Cu" "F.Mask" "F.Paste")
			(net "NIC1_ADC_A0")
		)
		(pad "3" smd rect
			(at -1.400048 0.249936)
			(size 0.2286 0.6096)
			(layers "F.Cu" "F.Mask" "F.Paste")
			(net "NIC1_ADC_ALERT_N")
		)
		(pad "4" smd rect
			(at -1.400048 0.750062)
			(size 0.2286 0.6096)
			(layers "F.Cu" "F.Mask" "F.Paste")
			(net "SMB_NIC1_ADC_SDA")
		)
		(pad "5" smd rect
			(at -0.750062 1.400048 90)
			(size 0.2286 0.6096)
			(layers "F.Cu" "F.Mask" "F.Paste")
			(net "SMB_NIC1_ADC_SCL")
		)
		(pad "6" smd rect
			(at -0.249936 1.400048 90)
			(size 0.2286 0.6096)
			(layers "F.Cu" "F.Mask" "F.Paste")
			(net "Net_8660")
		)
		(pad "7" smd rect
			(at 0.249936 1.400048 90)
			(size 0.2286 0.6096)
			(layers "F.Cu" "F.Mask" "F.Paste")
			(net "Net_8659")
		)
		(pad "8" smd rect
			(at 0.750062 1.400048 90)
			(size 0.2286 0.6096)
			(layers "F.Cu" "F.Mask" "F.Paste")
			(net "Net_8658")
		)
		(pad "9" smd rect
			(at 1.400048 0.750062)
			(size 0.2286 0.6096)
			(layers "F.Cu" "F.Mask" "F.Paste")
			(net "P3V3_AUX")
		)
		(pad "10" smd rect
			(at 1.400048 0.249936)
			(size 0.2286 0.6096)
			(layers "F.Cu" "F.Mask" "F.Paste")
			(net "GND")
		)
		(pad "11" smd rect
			(at 1.400048 -0.249936)
			(size 0.2286 0.6096)
			(layers "F.Cu" "F.Mask" "F.Paste")
			(net "P12V_NIC1_R")
		)
		(pad "12" smd rect
			(at 1.400048 -0.750062)
			(size 0.2286 0.6096)
			(layers "F.Cu" "F.Mask" "F.Paste")
			(net "P12V_NIC1_VIN_N")
		)
		(pad "13" smd rect
			(at 0.750062 -1.400048 90)
			(size 0.2286 0.6096)
			(layers "F.Cu" "F.Mask" "F.Paste")
			(net "P12V_NIC1_VIN_P")
		)
		(pad "14" smd rect
			(at 0.249936 -1.400048 90)
			(size 0.2286 0.6096)
			(layers "F.Cu" "F.Mask" "F.Paste")
			(net "Net_8657")
		)
		(pad "15" smd rect
			(at -0.249936 -1.400048 90)
			(size 0.2286 0.6096)
			(layers "F.Cu" "F.Mask" "F.Paste")
			(net "Net_8656")
		)
		(pad "16" smd rect
			(at -0.750062 -1.400048 90)
			(size 0.2286 0.6096)
			(layers "F.Cu" "F.Mask" "F.Paste")
			(net "Net_8655")
		)
		(pad "TH" smd rect
			(at 0 0 90)
			(size 1.7018 1.7018)
			(layers "F.Cu" "F.Mask" "F.Paste")
			(net "GND")
		)
		(zone
			(layer "F.Cu")
			(hatch none 0.5)
			(connect_pads
				(clearance 0)
			)
			(min_thickness 0.25)
			(keepout
				(tracks not_allowed)
				(vias allowed)
				(pads allowed)
				(copperpour not_allowed)
				(footprints allowed)
			)
			(placement
				(enabled no)
				(sheetname "")
			)
			(fill
				(thermal_gap 0.5)
				(thermal_bridge_width 0.5)
				(island_removal_mode 0)
			)
			(polygon
				(pts
					(xy 91.286584 -99.164902) (xy 90.267536 -99.164902) (xy 90.267536 -101.253798) (xy 92.356432 -101.253798)
					(xy 92.356432 -99.164902) (xy 91.311984 -99.164902) (xy 91.311984 -99.30765) (xy 92.213684 -99.30765)
					(xy 92.213684 -101.11105) (xy 90.410284 -101.11105) (xy 90.410284 -99.30765) (xy 91.286584 -99.30765)
				)
			)
		)
	)
	(footprint ""
		(layer "F.Cu")
		(at 164.920676 -70.307454 90)
		(property "Reference" "PC848"
			(at 0 0 90)
			(layer "F.SilkS")
			(hide yes)
			(effects
				(font
					(size 1.27 1.27)
				)
			)
		)
		(property "Value" ""
			(at 0 0 90)
			(layer "F.Fab")
			(effects
				(font
					(size 1.27 1.27)
				)
			)
		)
		(duplicate_pad_numbers_are_jumpers no)
		(fp_line
			(start 0.7874 -0.4064)
			(end 0.7874 0.4064)
			(stroke
				(width 0.1524)
				(type default)
			)
			(layer "F.SilkS")
		)
		(fp_line
			(start -0.7874 -0.4064)
			(end 0.7874 -0.4064)
			(stroke
				(width 0.1524)
				(type default)
			)
			(layer "F.SilkS")
		)
		(fp_line
			(start 0.7874 0.4064)
			(end -0.7874 0.4064)
			(stroke
				(width 0.1524)
				(type default)
			)
			(layer "F.SilkS")
		)
		(fp_line
			(start -0.7874 0.4064)
			(end -0.7874 -0.4064)
			(stroke
				(width 0.1524)
				(type default)
			)
			(layer "F.SilkS")
		)
		(fp_line
			(start -0.12065 -0.305054)
			(end -0.12065 -0.2794)
			(stroke
				(width 0.1)
				(type default)
			)
			(layer "F.Fab")
		)
		(fp_line
			(start -0.67945 -0.305054)
			(end -0.12065 -0.305054)
			(stroke
				(width 0.1)
				(type default)
			)
			(layer "F.Fab")
		)
		(fp_line
			(start 0.67945 -0.3048)
			(end 0.67945 0.3048)
			(stroke
				(width 0.1)
				(type default)
			)
			(layer "F.Fab")
		)
		(fp_line
			(start 0.12065 -0.3048)
			(end 0.67945 -0.3048)
			(stroke
				(width 0.1)
				(type default)
			)
			(layer "F.Fab")
		)
		(fp_line
			(start 0.12065 -0.2794)
			(end 0.12065 -0.3048)
			(stroke
				(width 0.1)
				(type default)
			)
			(layer "F.Fab")
		)
		(fp_line
			(start -0.12065 -0.2794)
			(end 0.12065 -0.2794)
			(stroke
				(width 0.1)
				(type default)
			)
			(layer "F.Fab")
		)
		(fp_line
			(start 0.120396 0.2794)
			(end -0.12065 0.2794)
			(stroke
				(width 0.1)
				(type default)
			)
			(layer "F.Fab")
		)
		(fp_line
			(start -0.12065 0.2794)
			(end -0.12065 0.3048)
			(stroke
				(width 0.1)
				(type default)
			)
			(layer "F.Fab")
		)
		(fp_line
			(start 0.67945 0.3048)
			(end 0.120396 0.3048)
			(stroke
				(width 0.1)
				(type default)
			)
			(layer "F.Fab")
		)
		(fp_line
			(start 0.120396 0.3048)
			(end 0.120396 0.2794)
			(stroke
				(width 0.1)
				(type default)
			)
			(layer "F.Fab")
		)
		(fp_line
			(start -0.12065 0.3048)
			(end -0.67945 0.3048)
			(stroke
				(width 0.1)
				(type default)
			)
			(layer "F.Fab")
		)
		(fp_line
			(start -0.67945 0.3048)
			(end -0.67945 -0.305054)
			(stroke
				(width 0.1)
				(type default)
			)
			(layer "F.Fab")
		)
		(pad "1" smd circle
			(at -0.40005 0 90)
			(size 0 0)
			(layers "F.Cu" "F.Mask" "F.Paste")
			(net "P12V_AUX")
		)
		(pad "2" smd circle
			(at 0.40005 0 90)
			(size 0 0)
			(layers "F.Cu" "F.Mask" "F.Paste")
			(net "GND")
		)
	)
	(footprint ""
		(layer "F.Cu")
		(at 136.33958 -152.71115 90)
		(property "Reference" "R703"
			(at 0 0 90)
			(layer "F.SilkS")
			(hide yes)
			(effects
				(font
					(size 1.27 1.27)
				)
			)
		)
		(property "Value" ""
			(at 0 0 90)
			(layer "F.Fab")
			(effects
				(font
					(size 1.27 1.27)
				)
			)
		)
		(duplicate_pad_numbers_are_jumpers no)
		(fp_line
			(start 0.7874 -0.4064)
			(end 0.7874 0.4064)
			(stroke
				(width 0.1524)
				(type default)
			)
			(layer "F.SilkS")
		)
		(fp_line
			(start -0.7874 -0.4064)
			(end 0.7874 -0.4064)
			(stroke
				(width 0.1524)
				(type default)
			)
			(layer "F.SilkS")
		)
		(fp_line
			(start 0.7874 0.4064)
			(end -0.7874 0.4064)
			(stroke
				(width 0.1524)
				(type default)
			)
			(layer "F.SilkS")
		)
		(fp_line
			(start -0.7874 0.4064)
			(end -0.7874 -0.4064)
			(stroke
				(width 0.1524)
				(type default)
			)
			(layer "F.SilkS")
		)
		(fp_line
			(start -0.12065 -0.305054)
			(end -0.12065 -0.2794)
			(stroke
				(width 0.1)
				(type default)
			)
			(layer "F.Fab")
		)
		(fp_line
			(start -0.67945 -0.305054)
			(end -0.12065 -0.305054)
			(stroke
				(width 0.1)
				(type default)
			)
			(layer "F.Fab")
		)
		(fp_line
			(start 0.67945 -0.3048)
			(end 0.67945 0.3048)
			(stroke
				(width 0.1)
				(type default)
			)
			(layer "F.Fab")
		)
		(fp_line
			(start 0.12065 -0.3048)
			(end 0.67945 -0.3048)
			(stroke
				(width 0.1)
				(type default)
			)
			(layer "F.Fab")
		)
		(fp_line
			(start 0.12065 -0.2794)
			(end 0.12065 -0.3048)
			(stroke
				(width 0.1)
				(type default)
			)
			(layer "F.Fab")
		)
		(fp_line
			(start -0.12065 -0.2794)
			(end 0.12065 -0.2794)
			(stroke
				(width 0.1)
				(type default)
			)
			(layer "F.Fab")
		)
		(fp_line
			(start 0.120396 0.2794)
			(end -0.12065 0.2794)
			(stroke
				(width 0.1)
				(type default)
			)
			(layer "F.Fab")
		)
		(fp_line
			(start -0.12065 0.2794)
			(end -0.12065 0.3048)
			(stroke
				(width 0.1)
				(type default)
			)
			(layer "F.Fab")
		)
		(fp_line
			(start 0.67945 0.3048)
			(end 0.120396 0.3048)
			(stroke
				(width 0.1)
				(type default)
			)
			(layer "F.Fab")
		)
		(fp_line
			(start 0.120396 0.3048)
			(end 0.120396 0.2794)
			(stroke
				(width 0.1)
				(type default)
			)
			(layer "F.Fab")
		)
		(fp_line
			(start -0.12065 0.3048)
			(end -0.67945 0.3048)
			(stroke
				(width 0.1)
				(type default)
			)
			(layer "F.Fab")
		)
		(fp_line
			(start -0.67945 0.3048)
			(end -0.67945 -0.305054)
			(stroke
				(width 0.1)
				(type default)
			)
			(layer "F.Fab")
		)
		(pad "1" smd circle
			(at -0.40005 0 90)
			(size 0 0)
			(layers "F.Cu" "F.Mask" "F.Paste")
			(net "NIC2_ADC_A0")
		)
		(pad "2" smd circle
			(at 0.40005 0 90)
			(size 0 0)
			(layers "F.Cu" "F.Mask" "F.Paste")
			(net "P3V3_AUX")
		)
	)
	(footprint ""
		(layer "F.Cu")
		(at 134.720076 -15.649956 180)
		(property "Reference" "H129"
			(at -2.106422 2.488184 0)
			(unlocked yes)
			(layer "B.SilkS")
			(effects
				(font
					(size 0.7874 0.5842)
					(thickness 0.1524)
				)
				(justify left mirror)
			)
		)
		(property "Value" ""
			(at 0 0 180)
			(layer "F.Fab")
			(effects
				(font
					(size 1.27 1.27)
				)
			)
		)
		(duplicate_pad_numbers_are_jumpers no)
		(pad "1" thru_hole rect
			(at 0 0 180)
			(size 4.2164 5.0038)
			(drill 2.0066
				(offset 0.099822 0)
			)
			(layers "*.Cu" "*.Mask")
			(remove_unused_layers no)
			(net "Net_8534")
			(clearance -0.8509)
			(padstack
				(mode front_inner_back)
				(layer "Inner"
					(shape circle)
					(size 4.0132 4.0132)
					(clearance -0.7493)
				)
				(layer "B.Cu"
					(shape circle)
					(size 4.0132 4.0132)
					(clearance -0.7493)
				)
			)
		)
	)
	(footprint ""
		(layer "F.Cu")
		(at 238.15929 -209.564478 -90)
		(property "Reference" "R476"
			(at 0 0 270)
			(layer "F.SilkS")
			(hide yes)
			(effects
				(font
					(size 1.27 1.27)
				)
			)
		)
		(property "Value" ""
			(at 0 0 270)
			(layer "F.Fab")
			(effects
				(font
					(size 1.27 1.27)
				)
			)
		)
		(duplicate_pad_numbers_are_jumpers no)
		(fp_line
			(start -0.7874 0.4064)
			(end -0.7874 -0.4064)
			(stroke
				(width 0.1524)
				(type default)
			)
			(layer "F.SilkS")
		)
		(fp_line
			(start 0.7874 0.4064)
			(end -0.7874 0.4064)
			(stroke
				(width 0.1524)
				(type default)
			)
			(layer "F.SilkS")
		)
		(fp_line
			(start -0.7874 -0.4064)
			(end 0.7874 -0.4064)
			(stroke
				(width 0.1524)
				(type default)
			)
			(layer "F.SilkS")
		)
		(fp_line
			(start 0.7874 -0.4064)
			(end 0.7874 0.4064)
			(stroke
				(width 0.1524)
				(type default)
			)
			(layer "F.SilkS")
		)
		(fp_line
			(start -0.67945 0.3048)
			(end -0.67945 -0.305054)
			(stroke
				(width 0.1)
				(type default)
			)
			(layer "F.Fab")
		)
		(fp_line
			(start -0.12065 0.3048)
			(end -0.67945 0.3048)
			(stroke
				(width 0.1)
				(type default)
			)
			(layer "F.Fab")
		)
		(fp_line
			(start 0.120396 0.3048)
			(end 0.120396 0.2794)
			(stroke
				(width 0.1)
				(type default)
			)
			(layer "F.Fab")
		)
		(fp_line
			(start 0.67945 0.3048)
			(end 0.120396 0.3048)
			(stroke
				(width 0.1)
				(type default)
			)
			(layer "F.Fab")
		)
		(fp_line
			(start -0.12065 0.2794)
			(end -0.12065 0.3048)
			(stroke
				(width 0.1)
				(type default)
			)
			(layer "F.Fab")
		)
		(fp_line
			(start 0.120396 0.2794)
			(end -0.12065 0.2794)
			(stroke
				(width 0.1)
				(type default)
			)
			(layer "F.Fab")
		)
		(fp_line
			(start -0.12065 -0.2794)
			(end 0.12065 -0.2794)
			(stroke
				(width 0.1)
				(type default)
			)
			(layer "F.Fab")
		)
		(fp_line
			(start 0.12065 -0.2794)
			(end 0.12065 -0.3048)
			(stroke
				(width 0.1)
				(type default)
			)
			(layer "F.Fab")
		)
		(fp_line
			(start 0.12065 -0.3048)
			(end 0.67945 -0.3048)
			(stroke
				(width 0.1)
				(type default)
			)
			(layer "F.Fab")
		)
		(fp_line
			(start 0.67945 -0.3048)
			(end 0.67945 0.3048)
			(stroke
				(width 0.1)
				(type default)
			)
			(layer "F.Fab")
		)
		(fp_line
			(start -0.67945 -0.305054)
			(end -0.12065 -0.305054)
			(stroke
				(width 0.1)
				(type default)
			)
			(layer "F.Fab")
		)
		(fp_line
			(start -0.12065 -0.305054)
			(end -0.12065 -0.2794)
			(stroke
				(width 0.1)
				(type default)
			)
			(layer "F.Fab")
		)
		(pad "1" smd circle
			(at -0.40005 0 270)
			(size 0 0)
			(layers "F.Cu" "F.Mask" "F.Paste")
			(net "P5V_AUX_SCALED")
		)
		(pad "2" smd circle
			(at 0.40005 0 270)
			(size 0 0)
			(layers "F.Cu" "F.Mask" "F.Paste")
			(net "GND")
		)
	)
	(footprint ""
		(layer "F.Cu")
		(at 224.022158 -83.659472 180)
		(property "Reference" "R4352"
			(at 0 0 180)
			(layer "F.SilkS")
			(hide yes)
			(effects
				(font
					(size 1.27 1.27)
				)
			)
		)
		(property "Value" ""
			(at 0 0 180)
			(layer "F.Fab")
			(effects
				(font
					(size 1.27 1.27)
				)
			)
		)
		(duplicate_pad_numbers_are_jumpers no)
		(fp_line
			(start 0.7874 0.4064)
			(end -0.7874 0.4064)
			(stroke
				(width 0.1524)
				(type default)
			)
			(layer "F.SilkS")
		)
		(fp_line
			(start 0.7874 -0.4064)
			(end 0.7874 0.4064)
			(stroke
				(width 0.1524)
				(type default)
			)
			(layer "F.SilkS")
		)
		(fp_line
			(start -0.7874 0.4064)
			(end -0.7874 -0.4064)
			(stroke
				(width 0.1524)
				(type default)
			)
			(layer "F.SilkS")
		)
		(fp_line
			(start -0.7874 -0.4064)
			(end 0.7874 -0.4064)
			(stroke
				(width 0.1524)
				(type default)
			)
			(layer "F.SilkS")
		)
		(fp_line
			(start 0.67945 0.3048)
			(end 0.120396 0.3048)
			(stroke
				(width 0.1)
				(type default)
			)
			(layer "F.Fab")
		)
		(fp_line
			(start 0.67945 -0.3048)
			(end 0.67945 0.3048)
			(stroke
				(width 0.1)
				(type default)
			)
			(layer "F.Fab")
		)
		(fp_line
			(start 0.12065 -0.2794)
			(end 0.12065 -0.3048)
			(stroke
				(width 0.1)
				(type default)
			)
			(layer "F.Fab")
		)
		(fp_line
			(start 0.12065 -0.3048)
			(end 0.67945 -0.3048)
			(stroke
				(width 0.1)
				(type default)
			)
			(layer "F.Fab")
		)
		(fp_line
			(start 0.120396 0.3048)
			(end 0.120396 0.2794)
			(stroke
				(width 0.1)
				(type default)
			)
			(layer "F.Fab")
		)
		(fp_line
			(start 0.120396 0.2794)
			(end -0.12065 0.2794)
			(stroke
				(width 0.1)
				(type default)
			)
			(layer "F.Fab")
		)
		(fp_line
			(start -0.12065 0.3048)
			(end -0.67945 0.3048)
			(stroke
				(width 0.1)
				(type default)
			)
			(layer "F.Fab")
		)
		(fp_line
			(start -0.12065 0.2794)
			(end -0.12065 0.3048)
			(stroke
				(width 0.1)
				(type default)
			)
			(layer "F.Fab")
		)
		(fp_line
			(start -0.12065 -0.2794)
			(end 0.12065 -0.2794)
			(stroke
				(width 0.1)
				(type default)
			)
			(layer "F.Fab")
		)
		(fp_line
			(start -0.12065 -0.305054)
			(end -0.12065 -0.2794)
			(stroke
				(width 0.1)
				(type default)
			)
			(layer "F.Fab")
		)
		(fp_line
			(start -0.67945 0.3048)
			(end -0.67945 -0.305054)
			(stroke
				(width 0.1)
				(type default)
			)
			(layer "F.Fab")
		)
		(fp_line
			(start -0.67945 -0.305054)
			(end -0.12065 -0.305054)
			(stroke
				(width 0.1)
				(type default)
			)
			(layer "F.Fab")
		)
		(pad "1" smd circle
			(at -0.40005 0 180)
			(size 0 0)
			(layers "F.Cu" "F.Mask" "F.Paste")
			(net "P3V3_AUX")
		)
		(pad "2" smd circle
			(at 0.40005 0 180)
			(size 0 0)
			(layers "F.Cu" "F.Mask" "F.Paste")
			(net "SSD14_LED_R")
		)
	)
	(footprint ""
		(layer "F.Cu")
		(at 397.967962 -19.453098)
		(property "Reference" "R1724"
			(at 0 0 0)
			(layer "F.SilkS")
			(hide yes)
			(effects
				(font
					(size 1.27 1.27)
				)
			)
		)
		(property "Value" ""
			(at 0 0 0)
			(layer "F.Fab")
			(effects
				(font
					(size 1.27 1.27)
				)
			)
		)
		(duplicate_pad_numbers_are_jumpers no)
		(fp_line
			(start -0.7874 -0.4064)
			(end 0.7874 -0.4064)
			(stroke
				(width 0.1524)
				(type default)
			)
			(layer "F.SilkS")
		)
		(fp_line
			(start -0.7874 0.4064)
			(end -0.7874 -0.4064)
			(stroke
				(width 0.1524)
				(type default)
			)
			(layer "F.SilkS")
		)
		(fp_line
			(start 0.7874 -0.4064)
			(end 0.7874 0.4064)
			(stroke
				(width 0.1524)
				(type default)
			)
			(layer "F.SilkS")
		)
		(fp_line
			(start 0.7874 0.4064)
			(end -0.7874 0.4064)
			(stroke
				(width 0.1524)
				(type default)
			)
			(layer "F.SilkS")
		)
		(fp_line
			(start -0.67945 -0.305054)
			(end -0.12065 -0.305054)
			(stroke
				(width 0.1)
				(type default)
			)
			(layer "F.Fab")
		)
		(fp_line
			(start -0.67945 0.3048)
			(end -0.67945 -0.305054)
			(stroke
				(width 0.1)
				(type default)
			)
			(layer "F.Fab")
		)
		(fp_line
			(start -0.12065 -0.305054)
			(end -0.12065 -0.2794)
			(stroke
				(width 0.1)
				(type default)
			)
			(layer "F.Fab")
		)
		(fp_line
			(start -0.12065 -0.2794)
			(end 0.12065 -0.2794)
			(stroke
				(width 0.1)
				(type default)
			)
			(layer "F.Fab")
		)
		(fp_line
			(start -0.12065 0.2794)
			(end -0.12065 0.3048)
			(stroke
				(width 0.1)
				(type default)
			)
			(layer "F.Fab")
		)
		(fp_line
			(start -0.12065 0.3048)
			(end -0.67945 0.3048)
			(stroke
				(width 0.1)
				(type default)
			)
			(layer "F.Fab")
		)
		(fp_line
			(start 0.120396 0.2794)
			(end -0.12065 0.2794)
			(stroke
				(width 0.1)
				(type default)
			)
			(layer "F.Fab")
		)
		(fp_line
			(start 0.120396 0.3048)
			(end 0.120396 0.2794)
			(stroke
				(width 0.1)
				(type default)
			)
			(layer "F.Fab")
		)
		(fp_line
			(start 0.12065 -0.3048)
			(end 0.67945 -0.3048)
			(stroke
				(width 0.1)
				(type default)
			)
			(layer "F.Fab")
		)
		(fp_line
			(start 0.12065 -0.2794)
			(end 0.12065 -0.3048)
			(stroke
				(width 0.1)
				(type default)
			)
			(layer "F.Fab")
		)
		(fp_line
			(start 0.67945 -0.3048)
			(end 0.67945 0.3048)
			(stroke
				(width 0.1)
				(type default)
			)
			(layer "F.Fab")
		)
		(fp_line
			(start 0.67945 0.3048)
			(end 0.120396 0.3048)
			(stroke
				(width 0.1)
				(type default)
			)
			(layer "F.Fab")
		)
		(pad "1" smd circle
			(at -0.40005 0)
			(size 0 0)
			(layers "F.Cu" "F.Mask" "F.Paste")
			(net "SMB_ISO_SSD13_R_SDA")
		)
		(pad "2" smd circle
			(at 0.40005 0)
			(size 0 0)
			(layers "F.Cu" "F.Mask" "F.Paste")
			(net "SMB_ISO_SSD13_SDA")
		)
	)
	(footprint ""
		(layer "F.Cu")
		(at 9.62914 -311.76087 180)
		(property "Reference" "PC208"
			(at 0 0 180)
			(layer "F.SilkS")
			(hide yes)
			(effects
				(font
					(size 1.27 1.27)
				)
			)
		)
		(property "Value" ""
			(at 0 0 180)
			(layer "F.Fab")
			(effects
				(font
					(size 1.27 1.27)
				)
			)
		)
		(duplicate_pad_numbers_are_jumpers no)
		(fp_line
			(start 1.524 0.762)
			(end -1.524 0.762)
			(stroke
				(width 0.1524)
				(type default)
			)
			(layer "F.SilkS")
		)
		(fp_line
			(start 1.524 -0.762)
			(end 1.524 0.762)
			(stroke
				(width 0.1524)
				(type default)
			)
			(layer "F.SilkS")
		)
		(fp_line
			(start -1.524 0.762)
			(end -1.524 -0.762)
			(stroke
				(width 0.1524)
				(type default)
			)
			(layer "F.SilkS")
		)
		(fp_line
			(start -1.524 -0.762)
			(end 1.524 -0.762)
			(stroke
				(width 0.1524)
				(type default)
			)
			(layer "F.SilkS")
		)
		(fp_line
			(start 1.1049 0.724916)
			(end 1.1049 -0.724916)
			(stroke
				(width 0.1)
				(type default)
			)
			(layer "F.Fab")
		)
		(fp_line
			(start 1.1049 -0.724916)
			(end -1.1049 -0.724916)
			(stroke
				(width 0.1)
				(type default)
			)
			(layer "F.Fab")
		)
		(fp_line
			(start -1.1049 0.724916)
			(end 1.1049 0.724916)
			(stroke
				(width 0.1)
				(type default)
			)
			(layer "F.Fab")
		)
		(fp_line
			(start -1.1049 -0.724916)
			(end -1.1049 0.724916)
			(stroke
				(width 0.1)
				(type default)
			)
			(layer "F.Fab")
		)
		(pad "1" smd rect
			(at -0.889 0)
			(size 1.016 1.27)
			(layers "F.Cu" "F.Mask" "F.Paste")
			(net "SW_P12V_P1V25_PEX0_FLT")
		)
		(pad "2" smd rect
			(at 0.889 0)
			(size 1.016 1.27)
			(layers "F.Cu" "F.Mask" "F.Paste")
			(net "GND")
		)
	)
	(footprint ""
		(layer "F.Cu")
		(at 119.225314 -117.313456)
		(property "Reference" "PC593"
			(at 0 0 0)
			(layer "F.SilkS")
			(hide yes)
			(effects
				(font
					(size 1.27 1.27)
				)
			)
		)
		(property "Value" ""
			(at 0 0 0)
			(layer "F.Fab")
			(effects
				(font
					(size 1.27 1.27)
				)
			)
		)
		(duplicate_pad_numbers_are_jumpers no)
		(fp_line
			(start -0.7874 -0.4064)
			(end 0.7874 -0.4064)
			(stroke
				(width 0.1524)
				(type default)
			)
			(layer "F.SilkS")
		)
		(fp_line
			(start -0.7874 0.4064)
			(end -0.7874 -0.4064)
			(stroke
				(width 0.1524)
				(type default)
			)
			(layer "F.SilkS")
		)
		(fp_line
			(start 0.7874 -0.4064)
			(end 0.7874 0.4064)
			(stroke
				(width 0.1524)
				(type default)
			)
			(layer "F.SilkS")
		)
		(fp_line
			(start 0.7874 0.4064)
			(end -0.7874 0.4064)
			(stroke
				(width 0.1524)
				(type default)
			)
			(layer "F.SilkS")
		)
		(fp_line
			(start -0.67945 -0.305054)
			(end -0.12065 -0.305054)
			(stroke
				(width 0.1)
				(type default)
			)
			(layer "F.Fab")
		)
		(fp_line
			(start -0.67945 0.3048)
			(end -0.67945 -0.305054)
			(stroke
				(width 0.1)
				(type default)
			)
			(layer "F.Fab")
		)
		(fp_line
			(start -0.12065 -0.305054)
			(end -0.12065 -0.2794)
			(stroke
				(width 0.1)
				(type default)
			)
			(layer "F.Fab")
		)
		(fp_line
			(start -0.12065 -0.2794)
			(end 0.12065 -0.2794)
			(stroke
				(width 0.1)
				(type default)
			)
			(layer "F.Fab")
		)
		(fp_line
			(start -0.12065 0.2794)
			(end -0.12065 0.3048)
			(stroke
				(width 0.1)
				(type default)
			)
			(layer "F.Fab")
		)
		(fp_line
			(start -0.12065 0.3048)
			(end -0.67945 0.3048)
			(stroke
				(width 0.1)
				(type default)
			)
			(layer "F.Fab")
		)
		(fp_line
			(start 0.120396 0.2794)
			(end -0.12065 0.2794)
			(stroke
				(width 0.1)
				(type default)
			)
			(layer "F.Fab")
		)
		(fp_line
			(start 0.120396 0.3048)
			(end 0.120396 0.2794)
			(stroke
				(width 0.1)
				(type default)
			)
			(layer "F.Fab")
		)
		(fp_line
			(start 0.12065 -0.3048)
			(end 0.67945 -0.3048)
			(stroke
				(width 0.1)
				(type default)
			)
			(layer "F.Fab")
		)
		(fp_line
			(start 0.12065 -0.2794)
			(end 0.12065 -0.3048)
			(stroke
				(width 0.1)
				(type default)
			)
			(layer "F.Fab")
		)
		(fp_line
			(start 0.67945 -0.3048)
			(end 0.67945 0.3048)
			(stroke
				(width 0.1)
				(type default)
			)
			(layer "F.Fab")
		)
		(fp_line
			(start 0.67945 0.3048)
			(end 0.120396 0.3048)
			(stroke
				(width 0.1)
				(type default)
			)
			(layer "F.Fab")
		)
		(pad "1" smd circle
			(at -0.40005 0)
			(size 0 0)
			(layers "F.Cu" "F.Mask" "F.Paste")
			(net "P3V3_AUX")
		)
		(pad "2" smd circle
			(at 0.40005 0)
			(size 0 0)
			(layers "F.Cu" "F.Mask" "F.Paste")
			(net "GND")
		)
	)
	(footprint ""
		(layer "F.Cu")
		(at 368.55527 -35.876738)
		(property "Reference" "R6105"
			(at 0 0 0)
			(layer "F.SilkS")
			(hide yes)
			(effects
				(font
					(size 1.27 1.27)
				)
			)
		)
		(property "Value" ""
			(at 0 0 0)
			(layer "F.Fab")
			(effects
				(font
					(size 1.27 1.27)
				)
			)
		)
		(duplicate_pad_numbers_are_jumpers no)
		(fp_line
			(start -0.7874 -0.4064)
			(end 0.7874 -0.4064)
			(stroke
				(width 0.1524)
				(type default)
			)
			(layer "F.SilkS")
		)
		(fp_line
			(start -0.7874 0.4064)
			(end -0.7874 -0.4064)
			(stroke
				(width 0.1524)
				(type default)
			)
			(layer "F.SilkS")
		)
		(fp_line
			(start 0.7874 -0.4064)
			(end 0.7874 0.4064)
			(stroke
				(width 0.1524)
				(type default)
			)
			(layer "F.SilkS")
		)
		(fp_line
			(start 0.7874 0.4064)
			(end -0.7874 0.4064)
			(stroke
				(width 0.1524)
				(type default)
			)
			(layer "F.SilkS")
		)
		(fp_line
			(start -0.67945 -0.305054)
			(end -0.12065 -0.305054)
			(stroke
				(width 0.1)
				(type default)
			)
			(layer "F.Fab")
		)
		(fp_line
			(start -0.67945 0.3048)
			(end -0.67945 -0.305054)
			(stroke
				(width 0.1)
				(type default)
			)
			(layer "F.Fab")
		)
		(fp_line
			(start -0.12065 -0.305054)
			(end -0.12065 -0.2794)
			(stroke
				(width 0.1)
				(type default)
			)
			(layer "F.Fab")
		)
		(fp_line
			(start -0.12065 -0.2794)
			(end 0.12065 -0.2794)
			(stroke
				(width 0.1)
				(type default)
			)
			(layer "F.Fab")
		)
		(fp_line
			(start -0.12065 0.2794)
			(end -0.12065 0.3048)
			(stroke
				(width 0.1)
				(type default)
			)
			(layer "F.Fab")
		)
		(fp_line
			(start -0.12065 0.3048)
			(end -0.67945 0.3048)
			(stroke
				(width 0.1)
				(type default)
			)
			(layer "F.Fab")
		)
		(fp_line
			(start 0.120396 0.2794)
			(end -0.12065 0.2794)
			(stroke
				(width 0.1)
				(type default)
			)
			(layer "F.Fab")
		)
		(fp_line
			(start 0.120396 0.3048)
			(end 0.120396 0.2794)
			(stroke
				(width 0.1)
				(type default)
			)
			(layer "F.Fab")
		)
		(fp_line
			(start 0.12065 -0.3048)
			(end 0.67945 -0.3048)
			(stroke
				(width 0.1)
				(type default)
			)
			(layer "F.Fab")
		)
		(fp_line
			(start 0.12065 -0.2794)
			(end 0.12065 -0.3048)
			(stroke
				(width 0.1)
				(type default)
			)
			(layer "F.Fab")
		)
		(fp_line
			(start 0.67945 -0.3048)
			(end 0.67945 0.3048)
			(stroke
				(width 0.1)
				(type default)
			)
			(layer "F.Fab")
		)
		(fp_line
			(start 0.67945 0.3048)
			(end 0.120396 0.3048)
			(stroke
				(width 0.1)
				(type default)
			)
			(layer "F.Fab")
		)
		(pad "1" smd circle
			(at -0.40005 0)
			(size 0 0)
			(layers "F.Cu" "F.Mask" "F.Paste")
			(net "P3V3_AUX")
		)
		(pad "2" smd circle
			(at 0.40005 0)
			(size 0 0)
			(layers "F.Cu" "F.Mask" "F.Paste")
			(net "PWRGD_P3V3_SSD13_D")
		)
	)
	(footprint ""
		(layer "F.Cu")
		(at 17.853914 -413.969708 90)
		(property "Reference" "R5594"
			(at 0 0 90)
			(layer "F.SilkS")
			(hide yes)
			(effects
				(font
					(size 1.27 1.27)
				)
			)
		)
		(property "Value" ""
			(at 0 0 90)
			(layer "F.Fab")
			(effects
				(font
					(size 1.27 1.27)
				)
			)
		)
		(duplicate_pad_numbers_are_jumpers no)
		(fp_line
			(start 0.7874 -0.4064)
			(end 0.7874 0.4064)
			(stroke
				(width 0.1524)
				(type default)
			)
			(layer "F.SilkS")
		)
		(fp_line
			(start -0.7874 -0.4064)
			(end 0.7874 -0.4064)
			(stroke
				(width 0.1524)
				(type default)
			)
			(layer "F.SilkS")
		)
		(fp_line
			(start 0.7874 0.4064)
			(end -0.7874 0.4064)
			(stroke
				(width 0.1524)
				(type default)
			)
			(layer "F.SilkS")
		)
		(fp_line
			(start -0.7874 0.4064)
			(end -0.7874 -0.4064)
			(stroke
				(width 0.1524)
				(type default)
			)
			(layer "F.SilkS")
		)
		(fp_line
			(start -0.12065 -0.305054)
			(end -0.12065 -0.2794)
			(stroke
				(width 0.1)
				(type default)
			)
			(layer "F.Fab")
		)
		(fp_line
			(start -0.67945 -0.305054)
			(end -0.12065 -0.305054)
			(stroke
				(width 0.1)
				(type default)
			)
			(layer "F.Fab")
		)
		(fp_line
			(start 0.67945 -0.3048)
			(end 0.67945 0.3048)
			(stroke
				(width 0.1)
				(type default)
			)
			(layer "F.Fab")
		)
		(fp_line
			(start 0.12065 -0.3048)
			(end 0.67945 -0.3048)
			(stroke
				(width 0.1)
				(type default)
			)
			(layer "F.Fab")
		)
		(fp_line
			(start 0.12065 -0.2794)
			(end 0.12065 -0.3048)
			(stroke
				(width 0.1)
				(type default)
			)
			(layer "F.Fab")
		)
		(fp_line
			(start -0.12065 -0.2794)
			(end 0.12065 -0.2794)
			(stroke
				(width 0.1)
				(type default)
			)
			(layer "F.Fab")
		)
		(fp_line
			(start 0.120396 0.2794)
			(end -0.12065 0.2794)
			(stroke
				(width 0.1)
				(type default)
			)
			(layer "F.Fab")
		)
		(fp_line
			(start -0.12065 0.2794)
			(end -0.12065 0.3048)
			(stroke
				(width 0.1)
				(type default)
			)
			(layer "F.Fab")
		)
		(fp_line
			(start 0.67945 0.3048)
			(end 0.120396 0.3048)
			(stroke
				(width 0.1)
				(type default)
			)
			(layer "F.Fab")
		)
		(fp_line
			(start 0.120396 0.3048)
			(end 0.120396 0.2794)
			(stroke
				(width 0.1)
				(type default)
			)
			(layer "F.Fab")
		)
		(fp_line
			(start -0.12065 0.3048)
			(end -0.67945 0.3048)
			(stroke
				(width 0.1)
				(type default)
			)
			(layer "F.Fab")
		)
		(fp_line
			(start -0.67945 0.3048)
			(end -0.67945 -0.305054)
			(stroke
				(width 0.1)
				(type default)
			)
			(layer "F.Fab")
		)
		(pad "1" smd circle
			(at -0.40005 0 90)
			(size 0 0)
			(layers "F.Cu" "F.Mask" "F.Paste")
			(net "LM75_0_A0")
		)
		(pad "2" smd circle
			(at 0.40005 0 90)
			(size 0 0)
			(layers "F.Cu" "F.Mask" "F.Paste")
			(net "P3V3_AUX")
		)
	)
	(footprint ""
		(layer "F.Cu")
		(at 452.759318 -22.955504 90)
		(property "Reference" "R1742"
			(at 0 0 90)
			(layer "F.SilkS")
			(hide yes)
			(effects
				(font
					(size 1.27 1.27)
				)
			)
		)
		(property "Value" ""
			(at 0 0 90)
			(layer "F.Fab")
			(effects
				(font
					(size 1.27 1.27)
				)
			)
		)
		(duplicate_pad_numbers_are_jumpers no)
		(fp_line
			(start 0.7874 -0.4064)
			(end 0.7874 0.4064)
			(stroke
				(width 0.1524)
				(type default)
			)
			(layer "F.SilkS")
		)
		(fp_line
			(start -0.7874 -0.4064)
			(end 0.7874 -0.4064)
			(stroke
				(width 0.1524)
				(type default)
			)
			(layer "F.SilkS")
		)
		(fp_line
			(start 0.7874 0.4064)
			(end -0.7874 0.4064)
			(stroke
				(width 0.1524)
				(type default)
			)
			(layer "F.SilkS")
		)
		(fp_line
			(start -0.7874 0.4064)
			(end -0.7874 -0.4064)
			(stroke
				(width 0.1524)
				(type default)
			)
			(layer "F.SilkS")
		)
		(fp_line
			(start -0.12065 -0.305054)
			(end -0.12065 -0.2794)
			(stroke
				(width 0.1)
				(type default)
			)
			(layer "F.Fab")
		)
		(fp_line
			(start -0.67945 -0.305054)
			(end -0.12065 -0.305054)
			(stroke
				(width 0.1)
				(type default)
			)
			(layer "F.Fab")
		)
		(fp_line
			(start 0.67945 -0.3048)
			(end 0.67945 0.3048)
			(stroke
				(width 0.1)
				(type default)
			)
			(layer "F.Fab")
		)
		(fp_line
			(start 0.12065 -0.3048)
			(end 0.67945 -0.3048)
			(stroke
				(width 0.1)
				(type default)
			)
			(layer "F.Fab")
		)
		(fp_line
			(start 0.12065 -0.2794)
			(end 0.12065 -0.3048)
			(stroke
				(width 0.1)
				(type default)
			)
			(layer "F.Fab")
		)
		(fp_line
			(start -0.12065 -0.2794)
			(end 0.12065 -0.2794)
			(stroke
				(width 0.1)
				(type default)
			)
			(layer "F.Fab")
		)
		(fp_line
			(start 0.120396 0.2794)
			(end -0.12065 0.2794)
			(stroke
				(width 0.1)
				(type default)
			)
			(layer "F.Fab")
		)
		(fp_line
			(start -0.12065 0.2794)
			(end -0.12065 0.3048)
			(stroke
				(width 0.1)
				(type default)
			)
			(layer "F.Fab")
		)
		(fp_line
			(start 0.67945 0.3048)
			(end 0.120396 0.3048)
			(stroke
				(width 0.1)
				(type default)
			)
			(layer "F.Fab")
		)
		(fp_line
			(start 0.120396 0.3048)
			(end 0.120396 0.2794)
			(stroke
				(width 0.1)
				(type default)
			)
			(layer "F.Fab")
		)
		(fp_line
			(start -0.12065 0.3048)
			(end -0.67945 0.3048)
			(stroke
				(width 0.1)
				(type default)
			)
			(layer "F.Fab")
		)
		(fp_line
			(start -0.67945 0.3048)
			(end -0.67945 -0.305054)
			(stroke
				(width 0.1)
				(type default)
			)
			(layer "F.Fab")
		)
		(pad "1" smd circle
			(at -0.40005 0 90)
			(size 0 0)
			(layers "F.Cu" "F.Mask" "F.Paste")
			(net "SMB_BIC_I2C9_MUX1_SSD15_R_SCL")
		)
		(pad "2" smd circle
			(at 0.40005 0 90)
			(size 0 0)
			(layers "F.Cu" "F.Mask" "F.Paste")
			(net "SMB_ISO_SSD15_SCL")
		)
	)
	(footprint ""
		(layer "F.Cu")
		(at 349.123 -234.061 -90)
		(property "Reference" "R3583"
			(at 0 0 270)
			(layer "F.SilkS")
			(hide yes)
			(effects
				(font
					(size 1.27 1.27)
				)
			)
		)
		(property "Value" ""
			(at 0 0 270)
			(layer "F.Fab")
			(effects
				(font
					(size 1.27 1.27)
				)
			)
		)
		(duplicate_pad_numbers_are_jumpers no)
		(fp_line
			(start -0.7874 0.4064)
			(end -0.7874 -0.4064)
			(stroke
				(width 0.1524)
				(type default)
			)
			(layer "F.SilkS")
		)
		(fp_line
			(start 0.7874 0.4064)
			(end -0.7874 0.4064)
			(stroke
				(width 0.1524)
				(type default)
			)
			(layer "F.SilkS")
		)
		(fp_line
			(start -0.7874 -0.4064)
			(end 0.7874 -0.4064)
			(stroke
				(width 0.1524)
				(type default)
			)
			(layer "F.SilkS")
		)
		(fp_line
			(start 0.7874 -0.4064)
			(end 0.7874 0.4064)
			(stroke
				(width 0.1524)
				(type default)
			)
			(layer "F.SilkS")
		)
		(fp_line
			(start -0.67945 0.3048)
			(end -0.67945 -0.305054)
			(stroke
				(width 0.1)
				(type default)
			)
			(layer "F.Fab")
		)
		(fp_line
			(start -0.12065 0.3048)
			(end -0.67945 0.3048)
			(stroke
				(width 0.1)
				(type default)
			)
			(layer "F.Fab")
		)
		(fp_line
			(start 0.120396 0.3048)
			(end 0.120396 0.2794)
			(stroke
				(width 0.1)
				(type default)
			)
			(layer "F.Fab")
		)
		(fp_line
			(start 0.67945 0.3048)
			(end 0.120396 0.3048)
			(stroke
				(width 0.1)
				(type default)
			)
			(layer "F.Fab")
		)
		(fp_line
			(start -0.12065 0.2794)
			(end -0.12065 0.3048)
			(stroke
				(width 0.1)
				(type default)
			)
			(layer "F.Fab")
		)
		(fp_line
			(start 0.120396 0.2794)
			(end -0.12065 0.2794)
			(stroke
				(width 0.1)
				(type default)
			)
			(layer "F.Fab")
		)
		(fp_line
			(start -0.12065 -0.2794)
			(end 0.12065 -0.2794)
			(stroke
				(width 0.1)
				(type default)
			)
			(layer "F.Fab")
		)
		(fp_line
			(start 0.12065 -0.2794)
			(end 0.12065 -0.3048)
			(stroke
				(width 0.1)
				(type default)
			)
			(layer "F.Fab")
		)
		(fp_line
			(start 0.12065 -0.3048)
			(end 0.67945 -0.3048)
			(stroke
				(width 0.1)
				(type default)
			)
			(layer "F.Fab")
		)
		(fp_line
			(start 0.67945 -0.3048)
			(end 0.67945 0.3048)
			(stroke
				(width 0.1)
				(type default)
			)
			(layer "F.Fab")
		)
		(fp_line
			(start -0.67945 -0.305054)
			(end -0.12065 -0.305054)
			(stroke
				(width 0.1)
				(type default)
			)
			(layer "F.Fab")
		)
		(fp_line
			(start -0.12065 -0.305054)
			(end -0.12065 -0.2794)
			(stroke
				(width 0.1)
				(type default)
			)
			(layer "F.Fab")
		)
		(pad "1" smd circle
			(at -0.40005 0 270)
			(size 0 0)
			(layers "F.Cu" "F.Mask" "F.Paste")
			(net "SSD6_CLK_EN_R_N")
		)
		(pad "2" smd circle
			(at 0.40005 0 270)
			(size 0 0)
			(layers "F.Cu" "F.Mask" "F.Paste")
			(net "SSD6_CLK_EN_N")
		)
	)
	(footprint ""
		(layer "F.Cu")
		(at 26.243788 -47.92091)
		(property "Reference" "R504"
			(at 0 0 0)
			(layer "F.SilkS")
			(hide yes)
			(effects
				(font
					(size 1.27 1.27)
				)
			)
		)
		(property "Value" ""
			(at 0 0 0)
			(layer "F.Fab")
			(effects
				(font
					(size 1.27 1.27)
				)
			)
		)
		(duplicate_pad_numbers_are_jumpers no)
		(fp_line
			(start -0.7874 -0.4064)
			(end 0.7874 -0.4064)
			(stroke
				(width 0.1524)
				(type default)
			)
			(layer "F.SilkS")
		)
		(fp_line
			(start -0.7874 0.4064)
			(end -0.7874 -0.4064)
			(stroke
				(width 0.1524)
				(type default)
			)
			(layer "F.SilkS")
		)
		(fp_line
			(start 0.7874 -0.4064)
			(end 0.7874 0.4064)
			(stroke
				(width 0.1524)
				(type default)
			)
			(layer "F.SilkS")
		)
		(fp_line
			(start 0.7874 0.4064)
			(end -0.7874 0.4064)
			(stroke
				(width 0.1524)
				(type default)
			)
			(layer "F.SilkS")
		)
		(fp_line
			(start -0.67945 -0.305054)
			(end -0.12065 -0.305054)
			(stroke
				(width 0.1)
				(type default)
			)
			(layer "F.Fab")
		)
		(fp_line
			(start -0.67945 0.3048)
			(end -0.67945 -0.305054)
			(stroke
				(width 0.1)
				(type default)
			)
			(layer "F.Fab")
		)
		(fp_line
			(start -0.12065 -0.305054)
			(end -0.12065 -0.2794)
			(stroke
				(width 0.1)
				(type default)
			)
			(layer "F.Fab")
		)
		(fp_line
			(start -0.12065 -0.2794)
			(end 0.12065 -0.2794)
			(stroke
				(width 0.1)
				(type default)
			)
			(layer "F.Fab")
		)
		(fp_line
			(start -0.12065 0.2794)
			(end -0.12065 0.3048)
			(stroke
				(width 0.1)
				(type default)
			)
			(layer "F.Fab")
		)
		(fp_line
			(start -0.12065 0.3048)
			(end -0.67945 0.3048)
			(stroke
				(width 0.1)
				(type default)
			)
			(layer "F.Fab")
		)
		(fp_line
			(start 0.120396 0.2794)
			(end -0.12065 0.2794)
			(stroke
				(width 0.1)
				(type default)
			)
			(layer "F.Fab")
		)
		(fp_line
			(start 0.120396 0.3048)
			(end 0.120396 0.2794)
			(stroke
				(width 0.1)
				(type default)
			)
			(layer "F.Fab")
		)
		(fp_line
			(start 0.12065 -0.3048)
			(end 0.67945 -0.3048)
			(stroke
				(width 0.1)
				(type default)
			)
			(layer "F.Fab")
		)
		(fp_line
			(start 0.12065 -0.2794)
			(end 0.12065 -0.3048)
			(stroke
				(width 0.1)
				(type default)
			)
			(layer "F.Fab")
		)
		(fp_line
			(start 0.67945 -0.3048)
			(end 0.67945 0.3048)
			(stroke
				(width 0.1)
				(type default)
			)
			(layer "F.Fab")
		)
		(fp_line
			(start 0.67945 0.3048)
			(end 0.120396 0.3048)
			(stroke
				(width 0.1)
				(type default)
			)
			(layer "F.Fab")
		)
		(pad "1" smd circle
			(at -0.40005 0)
			(size 0 0)
			(layers "F.Cu" "F.Mask" "F.Paste")
			(net "P3V3_AUX")
		)
		(pad "2" smd circle
			(at 0.40005 0)
			(size 0 0)
			(layers "F.Cu" "F.Mask" "F.Paste")
			(net "SSD_0_7_ADC_ALERT_N")
		)
	)
	(footprint ""
		(layer "F.Cu")
		(at 369.495578 -83.784694 180)
		(property "Reference" "R1604"
			(at 0 0 180)
			(layer "F.SilkS")
			(hide yes)
			(effects
				(font
					(size 1.27 1.27)
				)
			)
		)
		(property "Value" ""
			(at 0 0 180)
			(layer "F.Fab")
			(effects
				(font
					(size 1.27 1.27)
				)
			)
		)
		(duplicate_pad_numbers_are_jumpers no)
		(fp_line
			(start 0.7874 0.4064)
			(end -0.7874 0.4064)
			(stroke
				(width 0.1524)
				(type default)
			)
			(layer "F.SilkS")
		)
		(fp_line
			(start 0.7874 -0.4064)
			(end 0.7874 0.4064)
			(stroke
				(width 0.1524)
				(type default)
			)
			(layer "F.SilkS")
		)
		(fp_line
			(start -0.7874 0.4064)
			(end -0.7874 -0.4064)
			(stroke
				(width 0.1524)
				(type default)
			)
			(layer "F.SilkS")
		)
		(fp_line
			(start -0.7874 -0.4064)
			(end 0.7874 -0.4064)
			(stroke
				(width 0.1524)
				(type default)
			)
			(layer "F.SilkS")
		)
		(fp_line
			(start 0.67945 0.3048)
			(end 0.120396 0.3048)
			(stroke
				(width 0.1)
				(type default)
			)
			(layer "F.Fab")
		)
		(fp_line
			(start 0.67945 -0.3048)
			(end 0.67945 0.3048)
			(stroke
				(width 0.1)
				(type default)
			)
			(layer "F.Fab")
		)
		(fp_line
			(start 0.12065 -0.2794)
			(end 0.12065 -0.3048)
			(stroke
				(width 0.1)
				(type default)
			)
			(layer "F.Fab")
		)
		(fp_line
			(start 0.12065 -0.3048)
			(end 0.67945 -0.3048)
			(stroke
				(width 0.1)
				(type default)
			)
			(layer "F.Fab")
		)
		(fp_line
			(start 0.120396 0.3048)
			(end 0.120396 0.2794)
			(stroke
				(width 0.1)
				(type default)
			)
			(layer "F.Fab")
		)
		(fp_line
			(start 0.120396 0.2794)
			(end -0.12065 0.2794)
			(stroke
				(width 0.1)
				(type default)
			)
			(layer "F.Fab")
		)
		(fp_line
			(start -0.12065 0.3048)
			(end -0.67945 0.3048)
			(stroke
				(width 0.1)
				(type default)
			)
			(layer "F.Fab")
		)
		(fp_line
			(start -0.12065 0.2794)
			(end -0.12065 0.3048)
			(stroke
				(width 0.1)
				(type default)
			)
			(layer "F.Fab")
		)
		(fp_line
			(start -0.12065 -0.2794)
			(end 0.12065 -0.2794)
			(stroke
				(width 0.1)
				(type default)
			)
			(layer "F.Fab")
		)
		(fp_line
			(start -0.12065 -0.305054)
			(end -0.12065 -0.2794)
			(stroke
				(width 0.1)
				(type default)
			)
			(layer "F.Fab")
		)
		(fp_line
			(start -0.67945 0.3048)
			(end -0.67945 -0.305054)
			(stroke
				(width 0.1)
				(type default)
			)
			(layer "F.Fab")
		)
		(fp_line
			(start -0.67945 -0.305054)
			(end -0.12065 -0.305054)
			(stroke
				(width 0.1)
				(type default)
			)
			(layer "F.Fab")
		)
		(pad "1" smd circle
			(at -0.40005 0 180)
			(size 0 0)
			(layers "F.Cu" "F.Mask" "F.Paste")
			(net "P3V3_AUX")
		)
		(pad "2" smd circle
			(at 0.40005 0 180)
			(size 0 0)
			(layers "F.Cu" "F.Mask" "F.Paste")
			(net "SMB_BIC_I2C9_MUX1_SSD13_R_SDA")
		)
	)
	(footprint ""
		(layer "F.Cu")
		(at 320.354452 -222.119698 180)
		(property "Reference" "D16"
			(at 3.743452 0.103632 0)
			(unlocked yes)
			(layer "F.SilkS")
			(effects
				(font
					(size 0.7874 0.5842)
					(thickness 0.1524)
				)
				(justify left)
			)
		)
		(property "Value" ""
			(at 0 0 180)
			(layer "F.Fab")
			(effects
				(font
					(size 1.27 1.27)
				)
			)
		)
		(duplicate_pad_numbers_are_jumpers no)
		(fp_line
			(start 1.16078 0.4826)
			(end -0.64008 0.4826)
			(stroke
				(width 0.1524)
				(type default)
			)
			(layer "F.SilkS")
		)
		(fp_line
			(start 1.16078 -0.4826)
			(end 1.16078 0.4826)
			(stroke
				(width 0.1524)
				(type default)
			)
			(layer "F.SilkS")
		)
		(fp_line
			(start 1.03378 0.4826)
			(end -0.79248 0.4826)
			(stroke
				(width 0.1524)
				(type default)
			)
			(layer "F.SilkS")
		)
		(fp_line
			(start 1.03378 -0.4826)
			(end 1.03378 0.4826)
			(stroke
				(width 0.1524)
				(type default)
			)
			(layer "F.SilkS")
		)
		(fp_line
			(start 0.90678 0.4826)
			(end -0.90678 0.4826)
			(stroke
				(width 0.1524)
				(type default)
			)
			(layer "F.SilkS")
		)
		(fp_line
			(start 0.90678 -0.4826)
			(end 0.90678 0.4826)
			(stroke
				(width 0.1524)
				(type default)
			)
			(layer "F.SilkS")
		)
		(fp_line
			(start -0.64008 -0.4826)
			(end 1.16078 -0.4826)
			(stroke
				(width 0.1524)
				(type default)
			)
			(layer "F.SilkS")
		)
		(fp_line
			(start -0.79248 -0.4826)
			(end 1.03378 -0.4826)
			(stroke
				(width 0.1524)
				(type default)
			)
			(layer "F.SilkS")
		)
		(fp_line
			(start -0.89408 -0.4826)
			(end 0.90678 -0.4826)
			(stroke
				(width 0.1524)
				(type default)
			)
			(layer "F.SilkS")
		)
		(fp_line
			(start -0.90678 0.4826)
			(end -0.90678 -0.4699)
			(stroke
				(width 0.1524)
				(type default)
			)
			(layer "F.SilkS")
		)
		(fp_line
			(start 0.499872 0.249936)
			(end -0.499872 0.249936)
			(stroke
				(width 0.1)
				(type default)
			)
			(layer "F.Fab")
		)
		(fp_line
			(start 0.499872 -0.249936)
			(end 0.499872 0.249936)
			(stroke
				(width 0.1)
				(type default)
			)
			(layer "F.Fab")
		)
		(fp_line
			(start -0.499872 0.249936)
			(end -0.499872 -0.249936)
			(stroke
				(width 0.1)
				(type default)
			)
			(layer "F.Fab")
		)
		(fp_line
			(start -0.499872 -0.249936)
			(end 0.499872 -0.249936)
			(stroke
				(width 0.1)
				(type default)
			)
			(layer "F.Fab")
		)
		(pad "A" smd rect
			(at -0.47498 0 180)
			(size 0.6096 0.7112)
			(layers "F.Cu" "F.Mask" "F.Paste")
			(net "LED_POSTCODE_R_3")
		)
		(pad "C" smd rect
			(at 0.47498 0 180)
			(size 0.6096 0.7112)
			(layers "F.Cu" "F.Mask" "F.Paste")
			(net "FPGA_DEBUG_LED_R_N")
		)
	)
	(footprint ""
		(layer "F.Cu")
		(at 276.838664 -22.867366 90)
		(property "Reference" "C3941"
			(at 0 0 90)
			(layer "F.SilkS")
			(hide yes)
			(effects
				(font
					(size 1.27 1.27)
				)
			)
		)
		(property "Value" ""
			(at 0 0 90)
			(layer "F.Fab")
			(effects
				(font
					(size 1.27 1.27)
				)
			)
		)
		(duplicate_pad_numbers_are_jumpers no)
		(fp_line
			(start 0.7874 -0.4064)
			(end 0.7874 0.4064)
			(stroke
				(width 0.1524)
				(type default)
			)
			(layer "F.SilkS")
		)
		(fp_line
			(start -0.7874 -0.4064)
			(end 0.7874 -0.4064)
			(stroke
				(width 0.1524)
				(type default)
			)
			(layer "F.SilkS")
		)
		(fp_line
			(start 0.7874 0.4064)
			(end -0.7874 0.4064)
			(stroke
				(width 0.1524)
				(type default)
			)
			(layer "F.SilkS")
		)
		(fp_line
			(start -0.7874 0.4064)
			(end -0.7874 -0.4064)
			(stroke
				(width 0.1524)
				(type default)
			)
			(layer "F.SilkS")
		)
		(fp_line
			(start -0.12065 -0.305054)
			(end -0.12065 -0.2794)
			(stroke
				(width 0.1)
				(type default)
			)
			(layer "F.Fab")
		)
		(fp_line
			(start -0.67945 -0.305054)
			(end -0.12065 -0.305054)
			(stroke
				(width 0.1)
				(type default)
			)
			(layer "F.Fab")
		)
		(fp_line
			(start 0.67945 -0.3048)
			(end 0.67945 0.3048)
			(stroke
				(width 0.1)
				(type default)
			)
			(layer "F.Fab")
		)
		(fp_line
			(start 0.12065 -0.3048)
			(end 0.67945 -0.3048)
			(stroke
				(width 0.1)
				(type default)
			)
			(layer "F.Fab")
		)
		(fp_line
			(start 0.12065 -0.2794)
			(end 0.12065 -0.3048)
			(stroke
				(width 0.1)
				(type default)
			)
			(layer "F.Fab")
		)
		(fp_line
			(start -0.12065 -0.2794)
			(end 0.12065 -0.2794)
			(stroke
				(width 0.1)
				(type default)
			)
			(layer "F.Fab")
		)
		(fp_line
			(start 0.120396 0.2794)
			(end -0.12065 0.2794)
			(stroke
				(width 0.1)
				(type default)
			)
			(layer "F.Fab")
		)
		(fp_line
			(start -0.12065 0.2794)
			(end -0.12065 0.3048)
			(stroke
				(width 0.1)
				(type default)
			)
			(layer "F.Fab")
		)
		(fp_line
			(start 0.67945 0.3048)
			(end 0.120396 0.3048)
			(stroke
				(width 0.1)
				(type default)
			)
			(layer "F.Fab")
		)
		(fp_line
			(start 0.120396 0.3048)
			(end 0.120396 0.2794)
			(stroke
				(width 0.1)
				(type default)
			)
			(layer "F.Fab")
		)
		(fp_line
			(start -0.12065 0.3048)
			(end -0.67945 0.3048)
			(stroke
				(width 0.1)
				(type default)
			)
			(layer "F.Fab")
		)
		(fp_line
			(start -0.67945 0.3048)
			(end -0.67945 -0.305054)
			(stroke
				(width 0.1)
				(type default)
			)
			(layer "F.Fab")
		)
		(pad "1" smd circle
			(at -0.40005 0 90)
			(size 0 0)
			(layers "F.Cu" "F.Mask" "F.Paste")
			(net "P12V_SSD9")
		)
		(pad "2" smd circle
			(at 0.40005 0 90)
			(size 0 0)
			(layers "F.Cu" "F.Mask" "F.Paste")
			(net "GND")
		)
	)
	(footprint ""
		(layer "F.Cu")
		(at 443.802262 -443.028832 90)
		(property "Reference" "J48"
			(at -3.5052 -5.552948 90)
			(unlocked yes)
			(layer "F.SilkS")
			(effects
				(font
					(size 0.7874 0.5842)
					(thickness 0.1524)
				)
				(justify left)
			)
		)
		(property "Value" ""
			(at 0 0 90)
			(layer "F.Fab")
			(effects
				(font
					(size 1.27 1.27)
				)
			)
		)
		(duplicate_pad_numbers_are_jumpers no)
		(fp_line
			(start 3.330702 -4.771136)
			(end 0 4.011168)
			(stroke
				(width 0.1524)
				(type default)
			)
			(layer "F.SilkS")
		)
		(fp_line
			(start -3.330702 -4.771136)
			(end 3.330702 -4.771136)
			(stroke
				(width 0.1524)
				(type default)
			)
			(layer "F.SilkS")
		)
		(fp_line
			(start 0 4.011168)
			(end -3.330702 -4.771136)
			(stroke
				(width 0.1524)
				(type default)
			)
			(layer "F.SilkS")
		)
		(fp_line
			(start 3.330702 -4.771136)
			(end 0 4.011168)
			(stroke
				(width 0.1)
				(type default)
			)
			(layer "F.Fab")
		)
		(fp_line
			(start -3.330702 -4.771136)
			(end 3.330702 -4.771136)
			(stroke
				(width 0.1)
				(type default)
			)
			(layer "F.Fab")
		)
		(fp_line
			(start 0 4.011168)
			(end -3.330702 -4.771136)
			(stroke
				(width 0.1)
				(type default)
			)
			(layer "F.Fab")
		)
		(pad "1" thru_hole circle
			(at 0 0 90)
			(size 2.159 2.159)
			(drill 1.7018)
			(layers "*.Cu" "*.Mask")
			(remove_unused_layers no)
			(net "COUPON_GND1")
			(clearance 0.0254)
			(thermal_gap 0.0254)
		)
		(pad "2" thru_hole circle
			(at -1.27 -3.348736 90)
			(size 2.159 2.159)
			(drill 1.7018)
			(layers "*.Cu" "*.Mask")
			(remove_unused_layers no)
			(net "TDR_SE_50_OHM_IN2")
			(clearance 0.0254)
			(thermal_gap 0.0254)
		)
		(pad "3" thru_hole circle
			(at 1.27 -3.348736 90)
			(size 2.159 2.159)
			(drill 1.7018)
			(layers "*.Cu" "*.Mask")
			(remove_unused_layers no)
			(net "TDR_SE_50_OHM_IN2")
			(clearance 0.0254)
			(thermal_gap 0.0254)
		)
	)
	(footprint ""
		(layer "F.Cu")
		(at 19.225768 -159.082994 -90)
		(property "Reference" "PD76"
			(at 3.838194 -2.771902 90)
			(unlocked yes)
			(layer "F.SilkS")
			(effects
				(font
					(size 0.7874 0.5842)
					(thickness 0.1524)
				)
				(justify left)
			)
		)
		(property "Value" ""
			(at 0 0 270)
			(layer "F.Fab")
			(effects
				(font
					(size 1.27 1.27)
				)
			)
		)
		(duplicate_pad_numbers_are_jumpers no)
		(fp_line
			(start -3.656584 1.970024)
			(end 4.240784 1.970024)
			(stroke
				(width 0.1524)
				(type default)
			)
			(layer "F.SilkS")
		)
		(fp_line
			(start 4.240784 1.970024)
			(end 4.240784 -1.970024)
			(stroke
				(width 0.1524)
				(type default)
			)
			(layer "F.SilkS")
		)
		(fp_line
			(start -3.656584 -1.970024)
			(end -3.656584 1.970024)
			(stroke
				(width 0.1524)
				(type default)
			)
			(layer "F.SilkS")
		)
		(fp_line
			(start 4.240784 -1.970024)
			(end -3.656584 -1.970024)
			(stroke
				(width 0.1524)
				(type default)
			)
			(layer "F.SilkS")
		)
		(fp_poly
			(pts
				(xy 3.580384 1.970024) (xy 3.580384 -1.970024) (xy 4.240784 -1.970024) (xy 4.240784 1.970024)
			)
			(stroke
				(width 0)
				(type default)
			)
			(fill yes)
			(layer "F.SilkS")
		)
		(fp_line
			(start -2.3749 1.970024)
			(end 2.3749 1.970024)
			(stroke
				(width 0.1)
				(type default)
			)
			(layer "F.Fab")
		)
		(fp_line
			(start 2.3749 1.970024)
			(end 2.3749 -1.970024)
			(stroke
				(width 0.1)
				(type default)
			)
			(layer "F.Fab")
		)
		(fp_line
			(start -2.3749 -1.970024)
			(end -2.3749 1.970024)
			(stroke
				(width 0.1)
				(type default)
			)
			(layer "F.Fab")
		)
		(fp_line
			(start 2.3749 -1.970024)
			(end -2.3749 -1.970024)
			(stroke
				(width 0.1)
				(type default)
			)
			(layer "F.Fab")
		)
		(fp_text user "+"
			(at -4.9784 -0.23495 270)
			(unlocked yes)
			(layer "F.Fab")
			(effects
				(font
					(size 1.905 1.4224)
					(thickness 0.1524)
				)
				(justify left)
			)
		)
		(fp_text user "-"
			(at 4.1656 -0.23495 270)
			(unlocked yes)
			(layer "F.Fab")
			(effects
				(font
					(size 1.905 1.4224)
					(thickness 0.1524)
				)
				(justify left)
			)
		)
		(pad "A" smd rect
			(at -2.450084 0 270)
			(size 2.159 2.2606)
			(layers "F.Cu" "F.Mask" "F.Paste")
			(net "GND")
		)
		(pad "C" smd rect
			(at 2.450084 0 270)
			(size 2.159 2.2606)
			(layers "F.Cu" "F.Mask" "F.Paste")
			(net "P12V_AUX")
		)
	)
	(footprint ""
		(layer "F.Cu")
		(at 263.55294 -335.115408)
		(property "Reference" "U448"
			(at -2.956306 2.612898 0)
			(unlocked yes)
			(layer "F.SilkS")
			(effects
				(font
					(size 0.7874 0.5842)
					(thickness 0.1524)
				)
			)
		)
		(property "Value" ""
			(at 0 0 0)
			(layer "F.Fab")
			(effects
				(font
					(size 1.27 1.27)
				)
			)
		)
		(duplicate_pad_numbers_are_jumpers no)
		(fp_line
			(start -2.032 -1.549908)
			(end -0.508 -1.549908)
			(stroke
				(width 0.1524)
				(type default)
			)
			(layer "F.SilkS")
		)
		(fp_line
			(start -2.032 1.549908)
			(end -2.032 -1.549908)
			(stroke
				(width 0.1524)
				(type default)
			)
			(layer "F.SilkS")
		)
		(fp_line
			(start -0.508 -1.549908)
			(end 0 -0.762)
			(stroke
				(width 0.1524)
				(type default)
			)
			(layer "F.SilkS")
		)
		(fp_line
			(start 0 -0.762)
			(end 0.508 -1.549908)
			(stroke
				(width 0.1524)
				(type default)
			)
			(layer "F.SilkS")
		)
		(fp_line
			(start 0.508 -1.549908)
			(end 2.032 -1.549908)
			(stroke
				(width 0.1524)
				(type default)
			)
			(layer "F.SilkS")
		)
		(fp_line
			(start 2.032 -1.549908)
			(end 2.032 1.549908)
			(stroke
				(width 0.1524)
				(type default)
			)
			(layer "F.SilkS")
		)
		(fp_line
			(start 2.032 1.549908)
			(end -2.032 1.549908)
			(stroke
				(width 0.1524)
				(type default)
			)
			(layer "F.SilkS")
		)
		(fp_poly
			(pts
				(xy -3.2004 -1.45796) (xy -3.2004 -0.44196) (xy -2.1844 -0.94996)
			)
			(stroke
				(width 0)
				(type default)
			)
			(fill yes)
			(layer "F.SilkS")
		)
		(fp_line
			(start -0.849884 -1.549908)
			(end 0.849884 -1.549908)
			(stroke
				(width 0.1)
				(type default)
			)
			(layer "F.Fab")
		)
		(fp_line
			(start -0.849884 1.549908)
			(end -0.849884 -1.549908)
			(stroke
				(width 0.1)
				(type default)
			)
			(layer "F.Fab")
		)
		(fp_line
			(start 0.849884 -1.549908)
			(end 0.849884 1.549908)
			(stroke
				(width 0.1)
				(type default)
			)
			(layer "F.Fab")
		)
		(fp_line
			(start 0.849884 1.549908)
			(end -0.849884 1.549908)
			(stroke
				(width 0.1)
				(type default)
			)
			(layer "F.Fab")
		)
		(fp_poly
			(pts
				(xy -3.2004 -1.45796) (xy -3.2004 -0.44196) (xy -2.1844 -0.94996)
			)
			(stroke
				(width 0)
				(type default)
			)
			(fill yes)
			(layer "F.Fab")
		)
		(pad "1" smd rect
			(at -1.35001 -0.94996 270)
			(size 0.6096 1.0668)
			(layers "F.Cu" "F.Mask" "F.Paste")
			(net "OC_P2V5_COMP")
		)
		(pad "2" smd rect
			(at -1.35001 0 270)
			(size 0.6096 1.0668)
			(layers "F.Cu" "F.Mask" "F.Paste")
			(net "GND")
		)
		(pad "3" smd rect
			(at -1.35001 0.94996 270)
			(size 0.6096 1.0668)
			(layers "F.Cu" "F.Mask" "F.Paste")
			(net "HSC_OC_VOL")
		)
		(pad "4" smd rect
			(at 1.35001 0.94996 270)
			(size 0.6096 1.0668)
			(layers "F.Cu" "F.Mask" "F.Paste")
			(net "HSC_D_OC_R2")
		)
		(pad "5" smd rect
			(at 1.35001 -0.94996 270)
			(size 0.6096 1.0668)
			(layers "F.Cu" "F.Mask" "F.Paste")
			(net "P12V_AUX")
		)
	)
	(footprint ""
		(layer "F.Cu")
		(at 259.24129 -77.279754 -90)
		(property "Reference" "R1080"
			(at 0 0 270)
			(layer "F.SilkS")
			(hide yes)
			(effects
				(font
					(size 1.27 1.27)
				)
			)
		)
		(property "Value" ""
			(at 0 0 270)
			(layer "F.Fab")
			(effects
				(font
					(size 1.27 1.27)
				)
			)
		)
		(duplicate_pad_numbers_are_jumpers no)
		(fp_line
			(start -0.7874 0.4064)
			(end -0.7874 -0.4064)
			(stroke
				(width 0.1524)
				(type default)
			)
			(layer "F.SilkS")
		)
		(fp_line
			(start 0.7874 0.4064)
			(end -0.7874 0.4064)
			(stroke
				(width 0.1524)
				(type default)
			)
			(layer "F.SilkS")
		)
		(fp_line
			(start -0.7874 -0.4064)
			(end 0.7874 -0.4064)
			(stroke
				(width 0.1524)
				(type default)
			)
			(layer "F.SilkS")
		)
		(fp_line
			(start 0.7874 -0.4064)
			(end 0.7874 0.4064)
			(stroke
				(width 0.1524)
				(type default)
			)
			(layer "F.SilkS")
		)
		(fp_line
			(start -0.67945 0.3048)
			(end -0.67945 -0.305054)
			(stroke
				(width 0.1)
				(type default)
			)
			(layer "F.Fab")
		)
		(fp_line
			(start -0.12065 0.3048)
			(end -0.67945 0.3048)
			(stroke
				(width 0.1)
				(type default)
			)
			(layer "F.Fab")
		)
		(fp_line
			(start 0.120396 0.3048)
			(end 0.120396 0.2794)
			(stroke
				(width 0.1)
				(type default)
			)
			(layer "F.Fab")
		)
		(fp_line
			(start 0.67945 0.3048)
			(end 0.120396 0.3048)
			(stroke
				(width 0.1)
				(type default)
			)
			(layer "F.Fab")
		)
		(fp_line
			(start -0.12065 0.2794)
			(end -0.12065 0.3048)
			(stroke
				(width 0.1)
				(type default)
			)
			(layer "F.Fab")
		)
		(fp_line
			(start 0.120396 0.2794)
			(end -0.12065 0.2794)
			(stroke
				(width 0.1)
				(type default)
			)
			(layer "F.Fab")
		)
		(fp_line
			(start -0.12065 -0.2794)
			(end 0.12065 -0.2794)
			(stroke
				(width 0.1)
				(type default)
			)
			(layer "F.Fab")
		)
		(fp_line
			(start 0.12065 -0.2794)
			(end 0.12065 -0.3048)
			(stroke
				(width 0.1)
				(type default)
			)
			(layer "F.Fab")
		)
		(fp_line
			(start 0.12065 -0.3048)
			(end 0.67945 -0.3048)
			(stroke
				(width 0.1)
				(type default)
			)
			(layer "F.Fab")
		)
		(fp_line
			(start 0.67945 -0.3048)
			(end 0.67945 0.3048)
			(stroke
				(width 0.1)
				(type default)
			)
			(layer "F.Fab")
		)
		(fp_line
			(start -0.67945 -0.305054)
			(end -0.12065 -0.305054)
			(stroke
				(width 0.1)
				(type default)
			)
			(layer "F.Fab")
		)
		(fp_line
			(start -0.12065 -0.305054)
			(end -0.12065 -0.2794)
			(stroke
				(width 0.1)
				(type default)
			)
			(layer "F.Fab")
		)
		(pad "1" smd circle
			(at -0.40005 0 270)
			(size 0 0)
			(layers "F.Cu" "F.Mask" "F.Paste")
			(net "CLK_GEN_CK440_OE5_N")
		)
		(pad "2" smd circle
			(at 0.40005 0 270)
			(size 0 0)
			(layers "F.Cu" "F.Mask" "F.Paste")
			(net "P3V3")
		)
	)
	(footprint ""
		(layer "F.Cu")
		(at 271.480534 -111.003334)
		(property "Reference" "C474"
			(at 0 0 0)
			(layer "F.SilkS")
			(hide yes)
			(effects
				(font
					(size 1.27 1.27)
				)
			)
		)
		(property "Value" ""
			(at 0 0 0)
			(layer "F.Fab")
			(effects
				(font
					(size 1.27 1.27)
				)
			)
		)
		(duplicate_pad_numbers_are_jumpers no)
		(fp_line
			(start -0.299974 -0.150114)
			(end 0.299974 -0.150114)
			(stroke
				(width 0.1)
				(type default)
			)
			(layer "F.Fab")
		)
		(fp_line
			(start -0.299974 0.150114)
			(end -0.299974 -0.150114)
			(stroke
				(width 0.1)
				(type default)
			)
			(layer "F.Fab")
		)
		(fp_line
			(start 0.299974 -0.150114)
			(end 0.299974 0.150114)
			(stroke
				(width 0.1)
				(type default)
			)
			(layer "F.Fab")
		)
		(fp_line
			(start 0.299974 0.150114)
			(end -0.299974 0.150114)
			(stroke
				(width 0.1)
				(type default)
			)
			(layer "F.Fab")
		)
		(pad "1" smd rect
			(at -0.2667 0)
			(size 0.3048 0.381)
			(layers "F.Cu" "F.Mask" "F.Paste")
			(net "P5E_PEX2_STN1_TX_DN<22>")
		)
		(pad "2" smd rect
			(at 0.2667 0)
			(size 0.3048 0.381)
			(layers "F.Cu" "F.Mask" "F.Paste")
			(net "P5E_PEX2_STN1_TX_C_DN<22>")
		)
	)
	(footprint ""
		(layer "F.Cu")
		(at 235.623608 -143.656812 180)
		(property "Reference" "R4205"
			(at 0 0 180)
			(layer "F.SilkS")
			(hide yes)
			(effects
				(font
					(size 1.27 1.27)
				)
			)
		)
		(property "Value" ""
			(at 0 0 180)
			(layer "F.Fab")
			(effects
				(font
					(size 1.27 1.27)
				)
			)
		)
		(duplicate_pad_numbers_are_jumpers no)
		(fp_line
			(start 0.7874 0.4064)
			(end -0.7874 0.4064)
			(stroke
				(width 0.1524)
				(type default)
			)
			(layer "F.SilkS")
		)
		(fp_line
			(start 0.7874 -0.4064)
			(end 0.7874 0.4064)
			(stroke
				(width 0.1524)
				(type default)
			)
			(layer "F.SilkS")
		)
		(fp_line
			(start -0.7874 0.4064)
			(end -0.7874 -0.4064)
			(stroke
				(width 0.1524)
				(type default)
			)
			(layer "F.SilkS")
		)
		(fp_line
			(start -0.7874 -0.4064)
			(end 0.7874 -0.4064)
			(stroke
				(width 0.1524)
				(type default)
			)
			(layer "F.SilkS")
		)
		(fp_line
			(start 0.67945 0.3048)
			(end 0.120396 0.3048)
			(stroke
				(width 0.1)
				(type default)
			)
			(layer "F.Fab")
		)
		(fp_line
			(start 0.67945 -0.3048)
			(end 0.67945 0.3048)
			(stroke
				(width 0.1)
				(type default)
			)
			(layer "F.Fab")
		)
		(fp_line
			(start 0.12065 -0.2794)
			(end 0.12065 -0.3048)
			(stroke
				(width 0.1)
				(type default)
			)
			(layer "F.Fab")
		)
		(fp_line
			(start 0.12065 -0.3048)
			(end 0.67945 -0.3048)
			(stroke
				(width 0.1)
				(type default)
			)
			(layer "F.Fab")
		)
		(fp_line
			(start 0.120396 0.3048)
			(end 0.120396 0.2794)
			(stroke
				(width 0.1)
				(type default)
			)
			(layer "F.Fab")
		)
		(fp_line
			(start 0.120396 0.2794)
			(end -0.12065 0.2794)
			(stroke
				(width 0.1)
				(type default)
			)
			(layer "F.Fab")
		)
		(fp_line
			(start -0.12065 0.3048)
			(end -0.67945 0.3048)
			(stroke
				(width 0.1)
				(type default)
			)
			(layer "F.Fab")
		)
		(fp_line
			(start -0.12065 0.2794)
			(end -0.12065 0.3048)
			(stroke
				(width 0.1)
				(type default)
			)
			(layer "F.Fab")
		)
		(fp_line
			(start -0.12065 -0.2794)
			(end 0.12065 -0.2794)
			(stroke
				(width 0.1)
				(type default)
			)
			(layer "F.Fab")
		)
		(fp_line
			(start -0.12065 -0.305054)
			(end -0.12065 -0.2794)
			(stroke
				(width 0.1)
				(type default)
			)
			(layer "F.Fab")
		)
		(fp_line
			(start -0.67945 0.3048)
			(end -0.67945 -0.305054)
			(stroke
				(width 0.1)
				(type default)
			)
			(layer "F.Fab")
		)
		(fp_line
			(start -0.67945 -0.305054)
			(end -0.12065 -0.305054)
			(stroke
				(width 0.1)
				(type default)
			)
			(layer "F.Fab")
		)
		(pad "1" smd circle
			(at -0.40005 0 180)
			(size 0 0)
			(layers "F.Cu" "F.Mask" "F.Paste")
			(net "GND")
		)
		(pad "2" smd circle
			(at 0.40005 0 180)
			(size 0 0)
			(layers "F.Cu" "F.Mask" "F.Paste")
			(net "FM_CLK_EN_R")
		)
	)
	(footprint ""
		(layer "F.Cu")
		(at 206.710534 -187.165234 90)
		(property "Reference" "R3761"
			(at 0 0 90)
			(layer "F.SilkS")
			(hide yes)
			(effects
				(font
					(size 1.27 1.27)
				)
			)
		)
		(property "Value" ""
			(at 0 0 90)
			(layer "F.Fab")
			(effects
				(font
					(size 1.27 1.27)
				)
			)
		)
		(duplicate_pad_numbers_are_jumpers no)
		(fp_line
			(start 0.7874 -0.4064)
			(end 0.7874 0.4064)
			(stroke
				(width 0.1524)
				(type default)
			)
			(layer "F.SilkS")
		)
		(fp_line
			(start -0.7874 -0.4064)
			(end 0.7874 -0.4064)
			(stroke
				(width 0.1524)
				(type default)
			)
			(layer "F.SilkS")
		)
		(fp_line
			(start 0.7874 0.4064)
			(end -0.7874 0.4064)
			(stroke
				(width 0.1524)
				(type default)
			)
			(layer "F.SilkS")
		)
		(fp_line
			(start -0.7874 0.4064)
			(end -0.7874 -0.4064)
			(stroke
				(width 0.1524)
				(type default)
			)
			(layer "F.SilkS")
		)
		(fp_line
			(start -0.12065 -0.305054)
			(end -0.12065 -0.2794)
			(stroke
				(width 0.1)
				(type default)
			)
			(layer "F.Fab")
		)
		(fp_line
			(start -0.67945 -0.305054)
			(end -0.12065 -0.305054)
			(stroke
				(width 0.1)
				(type default)
			)
			(layer "F.Fab")
		)
		(fp_line
			(start 0.67945 -0.3048)
			(end 0.67945 0.3048)
			(stroke
				(width 0.1)
				(type default)
			)
			(layer "F.Fab")
		)
		(fp_line
			(start 0.12065 -0.3048)
			(end 0.67945 -0.3048)
			(stroke
				(width 0.1)
				(type default)
			)
			(layer "F.Fab")
		)
		(fp_line
			(start 0.12065 -0.2794)
			(end 0.12065 -0.3048)
			(stroke
				(width 0.1)
				(type default)
			)
			(layer "F.Fab")
		)
		(fp_line
			(start -0.12065 -0.2794)
			(end 0.12065 -0.2794)
			(stroke
				(width 0.1)
				(type default)
			)
			(layer "F.Fab")
		)
		(fp_line
			(start 0.120396 0.2794)
			(end -0.12065 0.2794)
			(stroke
				(width 0.1)
				(type default)
			)
			(layer "F.Fab")
		)
		(fp_line
			(start -0.12065 0.2794)
			(end -0.12065 0.3048)
			(stroke
				(width 0.1)
				(type default)
			)
			(layer "F.Fab")
		)
		(fp_line
			(start 0.67945 0.3048)
			(end 0.120396 0.3048)
			(stroke
				(width 0.1)
				(type default)
			)
			(layer "F.Fab")
		)
		(fp_line
			(start 0.120396 0.3048)
			(end 0.120396 0.2794)
			(stroke
				(width 0.1)
				(type default)
			)
			(layer "F.Fab")
		)
		(fp_line
			(start -0.12065 0.3048)
			(end -0.67945 0.3048)
			(stroke
				(width 0.1)
				(type default)
			)
			(layer "F.Fab")
		)
		(fp_line
			(start -0.67945 0.3048)
			(end -0.67945 -0.305054)
			(stroke
				(width 0.1)
				(type default)
			)
			(layer "F.Fab")
		)
		(pad "1" smd circle
			(at -0.40005 0 90)
			(size 0 0)
			(layers "F.Cu" "F.Mask" "F.Paste")
			(net "SMB_FIO_R2_SCL")
		)
		(pad "2" smd circle
			(at 0.40005 0 90)
			(size 0 0)
			(layers "F.Cu" "F.Mask" "F.Paste")
			(net "SMB_FIO_R1_SCL")
		)
	)
	(footprint ""
		(layer "F.Cu")
		(at 234.072938 -128.632966)
		(property "Reference" "J4"
			(at -1.156716 4.549902 0)
			(unlocked yes)
			(layer "F.SilkS")
			(effects
				(font
					(size 0.7874 0.5842)
					(thickness 0.1524)
				)
				(justify left)
			)
		)
		(property "Value" ""
			(at 0 0 0)
			(layer "F.Fab")
			(effects
				(font
					(size 1.27 1.27)
				)
			)
		)
		(duplicate_pad_numbers_are_jumpers no)
		(fp_line
			(start -1.27 -3.81)
			(end 1.27 -3.81)
			(stroke
				(width 0.1524)
				(type default)
			)
			(layer "F.SilkS")
		)
		(fp_line
			(start -1.27 -0.7747)
			(end -1.27 -3.81)
			(stroke
				(width 0.1524)
				(type default)
			)
			(layer "F.SilkS")
		)
		(fp_line
			(start -1.27 3.81)
			(end -1.27 0.7747)
			(stroke
				(width 0.1524)
				(type default)
			)
			(layer "F.SilkS")
		)
		(fp_line
			(start 1.27 -3.81)
			(end 1.27 -3.3147)
			(stroke
				(width 0.1524)
				(type default)
			)
			(layer "F.SilkS")
		)
		(fp_line
			(start 1.27 -1.7653)
			(end 1.27 1.7653)
			(stroke
				(width 0.1524)
				(type default)
			)
			(layer "F.SilkS")
		)
		(fp_line
			(start 1.27 3.3147)
			(end 1.27 3.81)
			(stroke
				(width 0.1524)
				(type default)
			)
			(layer "F.SilkS")
		)
		(fp_line
			(start 1.27 3.81)
			(end -1.27 3.81)
			(stroke
				(width 0.1524)
				(type default)
			)
			(layer "F.SilkS")
		)
		(fp_poly
			(pts
				(xy 4.3942 -3.048) (xy 4.3942 -2.032) (xy 3.3782 -2.54)
			)
			(stroke
				(width 0)
				(type default)
			)
			(fill yes)
			(layer "F.SilkS")
		)
		(fp_line
			(start -1.27 -3.81)
			(end -1.27 3.81)
			(stroke
				(width 0.1)
				(type default)
			)
			(layer "F.Fab")
		)
		(fp_line
			(start -1.27 3.81)
			(end 1.27 3.81)
			(stroke
				(width 0.1)
				(type default)
			)
			(layer "F.Fab")
		)
		(fp_line
			(start 1.27 -3.81)
			(end -1.27 -3.81)
			(stroke
				(width 0.1)
				(type default)
			)
			(layer "F.Fab")
		)
		(fp_line
			(start 1.27 3.81)
			(end 1.27 -3.81)
			(stroke
				(width 0.1)
				(type default)
			)
			(layer "F.Fab")
		)
		(fp_poly
			(pts
				(xy 4.3942 -3.048) (xy 4.3942 -2.032) (xy 3.3782 -2.54)
			)
			(stroke
				(width 0)
				(type default)
			)
			(fill yes)
			(layer "F.Fab")
		)
		(fp_text user "3"
			(at 3.921252 2.54 90)
			(unlocked yes)
			(layer "F.SilkS")
			(effects
				(font
					(size 0.7874 0.5842)
					(thickness 0.1524)
				)
			)
		)
		(fp_text user "3"
			(at 3.921252 2.54 90)
			(unlocked yes)
			(layer "F.Fab")
			(effects
				(font
					(size 0.7874 0.5842)
					(thickness 0.1524)
				)
			)
		)
		(pad "1" smd rect
			(at 1.459992 -2.54 90)
			(size 1.27 3.429)
			(layers "F.Cu" "F.Mask" "F.Paste")
			(net "Net_1738")
		)
		(pad "2" smd rect
			(at -1.459992 0 90)
			(size 1.27 3.429)
			(layers "F.Cu" "F.Mask" "F.Paste")
			(net "PEX_USB2_SEL")
		)
		(pad "3" smd rect
			(at 1.459992 2.54 90)
			(size 1.27 3.429)
			(layers "F.Cu" "F.Mask" "F.Paste")
			(net "PEX_USB2_SEL_CONN")
		)
	)
	(footprint ""
		(layer "F.Cu")
		(at 428.319438 -133.480302 180)
		(property "Reference" "C653"
			(at 0 0 180)
			(layer "F.SilkS")
			(hide yes)
			(effects
				(font
					(size 1.27 1.27)
				)
			)
		)
		(property "Value" ""
			(at 0 0 180)
			(layer "F.Fab")
			(effects
				(font
					(size 1.27 1.27)
				)
			)
		)
		(duplicate_pad_numbers_are_jumpers no)
		(fp_line
			(start 0.299974 0.150114)
			(end -0.299974 0.150114)
			(stroke
				(width 0.1)
				(type default)
			)
			(layer "F.Fab")
		)
		(fp_line
			(start 0.299974 -0.150114)
			(end 0.299974 0.150114)
			(stroke
				(width 0.1)
				(type default)
			)
			(layer "F.Fab")
		)
		(fp_line
			(start -0.299974 0.150114)
			(end -0.299974 -0.150114)
			(stroke
				(width 0.1)
				(type default)
			)
			(layer "F.Fab")
		)
		(fp_line
			(start -0.299974 -0.150114)
			(end 0.299974 -0.150114)
			(stroke
				(width 0.1)
				(type default)
			)
			(layer "F.Fab")
		)
		(pad "1" smd rect
			(at -0.2667 0 180)
			(size 0.3048 0.381)
			(layers "F.Cu" "F.Mask" "F.Paste")
			(net "P5E_PEX3_STN0_TX_DN<6>")
		)
		(pad "2" smd rect
			(at 0.2667 0 180)
			(size 0.3048 0.381)
			(layers "F.Cu" "F.Mask" "F.Paste")
			(net "P5E_PEX3_STN0_TX_C_DN<6>")
		)
	)
	(footprint ""
		(layer "F.Cu")
		(at 58.575702 -36.915598 -90)
		(property "Reference" "R5547"
			(at 0 0 270)
			(layer "F.SilkS")
			(hide yes)
			(effects
				(font
					(size 1.27 1.27)
				)
			)
		)
		(property "Value" ""
			(at 0 0 270)
			(layer "F.Fab")
			(effects
				(font
					(size 1.27 1.27)
				)
			)
		)
		(duplicate_pad_numbers_are_jumpers no)
		(fp_line
			(start -0.7874 0.4064)
			(end -0.7874 -0.4064)
			(stroke
				(width 0.1524)
				(type default)
			)
			(layer "F.SilkS")
		)
		(fp_line
			(start 0.7874 0.4064)
			(end -0.7874 0.4064)
			(stroke
				(width 0.1524)
				(type default)
			)
			(layer "F.SilkS")
		)
		(fp_line
			(start -0.7874 -0.4064)
			(end 0.7874 -0.4064)
			(stroke
				(width 0.1524)
				(type default)
			)
			(layer "F.SilkS")
		)
		(fp_line
			(start 0.7874 -0.4064)
			(end 0.7874 0.4064)
			(stroke
				(width 0.1524)
				(type default)
			)
			(layer "F.SilkS")
		)
		(fp_line
			(start -0.67945 0.3048)
			(end -0.67945 -0.305054)
			(stroke
				(width 0.1)
				(type default)
			)
			(layer "F.Fab")
		)
		(fp_line
			(start -0.12065 0.3048)
			(end -0.67945 0.3048)
			(stroke
				(width 0.1)
				(type default)
			)
			(layer "F.Fab")
		)
		(fp_line
			(start 0.120396 0.3048)
			(end 0.120396 0.2794)
			(stroke
				(width 0.1)
				(type default)
			)
			(layer "F.Fab")
		)
		(fp_line
			(start 0.67945 0.3048)
			(end 0.120396 0.3048)
			(stroke
				(width 0.1)
				(type default)
			)
			(layer "F.Fab")
		)
		(fp_line
			(start -0.12065 0.2794)
			(end -0.12065 0.3048)
			(stroke
				(width 0.1)
				(type default)
			)
			(layer "F.Fab")
		)
		(fp_line
			(start 0.120396 0.2794)
			(end -0.12065 0.2794)
			(stroke
				(width 0.1)
				(type default)
			)
			(layer "F.Fab")
		)
		(fp_line
			(start -0.12065 -0.2794)
			(end 0.12065 -0.2794)
			(stroke
				(width 0.1)
				(type default)
			)
			(layer "F.Fab")
		)
		(fp_line
			(start 0.12065 -0.2794)
			(end 0.12065 -0.3048)
			(stroke
				(width 0.1)
				(type default)
			)
			(layer "F.Fab")
		)
		(fp_line
			(start 0.12065 -0.3048)
			(end 0.67945 -0.3048)
			(stroke
				(width 0.1)
				(type default)
			)
			(layer "F.Fab")
		)
		(fp_line
			(start 0.67945 -0.3048)
			(end 0.67945 0.3048)
			(stroke
				(width 0.1)
				(type default)
			)
			(layer "F.Fab")
		)
		(fp_line
			(start -0.67945 -0.305054)
			(end -0.12065 -0.305054)
			(stroke
				(width 0.1)
				(type default)
			)
			(layer "F.Fab")
		)
		(fp_line
			(start -0.12065 -0.305054)
			(end -0.12065 -0.2794)
			(stroke
				(width 0.1)
				(type default)
			)
			(layer "F.Fab")
		)
		(pad "1" smd circle
			(at -0.40005 0 270)
			(size 0 0)
			(layers "F.Cu" "F.Mask" "F.Paste")
			(net "PRSNT_SSD2_R1_N")
		)
		(pad "2" smd circle
			(at 0.40005 0 270)
			(size 0 0)
			(layers "F.Cu" "F.Mask" "F.Paste")
			(net "PRSNT_SSD2_R_N")
		)
	)
	(footprint ""
		(layer "F.Cu")
		(at 378.382022 -286.590232 180)
		(property "Reference" "C3583"
			(at 0 0 180)
			(layer "F.SilkS")
			(hide yes)
			(effects
				(font
					(size 1.27 1.27)
				)
			)
		)
		(property "Value" ""
			(at 0 0 180)
			(layer "F.Fab")
			(effects
				(font
					(size 1.27 1.27)
				)
			)
		)
		(duplicate_pad_numbers_are_jumpers no)
		(fp_line
			(start 1.2954 0.5842)
			(end -1.2954 0.5842)
			(stroke
				(width 0.1524)
				(type default)
			)
			(layer "F.SilkS")
		)
		(fp_line
			(start 1.2954 -0.5842)
			(end 1.2954 0.5842)
			(stroke
				(width 0.1524)
				(type default)
			)
			(layer "F.SilkS")
		)
		(fp_line
			(start -1.2954 0.5842)
			(end -1.2954 -0.5842)
			(stroke
				(width 0.1524)
				(type default)
			)
			(layer "F.SilkS")
		)
		(fp_line
			(start -1.2954 -0.5842)
			(end 1.2954 -0.5842)
			(stroke
				(width 0.1524)
				(type default)
			)
			(layer "F.SilkS")
		)
		(fp_line
			(start 1.1938 0.4064)
			(end 0.8636 0.4064)
			(stroke
				(width 0.1)
				(type default)
			)
			(layer "F.Fab")
		)
		(fp_line
			(start 1.1938 -0.4064)
			(end 1.1938 0.4064)
			(stroke
				(width 0.1)
				(type default)
			)
			(layer "F.Fab")
		)
		(fp_line
			(start 0.8636 0.4572)
			(end -0.8636 0.4572)
			(stroke
				(width 0.1)
				(type default)
			)
			(layer "F.Fab")
		)
		(fp_line
			(start 0.8636 0.4064)
			(end 0.8636 0.4572)
			(stroke
				(width 0.1)
				(type default)
			)
			(layer "F.Fab")
		)
		(fp_line
			(start 0.8636 -0.4064)
			(end 1.1938 -0.4064)
			(stroke
				(width 0.1)
				(type default)
			)
			(layer "F.Fab")
		)
		(fp_line
			(start 0.8636 -0.4572)
			(end 0.8636 -0.4064)
			(stroke
				(width 0.1)
				(type default)
			)
			(layer "F.Fab")
		)
		(fp_line
			(start -0.8636 0.4572)
			(end -0.8636 0.4064)
			(stroke
				(width 0.1)
				(type default)
			)
			(layer "F.Fab")
		)
		(fp_line
			(start -0.8636 0.4064)
			(end -1.1938 0.4064)
			(stroke
				(width 0.1)
				(type default)
			)
			(layer "F.Fab")
		)
		(fp_line
			(start -0.8636 -0.4064)
			(end -0.8636 -0.4572)
			(stroke
				(width 0.1)
				(type default)
			)
			(layer "F.Fab")
		)
		(fp_line
			(start -0.8636 -0.4572)
			(end 0.8636 -0.4572)
			(stroke
				(width 0.1)
				(type default)
			)
			(layer "F.Fab")
		)
		(fp_line
			(start -1.1938 0.4064)
			(end -1.1938 -0.4064)
			(stroke
				(width 0.1)
				(type default)
			)
			(layer "F.Fab")
		)
		(fp_line
			(start -1.1938 -0.4064)
			(end -0.8636 -0.4064)
			(stroke
				(width 0.1)
				(type default)
			)
			(layer "F.Fab")
		)
		(pad "1" smd rect
			(at -0.7366 0 90)
			(size 0.7112 0.8128)
			(layers "F.Cu" "F.Mask" "F.Paste")
			(net "PCEPLL6_VDDA18_PEX3_R")
		)
		(pad "2" smd rect
			(at 0.7366 0 90)
			(size 0.7112 0.8128)
			(layers "F.Cu" "F.Mask" "F.Paste")
			(net "GND")
		)
	)
	(footprint ""
		(layer "F.Cu")
		(at 251.96546 -195.573396 90)
		(property "Reference" "R875"
			(at 0 0 90)
			(layer "F.SilkS")
			(hide yes)
			(effects
				(font
					(size 1.27 1.27)
				)
			)
		)
		(property "Value" ""
			(at 0 0 90)
			(layer "F.Fab")
			(effects
				(font
					(size 1.27 1.27)
				)
			)
		)
		(duplicate_pad_numbers_are_jumpers no)
		(fp_line
			(start 0.7874 -0.4064)
			(end 0.7874 0.4064)
			(stroke
				(width 0.1524)
				(type default)
			)
			(layer "F.SilkS")
		)
		(fp_line
			(start -0.7874 -0.4064)
			(end 0.7874 -0.4064)
			(stroke
				(width 0.1524)
				(type default)
			)
			(layer "F.SilkS")
		)
		(fp_line
			(start 0.7874 0.4064)
			(end -0.7874 0.4064)
			(stroke
				(width 0.1524)
				(type default)
			)
			(layer "F.SilkS")
		)
		(fp_line
			(start -0.7874 0.4064)
			(end -0.7874 -0.4064)
			(stroke
				(width 0.1524)
				(type default)
			)
			(layer "F.SilkS")
		)
		(fp_line
			(start -0.12065 -0.305054)
			(end -0.12065 -0.2794)
			(stroke
				(width 0.1)
				(type default)
			)
			(layer "F.Fab")
		)
		(fp_line
			(start -0.67945 -0.305054)
			(end -0.12065 -0.305054)
			(stroke
				(width 0.1)
				(type default)
			)
			(layer "F.Fab")
		)
		(fp_line
			(start 0.67945 -0.3048)
			(end 0.67945 0.3048)
			(stroke
				(width 0.1)
				(type default)
			)
			(layer "F.Fab")
		)
		(fp_line
			(start 0.12065 -0.3048)
			(end 0.67945 -0.3048)
			(stroke
				(width 0.1)
				(type default)
			)
			(layer "F.Fab")
		)
		(fp_line
			(start 0.12065 -0.2794)
			(end 0.12065 -0.3048)
			(stroke
				(width 0.1)
				(type default)
			)
			(layer "F.Fab")
		)
		(fp_line
			(start -0.12065 -0.2794)
			(end 0.12065 -0.2794)
			(stroke
				(width 0.1)
				(type default)
			)
			(layer "F.Fab")
		)
		(fp_line
			(start 0.120396 0.2794)
			(end -0.12065 0.2794)
			(stroke
				(width 0.1)
				(type default)
			)
			(layer "F.Fab")
		)
		(fp_line
			(start -0.12065 0.2794)
			(end -0.12065 0.3048)
			(stroke
				(width 0.1)
				(type default)
			)
			(layer "F.Fab")
		)
		(fp_line
			(start 0.67945 0.3048)
			(end 0.120396 0.3048)
			(stroke
				(width 0.1)
				(type default)
			)
			(layer "F.Fab")
		)
		(fp_line
			(start 0.120396 0.3048)
			(end 0.120396 0.2794)
			(stroke
				(width 0.1)
				(type default)
			)
			(layer "F.Fab")
		)
		(fp_line
			(start -0.12065 0.3048)
			(end -0.67945 0.3048)
			(stroke
				(width 0.1)
				(type default)
			)
			(layer "F.Fab")
		)
		(fp_line
			(start -0.67945 0.3048)
			(end -0.67945 -0.305054)
			(stroke
				(width 0.1)
				(type default)
			)
			(layer "F.Fab")
		)
		(pad "1" smd circle
			(at -0.40005 0 90)
			(size 0 0)
			(layers "F.Cu" "F.Mask" "F.Paste")
			(net "JTAG_FPGA_TCK")
		)
		(pad "2" smd circle
			(at 0.40005 0 90)
			(size 0 0)
			(layers "F.Cu" "F.Mask" "F.Paste")
			(net "GND")
		)
	)
	(footprint ""
		(layer "F.Cu")
		(at 338.074 -186.055)
		(property "Reference" "R4748"
			(at 0 0 0)
			(layer "F.SilkS")
			(hide yes)
			(effects
				(font
					(size 1.27 1.27)
				)
			)
		)
		(property "Value" ""
			(at 0 0 0)
			(layer "F.Fab")
			(effects
				(font
					(size 1.27 1.27)
				)
			)
		)
		(duplicate_pad_numbers_are_jumpers no)
		(fp_line
			(start -0.7874 -0.4064)
			(end 0.7874 -0.4064)
			(stroke
				(width 0.1524)
				(type default)
			)
			(layer "F.SilkS")
		)
		(fp_line
			(start -0.7874 0.4064)
			(end -0.7874 -0.4064)
			(stroke
				(width 0.1524)
				(type default)
			)
			(layer "F.SilkS")
		)
		(fp_line
			(start 0.7874 -0.4064)
			(end 0.7874 0.4064)
			(stroke
				(width 0.1524)
				(type default)
			)
			(layer "F.SilkS")
		)
		(fp_line
			(start 0.7874 0.4064)
			(end -0.7874 0.4064)
			(stroke
				(width 0.1524)
				(type default)
			)
			(layer "F.SilkS")
		)
		(fp_line
			(start -0.67945 -0.305054)
			(end -0.12065 -0.305054)
			(stroke
				(width 0.1)
				(type default)
			)
			(layer "F.Fab")
		)
		(fp_line
			(start -0.67945 0.3048)
			(end -0.67945 -0.305054)
			(stroke
				(width 0.1)
				(type default)
			)
			(layer "F.Fab")
		)
		(fp_line
			(start -0.12065 -0.305054)
			(end -0.12065 -0.2794)
			(stroke
				(width 0.1)
				(type default)
			)
			(layer "F.Fab")
		)
		(fp_line
			(start -0.12065 -0.2794)
			(end 0.12065 -0.2794)
			(stroke
				(width 0.1)
				(type default)
			)
			(layer "F.Fab")
		)
		(fp_line
			(start -0.12065 0.2794)
			(end -0.12065 0.3048)
			(stroke
				(width 0.1)
				(type default)
			)
			(layer "F.Fab")
		)
		(fp_line
			(start -0.12065 0.3048)
			(end -0.67945 0.3048)
			(stroke
				(width 0.1)
				(type default)
			)
			(layer "F.Fab")
		)
		(fp_line
			(start 0.120396 0.2794)
			(end -0.12065 0.2794)
			(stroke
				(width 0.1)
				(type default)
			)
			(layer "F.Fab")
		)
		(fp_line
			(start 0.120396 0.3048)
			(end 0.120396 0.2794)
			(stroke
				(width 0.1)
				(type default)
			)
			(layer "F.Fab")
		)
		(fp_line
			(start 0.12065 -0.3048)
			(end 0.67945 -0.3048)
			(stroke
				(width 0.1)
				(type default)
			)
			(layer "F.Fab")
		)
		(fp_line
			(start 0.12065 -0.2794)
			(end 0.12065 -0.3048)
			(stroke
				(width 0.1)
				(type default)
			)
			(layer "F.Fab")
		)
		(fp_line
			(start 0.67945 -0.3048)
			(end 0.67945 0.3048)
			(stroke
				(width 0.1)
				(type default)
			)
			(layer "F.Fab")
		)
		(fp_line
			(start 0.67945 0.3048)
			(end 0.120396 0.3048)
			(stroke
				(width 0.1)
				(type default)
			)
			(layer "F.Fab")
		)
		(pad "1" smd circle
			(at -0.40005 0)
			(size 0 0)
			(layers "F.Cu" "F.Mask" "F.Paste")
			(net "PEX2_PCA9555_0_INT_N")
		)
		(pad "2" smd circle
			(at 0.40005 0)
			(size 0 0)
			(layers "F.Cu" "F.Mask" "F.Paste")
			(net "P1V8_PEX")
		)
	)
	(footprint ""
		(layer "F.Cu")
		(at 136.445244 -99.243642 180)
		(property "Reference" "R1573"
			(at 0 0 180)
			(layer "F.SilkS")
			(hide yes)
			(effects
				(font
					(size 1.27 1.27)
				)
			)
		)
		(property "Value" ""
			(at 0 0 180)
			(layer "F.Fab")
			(effects
				(font
					(size 1.27 1.27)
				)
			)
		)
		(duplicate_pad_numbers_are_jumpers no)
		(fp_line
			(start 0.7874 0.4064)
			(end -0.7874 0.4064)
			(stroke
				(width 0.1524)
				(type default)
			)
			(layer "F.SilkS")
		)
		(fp_line
			(start 0.7874 -0.4064)
			(end 0.7874 0.4064)
			(stroke
				(width 0.1524)
				(type default)
			)
			(layer "F.SilkS")
		)
		(fp_line
			(start -0.7874 0.4064)
			(end -0.7874 -0.4064)
			(stroke
				(width 0.1524)
				(type default)
			)
			(layer "F.SilkS")
		)
		(fp_line
			(start -0.7874 -0.4064)
			(end 0.7874 -0.4064)
			(stroke
				(width 0.1524)
				(type default)
			)
			(layer "F.SilkS")
		)
		(fp_line
			(start 0.67945 0.3048)
			(end 0.120396 0.3048)
			(stroke
				(width 0.1)
				(type default)
			)
			(layer "F.Fab")
		)
		(fp_line
			(start 0.67945 -0.3048)
			(end 0.67945 0.3048)
			(stroke
				(width 0.1)
				(type default)
			)
			(layer "F.Fab")
		)
		(fp_line
			(start 0.12065 -0.2794)
			(end 0.12065 -0.3048)
			(stroke
				(width 0.1)
				(type default)
			)
			(layer "F.Fab")
		)
		(fp_line
			(start 0.12065 -0.3048)
			(end 0.67945 -0.3048)
			(stroke
				(width 0.1)
				(type default)
			)
			(layer "F.Fab")
		)
		(fp_line
			(start 0.120396 0.3048)
			(end 0.120396 0.2794)
			(stroke
				(width 0.1)
				(type default)
			)
			(layer "F.Fab")
		)
		(fp_line
			(start 0.120396 0.2794)
			(end -0.12065 0.2794)
			(stroke
				(width 0.1)
				(type default)
			)
			(layer "F.Fab")
		)
		(fp_line
			(start -0.12065 0.3048)
			(end -0.67945 0.3048)
			(stroke
				(width 0.1)
				(type default)
			)
			(layer "F.Fab")
		)
		(fp_line
			(start -0.12065 0.2794)
			(end -0.12065 0.3048)
			(stroke
				(width 0.1)
				(type default)
			)
			(layer "F.Fab")
		)
		(fp_line
			(start -0.12065 -0.2794)
			(end 0.12065 -0.2794)
			(stroke
				(width 0.1)
				(type default)
			)
			(layer "F.Fab")
		)
		(fp_line
			(start -0.12065 -0.305054)
			(end -0.12065 -0.2794)
			(stroke
				(width 0.1)
				(type default)
			)
			(layer "F.Fab")
		)
		(fp_line
			(start -0.67945 0.3048)
			(end -0.67945 -0.305054)
			(stroke
				(width 0.1)
				(type default)
			)
			(layer "F.Fab")
		)
		(fp_line
			(start -0.67945 -0.305054)
			(end -0.12065 -0.305054)
			(stroke
				(width 0.1)
				(type default)
			)
			(layer "F.Fab")
		)
		(pad "1" smd circle
			(at -0.40005 0 180)
			(size 0 0)
			(layers "F.Cu" "F.Mask" "F.Paste")
			(net "SMB_BIC_I2C9_SSD_MUX_R_SDA")
		)
		(pad "2" smd circle
			(at 0.40005 0 180)
			(size 0 0)
			(layers "F.Cu" "F.Mask" "F.Paste")
			(net "SMB_BIC_I2C9_SSD_MUX0_SDA")
		)
	)
	(footprint ""
		(layer "F.Cu")
		(at 131.25958 -152.71115 -90)
		(property "Reference" "R709"
			(at 0 0 270)
			(layer "F.SilkS")
			(hide yes)
			(effects
				(font
					(size 1.27 1.27)
				)
			)
		)
		(property "Value" ""
			(at 0 0 270)
			(layer "F.Fab")
			(effects
				(font
					(size 1.27 1.27)
				)
			)
		)
		(duplicate_pad_numbers_are_jumpers no)
		(fp_line
			(start -0.7874 0.4064)
			(end -0.7874 -0.4064)
			(stroke
				(width 0.1524)
				(type default)
			)
			(layer "F.SilkS")
		)
		(fp_line
			(start 0.7874 0.4064)
			(end -0.7874 0.4064)
			(stroke
				(width 0.1524)
				(type default)
			)
			(layer "F.SilkS")
		)
		(fp_line
			(start -0.7874 -0.4064)
			(end 0.7874 -0.4064)
			(stroke
				(width 0.1524)
				(type default)
			)
			(layer "F.SilkS")
		)
		(fp_line
			(start 0.7874 -0.4064)
			(end 0.7874 0.4064)
			(stroke
				(width 0.1524)
				(type default)
			)
			(layer "F.SilkS")
		)
		(fp_line
			(start -0.67945 0.3048)
			(end -0.67945 -0.305054)
			(stroke
				(width 0.1)
				(type default)
			)
			(layer "F.Fab")
		)
		(fp_line
			(start -0.12065 0.3048)
			(end -0.67945 0.3048)
			(stroke
				(width 0.1)
				(type default)
			)
			(layer "F.Fab")
		)
		(fp_line
			(start 0.120396 0.3048)
			(end 0.120396 0.2794)
			(stroke
				(width 0.1)
				(type default)
			)
			(layer "F.Fab")
		)
		(fp_line
			(start 0.67945 0.3048)
			(end 0.120396 0.3048)
			(stroke
				(width 0.1)
				(type default)
			)
			(layer "F.Fab")
		)
		(fp_line
			(start -0.12065 0.2794)
			(end -0.12065 0.3048)
			(stroke
				(width 0.1)
				(type default)
			)
			(layer "F.Fab")
		)
		(fp_line
			(start 0.120396 0.2794)
			(end -0.12065 0.2794)
			(stroke
				(width 0.1)
				(type default)
			)
			(layer "F.Fab")
		)
		(fp_line
			(start -0.12065 -0.2794)
			(end 0.12065 -0.2794)
			(stroke
				(width 0.1)
				(type default)
			)
			(layer "F.Fab")
		)
		(fp_line
			(start 0.12065 -0.2794)
			(end 0.12065 -0.3048)
			(stroke
				(width 0.1)
				(type default)
			)
			(layer "F.Fab")
		)
		(fp_line
			(start 0.12065 -0.3048)
			(end 0.67945 -0.3048)
			(stroke
				(width 0.1)
				(type default)
			)
			(layer "F.Fab")
		)
		(fp_line
			(start 0.67945 -0.3048)
			(end 0.67945 0.3048)
			(stroke
				(width 0.1)
				(type default)
			)
			(layer "F.Fab")
		)
		(fp_line
			(start -0.67945 -0.305054)
			(end -0.12065 -0.305054)
			(stroke
				(width 0.1)
				(type default)
			)
			(layer "F.Fab")
		)
		(fp_line
			(start -0.12065 -0.305054)
			(end -0.12065 -0.2794)
			(stroke
				(width 0.1)
				(type default)
			)
			(layer "F.Fab")
		)
		(pad "1" smd circle
			(at -0.40005 0 270)
			(size 0 0)
			(layers "F.Cu" "F.Mask" "F.Paste")
			(net "SMB_BIC_I2C6_MUX_NIC_ADC_R_SCL")
		)
		(pad "2" smd circle
			(at 0.40005 0 270)
			(size 0 0)
			(layers "F.Cu" "F.Mask" "F.Paste")
			(net "SMB_NIC2_ADC_SCL")
		)
	)
	(footprint ""
		(layer "F.Cu")
		(at 148.21916 -59.574684 90)
		(property "Reference" "PC505"
			(at 0 0 90)
			(layer "F.SilkS")
			(hide yes)
			(effects
				(font
					(size 1.27 1.27)
				)
			)
		)
		(property "Value" ""
			(at 0 0 90)
			(layer "F.Fab")
			(effects
				(font
					(size 1.27 1.27)
				)
			)
		)
		(duplicate_pad_numbers_are_jumpers no)
		(fp_line
			(start 0.7874 -0.4064)
			(end 0.7874 0.4064)
			(stroke
				(width 0.1524)
				(type default)
			)
			(layer "F.SilkS")
		)
		(fp_line
			(start -0.7874 -0.4064)
			(end 0.7874 -0.4064)
			(stroke
				(width 0.1524)
				(type default)
			)
			(layer "F.SilkS")
		)
		(fp_line
			(start 0.7874 0.4064)
			(end -0.7874 0.4064)
			(stroke
				(width 0.1524)
				(type default)
			)
			(layer "F.SilkS")
		)
		(fp_line
			(start -0.7874 0.4064)
			(end -0.7874 -0.4064)
			(stroke
				(width 0.1524)
				(type default)
			)
			(layer "F.SilkS")
		)
		(fp_line
			(start -0.12065 -0.305054)
			(end -0.12065 -0.2794)
			(stroke
				(width 0.1)
				(type default)
			)
			(layer "F.Fab")
		)
		(fp_line
			(start -0.67945 -0.305054)
			(end -0.12065 -0.305054)
			(stroke
				(width 0.1)
				(type default)
			)
			(layer "F.Fab")
		)
		(fp_line
			(start 0.67945 -0.3048)
			(end 0.67945 0.3048)
			(stroke
				(width 0.1)
				(type default)
			)
			(layer "F.Fab")
		)
		(fp_line
			(start 0.12065 -0.3048)
			(end 0.67945 -0.3048)
			(stroke
				(width 0.1)
				(type default)
			)
			(layer "F.Fab")
		)
		(fp_line
			(start 0.12065 -0.2794)
			(end 0.12065 -0.3048)
			(stroke
				(width 0.1)
				(type default)
			)
			(layer "F.Fab")
		)
		(fp_line
			(start -0.12065 -0.2794)
			(end 0.12065 -0.2794)
			(stroke
				(width 0.1)
				(type default)
			)
			(layer "F.Fab")
		)
		(fp_line
			(start 0.120396 0.2794)
			(end -0.12065 0.2794)
			(stroke
				(width 0.1)
				(type default)
			)
			(layer "F.Fab")
		)
		(fp_line
			(start -0.12065 0.2794)
			(end -0.12065 0.3048)
			(stroke
				(width 0.1)
				(type default)
			)
			(layer "F.Fab")
		)
		(fp_line
			(start 0.67945 0.3048)
			(end 0.120396 0.3048)
			(stroke
				(width 0.1)
				(type default)
			)
			(layer "F.Fab")
		)
		(fp_line
			(start 0.120396 0.3048)
			(end 0.120396 0.2794)
			(stroke
				(width 0.1)
				(type default)
			)
			(layer "F.Fab")
		)
		(fp_line
			(start -0.12065 0.3048)
			(end -0.67945 0.3048)
			(stroke
				(width 0.1)
				(type default)
			)
			(layer "F.Fab")
		)
		(fp_line
			(start -0.67945 0.3048)
			(end -0.67945 -0.305054)
			(stroke
				(width 0.1)
				(type default)
			)
			(layer "F.Fab")
		)
		(pad "1" smd circle
			(at -0.40005 0 90)
			(size 0 0)
			(layers "F.Cu" "F.Mask" "F.Paste")
			(net "P5V_AUX")
		)
		(pad "2" smd circle
			(at 0.40005 0 90)
			(size 0 0)
			(layers "F.Cu" "F.Mask" "F.Paste")
			(net "GND")
		)
	)
	(footprint ""
		(layer "F.Cu")
		(at 423.95648 -17.419574 180)
		(property "Reference" "R1730"
			(at 0 0 180)
			(layer "F.SilkS")
			(hide yes)
			(effects
				(font
					(size 1.27 1.27)
				)
			)
		)
		(property "Value" ""
			(at 0 0 180)
			(layer "F.Fab")
			(effects
				(font
					(size 1.27 1.27)
				)
			)
		)
		(duplicate_pad_numbers_are_jumpers no)
		(fp_line
			(start 0.7874 0.4064)
			(end -0.7874 0.4064)
			(stroke
				(width 0.1524)
				(type default)
			)
			(layer "F.SilkS")
		)
		(fp_line
			(start 0.7874 -0.4064)
			(end 0.7874 0.4064)
			(stroke
				(width 0.1524)
				(type default)
			)
			(layer "F.SilkS")
		)
		(fp_line
			(start -0.7874 0.4064)
			(end -0.7874 -0.4064)
			(stroke
				(width 0.1524)
				(type default)
			)
			(layer "F.SilkS")
		)
		(fp_line
			(start -0.7874 -0.4064)
			(end 0.7874 -0.4064)
			(stroke
				(width 0.1524)
				(type default)
			)
			(layer "F.SilkS")
		)
		(fp_line
			(start 0.67945 0.3048)
			(end 0.120396 0.3048)
			(stroke
				(width 0.1)
				(type default)
			)
			(layer "F.Fab")
		)
		(fp_line
			(start 0.67945 -0.3048)
			(end 0.67945 0.3048)
			(stroke
				(width 0.1)
				(type default)
			)
			(layer "F.Fab")
		)
		(fp_line
			(start 0.12065 -0.2794)
			(end 0.12065 -0.3048)
			(stroke
				(width 0.1)
				(type default)
			)
			(layer "F.Fab")
		)
		(fp_line
			(start 0.12065 -0.3048)
			(end 0.67945 -0.3048)
			(stroke
				(width 0.1)
				(type default)
			)
			(layer "F.Fab")
		)
		(fp_line
			(start 0.120396 0.3048)
			(end 0.120396 0.2794)
			(stroke
				(width 0.1)
				(type default)
			)
			(layer "F.Fab")
		)
		(fp_line
			(start 0.120396 0.2794)
			(end -0.12065 0.2794)
			(stroke
				(width 0.1)
				(type default)
			)
			(layer "F.Fab")
		)
		(fp_line
			(start -0.12065 0.3048)
			(end -0.67945 0.3048)
			(stroke
				(width 0.1)
				(type default)
			)
			(layer "F.Fab")
		)
		(fp_line
			(start -0.12065 0.2794)
			(end -0.12065 0.3048)
			(stroke
				(width 0.1)
				(type default)
			)
			(layer "F.Fab")
		)
		(fp_line
			(start -0.12065 -0.2794)
			(end 0.12065 -0.2794)
			(stroke
				(width 0.1)
				(type default)
			)
			(layer "F.Fab")
		)
		(fp_line
			(start -0.12065 -0.305054)
			(end -0.12065 -0.2794)
			(stroke
				(width 0.1)
				(type default)
			)
			(layer "F.Fab")
		)
		(fp_line
			(start -0.67945 0.3048)
			(end -0.67945 -0.305054)
			(stroke
				(width 0.1)
				(type default)
			)
			(layer "F.Fab")
		)
		(fp_line
			(start -0.67945 -0.305054)
			(end -0.12065 -0.305054)
			(stroke
				(width 0.1)
				(type default)
			)
			(layer "F.Fab")
		)
		(pad "1" smd circle
			(at -0.40005 0 180)
			(size 0 0)
			(layers "F.Cu" "F.Mask" "F.Paste")
			(net "P3V3_SSD14")
		)
		(pad "2" smd circle
			(at 0.40005 0 180)
			(size 0 0)
			(layers "F.Cu" "F.Mask" "F.Paste")
			(net "SMB_ISO_SSD14_SCL")
		)
	)
	(footprint ""
		(layer "F.Cu")
		(at 186.738768 -22.867366 90)
		(property "Reference" "C3915"
			(at 0 0 90)
			(layer "F.SilkS")
			(hide yes)
			(effects
				(font
					(size 1.27 1.27)
				)
			)
		)
		(property "Value" ""
			(at 0 0 90)
			(layer "F.Fab")
			(effects
				(font
					(size 1.27 1.27)
				)
			)
		)
		(duplicate_pad_numbers_are_jumpers no)
		(fp_line
			(start 0.7874 -0.4064)
			(end 0.7874 0.4064)
			(stroke
				(width 0.1524)
				(type default)
			)
			(layer "F.SilkS")
		)
		(fp_line
			(start -0.7874 -0.4064)
			(end 0.7874 -0.4064)
			(stroke
				(width 0.1524)
				(type default)
			)
			(layer "F.SilkS")
		)
		(fp_line
			(start 0.7874 0.4064)
			(end -0.7874 0.4064)
			(stroke
				(width 0.1524)
				(type default)
			)
			(layer "F.SilkS")
		)
		(fp_line
			(start -0.7874 0.4064)
			(end -0.7874 -0.4064)
			(stroke
				(width 0.1524)
				(type default)
			)
			(layer "F.SilkS")
		)
		(fp_line
			(start -0.12065 -0.305054)
			(end -0.12065 -0.2794)
			(stroke
				(width 0.1)
				(type default)
			)
			(layer "F.Fab")
		)
		(fp_line
			(start -0.67945 -0.305054)
			(end -0.12065 -0.305054)
			(stroke
				(width 0.1)
				(type default)
			)
			(layer "F.Fab")
		)
		(fp_line
			(start 0.67945 -0.3048)
			(end 0.67945 0.3048)
			(stroke
				(width 0.1)
				(type default)
			)
			(layer "F.Fab")
		)
		(fp_line
			(start 0.12065 -0.3048)
			(end 0.67945 -0.3048)
			(stroke
				(width 0.1)
				(type default)
			)
			(layer "F.Fab")
		)
		(fp_line
			(start 0.12065 -0.2794)
			(end 0.12065 -0.3048)
			(stroke
				(width 0.1)
				(type default)
			)
			(layer "F.Fab")
		)
		(fp_line
			(start -0.12065 -0.2794)
			(end 0.12065 -0.2794)
			(stroke
				(width 0.1)
				(type default)
			)
			(layer "F.Fab")
		)
		(fp_line
			(start 0.120396 0.2794)
			(end -0.12065 0.2794)
			(stroke
				(width 0.1)
				(type default)
			)
			(layer "F.Fab")
		)
		(fp_line
			(start -0.12065 0.2794)
			(end -0.12065 0.3048)
			(stroke
				(width 0.1)
				(type default)
			)
			(layer "F.Fab")
		)
		(fp_line
			(start 0.67945 0.3048)
			(end 0.120396 0.3048)
			(stroke
				(width 0.1)
				(type default)
			)
			(layer "F.Fab")
		)
		(fp_line
			(start 0.120396 0.3048)
			(end 0.120396 0.2794)
			(stroke
				(width 0.1)
				(type default)
			)
			(layer "F.Fab")
		)
		(fp_line
			(start -0.12065 0.3048)
			(end -0.67945 0.3048)
			(stroke
				(width 0.1)
				(type default)
			)
			(layer "F.Fab")
		)
		(fp_line
			(start -0.67945 0.3048)
			(end -0.67945 -0.305054)
			(stroke
				(width 0.1)
				(type default)
			)
			(layer "F.Fab")
		)
		(pad "1" smd circle
			(at -0.40005 0 90)
			(size 0 0)
			(layers "F.Cu" "F.Mask" "F.Paste")
			(net "P12V_SSD6")
		)
		(pad "2" smd circle
			(at 0.40005 0 90)
			(size 0 0)
			(layers "F.Cu" "F.Mask" "F.Paste")
			(net "GND")
		)
	)
	(footprint ""
		(layer "F.Cu")
		(at 319.692782 -385.942586)
		(property "Reference" "R6771"
			(at 0 0 0)
			(layer "F.SilkS")
			(hide yes)
			(effects
				(font
					(size 1.27 1.27)
				)
			)
		)
		(property "Value" ""
			(at 0 0 0)
			(layer "F.Fab")
			(effects
				(font
					(size 1.27 1.27)
				)
			)
		)
		(duplicate_pad_numbers_are_jumpers no)
		(fp_line
			(start -0.7874 -0.4064)
			(end 0.7874 -0.4064)
			(stroke
				(width 0.1524)
				(type default)
			)
			(layer "F.SilkS")
		)
		(fp_line
			(start -0.7874 0.4064)
			(end -0.7874 -0.4064)
			(stroke
				(width 0.1524)
				(type default)
			)
			(layer "F.SilkS")
		)
		(fp_line
			(start 0.7874 -0.4064)
			(end 0.7874 0.4064)
			(stroke
				(width 0.1524)
				(type default)
			)
			(layer "F.SilkS")
		)
		(fp_line
			(start 0.7874 0.4064)
			(end -0.7874 0.4064)
			(stroke
				(width 0.1524)
				(type default)
			)
			(layer "F.SilkS")
		)
		(fp_line
			(start -0.67945 -0.305054)
			(end -0.12065 -0.305054)
			(stroke
				(width 0.1)
				(type default)
			)
			(layer "F.Fab")
		)
		(fp_line
			(start -0.67945 0.3048)
			(end -0.67945 -0.305054)
			(stroke
				(width 0.1)
				(type default)
			)
			(layer "F.Fab")
		)
		(fp_line
			(start -0.12065 -0.305054)
			(end -0.12065 -0.2794)
			(stroke
				(width 0.1)
				(type default)
			)
			(layer "F.Fab")
		)
		(fp_line
			(start -0.12065 -0.2794)
			(end 0.12065 -0.2794)
			(stroke
				(width 0.1)
				(type default)
			)
			(layer "F.Fab")
		)
		(fp_line
			(start -0.12065 0.2794)
			(end -0.12065 0.3048)
			(stroke
				(width 0.1)
				(type default)
			)
			(layer "F.Fab")
		)
		(fp_line
			(start -0.12065 0.3048)
			(end -0.67945 0.3048)
			(stroke
				(width 0.1)
				(type default)
			)
			(layer "F.Fab")
		)
		(fp_line
			(start 0.120396 0.2794)
			(end -0.12065 0.2794)
			(stroke
				(width 0.1)
				(type default)
			)
			(layer "F.Fab")
		)
		(fp_line
			(start 0.120396 0.3048)
			(end 0.120396 0.2794)
			(stroke
				(width 0.1)
				(type default)
			)
			(layer "F.Fab")
		)
		(fp_line
			(start 0.12065 -0.3048)
			(end 0.67945 -0.3048)
			(stroke
				(width 0.1)
				(type default)
			)
			(layer "F.Fab")
		)
		(fp_line
			(start 0.12065 -0.2794)
			(end 0.12065 -0.3048)
			(stroke
				(width 0.1)
				(type default)
			)
			(layer "F.Fab")
		)
		(fp_line
			(start 0.67945 -0.3048)
			(end 0.67945 0.3048)
			(stroke
				(width 0.1)
				(type default)
			)
			(layer "F.Fab")
		)
		(fp_line
			(start 0.67945 0.3048)
			(end 0.120396 0.3048)
			(stroke
				(width 0.1)
				(type default)
			)
			(layer "F.Fab")
		)
		(pad "1" smd circle
			(at -0.40005 0)
			(size 0 0)
			(layers "F.Cu" "F.Mask" "F.Paste")
			(net "PRSNT_SWB_B2_N")
		)
		(pad "2" smd circle
			(at 0.40005 0)
			(size 0 0)
			(layers "F.Cu" "F.Mask" "F.Paste")
			(net "GND")
		)
	)
	(footprint ""
		(layer "F.Cu")
		(at 387.62178 -343.952322 90)
		(property "Reference" "C793"
			(at 0 0 90)
			(layer "F.SilkS")
			(hide yes)
			(effects
				(font
					(size 1.27 1.27)
				)
			)
		)
		(property "Value" ""
			(at 0 0 90)
			(layer "F.Fab")
			(effects
				(font
					(size 1.27 1.27)
				)
			)
		)
		(duplicate_pad_numbers_are_jumpers no)
		(fp_line
			(start 0.299974 -0.150114)
			(end 0.299974 0.150114)
			(stroke
				(width 0.1)
				(type default)
			)
			(layer "F.Fab")
		)
		(fp_line
			(start -0.299974 -0.150114)
			(end 0.299974 -0.150114)
			(stroke
				(width 0.1)
				(type default)
			)
			(layer "F.Fab")
		)
		(fp_line
			(start 0.299974 0.150114)
			(end -0.299974 0.150114)
			(stroke
				(width 0.1)
				(type default)
			)
			(layer "F.Fab")
		)
		(fp_line
			(start -0.299974 0.150114)
			(end -0.299974 -0.150114)
			(stroke
				(width 0.1)
				(type default)
			)
			(layer "F.Fab")
		)
		(pad "1" smd rect
			(at -0.2667 0 90)
			(size 0.3048 0.381)
			(layers "F.Cu" "F.Mask" "F.Paste")
			(net "P5E_PEX3_STN6_TX_DN<96>")
		)
		(pad "2" smd rect
			(at 0.2667 0 90)
			(size 0.3048 0.381)
			(layers "F.Cu" "F.Mask" "F.Paste")
			(net "P5E_PEX3_STN6_TX_C_DN<96>")
		)
	)
	(footprint ""
		(layer "F.Cu")
		(at 140.374116 -26.31186 -90)
		(property "Reference" "U402"
			(at -0.10414 -2.324354 90)
			(unlocked yes)
			(layer "F.SilkS")
			(effects
				(font
					(size 0.7874 0.5842)
					(thickness 0.1524)
				)
			)
		)
		(property "Value" ""
			(at 0 0 270)
			(layer "F.Fab")
			(effects
				(font
					(size 1.27 1.27)
				)
			)
		)
		(duplicate_pad_numbers_are_jumpers no)
		(fp_line
			(start -1.949958 1.610106)
			(end -1.949958 -1.610106)
			(stroke
				(width 0.1524)
				(type default)
			)
			(layer "F.SilkS")
		)
		(fp_line
			(start 1.949958 1.610106)
			(end -1.949958 1.610106)
			(stroke
				(width 0.1524)
				(type default)
			)
			(layer "F.SilkS")
		)
		(fp_line
			(start 1.949958 -1.560068)
			(end 1.949958 1.610106)
			(stroke
				(width 0.1524)
				(type default)
			)
			(layer "F.SilkS")
		)
		(fp_line
			(start -1.949958 -1.610106)
			(end 1.949958 -1.610106)
			(stroke
				(width 0.1524)
				(type default)
			)
			(layer "F.SilkS")
		)
		(fp_line
			(start -0.750062 1.560068)
			(end -0.750062 -1.560068)
			(stroke
				(width 0.1)
				(type default)
			)
			(layer "F.Fab")
		)
		(fp_line
			(start 0.750062 1.560068)
			(end -0.750062 1.560068)
			(stroke
				(width 0.1)
				(type default)
			)
			(layer "F.Fab")
		)
		(fp_line
			(start -0.750062 -1.560068)
			(end 0.750062 -1.560068)
			(stroke
				(width 0.1)
				(type default)
			)
			(layer "F.Fab")
		)
		(fp_line
			(start 0.750062 -1.560068)
			(end 0.750062 1.560068)
			(stroke
				(width 0.1)
				(type default)
			)
			(layer "F.Fab")
		)
		(pad "D" smd rect
			(at 1.100074 0 180)
			(size 1.016 1.4224)
			(layers "F.Cu" "F.Mask" "F.Paste")
			(net "SSD4_LED_ISO_N")
		)
		(pad "G" smd rect
			(at -1.100074 -0.94996 180)
			(size 1.016 1.4224)
			(layers "F.Cu" "F.Mask" "F.Paste")
			(net "SSD4_LED_R")
		)
		(pad "S" smd rect
			(at -1.100074 0.94996 180)
			(size 1.016 1.4224)
			(layers "F.Cu" "F.Mask" "F.Paste")
			(net "GND")
		)
	)
	(footprint ""
		(layer "F.Cu")
		(at 97.526602 -55.418228 90)
		(property "Reference" "PC392"
			(at 0 0 90)
			(layer "F.SilkS")
			(hide yes)
			(effects
				(font
					(size 1.27 1.27)
				)
			)
		)
		(property "Value" ""
			(at 0 0 90)
			(layer "F.Fab")
			(effects
				(font
					(size 1.27 1.27)
				)
			)
		)
		(duplicate_pad_numbers_are_jumpers no)
		(fp_line
			(start 0.7874 -0.4064)
			(end 0.7874 0.4064)
			(stroke
				(width 0.1524)
				(type default)
			)
			(layer "F.SilkS")
		)
		(fp_line
			(start -0.7874 -0.4064)
			(end 0.7874 -0.4064)
			(stroke
				(width 0.1524)
				(type default)
			)
			(layer "F.SilkS")
		)
		(fp_line
			(start 0.7874 0.4064)
			(end -0.7874 0.4064)
			(stroke
				(width 0.1524)
				(type default)
			)
			(layer "F.SilkS")
		)
		(fp_line
			(start -0.7874 0.4064)
			(end -0.7874 -0.4064)
			(stroke
				(width 0.1524)
				(type default)
			)
			(layer "F.SilkS")
		)
		(fp_line
			(start -0.12065 -0.305054)
			(end -0.12065 -0.2794)
			(stroke
				(width 0.1)
				(type default)
			)
			(layer "F.Fab")
		)
		(fp_line
			(start -0.67945 -0.305054)
			(end -0.12065 -0.305054)
			(stroke
				(width 0.1)
				(type default)
			)
			(layer "F.Fab")
		)
		(fp_line
			(start 0.67945 -0.3048)
			(end 0.67945 0.3048)
			(stroke
				(width 0.1)
				(type default)
			)
			(layer "F.Fab")
		)
		(fp_line
			(start 0.12065 -0.3048)
			(end 0.67945 -0.3048)
			(stroke
				(width 0.1)
				(type default)
			)
			(layer "F.Fab")
		)
		(fp_line
			(start 0.12065 -0.2794)
			(end 0.12065 -0.3048)
			(stroke
				(width 0.1)
				(type default)
			)
			(layer "F.Fab")
		)
		(fp_line
			(start -0.12065 -0.2794)
			(end 0.12065 -0.2794)
			(stroke
				(width 0.1)
				(type default)
			)
			(layer "F.Fab")
		)
		(fp_line
			(start 0.120396 0.2794)
			(end -0.12065 0.2794)
			(stroke
				(width 0.1)
				(type default)
			)
			(layer "F.Fab")
		)
		(fp_line
			(start -0.12065 0.2794)
			(end -0.12065 0.3048)
			(stroke
				(width 0.1)
				(type default)
			)
			(layer "F.Fab")
		)
		(fp_line
			(start 0.67945 0.3048)
			(end 0.120396 0.3048)
			(stroke
				(width 0.1)
				(type default)
			)
			(layer "F.Fab")
		)
		(fp_line
			(start 0.120396 0.3048)
			(end 0.120396 0.2794)
			(stroke
				(width 0.1)
				(type default)
			)
			(layer "F.Fab")
		)
		(fp_line
			(start -0.12065 0.3048)
			(end -0.67945 0.3048)
			(stroke
				(width 0.1)
				(type default)
			)
			(layer "F.Fab")
		)
		(fp_line
			(start -0.67945 0.3048)
			(end -0.67945 -0.305054)
			(stroke
				(width 0.1)
				(type default)
			)
			(layer "F.Fab")
		)
		(pad "1" smd circle
			(at -0.40005 0 90)
			(size 0 0)
			(layers "F.Cu" "F.Mask" "F.Paste")
			(net "P12V_SSD3_R")
		)
		(pad "2" smd circle
			(at 0.40005 0 90)
			(size 0 0)
			(layers "F.Cu" "F.Mask" "F.Paste")
			(net "GND")
		)
	)
	(footprint ""
		(layer "F.Cu")
		(at 242.730528 -144.067276 180)
		(property "Reference" "PC800"
			(at 0 0 180)
			(layer "F.SilkS")
			(hide yes)
			(effects
				(font
					(size 1.27 1.27)
				)
			)
		)
		(property "Value" ""
			(at 0 0 180)
			(layer "F.Fab")
			(effects
				(font
					(size 1.27 1.27)
				)
			)
		)
		(duplicate_pad_numbers_are_jumpers no)
		(fp_line
			(start 1.524 0.762)
			(end -1.524 0.762)
			(stroke
				(width 0.1524)
				(type default)
			)
			(layer "F.SilkS")
		)
		(fp_line
			(start 1.524 -0.762)
			(end 1.524 0.762)
			(stroke
				(width 0.1524)
				(type default)
			)
			(layer "F.SilkS")
		)
		(fp_line
			(start -1.524 0.762)
			(end -1.524 -0.762)
			(stroke
				(width 0.1524)
				(type default)
			)
			(layer "F.SilkS")
		)
		(fp_line
			(start -1.524 -0.762)
			(end 1.524 -0.762)
			(stroke
				(width 0.1524)
				(type default)
			)
			(layer "F.SilkS")
		)
		(fp_line
			(start 1.1049 0.724916)
			(end 1.1049 -0.724916)
			(stroke
				(width 0.1)
				(type default)
			)
			(layer "F.Fab")
		)
		(fp_line
			(start 1.1049 -0.724916)
			(end -1.1049 -0.724916)
			(stroke
				(width 0.1)
				(type default)
			)
			(layer "F.Fab")
		)
		(fp_line
			(start -1.1049 0.724916)
			(end 1.1049 0.724916)
			(stroke
				(width 0.1)
				(type default)
			)
			(layer "F.Fab")
		)
		(fp_line
			(start -1.1049 -0.724916)
			(end -1.1049 0.724916)
			(stroke
				(width 0.1)
				(type default)
			)
			(layer "F.Fab")
		)
		(pad "1" smd rect
			(at -0.889 0)
			(size 1.016 1.27)
			(layers "F.Cu" "F.Mask" "F.Paste")
			(net "P12V_NIC4_R")
		)
		(pad "2" smd rect
			(at 0.889 0)
			(size 1.016 1.27)
			(layers "F.Cu" "F.Mask" "F.Paste")
			(net "GND")
		)
	)
	(footprint ""
		(layer "F.Cu")
		(at 71.257922 -72.766682 90)
		(property "Reference" "PC651"
			(at 0 0 90)
			(layer "F.SilkS")
			(hide yes)
			(effects
				(font
					(size 1.27 1.27)
				)
			)
		)
		(property "Value" ""
			(at 0 0 90)
			(layer "F.Fab")
			(effects
				(font
					(size 1.27 1.27)
				)
			)
		)
		(duplicate_pad_numbers_are_jumpers no)
		(fp_line
			(start 0.7874 -0.4064)
			(end 0.7874 0.4064)
			(stroke
				(width 0.1524)
				(type default)
			)
			(layer "F.SilkS")
		)
		(fp_line
			(start -0.7874 -0.4064)
			(end 0.7874 -0.4064)
			(stroke
				(width 0.1524)
				(type default)
			)
			(layer "F.SilkS")
		)
		(fp_line
			(start 0.7874 0.4064)
			(end -0.7874 0.4064)
			(stroke
				(width 0.1524)
				(type default)
			)
			(layer "F.SilkS")
		)
		(fp_line
			(start -0.7874 0.4064)
			(end -0.7874 -0.4064)
			(stroke
				(width 0.1524)
				(type default)
			)
			(layer "F.SilkS")
		)
		(fp_line
			(start -0.12065 -0.305054)
			(end -0.12065 -0.2794)
			(stroke
				(width 0.1)
				(type default)
			)
			(layer "F.Fab")
		)
		(fp_line
			(start -0.67945 -0.305054)
			(end -0.12065 -0.305054)
			(stroke
				(width 0.1)
				(type default)
			)
			(layer "F.Fab")
		)
		(fp_line
			(start 0.67945 -0.3048)
			(end 0.67945 0.3048)
			(stroke
				(width 0.1)
				(type default)
			)
			(layer "F.Fab")
		)
		(fp_line
			(start 0.12065 -0.3048)
			(end 0.67945 -0.3048)
			(stroke
				(width 0.1)
				(type default)
			)
			(layer "F.Fab")
		)
		(fp_line
			(start 0.12065 -0.2794)
			(end 0.12065 -0.3048)
			(stroke
				(width 0.1)
				(type default)
			)
			(layer "F.Fab")
		)
		(fp_line
			(start -0.12065 -0.2794)
			(end 0.12065 -0.2794)
			(stroke
				(width 0.1)
				(type default)
			)
			(layer "F.Fab")
		)
		(fp_line
			(start 0.120396 0.2794)
			(end -0.12065 0.2794)
			(stroke
				(width 0.1)
				(type default)
			)
			(layer "F.Fab")
		)
		(fp_line
			(start -0.12065 0.2794)
			(end -0.12065 0.3048)
			(stroke
				(width 0.1)
				(type default)
			)
			(layer "F.Fab")
		)
		(fp_line
			(start 0.67945 0.3048)
			(end 0.120396 0.3048)
			(stroke
				(width 0.1)
				(type default)
			)
			(layer "F.Fab")
		)
		(fp_line
			(start 0.120396 0.3048)
			(end 0.120396 0.2794)
			(stroke
				(width 0.1)
				(type default)
			)
			(layer "F.Fab")
		)
		(fp_line
			(start -0.12065 0.3048)
			(end -0.67945 0.3048)
			(stroke
				(width 0.1)
				(type default)
			)
			(layer "F.Fab")
		)
		(fp_line
			(start -0.67945 0.3048)
			(end -0.67945 -0.305054)
			(stroke
				(width 0.1)
				(type default)
			)
			(layer "F.Fab")
		)
		(pad "1" smd circle
			(at -0.40005 0 90)
			(size 0 0)
			(layers "F.Cu" "F.Mask" "F.Paste")
			(net "P12V_SSD2_CO_MODE")
		)
		(pad "2" smd circle
			(at 0.40005 0 90)
			(size 0 0)
			(layers "F.Cu" "F.Mask" "F.Paste")
			(net "GND")
		)
	)
	(footprint ""
		(layer "F.Cu")
		(at 222.053658 -184.053226)
		(property "Reference" "U362"
			(at -1.524 -1.87833 0)
			(unlocked yes)
			(layer "F.SilkS")
			(effects
				(font
					(size 0.7874 0.5842)
					(thickness 0.1524)
				)
				(justify left)
			)
		)
		(property "Value" ""
			(at 0 0 0)
			(layer "F.Fab")
			(effects
				(font
					(size 1.27 1.27)
				)
			)
		)
		(duplicate_pad_numbers_are_jumpers no)
		(fp_line
			(start -1.4986 -1.100074)
			(end 1.4986 -1.100074)
			(stroke
				(width 0.1524)
				(type default)
			)
			(layer "F.SilkS")
		)
		(fp_line
			(start -1.4986 1.100074)
			(end -1.4986 -1.100074)
			(stroke
				(width 0.1524)
				(type default)
			)
			(layer "F.SilkS")
		)
		(fp_line
			(start 1.4986 -1.100074)
			(end 1.4986 1.100074)
			(stroke
				(width 0.1524)
				(type default)
			)
			(layer "F.SilkS")
		)
		(fp_line
			(start 1.4986 1.100074)
			(end -1.4986 1.100074)
			(stroke
				(width 0.1524)
				(type default)
			)
			(layer "F.SilkS")
		)
		(fp_poly
			(pts
				(xy -2.323338 -1.214628) (xy -1.881632 -1.656334) (xy -1.72212 -1.032764)
			)
			(stroke
				(width 0)
				(type default)
			)
			(fill yes)
			(layer "F.SilkS")
		)
		(fp_line
			(start -0.67437 -1.100074)
			(end 0.67437 -1.100074)
			(stroke
				(width 0.1)
				(type default)
			)
			(layer "F.Fab")
		)
		(fp_line
			(start -0.67437 1.100074)
			(end -0.67437 -1.100074)
			(stroke
				(width 0.1)
				(type default)
			)
			(layer "F.Fab")
		)
		(fp_line
			(start 0.67437 -1.100074)
			(end 0.67437 1.100074)
			(stroke
				(width 0.1)
				(type default)
			)
			(layer "F.Fab")
		)
		(fp_line
			(start 0.67437 1.100074)
			(end -0.67437 1.100074)
			(stroke
				(width 0.1)
				(type default)
			)
			(layer "F.Fab")
		)
		(fp_poly
			(pts
				(xy -2.20472 -0.338328) (xy -2.20472 -0.963168) (xy -1.651 -0.635)
			)
			(stroke
				(width 0)
				(type default)
			)
			(fill yes)
			(layer "F.Fab")
		)
		(pad "1" smd rect
			(at -0.889 -0.649986)
			(size 1.016 0.381)
			(layers "F.Cu" "F.Mask" "F.Paste")
			(net "Net_8959")
		)
		(pad "2" smd rect
			(at -0.889 0)
			(size 1.016 0.381)
			(layers "F.Cu" "F.Mask" "F.Paste")
			(net "RST_BIC_BUF_RSMRST_N")
		)
		(pad "3" smd rect
			(at -0.889 0.649986)
			(size 1.016 0.381)
			(layers "F.Cu" "F.Mask" "F.Paste")
			(net "GND")
		)
		(pad "4" smd rect
			(at 0.889 0.649986)
			(size 1.016 0.381)
			(layers "F.Cu" "F.Mask" "F.Paste")
			(net "RST_BIC_BUF_RSMRST_N_BUF")
		)
		(pad "5" smd rect
			(at 0.889 -0.649986)
			(size 1.016 0.381)
			(layers "F.Cu" "F.Mask" "F.Paste")
			(net "P3V3_AUX")
		)
	)
	(footprint ""
		(layer "F.Cu")
		(at 80.915002 -350.098614 90)
		(property "Reference" "C110"
			(at 0 0 90)
			(layer "F.SilkS")
			(hide yes)
			(effects
				(font
					(size 1.27 1.27)
				)
			)
		)
		(property "Value" ""
			(at 0 0 90)
			(layer "F.Fab")
			(effects
				(font
					(size 1.27 1.27)
				)
			)
		)
		(duplicate_pad_numbers_are_jumpers no)
		(fp_line
			(start 0.299974 -0.150114)
			(end 0.299974 0.150114)
			(stroke
				(width 0.1)
				(type default)
			)
			(layer "F.Fab")
		)
		(fp_line
			(start -0.299974 -0.150114)
			(end 0.299974 -0.150114)
			(stroke
				(width 0.1)
				(type default)
			)
			(layer "F.Fab")
		)
		(fp_line
			(start 0.299974 0.150114)
			(end -0.299974 0.150114)
			(stroke
				(width 0.1)
				(type default)
			)
			(layer "F.Fab")
		)
		(fp_line
			(start -0.299974 0.150114)
			(end -0.299974 -0.150114)
			(stroke
				(width 0.1)
				(type default)
			)
			(layer "F.Fab")
		)
		(pad "1" smd rect
			(at -0.2667 0 90)
			(size 0.3048 0.381)
			(layers "F.Cu" "F.Mask" "F.Paste")
			(net "P5E_PEX0_STN5_TX_DN<89>")
		)
		(pad "2" smd rect
			(at 0.2667 0 90)
			(size 0.3048 0.381)
			(layers "F.Cu" "F.Mask" "F.Paste")
			(net "P5E_PEX0_STN5_TX_C_DN<89>")
		)
	)
	(footprint ""
		(layer "F.Cu")
		(at 441.273692 -343.952322 90)
		(property "Reference" "C797"
			(at 0 0 90)
			(layer "F.SilkS")
			(hide yes)
			(effects
				(font
					(size 1.27 1.27)
				)
			)
		)
		(property "Value" ""
			(at 0 0 90)
			(layer "F.Fab")
			(effects
				(font
					(size 1.27 1.27)
				)
			)
		)
		(duplicate_pad_numbers_are_jumpers no)
		(fp_line
			(start 0.299974 -0.150114)
			(end 0.299974 0.150114)
			(stroke
				(width 0.1)
				(type default)
			)
			(layer "F.Fab")
		)
		(fp_line
			(start -0.299974 -0.150114)
			(end 0.299974 -0.150114)
			(stroke
				(width 0.1)
				(type default)
			)
			(layer "F.Fab")
		)
		(fp_line
			(start 0.299974 0.150114)
			(end -0.299974 0.150114)
			(stroke
				(width 0.1)
				(type default)
			)
			(layer "F.Fab")
		)
		(fp_line
			(start -0.299974 0.150114)
			(end -0.299974 -0.150114)
			(stroke
				(width 0.1)
				(type default)
			)
			(layer "F.Fab")
		)
		(pad "1" smd rect
			(at -0.2667 0 90)
			(size 0.3048 0.381)
			(layers "F.Cu" "F.Mask" "F.Paste")
			(net "P5E_PEX3_STN7_TX_DN<126>")
		)
		(pad "2" smd rect
			(at 0.2667 0 90)
			(size 0.3048 0.381)
			(layers "F.Cu" "F.Mask" "F.Paste")
			(net "P5E_PEX3_STN7_TX_C_DN<126>")
		)
	)
	(footprint ""
		(layer "F.Cu")
		(at 99.28987 -72.766682 90)
		(property "Reference" "PR6912"
			(at 0 0 90)
			(layer "F.SilkS")
			(hide yes)
			(effects
				(font
					(size 1.27 1.27)
				)
			)
		)
		(property "Value" ""
			(at 0 0 90)
			(layer "F.Fab")
			(effects
				(font
					(size 1.27 1.27)
				)
			)
		)
		(duplicate_pad_numbers_are_jumpers no)
		(fp_line
			(start 0.7874 -0.4064)
			(end 0.7874 0.4064)
			(stroke
				(width 0.1524)
				(type default)
			)
			(layer "F.SilkS")
		)
		(fp_line
			(start -0.7874 -0.4064)
			(end 0.7874 -0.4064)
			(stroke
				(width 0.1524)
				(type default)
			)
			(layer "F.SilkS")
		)
		(fp_line
			(start 0.7874 0.4064)
			(end -0.7874 0.4064)
			(stroke
				(width 0.1524)
				(type default)
			)
			(layer "F.SilkS")
		)
		(fp_line
			(start -0.7874 0.4064)
			(end -0.7874 -0.4064)
			(stroke
				(width 0.1524)
				(type default)
			)
			(layer "F.SilkS")
		)
		(fp_line
			(start -0.12065 -0.305054)
			(end -0.12065 -0.2794)
			(stroke
				(width 0.1)
				(type default)
			)
			(layer "F.Fab")
		)
		(fp_line
			(start -0.67945 -0.305054)
			(end -0.12065 -0.305054)
			(stroke
				(width 0.1)
				(type default)
			)
			(layer "F.Fab")
		)
		(fp_line
			(start 0.67945 -0.3048)
			(end 0.67945 0.3048)
			(stroke
				(width 0.1)
				(type default)
			)
			(layer "F.Fab")
		)
		(fp_line
			(start 0.12065 -0.3048)
			(end 0.67945 -0.3048)
			(stroke
				(width 0.1)
				(type default)
			)
			(layer "F.Fab")
		)
		(fp_line
			(start 0.12065 -0.2794)
			(end 0.12065 -0.3048)
			(stroke
				(width 0.1)
				(type default)
			)
			(layer "F.Fab")
		)
		(fp_line
			(start -0.12065 -0.2794)
			(end 0.12065 -0.2794)
			(stroke
				(width 0.1)
				(type default)
			)
			(layer "F.Fab")
		)
		(fp_line
			(start 0.120396 0.2794)
			(end -0.12065 0.2794)
			(stroke
				(width 0.1)
				(type default)
			)
			(layer "F.Fab")
		)
		(fp_line
			(start -0.12065 0.2794)
			(end -0.12065 0.3048)
			(stroke
				(width 0.1)
				(type default)
			)
			(layer "F.Fab")
		)
		(fp_line
			(start 0.67945 0.3048)
			(end 0.120396 0.3048)
			(stroke
				(width 0.1)
				(type default)
			)
			(layer "F.Fab")
		)
		(fp_line
			(start 0.120396 0.3048)
			(end 0.120396 0.2794)
			(stroke
				(width 0.1)
				(type default)
			)
			(layer "F.Fab")
		)
		(fp_line
			(start -0.12065 0.3048)
			(end -0.67945 0.3048)
			(stroke
				(width 0.1)
				(type default)
			)
			(layer "F.Fab")
		)
		(fp_line
			(start -0.67945 0.3048)
			(end -0.67945 -0.305054)
			(stroke
				(width 0.1)
				(type default)
			)
			(layer "F.Fab")
		)
		(pad "1" smd circle
			(at -0.40005 0 90)
			(size 0 0)
			(layers "F.Cu" "F.Mask" "F.Paste")
			(net "P12V_SSD3_CO_ILIMIT")
		)
		(pad "2" smd circle
			(at 0.40005 0 90)
			(size 0 0)
			(layers "F.Cu" "F.Mask" "F.Paste")
			(net "GND")
		)
	)
	(footprint ""
		(layer "F.Cu")
		(at 143.091154 -255.359662)
		(property "Reference" "C3239"
			(at 0 0 0)
			(layer "F.SilkS")
			(hide yes)
			(effects
				(font
					(size 1.27 1.27)
				)
			)
		)
		(property "Value" ""
			(at 0 0 0)
			(layer "F.Fab")
			(effects
				(font
					(size 1.27 1.27)
				)
			)
		)
		(duplicate_pad_numbers_are_jumpers no)
		(fp_line
			(start -1.2954 -0.5842)
			(end 1.2954 -0.5842)
			(stroke
				(width 0.1524)
				(type default)
			)
			(layer "F.SilkS")
		)
		(fp_line
			(start -1.2954 0.5842)
			(end -1.2954 -0.5842)
			(stroke
				(width 0.1524)
				(type default)
			)
			(layer "F.SilkS")
		)
		(fp_line
			(start 1.2954 -0.5842)
			(end 1.2954 0.5842)
			(stroke
				(width 0.1524)
				(type default)
			)
			(layer "F.SilkS")
		)
		(fp_line
			(start 1.2954 0.5842)
			(end -1.2954 0.5842)
			(stroke
				(width 0.1524)
				(type default)
			)
			(layer "F.SilkS")
		)
		(fp_line
			(start -1.1938 -0.4064)
			(end -0.8636 -0.4064)
			(stroke
				(width 0.1)
				(type default)
			)
			(layer "F.Fab")
		)
		(fp_line
			(start -1.1938 0.4064)
			(end -1.1938 -0.4064)
			(stroke
				(width 0.1)
				(type default)
			)
			(layer "F.Fab")
		)
		(fp_line
			(start -0.8636 -0.4572)
			(end 0.8636 -0.4572)
			(stroke
				(width 0.1)
				(type default)
			)
			(layer "F.Fab")
		)
		(fp_line
			(start -0.8636 -0.4064)
			(end -0.8636 -0.4572)
			(stroke
				(width 0.1)
				(type default)
			)
			(layer "F.Fab")
		)
		(fp_line
			(start -0.8636 0.4064)
			(end -1.1938 0.4064)
			(stroke
				(width 0.1)
				(type default)
			)
			(layer "F.Fab")
		)
		(fp_line
			(start -0.8636 0.4572)
			(end -0.8636 0.4064)
			(stroke
				(width 0.1)
				(type default)
			)
			(layer "F.Fab")
		)
		(fp_line
			(start 0.8636 -0.4572)
			(end 0.8636 -0.4064)
			(stroke
				(width 0.1)
				(type default)
			)
			(layer "F.Fab")
		)
		(fp_line
			(start 0.8636 -0.4064)
			(end 1.1938 -0.4064)
			(stroke
				(width 0.1)
				(type default)
			)
			(layer "F.Fab")
		)
		(fp_line
			(start 0.8636 0.4064)
			(end 0.8636 0.4572)
			(stroke
				(width 0.1)
				(type default)
			)
			(layer "F.Fab")
		)
		(fp_line
			(start 0.8636 0.4572)
			(end -0.8636 0.4572)
			(stroke
				(width 0.1)
				(type default)
			)
			(layer "F.Fab")
		)
		(fp_line
			(start 1.1938 -0.4064)
			(end 1.1938 0.4064)
			(stroke
				(width 0.1)
				(type default)
			)
			(layer "F.Fab")
		)
		(fp_line
			(start 1.1938 0.4064)
			(end 0.8636 0.4064)
			(stroke
				(width 0.1)
				(type default)
			)
			(layer "F.Fab")
		)
		(pad "1" smd rect
			(at -0.7366 0 270)
			(size 0.7112 0.8128)
			(layers "F.Cu" "F.Mask" "F.Paste")
			(net "P1V8_PLL0_PEX1")
		)
		(pad "2" smd rect
			(at 0.7366 0 270)
			(size 0.7112 0.8128)
			(layers "F.Cu" "F.Mask" "F.Paste")
			(net "GND")
		)
	)
	(footprint ""
		(layer "F.Cu")
		(at 124.220732 -26.666444 -90)
		(property "Reference" "R4061"
			(at 0 0 270)
			(layer "F.SilkS")
			(hide yes)
			(effects
				(font
					(size 1.27 1.27)
				)
			)
		)
		(property "Value" ""
			(at 0 0 270)
			(layer "F.Fab")
			(effects
				(font
					(size 1.27 1.27)
				)
			)
		)
		(duplicate_pad_numbers_are_jumpers no)
		(fp_line
			(start -0.7874 0.4064)
			(end -0.7874 -0.4064)
			(stroke
				(width 0.1524)
				(type default)
			)
			(layer "F.SilkS")
		)
		(fp_line
			(start 0.7874 0.4064)
			(end -0.7874 0.4064)
			(stroke
				(width 0.1524)
				(type default)
			)
			(layer "F.SilkS")
		)
		(fp_line
			(start -0.7874 -0.4064)
			(end 0.7874 -0.4064)
			(stroke
				(width 0.1524)
				(type default)
			)
			(layer "F.SilkS")
		)
		(fp_line
			(start 0.7874 -0.4064)
			(end 0.7874 0.4064)
			(stroke
				(width 0.1524)
				(type default)
			)
			(layer "F.SilkS")
		)
		(fp_line
			(start -0.67945 0.3048)
			(end -0.67945 -0.305054)
			(stroke
				(width 0.1)
				(type default)
			)
			(layer "F.Fab")
		)
		(fp_line
			(start -0.12065 0.3048)
			(end -0.67945 0.3048)
			(stroke
				(width 0.1)
				(type default)
			)
			(layer "F.Fab")
		)
		(fp_line
			(start 0.120396 0.3048)
			(end 0.120396 0.2794)
			(stroke
				(width 0.1)
				(type default)
			)
			(layer "F.Fab")
		)
		(fp_line
			(start 0.67945 0.3048)
			(end 0.120396 0.3048)
			(stroke
				(width 0.1)
				(type default)
			)
			(layer "F.Fab")
		)
		(fp_line
			(start -0.12065 0.2794)
			(end -0.12065 0.3048)
			(stroke
				(width 0.1)
				(type default)
			)
			(layer "F.Fab")
		)
		(fp_line
			(start 0.120396 0.2794)
			(end -0.12065 0.2794)
			(stroke
				(width 0.1)
				(type default)
			)
			(layer "F.Fab")
		)
		(fp_line
			(start -0.12065 -0.2794)
			(end 0.12065 -0.2794)
			(stroke
				(width 0.1)
				(type default)
			)
			(layer "F.Fab")
		)
		(fp_line
			(start 0.12065 -0.2794)
			(end 0.12065 -0.3048)
			(stroke
				(width 0.1)
				(type default)
			)
			(layer "F.Fab")
		)
		(fp_line
			(start 0.12065 -0.3048)
			(end 0.67945 -0.3048)
			(stroke
				(width 0.1)
				(type default)
			)
			(layer "F.Fab")
		)
		(fp_line
			(start 0.67945 -0.3048)
			(end 0.67945 0.3048)
			(stroke
				(width 0.1)
				(type default)
			)
			(layer "F.Fab")
		)
		(fp_line
			(start -0.67945 -0.305054)
			(end -0.12065 -0.305054)
			(stroke
				(width 0.1)
				(type default)
			)
			(layer "F.Fab")
		)
		(fp_line
			(start -0.12065 -0.305054)
			(end -0.12065 -0.2794)
			(stroke
				(width 0.1)
				(type default)
			)
			(layer "F.Fab")
		)
		(pad "1" smd circle
			(at -0.40005 0 270)
			(size 0 0)
			(layers "F.Cu" "F.Mask" "F.Paste")
			(net "PRSNT_SSD4_R_N")
		)
		(pad "2" smd circle
			(at 0.40005 0 270)
			(size 0 0)
			(layers "F.Cu" "F.Mask" "F.Paste")
			(net "PRSNT_SSD4_N")
		)
	)
	(footprint ""
		(layer "F.Cu")
		(at 194.367912 -56.353456)
		(property "Reference" "C2866"
			(at 0 0 0)
			(layer "F.SilkS")
			(hide yes)
			(effects
				(font
					(size 1.27 1.27)
				)
			)
		)
		(property "Value" ""
			(at 0 0 0)
			(layer "F.Fab")
			(effects
				(font
					(size 1.27 1.27)
				)
			)
		)
		(duplicate_pad_numbers_are_jumpers no)
		(fp_line
			(start -0.7874 -0.4064)
			(end 0.7874 -0.4064)
			(stroke
				(width 0.1524)
				(type default)
			)
			(layer "F.SilkS")
		)
		(fp_line
			(start -0.7874 0.4064)
			(end -0.7874 -0.4064)
			(stroke
				(width 0.1524)
				(type default)
			)
			(layer "F.SilkS")
		)
		(fp_line
			(start 0.7874 -0.4064)
			(end 0.7874 0.4064)
			(stroke
				(width 0.1524)
				(type default)
			)
			(layer "F.SilkS")
		)
		(fp_line
			(start 0.7874 0.4064)
			(end -0.7874 0.4064)
			(stroke
				(width 0.1524)
				(type default)
			)
			(layer "F.SilkS")
		)
		(fp_line
			(start -0.67945 -0.305054)
			(end -0.12065 -0.305054)
			(stroke
				(width 0.1)
				(type default)
			)
			(layer "F.Fab")
		)
		(fp_line
			(start -0.67945 0.3048)
			(end -0.67945 -0.305054)
			(stroke
				(width 0.1)
				(type default)
			)
			(layer "F.Fab")
		)
		(fp_line
			(start -0.12065 -0.305054)
			(end -0.12065 -0.2794)
			(stroke
				(width 0.1)
				(type default)
			)
			(layer "F.Fab")
		)
		(fp_line
			(start -0.12065 -0.2794)
			(end 0.12065 -0.2794)
			(stroke
				(width 0.1)
				(type default)
			)
			(layer "F.Fab")
		)
		(fp_line
			(start -0.12065 0.2794)
			(end -0.12065 0.3048)
			(stroke
				(width 0.1)
				(type default)
			)
			(layer "F.Fab")
		)
		(fp_line
			(start -0.12065 0.3048)
			(end -0.67945 0.3048)
			(stroke
				(width 0.1)
				(type default)
			)
			(layer "F.Fab")
		)
		(fp_line
			(start 0.120396 0.2794)
			(end -0.12065 0.2794)
			(stroke
				(width 0.1)
				(type default)
			)
			(layer "F.Fab")
		)
		(fp_line
			(start 0.120396 0.3048)
			(end 0.120396 0.2794)
			(stroke
				(width 0.1)
				(type default)
			)
			(layer "F.Fab")
		)
		(fp_line
			(start 0.12065 -0.3048)
			(end 0.67945 -0.3048)
			(stroke
				(width 0.1)
				(type default)
			)
			(layer "F.Fab")
		)
		(fp_line
			(start 0.12065 -0.2794)
			(end 0.12065 -0.3048)
			(stroke
				(width 0.1)
				(type default)
			)
			(layer "F.Fab")
		)
		(fp_line
			(start 0.67945 -0.3048)
			(end 0.67945 0.3048)
			(stroke
				(width 0.1)
				(type default)
			)
			(layer "F.Fab")
		)
		(fp_line
			(start 0.67945 0.3048)
			(end 0.120396 0.3048)
			(stroke
				(width 0.1)
				(type default)
			)
			(layer "F.Fab")
		)
		(pad "1" smd circle
			(at -0.40005 0)
			(size 0 0)
			(layers "F.Cu" "F.Mask" "F.Paste")
			(net "SSD6_PWR_EN_R")
		)
		(pad "2" smd circle
			(at 0.40005 0)
			(size 0 0)
			(layers "F.Cu" "F.Mask" "F.Paste")
			(net "GND")
		)
	)
	(footprint ""
		(layer "F.Cu")
		(at 349.426276 -37.929566 90)
		(property "Reference" "R5567"
			(at 0 0 90)
			(layer "F.SilkS")
			(hide yes)
			(effects
				(font
					(size 1.27 1.27)
				)
			)
		)
		(property "Value" ""
			(at 0 0 90)
			(layer "F.Fab")
			(effects
				(font
					(size 1.27 1.27)
				)
			)
		)
		(duplicate_pad_numbers_are_jumpers no)
		(fp_line
			(start 0.7874 -0.4064)
			(end 0.7874 0.4064)
			(stroke
				(width 0.1524)
				(type default)
			)
			(layer "F.SilkS")
		)
		(fp_line
			(start -0.7874 -0.4064)
			(end 0.7874 -0.4064)
			(stroke
				(width 0.1524)
				(type default)
			)
			(layer "F.SilkS")
		)
		(fp_line
			(start 0.7874 0.4064)
			(end -0.7874 0.4064)
			(stroke
				(width 0.1524)
				(type default)
			)
			(layer "F.SilkS")
		)
		(fp_line
			(start -0.7874 0.4064)
			(end -0.7874 -0.4064)
			(stroke
				(width 0.1524)
				(type default)
			)
			(layer "F.SilkS")
		)
		(fp_line
			(start -0.12065 -0.305054)
			(end -0.12065 -0.2794)
			(stroke
				(width 0.1)
				(type default)
			)
			(layer "F.Fab")
		)
		(fp_line
			(start -0.67945 -0.305054)
			(end -0.12065 -0.305054)
			(stroke
				(width 0.1)
				(type default)
			)
			(layer "F.Fab")
		)
		(fp_line
			(start 0.67945 -0.3048)
			(end 0.67945 0.3048)
			(stroke
				(width 0.1)
				(type default)
			)
			(layer "F.Fab")
		)
		(fp_line
			(start 0.12065 -0.3048)
			(end 0.67945 -0.3048)
			(stroke
				(width 0.1)
				(type default)
			)
			(layer "F.Fab")
		)
		(fp_line
			(start 0.12065 -0.2794)
			(end 0.12065 -0.3048)
			(stroke
				(width 0.1)
				(type default)
			)
			(layer "F.Fab")
		)
		(fp_line
			(start -0.12065 -0.2794)
			(end 0.12065 -0.2794)
			(stroke
				(width 0.1)
				(type default)
			)
			(layer "F.Fab")
		)
		(fp_line
			(start 0.120396 0.2794)
			(end -0.12065 0.2794)
			(stroke
				(width 0.1)
				(type default)
			)
			(layer "F.Fab")
		)
		(fp_line
			(start -0.12065 0.2794)
			(end -0.12065 0.3048)
			(stroke
				(width 0.1)
				(type default)
			)
			(layer "F.Fab")
		)
		(fp_line
			(start 0.67945 0.3048)
			(end 0.120396 0.3048)
			(stroke
				(width 0.1)
				(type default)
			)
			(layer "F.Fab")
		)
		(fp_line
			(start 0.120396 0.3048)
			(end 0.120396 0.2794)
			(stroke
				(width 0.1)
				(type default)
			)
			(layer "F.Fab")
		)
		(fp_line
			(start -0.12065 0.3048)
			(end -0.67945 0.3048)
			(stroke
				(width 0.1)
				(type default)
			)
			(layer "F.Fab")
		)
		(fp_line
			(start -0.67945 0.3048)
			(end -0.67945 -0.305054)
			(stroke
				(width 0.1)
				(type default)
			)
			(layer "F.Fab")
		)
		(pad "1" smd circle
			(at -0.40005 0 90)
			(size 0 0)
			(layers "F.Cu" "F.Mask" "F.Paste")
			(net "SSD12_AUX_P3V3_EN_R")
		)
		(pad "2" smd circle
			(at 0.40005 0 90)
			(size 0 0)
			(layers "F.Cu" "F.Mask" "F.Paste")
			(net "SSD12_AUX_P3V3_EN")
		)
	)
	(footprint ""
		(layer "F.Cu")
		(at 223.45396 -65.712086 90)
		(property "Reference" "R3762"
			(at 0 0 90)
			(layer "F.SilkS")
			(hide yes)
			(effects
				(font
					(size 1.27 1.27)
				)
			)
		)
		(property "Value" ""
			(at 0 0 90)
			(layer "F.Fab")
			(effects
				(font
					(size 1.27 1.27)
				)
			)
		)
		(duplicate_pad_numbers_are_jumpers no)
		(fp_line
			(start 0.7874 -0.4064)
			(end 0.7874 0.4064)
			(stroke
				(width 0.1524)
				(type default)
			)
			(layer "F.SilkS")
		)
		(fp_line
			(start -0.7874 -0.4064)
			(end 0.7874 -0.4064)
			(stroke
				(width 0.1524)
				(type default)
			)
			(layer "F.SilkS")
		)
		(fp_line
			(start 0.7874 0.4064)
			(end -0.7874 0.4064)
			(stroke
				(width 0.1524)
				(type default)
			)
			(layer "F.SilkS")
		)
		(fp_line
			(start -0.7874 0.4064)
			(end -0.7874 -0.4064)
			(stroke
				(width 0.1524)
				(type default)
			)
			(layer "F.SilkS")
		)
		(fp_line
			(start -0.12065 -0.305054)
			(end -0.12065 -0.2794)
			(stroke
				(width 0.1)
				(type default)
			)
			(layer "F.Fab")
		)
		(fp_line
			(start -0.67945 -0.305054)
			(end -0.12065 -0.305054)
			(stroke
				(width 0.1)
				(type default)
			)
			(layer "F.Fab")
		)
		(fp_line
			(start 0.67945 -0.3048)
			(end 0.67945 0.3048)
			(stroke
				(width 0.1)
				(type default)
			)
			(layer "F.Fab")
		)
		(fp_line
			(start 0.12065 -0.3048)
			(end 0.67945 -0.3048)
			(stroke
				(width 0.1)
				(type default)
			)
			(layer "F.Fab")
		)
		(fp_line
			(start 0.12065 -0.2794)
			(end 0.12065 -0.3048)
			(stroke
				(width 0.1)
				(type default)
			)
			(layer "F.Fab")
		)
		(fp_line
			(start -0.12065 -0.2794)
			(end 0.12065 -0.2794)
			(stroke
				(width 0.1)
				(type default)
			)
			(layer "F.Fab")
		)
		(fp_line
			(start 0.120396 0.2794)
			(end -0.12065 0.2794)
			(stroke
				(width 0.1)
				(type default)
			)
			(layer "F.Fab")
		)
		(fp_line
			(start -0.12065 0.2794)
			(end -0.12065 0.3048)
			(stroke
				(width 0.1)
				(type default)
			)
			(layer "F.Fab")
		)
		(fp_line
			(start 0.67945 0.3048)
			(end 0.120396 0.3048)
			(stroke
				(width 0.1)
				(type default)
			)
			(layer "F.Fab")
		)
		(fp_line
			(start 0.120396 0.3048)
			(end 0.120396 0.2794)
			(stroke
				(width 0.1)
				(type default)
			)
			(layer "F.Fab")
		)
		(fp_line
			(start -0.12065 0.3048)
			(end -0.67945 0.3048)
			(stroke
				(width 0.1)
				(type default)
			)
			(layer "F.Fab")
		)
		(fp_line
			(start -0.67945 0.3048)
			(end -0.67945 -0.305054)
			(stroke
				(width 0.1)
				(type default)
			)
			(layer "F.Fab")
		)
		(pad "1" smd circle
			(at -0.40005 0 90)
			(size 0 0)
			(layers "F.Cu" "F.Mask" "F.Paste")
			(net "SMB_FIO_R2_SDA")
		)
		(pad "2" smd circle
			(at 0.40005 0 90)
			(size 0 0)
			(layers "F.Cu" "F.Mask" "F.Paste")
			(net "SMB_FIO_R1_SDA")
		)
	)
	(footprint ""
		(layer "F.Cu")
		(at 331.131164 -350.098614 90)
		(property "Reference" "C531"
			(at 0 0 90)
			(layer "F.SilkS")
			(hide yes)
			(effects
				(font
					(size 1.27 1.27)
				)
			)
		)
		(property "Value" ""
			(at 0 0 90)
			(layer "F.Fab")
			(effects
				(font
					(size 1.27 1.27)
				)
			)
		)
		(duplicate_pad_numbers_are_jumpers no)
		(fp_line
			(start 0.299974 -0.150114)
			(end 0.299974 0.150114)
			(stroke
				(width 0.1)
				(type default)
			)
			(layer "F.Fab")
		)
		(fp_line
			(start -0.299974 -0.150114)
			(end 0.299974 -0.150114)
			(stroke
				(width 0.1)
				(type default)
			)
			(layer "F.Fab")
		)
		(fp_line
			(start 0.299974 0.150114)
			(end -0.299974 0.150114)
			(stroke
				(width 0.1)
				(type default)
			)
			(layer "F.Fab")
		)
		(fp_line
			(start -0.299974 0.150114)
			(end -0.299974 -0.150114)
			(stroke
				(width 0.1)
				(type default)
			)
			(layer "F.Fab")
		)
		(pad "1" smd rect
			(at -0.2667 0 90)
			(size 0.3048 0.381)
			(layers "F.Cu" "F.Mask" "F.Paste")
			(net "P5E_PEX2_STN5_TX_DP<89>")
		)
		(pad "2" smd rect
			(at 0.2667 0 90)
			(size 0.3048 0.381)
			(layers "F.Cu" "F.Mask" "F.Paste")
			(net "P5E_PEX2_STN5_TX_C_DP<89>")
		)
	)
	(footprint ""
		(layer "F.Cu")
		(at 361.188 -182.118)
		(property "Reference" "R4703"
			(at 0 0 0)
			(layer "F.SilkS")
			(hide yes)
			(effects
				(font
					(size 1.27 1.27)
				)
			)
		)
		(property "Value" ""
			(at 0 0 0)
			(layer "F.Fab")
			(effects
				(font
					(size 1.27 1.27)
				)
			)
		)
		(duplicate_pad_numbers_are_jumpers no)
		(fp_line
			(start -0.7874 -0.4064)
			(end 0.7874 -0.4064)
			(stroke
				(width 0.1524)
				(type default)
			)
			(layer "F.SilkS")
		)
		(fp_line
			(start -0.7874 0.4064)
			(end -0.7874 -0.4064)
			(stroke
				(width 0.1524)
				(type default)
			)
			(layer "F.SilkS")
		)
		(fp_line
			(start 0.7874 -0.4064)
			(end 0.7874 0.4064)
			(stroke
				(width 0.1524)
				(type default)
			)
			(layer "F.SilkS")
		)
		(fp_line
			(start 0.7874 0.4064)
			(end -0.7874 0.4064)
			(stroke
				(width 0.1524)
				(type default)
			)
			(layer "F.SilkS")
		)
		(fp_line
			(start -0.67945 -0.305054)
			(end -0.12065 -0.305054)
			(stroke
				(width 0.1)
				(type default)
			)
			(layer "F.Fab")
		)
		(fp_line
			(start -0.67945 0.3048)
			(end -0.67945 -0.305054)
			(stroke
				(width 0.1)
				(type default)
			)
			(layer "F.Fab")
		)
		(fp_line
			(start -0.12065 -0.305054)
			(end -0.12065 -0.2794)
			(stroke
				(width 0.1)
				(type default)
			)
			(layer "F.Fab")
		)
		(fp_line
			(start -0.12065 -0.2794)
			(end 0.12065 -0.2794)
			(stroke
				(width 0.1)
				(type default)
			)
			(layer "F.Fab")
		)
		(fp_line
			(start -0.12065 0.2794)
			(end -0.12065 0.3048)
			(stroke
				(width 0.1)
				(type default)
			)
			(layer "F.Fab")
		)
		(fp_line
			(start -0.12065 0.3048)
			(end -0.67945 0.3048)
			(stroke
				(width 0.1)
				(type default)
			)
			(layer "F.Fab")
		)
		(fp_line
			(start 0.120396 0.2794)
			(end -0.12065 0.2794)
			(stroke
				(width 0.1)
				(type default)
			)
			(layer "F.Fab")
		)
		(fp_line
			(start 0.120396 0.3048)
			(end 0.120396 0.2794)
			(stroke
				(width 0.1)
				(type default)
			)
			(layer "F.Fab")
		)
		(fp_line
			(start 0.12065 -0.3048)
			(end 0.67945 -0.3048)
			(stroke
				(width 0.1)
				(type default)
			)
			(layer "F.Fab")
		)
		(fp_line
			(start 0.12065 -0.2794)
			(end 0.12065 -0.3048)
			(stroke
				(width 0.1)
				(type default)
			)
			(layer "F.Fab")
		)
		(fp_line
			(start 0.67945 -0.3048)
			(end 0.67945 0.3048)
			(stroke
				(width 0.1)
				(type default)
			)
			(layer "F.Fab")
		)
		(fp_line
			(start 0.67945 0.3048)
			(end 0.120396 0.3048)
			(stroke
				(width 0.1)
				(type default)
			)
			(layer "F.Fab")
		)
		(pad "1" smd circle
			(at -0.40005 0)
			(size 0 0)
			(layers "F.Cu" "F.Mask" "F.Paste")
			(net "PEX1_PCA9555_1_INT_N")
		)
		(pad "2" smd circle
			(at 0.40005 0)
			(size 0 0)
			(layers "F.Cu" "F.Mask" "F.Paste")
			(net "P1V8_PEX")
		)
	)
	(footprint ""
		(layer "F.Cu")
		(at 46.125384 -42.849038 180)
		(property "Reference" "R524"
			(at 0 0 180)
			(layer "F.SilkS")
			(hide yes)
			(effects
				(font
					(size 1.27 1.27)
				)
			)
		)
		(property "Value" ""
			(at 0 0 180)
			(layer "F.Fab")
			(effects
				(font
					(size 1.27 1.27)
				)
			)
		)
		(duplicate_pad_numbers_are_jumpers no)
		(fp_line
			(start 0.7874 0.4064)
			(end -0.7874 0.4064)
			(stroke
				(width 0.1524)
				(type default)
			)
			(layer "F.SilkS")
		)
		(fp_line
			(start 0.7874 -0.4064)
			(end 0.7874 0.4064)
			(stroke
				(width 0.1524)
				(type default)
			)
			(layer "F.SilkS")
		)
		(fp_line
			(start -0.7874 0.4064)
			(end -0.7874 -0.4064)
			(stroke
				(width 0.1524)
				(type default)
			)
			(layer "F.SilkS")
		)
		(fp_line
			(start -0.7874 -0.4064)
			(end 0.7874 -0.4064)
			(stroke
				(width 0.1524)
				(type default)
			)
			(layer "F.SilkS")
		)
		(fp_line
			(start 0.67945 0.3048)
			(end 0.120396 0.3048)
			(stroke
				(width 0.1)
				(type default)
			)
			(layer "F.Fab")
		)
		(fp_line
			(start 0.67945 -0.3048)
			(end 0.67945 0.3048)
			(stroke
				(width 0.1)
				(type default)
			)
			(layer "F.Fab")
		)
		(fp_line
			(start 0.12065 -0.2794)
			(end 0.12065 -0.3048)
			(stroke
				(width 0.1)
				(type default)
			)
			(layer "F.Fab")
		)
		(fp_line
			(start 0.12065 -0.3048)
			(end 0.67945 -0.3048)
			(stroke
				(width 0.1)
				(type default)
			)
			(layer "F.Fab")
		)
		(fp_line
			(start 0.120396 0.3048)
			(end 0.120396 0.2794)
			(stroke
				(width 0.1)
				(type default)
			)
			(layer "F.Fab")
		)
		(fp_line
			(start 0.120396 0.2794)
			(end -0.12065 0.2794)
			(stroke
				(width 0.1)
				(type default)
			)
			(layer "F.Fab")
		)
		(fp_line
			(start -0.12065 0.3048)
			(end -0.67945 0.3048)
			(stroke
				(width 0.1)
				(type default)
			)
			(layer "F.Fab")
		)
		(fp_line
			(start -0.12065 0.2794)
			(end -0.12065 0.3048)
			(stroke
				(width 0.1)
				(type default)
			)
			(layer "F.Fab")
		)
		(fp_line
			(start -0.12065 -0.2794)
			(end 0.12065 -0.2794)
			(stroke
				(width 0.1)
				(type default)
			)
			(layer "F.Fab")
		)
		(fp_line
			(start -0.12065 -0.305054)
			(end -0.12065 -0.2794)
			(stroke
				(width 0.1)
				(type default)
			)
			(layer "F.Fab")
		)
		(fp_line
			(start -0.67945 0.3048)
			(end -0.67945 -0.305054)
			(stroke
				(width 0.1)
				(type default)
			)
			(layer "F.Fab")
		)
		(fp_line
			(start -0.67945 -0.305054)
			(end -0.12065 -0.305054)
			(stroke
				(width 0.1)
				(type default)
			)
			(layer "F.Fab")
		)
		(pad "1" smd circle
			(at -0.40005 0 180)
			(size 0 0)
			(layers "F.Cu" "F.Mask" "F.Paste")
			(net "P12V_SSD1_R")
		)
		(pad "2" smd circle
			(at 0.40005 0 180)
			(size 0 0)
			(layers "F.Cu" "F.Mask" "F.Paste")
			(net "P12V_SSD1_VIN_P")
		)
	)
	(footprint ""
		(layer "F.Cu")
		(at 334.772 -241.808 90)
		(property "Reference" "U145"
			(at 0 -1.67513 90)
			(unlocked yes)
			(layer "F.SilkS")
			(effects
				(font
					(size 0.7874 0.5842)
					(thickness 0.1524)
				)
			)
		)
		(property "Value" ""
			(at 0 0 90)
			(layer "F.Fab")
			(effects
				(font
					(size 1.27 1.27)
				)
			)
		)
		(duplicate_pad_numbers_are_jumpers no)
		(fp_line
			(start 1.7272 -1.1176)
			(end 0.254 -1.1176)
			(stroke
				(width 0.1524)
				(type default)
			)
			(layer "F.SilkS")
		)
		(fp_line
			(start 1.7272 -1.1176)
			(end 1.7272 1.1176)
			(stroke
				(width 0.1524)
				(type default)
			)
			(layer "F.SilkS")
		)
		(fp_line
			(start 0.254 -1.1176)
			(end 0 -0.7366)
			(stroke
				(width 0.1524)
				(type default)
			)
			(layer "F.SilkS")
		)
		(fp_line
			(start -0.254 -1.1176)
			(end -1.7272 -1.1176)
			(stroke
				(width 0.1524)
				(type default)
			)
			(layer "F.SilkS")
		)
		(fp_line
			(start 0 -0.7366)
			(end -0.254 -1.1176)
			(stroke
				(width 0.1524)
				(type default)
			)
			(layer "F.SilkS")
		)
		(fp_line
			(start 1.7272 1.1176)
			(end -1.7272 1.1176)
			(stroke
				(width 0.1524)
				(type default)
			)
			(layer "F.SilkS")
		)
		(fp_line
			(start -1.7272 1.1176)
			(end -1.7272 -1.1176)
			(stroke
				(width 0.1524)
				(type default)
			)
			(layer "F.SilkS")
		)
		(fp_poly
			(pts
				(xy -1.9558 -0.649986) (xy -2.7178 -0.268986) (xy -2.7178 -1.030986)
			)
			(stroke
				(width 0)
				(type default)
			)
			(fill yes)
			(layer "F.SilkS")
		)
		(fp_line
			(start 1.5748 -1.1176)
			(end -1.5748 -1.1176)
			(stroke
				(width 0.1)
				(type default)
			)
			(layer "F.Fab")
		)
		(fp_line
			(start -1.5748 -1.1176)
			(end -1.5748 1.1176)
			(stroke
				(width 0.1)
				(type default)
			)
			(layer "F.Fab")
		)
		(fp_line
			(start 1.5748 1.1176)
			(end 1.5748 -1.1176)
			(stroke
				(width 0.1)
				(type default)
			)
			(layer "F.Fab")
		)
		(fp_line
			(start -1.5748 1.1176)
			(end 1.5748 1.1176)
			(stroke
				(width 0.1)
				(type default)
			)
			(layer "F.Fab")
		)
		(fp_poly
			(pts
				(xy -1.9558 -0.649986) (xy -2.7178 -0.268986) (xy -2.7178 -1.030986)
			)
			(stroke
				(width 0)
				(type default)
			)
			(fill yes)
			(layer "F.Fab")
		)
		(pad "1" smd rect
			(at -0.999998 -0.649986)
			(size 0.3556 1.1176)
			(layers "F.Cu" "F.Mask" "F.Paste")
			(net "MB_SWB_PWRGD_R")
		)
		(pad "2" smd rect
			(at -0.999998 0)
			(size 0.3556 1.1176)
			(layers "F.Cu" "F.Mask" "F.Paste")
			(net "GND")
		)
		(pad "3" smd rect
			(at -0.999998 0.649986)
			(size 0.3556 1.1176)
			(layers "F.Cu" "F.Mask" "F.Paste")
			(net "Net_585")
		)
		(pad "4" smd rect
			(at 0.999998 0.649986)
			(size 0.3556 1.1176)
			(layers "F.Cu" "F.Mask" "F.Paste")
			(net "Net_586")
		)
		(pad "5" smd rect
			(at 0.999998 0)
			(size 0.3556 1.1176)
			(layers "F.Cu" "F.Mask" "F.Paste")
			(net "P3V3_AUX")
		)
		(pad "6" smd rect
			(at 0.999998 -0.649986)
			(size 0.3556 1.1176)
			(layers "F.Cu" "F.Mask" "F.Paste")
			(net "MB_SWB_PWRGD_BUF")
		)
	)
	(footprint ""
		(layer "F.Cu")
		(at 13.476224 -306.924456 90)
		(property "Reference" "PR168"
			(at 0 0 90)
			(layer "F.SilkS")
			(hide yes)
			(effects
				(font
					(size 1.27 1.27)
				)
			)
		)
		(property "Value" ""
			(at 0 0 90)
			(layer "F.Fab")
			(effects
				(font
					(size 1.27 1.27)
				)
			)
		)
		(duplicate_pad_numbers_are_jumpers no)
		(fp_line
			(start 0.7874 -0.4064)
			(end 0.7874 0.4064)
			(stroke
				(width 0.1524)
				(type default)
			)
			(layer "F.SilkS")
		)
		(fp_line
			(start -0.7874 -0.4064)
			(end 0.7874 -0.4064)
			(stroke
				(width 0.1524)
				(type default)
			)
			(layer "F.SilkS")
		)
		(fp_line
			(start 0.7874 0.4064)
			(end -0.7874 0.4064)
			(stroke
				(width 0.1524)
				(type default)
			)
			(layer "F.SilkS")
		)
		(fp_line
			(start -0.7874 0.4064)
			(end -0.7874 -0.4064)
			(stroke
				(width 0.1524)
				(type default)
			)
			(layer "F.SilkS")
		)
		(fp_line
			(start -0.12065 -0.305054)
			(end -0.12065 -0.2794)
			(stroke
				(width 0.1)
				(type default)
			)
			(layer "F.Fab")
		)
		(fp_line
			(start -0.67945 -0.305054)
			(end -0.12065 -0.305054)
			(stroke
				(width 0.1)
				(type default)
			)
			(layer "F.Fab")
		)
		(fp_line
			(start 0.67945 -0.3048)
			(end 0.67945 0.3048)
			(stroke
				(width 0.1)
				(type default)
			)
			(layer "F.Fab")
		)
		(fp_line
			(start 0.12065 -0.3048)
			(end 0.67945 -0.3048)
			(stroke
				(width 0.1)
				(type default)
			)
			(layer "F.Fab")
		)
		(fp_line
			(start 0.12065 -0.2794)
			(end 0.12065 -0.3048)
			(stroke
				(width 0.1)
				(type default)
			)
			(layer "F.Fab")
		)
		(fp_line
			(start -0.12065 -0.2794)
			(end 0.12065 -0.2794)
			(stroke
				(width 0.1)
				(type default)
			)
			(layer "F.Fab")
		)
		(fp_line
			(start 0.120396 0.2794)
			(end -0.12065 0.2794)
			(stroke
				(width 0.1)
				(type default)
			)
			(layer "F.Fab")
		)
		(fp_line
			(start -0.12065 0.2794)
			(end -0.12065 0.3048)
			(stroke
				(width 0.1)
				(type default)
			)
			(layer "F.Fab")
		)
		(fp_line
			(start 0.67945 0.3048)
			(end 0.120396 0.3048)
			(stroke
				(width 0.1)
				(type default)
			)
			(layer "F.Fab")
		)
		(fp_line
			(start 0.120396 0.3048)
			(end 0.120396 0.2794)
			(stroke
				(width 0.1)
				(type default)
			)
			(layer "F.Fab")
		)
		(fp_line
			(start -0.12065 0.3048)
			(end -0.67945 0.3048)
			(stroke
				(width 0.1)
				(type default)
			)
			(layer "F.Fab")
		)
		(fp_line
			(start -0.67945 0.3048)
			(end -0.67945 -0.305054)
			(stroke
				(width 0.1)
				(type default)
			)
			(layer "F.Fab")
		)
		(pad "1" smd circle
			(at -0.40005 0 90)
			(size 0 0)
			(layers "F.Cu" "F.Mask" "F.Paste")
			(net "SH_P1V25_PEX0_FB_N")
		)
		(pad "2" smd circle
			(at 0.40005 0 90)
			(size 0 0)
			(layers "F.Cu" "F.Mask" "F.Paste")
			(net "P1V25_PEX0_FB")
		)
	)
	(footprint ""
		(layer "F.Cu")
		(at 65.370202 -350.098614 90)
		(property "Reference" "C132"
			(at 0 0 90)
			(layer "F.SilkS")
			(hide yes)
			(effects
				(font
					(size 1.27 1.27)
				)
			)
		)
		(property "Value" ""
			(at 0 0 90)
			(layer "F.Fab")
			(effects
				(font
					(size 1.27 1.27)
				)
			)
		)
		(duplicate_pad_numbers_are_jumpers no)
		(fp_line
			(start 0.299974 -0.150114)
			(end 0.299974 0.150114)
			(stroke
				(width 0.1)
				(type default)
			)
			(layer "F.Fab")
		)
		(fp_line
			(start -0.299974 -0.150114)
			(end 0.299974 -0.150114)
			(stroke
				(width 0.1)
				(type default)
			)
			(layer "F.Fab")
		)
		(fp_line
			(start 0.299974 0.150114)
			(end -0.299974 0.150114)
			(stroke
				(width 0.1)
				(type default)
			)
			(layer "F.Fab")
		)
		(fp_line
			(start -0.299974 0.150114)
			(end -0.299974 -0.150114)
			(stroke
				(width 0.1)
				(type default)
			)
			(layer "F.Fab")
		)
		(pad "1" smd rect
			(at -0.2667 0 90)
			(size 0.3048 0.381)
			(layers "F.Cu" "F.Mask" "F.Paste")
			(net "P5E_PEX0_STN6_TX_DN<110>")
		)
		(pad "2" smd rect
			(at 0.2667 0 90)
			(size 0.3048 0.381)
			(layers "F.Cu" "F.Mask" "F.Paste")
			(net "P5E_PEX0_STN6_TX_C_DN<110>")
		)
	)
	(footprint ""
		(layer "F.Cu")
		(at 403.16658 -350.098614 90)
		(property "Reference" "C747"
			(at 0 0 90)
			(layer "F.SilkS")
			(hide yes)
			(effects
				(font
					(size 1.27 1.27)
				)
			)
		)
		(property "Value" ""
			(at 0 0 90)
			(layer "F.Fab")
			(effects
				(font
					(size 1.27 1.27)
				)
			)
		)
		(duplicate_pad_numbers_are_jumpers no)
		(fp_line
			(start 0.299974 -0.150114)
			(end 0.299974 0.150114)
			(stroke
				(width 0.1)
				(type default)
			)
			(layer "F.Fab")
		)
		(fp_line
			(start -0.299974 -0.150114)
			(end 0.299974 -0.150114)
			(stroke
				(width 0.1)
				(type default)
			)
			(layer "F.Fab")
		)
		(fp_line
			(start 0.299974 0.150114)
			(end -0.299974 0.150114)
			(stroke
				(width 0.1)
				(type default)
			)
			(layer "F.Fab")
		)
		(fp_line
			(start -0.299974 0.150114)
			(end -0.299974 -0.150114)
			(stroke
				(width 0.1)
				(type default)
			)
			(layer "F.Fab")
		)
		(pad "1" smd rect
			(at -0.2667 0 90)
			(size 0.3048 0.381)
			(layers "F.Cu" "F.Mask" "F.Paste")
			(net "P5E_PEX3_STN5_TX_DN<87>")
		)
		(pad "2" smd rect
			(at 0.2667 0 90)
			(size 0.3048 0.381)
			(layers "F.Cu" "F.Mask" "F.Paste")
			(net "P5E_PEX3_STN5_TX_C_DN<87>")
		)
	)
	(footprint ""
		(layer "F.Cu")
		(at 43.792394 -31.825184 180)
		(property "Reference" "C76"
			(at 0 0 180)
			(layer "F.SilkS")
			(hide yes)
			(effects
				(font
					(size 1.27 1.27)
				)
			)
		)
		(property "Value" ""
			(at 0 0 180)
			(layer "F.Fab")
			(effects
				(font
					(size 1.27 1.27)
				)
			)
		)
		(duplicate_pad_numbers_are_jumpers no)
		(fp_line
			(start 0.299974 0.150114)
			(end -0.299974 0.150114)
			(stroke
				(width 0.1)
				(type default)
			)
			(layer "F.Fab")
		)
		(fp_line
			(start 0.299974 -0.150114)
			(end 0.299974 0.150114)
			(stroke
				(width 0.1)
				(type default)
			)
			(layer "F.Fab")
		)
		(fp_line
			(start -0.299974 0.150114)
			(end -0.299974 -0.150114)
			(stroke
				(width 0.1)
				(type default)
			)
			(layer "F.Fab")
		)
		(fp_line
			(start -0.299974 -0.150114)
			(end 0.299974 -0.150114)
			(stroke
				(width 0.1)
				(type default)
			)
			(layer "F.Fab")
		)
		(pad "1" smd rect
			(at -0.2667 0 180)
			(size 0.3048 0.381)
			(layers "F.Cu" "F.Mask" "F.Paste")
			(net "P5E_PEX0_STN2_TX_DN<42>")
		)
		(pad "2" smd rect
			(at 0.2667 0 180)
			(size 0.3048 0.381)
			(layers "F.Cu" "F.Mask" "F.Paste")
			(net "P5E_PEX0_STN2_TX_C_DN<42>")
		)
	)
	(footprint ""
		(layer "F.Cu")
		(at 245.732808 -310.571642 180)
		(property "Reference" "PR176"
			(at 0 0 180)
			(layer "F.SilkS")
			(hide yes)
			(effects
				(font
					(size 1.27 1.27)
				)
			)
		)
		(property "Value" ""
			(at 0 0 180)
			(layer "F.Fab")
			(effects
				(font
					(size 1.27 1.27)
				)
			)
		)
		(duplicate_pad_numbers_are_jumpers no)
		(fp_line
			(start 0.7874 0.4064)
			(end -0.7874 0.4064)
			(stroke
				(width 0.1524)
				(type default)
			)
			(layer "F.SilkS")
		)
		(fp_line
			(start 0.7874 -0.4064)
			(end 0.7874 0.4064)
			(stroke
				(width 0.1524)
				(type default)
			)
			(layer "F.SilkS")
		)
		(fp_line
			(start -0.7874 0.4064)
			(end -0.7874 -0.4064)
			(stroke
				(width 0.1524)
				(type default)
			)
			(layer "F.SilkS")
		)
		(fp_line
			(start -0.7874 -0.4064)
			(end 0.7874 -0.4064)
			(stroke
				(width 0.1524)
				(type default)
			)
			(layer "F.SilkS")
		)
		(fp_line
			(start 0.67945 0.3048)
			(end 0.120396 0.3048)
			(stroke
				(width 0.1)
				(type default)
			)
			(layer "F.Fab")
		)
		(fp_line
			(start 0.67945 -0.3048)
			(end 0.67945 0.3048)
			(stroke
				(width 0.1)
				(type default)
			)
			(layer "F.Fab")
		)
		(fp_line
			(start 0.12065 -0.2794)
			(end 0.12065 -0.3048)
			(stroke
				(width 0.1)
				(type default)
			)
			(layer "F.Fab")
		)
		(fp_line
			(start 0.12065 -0.3048)
			(end 0.67945 -0.3048)
			(stroke
				(width 0.1)
				(type default)
			)
			(layer "F.Fab")
		)
		(fp_line
			(start 0.120396 0.3048)
			(end 0.120396 0.2794)
			(stroke
				(width 0.1)
				(type default)
			)
			(layer "F.Fab")
		)
		(fp_line
			(start 0.120396 0.2794)
			(end -0.12065 0.2794)
			(stroke
				(width 0.1)
				(type default)
			)
			(layer "F.Fab")
		)
		(fp_line
			(start -0.12065 0.3048)
			(end -0.67945 0.3048)
			(stroke
				(width 0.1)
				(type default)
			)
			(layer "F.Fab")
		)
		(fp_line
			(start -0.12065 0.2794)
			(end -0.12065 0.3048)
			(stroke
				(width 0.1)
				(type default)
			)
			(layer "F.Fab")
		)
		(fp_line
			(start -0.12065 -0.2794)
			(end 0.12065 -0.2794)
			(stroke
				(width 0.1)
				(type default)
			)
			(layer "F.Fab")
		)
		(fp_line
			(start -0.12065 -0.305054)
			(end -0.12065 -0.2794)
			(stroke
				(width 0.1)
				(type default)
			)
			(layer "F.Fab")
		)
		(fp_line
			(start -0.67945 0.3048)
			(end -0.67945 -0.305054)
			(stroke
				(width 0.1)
				(type default)
			)
			(layer "F.Fab")
		)
		(fp_line
			(start -0.67945 -0.305054)
			(end -0.12065 -0.305054)
			(stroke
				(width 0.1)
				(type default)
			)
			(layer "F.Fab")
		)
		(pad "1" smd circle
			(at -0.40005 0 180)
			(size 0 0)
			(layers "F.Cu" "F.Mask" "F.Paste")
			(net "SH_P1V25_PEX2_FB_P")
		)
		(pad "2" smd circle
			(at 0.40005 0 180)
			(size 0 0)
			(layers "F.Cu" "F.Mask" "F.Paste")
			(net "P1V25_PEX2_FB")
		)
	)
	(footprint ""
		(layer "F.Cu")
		(at 198.76135 -136.20115 180)
		(property "Reference" "C228"
			(at 0 0 180)
			(layer "F.SilkS")
			(hide yes)
			(effects
				(font
					(size 1.27 1.27)
				)
			)
		)
		(property "Value" ""
			(at 0 0 180)
			(layer "F.Fab")
			(effects
				(font
					(size 1.27 1.27)
				)
			)
		)
		(duplicate_pad_numbers_are_jumpers no)
		(fp_line
			(start 0.299974 0.150114)
			(end -0.299974 0.150114)
			(stroke
				(width 0.1)
				(type default)
			)
			(layer "F.Fab")
		)
		(fp_line
			(start 0.299974 -0.150114)
			(end 0.299974 0.150114)
			(stroke
				(width 0.1)
				(type default)
			)
			(layer "F.Fab")
		)
		(fp_line
			(start -0.299974 0.150114)
			(end -0.299974 -0.150114)
			(stroke
				(width 0.1)
				(type default)
			)
			(layer "F.Fab")
		)
		(fp_line
			(start -0.299974 -0.150114)
			(end 0.299974 -0.150114)
			(stroke
				(width 0.1)
				(type default)
			)
			(layer "F.Fab")
		)
		(pad "1" smd rect
			(at -0.2667 0 180)
			(size 0.3048 0.381)
			(layers "F.Cu" "F.Mask" "F.Paste")
			(net "P5E_PEX1_STN0_TX_DP<7>")
		)
		(pad "2" smd rect
			(at 0.2667 0 180)
			(size 0.3048 0.381)
			(layers "F.Cu" "F.Mask" "F.Paste")
			(net "P5E_PEX1_STN0_TX_C_DP<7>")
		)
	)
	(footprint ""
		(layer "F.Cu")
		(at 212.738716 -22.867366 90)
		(property "Reference" "C3926"
			(at 0 0 90)
			(layer "F.SilkS")
			(hide yes)
			(effects
				(font
					(size 1.27 1.27)
				)
			)
		)
		(property "Value" ""
			(at 0 0 90)
			(layer "F.Fab")
			(effects
				(font
					(size 1.27 1.27)
				)
			)
		)
		(duplicate_pad_numbers_are_jumpers no)
		(fp_line
			(start 0.7874 -0.4064)
			(end 0.7874 0.4064)
			(stroke
				(width 0.1524)
				(type default)
			)
			(layer "F.SilkS")
		)
		(fp_line
			(start -0.7874 -0.4064)
			(end 0.7874 -0.4064)
			(stroke
				(width 0.1524)
				(type default)
			)
			(layer "F.SilkS")
		)
		(fp_line
			(start 0.7874 0.4064)
			(end -0.7874 0.4064)
			(stroke
				(width 0.1524)
				(type default)
			)
			(layer "F.SilkS")
		)
		(fp_line
			(start -0.7874 0.4064)
			(end -0.7874 -0.4064)
			(stroke
				(width 0.1524)
				(type default)
			)
			(layer "F.SilkS")
		)
		(fp_line
			(start -0.12065 -0.305054)
			(end -0.12065 -0.2794)
			(stroke
				(width 0.1)
				(type default)
			)
			(layer "F.Fab")
		)
		(fp_line
			(start -0.67945 -0.305054)
			(end -0.12065 -0.305054)
			(stroke
				(width 0.1)
				(type default)
			)
			(layer "F.Fab")
		)
		(fp_line
			(start 0.67945 -0.3048)
			(end 0.67945 0.3048)
			(stroke
				(width 0.1)
				(type default)
			)
			(layer "F.Fab")
		)
		(fp_line
			(start 0.12065 -0.3048)
			(end 0.67945 -0.3048)
			(stroke
				(width 0.1)
				(type default)
			)
			(layer "F.Fab")
		)
		(fp_line
			(start 0.12065 -0.2794)
			(end 0.12065 -0.3048)
			(stroke
				(width 0.1)
				(type default)
			)
			(layer "F.Fab")
		)
		(fp_line
			(start -0.12065 -0.2794)
			(end 0.12065 -0.2794)
			(stroke
				(width 0.1)
				(type default)
			)
			(layer "F.Fab")
		)
		(fp_line
			(start 0.120396 0.2794)
			(end -0.12065 0.2794)
			(stroke
				(width 0.1)
				(type default)
			)
			(layer "F.Fab")
		)
		(fp_line
			(start -0.12065 0.2794)
			(end -0.12065 0.3048)
			(stroke
				(width 0.1)
				(type default)
			)
			(layer "F.Fab")
		)
		(fp_line
			(start 0.67945 0.3048)
			(end 0.120396 0.3048)
			(stroke
				(width 0.1)
				(type default)
			)
			(layer "F.Fab")
		)
		(fp_line
			(start 0.120396 0.3048)
			(end 0.120396 0.2794)
			(stroke
				(width 0.1)
				(type default)
			)
			(layer "F.Fab")
		)
		(fp_line
			(start -0.12065 0.3048)
			(end -0.67945 0.3048)
			(stroke
				(width 0.1)
				(type default)
			)
			(layer "F.Fab")
		)
		(fp_line
			(start -0.67945 0.3048)
			(end -0.67945 -0.305054)
			(stroke
				(width 0.1)
				(type default)
			)
			(layer "F.Fab")
		)
		(pad "1" smd circle
			(at -0.40005 0 90)
			(size 0 0)
			(layers "F.Cu" "F.Mask" "F.Paste")
			(net "P12V_SSD7")
		)
		(pad "2" smd circle
			(at 0.40005 0 90)
			(size 0 0)
			(layers "F.Cu" "F.Mask" "F.Paste")
			(net "GND")
		)
	)
	(footprint ""
		(layer "F.Cu")
		(at 409.015438 -87.440008 180)
		(property "Reference" "R6269"
			(at 0 0 180)
			(layer "F.SilkS")
			(hide yes)
			(effects
				(font
					(size 1.27 1.27)
				)
			)
		)
		(property "Value" ""
			(at 0 0 180)
			(layer "F.Fab")
			(effects
				(font
					(size 1.27 1.27)
				)
			)
		)
		(duplicate_pad_numbers_are_jumpers no)
		(fp_line
			(start 0.7874 0.4064)
			(end -0.7874 0.4064)
			(stroke
				(width 0.1524)
				(type default)
			)
			(layer "F.SilkS")
		)
		(fp_line
			(start 0.7874 -0.4064)
			(end 0.7874 0.4064)
			(stroke
				(width 0.1524)
				(type default)
			)
			(layer "F.SilkS")
		)
		(fp_line
			(start -0.7874 0.4064)
			(end -0.7874 -0.4064)
			(stroke
				(width 0.1524)
				(type default)
			)
			(layer "F.SilkS")
		)
		(fp_line
			(start -0.7874 -0.4064)
			(end 0.7874 -0.4064)
			(stroke
				(width 0.1524)
				(type default)
			)
			(layer "F.SilkS")
		)
		(fp_line
			(start 0.67945 0.3048)
			(end 0.120396 0.3048)
			(stroke
				(width 0.1)
				(type default)
			)
			(layer "F.Fab")
		)
		(fp_line
			(start 0.67945 -0.3048)
			(end 0.67945 0.3048)
			(stroke
				(width 0.1)
				(type default)
			)
			(layer "F.Fab")
		)
		(fp_line
			(start 0.12065 -0.2794)
			(end 0.12065 -0.3048)
			(stroke
				(width 0.1)
				(type default)
			)
			(layer "F.Fab")
		)
		(fp_line
			(start 0.12065 -0.3048)
			(end 0.67945 -0.3048)
			(stroke
				(width 0.1)
				(type default)
			)
			(layer "F.Fab")
		)
		(fp_line
			(start 0.120396 0.3048)
			(end 0.120396 0.2794)
			(stroke
				(width 0.1)
				(type default)
			)
			(layer "F.Fab")
		)
		(fp_line
			(start 0.120396 0.2794)
			(end -0.12065 0.2794)
			(stroke
				(width 0.1)
				(type default)
			)
			(layer "F.Fab")
		)
		(fp_line
			(start -0.12065 0.3048)
			(end -0.67945 0.3048)
			(stroke
				(width 0.1)
				(type default)
			)
			(layer "F.Fab")
		)
		(fp_line
			(start -0.12065 0.2794)
			(end -0.12065 0.3048)
			(stroke
				(width 0.1)
				(type default)
			)
			(layer "F.Fab")
		)
		(fp_line
			(start -0.12065 -0.2794)
			(end 0.12065 -0.2794)
			(stroke
				(width 0.1)
				(type default)
			)
			(layer "F.Fab")
		)
		(fp_line
			(start -0.12065 -0.305054)
			(end -0.12065 -0.2794)
			(stroke
				(width 0.1)
				(type default)
			)
			(layer "F.Fab")
		)
		(fp_line
			(start -0.67945 0.3048)
			(end -0.67945 -0.305054)
			(stroke
				(width 0.1)
				(type default)
			)
			(layer "F.Fab")
		)
		(fp_line
			(start -0.67945 -0.305054)
			(end -0.12065 -0.305054)
			(stroke
				(width 0.1)
				(type default)
			)
			(layer "F.Fab")
		)
		(pad "1" smd circle
			(at -0.40005 0 180)
			(size 0 0)
			(layers "F.Cu" "F.Mask" "F.Paste")
			(net "SMB_CLK_ISO_R_SDA")
		)
		(pad "2" smd circle
			(at 0.40005 0 180)
			(size 0 0)
			(layers "F.Cu" "F.Mask" "F.Paste")
			(net "SMB_CLK_ISO_SDA")
		)
	)
	(footprint ""
		(layer "F.Cu")
		(at 107.612942 -111.785654 180)
		(property "Reference" "PU72"
			(at 3.674872 -1.397254 90)
			(unlocked yes)
			(layer "F.SilkS")
			(effects
				(font
					(size 0.7874 0.5842)
					(thickness 0.1524)
				)
				(justify left)
			)
		)
		(property "Value" ""
			(at 0 0 180)
			(layer "F.Fab")
			(effects
				(font
					(size 1.27 1.27)
				)
			)
		)
		(duplicate_pad_numbers_are_jumpers no)
		(fp_line
			(start 1.549908 2.549906)
			(end 1.549908 2.253996)
			(stroke
				(width 0.1524)
				(type default)
			)
			(layer "F.SilkS")
		)
		(fp_line
			(start 1.549908 -2.253996)
			(end 1.549908 -2.549906)
			(stroke
				(width 0.1524)
				(type default)
			)
			(layer "F.SilkS")
		)
		(fp_line
			(start 1.549908 -2.549906)
			(end 0.752094 -2.549906)
			(stroke
				(width 0.1524)
				(type default)
			)
			(layer "F.SilkS")
		)
		(fp_line
			(start 0.753872 2.549906)
			(end 1.549908 2.549906)
			(stroke
				(width 0.1524)
				(type default)
			)
			(layer "F.SilkS")
		)
		(fp_line
			(start 0.2413 -2.549906)
			(end -0.2413 -2.549906)
			(stroke
				(width 0.1524)
				(type default)
			)
			(layer "F.SilkS")
		)
		(fp_line
			(start -0.245872 2.549906)
			(end 0.245872 2.549906)
			(stroke
				(width 0.1524)
				(type default)
			)
			(layer "F.SilkS")
		)
		(fp_line
			(start -0.752094 -2.549906)
			(end -1.549908 -2.549906)
			(stroke
				(width 0.1524)
				(type default)
			)
			(layer "F.SilkS")
		)
		(fp_line
			(start -1.549908 2.549906)
			(end -0.753872 2.549906)
			(stroke
				(width 0.1524)
				(type default)
			)
			(layer "F.SilkS")
		)
		(fp_line
			(start -1.549908 2.253996)
			(end -1.549908 2.549906)
			(stroke
				(width 0.1524)
				(type default)
			)
			(layer "F.SilkS")
		)
		(fp_line
			(start -1.549908 -2.549906)
			(end -1.549908 -2.251964)
			(stroke
				(width 0.1524)
				(type default)
			)
			(layer "F.SilkS")
		)
		(fp_poly
			(pts
				(xy -1.891538 -1.999996) (xy -2.7432 -1.574292) (xy -2.7432 -2.4257)
			)
			(stroke
				(width 0)
				(type default)
			)
			(fill yes)
			(layer "F.SilkS")
		)
		(fp_line
			(start 1.549908 2.549906)
			(end 1.549908 -2.549906)
			(stroke
				(width 0.1)
				(type default)
			)
			(layer "F.Fab")
		)
		(fp_line
			(start 1.549908 -2.549906)
			(end -1.549908 -2.549906)
			(stroke
				(width 0.1)
				(type default)
			)
			(layer "F.Fab")
		)
		(fp_line
			(start -1.549908 2.549906)
			(end 1.549908 2.549906)
			(stroke
				(width 0.1)
				(type default)
			)
			(layer "F.Fab")
		)
		(fp_line
			(start -1.549908 -2.549906)
			(end -1.549908 2.549906)
			(stroke
				(width 0.1)
				(type default)
			)
			(layer "F.Fab")
		)
		(fp_poly
			(pts
				(xy -1.891538 -1.999996) (xy -2.7432 -1.574292) (xy -2.7432 -2.4257)
			)
			(stroke
				(width 0)
				(type default)
			)
			(fill yes)
			(layer "F.Fab")
		)
		(fp_text user "12"
			(at 2.482342 1.081786 90)
			(unlocked yes)
			(layer "F.SilkS")
			(effects
				(font
					(size 0.635 0.4064)
					(thickness 0.1524)
				)
			)
		)
		(fp_text user "20"
			(at 2.055368 -2.7686 90)
			(unlocked yes)
			(layer "F.SilkS")
			(effects
				(font
					(size 0.635 0.4064)
					(thickness 0.1524)
				)
			)
		)
		(fp_text user "11"
			(at 1.245362 3.077464 180)
			(unlocked yes)
			(layer "F.SilkS")
			(effects
				(font
					(size 0.635 0.4064)
					(thickness 0.1524)
				)
			)
		)
		(fp_text user "21_22"
			(at -1.138682 -3.574542 180)
			(unlocked yes)
			(layer "F.SilkS")
			(effects
				(font
					(size 0.635 0.4064)
					(thickness 0.1524)
				)
			)
		)
		(fp_text user "10"
			(at -1.4224 3.253232 180)
			(unlocked yes)
			(layer "F.SilkS")
			(effects
				(font
					(size 0.635 0.4064)
					(thickness 0.1524)
				)
			)
		)
		(fp_text user "9"
			(at -2.338832 2.5908 90)
			(unlocked yes)
			(layer "F.SilkS")
			(effects
				(font
					(size 0.635 0.4064)
					(thickness 0.1524)
				)
			)
		)
		(fp_text user "12"
			(at 2.207768 2.7178 90)
			(unlocked yes)
			(layer "F.Fab")
			(effects
				(font
					(size 0.635 0.4064)
					(thickness 0.1524)
				)
			)
		)
		(fp_text user "20"
			(at 2.055368 -2.7686 90)
			(unlocked yes)
			(layer "F.Fab")
			(effects
				(font
					(size 0.635 0.4064)
					(thickness 0.1524)
				)
			)
		)
		(fp_text user "11"
			(at 1.1938 3.329432 180)
			(unlocked yes)
			(layer "F.Fab")
			(effects
				(font
					(size 0.635 0.4064)
					(thickness 0.1524)
				)
			)
		)
		(fp_text user "21_22"
			(at -0.0762 -3.401568 180)
			(unlocked yes)
			(layer "F.Fab")
			(effects
				(font
					(size 0.635 0.4064)
					(thickness 0.1524)
				)
			)
		)
		(fp_text user "10"
			(at -1.4224 3.253232 180)
			(unlocked yes)
			(layer "F.Fab")
			(effects
				(font
					(size 0.635 0.4064)
					(thickness 0.1524)
				)
			)
		)
		(fp_text user "9"
			(at -2.338832 2.5908 90)
			(unlocked yes)
			(layer "F.Fab")
			(effects
				(font
					(size 0.635 0.4064)
					(thickness 0.1524)
				)
			)
		)
		(pad "1" smd circle
			(at -1.374902 -1.999996 90)
			(size 0 0)
			(layers "F.Cu" "F.Mask" "F.Paste")
			(net "P12V_NIC1_CO_EN")
		)
		(pad "2" smd rect
			(at -1.400048 -1.500124 90)
			(size 0.254 0.8128)
			(layers "F.Cu" "F.Mask" "F.Paste")
			(net "GND")
		)
		(pad "3" smd rect
			(at -1.400048 -0.999998 90)
			(size 0.254 0.8128)
			(layers "F.Cu" "F.Mask" "F.Paste")
			(net "GND")
		)
		(pad "4" smd rect
			(at -1.400048 -0.499872 90)
			(size 0.254 0.8128)
			(layers "F.Cu" "F.Mask" "F.Paste")
			(net "P12V_NIC1_CO_TIMER")
		)
		(pad "5" smd rect
			(at -1.400048 0 90)
			(size 0.254 0.8128)
			(layers "F.Cu" "F.Mask" "F.Paste")
			(net "P12V_NIC1_CO_ISET")
		)
		(pad "6" smd rect
			(at -1.400048 0.499872 90)
			(size 0.254 0.8128)
			(layers "F.Cu" "F.Mask" "F.Paste")
			(net "P12V_NIC1_CO_SS")
		)
		(pad "7" smd rect
			(at -1.400048 0.999998 90)
			(size 0.254 0.8128)
			(layers "F.Cu" "F.Mask" "F.Paste")
			(net "GND")
		)
		(pad "8" smd rect
			(at -1.400048 1.500124 90)
			(size 0.254 0.8128)
			(layers "F.Cu" "F.Mask" "F.Paste")
			(net "P12V_NIC1_CO_IMON_VR")
		)
		(pad "9" smd rect
			(at -1.400048 1.999996 90)
			(size 0.254 0.8128)
			(layers "F.Cu" "F.Mask" "F.Paste")
			(net "P12V_NIC1_CO_FLTB")
		)
		(pad "10" smd rect
			(at -0.499872 2.400046 180)
			(size 0.254 0.8128)
			(layers "F.Cu" "F.Mask" "F.Paste")
			(net "PWRGD_P12V_NIC1_CO")
		)
		(pad "11" smd rect
			(at 0.499872 2.400046 180)
			(size 0.254 0.8128)
			(layers "F.Cu" "F.Mask" "F.Paste")
			(net "P12V_NIC1_CO_OV_FB")
		)
		(pad "12" smd rect
			(at 1.400048 1.999996 90)
			(size 0.254 0.8128)
			(layers "F.Cu" "F.Mask" "F.Paste")
			(net "P12V_NIC1_CO_AVIN_PD")
		)
		(pad "13" smd rect
			(at 1.400048 1.500124 90)
			(size 0.254 0.8128)
			(layers "F.Cu" "F.Mask" "F.Paste")
			(net "P12V_NIC1_R")
		)
		(pad "14" smd rect
			(at 1.400048 0.999998 90)
			(size 0.254 0.8128)
			(layers "F.Cu" "F.Mask" "F.Paste")
			(net "P12V_NIC1_R")
		)
		(pad "15" smd rect
			(at 1.400048 0.499872 90)
			(size 0.254 0.8128)
			(layers "F.Cu" "F.Mask" "F.Paste")
			(net "P12V_NIC1_R")
		)
		(pad "16" smd rect
			(at 1.400048 0 90)
			(size 0.254 0.8128)
			(layers "F.Cu" "F.Mask" "F.Paste")
			(net "P12V_NIC1_R")
		)
		(pad "17" smd rect
			(at 1.400048 -0.499872 90)
			(size 0.254 0.8128)
			(layers "F.Cu" "F.Mask" "F.Paste")
			(net "P12V_NIC1_R")
		)
		(pad "18" smd rect
			(at 1.400048 -0.999998 90)
			(size 0.254 0.8128)
			(layers "F.Cu" "F.Mask" "F.Paste")
			(net "P12V_NIC1_R")
		)
		(pad "19" smd rect
			(at 1.400048 -1.500124 90)
			(size 0.254 0.8128)
			(layers "F.Cu" "F.Mask" "F.Paste")
			(net "P12V_NIC1_R")
		)
		(pad "20" smd rect
			(at 1.400048 -1.999996 90)
			(size 0.254 0.8128)
			(layers "F.Cu" "F.Mask" "F.Paste")
			(net "P12V_NIC1_R")
		)
		(pad "21_22" smd circle
			(at 0.499872 -2.337562 90)
			(size 0 0)
			(layers "F.Cu" "F.Mask" "F.Paste")
			(net "P12V_AUX")
		)
		(pad "23" smd rect
			(at 0 -1.100074 90)
			(size 0.254 1.27)
			(layers "F.Cu" "F.Mask" "F.Paste")
			(net "P12V_AUX")
		)
		(pad "24" smd rect
			(at 0 -0.199898 90)
			(size 0.254 1.27)
			(layers "F.Cu" "F.Mask" "F.Paste")
			(net "P12V_AUX")
		)
		(pad "25" smd rect
			(at 0 0.700024 90)
			(size 0.254 1.27)
			(layers "F.Cu" "F.Mask" "F.Paste")
			(net "P12V_AUX")
		)
		(pad "26" smd rect
			(at 0 1.599946 90)
			(size 0.254 1.27)
			(layers "F.Cu" "F.Mask" "F.Paste")
			(net "P12V_AUX")
		)
	)
	(footprint ""
		(layer "F.Cu")
		(at 404.28164 -157.8356)
		(property "Reference" "R354"
			(at 0 0 0)
			(layer "F.SilkS")
			(hide yes)
			(effects
				(font
					(size 1.27 1.27)
				)
			)
		)
		(property "Value" ""
			(at 0 0 0)
			(layer "F.Fab")
			(effects
				(font
					(size 1.27 1.27)
				)
			)
		)
		(duplicate_pad_numbers_are_jumpers no)
		(fp_line
			(start -0.7874 -0.4064)
			(end 0.7874 -0.4064)
			(stroke
				(width 0.1524)
				(type default)
			)
			(layer "F.SilkS")
		)
		(fp_line
			(start -0.7874 0.4064)
			(end -0.7874 -0.4064)
			(stroke
				(width 0.1524)
				(type default)
			)
			(layer "F.SilkS")
		)
		(fp_line
			(start 0.7874 -0.4064)
			(end 0.7874 0.4064)
			(stroke
				(width 0.1524)
				(type default)
			)
			(layer "F.SilkS")
		)
		(fp_line
			(start 0.7874 0.4064)
			(end -0.7874 0.4064)
			(stroke
				(width 0.1524)
				(type default)
			)
			(layer "F.SilkS")
		)
		(fp_line
			(start -0.67945 -0.305054)
			(end -0.12065 -0.305054)
			(stroke
				(width 0.1)
				(type default)
			)
			(layer "F.Fab")
		)
		(fp_line
			(start -0.67945 0.3048)
			(end -0.67945 -0.305054)
			(stroke
				(width 0.1)
				(type default)
			)
			(layer "F.Fab")
		)
		(fp_line
			(start -0.12065 -0.305054)
			(end -0.12065 -0.2794)
			(stroke
				(width 0.1)
				(type default)
			)
			(layer "F.Fab")
		)
		(fp_line
			(start -0.12065 -0.2794)
			(end 0.12065 -0.2794)
			(stroke
				(width 0.1)
				(type default)
			)
			(layer "F.Fab")
		)
		(fp_line
			(start -0.12065 0.2794)
			(end -0.12065 0.3048)
			(stroke
				(width 0.1)
				(type default)
			)
			(layer "F.Fab")
		)
		(fp_line
			(start -0.12065 0.3048)
			(end -0.67945 0.3048)
			(stroke
				(width 0.1)
				(type default)
			)
			(layer "F.Fab")
		)
		(fp_line
			(start 0.120396 0.2794)
			(end -0.12065 0.2794)
			(stroke
				(width 0.1)
				(type default)
			)
			(layer "F.Fab")
		)
		(fp_line
			(start 0.120396 0.3048)
			(end 0.120396 0.2794)
			(stroke
				(width 0.1)
				(type default)
			)
			(layer "F.Fab")
		)
		(fp_line
			(start 0.12065 -0.3048)
			(end 0.67945 -0.3048)
			(stroke
				(width 0.1)
				(type default)
			)
			(layer "F.Fab")
		)
		(fp_line
			(start 0.12065 -0.2794)
			(end 0.12065 -0.3048)
			(stroke
				(width 0.1)
				(type default)
			)
			(layer "F.Fab")
		)
		(fp_line
			(start 0.67945 -0.3048)
			(end 0.67945 0.3048)
			(stroke
				(width 0.1)
				(type default)
			)
			(layer "F.Fab")
		)
		(fp_line
			(start 0.67945 0.3048)
			(end 0.120396 0.3048)
			(stroke
				(width 0.1)
				(type default)
			)
			(layer "F.Fab")
		)
		(pad "1" smd circle
			(at -0.40005 0)
			(size 0 0)
			(layers "F.Cu" "F.Mask" "F.Paste")
			(net "RST_NIC6_PERST3_R_N")
		)
		(pad "2" smd circle
			(at 0.40005 0)
			(size 0 0)
			(layers "F.Cu" "F.Mask" "F.Paste")
			(net "RST_HP_NIC6_BUF_N")
		)
	)
	(footprint ""
		(layer "F.Cu")
		(at 478.056194 -553.484796 180)
		(property "Reference" "JPEX0_FW1"
			(at -4.0259 -1.402334 0)
			(unlocked yes)
			(layer "B.SilkS")
			(effects
				(font
					(size 0.7874 0.5842)
					(thickness 0.1524)
				)
				(justify mirror)
			)
		)
		(property "Value" ""
			(at 0 0 180)
			(layer "F.Fab")
			(effects
				(font
					(size 1.27 1.27)
				)
			)
		)
		(duplicate_pad_numbers_are_jumpers no)
		(pad "1" thru_hole circle
			(at 0 0 180)
			(size 0.4572 0.4572)
			(drill 0.2032)
			(layers "*.Cu" "*.Mask")
			(remove_unused_layers no)
			(net "Net_9090")
			(clearance 0.127)
			(thermal_gap 0.127)
			(padstack
				(mode front_inner_back)
				(layer "Inner"
					(shape circle)
					(size 0.4572 0.4572)
					(clearance 0.127)
				)
				(layer "B.Cu"
					(shape circle)
					(size 0.508 0.508)
					(clearance 0.1016)
				)
			)
		)
	)
	(footprint ""
		(layer "F.Cu")
		(at 231.30383 -308.568852)
		(property "Reference" "PJ11"
			(at 0 0 0)
			(layer "F.SilkS")
			(hide yes)
			(effects
				(font
					(size 1.27 1.27)
				)
			)
		)
		(property "Value" ""
			(at 0 0 0)
			(layer "F.Fab")
			(effects
				(font
					(size 1.27 1.27)
				)
			)
		)
		(duplicate_pad_numbers_are_jumpers no)
		(pad "1" smd circle
			(at -0.40005 0 90)
			(size 0 0)
			(layers "F.Cu" "F.Mask" "F.Paste")
			(net "SH_P1V25_PEX1_FB_P")
		)
		(pad "2" smd rect
			(at 0.40005 0 180)
			(size 0.4572 0.508)
			(layers "F.Cu" "F.Mask" "F.Paste")
			(net "P1V25_PEX1")
		)
		(zone
			(layer "F.Cu")
			(hatch none 0.5)
			(connect_pads
				(clearance 0)
			)
			(min_thickness 0.25)
			(keepout
				(tracks allowed)
				(vias not_allowed)
				(pads allowed)
				(copperpour not_allowed)
				(footprints allowed)
			)
			(placement
				(enabled no)
				(sheetname "")
			)
			(fill
				(thermal_gap 0.5)
				(thermal_bridge_width 0.5)
				(island_removal_mode 0)
			)
			(polygon
				(pts
					(xy 230.61803 -308.264052) (xy 231.98963 -308.264052) (xy 231.98963 -308.873652) (xy 230.61803 -308.873652)
				)
			)
		)
	)
	(footprint ""
		(layer "F.Cu")
		(at 278.45512 -35.876738)
		(property "Reference" "R6092"
			(at 0 0 0)
			(layer "F.SilkS")
			(hide yes)
			(effects
				(font
					(size 1.27 1.27)
				)
			)
		)
		(property "Value" ""
			(at 0 0 0)
			(layer "F.Fab")
			(effects
				(font
					(size 1.27 1.27)
				)
			)
		)
		(duplicate_pad_numbers_are_jumpers no)
		(fp_line
			(start -0.7874 -0.4064)
			(end 0.7874 -0.4064)
			(stroke
				(width 0.1524)
				(type default)
			)
			(layer "F.SilkS")
		)
		(fp_line
			(start -0.7874 0.4064)
			(end -0.7874 -0.4064)
			(stroke
				(width 0.1524)
				(type default)
			)
			(layer "F.SilkS")
		)
		(fp_line
			(start 0.7874 -0.4064)
			(end 0.7874 0.4064)
			(stroke
				(width 0.1524)
				(type default)
			)
			(layer "F.SilkS")
		)
		(fp_line
			(start 0.7874 0.4064)
			(end -0.7874 0.4064)
			(stroke
				(width 0.1524)
				(type default)
			)
			(layer "F.SilkS")
		)
		(fp_line
			(start -0.67945 -0.305054)
			(end -0.12065 -0.305054)
			(stroke
				(width 0.1)
				(type default)
			)
			(layer "F.Fab")
		)
		(fp_line
			(start -0.67945 0.3048)
			(end -0.67945 -0.305054)
			(stroke
				(width 0.1)
				(type default)
			)
			(layer "F.Fab")
		)
		(fp_line
			(start -0.12065 -0.305054)
			(end -0.12065 -0.2794)
			(stroke
				(width 0.1)
				(type default)
			)
			(layer "F.Fab")
		)
		(fp_line
			(start -0.12065 -0.2794)
			(end 0.12065 -0.2794)
			(stroke
				(width 0.1)
				(type default)
			)
			(layer "F.Fab")
		)
		(fp_line
			(start -0.12065 0.2794)
			(end -0.12065 0.3048)
			(stroke
				(width 0.1)
				(type default)
			)
			(layer "F.Fab")
		)
		(fp_line
			(start -0.12065 0.3048)
			(end -0.67945 0.3048)
			(stroke
				(width 0.1)
				(type default)
			)
			(layer "F.Fab")
		)
		(fp_line
			(start 0.120396 0.2794)
			(end -0.12065 0.2794)
			(stroke
				(width 0.1)
				(type default)
			)
			(layer "F.Fab")
		)
		(fp_line
			(start 0.120396 0.3048)
			(end 0.120396 0.2794)
			(stroke
				(width 0.1)
				(type default)
			)
			(layer "F.Fab")
		)
		(fp_line
			(start 0.12065 -0.3048)
			(end 0.67945 -0.3048)
			(stroke
				(width 0.1)
				(type default)
			)
			(layer "F.Fab")
		)
		(fp_line
			(start 0.12065 -0.2794)
			(end 0.12065 -0.3048)
			(stroke
				(width 0.1)
				(type default)
			)
			(layer "F.Fab")
		)
		(fp_line
			(start 0.67945 -0.3048)
			(end 0.67945 0.3048)
			(stroke
				(width 0.1)
				(type default)
			)
			(layer "F.Fab")
		)
		(fp_line
			(start 0.67945 0.3048)
			(end 0.120396 0.3048)
			(stroke
				(width 0.1)
				(type default)
			)
			(layer "F.Fab")
		)
		(pad "1" smd circle
			(at -0.40005 0)
			(size 0 0)
			(layers "F.Cu" "F.Mask" "F.Paste")
			(net "P3V3_AUX")
		)
		(pad "2" smd circle
			(at 0.40005 0)
			(size 0 0)
			(layers "F.Cu" "F.Mask" "F.Paste")
			(net "PWRGD_P3V3_SSD10_D")
		)
	)
	(footprint ""
		(layer "F.Cu")
		(at 444.139828 -70.52437 90)
		(property "Reference" "PC443"
			(at 0 0 90)
			(layer "F.SilkS")
			(hide yes)
			(effects
				(font
					(size 1.27 1.27)
				)
			)
		)
		(property "Value" ""
			(at 0 0 90)
			(layer "F.Fab")
			(effects
				(font
					(size 1.27 1.27)
				)
			)
		)
		(duplicate_pad_numbers_are_jumpers no)
		(fp_line
			(start 1.524 -0.762)
			(end 1.524 0.762)
			(stroke
				(width 0.1524)
				(type default)
			)
			(layer "F.SilkS")
		)
		(fp_line
			(start -1.524 -0.762)
			(end 1.524 -0.762)
			(stroke
				(width 0.1524)
				(type default)
			)
			(layer "F.SilkS")
		)
		(fp_line
			(start 1.524 0.762)
			(end -1.524 0.762)
			(stroke
				(width 0.1524)
				(type default)
			)
			(layer "F.SilkS")
		)
		(fp_line
			(start -1.524 0.762)
			(end -1.524 -0.762)
			(stroke
				(width 0.1524)
				(type default)
			)
			(layer "F.SilkS")
		)
		(fp_line
			(start 1.1049 -0.724916)
			(end -1.1049 -0.724916)
			(stroke
				(width 0.1)
				(type default)
			)
			(layer "F.Fab")
		)
		(fp_line
			(start -1.1049 -0.724916)
			(end -1.1049 0.724916)
			(stroke
				(width 0.1)
				(type default)
			)
			(layer "F.Fab")
		)
		(fp_line
			(start 1.1049 0.724916)
			(end 1.1049 -0.724916)
			(stroke
				(width 0.1)
				(type default)
			)
			(layer "F.Fab")
		)
		(fp_line
			(start -1.1049 0.724916)
			(end 1.1049 0.724916)
			(stroke
				(width 0.1)
				(type default)
			)
			(layer "F.Fab")
		)
		(pad "1" smd rect
			(at -0.889 0 270)
			(size 1.016 1.27)
			(layers "F.Cu" "F.Mask" "F.Paste")
			(net "P12V_SSD15_R")
		)
		(pad "2" smd rect
			(at 0.889 0 270)
			(size 1.016 1.27)
			(layers "F.Cu" "F.Mask" "F.Paste")
			(net "GND")
		)
	)
	(footprint ""
		(layer "F.Cu")
		(at 456.818238 -266.91844)
		(property "Reference" "L133"
			(at 0 0 0)
			(layer "F.SilkS")
			(hide yes)
			(effects
				(font
					(size 1.27 1.27)
				)
			)
		)
		(property "Value" ""
			(at 0 0 0)
			(layer "F.Fab")
			(effects
				(font
					(size 1.27 1.27)
				)
			)
		)
		(duplicate_pad_numbers_are_jumpers no)
		(fp_line
			(start -2.248154 -4.9911)
			(end -2.248154 -1.890522)
			(stroke
				(width 0.1524)
				(type default)
			)
			(layer "F.SilkS")
		)
		(fp_line
			(start -2.248154 1.6891)
			(end -2.248154 4.9911)
			(stroke
				(width 0.1524)
				(type default)
			)
			(layer "F.SilkS")
		)
		(fp_line
			(start -2.248154 4.9911)
			(end 2.248154 4.9911)
			(stroke
				(width 0.1524)
				(type default)
			)
			(layer "F.SilkS")
		)
		(fp_line
			(start 2.248154 -4.9911)
			(end -2.248154 -4.9911)
			(stroke
				(width 0.1524)
				(type default)
			)
			(layer "F.SilkS")
		)
		(fp_line
			(start 2.248154 -2.022094)
			(end 2.248154 -4.9911)
			(stroke
				(width 0.1524)
				(type default)
			)
			(layer "F.SilkS")
		)
		(fp_line
			(start 2.248154 4.9911)
			(end 2.248154 1.667002)
			(stroke
				(width 0.1524)
				(type default)
			)
			(layer "F.SilkS")
		)
		(fp_line
			(start -1.700022 -0.899922)
			(end -1.700022 0.899922)
			(stroke
				(width 0.1)
				(type default)
			)
			(layer "F.Fab")
		)
		(fp_line
			(start -1.700022 0.899922)
			(end 1.700022 0.899922)
			(stroke
				(width 0.1)
				(type default)
			)
			(layer "F.Fab")
		)
		(fp_line
			(start 1.700022 -0.899922)
			(end -1.700022 -0.899922)
			(stroke
				(width 0.1)
				(type default)
			)
			(layer "F.Fab")
		)
		(fp_line
			(start 1.700022 0.899922)
			(end 1.700022 -0.899922)
			(stroke
				(width 0.1)
				(type default)
			)
			(layer "F.Fab")
		)
		(pad "1" smd rect
			(at -1.575054 0)
			(size 1.1684 9.8044)
			(layers "F.Cu" "F.Mask" "F.Paste")
			(net "P1V25_PEX3")
		)
		(pad "2" smd rect
			(at 1.575054 0)
			(size 1.1684 9.8044)
			(layers "F.Cu" "F.Mask" "F.Paste")
			(net "P1V25_SERDES_VDDPLL_PEX3")
		)
	)
	(footprint ""
		(layer "F.Cu")
		(at 358.013 -217.424 180)
		(property "Reference" "R4090"
			(at 0 0 180)
			(layer "F.SilkS")
			(hide yes)
			(effects
				(font
					(size 1.27 1.27)
				)
			)
		)
		(property "Value" ""
			(at 0 0 180)
			(layer "F.Fab")
			(effects
				(font
					(size 1.27 1.27)
				)
			)
		)
		(duplicate_pad_numbers_are_jumpers no)
		(fp_line
			(start 0.7874 0.4064)
			(end -0.7874 0.4064)
			(stroke
				(width 0.1524)
				(type default)
			)
			(layer "F.SilkS")
		)
		(fp_line
			(start 0.7874 -0.4064)
			(end 0.7874 0.4064)
			(stroke
				(width 0.1524)
				(type default)
			)
			(layer "F.SilkS")
		)
		(fp_line
			(start -0.7874 0.4064)
			(end -0.7874 -0.4064)
			(stroke
				(width 0.1524)
				(type default)
			)
			(layer "F.SilkS")
		)
		(fp_line
			(start -0.7874 -0.4064)
			(end 0.7874 -0.4064)
			(stroke
				(width 0.1524)
				(type default)
			)
			(layer "F.SilkS")
		)
		(fp_line
			(start 0.67945 0.3048)
			(end 0.120396 0.3048)
			(stroke
				(width 0.1)
				(type default)
			)
			(layer "F.Fab")
		)
		(fp_line
			(start 0.67945 -0.3048)
			(end 0.67945 0.3048)
			(stroke
				(width 0.1)
				(type default)
			)
			(layer "F.Fab")
		)
		(fp_line
			(start 0.12065 -0.2794)
			(end 0.12065 -0.3048)
			(stroke
				(width 0.1)
				(type default)
			)
			(layer "F.Fab")
		)
		(fp_line
			(start 0.12065 -0.3048)
			(end 0.67945 -0.3048)
			(stroke
				(width 0.1)
				(type default)
			)
			(layer "F.Fab")
		)
		(fp_line
			(start 0.120396 0.3048)
			(end 0.120396 0.2794)
			(stroke
				(width 0.1)
				(type default)
			)
			(layer "F.Fab")
		)
		(fp_line
			(start 0.120396 0.2794)
			(end -0.12065 0.2794)
			(stroke
				(width 0.1)
				(type default)
			)
			(layer "F.Fab")
		)
		(fp_line
			(start -0.12065 0.3048)
			(end -0.67945 0.3048)
			(stroke
				(width 0.1)
				(type default)
			)
			(layer "F.Fab")
		)
		(fp_line
			(start -0.12065 0.2794)
			(end -0.12065 0.3048)
			(stroke
				(width 0.1)
				(type default)
			)
			(layer "F.Fab")
		)
		(fp_line
			(start -0.12065 -0.2794)
			(end 0.12065 -0.2794)
			(stroke
				(width 0.1)
				(type default)
			)
			(layer "F.Fab")
		)
		(fp_line
			(start -0.12065 -0.305054)
			(end -0.12065 -0.2794)
			(stroke
				(width 0.1)
				(type default)
			)
			(layer "F.Fab")
		)
		(fp_line
			(start -0.67945 0.3048)
			(end -0.67945 -0.305054)
			(stroke
				(width 0.1)
				(type default)
			)
			(layer "F.Fab")
		)
		(fp_line
			(start -0.67945 -0.305054)
			(end -0.12065 -0.305054)
			(stroke
				(width 0.1)
				(type default)
			)
			(layer "F.Fab")
		)
		(pad "1" smd circle
			(at -0.40005 0 180)
			(size 0 0)
			(layers "F.Cu" "F.Mask" "F.Paste")
			(net "RST_NIC7_PERST_R_N")
		)
		(pad "2" smd circle
			(at 0.40005 0 180)
			(size 0 0)
			(layers "F.Cu" "F.Mask" "F.Paste")
			(net "RST_NIC7_PERST_N")
		)
	)
	(footprint ""
		(layer "F.Cu")
		(at 237.945676 -307.137308 90)
		(property "Reference" "PC257"
			(at 0 0 90)
			(layer "F.SilkS")
			(hide yes)
			(effects
				(font
					(size 1.27 1.27)
				)
			)
		)
		(property "Value" ""
			(at 0 0 90)
			(layer "F.Fab")
			(effects
				(font
					(size 1.27 1.27)
				)
			)
		)
		(duplicate_pad_numbers_are_jumpers no)
		(fp_line
			(start 0.7874 -0.4064)
			(end 0.7874 0.4064)
			(stroke
				(width 0.1524)
				(type default)
			)
			(layer "F.SilkS")
		)
		(fp_line
			(start -0.7874 -0.4064)
			(end 0.7874 -0.4064)
			(stroke
				(width 0.1524)
				(type default)
			)
			(layer "F.SilkS")
		)
		(fp_line
			(start 0.7874 0.4064)
			(end -0.7874 0.4064)
			(stroke
				(width 0.1524)
				(type default)
			)
			(layer "F.SilkS")
		)
		(fp_line
			(start -0.7874 0.4064)
			(end -0.7874 -0.4064)
			(stroke
				(width 0.1524)
				(type default)
			)
			(layer "F.SilkS")
		)
		(fp_line
			(start -0.12065 -0.305054)
			(end -0.12065 -0.2794)
			(stroke
				(width 0.1)
				(type default)
			)
			(layer "F.Fab")
		)
		(fp_line
			(start -0.67945 -0.305054)
			(end -0.12065 -0.305054)
			(stroke
				(width 0.1)
				(type default)
			)
			(layer "F.Fab")
		)
		(fp_line
			(start 0.67945 -0.3048)
			(end 0.67945 0.3048)
			(stroke
				(width 0.1)
				(type default)
			)
			(layer "F.Fab")
		)
		(fp_line
			(start 0.12065 -0.3048)
			(end 0.67945 -0.3048)
			(stroke
				(width 0.1)
				(type default)
			)
			(layer "F.Fab")
		)
		(fp_line
			(start 0.12065 -0.2794)
			(end 0.12065 -0.3048)
			(stroke
				(width 0.1)
				(type default)
			)
			(layer "F.Fab")
		)
		(fp_line
			(start -0.12065 -0.2794)
			(end 0.12065 -0.2794)
			(stroke
				(width 0.1)
				(type default)
			)
			(layer "F.Fab")
		)
		(fp_line
			(start 0.120396 0.2794)
			(end -0.12065 0.2794)
			(stroke
				(width 0.1)
				(type default)
			)
			(layer "F.Fab")
		)
		(fp_line
			(start -0.12065 0.2794)
			(end -0.12065 0.3048)
			(stroke
				(width 0.1)
				(type default)
			)
			(layer "F.Fab")
		)
		(fp_line
			(start 0.67945 0.3048)
			(end 0.120396 0.3048)
			(stroke
				(width 0.1)
				(type default)
			)
			(layer "F.Fab")
		)
		(fp_line
			(start 0.120396 0.3048)
			(end 0.120396 0.2794)
			(stroke
				(width 0.1)
				(type default)
			)
			(layer "F.Fab")
		)
		(fp_line
			(start -0.12065 0.3048)
			(end -0.67945 0.3048)
			(stroke
				(width 0.1)
				(type default)
			)
			(layer "F.Fab")
		)
		(fp_line
			(start -0.67945 0.3048)
			(end -0.67945 -0.305054)
			(stroke
				(width 0.1)
				(type default)
			)
			(layer "F.Fab")
		)
		(pad "1" smd circle
			(at -0.40005 0 90)
			(size 0 0)
			(layers "F.Cu" "F.Mask" "F.Paste")
			(net "P1V25_PEX2_VCC")
		)
		(pad "2" smd circle
			(at 0.40005 0 90)
			(size 0 0)
			(layers "F.Cu" "F.Mask" "F.Paste")
			(net "GND")
		)
	)
	(footprint ""
		(layer "F.Cu")
		(at 162.759644 -61.612526)
		(property "Reference" "PD28"
			(at -3.552444 -2.546604 0)
			(unlocked yes)
			(layer "F.SilkS")
			(effects
				(font
					(size 0.7874 0.5842)
					(thickness 0.1524)
				)
				(justify left)
			)
		)
		(property "Value" ""
			(at 0 0 0)
			(layer "F.Fab")
			(effects
				(font
					(size 1.27 1.27)
				)
			)
		)
		(duplicate_pad_numbers_are_jumpers no)
		(fp_line
			(start -3.656584 -1.970024)
			(end -3.656584 1.970024)
			(stroke
				(width 0.1524)
				(type default)
			)
			(layer "F.SilkS")
		)
		(fp_line
			(start -3.656584 1.970024)
			(end 4.240784 1.970024)
			(stroke
				(width 0.1524)
				(type default)
			)
			(layer "F.SilkS")
		)
		(fp_line
			(start 4.240784 -1.970024)
			(end -3.656584 -1.970024)
			(stroke
				(width 0.1524)
				(type default)
			)
			(layer "F.SilkS")
		)
		(fp_line
			(start 4.240784 1.970024)
			(end 4.240784 -1.970024)
			(stroke
				(width 0.1524)
				(type default)
			)
			(layer "F.SilkS")
		)
		(fp_poly
			(pts
				(xy 3.580384 1.970024) (xy 3.580384 -1.970024) (xy 4.240784 -1.970024) (xy 4.240784 1.970024)
			)
			(stroke
				(width 0)
				(type default)
			)
			(fill yes)
			(layer "F.SilkS")
		)
		(fp_line
			(start -2.3749 -1.970024)
			(end -2.3749 1.970024)
			(stroke
				(width 0.1)
				(type default)
			)
			(layer "F.Fab")
		)
		(fp_line
			(start -2.3749 1.970024)
			(end 2.3749 1.970024)
			(stroke
				(width 0.1)
				(type default)
			)
			(layer "F.Fab")
		)
		(fp_line
			(start 2.3749 -1.970024)
			(end -2.3749 -1.970024)
			(stroke
				(width 0.1)
				(type default)
			)
			(layer "F.Fab")
		)
		(fp_line
			(start 2.3749 1.970024)
			(end 2.3749 -1.970024)
			(stroke
				(width 0.1)
				(type default)
			)
			(layer "F.Fab")
		)
		(fp_text user "+"
			(at -4.9784 -0.23495 0)
			(unlocked yes)
			(layer "F.Fab")
			(effects
				(font
					(size 1.905 1.4224)
					(thickness 0.1524)
				)
				(justify left)
			)
		)
		(fp_text user "-"
			(at 4.1656 -0.23495 0)
			(unlocked yes)
			(layer "F.Fab")
			(effects
				(font
					(size 1.905 1.4224)
					(thickness 0.1524)
				)
				(justify left)
			)
		)
		(pad "A" smd rect
			(at -2.450084 0)
			(size 2.159 2.2606)
			(layers "F.Cu" "F.Mask" "F.Paste")
			(net "GND")
		)
		(pad "C" smd rect
			(at 2.450084 0)
			(size 2.159 2.2606)
			(layers "F.Cu" "F.Mask" "F.Paste")
			(net "P12V_AUX")
		)
	)
	(footprint ""
		(layer "F.Cu")
		(at 45.093128 -343.952322 90)
		(property "Reference" "C2175"
			(at 0 0 90)
			(layer "F.SilkS")
			(hide yes)
			(effects
				(font
					(size 1.27 1.27)
				)
			)
		)
		(property "Value" ""
			(at 0 0 90)
			(layer "F.Fab")
			(effects
				(font
					(size 1.27 1.27)
				)
			)
		)
		(duplicate_pad_numbers_are_jumpers no)
		(fp_line
			(start 0.299974 -0.150114)
			(end 0.299974 0.150114)
			(stroke
				(width 0.1)
				(type default)
			)
			(layer "F.Fab")
		)
		(fp_line
			(start -0.299974 -0.150114)
			(end 0.299974 -0.150114)
			(stroke
				(width 0.1)
				(type default)
			)
			(layer "F.Fab")
		)
		(fp_line
			(start 0.299974 0.150114)
			(end -0.299974 0.150114)
			(stroke
				(width 0.1)
				(type default)
			)
			(layer "F.Fab")
		)
		(fp_line
			(start -0.299974 0.150114)
			(end -0.299974 -0.150114)
			(stroke
				(width 0.1)
				(type default)
			)
			(layer "F.Fab")
		)
		(pad "1" smd rect
			(at -0.2667 0 90)
			(size 0.3048 0.381)
			(layers "F.Cu" "F.Mask" "F.Paste")
			(net "P5E_PEX0_STN4_TX_DN<68>")
		)
		(pad "2" smd rect
			(at 0.2667 0 90)
			(size 0.3048 0.381)
			(layers "F.Cu" "F.Mask" "F.Paste")
			(net "P5E_PEX0_STN4_TX_C_DN<68>")
		)
	)
	(footprint ""
		(layer "F.Cu")
		(at 438.321196 -298.87291 -90)
		(property "Reference" "R4020"
			(at 0 0 270)
			(layer "F.SilkS")
			(hide yes)
			(effects
				(font
					(size 1.27 1.27)
				)
			)
		)
		(property "Value" ""
			(at 0 0 270)
			(layer "F.Fab")
			(effects
				(font
					(size 1.27 1.27)
				)
			)
		)
		(duplicate_pad_numbers_are_jumpers no)
		(fp_line
			(start -0.7874 0.4064)
			(end -0.7874 -0.4064)
			(stroke
				(width 0.1524)
				(type default)
			)
			(layer "F.SilkS")
		)
		(fp_line
			(start 0.7874 0.4064)
			(end -0.7874 0.4064)
			(stroke
				(width 0.1524)
				(type default)
			)
			(layer "F.SilkS")
		)
		(fp_line
			(start -0.7874 -0.4064)
			(end 0.7874 -0.4064)
			(stroke
				(width 0.1524)
				(type default)
			)
			(layer "F.SilkS")
		)
		(fp_line
			(start 0.7874 -0.4064)
			(end 0.7874 0.4064)
			(stroke
				(width 0.1524)
				(type default)
			)
			(layer "F.SilkS")
		)
		(fp_line
			(start -0.67945 0.3048)
			(end -0.67945 -0.305054)
			(stroke
				(width 0.1)
				(type default)
			)
			(layer "F.Fab")
		)
		(fp_line
			(start -0.12065 0.3048)
			(end -0.67945 0.3048)
			(stroke
				(width 0.1)
				(type default)
			)
			(layer "F.Fab")
		)
		(fp_line
			(start 0.120396 0.3048)
			(end 0.120396 0.2794)
			(stroke
				(width 0.1)
				(type default)
			)
			(layer "F.Fab")
		)
		(fp_line
			(start 0.67945 0.3048)
			(end 0.120396 0.3048)
			(stroke
				(width 0.1)
				(type default)
			)
			(layer "F.Fab")
		)
		(fp_line
			(start -0.12065 0.2794)
			(end -0.12065 0.3048)
			(stroke
				(width 0.1)
				(type default)
			)
			(layer "F.Fab")
		)
		(fp_line
			(start 0.120396 0.2794)
			(end -0.12065 0.2794)
			(stroke
				(width 0.1)
				(type default)
			)
			(layer "F.Fab")
		)
		(fp_line
			(start -0.12065 -0.2794)
			(end 0.12065 -0.2794)
			(stroke
				(width 0.1)
				(type default)
			)
			(layer "F.Fab")
		)
		(fp_line
			(start 0.12065 -0.2794)
			(end 0.12065 -0.3048)
			(stroke
				(width 0.1)
				(type default)
			)
			(layer "F.Fab")
		)
		(fp_line
			(start 0.12065 -0.3048)
			(end 0.67945 -0.3048)
			(stroke
				(width 0.1)
				(type default)
			)
			(layer "F.Fab")
		)
		(fp_line
			(start 0.67945 -0.3048)
			(end 0.67945 0.3048)
			(stroke
				(width 0.1)
				(type default)
			)
			(layer "F.Fab")
		)
		(fp_line
			(start -0.67945 -0.305054)
			(end -0.12065 -0.305054)
			(stroke
				(width 0.1)
				(type default)
			)
			(layer "F.Fab")
		)
		(fp_line
			(start -0.12065 -0.305054)
			(end -0.12065 -0.2794)
			(stroke
				(width 0.1)
				(type default)
			)
			(layer "F.Fab")
		)
		(pad "1" smd circle
			(at -0.40005 0 270)
			(size 0 0)
			(layers "F.Cu" "F.Mask" "F.Paste")
			(net "P1V8_PEX")
		)
		(pad "2" smd circle
			(at 0.40005 0 270)
			(size 0 0)
			(layers "F.Cu" "F.Mask" "F.Paste")
			(net "I2C_PEX3_HOST_R_SDA")
		)
	)
	(footprint ""
		(layer "F.Cu")
		(at 315.593984 -29.507688 -90)
		(property "Reference" "PC953"
			(at 0 0 270)
			(layer "F.SilkS")
			(hide yes)
			(effects
				(font
					(size 1.27 1.27)
				)
			)
		)
		(property "Value" ""
			(at 0 0 270)
			(layer "F.Fab")
			(effects
				(font
					(size 1.27 1.27)
				)
			)
		)
		(duplicate_pad_numbers_are_jumpers no)
		(fp_line
			(start -1.524 0.762)
			(end -1.524 -0.762)
			(stroke
				(width 0.1524)
				(type default)
			)
			(layer "F.SilkS")
		)
		(fp_line
			(start 1.524 0.762)
			(end -1.524 0.762)
			(stroke
				(width 0.1524)
				(type default)
			)
			(layer "F.SilkS")
		)
		(fp_line
			(start -1.524 -0.762)
			(end 1.524 -0.762)
			(stroke
				(width 0.1524)
				(type default)
			)
			(layer "F.SilkS")
		)
		(fp_line
			(start 1.524 -0.762)
			(end 1.524 0.762)
			(stroke
				(width 0.1524)
				(type default)
			)
			(layer "F.SilkS")
		)
		(fp_line
			(start -1.1049 0.724916)
			(end 1.1049 0.724916)
			(stroke
				(width 0.1)
				(type default)
			)
			(layer "F.Fab")
		)
		(fp_line
			(start 1.1049 0.724916)
			(end 1.1049 -0.724916)
			(stroke
				(width 0.1)
				(type default)
			)
			(layer "F.Fab")
		)
		(fp_line
			(start -1.1049 -0.724916)
			(end -1.1049 0.724916)
			(stroke
				(width 0.1)
				(type default)
			)
			(layer "F.Fab")
		)
		(fp_line
			(start 1.1049 -0.724916)
			(end -1.1049 -0.724916)
			(stroke
				(width 0.1)
				(type default)
			)
			(layer "F.Fab")
		)
		(pad "1" smd rect
			(at -0.889 0 90)
			(size 1.016 1.27)
			(layers "F.Cu" "F.Mask" "F.Paste")
			(net "P3V3_SSD11")
		)
		(pad "2" smd rect
			(at 0.889 0 90)
			(size 1.016 1.27)
			(layers "F.Cu" "F.Mask" "F.Paste")
			(net "GND")
		)
	)
	(footprint ""
		(layer "F.Cu")
		(at 369.590066 -72.766682 90)
		(property "Reference" "PR7088"
			(at 0 0 90)
			(layer "F.SilkS")
			(hide yes)
			(effects
				(font
					(size 1.27 1.27)
				)
			)
		)
		(property "Value" ""
			(at 0 0 90)
			(layer "F.Fab")
			(effects
				(font
					(size 1.27 1.27)
				)
			)
		)
		(duplicate_pad_numbers_are_jumpers no)
		(fp_line
			(start 0.7874 -0.4064)
			(end 0.7874 0.4064)
			(stroke
				(width 0.1524)
				(type default)
			)
			(layer "F.SilkS")
		)
		(fp_line
			(start -0.7874 -0.4064)
			(end 0.7874 -0.4064)
			(stroke
				(width 0.1524)
				(type default)
			)
			(layer "F.SilkS")
		)
		(fp_line
			(start 0.7874 0.4064)
			(end -0.7874 0.4064)
			(stroke
				(width 0.1524)
				(type default)
			)
			(layer "F.SilkS")
		)
		(fp_line
			(start -0.7874 0.4064)
			(end -0.7874 -0.4064)
			(stroke
				(width 0.1524)
				(type default)
			)
			(layer "F.SilkS")
		)
		(fp_line
			(start -0.12065 -0.305054)
			(end -0.12065 -0.2794)
			(stroke
				(width 0.1)
				(type default)
			)
			(layer "F.Fab")
		)
		(fp_line
			(start -0.67945 -0.305054)
			(end -0.12065 -0.305054)
			(stroke
				(width 0.1)
				(type default)
			)
			(layer "F.Fab")
		)
		(fp_line
			(start 0.67945 -0.3048)
			(end 0.67945 0.3048)
			(stroke
				(width 0.1)
				(type default)
			)
			(layer "F.Fab")
		)
		(fp_line
			(start 0.12065 -0.3048)
			(end 0.67945 -0.3048)
			(stroke
				(width 0.1)
				(type default)
			)
			(layer "F.Fab")
		)
		(fp_line
			(start 0.12065 -0.2794)
			(end 0.12065 -0.3048)
			(stroke
				(width 0.1)
				(type default)
			)
			(layer "F.Fab")
		)
		(fp_line
			(start -0.12065 -0.2794)
			(end 0.12065 -0.2794)
			(stroke
				(width 0.1)
				(type default)
			)
			(layer "F.Fab")
		)
		(fp_line
			(start 0.120396 0.2794)
			(end -0.12065 0.2794)
			(stroke
				(width 0.1)
				(type default)
			)
			(layer "F.Fab")
		)
		(fp_line
			(start -0.12065 0.2794)
			(end -0.12065 0.3048)
			(stroke
				(width 0.1)
				(type default)
			)
			(layer "F.Fab")
		)
		(fp_line
			(start 0.67945 0.3048)
			(end 0.120396 0.3048)
			(stroke
				(width 0.1)
				(type default)
			)
			(layer "F.Fab")
		)
		(fp_line
			(start 0.120396 0.3048)
			(end 0.120396 0.2794)
			(stroke
				(width 0.1)
				(type default)
			)
			(layer "F.Fab")
		)
		(fp_line
			(start -0.12065 0.3048)
			(end -0.67945 0.3048)
			(stroke
				(width 0.1)
				(type default)
			)
			(layer "F.Fab")
		)
		(fp_line
			(start -0.67945 0.3048)
			(end -0.67945 -0.305054)
			(stroke
				(width 0.1)
				(type default)
			)
			(layer "F.Fab")
		)
		(pad "1" smd circle
			(at -0.40005 0 90)
			(size 0 0)
			(layers "F.Cu" "F.Mask" "F.Paste")
			(net "P12V_SSD12_CO_ILIMIT")
		)
		(pad "2" smd circle
			(at 0.40005 0 90)
			(size 0 0)
			(layers "F.Cu" "F.Mask" "F.Paste")
			(net "GND")
		)
	)
	(footprint ""
		(layer "F.Cu")
		(at 149.235668 -308.13375 -135)
		(property "Reference" "R1265"
			(at 0 0 225)
			(layer "F.SilkS")
			(hide yes)
			(effects
				(font
					(size 1.27 1.27)
				)
			)
		)
		(property "Value" ""
			(at 0 0 225)
			(layer "F.Fab")
			(effects
				(font
					(size 1.27 1.27)
				)
			)
		)
		(duplicate_pad_numbers_are_jumpers no)
		(fp_line
			(start 0.787389 0.406267)
			(end -0.787389 0.406267)
			(stroke
				(width 0.1524)
				(type default)
			)
			(layer "F.SilkS")
		)
		(fp_line
			(start 0.787389 -0.406267)
			(end 0.787389 0.406267)
			(stroke
				(width 0.1524)
				(type default)
			)
			(layer "F.SilkS")
		)
		(fp_line
			(start -0.787389 0.406267)
			(end -0.787389 -0.406267)
			(stroke
				(width 0.1524)
				(type default)
			)
			(layer "F.SilkS")
		)
		(fp_line
			(start -0.787389 -0.406267)
			(end 0.787389 -0.406267)
			(stroke
				(width 0.1524)
				(type default)
			)
			(layer "F.SilkS")
		)
		(fp_line
			(start 0.679446 0.30479)
			(end 0.120515 0.30479)
			(stroke
				(width 0.1)
				(type default)
			)
			(layer "F.Fab")
		)
		(fp_line
			(start 0.120515 0.30479)
			(end 0.120335 0.279466)
			(stroke
				(width 0.1)
				(type default)
			)
			(layer "F.Fab")
		)
		(fp_line
			(start 0.120335 0.279466)
			(end -0.120695 0.279466)
			(stroke
				(width 0.1)
				(type default)
			)
			(layer "F.Fab")
		)
		(fp_line
			(start 0.679446 -0.30479)
			(end 0.679446 0.30479)
			(stroke
				(width 0.1)
				(type default)
			)
			(layer "F.Fab")
		)
		(fp_line
			(start -0.120515 0.30479)
			(end -0.679446 0.30479)
			(stroke
				(width 0.1)
				(type default)
			)
			(layer "F.Fab")
		)
		(fp_line
			(start -0.120695 0.279466)
			(end -0.120515 0.30479)
			(stroke
				(width 0.1)
				(type default)
			)
			(layer "F.Fab")
		)
		(fp_line
			(start 0.120695 -0.279466)
			(end 0.120515 -0.30479)
			(stroke
				(width 0.1)
				(type default)
			)
			(layer "F.Fab")
		)
		(fp_line
			(start 0.120515 -0.30479)
			(end 0.679446 -0.30479)
			(stroke
				(width 0.1)
				(type default)
			)
			(layer "F.Fab")
		)
		(fp_line
			(start -0.679446 0.30479)
			(end -0.679446 -0.305149)
			(stroke
				(width 0.1)
				(type default)
			)
			(layer "F.Fab")
		)
		(fp_line
			(start -0.120695 -0.279466)
			(end 0.120695 -0.279466)
			(stroke
				(width 0.1)
				(type default)
			)
			(layer "F.Fab")
		)
		(fp_line
			(start -0.120695 -0.304969)
			(end -0.120695 -0.279466)
			(stroke
				(width 0.1)
				(type default)
			)
			(layer "F.Fab")
		)
		(fp_line
			(start -0.679446 -0.305149)
			(end -0.120695 -0.304969)
			(stroke
				(width 0.1)
				(type default)
			)
			(layer "F.Fab")
		)
		(pad "1" smd circle
			(at -0.40005 0 225)
			(size 0 0)
			(layers "F.Cu" "F.Mask" "F.Paste")
			(net "PEX1_DBG_MODE1")
		)
		(pad "2" smd circle
			(at 0.40005 0 225)
			(size 0 0)
			(layers "F.Cu" "F.Mask" "F.Paste")
			(net "P1V8_PEX")
		)
	)
	(footprint ""
		(layer "F.Cu")
		(at 186.376818 -414.02762 180)
		(property "Reference" "R6777"
			(at 0 0 180)
			(layer "F.SilkS")
			(hide yes)
			(effects
				(font
					(size 1.27 1.27)
				)
			)
		)
		(property "Value" ""
			(at 0 0 180)
			(layer "F.Fab")
			(effects
				(font
					(size 1.27 1.27)
				)
			)
		)
		(duplicate_pad_numbers_are_jumpers no)
		(fp_line
			(start 0.7874 0.4064)
			(end -0.7874 0.4064)
			(stroke
				(width 0.1524)
				(type default)
			)
			(layer "F.SilkS")
		)
		(fp_line
			(start 0.7874 -0.4064)
			(end 0.7874 0.4064)
			(stroke
				(width 0.1524)
				(type default)
			)
			(layer "F.SilkS")
		)
		(fp_line
			(start -0.7874 0.4064)
			(end -0.7874 -0.4064)
			(stroke
				(width 0.1524)
				(type default)
			)
			(layer "F.SilkS")
		)
		(fp_line
			(start -0.7874 -0.4064)
			(end 0.7874 -0.4064)
			(stroke
				(width 0.1524)
				(type default)
			)
			(layer "F.SilkS")
		)
		(fp_line
			(start 0.67945 0.3048)
			(end 0.120396 0.3048)
			(stroke
				(width 0.1)
				(type default)
			)
			(layer "F.Fab")
		)
		(fp_line
			(start 0.67945 -0.3048)
			(end 0.67945 0.3048)
			(stroke
				(width 0.1)
				(type default)
			)
			(layer "F.Fab")
		)
		(fp_line
			(start 0.12065 -0.2794)
			(end 0.12065 -0.3048)
			(stroke
				(width 0.1)
				(type default)
			)
			(layer "F.Fab")
		)
		(fp_line
			(start 0.12065 -0.3048)
			(end 0.67945 -0.3048)
			(stroke
				(width 0.1)
				(type default)
			)
			(layer "F.Fab")
		)
		(fp_line
			(start 0.120396 0.3048)
			(end 0.120396 0.2794)
			(stroke
				(width 0.1)
				(type default)
			)
			(layer "F.Fab")
		)
		(fp_line
			(start 0.120396 0.2794)
			(end -0.12065 0.2794)
			(stroke
				(width 0.1)
				(type default)
			)
			(layer "F.Fab")
		)
		(fp_line
			(start -0.12065 0.3048)
			(end -0.67945 0.3048)
			(stroke
				(width 0.1)
				(type default)
			)
			(layer "F.Fab")
		)
		(fp_line
			(start -0.12065 0.2794)
			(end -0.12065 0.3048)
			(stroke
				(width 0.1)
				(type default)
			)
			(layer "F.Fab")
		)
		(fp_line
			(start -0.12065 -0.2794)
			(end 0.12065 -0.2794)
			(stroke
				(width 0.1)
				(type default)
			)
			(layer "F.Fab")
		)
		(fp_line
			(start -0.12065 -0.305054)
			(end -0.12065 -0.2794)
			(stroke
				(width 0.1)
				(type default)
			)
			(layer "F.Fab")
		)
		(fp_line
			(start -0.67945 0.3048)
			(end -0.67945 -0.305054)
			(stroke
				(width 0.1)
				(type default)
			)
			(layer "F.Fab")
		)
		(fp_line
			(start -0.67945 -0.305054)
			(end -0.12065 -0.305054)
			(stroke
				(width 0.1)
				(type default)
			)
			(layer "F.Fab")
		)
		(pad "1" smd circle
			(at -0.40005 0 180)
			(size 0 0)
			(layers "F.Cu" "F.Mask" "F.Paste")
			(net "HSC_UV_R2_N")
		)
		(pad "2" smd circle
			(at 0.40005 0 180)
			(size 0 0)
			(layers "F.Cu" "F.Mask" "F.Paste")
			(net "HSC_UV_R_N")
		)
	)
	(footprint ""
		(layer "F.Cu")
		(at 278.859488 -61.612526)
		(property "Reference" "PD44"
			(at -3.726688 -2.648204 0)
			(unlocked yes)
			(layer "F.SilkS")
			(effects
				(font
					(size 0.7874 0.5842)
					(thickness 0.1524)
				)
				(justify left)
			)
		)
		(property "Value" ""
			(at 0 0 0)
			(layer "F.Fab")
			(effects
				(font
					(size 1.27 1.27)
				)
			)
		)
		(duplicate_pad_numbers_are_jumpers no)
		(fp_line
			(start -3.656584 -1.970024)
			(end -3.656584 1.970024)
			(stroke
				(width 0.1524)
				(type default)
			)
			(layer "F.SilkS")
		)
		(fp_line
			(start -3.656584 1.970024)
			(end 4.240784 1.970024)
			(stroke
				(width 0.1524)
				(type default)
			)
			(layer "F.SilkS")
		)
		(fp_line
			(start 4.240784 -1.970024)
			(end -3.656584 -1.970024)
			(stroke
				(width 0.1524)
				(type default)
			)
			(layer "F.SilkS")
		)
		(fp_line
			(start 4.240784 1.970024)
			(end 4.240784 -1.970024)
			(stroke
				(width 0.1524)
				(type default)
			)
			(layer "F.SilkS")
		)
		(fp_poly
			(pts
				(xy 3.580384 1.970024) (xy 3.580384 -1.970024) (xy 4.240784 -1.970024) (xy 4.240784 1.970024)
			)
			(stroke
				(width 0)
				(type default)
			)
			(fill yes)
			(layer "F.SilkS")
		)
		(fp_line
			(start -2.3749 -1.970024)
			(end -2.3749 1.970024)
			(stroke
				(width 0.1)
				(type default)
			)
			(layer "F.Fab")
		)
		(fp_line
			(start -2.3749 1.970024)
			(end 2.3749 1.970024)
			(stroke
				(width 0.1)
				(type default)
			)
			(layer "F.Fab")
		)
		(fp_line
			(start 2.3749 -1.970024)
			(end -2.3749 -1.970024)
			(stroke
				(width 0.1)
				(type default)
			)
			(layer "F.Fab")
		)
		(fp_line
			(start 2.3749 1.970024)
			(end 2.3749 -1.970024)
			(stroke
				(width 0.1)
				(type default)
			)
			(layer "F.Fab")
		)
		(fp_text user "+"
			(at -4.9784 -0.23495 0)
			(unlocked yes)
			(layer "F.Fab")
			(effects
				(font
					(size 1.905 1.4224)
					(thickness 0.1524)
				)
				(justify left)
			)
		)
		(fp_text user "-"
			(at 4.1656 -0.23495 0)
			(unlocked yes)
			(layer "F.Fab")
			(effects
				(font
					(size 1.905 1.4224)
					(thickness 0.1524)
				)
				(justify left)
			)
		)
		(pad "A" smd rect
			(at -2.450084 0)
			(size 2.159 2.2606)
			(layers "F.Cu" "F.Mask" "F.Paste")
			(net "GND")
		)
		(pad "C" smd rect
			(at 2.450084 0)
			(size 2.159 2.2606)
			(layers "F.Cu" "F.Mask" "F.Paste")
			(net "P12V_AUX")
		)
	)
	(footprint ""
		(layer "F.Cu")
		(at 449.120514 -70.307454 90)
		(property "Reference" "PC879"
			(at 0 0 90)
			(layer "F.SilkS")
			(hide yes)
			(effects
				(font
					(size 1.27 1.27)
				)
			)
		)
		(property "Value" ""
			(at 0 0 90)
			(layer "F.Fab")
			(effects
				(font
					(size 1.27 1.27)
				)
			)
		)
		(duplicate_pad_numbers_are_jumpers no)
		(fp_line
			(start 0.7874 -0.4064)
			(end 0.7874 0.4064)
			(stroke
				(width 0.1524)
				(type default)
			)
			(layer "F.SilkS")
		)
		(fp_line
			(start -0.7874 -0.4064)
			(end 0.7874 -0.4064)
			(stroke
				(width 0.1524)
				(type default)
			)
			(layer "F.SilkS")
		)
		(fp_line
			(start 0.7874 0.4064)
			(end -0.7874 0.4064)
			(stroke
				(width 0.1524)
				(type default)
			)
			(layer "F.SilkS")
		)
		(fp_line
			(start -0.7874 0.4064)
			(end -0.7874 -0.4064)
			(stroke
				(width 0.1524)
				(type default)
			)
			(layer "F.SilkS")
		)
		(fp_line
			(start -0.12065 -0.305054)
			(end -0.12065 -0.2794)
			(stroke
				(width 0.1)
				(type default)
			)
			(layer "F.Fab")
		)
		(fp_line
			(start -0.67945 -0.305054)
			(end -0.12065 -0.305054)
			(stroke
				(width 0.1)
				(type default)
			)
			(layer "F.Fab")
		)
		(fp_line
			(start 0.67945 -0.3048)
			(end 0.67945 0.3048)
			(stroke
				(width 0.1)
				(type default)
			)
			(layer "F.Fab")
		)
		(fp_line
			(start 0.12065 -0.3048)
			(end 0.67945 -0.3048)
			(stroke
				(width 0.1)
				(type default)
			)
			(layer "F.Fab")
		)
		(fp_line
			(start 0.12065 -0.2794)
			(end 0.12065 -0.3048)
			(stroke
				(width 0.1)
				(type default)
			)
			(layer "F.Fab")
		)
		(fp_line
			(start -0.12065 -0.2794)
			(end 0.12065 -0.2794)
			(stroke
				(width 0.1)
				(type default)
			)
			(layer "F.Fab")
		)
		(fp_line
			(start 0.120396 0.2794)
			(end -0.12065 0.2794)
			(stroke
				(width 0.1)
				(type default)
			)
			(layer "F.Fab")
		)
		(fp_line
			(start -0.12065 0.2794)
			(end -0.12065 0.3048)
			(stroke
				(width 0.1)
				(type default)
			)
			(layer "F.Fab")
		)
		(fp_line
			(start 0.67945 0.3048)
			(end 0.120396 0.3048)
			(stroke
				(width 0.1)
				(type default)
			)
			(layer "F.Fab")
		)
		(fp_line
			(start 0.120396 0.3048)
			(end 0.120396 0.2794)
			(stroke
				(width 0.1)
				(type default)
			)
			(layer "F.Fab")
		)
		(fp_line
			(start -0.12065 0.3048)
			(end -0.67945 0.3048)
			(stroke
				(width 0.1)
				(type default)
			)
			(layer "F.Fab")
		)
		(fp_line
			(start -0.67945 0.3048)
			(end -0.67945 -0.305054)
			(stroke
				(width 0.1)
				(type default)
			)
			(layer "F.Fab")
		)
		(pad "1" smd circle
			(at -0.40005 0 90)
			(size 0 0)
			(layers "F.Cu" "F.Mask" "F.Paste")
			(net "P12V_AUX")
		)
		(pad "2" smd circle
			(at 0.40005 0 90)
			(size 0 0)
			(layers "F.Cu" "F.Mask" "F.Paste")
			(net "GND")
		)
	)
	(footprint ""
		(layer "F.Cu")
		(at 280.227786 -35.876738)
		(property "Reference" "R6094"
			(at 0 0 0)
			(layer "F.SilkS")
			(hide yes)
			(effects
				(font
					(size 1.27 1.27)
				)
			)
		)
		(property "Value" ""
			(at 0 0 0)
			(layer "F.Fab")
			(effects
				(font
					(size 1.27 1.27)
				)
			)
		)
		(duplicate_pad_numbers_are_jumpers no)
		(fp_line
			(start -0.7874 -0.4064)
			(end 0.7874 -0.4064)
			(stroke
				(width 0.1524)
				(type default)
			)
			(layer "F.SilkS")
		)
		(fp_line
			(start -0.7874 0.4064)
			(end -0.7874 -0.4064)
			(stroke
				(width 0.1524)
				(type default)
			)
			(layer "F.SilkS")
		)
		(fp_line
			(start 0.7874 -0.4064)
			(end 0.7874 0.4064)
			(stroke
				(width 0.1524)
				(type default)
			)
			(layer "F.SilkS")
		)
		(fp_line
			(start 0.7874 0.4064)
			(end -0.7874 0.4064)
			(stroke
				(width 0.1524)
				(type default)
			)
			(layer "F.SilkS")
		)
		(fp_line
			(start -0.67945 -0.305054)
			(end -0.12065 -0.305054)
			(stroke
				(width 0.1)
				(type default)
			)
			(layer "F.Fab")
		)
		(fp_line
			(start -0.67945 0.3048)
			(end -0.67945 -0.305054)
			(stroke
				(width 0.1)
				(type default)
			)
			(layer "F.Fab")
		)
		(fp_line
			(start -0.12065 -0.305054)
			(end -0.12065 -0.2794)
			(stroke
				(width 0.1)
				(type default)
			)
			(layer "F.Fab")
		)
		(fp_line
			(start -0.12065 -0.2794)
			(end 0.12065 -0.2794)
			(stroke
				(width 0.1)
				(type default)
			)
			(layer "F.Fab")
		)
		(fp_line
			(start -0.12065 0.2794)
			(end -0.12065 0.3048)
			(stroke
				(width 0.1)
				(type default)
			)
			(layer "F.Fab")
		)
		(fp_line
			(start -0.12065 0.3048)
			(end -0.67945 0.3048)
			(stroke
				(width 0.1)
				(type default)
			)
			(layer "F.Fab")
		)
		(fp_line
			(start 0.120396 0.2794)
			(end -0.12065 0.2794)
			(stroke
				(width 0.1)
				(type default)
			)
			(layer "F.Fab")
		)
		(fp_line
			(start 0.120396 0.3048)
			(end 0.120396 0.2794)
			(stroke
				(width 0.1)
				(type default)
			)
			(layer "F.Fab")
		)
		(fp_line
			(start 0.12065 -0.3048)
			(end 0.67945 -0.3048)
			(stroke
				(width 0.1)
				(type default)
			)
			(layer "F.Fab")
		)
		(fp_line
			(start 0.12065 -0.2794)
			(end 0.12065 -0.3048)
			(stroke
				(width 0.1)
				(type default)
			)
			(layer "F.Fab")
		)
		(fp_line
			(start 0.67945 -0.3048)
			(end 0.67945 0.3048)
			(stroke
				(width 0.1)
				(type default)
			)
			(layer "F.Fab")
		)
		(fp_line
			(start 0.67945 0.3048)
			(end 0.120396 0.3048)
			(stroke
				(width 0.1)
				(type default)
			)
			(layer "F.Fab")
		)
		(pad "1" smd circle
			(at -0.40005 0)
			(size 0 0)
			(layers "F.Cu" "F.Mask" "F.Paste")
			(net "PWRGD_P3V3_SSD10_D")
		)
		(pad "2" smd circle
			(at 0.40005 0)
			(size 0 0)
			(layers "F.Cu" "F.Mask" "F.Paste")
			(net "PWRGD_P3V3_SSD10_R")
		)
	)
	(footprint ""
		(layer "F.Cu")
		(at 146.18208 -296.191432 180)
		(property "Reference" "C3204"
			(at 0 0 180)
			(layer "F.SilkS")
			(hide yes)
			(effects
				(font
					(size 1.27 1.27)
				)
			)
		)
		(property "Value" ""
			(at 0 0 180)
			(layer "F.Fab")
			(effects
				(font
					(size 1.27 1.27)
				)
			)
		)
		(duplicate_pad_numbers_are_jumpers no)
		(fp_line
			(start 1.2954 0.5842)
			(end -1.2954 0.5842)
			(stroke
				(width 0.1524)
				(type default)
			)
			(layer "F.SilkS")
		)
		(fp_line
			(start 1.2954 -0.5842)
			(end 1.2954 0.5842)
			(stroke
				(width 0.1524)
				(type default)
			)
			(layer "F.SilkS")
		)
		(fp_line
			(start -1.2954 0.5842)
			(end -1.2954 -0.5842)
			(stroke
				(width 0.1524)
				(type default)
			)
			(layer "F.SilkS")
		)
		(fp_line
			(start -1.2954 -0.5842)
			(end 1.2954 -0.5842)
			(stroke
				(width 0.1524)
				(type default)
			)
			(layer "F.SilkS")
		)
		(fp_line
			(start 1.1938 0.4064)
			(end 0.8636 0.4064)
			(stroke
				(width 0.1)
				(type default)
			)
			(layer "F.Fab")
		)
		(fp_line
			(start 1.1938 -0.4064)
			(end 1.1938 0.4064)
			(stroke
				(width 0.1)
				(type default)
			)
			(layer "F.Fab")
		)
		(fp_line
			(start 0.8636 0.4572)
			(end -0.8636 0.4572)
			(stroke
				(width 0.1)
				(type default)
			)
			(layer "F.Fab")
		)
		(fp_line
			(start 0.8636 0.4064)
			(end 0.8636 0.4572)
			(stroke
				(width 0.1)
				(type default)
			)
			(layer "F.Fab")
		)
		(fp_line
			(start 0.8636 -0.4064)
			(end 1.1938 -0.4064)
			(stroke
				(width 0.1)
				(type default)
			)
			(layer "F.Fab")
		)
		(fp_line
			(start 0.8636 -0.4572)
			(end 0.8636 -0.4064)
			(stroke
				(width 0.1)
				(type default)
			)
			(layer "F.Fab")
		)
		(fp_line
			(start -0.8636 0.4572)
			(end -0.8636 0.4064)
			(stroke
				(width 0.1)
				(type default)
			)
			(layer "F.Fab")
		)
		(fp_line
			(start -0.8636 0.4064)
			(end -1.1938 0.4064)
			(stroke
				(width 0.1)
				(type default)
			)
			(layer "F.Fab")
		)
		(fp_line
			(start -0.8636 -0.4064)
			(end -0.8636 -0.4572)
			(stroke
				(width 0.1)
				(type default)
			)
			(layer "F.Fab")
		)
		(fp_line
			(start -0.8636 -0.4572)
			(end 0.8636 -0.4572)
			(stroke
				(width 0.1)
				(type default)
			)
			(layer "F.Fab")
		)
		(fp_line
			(start -1.1938 0.4064)
			(end -1.1938 -0.4064)
			(stroke
				(width 0.1)
				(type default)
			)
			(layer "F.Fab")
		)
		(fp_line
			(start -1.1938 -0.4064)
			(end -0.8636 -0.4064)
			(stroke
				(width 0.1)
				(type default)
			)
			(layer "F.Fab")
		)
		(pad "1" smd rect
			(at -0.7366 0 90)
			(size 0.7112 0.8128)
			(layers "F.Cu" "F.Mask" "F.Paste")
			(net "PCEPLL0_VDDA18_PEX1_R")
		)
		(pad "2" smd rect
			(at 0.7366 0 90)
			(size 0.7112 0.8128)
			(layers "F.Cu" "F.Mask" "F.Paste")
			(net "GND")
		)
	)
	(footprint ""
		(layer "F.Cu")
		(at 460.103728 -310.695086 180)
		(property "Reference" "PR181"
			(at 0 0 180)
			(layer "F.SilkS")
			(hide yes)
			(effects
				(font
					(size 1.27 1.27)
				)
			)
		)
		(property "Value" ""
			(at 0 0 180)
			(layer "F.Fab")
			(effects
				(font
					(size 1.27 1.27)
				)
			)
		)
		(duplicate_pad_numbers_are_jumpers no)
		(fp_line
			(start 0.7874 0.4064)
			(end -0.7874 0.4064)
			(stroke
				(width 0.1524)
				(type default)
			)
			(layer "F.SilkS")
		)
		(fp_line
			(start 0.7874 -0.4064)
			(end 0.7874 0.4064)
			(stroke
				(width 0.1524)
				(type default)
			)
			(layer "F.SilkS")
		)
		(fp_line
			(start -0.7874 0.4064)
			(end -0.7874 -0.4064)
			(stroke
				(width 0.1524)
				(type default)
			)
			(layer "F.SilkS")
		)
		(fp_line
			(start -0.7874 -0.4064)
			(end 0.7874 -0.4064)
			(stroke
				(width 0.1524)
				(type default)
			)
			(layer "F.SilkS")
		)
		(fp_line
			(start 0.67945 0.3048)
			(end 0.120396 0.3048)
			(stroke
				(width 0.1)
				(type default)
			)
			(layer "F.Fab")
		)
		(fp_line
			(start 0.67945 -0.3048)
			(end 0.67945 0.3048)
			(stroke
				(width 0.1)
				(type default)
			)
			(layer "F.Fab")
		)
		(fp_line
			(start 0.12065 -0.2794)
			(end 0.12065 -0.3048)
			(stroke
				(width 0.1)
				(type default)
			)
			(layer "F.Fab")
		)
		(fp_line
			(start 0.12065 -0.3048)
			(end 0.67945 -0.3048)
			(stroke
				(width 0.1)
				(type default)
			)
			(layer "F.Fab")
		)
		(fp_line
			(start 0.120396 0.3048)
			(end 0.120396 0.2794)
			(stroke
				(width 0.1)
				(type default)
			)
			(layer "F.Fab")
		)
		(fp_line
			(start 0.120396 0.2794)
			(end -0.12065 0.2794)
			(stroke
				(width 0.1)
				(type default)
			)
			(layer "F.Fab")
		)
		(fp_line
			(start -0.12065 0.3048)
			(end -0.67945 0.3048)
			(stroke
				(width 0.1)
				(type default)
			)
			(layer "F.Fab")
		)
		(fp_line
			(start -0.12065 0.2794)
			(end -0.12065 0.3048)
			(stroke
				(width 0.1)
				(type default)
			)
			(layer "F.Fab")
		)
		(fp_line
			(start -0.12065 -0.2794)
			(end 0.12065 -0.2794)
			(stroke
				(width 0.1)
				(type default)
			)
			(layer "F.Fab")
		)
		(fp_line
			(start -0.12065 -0.305054)
			(end -0.12065 -0.2794)
			(stroke
				(width 0.1)
				(type default)
			)
			(layer "F.Fab")
		)
		(fp_line
			(start -0.67945 0.3048)
			(end -0.67945 -0.305054)
			(stroke
				(width 0.1)
				(type default)
			)
			(layer "F.Fab")
		)
		(fp_line
			(start -0.67945 -0.305054)
			(end -0.12065 -0.305054)
			(stroke
				(width 0.1)
				(type default)
			)
			(layer "F.Fab")
		)
		(pad "1" smd circle
			(at -0.40005 0 180)
			(size 0 0)
			(layers "F.Cu" "F.Mask" "F.Paste")
			(net "SH_P1V25_PEX3_FB_P")
		)
		(pad "2" smd circle
			(at 0.40005 0 180)
			(size 0 0)
			(layers "F.Cu" "F.Mask" "F.Paste")
			(net "P1V25_PEX3_FB")
		)
	)
	(footprint ""
		(layer "F.Cu")
		(at 394.875512 -69.47916 180)
		(property "Reference" "PU116"
			(at -1.975358 4.07924 90)
			(unlocked yes)
			(layer "F.SilkS")
			(effects
				(font
					(size 0.7874 0.5842)
					(thickness 0.1524)
				)
			)
		)
		(property "Value" ""
			(at 0 0 180)
			(layer "F.Fab")
			(effects
				(font
					(size 1.27 1.27)
				)
			)
		)
		(duplicate_pad_numbers_are_jumpers no)
		(fp_line
			(start 1.239774 1.495298)
			(end -1.239774 1.495298)
			(stroke
				(width 0.1524)
				(type default)
			)
			(layer "F.SilkS")
		)
		(fp_line
			(start 1.239774 -1.495298)
			(end 1.239774 1.495298)
			(stroke
				(width 0.1524)
				(type default)
			)
			(layer "F.SilkS")
		)
		(fp_line
			(start -1.239774 1.495298)
			(end -1.239774 -1.495298)
			(stroke
				(width 0.1524)
				(type default)
			)
			(layer "F.SilkS")
		)
		(fp_line
			(start -1.239774 -1.495298)
			(end 1.239774 -1.495298)
			(stroke
				(width 0.1524)
				(type default)
			)
			(layer "F.SilkS")
		)
		(fp_poly
			(pts
				(xy -2.061972 -2.668778) (xy -2.780538 -1.950466) (xy -1.702816 -1.59131)
			)
			(stroke
				(width 0)
				(type default)
			)
			(fill yes)
			(layer "F.SilkS")
		)
		(fp_line
			(start 0.8001 1.050036)
			(end -0.8001 1.050036)
			(stroke
				(width 0.1)
				(type default)
			)
			(layer "F.Fab")
		)
		(fp_line
			(start 0.8001 -1.050036)
			(end 0.8001 1.050036)
			(stroke
				(width 0.1)
				(type default)
			)
			(layer "F.Fab")
		)
		(fp_line
			(start -0.8001 1.050036)
			(end -0.8001 -1.050036)
			(stroke
				(width 0.1)
				(type default)
			)
			(layer "F.Fab")
		)
		(fp_line
			(start -0.8001 -1.050036)
			(end 0.8001 -1.050036)
			(stroke
				(width 0.1)
				(type default)
			)
			(layer "F.Fab")
		)
		(fp_poly
			(pts
				(xy -2.458974 -0.508) (xy -2.458974 0.508) (xy -1.442974 0)
			)
			(stroke
				(width 0)
				(type default)
			)
			(fill yes)
			(layer "F.Fab")
		)
		(pad "1_2" smd circle
			(at -0.374904 0 270)
			(size 0 0)
			(layers "F.Cu" "F.Mask" "F.Paste")
			(net "P12V_AUX")
		)
		(pad "3" smd rect
			(at -0.499872 0.999998 180)
			(size 0.254 0.7112)
			(layers "F.Cu" "F.Mask" "F.Paste")
			(net "GND")
		)
		(pad "4" smd rect
			(at 0 0.999998 180)
			(size 0.254 0.7112)
			(layers "F.Cu" "F.Mask" "F.Paste")
			(net "P12V_SSD13_CO_ILIMIT")
		)
		(pad "5" smd rect
			(at 0.499872 0.999998 180)
			(size 0.254 0.7112)
			(layers "F.Cu" "F.Mask" "F.Paste")
			(net "P12V_SSD13_CO_MODE")
		)
		(pad "6_7" smd circle
			(at 0.374904 0 90)
			(size 0 0)
			(layers "F.Cu" "F.Mask" "F.Paste")
			(net "P12V_SSD13_R")
		)
		(pad "8" smd rect
			(at 0.499872 -0.999998 180)
			(size 0.254 0.7112)
			(layers "F.Cu" "F.Mask" "F.Paste")
			(net "P12V_SSD13_CO_GATE")
		)
		(pad "9" smd rect
			(at 0 -0.999998 180)
			(size 0.254 0.7112)
			(layers "F.Cu" "F.Mask" "F.Paste")
			(net "P12V_SSD13_CO_EN")
		)
		(pad "10" smd rect
			(at -0.499872 -0.999998 180)
			(size 0.254 0.7112)
			(layers "F.Cu" "F.Mask" "F.Paste")
			(net "P12V_SSD13_CO_DV_DT")
		)
	)
	(footprint ""
		(layer "F.Cu")
		(at 338.492592 -9.139682 180)
		(property "Reference" "C2739"
			(at 0 0 180)
			(layer "F.SilkS")
			(hide yes)
			(effects
				(font
					(size 1.27 1.27)
				)
			)
		)
		(property "Value" ""
			(at 0 0 180)
			(layer "F.Fab")
			(effects
				(font
					(size 1.27 1.27)
				)
			)
		)
		(duplicate_pad_numbers_are_jumpers no)
		(fp_line
			(start 0.7874 0.4064)
			(end -0.7874 0.4064)
			(stroke
				(width 0.1524)
				(type default)
			)
			(layer "F.SilkS")
		)
		(fp_line
			(start 0.7874 -0.4064)
			(end 0.7874 0.4064)
			(stroke
				(width 0.1524)
				(type default)
			)
			(layer "F.SilkS")
		)
		(fp_line
			(start -0.7874 0.4064)
			(end -0.7874 -0.4064)
			(stroke
				(width 0.1524)
				(type default)
			)
			(layer "F.SilkS")
		)
		(fp_line
			(start -0.7874 -0.4064)
			(end 0.7874 -0.4064)
			(stroke
				(width 0.1524)
				(type default)
			)
			(layer "F.SilkS")
		)
		(fp_line
			(start 0.67945 0.3048)
			(end 0.120396 0.3048)
			(stroke
				(width 0.1)
				(type default)
			)
			(layer "F.Fab")
		)
		(fp_line
			(start 0.67945 -0.3048)
			(end 0.67945 0.3048)
			(stroke
				(width 0.1)
				(type default)
			)
			(layer "F.Fab")
		)
		(fp_line
			(start 0.12065 -0.2794)
			(end 0.12065 -0.3048)
			(stroke
				(width 0.1)
				(type default)
			)
			(layer "F.Fab")
		)
		(fp_line
			(start 0.12065 -0.3048)
			(end 0.67945 -0.3048)
			(stroke
				(width 0.1)
				(type default)
			)
			(layer "F.Fab")
		)
		(fp_line
			(start 0.120396 0.3048)
			(end 0.120396 0.2794)
			(stroke
				(width 0.1)
				(type default)
			)
			(layer "F.Fab")
		)
		(fp_line
			(start 0.120396 0.2794)
			(end -0.12065 0.2794)
			(stroke
				(width 0.1)
				(type default)
			)
			(layer "F.Fab")
		)
		(fp_line
			(start -0.12065 0.3048)
			(end -0.67945 0.3048)
			(stroke
				(width 0.1)
				(type default)
			)
			(layer "F.Fab")
		)
		(fp_line
			(start -0.12065 0.2794)
			(end -0.12065 0.3048)
			(stroke
				(width 0.1)
				(type default)
			)
			(layer "F.Fab")
		)
		(fp_line
			(start -0.12065 -0.2794)
			(end 0.12065 -0.2794)
			(stroke
				(width 0.1)
				(type default)
			)
			(layer "F.Fab")
		)
		(fp_line
			(start -0.12065 -0.305054)
			(end -0.12065 -0.2794)
			(stroke
				(width 0.1)
				(type default)
			)
			(layer "F.Fab")
		)
		(fp_line
			(start -0.67945 0.3048)
			(end -0.67945 -0.305054)
			(stroke
				(width 0.1)
				(type default)
			)
			(layer "F.Fab")
		)
		(fp_line
			(start -0.67945 -0.305054)
			(end -0.12065 -0.305054)
			(stroke
				(width 0.1)
				(type default)
			)
			(layer "F.Fab")
		)
		(pad "1" smd circle
			(at -0.40005 0 180)
			(size 0 0)
			(layers "F.Cu" "F.Mask" "F.Paste")
			(net "GND")
		)
		(pad "2" smd circle
			(at 0.40005 0 180)
			(size 0 0)
			(layers "F.Cu" "F.Mask" "F.Paste")
			(net "P3V3_AUX")
		)
	)
	(footprint ""
		(layer "F.Cu")
		(at 169.562526 -22.937216 90)
		(property "Reference" "R1670"
			(at 0 0 90)
			(layer "F.SilkS")
			(hide yes)
			(effects
				(font
					(size 1.27 1.27)
				)
			)
		)
		(property "Value" ""
			(at 0 0 90)
			(layer "F.Fab")
			(effects
				(font
					(size 1.27 1.27)
				)
			)
		)
		(duplicate_pad_numbers_are_jumpers no)
		(fp_line
			(start 0.7874 -0.4064)
			(end 0.7874 0.4064)
			(stroke
				(width 0.1524)
				(type default)
			)
			(layer "F.SilkS")
		)
		(fp_line
			(start -0.7874 -0.4064)
			(end 0.7874 -0.4064)
			(stroke
				(width 0.1524)
				(type default)
			)
			(layer "F.SilkS")
		)
		(fp_line
			(start 0.7874 0.4064)
			(end -0.7874 0.4064)
			(stroke
				(width 0.1524)
				(type default)
			)
			(layer "F.SilkS")
		)
		(fp_line
			(start -0.7874 0.4064)
			(end -0.7874 -0.4064)
			(stroke
				(width 0.1524)
				(type default)
			)
			(layer "F.SilkS")
		)
		(fp_line
			(start -0.12065 -0.305054)
			(end -0.12065 -0.2794)
			(stroke
				(width 0.1)
				(type default)
			)
			(layer "F.Fab")
		)
		(fp_line
			(start -0.67945 -0.305054)
			(end -0.12065 -0.305054)
			(stroke
				(width 0.1)
				(type default)
			)
			(layer "F.Fab")
		)
		(fp_line
			(start 0.67945 -0.3048)
			(end 0.67945 0.3048)
			(stroke
				(width 0.1)
				(type default)
			)
			(layer "F.Fab")
		)
		(fp_line
			(start 0.12065 -0.3048)
			(end 0.67945 -0.3048)
			(stroke
				(width 0.1)
				(type default)
			)
			(layer "F.Fab")
		)
		(fp_line
			(start 0.12065 -0.2794)
			(end 0.12065 -0.3048)
			(stroke
				(width 0.1)
				(type default)
			)
			(layer "F.Fab")
		)
		(fp_line
			(start -0.12065 -0.2794)
			(end 0.12065 -0.2794)
			(stroke
				(width 0.1)
				(type default)
			)
			(layer "F.Fab")
		)
		(fp_line
			(start 0.120396 0.2794)
			(end -0.12065 0.2794)
			(stroke
				(width 0.1)
				(type default)
			)
			(layer "F.Fab")
		)
		(fp_line
			(start -0.12065 0.2794)
			(end -0.12065 0.3048)
			(stroke
				(width 0.1)
				(type default)
			)
			(layer "F.Fab")
		)
		(fp_line
			(start 0.67945 0.3048)
			(end 0.120396 0.3048)
			(stroke
				(width 0.1)
				(type default)
			)
			(layer "F.Fab")
		)
		(fp_line
			(start 0.120396 0.3048)
			(end 0.120396 0.2794)
			(stroke
				(width 0.1)
				(type default)
			)
			(layer "F.Fab")
		)
		(fp_line
			(start -0.12065 0.3048)
			(end -0.67945 0.3048)
			(stroke
				(width 0.1)
				(type default)
			)
			(layer "F.Fab")
		)
		(fp_line
			(start -0.67945 0.3048)
			(end -0.67945 -0.305054)
			(stroke
				(width 0.1)
				(type default)
			)
			(layer "F.Fab")
		)
		(pad "1" smd circle
			(at -0.40005 0 90)
			(size 0 0)
			(layers "F.Cu" "F.Mask" "F.Paste")
			(net "SMB_BIC_I2C9_MUX0_SSD5_R_SDA")
		)
		(pad "2" smd circle
			(at 0.40005 0 90)
			(size 0 0)
			(layers "F.Cu" "F.Mask" "F.Paste")
			(net "SMB_ISO_SSD5_SDA")
		)
	)
	(footprint ""
		(layer "F.Cu")
		(at 165.269672 -343.952322 90)
		(property "Reference" "C2514"
			(at 0 0 90)
			(layer "F.SilkS")
			(hide yes)
			(effects
				(font
					(size 1.27 1.27)
				)
			)
		)
		(property "Value" ""
			(at 0 0 90)
			(layer "F.Fab")
			(effects
				(font
					(size 1.27 1.27)
				)
			)
		)
		(duplicate_pad_numbers_are_jumpers no)
		(fp_line
			(start 0.299974 -0.150114)
			(end 0.299974 0.150114)
			(stroke
				(width 0.1)
				(type default)
			)
			(layer "F.Fab")
		)
		(fp_line
			(start -0.299974 -0.150114)
			(end 0.299974 -0.150114)
			(stroke
				(width 0.1)
				(type default)
			)
			(layer "F.Fab")
		)
		(fp_line
			(start 0.299974 0.150114)
			(end -0.299974 0.150114)
			(stroke
				(width 0.1)
				(type default)
			)
			(layer "F.Fab")
		)
		(fp_line
			(start -0.299974 0.150114)
			(end -0.299974 -0.150114)
			(stroke
				(width 0.1)
				(type default)
			)
			(layer "F.Fab")
		)
		(pad "1" smd rect
			(at -0.2667 0 90)
			(size 0.3048 0.381)
			(layers "F.Cu" "F.Mask" "F.Paste")
			(net "P5E_PEX1_STN4_TX_DP<78>")
		)
		(pad "2" smd rect
			(at 0.2667 0 90)
			(size 0.3048 0.381)
			(layers "F.Cu" "F.Mask" "F.Paste")
			(net "P5E_PEX1_STN4_TX_C_DP<78>")
		)
	)
	(footprint ""
		(layer "F.Cu")
		(at 56.526684 -53.697124 -90)
		(property "Reference" "PC534"
			(at 0 0 270)
			(layer "F.SilkS")
			(hide yes)
			(effects
				(font
					(size 1.27 1.27)
				)
			)
		)
		(property "Value" ""
			(at 0 0 270)
			(layer "F.Fab")
			(effects
				(font
					(size 1.27 1.27)
				)
			)
		)
		(duplicate_pad_numbers_are_jumpers no)
		(fp_line
			(start -0.7874 0.4064)
			(end -0.7874 -0.4064)
			(stroke
				(width 0.1524)
				(type default)
			)
			(layer "F.SilkS")
		)
		(fp_line
			(start 0.7874 0.4064)
			(end -0.7874 0.4064)
			(stroke
				(width 0.1524)
				(type default)
			)
			(layer "F.SilkS")
		)
		(fp_line
			(start -0.7874 -0.4064)
			(end 0.7874 -0.4064)
			(stroke
				(width 0.1524)
				(type default)
			)
			(layer "F.SilkS")
		)
		(fp_line
			(start 0.7874 -0.4064)
			(end 0.7874 0.4064)
			(stroke
				(width 0.1524)
				(type default)
			)
			(layer "F.SilkS")
		)
		(fp_line
			(start -0.67945 0.3048)
			(end -0.67945 -0.305054)
			(stroke
				(width 0.1)
				(type default)
			)
			(layer "F.Fab")
		)
		(fp_line
			(start -0.12065 0.3048)
			(end -0.67945 0.3048)
			(stroke
				(width 0.1)
				(type default)
			)
			(layer "F.Fab")
		)
		(fp_line
			(start 0.120396 0.3048)
			(end 0.120396 0.2794)
			(stroke
				(width 0.1)
				(type default)
			)
			(layer "F.Fab")
		)
		(fp_line
			(start 0.67945 0.3048)
			(end 0.120396 0.3048)
			(stroke
				(width 0.1)
				(type default)
			)
			(layer "F.Fab")
		)
		(fp_line
			(start -0.12065 0.2794)
			(end -0.12065 0.3048)
			(stroke
				(width 0.1)
				(type default)
			)
			(layer "F.Fab")
		)
		(fp_line
			(start 0.120396 0.2794)
			(end -0.12065 0.2794)
			(stroke
				(width 0.1)
				(type default)
			)
			(layer "F.Fab")
		)
		(fp_line
			(start -0.12065 -0.2794)
			(end 0.12065 -0.2794)
			(stroke
				(width 0.1)
				(type default)
			)
			(layer "F.Fab")
		)
		(fp_line
			(start 0.12065 -0.2794)
			(end 0.12065 -0.3048)
			(stroke
				(width 0.1)
				(type default)
			)
			(layer "F.Fab")
		)
		(fp_line
			(start 0.12065 -0.3048)
			(end 0.67945 -0.3048)
			(stroke
				(width 0.1)
				(type default)
			)
			(layer "F.Fab")
		)
		(fp_line
			(start 0.67945 -0.3048)
			(end 0.67945 0.3048)
			(stroke
				(width 0.1)
				(type default)
			)
			(layer "F.Fab")
		)
		(fp_line
			(start -0.67945 -0.305054)
			(end -0.12065 -0.305054)
			(stroke
				(width 0.1)
				(type default)
			)
			(layer "F.Fab")
		)
		(fp_line
			(start -0.12065 -0.305054)
			(end -0.12065 -0.2794)
			(stroke
				(width 0.1)
				(type default)
			)
			(layer "F.Fab")
		)
		(pad "1" smd circle
			(at -0.40005 0 270)
			(size 0 0)
			(layers "F.Cu" "F.Mask" "F.Paste")
			(net "P3V3_AUX")
		)
		(pad "2" smd circle
			(at 0.40005 0 270)
			(size 0 0)
			(layers "F.Cu" "F.Mask" "F.Paste")
			(net "GND")
		)
	)
	(footprint ""
		(layer "F.Cu")
		(at 385.548124 -101.095302)
		(property "Reference" "C694"
			(at 0 0 0)
			(layer "F.SilkS")
			(hide yes)
			(effects
				(font
					(size 1.27 1.27)
				)
			)
		)
		(property "Value" ""
			(at 0 0 0)
			(layer "F.Fab")
			(effects
				(font
					(size 1.27 1.27)
				)
			)
		)
		(duplicate_pad_numbers_are_jumpers no)
		(fp_line
			(start -0.299974 -0.150114)
			(end 0.299974 -0.150114)
			(stroke
				(width 0.1)
				(type default)
			)
			(layer "F.Fab")
		)
		(fp_line
			(start -0.299974 0.150114)
			(end -0.299974 -0.150114)
			(stroke
				(width 0.1)
				(type default)
			)
			(layer "F.Fab")
		)
		(fp_line
			(start 0.299974 -0.150114)
			(end 0.299974 0.150114)
			(stroke
				(width 0.1)
				(type default)
			)
			(layer "F.Fab")
		)
		(fp_line
			(start 0.299974 0.150114)
			(end -0.299974 0.150114)
			(stroke
				(width 0.1)
				(type default)
			)
			(layer "F.Fab")
		)
		(pad "1" smd rect
			(at -0.2667 0)
			(size 0.3048 0.381)
			(layers "F.Cu" "F.Mask" "F.Paste")
			(net "P5E_PEX3_STN1_TX_DN<17>")
		)
		(pad "2" smd rect
			(at 0.2667 0)
			(size 0.3048 0.381)
			(layers "F.Cu" "F.Mask" "F.Paste")
			(net "P5E_PEX3_STN1_TX_C_DN<17>")
		)
	)
	(footprint ""
		(layer "F.Cu")
		(at 376.34926 -287.395412 -90)
		(property "Reference" "C3574"
			(at 0 0 270)
			(layer "F.SilkS")
			(hide yes)
			(effects
				(font
					(size 1.27 1.27)
				)
			)
		)
		(property "Value" ""
			(at 0 0 270)
			(layer "F.Fab")
			(effects
				(font
					(size 1.27 1.27)
				)
			)
		)
		(duplicate_pad_numbers_are_jumpers no)
		(fp_line
			(start -0.299974 0.150114)
			(end -0.299974 -0.150114)
			(stroke
				(width 0.1)
				(type default)
			)
			(layer "F.Fab")
		)
		(fp_line
			(start 0.299974 0.150114)
			(end -0.299974 0.150114)
			(stroke
				(width 0.1)
				(type default)
			)
			(layer "F.Fab")
		)
		(fp_line
			(start -0.299974 -0.150114)
			(end 0.299974 -0.150114)
			(stroke
				(width 0.1)
				(type default)
			)
			(layer "F.Fab")
		)
		(fp_line
			(start 0.299974 -0.150114)
			(end 0.299974 0.150114)
			(stroke
				(width 0.1)
				(type default)
			)
			(layer "F.Fab")
		)
		(pad "1" smd rect
			(at -0.2667 0 270)
			(size 0.3048 0.381)
			(layers "F.Cu" "F.Mask" "F.Paste")
			(net "P1V8_PLL0_PEX3")
		)
		(pad "2" smd rect
			(at 0.2667 0 270)
			(size 0.3048 0.381)
			(layers "F.Cu" "F.Mask" "F.Paste")
			(net "GND")
		)
	)
	(footprint ""
		(layer "F.Cu")
		(at 294.691816 -161.881566 90)
		(property "Reference" "Q121"
			(at -0.032766 -1.930146 90)
			(unlocked yes)
			(layer "F.SilkS")
			(effects
				(font
					(size 0.7874 0.5842)
					(thickness 0.1524)
				)
			)
		)
		(property "Value" ""
			(at 0 0 90)
			(layer "F.Fab")
			(effects
				(font
					(size 1.27 1.27)
				)
			)
		)
		(duplicate_pad_numbers_are_jumpers no)
		(fp_line
			(start 1.376172 -1.199896)
			(end 1.376172 1.199896)
			(stroke
				(width 0.1524)
				(type default)
			)
			(layer "F.SilkS")
		)
		(fp_line
			(start 0.508 -1.199896)
			(end 1.376172 -1.199896)
			(stroke
				(width 0.1524)
				(type default)
			)
			(layer "F.SilkS")
		)
		(fp_line
			(start -0.508 -1.199896)
			(end 0 -0.762)
			(stroke
				(width 0.1524)
				(type default)
			)
			(layer "F.SilkS")
		)
		(fp_line
			(start -1.376172 -1.199896)
			(end -0.508 -1.199896)
			(stroke
				(width 0.1524)
				(type default)
			)
			(layer "F.SilkS")
		)
		(fp_line
			(start 0 -0.762)
			(end 0.508 -1.199896)
			(stroke
				(width 0.1524)
				(type default)
			)
			(layer "F.SilkS")
		)
		(fp_line
			(start 1.376172 1.199896)
			(end -1.376172 1.199896)
			(stroke
				(width 0.1524)
				(type default)
			)
			(layer "F.SilkS")
		)
		(fp_line
			(start -1.376172 1.199896)
			(end -1.376172 -1.199896)
			(stroke
				(width 0.1524)
				(type default)
			)
			(layer "F.SilkS")
		)
		(fp_poly
			(pts
				(xy -1.537208 -1.13538) (xy -1.806702 -1.943608) (xy -2.345436 -1.404874)
			)
			(stroke
				(width 0)
				(type default)
			)
			(fill yes)
			(layer "F.SilkS")
		)
		(fp_line
			(start 0.674878 -1.100074)
			(end 0.674878 1.100074)
			(stroke
				(width 0.1)
				(type default)
			)
			(layer "F.Fab")
		)
		(fp_line
			(start -0.674878 -1.100074)
			(end 0.674878 -1.100074)
			(stroke
				(width 0.1)
				(type default)
			)
			(layer "F.Fab")
		)
		(fp_line
			(start 0.674878 1.100074)
			(end -0.674878 1.100074)
			(stroke
				(width 0.1)
				(type default)
			)
			(layer "F.Fab")
		)
		(fp_line
			(start -0.674878 1.100074)
			(end -0.674878 -1.100074)
			(stroke
				(width 0.1)
				(type default)
			)
			(layer "F.Fab")
		)
		(fp_poly
			(pts
				(xy -1.4605 -0.7493) (xy -2.2225 -1.1303) (xy -2.2225 -0.3683)
			)
			(stroke
				(width 0)
				(type default)
			)
			(fill yes)
			(layer "F.Fab")
		)
		(pad "1" smd rect
			(at -0.899922 -0.750062)
			(size 0.6096 0.6096)
			(layers "F.Cu" "F.Mask" "F.Paste")
			(net "GND")
		)
		(pad "2" smd rect
			(at -0.899922 0)
			(size 0.4064 0.6096)
			(layers "F.Cu" "F.Mask" "F.Paste")
			(net "FM_SYS_THROTTLE_NIC4")
		)
		(pad "3" smd rect
			(at -0.899922 0.750062)
			(size 0.6096 0.6096)
			(layers "F.Cu" "F.Mask" "F.Paste")
			(net "NIC5_PWRBRK_N")
		)
		(pad "4" smd rect
			(at 0.899922 0.750062)
			(size 0.6096 0.6096)
			(layers "F.Cu" "F.Mask" "F.Paste")
			(net "GND")
		)
		(pad "5" smd rect
			(at 0.899922 0)
			(size 0.4064 0.6096)
			(layers "F.Cu" "F.Mask" "F.Paste")
			(net "FM_SYS_THROTTLE_NIC5")
		)
		(pad "6" smd rect
			(at 0.899922 -0.750062)
			(size 0.6096 0.6096)
			(layers "F.Cu" "F.Mask" "F.Paste")
			(net "NIC4_PWRBRK_N")
		)
	)
	(footprint ""
		(layer "F.Cu")
		(at 200.691496 -114.42954)
		(property "Reference" "R186"
			(at 0 0 0)
			(layer "F.SilkS")
			(hide yes)
			(effects
				(font
					(size 1.27 1.27)
				)
			)
		)
		(property "Value" ""
			(at 0 0 0)
			(layer "F.Fab")
			(effects
				(font
					(size 1.27 1.27)
				)
			)
		)
		(duplicate_pad_numbers_are_jumpers no)
		(fp_line
			(start -0.7874 -0.4064)
			(end 0.7874 -0.4064)
			(stroke
				(width 0.1524)
				(type default)
			)
			(layer "F.SilkS")
		)
		(fp_line
			(start -0.7874 0.4064)
			(end -0.7874 -0.4064)
			(stroke
				(width 0.1524)
				(type default)
			)
			(layer "F.SilkS")
		)
		(fp_line
			(start 0.7874 -0.4064)
			(end 0.7874 0.4064)
			(stroke
				(width 0.1524)
				(type default)
			)
			(layer "F.SilkS")
		)
		(fp_line
			(start 0.7874 0.4064)
			(end -0.7874 0.4064)
			(stroke
				(width 0.1524)
				(type default)
			)
			(layer "F.SilkS")
		)
		(fp_line
			(start -0.67945 -0.305054)
			(end -0.12065 -0.305054)
			(stroke
				(width 0.1)
				(type default)
			)
			(layer "F.Fab")
		)
		(fp_line
			(start -0.67945 0.3048)
			(end -0.67945 -0.305054)
			(stroke
				(width 0.1)
				(type default)
			)
			(layer "F.Fab")
		)
		(fp_line
			(start -0.12065 -0.305054)
			(end -0.12065 -0.2794)
			(stroke
				(width 0.1)
				(type default)
			)
			(layer "F.Fab")
		)
		(fp_line
			(start -0.12065 -0.2794)
			(end 0.12065 -0.2794)
			(stroke
				(width 0.1)
				(type default)
			)
			(layer "F.Fab")
		)
		(fp_line
			(start -0.12065 0.2794)
			(end -0.12065 0.3048)
			(stroke
				(width 0.1)
				(type default)
			)
			(layer "F.Fab")
		)
		(fp_line
			(start -0.12065 0.3048)
			(end -0.67945 0.3048)
			(stroke
				(width 0.1)
				(type default)
			)
			(layer "F.Fab")
		)
		(fp_line
			(start 0.120396 0.2794)
			(end -0.12065 0.2794)
			(stroke
				(width 0.1)
				(type default)
			)
			(layer "F.Fab")
		)
		(fp_line
			(start 0.120396 0.3048)
			(end 0.120396 0.2794)
			(stroke
				(width 0.1)
				(type default)
			)
			(layer "F.Fab")
		)
		(fp_line
			(start 0.12065 -0.3048)
			(end 0.67945 -0.3048)
			(stroke
				(width 0.1)
				(type default)
			)
			(layer "F.Fab")
		)
		(fp_line
			(start 0.12065 -0.2794)
			(end 0.12065 -0.3048)
			(stroke
				(width 0.1)
				(type default)
			)
			(layer "F.Fab")
		)
		(fp_line
			(start 0.67945 -0.3048)
			(end 0.67945 0.3048)
			(stroke
				(width 0.1)
				(type default)
			)
			(layer "F.Fab")
		)
		(fp_line
			(start 0.67945 0.3048)
			(end 0.120396 0.3048)
			(stroke
				(width 0.1)
				(type default)
			)
			(layer "F.Fab")
		)
		(pad "1" smd circle
			(at -0.40005 0)
			(size 0 0)
			(layers "F.Cu" "F.Mask" "F.Paste")
			(net "NIC3_BIF2_N")
		)
		(pad "2" smd circle
			(at 0.40005 0)
			(size 0 0)
			(layers "F.Cu" "F.Mask" "F.Paste")
			(net "P3V3_AUX")
		)
	)
	(footprint ""
		(layer "F.Cu")
		(at 128.966214 -214.540846)
		(property "Reference" "C2609"
			(at 0 0 0)
			(layer "F.SilkS")
			(hide yes)
			(effects
				(font
					(size 1.27 1.27)
				)
			)
		)
		(property "Value" ""
			(at 0 0 0)
			(layer "F.Fab")
			(effects
				(font
					(size 1.27 1.27)
				)
			)
		)
		(duplicate_pad_numbers_are_jumpers no)
		(fp_line
			(start -0.7874 -0.4064)
			(end 0.7874 -0.4064)
			(stroke
				(width 0.1524)
				(type default)
			)
			(layer "F.SilkS")
		)
		(fp_line
			(start -0.7874 0.4064)
			(end -0.7874 -0.4064)
			(stroke
				(width 0.1524)
				(type default)
			)
			(layer "F.SilkS")
		)
		(fp_line
			(start 0.7874 -0.4064)
			(end 0.7874 0.4064)
			(stroke
				(width 0.1524)
				(type default)
			)
			(layer "F.SilkS")
		)
		(fp_line
			(start 0.7874 0.4064)
			(end -0.7874 0.4064)
			(stroke
				(width 0.1524)
				(type default)
			)
			(layer "F.SilkS")
		)
		(fp_line
			(start -0.67945 -0.305054)
			(end -0.12065 -0.305054)
			(stroke
				(width 0.1)
				(type default)
			)
			(layer "F.Fab")
		)
		(fp_line
			(start -0.67945 0.3048)
			(end -0.67945 -0.305054)
			(stroke
				(width 0.1)
				(type default)
			)
			(layer "F.Fab")
		)
		(fp_line
			(start -0.12065 -0.305054)
			(end -0.12065 -0.2794)
			(stroke
				(width 0.1)
				(type default)
			)
			(layer "F.Fab")
		)
		(fp_line
			(start -0.12065 -0.2794)
			(end 0.12065 -0.2794)
			(stroke
				(width 0.1)
				(type default)
			)
			(layer "F.Fab")
		)
		(fp_line
			(start -0.12065 0.2794)
			(end -0.12065 0.3048)
			(stroke
				(width 0.1)
				(type default)
			)
			(layer "F.Fab")
		)
		(fp_line
			(start -0.12065 0.3048)
			(end -0.67945 0.3048)
			(stroke
				(width 0.1)
				(type default)
			)
			(layer "F.Fab")
		)
		(fp_line
			(start 0.120396 0.2794)
			(end -0.12065 0.2794)
			(stroke
				(width 0.1)
				(type default)
			)
			(layer "F.Fab")
		)
		(fp_line
			(start 0.120396 0.3048)
			(end 0.120396 0.2794)
			(stroke
				(width 0.1)
				(type default)
			)
			(layer "F.Fab")
		)
		(fp_line
			(start 0.12065 -0.3048)
			(end 0.67945 -0.3048)
			(stroke
				(width 0.1)
				(type default)
			)
			(layer "F.Fab")
		)
		(fp_line
			(start 0.12065 -0.2794)
			(end 0.12065 -0.3048)
			(stroke
				(width 0.1)
				(type default)
			)
			(layer "F.Fab")
		)
		(fp_line
			(start 0.67945 -0.3048)
			(end 0.67945 0.3048)
			(stroke
				(width 0.1)
				(type default)
			)
			(layer "F.Fab")
		)
		(fp_line
			(start 0.67945 0.3048)
			(end 0.120396 0.3048)
			(stroke
				(width 0.1)
				(type default)
			)
			(layer "F.Fab")
		)
		(pad "1" smd circle
			(at -0.40005 0)
			(size 0 0)
			(layers "F.Cu" "F.Mask" "F.Paste")
			(net "GND")
		)
		(pad "2" smd circle
			(at 0.40005 0)
			(size 0 0)
			(layers "F.Cu" "F.Mask" "F.Paste")
			(net "P1V8_PEX")
		)
	)
	(footprint ""
		(layer "F.Cu")
		(at 67.987926 -45.704252 90)
		(property "Reference" "R527"
			(at 0 0 90)
			(layer "F.SilkS")
			(hide yes)
			(effects
				(font
					(size 1.27 1.27)
				)
			)
		)
		(property "Value" ""
			(at 0 0 90)
			(layer "F.Fab")
			(effects
				(font
					(size 1.27 1.27)
				)
			)
		)
		(duplicate_pad_numbers_are_jumpers no)
		(fp_line
			(start 3.937508 -1.8796)
			(end -3.937508 -1.8796)
			(stroke
				(width 0.1524)
				(type default)
			)
			(layer "F.SilkS")
		)
		(fp_line
			(start -3.937508 -1.8796)
			(end -3.937508 1.8796)
			(stroke
				(width 0.1524)
				(type default)
			)
			(layer "F.SilkS")
		)
		(fp_line
			(start 3.937508 1.8796)
			(end 3.937508 -1.8796)
			(stroke
				(width 0.1524)
				(type default)
			)
			(layer "F.SilkS")
		)
		(fp_line
			(start -3.937508 1.8796)
			(end 3.937508 1.8796)
			(stroke
				(width 0.1524)
				(type default)
			)
			(layer "F.SilkS")
		)
		(fp_line
			(start 3.275076 -1.674876)
			(end -3.275076 -1.674876)
			(stroke
				(width 0.1)
				(type default)
			)
			(layer "F.Fab")
		)
		(fp_line
			(start -3.275076 -1.674876)
			(end -3.275076 1.674876)
			(stroke
				(width 0.1)
				(type default)
			)
			(layer "F.Fab")
		)
		(fp_line
			(start 3.275076 1.674876)
			(end 3.275076 -1.674876)
			(stroke
				(width 0.1)
				(type default)
			)
			(layer "F.Fab")
		)
		(fp_line
			(start -3.275076 1.674876)
			(end 3.275076 1.674876)
			(stroke
				(width 0.1)
				(type default)
			)
			(layer "F.Fab")
		)
		(pad "1" smd rect
			(at -2.350008 0 90)
			(size 2.921 3.5052)
			(layers "F.Cu" "F.Mask" "F.Paste")
			(net "P12V_SSD2")
		)
		(pad "2" smd rect
			(at 2.350008 0 90)
			(size 2.921 3.5052)
			(layers "F.Cu" "F.Mask" "F.Paste")
			(net "P12V_SSD2_R")
		)
	)
	(footprint ""
		(layer "F.Cu")
		(at 75.66787 -18.437098)
		(property "Reference" "R1651"
			(at 0 0 0)
			(layer "F.SilkS")
			(hide yes)
			(effects
				(font
					(size 1.27 1.27)
				)
			)
		)
		(property "Value" ""
			(at 0 0 0)
			(layer "F.Fab")
			(effects
				(font
					(size 1.27 1.27)
				)
			)
		)
		(duplicate_pad_numbers_are_jumpers no)
		(fp_line
			(start -0.7874 -0.4064)
			(end 0.7874 -0.4064)
			(stroke
				(width 0.1524)
				(type default)
			)
			(layer "F.SilkS")
		)
		(fp_line
			(start -0.7874 0.4064)
			(end -0.7874 -0.4064)
			(stroke
				(width 0.1524)
				(type default)
			)
			(layer "F.SilkS")
		)
		(fp_line
			(start 0.7874 -0.4064)
			(end 0.7874 0.4064)
			(stroke
				(width 0.1524)
				(type default)
			)
			(layer "F.SilkS")
		)
		(fp_line
			(start 0.7874 0.4064)
			(end -0.7874 0.4064)
			(stroke
				(width 0.1524)
				(type default)
			)
			(layer "F.SilkS")
		)
		(fp_line
			(start -0.67945 -0.305054)
			(end -0.12065 -0.305054)
			(stroke
				(width 0.1)
				(type default)
			)
			(layer "F.Fab")
		)
		(fp_line
			(start -0.67945 0.3048)
			(end -0.67945 -0.305054)
			(stroke
				(width 0.1)
				(type default)
			)
			(layer "F.Fab")
		)
		(fp_line
			(start -0.12065 -0.305054)
			(end -0.12065 -0.2794)
			(stroke
				(width 0.1)
				(type default)
			)
			(layer "F.Fab")
		)
		(fp_line
			(start -0.12065 -0.2794)
			(end 0.12065 -0.2794)
			(stroke
				(width 0.1)
				(type default)
			)
			(layer "F.Fab")
		)
		(fp_line
			(start -0.12065 0.2794)
			(end -0.12065 0.3048)
			(stroke
				(width 0.1)
				(type default)
			)
			(layer "F.Fab")
		)
		(fp_line
			(start -0.12065 0.3048)
			(end -0.67945 0.3048)
			(stroke
				(width 0.1)
				(type default)
			)
			(layer "F.Fab")
		)
		(fp_line
			(start 0.120396 0.2794)
			(end -0.12065 0.2794)
			(stroke
				(width 0.1)
				(type default)
			)
			(layer "F.Fab")
		)
		(fp_line
			(start 0.120396 0.3048)
			(end 0.120396 0.2794)
			(stroke
				(width 0.1)
				(type default)
			)
			(layer "F.Fab")
		)
		(fp_line
			(start 0.12065 -0.3048)
			(end 0.67945 -0.3048)
			(stroke
				(width 0.1)
				(type default)
			)
			(layer "F.Fab")
		)
		(fp_line
			(start 0.12065 -0.2794)
			(end 0.12065 -0.3048)
			(stroke
				(width 0.1)
				(type default)
			)
			(layer "F.Fab")
		)
		(fp_line
			(start 0.67945 -0.3048)
			(end 0.67945 0.3048)
			(stroke
				(width 0.1)
				(type default)
			)
			(layer "F.Fab")
		)
		(fp_line
			(start 0.67945 0.3048)
			(end 0.120396 0.3048)
			(stroke
				(width 0.1)
				(type default)
			)
			(layer "F.Fab")
		)
		(pad "1" smd circle
			(at -0.40005 0)
			(size 0 0)
			(layers "F.Cu" "F.Mask" "F.Paste")
			(net "SMB_ISO_SSD2_R_SCL")
		)
		(pad "2" smd circle
			(at 0.40005 0)
			(size 0 0)
			(layers "F.Cu" "F.Mask" "F.Paste")
			(net "SMB_ISO_SSD2_SCL")
		)
	)
	(footprint ""
		(layer "F.Cu")
		(at 240.24971 -158.828994 180)
		(property "Reference" "R5966"
			(at 0 0 180)
			(layer "F.SilkS")
			(hide yes)
			(effects
				(font
					(size 1.27 1.27)
				)
			)
		)
		(property "Value" ""
			(at 0 0 180)
			(layer "F.Fab")
			(effects
				(font
					(size 1.27 1.27)
				)
			)
		)
		(duplicate_pad_numbers_are_jumpers no)
		(fp_line
			(start 0.7874 0.4064)
			(end -0.7874 0.4064)
			(stroke
				(width 0.1524)
				(type default)
			)
			(layer "F.SilkS")
		)
		(fp_line
			(start 0.7874 -0.4064)
			(end 0.7874 0.4064)
			(stroke
				(width 0.1524)
				(type default)
			)
			(layer "F.SilkS")
		)
		(fp_line
			(start -0.7874 0.4064)
			(end -0.7874 -0.4064)
			(stroke
				(width 0.1524)
				(type default)
			)
			(layer "F.SilkS")
		)
		(fp_line
			(start -0.7874 -0.4064)
			(end 0.7874 -0.4064)
			(stroke
				(width 0.1524)
				(type default)
			)
			(layer "F.SilkS")
		)
		(fp_line
			(start 0.67945 0.3048)
			(end 0.120396 0.3048)
			(stroke
				(width 0.1)
				(type default)
			)
			(layer "F.Fab")
		)
		(fp_line
			(start 0.67945 -0.3048)
			(end 0.67945 0.3048)
			(stroke
				(width 0.1)
				(type default)
			)
			(layer "F.Fab")
		)
		(fp_line
			(start 0.12065 -0.2794)
			(end 0.12065 -0.3048)
			(stroke
				(width 0.1)
				(type default)
			)
			(layer "F.Fab")
		)
		(fp_line
			(start 0.12065 -0.3048)
			(end 0.67945 -0.3048)
			(stroke
				(width 0.1)
				(type default)
			)
			(layer "F.Fab")
		)
		(fp_line
			(start 0.120396 0.3048)
			(end 0.120396 0.2794)
			(stroke
				(width 0.1)
				(type default)
			)
			(layer "F.Fab")
		)
		(fp_line
			(start 0.120396 0.2794)
			(end -0.12065 0.2794)
			(stroke
				(width 0.1)
				(type default)
			)
			(layer "F.Fab")
		)
		(fp_line
			(start -0.12065 0.3048)
			(end -0.67945 0.3048)
			(stroke
				(width 0.1)
				(type default)
			)
			(layer "F.Fab")
		)
		(fp_line
			(start -0.12065 0.2794)
			(end -0.12065 0.3048)
			(stroke
				(width 0.1)
				(type default)
			)
			(layer "F.Fab")
		)
		(fp_line
			(start -0.12065 -0.2794)
			(end 0.12065 -0.2794)
			(stroke
				(width 0.1)
				(type default)
			)
			(layer "F.Fab")
		)
		(fp_line
			(start -0.12065 -0.305054)
			(end -0.12065 -0.2794)
			(stroke
				(width 0.1)
				(type default)
			)
			(layer "F.Fab")
		)
		(fp_line
			(start -0.67945 0.3048)
			(end -0.67945 -0.305054)
			(stroke
				(width 0.1)
				(type default)
			)
			(layer "F.Fab")
		)
		(fp_line
			(start -0.67945 -0.305054)
			(end -0.12065 -0.305054)
			(stroke
				(width 0.1)
				(type default)
			)
			(layer "F.Fab")
		)
		(pad "1" smd circle
			(at -0.40005 0 180)
			(size 0 0)
			(layers "F.Cu" "F.Mask" "F.Paste")
			(net "PWRGD_P12V_NIC4_CO")
		)
		(pad "2" smd circle
			(at 0.40005 0 180)
			(size 0 0)
			(layers "F.Cu" "F.Mask" "F.Paste")
			(net "PWRGD_P12V_NIC4_R")
		)
	)
	(footprint ""
		(layer "F.Cu")
		(at 423.120566 -70.307454 90)
		(property "Reference" "PC878"
			(at 0 0 90)
			(layer "F.SilkS")
			(hide yes)
			(effects
				(font
					(size 1.27 1.27)
				)
			)
		)
		(property "Value" ""
			(at 0 0 90)
			(layer "F.Fab")
			(effects
				(font
					(size 1.27 1.27)
				)
			)
		)
		(duplicate_pad_numbers_are_jumpers no)
		(fp_line
			(start 0.7874 -0.4064)
			(end 0.7874 0.4064)
			(stroke
				(width 0.1524)
				(type default)
			)
			(layer "F.SilkS")
		)
		(fp_line
			(start -0.7874 -0.4064)
			(end 0.7874 -0.4064)
			(stroke
				(width 0.1524)
				(type default)
			)
			(layer "F.SilkS")
		)
		(fp_line
			(start 0.7874 0.4064)
			(end -0.7874 0.4064)
			(stroke
				(width 0.1524)
				(type default)
			)
			(layer "F.SilkS")
		)
		(fp_line
			(start -0.7874 0.4064)
			(end -0.7874 -0.4064)
			(stroke
				(width 0.1524)
				(type default)
			)
			(layer "F.SilkS")
		)
		(fp_line
			(start -0.12065 -0.305054)
			(end -0.12065 -0.2794)
			(stroke
				(width 0.1)
				(type default)
			)
			(layer "F.Fab")
		)
		(fp_line
			(start -0.67945 -0.305054)
			(end -0.12065 -0.305054)
			(stroke
				(width 0.1)
				(type default)
			)
			(layer "F.Fab")
		)
		(fp_line
			(start 0.67945 -0.3048)
			(end 0.67945 0.3048)
			(stroke
				(width 0.1)
				(type default)
			)
			(layer "F.Fab")
		)
		(fp_line
			(start 0.12065 -0.3048)
			(end 0.67945 -0.3048)
			(stroke
				(width 0.1)
				(type default)
			)
			(layer "F.Fab")
		)
		(fp_line
			(start 0.12065 -0.2794)
			(end 0.12065 -0.3048)
			(stroke
				(width 0.1)
				(type default)
			)
			(layer "F.Fab")
		)
		(fp_line
			(start -0.12065 -0.2794)
			(end 0.12065 -0.2794)
			(stroke
				(width 0.1)
				(type default)
			)
			(layer "F.Fab")
		)
		(fp_line
			(start 0.120396 0.2794)
			(end -0.12065 0.2794)
			(stroke
				(width 0.1)
				(type default)
			)
			(layer "F.Fab")
		)
		(fp_line
			(start -0.12065 0.2794)
			(end -0.12065 0.3048)
			(stroke
				(width 0.1)
				(type default)
			)
			(layer "F.Fab")
		)
		(fp_line
			(start 0.67945 0.3048)
			(end 0.120396 0.3048)
			(stroke
				(width 0.1)
				(type default)
			)
			(layer "F.Fab")
		)
		(fp_line
			(start 0.120396 0.3048)
			(end 0.120396 0.2794)
			(stroke
				(width 0.1)
				(type default)
			)
			(layer "F.Fab")
		)
		(fp_line
			(start -0.12065 0.3048)
			(end -0.67945 0.3048)
			(stroke
				(width 0.1)
				(type default)
			)
			(layer "F.Fab")
		)
		(fp_line
			(start -0.67945 0.3048)
			(end -0.67945 -0.305054)
			(stroke
				(width 0.1)
				(type default)
			)
			(layer "F.Fab")
		)
		(pad "1" smd circle
			(at -0.40005 0 90)
			(size 0 0)
			(layers "F.Cu" "F.Mask" "F.Paste")
			(net "P12V_AUX")
		)
		(pad "2" smd circle
			(at 0.40005 0 90)
			(size 0 0)
			(layers "F.Cu" "F.Mask" "F.Paste")
			(net "GND")
		)
	)
	(footprint ""
		(layer "F.Cu")
		(at 72.273922 -72.766682 90)
		(property "Reference" "PR6909"
			(at 0 0 90)
			(layer "F.SilkS")
			(hide yes)
			(effects
				(font
					(size 1.27 1.27)
				)
			)
		)
		(property "Value" ""
			(at 0 0 90)
			(layer "F.Fab")
			(effects
				(font
					(size 1.27 1.27)
				)
			)
		)
		(duplicate_pad_numbers_are_jumpers no)
		(fp_line
			(start 0.7874 -0.4064)
			(end 0.7874 0.4064)
			(stroke
				(width 0.1524)
				(type default)
			)
			(layer "F.SilkS")
		)
		(fp_line
			(start -0.7874 -0.4064)
			(end 0.7874 -0.4064)
			(stroke
				(width 0.1524)
				(type default)
			)
			(layer "F.SilkS")
		)
		(fp_line
			(start 0.7874 0.4064)
			(end -0.7874 0.4064)
			(stroke
				(width 0.1524)
				(type default)
			)
			(layer "F.SilkS")
		)
		(fp_line
			(start -0.7874 0.4064)
			(end -0.7874 -0.4064)
			(stroke
				(width 0.1524)
				(type default)
			)
			(layer "F.SilkS")
		)
		(fp_line
			(start -0.12065 -0.305054)
			(end -0.12065 -0.2794)
			(stroke
				(width 0.1)
				(type default)
			)
			(layer "F.Fab")
		)
		(fp_line
			(start -0.67945 -0.305054)
			(end -0.12065 -0.305054)
			(stroke
				(width 0.1)
				(type default)
			)
			(layer "F.Fab")
		)
		(fp_line
			(start 0.67945 -0.3048)
			(end 0.67945 0.3048)
			(stroke
				(width 0.1)
				(type default)
			)
			(layer "F.Fab")
		)
		(fp_line
			(start 0.12065 -0.3048)
			(end 0.67945 -0.3048)
			(stroke
				(width 0.1)
				(type default)
			)
			(layer "F.Fab")
		)
		(fp_line
			(start 0.12065 -0.2794)
			(end 0.12065 -0.3048)
			(stroke
				(width 0.1)
				(type default)
			)
			(layer "F.Fab")
		)
		(fp_line
			(start -0.12065 -0.2794)
			(end 0.12065 -0.2794)
			(stroke
				(width 0.1)
				(type default)
			)
			(layer "F.Fab")
		)
		(fp_line
			(start 0.120396 0.2794)
			(end -0.12065 0.2794)
			(stroke
				(width 0.1)
				(type default)
			)
			(layer "F.Fab")
		)
		(fp_line
			(start -0.12065 0.2794)
			(end -0.12065 0.3048)
			(stroke
				(width 0.1)
				(type default)
			)
			(layer "F.Fab")
		)
		(fp_line
			(start 0.67945 0.3048)
			(end 0.120396 0.3048)
			(stroke
				(width 0.1)
				(type default)
			)
			(layer "F.Fab")
		)
		(fp_line
			(start 0.120396 0.3048)
			(end 0.120396 0.2794)
			(stroke
				(width 0.1)
				(type default)
			)
			(layer "F.Fab")
		)
		(fp_line
			(start -0.12065 0.3048)
			(end -0.67945 0.3048)
			(stroke
				(width 0.1)
				(type default)
			)
			(layer "F.Fab")
		)
		(fp_line
			(start -0.67945 0.3048)
			(end -0.67945 -0.305054)
			(stroke
				(width 0.1)
				(type default)
			)
			(layer "F.Fab")
		)
		(pad "1" smd circle
			(at -0.40005 0 90)
			(size 0 0)
			(layers "F.Cu" "F.Mask" "F.Paste")
			(net "P12V_SSD2_CO_MODE")
		)
		(pad "2" smd circle
			(at 0.40005 0 90)
			(size 0 0)
			(layers "F.Cu" "F.Mask" "F.Paste")
			(net "GND")
		)
	)
	(footprint ""
		(layer "F.Cu")
		(at 296.54119 -210.094068 -90)
		(property "Reference" "R3367"
			(at 0 0 270)
			(layer "F.SilkS")
			(hide yes)
			(effects
				(font
					(size 1.27 1.27)
				)
			)
		)
		(property "Value" ""
			(at 0 0 270)
			(layer "F.Fab")
			(effects
				(font
					(size 1.27 1.27)
				)
			)
		)
		(duplicate_pad_numbers_are_jumpers no)
		(fp_line
			(start -0.7874 0.4064)
			(end -0.7874 -0.4064)
			(stroke
				(width 0.1524)
				(type default)
			)
			(layer "F.SilkS")
		)
		(fp_line
			(start 0.7874 0.4064)
			(end -0.7874 0.4064)
			(stroke
				(width 0.1524)
				(type default)
			)
			(layer "F.SilkS")
		)
		(fp_line
			(start -0.7874 -0.4064)
			(end 0.7874 -0.4064)
			(stroke
				(width 0.1524)
				(type default)
			)
			(layer "F.SilkS")
		)
		(fp_line
			(start 0.7874 -0.4064)
			(end 0.7874 0.4064)
			(stroke
				(width 0.1524)
				(type default)
			)
			(layer "F.SilkS")
		)
		(fp_line
			(start -0.67945 0.3048)
			(end -0.67945 -0.305054)
			(stroke
				(width 0.1)
				(type default)
			)
			(layer "F.Fab")
		)
		(fp_line
			(start -0.12065 0.3048)
			(end -0.67945 0.3048)
			(stroke
				(width 0.1)
				(type default)
			)
			(layer "F.Fab")
		)
		(fp_line
			(start 0.120396 0.3048)
			(end 0.120396 0.2794)
			(stroke
				(width 0.1)
				(type default)
			)
			(layer "F.Fab")
		)
		(fp_line
			(start 0.67945 0.3048)
			(end 0.120396 0.3048)
			(stroke
				(width 0.1)
				(type default)
			)
			(layer "F.Fab")
		)
		(fp_line
			(start -0.12065 0.2794)
			(end -0.12065 0.3048)
			(stroke
				(width 0.1)
				(type default)
			)
			(layer "F.Fab")
		)
		(fp_line
			(start 0.120396 0.2794)
			(end -0.12065 0.2794)
			(stroke
				(width 0.1)
				(type default)
			)
			(layer "F.Fab")
		)
		(fp_line
			(start -0.12065 -0.2794)
			(end 0.12065 -0.2794)
			(stroke
				(width 0.1)
				(type default)
			)
			(layer "F.Fab")
		)
		(fp_line
			(start 0.12065 -0.2794)
			(end 0.12065 -0.3048)
			(stroke
				(width 0.1)
				(type default)
			)
			(layer "F.Fab")
		)
		(fp_line
			(start 0.12065 -0.3048)
			(end 0.67945 -0.3048)
			(stroke
				(width 0.1)
				(type default)
			)
			(layer "F.Fab")
		)
		(fp_line
			(start 0.67945 -0.3048)
			(end 0.67945 0.3048)
			(stroke
				(width 0.1)
				(type default)
			)
			(layer "F.Fab")
		)
		(fp_line
			(start -0.67945 -0.305054)
			(end -0.12065 -0.305054)
			(stroke
				(width 0.1)
				(type default)
			)
			(layer "F.Fab")
		)
		(fp_line
			(start -0.12065 -0.305054)
			(end -0.12065 -0.2794)
			(stroke
				(width 0.1)
				(type default)
			)
			(layer "F.Fab")
		)
		(pad "1" smd circle
			(at -0.40005 0 270)
			(size 0 0)
			(layers "F.Cu" "F.Mask" "F.Paste")
			(net "SPI_BIC1_MOSI_LS23_R")
		)
		(pad "2" smd circle
			(at 0.40005 0 270)
			(size 0 0)
			(layers "F.Cu" "F.Mask" "F.Paste")
			(net "SPI_BIC1_MOSI_LS23")
		)
	)
	(footprint ""
		(layer "F.Cu")
		(at 261.468362 -349.746824)
		(property "Reference" "U437"
			(at 0.670814 -2.57175 0)
			(unlocked yes)
			(layer "F.SilkS")
			(effects
				(font
					(size 0.7874 0.5842)
					(thickness 0.1524)
				)
				(justify left)
			)
		)
		(property "Value" ""
			(at 0 0 0)
			(layer "F.Fab")
			(effects
				(font
					(size 1.27 1.27)
				)
			)
		)
		(duplicate_pad_numbers_are_jumpers no)
		(fp_line
			(start -1.603248 -1.500124)
			(end 1.603248 -1.500124)
			(stroke
				(width 0.1524)
				(type default)
			)
			(layer "F.SilkS")
		)
		(fp_line
			(start -1.603248 1.500124)
			(end -1.603248 -1.500124)
			(stroke
				(width 0.1524)
				(type default)
			)
			(layer "F.SilkS")
		)
		(fp_line
			(start 1.603248 -1.500124)
			(end 1.603248 1.500124)
			(stroke
				(width 0.1524)
				(type default)
			)
			(layer "F.SilkS")
		)
		(fp_line
			(start 1.603248 1.500124)
			(end -1.603248 1.500124)
			(stroke
				(width 0.1524)
				(type default)
			)
			(layer "F.SilkS")
		)
		(fp_line
			(start -1.249934 -1.169924)
			(end -1.249934 -0.729996)
			(stroke
				(width 0.1)
				(type default)
			)
			(layer "F.Fab")
		)
		(fp_line
			(start -1.249934 -0.729996)
			(end -0.6985 -0.729996)
			(stroke
				(width 0.1)
				(type default)
			)
			(layer "F.Fab")
		)
		(fp_line
			(start -1.249934 0.729996)
			(end -1.249934 1.169924)
			(stroke
				(width 0.1)
				(type default)
			)
			(layer "F.Fab")
		)
		(fp_line
			(start -1.249934 1.169924)
			(end -0.700024 1.169924)
			(stroke
				(width 0.1)
				(type default)
			)
			(layer "F.Fab")
		)
		(fp_line
			(start -0.700024 -1.500124)
			(end -0.700024 -1.169924)
			(stroke
				(width 0.1)
				(type default)
			)
			(layer "F.Fab")
		)
		(fp_line
			(start -0.700024 -1.169924)
			(end -1.249934 -1.169924)
			(stroke
				(width 0.1)
				(type default)
			)
			(layer "F.Fab")
		)
		(fp_line
			(start -0.700024 1.169924)
			(end -0.700024 1.500124)
			(stroke
				(width 0.1)
				(type default)
			)
			(layer "F.Fab")
		)
		(fp_line
			(start -0.700024 1.500124)
			(end 0.700024 1.500124)
			(stroke
				(width 0.1)
				(type default)
			)
			(layer "F.Fab")
		)
		(fp_line
			(start -0.6985 -0.729996)
			(end -0.6985 0.729996)
			(stroke
				(width 0.1)
				(type default)
			)
			(layer "F.Fab")
		)
		(fp_line
			(start -0.6985 0.729996)
			(end -1.249934 0.729996)
			(stroke
				(width 0.1)
				(type default)
			)
			(layer "F.Fab")
		)
		(fp_line
			(start 0.700024 -1.500124)
			(end -0.700024 -1.500124)
			(stroke
				(width 0.1)
				(type default)
			)
			(layer "F.Fab")
		)
		(fp_line
			(start 0.700024 -0.219964)
			(end 0.700024 -1.500124)
			(stroke
				(width 0.1)
				(type default)
			)
			(layer "F.Fab")
		)
		(fp_line
			(start 0.700024 0.219964)
			(end 1.249934 0.219964)
			(stroke
				(width 0.1)
				(type default)
			)
			(layer "F.Fab")
		)
		(fp_line
			(start 0.700024 1.500124)
			(end 0.700024 0.219964)
			(stroke
				(width 0.1)
				(type default)
			)
			(layer "F.Fab")
		)
		(fp_line
			(start 1.249934 -0.219964)
			(end 0.700024 -0.219964)
			(stroke
				(width 0.1)
				(type default)
			)
			(layer "F.Fab")
		)
		(fp_line
			(start 1.249934 0.219964)
			(end 1.249934 -0.219964)
			(stroke
				(width 0.1)
				(type default)
			)
			(layer "F.Fab")
		)
		(fp_rect
			(start -0.700024 1.500124)
			(end 0.700024 -1.500124)
			(stroke
				(width 0)
				(type default)
			)
			(fill no)
			(layer "F.Fab")
		)
		(pad "D" smd rect
			(at 0.999998 0 270)
			(size 0.8128 0.9144)
			(layers "F.Cu" "F.Mask" "F.Paste")
			(net "A_HSC_LOW_DRAIN")
		)
		(pad "G" smd rect
			(at -0.999998 -0.94996 270)
			(size 0.8128 0.9144)
			(layers "F.Cu" "F.Mask" "F.Paste")
			(net "A_HSC_LOW_GATE")
		)
		(pad "S" smd rect
			(at -0.999998 0.94996 270)
			(size 0.8128 0.9144)
			(layers "F.Cu" "F.Mask" "F.Paste")
			(net "GND")
		)
	)
	(footprint ""
		(layer "F.Cu")
		(at 80.915002 -343.952322 90)
		(property "Reference" "C146"
			(at 0 0 90)
			(layer "F.SilkS")
			(hide yes)
			(effects
				(font
					(size 1.27 1.27)
				)
			)
		)
		(property "Value" ""
			(at 0 0 90)
			(layer "F.Fab")
			(effects
				(font
					(size 1.27 1.27)
				)
			)
		)
		(duplicate_pad_numbers_are_jumpers no)
		(fp_line
			(start 0.299974 -0.150114)
			(end 0.299974 0.150114)
			(stroke
				(width 0.1)
				(type default)
			)
			(layer "F.Fab")
		)
		(fp_line
			(start -0.299974 -0.150114)
			(end 0.299974 -0.150114)
			(stroke
				(width 0.1)
				(type default)
			)
			(layer "F.Fab")
		)
		(fp_line
			(start 0.299974 0.150114)
			(end -0.299974 0.150114)
			(stroke
				(width 0.1)
				(type default)
			)
			(layer "F.Fab")
		)
		(fp_line
			(start -0.299974 0.150114)
			(end -0.299974 -0.150114)
			(stroke
				(width 0.1)
				(type default)
			)
			(layer "F.Fab")
		)
		(pad "1" smd rect
			(at -0.2667 0 90)
			(size 0.3048 0.381)
			(layers "F.Cu" "F.Mask" "F.Paste")
			(net "P5E_PEX0_STN6_TX_DN<103>")
		)
		(pad "2" smd rect
			(at 0.2667 0 90)
			(size 0.3048 0.381)
			(layers "F.Cu" "F.Mask" "F.Paste")
			(net "P5E_PEX0_STN6_TX_C_DN<103>")
		)
	)
	(footprint ""
		(layer "F.Cu")
		(at 89.498424 -297.46448)
		(property "Reference" "R3873"
			(at 0 0 0)
			(layer "F.SilkS")
			(hide yes)
			(effects
				(font
					(size 1.27 1.27)
				)
			)
		)
		(property "Value" ""
			(at 0 0 0)
			(layer "F.Fab")
			(effects
				(font
					(size 1.27 1.27)
				)
			)
		)
		(duplicate_pad_numbers_are_jumpers no)
		(fp_line
			(start -0.7874 -0.4064)
			(end 0.7874 -0.4064)
			(stroke
				(width 0.1524)
				(type default)
			)
			(layer "F.SilkS")
		)
		(fp_line
			(start -0.7874 0.4064)
			(end -0.7874 -0.4064)
			(stroke
				(width 0.1524)
				(type default)
			)
			(layer "F.SilkS")
		)
		(fp_line
			(start 0.7874 -0.4064)
			(end 0.7874 0.4064)
			(stroke
				(width 0.1524)
				(type default)
			)
			(layer "F.SilkS")
		)
		(fp_line
			(start 0.7874 0.4064)
			(end -0.7874 0.4064)
			(stroke
				(width 0.1524)
				(type default)
			)
			(layer "F.SilkS")
		)
		(fp_line
			(start -0.67945 -0.305054)
			(end -0.12065 -0.305054)
			(stroke
				(width 0.1)
				(type default)
			)
			(layer "F.Fab")
		)
		(fp_line
			(start -0.67945 0.3048)
			(end -0.67945 -0.305054)
			(stroke
				(width 0.1)
				(type default)
			)
			(layer "F.Fab")
		)
		(fp_line
			(start -0.12065 -0.305054)
			(end -0.12065 -0.2794)
			(stroke
				(width 0.1)
				(type default)
			)
			(layer "F.Fab")
		)
		(fp_line
			(start -0.12065 -0.2794)
			(end 0.12065 -0.2794)
			(stroke
				(width 0.1)
				(type default)
			)
			(layer "F.Fab")
		)
		(fp_line
			(start -0.12065 0.2794)
			(end -0.12065 0.3048)
			(stroke
				(width 0.1)
				(type default)
			)
			(layer "F.Fab")
		)
		(fp_line
			(start -0.12065 0.3048)
			(end -0.67945 0.3048)
			(stroke
				(width 0.1)
				(type default)
			)
			(layer "F.Fab")
		)
		(fp_line
			(start 0.120396 0.2794)
			(end -0.12065 0.2794)
			(stroke
				(width 0.1)
				(type default)
			)
			(layer "F.Fab")
		)
		(fp_line
			(start 0.120396 0.3048)
			(end 0.120396 0.2794)
			(stroke
				(width 0.1)
				(type default)
			)
			(layer "F.Fab")
		)
		(fp_line
			(start 0.12065 -0.3048)
			(end 0.67945 -0.3048)
			(stroke
				(width 0.1)
				(type default)
			)
			(layer "F.Fab")
		)
		(fp_line
			(start 0.12065 -0.2794)
			(end 0.12065 -0.3048)
			(stroke
				(width 0.1)
				(type default)
			)
			(layer "F.Fab")
		)
		(fp_line
			(start 0.67945 -0.3048)
			(end 0.67945 0.3048)
			(stroke
				(width 0.1)
				(type default)
			)
			(layer "F.Fab")
		)
		(fp_line
			(start 0.67945 0.3048)
			(end 0.120396 0.3048)
			(stroke
				(width 0.1)
				(type default)
			)
			(layer "F.Fab")
		)
		(pad "1" smd circle
			(at -0.40005 0)
			(size 0 0)
			(layers "F.Cu" "F.Mask" "F.Paste")
			(net "SMB_PEX0_HOST_LS_SDA")
		)
		(pad "2" smd circle
			(at 0.40005 0)
			(size 0 0)
			(layers "F.Cu" "F.Mask" "F.Paste")
			(net "I2C_PEX0_HOST_R_SDA")
		)
	)
	(footprint ""
		(layer "F.Cu")
		(at 33.287716 -282.018232)
		(property "Reference" "C3067"
			(at 0 0 0)
			(layer "F.SilkS")
			(hide yes)
			(effects
				(font
					(size 1.27 1.27)
				)
			)
		)
		(property "Value" ""
			(at 0 0 0)
			(layer "F.Fab")
			(effects
				(font
					(size 1.27 1.27)
				)
			)
		)
		(duplicate_pad_numbers_are_jumpers no)
		(fp_line
			(start -1.2954 -0.5842)
			(end 1.2954 -0.5842)
			(stroke
				(width 0.1524)
				(type default)
			)
			(layer "F.SilkS")
		)
		(fp_line
			(start -1.2954 0.5842)
			(end -1.2954 -0.5842)
			(stroke
				(width 0.1524)
				(type default)
			)
			(layer "F.SilkS")
		)
		(fp_line
			(start 1.2954 -0.5842)
			(end 1.2954 0.5842)
			(stroke
				(width 0.1524)
				(type default)
			)
			(layer "F.SilkS")
		)
		(fp_line
			(start 1.2954 0.5842)
			(end -1.2954 0.5842)
			(stroke
				(width 0.1524)
				(type default)
			)
			(layer "F.SilkS")
		)
		(fp_line
			(start -1.1938 -0.4064)
			(end -0.8636 -0.4064)
			(stroke
				(width 0.1)
				(type default)
			)
			(layer "F.Fab")
		)
		(fp_line
			(start -1.1938 0.4064)
			(end -1.1938 -0.4064)
			(stroke
				(width 0.1)
				(type default)
			)
			(layer "F.Fab")
		)
		(fp_line
			(start -0.8636 -0.4572)
			(end 0.8636 -0.4572)
			(stroke
				(width 0.1)
				(type default)
			)
			(layer "F.Fab")
		)
		(fp_line
			(start -0.8636 -0.4064)
			(end -0.8636 -0.4572)
			(stroke
				(width 0.1)
				(type default)
			)
			(layer "F.Fab")
		)
		(fp_line
			(start -0.8636 0.4064)
			(end -1.1938 0.4064)
			(stroke
				(width 0.1)
				(type default)
			)
			(layer "F.Fab")
		)
		(fp_line
			(start -0.8636 0.4572)
			(end -0.8636 0.4064)
			(stroke
				(width 0.1)
				(type default)
			)
			(layer "F.Fab")
		)
		(fp_line
			(start 0.8636 -0.4572)
			(end 0.8636 -0.4064)
			(stroke
				(width 0.1)
				(type default)
			)
			(layer "F.Fab")
		)
		(fp_line
			(start 0.8636 -0.4064)
			(end 1.1938 -0.4064)
			(stroke
				(width 0.1)
				(type default)
			)
			(layer "F.Fab")
		)
		(fp_line
			(start 0.8636 0.4064)
			(end 0.8636 0.4572)
			(stroke
				(width 0.1)
				(type default)
			)
			(layer "F.Fab")
		)
		(fp_line
			(start 0.8636 0.4572)
			(end -0.8636 0.4572)
			(stroke
				(width 0.1)
				(type default)
			)
			(layer "F.Fab")
		)
		(fp_line
			(start 1.1938 -0.4064)
			(end 1.1938 0.4064)
			(stroke
				(width 0.1)
				(type default)
			)
			(layer "F.Fab")
		)
		(fp_line
			(start 1.1938 0.4064)
			(end 0.8636 0.4064)
			(stroke
				(width 0.1)
				(type default)
			)
			(layer "F.Fab")
		)
		(pad "1" smd rect
			(at -0.7366 0 270)
			(size 0.7112 0.8128)
			(layers "F.Cu" "F.Mask" "F.Paste")
			(net "SYSPLL_VDDA18_PEX0")
		)
		(pad "2" smd rect
			(at 0.7366 0 270)
			(size 0.7112 0.8128)
			(layers "F.Cu" "F.Mask" "F.Paste")
			(net "GND")
		)
	)
	(footprint ""
		(layer "F.Cu")
		(at 449.145914 -46.4439 180)
		(property "Reference" "U78"
			(at 0.480314 -2.45237 0)
			(unlocked yes)
			(layer "F.SilkS")
			(effects
				(font
					(size 0.7874 0.5842)
					(thickness 0.1524)
				)
			)
		)
		(property "Value" ""
			(at 0 0 180)
			(layer "F.Fab")
			(effects
				(font
					(size 1.27 1.27)
				)
			)
		)
		(duplicate_pad_numbers_are_jumpers no)
		(fp_line
			(start 1.500124 1.500124)
			(end 1.004062 1.500124)
			(stroke
				(width 0.1524)
				(type default)
			)
			(layer "F.SilkS")
		)
		(fp_line
			(start 1.500124 1.004062)
			(end 1.500124 1.500124)
			(stroke
				(width 0.1524)
				(type default)
			)
			(layer "F.SilkS")
		)
		(fp_line
			(start 1.500124 -1.500124)
			(end 1.500124 -1.004062)
			(stroke
				(width 0.1524)
				(type default)
			)
			(layer "F.SilkS")
		)
		(fp_line
			(start 1.004062 -1.500124)
			(end 1.500124 -1.500124)
			(stroke
				(width 0.1524)
				(type default)
			)
			(layer "F.SilkS")
		)
		(fp_line
			(start -1.004062 1.500124)
			(end -1.500124 1.500124)
			(stroke
				(width 0.1524)
				(type default)
			)
			(layer "F.SilkS")
		)
		(fp_line
			(start -1.500124 1.500124)
			(end -1.500124 1.004062)
			(stroke
				(width 0.1524)
				(type default)
			)
			(layer "F.SilkS")
		)
		(fp_line
			(start -1.500124 -1.004062)
			(end -1.500124 -1.500124)
			(stroke
				(width 0.1524)
				(type default)
			)
			(layer "F.SilkS")
		)
		(fp_line
			(start -1.500124 -1.500124)
			(end -1.004062 -1.500124)
			(stroke
				(width 0.1524)
				(type default)
			)
			(layer "F.SilkS")
		)
		(fp_poly
			(pts
				(xy -1.903222 -2.34188) (xy -2.621788 -1.623568) (xy -1.544066 -1.264412)
			)
			(stroke
				(width 0)
				(type default)
			)
			(fill yes)
			(layer "F.SilkS")
		)
		(fp_line
			(start 1.500124 1.500124)
			(end -1.500124 1.500124)
			(stroke
				(width 0.1)
				(type default)
			)
			(layer "F.Fab")
		)
		(fp_line
			(start 1.500124 -1.500124)
			(end 1.500124 1.500124)
			(stroke
				(width 0.1)
				(type default)
			)
			(layer "F.Fab")
		)
		(fp_line
			(start -1.500124 1.500124)
			(end -1.500124 -1.500124)
			(stroke
				(width 0.1)
				(type default)
			)
			(layer "F.Fab")
		)
		(fp_line
			(start -1.500124 -1.500124)
			(end 1.500124 -1.500124)
			(stroke
				(width 0.1)
				(type default)
			)
			(layer "F.Fab")
		)
		(fp_poly
			(pts
				(xy -2.847848 -1.258062) (xy -2.847848 -0.242062) (xy -1.831848 -0.750062)
			)
			(stroke
				(width 0)
				(type default)
			)
			(fill yes)
			(layer "F.Fab")
		)
		(pad "1" smd rect
			(at -1.400048 -0.750062 90)
			(size 0.2286 0.6096)
			(layers "F.Cu" "F.Mask" "F.Paste")
			(net "SSD15_ADC_A1")
		)
		(pad "2" smd rect
			(at -1.400048 -0.249936 90)
			(size 0.2286 0.6096)
			(layers "F.Cu" "F.Mask" "F.Paste")
			(net "SSD15_ADC_A0")
		)
		(pad "3" smd rect
			(at -1.400048 0.249936 90)
			(size 0.2286 0.6096)
			(layers "F.Cu" "F.Mask" "F.Paste")
			(net "SSD15_ADC_ALERT_N")
		)
		(pad "4" smd rect
			(at -1.400048 0.750062 90)
			(size 0.2286 0.6096)
			(layers "F.Cu" "F.Mask" "F.Paste")
			(net "SMB_SSD15_ADC_SDA")
		)
		(pad "5" smd rect
			(at -0.750062 1.400048 180)
			(size 0.2286 0.6096)
			(layers "F.Cu" "F.Mask" "F.Paste")
			(net "SMB_SSD15_ADC_SCL")
		)
		(pad "6" smd rect
			(at -0.249936 1.400048 180)
			(size 0.2286 0.6096)
			(layers "F.Cu" "F.Mask" "F.Paste")
			(net "Net_8672")
		)
		(pad "7" smd rect
			(at 0.249936 1.400048 180)
			(size 0.2286 0.6096)
			(layers "F.Cu" "F.Mask" "F.Paste")
			(net "Net_8671")
		)
		(pad "8" smd rect
			(at 0.750062 1.400048 180)
			(size 0.2286 0.6096)
			(layers "F.Cu" "F.Mask" "F.Paste")
			(net "Net_8670")
		)
		(pad "9" smd rect
			(at 1.400048 0.750062 90)
			(size 0.2286 0.6096)
			(layers "F.Cu" "F.Mask" "F.Paste")
			(net "P3V3_AUX")
		)
		(pad "10" smd rect
			(at 1.400048 0.249936 90)
			(size 0.2286 0.6096)
			(layers "F.Cu" "F.Mask" "F.Paste")
			(net "GND")
		)
		(pad "11" smd rect
			(at 1.400048 -0.249936 90)
			(size 0.2286 0.6096)
			(layers "F.Cu" "F.Mask" "F.Paste")
			(net "P12V_SSD15_R")
		)
		(pad "12" smd rect
			(at 1.400048 -0.750062 90)
			(size 0.2286 0.6096)
			(layers "F.Cu" "F.Mask" "F.Paste")
			(net "P12V_SSD15_VIN_N")
		)
		(pad "13" smd rect
			(at 0.750062 -1.400048 180)
			(size 0.2286 0.6096)
			(layers "F.Cu" "F.Mask" "F.Paste")
			(net "P12V_SSD15_VIN_P")
		)
		(pad "14" smd rect
			(at 0.249936 -1.400048 180)
			(size 0.2286 0.6096)
			(layers "F.Cu" "F.Mask" "F.Paste")
			(net "Net_8669")
		)
		(pad "15" smd rect
			(at -0.249936 -1.400048 180)
			(size 0.2286 0.6096)
			(layers "F.Cu" "F.Mask" "F.Paste")
			(net "Net_8668")
		)
		(pad "16" smd rect
			(at -0.750062 -1.400048 180)
			(size 0.2286 0.6096)
			(layers "F.Cu" "F.Mask" "F.Paste")
			(net "Net_8667")
		)
		(pad "TH" smd rect
			(at 0 0 180)
			(size 1.7018 1.7018)
			(layers "F.Cu" "F.Mask" "F.Paste")
			(net "GND")
		)
		(zone
			(layer "F.Cu")
			(hatch none 0.5)
			(connect_pads
				(clearance 0)
			)
			(min_thickness 0.25)
			(keepout
				(tracks not_allowed)
				(vias allowed)
				(pads allowed)
				(copperpour not_allowed)
				(footprints allowed)
			)
			(placement
				(enabled no)
				(sheetname "")
			)
			(fill
				(thermal_gap 0.5)
				(thermal_bridge_width 0.5)
				(island_removal_mode 0)
			)
			(polygon
				(pts
					(xy 450.190362 -46.4185) (xy 450.190362 -45.399452) (xy 448.101466 -45.399452) (xy 448.101466 -47.488348)
					(xy 450.190362 -47.488348) (xy 450.190362 -46.4439) (xy 450.047614 -46.4439) (xy 450.047614 -47.3456)
					(xy 448.244214 -47.3456) (xy 448.244214 -45.5422) (xy 450.047614 -45.5422) (xy 450.047614 -46.4185)
				)
			)
		)
	)
	(footprint ""
		(layer "F.Cu")
		(at 431.946812 -343.952322 90)
		(property "Reference" "C2460"
			(at 0 0 90)
			(layer "F.SilkS")
			(hide yes)
			(effects
				(font
					(size 1.27 1.27)
				)
			)
		)
		(property "Value" ""
			(at 0 0 90)
			(layer "F.Fab")
			(effects
				(font
					(size 1.27 1.27)
				)
			)
		)
		(duplicate_pad_numbers_are_jumpers no)
		(fp_line
			(start 0.299974 -0.150114)
			(end 0.299974 0.150114)
			(stroke
				(width 0.1)
				(type default)
			)
			(layer "F.Fab")
		)
		(fp_line
			(start -0.299974 -0.150114)
			(end 0.299974 -0.150114)
			(stroke
				(width 0.1)
				(type default)
			)
			(layer "F.Fab")
		)
		(fp_line
			(start 0.299974 0.150114)
			(end -0.299974 0.150114)
			(stroke
				(width 0.1)
				(type default)
			)
			(layer "F.Fab")
		)
		(fp_line
			(start -0.299974 0.150114)
			(end -0.299974 -0.150114)
			(stroke
				(width 0.1)
				(type default)
			)
			(layer "F.Fab")
		)
		(pad "1" smd rect
			(at -0.2667 0 90)
			(size 0.3048 0.381)
			(layers "F.Cu" "F.Mask" "F.Paste")
			(net "P5E_PEX3_STN4_TX_DN<69>")
		)
		(pad "2" smd rect
			(at 0.2667 0 90)
			(size 0.3048 0.381)
			(layers "F.Cu" "F.Mask" "F.Paste")
			(net "P5E_PEX3_STN4_TX_C_DN<69>")
		)
	)
	(footprint ""
		(layer "F.Cu")
		(at 405.201882 -32.849312 90)
		(property "Reference" "R5710"
			(at 0 0 90)
			(layer "F.SilkS")
			(hide yes)
			(effects
				(font
					(size 1.27 1.27)
				)
			)
		)
		(property "Value" ""
			(at 0 0 90)
			(layer "F.Fab")
			(effects
				(font
					(size 1.27 1.27)
				)
			)
		)
		(duplicate_pad_numbers_are_jumpers no)
		(fp_line
			(start 0.7874 -0.4064)
			(end 0.7874 0.4064)
			(stroke
				(width 0.1524)
				(type default)
			)
			(layer "F.SilkS")
		)
		(fp_line
			(start -0.7874 -0.4064)
			(end 0.7874 -0.4064)
			(stroke
				(width 0.1524)
				(type default)
			)
			(layer "F.SilkS")
		)
		(fp_line
			(start 0.7874 0.4064)
			(end -0.7874 0.4064)
			(stroke
				(width 0.1524)
				(type default)
			)
			(layer "F.SilkS")
		)
		(fp_line
			(start -0.7874 0.4064)
			(end -0.7874 -0.4064)
			(stroke
				(width 0.1524)
				(type default)
			)
			(layer "F.SilkS")
		)
		(fp_line
			(start -0.12065 -0.305054)
			(end -0.12065 -0.2794)
			(stroke
				(width 0.1)
				(type default)
			)
			(layer "F.Fab")
		)
		(fp_line
			(start -0.67945 -0.305054)
			(end -0.12065 -0.305054)
			(stroke
				(width 0.1)
				(type default)
			)
			(layer "F.Fab")
		)
		(fp_line
			(start 0.67945 -0.3048)
			(end 0.67945 0.3048)
			(stroke
				(width 0.1)
				(type default)
			)
			(layer "F.Fab")
		)
		(fp_line
			(start 0.12065 -0.3048)
			(end 0.67945 -0.3048)
			(stroke
				(width 0.1)
				(type default)
			)
			(layer "F.Fab")
		)
		(fp_line
			(start 0.12065 -0.2794)
			(end 0.12065 -0.3048)
			(stroke
				(width 0.1)
				(type default)
			)
			(layer "F.Fab")
		)
		(fp_line
			(start -0.12065 -0.2794)
			(end 0.12065 -0.2794)
			(stroke
				(width 0.1)
				(type default)
			)
			(layer "F.Fab")
		)
		(fp_line
			(start 0.120396 0.2794)
			(end -0.12065 0.2794)
			(stroke
				(width 0.1)
				(type default)
			)
			(layer "F.Fab")
		)
		(fp_line
			(start -0.12065 0.2794)
			(end -0.12065 0.3048)
			(stroke
				(width 0.1)
				(type default)
			)
			(layer "F.Fab")
		)
		(fp_line
			(start 0.67945 0.3048)
			(end 0.120396 0.3048)
			(stroke
				(width 0.1)
				(type default)
			)
			(layer "F.Fab")
		)
		(fp_line
			(start 0.120396 0.3048)
			(end 0.120396 0.2794)
			(stroke
				(width 0.1)
				(type default)
			)
			(layer "F.Fab")
		)
		(fp_line
			(start -0.12065 0.3048)
			(end -0.67945 0.3048)
			(stroke
				(width 0.1)
				(type default)
			)
			(layer "F.Fab")
		)
		(fp_line
			(start -0.67945 0.3048)
			(end -0.67945 -0.305054)
			(stroke
				(width 0.1)
				(type default)
			)
			(layer "F.Fab")
		)
		(pad "1" smd circle
			(at -0.40005 0 90)
			(size 0 0)
			(layers "F.Cu" "F.Mask" "F.Paste")
			(net "RST_SMB_SSD14_ISO_R_N")
		)
		(pad "2" smd circle
			(at 0.40005 0 90)
			(size 0 0)
			(layers "F.Cu" "F.Mask" "F.Paste")
			(net "RST_SMB_SSD14_ISO_N")
		)
	)
	(footprint ""
		(layer "F.Cu")
		(at 482.178868 -523.784322 180)
		(property "Reference" "SCREW_7"
			(at -3.2385 -1.402334 0)
			(unlocked yes)
			(layer "B.SilkS")
			(effects
				(font
					(size 0.7874 0.5842)
					(thickness 0.1524)
				)
				(justify mirror)
			)
		)
		(property "Value" ""
			(at 0 0 180)
			(layer "F.Fab")
			(effects
				(font
					(size 1.27 1.27)
				)
			)
		)
		(duplicate_pad_numbers_are_jumpers no)
		(pad "1" thru_hole circle
			(at 0 0 180)
			(size 0.4572 0.4572)
			(drill 0.2032)
			(layers "*.Cu" "*.Mask")
			(remove_unused_layers no)
			(net "Net_9157")
			(clearance 0.127)
			(thermal_gap 0.127)
			(padstack
				(mode front_inner_back)
				(layer "Inner"
					(shape circle)
					(size 0.4572 0.4572)
					(clearance 0.127)
				)
				(layer "B.Cu"
					(shape circle)
					(size 0.508 0.508)
					(clearance 0.1016)
				)
			)
		)
	)
	(footprint ""
		(layer "F.Cu")
		(at 448.799966 -84.699856)
		(property "Reference" "H70"
			(at -4.574794 -5.040884 0)
			(unlocked yes)
			(layer "F.SilkS")
			(effects
				(font
					(size 0.7874 0.5842)
					(thickness 0.1524)
				)
				(justify left)
			)
		)
		(property "Value" ""
			(at 0 0 0)
			(layer "F.Fab")
			(effects
				(font
					(size 1.27 1.27)
				)
			)
		)
		(duplicate_pad_numbers_are_jumpers no)
		(pad "1" thru_hole circle
			(at 0 0)
			(size 10.0076 10.0076)
			(drill 5.6134)
			(layers "*.Cu" "*.Mask")
			(remove_unused_layers no)
			(net "GND")
			(clearance -1.9431)
		)
	)
	(footprint ""
		(layer "F.Cu")
		(at 336.042 -162.814)
		(property "Reference" "R4799"
			(at 0 0 0)
			(layer "F.SilkS")
			(hide yes)
			(effects
				(font
					(size 1.27 1.27)
				)
			)
		)
		(property "Value" ""
			(at 0 0 0)
			(layer "F.Fab")
			(effects
				(font
					(size 1.27 1.27)
				)
			)
		)
		(duplicate_pad_numbers_are_jumpers no)
		(fp_line
			(start -0.7874 -0.4064)
			(end 0.7874 -0.4064)
			(stroke
				(width 0.1524)
				(type default)
			)
			(layer "F.SilkS")
		)
		(fp_line
			(start -0.7874 0.4064)
			(end -0.7874 -0.4064)
			(stroke
				(width 0.1524)
				(type default)
			)
			(layer "F.SilkS")
		)
		(fp_line
			(start 0.7874 -0.4064)
			(end 0.7874 0.4064)
			(stroke
				(width 0.1524)
				(type default)
			)
			(layer "F.SilkS")
		)
		(fp_line
			(start 0.7874 0.4064)
			(end -0.7874 0.4064)
			(stroke
				(width 0.1524)
				(type default)
			)
			(layer "F.SilkS")
		)
		(fp_line
			(start -0.67945 -0.305054)
			(end -0.12065 -0.305054)
			(stroke
				(width 0.1)
				(type default)
			)
			(layer "F.Fab")
		)
		(fp_line
			(start -0.67945 0.3048)
			(end -0.67945 -0.305054)
			(stroke
				(width 0.1)
				(type default)
			)
			(layer "F.Fab")
		)
		(fp_line
			(start -0.12065 -0.305054)
			(end -0.12065 -0.2794)
			(stroke
				(width 0.1)
				(type default)
			)
			(layer "F.Fab")
		)
		(fp_line
			(start -0.12065 -0.2794)
			(end 0.12065 -0.2794)
			(stroke
				(width 0.1)
				(type default)
			)
			(layer "F.Fab")
		)
		(fp_line
			(start -0.12065 0.2794)
			(end -0.12065 0.3048)
			(stroke
				(width 0.1)
				(type default)
			)
			(layer "F.Fab")
		)
		(fp_line
			(start -0.12065 0.3048)
			(end -0.67945 0.3048)
			(stroke
				(width 0.1)
				(type default)
			)
			(layer "F.Fab")
		)
		(fp_line
			(start 0.120396 0.2794)
			(end -0.12065 0.2794)
			(stroke
				(width 0.1)
				(type default)
			)
			(layer "F.Fab")
		)
		(fp_line
			(start 0.120396 0.3048)
			(end 0.120396 0.2794)
			(stroke
				(width 0.1)
				(type default)
			)
			(layer "F.Fab")
		)
		(fp_line
			(start 0.12065 -0.3048)
			(end 0.67945 -0.3048)
			(stroke
				(width 0.1)
				(type default)
			)
			(layer "F.Fab")
		)
		(fp_line
			(start 0.12065 -0.2794)
			(end 0.12065 -0.3048)
			(stroke
				(width 0.1)
				(type default)
			)
			(layer "F.Fab")
		)
		(fp_line
			(start 0.67945 -0.3048)
			(end 0.67945 0.3048)
			(stroke
				(width 0.1)
				(type default)
			)
			(layer "F.Fab")
		)
		(fp_line
			(start 0.67945 0.3048)
			(end 0.120396 0.3048)
			(stroke
				(width 0.1)
				(type default)
			)
			(layer "F.Fab")
		)
		(pad "1" smd circle
			(at -0.40005 0)
			(size 0 0)
			(layers "F.Cu" "F.Mask" "F.Paste")
			(net "PEX3_PCA9555_INT_N")
		)
		(pad "2" smd circle
			(at 0.40005 0)
			(size 0 0)
			(layers "F.Cu" "F.Mask" "F.Paste")
			(net "PEX3_PCA9555_0_INT_N")
		)
	)
	(footprint ""
		(layer "F.Cu")
		(at 271.480534 -125.519942)
		(property "Reference" "C464"
			(at 0 0 0)
			(layer "F.SilkS")
			(hide yes)
			(effects
				(font
					(size 1.27 1.27)
				)
			)
		)
		(property "Value" ""
			(at 0 0 0)
			(layer "F.Fab")
			(effects
				(font
					(size 1.27 1.27)
				)
			)
		)
		(duplicate_pad_numbers_are_jumpers no)
		(fp_line
			(start -0.299974 -0.150114)
			(end 0.299974 -0.150114)
			(stroke
				(width 0.1)
				(type default)
			)
			(layer "F.Fab")
		)
		(fp_line
			(start -0.299974 0.150114)
			(end -0.299974 -0.150114)
			(stroke
				(width 0.1)
				(type default)
			)
			(layer "F.Fab")
		)
		(fp_line
			(start 0.299974 -0.150114)
			(end 0.299974 0.150114)
			(stroke
				(width 0.1)
				(type default)
			)
			(layer "F.Fab")
		)
		(fp_line
			(start 0.299974 0.150114)
			(end -0.299974 0.150114)
			(stroke
				(width 0.1)
				(type default)
			)
			(layer "F.Fab")
		)
		(pad "1" smd rect
			(at -0.2667 0)
			(size 0.3048 0.381)
			(layers "F.Cu" "F.Mask" "F.Paste")
			(net "P5E_PEX2_STN1_TX_DP<27>")
		)
		(pad "2" smd rect
			(at 0.2667 0)
			(size 0.3048 0.381)
			(layers "F.Cu" "F.Mask" "F.Paste")
			(net "P5E_PEX2_STN1_TX_C_DP<27>")
		)
	)
	(footprint ""
		(layer "F.Cu")
		(at 46.673008 -22.867366 90)
		(property "Reference" "C3879"
			(at 0 0 90)
			(layer "F.SilkS")
			(hide yes)
			(effects
				(font
					(size 1.27 1.27)
				)
			)
		)
		(property "Value" ""
			(at 0 0 90)
			(layer "F.Fab")
			(effects
				(font
					(size 1.27 1.27)
				)
			)
		)
		(duplicate_pad_numbers_are_jumpers no)
		(fp_line
			(start 0.7874 -0.4064)
			(end 0.7874 0.4064)
			(stroke
				(width 0.1524)
				(type default)
			)
			(layer "F.SilkS")
		)
		(fp_line
			(start -0.7874 -0.4064)
			(end 0.7874 -0.4064)
			(stroke
				(width 0.1524)
				(type default)
			)
			(layer "F.SilkS")
		)
		(fp_line
			(start 0.7874 0.4064)
			(end -0.7874 0.4064)
			(stroke
				(width 0.1524)
				(type default)
			)
			(layer "F.SilkS")
		)
		(fp_line
			(start -0.7874 0.4064)
			(end -0.7874 -0.4064)
			(stroke
				(width 0.1524)
				(type default)
			)
			(layer "F.SilkS")
		)
		(fp_line
			(start -0.12065 -0.305054)
			(end -0.12065 -0.2794)
			(stroke
				(width 0.1)
				(type default)
			)
			(layer "F.Fab")
		)
		(fp_line
			(start -0.67945 -0.305054)
			(end -0.12065 -0.305054)
			(stroke
				(width 0.1)
				(type default)
			)
			(layer "F.Fab")
		)
		(fp_line
			(start 0.67945 -0.3048)
			(end 0.67945 0.3048)
			(stroke
				(width 0.1)
				(type default)
			)
			(layer "F.Fab")
		)
		(fp_line
			(start 0.12065 -0.3048)
			(end 0.67945 -0.3048)
			(stroke
				(width 0.1)
				(type default)
			)
			(layer "F.Fab")
		)
		(fp_line
			(start 0.12065 -0.2794)
			(end 0.12065 -0.3048)
			(stroke
				(width 0.1)
				(type default)
			)
			(layer "F.Fab")
		)
		(fp_line
			(start -0.12065 -0.2794)
			(end 0.12065 -0.2794)
			(stroke
				(width 0.1)
				(type default)
			)
			(layer "F.Fab")
		)
		(fp_line
			(start 0.120396 0.2794)
			(end -0.12065 0.2794)
			(stroke
				(width 0.1)
				(type default)
			)
			(layer "F.Fab")
		)
		(fp_line
			(start -0.12065 0.2794)
			(end -0.12065 0.3048)
			(stroke
				(width 0.1)
				(type default)
			)
			(layer "F.Fab")
		)
		(fp_line
			(start 0.67945 0.3048)
			(end 0.120396 0.3048)
			(stroke
				(width 0.1)
				(type default)
			)
			(layer "F.Fab")
		)
		(fp_line
			(start 0.120396 0.3048)
			(end 0.120396 0.2794)
			(stroke
				(width 0.1)
				(type default)
			)
			(layer "F.Fab")
		)
		(fp_line
			(start -0.12065 0.3048)
			(end -0.67945 0.3048)
			(stroke
				(width 0.1)
				(type default)
			)
			(layer "F.Fab")
		)
		(fp_line
			(start -0.67945 0.3048)
			(end -0.67945 -0.305054)
			(stroke
				(width 0.1)
				(type default)
			)
			(layer "F.Fab")
		)
		(pad "1" smd circle
			(at -0.40005 0 90)
			(size 0 0)
			(layers "F.Cu" "F.Mask" "F.Paste")
			(net "P12V_SSD1")
		)
		(pad "2" smd circle
			(at 0.40005 0 90)
			(size 0 0)
			(layers "F.Cu" "F.Mask" "F.Paste")
			(net "GND")
		)
	)
	(footprint ""
		(layer "F.Cu")
		(at 286.525462 -343.952322 90)
		(property "Reference" "C2357"
			(at 0 0 90)
			(layer "F.SilkS")
			(hide yes)
			(effects
				(font
					(size 1.27 1.27)
				)
			)
		)
		(property "Value" ""
			(at 0 0 90)
			(layer "F.Fab")
			(effects
				(font
					(size 1.27 1.27)
				)
			)
		)
		(duplicate_pad_numbers_are_jumpers no)
		(fp_line
			(start 0.299974 -0.150114)
			(end 0.299974 0.150114)
			(stroke
				(width 0.1)
				(type default)
			)
			(layer "F.Fab")
		)
		(fp_line
			(start -0.299974 -0.150114)
			(end 0.299974 -0.150114)
			(stroke
				(width 0.1)
				(type default)
			)
			(layer "F.Fab")
		)
		(fp_line
			(start 0.299974 0.150114)
			(end -0.299974 0.150114)
			(stroke
				(width 0.1)
				(type default)
			)
			(layer "F.Fab")
		)
		(fp_line
			(start -0.299974 0.150114)
			(end -0.299974 -0.150114)
			(stroke
				(width 0.1)
				(type default)
			)
			(layer "F.Fab")
		)
		(pad "1" smd rect
			(at -0.2667 0 90)
			(size 0.3048 0.381)
			(layers "F.Cu" "F.Mask" "F.Paste")
			(net "P5E_PEX2_STN4_TX_DP<71>")
		)
		(pad "2" smd rect
			(at 0.2667 0 90)
			(size 0.3048 0.381)
			(layers "F.Cu" "F.Mask" "F.Paste")
			(net "P5E_PEX2_STN4_TX_C_DP<71>")
		)
	)
	(footprint ""
		(layer "F.Cu")
		(at 361.188 -172.974 180)
		(property "Reference" "R4711"
			(at 0 0 180)
			(layer "F.SilkS")
			(hide yes)
			(effects
				(font
					(size 1.27 1.27)
				)
			)
		)
		(property "Value" ""
			(at 0 0 180)
			(layer "F.Fab")
			(effects
				(font
					(size 1.27 1.27)
				)
			)
		)
		(duplicate_pad_numbers_are_jumpers no)
		(fp_line
			(start 0.7874 0.4064)
			(end -0.7874 0.4064)
			(stroke
				(width 0.1524)
				(type default)
			)
			(layer "F.SilkS")
		)
		(fp_line
			(start 0.7874 -0.4064)
			(end 0.7874 0.4064)
			(stroke
				(width 0.1524)
				(type default)
			)
			(layer "F.SilkS")
		)
		(fp_line
			(start -0.7874 0.4064)
			(end -0.7874 -0.4064)
			(stroke
				(width 0.1524)
				(type default)
			)
			(layer "F.SilkS")
		)
		(fp_line
			(start -0.7874 -0.4064)
			(end 0.7874 -0.4064)
			(stroke
				(width 0.1524)
				(type default)
			)
			(layer "F.SilkS")
		)
		(fp_line
			(start 0.67945 0.3048)
			(end 0.120396 0.3048)
			(stroke
				(width 0.1)
				(type default)
			)
			(layer "F.Fab")
		)
		(fp_line
			(start 0.67945 -0.3048)
			(end 0.67945 0.3048)
			(stroke
				(width 0.1)
				(type default)
			)
			(layer "F.Fab")
		)
		(fp_line
			(start 0.12065 -0.2794)
			(end 0.12065 -0.3048)
			(stroke
				(width 0.1)
				(type default)
			)
			(layer "F.Fab")
		)
		(fp_line
			(start 0.12065 -0.3048)
			(end 0.67945 -0.3048)
			(stroke
				(width 0.1)
				(type default)
			)
			(layer "F.Fab")
		)
		(fp_line
			(start 0.120396 0.3048)
			(end 0.120396 0.2794)
			(stroke
				(width 0.1)
				(type default)
			)
			(layer "F.Fab")
		)
		(fp_line
			(start 0.120396 0.2794)
			(end -0.12065 0.2794)
			(stroke
				(width 0.1)
				(type default)
			)
			(layer "F.Fab")
		)
		(fp_line
			(start -0.12065 0.3048)
			(end -0.67945 0.3048)
			(stroke
				(width 0.1)
				(type default)
			)
			(layer "F.Fab")
		)
		(fp_line
			(start -0.12065 0.2794)
			(end -0.12065 0.3048)
			(stroke
				(width 0.1)
				(type default)
			)
			(layer "F.Fab")
		)
		(fp_line
			(start -0.12065 -0.2794)
			(end 0.12065 -0.2794)
			(stroke
				(width 0.1)
				(type default)
			)
			(layer "F.Fab")
		)
		(fp_line
			(start -0.12065 -0.305054)
			(end -0.12065 -0.2794)
			(stroke
				(width 0.1)
				(type default)
			)
			(layer "F.Fab")
		)
		(fp_line
			(start -0.67945 0.3048)
			(end -0.67945 -0.305054)
			(stroke
				(width 0.1)
				(type default)
			)
			(layer "F.Fab")
		)
		(fp_line
			(start -0.67945 -0.305054)
			(end -0.12065 -0.305054)
			(stroke
				(width 0.1)
				(type default)
			)
			(layer "F.Fab")
		)
		(pad "1" smd circle
			(at -0.40005 0 180)
			(size 0 0)
			(layers "F.Cu" "F.Mask" "F.Paste")
			(net "RST_PEX_SSD7_PERST_N")
		)
		(pad "2" smd circle
			(at 0.40005 0 180)
			(size 0 0)
			(layers "F.Cu" "F.Mask" "F.Paste")
			(net "RST_PEX_SSD7_PERST_R_N")
		)
	)
	(footprint ""
		(layer "F.Cu")
		(at 241.542062 -199.736964)
		(property "Reference" "R6148"
			(at 0 0 0)
			(layer "F.SilkS")
			(hide yes)
			(effects
				(font
					(size 1.27 1.27)
				)
			)
		)
		(property "Value" ""
			(at 0 0 0)
			(layer "F.Fab")
			(effects
				(font
					(size 1.27 1.27)
				)
			)
		)
		(duplicate_pad_numbers_are_jumpers no)
		(fp_line
			(start -0.7874 -0.4064)
			(end 0.7874 -0.4064)
			(stroke
				(width 0.1524)
				(type default)
			)
			(layer "F.SilkS")
		)
		(fp_line
			(start -0.7874 0.4064)
			(end -0.7874 -0.4064)
			(stroke
				(width 0.1524)
				(type default)
			)
			(layer "F.SilkS")
		)
		(fp_line
			(start 0.7874 -0.4064)
			(end 0.7874 0.4064)
			(stroke
				(width 0.1524)
				(type default)
			)
			(layer "F.SilkS")
		)
		(fp_line
			(start 0.7874 0.4064)
			(end -0.7874 0.4064)
			(stroke
				(width 0.1524)
				(type default)
			)
			(layer "F.SilkS")
		)
		(fp_line
			(start -0.67945 -0.305054)
			(end -0.12065 -0.305054)
			(stroke
				(width 0.1)
				(type default)
			)
			(layer "F.Fab")
		)
		(fp_line
			(start -0.67945 0.3048)
			(end -0.67945 -0.305054)
			(stroke
				(width 0.1)
				(type default)
			)
			(layer "F.Fab")
		)
		(fp_line
			(start -0.12065 -0.305054)
			(end -0.12065 -0.2794)
			(stroke
				(width 0.1)
				(type default)
			)
			(layer "F.Fab")
		)
		(fp_line
			(start -0.12065 -0.2794)
			(end 0.12065 -0.2794)
			(stroke
				(width 0.1)
				(type default)
			)
			(layer "F.Fab")
		)
		(fp_line
			(start -0.12065 0.2794)
			(end -0.12065 0.3048)
			(stroke
				(width 0.1)
				(type default)
			)
			(layer "F.Fab")
		)
		(fp_line
			(start -0.12065 0.3048)
			(end -0.67945 0.3048)
			(stroke
				(width 0.1)
				(type default)
			)
			(layer "F.Fab")
		)
		(fp_line
			(start 0.120396 0.2794)
			(end -0.12065 0.2794)
			(stroke
				(width 0.1)
				(type default)
			)
			(layer "F.Fab")
		)
		(fp_line
			(start 0.120396 0.3048)
			(end 0.120396 0.2794)
			(stroke
				(width 0.1)
				(type default)
			)
			(layer "F.Fab")
		)
		(fp_line
			(start 0.12065 -0.3048)
			(end 0.67945 -0.3048)
			(stroke
				(width 0.1)
				(type default)
			)
			(layer "F.Fab")
		)
		(fp_line
			(start 0.12065 -0.2794)
			(end 0.12065 -0.3048)
			(stroke
				(width 0.1)
				(type default)
			)
			(layer "F.Fab")
		)
		(fp_line
			(start 0.67945 -0.3048)
			(end 0.67945 0.3048)
			(stroke
				(width 0.1)
				(type default)
			)
			(layer "F.Fab")
		)
		(fp_line
			(start 0.67945 0.3048)
			(end 0.120396 0.3048)
			(stroke
				(width 0.1)
				(type default)
			)
			(layer "F.Fab")
		)
		(pad "1" smd circle
			(at -0.40005 0)
			(size 0 0)
			(layers "F.Cu" "F.Mask" "F.Paste")
			(net "BIC_FWSPICS1_N")
		)
		(pad "2" smd circle
			(at 0.40005 0)
			(size 0 0)
			(layers "F.Cu" "F.Mask" "F.Paste")
			(net "P3V3_AUX")
		)
	)
	(footprint ""
		(layer "F.Cu")
		(at 198.765922 -77.889608 180)
		(property "Reference" "C904"
			(at 0 0 180)
			(layer "F.SilkS")
			(hide yes)
			(effects
				(font
					(size 1.27 1.27)
				)
			)
		)
		(property "Value" ""
			(at 0 0 180)
			(layer "F.Fab")
			(effects
				(font
					(size 1.27 1.27)
				)
			)
		)
		(duplicate_pad_numbers_are_jumpers no)
		(fp_line
			(start 0.7874 0.4064)
			(end -0.7874 0.4064)
			(stroke
				(width 0.1524)
				(type default)
			)
			(layer "F.SilkS")
		)
		(fp_line
			(start 0.7874 -0.4064)
			(end 0.7874 0.4064)
			(stroke
				(width 0.1524)
				(type default)
			)
			(layer "F.SilkS")
		)
		(fp_line
			(start -0.7874 0.4064)
			(end -0.7874 -0.4064)
			(stroke
				(width 0.1524)
				(type default)
			)
			(layer "F.SilkS")
		)
		(fp_line
			(start -0.7874 -0.4064)
			(end 0.7874 -0.4064)
			(stroke
				(width 0.1524)
				(type default)
			)
			(layer "F.SilkS")
		)
		(fp_line
			(start 0.67945 0.3048)
			(end 0.120396 0.3048)
			(stroke
				(width 0.1)
				(type default)
			)
			(layer "F.Fab")
		)
		(fp_line
			(start 0.67945 -0.3048)
			(end 0.67945 0.3048)
			(stroke
				(width 0.1)
				(type default)
			)
			(layer "F.Fab")
		)
		(fp_line
			(start 0.12065 -0.2794)
			(end 0.12065 -0.3048)
			(stroke
				(width 0.1)
				(type default)
			)
			(layer "F.Fab")
		)
		(fp_line
			(start 0.12065 -0.3048)
			(end 0.67945 -0.3048)
			(stroke
				(width 0.1)
				(type default)
			)
			(layer "F.Fab")
		)
		(fp_line
			(start 0.120396 0.3048)
			(end 0.120396 0.2794)
			(stroke
				(width 0.1)
				(type default)
			)
			(layer "F.Fab")
		)
		(fp_line
			(start 0.120396 0.2794)
			(end -0.12065 0.2794)
			(stroke
				(width 0.1)
				(type default)
			)
			(layer "F.Fab")
		)
		(fp_line
			(start -0.12065 0.3048)
			(end -0.67945 0.3048)
			(stroke
				(width 0.1)
				(type default)
			)
			(layer "F.Fab")
		)
		(fp_line
			(start -0.12065 0.2794)
			(end -0.12065 0.3048)
			(stroke
				(width 0.1)
				(type default)
			)
			(layer "F.Fab")
		)
		(fp_line
			(start -0.12065 -0.2794)
			(end 0.12065 -0.2794)
			(stroke
				(width 0.1)
				(type default)
			)
			(layer "F.Fab")
		)
		(fp_line
			(start -0.12065 -0.305054)
			(end -0.12065 -0.2794)
			(stroke
				(width 0.1)
				(type default)
			)
			(layer "F.Fab")
		)
		(fp_line
			(start -0.67945 0.3048)
			(end -0.67945 -0.305054)
			(stroke
				(width 0.1)
				(type default)
			)
			(layer "F.Fab")
		)
		(fp_line
			(start -0.67945 -0.305054)
			(end -0.12065 -0.305054)
			(stroke
				(width 0.1)
				(type default)
			)
			(layer "F.Fab")
		)
		(pad "1" smd circle
			(at -0.40005 0 180)
			(size 0 0)
			(layers "F.Cu" "F.Mask" "F.Paste")
			(net "P3V3_NIC3")
		)
		(pad "2" smd circle
			(at 0.40005 0 180)
			(size 0 0)
			(layers "F.Cu" "F.Mask" "F.Paste")
			(net "GND")
		)
	)
	(footprint ""
		(layer "F.Cu")
		(at 55.872126 -32.848042 90)
		(property "Reference" "PC680"
			(at 0 0 90)
			(layer "F.SilkS")
			(hide yes)
			(effects
				(font
					(size 1.27 1.27)
				)
			)
		)
		(property "Value" ""
			(at 0 0 90)
			(layer "F.Fab")
			(effects
				(font
					(size 1.27 1.27)
				)
			)
		)
		(duplicate_pad_numbers_are_jumpers no)
		(fp_line
			(start 0.7874 -0.4064)
			(end 0.7874 0.4064)
			(stroke
				(width 0.1524)
				(type default)
			)
			(layer "F.SilkS")
		)
		(fp_line
			(start -0.7874 -0.4064)
			(end 0.7874 -0.4064)
			(stroke
				(width 0.1524)
				(type default)
			)
			(layer "F.SilkS")
		)
		(fp_line
			(start 0.7874 0.4064)
			(end -0.7874 0.4064)
			(stroke
				(width 0.1524)
				(type default)
			)
			(layer "F.SilkS")
		)
		(fp_line
			(start -0.7874 0.4064)
			(end -0.7874 -0.4064)
			(stroke
				(width 0.1524)
				(type default)
			)
			(layer "F.SilkS")
		)
		(fp_line
			(start -0.12065 -0.305054)
			(end -0.12065 -0.2794)
			(stroke
				(width 0.1)
				(type default)
			)
			(layer "F.Fab")
		)
		(fp_line
			(start -0.67945 -0.305054)
			(end -0.12065 -0.305054)
			(stroke
				(width 0.1)
				(type default)
			)
			(layer "F.Fab")
		)
		(fp_line
			(start 0.67945 -0.3048)
			(end 0.67945 0.3048)
			(stroke
				(width 0.1)
				(type default)
			)
			(layer "F.Fab")
		)
		(fp_line
			(start 0.12065 -0.3048)
			(end 0.67945 -0.3048)
			(stroke
				(width 0.1)
				(type default)
			)
			(layer "F.Fab")
		)
		(fp_line
			(start 0.12065 -0.2794)
			(end 0.12065 -0.3048)
			(stroke
				(width 0.1)
				(type default)
			)
			(layer "F.Fab")
		)
		(fp_line
			(start -0.12065 -0.2794)
			(end 0.12065 -0.2794)
			(stroke
				(width 0.1)
				(type default)
			)
			(layer "F.Fab")
		)
		(fp_line
			(start 0.120396 0.2794)
			(end -0.12065 0.2794)
			(stroke
				(width 0.1)
				(type default)
			)
			(layer "F.Fab")
		)
		(fp_line
			(start -0.12065 0.2794)
			(end -0.12065 0.3048)
			(stroke
				(width 0.1)
				(type default)
			)
			(layer "F.Fab")
		)
		(fp_line
			(start 0.67945 0.3048)
			(end 0.120396 0.3048)
			(stroke
				(width 0.1)
				(type default)
			)
			(layer "F.Fab")
		)
		(fp_line
			(start 0.120396 0.3048)
			(end 0.120396 0.2794)
			(stroke
				(width 0.1)
				(type default)
			)
			(layer "F.Fab")
		)
		(fp_line
			(start -0.12065 0.3048)
			(end -0.67945 0.3048)
			(stroke
				(width 0.1)
				(type default)
			)
			(layer "F.Fab")
		)
		(fp_line
			(start -0.67945 0.3048)
			(end -0.67945 -0.305054)
			(stroke
				(width 0.1)
				(type default)
			)
			(layer "F.Fab")
		)
		(pad "1" smd circle
			(at -0.40005 0 90)
			(size 0 0)
			(layers "F.Cu" "F.Mask" "F.Paste")
			(net "P3V3_SSD2_CO_GATE")
		)
		(pad "2" smd circle
			(at 0.40005 0 90)
			(size 0 0)
			(layers "F.Cu" "F.Mask" "F.Paste")
			(net "GND")
		)
	)
	(footprint ""
		(layer "F.Cu")
		(at 266.310364 -63.652146 180)
		(property "Reference" "R5997"
			(at 0 0 180)
			(layer "F.SilkS")
			(hide yes)
			(effects
				(font
					(size 1.27 1.27)
				)
			)
		)
		(property "Value" ""
			(at 0 0 180)
			(layer "F.Fab")
			(effects
				(font
					(size 1.27 1.27)
				)
			)
		)
		(duplicate_pad_numbers_are_jumpers no)
		(fp_line
			(start 0.7874 0.4064)
			(end -0.7874 0.4064)
			(stroke
				(width 0.1524)
				(type default)
			)
			(layer "F.SilkS")
		)
		(fp_line
			(start 0.7874 -0.4064)
			(end 0.7874 0.4064)
			(stroke
				(width 0.1524)
				(type default)
			)
			(layer "F.SilkS")
		)
		(fp_line
			(start -0.7874 0.4064)
			(end -0.7874 -0.4064)
			(stroke
				(width 0.1524)
				(type default)
			)
			(layer "F.SilkS")
		)
		(fp_line
			(start -0.7874 -0.4064)
			(end 0.7874 -0.4064)
			(stroke
				(width 0.1524)
				(type default)
			)
			(layer "F.SilkS")
		)
		(fp_line
			(start 0.67945 0.3048)
			(end 0.120396 0.3048)
			(stroke
				(width 0.1)
				(type default)
			)
			(layer "F.Fab")
		)
		(fp_line
			(start 0.67945 -0.3048)
			(end 0.67945 0.3048)
			(stroke
				(width 0.1)
				(type default)
			)
			(layer "F.Fab")
		)
		(fp_line
			(start 0.12065 -0.2794)
			(end 0.12065 -0.3048)
			(stroke
				(width 0.1)
				(type default)
			)
			(layer "F.Fab")
		)
		(fp_line
			(start 0.12065 -0.3048)
			(end 0.67945 -0.3048)
			(stroke
				(width 0.1)
				(type default)
			)
			(layer "F.Fab")
		)
		(fp_line
			(start 0.120396 0.3048)
			(end 0.120396 0.2794)
			(stroke
				(width 0.1)
				(type default)
			)
			(layer "F.Fab")
		)
		(fp_line
			(start 0.120396 0.2794)
			(end -0.12065 0.2794)
			(stroke
				(width 0.1)
				(type default)
			)
			(layer "F.Fab")
		)
		(fp_line
			(start -0.12065 0.3048)
			(end -0.67945 0.3048)
			(stroke
				(width 0.1)
				(type default)
			)
			(layer "F.Fab")
		)
		(fp_line
			(start -0.12065 0.2794)
			(end -0.12065 0.3048)
			(stroke
				(width 0.1)
				(type default)
			)
			(layer "F.Fab")
		)
		(fp_line
			(start -0.12065 -0.2794)
			(end 0.12065 -0.2794)
			(stroke
				(width 0.1)
				(type default)
			)
			(layer "F.Fab")
		)
		(fp_line
			(start -0.12065 -0.305054)
			(end -0.12065 -0.2794)
			(stroke
				(width 0.1)
				(type default)
			)
			(layer "F.Fab")
		)
		(fp_line
			(start -0.67945 0.3048)
			(end -0.67945 -0.305054)
			(stroke
				(width 0.1)
				(type default)
			)
			(layer "F.Fab")
		)
		(fp_line
			(start -0.67945 -0.305054)
			(end -0.12065 -0.305054)
			(stroke
				(width 0.1)
				(type default)
			)
			(layer "F.Fab")
		)
		(pad "1" smd circle
			(at -0.40005 0 180)
			(size 0 0)
			(layers "F.Cu" "F.Mask" "F.Paste")
			(net "P5V_AUX")
		)
		(pad "2" smd circle
			(at 0.40005 0 180)
			(size 0 0)
			(layers "F.Cu" "F.Mask" "F.Paste")
			(net "P12V_SSD9_PG_G2")
		)
	)
	(footprint ""
		(layer "F.Cu")
		(at 231.30383 -307.484272)
		(property "Reference" "PJ12"
			(at 0 0 0)
			(layer "F.SilkS")
			(hide yes)
			(effects
				(font
					(size 1.27 1.27)
				)
			)
		)
		(property "Value" ""
			(at 0 0 0)
			(layer "F.Fab")
			(effects
				(font
					(size 1.27 1.27)
				)
			)
		)
		(duplicate_pad_numbers_are_jumpers no)
		(pad "1" smd circle
			(at -0.40005 0 90)
			(size 0 0)
			(layers "F.Cu" "F.Mask" "F.Paste")
			(net "SH_P1V25_PEX1_FB_N")
		)
		(pad "2" smd rect
			(at 0.40005 0 180)
			(size 0.4572 0.508)
			(layers "F.Cu" "F.Mask" "F.Paste")
			(net "GND")
		)
		(zone
			(layer "F.Cu")
			(hatch none 0.5)
			(connect_pads
				(clearance 0)
			)
			(min_thickness 0.25)
			(keepout
				(tracks allowed)
				(vias not_allowed)
				(pads allowed)
				(copperpour not_allowed)
				(footprints allowed)
			)
			(placement
				(enabled no)
				(sheetname "")
			)
			(fill
				(thermal_gap 0.5)
				(thermal_bridge_width 0.5)
				(island_removal_mode 0)
			)
			(polygon
				(pts
					(xy 230.61803 -307.179472) (xy 231.98963 -307.179472) (xy 231.98963 -307.789072) (xy 230.61803 -307.789072)
				)
			)
		)
	)
	(footprint ""
		(layer "F.Cu")
		(at 289.789362 -63.56223)
		(property "Reference" "Q206"
			(at 0.024638 -1.8161 0)
			(unlocked yes)
			(layer "F.SilkS")
			(effects
				(font
					(size 0.7874 0.5842)
					(thickness 0.1524)
				)
			)
		)
		(property "Value" ""
			(at 0 0 0)
			(layer "F.Fab")
			(effects
				(font
					(size 1.27 1.27)
				)
			)
		)
		(duplicate_pad_numbers_are_jumpers no)
		(fp_line
			(start -1.376172 -1.199896)
			(end -0.508 -1.199896)
			(stroke
				(width 0.1524)
				(type default)
			)
			(layer "F.SilkS")
		)
		(fp_line
			(start -1.376172 1.199896)
			(end -1.376172 -1.199896)
			(stroke
				(width 0.1524)
				(type default)
			)
			(layer "F.SilkS")
		)
		(fp_line
			(start -0.508 -1.199896)
			(end 0 -0.762)
			(stroke
				(width 0.1524)
				(type default)
			)
			(layer "F.SilkS")
		)
		(fp_line
			(start 0 -0.762)
			(end 0.508 -1.199896)
			(stroke
				(width 0.1524)
				(type default)
			)
			(layer "F.SilkS")
		)
		(fp_line
			(start 0.508 -1.199896)
			(end 1.376172 -1.199896)
			(stroke
				(width 0.1524)
				(type default)
			)
			(layer "F.SilkS")
		)
		(fp_line
			(start 1.376172 -1.199896)
			(end 1.376172 1.199896)
			(stroke
				(width 0.1524)
				(type default)
			)
			(layer "F.SilkS")
		)
		(fp_line
			(start 1.376172 1.199896)
			(end -1.376172 1.199896)
			(stroke
				(width 0.1524)
				(type default)
			)
			(layer "F.SilkS")
		)
		(fp_poly
			(pts
				(xy -1.493774 -1.180084) (xy -1.763268 -1.988312) (xy -2.302002 -1.449578)
			)
			(stroke
				(width 0)
				(type default)
			)
			(fill yes)
			(layer "F.SilkS")
		)
		(fp_line
			(start -0.674878 -1.100074)
			(end 0.674878 -1.100074)
			(stroke
				(width 0.1)
				(type default)
			)
			(layer "F.Fab")
		)
		(fp_line
			(start -0.674878 1.100074)
			(end -0.674878 -1.100074)
			(stroke
				(width 0.1)
				(type default)
			)
			(layer "F.Fab")
		)
		(fp_line
			(start 0.674878 -1.100074)
			(end 0.674878 1.100074)
			(stroke
				(width 0.1)
				(type default)
			)
			(layer "F.Fab")
		)
		(fp_line
			(start 0.674878 1.100074)
			(end -0.674878 1.100074)
			(stroke
				(width 0.1)
				(type default)
			)
			(layer "F.Fab")
		)
		(fp_poly
			(pts
				(xy -1.4605 -0.7493) (xy -2.2225 -1.1303) (xy -2.2225 -0.3683)
			)
			(stroke
				(width 0)
				(type default)
			)
			(fill yes)
			(layer "F.Fab")
		)
		(pad "1" smd rect
			(at -0.899922 -0.750062 270)
			(size 0.6096 0.6096)
			(layers "F.Cu" "F.Mask" "F.Paste")
			(net "GND")
		)
		(pad "2" smd rect
			(at -0.899922 0 270)
			(size 0.4064 0.6096)
			(layers "F.Cu" "F.Mask" "F.Paste")
			(net "P12V_SSD10_PG_G1")
		)
		(pad "3" smd rect
			(at -0.899922 0.750062 270)
			(size 0.6096 0.6096)
			(layers "F.Cu" "F.Mask" "F.Paste")
			(net "PWRGD_P12V_SSD10_D")
		)
		(pad "4" smd rect
			(at 0.899922 0.750062 270)
			(size 0.6096 0.6096)
			(layers "F.Cu" "F.Mask" "F.Paste")
			(net "GND")
		)
		(pad "5" smd rect
			(at 0.899922 0 270)
			(size 0.4064 0.6096)
			(layers "F.Cu" "F.Mask" "F.Paste")
			(net "P12V_SSD10_PG_G2")
		)
		(pad "6" smd rect
			(at 0.899922 -0.750062 270)
			(size 0.6096 0.6096)
			(layers "F.Cu" "F.Mask" "F.Paste")
			(net "P12V_SSD10_PG_G2")
		)
	)
	(footprint ""
		(layer "F.Cu")
		(at 304.455068 -35.876738)
		(property "Reference" "R6093"
			(at 0 0 0)
			(layer "F.SilkS")
			(hide yes)
			(effects
				(font
					(size 1.27 1.27)
				)
			)
		)
		(property "Value" ""
			(at 0 0 0)
			(layer "F.Fab")
			(effects
				(font
					(size 1.27 1.27)
				)
			)
		)
		(duplicate_pad_numbers_are_jumpers no)
		(fp_line
			(start -0.7874 -0.4064)
			(end 0.7874 -0.4064)
			(stroke
				(width 0.1524)
				(type default)
			)
			(layer "F.SilkS")
		)
		(fp_line
			(start -0.7874 0.4064)
			(end -0.7874 -0.4064)
			(stroke
				(width 0.1524)
				(type default)
			)
			(layer "F.SilkS")
		)
		(fp_line
			(start 0.7874 -0.4064)
			(end 0.7874 0.4064)
			(stroke
				(width 0.1524)
				(type default)
			)
			(layer "F.SilkS")
		)
		(fp_line
			(start 0.7874 0.4064)
			(end -0.7874 0.4064)
			(stroke
				(width 0.1524)
				(type default)
			)
			(layer "F.SilkS")
		)
		(fp_line
			(start -0.67945 -0.305054)
			(end -0.12065 -0.305054)
			(stroke
				(width 0.1)
				(type default)
			)
			(layer "F.Fab")
		)
		(fp_line
			(start -0.67945 0.3048)
			(end -0.67945 -0.305054)
			(stroke
				(width 0.1)
				(type default)
			)
			(layer "F.Fab")
		)
		(fp_line
			(start -0.12065 -0.305054)
			(end -0.12065 -0.2794)
			(stroke
				(width 0.1)
				(type default)
			)
			(layer "F.Fab")
		)
		(fp_line
			(start -0.12065 -0.2794)
			(end 0.12065 -0.2794)
			(stroke
				(width 0.1)
				(type default)
			)
			(layer "F.Fab")
		)
		(fp_line
			(start -0.12065 0.2794)
			(end -0.12065 0.3048)
			(stroke
				(width 0.1)
				(type default)
			)
			(layer "F.Fab")
		)
		(fp_line
			(start -0.12065 0.3048)
			(end -0.67945 0.3048)
			(stroke
				(width 0.1)
				(type default)
			)
			(layer "F.Fab")
		)
		(fp_line
			(start 0.120396 0.2794)
			(end -0.12065 0.2794)
			(stroke
				(width 0.1)
				(type default)
			)
			(layer "F.Fab")
		)
		(fp_line
			(start 0.120396 0.3048)
			(end 0.120396 0.2794)
			(stroke
				(width 0.1)
				(type default)
			)
			(layer "F.Fab")
		)
		(fp_line
			(start 0.12065 -0.3048)
			(end 0.67945 -0.3048)
			(stroke
				(width 0.1)
				(type default)
			)
			(layer "F.Fab")
		)
		(fp_line
			(start 0.12065 -0.2794)
			(end 0.12065 -0.3048)
			(stroke
				(width 0.1)
				(type default)
			)
			(layer "F.Fab")
		)
		(fp_line
			(start 0.67945 -0.3048)
			(end 0.67945 0.3048)
			(stroke
				(width 0.1)
				(type default)
			)
			(layer "F.Fab")
		)
		(fp_line
			(start 0.67945 0.3048)
			(end 0.120396 0.3048)
			(stroke
				(width 0.1)
				(type default)
			)
			(layer "F.Fab")
		)
		(pad "1" smd circle
			(at -0.40005 0)
			(size 0 0)
			(layers "F.Cu" "F.Mask" "F.Paste")
			(net "P3V3_AUX")
		)
		(pad "2" smd circle
			(at 0.40005 0)
			(size 0 0)
			(layers "F.Cu" "F.Mask" "F.Paste")
			(net "PWRGD_P3V3_SSD11_D")
		)
	)
	(footprint ""
		(layer "F.Cu")
		(at 387.580632 -132.215382)
		(property "Reference" "C670"
			(at 0 0 0)
			(layer "F.SilkS")
			(hide yes)
			(effects
				(font
					(size 1.27 1.27)
				)
			)
		)
		(property "Value" ""
			(at 0 0 0)
			(layer "F.Fab")
			(effects
				(font
					(size 1.27 1.27)
				)
			)
		)
		(duplicate_pad_numbers_are_jumpers no)
		(fp_line
			(start -0.299974 -0.150114)
			(end 0.299974 -0.150114)
			(stroke
				(width 0.1)
				(type default)
			)
			(layer "F.Fab")
		)
		(fp_line
			(start -0.299974 0.150114)
			(end -0.299974 -0.150114)
			(stroke
				(width 0.1)
				(type default)
			)
			(layer "F.Fab")
		)
		(fp_line
			(start 0.299974 -0.150114)
			(end 0.299974 0.150114)
			(stroke
				(width 0.1)
				(type default)
			)
			(layer "F.Fab")
		)
		(fp_line
			(start 0.299974 0.150114)
			(end -0.299974 0.150114)
			(stroke
				(width 0.1)
				(type default)
			)
			(layer "F.Fab")
		)
		(pad "1" smd rect
			(at -0.2667 0)
			(size 0.3048 0.381)
			(layers "F.Cu" "F.Mask" "F.Paste")
			(net "P5E_PEX3_STN1_TX_DN<29>")
		)
		(pad "2" smd rect
			(at 0.2667 0)
			(size 0.3048 0.381)
			(layers "F.Cu" "F.Mask" "F.Paste")
			(net "P5E_PEX3_STN1_TX_C_DN<29>")
		)
	)
	(footprint ""
		(layer "F.Cu")
		(at 378.453396 -284.990032)
		(property "Reference" "L143"
			(at 0 0 0)
			(layer "F.SilkS")
			(hide yes)
			(effects
				(font
					(size 1.27 1.27)
				)
			)
		)
		(property "Value" ""
			(at 0 0 0)
			(layer "F.Fab")
			(effects
				(font
					(size 1.27 1.27)
				)
			)
		)
		(duplicate_pad_numbers_are_jumpers no)
		(fp_line
			(start -1.63576 -0.8128)
			(end -1.63576 0.8128)
			(stroke
				(width 0.1524)
				(type default)
			)
			(layer "F.SilkS")
		)
		(fp_line
			(start -1.63576 -0.8128)
			(end 1.63576 -0.8128)
			(stroke
				(width 0.1524)
				(type default)
			)
			(layer "F.SilkS")
		)
		(fp_line
			(start 1.63576 -0.8128)
			(end 1.63576 0.8128)
			(stroke
				(width 0.1524)
				(type default)
			)
			(layer "F.SilkS")
		)
		(fp_line
			(start 1.63576 0.8128)
			(end -1.63576 0.8128)
			(stroke
				(width 0.1524)
				(type default)
			)
			(layer "F.SilkS")
		)
		(fp_line
			(start -1.56083 -0.738632)
			(end -1.56083 0.7366)
			(stroke
				(width 0.1)
				(type default)
			)
			(layer "F.Fab")
		)
		(fp_line
			(start -1.56083 0.7366)
			(end -1.524 0.7366)
			(stroke
				(width 0.1)
				(type default)
			)
			(layer "F.Fab")
		)
		(fp_line
			(start -1.524 0.7366)
			(end 1.524 0.7366)
			(stroke
				(width 0.1)
				(type default)
			)
			(layer "F.Fab")
		)
		(fp_line
			(start 1.524 0.7366)
			(end 1.560576 0.7366)
			(stroke
				(width 0.1)
				(type default)
			)
			(layer "F.Fab")
		)
		(fp_line
			(start 1.560576 -0.738632)
			(end -1.56083 -0.738632)
			(stroke
				(width 0.1)
				(type default)
			)
			(layer "F.Fab")
		)
		(fp_line
			(start 1.560576 0.7366)
			(end 1.560576 -0.738632)
			(stroke
				(width 0.1)
				(type default)
			)
			(layer "F.Fab")
		)
		(pad "1" smd rect
			(at -0.94996 0 180)
			(size 1.1176 1.3716)
			(layers "F.Cu" "F.Mask" "F.Paste")
			(net "P1V8_PLL0_PEX3")
		)
		(pad "2" smd rect
			(at 0.94996 0 180)
			(size 1.1176 1.3716)
			(layers "F.Cu" "F.Mask" "F.Paste")
			(net "PCEPLL7_VDDA18_PEX3")
		)
	)
	(footprint ""
		(layer "F.Cu")
		(at 171.979844 -139.6492)
		(property "Reference" "R109"
			(at 0 0 0)
			(layer "F.SilkS")
			(hide yes)
			(effects
				(font
					(size 1.27 1.27)
				)
			)
		)
		(property "Value" ""
			(at 0 0 0)
			(layer "F.Fab")
			(effects
				(font
					(size 1.27 1.27)
				)
			)
		)
		(duplicate_pad_numbers_are_jumpers no)
		(fp_line
			(start -0.7874 -0.4064)
			(end 0.7874 -0.4064)
			(stroke
				(width 0.1524)
				(type default)
			)
			(layer "F.SilkS")
		)
		(fp_line
			(start -0.7874 0.4064)
			(end -0.7874 -0.4064)
			(stroke
				(width 0.1524)
				(type default)
			)
			(layer "F.SilkS")
		)
		(fp_line
			(start 0.7874 -0.4064)
			(end 0.7874 0.4064)
			(stroke
				(width 0.1524)
				(type default)
			)
			(layer "F.SilkS")
		)
		(fp_line
			(start 0.7874 0.4064)
			(end -0.7874 0.4064)
			(stroke
				(width 0.1524)
				(type default)
			)
			(layer "F.SilkS")
		)
		(fp_line
			(start -0.67945 -0.305054)
			(end -0.12065 -0.305054)
			(stroke
				(width 0.1)
				(type default)
			)
			(layer "F.Fab")
		)
		(fp_line
			(start -0.67945 0.3048)
			(end -0.67945 -0.305054)
			(stroke
				(width 0.1)
				(type default)
			)
			(layer "F.Fab")
		)
		(fp_line
			(start -0.12065 -0.305054)
			(end -0.12065 -0.2794)
			(stroke
				(width 0.1)
				(type default)
			)
			(layer "F.Fab")
		)
		(fp_line
			(start -0.12065 -0.2794)
			(end 0.12065 -0.2794)
			(stroke
				(width 0.1)
				(type default)
			)
			(layer "F.Fab")
		)
		(fp_line
			(start -0.12065 0.2794)
			(end -0.12065 0.3048)
			(stroke
				(width 0.1)
				(type default)
			)
			(layer "F.Fab")
		)
		(fp_line
			(start -0.12065 0.3048)
			(end -0.67945 0.3048)
			(stroke
				(width 0.1)
				(type default)
			)
			(layer "F.Fab")
		)
		(fp_line
			(start 0.120396 0.2794)
			(end -0.12065 0.2794)
			(stroke
				(width 0.1)
				(type default)
			)
			(layer "F.Fab")
		)
		(fp_line
			(start 0.120396 0.3048)
			(end 0.120396 0.2794)
			(stroke
				(width 0.1)
				(type default)
			)
			(layer "F.Fab")
		)
		(fp_line
			(start 0.12065 -0.3048)
			(end 0.67945 -0.3048)
			(stroke
				(width 0.1)
				(type default)
			)
			(layer "F.Fab")
		)
		(fp_line
			(start 0.12065 -0.2794)
			(end 0.12065 -0.3048)
			(stroke
				(width 0.1)
				(type default)
			)
			(layer "F.Fab")
		)
		(fp_line
			(start 0.67945 -0.3048)
			(end 0.67945 0.3048)
			(stroke
				(width 0.1)
				(type default)
			)
			(layer "F.Fab")
		)
		(fp_line
			(start 0.67945 0.3048)
			(end 0.120396 0.3048)
			(stroke
				(width 0.1)
				(type default)
			)
			(layer "F.Fab")
		)
		(pad "1" smd circle
			(at -0.40005 0)
			(size 0 0)
			(layers "F.Cu" "F.Mask" "F.Paste")
			(net "PRSNTB2_NIC2_N")
		)
		(pad "2" smd circle
			(at 0.40005 0)
			(size 0 0)
			(layers "F.Cu" "F.Mask" "F.Paste")
			(net "P3V3_AUX")
		)
	)
	(footprint ""
		(layer "F.Cu")
		(at 334.130396 -120.79224)
		(property "Reference" "R6039"
			(at 0 0 0)
			(layer "F.SilkS")
			(hide yes)
			(effects
				(font
					(size 1.27 1.27)
				)
			)
		)
		(property "Value" ""
			(at 0 0 0)
			(layer "F.Fab")
			(effects
				(font
					(size 1.27 1.27)
				)
			)
		)
		(duplicate_pad_numbers_are_jumpers no)
		(fp_line
			(start -0.7874 -0.4064)
			(end 0.7874 -0.4064)
			(stroke
				(width 0.1524)
				(type default)
			)
			(layer "F.SilkS")
		)
		(fp_line
			(start -0.7874 0.4064)
			(end -0.7874 -0.4064)
			(stroke
				(width 0.1524)
				(type default)
			)
			(layer "F.SilkS")
		)
		(fp_line
			(start 0.7874 -0.4064)
			(end 0.7874 0.4064)
			(stroke
				(width 0.1524)
				(type default)
			)
			(layer "F.SilkS")
		)
		(fp_line
			(start 0.7874 0.4064)
			(end -0.7874 0.4064)
			(stroke
				(width 0.1524)
				(type default)
			)
			(layer "F.SilkS")
		)
		(fp_line
			(start -0.67945 -0.305054)
			(end -0.12065 -0.305054)
			(stroke
				(width 0.1)
				(type default)
			)
			(layer "F.Fab")
		)
		(fp_line
			(start -0.67945 0.3048)
			(end -0.67945 -0.305054)
			(stroke
				(width 0.1)
				(type default)
			)
			(layer "F.Fab")
		)
		(fp_line
			(start -0.12065 -0.305054)
			(end -0.12065 -0.2794)
			(stroke
				(width 0.1)
				(type default)
			)
			(layer "F.Fab")
		)
		(fp_line
			(start -0.12065 -0.2794)
			(end 0.12065 -0.2794)
			(stroke
				(width 0.1)
				(type default)
			)
			(layer "F.Fab")
		)
		(fp_line
			(start -0.12065 0.2794)
			(end -0.12065 0.3048)
			(stroke
				(width 0.1)
				(type default)
			)
			(layer "F.Fab")
		)
		(fp_line
			(start -0.12065 0.3048)
			(end -0.67945 0.3048)
			(stroke
				(width 0.1)
				(type default)
			)
			(layer "F.Fab")
		)
		(fp_line
			(start 0.120396 0.2794)
			(end -0.12065 0.2794)
			(stroke
				(width 0.1)
				(type default)
			)
			(layer "F.Fab")
		)
		(fp_line
			(start 0.120396 0.3048)
			(end 0.120396 0.2794)
			(stroke
				(width 0.1)
				(type default)
			)
			(layer "F.Fab")
		)
		(fp_line
			(start 0.12065 -0.3048)
			(end 0.67945 -0.3048)
			(stroke
				(width 0.1)
				(type default)
			)
			(layer "F.Fab")
		)
		(fp_line
			(start 0.12065 -0.2794)
			(end 0.12065 -0.3048)
			(stroke
				(width 0.1)
				(type default)
			)
			(layer "F.Fab")
		)
		(fp_line
			(start 0.67945 -0.3048)
			(end 0.67945 0.3048)
			(stroke
				(width 0.1)
				(type default)
			)
			(layer "F.Fab")
		)
		(fp_line
			(start 0.67945 0.3048)
			(end 0.120396 0.3048)
			(stroke
				(width 0.1)
				(type default)
			)
			(layer "F.Fab")
		)
		(pad "1" smd circle
			(at -0.40005 0)
			(size 0 0)
			(layers "F.Cu" "F.Mask" "F.Paste")
			(net "P3V3_NIC5")
		)
		(pad "2" smd circle
			(at 0.40005 0)
			(size 0 0)
			(layers "F.Cu" "F.Mask" "F.Paste")
			(net "P3V3_NIC5_PG_G1")
		)
	)
	(footprint ""
		(layer "F.Cu")
		(at 8.211058 -61.386974)
		(property "Reference" "R4482"
			(at 0 0 0)
			(layer "F.SilkS")
			(hide yes)
			(effects
				(font
					(size 1.27 1.27)
				)
			)
		)
		(property "Value" ""
			(at 0 0 0)
			(layer "F.Fab")
			(effects
				(font
					(size 1.27 1.27)
				)
			)
		)
		(duplicate_pad_numbers_are_jumpers no)
		(fp_line
			(start -0.7874 -0.4064)
			(end 0.7874 -0.4064)
			(stroke
				(width 0.1524)
				(type default)
			)
			(layer "F.SilkS")
		)
		(fp_line
			(start -0.7874 0.4064)
			(end -0.7874 -0.4064)
			(stroke
				(width 0.1524)
				(type default)
			)
			(layer "F.SilkS")
		)
		(fp_line
			(start 0.7874 -0.4064)
			(end 0.7874 0.4064)
			(stroke
				(width 0.1524)
				(type default)
			)
			(layer "F.SilkS")
		)
		(fp_line
			(start 0.7874 0.4064)
			(end -0.7874 0.4064)
			(stroke
				(width 0.1524)
				(type default)
			)
			(layer "F.SilkS")
		)
		(fp_line
			(start -0.67945 -0.305054)
			(end -0.12065 -0.305054)
			(stroke
				(width 0.1)
				(type default)
			)
			(layer "F.Fab")
		)
		(fp_line
			(start -0.67945 0.3048)
			(end -0.67945 -0.305054)
			(stroke
				(width 0.1)
				(type default)
			)
			(layer "F.Fab")
		)
		(fp_line
			(start -0.12065 -0.305054)
			(end -0.12065 -0.2794)
			(stroke
				(width 0.1)
				(type default)
			)
			(layer "F.Fab")
		)
		(fp_line
			(start -0.12065 -0.2794)
			(end 0.12065 -0.2794)
			(stroke
				(width 0.1)
				(type default)
			)
			(layer "F.Fab")
		)
		(fp_line
			(start -0.12065 0.2794)
			(end -0.12065 0.3048)
			(stroke
				(width 0.1)
				(type default)
			)
			(layer "F.Fab")
		)
		(fp_line
			(start -0.12065 0.3048)
			(end -0.67945 0.3048)
			(stroke
				(width 0.1)
				(type default)
			)
			(layer "F.Fab")
		)
		(fp_line
			(start 0.120396 0.2794)
			(end -0.12065 0.2794)
			(stroke
				(width 0.1)
				(type default)
			)
			(layer "F.Fab")
		)
		(fp_line
			(start 0.120396 0.3048)
			(end 0.120396 0.2794)
			(stroke
				(width 0.1)
				(type default)
			)
			(layer "F.Fab")
		)
		(fp_line
			(start 0.12065 -0.3048)
			(end 0.67945 -0.3048)
			(stroke
				(width 0.1)
				(type default)
			)
			(layer "F.Fab")
		)
		(fp_line
			(start 0.12065 -0.2794)
			(end 0.12065 -0.3048)
			(stroke
				(width 0.1)
				(type default)
			)
			(layer "F.Fab")
		)
		(fp_line
			(start 0.67945 -0.3048)
			(end 0.67945 0.3048)
			(stroke
				(width 0.1)
				(type default)
			)
			(layer "F.Fab")
		)
		(fp_line
			(start 0.67945 0.3048)
			(end 0.120396 0.3048)
			(stroke
				(width 0.1)
				(type default)
			)
			(layer "F.Fab")
		)
		(pad "1" smd circle
			(at -0.40005 0)
			(size 0 0)
			(layers "F.Cu" "F.Mask" "F.Paste")
			(net "PWRGD_P3V3_SSD0")
		)
		(pad "2" smd circle
			(at 0.40005 0)
			(size 0 0)
			(layers "F.Cu" "F.Mask" "F.Paste")
			(net "PWRGD_P3V3_SSD0_R")
		)
	)
	(footprint ""
		(layer "F.Cu")
		(at 169.759884 -193.836798)
		(property "Reference" "R3290"
			(at 0 0 0)
			(layer "F.SilkS")
			(hide yes)
			(effects
				(font
					(size 1.27 1.27)
				)
			)
		)
		(property "Value" ""
			(at 0 0 0)
			(layer "F.Fab")
			(effects
				(font
					(size 1.27 1.27)
				)
			)
		)
		(duplicate_pad_numbers_are_jumpers no)
		(fp_line
			(start -0.7874 -0.4064)
			(end 0.7874 -0.4064)
			(stroke
				(width 0.1524)
				(type default)
			)
			(layer "F.SilkS")
		)
		(fp_line
			(start -0.7874 0.4064)
			(end -0.7874 -0.4064)
			(stroke
				(width 0.1524)
				(type default)
			)
			(layer "F.SilkS")
		)
		(fp_line
			(start 0.7874 -0.4064)
			(end 0.7874 0.4064)
			(stroke
				(width 0.1524)
				(type default)
			)
			(layer "F.SilkS")
		)
		(fp_line
			(start 0.7874 0.4064)
			(end -0.7874 0.4064)
			(stroke
				(width 0.1524)
				(type default)
			)
			(layer "F.SilkS")
		)
		(fp_line
			(start -0.67945 -0.305054)
			(end -0.12065 -0.305054)
			(stroke
				(width 0.1)
				(type default)
			)
			(layer "F.Fab")
		)
		(fp_line
			(start -0.67945 0.3048)
			(end -0.67945 -0.305054)
			(stroke
				(width 0.1)
				(type default)
			)
			(layer "F.Fab")
		)
		(fp_line
			(start -0.12065 -0.305054)
			(end -0.12065 -0.2794)
			(stroke
				(width 0.1)
				(type default)
			)
			(layer "F.Fab")
		)
		(fp_line
			(start -0.12065 -0.2794)
			(end 0.12065 -0.2794)
			(stroke
				(width 0.1)
				(type default)
			)
			(layer "F.Fab")
		)
		(fp_line
			(start -0.12065 0.2794)
			(end -0.12065 0.3048)
			(stroke
				(width 0.1)
				(type default)
			)
			(layer "F.Fab")
		)
		(fp_line
			(start -0.12065 0.3048)
			(end -0.67945 0.3048)
			(stroke
				(width 0.1)
				(type default)
			)
			(layer "F.Fab")
		)
		(fp_line
			(start 0.120396 0.2794)
			(end -0.12065 0.2794)
			(stroke
				(width 0.1)
				(type default)
			)
			(layer "F.Fab")
		)
		(fp_line
			(start 0.120396 0.3048)
			(end 0.120396 0.2794)
			(stroke
				(width 0.1)
				(type default)
			)
			(layer "F.Fab")
		)
		(fp_line
			(start 0.12065 -0.3048)
			(end 0.67945 -0.3048)
			(stroke
				(width 0.1)
				(type default)
			)
			(layer "F.Fab")
		)
		(fp_line
			(start 0.12065 -0.2794)
			(end 0.12065 -0.3048)
			(stroke
				(width 0.1)
				(type default)
			)
			(layer "F.Fab")
		)
		(fp_line
			(start 0.67945 -0.3048)
			(end 0.67945 0.3048)
			(stroke
				(width 0.1)
				(type default)
			)
			(layer "F.Fab")
		)
		(fp_line
			(start 0.67945 0.3048)
			(end 0.120396 0.3048)
			(stroke
				(width 0.1)
				(type default)
			)
			(layer "F.Fab")
		)
		(pad "1" smd circle
			(at -0.40005 0)
			(size 0 0)
			(layers "F.Cu" "F.Mask" "F.Paste")
			(net "SPI_BIC1_MISO_LS01_R")
		)
		(pad "2" smd circle
			(at 0.40005 0)
			(size 0 0)
			(layers "F.Cu" "F.Mask" "F.Paste")
			(net "SPI_BIC1_MISO_LS01")
		)
	)
	(footprint ""
		(layer "F.Cu")
		(at 449.956428 -20.467574 180)
		(property "Reference" "R1734"
			(at 0 0 180)
			(layer "F.SilkS")
			(hide yes)
			(effects
				(font
					(size 1.27 1.27)
				)
			)
		)
		(property "Value" ""
			(at 0 0 180)
			(layer "F.Fab")
			(effects
				(font
					(size 1.27 1.27)
				)
			)
		)
		(duplicate_pad_numbers_are_jumpers no)
		(fp_line
			(start 0.7874 0.4064)
			(end -0.7874 0.4064)
			(stroke
				(width 0.1524)
				(type default)
			)
			(layer "F.SilkS")
		)
		(fp_line
			(start 0.7874 -0.4064)
			(end 0.7874 0.4064)
			(stroke
				(width 0.1524)
				(type default)
			)
			(layer "F.SilkS")
		)
		(fp_line
			(start -0.7874 0.4064)
			(end -0.7874 -0.4064)
			(stroke
				(width 0.1524)
				(type default)
			)
			(layer "F.SilkS")
		)
		(fp_line
			(start -0.7874 -0.4064)
			(end 0.7874 -0.4064)
			(stroke
				(width 0.1524)
				(type default)
			)
			(layer "F.SilkS")
		)
		(fp_line
			(start 0.67945 0.3048)
			(end 0.120396 0.3048)
			(stroke
				(width 0.1)
				(type default)
			)
			(layer "F.Fab")
		)
		(fp_line
			(start 0.67945 -0.3048)
			(end 0.67945 0.3048)
			(stroke
				(width 0.1)
				(type default)
			)
			(layer "F.Fab")
		)
		(fp_line
			(start 0.12065 -0.2794)
			(end 0.12065 -0.3048)
			(stroke
				(width 0.1)
				(type default)
			)
			(layer "F.Fab")
		)
		(fp_line
			(start 0.12065 -0.3048)
			(end 0.67945 -0.3048)
			(stroke
				(width 0.1)
				(type default)
			)
			(layer "F.Fab")
		)
		(fp_line
			(start 0.120396 0.3048)
			(end 0.120396 0.2794)
			(stroke
				(width 0.1)
				(type default)
			)
			(layer "F.Fab")
		)
		(fp_line
			(start 0.120396 0.2794)
			(end -0.12065 0.2794)
			(stroke
				(width 0.1)
				(type default)
			)
			(layer "F.Fab")
		)
		(fp_line
			(start -0.12065 0.3048)
			(end -0.67945 0.3048)
			(stroke
				(width 0.1)
				(type default)
			)
			(layer "F.Fab")
		)
		(fp_line
			(start -0.12065 0.2794)
			(end -0.12065 0.3048)
			(stroke
				(width 0.1)
				(type default)
			)
			(layer "F.Fab")
		)
		(fp_line
			(start -0.12065 -0.2794)
			(end 0.12065 -0.2794)
			(stroke
				(width 0.1)
				(type default)
			)
			(layer "F.Fab")
		)
		(fp_line
			(start -0.12065 -0.305054)
			(end -0.12065 -0.2794)
			(stroke
				(width 0.1)
				(type default)
			)
			(layer "F.Fab")
		)
		(fp_line
			(start -0.67945 0.3048)
			(end -0.67945 -0.305054)
			(stroke
				(width 0.1)
				(type default)
			)
			(layer "F.Fab")
		)
		(fp_line
			(start -0.67945 -0.305054)
			(end -0.12065 -0.305054)
			(stroke
				(width 0.1)
				(type default)
			)
			(layer "F.Fab")
		)
		(pad "1" smd circle
			(at -0.40005 0 180)
			(size 0 0)
			(layers "F.Cu" "F.Mask" "F.Paste")
			(net "P3V3_SSD15")
		)
		(pad "2" smd circle
			(at 0.40005 0 180)
			(size 0 0)
			(layers "F.Cu" "F.Mask" "F.Paste")
			(net "SMB_ISO_SSD15_SDA")
		)
	)
	(footprint ""
		(layer "F.Cu")
		(at 120.473978 -27.006296 -90)
		(property "Reference" "PC924"
			(at 0 0 270)
			(layer "F.SilkS")
			(hide yes)
			(effects
				(font
					(size 1.27 1.27)
				)
			)
		)
		(property "Value" ""
			(at 0 0 270)
			(layer "F.Fab")
			(effects
				(font
					(size 1.27 1.27)
				)
			)
		)
		(duplicate_pad_numbers_are_jumpers no)
		(fp_line
			(start -0.7874 0.4064)
			(end -0.7874 -0.4064)
			(stroke
				(width 0.1524)
				(type default)
			)
			(layer "F.SilkS")
		)
		(fp_line
			(start 0.7874 0.4064)
			(end -0.7874 0.4064)
			(stroke
				(width 0.1524)
				(type default)
			)
			(layer "F.SilkS")
		)
		(fp_line
			(start -0.7874 -0.4064)
			(end 0.7874 -0.4064)
			(stroke
				(width 0.1524)
				(type default)
			)
			(layer "F.SilkS")
		)
		(fp_line
			(start 0.7874 -0.4064)
			(end 0.7874 0.4064)
			(stroke
				(width 0.1524)
				(type default)
			)
			(layer "F.SilkS")
		)
		(fp_line
			(start -0.67945 0.3048)
			(end -0.67945 -0.305054)
			(stroke
				(width 0.1)
				(type default)
			)
			(layer "F.Fab")
		)
		(fp_line
			(start -0.12065 0.3048)
			(end -0.67945 0.3048)
			(stroke
				(width 0.1)
				(type default)
			)
			(layer "F.Fab")
		)
		(fp_line
			(start 0.120396 0.3048)
			(end 0.120396 0.2794)
			(stroke
				(width 0.1)
				(type default)
			)
			(layer "F.Fab")
		)
		(fp_line
			(start 0.67945 0.3048)
			(end 0.120396 0.3048)
			(stroke
				(width 0.1)
				(type default)
			)
			(layer "F.Fab")
		)
		(fp_line
			(start -0.12065 0.2794)
			(end -0.12065 0.3048)
			(stroke
				(width 0.1)
				(type default)
			)
			(layer "F.Fab")
		)
		(fp_line
			(start 0.120396 0.2794)
			(end -0.12065 0.2794)
			(stroke
				(width 0.1)
				(type default)
			)
			(layer "F.Fab")
		)
		(fp_line
			(start -0.12065 -0.2794)
			(end 0.12065 -0.2794)
			(stroke
				(width 0.1)
				(type default)
			)
			(layer "F.Fab")
		)
		(fp_line
			(start 0.12065 -0.2794)
			(end 0.12065 -0.3048)
			(stroke
				(width 0.1)
				(type default)
			)
			(layer "F.Fab")
		)
		(fp_line
			(start 0.12065 -0.3048)
			(end 0.67945 -0.3048)
			(stroke
				(width 0.1)
				(type default)
			)
			(layer "F.Fab")
		)
		(fp_line
			(start 0.67945 -0.3048)
			(end 0.67945 0.3048)
			(stroke
				(width 0.1)
				(type default)
			)
			(layer "F.Fab")
		)
		(fp_line
			(start -0.67945 -0.305054)
			(end -0.12065 -0.305054)
			(stroke
				(width 0.1)
				(type default)
			)
			(layer "F.Fab")
		)
		(fp_line
			(start -0.12065 -0.305054)
			(end -0.12065 -0.2794)
			(stroke
				(width 0.1)
				(type default)
			)
			(layer "F.Fab")
		)
		(pad "1" smd circle
			(at -0.40005 0 270)
			(size 0 0)
			(layers "F.Cu" "F.Mask" "F.Paste")
			(net "P3V3_SSD4_CO_MODE")
		)
		(pad "2" smd circle
			(at 0.40005 0 270)
			(size 0 0)
			(layers "F.Cu" "F.Mask" "F.Paste")
			(net "GND")
		)
	)
	(footprint ""
		(layer "F.Cu")
		(at 133.599428 -356.244906 90)
		(property "Reference" "C2267"
			(at 0 0 90)
			(layer "F.SilkS")
			(hide yes)
			(effects
				(font
					(size 1.27 1.27)
				)
			)
		)
		(property "Value" ""
			(at 0 0 90)
			(layer "F.Fab")
			(effects
				(font
					(size 1.27 1.27)
				)
			)
		)
		(duplicate_pad_numbers_are_jumpers no)
		(fp_line
			(start 0.299974 -0.150114)
			(end 0.299974 0.150114)
			(stroke
				(width 0.1)
				(type default)
			)
			(layer "F.Fab")
		)
		(fp_line
			(start -0.299974 -0.150114)
			(end 0.299974 -0.150114)
			(stroke
				(width 0.1)
				(type default)
			)
			(layer "F.Fab")
		)
		(fp_line
			(start 0.299974 0.150114)
			(end -0.299974 0.150114)
			(stroke
				(width 0.1)
				(type default)
			)
			(layer "F.Fab")
		)
		(fp_line
			(start -0.299974 0.150114)
			(end -0.299974 -0.150114)
			(stroke
				(width 0.1)
				(type default)
			)
			(layer "F.Fab")
		)
		(pad "1" smd rect
			(at -0.2667 0 90)
			(size 0.3048 0.381)
			(layers "F.Cu" "F.Mask" "F.Paste")
			(net "P5E_PEX1_STN5_TX_DP<83>")
		)
		(pad "2" smd rect
			(at 0.2667 0 90)
			(size 0.3048 0.381)
			(layers "F.Cu" "F.Mask" "F.Paste")
			(net "P5E_PEX1_STN5_TX_C_DP<83>")
		)
	)
	(footprint ""
		(layer "F.Cu")
		(at 421.8305 -66.32194 -90)
		(property "Reference" "PC895"
			(at 0 0 270)
			(layer "F.SilkS")
			(hide yes)
			(effects
				(font
					(size 1.27 1.27)
				)
			)
		)
		(property "Value" ""
			(at 0 0 270)
			(layer "F.Fab")
			(effects
				(font
					(size 1.27 1.27)
				)
			)
		)
		(duplicate_pad_numbers_are_jumpers no)
		(fp_line
			(start -0.7874 0.4064)
			(end -0.7874 -0.4064)
			(stroke
				(width 0.1524)
				(type default)
			)
			(layer "F.SilkS")
		)
		(fp_line
			(start 0.7874 0.4064)
			(end -0.7874 0.4064)
			(stroke
				(width 0.1524)
				(type default)
			)
			(layer "F.SilkS")
		)
		(fp_line
			(start -0.7874 -0.4064)
			(end 0.7874 -0.4064)
			(stroke
				(width 0.1524)
				(type default)
			)
			(layer "F.SilkS")
		)
		(fp_line
			(start 0.7874 -0.4064)
			(end 0.7874 0.4064)
			(stroke
				(width 0.1524)
				(type default)
			)
			(layer "F.SilkS")
		)
		(fp_line
			(start -0.67945 0.3048)
			(end -0.67945 -0.305054)
			(stroke
				(width 0.1)
				(type default)
			)
			(layer "F.Fab")
		)
		(fp_line
			(start -0.12065 0.3048)
			(end -0.67945 0.3048)
			(stroke
				(width 0.1)
				(type default)
			)
			(layer "F.Fab")
		)
		(fp_line
			(start 0.120396 0.3048)
			(end 0.120396 0.2794)
			(stroke
				(width 0.1)
				(type default)
			)
			(layer "F.Fab")
		)
		(fp_line
			(start 0.67945 0.3048)
			(end 0.120396 0.3048)
			(stroke
				(width 0.1)
				(type default)
			)
			(layer "F.Fab")
		)
		(fp_line
			(start -0.12065 0.2794)
			(end -0.12065 0.3048)
			(stroke
				(width 0.1)
				(type default)
			)
			(layer "F.Fab")
		)
		(fp_line
			(start 0.120396 0.2794)
			(end -0.12065 0.2794)
			(stroke
				(width 0.1)
				(type default)
			)
			(layer "F.Fab")
		)
		(fp_line
			(start -0.12065 -0.2794)
			(end 0.12065 -0.2794)
			(stroke
				(width 0.1)
				(type default)
			)
			(layer "F.Fab")
		)
		(fp_line
			(start 0.12065 -0.2794)
			(end 0.12065 -0.3048)
			(stroke
				(width 0.1)
				(type default)
			)
			(layer "F.Fab")
		)
		(fp_line
			(start 0.12065 -0.3048)
			(end 0.67945 -0.3048)
			(stroke
				(width 0.1)
				(type default)
			)
			(layer "F.Fab")
		)
		(fp_line
			(start 0.67945 -0.3048)
			(end 0.67945 0.3048)
			(stroke
				(width 0.1)
				(type default)
			)
			(layer "F.Fab")
		)
		(fp_line
			(start -0.67945 -0.305054)
			(end -0.12065 -0.305054)
			(stroke
				(width 0.1)
				(type default)
			)
			(layer "F.Fab")
		)
		(fp_line
			(start -0.12065 -0.305054)
			(end -0.12065 -0.2794)
			(stroke
				(width 0.1)
				(type default)
			)
			(layer "F.Fab")
		)
		(pad "1" smd circle
			(at -0.40005 0 270)
			(size 0 0)
			(layers "F.Cu" "F.Mask" "F.Paste")
			(net "P12V_SSD14_CO_DV_DT")
		)
		(pad "2" smd circle
			(at 0.40005 0 270)
			(size 0 0)
			(layers "F.Cu" "F.Mask" "F.Paste")
			(net "GND")
		)
	)
	(footprint ""
		(layer "F.Cu")
		(at 331.131164 -343.952322 90)
		(property "Reference" "C567"
			(at 0 0 90)
			(layer "F.SilkS")
			(hide yes)
			(effects
				(font
					(size 1.27 1.27)
				)
			)
		)
		(property "Value" ""
			(at 0 0 90)
			(layer "F.Fab")
			(effects
				(font
					(size 1.27 1.27)
				)
			)
		)
		(duplicate_pad_numbers_are_jumpers no)
		(fp_line
			(start 0.299974 -0.150114)
			(end 0.299974 0.150114)
			(stroke
				(width 0.1)
				(type default)
			)
			(layer "F.Fab")
		)
		(fp_line
			(start -0.299974 -0.150114)
			(end 0.299974 -0.150114)
			(stroke
				(width 0.1)
				(type default)
			)
			(layer "F.Fab")
		)
		(fp_line
			(start 0.299974 0.150114)
			(end -0.299974 0.150114)
			(stroke
				(width 0.1)
				(type default)
			)
			(layer "F.Fab")
		)
		(fp_line
			(start -0.299974 0.150114)
			(end -0.299974 -0.150114)
			(stroke
				(width 0.1)
				(type default)
			)
			(layer "F.Fab")
		)
		(pad "1" smd rect
			(at -0.2667 0 90)
			(size 0.3048 0.381)
			(layers "F.Cu" "F.Mask" "F.Paste")
			(net "P5E_PEX2_STN6_TX_DP<103>")
		)
		(pad "2" smd rect
			(at 0.2667 0 90)
			(size 0.3048 0.381)
			(layers "F.Cu" "F.Mask" "F.Paste")
			(net "P5E_PEX2_STN6_TX_C_DP<103>")
		)
	)
	(footprint ""
		(layer "F.Cu")
		(at 208.638648 -121.528332 90)
		(property "Reference" "PC488"
			(at 0 0 90)
			(layer "F.SilkS")
			(hide yes)
			(effects
				(font
					(size 1.27 1.27)
				)
			)
		)
		(property "Value" ""
			(at 0 0 90)
			(layer "F.Fab")
			(effects
				(font
					(size 1.27 1.27)
				)
			)
		)
		(duplicate_pad_numbers_are_jumpers no)
		(fp_line
			(start 0.7874 -0.4064)
			(end 0.7874 0.4064)
			(stroke
				(width 0.1524)
				(type default)
			)
			(layer "F.SilkS")
		)
		(fp_line
			(start -0.7874 -0.4064)
			(end 0.7874 -0.4064)
			(stroke
				(width 0.1524)
				(type default)
			)
			(layer "F.SilkS")
		)
		(fp_line
			(start 0.7874 0.4064)
			(end -0.7874 0.4064)
			(stroke
				(width 0.1524)
				(type default)
			)
			(layer "F.SilkS")
		)
		(fp_line
			(start -0.7874 0.4064)
			(end -0.7874 -0.4064)
			(stroke
				(width 0.1524)
				(type default)
			)
			(layer "F.SilkS")
		)
		(fp_line
			(start -0.12065 -0.305054)
			(end -0.12065 -0.2794)
			(stroke
				(width 0.1)
				(type default)
			)
			(layer "F.Fab")
		)
		(fp_line
			(start -0.67945 -0.305054)
			(end -0.12065 -0.305054)
			(stroke
				(width 0.1)
				(type default)
			)
			(layer "F.Fab")
		)
		(fp_line
			(start 0.67945 -0.3048)
			(end 0.67945 0.3048)
			(stroke
				(width 0.1)
				(type default)
			)
			(layer "F.Fab")
		)
		(fp_line
			(start 0.12065 -0.3048)
			(end 0.67945 -0.3048)
			(stroke
				(width 0.1)
				(type default)
			)
			(layer "F.Fab")
		)
		(fp_line
			(start 0.12065 -0.2794)
			(end 0.12065 -0.3048)
			(stroke
				(width 0.1)
				(type default)
			)
			(layer "F.Fab")
		)
		(fp_line
			(start -0.12065 -0.2794)
			(end 0.12065 -0.2794)
			(stroke
				(width 0.1)
				(type default)
			)
			(layer "F.Fab")
		)
		(fp_line
			(start 0.120396 0.2794)
			(end -0.12065 0.2794)
			(stroke
				(width 0.1)
				(type default)
			)
			(layer "F.Fab")
		)
		(fp_line
			(start -0.12065 0.2794)
			(end -0.12065 0.3048)
			(stroke
				(width 0.1)
				(type default)
			)
			(layer "F.Fab")
		)
		(fp_line
			(start 0.67945 0.3048)
			(end 0.120396 0.3048)
			(stroke
				(width 0.1)
				(type default)
			)
			(layer "F.Fab")
		)
		(fp_line
			(start 0.120396 0.3048)
			(end 0.120396 0.2794)
			(stroke
				(width 0.1)
				(type default)
			)
			(layer "F.Fab")
		)
		(fp_line
			(start -0.12065 0.3048)
			(end -0.67945 0.3048)
			(stroke
				(width 0.1)
				(type default)
			)
			(layer "F.Fab")
		)
		(fp_line
			(start -0.67945 0.3048)
			(end -0.67945 -0.305054)
			(stroke
				(width 0.1)
				(type default)
			)
			(layer "F.Fab")
		)
		(pad "1" smd circle
			(at -0.40005 0 90)
			(size 0 0)
			(layers "F.Cu" "F.Mask" "F.Paste")
			(net "P3V3_NIC3")
		)
		(pad "2" smd circle
			(at 0.40005 0 90)
			(size 0 0)
			(layers "F.Cu" "F.Mask" "F.Paste")
			(net "GND")
		)
	)
	(footprint ""
		(layer "F.Cu")
		(at 342.214962 -17.999964)
		(property "Reference" "H54"
			(at -4.629912 -4.985512 0)
			(unlocked yes)
			(layer "F.SilkS")
			(effects
				(font
					(size 0.7874 0.5842)
					(thickness 0.1524)
				)
				(justify left)
			)
		)
		(property "Value" ""
			(at 0 0 0)
			(layer "F.Fab")
			(effects
				(font
					(size 1.27 1.27)
				)
			)
		)
		(duplicate_pad_numbers_are_jumpers no)
		(pad "1" thru_hole circle
			(at 0 0)
			(size 10.0076 10.0076)
			(drill 5.6134)
			(layers "*.Cu" "*.Mask")
			(remove_unused_layers no)
			(net "GND")
			(clearance -1.9431)
		)
	)
	(footprint ""
		(layer "F.Cu")
		(at 89.005156 -298.87291 -90)
		(property "Reference" "R3885"
			(at 0 0 270)
			(layer "F.SilkS")
			(hide yes)
			(effects
				(font
					(size 1.27 1.27)
				)
			)
		)
		(property "Value" ""
			(at 0 0 270)
			(layer "F.Fab")
			(effects
				(font
					(size 1.27 1.27)
				)
			)
		)
		(duplicate_pad_numbers_are_jumpers no)
		(fp_line
			(start -0.7874 0.4064)
			(end -0.7874 -0.4064)
			(stroke
				(width 0.1524)
				(type default)
			)
			(layer "F.SilkS")
		)
		(fp_line
			(start 0.7874 0.4064)
			(end -0.7874 0.4064)
			(stroke
				(width 0.1524)
				(type default)
			)
			(layer "F.SilkS")
		)
		(fp_line
			(start -0.7874 -0.4064)
			(end 0.7874 -0.4064)
			(stroke
				(width 0.1524)
				(type default)
			)
			(layer "F.SilkS")
		)
		(fp_line
			(start 0.7874 -0.4064)
			(end 0.7874 0.4064)
			(stroke
				(width 0.1524)
				(type default)
			)
			(layer "F.SilkS")
		)
		(fp_line
			(start -0.67945 0.3048)
			(end -0.67945 -0.305054)
			(stroke
				(width 0.1)
				(type default)
			)
			(layer "F.Fab")
		)
		(fp_line
			(start -0.12065 0.3048)
			(end -0.67945 0.3048)
			(stroke
				(width 0.1)
				(type default)
			)
			(layer "F.Fab")
		)
		(fp_line
			(start 0.120396 0.3048)
			(end 0.120396 0.2794)
			(stroke
				(width 0.1)
				(type default)
			)
			(layer "F.Fab")
		)
		(fp_line
			(start 0.67945 0.3048)
			(end 0.120396 0.3048)
			(stroke
				(width 0.1)
				(type default)
			)
			(layer "F.Fab")
		)
		(fp_line
			(start -0.12065 0.2794)
			(end -0.12065 0.3048)
			(stroke
				(width 0.1)
				(type default)
			)
			(layer "F.Fab")
		)
		(fp_line
			(start 0.120396 0.2794)
			(end -0.12065 0.2794)
			(stroke
				(width 0.1)
				(type default)
			)
			(layer "F.Fab")
		)
		(fp_line
			(start -0.12065 -0.2794)
			(end 0.12065 -0.2794)
			(stroke
				(width 0.1)
				(type default)
			)
			(layer "F.Fab")
		)
		(fp_line
			(start 0.12065 -0.2794)
			(end 0.12065 -0.3048)
			(stroke
				(width 0.1)
				(type default)
			)
			(layer "F.Fab")
		)
		(fp_line
			(start 0.12065 -0.3048)
			(end 0.67945 -0.3048)
			(stroke
				(width 0.1)
				(type default)
			)
			(layer "F.Fab")
		)
		(fp_line
			(start 0.67945 -0.3048)
			(end 0.67945 0.3048)
			(stroke
				(width 0.1)
				(type default)
			)
			(layer "F.Fab")
		)
		(fp_line
			(start -0.67945 -0.305054)
			(end -0.12065 -0.305054)
			(stroke
				(width 0.1)
				(type default)
			)
			(layer "F.Fab")
		)
		(fp_line
			(start -0.12065 -0.305054)
			(end -0.12065 -0.2794)
			(stroke
				(width 0.1)
				(type default)
			)
			(layer "F.Fab")
		)
		(pad "1" smd circle
			(at -0.40005 0 270)
			(size 0 0)
			(layers "F.Cu" "F.Mask" "F.Paste")
			(net "I2C_PEX0_HOST_SDA")
		)
		(pad "2" smd circle
			(at 0.40005 0 270)
			(size 0 0)
			(layers "F.Cu" "F.Mask" "F.Paste")
			(net "I2C_PEX0_HOST_R_SDA")
		)
	)
	(footprint ""
		(layer "F.Cu")
		(at 19.062446 -212.631528 90)
		(property "Reference" "R6567"
			(at 0 0 90)
			(layer "F.SilkS")
			(hide yes)
			(effects
				(font
					(size 1.27 1.27)
				)
			)
		)
		(property "Value" ""
			(at 0 0 90)
			(layer "F.Fab")
			(effects
				(font
					(size 1.27 1.27)
				)
			)
		)
		(duplicate_pad_numbers_are_jumpers no)
		(fp_line
			(start 0.7874 -0.4064)
			(end 0.7874 0.4064)
			(stroke
				(width 0.1524)
				(type default)
			)
			(layer "F.SilkS")
		)
		(fp_line
			(start -0.7874 -0.4064)
			(end 0.7874 -0.4064)
			(stroke
				(width 0.1524)
				(type default)
			)
			(layer "F.SilkS")
		)
		(fp_line
			(start 0.7874 0.4064)
			(end -0.7874 0.4064)
			(stroke
				(width 0.1524)
				(type default)
			)
			(layer "F.SilkS")
		)
		(fp_line
			(start -0.7874 0.4064)
			(end -0.7874 -0.4064)
			(stroke
				(width 0.1524)
				(type default)
			)
			(layer "F.SilkS")
		)
		(fp_line
			(start -0.12065 -0.305054)
			(end -0.12065 -0.2794)
			(stroke
				(width 0.1)
				(type default)
			)
			(layer "F.Fab")
		)
		(fp_line
			(start -0.67945 -0.305054)
			(end -0.12065 -0.305054)
			(stroke
				(width 0.1)
				(type default)
			)
			(layer "F.Fab")
		)
		(fp_line
			(start 0.67945 -0.3048)
			(end 0.67945 0.3048)
			(stroke
				(width 0.1)
				(type default)
			)
			(layer "F.Fab")
		)
		(fp_line
			(start 0.12065 -0.3048)
			(end 0.67945 -0.3048)
			(stroke
				(width 0.1)
				(type default)
			)
			(layer "F.Fab")
		)
		(fp_line
			(start 0.12065 -0.2794)
			(end 0.12065 -0.3048)
			(stroke
				(width 0.1)
				(type default)
			)
			(layer "F.Fab")
		)
		(fp_line
			(start -0.12065 -0.2794)
			(end 0.12065 -0.2794)
			(stroke
				(width 0.1)
				(type default)
			)
			(layer "F.Fab")
		)
		(fp_line
			(start 0.120396 0.2794)
			(end -0.12065 0.2794)
			(stroke
				(width 0.1)
				(type default)
			)
			(layer "F.Fab")
		)
		(fp_line
			(start -0.12065 0.2794)
			(end -0.12065 0.3048)
			(stroke
				(width 0.1)
				(type default)
			)
			(layer "F.Fab")
		)
		(fp_line
			(start 0.67945 0.3048)
			(end 0.120396 0.3048)
			(stroke
				(width 0.1)
				(type default)
			)
			(layer "F.Fab")
		)
		(fp_line
			(start 0.120396 0.3048)
			(end 0.120396 0.2794)
			(stroke
				(width 0.1)
				(type default)
			)
			(layer "F.Fab")
		)
		(fp_line
			(start -0.12065 0.3048)
			(end -0.67945 0.3048)
			(stroke
				(width 0.1)
				(type default)
			)
			(layer "F.Fab")
		)
		(fp_line
			(start -0.67945 0.3048)
			(end -0.67945 -0.305054)
			(stroke
				(width 0.1)
				(type default)
			)
			(layer "F.Fab")
		)
		(pad "1" smd circle
			(at -0.40005 0 90)
			(size 0 0)
			(layers "F.Cu" "F.Mask" "F.Paste")
			(net "P1V8_PLL_PEX0_ADJ")
		)
		(pad "2" smd circle
			(at 0.40005 0 90)
			(size 0 0)
			(layers "F.Cu" "F.Mask" "F.Paste")
			(net "GND")
		)
	)
	(footprint ""
		(layer "F.Cu")
		(at 353.889564 -63.56223)
		(property "Reference" "Q208"
			(at 2.523236 -1.9177 0)
			(unlocked yes)
			(layer "F.SilkS")
			(effects
				(font
					(size 0.7874 0.5842)
					(thickness 0.1524)
				)
			)
		)
		(property "Value" ""
			(at 0 0 0)
			(layer "F.Fab")
			(effects
				(font
					(size 1.27 1.27)
				)
			)
		)
		(duplicate_pad_numbers_are_jumpers no)
		(fp_line
			(start -1.376172 -1.199896)
			(end -0.508 -1.199896)
			(stroke
				(width 0.1524)
				(type default)
			)
			(layer "F.SilkS")
		)
		(fp_line
			(start -1.376172 1.199896)
			(end -1.376172 -1.199896)
			(stroke
				(width 0.1524)
				(type default)
			)
			(layer "F.SilkS")
		)
		(fp_line
			(start -0.508 -1.199896)
			(end 0 -0.762)
			(stroke
				(width 0.1524)
				(type default)
			)
			(layer "F.SilkS")
		)
		(fp_line
			(start 0 -0.762)
			(end 0.508 -1.199896)
			(stroke
				(width 0.1524)
				(type default)
			)
			(layer "F.SilkS")
		)
		(fp_line
			(start 0.508 -1.199896)
			(end 1.376172 -1.199896)
			(stroke
				(width 0.1524)
				(type default)
			)
			(layer "F.SilkS")
		)
		(fp_line
			(start 1.376172 -1.199896)
			(end 1.376172 1.199896)
			(stroke
				(width 0.1524)
				(type default)
			)
			(layer "F.SilkS")
		)
		(fp_line
			(start 1.376172 1.199896)
			(end -1.376172 1.199896)
			(stroke
				(width 0.1524)
				(type default)
			)
			(layer "F.SilkS")
		)
		(fp_poly
			(pts
				(xy -1.421638 -0.804164) (xy -1.691132 -1.612392) (xy -2.229866 -1.073658)
			)
			(stroke
				(width 0)
				(type default)
			)
			(fill yes)
			(layer "F.SilkS")
		)
		(fp_line
			(start -0.674878 -1.100074)
			(end 0.674878 -1.100074)
			(stroke
				(width 0.1)
				(type default)
			)
			(layer "F.Fab")
		)
		(fp_line
			(start -0.674878 1.100074)
			(end -0.674878 -1.100074)
			(stroke
				(width 0.1)
				(type default)
			)
			(layer "F.Fab")
		)
		(fp_line
			(start 0.674878 -1.100074)
			(end 0.674878 1.100074)
			(stroke
				(width 0.1)
				(type default)
			)
			(layer "F.Fab")
		)
		(fp_line
			(start 0.674878 1.100074)
			(end -0.674878 1.100074)
			(stroke
				(width 0.1)
				(type default)
			)
			(layer "F.Fab")
		)
		(fp_poly
			(pts
				(xy -1.4605 -0.7493) (xy -2.2225 -1.1303) (xy -2.2225 -0.3683)
			)
			(stroke
				(width 0)
				(type default)
			)
			(fill yes)
			(layer "F.Fab")
		)
		(pad "1" smd rect
			(at -0.899922 -0.750062 270)
			(size 0.6096 0.6096)
			(layers "F.Cu" "F.Mask" "F.Paste")
			(net "GND")
		)
		(pad "2" smd rect
			(at -0.899922 0 270)
			(size 0.4064 0.6096)
			(layers "F.Cu" "F.Mask" "F.Paste")
			(net "P12V_SSD12_PG_G1")
		)
		(pad "3" smd rect
			(at -0.899922 0.750062 270)
			(size 0.6096 0.6096)
			(layers "F.Cu" "F.Mask" "F.Paste")
			(net "PWRGD_P12V_SSD12_D")
		)
		(pad "4" smd rect
			(at 0.899922 0.750062 270)
			(size 0.6096 0.6096)
			(layers "F.Cu" "F.Mask" "F.Paste")
			(net "GND")
		)
		(pad "5" smd rect
			(at 0.899922 0 270)
			(size 0.4064 0.6096)
			(layers "F.Cu" "F.Mask" "F.Paste")
			(net "P12V_SSD12_PG_G2")
		)
		(pad "6" smd rect
			(at 0.899922 -0.750062 270)
			(size 0.6096 0.6096)
			(layers "F.Cu" "F.Mask" "F.Paste")
			(net "P12V_SSD12_PG_G2")
		)
	)
	(footprint ""
		(layer "F.Cu")
		(at 11.593322 -116.311426 -90)
		(property "Reference" "Q212"
			(at 0.030226 1.990852 90)
			(unlocked yes)
			(layer "F.SilkS")
			(effects
				(font
					(size 0.7874 0.5842)
					(thickness 0.1524)
				)
			)
		)
		(property "Value" ""
			(at 0 0 270)
			(layer "F.Fab")
			(effects
				(font
					(size 1.27 1.27)
				)
			)
		)
		(duplicate_pad_numbers_are_jumpers no)
		(fp_line
			(start -1.376172 1.199896)
			(end -1.376172 -1.199896)
			(stroke
				(width 0.1524)
				(type default)
			)
			(layer "F.SilkS")
		)
		(fp_line
			(start 1.376172 1.199896)
			(end -1.376172 1.199896)
			(stroke
				(width 0.1524)
				(type default)
			)
			(layer "F.SilkS")
		)
		(fp_line
			(start 0 -0.762)
			(end 0.508 -1.199896)
			(stroke
				(width 0.1524)
				(type default)
			)
			(layer "F.SilkS")
		)
		(fp_line
			(start -1.376172 -1.199896)
			(end -0.508 -1.199896)
			(stroke
				(width 0.1524)
				(type default)
			)
			(layer "F.SilkS")
		)
		(fp_line
			(start -0.508 -1.199896)
			(end 0 -0.762)
			(stroke
				(width 0.1524)
				(type default)
			)
			(layer "F.SilkS")
		)
		(fp_line
			(start 0.508 -1.199896)
			(end 1.376172 -1.199896)
			(stroke
				(width 0.1524)
				(type default)
			)
			(layer "F.SilkS")
		)
		(fp_line
			(start 1.376172 -1.199896)
			(end 1.376172 1.199896)
			(stroke
				(width 0.1524)
				(type default)
			)
			(layer "F.SilkS")
		)
		(fp_poly
			(pts
				(xy -1.141984 -1.262126) (xy -1.411478 -2.070354) (xy -1.950212 -1.531366)
			)
			(stroke
				(width 0)
				(type default)
			)
			(fill yes)
			(layer "F.SilkS")
		)
		(fp_line
			(start -0.674878 1.100074)
			(end -0.674878 -1.100074)
			(stroke
				(width 0.1)
				(type default)
			)
			(layer "F.Fab")
		)
		(fp_line
			(start 0.674878 1.100074)
			(end -0.674878 1.100074)
			(stroke
				(width 0.1)
				(type default)
			)
			(layer "F.Fab")
		)
		(fp_line
			(start -0.674878 -1.100074)
			(end 0.674878 -1.100074)
			(stroke
				(width 0.1)
				(type default)
			)
			(layer "F.Fab")
		)
		(fp_line
			(start 0.674878 -1.100074)
			(end 0.674878 1.100074)
			(stroke
				(width 0.1)
				(type default)
			)
			(layer "F.Fab")
		)
		(fp_poly
			(pts
				(xy -1.4605 -0.7493) (xy -2.2225 -1.1303) (xy -2.2225 -0.3683)
			)
			(stroke
				(width 0)
				(type default)
			)
			(fill yes)
			(layer "F.Fab")
		)
		(pad "1" smd rect
			(at -0.899922 -0.750062 180)
			(size 0.6096 0.6096)
			(layers "F.Cu" "F.Mask" "F.Paste")
			(net "GND")
		)
		(pad "2" smd rect
			(at -0.899922 0 180)
			(size 0.4064 0.6096)
			(layers "F.Cu" "F.Mask" "F.Paste")
			(net "P3V3_NIC0_PG_G1")
		)
		(pad "3" smd rect
			(at -0.899922 0.750062 180)
			(size 0.6096 0.6096)
			(layers "F.Cu" "F.Mask" "F.Paste")
			(net "PWRGD_P3V3_NIC0_D")
		)
		(pad "4" smd rect
			(at 0.899922 0.750062 180)
			(size 0.6096 0.6096)
			(layers "F.Cu" "F.Mask" "F.Paste")
			(net "GND")
		)
		(pad "5" smd rect
			(at 0.899922 0 180)
			(size 0.4064 0.6096)
			(layers "F.Cu" "F.Mask" "F.Paste")
			(net "P3V3_NIC0_PG_G2")
		)
		(pad "6" smd rect
			(at 0.899922 -0.750062 180)
			(size 0.6096 0.6096)
			(layers "F.Cu" "F.Mask" "F.Paste")
			(net "P3V3_NIC0_PG_G2")
		)
	)
	(footprint ""
		(layer "F.Cu")
		(at 361.745784 -114.385852 -90)
		(property "Reference" "PC909"
			(at 0 0 270)
			(layer "F.SilkS")
			(hide yes)
			(effects
				(font
					(size 1.27 1.27)
				)
			)
		)
		(property "Value" ""
			(at 0 0 270)
			(layer "F.Fab")
			(effects
				(font
					(size 1.27 1.27)
				)
			)
		)
		(duplicate_pad_numbers_are_jumpers no)
		(fp_line
			(start -0.7874 0.4064)
			(end -0.7874 -0.4064)
			(stroke
				(width 0.1524)
				(type default)
			)
			(layer "F.SilkS")
		)
		(fp_line
			(start 0.7874 0.4064)
			(end -0.7874 0.4064)
			(stroke
				(width 0.1524)
				(type default)
			)
			(layer "F.SilkS")
		)
		(fp_line
			(start -0.7874 -0.4064)
			(end 0.7874 -0.4064)
			(stroke
				(width 0.1524)
				(type default)
			)
			(layer "F.SilkS")
		)
		(fp_line
			(start 0.7874 -0.4064)
			(end 0.7874 0.4064)
			(stroke
				(width 0.1524)
				(type default)
			)
			(layer "F.SilkS")
		)
		(fp_line
			(start -0.67945 0.3048)
			(end -0.67945 -0.305054)
			(stroke
				(width 0.1)
				(type default)
			)
			(layer "F.Fab")
		)
		(fp_line
			(start -0.12065 0.3048)
			(end -0.67945 0.3048)
			(stroke
				(width 0.1)
				(type default)
			)
			(layer "F.Fab")
		)
		(fp_line
			(start 0.120396 0.3048)
			(end 0.120396 0.2794)
			(stroke
				(width 0.1)
				(type default)
			)
			(layer "F.Fab")
		)
		(fp_line
			(start 0.67945 0.3048)
			(end 0.120396 0.3048)
			(stroke
				(width 0.1)
				(type default)
			)
			(layer "F.Fab")
		)
		(fp_line
			(start -0.12065 0.2794)
			(end -0.12065 0.3048)
			(stroke
				(width 0.1)
				(type default)
			)
			(layer "F.Fab")
		)
		(fp_line
			(start 0.120396 0.2794)
			(end -0.12065 0.2794)
			(stroke
				(width 0.1)
				(type default)
			)
			(layer "F.Fab")
		)
		(fp_line
			(start -0.12065 -0.2794)
			(end 0.12065 -0.2794)
			(stroke
				(width 0.1)
				(type default)
			)
			(layer "F.Fab")
		)
		(fp_line
			(start 0.12065 -0.2794)
			(end 0.12065 -0.3048)
			(stroke
				(width 0.1)
				(type default)
			)
			(layer "F.Fab")
		)
		(fp_line
			(start 0.12065 -0.3048)
			(end 0.67945 -0.3048)
			(stroke
				(width 0.1)
				(type default)
			)
			(layer "F.Fab")
		)
		(fp_line
			(start 0.67945 -0.3048)
			(end 0.67945 0.3048)
			(stroke
				(width 0.1)
				(type default)
			)
			(layer "F.Fab")
		)
		(fp_line
			(start -0.67945 -0.305054)
			(end -0.12065 -0.305054)
			(stroke
				(width 0.1)
				(type default)
			)
			(layer "F.Fab")
		)
		(fp_line
			(start -0.12065 -0.305054)
			(end -0.12065 -0.2794)
			(stroke
				(width 0.1)
				(type default)
			)
			(layer "F.Fab")
		)
		(pad "1" smd circle
			(at -0.40005 0 270)
			(size 0 0)
			(layers "F.Cu" "F.Mask" "F.Paste")
			(net "P3V3_AUX")
		)
		(pad "2" smd circle
			(at 0.40005 0 270)
			(size 0 0)
			(layers "F.Cu" "F.Mask" "F.Paste")
			(net "GND")
		)
	)
	(footprint ""
		(layer "F.Cu")
		(at 19.352006 -408.505152 90)
		(property "Reference" "U328"
			(at -3.6576 -3.190748 90)
			(unlocked yes)
			(layer "F.SilkS")
			(effects
				(font
					(size 0.7874 0.5842)
					(thickness 0.1524)
				)
				(justify left)
			)
		)
		(property "Value" ""
			(at 0 0 90)
			(layer "F.Fab")
			(effects
				(font
					(size 1.27 1.27)
				)
			)
		)
		(duplicate_pad_numbers_are_jumpers no)
		(fp_line
			(start 3.447796 -2.500122)
			(end 1.484122 -2.500122)
			(stroke
				(width 0.1524)
				(type default)
			)
			(layer "F.SilkS")
		)
		(fp_line
			(start 1.484122 -2.500122)
			(end 0 -1.016)
			(stroke
				(width 0.1524)
				(type default)
			)
			(layer "F.SilkS")
		)
		(fp_line
			(start -1.484122 -2.500122)
			(end -3.447796 -2.500122)
			(stroke
				(width 0.1524)
				(type default)
			)
			(layer "F.SilkS")
		)
		(fp_line
			(start -3.447796 -2.500122)
			(end -3.447796 2.500122)
			(stroke
				(width 0.1524)
				(type default)
			)
			(layer "F.SilkS")
		)
		(fp_line
			(start 0 -1.016)
			(end -1.484122 -2.500122)
			(stroke
				(width 0.1524)
				(type default)
			)
			(layer "F.SilkS")
		)
		(fp_line
			(start 3.447796 2.500122)
			(end 3.447796 -2.500122)
			(stroke
				(width 0.1524)
				(type default)
			)
			(layer "F.SilkS")
		)
		(fp_line
			(start -3.447796 2.500122)
			(end 3.447796 2.500122)
			(stroke
				(width 0.1524)
				(type default)
			)
			(layer "F.SilkS")
		)
		(fp_poly
			(pts
				(xy -4.088892 -3.269234) (xy -4.807204 -2.550922) (xy -3.729736 -2.191766)
			)
			(stroke
				(width 0)
				(type default)
			)
			(fill yes)
			(layer "F.SilkS")
		)
		(fp_line
			(start 1.999996 -2.500122)
			(end -1.999996 -2.500122)
			(stroke
				(width 0.1)
				(type default)
			)
			(layer "F.Fab")
		)
		(fp_line
			(start -1.999996 -2.500122)
			(end -1.999996 2.500122)
			(stroke
				(width 0.1)
				(type default)
			)
			(layer "F.Fab")
		)
		(fp_line
			(start 1.999996 2.500122)
			(end 1.999996 -2.500122)
			(stroke
				(width 0.1)
				(type default)
			)
			(layer "F.Fab")
		)
		(fp_line
			(start -1.999996 2.500122)
			(end 1.999996 2.500122)
			(stroke
				(width 0.1)
				(type default)
			)
			(layer "F.Fab")
		)
		(fp_poly
			(pts
				(xy -4.5974 -2.413) (xy -4.5974 -1.397) (xy -3.5814 -1.905)
			)
			(stroke
				(width 0)
				(type default)
			)
			(fill yes)
			(layer "F.Fab")
		)
		(pad "1" smd rect
			(at -2.649982 -1.905)
			(size 0.6096 1.3208)
			(layers "F.Cu" "F.Mask" "F.Paste")
			(net "SMB_LM75_0_SDA")
		)
		(pad "2" smd rect
			(at -2.649982 -0.635)
			(size 0.6096 1.3208)
			(layers "F.Cu" "F.Mask" "F.Paste")
			(net "SMB_LM75_0_SCL")
		)
		(pad "3" smd rect
			(at -2.649982 0.635)
			(size 0.6096 1.3208)
			(layers "F.Cu" "F.Mask" "F.Paste")
			(net "Net_405")
		)
		(pad "4" smd rect
			(at -2.649982 1.905)
			(size 0.6096 1.3208)
			(layers "F.Cu" "F.Mask" "F.Paste")
			(net "GND")
		)
		(pad "5" smd rect
			(at 2.649982 1.905)
			(size 0.6096 1.3208)
			(layers "F.Cu" "F.Mask" "F.Paste")
			(net "LM75_0_A2")
		)
		(pad "6" smd rect
			(at 2.649982 0.635)
			(size 0.6096 1.3208)
			(layers "F.Cu" "F.Mask" "F.Paste")
			(net "LM75_0_A1")
		)
		(pad "7" smd rect
			(at 2.649982 -0.635)
			(size 0.6096 1.3208)
			(layers "F.Cu" "F.Mask" "F.Paste")
			(net "LM75_0_A0")
		)
		(pad "8" smd rect
			(at 2.649982 -1.905)
			(size 0.6096 1.3208)
			(layers "F.Cu" "F.Mask" "F.Paste")
			(net "P3V3_AUX")
		)
	)
	(footprint ""
		(layer "F.Cu")
		(at 90.0176 -304.036476 90)
		(property "Reference" "R1248"
			(at 0 0 90)
			(layer "F.SilkS")
			(hide yes)
			(effects
				(font
					(size 1.27 1.27)
				)
			)
		)
		(property "Value" ""
			(at 0 0 90)
			(layer "F.Fab")
			(effects
				(font
					(size 1.27 1.27)
				)
			)
		)
		(duplicate_pad_numbers_are_jumpers no)
		(fp_line
			(start 0.7874 -0.4064)
			(end 0.7874 0.4064)
			(stroke
				(width 0.1524)
				(type default)
			)
			(layer "F.SilkS")
		)
		(fp_line
			(start -0.7874 -0.4064)
			(end 0.7874 -0.4064)
			(stroke
				(width 0.1524)
				(type default)
			)
			(layer "F.SilkS")
		)
		(fp_line
			(start 0.7874 0.4064)
			(end -0.7874 0.4064)
			(stroke
				(width 0.1524)
				(type default)
			)
			(layer "F.SilkS")
		)
		(fp_line
			(start -0.7874 0.4064)
			(end -0.7874 -0.4064)
			(stroke
				(width 0.1524)
				(type default)
			)
			(layer "F.SilkS")
		)
		(fp_line
			(start -0.12065 -0.305054)
			(end -0.12065 -0.2794)
			(stroke
				(width 0.1)
				(type default)
			)
			(layer "F.Fab")
		)
		(fp_line
			(start -0.67945 -0.305054)
			(end -0.12065 -0.305054)
			(stroke
				(width 0.1)
				(type default)
			)
			(layer "F.Fab")
		)
		(fp_line
			(start 0.67945 -0.3048)
			(end 0.67945 0.3048)
			(stroke
				(width 0.1)
				(type default)
			)
			(layer "F.Fab")
		)
		(fp_line
			(start 0.12065 -0.3048)
			(end 0.67945 -0.3048)
			(stroke
				(width 0.1)
				(type default)
			)
			(layer "F.Fab")
		)
		(fp_line
			(start 0.12065 -0.2794)
			(end 0.12065 -0.3048)
			(stroke
				(width 0.1)
				(type default)
			)
			(layer "F.Fab")
		)
		(fp_line
			(start -0.12065 -0.2794)
			(end 0.12065 -0.2794)
			(stroke
				(width 0.1)
				(type default)
			)
			(layer "F.Fab")
		)
		(fp_line
			(start 0.120396 0.2794)
			(end -0.12065 0.2794)
			(stroke
				(width 0.1)
				(type default)
			)
			(layer "F.Fab")
		)
		(fp_line
			(start -0.12065 0.2794)
			(end -0.12065 0.3048)
			(stroke
				(width 0.1)
				(type default)
			)
			(layer "F.Fab")
		)
		(fp_line
			(start 0.67945 0.3048)
			(end 0.120396 0.3048)
			(stroke
				(width 0.1)
				(type default)
			)
			(layer "F.Fab")
		)
		(fp_line
			(start 0.120396 0.3048)
			(end 0.120396 0.2794)
			(stroke
				(width 0.1)
				(type default)
			)
			(layer "F.Fab")
		)
		(fp_line
			(start -0.12065 0.3048)
			(end -0.67945 0.3048)
			(stroke
				(width 0.1)
				(type default)
			)
			(layer "F.Fab")
		)
		(fp_line
			(start -0.67945 0.3048)
			(end -0.67945 -0.305054)
			(stroke
				(width 0.1)
				(type default)
			)
			(layer "F.Fab")
		)
		(pad "1" smd circle
			(at -0.40005 0 90)
			(size 0 0)
			(layers "F.Cu" "F.Mask" "F.Paste")
			(net "GND")
		)
		(pad "2" smd circle
			(at 0.40005 0 90)
			(size 0 0)
			(layers "F.Cu" "F.Mask" "F.Paste")
			(net "PEX0_SPARE3")
		)
	)
	(footprint ""
		(layer "F.Cu")
		(at 130.791204 -284.8991 180)
		(property "Reference" "PU10"
			(at -9.227566 -1.164082 90)
			(unlocked yes)
			(layer "F.SilkS")
			(effects
				(font
					(size 0.7874 0.5842)
					(thickness 0.1524)
				)
			)
		)
		(property "Value" ""
			(at 0 0 180)
			(layer "F.Fab")
			(effects
				(font
					(size 1.27 1.27)
				)
			)
		)
		(duplicate_pad_numbers_are_jumpers no)
		(fp_line
			(start 2.500122 2.999994)
			(end 2.2987 2.999994)
			(stroke
				(width 0.1524)
				(type default)
			)
			(layer "F.SilkS")
		)
		(fp_line
			(start 2.500122 2.339594)
			(end 2.500122 2.999994)
			(stroke
				(width 0.1524)
				(type default)
			)
			(layer "F.SilkS")
		)
		(fp_line
			(start 2.500122 -2.999994)
			(end 2.500122 -2.44348)
			(stroke
				(width 0.1524)
				(type default)
			)
			(layer "F.SilkS")
		)
		(fp_line
			(start 2.31394 -2.999994)
			(end 2.500122 -2.999994)
			(stroke
				(width 0.1524)
				(type default)
			)
			(layer "F.SilkS")
		)
		(fp_line
			(start -2.2987 2.999994)
			(end -2.500122 2.999994)
			(stroke
				(width 0.1524)
				(type default)
			)
			(layer "F.SilkS")
		)
		(fp_line
			(start -2.500122 2.999994)
			(end -2.500122 2.339594)
			(stroke
				(width 0.1524)
				(type default)
			)
			(layer "F.SilkS")
		)
		(fp_line
			(start -2.500122 0.6604)
			(end -2.500122 0.229108)
			(stroke
				(width 0.1524)
				(type default)
			)
			(layer "F.SilkS")
		)
		(fp_line
			(start -2.500122 -2.529078)
			(end -2.500122 -2.999994)
			(stroke
				(width 0.1524)
				(type default)
			)
			(layer "F.SilkS")
		)
		(fp_line
			(start -2.500122 -2.999994)
			(end -2.24409 -2.999994)
			(stroke
				(width 0.1524)
				(type default)
			)
			(layer "F.SilkS")
		)
		(fp_poly
			(pts
				(xy -2.129282 -3.790442) (xy -3.145028 -3.790442) (xy -2.637282 -2.774442)
			)
			(stroke
				(width 0)
				(type default)
			)
			(fill yes)
			(layer "F.SilkS")
		)
		(fp_line
			(start 2.500122 2.999994)
			(end -2.500122 2.999994)
			(stroke
				(width 0.1)
				(type default)
			)
			(layer "F.Fab")
		)
		(fp_line
			(start 2.500122 -2.999994)
			(end 2.500122 2.999994)
			(stroke
				(width 0.1)
				(type default)
			)
			(layer "F.Fab")
		)
		(fp_line
			(start -2.500122 2.999994)
			(end -2.500122 -2.999994)
			(stroke
				(width 0.1)
				(type default)
			)
			(layer "F.Fab")
		)
		(fp_line
			(start -2.500122 -2.999994)
			(end 2.500122 -2.999994)
			(stroke
				(width 0.1)
				(type default)
			)
			(layer "F.Fab")
		)
		(fp_poly
			(pts
				(xy -4.218432 -2.783078) (xy -4.218432 -1.767078) (xy -3.202432 -2.275078)
			)
			(stroke
				(width 0)
				(type default)
			)
			(fill yes)
			(layer "F.Fab")
		)
		(pad "1" smd rect
			(at -2.400046 -2.275078 270)
			(size 0.2286 0.6096)
			(layers "F.Cu" "F.Mask" "F.Paste")
			(net "SW_P0V8_PEX1_VOS2")
		)
		(pad "2" smd rect
			(at -2.400046 -1.82499 270)
			(size 0.2286 0.6096)
			(layers "F.Cu" "F.Mask" "F.Paste")
			(net "GND")
		)
		(pad "3" smd rect
			(at -2.400046 -1.374902 270)
			(size 0.2286 0.6096)
			(layers "F.Cu" "F.Mask" "F.Paste")
			(net "P0V8_PEX1_VCC2")
		)
		(pad "4" smd rect
			(at -2.400046 -0.925068 270)
			(size 0.2286 0.6096)
			(layers "F.Cu" "F.Mask" "F.Paste")
			(net "P0V8_PEX1_PVCC")
		)
		(pad "5" smd rect
			(at -2.400046 -0.47498 270)
			(size 0.2286 0.6096)
			(layers "F.Cu" "F.Mask" "F.Paste")
			(net "GND")
		)
		(pad "6" smd rect
			(at -2.400046 -0.024892 270)
			(size 0.2286 0.6096)
			(layers "F.Cu" "F.Mask" "F.Paste")
			(net "NC_P0V8_PEX1_PH2_NC1")
		)
		(pad "7_9-20_24" smd circle
			(at 0 1.150112 270)
			(size 0 0)
			(layers "F.Cu" "F.Mask" "F.Paste")
			(net "GND")
		)
		(pad "10_19" smd rect
			(at 0 2.899918 270)
			(size 0.6096 4.318)
			(layers "F.Cu" "F.Mask" "F.Paste")
			(net "SW_P0V8_PEX1_PH2")
		)
		(pad "25_29" smd rect
			(at 1.549908 -1.279906 90)
			(size 2.0574 2.3114)
			(layers "F.Cu" "F.Mask" "F.Paste")
			(net "SW_P12V_P0V8_PEX1_FLT")
		)
		(pad "30" smd rect
			(at 2.05994 -2.899918 180)
			(size 0.2286 0.6096)
			(layers "F.Cu" "F.Mask" "F.Paste")
			(net "SW_P12V_P0V8_PEX1_FLT")
		)
		(pad "31" smd rect
			(at 1.610106 -2.899918 180)
			(size 0.2286 0.6096)
			(layers "F.Cu" "F.Mask" "F.Paste")
			(net "NC_P0V8_PEX1_PH2_NC3")
		)
		(pad "32" smd rect
			(at 1.160018 -2.899918 180)
			(size 0.2286 0.6096)
			(layers "F.Cu" "F.Mask" "F.Paste")
			(net "SW_P0V8_PEX1_PHASE2")
		)
		(pad "33" smd rect
			(at 0.70993 -2.899918 180)
			(size 0.2286 0.6096)
			(layers "F.Cu" "F.Mask" "F.Paste")
			(net "SW_P0V8_PEX1_BOOT2")
		)
		(pad "34" smd rect
			(at 0.260096 -2.899918 180)
			(size 0.2286 0.6096)
			(layers "F.Cu" "F.Mask" "F.Paste")
			(net "P0V8_PEX1_PWM2")
		)
		(pad "35" smd rect
			(at -0.189992 -2.899918 180)
			(size 0.2286 0.6096)
			(layers "F.Cu" "F.Mask" "F.Paste")
			(net "P0V8_PEX0_EN4")
		)
		(pad "36" smd rect
			(at -0.64008 -2.899918 180)
			(size 0.2286 0.6096)
			(layers "F.Cu" "F.Mask" "F.Paste")
			(net "P0V8_PEX1_TSEN")
		)
		(pad "37" smd rect
			(at -1.089914 -2.899918 180)
			(size 0.2286 0.6096)
			(layers "F.Cu" "F.Mask" "F.Paste")
			(net "P0V8_PEX1_LSET2")
		)
		(pad "38" smd rect
			(at -1.540002 -2.899918 180)
			(size 0.2286 0.6096)
			(layers "F.Cu" "F.Mask" "F.Paste")
			(net "P0V8_PEX1_ISEN2")
		)
		(pad "39" smd rect
			(at -1.99009 -2.899918 180)
			(size 0.2286 0.6096)
			(layers "F.Cu" "F.Mask" "F.Paste")
			(net "P0V8_PEX0_VREF")
		)
		(pad "40" smd rect
			(at -0.87503 -1.27508 180)
			(size 1.7526 1.9558)
			(layers "F.Cu" "F.Mask" "F.Paste")
			(net "GND")
		)
		(pad "41" smd rect
			(at -1.525016 0.249936 90)
			(size 0.3048 0.4572)
			(layers "F.Cu" "F.Mask" "F.Paste")
			(net "NC_P0V8_PEX1_PH2_NC2")
		)
		(zone
			(layer "F.Cu")
			(hatch none 0.5)
			(connect_pads
				(clearance 0)
			)
			(min_thickness 0.25)
			(keepout
				(tracks not_allowed)
				(vias allowed)
				(pads allowed)
				(copperpour not_allowed)
				(footprints allowed)
			)
			(placement
				(enabled no)
				(sheetname "")
			)
			(fill
				(thermal_gap 0.5)
				(thermal_bridge_width 0.5)
				(island_removal_mode 0)
			)
			(polygon
				(pts
					(xy 133.291326 -287.899094) (xy 133.291326 -287.149794) (xy 128.291082 -287.149794) (xy 128.291082 -287.899094)
					(xy 128.581404 -287.899094) (xy 128.581404 -287.443418) (xy 133.001004 -287.443418) (xy 133.001004 -287.899094)
				)
			)
		)
	)
	(footprint ""
		(layer "F.Cu")
		(at 134.181596 -293.816786 -90)
		(property "Reference" "PC116"
			(at 0 0 270)
			(layer "F.SilkS")
			(hide yes)
			(effects
				(font
					(size 1.27 1.27)
				)
			)
		)
		(property "Value" ""
			(at 0 0 270)
			(layer "F.Fab")
			(effects
				(font
					(size 1.27 1.27)
				)
			)
		)
		(duplicate_pad_numbers_are_jumpers no)
		(fp_line
			(start -0.7874 0.4064)
			(end -0.7874 -0.4064)
			(stroke
				(width 0.1524)
				(type default)
			)
			(layer "F.SilkS")
		)
		(fp_line
			(start 0.7874 0.4064)
			(end -0.7874 0.4064)
			(stroke
				(width 0.1524)
				(type default)
			)
			(layer "F.SilkS")
		)
		(fp_line
			(start -0.7874 -0.4064)
			(end 0.7874 -0.4064)
			(stroke
				(width 0.1524)
				(type default)
			)
			(layer "F.SilkS")
		)
		(fp_line
			(start 0.7874 -0.4064)
			(end 0.7874 0.4064)
			(stroke
				(width 0.1524)
				(type default)
			)
			(layer "F.SilkS")
		)
		(fp_line
			(start -0.67945 0.3048)
			(end -0.67945 -0.305054)
			(stroke
				(width 0.1)
				(type default)
			)
			(layer "F.Fab")
		)
		(fp_line
			(start -0.12065 0.3048)
			(end -0.67945 0.3048)
			(stroke
				(width 0.1)
				(type default)
			)
			(layer "F.Fab")
		)
		(fp_line
			(start 0.120396 0.3048)
			(end 0.120396 0.2794)
			(stroke
				(width 0.1)
				(type default)
			)
			(layer "F.Fab")
		)
		(fp_line
			(start 0.67945 0.3048)
			(end 0.120396 0.3048)
			(stroke
				(width 0.1)
				(type default)
			)
			(layer "F.Fab")
		)
		(fp_line
			(start -0.12065 0.2794)
			(end -0.12065 0.3048)
			(stroke
				(width 0.1)
				(type default)
			)
			(layer "F.Fab")
		)
		(fp_line
			(start 0.120396 0.2794)
			(end -0.12065 0.2794)
			(stroke
				(width 0.1)
				(type default)
			)
			(layer "F.Fab")
		)
		(fp_line
			(start -0.12065 -0.2794)
			(end 0.12065 -0.2794)
			(stroke
				(width 0.1)
				(type default)
			)
			(layer "F.Fab")
		)
		(fp_line
			(start 0.12065 -0.2794)
			(end 0.12065 -0.3048)
			(stroke
				(width 0.1)
				(type default)
			)
			(layer "F.Fab")
		)
		(fp_line
			(start 0.12065 -0.3048)
			(end 0.67945 -0.3048)
			(stroke
				(width 0.1)
				(type default)
			)
			(layer "F.Fab")
		)
		(fp_line
			(start 0.67945 -0.3048)
			(end 0.67945 0.3048)
			(stroke
				(width 0.1)
				(type default)
			)
			(layer "F.Fab")
		)
		(fp_line
			(start -0.67945 -0.305054)
			(end -0.12065 -0.305054)
			(stroke
				(width 0.1)
				(type default)
			)
			(layer "F.Fab")
		)
		(fp_line
			(start -0.12065 -0.305054)
			(end -0.12065 -0.2794)
			(stroke
				(width 0.1)
				(type default)
			)
			(layer "F.Fab")
		)
		(pad "1" smd circle
			(at -0.40005 0 270)
			(size 0 0)
			(layers "F.Cu" "F.Mask" "F.Paste")
			(net "P0V8_PEX1")
		)
		(pad "2" smd circle
			(at 0.40005 0 270)
			(size 0 0)
			(layers "F.Cu" "F.Mask" "F.Paste")
			(net "GND")
		)
	)
	(footprint ""
		(layer "F.Cu")
		(at 379.633988 -8.900922)
		(property "Reference" "R5821"
			(at 0 0 0)
			(layer "F.SilkS")
			(hide yes)
			(effects
				(font
					(size 1.27 1.27)
				)
			)
		)
		(property "Value" ""
			(at 0 0 0)
			(layer "F.Fab")
			(effects
				(font
					(size 1.27 1.27)
				)
			)
		)
		(duplicate_pad_numbers_are_jumpers no)
		(fp_line
			(start -0.7874 -0.4064)
			(end 0.7874 -0.4064)
			(stroke
				(width 0.1524)
				(type default)
			)
			(layer "F.SilkS")
		)
		(fp_line
			(start -0.7874 0.4064)
			(end -0.7874 -0.4064)
			(stroke
				(width 0.1524)
				(type default)
			)
			(layer "F.SilkS")
		)
		(fp_line
			(start 0.7874 -0.4064)
			(end 0.7874 0.4064)
			(stroke
				(width 0.1524)
				(type default)
			)
			(layer "F.SilkS")
		)
		(fp_line
			(start 0.7874 0.4064)
			(end -0.7874 0.4064)
			(stroke
				(width 0.1524)
				(type default)
			)
			(layer "F.SilkS")
		)
		(fp_line
			(start -0.67945 -0.305054)
			(end -0.12065 -0.305054)
			(stroke
				(width 0.1)
				(type default)
			)
			(layer "F.Fab")
		)
		(fp_line
			(start -0.67945 0.3048)
			(end -0.67945 -0.305054)
			(stroke
				(width 0.1)
				(type default)
			)
			(layer "F.Fab")
		)
		(fp_line
			(start -0.12065 -0.305054)
			(end -0.12065 -0.2794)
			(stroke
				(width 0.1)
				(type default)
			)
			(layer "F.Fab")
		)
		(fp_line
			(start -0.12065 -0.2794)
			(end 0.12065 -0.2794)
			(stroke
				(width 0.1)
				(type default)
			)
			(layer "F.Fab")
		)
		(fp_line
			(start -0.12065 0.2794)
			(end -0.12065 0.3048)
			(stroke
				(width 0.1)
				(type default)
			)
			(layer "F.Fab")
		)
		(fp_line
			(start -0.12065 0.3048)
			(end -0.67945 0.3048)
			(stroke
				(width 0.1)
				(type default)
			)
			(layer "F.Fab")
		)
		(fp_line
			(start 0.120396 0.2794)
			(end -0.12065 0.2794)
			(stroke
				(width 0.1)
				(type default)
			)
			(layer "F.Fab")
		)
		(fp_line
			(start 0.120396 0.3048)
			(end 0.120396 0.2794)
			(stroke
				(width 0.1)
				(type default)
			)
			(layer "F.Fab")
		)
		(fp_line
			(start 0.12065 -0.3048)
			(end 0.67945 -0.3048)
			(stroke
				(width 0.1)
				(type default)
			)
			(layer "F.Fab")
		)
		(fp_line
			(start 0.12065 -0.2794)
			(end 0.12065 -0.3048)
			(stroke
				(width 0.1)
				(type default)
			)
			(layer "F.Fab")
		)
		(fp_line
			(start 0.67945 -0.3048)
			(end 0.67945 0.3048)
			(stroke
				(width 0.1)
				(type default)
			)
			(layer "F.Fab")
		)
		(fp_line
			(start 0.67945 0.3048)
			(end 0.120396 0.3048)
			(stroke
				(width 0.1)
				(type default)
			)
			(layer "F.Fab")
		)
		(pad "1" smd circle
			(at -0.40005 0)
			(size 0 0)
			(layers "F.Cu" "F.Mask" "F.Paste")
			(net "LM75_3_A0")
		)
		(pad "2" smd circle
			(at 0.40005 0)
			(size 0 0)
			(layers "F.Cu" "F.Mask" "F.Paste")
			(net "GND")
		)
	)
	(footprint ""
		(layer "F.Cu")
		(at 387.580632 -100.203254)
		(property "Reference" "C697"
			(at 0 0 0)
			(layer "F.SilkS")
			(hide yes)
			(effects
				(font
					(size 1.27 1.27)
				)
			)
		)
		(property "Value" ""
			(at 0 0 0)
			(layer "F.Fab")
			(effects
				(font
					(size 1.27 1.27)
				)
			)
		)
		(duplicate_pad_numbers_are_jumpers no)
		(fp_line
			(start -0.299974 -0.150114)
			(end 0.299974 -0.150114)
			(stroke
				(width 0.1)
				(type default)
			)
			(layer "F.Fab")
		)
		(fp_line
			(start -0.299974 0.150114)
			(end -0.299974 -0.150114)
			(stroke
				(width 0.1)
				(type default)
			)
			(layer "F.Fab")
		)
		(fp_line
			(start 0.299974 -0.150114)
			(end 0.299974 0.150114)
			(stroke
				(width 0.1)
				(type default)
			)
			(layer "F.Fab")
		)
		(fp_line
			(start 0.299974 0.150114)
			(end -0.299974 0.150114)
			(stroke
				(width 0.1)
				(type default)
			)
			(layer "F.Fab")
		)
		(pad "1" smd rect
			(at -0.2667 0)
			(size 0.3048 0.381)
			(layers "F.Cu" "F.Mask" "F.Paste")
			(net "P5E_PEX3_STN1_TX_DN<16>")
		)
		(pad "2" smd rect
			(at 0.2667 0)
			(size 0.3048 0.381)
			(layers "F.Cu" "F.Mask" "F.Paste")
			(net "P5E_PEX3_STN1_TX_C_DN<16>")
		)
	)
	(footprint ""
		(layer "F.Cu")
		(at 375.18594 -350.098614 90)
		(property "Reference" "C765"
			(at 0 0 90)
			(layer "F.SilkS")
			(hide yes)
			(effects
				(font
					(size 1.27 1.27)
				)
			)
		)
		(property "Value" ""
			(at 0 0 90)
			(layer "F.Fab")
			(effects
				(font
					(size 1.27 1.27)
				)
			)
		)
		(duplicate_pad_numbers_are_jumpers no)
		(fp_line
			(start 0.299974 -0.150114)
			(end 0.299974 0.150114)
			(stroke
				(width 0.1)
				(type default)
			)
			(layer "F.Fab")
		)
		(fp_line
			(start -0.299974 -0.150114)
			(end 0.299974 -0.150114)
			(stroke
				(width 0.1)
				(type default)
			)
			(layer "F.Fab")
		)
		(fp_line
			(start 0.299974 0.150114)
			(end -0.299974 0.150114)
			(stroke
				(width 0.1)
				(type default)
			)
			(layer "F.Fab")
		)
		(fp_line
			(start -0.299974 0.150114)
			(end -0.299974 -0.150114)
			(stroke
				(width 0.1)
				(type default)
			)
			(layer "F.Fab")
		)
		(pad "1" smd rect
			(at -0.2667 0 90)
			(size 0.3048 0.381)
			(layers "F.Cu" "F.Mask" "F.Paste")
			(net "P5E_PEX3_STN6_TX_DN<110>")
		)
		(pad "2" smd rect
			(at 0.2667 0 90)
			(size 0.3048 0.381)
			(layers "F.Cu" "F.Mask" "F.Paste")
			(net "P5E_PEX3_STN6_TX_C_DN<110>")
		)
	)
	(footprint ""
		(layer "F.Cu")
		(at 144.149318 -293.796212 -90)
		(property "Reference" "C3192"
			(at 0 0 270)
			(layer "F.SilkS")
			(hide yes)
			(effects
				(font
					(size 1.27 1.27)
				)
			)
		)
		(property "Value" ""
			(at 0 0 270)
			(layer "F.Fab")
			(effects
				(font
					(size 1.27 1.27)
				)
			)
		)
		(duplicate_pad_numbers_are_jumpers no)
		(fp_line
			(start -0.299974 0.150114)
			(end -0.299974 -0.150114)
			(stroke
				(width 0.1)
				(type default)
			)
			(layer "F.Fab")
		)
		(fp_line
			(start 0.299974 0.150114)
			(end -0.299974 0.150114)
			(stroke
				(width 0.1)
				(type default)
			)
			(layer "F.Fab")
		)
		(fp_line
			(start -0.299974 -0.150114)
			(end 0.299974 -0.150114)
			(stroke
				(width 0.1)
				(type default)
			)
			(layer "F.Fab")
		)
		(fp_line
			(start 0.299974 -0.150114)
			(end 0.299974 0.150114)
			(stroke
				(width 0.1)
				(type default)
			)
			(layer "F.Fab")
		)
		(pad "1" smd rect
			(at -0.2667 0 270)
			(size 0.3048 0.381)
			(layers "F.Cu" "F.Mask" "F.Paste")
			(net "P1V8_PLL0_PEX1")
		)
		(pad "2" smd rect
			(at 0.2667 0 270)
			(size 0.3048 0.381)
			(layers "F.Cu" "F.Mask" "F.Paste")
			(net "GND")
		)
	)
	(footprint ""
		(layer "F.Cu")
		(at 253.99746 -195.573396 90)
		(property "Reference" "R5644"
			(at 0 0 90)
			(layer "F.SilkS")
			(hide yes)
			(effects
				(font
					(size 1.27 1.27)
				)
			)
		)
		(property "Value" ""
			(at 0 0 90)
			(layer "F.Fab")
			(effects
				(font
					(size 1.27 1.27)
				)
			)
		)
		(duplicate_pad_numbers_are_jumpers no)
		(fp_line
			(start 0.7874 -0.4064)
			(end 0.7874 0.4064)
			(stroke
				(width 0.1524)
				(type default)
			)
			(layer "F.SilkS")
		)
		(fp_line
			(start -0.7874 -0.4064)
			(end 0.7874 -0.4064)
			(stroke
				(width 0.1524)
				(type default)
			)
			(layer "F.SilkS")
		)
		(fp_line
			(start 0.7874 0.4064)
			(end -0.7874 0.4064)
			(stroke
				(width 0.1524)
				(type default)
			)
			(layer "F.SilkS")
		)
		(fp_line
			(start -0.7874 0.4064)
			(end -0.7874 -0.4064)
			(stroke
				(width 0.1524)
				(type default)
			)
			(layer "F.SilkS")
		)
		(fp_line
			(start -0.12065 -0.305054)
			(end -0.12065 -0.2794)
			(stroke
				(width 0.1)
				(type default)
			)
			(layer "F.Fab")
		)
		(fp_line
			(start -0.67945 -0.305054)
			(end -0.12065 -0.305054)
			(stroke
				(width 0.1)
				(type default)
			)
			(layer "F.Fab")
		)
		(fp_line
			(start 0.67945 -0.3048)
			(end 0.67945 0.3048)
			(stroke
				(width 0.1)
				(type default)
			)
			(layer "F.Fab")
		)
		(fp_line
			(start 0.12065 -0.3048)
			(end 0.67945 -0.3048)
			(stroke
				(width 0.1)
				(type default)
			)
			(layer "F.Fab")
		)
		(fp_line
			(start 0.12065 -0.2794)
			(end 0.12065 -0.3048)
			(stroke
				(width 0.1)
				(type default)
			)
			(layer "F.Fab")
		)
		(fp_line
			(start -0.12065 -0.2794)
			(end 0.12065 -0.2794)
			(stroke
				(width 0.1)
				(type default)
			)
			(layer "F.Fab")
		)
		(fp_line
			(start 0.120396 0.2794)
			(end -0.12065 0.2794)
			(stroke
				(width 0.1)
				(type default)
			)
			(layer "F.Fab")
		)
		(fp_line
			(start -0.12065 0.2794)
			(end -0.12065 0.3048)
			(stroke
				(width 0.1)
				(type default)
			)
			(layer "F.Fab")
		)
		(fp_line
			(start 0.67945 0.3048)
			(end 0.120396 0.3048)
			(stroke
				(width 0.1)
				(type default)
			)
			(layer "F.Fab")
		)
		(fp_line
			(start 0.120396 0.3048)
			(end 0.120396 0.2794)
			(stroke
				(width 0.1)
				(type default)
			)
			(layer "F.Fab")
		)
		(fp_line
			(start -0.12065 0.3048)
			(end -0.67945 0.3048)
			(stroke
				(width 0.1)
				(type default)
			)
			(layer "F.Fab")
		)
		(fp_line
			(start -0.67945 0.3048)
			(end -0.67945 -0.305054)
			(stroke
				(width 0.1)
				(type default)
			)
			(layer "F.Fab")
		)
		(pad "1" smd circle
			(at -0.40005 0 90)
			(size 0 0)
			(layers "F.Cu" "F.Mask" "F.Paste")
			(net "JTAG_BIC_TMS_R")
		)
		(pad "2" smd circle
			(at 0.40005 0 90)
			(size 0 0)
			(layers "F.Cu" "F.Mask" "F.Paste")
			(net "JTAG_BIC_TMS_R1")
		)
	)
	(footprint ""
		(layer "F.Cu")
		(at 409.793948 -165.670484 -90)
		(property "Reference" "R2469"
			(at 0 0 270)
			(layer "F.SilkS")
			(hide yes)
			(effects
				(font
					(size 1.27 1.27)
				)
			)
		)
		(property "Value" ""
			(at 0 0 270)
			(layer "F.Fab")
			(effects
				(font
					(size 1.27 1.27)
				)
			)
		)
		(duplicate_pad_numbers_are_jumpers no)
		(fp_line
			(start -0.7874 0.4064)
			(end -0.7874 -0.4064)
			(stroke
				(width 0.1524)
				(type default)
			)
			(layer "F.SilkS")
		)
		(fp_line
			(start 0.7874 0.4064)
			(end -0.7874 0.4064)
			(stroke
				(width 0.1524)
				(type default)
			)
			(layer "F.SilkS")
		)
		(fp_line
			(start -0.7874 -0.4064)
			(end 0.7874 -0.4064)
			(stroke
				(width 0.1524)
				(type default)
			)
			(layer "F.SilkS")
		)
		(fp_line
			(start 0.7874 -0.4064)
			(end 0.7874 0.4064)
			(stroke
				(width 0.1524)
				(type default)
			)
			(layer "F.SilkS")
		)
		(fp_line
			(start -0.67945 0.3048)
			(end -0.67945 -0.305054)
			(stroke
				(width 0.1)
				(type default)
			)
			(layer "F.Fab")
		)
		(fp_line
			(start -0.12065 0.3048)
			(end -0.67945 0.3048)
			(stroke
				(width 0.1)
				(type default)
			)
			(layer "F.Fab")
		)
		(fp_line
			(start 0.120396 0.3048)
			(end 0.120396 0.2794)
			(stroke
				(width 0.1)
				(type default)
			)
			(layer "F.Fab")
		)
		(fp_line
			(start 0.67945 0.3048)
			(end 0.120396 0.3048)
			(stroke
				(width 0.1)
				(type default)
			)
			(layer "F.Fab")
		)
		(fp_line
			(start -0.12065 0.2794)
			(end -0.12065 0.3048)
			(stroke
				(width 0.1)
				(type default)
			)
			(layer "F.Fab")
		)
		(fp_line
			(start 0.120396 0.2794)
			(end -0.12065 0.2794)
			(stroke
				(width 0.1)
				(type default)
			)
			(layer "F.Fab")
		)
		(fp_line
			(start -0.12065 -0.2794)
			(end 0.12065 -0.2794)
			(stroke
				(width 0.1)
				(type default)
			)
			(layer "F.Fab")
		)
		(fp_line
			(start 0.12065 -0.2794)
			(end 0.12065 -0.3048)
			(stroke
				(width 0.1)
				(type default)
			)
			(layer "F.Fab")
		)
		(fp_line
			(start 0.12065 -0.3048)
			(end 0.67945 -0.3048)
			(stroke
				(width 0.1)
				(type default)
			)
			(layer "F.Fab")
		)
		(fp_line
			(start 0.67945 -0.3048)
			(end 0.67945 0.3048)
			(stroke
				(width 0.1)
				(type default)
			)
			(layer "F.Fab")
		)
		(fp_line
			(start -0.67945 -0.305054)
			(end -0.12065 -0.305054)
			(stroke
				(width 0.1)
				(type default)
			)
			(layer "F.Fab")
		)
		(fp_line
			(start -0.12065 -0.305054)
			(end -0.12065 -0.2794)
			(stroke
				(width 0.1)
				(type default)
			)
			(layer "F.Fab")
		)
		(pad "1" smd circle
			(at -0.40005 0 270)
			(size 0 0)
			(layers "F.Cu" "F.Mask" "F.Paste")
			(net "P3V3_NIC6")
		)
		(pad "2" smd circle
			(at 0.40005 0 270)
			(size 0 0)
			(layers "F.Cu" "F.Mask" "F.Paste")
			(net "NIC6_PWRBRK_N")
		)
	)
	(footprint ""
		(layer "F.Cu")
		(at 80.875124 -63.086234)
		(property "Reference" "R5853"
			(at 0 0 0)
			(layer "F.SilkS")
			(hide yes)
			(effects
				(font
					(size 1.27 1.27)
				)
			)
		)
		(property "Value" ""
			(at 0 0 0)
			(layer "F.Fab")
			(effects
				(font
					(size 1.27 1.27)
				)
			)
		)
		(duplicate_pad_numbers_are_jumpers no)
		(fp_line
			(start -0.7874 -0.4064)
			(end 0.7874 -0.4064)
			(stroke
				(width 0.1524)
				(type default)
			)
			(layer "F.SilkS")
		)
		(fp_line
			(start -0.7874 0.4064)
			(end -0.7874 -0.4064)
			(stroke
				(width 0.1524)
				(type default)
			)
			(layer "F.SilkS")
		)
		(fp_line
			(start 0.7874 -0.4064)
			(end 0.7874 0.4064)
			(stroke
				(width 0.1524)
				(type default)
			)
			(layer "F.SilkS")
		)
		(fp_line
			(start 0.7874 0.4064)
			(end -0.7874 0.4064)
			(stroke
				(width 0.1524)
				(type default)
			)
			(layer "F.SilkS")
		)
		(fp_line
			(start -0.67945 -0.305054)
			(end -0.12065 -0.305054)
			(stroke
				(width 0.1)
				(type default)
			)
			(layer "F.Fab")
		)
		(fp_line
			(start -0.67945 0.3048)
			(end -0.67945 -0.305054)
			(stroke
				(width 0.1)
				(type default)
			)
			(layer "F.Fab")
		)
		(fp_line
			(start -0.12065 -0.305054)
			(end -0.12065 -0.2794)
			(stroke
				(width 0.1)
				(type default)
			)
			(layer "F.Fab")
		)
		(fp_line
			(start -0.12065 -0.2794)
			(end 0.12065 -0.2794)
			(stroke
				(width 0.1)
				(type default)
			)
			(layer "F.Fab")
		)
		(fp_line
			(start -0.12065 0.2794)
			(end -0.12065 0.3048)
			(stroke
				(width 0.1)
				(type default)
			)
			(layer "F.Fab")
		)
		(fp_line
			(start -0.12065 0.3048)
			(end -0.67945 0.3048)
			(stroke
				(width 0.1)
				(type default)
			)
			(layer "F.Fab")
		)
		(fp_line
			(start 0.120396 0.2794)
			(end -0.12065 0.2794)
			(stroke
				(width 0.1)
				(type default)
			)
			(layer "F.Fab")
		)
		(fp_line
			(start 0.120396 0.3048)
			(end 0.120396 0.2794)
			(stroke
				(width 0.1)
				(type default)
			)
			(layer "F.Fab")
		)
		(fp_line
			(start 0.12065 -0.3048)
			(end 0.67945 -0.3048)
			(stroke
				(width 0.1)
				(type default)
			)
			(layer "F.Fab")
		)
		(fp_line
			(start 0.12065 -0.2794)
			(end 0.12065 -0.3048)
			(stroke
				(width 0.1)
				(type default)
			)
			(layer "F.Fab")
		)
		(fp_line
			(start 0.67945 -0.3048)
			(end 0.67945 0.3048)
			(stroke
				(width 0.1)
				(type default)
			)
			(layer "F.Fab")
		)
		(fp_line
			(start 0.67945 0.3048)
			(end 0.120396 0.3048)
			(stroke
				(width 0.1)
				(type default)
			)
			(layer "F.Fab")
		)
		(pad "1" smd circle
			(at -0.40005 0)
			(size 0 0)
			(layers "F.Cu" "F.Mask" "F.Paste")
			(net "P12V_SSD3_R")
		)
		(pad "2" smd circle
			(at 0.40005 0)
			(size 0 0)
			(layers "F.Cu" "F.Mask" "F.Paste")
			(net "P12V_SSD3_PG_G1")
		)
	)
	(footprint ""
		(layer "F.Cu")
		(at 121.002044 -32.849312 90)
		(property "Reference" "R5670"
			(at 0 0 90)
			(layer "F.SilkS")
			(hide yes)
			(effects
				(font
					(size 1.27 1.27)
				)
			)
		)
		(property "Value" ""
			(at 0 0 90)
			(layer "F.Fab")
			(effects
				(font
					(size 1.27 1.27)
				)
			)
		)
		(duplicate_pad_numbers_are_jumpers no)
		(fp_line
			(start 0.7874 -0.4064)
			(end 0.7874 0.4064)
			(stroke
				(width 0.1524)
				(type default)
			)
			(layer "F.SilkS")
		)
		(fp_line
			(start -0.7874 -0.4064)
			(end 0.7874 -0.4064)
			(stroke
				(width 0.1524)
				(type default)
			)
			(layer "F.SilkS")
		)
		(fp_line
			(start 0.7874 0.4064)
			(end -0.7874 0.4064)
			(stroke
				(width 0.1524)
				(type default)
			)
			(layer "F.SilkS")
		)
		(fp_line
			(start -0.7874 0.4064)
			(end -0.7874 -0.4064)
			(stroke
				(width 0.1524)
				(type default)
			)
			(layer "F.SilkS")
		)
		(fp_line
			(start -0.12065 -0.305054)
			(end -0.12065 -0.2794)
			(stroke
				(width 0.1)
				(type default)
			)
			(layer "F.Fab")
		)
		(fp_line
			(start -0.67945 -0.305054)
			(end -0.12065 -0.305054)
			(stroke
				(width 0.1)
				(type default)
			)
			(layer "F.Fab")
		)
		(fp_line
			(start 0.67945 -0.3048)
			(end 0.67945 0.3048)
			(stroke
				(width 0.1)
				(type default)
			)
			(layer "F.Fab")
		)
		(fp_line
			(start 0.12065 -0.3048)
			(end 0.67945 -0.3048)
			(stroke
				(width 0.1)
				(type default)
			)
			(layer "F.Fab")
		)
		(fp_line
			(start 0.12065 -0.2794)
			(end 0.12065 -0.3048)
			(stroke
				(width 0.1)
				(type default)
			)
			(layer "F.Fab")
		)
		(fp_line
			(start -0.12065 -0.2794)
			(end 0.12065 -0.2794)
			(stroke
				(width 0.1)
				(type default)
			)
			(layer "F.Fab")
		)
		(fp_line
			(start 0.120396 0.2794)
			(end -0.12065 0.2794)
			(stroke
				(width 0.1)
				(type default)
			)
			(layer "F.Fab")
		)
		(fp_line
			(start -0.12065 0.2794)
			(end -0.12065 0.3048)
			(stroke
				(width 0.1)
				(type default)
			)
			(layer "F.Fab")
		)
		(fp_line
			(start 0.67945 0.3048)
			(end 0.120396 0.3048)
			(stroke
				(width 0.1)
				(type default)
			)
			(layer "F.Fab")
		)
		(fp_line
			(start 0.120396 0.3048)
			(end 0.120396 0.2794)
			(stroke
				(width 0.1)
				(type default)
			)
			(layer "F.Fab")
		)
		(fp_line
			(start -0.12065 0.3048)
			(end -0.67945 0.3048)
			(stroke
				(width 0.1)
				(type default)
			)
			(layer "F.Fab")
		)
		(fp_line
			(start -0.67945 0.3048)
			(end -0.67945 -0.305054)
			(stroke
				(width 0.1)
				(type default)
			)
			(layer "F.Fab")
		)
		(pad "1" smd circle
			(at -0.40005 0 90)
			(size 0 0)
			(layers "F.Cu" "F.Mask" "F.Paste")
			(net "RST_SMB_SSD4_ISO_R_N")
		)
		(pad "2" smd circle
			(at 0.40005 0 90)
			(size 0 0)
			(layers "F.Cu" "F.Mask" "F.Paste")
			(net "RST_SMB_SSD4_ISO_N")
		)
	)
	(footprint ""
		(layer "F.Cu")
		(at 23.737824 -166.07155 -90)
		(property "Reference" "PC18"
			(at 0 0 270)
			(layer "F.SilkS")
			(hide yes)
			(effects
				(font
					(size 1.27 1.27)
				)
			)
		)
		(property "Value" ""
			(at 0 0 270)
			(layer "F.Fab")
			(effects
				(font
					(size 1.27 1.27)
				)
			)
		)
		(duplicate_pad_numbers_are_jumpers no)
		(fp_line
			(start -0.7874 0.4064)
			(end -0.7874 -0.4064)
			(stroke
				(width 0.1524)
				(type default)
			)
			(layer "F.SilkS")
		)
		(fp_line
			(start 0.7874 0.4064)
			(end -0.7874 0.4064)
			(stroke
				(width 0.1524)
				(type default)
			)
			(layer "F.SilkS")
		)
		(fp_line
			(start -0.7874 -0.4064)
			(end 0.7874 -0.4064)
			(stroke
				(width 0.1524)
				(type default)
			)
			(layer "F.SilkS")
		)
		(fp_line
			(start 0.7874 -0.4064)
			(end 0.7874 0.4064)
			(stroke
				(width 0.1524)
				(type default)
			)
			(layer "F.SilkS")
		)
		(fp_line
			(start -0.67945 0.3048)
			(end -0.67945 -0.305054)
			(stroke
				(width 0.1)
				(type default)
			)
			(layer "F.Fab")
		)
		(fp_line
			(start -0.12065 0.3048)
			(end -0.67945 0.3048)
			(stroke
				(width 0.1)
				(type default)
			)
			(layer "F.Fab")
		)
		(fp_line
			(start 0.120396 0.3048)
			(end 0.120396 0.2794)
			(stroke
				(width 0.1)
				(type default)
			)
			(layer "F.Fab")
		)
		(fp_line
			(start 0.67945 0.3048)
			(end 0.120396 0.3048)
			(stroke
				(width 0.1)
				(type default)
			)
			(layer "F.Fab")
		)
		(fp_line
			(start -0.12065 0.2794)
			(end -0.12065 0.3048)
			(stroke
				(width 0.1)
				(type default)
			)
			(layer "F.Fab")
		)
		(fp_line
			(start 0.120396 0.2794)
			(end -0.12065 0.2794)
			(stroke
				(width 0.1)
				(type default)
			)
			(layer "F.Fab")
		)
		(fp_line
			(start -0.12065 -0.2794)
			(end 0.12065 -0.2794)
			(stroke
				(width 0.1)
				(type default)
			)
			(layer "F.Fab")
		)
		(fp_line
			(start 0.12065 -0.2794)
			(end 0.12065 -0.3048)
			(stroke
				(width 0.1)
				(type default)
			)
			(layer "F.Fab")
		)
		(fp_line
			(start 0.12065 -0.3048)
			(end 0.67945 -0.3048)
			(stroke
				(width 0.1)
				(type default)
			)
			(layer "F.Fab")
		)
		(fp_line
			(start 0.67945 -0.3048)
			(end 0.67945 0.3048)
			(stroke
				(width 0.1)
				(type default)
			)
			(layer "F.Fab")
		)
		(fp_line
			(start -0.67945 -0.305054)
			(end -0.12065 -0.305054)
			(stroke
				(width 0.1)
				(type default)
			)
			(layer "F.Fab")
		)
		(fp_line
			(start -0.12065 -0.305054)
			(end -0.12065 -0.2794)
			(stroke
				(width 0.1)
				(type default)
			)
			(layer "F.Fab")
		)
		(pad "1" smd circle
			(at -0.40005 0 270)
			(size 0 0)
			(layers "F.Cu" "F.Mask" "F.Paste")
			(net "P12V_AUX")
		)
		(pad "2" smd circle
			(at 0.40005 0 270)
			(size 0 0)
			(layers "F.Cu" "F.Mask" "F.Paste")
			(net "GND")
		)
	)
	(footprint ""
		(layer "F.Cu")
		(at 422.185592 -27.092148 -90)
		(property "Reference" "R5747"
			(at 0 0 270)
			(layer "F.SilkS")
			(hide yes)
			(effects
				(font
					(size 1.27 1.27)
				)
			)
		)
		(property "Value" ""
			(at 0 0 270)
			(layer "F.Fab")
			(effects
				(font
					(size 1.27 1.27)
				)
			)
		)
		(duplicate_pad_numbers_are_jumpers no)
		(fp_line
			(start -0.7874 0.4064)
			(end -0.7874 -0.4064)
			(stroke
				(width 0.1524)
				(type default)
			)
			(layer "F.SilkS")
		)
		(fp_line
			(start 0.7874 0.4064)
			(end -0.7874 0.4064)
			(stroke
				(width 0.1524)
				(type default)
			)
			(layer "F.SilkS")
		)
		(fp_line
			(start -0.7874 -0.4064)
			(end 0.7874 -0.4064)
			(stroke
				(width 0.1524)
				(type default)
			)
			(layer "F.SilkS")
		)
		(fp_line
			(start 0.7874 -0.4064)
			(end 0.7874 0.4064)
			(stroke
				(width 0.1524)
				(type default)
			)
			(layer "F.SilkS")
		)
		(fp_line
			(start -0.67945 0.3048)
			(end -0.67945 -0.305054)
			(stroke
				(width 0.1)
				(type default)
			)
			(layer "F.Fab")
		)
		(fp_line
			(start -0.12065 0.3048)
			(end -0.67945 0.3048)
			(stroke
				(width 0.1)
				(type default)
			)
			(layer "F.Fab")
		)
		(fp_line
			(start 0.120396 0.3048)
			(end 0.120396 0.2794)
			(stroke
				(width 0.1)
				(type default)
			)
			(layer "F.Fab")
		)
		(fp_line
			(start 0.67945 0.3048)
			(end 0.120396 0.3048)
			(stroke
				(width 0.1)
				(type default)
			)
			(layer "F.Fab")
		)
		(fp_line
			(start -0.12065 0.2794)
			(end -0.12065 0.3048)
			(stroke
				(width 0.1)
				(type default)
			)
			(layer "F.Fab")
		)
		(fp_line
			(start 0.120396 0.2794)
			(end -0.12065 0.2794)
			(stroke
				(width 0.1)
				(type default)
			)
			(layer "F.Fab")
		)
		(fp_line
			(start -0.12065 -0.2794)
			(end 0.12065 -0.2794)
			(stroke
				(width 0.1)
				(type default)
			)
			(layer "F.Fab")
		)
		(fp_line
			(start 0.12065 -0.2794)
			(end 0.12065 -0.3048)
			(stroke
				(width 0.1)
				(type default)
			)
			(layer "F.Fab")
		)
		(fp_line
			(start 0.12065 -0.3048)
			(end 0.67945 -0.3048)
			(stroke
				(width 0.1)
				(type default)
			)
			(layer "F.Fab")
		)
		(fp_line
			(start 0.67945 -0.3048)
			(end 0.67945 0.3048)
			(stroke
				(width 0.1)
				(type default)
			)
			(layer "F.Fab")
		)
		(fp_line
			(start -0.67945 -0.305054)
			(end -0.12065 -0.305054)
			(stroke
				(width 0.1)
				(type default)
			)
			(layer "F.Fab")
		)
		(fp_line
			(start -0.12065 -0.305054)
			(end -0.12065 -0.2794)
			(stroke
				(width 0.1)
				(type default)
			)
			(layer "F.Fab")
		)
		(pad "1" smd circle
			(at -0.40005 0 270)
			(size 0 0)
			(layers "F.Cu" "F.Mask" "F.Paste")
			(net "P3V3_SSD14")
		)
		(pad "2" smd circle
			(at 0.40005 0 270)
			(size 0 0)
			(layers "F.Cu" "F.Mask" "F.Paste")
			(net "SSD14_LED_ISO_N")
		)
	)
	(footprint ""
		(layer "F.Cu")
		(at 198.76135 -152.511252 180)
		(property "Reference" "C216"
			(at 0 0 180)
			(layer "F.SilkS")
			(hide yes)
			(effects
				(font
					(size 1.27 1.27)
				)
			)
		)
		(property "Value" ""
			(at 0 0 180)
			(layer "F.Fab")
			(effects
				(font
					(size 1.27 1.27)
				)
			)
		)
		(duplicate_pad_numbers_are_jumpers no)
		(fp_line
			(start 0.299974 0.150114)
			(end -0.299974 0.150114)
			(stroke
				(width 0.1)
				(type default)
			)
			(layer "F.Fab")
		)
		(fp_line
			(start 0.299974 -0.150114)
			(end 0.299974 0.150114)
			(stroke
				(width 0.1)
				(type default)
			)
			(layer "F.Fab")
		)
		(fp_line
			(start -0.299974 0.150114)
			(end -0.299974 -0.150114)
			(stroke
				(width 0.1)
				(type default)
			)
			(layer "F.Fab")
		)
		(fp_line
			(start -0.299974 -0.150114)
			(end 0.299974 -0.150114)
			(stroke
				(width 0.1)
				(type default)
			)
			(layer "F.Fab")
		)
		(pad "1" smd rect
			(at -0.2667 0 180)
			(size 0.3048 0.381)
			(layers "F.Cu" "F.Mask" "F.Paste")
			(net "P5E_PEX1_STN0_TX_DP<13>")
		)
		(pad "2" smd rect
			(at 0.2667 0 180)
			(size 0.3048 0.381)
			(layers "F.Cu" "F.Mask" "F.Paste")
			(net "P5E_PEX1_STN0_TX_C_DP<13>")
		)
	)
	(footprint ""
		(layer "F.Cu")
		(at 106.274362 -6.739636)
		(property "Reference" "R1656"
			(at 0 0 0)
			(layer "F.SilkS")
			(hide yes)
			(effects
				(font
					(size 1.27 1.27)
				)
			)
		)
		(property "Value" ""
			(at 0 0 0)
			(layer "F.Fab")
			(effects
				(font
					(size 1.27 1.27)
				)
			)
		)
		(duplicate_pad_numbers_are_jumpers no)
		(fp_line
			(start -0.7874 -0.4064)
			(end 0.7874 -0.4064)
			(stroke
				(width 0.1524)
				(type default)
			)
			(layer "F.SilkS")
		)
		(fp_line
			(start -0.7874 0.4064)
			(end -0.7874 -0.4064)
			(stroke
				(width 0.1524)
				(type default)
			)
			(layer "F.SilkS")
		)
		(fp_line
			(start 0.7874 -0.4064)
			(end 0.7874 0.4064)
			(stroke
				(width 0.1524)
				(type default)
			)
			(layer "F.SilkS")
		)
		(fp_line
			(start 0.7874 0.4064)
			(end -0.7874 0.4064)
			(stroke
				(width 0.1524)
				(type default)
			)
			(layer "F.SilkS")
		)
		(fp_line
			(start -0.67945 -0.305054)
			(end -0.12065 -0.305054)
			(stroke
				(width 0.1)
				(type default)
			)
			(layer "F.Fab")
		)
		(fp_line
			(start -0.67945 0.3048)
			(end -0.67945 -0.305054)
			(stroke
				(width 0.1)
				(type default)
			)
			(layer "F.Fab")
		)
		(fp_line
			(start -0.12065 -0.305054)
			(end -0.12065 -0.2794)
			(stroke
				(width 0.1)
				(type default)
			)
			(layer "F.Fab")
		)
		(fp_line
			(start -0.12065 -0.2794)
			(end 0.12065 -0.2794)
			(stroke
				(width 0.1)
				(type default)
			)
			(layer "F.Fab")
		)
		(fp_line
			(start -0.12065 0.2794)
			(end -0.12065 0.3048)
			(stroke
				(width 0.1)
				(type default)
			)
			(layer "F.Fab")
		)
		(fp_line
			(start -0.12065 0.3048)
			(end -0.67945 0.3048)
			(stroke
				(width 0.1)
				(type default)
			)
			(layer "F.Fab")
		)
		(fp_line
			(start 0.120396 0.2794)
			(end -0.12065 0.2794)
			(stroke
				(width 0.1)
				(type default)
			)
			(layer "F.Fab")
		)
		(fp_line
			(start 0.120396 0.3048)
			(end 0.120396 0.2794)
			(stroke
				(width 0.1)
				(type default)
			)
			(layer "F.Fab")
		)
		(fp_line
			(start 0.12065 -0.3048)
			(end 0.67945 -0.3048)
			(stroke
				(width 0.1)
				(type default)
			)
			(layer "F.Fab")
		)
		(fp_line
			(start 0.12065 -0.2794)
			(end 0.12065 -0.3048)
			(stroke
				(width 0.1)
				(type default)
			)
			(layer "F.Fab")
		)
		(fp_line
			(start 0.67945 -0.3048)
			(end 0.67945 0.3048)
			(stroke
				(width 0.1)
				(type default)
			)
			(layer "F.Fab")
		)
		(fp_line
			(start 0.67945 0.3048)
			(end 0.120396 0.3048)
			(stroke
				(width 0.1)
				(type default)
			)
			(layer "F.Fab")
		)
		(pad "1" smd circle
			(at -0.40005 0)
			(size 0 0)
			(layers "F.Cu" "F.Mask" "F.Paste")
			(net "SMB_BIC_I2C9_MUX0_SSD3_R_SDA")
		)
		(pad "2" smd circle
			(at 0.40005 0)
			(size 0 0)
			(layers "F.Cu" "F.Mask" "F.Paste")
			(net "SMB_ISO_SSD3_SDA")
		)
	)
	(footprint ""
		(layer "F.Cu")
		(at 226.19716 -266.873228)
		(property "Reference" "R6132"
			(at 0 0 0)
			(layer "F.SilkS")
			(hide yes)
			(effects
				(font
					(size 1.27 1.27)
				)
			)
		)
		(property "Value" ""
			(at 0 0 0)
			(layer "F.Fab")
			(effects
				(font
					(size 1.27 1.27)
				)
			)
		)
		(duplicate_pad_numbers_are_jumpers no)
		(fp_line
			(start -2.576322 -1.1303)
			(end 2.576322 -1.1303)
			(stroke
				(width 0.1524)
				(type default)
			)
			(layer "F.SilkS")
		)
		(fp_line
			(start -2.576322 1.1303)
			(end -2.576322 -1.1303)
			(stroke
				(width 0.1524)
				(type default)
			)
			(layer "F.SilkS")
		)
		(fp_line
			(start 2.576322 -1.1303)
			(end 2.576322 1.1303)
			(stroke
				(width 0.1524)
				(type default)
			)
			(layer "F.SilkS")
		)
		(fp_line
			(start 2.576322 1.1303)
			(end -2.576322 1.1303)
			(stroke
				(width 0.1524)
				(type default)
			)
			(layer "F.SilkS")
		)
		(fp_line
			(start -1.649984 -0.899922)
			(end -1.649984 0.899922)
			(stroke
				(width 0.1)
				(type default)
			)
			(layer "F.Fab")
		)
		(fp_line
			(start -1.649984 0.899922)
			(end 1.649984 0.899922)
			(stroke
				(width 0.1)
				(type default)
			)
			(layer "F.Fab")
		)
		(fp_line
			(start 1.649984 -0.899922)
			(end -1.649984 -0.899922)
			(stroke
				(width 0.1)
				(type default)
			)
			(layer "F.Fab")
		)
		(fp_line
			(start 1.649984 0.899922)
			(end 1.649984 -0.899922)
			(stroke
				(width 0.1)
				(type default)
			)
			(layer "F.Fab")
		)
		(pad "1A" smd rect
			(at -1.700022 0)
			(size 1.4986 2.0066)
			(layers "F.Cu" "F.Mask" "F.Paste")
			(net "P1V25_PEX1")
		)
		(pad "1B" smd rect
			(at -1.077722 0)
			(size 0.254 0.508)
			(layers "F.Cu" "F.Mask" "F.Paste")
			(net "P1V25_PEX1")
		)
		(pad "2A" smd rect
			(at 1.700022 0)
			(size 1.4986 2.0066)
			(layers "F.Cu" "F.Mask" "F.Paste")
			(net "P1V25_SERDES_VDDPLL_PEX1")
		)
		(pad "2B" smd rect
			(at 1.077722 0)
			(size 0.254 0.508)
			(layers "F.Cu" "F.Mask" "F.Paste")
			(net "P1V25_SERDES_VDDPLL_PEX1")
		)
	)
	(footprint ""
		(layer "F.Cu")
		(at 166.58209 -37.025072)
		(property "Reference" "R5677"
			(at 0 0 0)
			(layer "F.SilkS")
			(hide yes)
			(effects
				(font
					(size 1.27 1.27)
				)
			)
		)
		(property "Value" ""
			(at 0 0 0)
			(layer "F.Fab")
			(effects
				(font
					(size 1.27 1.27)
				)
			)
		)
		(duplicate_pad_numbers_are_jumpers no)
		(fp_line
			(start -0.7874 -0.4064)
			(end 0.7874 -0.4064)
			(stroke
				(width 0.1524)
				(type default)
			)
			(layer "F.SilkS")
		)
		(fp_line
			(start -0.7874 0.4064)
			(end -0.7874 -0.4064)
			(stroke
				(width 0.1524)
				(type default)
			)
			(layer "F.SilkS")
		)
		(fp_line
			(start 0.7874 -0.4064)
			(end 0.7874 0.4064)
			(stroke
				(width 0.1524)
				(type default)
			)
			(layer "F.SilkS")
		)
		(fp_line
			(start 0.7874 0.4064)
			(end -0.7874 0.4064)
			(stroke
				(width 0.1524)
				(type default)
			)
			(layer "F.SilkS")
		)
		(fp_line
			(start -0.67945 -0.305054)
			(end -0.12065 -0.305054)
			(stroke
				(width 0.1)
				(type default)
			)
			(layer "F.Fab")
		)
		(fp_line
			(start -0.67945 0.3048)
			(end -0.67945 -0.305054)
			(stroke
				(width 0.1)
				(type default)
			)
			(layer "F.Fab")
		)
		(fp_line
			(start -0.12065 -0.305054)
			(end -0.12065 -0.2794)
			(stroke
				(width 0.1)
				(type default)
			)
			(layer "F.Fab")
		)
		(fp_line
			(start -0.12065 -0.2794)
			(end 0.12065 -0.2794)
			(stroke
				(width 0.1)
				(type default)
			)
			(layer "F.Fab")
		)
		(fp_line
			(start -0.12065 0.2794)
			(end -0.12065 0.3048)
			(stroke
				(width 0.1)
				(type default)
			)
			(layer "F.Fab")
		)
		(fp_line
			(start -0.12065 0.3048)
			(end -0.67945 0.3048)
			(stroke
				(width 0.1)
				(type default)
			)
			(layer "F.Fab")
		)
		(fp_line
			(start 0.120396 0.2794)
			(end -0.12065 0.2794)
			(stroke
				(width 0.1)
				(type default)
			)
			(layer "F.Fab")
		)
		(fp_line
			(start 0.120396 0.3048)
			(end 0.120396 0.2794)
			(stroke
				(width 0.1)
				(type default)
			)
			(layer "F.Fab")
		)
		(fp_line
			(start 0.12065 -0.3048)
			(end 0.67945 -0.3048)
			(stroke
				(width 0.1)
				(type default)
			)
			(layer "F.Fab")
		)
		(fp_line
			(start 0.12065 -0.2794)
			(end 0.12065 -0.3048)
			(stroke
				(width 0.1)
				(type default)
			)
			(layer "F.Fab")
		)
		(fp_line
			(start 0.67945 -0.3048)
			(end 0.67945 0.3048)
			(stroke
				(width 0.1)
				(type default)
			)
			(layer "F.Fab")
		)
		(fp_line
			(start 0.67945 0.3048)
			(end 0.120396 0.3048)
			(stroke
				(width 0.1)
				(type default)
			)
			(layer "F.Fab")
		)
		(pad "1" smd circle
			(at -0.40005 0)
			(size 0 0)
			(layers "F.Cu" "F.Mask" "F.Paste")
			(net "RST_SMB_SSD_R_N")
		)
		(pad "2" smd circle
			(at 0.40005 0)
			(size 0 0)
			(layers "F.Cu" "F.Mask" "F.Paste")
			(net "RST_SMB_SSD6_N")
		)
	)
	(footprint ""
		(layer "F.Cu")
		(at 420.280084 -127.700024 180)
		(property "Reference" "J27"
			(at 5.446014 -34.532824 90)
			(unlocked yes)
			(layer "F.SilkS")
			(effects
				(font
					(size 0.7874 0.5842)
					(thickness 0.1524)
				)
				(justify left)
			)
		)
		(property "Value" ""
			(at 0 0 180)
			(layer "F.Fab")
			(effects
				(font
					(size 1.27 1.27)
				)
			)
		)
		(duplicate_pad_numbers_are_jumpers no)
		(fp_line
			(start 4.507484 -21.5265)
			(end 4.507484 -34.720022)
			(stroke
				(width 0.1524)
				(type default)
			)
			(layer "F.SilkS")
		)
		(fp_line
			(start 4.507484 -34.720022)
			(end 2.6162 -34.720022)
			(stroke
				(width 0.1524)
				(type default)
			)
			(layer "F.SilkS")
		)
		(fp_line
			(start 2.6035 34.720022)
			(end 4.507484 34.720022)
			(stroke
				(width 0.1524)
				(type default)
			)
			(layer "F.SilkS")
		)
		(fp_line
			(start -0.57658 -34.720022)
			(end -4.507484 -34.720022)
			(stroke
				(width 0.1524)
				(type default)
			)
			(layer "F.SilkS")
		)
		(fp_line
			(start -4.507484 34.720022)
			(end -0.5588 34.720022)
			(stroke
				(width 0.1524)
				(type default)
			)
			(layer "F.SilkS")
		)
		(fp_poly
			(pts
				(xy 5.735574 -17.957038) (xy 5.735574 -18.973038) (xy 4.719574 -18.465038)
			)
			(stroke
				(width 0)
				(type default)
			)
			(fill yes)
			(layer "F.SilkS")
		)
		(fp_line
			(start 4.507484 34.720022)
			(end 4.507484 -34.720022)
			(stroke
				(width 0.1)
				(type default)
			)
			(layer "F.Fab")
		)
		(fp_line
			(start 4.507484 -34.720022)
			(end -4.507484 -34.720022)
			(stroke
				(width 0.1)
				(type default)
			)
			(layer "F.Fab")
		)
		(fp_line
			(start -4.507484 34.720022)
			(end 4.507484 34.720022)
			(stroke
				(width 0.1)
				(type default)
			)
			(layer "F.Fab")
		)
		(fp_line
			(start -4.507484 -34.720022)
			(end -4.507484 34.720022)
			(stroke
				(width 0.1)
				(type default)
			)
			(layer "F.Fab")
		)
		(fp_poly
			(pts
				(xy 5.735574 -17.957038) (xy 5.735574 -18.973038) (xy 4.719574 -18.465038)
			)
			(stroke
				(width 0)
				(type default)
			)
			(fill yes)
			(layer "F.Fab")
		)
		(pad "" np_thru_hole circle
			(at -0.727456 -32.485076 180)
			(size 1.1176 1.1176)
			(drill 1.1176)
			(layers "*.Cu" "*.Mask")
			(clearance 0.381)
			(thermal_gap 0.381)
		)
		(pad "" np_thru_hole circle
			(at 1.022604 32.485076 180)
			(size 1.1176 1.1176)
			(drill 1.1176)
			(layers "*.Cu" "*.Mask")
			(clearance 0.381)
			(thermal_gap 0.381)
		)
		(pad "A1" smd rect
			(at 3.322574 -18.465038 90)
			(size 0.3556 1.2192)
			(layers "F.Cu" "F.Mask" "F.Paste")
			(net "GND")
		)
		(pad "A2" smd rect
			(at 3.322574 -17.86509 90)
			(size 0.3556 1.2192)
			(layers "F.Cu" "F.Mask" "F.Paste")
			(net "GND")
		)
		(pad "A3" smd rect
			(at 3.322574 -17.264888 90)
			(size 0.3556 1.2192)
			(layers "F.Cu" "F.Mask" "F.Paste")
			(net "GND")
		)
		(pad "A4" smd rect
			(at 3.322574 -16.66494 90)
			(size 0.3556 1.2192)
			(layers "F.Cu" "F.Mask" "F.Paste")
			(net "GND")
		)
		(pad "A5" smd rect
			(at 3.322574 -16.064992 90)
			(size 0.3556 1.2192)
			(layers "F.Cu" "F.Mask" "F.Paste")
			(net "GND")
		)
		(pad "A6" smd rect
			(at 3.322574 -15.465044 90)
			(size 0.3556 1.2192)
			(layers "F.Cu" "F.Mask" "F.Paste")
			(net "GND")
		)
		(pad "A7" smd rect
			(at 3.322574 -14.865096 90)
			(size 0.3556 1.2192)
			(layers "F.Cu" "F.Mask" "F.Paste")
			(net "SMB_NIC7_LS_SCL")
		)
		(pad "A8" smd rect
			(at 3.322574 -14.264894 90)
			(size 0.3556 1.2192)
			(layers "F.Cu" "F.Mask" "F.Paste")
			(net "SMB_NIC7_LS_SDA")
		)
		(pad "A9" smd rect
			(at 3.322574 -13.664946 90)
			(size 0.3556 1.2192)
			(layers "F.Cu" "F.Mask" "F.Paste")
			(net "RST_SMB_NIC7_MUX_ISO_R_N")
		)
		(pad "A10" smd rect
			(at 3.322574 -13.064998 90)
			(size 0.3556 1.2192)
			(layers "F.Cu" "F.Mask" "F.Paste")
			(net "GND")
		)
		(pad "A11" smd rect
			(at 3.322574 -12.46505 90)
			(size 0.3556 1.2192)
			(layers "F.Cu" "F.Mask" "F.Paste")
			(net "RST_NIC7_PERST1_R_N")
		)
		(pad "A12" smd rect
			(at 3.322574 -11.865102 90)
			(size 0.3556 1.2192)
			(layers "F.Cu" "F.Mask" "F.Paste")
			(net "PRSNTB2_NIC7_N")
		)
		(pad "A13" smd rect
			(at 3.322574 -11.2649 90)
			(size 0.3556 1.2192)
			(layers "F.Cu" "F.Mask" "F.Paste")
			(net "GND")
		)
		(pad "A14" smd rect
			(at 3.322574 -10.664952 90)
			(size 0.3556 1.2192)
			(layers "F.Cu" "F.Mask" "F.Paste")
			(net "Net_2666")
		)
		(pad "A15" smd rect
			(at 3.322574 -10.065004 90)
			(size 0.3556 1.2192)
			(layers "F.Cu" "F.Mask" "F.Paste")
			(net "Net_2669")
		)
		(pad "A16" smd rect
			(at 3.322574 -9.465056 90)
			(size 0.3556 1.2192)
			(layers "F.Cu" "F.Mask" "F.Paste")
			(net "GND")
		)
		(pad "A17" smd rect
			(at 3.322574 -8.865108 90)
			(size 0.3556 1.2192)
			(layers "F.Cu" "F.Mask" "F.Paste")
			(net "P5E_PEX3_STN0_RX_DN<0>")
		)
		(pad "A18" smd rect
			(at 3.322574 -8.264906 90)
			(size 0.3556 1.2192)
			(layers "F.Cu" "F.Mask" "F.Paste")
			(net "P5E_PEX3_STN0_RX_DP<0>")
		)
		(pad "A19" smd rect
			(at 3.322574 -7.664958 90)
			(size 0.3556 1.2192)
			(layers "F.Cu" "F.Mask" "F.Paste")
			(net "GND")
		)
		(pad "A20" smd rect
			(at 3.322574 -7.06501 90)
			(size 0.3556 1.2192)
			(layers "F.Cu" "F.Mask" "F.Paste")
			(net "P5E_PEX3_STN0_RX_DN<1>")
		)
		(pad "A21" smd rect
			(at 3.322574 -6.465062 90)
			(size 0.3556 1.2192)
			(layers "F.Cu" "F.Mask" "F.Paste")
			(net "P5E_PEX3_STN0_RX_DP<1>")
		)
		(pad "A22" smd rect
			(at 3.322574 -5.865114 90)
			(size 0.3556 1.2192)
			(layers "F.Cu" "F.Mask" "F.Paste")
			(net "GND")
		)
		(pad "A23" smd rect
			(at 3.322574 -5.264912 90)
			(size 0.3556 1.2192)
			(layers "F.Cu" "F.Mask" "F.Paste")
			(net "P5E_PEX3_STN0_RX_DN<2>")
		)
		(pad "A24" smd rect
			(at 3.322574 -4.664964 90)
			(size 0.3556 1.2192)
			(layers "F.Cu" "F.Mask" "F.Paste")
			(net "P5E_PEX3_STN0_RX_DP<2>")
		)
		(pad "A25" smd rect
			(at 3.322574 -4.065016 90)
			(size 0.3556 1.2192)
			(layers "F.Cu" "F.Mask" "F.Paste")
			(net "GND")
		)
		(pad "A26" smd rect
			(at 3.322574 -3.465068 90)
			(size 0.3556 1.2192)
			(layers "F.Cu" "F.Mask" "F.Paste")
			(net "P5E_PEX3_STN0_RX_DN<3>")
		)
		(pad "A27" smd rect
			(at 3.322574 -2.86512 90)
			(size 0.3556 1.2192)
			(layers "F.Cu" "F.Mask" "F.Paste")
			(net "P5E_PEX3_STN0_RX_DP<3>")
		)
		(pad "A28" smd rect
			(at 3.322574 -2.264918 90)
			(size 0.3556 1.2192)
			(layers "F.Cu" "F.Mask" "F.Paste")
			(net "GND")
		)
		(pad "A29" smd rect
			(at 3.322574 1.74498 90)
			(size 0.3556 1.2192)
			(layers "F.Cu" "F.Mask" "F.Paste")
			(net "GND")
		)
		(pad "A30" smd rect
			(at 3.322574 2.344928 90)
			(size 0.3556 1.2192)
			(layers "F.Cu" "F.Mask" "F.Paste")
			(net "P5E_PEX3_STN0_RX_DN<4>")
		)
		(pad "A31" smd rect
			(at 3.322574 2.944876 90)
			(size 0.3556 1.2192)
			(layers "F.Cu" "F.Mask" "F.Paste")
			(net "P5E_PEX3_STN0_RX_DP<4>")
		)
		(pad "A32" smd rect
			(at 3.322574 3.545078 90)
			(size 0.3556 1.2192)
			(layers "F.Cu" "F.Mask" "F.Paste")
			(net "GND")
		)
		(pad "A33" smd rect
			(at 3.322574 4.145026 90)
			(size 0.3556 1.2192)
			(layers "F.Cu" "F.Mask" "F.Paste")
			(net "P5E_PEX3_STN0_RX_DN<5>")
		)
		(pad "A34" smd rect
			(at 3.322574 4.744974 90)
			(size 0.3556 1.2192)
			(layers "F.Cu" "F.Mask" "F.Paste")
			(net "P5E_PEX3_STN0_RX_DP<5>")
		)
		(pad "A35" smd rect
			(at 3.322574 5.344922 90)
			(size 0.3556 1.2192)
			(layers "F.Cu" "F.Mask" "F.Paste")
			(net "GND")
		)
		(pad "A36" smd rect
			(at 3.322574 5.945124 90)
			(size 0.3556 1.2192)
			(layers "F.Cu" "F.Mask" "F.Paste")
			(net "P5E_PEX3_STN0_RX_DN<6>")
		)
		(pad "A37" smd rect
			(at 3.322574 6.545072 90)
			(size 0.3556 1.2192)
			(layers "F.Cu" "F.Mask" "F.Paste")
			(net "P5E_PEX3_STN0_RX_DP<6>")
		)
		(pad "A38" smd rect
			(at 3.322574 7.14502 90)
			(size 0.3556 1.2192)
			(layers "F.Cu" "F.Mask" "F.Paste")
			(net "GND")
		)
		(pad "A39" smd rect
			(at 3.322574 7.744968 90)
			(size 0.3556 1.2192)
			(layers "F.Cu" "F.Mask" "F.Paste")
			(net "P5E_PEX3_STN0_RX_DN<7>")
		)
		(pad "A40" smd rect
			(at 3.322574 8.344916 90)
			(size 0.3556 1.2192)
			(layers "F.Cu" "F.Mask" "F.Paste")
			(net "P5E_PEX3_STN0_RX_DP<7>")
		)
		(pad "A41" smd rect
			(at 3.322574 8.945118 90)
			(size 0.3556 1.2192)
			(layers "F.Cu" "F.Mask" "F.Paste")
			(net "GND")
		)
		(pad "A42" smd rect
			(at 3.322574 9.545066 90)
			(size 0.3556 1.2192)
			(layers "F.Cu" "F.Mask" "F.Paste")
			(net "PRSNTB1_NIC7_N")
		)
		(pad "A43" smd rect
			(at 3.322574 14.454886 90)
			(size 0.3556 1.2192)
			(layers "F.Cu" "F.Mask" "F.Paste")
			(net "GND")
		)
		(pad "A44" smd rect
			(at 3.322574 15.055088 90)
			(size 0.3556 1.2192)
			(layers "F.Cu" "F.Mask" "F.Paste")
			(net "P5E_PEX3_STN0_RX_DN<8>")
		)
		(pad "A45" smd rect
			(at 3.322574 15.655036 90)
			(size 0.3556 1.2192)
			(layers "F.Cu" "F.Mask" "F.Paste")
			(net "P5E_PEX3_STN0_RX_DP<8>")
		)
		(pad "A46" smd rect
			(at 3.322574 16.254984 90)
			(size 0.3556 1.2192)
			(layers "F.Cu" "F.Mask" "F.Paste")
			(net "GND")
		)
		(pad "A47" smd rect
			(at 3.322574 16.854932 90)
			(size 0.3556 1.2192)
			(layers "F.Cu" "F.Mask" "F.Paste")
			(net "P5E_PEX3_STN0_RX_DN<9>")
		)
		(pad "A48" smd rect
			(at 3.322574 17.45488 90)
			(size 0.3556 1.2192)
			(layers "F.Cu" "F.Mask" "F.Paste")
			(net "P5E_PEX3_STN0_RX_DP<9>")
		)
		(pad "A49" smd rect
			(at 3.322574 18.055082 90)
			(size 0.3556 1.2192)
			(layers "F.Cu" "F.Mask" "F.Paste")
			(net "GND")
		)
		(pad "A50" smd rect
			(at 3.322574 18.65503 90)
			(size 0.3556 1.2192)
			(layers "F.Cu" "F.Mask" "F.Paste")
			(net "P5E_PEX3_STN0_RX_DN<10>")
		)
		(pad "A51" smd rect
			(at 3.322574 19.254978 90)
			(size 0.3556 1.2192)
			(layers "F.Cu" "F.Mask" "F.Paste")
			(net "P5E_PEX3_STN0_RX_DP<10>")
		)
		(pad "A52" smd rect
			(at 3.322574 19.854926 90)
			(size 0.3556 1.2192)
			(layers "F.Cu" "F.Mask" "F.Paste")
			(net "GND")
		)
		(pad "A53" smd rect
			(at 3.322574 20.455128 90)
			(size 0.3556 1.2192)
			(layers "F.Cu" "F.Mask" "F.Paste")
			(net "P5E_PEX3_STN0_RX_DN<11>")
		)
		(pad "A54" smd rect
			(at 3.322574 21.055076 90)
			(size 0.3556 1.2192)
			(layers "F.Cu" "F.Mask" "F.Paste")
			(net "P5E_PEX3_STN0_RX_DP<11>")
		)
		(pad "A55" smd rect
			(at 3.322574 21.655024 90)
			(size 0.3556 1.2192)
			(layers "F.Cu" "F.Mask" "F.Paste")
			(net "GND")
		)
		(pad "A56" smd rect
			(at 3.322574 22.254972 90)
			(size 0.3556 1.2192)
			(layers "F.Cu" "F.Mask" "F.Paste")
			(net "P5E_PEX3_STN0_RX_DN<12>")
		)
		(pad "A57" smd rect
			(at 3.322574 22.85492 90)
			(size 0.3556 1.2192)
			(layers "F.Cu" "F.Mask" "F.Paste")
			(net "P5E_PEX3_STN0_RX_DP<12>")
		)
		(pad "A58" smd rect
			(at 3.322574 23.455122 90)
			(size 0.3556 1.2192)
			(layers "F.Cu" "F.Mask" "F.Paste")
			(net "GND")
		)
		(pad "A59" smd rect
			(at 3.322574 24.05507 90)
			(size 0.3556 1.2192)
			(layers "F.Cu" "F.Mask" "F.Paste")
			(net "P5E_PEX3_STN0_RX_DN<13>")
		)
		(pad "A60" smd rect
			(at 3.322574 24.655018 90)
			(size 0.3556 1.2192)
			(layers "F.Cu" "F.Mask" "F.Paste")
			(net "P5E_PEX3_STN0_RX_DP<13>")
		)
		(pad "A61" smd rect
			(at 3.322574 25.254966 90)
			(size 0.3556 1.2192)
			(layers "F.Cu" "F.Mask" "F.Paste")
			(net "GND")
		)
		(pad "A62" smd rect
			(at 3.322574 25.854914 90)
			(size 0.3556 1.2192)
			(layers "F.Cu" "F.Mask" "F.Paste")
			(net "P5E_PEX3_STN0_RX_DN<14>")
		)
		(pad "A63" smd rect
			(at 3.322574 26.455116 90)
			(size 0.3556 1.2192)
			(layers "F.Cu" "F.Mask" "F.Paste")
			(net "P5E_PEX3_STN0_RX_DP<14>")
		)
		(pad "A64" smd rect
			(at 3.322574 27.055064 90)
			(size 0.3556 1.2192)
			(layers "F.Cu" "F.Mask" "F.Paste")
			(net "GND")
		)
		(pad "A65" smd rect
			(at 3.322574 27.655012 90)
			(size 0.3556 1.2192)
			(layers "F.Cu" "F.Mask" "F.Paste")
			(net "P5E_PEX3_STN0_RX_DN<15>")
		)
		(pad "A66" smd rect
			(at 3.322574 28.25496 90)
			(size 0.3556 1.2192)
			(layers "F.Cu" "F.Mask" "F.Paste")
			(net "P5E_PEX3_STN0_RX_DP<15>")
		)
		(pad "A67" smd rect
			(at 3.322574 28.854908 90)
			(size 0.3556 1.2192)
			(layers "F.Cu" "F.Mask" "F.Paste")
			(net "GND")
		)
		(pad "A68" smd rect
			(at 3.322574 29.45511 90)
			(size 0.3556 1.2192)
			(layers "F.Cu" "F.Mask" "F.Paste")
			(net "Net_2674")
		)
		(pad "A69" smd rect
			(at 3.322574 30.055058 90)
			(size 0.3556 1.2192)
			(layers "F.Cu" "F.Mask" "F.Paste")
			(net "Net_2675")
		)
		(pad "A70" smd rect
			(at 3.322574 30.655006 90)
			(size 0.3556 1.2192)
			(layers "F.Cu" "F.Mask" "F.Paste")
			(net "NIC7_PWRBRK_R_N")
		)
		(pad "B1" smd rect
			(at -1.27762 -18.465038 90)
			(size 0.3556 1.2192)
			(layers "F.Cu" "F.Mask" "F.Paste")
			(net "P12V_NIC7")
		)
		(pad "B2" smd rect
			(at -1.27762 -17.86509 90)
			(size 0.3556 1.2192)
			(layers "F.Cu" "F.Mask" "F.Paste")
			(net "P12V_NIC7")
		)
		(pad "B3" smd rect
			(at -1.27762 -17.264888 90)
			(size 0.3556 1.2192)
			(layers "F.Cu" "F.Mask" "F.Paste")
			(net "P12V_NIC7")
		)
		(pad "B4" smd rect
			(at -1.27762 -16.66494 90)
			(size 0.3556 1.2192)
			(layers "F.Cu" "F.Mask" "F.Paste")
			(net "P12V_NIC7")
		)
		(pad "B5" smd rect
			(at -1.27762 -16.064992 90)
			(size 0.3556 1.2192)
			(layers "F.Cu" "F.Mask" "F.Paste")
			(net "P12V_NIC7")
		)
		(pad "B6" smd rect
			(at -1.27762 -15.465044 90)
			(size 0.3556 1.2192)
			(layers "F.Cu" "F.Mask" "F.Paste")
			(net "P12V_NIC7")
		)
		(pad "B7" smd rect
			(at -1.27762 -14.865096 90)
			(size 0.3556 1.2192)
			(layers "F.Cu" "F.Mask" "F.Paste")
			(net "NIC7_BIF0_N")
		)
		(pad "B8" smd rect
			(at -1.27762 -14.264894 90)
			(size 0.3556 1.2192)
			(layers "F.Cu" "F.Mask" "F.Paste")
			(net "NIC7_BIF1_N")
		)
		(pad "B9" smd rect
			(at -1.27762 -13.664946 90)
			(size 0.3556 1.2192)
			(layers "F.Cu" "F.Mask" "F.Paste")
			(net "NIC7_BIF2_N")
		)
		(pad "B10" smd rect
			(at -1.27762 -13.064998 90)
			(size 0.3556 1.2192)
			(layers "F.Cu" "F.Mask" "F.Paste")
			(net "RST_NIC7_PERST0_R_N")
		)
		(pad "B11" smd rect
			(at -1.27762 -12.46505 90)
			(size 0.3556 1.2192)
			(layers "F.Cu" "F.Mask" "F.Paste")
			(net "P3V3_NIC7")
		)
		(pad "B12" smd rect
			(at -1.27762 -11.865102 90)
			(size 0.3556 1.2192)
			(layers "F.Cu" "F.Mask" "F.Paste")
			(net "NIC7_AUX_PWR_EN_R")
		)
		(pad "B13" smd rect
			(at -1.27762 -11.2649 90)
			(size 0.3556 1.2192)
			(layers "F.Cu" "F.Mask" "F.Paste")
			(net "GND")
		)
		(pad "B14" smd rect
			(at -1.27762 -10.664952 90)
			(size 0.3556 1.2192)
			(layers "F.Cu" "F.Mask" "F.Paste")
			(net "CLK_100M_DB2000QL_NIC7_R_DN")
		)
		(pad "B15" smd rect
			(at -1.27762 -10.065004 90)
			(size 0.3556 1.2192)
			(layers "F.Cu" "F.Mask" "F.Paste")
			(net "CLK_100M_DB2000QL_NIC7_R_DP")
		)
		(pad "B16" smd rect
			(at -1.27762 -9.465056 90)
			(size 0.3556 1.2192)
			(layers "F.Cu" "F.Mask" "F.Paste")
			(net "GND")
		)
		(pad "B17" smd rect
			(at -1.27762 -8.865108 90)
			(size 0.3556 1.2192)
			(layers "F.Cu" "F.Mask" "F.Paste")
			(net "P5E_PEX3_STN0_TX_C_DN<0>")
		)
		(pad "B18" smd rect
			(at -1.27762 -8.264906 90)
			(size 0.3556 1.2192)
			(layers "F.Cu" "F.Mask" "F.Paste")
			(net "P5E_PEX3_STN0_TX_C_DP<0>")
		)
		(pad "B19" smd rect
			(at -1.27762 -7.664958 90)
			(size 0.3556 1.2192)
			(layers "F.Cu" "F.Mask" "F.Paste")
			(net "GND")
		)
		(pad "B20" smd rect
			(at -1.27762 -7.06501 90)
			(size 0.3556 1.2192)
			(layers "F.Cu" "F.Mask" "F.Paste")
			(net "P5E_PEX3_STN0_TX_C_DN<1>")
		)
		(pad "B21" smd rect
			(at -1.27762 -6.465062 90)
			(size 0.3556 1.2192)
			(layers "F.Cu" "F.Mask" "F.Paste")
			(net "P5E_PEX3_STN0_TX_C_DP<1>")
		)
		(pad "B22" smd rect
			(at -1.27762 -5.865114 90)
			(size 0.3556 1.2192)
			(layers "F.Cu" "F.Mask" "F.Paste")
			(net "GND")
		)
		(pad "B23" smd rect
			(at -1.27762 -5.264912 90)
			(size 0.3556 1.2192)
			(layers "F.Cu" "F.Mask" "F.Paste")
			(net "P5E_PEX3_STN0_TX_C_DN<2>")
		)
		(pad "B24" smd rect
			(at -1.27762 -4.664964 90)
			(size 0.3556 1.2192)
			(layers "F.Cu" "F.Mask" "F.Paste")
			(net "P5E_PEX3_STN0_TX_C_DP<2>")
		)
		(pad "B25" smd rect
			(at -1.27762 -4.065016 90)
			(size 0.3556 1.2192)
			(layers "F.Cu" "F.Mask" "F.Paste")
			(net "GND")
		)
		(pad "B26" smd rect
			(at -1.27762 -3.465068 90)
			(size 0.3556 1.2192)
			(layers "F.Cu" "F.Mask" "F.Paste")
			(net "P5E_PEX3_STN0_TX_C_DN<3>")
		)
		(pad "B27" smd rect
			(at -1.27762 -2.86512 90)
			(size 0.3556 1.2192)
			(layers "F.Cu" "F.Mask" "F.Paste")
			(net "P5E_PEX3_STN0_TX_C_DP<3>")
		)
		(pad "B28" smd rect
			(at -1.27762 -2.264918 90)
			(size 0.3556 1.2192)
			(layers "F.Cu" "F.Mask" "F.Paste")
			(net "GND")
		)
		(pad "B29" smd rect
			(at -1.27762 1.74498 90)
			(size 0.3556 1.2192)
			(layers "F.Cu" "F.Mask" "F.Paste")
			(net "GND")
		)
		(pad "B30" smd rect
			(at -1.27762 2.344928 90)
			(size 0.3556 1.2192)
			(layers "F.Cu" "F.Mask" "F.Paste")
			(net "P5E_PEX3_STN0_TX_C_DN<4>")
		)
		(pad "B31" smd rect
			(at -1.27762 2.944876 90)
			(size 0.3556 1.2192)
			(layers "F.Cu" "F.Mask" "F.Paste")
			(net "P5E_PEX3_STN0_TX_C_DP<4>")
		)
		(pad "B32" smd rect
			(at -1.27762 3.545078 90)
			(size 0.3556 1.2192)
			(layers "F.Cu" "F.Mask" "F.Paste")
			(net "GND")
		)
		(pad "B33" smd rect
			(at -1.27762 4.145026 90)
			(size 0.3556 1.2192)
			(layers "F.Cu" "F.Mask" "F.Paste")
			(net "P5E_PEX3_STN0_TX_C_DN<5>")
		)
		(pad "B34" smd rect
			(at -1.27762 4.744974 90)
			(size 0.3556 1.2192)
			(layers "F.Cu" "F.Mask" "F.Paste")
			(net "P5E_PEX3_STN0_TX_C_DP<5>")
		)
		(pad "B35" smd rect
			(at -1.27762 5.344922 90)
			(size 0.3556 1.2192)
			(layers "F.Cu" "F.Mask" "F.Paste")
			(net "GND")
		)
		(pad "B36" smd rect
			(at -1.27762 5.945124 90)
			(size 0.3556 1.2192)
			(layers "F.Cu" "F.Mask" "F.Paste")
			(net "P5E_PEX3_STN0_TX_C_DN<6>")
		)
		(pad "B37" smd rect
			(at -1.27762 6.545072 90)
			(size 0.3556 1.2192)
			(layers "F.Cu" "F.Mask" "F.Paste")
			(net "P5E_PEX3_STN0_TX_C_DP<6>")
		)
		(pad "B38" smd rect
			(at -1.27762 7.14502 90)
			(size 0.3556 1.2192)
			(layers "F.Cu" "F.Mask" "F.Paste")
			(net "GND")
		)
		(pad "B39" smd rect
			(at -1.27762 7.744968 90)
			(size 0.3556 1.2192)
			(layers "F.Cu" "F.Mask" "F.Paste")
			(net "P5E_PEX3_STN0_TX_C_DN<7>")
		)
		(pad "B40" smd rect
			(at -1.27762 8.344916 90)
			(size 0.3556 1.2192)
			(layers "F.Cu" "F.Mask" "F.Paste")
			(net "P5E_PEX3_STN0_TX_C_DP<7>")
		)
		(pad "B41" smd rect
			(at -1.27762 8.945118 90)
			(size 0.3556 1.2192)
			(layers "F.Cu" "F.Mask" "F.Paste")
			(net "GND")
		)
		(pad "B42" smd rect
			(at -1.27762 9.545066 90)
			(size 0.3556 1.2192)
			(layers "F.Cu" "F.Mask" "F.Paste")
			(net "PRSNTB0_NIC7_N")
		)
		(pad "B43" smd rect
			(at -1.27762 14.454886 90)
			(size 0.3556 1.2192)
			(layers "F.Cu" "F.Mask" "F.Paste")
			(net "GND")
		)
		(pad "B44" smd rect
			(at -1.27762 15.055088 90)
			(size 0.3556 1.2192)
			(layers "F.Cu" "F.Mask" "F.Paste")
			(net "P5E_PEX3_STN0_TX_C_DN<8>")
		)
		(pad "B45" smd rect
			(at -1.27762 15.655036 90)
			(size 0.3556 1.2192)
			(layers "F.Cu" "F.Mask" "F.Paste")
			(net "P5E_PEX3_STN0_TX_C_DP<8>")
		)
		(pad "B46" smd rect
			(at -1.27762 16.254984 90)
			(size 0.3556 1.2192)
			(layers "F.Cu" "F.Mask" "F.Paste")
			(net "GND")
		)
		(pad "B47" smd rect
			(at -1.27762 16.854932 90)
			(size 0.3556 1.2192)
			(layers "F.Cu" "F.Mask" "F.Paste")
			(net "P5E_PEX3_STN0_TX_C_DN<9>")
		)
		(pad "B48" smd rect
			(at -1.27762 17.45488 90)
			(size 0.3556 1.2192)
			(layers "F.Cu" "F.Mask" "F.Paste")
			(net "P5E_PEX3_STN0_TX_C_DP<9>")
		)
		(pad "B49" smd rect
			(at -1.27762 18.055082 90)
			(size 0.3556 1.2192)
			(layers "F.Cu" "F.Mask" "F.Paste")
			(net "GND")
		)
		(pad "B50" smd rect
			(at -1.27762 18.65503 90)
			(size 0.3556 1.2192)
			(layers "F.Cu" "F.Mask" "F.Paste")
			(net "P5E_PEX3_STN0_TX_C_DN<10>")
		)
		(pad "B51" smd rect
			(at -1.27762 19.254978 90)
			(size 0.3556 1.2192)
			(layers "F.Cu" "F.Mask" "F.Paste")
			(net "P5E_PEX3_STN0_TX_C_DP<10>")
		)
		(pad "B52" smd rect
			(at -1.27762 19.854926 90)
			(size 0.3556 1.2192)
			(layers "F.Cu" "F.Mask" "F.Paste")
			(net "GND")
		)
		(pad "B53" smd rect
			(at -1.27762 20.455128 90)
			(size 0.3556 1.2192)
			(layers "F.Cu" "F.Mask" "F.Paste")
			(net "P5E_PEX3_STN0_TX_C_DN<11>")
		)
		(pad "B54" smd rect
			(at -1.27762 21.055076 90)
			(size 0.3556 1.2192)
			(layers "F.Cu" "F.Mask" "F.Paste")
			(net "P5E_PEX3_STN0_TX_C_DP<11>")
		)
		(pad "B55" smd rect
			(at -1.27762 21.655024 90)
			(size 0.3556 1.2192)
			(layers "F.Cu" "F.Mask" "F.Paste")
			(net "GND")
		)
		(pad "B56" smd rect
			(at -1.27762 22.254972 90)
			(size 0.3556 1.2192)
			(layers "F.Cu" "F.Mask" "F.Paste")
			(net "P5E_PEX3_STN0_TX_C_DP<12>")
		)
		(pad "B57" smd rect
			(at -1.27762 22.85492 90)
			(size 0.3556 1.2192)
			(layers "F.Cu" "F.Mask" "F.Paste")
			(net "P5E_PEX3_STN0_TX_C_DN<12>")
		)
		(pad "B58" smd rect
			(at -1.27762 23.455122 90)
			(size 0.3556 1.2192)
			(layers "F.Cu" "F.Mask" "F.Paste")
			(net "GND")
		)
		(pad "B59" smd rect
			(at -1.27762 24.05507 90)
			(size 0.3556 1.2192)
			(layers "F.Cu" "F.Mask" "F.Paste")
			(net "P5E_PEX3_STN0_TX_C_DN<13>")
		)
		(pad "B60" smd rect
			(at -1.27762 24.655018 90)
			(size 0.3556 1.2192)
			(layers "F.Cu" "F.Mask" "F.Paste")
			(net "P5E_PEX3_STN0_TX_C_DP<13>")
		)
		(pad "B61" smd rect
			(at -1.27762 25.254966 90)
			(size 0.3556 1.2192)
			(layers "F.Cu" "F.Mask" "F.Paste")
			(net "GND")
		)
		(pad "B62" smd rect
			(at -1.27762 25.854914 90)
			(size 0.3556 1.2192)
			(layers "F.Cu" "F.Mask" "F.Paste")
			(net "P5E_PEX3_STN0_TX_C_DP<14>")
		)
		(pad "B63" smd rect
			(at -1.27762 26.455116 90)
			(size 0.3556 1.2192)
			(layers "F.Cu" "F.Mask" "F.Paste")
			(net "P5E_PEX3_STN0_TX_C_DN<14>")
		)
		(pad "B64" smd rect
			(at -1.27762 27.055064 90)
			(size 0.3556 1.2192)
			(layers "F.Cu" "F.Mask" "F.Paste")
			(net "GND")
		)
		(pad "B65" smd rect
			(at -1.27762 27.655012 90)
			(size 0.3556 1.2192)
			(layers "F.Cu" "F.Mask" "F.Paste")
			(net "P5E_PEX3_STN0_TX_C_DN<15>")
		)
		(pad "B66" smd rect
			(at -1.27762 28.25496 90)
			(size 0.3556 1.2192)
			(layers "F.Cu" "F.Mask" "F.Paste")
			(net "P5E_PEX3_STN0_TX_C_DP<15>")
		)
		(pad "B67" smd rect
			(at -1.27762 28.854908 90)
			(size 0.3556 1.2192)
			(layers "F.Cu" "F.Mask" "F.Paste")
			(net "GND")
		)
		(pad "B68" smd rect
			(at -1.27762 29.45511 90)
			(size 0.3556 1.2192)
			(layers "F.Cu" "F.Mask" "F.Paste")
			(net "Net_2672")
		)
		(pad "B69" smd rect
			(at -1.27762 30.055058 90)
			(size 0.3556 1.2192)
			(layers "F.Cu" "F.Mask" "F.Paste")
			(net "Net_2673")
		)
		(pad "B70" smd rect
			(at -1.27762 30.655006 90)
			(size 0.3556 1.2192)
			(layers "F.Cu" "F.Mask" "F.Paste")
			(net "PRSNTB3_NIC7_N")
		)
		(pad "G1" thru_hole oval
			(at 1.022604 -34.034984 90)
			(size 1.6256 3.4798)
			(drill oval 1.1176 2.4638)
			(layers "*.Cu" "*.Mask")
			(remove_unused_layers no)
			(net "GND")
			(clearance 0.127)
			(thermal_gap 0.127)
		)
		(pad "G2" thru_hole oval
			(at 1.022604 -20.625054 90)
			(size 1.6256 3.4798)
			(drill oval 1.1176 2.4638)
			(layers "*.Cu" "*.Mask")
			(remove_unused_layers no)
			(net "GND")
			(clearance 0.127)
			(thermal_gap 0.127)
		)
		(pad "G3" thru_hole oval
			(at 1.022604 -0.255016 90)
			(size 1.6256 3.4798)
			(drill oval 1.1176 2.4638)
			(layers "*.Cu" "*.Mask")
			(remove_unused_layers no)
			(net "GND")
			(clearance 0.127)
			(thermal_gap 0.127)
		)
		(pad "G4" thru_hole oval
			(at 1.022604 12.005056 90)
			(size 1.6256 3.4798)
			(drill oval 1.1176 2.4638)
			(layers "*.Cu" "*.Mask")
			(remove_unused_layers no)
			(net "GND")
			(clearance 0.127)
			(thermal_gap 0.127)
		)
		(pad "G5" thru_hole oval
			(at 1.022604 34.034984 90)
			(size 1.5748 3.4798)
			(drill oval 1.1176 2.4638)
			(layers "*.Cu" "*.Mask")
			(remove_unused_layers no)
			(net "GND")
			(clearance 0.1524)
			(thermal_gap 0.1524)
		)
		(pad "G6" thru_hole circle
			(at -3.16738 -20.625054 180)
			(size 1.6256 1.6256)
			(drill 1.1176)
			(layers "*.Cu" "*.Mask")
			(remove_unused_layers no)
			(net "GND")
			(clearance 0)
		)
		(pad "G7" thru_hole circle
			(at -3.16738 12.005056 180)
			(size 1.6256 1.6256)
			(drill 1.1176)
			(layers "*.Cu" "*.Mask")
			(remove_unused_layers no)
			(net "GND")
			(clearance 0)
		)
		(pad "G8" thru_hole circle
			(at 4.20243 -20.625054 180)
			(size 1.6256 1.6256)
			(drill 1.1176)
			(layers "*.Cu" "*.Mask")
			(remove_unused_layers no)
			(net "GND")
			(clearance 0)
		)
		(pad "G9" thru_hole circle
			(at 4.20243 12.005056 180)
			(size 1.6256 1.6256)
			(drill 1.1176)
			(layers "*.Cu" "*.Mask")
			(remove_unused_layers no)
			(net "GND")
			(clearance 0)
		)
		(pad "OA1" smd rect
			(at 3.322574 -30.660086 90)
			(size 0.3556 1.2192)
			(layers "F.Cu" "F.Mask" "F.Paste")
			(net "RST_NIC7_PERST2_R_N")
		)
		(pad "OA2" smd rect
			(at 3.322574 -30.059884 90)
			(size 0.3556 1.2192)
			(layers "F.Cu" "F.Mask" "F.Paste")
			(net "RST_NIC7_PERST3_R_N")
		)
		(pad "OA3" smd rect
			(at 3.322574 -29.459936 90)
			(size 0.3556 1.2192)
			(layers "F.Cu" "F.Mask" "F.Paste")
			(net "Net_2676")
		)
		(pad "OA4" smd rect
			(at 3.322574 -28.859988 90)
			(size 0.3556 1.2192)
			(layers "F.Cu" "F.Mask" "F.Paste")
			(net "NIC7_RBT_ARB_IN")
		)
		(pad "OA5" smd rect
			(at 3.322574 -28.26004 90)
			(size 0.3556 1.2192)
			(layers "F.Cu" "F.Mask" "F.Paste")
			(net "NIC7_RBT_ARB_OUT")
		)
		(pad "OA6" smd rect
			(at 3.322574 -27.660092 90)
			(size 0.3556 1.2192)
			(layers "F.Cu" "F.Mask" "F.Paste")
			(net "NIC7_SLOT_ID1")
		)
		(pad "OA7" smd rect
			(at 3.322574 -27.05989 90)
			(size 0.3556 1.2192)
			(layers "F.Cu" "F.Mask" "F.Paste")
			(net "NCSI_NIC7_TX_EN")
		)
		(pad "OA8" smd rect
			(at 3.322574 -26.459942 90)
			(size 0.3556 1.2192)
			(layers "F.Cu" "F.Mask" "F.Paste")
			(net "NCSI_NIC7_TXD1")
		)
		(pad "OA9" smd rect
			(at 3.322574 -25.859994 90)
			(size 0.3556 1.2192)
			(layers "F.Cu" "F.Mask" "F.Paste")
			(net "NCSI_NIC7_TXD0")
		)
		(pad "OA10" smd rect
			(at 3.322574 -25.260046 90)
			(size 0.3556 1.2192)
			(layers "F.Cu" "F.Mask" "F.Paste")
			(net "GND")
		)
		(pad "OA11" smd rect
			(at 3.322574 -24.660098 90)
			(size 0.3556 1.2192)
			(layers "F.Cu" "F.Mask" "F.Paste")
			(net "Net_2668")
		)
		(pad "OA12" smd rect
			(at 3.322574 -24.059896 90)
			(size 0.3556 1.2192)
			(layers "F.Cu" "F.Mask" "F.Paste")
			(net "Net_2671")
		)
		(pad "OA13" smd rect
			(at 3.322574 -23.459948 90)
			(size 0.3556 1.2192)
			(layers "F.Cu" "F.Mask" "F.Paste")
			(net "GND")
		)
		(pad "OA14" smd rect
			(at 3.322574 -22.86 90)
			(size 0.3556 1.2192)
			(layers "F.Cu" "F.Mask" "F.Paste")
			(net "CLK_50M_NIC7_RBT_REF")
		)
		(pad "OB1" smd rect
			(at -1.27762 -30.660086 90)
			(size 0.3556 1.2192)
			(layers "F.Cu" "F.Mask" "F.Paste")
			(net "PWRGD_NIC7_PWR_GOOD")
		)
		(pad "OB2" smd rect
			(at -1.27762 -30.059884 90)
			(size 0.3556 1.2192)
			(layers "F.Cu" "F.Mask" "F.Paste")
			(net "NIC7_MAIN_PWR_EN_R")
		)
		(pad "OB3" smd rect
			(at -1.27762 -29.459936 90)
			(size 0.3556 1.2192)
			(layers "F.Cu" "F.Mask" "F.Paste")
			(net "NIC7_LD_N")
		)
		(pad "OB4" smd rect
			(at -1.27762 -28.859988 90)
			(size 0.3556 1.2192)
			(layers "F.Cu" "F.Mask" "F.Paste")
			(net "NIC7_DATA_IN")
		)
		(pad "OB5" smd rect
			(at -1.27762 -28.26004 90)
			(size 0.3556 1.2192)
			(layers "F.Cu" "F.Mask" "F.Paste")
			(net "NIC7_DATA_OUT")
		)
		(pad "OB6" smd rect
			(at -1.27762 -27.660092 90)
			(size 0.3556 1.2192)
			(layers "F.Cu" "F.Mask" "F.Paste")
			(net "NIC7_CLK")
		)
		(pad "OB7" smd rect
			(at -1.27762 -27.05989 90)
			(size 0.3556 1.2192)
			(layers "F.Cu" "F.Mask" "F.Paste")
			(net "NIC7_SLOT_ID0")
		)
		(pad "OB8" smd rect
			(at -1.27762 -26.459942 90)
			(size 0.3556 1.2192)
			(layers "F.Cu" "F.Mask" "F.Paste")
			(net "NCSI_NIC7_RXD1")
		)
		(pad "OB9" smd rect
			(at -1.27762 -25.859994 90)
			(size 0.3556 1.2192)
			(layers "F.Cu" "F.Mask" "F.Paste")
			(net "NCSI_NIC7_RXD0")
		)
		(pad "OB10" smd rect
			(at -1.27762 -25.260046 90)
			(size 0.3556 1.2192)
			(layers "F.Cu" "F.Mask" "F.Paste")
			(net "GND")
		)
		(pad "OB11" smd rect
			(at -1.27762 -24.660098 90)
			(size 0.3556 1.2192)
			(layers "F.Cu" "F.Mask" "F.Paste")
			(net "Net_2667")
		)
		(pad "OB12" smd rect
			(at -1.27762 -24.059896 90)
			(size 0.3556 1.2192)
			(layers "F.Cu" "F.Mask" "F.Paste")
			(net "Net_2670")
		)
		(pad "OB13" smd rect
			(at -1.27762 -23.459948 90)
			(size 0.3556 1.2192)
			(layers "F.Cu" "F.Mask" "F.Paste")
			(net "GND")
		)
		(pad "OB14" smd rect
			(at -1.27762 -22.86 90)
			(size 0.3556 1.2192)
			(layers "F.Cu" "F.Mask" "F.Paste")
			(net "NCSI_NIC7_CRS_DV")
		)
		(zone
			(layers "F.Cu" "B.Cu" "In1.Cu" "In2.Cu" "In3.Cu" "In4.Cu" "In5.Cu" "In6.Cu"
				"In7.Cu" "In8.Cu" "In9.Cu" "In10.Cu" "In11.Cu" "In12.Cu" "In13.Cu" "In14.Cu"
				"In15.Cu" "In16.Cu"
			)
			(hatch none 0.5)
			(connect_pads
				(clearance 0)
			)
			(min_thickness 0.25)
			(keepout
				(tracks not_allowed)
				(vias allowed)
				(pads allowed)
				(copperpour not_allowed)
				(footprints allowed)
			)
			(placement
				(enabled no)
				(sheetname "")
			)
			(fill
				(thermal_gap 0.5)
				(thermal_bridge_width 0.5)
				(island_removal_mode 0)
			)
			(polygon
				(pts
					(arc
						(start 420.324534 -160.1851)
						(mid 418.190426 -160.1851)
						(end 420.324534 -160.1851)
					)
				)
			)
		)
		(zone
			(layers "F.Cu" "B.Cu" "In1.Cu" "In2.Cu" "In3.Cu" "In4.Cu" "In5.Cu" "In6.Cu"
				"In7.Cu" "In8.Cu" "In9.Cu" "In10.Cu" "In11.Cu" "In12.Cu" "In13.Cu" "In14.Cu"
				"In15.Cu" "In16.Cu"
			)
			(hatch none 0.5)
			(connect_pads
				(clearance 0)
			)
			(min_thickness 0.25)
			(keepout
				(tracks not_allowed)
				(vias allowed)
				(pads allowed)
				(copperpour not_allowed)
				(footprints allowed)
			)
			(placement
				(enabled no)
				(sheetname "")
			)
			(fill
				(thermal_gap 0.5)
				(thermal_bridge_width 0.5)
				(island_removal_mode 0)
			)
			(polygon
				(pts
					(arc
						(start 422.07434 -95.214948)
						(mid 419.94074 -95.214948)
						(end 422.07434 -95.214948)
					)
				)
			)
		)
	)
	(footprint ""
		(layer "F.Cu")
		(at 237.924848 -83.951318 180)
		(property "Reference" "R6724"
			(at 0 0 180)
			(layer "F.SilkS")
			(hide yes)
			(effects
				(font
					(size 1.27 1.27)
				)
			)
		)
		(property "Value" ""
			(at 0 0 180)
			(layer "F.Fab")
			(effects
				(font
					(size 1.27 1.27)
				)
			)
		)
		(duplicate_pad_numbers_are_jumpers no)
		(fp_line
			(start 0.7874 0.4064)
			(end -0.7874 0.4064)
			(stroke
				(width 0.1524)
				(type default)
			)
			(layer "F.SilkS")
		)
		(fp_line
			(start 0.7874 -0.4064)
			(end 0.7874 0.4064)
			(stroke
				(width 0.1524)
				(type default)
			)
			(layer "F.SilkS")
		)
		(fp_line
			(start -0.01651 -0.4064)
			(end 0.7874 -0.4064)
			(stroke
				(width 0.1524)
				(type default)
			)
			(layer "F.SilkS")
		)
		(fp_line
			(start -0.7874 0.4064)
			(end -0.7874 -0.4064)
			(stroke
				(width 0.1524)
				(type default)
			)
			(layer "F.SilkS")
		)
		(fp_line
			(start 0.67945 0.3048)
			(end 0.120396 0.3048)
			(stroke
				(width 0.1)
				(type default)
			)
			(layer "F.Fab")
		)
		(fp_line
			(start 0.67945 -0.3048)
			(end 0.67945 0.3048)
			(stroke
				(width 0.1)
				(type default)
			)
			(layer "F.Fab")
		)
		(fp_line
			(start 0.12065 -0.2794)
			(end 0.12065 -0.3048)
			(stroke
				(width 0.1)
				(type default)
			)
			(layer "F.Fab")
		)
		(fp_line
			(start 0.12065 -0.3048)
			(end 0.67945 -0.3048)
			(stroke
				(width 0.1)
				(type default)
			)
			(layer "F.Fab")
		)
		(fp_line
			(start 0.120396 0.3048)
			(end 0.120396 0.2794)
			(stroke
				(width 0.1)
				(type default)
			)
			(layer "F.Fab")
		)
		(fp_line
			(start 0.120396 0.2794)
			(end -0.12065 0.2794)
			(stroke
				(width 0.1)
				(type default)
			)
			(layer "F.Fab")
		)
		(fp_line
			(start -0.12065 0.3048)
			(end -0.67945 0.3048)
			(stroke
				(width 0.1)
				(type default)
			)
			(layer "F.Fab")
		)
		(fp_line
			(start -0.12065 0.2794)
			(end -0.12065 0.3048)
			(stroke
				(width 0.1)
				(type default)
			)
			(layer "F.Fab")
		)
		(fp_line
			(start -0.12065 -0.2794)
			(end 0.12065 -0.2794)
			(stroke
				(width 0.1)
				(type default)
			)
			(layer "F.Fab")
		)
		(fp_line
			(start -0.12065 -0.305054)
			(end -0.12065 -0.2794)
			(stroke
				(width 0.1)
				(type default)
			)
			(layer "F.Fab")
		)
		(fp_line
			(start -0.67945 0.3048)
			(end -0.67945 -0.305054)
			(stroke
				(width 0.1)
				(type default)
			)
			(layer "F.Fab")
		)
		(fp_line
			(start -0.67945 -0.305054)
			(end -0.12065 -0.305054)
			(stroke
				(width 0.1)
				(type default)
			)
			(layer "F.Fab")
		)
		(pad "1" smd rect
			(at -0.40005 0)
			(size 0.4572 0.508)
			(layers "F.Cu" "F.Mask" "F.Paste")
			(net "USB2_CP2108_CLI_DN")
		)
		(pad "2" smd rect
			(at 0.40005 0)
			(size 0.4572 0.508)
			(layers "F.Cu" "F.Mask" "F.Paste")
			(net "GND")
		)
	)
	(footprint ""
		(layer "F.Cu")
		(at 209.165698 -304.036476 90)
		(property "Reference" "R4178"
			(at 0 0 90)
			(layer "F.SilkS")
			(hide yes)
			(effects
				(font
					(size 1.27 1.27)
				)
			)
		)
		(property "Value" ""
			(at 0 0 90)
			(layer "F.Fab")
			(effects
				(font
					(size 1.27 1.27)
				)
			)
		)
		(duplicate_pad_numbers_are_jumpers no)
		(fp_line
			(start 0.7874 -0.4064)
			(end 0.7874 0.4064)
			(stroke
				(width 0.1524)
				(type default)
			)
			(layer "F.SilkS")
		)
		(fp_line
			(start -0.7874 -0.4064)
			(end 0.7874 -0.4064)
			(stroke
				(width 0.1524)
				(type default)
			)
			(layer "F.SilkS")
		)
		(fp_line
			(start 0.7874 0.4064)
			(end -0.7874 0.4064)
			(stroke
				(width 0.1524)
				(type default)
			)
			(layer "F.SilkS")
		)
		(fp_line
			(start -0.7874 0.4064)
			(end -0.7874 -0.4064)
			(stroke
				(width 0.1524)
				(type default)
			)
			(layer "F.SilkS")
		)
		(fp_line
			(start -0.12065 -0.305054)
			(end -0.12065 -0.2794)
			(stroke
				(width 0.1)
				(type default)
			)
			(layer "F.Fab")
		)
		(fp_line
			(start -0.67945 -0.305054)
			(end -0.12065 -0.305054)
			(stroke
				(width 0.1)
				(type default)
			)
			(layer "F.Fab")
		)
		(fp_line
			(start 0.67945 -0.3048)
			(end 0.67945 0.3048)
			(stroke
				(width 0.1)
				(type default)
			)
			(layer "F.Fab")
		)
		(fp_line
			(start 0.12065 -0.3048)
			(end 0.67945 -0.3048)
			(stroke
				(width 0.1)
				(type default)
			)
			(layer "F.Fab")
		)
		(fp_line
			(start 0.12065 -0.2794)
			(end 0.12065 -0.3048)
			(stroke
				(width 0.1)
				(type default)
			)
			(layer "F.Fab")
		)
		(fp_line
			(start -0.12065 -0.2794)
			(end 0.12065 -0.2794)
			(stroke
				(width 0.1)
				(type default)
			)
			(layer "F.Fab")
		)
		(fp_line
			(start 0.120396 0.2794)
			(end -0.12065 0.2794)
			(stroke
				(width 0.1)
				(type default)
			)
			(layer "F.Fab")
		)
		(fp_line
			(start -0.12065 0.2794)
			(end -0.12065 0.3048)
			(stroke
				(width 0.1)
				(type default)
			)
			(layer "F.Fab")
		)
		(fp_line
			(start 0.67945 0.3048)
			(end 0.120396 0.3048)
			(stroke
				(width 0.1)
				(type default)
			)
			(layer "F.Fab")
		)
		(fp_line
			(start 0.120396 0.3048)
			(end 0.120396 0.2794)
			(stroke
				(width 0.1)
				(type default)
			)
			(layer "F.Fab")
		)
		(fp_line
			(start -0.12065 0.3048)
			(end -0.67945 0.3048)
			(stroke
				(width 0.1)
				(type default)
			)
			(layer "F.Fab")
		)
		(fp_line
			(start -0.67945 0.3048)
			(end -0.67945 -0.305054)
			(stroke
				(width 0.1)
				(type default)
			)
			(layer "F.Fab")
		)
		(pad "1" smd circle
			(at -0.40005 0 90)
			(size 0 0)
			(layers "F.Cu" "F.Mask" "F.Paste")
			(net "GND")
		)
		(pad "2" smd circle
			(at 0.40005 0 90)
			(size 0 0)
			(layers "F.Cu" "F.Mask" "F.Paste")
			(net "PEX1_EXT_GPIO_LATCH_N")
		)
	)
	(footprint ""
		(layer "F.Cu")
		(at 344.918792 -240.691162 90)
		(property "Reference" "R3582"
			(at 0 0 90)
			(layer "F.SilkS")
			(hide yes)
			(effects
				(font
					(size 1.27 1.27)
				)
			)
		)
		(property "Value" ""
			(at 0 0 90)
			(layer "F.Fab")
			(effects
				(font
					(size 1.27 1.27)
				)
			)
		)
		(duplicate_pad_numbers_are_jumpers no)
		(fp_line
			(start 0.7874 -0.4064)
			(end 0.7874 0.4064)
			(stroke
				(width 0.1524)
				(type default)
			)
			(layer "F.SilkS")
		)
		(fp_line
			(start -0.7874 -0.4064)
			(end 0.7874 -0.4064)
			(stroke
				(width 0.1524)
				(type default)
			)
			(layer "F.SilkS")
		)
		(fp_line
			(start 0.7874 0.4064)
			(end -0.7874 0.4064)
			(stroke
				(width 0.1524)
				(type default)
			)
			(layer "F.SilkS")
		)
		(fp_line
			(start -0.7874 0.4064)
			(end -0.7874 -0.4064)
			(stroke
				(width 0.1524)
				(type default)
			)
			(layer "F.SilkS")
		)
		(fp_line
			(start -0.12065 -0.305054)
			(end -0.12065 -0.2794)
			(stroke
				(width 0.1)
				(type default)
			)
			(layer "F.Fab")
		)
		(fp_line
			(start -0.67945 -0.305054)
			(end -0.12065 -0.305054)
			(stroke
				(width 0.1)
				(type default)
			)
			(layer "F.Fab")
		)
		(fp_line
			(start 0.67945 -0.3048)
			(end 0.67945 0.3048)
			(stroke
				(width 0.1)
				(type default)
			)
			(layer "F.Fab")
		)
		(fp_line
			(start 0.12065 -0.3048)
			(end 0.67945 -0.3048)
			(stroke
				(width 0.1)
				(type default)
			)
			(layer "F.Fab")
		)
		(fp_line
			(start 0.12065 -0.2794)
			(end 0.12065 -0.3048)
			(stroke
				(width 0.1)
				(type default)
			)
			(layer "F.Fab")
		)
		(fp_line
			(start -0.12065 -0.2794)
			(end 0.12065 -0.2794)
			(stroke
				(width 0.1)
				(type default)
			)
			(layer "F.Fab")
		)
		(fp_line
			(start 0.120396 0.2794)
			(end -0.12065 0.2794)
			(stroke
				(width 0.1)
				(type default)
			)
			(layer "F.Fab")
		)
		(fp_line
			(start -0.12065 0.2794)
			(end -0.12065 0.3048)
			(stroke
				(width 0.1)
				(type default)
			)
			(layer "F.Fab")
		)
		(fp_line
			(start 0.67945 0.3048)
			(end 0.120396 0.3048)
			(stroke
				(width 0.1)
				(type default)
			)
			(layer "F.Fab")
		)
		(fp_line
			(start 0.120396 0.3048)
			(end 0.120396 0.2794)
			(stroke
				(width 0.1)
				(type default)
			)
			(layer "F.Fab")
		)
		(fp_line
			(start -0.12065 0.3048)
			(end -0.67945 0.3048)
			(stroke
				(width 0.1)
				(type default)
			)
			(layer "F.Fab")
		)
		(fp_line
			(start -0.67945 0.3048)
			(end -0.67945 -0.305054)
			(stroke
				(width 0.1)
				(type default)
			)
			(layer "F.Fab")
		)
		(pad "1" smd circle
			(at -0.40005 0 90)
			(size 0 0)
			(layers "F.Cu" "F.Mask" "F.Paste")
			(net "SSD0_PWRDIS")
		)
		(pad "2" smd circle
			(at 0.40005 0 90)
			(size 0 0)
			(layers "F.Cu" "F.Mask" "F.Paste")
			(net "SSD0_PWRDIS_R")
		)
	)
	(footprint ""
		(layer "F.Cu")
		(at 430.961546 -155.196794 180)
		(property "Reference" "C635"
			(at 0 0 180)
			(layer "F.SilkS")
			(hide yes)
			(effects
				(font
					(size 1.27 1.27)
				)
			)
		)
		(property "Value" ""
			(at 0 0 180)
			(layer "F.Fab")
			(effects
				(font
					(size 1.27 1.27)
				)
			)
		)
		(duplicate_pad_numbers_are_jumpers no)
		(fp_line
			(start 0.299974 0.150114)
			(end -0.299974 0.150114)
			(stroke
				(width 0.1)
				(type default)
			)
			(layer "F.Fab")
		)
		(fp_line
			(start 0.299974 -0.150114)
			(end 0.299974 0.150114)
			(stroke
				(width 0.1)
				(type default)
			)
			(layer "F.Fab")
		)
		(fp_line
			(start -0.299974 0.150114)
			(end -0.299974 -0.150114)
			(stroke
				(width 0.1)
				(type default)
			)
			(layer "F.Fab")
		)
		(fp_line
			(start -0.299974 -0.150114)
			(end 0.299974 -0.150114)
			(stroke
				(width 0.1)
				(type default)
			)
			(layer "F.Fab")
		)
		(pad "1" smd rect
			(at -0.2667 0 180)
			(size 0.3048 0.381)
			(layers "F.Cu" "F.Mask" "F.Paste")
			(net "P5E_PEX3_STN0_TX_DN<15>")
		)
		(pad "2" smd rect
			(at 0.2667 0 180)
			(size 0.3048 0.381)
			(layers "F.Cu" "F.Mask" "F.Paste")
			(net "P5E_PEX3_STN0_TX_C_DN<15>")
		)
	)
	(footprint ""
		(layer "F.Cu")
		(at 77.06233 -22.955504 -90)
		(property "Reference" "C2715"
			(at 0 0 270)
			(layer "F.SilkS")
			(hide yes)
			(effects
				(font
					(size 1.27 1.27)
				)
			)
		)
		(property "Value" ""
			(at 0 0 270)
			(layer "F.Fab")
			(effects
				(font
					(size 1.27 1.27)
				)
			)
		)
		(duplicate_pad_numbers_are_jumpers no)
		(fp_line
			(start -0.7874 0.4064)
			(end -0.7874 -0.4064)
			(stroke
				(width 0.1524)
				(type default)
			)
			(layer "F.SilkS")
		)
		(fp_line
			(start 0.7874 0.4064)
			(end -0.7874 0.4064)
			(stroke
				(width 0.1524)
				(type default)
			)
			(layer "F.SilkS")
		)
		(fp_line
			(start -0.7874 -0.4064)
			(end 0.7874 -0.4064)
			(stroke
				(width 0.1524)
				(type default)
			)
			(layer "F.SilkS")
		)
		(fp_line
			(start 0.7874 -0.4064)
			(end 0.7874 0.4064)
			(stroke
				(width 0.1524)
				(type default)
			)
			(layer "F.SilkS")
		)
		(fp_line
			(start -0.67945 0.3048)
			(end -0.67945 -0.305054)
			(stroke
				(width 0.1)
				(type default)
			)
			(layer "F.Fab")
		)
		(fp_line
			(start -0.12065 0.3048)
			(end -0.67945 0.3048)
			(stroke
				(width 0.1)
				(type default)
			)
			(layer "F.Fab")
		)
		(fp_line
			(start 0.120396 0.3048)
			(end 0.120396 0.2794)
			(stroke
				(width 0.1)
				(type default)
			)
			(layer "F.Fab")
		)
		(fp_line
			(start 0.67945 0.3048)
			(end 0.120396 0.3048)
			(stroke
				(width 0.1)
				(type default)
			)
			(layer "F.Fab")
		)
		(fp_line
			(start -0.12065 0.2794)
			(end -0.12065 0.3048)
			(stroke
				(width 0.1)
				(type default)
			)
			(layer "F.Fab")
		)
		(fp_line
			(start 0.120396 0.2794)
			(end -0.12065 0.2794)
			(stroke
				(width 0.1)
				(type default)
			)
			(layer "F.Fab")
		)
		(fp_line
			(start -0.12065 -0.2794)
			(end 0.12065 -0.2794)
			(stroke
				(width 0.1)
				(type default)
			)
			(layer "F.Fab")
		)
		(fp_line
			(start 0.12065 -0.2794)
			(end 0.12065 -0.3048)
			(stroke
				(width 0.1)
				(type default)
			)
			(layer "F.Fab")
		)
		(fp_line
			(start 0.12065 -0.3048)
			(end 0.67945 -0.3048)
			(stroke
				(width 0.1)
				(type default)
			)
			(layer "F.Fab")
		)
		(fp_line
			(start 0.67945 -0.3048)
			(end 0.67945 0.3048)
			(stroke
				(width 0.1)
				(type default)
			)
			(layer "F.Fab")
		)
		(fp_line
			(start -0.67945 -0.305054)
			(end -0.12065 -0.305054)
			(stroke
				(width 0.1)
				(type default)
			)
			(layer "F.Fab")
		)
		(fp_line
			(start -0.12065 -0.305054)
			(end -0.12065 -0.2794)
			(stroke
				(width 0.1)
				(type default)
			)
			(layer "F.Fab")
		)
		(pad "1" smd circle
			(at -0.40005 0 270)
			(size 0 0)
			(layers "F.Cu" "F.Mask" "F.Paste")
			(net "GND")
		)
		(pad "2" smd circle
			(at 0.40005 0 270)
			(size 0 0)
			(layers "F.Cu" "F.Mask" "F.Paste")
			(net "P3V3_AUX")
		)
	)
	(footprint ""
		(layer "F.Cu")
		(at 205.749652 -270.89989)
		(property "Reference" "H98"
			(at -2.32664 -8.786876 0)
			(unlocked yes)
			(layer "F.SilkS")
			(effects
				(font
					(size 0.7874 0.5842)
					(thickness 0.1524)
				)
				(justify left)
			)
		)
		(property "Value" ""
			(at 0 0 0)
			(layer "F.Fab")
			(effects
				(font
					(size 1.27 1.27)
				)
			)
		)
		(duplicate_pad_numbers_are_jumpers no)
		(fp_arc
			(start -5.489702 -5.819394)
			(mid 3.168767 -7.345623)
			(end 7.999984 0)
			(stroke
				(width 0.1524)
				(type default)
			)
			(layer "F.SilkS")
		)
		(fp_arc
			(start 7.999984 0)
			(mid -0.430148 7.988434)
			(end -7.953756 -0.859028)
			(stroke
				(width 0.1524)
				(type default)
			)
			(layer "F.SilkS")
		)
		(fp_arc
			(start -5.46735 -5.839968)
			(mid 3.182835 -7.339591)
			(end 7.999984 0)
			(stroke
				(width 0.1524)
				(type default)
			)
			(layer "B.SilkS")
		)
		(fp_arc
			(start 7.999984 0)
			(mid -0.459169 7.986684)
			(end -7.947152 -0.91694)
			(stroke
				(width 0.1524)
				(type default)
			)
			(layer "B.SilkS")
		)
		(fp_circle
			(center 0 0)
			(end 7.999984 0)
			(stroke
				(width 0.1)
				(type default)
			)
			(fill no)
			(layer "B.Fab")
		)
		(fp_circle
			(center 0 0)
			(end 7.999984 0)
			(stroke
				(width 0.1)
				(type default)
			)
			(fill no)
			(layer "F.Fab")
		)
		(pad "" np_thru_hole circle
			(at 0 0)
			(size 4.5212 4.5212)
			(drill 4.5212)
			(layers "*.Cu" "*.Mask")
			(clearance 0.381)
			(thermal_gap 0.381)
		)
		(pad "2" thru_hole circle
			(at 3.6322 0)
			(size 0.762 0.762)
			(drill 0.5588)
			(layers "*.Cu" "*.Mask")
			(remove_unused_layers no)
			(net "GND")
			(clearance 0.1524)
			(thermal_gap 0.1524)
		)
		(pad "3" thru_hole circle
			(at 2.568448 -2.568448)
			(size 0.762 0.762)
			(drill 0.5588)
			(layers "*.Cu" "*.Mask")
			(remove_unused_layers no)
			(net "GND")
			(clearance 0.1524)
			(thermal_gap 0.1524)
		)
		(pad "4" thru_hole circle
			(at 0 -3.6322)
			(size 0.762 0.762)
			(drill 0.5588)
			(layers "*.Cu" "*.Mask")
			(remove_unused_layers no)
			(net "GND")
			(clearance 0.1524)
			(thermal_gap 0.1524)
		)
		(pad "5" thru_hole circle
			(at -2.568448 -2.568448)
			(size 0.762 0.762)
			(drill 0.5588)
			(layers "*.Cu" "*.Mask")
			(remove_unused_layers no)
			(net "GND")
			(clearance 0.1524)
			(thermal_gap 0.1524)
		)
		(pad "6" thru_hole circle
			(at -3.6322 0)
			(size 0.762 0.762)
			(drill 0.5588)
			(layers "*.Cu" "*.Mask")
			(remove_unused_layers no)
			(net "GND")
			(clearance 0.1524)
			(thermal_gap 0.1524)
		)
		(pad "7" thru_hole circle
			(at -2.568448 2.568448)
			(size 0.762 0.762)
			(drill 0.5588)
			(layers "*.Cu" "*.Mask")
			(remove_unused_layers no)
			(net "GND")
			(clearance 0.1524)
			(thermal_gap 0.1524)
		)
		(pad "8" thru_hole circle
			(at 0 3.6322)
			(size 0.762 0.762)
			(drill 0.5588)
			(layers "*.Cu" "*.Mask")
			(remove_unused_layers no)
			(net "GND")
			(clearance 0.1524)
			(thermal_gap 0.1524)
		)
		(pad "9" thru_hole circle
			(at 2.568448 2.568448)
			(size 0.762 0.762)
			(drill 0.5588)
			(layers "*.Cu" "*.Mask")
			(remove_unused_layers no)
			(net "GND")
			(clearance 0.1524)
			(thermal_gap 0.1524)
		)
		(zone
			(layer "F.Cu")
			(hatch none 0.5)
			(connect_pads
				(clearance 0)
			)
			(min_thickness 0.25)
			(keepout
				(tracks not_allowed)
				(vias allowed)
				(pads allowed)
				(copperpour not_allowed)
				(footprints allowed)
			)
			(placement
				(enabled no)
				(sheetname "")
			)
			(fill
				(thermal_gap 0.5)
				(thermal_bridge_width 0.5)
				(island_removal_mode 0)
			)
			(polygon
				(pts
					(arc
						(start 205.749652 -262.899906)
						(mid 197.749668 -270.89989)
						(end 205.749652 -278.899874)
					)
					(arc
						(start 205.749652 -275.64969)
						(mid 200.999852 -270.89989)
						(end 205.749652 -266.15009)
					)
				)
			)
		)
		(zone
			(layer "F.Cu")
			(hatch none 0.5)
			(connect_pads
				(clearance 0)
			)
			(min_thickness 0.25)
			(keepout
				(tracks not_allowed)
				(vias allowed)
				(pads allowed)
				(copperpour not_allowed)
				(footprints allowed)
			)
			(placement
				(enabled no)
				(sheetname "")
			)
			(fill
				(thermal_gap 0.5)
				(thermal_bridge_width 0.5)
				(island_removal_mode 0)
			)
			(polygon
				(pts
					(arc
						(start 205.749652 -262.899906)
						(mid 213.749636 -270.89989)
						(end 205.749652 -278.899874)
					)
					(arc
						(start 205.749652 -275.64969)
						(mid 210.499452 -270.89989)
						(end 205.749652 -266.15009)
					)
				)
			)
		)
		(zone
			(layers "F.Cu" "B.Cu" "In1.Cu" "In2.Cu" "In3.Cu" "In4.Cu" "In5.Cu" "In6.Cu"
				"In7.Cu" "In8.Cu" "In9.Cu" "In10.Cu" "In11.Cu" "In12.Cu" "In13.Cu" "In14.Cu"
				"In15.Cu" "In16.Cu"
			)
			(hatch none 0.5)
			(connect_pads
				(clearance 0)
			)
			(min_thickness 0.25)
			(keepout
				(tracks not_allowed)
				(vias allowed)
				(pads allowed)
				(copperpour not_allowed)
				(footprints allowed)
			)
			(placement
				(enabled no)
				(sheetname "")
			)
			(fill
				(thermal_gap 0.5)
				(thermal_bridge_width 0.5)
				(island_removal_mode 0)
			)
			(polygon
				(pts
					(arc
						(start 208.515712 -270.89989)
						(mid 202.983592 -270.89989)
						(end 208.515712 -270.89989)
					)
				)
			)
		)
		(zone
			(layer "B.Cu")
			(hatch none 0.5)
			(connect_pads
				(clearance 0)
			)
			(min_thickness 0.25)
			(keepout
				(tracks not_allowed)
				(vias allowed)
				(pads allowed)
				(copperpour not_allowed)
				(footprints allowed)
			)
			(placement
				(enabled no)
				(sheetname "")
			)
			(fill
				(thermal_gap 0.5)
				(thermal_bridge_width 0.5)
				(island_removal_mode 0)
			)
			(polygon
				(pts
					(arc
						(start 205.749652 -265.89609)
						(mid 200.745852 -270.89989)
						(end 205.749652 -275.90369)
					)
					(arc
						(start 205.749652 -275.42109)
						(mid 201.228452 -270.89989)
						(end 205.749652 -266.37869)
					)
				)
			)
		)
		(zone
			(layer "B.Cu")
			(hatch none 0.5)
			(connect_pads
				(clearance 0)
			)
			(min_thickness 0.25)
			(keepout
				(tracks not_allowed)
				(vias allowed)
				(pads allowed)
				(copperpour not_allowed)
				(footprints allowed)
			)
			(placement
				(enabled no)
				(sheetname "")
			)
			(fill
				(thermal_gap 0.5)
				(thermal_bridge_width 0.5)
				(island_removal_mode 0)
			)
			(polygon
				(pts
					(arc
						(start 205.749652 -265.89609)
						(mid 210.753452 -270.89989)
						(end 205.749652 -275.90369)
					)
					(arc
						(start 205.749652 -275.42109)
						(mid 210.270852 -270.89989)
						(end 205.749652 -266.37869)
					)
				)
			)
		)
	)
	(footprint ""
		(layer "F.Cu")
		(at 462.465674 -274.61083)
		(property "Reference" "R806"
			(at 0 0 0)
			(layer "F.SilkS")
			(hide yes)
			(effects
				(font
					(size 1.27 1.27)
				)
			)
		)
		(property "Value" ""
			(at 0 0 0)
			(layer "F.Fab")
			(effects
				(font
					(size 1.27 1.27)
				)
			)
		)
		(duplicate_pad_numbers_are_jumpers no)
		(fp_line
			(start -0.7874 -0.4064)
			(end 0.7874 -0.4064)
			(stroke
				(width 0.1524)
				(type default)
			)
			(layer "F.SilkS")
		)
		(fp_line
			(start -0.7874 0.4064)
			(end -0.7874 -0.4064)
			(stroke
				(width 0.1524)
				(type default)
			)
			(layer "F.SilkS")
		)
		(fp_line
			(start 0.7874 -0.4064)
			(end 0.7874 0.4064)
			(stroke
				(width 0.1524)
				(type default)
			)
			(layer "F.SilkS")
		)
		(fp_line
			(start 0.7874 0.4064)
			(end -0.7874 0.4064)
			(stroke
				(width 0.1524)
				(type default)
			)
			(layer "F.SilkS")
		)
		(fp_line
			(start -0.67945 -0.305054)
			(end -0.12065 -0.305054)
			(stroke
				(width 0.1)
				(type default)
			)
			(layer "F.Fab")
		)
		(fp_line
			(start -0.67945 0.3048)
			(end -0.67945 -0.305054)
			(stroke
				(width 0.1)
				(type default)
			)
			(layer "F.Fab")
		)
		(fp_line
			(start -0.12065 -0.305054)
			(end -0.12065 -0.2794)
			(stroke
				(width 0.1)
				(type default)
			)
			(layer "F.Fab")
		)
		(fp_line
			(start -0.12065 -0.2794)
			(end 0.12065 -0.2794)
			(stroke
				(width 0.1)
				(type default)
			)
			(layer "F.Fab")
		)
		(fp_line
			(start -0.12065 0.2794)
			(end -0.12065 0.3048)
			(stroke
				(width 0.1)
				(type default)
			)
			(layer "F.Fab")
		)
		(fp_line
			(start -0.12065 0.3048)
			(end -0.67945 0.3048)
			(stroke
				(width 0.1)
				(type default)
			)
			(layer "F.Fab")
		)
		(fp_line
			(start 0.120396 0.2794)
			(end -0.12065 0.2794)
			(stroke
				(width 0.1)
				(type default)
			)
			(layer "F.Fab")
		)
		(fp_line
			(start 0.120396 0.3048)
			(end 0.120396 0.2794)
			(stroke
				(width 0.1)
				(type default)
			)
			(layer "F.Fab")
		)
		(fp_line
			(start 0.12065 -0.3048)
			(end 0.67945 -0.3048)
			(stroke
				(width 0.1)
				(type default)
			)
			(layer "F.Fab")
		)
		(fp_line
			(start 0.12065 -0.2794)
			(end 0.12065 -0.3048)
			(stroke
				(width 0.1)
				(type default)
			)
			(layer "F.Fab")
		)
		(fp_line
			(start 0.67945 -0.3048)
			(end 0.67945 0.3048)
			(stroke
				(width 0.1)
				(type default)
			)
			(layer "F.Fab")
		)
		(fp_line
			(start 0.67945 0.3048)
			(end 0.120396 0.3048)
			(stroke
				(width 0.1)
				(type default)
			)
			(layer "F.Fab")
		)
		(pad "1" smd circle
			(at -0.40005 0)
			(size 0 0)
			(layers "F.Cu" "F.Mask" "F.Paste")
			(net "PEX3_P1V25_ADC_A1")
		)
		(pad "2" smd circle
			(at 0.40005 0)
			(size 0 0)
			(layers "F.Cu" "F.Mask" "F.Paste")
			(net "GND")
		)
	)
	(footprint ""
		(layer "F.Cu")
		(at 426.567092 -57.332626)
		(property "Reference" "R6827"
			(at 0 0 0)
			(layer "F.SilkS")
			(hide yes)
			(effects
				(font
					(size 1.27 1.27)
				)
			)
		)
		(property "Value" ""
			(at 0 0 0)
			(layer "F.Fab")
			(effects
				(font
					(size 1.27 1.27)
				)
			)
		)
		(duplicate_pad_numbers_are_jumpers no)
		(fp_line
			(start -0.7874 -0.4064)
			(end 0.7874 -0.4064)
			(stroke
				(width 0.1524)
				(type default)
			)
			(layer "F.SilkS")
		)
		(fp_line
			(start -0.7874 0.4064)
			(end -0.7874 -0.4064)
			(stroke
				(width 0.1524)
				(type default)
			)
			(layer "F.SilkS")
		)
		(fp_line
			(start 0.7874 -0.4064)
			(end 0.7874 0.4064)
			(stroke
				(width 0.1524)
				(type default)
			)
			(layer "F.SilkS")
		)
		(fp_line
			(start 0.7874 0.4064)
			(end -0.7874 0.4064)
			(stroke
				(width 0.1524)
				(type default)
			)
			(layer "F.SilkS")
		)
		(fp_line
			(start -0.67945 -0.305054)
			(end -0.12065 -0.305054)
			(stroke
				(width 0.1)
				(type default)
			)
			(layer "F.Fab")
		)
		(fp_line
			(start -0.67945 0.3048)
			(end -0.67945 -0.305054)
			(stroke
				(width 0.1)
				(type default)
			)
			(layer "F.Fab")
		)
		(fp_line
			(start -0.12065 -0.305054)
			(end -0.12065 -0.2794)
			(stroke
				(width 0.1)
				(type default)
			)
			(layer "F.Fab")
		)
		(fp_line
			(start -0.12065 -0.2794)
			(end 0.12065 -0.2794)
			(stroke
				(width 0.1)
				(type default)
			)
			(layer "F.Fab")
		)
		(fp_line
			(start -0.12065 0.2794)
			(end -0.12065 0.3048)
			(stroke
				(width 0.1)
				(type default)
			)
			(layer "F.Fab")
		)
		(fp_line
			(start -0.12065 0.3048)
			(end -0.67945 0.3048)
			(stroke
				(width 0.1)
				(type default)
			)
			(layer "F.Fab")
		)
		(fp_line
			(start 0.120396 0.2794)
			(end -0.12065 0.2794)
			(stroke
				(width 0.1)
				(type default)
			)
			(layer "F.Fab")
		)
		(fp_line
			(start 0.120396 0.3048)
			(end 0.120396 0.2794)
			(stroke
				(width 0.1)
				(type default)
			)
			(layer "F.Fab")
		)
		(fp_line
			(start 0.12065 -0.3048)
			(end 0.67945 -0.3048)
			(stroke
				(width 0.1)
				(type default)
			)
			(layer "F.Fab")
		)
		(fp_line
			(start 0.12065 -0.2794)
			(end 0.12065 -0.3048)
			(stroke
				(width 0.1)
				(type default)
			)
			(layer "F.Fab")
		)
		(fp_line
			(start 0.67945 -0.3048)
			(end 0.67945 0.3048)
			(stroke
				(width 0.1)
				(type default)
			)
			(layer "F.Fab")
		)
		(fp_line
			(start 0.67945 0.3048)
			(end 0.120396 0.3048)
			(stroke
				(width 0.1)
				(type default)
			)
			(layer "F.Fab")
		)
		(pad "1" smd circle
			(at -0.40005 0)
			(size 0 0)
			(layers "F.Cu" "F.Mask" "F.Paste")
			(net "SSD14_PWR_EN_R")
		)
		(pad "2" smd circle
			(at 0.40005 0)
			(size 0 0)
			(layers "F.Cu" "F.Mask" "F.Paste")
			(net "GND")
		)
	)
	(footprint ""
		(layer "F.Cu")
		(at 259.58673 -307.803296 -135)
		(property "Reference" "R1329"
			(at 0 0 225)
			(layer "F.SilkS")
			(hide yes)
			(effects
				(font
					(size 1.27 1.27)
				)
			)
		)
		(property "Value" ""
			(at 0 0 225)
			(layer "F.Fab")
			(effects
				(font
					(size 1.27 1.27)
				)
			)
		)
		(duplicate_pad_numbers_are_jumpers no)
		(fp_line
			(start 0.787389 0.406267)
			(end -0.787389 0.406267)
			(stroke
				(width 0.1524)
				(type default)
			)
			(layer "F.SilkS")
		)
		(fp_line
			(start 0.787389 -0.406267)
			(end 0.787389 0.406267)
			(stroke
				(width 0.1524)
				(type default)
			)
			(layer "F.SilkS")
		)
		(fp_line
			(start -0.787389 0.406267)
			(end -0.787389 -0.406267)
			(stroke
				(width 0.1524)
				(type default)
			)
			(layer "F.SilkS")
		)
		(fp_line
			(start -0.787389 -0.406267)
			(end 0.787389 -0.406267)
			(stroke
				(width 0.1524)
				(type default)
			)
			(layer "F.SilkS")
		)
		(fp_line
			(start 0.679446 0.30479)
			(end 0.120515 0.30479)
			(stroke
				(width 0.1)
				(type default)
			)
			(layer "F.Fab")
		)
		(fp_line
			(start 0.120515 0.30479)
			(end 0.120335 0.279466)
			(stroke
				(width 0.1)
				(type default)
			)
			(layer "F.Fab")
		)
		(fp_line
			(start 0.120335 0.279466)
			(end -0.120695 0.279466)
			(stroke
				(width 0.1)
				(type default)
			)
			(layer "F.Fab")
		)
		(fp_line
			(start 0.679446 -0.30479)
			(end 0.679446 0.30479)
			(stroke
				(width 0.1)
				(type default)
			)
			(layer "F.Fab")
		)
		(fp_line
			(start -0.120515 0.30479)
			(end -0.679446 0.30479)
			(stroke
				(width 0.1)
				(type default)
			)
			(layer "F.Fab")
		)
		(fp_line
			(start -0.120695 0.279466)
			(end -0.120515 0.30479)
			(stroke
				(width 0.1)
				(type default)
			)
			(layer "F.Fab")
		)
		(fp_line
			(start 0.120695 -0.279466)
			(end 0.120515 -0.30479)
			(stroke
				(width 0.1)
				(type default)
			)
			(layer "F.Fab")
		)
		(fp_line
			(start 0.120515 -0.30479)
			(end 0.679446 -0.30479)
			(stroke
				(width 0.1)
				(type default)
			)
			(layer "F.Fab")
		)
		(fp_line
			(start -0.679446 0.30479)
			(end -0.679446 -0.305149)
			(stroke
				(width 0.1)
				(type default)
			)
			(layer "F.Fab")
		)
		(fp_line
			(start -0.120695 -0.279466)
			(end 0.120695 -0.279466)
			(stroke
				(width 0.1)
				(type default)
			)
			(layer "F.Fab")
		)
		(fp_line
			(start -0.120695 -0.304969)
			(end -0.120695 -0.279466)
			(stroke
				(width 0.1)
				(type default)
			)
			(layer "F.Fab")
		)
		(fp_line
			(start -0.679446 -0.305149)
			(end -0.120695 -0.304969)
			(stroke
				(width 0.1)
				(type default)
			)
			(layer "F.Fab")
		)
		(pad "1" smd circle
			(at -0.40005 0 225)
			(size 0 0)
			(layers "F.Cu" "F.Mask" "F.Paste")
			(net "PEX2_DBG_SEL0")
		)
		(pad "2" smd circle
			(at 0.40005 0 225)
			(size 0 0)
			(layers "F.Cu" "F.Mask" "F.Paste")
			(net "P1V8_PEX")
		)
	)
	(footprint ""
		(layer "F.Cu")
		(at 11.647932 -255.046734 -90)
		(property "Reference" "R6464"
			(at 0 0 270)
			(layer "F.SilkS")
			(hide yes)
			(effects
				(font
					(size 1.27 1.27)
				)
			)
		)
		(property "Value" ""
			(at 0 0 270)
			(layer "F.Fab")
			(effects
				(font
					(size 1.27 1.27)
				)
			)
		)
		(duplicate_pad_numbers_are_jumpers no)
		(fp_line
			(start -0.7874 0.4064)
			(end -0.7874 -0.4064)
			(stroke
				(width 0.1524)
				(type default)
			)
			(layer "F.SilkS")
		)
		(fp_line
			(start 0.7874 0.4064)
			(end -0.7874 0.4064)
			(stroke
				(width 0.1524)
				(type default)
			)
			(layer "F.SilkS")
		)
		(fp_line
			(start -0.7874 -0.4064)
			(end 0.7874 -0.4064)
			(stroke
				(width 0.1524)
				(type default)
			)
			(layer "F.SilkS")
		)
		(fp_line
			(start 0.7874 -0.4064)
			(end 0.7874 0.4064)
			(stroke
				(width 0.1524)
				(type default)
			)
			(layer "F.SilkS")
		)
		(fp_line
			(start -0.67945 0.3048)
			(end -0.67945 -0.305054)
			(stroke
				(width 0.1)
				(type default)
			)
			(layer "F.Fab")
		)
		(fp_line
			(start -0.12065 0.3048)
			(end -0.67945 0.3048)
			(stroke
				(width 0.1)
				(type default)
			)
			(layer "F.Fab")
		)
		(fp_line
			(start 0.120396 0.3048)
			(end 0.120396 0.2794)
			(stroke
				(width 0.1)
				(type default)
			)
			(layer "F.Fab")
		)
		(fp_line
			(start 0.67945 0.3048)
			(end 0.120396 0.3048)
			(stroke
				(width 0.1)
				(type default)
			)
			(layer "F.Fab")
		)
		(fp_line
			(start -0.12065 0.2794)
			(end -0.12065 0.3048)
			(stroke
				(width 0.1)
				(type default)
			)
			(layer "F.Fab")
		)
		(fp_line
			(start 0.120396 0.2794)
			(end -0.12065 0.2794)
			(stroke
				(width 0.1)
				(type default)
			)
			(layer "F.Fab")
		)
		(fp_line
			(start -0.12065 -0.2794)
			(end 0.12065 -0.2794)
			(stroke
				(width 0.1)
				(type default)
			)
			(layer "F.Fab")
		)
		(fp_line
			(start 0.12065 -0.2794)
			(end 0.12065 -0.3048)
			(stroke
				(width 0.1)
				(type default)
			)
			(layer "F.Fab")
		)
		(fp_line
			(start 0.12065 -0.3048)
			(end 0.67945 -0.3048)
			(stroke
				(width 0.1)
				(type default)
			)
			(layer "F.Fab")
		)
		(fp_line
			(start 0.67945 -0.3048)
			(end 0.67945 0.3048)
			(stroke
				(width 0.1)
				(type default)
			)
			(layer "F.Fab")
		)
		(fp_line
			(start -0.67945 -0.305054)
			(end -0.12065 -0.305054)
			(stroke
				(width 0.1)
				(type default)
			)
			(layer "F.Fab")
		)
		(fp_line
			(start -0.12065 -0.305054)
			(end -0.12065 -0.2794)
			(stroke
				(width 0.1)
				(type default)
			)
			(layer "F.Fab")
		)
		(pad "1" smd circle
			(at -0.40005 0 270)
			(size 0 0)
			(layers "F.Cu" "F.Mask" "F.Paste")
			(net "P1V25_SERDES_VDDPLL_PEX0")
		)
		(pad "2" smd circle
			(at 0.40005 0 270)
			(size 0 0)
			(layers "F.Cu" "F.Mask" "F.Paste")
			(net "P1V25_SERDES_VDDPLL_PEX0_C3")
		)
	)
	(footprint ""
		(layer "F.Cu")
		(at 32.411416 -280.443432 -90)
		(property "Reference" "R4566"
			(at 0 0 270)
			(layer "F.SilkS")
			(hide yes)
			(effects
				(font
					(size 1.27 1.27)
				)
			)
		)
		(property "Value" ""
			(at 0 0 270)
			(layer "F.Fab")
			(effects
				(font
					(size 1.27 1.27)
				)
			)
		)
		(duplicate_pad_numbers_are_jumpers no)
		(fp_line
			(start -0.7874 0.4064)
			(end -0.7874 -0.4064)
			(stroke
				(width 0.1524)
				(type default)
			)
			(layer "F.SilkS")
		)
		(fp_line
			(start 0.7874 0.4064)
			(end -0.7874 0.4064)
			(stroke
				(width 0.1524)
				(type default)
			)
			(layer "F.SilkS")
		)
		(fp_line
			(start -0.7874 -0.4064)
			(end 0.7874 -0.4064)
			(stroke
				(width 0.1524)
				(type default)
			)
			(layer "F.SilkS")
		)
		(fp_line
			(start 0.7874 -0.4064)
			(end 0.7874 0.4064)
			(stroke
				(width 0.1524)
				(type default)
			)
			(layer "F.SilkS")
		)
		(fp_line
			(start -0.67945 0.3048)
			(end -0.67945 -0.305054)
			(stroke
				(width 0.1)
				(type default)
			)
			(layer "F.Fab")
		)
		(fp_line
			(start -0.12065 0.3048)
			(end -0.67945 0.3048)
			(stroke
				(width 0.1)
				(type default)
			)
			(layer "F.Fab")
		)
		(fp_line
			(start 0.120396 0.3048)
			(end 0.120396 0.2794)
			(stroke
				(width 0.1)
				(type default)
			)
			(layer "F.Fab")
		)
		(fp_line
			(start 0.67945 0.3048)
			(end 0.120396 0.3048)
			(stroke
				(width 0.1)
				(type default)
			)
			(layer "F.Fab")
		)
		(fp_line
			(start -0.12065 0.2794)
			(end -0.12065 0.3048)
			(stroke
				(width 0.1)
				(type default)
			)
			(layer "F.Fab")
		)
		(fp_line
			(start 0.120396 0.2794)
			(end -0.12065 0.2794)
			(stroke
				(width 0.1)
				(type default)
			)
			(layer "F.Fab")
		)
		(fp_line
			(start -0.12065 -0.2794)
			(end 0.12065 -0.2794)
			(stroke
				(width 0.1)
				(type default)
			)
			(layer "F.Fab")
		)
		(fp_line
			(start 0.12065 -0.2794)
			(end 0.12065 -0.3048)
			(stroke
				(width 0.1)
				(type default)
			)
			(layer "F.Fab")
		)
		(fp_line
			(start 0.12065 -0.3048)
			(end 0.67945 -0.3048)
			(stroke
				(width 0.1)
				(type default)
			)
			(layer "F.Fab")
		)
		(fp_line
			(start 0.67945 -0.3048)
			(end 0.67945 0.3048)
			(stroke
				(width 0.1)
				(type default)
			)
			(layer "F.Fab")
		)
		(fp_line
			(start -0.67945 -0.305054)
			(end -0.12065 -0.305054)
			(stroke
				(width 0.1)
				(type default)
			)
			(layer "F.Fab")
		)
		(fp_line
			(start -0.12065 -0.305054)
			(end -0.12065 -0.2794)
			(stroke
				(width 0.1)
				(type default)
			)
			(layer "F.Fab")
		)
		(pad "1" smd circle
			(at -0.40005 0 270)
			(size 0 0)
			(layers "F.Cu" "F.Mask" "F.Paste")
			(net "SYSPLL_VDDA18_PEX0")
		)
		(pad "2" smd circle
			(at 0.40005 0 270)
			(size 0 0)
			(layers "F.Cu" "F.Mask" "F.Paste")
			(net "SYSPLL_VDDA18_PEX0_R")
		)
	)
	(footprint ""
		(layer "F.Cu")
		(at 102.353364 -224.249996 90)
		(property "Reference" "PR187"
			(at 0 0 90)
			(layer "F.SilkS")
			(hide yes)
			(effects
				(font
					(size 1.27 1.27)
				)
			)
		)
		(property "Value" ""
			(at 0 0 90)
			(layer "F.Fab")
			(effects
				(font
					(size 1.27 1.27)
				)
			)
		)
		(duplicate_pad_numbers_are_jumpers no)
		(fp_line
			(start 0.7874 -0.4064)
			(end 0.7874 0.4064)
			(stroke
				(width 0.1524)
				(type default)
			)
			(layer "F.SilkS")
		)
		(fp_line
			(start -0.7874 -0.4064)
			(end 0.7874 -0.4064)
			(stroke
				(width 0.1524)
				(type default)
			)
			(layer "F.SilkS")
		)
		(fp_line
			(start 0.7874 0.4064)
			(end -0.7874 0.4064)
			(stroke
				(width 0.1524)
				(type default)
			)
			(layer "F.SilkS")
		)
		(fp_line
			(start -0.7874 0.4064)
			(end -0.7874 -0.4064)
			(stroke
				(width 0.1524)
				(type default)
			)
			(layer "F.SilkS")
		)
		(fp_line
			(start -0.12065 -0.305054)
			(end -0.12065 -0.2794)
			(stroke
				(width 0.1)
				(type default)
			)
			(layer "F.Fab")
		)
		(fp_line
			(start -0.67945 -0.305054)
			(end -0.12065 -0.305054)
			(stroke
				(width 0.1)
				(type default)
			)
			(layer "F.Fab")
		)
		(fp_line
			(start 0.67945 -0.3048)
			(end 0.67945 0.3048)
			(stroke
				(width 0.1)
				(type default)
			)
			(layer "F.Fab")
		)
		(fp_line
			(start 0.12065 -0.3048)
			(end 0.67945 -0.3048)
			(stroke
				(width 0.1)
				(type default)
			)
			(layer "F.Fab")
		)
		(fp_line
			(start 0.12065 -0.2794)
			(end 0.12065 -0.3048)
			(stroke
				(width 0.1)
				(type default)
			)
			(layer "F.Fab")
		)
		(fp_line
			(start -0.12065 -0.2794)
			(end 0.12065 -0.2794)
			(stroke
				(width 0.1)
				(type default)
			)
			(layer "F.Fab")
		)
		(fp_line
			(start 0.120396 0.2794)
			(end -0.12065 0.2794)
			(stroke
				(width 0.1)
				(type default)
			)
			(layer "F.Fab")
		)
		(fp_line
			(start -0.12065 0.2794)
			(end -0.12065 0.3048)
			(stroke
				(width 0.1)
				(type default)
			)
			(layer "F.Fab")
		)
		(fp_line
			(start 0.67945 0.3048)
			(end 0.120396 0.3048)
			(stroke
				(width 0.1)
				(type default)
			)
			(layer "F.Fab")
		)
		(fp_line
			(start 0.120396 0.3048)
			(end 0.120396 0.2794)
			(stroke
				(width 0.1)
				(type default)
			)
			(layer "F.Fab")
		)
		(fp_line
			(start -0.12065 0.3048)
			(end -0.67945 0.3048)
			(stroke
				(width 0.1)
				(type default)
			)
			(layer "F.Fab")
		)
		(fp_line
			(start -0.67945 0.3048)
			(end -0.67945 -0.305054)
			(stroke
				(width 0.1)
				(type default)
			)
			(layer "F.Fab")
		)
		(pad "1" smd circle
			(at -0.40005 0 90)
			(size 0 0)
			(layers "F.Cu" "F.Mask" "F.Paste")
			(net "P1V8_PEX_CS")
		)
		(pad "2" smd circle
			(at 0.40005 0 90)
			(size 0 0)
			(layers "F.Cu" "F.Mask" "F.Paste")
			(net "GND")
		)
	)
	(footprint ""
		(layer "F.Cu")
		(at 83.034124 -5.030724)
		(property "Reference" "R5806"
			(at 0 0 0)
			(layer "F.SilkS")
			(hide yes)
			(effects
				(font
					(size 1.27 1.27)
				)
			)
		)
		(property "Value" ""
			(at 0 0 0)
			(layer "F.Fab")
			(effects
				(font
					(size 1.27 1.27)
				)
			)
		)
		(duplicate_pad_numbers_are_jumpers no)
		(fp_line
			(start -0.7874 -0.4064)
			(end 0.7874 -0.4064)
			(stroke
				(width 0.1524)
				(type default)
			)
			(layer "F.SilkS")
		)
		(fp_line
			(start -0.7874 0.4064)
			(end -0.7874 -0.4064)
			(stroke
				(width 0.1524)
				(type default)
			)
			(layer "F.SilkS")
		)
		(fp_line
			(start 0.7874 -0.4064)
			(end 0.7874 0.4064)
			(stroke
				(width 0.1524)
				(type default)
			)
			(layer "F.SilkS")
		)
		(fp_line
			(start 0.7874 0.4064)
			(end -0.7874 0.4064)
			(stroke
				(width 0.1524)
				(type default)
			)
			(layer "F.SilkS")
		)
		(fp_line
			(start -0.67945 -0.305054)
			(end -0.12065 -0.305054)
			(stroke
				(width 0.1)
				(type default)
			)
			(layer "F.Fab")
		)
		(fp_line
			(start -0.67945 0.3048)
			(end -0.67945 -0.305054)
			(stroke
				(width 0.1)
				(type default)
			)
			(layer "F.Fab")
		)
		(fp_line
			(start -0.12065 -0.305054)
			(end -0.12065 -0.2794)
			(stroke
				(width 0.1)
				(type default)
			)
			(layer "F.Fab")
		)
		(fp_line
			(start -0.12065 -0.2794)
			(end 0.12065 -0.2794)
			(stroke
				(width 0.1)
				(type default)
			)
			(layer "F.Fab")
		)
		(fp_line
			(start -0.12065 0.2794)
			(end -0.12065 0.3048)
			(stroke
				(width 0.1)
				(type default)
			)
			(layer "F.Fab")
		)
		(fp_line
			(start -0.12065 0.3048)
			(end -0.67945 0.3048)
			(stroke
				(width 0.1)
				(type default)
			)
			(layer "F.Fab")
		)
		(fp_line
			(start 0.120396 0.2794)
			(end -0.12065 0.2794)
			(stroke
				(width 0.1)
				(type default)
			)
			(layer "F.Fab")
		)
		(fp_line
			(start 0.120396 0.3048)
			(end 0.120396 0.2794)
			(stroke
				(width 0.1)
				(type default)
			)
			(layer "F.Fab")
		)
		(fp_line
			(start 0.12065 -0.3048)
			(end 0.67945 -0.3048)
			(stroke
				(width 0.1)
				(type default)
			)
			(layer "F.Fab")
		)
		(fp_line
			(start 0.12065 -0.2794)
			(end 0.12065 -0.3048)
			(stroke
				(width 0.1)
				(type default)
			)
			(layer "F.Fab")
		)
		(fp_line
			(start 0.67945 -0.3048)
			(end 0.67945 0.3048)
			(stroke
				(width 0.1)
				(type default)
			)
			(layer "F.Fab")
		)
		(fp_line
			(start 0.67945 0.3048)
			(end 0.120396 0.3048)
			(stroke
				(width 0.1)
				(type default)
			)
			(layer "F.Fab")
		)
		(pad "1" smd circle
			(at -0.40005 0)
			(size 0 0)
			(layers "F.Cu" "F.Mask" "F.Paste")
			(net "LM75_2_A1")
		)
		(pad "2" smd circle
			(at 0.40005 0)
			(size 0 0)
			(layers "F.Cu" "F.Mask" "F.Paste")
			(net "P3V3_AUX")
		)
	)
	(footprint ""
		(layer "F.Cu")
		(at 328.83856 -22.867366 90)
		(property "Reference" "C3953"
			(at 0 0 90)
			(layer "F.SilkS")
			(hide yes)
			(effects
				(font
					(size 1.27 1.27)
				)
			)
		)
		(property "Value" ""
			(at 0 0 90)
			(layer "F.Fab")
			(effects
				(font
					(size 1.27 1.27)
				)
			)
		)
		(duplicate_pad_numbers_are_jumpers no)
		(fp_line
			(start 0.7874 -0.4064)
			(end 0.7874 0.4064)
			(stroke
				(width 0.1524)
				(type default)
			)
			(layer "F.SilkS")
		)
		(fp_line
			(start -0.7874 -0.4064)
			(end 0.7874 -0.4064)
			(stroke
				(width 0.1524)
				(type default)
			)
			(layer "F.SilkS")
		)
		(fp_line
			(start 0.7874 0.4064)
			(end -0.7874 0.4064)
			(stroke
				(width 0.1524)
				(type default)
			)
			(layer "F.SilkS")
		)
		(fp_line
			(start -0.7874 0.4064)
			(end -0.7874 -0.4064)
			(stroke
				(width 0.1524)
				(type default)
			)
			(layer "F.SilkS")
		)
		(fp_line
			(start -0.12065 -0.305054)
			(end -0.12065 -0.2794)
			(stroke
				(width 0.1)
				(type default)
			)
			(layer "F.Fab")
		)
		(fp_line
			(start -0.67945 -0.305054)
			(end -0.12065 -0.305054)
			(stroke
				(width 0.1)
				(type default)
			)
			(layer "F.Fab")
		)
		(fp_line
			(start 0.67945 -0.3048)
			(end 0.67945 0.3048)
			(stroke
				(width 0.1)
				(type default)
			)
			(layer "F.Fab")
		)
		(fp_line
			(start 0.12065 -0.3048)
			(end 0.67945 -0.3048)
			(stroke
				(width 0.1)
				(type default)
			)
			(layer "F.Fab")
		)
		(fp_line
			(start 0.12065 -0.2794)
			(end 0.12065 -0.3048)
			(stroke
				(width 0.1)
				(type default)
			)
			(layer "F.Fab")
		)
		(fp_line
			(start -0.12065 -0.2794)
			(end 0.12065 -0.2794)
			(stroke
				(width 0.1)
				(type default)
			)
			(layer "F.Fab")
		)
		(fp_line
			(start 0.120396 0.2794)
			(end -0.12065 0.2794)
			(stroke
				(width 0.1)
				(type default)
			)
			(layer "F.Fab")
		)
		(fp_line
			(start -0.12065 0.2794)
			(end -0.12065 0.3048)
			(stroke
				(width 0.1)
				(type default)
			)
			(layer "F.Fab")
		)
		(fp_line
			(start 0.67945 0.3048)
			(end 0.120396 0.3048)
			(stroke
				(width 0.1)
				(type default)
			)
			(layer "F.Fab")
		)
		(fp_line
			(start 0.120396 0.3048)
			(end 0.120396 0.2794)
			(stroke
				(width 0.1)
				(type default)
			)
			(layer "F.Fab")
		)
		(fp_line
			(start -0.12065 0.3048)
			(end -0.67945 0.3048)
			(stroke
				(width 0.1)
				(type default)
			)
			(layer "F.Fab")
		)
		(fp_line
			(start -0.67945 0.3048)
			(end -0.67945 -0.305054)
			(stroke
				(width 0.1)
				(type default)
			)
			(layer "F.Fab")
		)
		(pad "1" smd circle
			(at -0.40005 0 90)
			(size 0 0)
			(layers "F.Cu" "F.Mask" "F.Paste")
			(net "P12V_SSD11")
		)
		(pad "2" smd circle
			(at 0.40005 0 90)
			(size 0 0)
			(layers "F.Cu" "F.Mask" "F.Paste")
			(net "GND")
		)
	)
	(footprint ""
		(layer "F.Cu")
		(at 130.454654 -303.698402 90)
		(property "Reference" "PC105"
			(at 0 0 90)
			(layer "F.SilkS")
			(hide yes)
			(effects
				(font
					(size 1.27 1.27)
				)
			)
		)
		(property "Value" ""
			(at 0 0 90)
			(layer "F.Fab")
			(effects
				(font
					(size 1.27 1.27)
				)
			)
		)
		(duplicate_pad_numbers_are_jumpers no)
		(fp_line
			(start -4.53898 -2.150618)
			(end -4.539742 2.152142)
			(stroke
				(width 0.1524)
				(type default)
			)
			(layer "F.SilkS")
		)
		(fp_line
			(start -4.69138 -2.150618)
			(end -4.692396 2.161032)
			(stroke
				(width 0.1524)
				(type default)
			)
			(layer "F.SilkS")
		)
		(fp_line
			(start -4.84378 -2.150618)
			(end -4.53898 -2.150618)
			(stroke
				(width 0.1524)
				(type default)
			)
			(layer "F.SilkS")
		)
		(fp_line
			(start -4.84378 -2.150618)
			(end -4.842256 2.163064)
			(stroke
				(width 0.1524)
				(type default)
			)
			(layer "F.SilkS")
		)
		(fp_line
			(start 4.53898 -2.15011)
			(end 4.53898 2.15011)
			(stroke
				(width 0.1524)
				(type default)
			)
			(layer "F.SilkS")
		)
		(fp_line
			(start -4.53898 -2.15011)
			(end 4.53898 -2.15011)
			(stroke
				(width 0.1524)
				(type default)
			)
			(layer "F.SilkS")
		)
		(fp_line
			(start 4.53898 2.15011)
			(end -4.53898 2.15011)
			(stroke
				(width 0.1524)
				(type default)
			)
			(layer "F.SilkS")
		)
		(fp_line
			(start -4.53898 2.15011)
			(end -4.53898 -2.15011)
			(stroke
				(width 0.1524)
				(type default)
			)
			(layer "F.SilkS")
		)
		(fp_line
			(start -4.83108 2.150364)
			(end -4.447794 2.149348)
			(stroke
				(width 0.1524)
				(type default)
			)
			(layer "F.SilkS")
		)
		(fp_line
			(start 3.64998 -2.15011)
			(end 3.64998 2.15011)
			(stroke
				(width 0.1)
				(type default)
			)
			(layer "F.Fab")
		)
		(fp_line
			(start -3.64998 -2.15011)
			(end 3.64998 -2.15011)
			(stroke
				(width 0.1)
				(type default)
			)
			(layer "F.Fab")
		)
		(fp_line
			(start 3.64998 2.15011)
			(end -3.64998 2.15011)
			(stroke
				(width 0.1)
				(type default)
			)
			(layer "F.Fab")
		)
		(fp_line
			(start -3.64998 2.15011)
			(end -3.64998 -2.15011)
			(stroke
				(width 0.1)
				(type default)
			)
			(layer "F.Fab")
		)
		(fp_text user "+"
			(at -5.027422 -3.06959 90)
			(unlocked yes)
			(layer "F.SilkS")
			(effects
				(font
					(size 1.905 1.4224)
					(thickness 0.1524)
				)
				(justify left)
			)
		)
		(fp_text user "-"
			(at 3.295396 -2.751836 90)
			(unlocked yes)
			(layer "F.SilkS")
			(effects
				(font
					(size 1.905 1.4224)
					(thickness 0.1524)
				)
				(justify left)
			)
		)
		(fp_text user "+"
			(at -6.214872 -0.337058 90)
			(unlocked yes)
			(layer "F.Fab")
			(effects
				(font
					(size 1.905 1.4224)
					(thickness 0.1524)
				)
				(justify left)
			)
		)
		(fp_text user "-"
			(at 4.313174 -0.094488 90)
			(unlocked yes)
			(layer "F.Fab")
			(effects
				(font
					(size 1.905 1.4224)
					(thickness 0.1524)
				)
				(justify left)
			)
		)
		(pad "1" smd rect
			(at -3.199892 0 90)
			(size 2.413 2.8194)
			(layers "F.Cu" "F.Mask" "F.Paste")
			(net "P0V8_PEX1")
		)
		(pad "2" smd rect
			(at 3.199892 0 90)
			(size 2.413 2.8194)
			(layers "F.Cu" "F.Mask" "F.Paste")
			(net "GND")
		)
	)
	(footprint ""
		(layer "F.Cu")
		(at 109.87405 -160.772094 180)
		(property "Reference" "PU5"
			(at -4.45262 -3.050032 0)
			(unlocked yes)
			(layer "F.SilkS")
			(effects
				(font
					(size 0.7874 0.5842)
					(thickness 0.1524)
				)
				(justify left)
			)
		)
		(property "Value" ""
			(at 0 0 180)
			(layer "F.Fab")
			(effects
				(font
					(size 1.27 1.27)
				)
			)
		)
		(duplicate_pad_numbers_are_jumpers no)
		(fp_line
			(start 1.549908 2.050034)
			(end 1.549908 1.9304)
			(stroke
				(width 0.1524)
				(type default)
			)
			(layer "F.SilkS")
		)
		(fp_line
			(start 1.549908 -1.9812)
			(end 1.549908 -2.050034)
			(stroke
				(width 0.1524)
				(type default)
			)
			(layer "F.SilkS")
		)
		(fp_line
			(start 1.549908 -2.050034)
			(end 0.5842 -2.050034)
			(stroke
				(width 0.1524)
				(type default)
			)
			(layer "F.SilkS")
		)
		(fp_line
			(start 0.3048 -2.4638)
			(end 0.3048 -3.2258)
			(stroke
				(width 0.1524)
				(type default)
			)
			(layer "F.SilkS")
		)
		(fp_line
			(start 0 2.050034)
			(end 1.549908 2.050034)
			(stroke
				(width 0.1524)
				(type default)
			)
			(layer "F.SilkS")
		)
		(fp_line
			(start -0.3048 2.4638)
			(end -0.3048 3.2258)
			(stroke
				(width 0.1524)
				(type default)
			)
			(layer "F.SilkS")
		)
		(fp_line
			(start -0.5842 -2.050034)
			(end -1.549908 -2.050034)
			(stroke
				(width 0.1524)
				(type default)
			)
			(layer "F.SilkS")
		)
		(fp_line
			(start -1.549908 2.050034)
			(end -0.5842 2.050034)
			(stroke
				(width 0.1524)
				(type default)
			)
			(layer "F.SilkS")
		)
		(fp_line
			(start -1.549908 1.9812)
			(end -1.549908 2.050034)
			(stroke
				(width 0.1524)
				(type default)
			)
			(layer "F.SilkS")
		)
		(fp_line
			(start -1.549908 -2.050034)
			(end -1.549908 -1.9812)
			(stroke
				(width 0.1524)
				(type default)
			)
			(layer "F.SilkS")
		)
		(fp_line
			(start -1.9812 0)
			(end -2.3622 0)
			(stroke
				(width 0.1524)
				(type default)
			)
			(layer "F.SilkS")
		)
		(fp_poly
			(pts
				(xy -2.9464 -2.208022) (xy -2.9464 -1.192022) (xy -1.9304 -1.700022)
			)
			(stroke
				(width 0)
				(type default)
			)
			(fill yes)
			(layer "F.SilkS")
		)
		(fp_line
			(start 1.549908 2.050034)
			(end 1.549908 -2.050034)
			(stroke
				(width 0.1)
				(type default)
			)
			(layer "F.Fab")
		)
		(fp_line
			(start 1.549908 -2.050034)
			(end -1.549908 -2.050034)
			(stroke
				(width 0.1)
				(type default)
			)
			(layer "F.Fab")
		)
		(fp_line
			(start 0.3048 -2.4638)
			(end 0.3048 -3.2258)
			(stroke
				(width 0.1)
				(type default)
			)
			(layer "F.Fab")
		)
		(fp_line
			(start -0.3048 2.4638)
			(end -0.3048 3.2258)
			(stroke
				(width 0.1)
				(type default)
			)
			(layer "F.Fab")
		)
		(fp_line
			(start -1.549908 2.050034)
			(end 1.549908 2.050034)
			(stroke
				(width 0.1)
				(type default)
			)
			(layer "F.Fab")
		)
		(fp_line
			(start -1.549908 -2.050034)
			(end -1.549908 2.050034)
			(stroke
				(width 0.1)
				(type default)
			)
			(layer "F.Fab")
		)
		(fp_line
			(start -1.9812 0)
			(end -2.3622 0)
			(stroke
				(width 0.1)
				(type default)
			)
			(layer "F.Fab")
		)
		(fp_poly
			(pts
				(xy -2.9464 -2.208022) (xy -2.9464 -1.192022) (xy -1.9304 -1.700022)
			)
			(stroke
				(width 0)
				(type default)
			)
			(fill yes)
			(layer "F.Fab")
		)
		(fp_text user "11_18"
			(at 2.512568 0.9906 90)
			(unlocked yes)
			(layer "F.SilkS")
			(effects
				(font
					(size 0.635 0.4064)
					(thickness 0.1524)
				)
			)
		)
		(fp_text user "19"
			(at 1.970786 -2.617724 90)
			(unlocked yes)
			(layer "F.SilkS")
			(effects
				(font
					(size 0.635 0.4064)
					(thickness 0.1524)
				)
			)
		)
		(fp_text user "9"
			(at -2.338832 2.0574 90)
			(unlocked yes)
			(layer "F.SilkS")
			(effects
				(font
					(size 0.635 0.4064)
					(thickness 0.1524)
				)
			)
		)
		(fp_text user "11_18"
			(at 2.512568 0.9906 90)
			(unlocked yes)
			(layer "F.Fab")
			(effects
				(font
					(size 0.635 0.4064)
					(thickness 0.1524)
				)
			)
		)
		(fp_text user "19"
			(at 2.410968 -2.159 90)
			(unlocked yes)
			(layer "F.Fab")
			(effects
				(font
					(size 0.635 0.4064)
					(thickness 0.1524)
				)
			)
		)
		(fp_text user "9"
			(at -2.338832 2.0574 90)
			(unlocked yes)
			(layer "F.Fab")
			(effects
				(font
					(size 0.635 0.4064)
					(thickness 0.1524)
				)
			)
		)
		(pad "1" smd rect
			(at -1.35001 -1.700022 270)
			(size 0.3048 0.9144)
			(layers "F.Cu" "F.Mask" "F.Paste")
			(net "SW_P3V3_AUX_BT")
		)
		(pad "2" smd rect
			(at -1.400048 -1.199896 270)
			(size 0.1778 0.8128)
			(layers "F.Cu" "F.Mask" "F.Paste")
			(net "GND")
		)
		(pad "3" smd rect
			(at -1.400048 -0.8001 270)
			(size 0.1778 0.8128)
			(layers "F.Cu" "F.Mask" "F.Paste")
			(net "P3V3_AUX_CS")
		)
		(pad "4" smd rect
			(at -1.400048 -0.40005 270)
			(size 0.1778 0.8128)
			(layers "F.Cu" "F.Mask" "F.Paste")
			(net "GND")
		)
		(pad "5" smd rect
			(at -1.400048 0 270)
			(size 0.1778 0.8128)
			(layers "F.Cu" "F.Mask" "F.Paste")
			(net "P3V3_AUX_REF")
		)
		(pad "6" smd rect
			(at -1.400048 0.40005 270)
			(size 0.1778 0.8128)
			(layers "F.Cu" "F.Mask" "F.Paste")
			(net "GND")
		)
		(pad "7" smd rect
			(at -1.400048 0.8001 270)
			(size 0.1778 0.8128)
			(layers "F.Cu" "F.Mask" "F.Paste")
			(net "P3V3_AUX_FB")
		)
		(pad "8" smd rect
			(at -1.400048 1.199896 270)
			(size 0.1778 0.8128)
			(layers "F.Cu" "F.Mask" "F.Paste")
			(net "P3V3_AUX_EN")
		)
		(pad "9" smd rect
			(at -1.400048 1.700022 270)
			(size 0.3048 0.8128)
			(layers "F.Cu" "F.Mask" "F.Paste")
			(net "PWRGD_P3V3_AUX")
		)
		(pad "10" smd rect
			(at -0.299974 1.299972 180)
			(size 0.3048 2.0066)
			(layers "F.Cu" "F.Mask" "F.Paste")
			(net "SW_P12V_P3V3_AUX_FLT")
		)
		(pad "11_18" smd circle
			(at 1.175004 0.275082 180)
			(size 0 0)
			(layers "F.Cu" "F.Mask" "F.Paste")
			(net "GND")
		)
		(pad "19" smd rect
			(at 1.400048 -1.700022 90)
			(size 0.3048 0.8128)
			(layers "F.Cu" "F.Mask" "F.Paste")
			(net "P3V3_AUX_VCC")
		)
		(pad "20" smd rect
			(at 0.299974 -1.299972 180)
			(size 0.3048 2.0066)
			(layers "F.Cu" "F.Mask" "F.Paste")
			(net "SW_P3V3_AUX_PH")
		)
		(pad "21" smd rect
			(at -0.299974 -1.299972 180)
			(size 0.3048 2.0066)
			(layers "F.Cu" "F.Mask" "F.Paste")
			(net "SW_P12V_P3V3_AUX_FLT")
		)
	)
	(footprint ""
		(layer "F.Cu")
		(at 466.762846 -526.370296 180)
		(property "Reference" "SCREW_SSD5_1"
			(at -5.207 -1.402334 0)
			(unlocked yes)
			(layer "B.SilkS")
			(effects
				(font
					(size 0.7874 0.5842)
					(thickness 0.1524)
				)
				(justify mirror)
			)
		)
		(property "Value" ""
			(at 0 0 180)
			(layer "F.Fab")
			(effects
				(font
					(size 1.27 1.27)
				)
			)
		)
		(duplicate_pad_numbers_are_jumpers no)
		(pad "1" thru_hole circle
			(at 0 0 180)
			(size 0.4572 0.4572)
			(drill 0.2032)
			(layers "*.Cu" "*.Mask")
			(remove_unused_layers no)
			(net "Net_9134")
			(clearance 0.127)
			(thermal_gap 0.127)
			(padstack
				(mode front_inner_back)
				(layer "Inner"
					(shape circle)
					(size 0.4572 0.4572)
					(clearance 0.127)
				)
				(layer "B.Cu"
					(shape circle)
					(size 0.508 0.508)
					(clearance 0.1016)
				)
			)
		)
	)
	(footprint ""
		(layer "F.Cu")
		(at 378.453396 -281.789632)
		(property "Reference" "L144"
			(at 0 0 0)
			(layer "F.SilkS")
			(hide yes)
			(effects
				(font
					(size 1.27 1.27)
				)
			)
		)
		(property "Value" ""
			(at 0 0 0)
			(layer "F.Fab")
			(effects
				(font
					(size 1.27 1.27)
				)
			)
		)
		(duplicate_pad_numbers_are_jumpers no)
		(fp_line
			(start -1.63576 -0.8128)
			(end -1.63576 0.8128)
			(stroke
				(width 0.1524)
				(type default)
			)
			(layer "F.SilkS")
		)
		(fp_line
			(start -1.63576 -0.8128)
			(end 1.63576 -0.8128)
			(stroke
				(width 0.1524)
				(type default)
			)
			(layer "F.SilkS")
		)
		(fp_line
			(start 1.63576 -0.8128)
			(end 1.63576 0.8128)
			(stroke
				(width 0.1524)
				(type default)
			)
			(layer "F.SilkS")
		)
		(fp_line
			(start 1.63576 0.8128)
			(end -1.63576 0.8128)
			(stroke
				(width 0.1524)
				(type default)
			)
			(layer "F.SilkS")
		)
		(fp_line
			(start -1.56083 -0.738632)
			(end -1.56083 0.7366)
			(stroke
				(width 0.1)
				(type default)
			)
			(layer "F.Fab")
		)
		(fp_line
			(start -1.56083 0.7366)
			(end -1.524 0.7366)
			(stroke
				(width 0.1)
				(type default)
			)
			(layer "F.Fab")
		)
		(fp_line
			(start -1.524 0.7366)
			(end 1.524 0.7366)
			(stroke
				(width 0.1)
				(type default)
			)
			(layer "F.Fab")
		)
		(fp_line
			(start 1.524 0.7366)
			(end 1.560576 0.7366)
			(stroke
				(width 0.1)
				(type default)
			)
			(layer "F.Fab")
		)
		(fp_line
			(start 1.560576 -0.738632)
			(end -1.56083 -0.738632)
			(stroke
				(width 0.1)
				(type default)
			)
			(layer "F.Fab")
		)
		(fp_line
			(start 1.560576 0.7366)
			(end 1.560576 -0.738632)
			(stroke
				(width 0.1)
				(type default)
			)
			(layer "F.Fab")
		)
		(pad "1" smd rect
			(at -0.94996 0 180)
			(size 1.1176 1.3716)
			(layers "F.Cu" "F.Mask" "F.Paste")
			(net "P1V8_PLL0_PEX3")
		)
		(pad "2" smd rect
			(at 0.94996 0 180)
			(size 1.1176 1.3716)
			(layers "F.Cu" "F.Mask" "F.Paste")
			(net "SYSPLL_VDDA18_PEX3")
		)
	)
	(footprint ""
		(layer "F.Cu")
		(at 30.847792 -40.037258 90)
		(property "Reference" "U364"
			(at 0.196342 2.376678 90)
			(unlocked yes)
			(layer "F.SilkS")
			(effects
				(font
					(size 0.7874 0.5842)
					(thickness 0.1524)
				)
			)
		)
		(property "Value" ""
			(at 0 0 90)
			(layer "F.Fab")
			(effects
				(font
					(size 1.27 1.27)
				)
			)
		)
		(duplicate_pad_numbers_are_jumpers no)
		(fp_line
			(start -1.949958 -1.610106)
			(end 1.949958 -1.610106)
			(stroke
				(width 0.1524)
				(type default)
			)
			(layer "F.SilkS")
		)
		(fp_line
			(start 1.949958 -1.560068)
			(end 1.949958 1.610106)
			(stroke
				(width 0.1524)
				(type default)
			)
			(layer "F.SilkS")
		)
		(fp_line
			(start 1.949958 1.610106)
			(end -1.949958 1.610106)
			(stroke
				(width 0.1524)
				(type default)
			)
			(layer "F.SilkS")
		)
		(fp_line
			(start -1.949958 1.610106)
			(end -1.949958 -1.610106)
			(stroke
				(width 0.1524)
				(type default)
			)
			(layer "F.SilkS")
		)
		(fp_line
			(start 0.750062 -1.560068)
			(end 0.750062 1.560068)
			(stroke
				(width 0.1)
				(type default)
			)
			(layer "F.Fab")
		)
		(fp_line
			(start -0.750062 -1.560068)
			(end 0.750062 -1.560068)
			(stroke
				(width 0.1)
				(type default)
			)
			(layer "F.Fab")
		)
		(fp_line
			(start 0.750062 1.560068)
			(end -0.750062 1.560068)
			(stroke
				(width 0.1)
				(type default)
			)
			(layer "F.Fab")
		)
		(fp_line
			(start -0.750062 1.560068)
			(end -0.750062 -1.560068)
			(stroke
				(width 0.1)
				(type default)
			)
			(layer "F.Fab")
		)
		(pad "D" smd rect
			(at 1.100074 0)
			(size 1.016 1.4224)
			(layers "F.Cu" "F.Mask" "F.Paste")
			(net "SSD1_AUX_P3V3_EN")
		)
		(pad "G" smd rect
			(at -1.100074 -0.94996)
			(size 1.016 1.4224)
			(layers "F.Cu" "F.Mask" "F.Paste")
			(net "PRSNT_SSD1_R1_N")
		)
		(pad "S" smd rect
			(at -1.100074 0.94996)
			(size 1.016 1.4224)
			(layers "F.Cu" "F.Mask" "F.Paste")
			(net "GND")
		)
	)
	(footprint ""
		(layer "F.Cu")
		(at 411.77083 -137.848848 180)
		(property "Reference" "R362"
			(at 0 0 180)
			(layer "F.SilkS")
			(hide yes)
			(effects
				(font
					(size 1.27 1.27)
				)
			)
		)
		(property "Value" ""
			(at 0 0 180)
			(layer "F.Fab")
			(effects
				(font
					(size 1.27 1.27)
				)
			)
		)
		(duplicate_pad_numbers_are_jumpers no)
		(fp_line
			(start 0.7874 0.4064)
			(end -0.7874 0.4064)
			(stroke
				(width 0.1524)
				(type default)
			)
			(layer "F.SilkS")
		)
		(fp_line
			(start 0.7874 -0.4064)
			(end 0.7874 0.4064)
			(stroke
				(width 0.1524)
				(type default)
			)
			(layer "F.SilkS")
		)
		(fp_line
			(start -0.7874 0.4064)
			(end -0.7874 -0.4064)
			(stroke
				(width 0.1524)
				(type default)
			)
			(layer "F.SilkS")
		)
		(fp_line
			(start -0.7874 -0.4064)
			(end 0.7874 -0.4064)
			(stroke
				(width 0.1524)
				(type default)
			)
			(layer "F.SilkS")
		)
		(fp_line
			(start 0.67945 0.3048)
			(end 0.120396 0.3048)
			(stroke
				(width 0.1)
				(type default)
			)
			(layer "F.Fab")
		)
		(fp_line
			(start 0.67945 -0.3048)
			(end 0.67945 0.3048)
			(stroke
				(width 0.1)
				(type default)
			)
			(layer "F.Fab")
		)
		(fp_line
			(start 0.12065 -0.2794)
			(end 0.12065 -0.3048)
			(stroke
				(width 0.1)
				(type default)
			)
			(layer "F.Fab")
		)
		(fp_line
			(start 0.12065 -0.3048)
			(end 0.67945 -0.3048)
			(stroke
				(width 0.1)
				(type default)
			)
			(layer "F.Fab")
		)
		(fp_line
			(start 0.120396 0.3048)
			(end 0.120396 0.2794)
			(stroke
				(width 0.1)
				(type default)
			)
			(layer "F.Fab")
		)
		(fp_line
			(start 0.120396 0.2794)
			(end -0.12065 0.2794)
			(stroke
				(width 0.1)
				(type default)
			)
			(layer "F.Fab")
		)
		(fp_line
			(start -0.12065 0.3048)
			(end -0.67945 0.3048)
			(stroke
				(width 0.1)
				(type default)
			)
			(layer "F.Fab")
		)
		(fp_line
			(start -0.12065 0.2794)
			(end -0.12065 0.3048)
			(stroke
				(width 0.1)
				(type default)
			)
			(layer "F.Fab")
		)
		(fp_line
			(start -0.12065 -0.2794)
			(end 0.12065 -0.2794)
			(stroke
				(width 0.1)
				(type default)
			)
			(layer "F.Fab")
		)
		(fp_line
			(start -0.12065 -0.305054)
			(end -0.12065 -0.2794)
			(stroke
				(width 0.1)
				(type default)
			)
			(layer "F.Fab")
		)
		(fp_line
			(start -0.67945 0.3048)
			(end -0.67945 -0.305054)
			(stroke
				(width 0.1)
				(type default)
			)
			(layer "F.Fab")
		)
		(fp_line
			(start -0.67945 -0.305054)
			(end -0.12065 -0.305054)
			(stroke
				(width 0.1)
				(type default)
			)
			(layer "F.Fab")
		)
		(pad "1" smd circle
			(at -0.40005 0 180)
			(size 0 0)
			(layers "F.Cu" "F.Mask" "F.Paste")
			(net "PRSNTB1_NIC7_N")
		)
		(pad "2" smd circle
			(at 0.40005 0 180)
			(size 0 0)
			(layers "F.Cu" "F.Mask" "F.Paste")
			(net "P3V3_AUX")
		)
	)
	(footprint ""
		(layer "F.Cu")
		(at 63.47079 -138.864848)
		(property "Reference" "R91"
			(at 0 0 0)
			(layer "F.SilkS")
			(hide yes)
			(effects
				(font
					(size 1.27 1.27)
				)
			)
		)
		(property "Value" ""
			(at 0 0 0)
			(layer "F.Fab")
			(effects
				(font
					(size 1.27 1.27)
				)
			)
		)
		(duplicate_pad_numbers_are_jumpers no)
		(fp_line
			(start -0.7874 -0.4064)
			(end 0.7874 -0.4064)
			(stroke
				(width 0.1524)
				(type default)
			)
			(layer "F.SilkS")
		)
		(fp_line
			(start -0.7874 0.4064)
			(end -0.7874 -0.4064)
			(stroke
				(width 0.1524)
				(type default)
			)
			(layer "F.SilkS")
		)
		(fp_line
			(start 0.7874 -0.4064)
			(end 0.7874 0.4064)
			(stroke
				(width 0.1524)
				(type default)
			)
			(layer "F.SilkS")
		)
		(fp_line
			(start 0.7874 0.4064)
			(end -0.7874 0.4064)
			(stroke
				(width 0.1524)
				(type default)
			)
			(layer "F.SilkS")
		)
		(fp_line
			(start -0.67945 -0.305054)
			(end -0.12065 -0.305054)
			(stroke
				(width 0.1)
				(type default)
			)
			(layer "F.Fab")
		)
		(fp_line
			(start -0.67945 0.3048)
			(end -0.67945 -0.305054)
			(stroke
				(width 0.1)
				(type default)
			)
			(layer "F.Fab")
		)
		(fp_line
			(start -0.12065 -0.305054)
			(end -0.12065 -0.2794)
			(stroke
				(width 0.1)
				(type default)
			)
			(layer "F.Fab")
		)
		(fp_line
			(start -0.12065 -0.2794)
			(end 0.12065 -0.2794)
			(stroke
				(width 0.1)
				(type default)
			)
			(layer "F.Fab")
		)
		(fp_line
			(start -0.12065 0.2794)
			(end -0.12065 0.3048)
			(stroke
				(width 0.1)
				(type default)
			)
			(layer "F.Fab")
		)
		(fp_line
			(start -0.12065 0.3048)
			(end -0.67945 0.3048)
			(stroke
				(width 0.1)
				(type default)
			)
			(layer "F.Fab")
		)
		(fp_line
			(start 0.120396 0.2794)
			(end -0.12065 0.2794)
			(stroke
				(width 0.1)
				(type default)
			)
			(layer "F.Fab")
		)
		(fp_line
			(start 0.120396 0.3048)
			(end 0.120396 0.2794)
			(stroke
				(width 0.1)
				(type default)
			)
			(layer "F.Fab")
		)
		(fp_line
			(start 0.12065 -0.3048)
			(end 0.67945 -0.3048)
			(stroke
				(width 0.1)
				(type default)
			)
			(layer "F.Fab")
		)
		(fp_line
			(start 0.12065 -0.2794)
			(end 0.12065 -0.3048)
			(stroke
				(width 0.1)
				(type default)
			)
			(layer "F.Fab")
		)
		(fp_line
			(start 0.67945 -0.3048)
			(end 0.67945 0.3048)
			(stroke
				(width 0.1)
				(type default)
			)
			(layer "F.Fab")
		)
		(fp_line
			(start 0.67945 0.3048)
			(end 0.120396 0.3048)
			(stroke
				(width 0.1)
				(type default)
			)
			(layer "F.Fab")
		)
		(pad "1" smd circle
			(at -0.40005 0)
			(size 0 0)
			(layers "F.Cu" "F.Mask" "F.Paste")
			(net "PRSNT_NIC1_N")
		)
		(pad "2" smd circle
			(at 0.40005 0)
			(size 0 0)
			(layers "F.Cu" "F.Mask" "F.Paste")
			(net "PRSNTB1_NIC1_N")
		)
	)
	(footprint ""
		(layer "F.Cu")
		(at 30.715204 -59.546236 90)
		(property "Reference" "C2887"
			(at 0 0 90)
			(layer "F.SilkS")
			(hide yes)
			(effects
				(font
					(size 1.27 1.27)
				)
			)
		)
		(property "Value" ""
			(at 0 0 90)
			(layer "F.Fab")
			(effects
				(font
					(size 1.27 1.27)
				)
			)
		)
		(duplicate_pad_numbers_are_jumpers no)
		(fp_line
			(start 0.7874 -0.4064)
			(end 0.7874 0.4064)
			(stroke
				(width 0.1524)
				(type default)
			)
			(layer "F.SilkS")
		)
		(fp_line
			(start -0.7874 -0.4064)
			(end 0.7874 -0.4064)
			(stroke
				(width 0.1524)
				(type default)
			)
			(layer "F.SilkS")
		)
		(fp_line
			(start 0.7874 0.4064)
			(end -0.7874 0.4064)
			(stroke
				(width 0.1524)
				(type default)
			)
			(layer "F.SilkS")
		)
		(fp_line
			(start -0.7874 0.4064)
			(end -0.7874 -0.4064)
			(stroke
				(width 0.1524)
				(type default)
			)
			(layer "F.SilkS")
		)
		(fp_line
			(start -0.12065 -0.305054)
			(end -0.12065 -0.2794)
			(stroke
				(width 0.1)
				(type default)
			)
			(layer "F.Fab")
		)
		(fp_line
			(start -0.67945 -0.305054)
			(end -0.12065 -0.305054)
			(stroke
				(width 0.1)
				(type default)
			)
			(layer "F.Fab")
		)
		(fp_line
			(start 0.67945 -0.3048)
			(end 0.67945 0.3048)
			(stroke
				(width 0.1)
				(type default)
			)
			(layer "F.Fab")
		)
		(fp_line
			(start 0.12065 -0.3048)
			(end 0.67945 -0.3048)
			(stroke
				(width 0.1)
				(type default)
			)
			(layer "F.Fab")
		)
		(fp_line
			(start 0.12065 -0.2794)
			(end 0.12065 -0.3048)
			(stroke
				(width 0.1)
				(type default)
			)
			(layer "F.Fab")
		)
		(fp_line
			(start -0.12065 -0.2794)
			(end 0.12065 -0.2794)
			(stroke
				(width 0.1)
				(type default)
			)
			(layer "F.Fab")
		)
		(fp_line
			(start 0.120396 0.2794)
			(end -0.12065 0.2794)
			(stroke
				(width 0.1)
				(type default)
			)
			(layer "F.Fab")
		)
		(fp_line
			(start -0.12065 0.2794)
			(end -0.12065 0.3048)
			(stroke
				(width 0.1)
				(type default)
			)
			(layer "F.Fab")
		)
		(fp_line
			(start 0.67945 0.3048)
			(end 0.120396 0.3048)
			(stroke
				(width 0.1)
				(type default)
			)
			(layer "F.Fab")
		)
		(fp_line
			(start 0.120396 0.3048)
			(end 0.120396 0.2794)
			(stroke
				(width 0.1)
				(type default)
			)
			(layer "F.Fab")
		)
		(fp_line
			(start -0.12065 0.3048)
			(end -0.67945 0.3048)
			(stroke
				(width 0.1)
				(type default)
			)
			(layer "F.Fab")
		)
		(fp_line
			(start -0.67945 0.3048)
			(end -0.67945 -0.305054)
			(stroke
				(width 0.1)
				(type default)
			)
			(layer "F.Fab")
		)
		(pad "1" smd circle
			(at -0.40005 0 90)
			(size 0 0)
			(layers "F.Cu" "F.Mask" "F.Paste")
			(net "SSD1_AUX_P3V3_EN_R")
		)
		(pad "2" smd circle
			(at 0.40005 0 90)
			(size 0 0)
			(layers "F.Cu" "F.Mask" "F.Paste")
			(net "GND")
		)
	)
	(footprint ""
		(layer "F.Cu")
		(at 56.947308 -36.686998 90)
		(property "Reference" "C204"
			(at 0 0 90)
			(layer "F.SilkS")
			(hide yes)
			(effects
				(font
					(size 1.27 1.27)
				)
			)
		)
		(property "Value" ""
			(at 0 0 90)
			(layer "F.Fab")
			(effects
				(font
					(size 1.27 1.27)
				)
			)
		)
		(duplicate_pad_numbers_are_jumpers no)
		(fp_line
			(start 0.7874 -0.4064)
			(end 0.7874 0.4064)
			(stroke
				(width 0.1524)
				(type default)
			)
			(layer "F.SilkS")
		)
		(fp_line
			(start -0.7874 -0.4064)
			(end 0.7874 -0.4064)
			(stroke
				(width 0.1524)
				(type default)
			)
			(layer "F.SilkS")
		)
		(fp_line
			(start 0.7874 0.4064)
			(end -0.7874 0.4064)
			(stroke
				(width 0.1524)
				(type default)
			)
			(layer "F.SilkS")
		)
		(fp_line
			(start -0.7874 0.4064)
			(end -0.7874 -0.4064)
			(stroke
				(width 0.1524)
				(type default)
			)
			(layer "F.SilkS")
		)
		(fp_line
			(start -0.12065 -0.305054)
			(end -0.12065 -0.2794)
			(stroke
				(width 0.1)
				(type default)
			)
			(layer "F.Fab")
		)
		(fp_line
			(start -0.67945 -0.305054)
			(end -0.12065 -0.305054)
			(stroke
				(width 0.1)
				(type default)
			)
			(layer "F.Fab")
		)
		(fp_line
			(start 0.67945 -0.3048)
			(end 0.67945 0.3048)
			(stroke
				(width 0.1)
				(type default)
			)
			(layer "F.Fab")
		)
		(fp_line
			(start 0.12065 -0.3048)
			(end 0.67945 -0.3048)
			(stroke
				(width 0.1)
				(type default)
			)
			(layer "F.Fab")
		)
		(fp_line
			(start 0.12065 -0.2794)
			(end 0.12065 -0.3048)
			(stroke
				(width 0.1)
				(type default)
			)
			(layer "F.Fab")
		)
		(fp_line
			(start -0.12065 -0.2794)
			(end 0.12065 -0.2794)
			(stroke
				(width 0.1)
				(type default)
			)
			(layer "F.Fab")
		)
		(fp_line
			(start 0.120396 0.2794)
			(end -0.12065 0.2794)
			(stroke
				(width 0.1)
				(type default)
			)
			(layer "F.Fab")
		)
		(fp_line
			(start -0.12065 0.2794)
			(end -0.12065 0.3048)
			(stroke
				(width 0.1)
				(type default)
			)
			(layer "F.Fab")
		)
		(fp_line
			(start 0.67945 0.3048)
			(end 0.120396 0.3048)
			(stroke
				(width 0.1)
				(type default)
			)
			(layer "F.Fab")
		)
		(fp_line
			(start 0.120396 0.3048)
			(end 0.120396 0.2794)
			(stroke
				(width 0.1)
				(type default)
			)
			(layer "F.Fab")
		)
		(fp_line
			(start -0.12065 0.3048)
			(end -0.67945 0.3048)
			(stroke
				(width 0.1)
				(type default)
			)
			(layer "F.Fab")
		)
		(fp_line
			(start -0.67945 0.3048)
			(end -0.67945 -0.305054)
			(stroke
				(width 0.1)
				(type default)
			)
			(layer "F.Fab")
		)
		(pad "1" smd circle
			(at -0.40005 0 90)
			(size 0 0)
			(layers "F.Cu" "F.Mask" "F.Paste")
			(net "P3V3_AUX")
		)
		(pad "2" smd circle
			(at 0.40005 0 90)
			(size 0 0)
			(layers "F.Cu" "F.Mask" "F.Paste")
			(net "GND")
		)
	)
	(footprint ""
		(layer "F.Cu")
		(at 147.271486 -390.398254 -90)
		(property "Reference" "R1845"
			(at 0 0 270)
			(layer "F.SilkS")
			(hide yes)
			(effects
				(font
					(size 1.27 1.27)
				)
			)
		)
		(property "Value" ""
			(at 0 0 270)
			(layer "F.Fab")
			(effects
				(font
					(size 1.27 1.27)
				)
			)
		)
		(duplicate_pad_numbers_are_jumpers no)
		(fp_line
			(start -0.7874 0.4064)
			(end -0.7874 -0.4064)
			(stroke
				(width 0.1524)
				(type default)
			)
			(layer "F.SilkS")
		)
		(fp_line
			(start 0.7874 0.4064)
			(end -0.7874 0.4064)
			(stroke
				(width 0.1524)
				(type default)
			)
			(layer "F.SilkS")
		)
		(fp_line
			(start -0.7874 -0.4064)
			(end 0.7874 -0.4064)
			(stroke
				(width 0.1524)
				(type default)
			)
			(layer "F.SilkS")
		)
		(fp_line
			(start 0.7874 -0.4064)
			(end 0.7874 0.4064)
			(stroke
				(width 0.1524)
				(type default)
			)
			(layer "F.SilkS")
		)
		(fp_line
			(start -0.67945 0.3048)
			(end -0.67945 -0.305054)
			(stroke
				(width 0.1)
				(type default)
			)
			(layer "F.Fab")
		)
		(fp_line
			(start -0.12065 0.3048)
			(end -0.67945 0.3048)
			(stroke
				(width 0.1)
				(type default)
			)
			(layer "F.Fab")
		)
		(fp_line
			(start 0.120396 0.3048)
			(end 0.120396 0.2794)
			(stroke
				(width 0.1)
				(type default)
			)
			(layer "F.Fab")
		)
		(fp_line
			(start 0.67945 0.3048)
			(end 0.120396 0.3048)
			(stroke
				(width 0.1)
				(type default)
			)
			(layer "F.Fab")
		)
		(fp_line
			(start -0.12065 0.2794)
			(end -0.12065 0.3048)
			(stroke
				(width 0.1)
				(type default)
			)
			(layer "F.Fab")
		)
		(fp_line
			(start 0.120396 0.2794)
			(end -0.12065 0.2794)
			(stroke
				(width 0.1)
				(type default)
			)
			(layer "F.Fab")
		)
		(fp_line
			(start -0.12065 -0.2794)
			(end 0.12065 -0.2794)
			(stroke
				(width 0.1)
				(type default)
			)
			(layer "F.Fab")
		)
		(fp_line
			(start 0.12065 -0.2794)
			(end 0.12065 -0.3048)
			(stroke
				(width 0.1)
				(type default)
			)
			(layer "F.Fab")
		)
		(fp_line
			(start 0.12065 -0.3048)
			(end 0.67945 -0.3048)
			(stroke
				(width 0.1)
				(type default)
			)
			(layer "F.Fab")
		)
		(fp_line
			(start 0.67945 -0.3048)
			(end 0.67945 0.3048)
			(stroke
				(width 0.1)
				(type default)
			)
			(layer "F.Fab")
		)
		(fp_line
			(start -0.67945 -0.305054)
			(end -0.12065 -0.305054)
			(stroke
				(width 0.1)
				(type default)
			)
			(layer "F.Fab")
		)
		(fp_line
			(start -0.12065 -0.305054)
			(end -0.12065 -0.2794)
			(stroke
				(width 0.1)
				(type default)
			)
			(layer "F.Fab")
		)
		(pad "1" smd circle
			(at -0.40005 0 270)
			(size 0 0)
			(layers "F.Cu" "F.Mask" "F.Paste")
			(net "SMB_GPU2_ALERT_R_N")
		)
		(pad "2" smd circle
			(at 0.40005 0 270)
			(size 0 0)
			(layers "F.Cu" "F.Mask" "F.Paste")
			(net "SMB_GPU2_ALERT_N")
		)
	)
	(footprint ""
		(layer "F.Cu")
		(at 26.822654 -311.156604 -90)
		(property "Reference" "R1258"
			(at 0 0 270)
			(layer "F.SilkS")
			(hide yes)
			(effects
				(font
					(size 1.27 1.27)
				)
			)
		)
		(property "Value" ""
			(at 0 0 270)
			(layer "F.Fab")
			(effects
				(font
					(size 1.27 1.27)
				)
			)
		)
		(duplicate_pad_numbers_are_jumpers no)
		(fp_line
			(start -0.7874 0.4064)
			(end -0.7874 -0.4064)
			(stroke
				(width 0.1524)
				(type default)
			)
			(layer "F.SilkS")
		)
		(fp_line
			(start 0.7874 0.4064)
			(end -0.7874 0.4064)
			(stroke
				(width 0.1524)
				(type default)
			)
			(layer "F.SilkS")
		)
		(fp_line
			(start -0.7874 -0.4064)
			(end 0.7874 -0.4064)
			(stroke
				(width 0.1524)
				(type default)
			)
			(layer "F.SilkS")
		)
		(fp_line
			(start 0.7874 -0.4064)
			(end 0.7874 0.4064)
			(stroke
				(width 0.1524)
				(type default)
			)
			(layer "F.SilkS")
		)
		(fp_line
			(start -0.67945 0.3048)
			(end -0.67945 -0.305054)
			(stroke
				(width 0.1)
				(type default)
			)
			(layer "F.Fab")
		)
		(fp_line
			(start -0.12065 0.3048)
			(end -0.67945 0.3048)
			(stroke
				(width 0.1)
				(type default)
			)
			(layer "F.Fab")
		)
		(fp_line
			(start 0.120396 0.3048)
			(end 0.120396 0.2794)
			(stroke
				(width 0.1)
				(type default)
			)
			(layer "F.Fab")
		)
		(fp_line
			(start 0.67945 0.3048)
			(end 0.120396 0.3048)
			(stroke
				(width 0.1)
				(type default)
			)
			(layer "F.Fab")
		)
		(fp_line
			(start -0.12065 0.2794)
			(end -0.12065 0.3048)
			(stroke
				(width 0.1)
				(type default)
			)
			(layer "F.Fab")
		)
		(fp_line
			(start 0.120396 0.2794)
			(end -0.12065 0.2794)
			(stroke
				(width 0.1)
				(type default)
			)
			(layer "F.Fab")
		)
		(fp_line
			(start -0.12065 -0.2794)
			(end 0.12065 -0.2794)
			(stroke
				(width 0.1)
				(type default)
			)
			(layer "F.Fab")
		)
		(fp_line
			(start 0.12065 -0.2794)
			(end 0.12065 -0.3048)
			(stroke
				(width 0.1)
				(type default)
			)
			(layer "F.Fab")
		)
		(fp_line
			(start 0.12065 -0.3048)
			(end 0.67945 -0.3048)
			(stroke
				(width 0.1)
				(type default)
			)
			(layer "F.Fab")
		)
		(fp_line
			(start 0.67945 -0.3048)
			(end 0.67945 0.3048)
			(stroke
				(width 0.1)
				(type default)
			)
			(layer "F.Fab")
		)
		(fp_line
			(start -0.67945 -0.305054)
			(end -0.12065 -0.305054)
			(stroke
				(width 0.1)
				(type default)
			)
			(layer "F.Fab")
		)
		(fp_line
			(start -0.12065 -0.305054)
			(end -0.12065 -0.2794)
			(stroke
				(width 0.1)
				(type default)
			)
			(layer "F.Fab")
		)
		(pad "1" smd circle
			(at -0.40005 0 270)
			(size 0 0)
			(layers "F.Cu" "F.Mask" "F.Paste")
			(net "PU_PEX0_TR_TCK")
		)
		(pad "2" smd circle
			(at 0.40005 0 270)
			(size 0 0)
			(layers "F.Cu" "F.Mask" "F.Paste")
			(net "P1V8_PEX")
		)
	)
	(footprint ""
		(layer "F.Cu")
		(at 50.273966 -26.31186 -90)
		(property "Reference" "U399"
			(at 0.04826 -2.356104 90)
			(unlocked yes)
			(layer "F.SilkS")
			(effects
				(font
					(size 0.7874 0.5842)
					(thickness 0.1524)
				)
			)
		)
		(property "Value" ""
			(at 0 0 270)
			(layer "F.Fab")
			(effects
				(font
					(size 1.27 1.27)
				)
			)
		)
		(duplicate_pad_numbers_are_jumpers no)
		(fp_line
			(start -1.949958 1.610106)
			(end -1.949958 -1.610106)
			(stroke
				(width 0.1524)
				(type default)
			)
			(layer "F.SilkS")
		)
		(fp_line
			(start 1.949958 1.610106)
			(end -1.949958 1.610106)
			(stroke
				(width 0.1524)
				(type default)
			)
			(layer "F.SilkS")
		)
		(fp_line
			(start 1.949958 -1.560068)
			(end 1.949958 1.610106)
			(stroke
				(width 0.1524)
				(type default)
			)
			(layer "F.SilkS")
		)
		(fp_line
			(start -1.949958 -1.610106)
			(end 1.949958 -1.610106)
			(stroke
				(width 0.1524)
				(type default)
			)
			(layer "F.SilkS")
		)
		(fp_line
			(start -0.750062 1.560068)
			(end -0.750062 -1.560068)
			(stroke
				(width 0.1)
				(type default)
			)
			(layer "F.Fab")
		)
		(fp_line
			(start 0.750062 1.560068)
			(end -0.750062 1.560068)
			(stroke
				(width 0.1)
				(type default)
			)
			(layer "F.Fab")
		)
		(fp_line
			(start -0.750062 -1.560068)
			(end 0.750062 -1.560068)
			(stroke
				(width 0.1)
				(type default)
			)
			(layer "F.Fab")
		)
		(fp_line
			(start 0.750062 -1.560068)
			(end 0.750062 1.560068)
			(stroke
				(width 0.1)
				(type default)
			)
			(layer "F.Fab")
		)
		(pad "D" smd rect
			(at 1.100074 0 180)
			(size 1.016 1.4224)
			(layers "F.Cu" "F.Mask" "F.Paste")
			(net "SSD1_LED_ISO_N")
		)
		(pad "G" smd rect
			(at -1.100074 -0.94996 180)
			(size 1.016 1.4224)
			(layers "F.Cu" "F.Mask" "F.Paste")
			(net "SSD1_LED_R")
		)
		(pad "S" smd rect
			(at -1.100074 0.94996 180)
			(size 1.016 1.4224)
			(layers "F.Cu" "F.Mask" "F.Paste")
			(net "GND")
		)
	)
	(footprint ""
		(layer "F.Cu")
		(at 389.81634 -350.098614 90)
		(property "Reference" "C758"
			(at 0 0 90)
			(layer "F.SilkS")
			(hide yes)
			(effects
				(font
					(size 1.27 1.27)
				)
			)
		)
		(property "Value" ""
			(at 0 0 90)
			(layer "F.Fab")
			(effects
				(font
					(size 1.27 1.27)
				)
			)
		)
		(duplicate_pad_numbers_are_jumpers no)
		(fp_line
			(start 0.299974 -0.150114)
			(end 0.299974 0.150114)
			(stroke
				(width 0.1)
				(type default)
			)
			(layer "F.Fab")
		)
		(fp_line
			(start -0.299974 -0.150114)
			(end 0.299974 -0.150114)
			(stroke
				(width 0.1)
				(type default)
			)
			(layer "F.Fab")
		)
		(fp_line
			(start 0.299974 0.150114)
			(end -0.299974 0.150114)
			(stroke
				(width 0.1)
				(type default)
			)
			(layer "F.Fab")
		)
		(fp_line
			(start -0.299974 0.150114)
			(end -0.299974 -0.150114)
			(stroke
				(width 0.1)
				(type default)
			)
			(layer "F.Fab")
		)
		(pad "1" smd rect
			(at -0.2667 0 90)
			(size 0.3048 0.381)
			(layers "F.Cu" "F.Mask" "F.Paste")
			(net "P5E_PEX3_STN5_TX_DP<81>")
		)
		(pad "2" smd rect
			(at 0.2667 0 90)
			(size 0.3048 0.381)
			(layers "F.Cu" "F.Mask" "F.Paste")
			(net "P5E_PEX3_STN5_TX_C_DP<81>")
		)
	)
	(footprint ""
		(layer "F.Cu")
		(at 442.403484 -96.811592 90)
		(property "Reference" "R5623"
			(at 0 0 90)
			(layer "F.SilkS")
			(hide yes)
			(effects
				(font
					(size 1.27 1.27)
				)
			)
		)
		(property "Value" ""
			(at 0 0 90)
			(layer "F.Fab")
			(effects
				(font
					(size 1.27 1.27)
				)
			)
		)
		(duplicate_pad_numbers_are_jumpers no)
		(fp_line
			(start 0.7874 -0.4064)
			(end 0.7874 0.4064)
			(stroke
				(width 0.1524)
				(type default)
			)
			(layer "F.SilkS")
		)
		(fp_line
			(start -0.7874 -0.4064)
			(end 0.7874 -0.4064)
			(stroke
				(width 0.1524)
				(type default)
			)
			(layer "F.SilkS")
		)
		(fp_line
			(start 0.7874 0.4064)
			(end -0.7874 0.4064)
			(stroke
				(width 0.1524)
				(type default)
			)
			(layer "F.SilkS")
		)
		(fp_line
			(start -0.7874 0.4064)
			(end -0.7874 -0.4064)
			(stroke
				(width 0.1524)
				(type default)
			)
			(layer "F.SilkS")
		)
		(fp_line
			(start -0.12065 -0.305054)
			(end -0.12065 -0.2794)
			(stroke
				(width 0.1)
				(type default)
			)
			(layer "F.Fab")
		)
		(fp_line
			(start -0.67945 -0.305054)
			(end -0.12065 -0.305054)
			(stroke
				(width 0.1)
				(type default)
			)
			(layer "F.Fab")
		)
		(fp_line
			(start 0.67945 -0.3048)
			(end 0.67945 0.3048)
			(stroke
				(width 0.1)
				(type default)
			)
			(layer "F.Fab")
		)
		(fp_line
			(start 0.12065 -0.3048)
			(end 0.67945 -0.3048)
			(stroke
				(width 0.1)
				(type default)
			)
			(layer "F.Fab")
		)
		(fp_line
			(start 0.12065 -0.2794)
			(end 0.12065 -0.3048)
			(stroke
				(width 0.1)
				(type default)
			)
			(layer "F.Fab")
		)
		(fp_line
			(start -0.12065 -0.2794)
			(end 0.12065 -0.2794)
			(stroke
				(width 0.1)
				(type default)
			)
			(layer "F.Fab")
		)
		(fp_line
			(start 0.120396 0.2794)
			(end -0.12065 0.2794)
			(stroke
				(width 0.1)
				(type default)
			)
			(layer "F.Fab")
		)
		(fp_line
			(start -0.12065 0.2794)
			(end -0.12065 0.3048)
			(stroke
				(width 0.1)
				(type default)
			)
			(layer "F.Fab")
		)
		(fp_line
			(start 0.67945 0.3048)
			(end 0.120396 0.3048)
			(stroke
				(width 0.1)
				(type default)
			)
			(layer "F.Fab")
		)
		(fp_line
			(start 0.120396 0.3048)
			(end 0.120396 0.2794)
			(stroke
				(width 0.1)
				(type default)
			)
			(layer "F.Fab")
		)
		(fp_line
			(start -0.12065 0.3048)
			(end -0.67945 0.3048)
			(stroke
				(width 0.1)
				(type default)
			)
			(layer "F.Fab")
		)
		(fp_line
			(start -0.67945 0.3048)
			(end -0.67945 -0.305054)
			(stroke
				(width 0.1)
				(type default)
			)
			(layer "F.Fab")
		)
		(pad "1" smd circle
			(at -0.40005 0 90)
			(size 0 0)
			(layers "F.Cu" "F.Mask" "F.Paste")
			(net "NIC7_ADC_A0")
		)
		(pad "2" smd circle
			(at 0.40005 0 90)
			(size 0 0)
			(layers "F.Cu" "F.Mask" "F.Paste")
			(net "SMB_NIC7_ADC_SCL")
		)
	)
	(footprint ""
		(layer "F.Cu")
		(at 149.171406 -243.130578 180)
		(property "Reference" "R6576"
			(at 0 0 180)
			(layer "F.SilkS")
			(hide yes)
			(effects
				(font
					(size 1.27 1.27)
				)
			)
		)
		(property "Value" ""
			(at 0 0 180)
			(layer "F.Fab")
			(effects
				(font
					(size 1.27 1.27)
				)
			)
		)
		(duplicate_pad_numbers_are_jumpers no)
		(fp_line
			(start 0.7874 0.4064)
			(end -0.7874 0.4064)
			(stroke
				(width 0.1524)
				(type default)
			)
			(layer "F.SilkS")
		)
		(fp_line
			(start 0.7874 -0.4064)
			(end 0.7874 0.4064)
			(stroke
				(width 0.1524)
				(type default)
			)
			(layer "F.SilkS")
		)
		(fp_line
			(start -0.7874 0.4064)
			(end -0.7874 -0.4064)
			(stroke
				(width 0.1524)
				(type default)
			)
			(layer "F.SilkS")
		)
		(fp_line
			(start -0.7874 -0.4064)
			(end 0.7874 -0.4064)
			(stroke
				(width 0.1524)
				(type default)
			)
			(layer "F.SilkS")
		)
		(fp_line
			(start 0.67945 0.3048)
			(end 0.120396 0.3048)
			(stroke
				(width 0.1)
				(type default)
			)
			(layer "F.Fab")
		)
		(fp_line
			(start 0.67945 -0.3048)
			(end 0.67945 0.3048)
			(stroke
				(width 0.1)
				(type default)
			)
			(layer "F.Fab")
		)
		(fp_line
			(start 0.12065 -0.2794)
			(end 0.12065 -0.3048)
			(stroke
				(width 0.1)
				(type default)
			)
			(layer "F.Fab")
		)
		(fp_line
			(start 0.12065 -0.3048)
			(end 0.67945 -0.3048)
			(stroke
				(width 0.1)
				(type default)
			)
			(layer "F.Fab")
		)
		(fp_line
			(start 0.120396 0.3048)
			(end 0.120396 0.2794)
			(stroke
				(width 0.1)
				(type default)
			)
			(layer "F.Fab")
		)
		(fp_line
			(start 0.120396 0.2794)
			(end -0.12065 0.2794)
			(stroke
				(width 0.1)
				(type default)
			)
			(layer "F.Fab")
		)
		(fp_line
			(start -0.12065 0.3048)
			(end -0.67945 0.3048)
			(stroke
				(width 0.1)
				(type default)
			)
			(layer "F.Fab")
		)
		(fp_line
			(start -0.12065 0.2794)
			(end -0.12065 0.3048)
			(stroke
				(width 0.1)
				(type default)
			)
			(layer "F.Fab")
		)
		(fp_line
			(start -0.12065 -0.2794)
			(end 0.12065 -0.2794)
			(stroke
				(width 0.1)
				(type default)
			)
			(layer "F.Fab")
		)
		(fp_line
			(start -0.12065 -0.305054)
			(end -0.12065 -0.2794)
			(stroke
				(width 0.1)
				(type default)
			)
			(layer "F.Fab")
		)
		(fp_line
			(start -0.67945 0.3048)
			(end -0.67945 -0.305054)
			(stroke
				(width 0.1)
				(type default)
			)
			(layer "F.Fab")
		)
		(fp_line
			(start -0.67945 -0.305054)
			(end -0.12065 -0.305054)
			(stroke
				(width 0.1)
				(type default)
			)
			(layer "F.Fab")
		)
		(pad "1" smd circle
			(at -0.40005 0 180)
			(size 0 0)
			(layers "F.Cu" "F.Mask" "F.Paste")
			(net "PWRGD_PEX1_P1V8_PLL_R")
		)
		(pad "2" smd circle
			(at 0.40005 0 180)
			(size 0 0)
			(layers "F.Cu" "F.Mask" "F.Paste")
			(net "PWRGD_PEX1_P1V8_PLL")
		)
	)
	(footprint ""
		(layer "F.Cu")
		(at 174.991014 -55.663846 90)
		(property "Reference" "PU58"
			(at -1.524 2.792222 90)
			(unlocked yes)
			(layer "F.SilkS")
			(effects
				(font
					(size 0.7874 0.5842)
					(thickness 0.1524)
				)
				(justify left)
			)
		)
		(property "Value" ""
			(at 0 0 90)
			(layer "F.Fab")
			(effects
				(font
					(size 1.27 1.27)
				)
			)
		)
		(duplicate_pad_numbers_are_jumpers no)
		(fp_line
			(start 1.943608 -1.549908)
			(end 1.943608 1.549908)
			(stroke
				(width 0.1524)
				(type default)
			)
			(layer "F.SilkS")
		)
		(fp_line
			(start -1.943608 -1.549908)
			(end 1.943608 -1.549908)
			(stroke
				(width 0.1524)
				(type default)
			)
			(layer "F.SilkS")
		)
		(fp_line
			(start 1.943608 1.549908)
			(end -1.943608 1.549908)
			(stroke
				(width 0.1524)
				(type default)
			)
			(layer "F.SilkS")
		)
		(fp_line
			(start -1.943608 1.549908)
			(end -1.943608 -1.549908)
			(stroke
				(width 0.1524)
				(type default)
			)
			(layer "F.SilkS")
		)
		(fp_poly
			(pts
				(xy -2.019808 -1.549908) (xy -1.257808 -1.549908) (xy -1.257808 -1.880108) (xy -2.019808 -1.880108)
			)
			(stroke
				(width 0)
				(type default)
			)
			(fill yes)
			(layer "F.SilkS")
		)
		(fp_line
			(start 1.549908 -1.549908)
			(end 1.549908 1.549908)
			(stroke
				(width 0.1)
				(type default)
			)
			(layer "F.Fab")
		)
		(fp_line
			(start -1.549908 -1.549908)
			(end 1.549908 -1.549908)
			(stroke
				(width 0.1)
				(type default)
			)
			(layer "F.Fab")
		)
		(fp_line
			(start 1.549908 1.549908)
			(end -1.549908 1.549908)
			(stroke
				(width 0.1)
				(type default)
			)
			(layer "F.Fab")
		)
		(fp_line
			(start -1.549908 1.549908)
			(end -1.549908 -1.549908)
			(stroke
				(width 0.1)
				(type default)
			)
			(layer "F.Fab")
		)
		(fp_poly
			(pts
				(xy -2.019808 -1.549908) (xy -1.257808 -1.549908) (xy -1.257808 -1.880108) (xy -2.019808 -1.880108)
			)
			(stroke
				(width 0)
				(type default)
			)
			(fill yes)
			(layer "F.Fab")
		)
		(pad "1" smd rect
			(at -1.500124 -1.249934)
			(size 0.2794 0.6096)
			(layers "F.Cu" "F.Mask" "F.Paste")
			(net "P3V3_SSD6")
		)
		(pad "2" smd rect
			(at -1.500124 -0.750062)
			(size 0.2794 0.6096)
			(layers "F.Cu" "F.Mask" "F.Paste")
			(net "P3V3_SSD6")
		)
		(pad "3" smd rect
			(at -1.500124 -0.249936)
			(size 0.2794 0.6096)
			(layers "F.Cu" "F.Mask" "F.Paste")
			(net "P3V3_SSD6")
		)
		(pad "4" smd rect
			(at -1.500124 0.249936)
			(size 0.2794 0.6096)
			(layers "F.Cu" "F.Mask" "F.Paste")
			(net "P3V3_SSD6")
		)
		(pad "5" smd rect
			(at -1.500124 0.750062)
			(size 0.2794 0.6096)
			(layers "F.Cu" "F.Mask" "F.Paste")
			(net "P3V3_SSD6")
		)
		(pad "6" smd rect
			(at -1.500124 1.249934)
			(size 0.2794 0.6096)
			(layers "F.Cu" "F.Mask" "F.Paste")
			(net "GND")
		)
		(pad "7" smd rect
			(at 1.500124 1.249934)
			(size 0.2794 0.6096)
			(layers "F.Cu" "F.Mask" "F.Paste")
			(net "P3V3_SSD6_SS")
		)
		(pad "8" smd rect
			(at 1.500124 0.750062)
			(size 0.2794 0.6096)
			(layers "F.Cu" "F.Mask" "F.Paste")
			(net "PWRGD_P3V3_SSD6")
		)
		(pad "9" smd rect
			(at 1.500124 0.249936)
			(size 0.2794 0.6096)
			(layers "F.Cu" "F.Mask" "F.Paste")
			(net "P3V3_SSD6_OCP")
		)
		(pad "10" smd rect
			(at 1.500124 -0.249936)
			(size 0.2794 0.6096)
			(layers "F.Cu" "F.Mask" "F.Paste")
			(net "P5V_AUX")
		)
		(pad "11" smd rect
			(at 1.500124 -0.750062)
			(size 0.2794 0.6096)
			(layers "F.Cu" "F.Mask" "F.Paste")
			(net "SSD6_AUX_P3V3_EN_R")
		)
		(pad "12" smd rect
			(at 1.500124 -1.249934)
			(size 0.2794 0.6096)
			(layers "F.Cu" "F.Mask" "F.Paste")
			(net "P3V3_AUX")
		)
		(pad "13" smd rect
			(at 0 0 90)
			(size 1.9812 2.7178)
			(layers "F.Cu" "F.Mask" "F.Paste")
			(net "P3V3_AUX")
		)
		(zone
			(layer "F.Cu")
			(hatch none 0.5)
			(connect_pads
				(clearance 0)
			)
			(min_thickness 0.25)
			(keepout
				(tracks not_allowed)
				(vias allowed)
				(pads allowed)
				(copperpour not_allowed)
				(footprints allowed)
			)
			(placement
				(enabled no)
				(sheetname "")
			)
			(fill
				(thermal_gap 0.5)
				(thermal_bridge_width 0.5)
				(island_removal_mode 0)
			)
			(polygon
				(pts
					(xy 173.441614 -56.806846) (xy 173.568614 -56.806846) (xy 176.540414 -56.806846) (xy 176.540922 -56.806846)
					(xy 176.540922 -54.520846) (xy 176.540414 -54.520846) (xy 176.413414 -54.520846) (xy 174.991014 -54.520846)
					(xy 174.991014 -54.622446) (xy 176.413414 -54.622446) (xy 176.413414 -56.705246) (xy 173.568614 -56.705246)
					(xy 173.568614 -54.622446) (xy 174.965614 -54.622446) (xy 174.965614 -54.520846) (xy 173.568614 -54.520846)
					(xy 173.441614 -54.520846) (xy 173.441106 -54.520846) (xy 173.441106 -56.806846)
				)
			)
		)
	)
	(footprint ""
		(layer "F.Cu")
		(at 374.543828 -43.85691)
		(property "Reference" "R640"
			(at 0 0 0)
			(layer "F.SilkS")
			(hide yes)
			(effects
				(font
					(size 1.27 1.27)
				)
			)
		)
		(property "Value" ""
			(at 0 0 0)
			(layer "F.Fab")
			(effects
				(font
					(size 1.27 1.27)
				)
			)
		)
		(duplicate_pad_numbers_are_jumpers no)
		(fp_line
			(start -0.7874 -0.4064)
			(end 0.7874 -0.4064)
			(stroke
				(width 0.1524)
				(type default)
			)
			(layer "F.SilkS")
		)
		(fp_line
			(start -0.7874 0.4064)
			(end -0.7874 -0.4064)
			(stroke
				(width 0.1524)
				(type default)
			)
			(layer "F.SilkS")
		)
		(fp_line
			(start 0.7874 -0.4064)
			(end 0.7874 0.4064)
			(stroke
				(width 0.1524)
				(type default)
			)
			(layer "F.SilkS")
		)
		(fp_line
			(start 0.7874 0.4064)
			(end -0.7874 0.4064)
			(stroke
				(width 0.1524)
				(type default)
			)
			(layer "F.SilkS")
		)
		(fp_line
			(start -0.67945 -0.305054)
			(end -0.12065 -0.305054)
			(stroke
				(width 0.1)
				(type default)
			)
			(layer "F.Fab")
		)
		(fp_line
			(start -0.67945 0.3048)
			(end -0.67945 -0.305054)
			(stroke
				(width 0.1)
				(type default)
			)
			(layer "F.Fab")
		)
		(fp_line
			(start -0.12065 -0.305054)
			(end -0.12065 -0.2794)
			(stroke
				(width 0.1)
				(type default)
			)
			(layer "F.Fab")
		)
		(fp_line
			(start -0.12065 -0.2794)
			(end 0.12065 -0.2794)
			(stroke
				(width 0.1)
				(type default)
			)
			(layer "F.Fab")
		)
		(fp_line
			(start -0.12065 0.2794)
			(end -0.12065 0.3048)
			(stroke
				(width 0.1)
				(type default)
			)
			(layer "F.Fab")
		)
		(fp_line
			(start -0.12065 0.3048)
			(end -0.67945 0.3048)
			(stroke
				(width 0.1)
				(type default)
			)
			(layer "F.Fab")
		)
		(fp_line
			(start 0.120396 0.2794)
			(end -0.12065 0.2794)
			(stroke
				(width 0.1)
				(type default)
			)
			(layer "F.Fab")
		)
		(fp_line
			(start 0.120396 0.3048)
			(end 0.120396 0.2794)
			(stroke
				(width 0.1)
				(type default)
			)
			(layer "F.Fab")
		)
		(fp_line
			(start 0.12065 -0.3048)
			(end 0.67945 -0.3048)
			(stroke
				(width 0.1)
				(type default)
			)
			(layer "F.Fab")
		)
		(fp_line
			(start 0.12065 -0.2794)
			(end 0.12065 -0.3048)
			(stroke
				(width 0.1)
				(type default)
			)
			(layer "F.Fab")
		)
		(fp_line
			(start 0.67945 -0.3048)
			(end 0.67945 0.3048)
			(stroke
				(width 0.1)
				(type default)
			)
			(layer "F.Fab")
		)
		(fp_line
			(start 0.67945 0.3048)
			(end 0.120396 0.3048)
			(stroke
				(width 0.1)
				(type default)
			)
			(layer "F.Fab")
		)
		(pad "1" smd circle
			(at -0.40005 0)
			(size 0 0)
			(layers "F.Cu" "F.Mask" "F.Paste")
			(net "SSD12_ADC_A1")
		)
		(pad "2" smd circle
			(at 0.40005 0)
			(size 0 0)
			(layers "F.Cu" "F.Mask" "F.Paste")
			(net "GND")
		)
	)
	(footprint ""
		(layer "F.Cu")
		(at 147.750276 -50.96383 180)
		(property "Reference" "PC515"
			(at 0 0 180)
			(layer "F.SilkS")
			(hide yes)
			(effects
				(font
					(size 1.27 1.27)
				)
			)
		)
		(property "Value" ""
			(at 0 0 180)
			(layer "F.Fab")
			(effects
				(font
					(size 1.27 1.27)
				)
			)
		)
		(duplicate_pad_numbers_are_jumpers no)
		(fp_line
			(start 1.524 0.762)
			(end -1.524 0.762)
			(stroke
				(width 0.1524)
				(type default)
			)
			(layer "F.SilkS")
		)
		(fp_line
			(start 1.524 -0.762)
			(end 1.524 0.762)
			(stroke
				(width 0.1524)
				(type default)
			)
			(layer "F.SilkS")
		)
		(fp_line
			(start -1.524 0.762)
			(end -1.524 -0.762)
			(stroke
				(width 0.1524)
				(type default)
			)
			(layer "F.SilkS")
		)
		(fp_line
			(start -1.524 -0.762)
			(end 1.524 -0.762)
			(stroke
				(width 0.1524)
				(type default)
			)
			(layer "F.SilkS")
		)
		(fp_line
			(start 1.1049 0.724916)
			(end 1.1049 -0.724916)
			(stroke
				(width 0.1)
				(type default)
			)
			(layer "F.Fab")
		)
		(fp_line
			(start 1.1049 -0.724916)
			(end -1.1049 -0.724916)
			(stroke
				(width 0.1)
				(type default)
			)
			(layer "F.Fab")
		)
		(fp_line
			(start -1.1049 0.724916)
			(end 1.1049 0.724916)
			(stroke
				(width 0.1)
				(type default)
			)
			(layer "F.Fab")
		)
		(fp_line
			(start -1.1049 -0.724916)
			(end -1.1049 0.724916)
			(stroke
				(width 0.1)
				(type default)
			)
			(layer "F.Fab")
		)
		(pad "1" smd rect
			(at -0.889 0)
			(size 1.016 1.27)
			(layers "F.Cu" "F.Mask" "F.Paste")
			(net "P3V3_SSD5")
		)
		(pad "2" smd rect
			(at 0.889 0)
			(size 1.016 1.27)
			(layers "F.Cu" "F.Mask" "F.Paste")
			(net "GND")
		)
	)
	(footprint ""
		(layer "F.Cu")
		(at 135.508238 -142.455392 180)
		(property "Reference" "R704"
			(at 0 0 180)
			(layer "F.SilkS")
			(hide yes)
			(effects
				(font
					(size 1.27 1.27)
				)
			)
		)
		(property "Value" ""
			(at 0 0 180)
			(layer "F.Fab")
			(effects
				(font
					(size 1.27 1.27)
				)
			)
		)
		(duplicate_pad_numbers_are_jumpers no)
		(fp_line
			(start 3.937508 1.8796)
			(end 3.937508 -1.8796)
			(stroke
				(width 0.1524)
				(type default)
			)
			(layer "F.SilkS")
		)
		(fp_line
			(start 3.937508 -1.8796)
			(end -3.937508 -1.8796)
			(stroke
				(width 0.1524)
				(type default)
			)
			(layer "F.SilkS")
		)
		(fp_line
			(start -3.937508 1.8796)
			(end 3.937508 1.8796)
			(stroke
				(width 0.1524)
				(type default)
			)
			(layer "F.SilkS")
		)
		(fp_line
			(start -3.937508 -1.8796)
			(end -3.937508 1.8796)
			(stroke
				(width 0.1524)
				(type default)
			)
			(layer "F.SilkS")
		)
		(fp_line
			(start 3.275076 1.674876)
			(end 3.275076 -1.674876)
			(stroke
				(width 0.1)
				(type default)
			)
			(layer "F.Fab")
		)
		(fp_line
			(start 3.275076 -1.674876)
			(end -3.275076 -1.674876)
			(stroke
				(width 0.1)
				(type default)
			)
			(layer "F.Fab")
		)
		(fp_line
			(start -3.275076 1.674876)
			(end 3.275076 1.674876)
			(stroke
				(width 0.1)
				(type default)
			)
			(layer "F.Fab")
		)
		(fp_line
			(start -3.275076 -1.674876)
			(end -3.275076 1.674876)
			(stroke
				(width 0.1)
				(type default)
			)
			(layer "F.Fab")
		)
		(pad "1" smd rect
			(at -2.350008 0 180)
			(size 2.921 3.5052)
			(layers "F.Cu" "F.Mask" "F.Paste")
			(net "P12V_NIC2")
		)
		(pad "2" smd rect
			(at 2.350008 0 180)
			(size 2.921 3.5052)
			(layers "F.Cu" "F.Mask" "F.Paste")
			(net "P12V_NIC2_R")
		)
	)
	(footprint ""
		(layer "F.Cu")
		(at 86.110318 -63.652146 180)
		(property "Reference" "R5851"
			(at 0 0 180)
			(layer "F.SilkS")
			(hide yes)
			(effects
				(font
					(size 1.27 1.27)
				)
			)
		)
		(property "Value" ""
			(at 0 0 180)
			(layer "F.Fab")
			(effects
				(font
					(size 1.27 1.27)
				)
			)
		)
		(duplicate_pad_numbers_are_jumpers no)
		(fp_line
			(start 0.7874 0.4064)
			(end -0.7874 0.4064)
			(stroke
				(width 0.1524)
				(type default)
			)
			(layer "F.SilkS")
		)
		(fp_line
			(start 0.7874 -0.4064)
			(end 0.7874 0.4064)
			(stroke
				(width 0.1524)
				(type default)
			)
			(layer "F.SilkS")
		)
		(fp_line
			(start -0.7874 0.4064)
			(end -0.7874 -0.4064)
			(stroke
				(width 0.1524)
				(type default)
			)
			(layer "F.SilkS")
		)
		(fp_line
			(start -0.7874 -0.4064)
			(end 0.7874 -0.4064)
			(stroke
				(width 0.1524)
				(type default)
			)
			(layer "F.SilkS")
		)
		(fp_line
			(start 0.67945 0.3048)
			(end 0.120396 0.3048)
			(stroke
				(width 0.1)
				(type default)
			)
			(layer "F.Fab")
		)
		(fp_line
			(start 0.67945 -0.3048)
			(end 0.67945 0.3048)
			(stroke
				(width 0.1)
				(type default)
			)
			(layer "F.Fab")
		)
		(fp_line
			(start 0.12065 -0.2794)
			(end 0.12065 -0.3048)
			(stroke
				(width 0.1)
				(type default)
			)
			(layer "F.Fab")
		)
		(fp_line
			(start 0.12065 -0.3048)
			(end 0.67945 -0.3048)
			(stroke
				(width 0.1)
				(type default)
			)
			(layer "F.Fab")
		)
		(fp_line
			(start 0.120396 0.3048)
			(end 0.120396 0.2794)
			(stroke
				(width 0.1)
				(type default)
			)
			(layer "F.Fab")
		)
		(fp_line
			(start 0.120396 0.2794)
			(end -0.12065 0.2794)
			(stroke
				(width 0.1)
				(type default)
			)
			(layer "F.Fab")
		)
		(fp_line
			(start -0.12065 0.3048)
			(end -0.67945 0.3048)
			(stroke
				(width 0.1)
				(type default)
			)
			(layer "F.Fab")
		)
		(fp_line
			(start -0.12065 0.2794)
			(end -0.12065 0.3048)
			(stroke
				(width 0.1)
				(type default)
			)
			(layer "F.Fab")
		)
		(fp_line
			(start -0.12065 -0.2794)
			(end 0.12065 -0.2794)
			(stroke
				(width 0.1)
				(type default)
			)
			(layer "F.Fab")
		)
		(fp_line
			(start -0.12065 -0.305054)
			(end -0.12065 -0.2794)
			(stroke
				(width 0.1)
				(type default)
			)
			(layer "F.Fab")
		)
		(fp_line
			(start -0.67945 0.3048)
			(end -0.67945 -0.305054)
			(stroke
				(width 0.1)
				(type default)
			)
			(layer "F.Fab")
		)
		(fp_line
			(start -0.67945 -0.305054)
			(end -0.12065 -0.305054)
			(stroke
				(width 0.1)
				(type default)
			)
			(layer "F.Fab")
		)
		(pad "1" smd circle
			(at -0.40005 0 180)
			(size 0 0)
			(layers "F.Cu" "F.Mask" "F.Paste")
			(net "P5V_AUX")
		)
		(pad "2" smd circle
			(at 0.40005 0 180)
			(size 0 0)
			(layers "F.Cu" "F.Mask" "F.Paste")
			(net "P12V_SSD3_PG_G2")
		)
	)
	(footprint ""
		(layer "F.Cu")
		(at 123.648978 -89.53373)
		(property "Reference" "R1587"
			(at 0 0 0)
			(layer "F.SilkS")
			(hide yes)
			(effects
				(font
					(size 1.27 1.27)
				)
			)
		)
		(property "Value" ""
			(at 0 0 0)
			(layer "F.Fab")
			(effects
				(font
					(size 1.27 1.27)
				)
			)
		)
		(duplicate_pad_numbers_are_jumpers no)
		(fp_line
			(start -0.7874 -0.4064)
			(end 0.7874 -0.4064)
			(stroke
				(width 0.1524)
				(type default)
			)
			(layer "F.SilkS")
		)
		(fp_line
			(start -0.7874 0.4064)
			(end -0.7874 -0.4064)
			(stroke
				(width 0.1524)
				(type default)
			)
			(layer "F.SilkS")
		)
		(fp_line
			(start 0.7874 -0.4064)
			(end 0.7874 0.4064)
			(stroke
				(width 0.1524)
				(type default)
			)
			(layer "F.SilkS")
		)
		(fp_line
			(start 0.7874 0.4064)
			(end -0.7874 0.4064)
			(stroke
				(width 0.1524)
				(type default)
			)
			(layer "F.SilkS")
		)
		(fp_line
			(start -0.67945 -0.305054)
			(end -0.12065 -0.305054)
			(stroke
				(width 0.1)
				(type default)
			)
			(layer "F.Fab")
		)
		(fp_line
			(start -0.67945 0.3048)
			(end -0.67945 -0.305054)
			(stroke
				(width 0.1)
				(type default)
			)
			(layer "F.Fab")
		)
		(fp_line
			(start -0.12065 -0.305054)
			(end -0.12065 -0.2794)
			(stroke
				(width 0.1)
				(type default)
			)
			(layer "F.Fab")
		)
		(fp_line
			(start -0.12065 -0.2794)
			(end 0.12065 -0.2794)
			(stroke
				(width 0.1)
				(type default)
			)
			(layer "F.Fab")
		)
		(fp_line
			(start -0.12065 0.2794)
			(end -0.12065 0.3048)
			(stroke
				(width 0.1)
				(type default)
			)
			(layer "F.Fab")
		)
		(fp_line
			(start -0.12065 0.3048)
			(end -0.67945 0.3048)
			(stroke
				(width 0.1)
				(type default)
			)
			(layer "F.Fab")
		)
		(fp_line
			(start 0.120396 0.2794)
			(end -0.12065 0.2794)
			(stroke
				(width 0.1)
				(type default)
			)
			(layer "F.Fab")
		)
		(fp_line
			(start 0.120396 0.3048)
			(end 0.120396 0.2794)
			(stroke
				(width 0.1)
				(type default)
			)
			(layer "F.Fab")
		)
		(fp_line
			(start 0.12065 -0.3048)
			(end 0.67945 -0.3048)
			(stroke
				(width 0.1)
				(type default)
			)
			(layer "F.Fab")
		)
		(fp_line
			(start 0.12065 -0.2794)
			(end 0.12065 -0.3048)
			(stroke
				(width 0.1)
				(type default)
			)
			(layer "F.Fab")
		)
		(fp_line
			(start 0.67945 -0.3048)
			(end 0.67945 0.3048)
			(stroke
				(width 0.1)
				(type default)
			)
			(layer "F.Fab")
		)
		(fp_line
			(start 0.67945 0.3048)
			(end 0.120396 0.3048)
			(stroke
				(width 0.1)
				(type default)
			)
			(layer "F.Fab")
		)
		(pad "1" smd circle
			(at -0.40005 0)
			(size 0 0)
			(layers "F.Cu" "F.Mask" "F.Paste")
			(net "SMB_BIC_I2C9_MUX0_SSD3_R_SDA")
		)
		(pad "2" smd circle
			(at 0.40005 0)
			(size 0 0)
			(layers "F.Cu" "F.Mask" "F.Paste")
			(net "SMB_BIC_I2C9_MUX0_SSD3_SDA")
		)
	)
	(footprint ""
		(layer "F.Cu")
		(at 462.465674 -279.69083 180)
		(property "Reference" "R809"
			(at 0 0 180)
			(layer "F.SilkS")
			(hide yes)
			(effects
				(font
					(size 1.27 1.27)
				)
			)
		)
		(property "Value" ""
			(at 0 0 180)
			(layer "F.Fab")
			(effects
				(font
					(size 1.27 1.27)
				)
			)
		)
		(duplicate_pad_numbers_are_jumpers no)
		(fp_line
			(start 0.7874 0.4064)
			(end -0.7874 0.4064)
			(stroke
				(width 0.1524)
				(type default)
			)
			(layer "F.SilkS")
		)
		(fp_line
			(start 0.7874 -0.4064)
			(end 0.7874 0.4064)
			(stroke
				(width 0.1524)
				(type default)
			)
			(layer "F.SilkS")
		)
		(fp_line
			(start -0.7874 0.4064)
			(end -0.7874 -0.4064)
			(stroke
				(width 0.1524)
				(type default)
			)
			(layer "F.SilkS")
		)
		(fp_line
			(start -0.7874 -0.4064)
			(end 0.7874 -0.4064)
			(stroke
				(width 0.1524)
				(type default)
			)
			(layer "F.SilkS")
		)
		(fp_line
			(start 0.67945 0.3048)
			(end 0.120396 0.3048)
			(stroke
				(width 0.1)
				(type default)
			)
			(layer "F.Fab")
		)
		(fp_line
			(start 0.67945 -0.3048)
			(end 0.67945 0.3048)
			(stroke
				(width 0.1)
				(type default)
			)
			(layer "F.Fab")
		)
		(fp_line
			(start 0.12065 -0.2794)
			(end 0.12065 -0.3048)
			(stroke
				(width 0.1)
				(type default)
			)
			(layer "F.Fab")
		)
		(fp_line
			(start 0.12065 -0.3048)
			(end 0.67945 -0.3048)
			(stroke
				(width 0.1)
				(type default)
			)
			(layer "F.Fab")
		)
		(fp_line
			(start 0.120396 0.3048)
			(end 0.120396 0.2794)
			(stroke
				(width 0.1)
				(type default)
			)
			(layer "F.Fab")
		)
		(fp_line
			(start 0.120396 0.2794)
			(end -0.12065 0.2794)
			(stroke
				(width 0.1)
				(type default)
			)
			(layer "F.Fab")
		)
		(fp_line
			(start -0.12065 0.3048)
			(end -0.67945 0.3048)
			(stroke
				(width 0.1)
				(type default)
			)
			(layer "F.Fab")
		)
		(fp_line
			(start -0.12065 0.2794)
			(end -0.12065 0.3048)
			(stroke
				(width 0.1)
				(type default)
			)
			(layer "F.Fab")
		)
		(fp_line
			(start -0.12065 -0.2794)
			(end 0.12065 -0.2794)
			(stroke
				(width 0.1)
				(type default)
			)
			(layer "F.Fab")
		)
		(fp_line
			(start -0.12065 -0.305054)
			(end -0.12065 -0.2794)
			(stroke
				(width 0.1)
				(type default)
			)
			(layer "F.Fab")
		)
		(fp_line
			(start -0.67945 0.3048)
			(end -0.67945 -0.305054)
			(stroke
				(width 0.1)
				(type default)
			)
			(layer "F.Fab")
		)
		(fp_line
			(start -0.67945 -0.305054)
			(end -0.12065 -0.305054)
			(stroke
				(width 0.1)
				(type default)
			)
			(layer "F.Fab")
		)
		(pad "1" smd circle
			(at -0.40005 0 180)
			(size 0 0)
			(layers "F.Cu" "F.Mask" "F.Paste")
			(net "SMB_BIC_I2C6_MUX_PEX_ADC_R_SDA")
		)
		(pad "2" smd circle
			(at 0.40005 0 180)
			(size 0 0)
			(layers "F.Cu" "F.Mask" "F.Paste")
			(net "SMB_PEX3_P1V25_ADC_SDA")
		)
	)
	(footprint ""
		(layer "F.Cu")
		(at 248.452894 -159.173418 90)
		(property "Reference" "PC799"
			(at 0 0 90)
			(layer "F.SilkS")
			(hide yes)
			(effects
				(font
					(size 1.27 1.27)
				)
			)
		)
		(property "Value" ""
			(at 0 0 90)
			(layer "F.Fab")
			(effects
				(font
					(size 1.27 1.27)
				)
			)
		)
		(duplicate_pad_numbers_are_jumpers no)
		(fp_line
			(start 0.7874 -0.4064)
			(end 0.7874 0.4064)
			(stroke
				(width 0.1524)
				(type default)
			)
			(layer "F.SilkS")
		)
		(fp_line
			(start -0.7874 -0.4064)
			(end 0.7874 -0.4064)
			(stroke
				(width 0.1524)
				(type default)
			)
			(layer "F.SilkS")
		)
		(fp_line
			(start 0.7874 0.4064)
			(end -0.7874 0.4064)
			(stroke
				(width 0.1524)
				(type default)
			)
			(layer "F.SilkS")
		)
		(fp_line
			(start -0.7874 0.4064)
			(end -0.7874 -0.4064)
			(stroke
				(width 0.1524)
				(type default)
			)
			(layer "F.SilkS")
		)
		(fp_line
			(start -0.12065 -0.305054)
			(end -0.12065 -0.2794)
			(stroke
				(width 0.1)
				(type default)
			)
			(layer "F.Fab")
		)
		(fp_line
			(start -0.67945 -0.305054)
			(end -0.12065 -0.305054)
			(stroke
				(width 0.1)
				(type default)
			)
			(layer "F.Fab")
		)
		(fp_line
			(start 0.67945 -0.3048)
			(end 0.67945 0.3048)
			(stroke
				(width 0.1)
				(type default)
			)
			(layer "F.Fab")
		)
		(fp_line
			(start 0.12065 -0.3048)
			(end 0.67945 -0.3048)
			(stroke
				(width 0.1)
				(type default)
			)
			(layer "F.Fab")
		)
		(fp_line
			(start 0.12065 -0.2794)
			(end 0.12065 -0.3048)
			(stroke
				(width 0.1)
				(type default)
			)
			(layer "F.Fab")
		)
		(fp_line
			(start -0.12065 -0.2794)
			(end 0.12065 -0.2794)
			(stroke
				(width 0.1)
				(type default)
			)
			(layer "F.Fab")
		)
		(fp_line
			(start 0.120396 0.2794)
			(end -0.12065 0.2794)
			(stroke
				(width 0.1)
				(type default)
			)
			(layer "F.Fab")
		)
		(fp_line
			(start -0.12065 0.2794)
			(end -0.12065 0.3048)
			(stroke
				(width 0.1)
				(type default)
			)
			(layer "F.Fab")
		)
		(fp_line
			(start 0.67945 0.3048)
			(end 0.120396 0.3048)
			(stroke
				(width 0.1)
				(type default)
			)
			(layer "F.Fab")
		)
		(fp_line
			(start 0.120396 0.3048)
			(end 0.120396 0.2794)
			(stroke
				(width 0.1)
				(type default)
			)
			(layer "F.Fab")
		)
		(fp_line
			(start -0.12065 0.3048)
			(end -0.67945 0.3048)
			(stroke
				(width 0.1)
				(type default)
			)
			(layer "F.Fab")
		)
		(fp_line
			(start -0.67945 0.3048)
			(end -0.67945 -0.305054)
			(stroke
				(width 0.1)
				(type default)
			)
			(layer "F.Fab")
		)
		(pad "1" smd circle
			(at -0.40005 0 90)
			(size 0 0)
			(layers "F.Cu" "F.Mask" "F.Paste")
			(net "P12V_AUX")
		)
		(pad "2" smd circle
			(at 0.40005 0 90)
			(size 0 0)
			(layers "F.Cu" "F.Mask" "F.Paste")
			(net "GND")
		)
	)
	(footprint ""
		(layer "F.Cu")
		(at 134.94639 -184.656984 -90)
		(property "Reference" "R1112"
			(at 0 0 270)
			(layer "F.SilkS")
			(hide yes)
			(effects
				(font
					(size 1.27 1.27)
				)
			)
		)
		(property "Value" ""
			(at 0 0 270)
			(layer "F.Fab")
			(effects
				(font
					(size 1.27 1.27)
				)
			)
		)
		(duplicate_pad_numbers_are_jumpers no)
		(fp_line
			(start -0.7874 -0.4064)
			(end 0.7874 -0.4064)
			(stroke
				(width 0.1524)
				(type default)
			)
			(layer "F.SilkS")
		)
		(fp_line
			(start -0.67945 0.3048)
			(end -0.67945 -0.305054)
			(stroke
				(width 0.1)
				(type default)
			)
			(layer "F.Fab")
		)
		(fp_line
			(start -0.12065 0.3048)
			(end -0.67945 0.3048)
			(stroke
				(width 0.1)
				(type default)
			)
			(layer "F.Fab")
		)
		(fp_line
			(start 0.120396 0.3048)
			(end 0.120396 0.2794)
			(stroke
				(width 0.1)
				(type default)
			)
			(layer "F.Fab")
		)
		(fp_line
			(start 0.67945 0.3048)
			(end 0.120396 0.3048)
			(stroke
				(width 0.1)
				(type default)
			)
			(layer "F.Fab")
		)
		(fp_line
			(start -0.12065 0.2794)
			(end -0.12065 0.3048)
			(stroke
				(width 0.1)
				(type default)
			)
			(layer "F.Fab")
		)
		(fp_line
			(start 0.120396 0.2794)
			(end -0.12065 0.2794)
			(stroke
				(width 0.1)
				(type default)
			)
			(layer "F.Fab")
		)
		(fp_line
			(start -0.12065 -0.2794)
			(end 0.12065 -0.2794)
			(stroke
				(width 0.1)
				(type default)
			)
			(layer "F.Fab")
		)
		(fp_line
			(start 0.12065 -0.2794)
			(end 0.12065 -0.3048)
			(stroke
				(width 0.1)
				(type default)
			)
			(layer "F.Fab")
		)
		(fp_line
			(start 0.12065 -0.3048)
			(end 0.67945 -0.3048)
			(stroke
				(width 0.1)
				(type default)
			)
			(layer "F.Fab")
		)
		(fp_line
			(start 0.67945 -0.3048)
			(end 0.67945 0.3048)
			(stroke
				(width 0.1)
				(type default)
			)
			(layer "F.Fab")
		)
		(fp_line
			(start -0.67945 -0.305054)
			(end -0.12065 -0.305054)
			(stroke
				(width 0.1)
				(type default)
			)
			(layer "F.Fab")
		)
		(fp_line
			(start -0.12065 -0.305054)
			(end -0.12065 -0.2794)
			(stroke
				(width 0.1)
				(type default)
			)
			(layer "F.Fab")
		)
		(pad "1" smd circle
			(at -0.40005 0 270)
			(size 0 0)
			(layers "F.Cu" "F.Mask" "F.Paste")
			(net "CLK_100M_DB2000QL_GPU_REF0_R_DP")
		)
		(pad "2" smd circle
			(at 0.40005 0 270)
			(size 0 0)
			(layers "F.Cu" "F.Mask" "F.Paste")
			(net "CLK_100M_DB2000QL_GPU_REF0_DP")
		)
	)
	(footprint ""
		(layer "F.Cu")
		(at 98.048318 -394.1318)
		(property "Reference" "R5458"
			(at 0 0 0)
			(layer "F.SilkS")
			(hide yes)
			(effects
				(font
					(size 1.27 1.27)
				)
			)
		)
		(property "Value" ""
			(at 0 0 0)
			(layer "F.Fab")
			(effects
				(font
					(size 1.27 1.27)
				)
			)
		)
		(duplicate_pad_numbers_are_jumpers no)
		(fp_line
			(start -0.7874 -0.4064)
			(end 0.7874 -0.4064)
			(stroke
				(width 0.1524)
				(type default)
			)
			(layer "F.SilkS")
		)
		(fp_line
			(start -0.7874 0.4064)
			(end -0.7874 -0.4064)
			(stroke
				(width 0.1524)
				(type default)
			)
			(layer "F.SilkS")
		)
		(fp_line
			(start 0.7874 -0.4064)
			(end 0.7874 0.4064)
			(stroke
				(width 0.1524)
				(type default)
			)
			(layer "F.SilkS")
		)
		(fp_line
			(start 0.7874 0.4064)
			(end -0.7874 0.4064)
			(stroke
				(width 0.1524)
				(type default)
			)
			(layer "F.SilkS")
		)
		(fp_line
			(start -0.67945 -0.305054)
			(end -0.12065 -0.305054)
			(stroke
				(width 0.1)
				(type default)
			)
			(layer "F.Fab")
		)
		(fp_line
			(start -0.67945 0.3048)
			(end -0.67945 -0.305054)
			(stroke
				(width 0.1)
				(type default)
			)
			(layer "F.Fab")
		)
		(fp_line
			(start -0.12065 -0.305054)
			(end -0.12065 -0.2794)
			(stroke
				(width 0.1)
				(type default)
			)
			(layer "F.Fab")
		)
		(fp_line
			(start -0.12065 -0.2794)
			(end 0.12065 -0.2794)
			(stroke
				(width 0.1)
				(type default)
			)
			(layer "F.Fab")
		)
		(fp_line
			(start -0.12065 0.2794)
			(end -0.12065 0.3048)
			(stroke
				(width 0.1)
				(type default)
			)
			(layer "F.Fab")
		)
		(fp_line
			(start -0.12065 0.3048)
			(end -0.67945 0.3048)
			(stroke
				(width 0.1)
				(type default)
			)
			(layer "F.Fab")
		)
		(fp_line
			(start 0.120396 0.2794)
			(end -0.12065 0.2794)
			(stroke
				(width 0.1)
				(type default)
			)
			(layer "F.Fab")
		)
		(fp_line
			(start 0.120396 0.3048)
			(end 0.120396 0.2794)
			(stroke
				(width 0.1)
				(type default)
			)
			(layer "F.Fab")
		)
		(fp_line
			(start 0.12065 -0.3048)
			(end 0.67945 -0.3048)
			(stroke
				(width 0.1)
				(type default)
			)
			(layer "F.Fab")
		)
		(fp_line
			(start 0.12065 -0.2794)
			(end 0.12065 -0.3048)
			(stroke
				(width 0.1)
				(type default)
			)
			(layer "F.Fab")
		)
		(fp_line
			(start 0.67945 -0.3048)
			(end 0.67945 0.3048)
			(stroke
				(width 0.1)
				(type default)
			)
			(layer "F.Fab")
		)
		(fp_line
			(start 0.67945 0.3048)
			(end 0.120396 0.3048)
			(stroke
				(width 0.1)
				(type default)
			)
			(layer "F.Fab")
		)
		(pad "1" smd circle
			(at -0.40005 0)
			(size 0 0)
			(layers "F.Cu" "F.Mask" "F.Paste")
			(net "GND")
		)
		(pad "2" smd circle
			(at 0.40005 0)
			(size 0 0)
			(layers "F.Cu" "F.Mask" "F.Paste")
			(net "BIC_USB_HUB_PSELF")
		)
	)
	(footprint ""
		(layer "F.Cu")
		(at 149.586442 -252.356874 -90)
		(property "Reference" "R1286"
			(at 0 0 270)
			(layer "F.SilkS")
			(hide yes)
			(effects
				(font
					(size 1.27 1.27)
				)
			)
		)
		(property "Value" ""
			(at 0 0 270)
			(layer "F.Fab")
			(effects
				(font
					(size 1.27 1.27)
				)
			)
		)
		(duplicate_pad_numbers_are_jumpers no)
		(fp_line
			(start -0.7874 0.4064)
			(end -0.7874 -0.4064)
			(stroke
				(width 0.1524)
				(type default)
			)
			(layer "F.SilkS")
		)
		(fp_line
			(start 0.7874 0.4064)
			(end -0.7874 0.4064)
			(stroke
				(width 0.1524)
				(type default)
			)
			(layer "F.SilkS")
		)
		(fp_line
			(start -0.7874 -0.4064)
			(end 0.7874 -0.4064)
			(stroke
				(width 0.1524)
				(type default)
			)
			(layer "F.SilkS")
		)
		(fp_line
			(start 0.7874 -0.4064)
			(end 0.7874 0.4064)
			(stroke
				(width 0.1524)
				(type default)
			)
			(layer "F.SilkS")
		)
		(fp_line
			(start -0.67945 0.3048)
			(end -0.67945 -0.305054)
			(stroke
				(width 0.1)
				(type default)
			)
			(layer "F.Fab")
		)
		(fp_line
			(start -0.12065 0.3048)
			(end -0.67945 0.3048)
			(stroke
				(width 0.1)
				(type default)
			)
			(layer "F.Fab")
		)
		(fp_line
			(start 0.120396 0.3048)
			(end 0.120396 0.2794)
			(stroke
				(width 0.1)
				(type default)
			)
			(layer "F.Fab")
		)
		(fp_line
			(start 0.67945 0.3048)
			(end 0.120396 0.3048)
			(stroke
				(width 0.1)
				(type default)
			)
			(layer "F.Fab")
		)
		(fp_line
			(start -0.12065 0.2794)
			(end -0.12065 0.3048)
			(stroke
				(width 0.1)
				(type default)
			)
			(layer "F.Fab")
		)
		(fp_line
			(start 0.120396 0.2794)
			(end -0.12065 0.2794)
			(stroke
				(width 0.1)
				(type default)
			)
			(layer "F.Fab")
		)
		(fp_line
			(start -0.12065 -0.2794)
			(end 0.12065 -0.2794)
			(stroke
				(width 0.1)
				(type default)
			)
			(layer "F.Fab")
		)
		(fp_line
			(start 0.12065 -0.2794)
			(end 0.12065 -0.3048)
			(stroke
				(width 0.1)
				(type default)
			)
			(layer "F.Fab")
		)
		(fp_line
			(start 0.12065 -0.3048)
			(end 0.67945 -0.3048)
			(stroke
				(width 0.1)
				(type default)
			)
			(layer "F.Fab")
		)
		(fp_line
			(start 0.67945 -0.3048)
			(end 0.67945 0.3048)
			(stroke
				(width 0.1)
				(type default)
			)
			(layer "F.Fab")
		)
		(fp_line
			(start -0.67945 -0.305054)
			(end -0.12065 -0.305054)
			(stroke
				(width 0.1)
				(type default)
			)
			(layer "F.Fab")
		)
		(fp_line
			(start -0.12065 -0.305054)
			(end -0.12065 -0.2794)
			(stroke
				(width 0.1)
				(type default)
			)
			(layer "F.Fab")
		)
		(pad "1" smd circle
			(at -0.40005 0 270)
			(size 0 0)
			(layers "F.Cu" "F.Mask" "F.Paste")
			(net "GND")
		)
		(pad "2" smd circle
			(at 0.40005 0 270)
			(size 0 0)
			(layers "F.Cu" "F.Mask" "F.Paste")
			(net "PEX1_DBG_MODE2")
		)
	)
	(footprint ""
		(layer "F.Cu")
		(at 114.132106 -284.8991 180)
		(property "Reference" "PU8"
			(at -23.263606 -1.566672 90)
			(unlocked yes)
			(layer "F.SilkS")
			(effects
				(font
					(size 0.7874 0.5842)
					(thickness 0.1524)
				)
			)
		)
		(property "Value" ""
			(at 0 0 180)
			(layer "F.Fab")
			(effects
				(font
					(size 1.27 1.27)
				)
			)
		)
		(duplicate_pad_numbers_are_jumpers no)
		(fp_line
			(start 2.500122 2.999994)
			(end 2.2987 2.999994)
			(stroke
				(width 0.1524)
				(type default)
			)
			(layer "F.SilkS")
		)
		(fp_line
			(start 2.500122 2.339594)
			(end 2.500122 2.999994)
			(stroke
				(width 0.1524)
				(type default)
			)
			(layer "F.SilkS")
		)
		(fp_line
			(start 2.500122 -2.999994)
			(end 2.500122 -2.44348)
			(stroke
				(width 0.1524)
				(type default)
			)
			(layer "F.SilkS")
		)
		(fp_line
			(start 2.31394 -2.999994)
			(end 2.500122 -2.999994)
			(stroke
				(width 0.1524)
				(type default)
			)
			(layer "F.SilkS")
		)
		(fp_line
			(start -2.2987 2.999994)
			(end -2.500122 2.999994)
			(stroke
				(width 0.1524)
				(type default)
			)
			(layer "F.SilkS")
		)
		(fp_line
			(start -2.500122 2.999994)
			(end -2.500122 2.339594)
			(stroke
				(width 0.1524)
				(type default)
			)
			(layer "F.SilkS")
		)
		(fp_line
			(start -2.500122 0.6604)
			(end -2.500122 0.229108)
			(stroke
				(width 0.1524)
				(type default)
			)
			(layer "F.SilkS")
		)
		(fp_line
			(start -2.500122 -2.529078)
			(end -2.500122 -2.999994)
			(stroke
				(width 0.1524)
				(type default)
			)
			(layer "F.SilkS")
		)
		(fp_line
			(start -2.500122 -2.999994)
			(end -2.24409 -2.999994)
			(stroke
				(width 0.1524)
				(type default)
			)
			(layer "F.SilkS")
		)
		(fp_poly
			(pts
				(xy -2.239518 -3.936238) (xy -3.255518 -3.936238) (xy -2.747518 -2.920238)
			)
			(stroke
				(width 0)
				(type default)
			)
			(fill yes)
			(layer "F.SilkS")
		)
		(fp_line
			(start 2.500122 2.999994)
			(end -2.500122 2.999994)
			(stroke
				(width 0.1)
				(type default)
			)
			(layer "F.Fab")
		)
		(fp_line
			(start 2.500122 -2.999994)
			(end 2.500122 2.999994)
			(stroke
				(width 0.1)
				(type default)
			)
			(layer "F.Fab")
		)
		(fp_line
			(start -2.500122 2.999994)
			(end -2.500122 -2.999994)
			(stroke
				(width 0.1)
				(type default)
			)
			(layer "F.Fab")
		)
		(fp_line
			(start -2.500122 -2.999994)
			(end 2.500122 -2.999994)
			(stroke
				(width 0.1)
				(type default)
			)
			(layer "F.Fab")
		)
		(fp_poly
			(pts
				(xy -4.218432 -2.783078) (xy -4.218432 -1.767078) (xy -3.202432 -2.275078)
			)
			(stroke
				(width 0)
				(type default)
			)
			(fill yes)
			(layer "F.Fab")
		)
		(pad "1" smd rect
			(at -2.400046 -2.275078 270)
			(size 0.2286 0.6096)
			(layers "F.Cu" "F.Mask" "F.Paste")
			(net "SW_P0V8_PEX0_VOS2")
		)
		(pad "2" smd rect
			(at -2.400046 -1.82499 270)
			(size 0.2286 0.6096)
			(layers "F.Cu" "F.Mask" "F.Paste")
			(net "GND")
		)
		(pad "3" smd rect
			(at -2.400046 -1.374902 270)
			(size 0.2286 0.6096)
			(layers "F.Cu" "F.Mask" "F.Paste")
			(net "P0V8_PEX0_VCC2")
		)
		(pad "4" smd rect
			(at -2.400046 -0.925068 270)
			(size 0.2286 0.6096)
			(layers "F.Cu" "F.Mask" "F.Paste")
			(net "P0V8_PEX0_PVCC")
		)
		(pad "5" smd rect
			(at -2.400046 -0.47498 270)
			(size 0.2286 0.6096)
			(layers "F.Cu" "F.Mask" "F.Paste")
			(net "GND")
		)
		(pad "6" smd rect
			(at -2.400046 -0.024892 270)
			(size 0.2286 0.6096)
			(layers "F.Cu" "F.Mask" "F.Paste")
			(net "NC_P0V8_PEX0_PH2_NC1")
		)
		(pad "7_9-20_24" smd circle
			(at 0 1.150112 270)
			(size 0 0)
			(layers "F.Cu" "F.Mask" "F.Paste")
			(net "GND")
		)
		(pad "10_19" smd rect
			(at 0 2.899918 270)
			(size 0.6096 4.318)
			(layers "F.Cu" "F.Mask" "F.Paste")
			(net "SW_P0V8_PEX0_PH2")
		)
		(pad "25_29" smd rect
			(at 1.549908 -1.279906 90)
			(size 2.0574 2.3114)
			(layers "F.Cu" "F.Mask" "F.Paste")
			(net "SW_P12V_P0V8_PEX0_FLT")
		)
		(pad "30" smd rect
			(at 2.05994 -2.899918 180)
			(size 0.2286 0.6096)
			(layers "F.Cu" "F.Mask" "F.Paste")
			(net "SW_P12V_P0V8_PEX0_FLT")
		)
		(pad "31" smd rect
			(at 1.610106 -2.899918 180)
			(size 0.2286 0.6096)
			(layers "F.Cu" "F.Mask" "F.Paste")
			(net "NC_P0V8_PEX0_PH2_NC3")
		)
		(pad "32" smd rect
			(at 1.160018 -2.899918 180)
			(size 0.2286 0.6096)
			(layers "F.Cu" "F.Mask" "F.Paste")
			(net "SW_P0V8_PEX0_PHASE2")
		)
		(pad "33" smd rect
			(at 0.70993 -2.899918 180)
			(size 0.2286 0.6096)
			(layers "F.Cu" "F.Mask" "F.Paste")
			(net "SW_P0V8_PEX0_BOOT2")
		)
		(pad "34" smd rect
			(at 0.260096 -2.899918 180)
			(size 0.2286 0.6096)
			(layers "F.Cu" "F.Mask" "F.Paste")
			(net "P0V8_PEX0_PWM2")
		)
		(pad "35" smd rect
			(at -0.189992 -2.899918 180)
			(size 0.2286 0.6096)
			(layers "F.Cu" "F.Mask" "F.Paste")
			(net "P0V8_PEX0_EN2")
		)
		(pad "36" smd rect
			(at -0.64008 -2.899918 180)
			(size 0.2286 0.6096)
			(layers "F.Cu" "F.Mask" "F.Paste")
			(net "P0V8_PEX0_TSEN")
		)
		(pad "37" smd rect
			(at -1.089914 -2.899918 180)
			(size 0.2286 0.6096)
			(layers "F.Cu" "F.Mask" "F.Paste")
			(net "P0V8_PEX0_LSET2")
		)
		(pad "38" smd rect
			(at -1.540002 -2.899918 180)
			(size 0.2286 0.6096)
			(layers "F.Cu" "F.Mask" "F.Paste")
			(net "P0V8_PEX0_ISEN2")
		)
		(pad "39" smd rect
			(at -1.99009 -2.899918 180)
			(size 0.2286 0.6096)
			(layers "F.Cu" "F.Mask" "F.Paste")
			(net "P0V8_PEX0_VREF")
		)
		(pad "40" smd rect
			(at -0.87503 -1.27508 180)
			(size 1.7526 1.9558)
			(layers "F.Cu" "F.Mask" "F.Paste")
			(net "GND")
		)
		(pad "41" smd rect
			(at -1.525016 0.249936 90)
			(size 0.3048 0.4572)
			(layers "F.Cu" "F.Mask" "F.Paste")
			(net "NC_P0V8_PEX0_PH2_NC2")
		)
		(zone
			(layer "F.Cu")
			(hatch none 0.5)
			(connect_pads
				(clearance 0)
			)
			(min_thickness 0.25)
			(keepout
				(tracks not_allowed)
				(vias allowed)
				(pads allowed)
				(copperpour not_allowed)
				(footprints allowed)
			)
			(placement
				(enabled no)
				(sheetname "")
			)
			(fill
				(thermal_gap 0.5)
				(thermal_bridge_width 0.5)
				(island_removal_mode 0)
			)
			(polygon
				(pts
					(xy 116.632228 -287.899094) (xy 116.632228 -287.149794) (xy 111.631984 -287.149794) (xy 111.631984 -287.899094)
					(xy 111.922306 -287.899094) (xy 111.922306 -287.443418) (xy 116.341906 -287.443418) (xy 116.341906 -287.899094)
				)
			)
		)
	)
	(footprint ""
		(layer "F.Cu")
		(at 26.930096 -297.205908 -90)
		(property "Reference" "C3015"
			(at 0 0 270)
			(layer "F.SilkS")
			(hide yes)
			(effects
				(font
					(size 1.27 1.27)
				)
			)
		)
		(property "Value" ""
			(at 0 0 270)
			(layer "F.Fab")
			(effects
				(font
					(size 1.27 1.27)
				)
			)
		)
		(duplicate_pad_numbers_are_jumpers no)
		(fp_line
			(start -1.2954 0.5842)
			(end -1.2954 -0.5842)
			(stroke
				(width 0.1524)
				(type default)
			)
			(layer "F.SilkS")
		)
		(fp_line
			(start 1.2954 0.5842)
			(end -1.2954 0.5842)
			(stroke
				(width 0.1524)
				(type default)
			)
			(layer "F.SilkS")
		)
		(fp_line
			(start -1.2954 -0.5842)
			(end 1.2954 -0.5842)
			(stroke
				(width 0.1524)
				(type default)
			)
			(layer "F.SilkS")
		)
		(fp_line
			(start 1.2954 -0.5842)
			(end 1.2954 0.5842)
			(stroke
				(width 0.1524)
				(type default)
			)
			(layer "F.SilkS")
		)
		(fp_line
			(start -0.8636 0.4572)
			(end -0.8636 0.4064)
			(stroke
				(width 0.1)
				(type default)
			)
			(layer "F.Fab")
		)
		(fp_line
			(start 0.8636 0.4572)
			(end -0.8636 0.4572)
			(stroke
				(width 0.1)
				(type default)
			)
			(layer "F.Fab")
		)
		(fp_line
			(start -1.1938 0.4064)
			(end -1.1938 -0.4064)
			(stroke
				(width 0.1)
				(type default)
			)
			(layer "F.Fab")
		)
		(fp_line
			(start -0.8636 0.4064)
			(end -1.1938 0.4064)
			(stroke
				(width 0.1)
				(type default)
			)
			(layer "F.Fab")
		)
		(fp_line
			(start 0.8636 0.4064)
			(end 0.8636 0.4572)
			(stroke
				(width 0.1)
				(type default)
			)
			(layer "F.Fab")
		)
		(fp_line
			(start 1.1938 0.4064)
			(end 0.8636 0.4064)
			(stroke
				(width 0.1)
				(type default)
			)
			(layer "F.Fab")
		)
		(fp_line
			(start -1.1938 -0.4064)
			(end -0.8636 -0.4064)
			(stroke
				(width 0.1)
				(type default)
			)
			(layer "F.Fab")
		)
		(fp_line
			(start -0.8636 -0.4064)
			(end -0.8636 -0.4572)
			(stroke
				(width 0.1)
				(type default)
			)
			(layer "F.Fab")
		)
		(fp_line
			(start 0.8636 -0.4064)
			(end 1.1938 -0.4064)
			(stroke
				(width 0.1)
				(type default)
			)
			(layer "F.Fab")
		)
		(fp_line
			(start 1.1938 -0.4064)
			(end 1.1938 0.4064)
			(stroke
				(width 0.1)
				(type default)
			)
			(layer "F.Fab")
		)
		(fp_line
			(start -0.8636 -0.4572)
			(end 0.8636 -0.4572)
			(stroke
				(width 0.1)
				(type default)
			)
			(layer "F.Fab")
		)
		(fp_line
			(start 0.8636 -0.4572)
			(end 0.8636 -0.4064)
			(stroke
				(width 0.1)
				(type default)
			)
			(layer "F.Fab")
		)
		(pad "1" smd rect
			(at -0.7366 0 180)
			(size 0.7112 0.8128)
			(layers "F.Cu" "F.Mask" "F.Paste")
			(net "P1V8_PLL0_PEX0")
		)
		(pad "2" smd rect
			(at 0.7366 0 180)
			(size 0.7112 0.8128)
			(layers "F.Cu" "F.Mask" "F.Paste")
			(net "GND")
		)
	)
	(footprint ""
		(layer "F.Cu")
		(at 134.043166 -114.152426 -90)
		(property "Reference" "PC791"
			(at 0 0 270)
			(layer "F.SilkS")
			(hide yes)
			(effects
				(font
					(size 1.27 1.27)
				)
			)
		)
		(property "Value" ""
			(at 0 0 270)
			(layer "F.Fab")
			(effects
				(font
					(size 1.27 1.27)
				)
			)
		)
		(duplicate_pad_numbers_are_jumpers no)
		(fp_line
			(start -1.524 0.762)
			(end -1.524 -0.762)
			(stroke
				(width 0.1524)
				(type default)
			)
			(layer "F.SilkS")
		)
		(fp_line
			(start 1.524 0.762)
			(end -1.524 0.762)
			(stroke
				(width 0.1524)
				(type default)
			)
			(layer "F.SilkS")
		)
		(fp_line
			(start -1.524 -0.762)
			(end 1.524 -0.762)
			(stroke
				(width 0.1524)
				(type default)
			)
			(layer "F.SilkS")
		)
		(fp_line
			(start 1.524 -0.762)
			(end 1.524 0.762)
			(stroke
				(width 0.1524)
				(type default)
			)
			(layer "F.SilkS")
		)
		(fp_line
			(start -1.1049 0.724916)
			(end 1.1049 0.724916)
			(stroke
				(width 0.1)
				(type default)
			)
			(layer "F.Fab")
		)
		(fp_line
			(start 1.1049 0.724916)
			(end 1.1049 -0.724916)
			(stroke
				(width 0.1)
				(type default)
			)
			(layer "F.Fab")
		)
		(fp_line
			(start -1.1049 -0.724916)
			(end -1.1049 0.724916)
			(stroke
				(width 0.1)
				(type default)
			)
			(layer "F.Fab")
		)
		(fp_line
			(start 1.1049 -0.724916)
			(end -1.1049 -0.724916)
			(stroke
				(width 0.1)
				(type default)
			)
			(layer "F.Fab")
		)
		(pad "1" smd rect
			(at -0.889 0 90)
			(size 1.016 1.27)
			(layers "F.Cu" "F.Mask" "F.Paste")
			(net "P3V3_NIC2")
		)
		(pad "2" smd rect
			(at 0.889 0 90)
			(size 1.016 1.27)
			(layers "F.Cu" "F.Mask" "F.Paste")
			(net "GND")
		)
	)
	(footprint ""
		(layer "F.Cu")
		(at 18.019014 -403.41931 90)
		(property "Reference" "R5587"
			(at 0 0 90)
			(layer "F.SilkS")
			(hide yes)
			(effects
				(font
					(size 1.27 1.27)
				)
			)
		)
		(property "Value" ""
			(at 0 0 90)
			(layer "F.Fab")
			(effects
				(font
					(size 1.27 1.27)
				)
			)
		)
		(duplicate_pad_numbers_are_jumpers no)
		(fp_line
			(start 0.7874 -0.4064)
			(end 0.7874 0.4064)
			(stroke
				(width 0.1524)
				(type default)
			)
			(layer "F.SilkS")
		)
		(fp_line
			(start -0.7874 -0.4064)
			(end 0.7874 -0.4064)
			(stroke
				(width 0.1524)
				(type default)
			)
			(layer "F.SilkS")
		)
		(fp_line
			(start 0.7874 0.4064)
			(end -0.7874 0.4064)
			(stroke
				(width 0.1524)
				(type default)
			)
			(layer "F.SilkS")
		)
		(fp_line
			(start -0.7874 0.4064)
			(end -0.7874 -0.4064)
			(stroke
				(width 0.1524)
				(type default)
			)
			(layer "F.SilkS")
		)
		(fp_line
			(start -0.12065 -0.305054)
			(end -0.12065 -0.2794)
			(stroke
				(width 0.1)
				(type default)
			)
			(layer "F.Fab")
		)
		(fp_line
			(start -0.67945 -0.305054)
			(end -0.12065 -0.305054)
			(stroke
				(width 0.1)
				(type default)
			)
			(layer "F.Fab")
		)
		(fp_line
			(start 0.67945 -0.3048)
			(end 0.67945 0.3048)
			(stroke
				(width 0.1)
				(type default)
			)
			(layer "F.Fab")
		)
		(fp_line
			(start 0.12065 -0.3048)
			(end 0.67945 -0.3048)
			(stroke
				(width 0.1)
				(type default)
			)
			(layer "F.Fab")
		)
		(fp_line
			(start 0.12065 -0.2794)
			(end 0.12065 -0.3048)
			(stroke
				(width 0.1)
				(type default)
			)
			(layer "F.Fab")
		)
		(fp_line
			(start -0.12065 -0.2794)
			(end 0.12065 -0.2794)
			(stroke
				(width 0.1)
				(type default)
			)
			(layer "F.Fab")
		)
		(fp_line
			(start 0.120396 0.2794)
			(end -0.12065 0.2794)
			(stroke
				(width 0.1)
				(type default)
			)
			(layer "F.Fab")
		)
		(fp_line
			(start -0.12065 0.2794)
			(end -0.12065 0.3048)
			(stroke
				(width 0.1)
				(type default)
			)
			(layer "F.Fab")
		)
		(fp_line
			(start 0.67945 0.3048)
			(end 0.120396 0.3048)
			(stroke
				(width 0.1)
				(type default)
			)
			(layer "F.Fab")
		)
		(fp_line
			(start 0.120396 0.3048)
			(end 0.120396 0.2794)
			(stroke
				(width 0.1)
				(type default)
			)
			(layer "F.Fab")
		)
		(fp_line
			(start -0.12065 0.3048)
			(end -0.67945 0.3048)
			(stroke
				(width 0.1)
				(type default)
			)
			(layer "F.Fab")
		)
		(fp_line
			(start -0.67945 0.3048)
			(end -0.67945 -0.305054)
			(stroke
				(width 0.1)
				(type default)
			)
			(layer "F.Fab")
		)
		(pad "1" smd circle
			(at -0.40005 0 90)
			(size 0 0)
			(layers "F.Cu" "F.Mask" "F.Paste")
			(net "SMB_BIC_I2C6_MUX_THERMAL_R_SDA")
		)
		(pad "2" smd circle
			(at 0.40005 0 90)
			(size 0 0)
			(layers "F.Cu" "F.Mask" "F.Paste")
			(net "SMB_LM75_0_SDA")
		)
	)
	(footprint ""
		(layer "F.Cu")
		(at 186.026552 -25.432004 -90)
		(property "Reference" "C971"
			(at 0 0 270)
			(layer "F.SilkS")
			(hide yes)
			(effects
				(font
					(size 1.27 1.27)
				)
			)
		)
		(property "Value" ""
			(at 0 0 270)
			(layer "F.Fab")
			(effects
				(font
					(size 1.27 1.27)
				)
			)
		)
		(duplicate_pad_numbers_are_jumpers no)
		(fp_line
			(start -0.7874 0.4064)
			(end -0.7874 -0.4064)
			(stroke
				(width 0.1524)
				(type default)
			)
			(layer "F.SilkS")
		)
		(fp_line
			(start 0.7874 0.4064)
			(end -0.7874 0.4064)
			(stroke
				(width 0.1524)
				(type default)
			)
			(layer "F.SilkS")
		)
		(fp_line
			(start -0.7874 -0.4064)
			(end 0.7874 -0.4064)
			(stroke
				(width 0.1524)
				(type default)
			)
			(layer "F.SilkS")
		)
		(fp_line
			(start 0.7874 -0.4064)
			(end 0.7874 0.4064)
			(stroke
				(width 0.1524)
				(type default)
			)
			(layer "F.SilkS")
		)
		(fp_line
			(start -0.67945 0.3048)
			(end -0.67945 -0.305054)
			(stroke
				(width 0.1)
				(type default)
			)
			(layer "F.Fab")
		)
		(fp_line
			(start -0.12065 0.3048)
			(end -0.67945 0.3048)
			(stroke
				(width 0.1)
				(type default)
			)
			(layer "F.Fab")
		)
		(fp_line
			(start 0.120396 0.3048)
			(end 0.120396 0.2794)
			(stroke
				(width 0.1)
				(type default)
			)
			(layer "F.Fab")
		)
		(fp_line
			(start 0.67945 0.3048)
			(end 0.120396 0.3048)
			(stroke
				(width 0.1)
				(type default)
			)
			(layer "F.Fab")
		)
		(fp_line
			(start -0.12065 0.2794)
			(end -0.12065 0.3048)
			(stroke
				(width 0.1)
				(type default)
			)
			(layer "F.Fab")
		)
		(fp_line
			(start 0.120396 0.2794)
			(end -0.12065 0.2794)
			(stroke
				(width 0.1)
				(type default)
			)
			(layer "F.Fab")
		)
		(fp_line
			(start -0.12065 -0.2794)
			(end 0.12065 -0.2794)
			(stroke
				(width 0.1)
				(type default)
			)
			(layer "F.Fab")
		)
		(fp_line
			(start 0.12065 -0.2794)
			(end 0.12065 -0.3048)
			(stroke
				(width 0.1)
				(type default)
			)
			(layer "F.Fab")
		)
		(fp_line
			(start 0.12065 -0.3048)
			(end 0.67945 -0.3048)
			(stroke
				(width 0.1)
				(type default)
			)
			(layer "F.Fab")
		)
		(fp_line
			(start 0.67945 -0.3048)
			(end 0.67945 0.3048)
			(stroke
				(width 0.1)
				(type default)
			)
			(layer "F.Fab")
		)
		(fp_line
			(start -0.67945 -0.305054)
			(end -0.12065 -0.305054)
			(stroke
				(width 0.1)
				(type default)
			)
			(layer "F.Fab")
		)
		(fp_line
			(start -0.12065 -0.305054)
			(end -0.12065 -0.2794)
			(stroke
				(width 0.1)
				(type default)
			)
			(layer "F.Fab")
		)
		(pad "1" smd circle
			(at -0.40005 0 270)
			(size 0 0)
			(layers "F.Cu" "F.Mask" "F.Paste")
			(net "GND")
		)
		(pad "2" smd circle
			(at 0.40005 0 270)
			(size 0 0)
			(layers "F.Cu" "F.Mask" "F.Paste")
			(net "P3V3_SSD6")
		)
	)
	(footprint ""
		(layer "F.Cu")
		(at 122.077988 -343.952322 90)
		(property "Reference" "C365"
			(at 0 0 90)
			(layer "F.SilkS")
			(hide yes)
			(effects
				(font
					(size 1.27 1.27)
				)
			)
		)
		(property "Value" ""
			(at 0 0 90)
			(layer "F.Fab")
			(effects
				(font
					(size 1.27 1.27)
				)
			)
		)
		(duplicate_pad_numbers_are_jumpers no)
		(fp_line
			(start 0.299974 -0.150114)
			(end 0.299974 0.150114)
			(stroke
				(width 0.1)
				(type default)
			)
			(layer "F.Fab")
		)
		(fp_line
			(start -0.299974 -0.150114)
			(end 0.299974 -0.150114)
			(stroke
				(width 0.1)
				(type default)
			)
			(layer "F.Fab")
		)
		(fp_line
			(start 0.299974 0.150114)
			(end -0.299974 0.150114)
			(stroke
				(width 0.1)
				(type default)
			)
			(layer "F.Fab")
		)
		(fp_line
			(start -0.299974 0.150114)
			(end -0.299974 -0.150114)
			(stroke
				(width 0.1)
				(type default)
			)
			(layer "F.Fab")
		)
		(pad "1" smd rect
			(at -0.2667 0 90)
			(size 0.3048 0.381)
			(layers "F.Cu" "F.Mask" "F.Paste")
			(net "P5E_PEX1_STN6_TX_DN<99>")
		)
		(pad "2" smd rect
			(at 0.2667 0 90)
			(size 0.3048 0.381)
			(layers "F.Cu" "F.Mask" "F.Paste")
			(net "P5E_PEX1_STN6_TX_C_DN<99>")
		)
	)
	(footprint ""
		(layer "F.Cu")
		(at 224.514664 -204.44206 90)
		(property "Reference" "R5289"
			(at 0 0 90)
			(layer "F.SilkS")
			(hide yes)
			(effects
				(font
					(size 1.27 1.27)
				)
			)
		)
		(property "Value" ""
			(at 0 0 90)
			(layer "F.Fab")
			(effects
				(font
					(size 1.27 1.27)
				)
			)
		)
		(duplicate_pad_numbers_are_jumpers no)
		(fp_line
			(start 0.7874 -0.4064)
			(end 0.7874 0.4064)
			(stroke
				(width 0.1524)
				(type default)
			)
			(layer "F.SilkS")
		)
		(fp_line
			(start -0.7874 -0.4064)
			(end 0.7874 -0.4064)
			(stroke
				(width 0.1524)
				(type default)
			)
			(layer "F.SilkS")
		)
		(fp_line
			(start 0.7874 0.4064)
			(end -0.7874 0.4064)
			(stroke
				(width 0.1524)
				(type default)
			)
			(layer "F.SilkS")
		)
		(fp_line
			(start -0.7874 0.4064)
			(end -0.7874 -0.4064)
			(stroke
				(width 0.1524)
				(type default)
			)
			(layer "F.SilkS")
		)
		(fp_line
			(start -0.12065 -0.305054)
			(end -0.12065 -0.2794)
			(stroke
				(width 0.1)
				(type default)
			)
			(layer "F.Fab")
		)
		(fp_line
			(start -0.67945 -0.305054)
			(end -0.12065 -0.305054)
			(stroke
				(width 0.1)
				(type default)
			)
			(layer "F.Fab")
		)
		(fp_line
			(start 0.67945 -0.3048)
			(end 0.67945 0.3048)
			(stroke
				(width 0.1)
				(type default)
			)
			(layer "F.Fab")
		)
		(fp_line
			(start 0.12065 -0.3048)
			(end 0.67945 -0.3048)
			(stroke
				(width 0.1)
				(type default)
			)
			(layer "F.Fab")
		)
		(fp_line
			(start 0.12065 -0.2794)
			(end 0.12065 -0.3048)
			(stroke
				(width 0.1)
				(type default)
			)
			(layer "F.Fab")
		)
		(fp_line
			(start -0.12065 -0.2794)
			(end 0.12065 -0.2794)
			(stroke
				(width 0.1)
				(type default)
			)
			(layer "F.Fab")
		)
		(fp_line
			(start 0.120396 0.2794)
			(end -0.12065 0.2794)
			(stroke
				(width 0.1)
				(type default)
			)
			(layer "F.Fab")
		)
		(fp_line
			(start -0.12065 0.2794)
			(end -0.12065 0.3048)
			(stroke
				(width 0.1)
				(type default)
			)
			(layer "F.Fab")
		)
		(fp_line
			(start 0.67945 0.3048)
			(end 0.120396 0.3048)
			(stroke
				(width 0.1)
				(type default)
			)
			(layer "F.Fab")
		)
		(fp_line
			(start 0.120396 0.3048)
			(end 0.120396 0.2794)
			(stroke
				(width 0.1)
				(type default)
			)
			(layer "F.Fab")
		)
		(fp_line
			(start -0.12065 0.3048)
			(end -0.67945 0.3048)
			(stroke
				(width 0.1)
				(type default)
			)
			(layer "F.Fab")
		)
		(fp_line
			(start -0.67945 0.3048)
			(end -0.67945 -0.305054)
			(stroke
				(width 0.1)
				(type default)
			)
			(layer "F.Fab")
		)
		(pad "1" smd circle
			(at -0.40005 0 90)
			(size 0 0)
			(layers "F.Cu" "F.Mask" "F.Paste")
			(net "RST_SMB_NIC_MUX_R_N")
		)
		(pad "2" smd circle
			(at 0.40005 0 90)
			(size 0 0)
			(layers "F.Cu" "F.Mask" "F.Paste")
			(net "RST_SMB_NIC_MUX_N")
		)
	)
	(footprint ""
		(layer "F.Cu")
		(at 58.176922 -377.556268 180)
		(property "Reference" "R1824"
			(at 0 0 180)
			(layer "F.SilkS")
			(hide yes)
			(effects
				(font
					(size 1.27 1.27)
				)
			)
		)
		(property "Value" ""
			(at 0 0 180)
			(layer "F.Fab")
			(effects
				(font
					(size 1.27 1.27)
				)
			)
		)
		(duplicate_pad_numbers_are_jumpers no)
		(fp_line
			(start 0.7874 0.4064)
			(end -0.7874 0.4064)
			(stroke
				(width 0.1524)
				(type default)
			)
			(layer "F.SilkS")
		)
		(fp_line
			(start 0.7874 -0.4064)
			(end 0.7874 0.4064)
			(stroke
				(width 0.1524)
				(type default)
			)
			(layer "F.SilkS")
		)
		(fp_line
			(start -0.7874 0.4064)
			(end -0.7874 -0.4064)
			(stroke
				(width 0.1524)
				(type default)
			)
			(layer "F.SilkS")
		)
		(fp_line
			(start -0.7874 -0.4064)
			(end 0.7874 -0.4064)
			(stroke
				(width 0.1524)
				(type default)
			)
			(layer "F.SilkS")
		)
		(fp_line
			(start 0.67945 0.3048)
			(end 0.120396 0.3048)
			(stroke
				(width 0.1)
				(type default)
			)
			(layer "F.Fab")
		)
		(fp_line
			(start 0.67945 -0.3048)
			(end 0.67945 0.3048)
			(stroke
				(width 0.1)
				(type default)
			)
			(layer "F.Fab")
		)
		(fp_line
			(start 0.12065 -0.2794)
			(end 0.12065 -0.3048)
			(stroke
				(width 0.1)
				(type default)
			)
			(layer "F.Fab")
		)
		(fp_line
			(start 0.12065 -0.3048)
			(end 0.67945 -0.3048)
			(stroke
				(width 0.1)
				(type default)
			)
			(layer "F.Fab")
		)
		(fp_line
			(start 0.120396 0.3048)
			(end 0.120396 0.2794)
			(stroke
				(width 0.1)
				(type default)
			)
			(layer "F.Fab")
		)
		(fp_line
			(start 0.120396 0.2794)
			(end -0.12065 0.2794)
			(stroke
				(width 0.1)
				(type default)
			)
			(layer "F.Fab")
		)
		(fp_line
			(start -0.12065 0.3048)
			(end -0.67945 0.3048)
			(stroke
				(width 0.1)
				(type default)
			)
			(layer "F.Fab")
		)
		(fp_line
			(start -0.12065 0.2794)
			(end -0.12065 0.3048)
			(stroke
				(width 0.1)
				(type default)
			)
			(layer "F.Fab")
		)
		(fp_line
			(start -0.12065 -0.2794)
			(end 0.12065 -0.2794)
			(stroke
				(width 0.1)
				(type default)
			)
			(layer "F.Fab")
		)
		(fp_line
			(start -0.12065 -0.305054)
			(end -0.12065 -0.2794)
			(stroke
				(width 0.1)
				(type default)
			)
			(layer "F.Fab")
		)
		(fp_line
			(start -0.67945 0.3048)
			(end -0.67945 -0.305054)
			(stroke
				(width 0.1)
				(type default)
			)
			(layer "F.Fab")
		)
		(fp_line
			(start -0.67945 -0.305054)
			(end -0.12065 -0.305054)
			(stroke
				(width 0.1)
				(type default)
			)
			(layer "F.Fab")
		)
		(pad "1" smd circle
			(at -0.40005 0 180)
			(size 0 0)
			(layers "F.Cu" "F.Mask" "F.Paste")
			(net "GPU_BASE_PWR_GD_R")
		)
		(pad "2" smd circle
			(at 0.40005 0 180)
			(size 0 0)
			(layers "F.Cu" "F.Mask" "F.Paste")
			(net "GPU_BASE_PWR_GD")
		)
	)
	(footprint ""
		(layer "F.Cu")
		(at 117.175026 -307.130704 -90)
		(property "Reference" "C4207"
			(at 0 0 270)
			(layer "F.SilkS")
			(hide yes)
			(effects
				(font
					(size 1.27 1.27)
				)
			)
		)
		(property "Value" ""
			(at 0 0 270)
			(layer "F.Fab")
			(effects
				(font
					(size 1.27 1.27)
				)
			)
		)
		(duplicate_pad_numbers_are_jumpers no)
		(fp_line
			(start -1.2954 0.5842)
			(end -1.2954 -0.5842)
			(stroke
				(width 0.1524)
				(type default)
			)
			(layer "F.SilkS")
		)
		(fp_line
			(start 1.2954 0.5842)
			(end -1.2954 0.5842)
			(stroke
				(width 0.1524)
				(type default)
			)
			(layer "F.SilkS")
		)
		(fp_line
			(start -1.2954 -0.5842)
			(end 1.2954 -0.5842)
			(stroke
				(width 0.1524)
				(type default)
			)
			(layer "F.SilkS")
		)
		(fp_line
			(start 1.2954 -0.5842)
			(end 1.2954 0.5842)
			(stroke
				(width 0.1524)
				(type default)
			)
			(layer "F.SilkS")
		)
		(fp_line
			(start -0.8636 0.4572)
			(end -0.8636 0.4064)
			(stroke
				(width 0.1)
				(type default)
			)
			(layer "F.Fab")
		)
		(fp_line
			(start 0.8636 0.4572)
			(end -0.8636 0.4572)
			(stroke
				(width 0.1)
				(type default)
			)
			(layer "F.Fab")
		)
		(fp_line
			(start -1.1938 0.4064)
			(end -1.1938 -0.4064)
			(stroke
				(width 0.1)
				(type default)
			)
			(layer "F.Fab")
		)
		(fp_line
			(start -0.8636 0.4064)
			(end -1.1938 0.4064)
			(stroke
				(width 0.1)
				(type default)
			)
			(layer "F.Fab")
		)
		(fp_line
			(start 0.8636 0.4064)
			(end 0.8636 0.4572)
			(stroke
				(width 0.1)
				(type default)
			)
			(layer "F.Fab")
		)
		(fp_line
			(start 1.1938 0.4064)
			(end 0.8636 0.4064)
			(stroke
				(width 0.1)
				(type default)
			)
			(layer "F.Fab")
		)
		(fp_line
			(start -1.1938 -0.4064)
			(end -0.8636 -0.4064)
			(stroke
				(width 0.1)
				(type default)
			)
			(layer "F.Fab")
		)
		(fp_line
			(start -0.8636 -0.4064)
			(end -0.8636 -0.4572)
			(stroke
				(width 0.1)
				(type default)
			)
			(layer "F.Fab")
		)
		(fp_line
			(start 0.8636 -0.4064)
			(end 1.1938 -0.4064)
			(stroke
				(width 0.1)
				(type default)
			)
			(layer "F.Fab")
		)
		(fp_line
			(start 1.1938 -0.4064)
			(end 1.1938 0.4064)
			(stroke
				(width 0.1)
				(type default)
			)
			(layer "F.Fab")
		)
		(fp_line
			(start -0.8636 -0.4572)
			(end 0.8636 -0.4572)
			(stroke
				(width 0.1)
				(type default)
			)
			(layer "F.Fab")
		)
		(fp_line
			(start 0.8636 -0.4572)
			(end 0.8636 -0.4064)
			(stroke
				(width 0.1)
				(type default)
			)
			(layer "F.Fab")
		)
		(pad "1" smd rect
			(at -0.7366 0 180)
			(size 0.7112 0.8128)
			(layers "F.Cu" "F.Mask" "F.Paste")
			(net "P0V8_SERDES_VDDA_PEX0_C5")
		)
		(pad "2" smd rect
			(at 0.7366 0 180)
			(size 0.7112 0.8128)
			(layers "F.Cu" "F.Mask" "F.Paste")
			(net "GND")
		)
	)
	(footprint ""
		(layer "F.Cu")
		(at 51.311048 -356.244906 90)
		(property "Reference" "C2183"
			(at 0 0 90)
			(layer "F.SilkS")
			(hide yes)
			(effects
				(font
					(size 1.27 1.27)
				)
			)
		)
		(property "Value" ""
			(at 0 0 90)
			(layer "F.Fab")
			(effects
				(font
					(size 1.27 1.27)
				)
			)
		)
		(duplicate_pad_numbers_are_jumpers no)
		(fp_line
			(start 0.299974 -0.150114)
			(end 0.299974 0.150114)
			(stroke
				(width 0.1)
				(type default)
			)
			(layer "F.Fab")
		)
		(fp_line
			(start -0.299974 -0.150114)
			(end 0.299974 -0.150114)
			(stroke
				(width 0.1)
				(type default)
			)
			(layer "F.Fab")
		)
		(fp_line
			(start 0.299974 0.150114)
			(end -0.299974 0.150114)
			(stroke
				(width 0.1)
				(type default)
			)
			(layer "F.Fab")
		)
		(fp_line
			(start -0.299974 0.150114)
			(end -0.299974 -0.150114)
			(stroke
				(width 0.1)
				(type default)
			)
			(layer "F.Fab")
		)
		(pad "1" smd rect
			(at -0.2667 0 90)
			(size 0.3048 0.381)
			(layers "F.Cu" "F.Mask" "F.Paste")
			(net "P5E_PEX0_STN4_TX_DN<64>")
		)
		(pad "2" smd rect
			(at 0.2667 0 90)
			(size 0.3048 0.381)
			(layers "F.Cu" "F.Mask" "F.Paste")
			(net "P5E_PEX0_STN4_TX_C_DN<64>")
		)
	)
	(footprint ""
		(layer "F.Cu")
		(at 312.654696 -22.961346 90)
		(property "Reference" "R1701"
			(at 0 0 90)
			(layer "F.SilkS")
			(hide yes)
			(effects
				(font
					(size 1.27 1.27)
				)
			)
		)
		(property "Value" ""
			(at 0 0 90)
			(layer "F.Fab")
			(effects
				(font
					(size 1.27 1.27)
				)
			)
		)
		(duplicate_pad_numbers_are_jumpers no)
		(fp_line
			(start 0.7874 -0.4064)
			(end 0.7874 0.4064)
			(stroke
				(width 0.1524)
				(type default)
			)
			(layer "F.SilkS")
		)
		(fp_line
			(start -0.7874 -0.4064)
			(end 0.7874 -0.4064)
			(stroke
				(width 0.1524)
				(type default)
			)
			(layer "F.SilkS")
		)
		(fp_line
			(start 0.7874 0.4064)
			(end -0.7874 0.4064)
			(stroke
				(width 0.1524)
				(type default)
			)
			(layer "F.SilkS")
		)
		(fp_line
			(start -0.7874 0.4064)
			(end -0.7874 -0.4064)
			(stroke
				(width 0.1524)
				(type default)
			)
			(layer "F.SilkS")
		)
		(fp_line
			(start -0.12065 -0.305054)
			(end -0.12065 -0.2794)
			(stroke
				(width 0.1)
				(type default)
			)
			(layer "F.Fab")
		)
		(fp_line
			(start -0.67945 -0.305054)
			(end -0.12065 -0.305054)
			(stroke
				(width 0.1)
				(type default)
			)
			(layer "F.Fab")
		)
		(fp_line
			(start 0.67945 -0.3048)
			(end 0.67945 0.3048)
			(stroke
				(width 0.1)
				(type default)
			)
			(layer "F.Fab")
		)
		(fp_line
			(start 0.12065 -0.3048)
			(end 0.67945 -0.3048)
			(stroke
				(width 0.1)
				(type default)
			)
			(layer "F.Fab")
		)
		(fp_line
			(start 0.12065 -0.2794)
			(end 0.12065 -0.3048)
			(stroke
				(width 0.1)
				(type default)
			)
			(layer "F.Fab")
		)
		(fp_line
			(start -0.12065 -0.2794)
			(end 0.12065 -0.2794)
			(stroke
				(width 0.1)
				(type default)
			)
			(layer "F.Fab")
		)
		(fp_line
			(start 0.120396 0.2794)
			(end -0.12065 0.2794)
			(stroke
				(width 0.1)
				(type default)
			)
			(layer "F.Fab")
		)
		(fp_line
			(start -0.12065 0.2794)
			(end -0.12065 0.3048)
			(stroke
				(width 0.1)
				(type default)
			)
			(layer "F.Fab")
		)
		(fp_line
			(start 0.67945 0.3048)
			(end 0.120396 0.3048)
			(stroke
				(width 0.1)
				(type default)
			)
			(layer "F.Fab")
		)
		(fp_line
			(start 0.120396 0.3048)
			(end 0.120396 0.2794)
			(stroke
				(width 0.1)
				(type default)
			)
			(layer "F.Fab")
		)
		(fp_line
			(start -0.12065 0.3048)
			(end -0.67945 0.3048)
			(stroke
				(width 0.1)
				(type default)
			)
			(layer "F.Fab")
		)
		(fp_line
			(start -0.67945 0.3048)
			(end -0.67945 -0.305054)
			(stroke
				(width 0.1)
				(type default)
			)
			(layer "F.Fab")
		)
		(pad "1" smd circle
			(at -0.40005 0 90)
			(size 0 0)
			(layers "F.Cu" "F.Mask" "F.Paste")
			(net "SMB_SSD10_ISO_EN")
		)
		(pad "2" smd circle
			(at 0.40005 0 90)
			(size 0 0)
			(layers "F.Cu" "F.Mask" "F.Paste")
			(net "P3V3_AUX")
		)
	)
	(footprint ""
		(layer "F.Cu")
		(at 252.634496 -30.03169 180)
		(property "Reference" "C492"
			(at 0 0 180)
			(layer "F.SilkS")
			(hide yes)
			(effects
				(font
					(size 1.27 1.27)
				)
			)
		)
		(property "Value" ""
			(at 0 0 180)
			(layer "F.Fab")
			(effects
				(font
					(size 1.27 1.27)
				)
			)
		)
		(duplicate_pad_numbers_are_jumpers no)
		(fp_line
			(start 0.299974 0.150114)
			(end -0.299974 0.150114)
			(stroke
				(width 0.1)
				(type default)
			)
			(layer "F.Fab")
		)
		(fp_line
			(start 0.299974 -0.150114)
			(end 0.299974 0.150114)
			(stroke
				(width 0.1)
				(type default)
			)
			(layer "F.Fab")
		)
		(fp_line
			(start -0.299974 0.150114)
			(end -0.299974 -0.150114)
			(stroke
				(width 0.1)
				(type default)
			)
			(layer "F.Fab")
		)
		(fp_line
			(start -0.299974 -0.150114)
			(end 0.299974 -0.150114)
			(stroke
				(width 0.1)
				(type default)
			)
			(layer "F.Fab")
		)
		(pad "1" smd rect
			(at -0.2667 0 180)
			(size 0.3048 0.381)
			(layers "F.Cu" "F.Mask" "F.Paste")
			(net "P5E_PEX2_STN2_TX_DN<45>")
		)
		(pad "2" smd rect
			(at 0.2667 0 180)
			(size 0.3048 0.381)
			(layers "F.Cu" "F.Mask" "F.Paste")
			(net "P5E_PEX2_STN2_TX_C_DN<45>")
		)
	)
	(footprint ""
		(layer "F.Cu")
		(at 206.622396 -90.104214)
		(property "Reference" "R4359"
			(at 0 0 0)
			(layer "F.SilkS")
			(hide yes)
			(effects
				(font
					(size 1.27 1.27)
				)
			)
		)
		(property "Value" ""
			(at 0 0 0)
			(layer "F.Fab")
			(effects
				(font
					(size 1.27 1.27)
				)
			)
		)
		(duplicate_pad_numbers_are_jumpers no)
		(fp_line
			(start -0.7874 -0.4064)
			(end 0.7874 -0.4064)
			(stroke
				(width 0.1524)
				(type default)
			)
			(layer "F.SilkS")
		)
		(fp_line
			(start -0.7874 0.4064)
			(end -0.7874 -0.4064)
			(stroke
				(width 0.1524)
				(type default)
			)
			(layer "F.SilkS")
		)
		(fp_line
			(start 0.7874 -0.4064)
			(end 0.7874 0.4064)
			(stroke
				(width 0.1524)
				(type default)
			)
			(layer "F.SilkS")
		)
		(fp_line
			(start 0.7874 0.4064)
			(end -0.7874 0.4064)
			(stroke
				(width 0.1524)
				(type default)
			)
			(layer "F.SilkS")
		)
		(fp_line
			(start -0.67945 -0.305054)
			(end -0.12065 -0.305054)
			(stroke
				(width 0.1)
				(type default)
			)
			(layer "F.Fab")
		)
		(fp_line
			(start -0.67945 0.3048)
			(end -0.67945 -0.305054)
			(stroke
				(width 0.1)
				(type default)
			)
			(layer "F.Fab")
		)
		(fp_line
			(start -0.12065 -0.305054)
			(end -0.12065 -0.2794)
			(stroke
				(width 0.1)
				(type default)
			)
			(layer "F.Fab")
		)
		(fp_line
			(start -0.12065 -0.2794)
			(end 0.12065 -0.2794)
			(stroke
				(width 0.1)
				(type default)
			)
			(layer "F.Fab")
		)
		(fp_line
			(start -0.12065 0.2794)
			(end -0.12065 0.3048)
			(stroke
				(width 0.1)
				(type default)
			)
			(layer "F.Fab")
		)
		(fp_line
			(start -0.12065 0.3048)
			(end -0.67945 0.3048)
			(stroke
				(width 0.1)
				(type default)
			)
			(layer "F.Fab")
		)
		(fp_line
			(start 0.120396 0.2794)
			(end -0.12065 0.2794)
			(stroke
				(width 0.1)
				(type default)
			)
			(layer "F.Fab")
		)
		(fp_line
			(start 0.120396 0.3048)
			(end 0.120396 0.2794)
			(stroke
				(width 0.1)
				(type default)
			)
			(layer "F.Fab")
		)
		(fp_line
			(start 0.12065 -0.3048)
			(end 0.67945 -0.3048)
			(stroke
				(width 0.1)
				(type default)
			)
			(layer "F.Fab")
		)
		(fp_line
			(start 0.12065 -0.2794)
			(end 0.12065 -0.3048)
			(stroke
				(width 0.1)
				(type default)
			)
			(layer "F.Fab")
		)
		(fp_line
			(start 0.67945 -0.3048)
			(end 0.67945 0.3048)
			(stroke
				(width 0.1)
				(type default)
			)
			(layer "F.Fab")
		)
		(fp_line
			(start 0.67945 0.3048)
			(end 0.120396 0.3048)
			(stroke
				(width 0.1)
				(type default)
			)
			(layer "F.Fab")
		)
		(pad "1" smd circle
			(at -0.40005 0)
			(size 0 0)
			(layers "F.Cu" "F.Mask" "F.Paste")
			(net "P3V3_AUX")
		)
		(pad "2" smd circle
			(at 0.40005 0)
			(size 0 0)
			(layers "F.Cu" "F.Mask" "F.Paste")
			(net "IRQ_SSD_LED_IOEXP_N")
		)
	)
	(footprint ""
		(layer "F.Cu")
		(at 136.77519 -56.977534 180)
		(property "Reference" "PC316"
			(at 0 0 180)
			(layer "F.SilkS")
			(hide yes)
			(effects
				(font
					(size 1.27 1.27)
				)
			)
		)
		(property "Value" ""
			(at 0 0 180)
			(layer "F.Fab")
			(effects
				(font
					(size 1.27 1.27)
				)
			)
		)
		(duplicate_pad_numbers_are_jumpers no)
		(fp_line
			(start 0.7874 0.4064)
			(end -0.7874 0.4064)
			(stroke
				(width 0.1524)
				(type default)
			)
			(layer "F.SilkS")
		)
		(fp_line
			(start 0.7874 -0.4064)
			(end 0.7874 0.4064)
			(stroke
				(width 0.1524)
				(type default)
			)
			(layer "F.SilkS")
		)
		(fp_line
			(start -0.7874 0.4064)
			(end -0.7874 -0.4064)
			(stroke
				(width 0.1524)
				(type default)
			)
			(layer "F.SilkS")
		)
		(fp_line
			(start -0.7874 -0.4064)
			(end 0.7874 -0.4064)
			(stroke
				(width 0.1524)
				(type default)
			)
			(layer "F.SilkS")
		)
		(fp_line
			(start 0.67945 0.3048)
			(end 0.120396 0.3048)
			(stroke
				(width 0.1)
				(type default)
			)
			(layer "F.Fab")
		)
		(fp_line
			(start 0.67945 -0.3048)
			(end 0.67945 0.3048)
			(stroke
				(width 0.1)
				(type default)
			)
			(layer "F.Fab")
		)
		(fp_line
			(start 0.12065 -0.2794)
			(end 0.12065 -0.3048)
			(stroke
				(width 0.1)
				(type default)
			)
			(layer "F.Fab")
		)
		(fp_line
			(start 0.12065 -0.3048)
			(end 0.67945 -0.3048)
			(stroke
				(width 0.1)
				(type default)
			)
			(layer "F.Fab")
		)
		(fp_line
			(start 0.120396 0.3048)
			(end 0.120396 0.2794)
			(stroke
				(width 0.1)
				(type default)
			)
			(layer "F.Fab")
		)
		(fp_line
			(start 0.120396 0.2794)
			(end -0.12065 0.2794)
			(stroke
				(width 0.1)
				(type default)
			)
			(layer "F.Fab")
		)
		(fp_line
			(start -0.12065 0.3048)
			(end -0.67945 0.3048)
			(stroke
				(width 0.1)
				(type default)
			)
			(layer "F.Fab")
		)
		(fp_line
			(start -0.12065 0.2794)
			(end -0.12065 0.3048)
			(stroke
				(width 0.1)
				(type default)
			)
			(layer "F.Fab")
		)
		(fp_line
			(start -0.12065 -0.2794)
			(end 0.12065 -0.2794)
			(stroke
				(width 0.1)
				(type default)
			)
			(layer "F.Fab")
		)
		(fp_line
			(start -0.12065 -0.305054)
			(end -0.12065 -0.2794)
			(stroke
				(width 0.1)
				(type default)
			)
			(layer "F.Fab")
		)
		(fp_line
			(start -0.67945 0.3048)
			(end -0.67945 -0.305054)
			(stroke
				(width 0.1)
				(type default)
			)
			(layer "F.Fab")
		)
		(fp_line
			(start -0.67945 -0.305054)
			(end -0.12065 -0.305054)
			(stroke
				(width 0.1)
				(type default)
			)
			(layer "F.Fab")
		)
		(pad "1" smd circle
			(at -0.40005 0 180)
			(size 0 0)
			(layers "F.Cu" "F.Mask" "F.Paste")
			(net "P12V_AUX")
		)
		(pad "2" smd circle
			(at 0.40005 0 180)
			(size 0 0)
			(layers "F.Cu" "F.Mask" "F.Paste")
			(net "GND")
		)
	)
	(footprint ""
		(layer "F.Cu")
		(at 459.324202 -248.684796 90)
		(property "Reference" "R6586"
			(at 0 0 90)
			(layer "F.SilkS")
			(hide yes)
			(effects
				(font
					(size 1.27 1.27)
				)
			)
		)
		(property "Value" ""
			(at 0 0 90)
			(layer "F.Fab")
			(effects
				(font
					(size 1.27 1.27)
				)
			)
		)
		(duplicate_pad_numbers_are_jumpers no)
		(fp_line
			(start 0.7874 -0.4064)
			(end 0.7874 0.4064)
			(stroke
				(width 0.1524)
				(type default)
			)
			(layer "F.SilkS")
		)
		(fp_line
			(start -0.7874 -0.4064)
			(end 0.7874 -0.4064)
			(stroke
				(width 0.1524)
				(type default)
			)
			(layer "F.SilkS")
		)
		(fp_line
			(start 0.7874 0.4064)
			(end -0.7874 0.4064)
			(stroke
				(width 0.1524)
				(type default)
			)
			(layer "F.SilkS")
		)
		(fp_line
			(start -0.7874 0.4064)
			(end -0.7874 -0.4064)
			(stroke
				(width 0.1524)
				(type default)
			)
			(layer "F.SilkS")
		)
		(fp_line
			(start -0.12065 -0.305054)
			(end -0.12065 -0.2794)
			(stroke
				(width 0.1)
				(type default)
			)
			(layer "F.Fab")
		)
		(fp_line
			(start -0.67945 -0.305054)
			(end -0.12065 -0.305054)
			(stroke
				(width 0.1)
				(type default)
			)
			(layer "F.Fab")
		)
		(fp_line
			(start 0.67945 -0.3048)
			(end 0.67945 0.3048)
			(stroke
				(width 0.1)
				(type default)
			)
			(layer "F.Fab")
		)
		(fp_line
			(start 0.12065 -0.3048)
			(end 0.67945 -0.3048)
			(stroke
				(width 0.1)
				(type default)
			)
			(layer "F.Fab")
		)
		(fp_line
			(start 0.12065 -0.2794)
			(end 0.12065 -0.3048)
			(stroke
				(width 0.1)
				(type default)
			)
			(layer "F.Fab")
		)
		(fp_line
			(start -0.12065 -0.2794)
			(end 0.12065 -0.2794)
			(stroke
				(width 0.1)
				(type default)
			)
			(layer "F.Fab")
		)
		(fp_line
			(start 0.120396 0.2794)
			(end -0.12065 0.2794)
			(stroke
				(width 0.1)
				(type default)
			)
			(layer "F.Fab")
		)
		(fp_line
			(start -0.12065 0.2794)
			(end -0.12065 0.3048)
			(stroke
				(width 0.1)
				(type default)
			)
			(layer "F.Fab")
		)
		(fp_line
			(start 0.67945 0.3048)
			(end 0.120396 0.3048)
			(stroke
				(width 0.1)
				(type default)
			)
			(layer "F.Fab")
		)
		(fp_line
			(start 0.120396 0.3048)
			(end 0.120396 0.2794)
			(stroke
				(width 0.1)
				(type default)
			)
			(layer "F.Fab")
		)
		(fp_line
			(start -0.12065 0.3048)
			(end -0.67945 0.3048)
			(stroke
				(width 0.1)
				(type default)
			)
			(layer "F.Fab")
		)
		(fp_line
			(start -0.67945 0.3048)
			(end -0.67945 -0.305054)
			(stroke
				(width 0.1)
				(type default)
			)
			(layer "F.Fab")
		)
		(pad "1" smd circle
			(at -0.40005 0 90)
			(size 0 0)
			(layers "F.Cu" "F.Mask" "F.Paste")
			(net "P1V8_PLL_PEX3_ADJ")
		)
		(pad "2" smd circle
			(at 0.40005 0 90)
			(size 0 0)
			(layers "F.Cu" "F.Mask" "F.Paste")
			(net "GND")
		)
	)
	(footprint ""
		(layer "F.Cu")
		(at 397.956532 -17.419574 180)
		(property "Reference" "R1719"
			(at 0 0 180)
			(layer "F.SilkS")
			(hide yes)
			(effects
				(font
					(size 1.27 1.27)
				)
			)
		)
		(property "Value" ""
			(at 0 0 180)
			(layer "F.Fab")
			(effects
				(font
					(size 1.27 1.27)
				)
			)
		)
		(duplicate_pad_numbers_are_jumpers no)
		(fp_line
			(start 0.7874 0.4064)
			(end -0.7874 0.4064)
			(stroke
				(width 0.1524)
				(type default)
			)
			(layer "F.SilkS")
		)
		(fp_line
			(start 0.7874 -0.4064)
			(end 0.7874 0.4064)
			(stroke
				(width 0.1524)
				(type default)
			)
			(layer "F.SilkS")
		)
		(fp_line
			(start -0.7874 0.4064)
			(end -0.7874 -0.4064)
			(stroke
				(width 0.1524)
				(type default)
			)
			(layer "F.SilkS")
		)
		(fp_line
			(start -0.7874 -0.4064)
			(end 0.7874 -0.4064)
			(stroke
				(width 0.1524)
				(type default)
			)
			(layer "F.SilkS")
		)
		(fp_line
			(start 0.67945 0.3048)
			(end 0.120396 0.3048)
			(stroke
				(width 0.1)
				(type default)
			)
			(layer "F.Fab")
		)
		(fp_line
			(start 0.67945 -0.3048)
			(end 0.67945 0.3048)
			(stroke
				(width 0.1)
				(type default)
			)
			(layer "F.Fab")
		)
		(fp_line
			(start 0.12065 -0.2794)
			(end 0.12065 -0.3048)
			(stroke
				(width 0.1)
				(type default)
			)
			(layer "F.Fab")
		)
		(fp_line
			(start 0.12065 -0.3048)
			(end 0.67945 -0.3048)
			(stroke
				(width 0.1)
				(type default)
			)
			(layer "F.Fab")
		)
		(fp_line
			(start 0.120396 0.3048)
			(end 0.120396 0.2794)
			(stroke
				(width 0.1)
				(type default)
			)
			(layer "F.Fab")
		)
		(fp_line
			(start 0.120396 0.2794)
			(end -0.12065 0.2794)
			(stroke
				(width 0.1)
				(type default)
			)
			(layer "F.Fab")
		)
		(fp_line
			(start -0.12065 0.3048)
			(end -0.67945 0.3048)
			(stroke
				(width 0.1)
				(type default)
			)
			(layer "F.Fab")
		)
		(fp_line
			(start -0.12065 0.2794)
			(end -0.12065 0.3048)
			(stroke
				(width 0.1)
				(type default)
			)
			(layer "F.Fab")
		)
		(fp_line
			(start -0.12065 -0.2794)
			(end 0.12065 -0.2794)
			(stroke
				(width 0.1)
				(type default)
			)
			(layer "F.Fab")
		)
		(fp_line
			(start -0.12065 -0.305054)
			(end -0.12065 -0.2794)
			(stroke
				(width 0.1)
				(type default)
			)
			(layer "F.Fab")
		)
		(fp_line
			(start -0.67945 0.3048)
			(end -0.67945 -0.305054)
			(stroke
				(width 0.1)
				(type default)
			)
			(layer "F.Fab")
		)
		(fp_line
			(start -0.67945 -0.305054)
			(end -0.12065 -0.305054)
			(stroke
				(width 0.1)
				(type default)
			)
			(layer "F.Fab")
		)
		(pad "1" smd circle
			(at -0.40005 0 180)
			(size 0 0)
			(layers "F.Cu" "F.Mask" "F.Paste")
			(net "P3V3_SSD13")
		)
		(pad "2" smd circle
			(at 0.40005 0 180)
			(size 0 0)
			(layers "F.Cu" "F.Mask" "F.Paste")
			(net "SMB_ISO_SSD13_SCL")
		)
	)
	(footprint ""
		(layer "F.Cu")
		(at 156.698442 -252.356874 -90)
		(property "Reference" "R1290"
			(at 0 0 270)
			(layer "F.SilkS")
			(hide yes)
			(effects
				(font
					(size 1.27 1.27)
				)
			)
		)
		(property "Value" ""
			(at 0 0 270)
			(layer "F.Fab")
			(effects
				(font
					(size 1.27 1.27)
				)
			)
		)
		(duplicate_pad_numbers_are_jumpers no)
		(fp_line
			(start -0.7874 0.4064)
			(end -0.7874 -0.4064)
			(stroke
				(width 0.1524)
				(type default)
			)
			(layer "F.SilkS")
		)
		(fp_line
			(start 0.7874 0.4064)
			(end -0.7874 0.4064)
			(stroke
				(width 0.1524)
				(type default)
			)
			(layer "F.SilkS")
		)
		(fp_line
			(start -0.7874 -0.4064)
			(end 0.7874 -0.4064)
			(stroke
				(width 0.1524)
				(type default)
			)
			(layer "F.SilkS")
		)
		(fp_line
			(start 0.7874 -0.4064)
			(end 0.7874 0.4064)
			(stroke
				(width 0.1524)
				(type default)
			)
			(layer "F.SilkS")
		)
		(fp_line
			(start -0.67945 0.3048)
			(end -0.67945 -0.305054)
			(stroke
				(width 0.1)
				(type default)
			)
			(layer "F.Fab")
		)
		(fp_line
			(start -0.12065 0.3048)
			(end -0.67945 0.3048)
			(stroke
				(width 0.1)
				(type default)
			)
			(layer "F.Fab")
		)
		(fp_line
			(start 0.120396 0.3048)
			(end 0.120396 0.2794)
			(stroke
				(width 0.1)
				(type default)
			)
			(layer "F.Fab")
		)
		(fp_line
			(start 0.67945 0.3048)
			(end 0.120396 0.3048)
			(stroke
				(width 0.1)
				(type default)
			)
			(layer "F.Fab")
		)
		(fp_line
			(start -0.12065 0.2794)
			(end -0.12065 0.3048)
			(stroke
				(width 0.1)
				(type default)
			)
			(layer "F.Fab")
		)
		(fp_line
			(start 0.120396 0.2794)
			(end -0.12065 0.2794)
			(stroke
				(width 0.1)
				(type default)
			)
			(layer "F.Fab")
		)
		(fp_line
			(start -0.12065 -0.2794)
			(end 0.12065 -0.2794)
			(stroke
				(width 0.1)
				(type default)
			)
			(layer "F.Fab")
		)
		(fp_line
			(start 0.12065 -0.2794)
			(end 0.12065 -0.3048)
			(stroke
				(width 0.1)
				(type default)
			)
			(layer "F.Fab")
		)
		(fp_line
			(start 0.12065 -0.3048)
			(end 0.67945 -0.3048)
			(stroke
				(width 0.1)
				(type default)
			)
			(layer "F.Fab")
		)
		(fp_line
			(start 0.67945 -0.3048)
			(end 0.67945 0.3048)
			(stroke
				(width 0.1)
				(type default)
			)
			(layer "F.Fab")
		)
		(fp_line
			(start -0.67945 -0.305054)
			(end -0.12065 -0.305054)
			(stroke
				(width 0.1)
				(type default)
			)
			(layer "F.Fab")
		)
		(fp_line
			(start -0.12065 -0.305054)
			(end -0.12065 -0.2794)
			(stroke
				(width 0.1)
				(type default)
			)
			(layer "F.Fab")
		)
		(pad "1" smd circle
			(at -0.40005 0 270)
			(size 0 0)
			(layers "F.Cu" "F.Mask" "F.Paste")
			(net "GND")
		)
		(pad "2" smd circle
			(at 0.40005 0 270)
			(size 0 0)
			(layers "F.Cu" "F.Mask" "F.Paste")
			(net "PEX1_MODE_SEL1")
		)
	)
	(footprint ""
		(layer "F.Cu")
		(at 351.17532 -63.086234)
		(property "Reference" "R6018"
			(at 0 0 0)
			(layer "F.SilkS")
			(hide yes)
			(effects
				(font
					(size 1.27 1.27)
				)
			)
		)
		(property "Value" ""
			(at 0 0 0)
			(layer "F.Fab")
			(effects
				(font
					(size 1.27 1.27)
				)
			)
		)
		(duplicate_pad_numbers_are_jumpers no)
		(fp_line
			(start -0.7874 -0.4064)
			(end 0.7874 -0.4064)
			(stroke
				(width 0.1524)
				(type default)
			)
			(layer "F.SilkS")
		)
		(fp_line
			(start -0.7874 0.4064)
			(end -0.7874 -0.4064)
			(stroke
				(width 0.1524)
				(type default)
			)
			(layer "F.SilkS")
		)
		(fp_line
			(start 0.7874 -0.4064)
			(end 0.7874 0.4064)
			(stroke
				(width 0.1524)
				(type default)
			)
			(layer "F.SilkS")
		)
		(fp_line
			(start 0.7874 0.4064)
			(end -0.7874 0.4064)
			(stroke
				(width 0.1524)
				(type default)
			)
			(layer "F.SilkS")
		)
		(fp_line
			(start -0.67945 -0.305054)
			(end -0.12065 -0.305054)
			(stroke
				(width 0.1)
				(type default)
			)
			(layer "F.Fab")
		)
		(fp_line
			(start -0.67945 0.3048)
			(end -0.67945 -0.305054)
			(stroke
				(width 0.1)
				(type default)
			)
			(layer "F.Fab")
		)
		(fp_line
			(start -0.12065 -0.305054)
			(end -0.12065 -0.2794)
			(stroke
				(width 0.1)
				(type default)
			)
			(layer "F.Fab")
		)
		(fp_line
			(start -0.12065 -0.2794)
			(end 0.12065 -0.2794)
			(stroke
				(width 0.1)
				(type default)
			)
			(layer "F.Fab")
		)
		(fp_line
			(start -0.12065 0.2794)
			(end -0.12065 0.3048)
			(stroke
				(width 0.1)
				(type default)
			)
			(layer "F.Fab")
		)
		(fp_line
			(start -0.12065 0.3048)
			(end -0.67945 0.3048)
			(stroke
				(width 0.1)
				(type default)
			)
			(layer "F.Fab")
		)
		(fp_line
			(start 0.120396 0.2794)
			(end -0.12065 0.2794)
			(stroke
				(width 0.1)
				(type default)
			)
			(layer "F.Fab")
		)
		(fp_line
			(start 0.120396 0.3048)
			(end 0.120396 0.2794)
			(stroke
				(width 0.1)
				(type default)
			)
			(layer "F.Fab")
		)
		(fp_line
			(start 0.12065 -0.3048)
			(end 0.67945 -0.3048)
			(stroke
				(width 0.1)
				(type default)
			)
			(layer "F.Fab")
		)
		(fp_line
			(start 0.12065 -0.2794)
			(end 0.12065 -0.3048)
			(stroke
				(width 0.1)
				(type default)
			)
			(layer "F.Fab")
		)
		(fp_line
			(start 0.67945 -0.3048)
			(end 0.67945 0.3048)
			(stroke
				(width 0.1)
				(type default)
			)
			(layer "F.Fab")
		)
		(fp_line
			(start 0.67945 0.3048)
			(end 0.120396 0.3048)
			(stroke
				(width 0.1)
				(type default)
			)
			(layer "F.Fab")
		)
		(pad "1" smd circle
			(at -0.40005 0)
			(size 0 0)
			(layers "F.Cu" "F.Mask" "F.Paste")
			(net "P12V_SSD12_R")
		)
		(pad "2" smd circle
			(at 0.40005 0)
			(size 0 0)
			(layers "F.Cu" "F.Mask" "F.Paste")
			(net "P12V_SSD12_PG_G1")
		)
	)
	(footprint ""
		(layer "F.Cu")
		(at 213.590886 -231.150922 90)
		(property "Reference" "R1550"
			(at 0 0 90)
			(layer "F.SilkS")
			(hide yes)
			(effects
				(font
					(size 1.27 1.27)
				)
			)
		)
		(property "Value" ""
			(at 0 0 90)
			(layer "F.Fab")
			(effects
				(font
					(size 1.27 1.27)
				)
			)
		)
		(duplicate_pad_numbers_are_jumpers no)
		(fp_line
			(start 0.7874 -0.4064)
			(end 0.7874 0.4064)
			(stroke
				(width 0.1524)
				(type default)
			)
			(layer "F.SilkS")
		)
		(fp_line
			(start -0.7874 -0.4064)
			(end 0.7874 -0.4064)
			(stroke
				(width 0.1524)
				(type default)
			)
			(layer "F.SilkS")
		)
		(fp_line
			(start 0.7874 0.4064)
			(end -0.7874 0.4064)
			(stroke
				(width 0.1524)
				(type default)
			)
			(layer "F.SilkS")
		)
		(fp_line
			(start -0.7874 0.4064)
			(end -0.7874 -0.4064)
			(stroke
				(width 0.1524)
				(type default)
			)
			(layer "F.SilkS")
		)
		(fp_line
			(start -0.12065 -0.305054)
			(end -0.12065 -0.2794)
			(stroke
				(width 0.1)
				(type default)
			)
			(layer "F.Fab")
		)
		(fp_line
			(start -0.67945 -0.305054)
			(end -0.12065 -0.305054)
			(stroke
				(width 0.1)
				(type default)
			)
			(layer "F.Fab")
		)
		(fp_line
			(start 0.67945 -0.3048)
			(end 0.67945 0.3048)
			(stroke
				(width 0.1)
				(type default)
			)
			(layer "F.Fab")
		)
		(fp_line
			(start 0.12065 -0.3048)
			(end 0.67945 -0.3048)
			(stroke
				(width 0.1)
				(type default)
			)
			(layer "F.Fab")
		)
		(fp_line
			(start 0.12065 -0.2794)
			(end 0.12065 -0.3048)
			(stroke
				(width 0.1)
				(type default)
			)
			(layer "F.Fab")
		)
		(fp_line
			(start -0.12065 -0.2794)
			(end 0.12065 -0.2794)
			(stroke
				(width 0.1)
				(type default)
			)
			(layer "F.Fab")
		)
		(fp_line
			(start 0.120396 0.2794)
			(end -0.12065 0.2794)
			(stroke
				(width 0.1)
				(type default)
			)
			(layer "F.Fab")
		)
		(fp_line
			(start -0.12065 0.2794)
			(end -0.12065 0.3048)
			(stroke
				(width 0.1)
				(type default)
			)
			(layer "F.Fab")
		)
		(fp_line
			(start 0.67945 0.3048)
			(end 0.120396 0.3048)
			(stroke
				(width 0.1)
				(type default)
			)
			(layer "F.Fab")
		)
		(fp_line
			(start 0.120396 0.3048)
			(end 0.120396 0.2794)
			(stroke
				(width 0.1)
				(type default)
			)
			(layer "F.Fab")
		)
		(fp_line
			(start -0.12065 0.3048)
			(end -0.67945 0.3048)
			(stroke
				(width 0.1)
				(type default)
			)
			(layer "F.Fab")
		)
		(fp_line
			(start -0.67945 0.3048)
			(end -0.67945 -0.305054)
			(stroke
				(width 0.1)
				(type default)
			)
			(layer "F.Fab")
		)
		(pad "1" smd circle
			(at -0.40005 0 90)
			(size 0 0)
			(layers "F.Cu" "F.Mask" "F.Paste")
			(net "SMB_PEX_LS_R_SDA")
		)
		(pad "2" smd circle
			(at 0.40005 0 90)
			(size 0 0)
			(layers "F.Cu" "F.Mask" "F.Paste")
			(net "SMB_PEX3_SDA")
		)
	)
	(footprint ""
		(layer "F.Cu")
		(at 431.032412 -350.098614 90)
		(property "Reference" "C805"
			(at 0 0 90)
			(layer "F.SilkS")
			(hide yes)
			(effects
				(font
					(size 1.27 1.27)
				)
			)
		)
		(property "Value" ""
			(at 0 0 90)
			(layer "F.Fab")
			(effects
				(font
					(size 1.27 1.27)
				)
			)
		)
		(duplicate_pad_numbers_are_jumpers no)
		(fp_line
			(start 0.299974 -0.150114)
			(end 0.299974 0.150114)
			(stroke
				(width 0.1)
				(type default)
			)
			(layer "F.Fab")
		)
		(fp_line
			(start -0.299974 -0.150114)
			(end 0.299974 -0.150114)
			(stroke
				(width 0.1)
				(type default)
			)
			(layer "F.Fab")
		)
		(fp_line
			(start 0.299974 0.150114)
			(end -0.299974 0.150114)
			(stroke
				(width 0.1)
				(type default)
			)
			(layer "F.Fab")
		)
		(fp_line
			(start -0.299974 0.150114)
			(end -0.299974 -0.150114)
			(stroke
				(width 0.1)
				(type default)
			)
			(layer "F.Fab")
		)
		(pad "1" smd rect
			(at -0.2667 0 90)
			(size 0.3048 0.381)
			(layers "F.Cu" "F.Mask" "F.Paste")
			(net "P5E_PEX3_STN7_TX_DN<122>")
		)
		(pad "2" smd rect
			(at 0.2667 0 90)
			(size 0.3048 0.381)
			(layers "F.Cu" "F.Mask" "F.Paste")
			(net "P5E_PEX3_STN7_TX_C_DN<122>")
		)
	)
	(footprint ""
		(layer "F.Cu")
		(at 409.600908 -182.325518 180)
		(property "Reference" "R6447"
			(at 0 0 180)
			(layer "F.SilkS")
			(hide yes)
			(effects
				(font
					(size 1.27 1.27)
				)
			)
		)
		(property "Value" ""
			(at 0 0 180)
			(layer "F.Fab")
			(effects
				(font
					(size 1.27 1.27)
				)
			)
		)
		(duplicate_pad_numbers_are_jumpers no)
		(fp_line
			(start 0.7874 0.4064)
			(end -0.7874 0.4064)
			(stroke
				(width 0.1524)
				(type default)
			)
			(layer "F.SilkS")
		)
		(fp_line
			(start 0.7874 -0.4064)
			(end 0.7874 0.4064)
			(stroke
				(width 0.1524)
				(type default)
			)
			(layer "F.SilkS")
		)
		(fp_line
			(start -0.7874 0.4064)
			(end -0.7874 -0.4064)
			(stroke
				(width 0.1524)
				(type default)
			)
			(layer "F.SilkS")
		)
		(fp_line
			(start -0.7874 -0.4064)
			(end 0.7874 -0.4064)
			(stroke
				(width 0.1524)
				(type default)
			)
			(layer "F.SilkS")
		)
		(fp_line
			(start 0.67945 0.3048)
			(end 0.120396 0.3048)
			(stroke
				(width 0.1)
				(type default)
			)
			(layer "F.Fab")
		)
		(fp_line
			(start 0.67945 -0.3048)
			(end 0.67945 0.3048)
			(stroke
				(width 0.1)
				(type default)
			)
			(layer "F.Fab")
		)
		(fp_line
			(start 0.12065 -0.2794)
			(end 0.12065 -0.3048)
			(stroke
				(width 0.1)
				(type default)
			)
			(layer "F.Fab")
		)
		(fp_line
			(start 0.12065 -0.3048)
			(end 0.67945 -0.3048)
			(stroke
				(width 0.1)
				(type default)
			)
			(layer "F.Fab")
		)
		(fp_line
			(start 0.120396 0.3048)
			(end 0.120396 0.2794)
			(stroke
				(width 0.1)
				(type default)
			)
			(layer "F.Fab")
		)
		(fp_line
			(start 0.120396 0.2794)
			(end -0.12065 0.2794)
			(stroke
				(width 0.1)
				(type default)
			)
			(layer "F.Fab")
		)
		(fp_line
			(start -0.12065 0.3048)
			(end -0.67945 0.3048)
			(stroke
				(width 0.1)
				(type default)
			)
			(layer "F.Fab")
		)
		(fp_line
			(start -0.12065 0.2794)
			(end -0.12065 0.3048)
			(stroke
				(width 0.1)
				(type default)
			)
			(layer "F.Fab")
		)
		(fp_line
			(start -0.12065 -0.2794)
			(end 0.12065 -0.2794)
			(stroke
				(width 0.1)
				(type default)
			)
			(layer "F.Fab")
		)
		(fp_line
			(start -0.12065 -0.305054)
			(end -0.12065 -0.2794)
			(stroke
				(width 0.1)
				(type default)
			)
			(layer "F.Fab")
		)
		(fp_line
			(start -0.67945 0.3048)
			(end -0.67945 -0.305054)
			(stroke
				(width 0.1)
				(type default)
			)
			(layer "F.Fab")
		)
		(fp_line
			(start -0.67945 -0.305054)
			(end -0.12065 -0.305054)
			(stroke
				(width 0.1)
				(type default)
			)
			(layer "F.Fab")
		)
		(pad "1" smd circle
			(at -0.40005 0 180)
			(size 0 0)
			(layers "F.Cu" "F.Mask" "F.Paste")
			(net "FPGA_PEX3_MODE_SEL2_ISO")
		)
		(pad "2" smd circle
			(at 0.40005 0 180)
			(size 0 0)
			(layers "F.Cu" "F.Mask" "F.Paste")
			(net "PEX3_MODE_SEL2")
		)
	)
	(footprint ""
		(layer "F.Cu")
		(at 126.221236 -175.007524)
		(property "Reference" "R1084"
			(at 0 0 0)
			(layer "F.SilkS")
			(hide yes)
			(effects
				(font
					(size 1.27 1.27)
				)
			)
		)
		(property "Value" ""
			(at 0 0 0)
			(layer "F.Fab")
			(effects
				(font
					(size 1.27 1.27)
				)
			)
		)
		(duplicate_pad_numbers_are_jumpers no)
		(fp_line
			(start -0.7874 -0.4064)
			(end 0.7874 -0.4064)
			(stroke
				(width 0.1524)
				(type default)
			)
			(layer "F.SilkS")
		)
		(fp_line
			(start -0.67945 -0.305054)
			(end -0.12065 -0.305054)
			(stroke
				(width 0.1)
				(type default)
			)
			(layer "F.Fab")
		)
		(fp_line
			(start -0.67945 0.3048)
			(end -0.67945 -0.305054)
			(stroke
				(width 0.1)
				(type default)
			)
			(layer "F.Fab")
		)
		(fp_line
			(start -0.12065 -0.305054)
			(end -0.12065 -0.2794)
			(stroke
				(width 0.1)
				(type default)
			)
			(layer "F.Fab")
		)
		(fp_line
			(start -0.12065 -0.2794)
			(end 0.12065 -0.2794)
			(stroke
				(width 0.1)
				(type default)
			)
			(layer "F.Fab")
		)
		(fp_line
			(start -0.12065 0.2794)
			(end -0.12065 0.3048)
			(stroke
				(width 0.1)
				(type default)
			)
			(layer "F.Fab")
		)
		(fp_line
			(start -0.12065 0.3048)
			(end -0.67945 0.3048)
			(stroke
				(width 0.1)
				(type default)
			)
			(layer "F.Fab")
		)
		(fp_line
			(start 0.120396 0.2794)
			(end -0.12065 0.2794)
			(stroke
				(width 0.1)
				(type default)
			)
			(layer "F.Fab")
		)
		(fp_line
			(start 0.120396 0.3048)
			(end 0.120396 0.2794)
			(stroke
				(width 0.1)
				(type default)
			)
			(layer "F.Fab")
		)
		(fp_line
			(start 0.12065 -0.3048)
			(end 0.67945 -0.3048)
			(stroke
				(width 0.1)
				(type default)
			)
			(layer "F.Fab")
		)
		(fp_line
			(start 0.12065 -0.2794)
			(end 0.12065 -0.3048)
			(stroke
				(width 0.1)
				(type default)
			)
			(layer "F.Fab")
		)
		(fp_line
			(start 0.67945 -0.3048)
			(end 0.67945 0.3048)
			(stroke
				(width 0.1)
				(type default)
			)
			(layer "F.Fab")
		)
		(fp_line
			(start 0.67945 0.3048)
			(end 0.120396 0.3048)
			(stroke
				(width 0.1)
				(type default)
			)
			(layer "F.Fab")
		)
		(pad "1" smd circle
			(at -0.40005 0)
			(size 0 0)
			(layers "F.Cu" "F.Mask" "F.Paste")
			(net "CLK_100M_DB2000QL_PEX1_S1_R_DP")
		)
		(pad "2" smd circle
			(at 0.40005 0)
			(size 0 0)
			(layers "F.Cu" "F.Mask" "F.Paste")
			(net "CLK_100M_DB2000QL_PEX1_S1_DP")
		)
	)
	(footprint ""
		(layer "F.Cu")
		(at 196.39534 -369.39347)
		(property "Reference" "PR16"
			(at 0 0 0)
			(layer "F.SilkS")
			(hide yes)
			(effects
				(font
					(size 1.27 1.27)
				)
			)
		)
		(property "Value" ""
			(at 0 0 0)
			(layer "F.Fab")
			(effects
				(font
					(size 1.27 1.27)
				)
			)
		)
		(duplicate_pad_numbers_are_jumpers no)
		(fp_line
			(start -0.7874 -0.4064)
			(end 0.7874 -0.4064)
			(stroke
				(width 0.1524)
				(type default)
			)
			(layer "F.SilkS")
		)
		(fp_line
			(start -0.7874 0.4064)
			(end -0.7874 -0.4064)
			(stroke
				(width 0.1524)
				(type default)
			)
			(layer "F.SilkS")
		)
		(fp_line
			(start 0.7874 -0.4064)
			(end 0.7874 0.4064)
			(stroke
				(width 0.1524)
				(type default)
			)
			(layer "F.SilkS")
		)
		(fp_line
			(start 0.7874 0.4064)
			(end -0.7874 0.4064)
			(stroke
				(width 0.1524)
				(type default)
			)
			(layer "F.SilkS")
		)
		(fp_line
			(start -0.67945 -0.305054)
			(end -0.12065 -0.305054)
			(stroke
				(width 0.1)
				(type default)
			)
			(layer "F.Fab")
		)
		(fp_line
			(start -0.67945 0.3048)
			(end -0.67945 -0.305054)
			(stroke
				(width 0.1)
				(type default)
			)
			(layer "F.Fab")
		)
		(fp_line
			(start -0.12065 -0.305054)
			(end -0.12065 -0.2794)
			(stroke
				(width 0.1)
				(type default)
			)
			(layer "F.Fab")
		)
		(fp_line
			(start -0.12065 -0.2794)
			(end 0.12065 -0.2794)
			(stroke
				(width 0.1)
				(type default)
			)
			(layer "F.Fab")
		)
		(fp_line
			(start -0.12065 0.2794)
			(end -0.12065 0.3048)
			(stroke
				(width 0.1)
				(type default)
			)
			(layer "F.Fab")
		)
		(fp_line
			(start -0.12065 0.3048)
			(end -0.67945 0.3048)
			(stroke
				(width 0.1)
				(type default)
			)
			(layer "F.Fab")
		)
		(fp_line
			(start 0.120396 0.2794)
			(end -0.12065 0.2794)
			(stroke
				(width 0.1)
				(type default)
			)
			(layer "F.Fab")
		)
		(fp_line
			(start 0.120396 0.3048)
			(end 0.120396 0.2794)
			(stroke
				(width 0.1)
				(type default)
			)
			(layer "F.Fab")
		)
		(fp_line
			(start 0.12065 -0.3048)
			(end 0.67945 -0.3048)
			(stroke
				(width 0.1)
				(type default)
			)
			(layer "F.Fab")
		)
		(fp_line
			(start 0.12065 -0.2794)
			(end 0.12065 -0.3048)
			(stroke
				(width 0.1)
				(type default)
			)
			(layer "F.Fab")
		)
		(fp_line
			(start 0.67945 -0.3048)
			(end 0.67945 0.3048)
			(stroke
				(width 0.1)
				(type default)
			)
			(layer "F.Fab")
		)
		(fp_line
			(start 0.67945 0.3048)
			(end 0.120396 0.3048)
			(stroke
				(width 0.1)
				(type default)
			)
			(layer "F.Fab")
		)
		(pad "1" smd circle
			(at -0.40005 0)
			(size 0 0)
			(layers "F.Cu" "F.Mask" "F.Paste")
			(net "HSC_VTEMP")
		)
		(pad "2" smd circle
			(at 0.40005 0)
			(size 0 0)
			(layers "F.Cu" "F.Mask" "F.Paste")
			(net "AGND_HSC")
		)
	)
	(footprint ""
		(layer "F.Cu")
		(at 355.913436 -136.328404 180)
		(property "Reference" "PC349"
			(at 0 0 180)
			(layer "F.SilkS")
			(hide yes)
			(effects
				(font
					(size 1.27 1.27)
				)
			)
		)
		(property "Value" ""
			(at 0 0 180)
			(layer "F.Fab")
			(effects
				(font
					(size 1.27 1.27)
				)
			)
		)
		(duplicate_pad_numbers_are_jumpers no)
		(fp_line
			(start 0.7874 0.4064)
			(end -0.7874 0.4064)
			(stroke
				(width 0.1524)
				(type default)
			)
			(layer "F.SilkS")
		)
		(fp_line
			(start 0.7874 -0.4064)
			(end 0.7874 0.4064)
			(stroke
				(width 0.1524)
				(type default)
			)
			(layer "F.SilkS")
		)
		(fp_line
			(start -0.7874 0.4064)
			(end -0.7874 -0.4064)
			(stroke
				(width 0.1524)
				(type default)
			)
			(layer "F.SilkS")
		)
		(fp_line
			(start -0.7874 -0.4064)
			(end 0.7874 -0.4064)
			(stroke
				(width 0.1524)
				(type default)
			)
			(layer "F.SilkS")
		)
		(fp_line
			(start 0.67945 0.3048)
			(end 0.120396 0.3048)
			(stroke
				(width 0.1)
				(type default)
			)
			(layer "F.Fab")
		)
		(fp_line
			(start 0.67945 -0.3048)
			(end 0.67945 0.3048)
			(stroke
				(width 0.1)
				(type default)
			)
			(layer "F.Fab")
		)
		(fp_line
			(start 0.12065 -0.2794)
			(end 0.12065 -0.3048)
			(stroke
				(width 0.1)
				(type default)
			)
			(layer "F.Fab")
		)
		(fp_line
			(start 0.12065 -0.3048)
			(end 0.67945 -0.3048)
			(stroke
				(width 0.1)
				(type default)
			)
			(layer "F.Fab")
		)
		(fp_line
			(start 0.120396 0.3048)
			(end 0.120396 0.2794)
			(stroke
				(width 0.1)
				(type default)
			)
			(layer "F.Fab")
		)
		(fp_line
			(start 0.120396 0.2794)
			(end -0.12065 0.2794)
			(stroke
				(width 0.1)
				(type default)
			)
			(layer "F.Fab")
		)
		(fp_line
			(start -0.12065 0.3048)
			(end -0.67945 0.3048)
			(stroke
				(width 0.1)
				(type default)
			)
			(layer "F.Fab")
		)
		(fp_line
			(start -0.12065 0.2794)
			(end -0.12065 0.3048)
			(stroke
				(width 0.1)
				(type default)
			)
			(layer "F.Fab")
		)
		(fp_line
			(start -0.12065 -0.2794)
			(end 0.12065 -0.2794)
			(stroke
				(width 0.1)
				(type default)
			)
			(layer "F.Fab")
		)
		(fp_line
			(start -0.12065 -0.305054)
			(end -0.12065 -0.2794)
			(stroke
				(width 0.1)
				(type default)
			)
			(layer "F.Fab")
		)
		(fp_line
			(start -0.67945 0.3048)
			(end -0.67945 -0.305054)
			(stroke
				(width 0.1)
				(type default)
			)
			(layer "F.Fab")
		)
		(fp_line
			(start -0.67945 -0.305054)
			(end -0.12065 -0.305054)
			(stroke
				(width 0.1)
				(type default)
			)
			(layer "F.Fab")
		)
		(pad "1" smd circle
			(at -0.40005 0 180)
			(size 0 0)
			(layers "F.Cu" "F.Mask" "F.Paste")
			(net "P5V_AUX")
		)
		(pad "2" smd circle
			(at 0.40005 0 180)
			(size 0 0)
			(layers "F.Cu" "F.Mask" "F.Paste")
			(net "GND")
		)
	)
	(footprint ""
		(layer "F.Cu")
		(at 209.301334 -55.78475 -90)
		(property "Reference" "PD107"
			(at 4.17195 2.137664 90)
			(unlocked yes)
			(layer "F.SilkS")
			(effects
				(font
					(size 0.7874 0.5842)
					(thickness 0.1524)
				)
				(justify left)
			)
		)
		(property "Value" ""
			(at 0 0 270)
			(layer "F.Fab")
			(effects
				(font
					(size 1.27 1.27)
				)
			)
		)
		(duplicate_pad_numbers_are_jumpers no)
		(fp_line
			(start -3.400044 1.459992)
			(end -3.400044 -1.459992)
			(stroke
				(width 0.1524)
				(type default)
			)
			(layer "F.SilkS")
		)
		(fp_line
			(start 4.107942 1.459992)
			(end -3.400044 1.459992)
			(stroke
				(width 0.1524)
				(type default)
			)
			(layer "F.SilkS")
		)
		(fp_line
			(start -3.400044 -1.459992)
			(end 4.107942 -1.459992)
			(stroke
				(width 0.1524)
				(type default)
			)
			(layer "F.SilkS")
		)
		(fp_line
			(start 4.107942 -1.459992)
			(end 4.107942 1.459992)
			(stroke
				(width 0.1524)
				(type default)
			)
			(layer "F.SilkS")
		)
		(fp_poly
			(pts
				(xy 4.107942 -1.459992) (xy 4.107942 1.459992) (xy 3.308096 1.459992) (xy 3.308096 -1.459992)
			)
			(stroke
				(width 0)
				(type default)
			)
			(fill yes)
			(layer "F.SilkS")
		)
		(fp_line
			(start -2.29997 1.459992)
			(end -2.29997 -1.459992)
			(stroke
				(width 0.1)
				(type default)
			)
			(layer "F.Fab")
		)
		(fp_line
			(start 2.29997 1.459992)
			(end -2.29997 1.459992)
			(stroke
				(width 0.1)
				(type default)
			)
			(layer "F.Fab")
		)
		(fp_line
			(start -2.29997 -1.459992)
			(end 2.29997 -1.459992)
			(stroke
				(width 0.1)
				(type default)
			)
			(layer "F.Fab")
		)
		(fp_line
			(start 2.29997 -1.459992)
			(end 2.29997 1.459992)
			(stroke
				(width 0.1)
				(type default)
			)
			(layer "F.Fab")
		)
		(fp_text user "-"
			(at 5.4102 0.29845 90)
			(unlocked yes)
			(layer "F.SilkS")
			(effects
				(font
					(size 1.905 1.4224)
					(thickness 0.1524)
				)
				(justify left)
			)
		)
		(fp_text user "+"
			(at -4.7752 -0.12065 270)
			(unlocked yes)
			(layer "F.SilkS")
			(effects
				(font
					(size 1.905 1.4224)
					(thickness 0.1524)
				)
				(justify left)
			)
		)
		(fp_text user "-"
			(at 5.4102 0.29845 90)
			(unlocked yes)
			(layer "F.Fab")
			(effects
				(font
					(size 1.905 1.4224)
					(thickness 0.1524)
				)
				(justify left)
			)
		)
		(fp_text user "+"
			(at -4.7752 -0.12065 270)
			(unlocked yes)
			(layer "F.Fab")
			(effects
				(font
					(size 1.905 1.4224)
					(thickness 0.1524)
				)
				(justify left)
			)
		)
		(pad "A" smd rect
			(at -1.999996 0)
			(size 1.7018 2.5146)
			(layers "F.Cu" "F.Mask" "F.Paste")
			(net "GND")
		)
		(pad "C" smd rect
			(at 1.999996 0)
			(size 1.7018 2.5146)
			(layers "F.Cu" "F.Mask" "F.Paste")
			(net "P12V_SSD7_R")
		)
	)
	(footprint ""
		(layer "F.Cu")
		(at 400.369024 8.149844)
		(property "Reference" "DE15T_2"
			(at -3.6068 -2.962148 0)
			(unlocked yes)
			(layer "F.SilkS")
			(effects
				(font
					(size 0.7874 0.5842)
					(thickness 0.1524)
				)
				(justify left)
			)
		)
		(property "Value" ""
			(at 0 0 0)
			(layer "F.Fab")
			(effects
				(font
					(size 1.27 1.27)
				)
			)
		)
		(duplicate_pad_numbers_are_jumpers no)
		(fp_line
			(start -1.2192 -2.1082)
			(end 1.2192 -2.1082)
			(stroke
				(width 0.1524)
				(type default)
			)
			(layer "F.SilkS")
		)
		(fp_line
			(start -1.2192 2.1082)
			(end -1.2192 -2.1082)
			(stroke
				(width 0.1524)
				(type default)
			)
			(layer "F.SilkS")
		)
		(fp_line
			(start 1.2192 -2.1082)
			(end 1.2192 2.1082)
			(stroke
				(width 0.1524)
				(type default)
			)
			(layer "F.SilkS")
		)
		(fp_line
			(start 1.2192 2.1082)
			(end -1.2192 2.1082)
			(stroke
				(width 0.1524)
				(type default)
			)
			(layer "F.SilkS")
		)
		(pad "" np_thru_hole circle
			(at -2.8829 -1.27 270)
			(size 1.0414 1.0414)
			(drill 1.0414)
			(layers "*.Cu" "*.Mask")
			(clearance 0.381)
			(thermal_gap 0.381)
		)
		(pad "" np_thru_hole circle
			(at -2.8829 1.27 270)
			(size 1.0414 1.0414)
			(drill 1.0414)
			(layers "*.Cu" "*.Mask")
			(clearance 0.381)
			(thermal_gap 0.381)
		)
		(pad "" np_thru_hole circle
			(at 3.4671 -1.27 270)
			(size 1.0414 1.0414)
			(drill 1.0414)
			(layers "*.Cu" "*.Mask")
			(clearance 0.381)
			(thermal_gap 0.381)
		)
		(pad "" np_thru_hole circle
			(at 3.4671 1.27 270)
			(size 1.0414 1.0414)
			(drill 1.0414)
			(layers "*.Cu" "*.Mask")
			(clearance 0.381)
			(thermal_gap 0.381)
		)
		(pad "1" smd rect
			(at 0.8255 -0.249936 270)
			(size 0.3048 0.508)
			(layers "F.Cu" "F.Mask" "F.Paste")
			(net "85_10INCH_IN3_DN")
		)
		(pad "2" smd rect
			(at 0.8255 0.249936 270)
			(size 0.3048 0.508)
			(layers "F.Cu" "F.Mask" "F.Paste")
			(net "85_10INCH_IN3_DP")
		)
		(pad "3" smd circle
			(at 0 0)
			(size 0 0)
			(layers "F.Cu" "F.Mask" "F.Paste")
			(net "COUPON_GND2")
		)
		(zone
			(layer "F.Cu")
			(hatch none 0.5)
			(connect_pads
				(clearance 0)
			)
			(min_thickness 0.25)
			(keepout
				(tracks not_allowed)
				(vias allowed)
				(pads allowed)
				(copperpour not_allowed)
				(footprints allowed)
			)
			(placement
				(enabled no)
				(sheetname "")
			)
			(fill
				(thermal_gap 0.5)
				(thermal_bridge_width 0.5)
				(island_removal_mode 0)
			)
			(polygon
				(pts
					(xy 401.486624 7.601204) (xy 401.486624 7.696708) (xy 400.889724 7.696708) (xy 400.889724 8.103108)
					(xy 401.486624 8.103108) (xy 401.486624 8.19658) (xy 400.889724 8.19658) (xy 400.889724 8.60298)
					(xy 401.486624 8.60298) (xy 401.486624 8.698484) (xy 400.788124 8.698484) (xy 400.788124 7.601204)
				)
			)
		)
		(zone
			(layers "F.Cu" "B.Cu" "In1.Cu" "In2.Cu" "In3.Cu" "In4.Cu" "In5.Cu" "In6.Cu"
				"In7.Cu" "In8.Cu" "In9.Cu" "In10.Cu" "In11.Cu" "In12.Cu" "In13.Cu" "In14.Cu"
				"In15.Cu" "In16.Cu"
			)
			(hatch none 0.5)
			(connect_pads
				(clearance 0)
			)
			(min_thickness 0.25)
			(keepout
				(tracks not_allowed)
				(vias allowed)
				(pads allowed)
				(copperpour not_allowed)
				(footprints allowed)
			)
			(placement
				(enabled no)
				(sheetname "")
			)
			(fill
				(thermal_gap 0.5)
				(thermal_bridge_width 0.5)
				(island_removal_mode 0)
			)
			(polygon
				(pts
					(arc
						(start 398.413224 6.879844)
						(mid 396.559024 6.879844)
						(end 398.413224 6.879844)
					)
				)
			)
		)
		(zone
			(layers "F.Cu" "B.Cu" "In1.Cu" "In2.Cu" "In3.Cu" "In4.Cu" "In5.Cu" "In6.Cu"
				"In7.Cu" "In8.Cu" "In9.Cu" "In10.Cu" "In11.Cu" "In12.Cu" "In13.Cu" "In14.Cu"
				"In15.Cu" "In16.Cu"
			)
			(hatch none 0.5)
			(connect_pads
				(clearance 0)
			)
			(min_thickness 0.25)
			(keepout
				(tracks not_allowed)
				(vias allowed)
				(pads allowed)
				(copperpour not_allowed)
				(footprints allowed)
			)
			(placement
				(enabled no)
				(sheetname "")
			)
			(fill
				(thermal_gap 0.5)
				(thermal_bridge_width 0.5)
				(island_removal_mode 0)
			)
			(polygon
				(pts
					(arc
						(start 398.413224 9.419844)
						(mid 396.559024 9.419844)
						(end 398.413224 9.419844)
					)
				)
			)
		)
		(zone
			(layers "F.Cu" "B.Cu" "In1.Cu" "In2.Cu" "In3.Cu" "In4.Cu" "In5.Cu" "In6.Cu"
				"In7.Cu" "In8.Cu" "In9.Cu" "In10.Cu" "In11.Cu" "In12.Cu" "In13.Cu" "In14.Cu"
				"In15.Cu" "In16.Cu"
			)
			(hatch none 0.5)
			(connect_pads
				(clearance 0)
			)
			(min_thickness 0.25)
			(keepout
				(tracks not_allowed)
				(vias allowed)
				(pads allowed)
				(copperpour not_allowed)
				(footprints allowed)
			)
			(placement
				(enabled no)
				(sheetname "")
			)
			(fill
				(thermal_gap 0.5)
				(thermal_bridge_width 0.5)
				(island_removal_mode 0)
			)
			(polygon
				(pts
					(arc
						(start 404.763224 6.879844)
						(mid 402.909024 6.879844)
						(end 404.763224 6.879844)
					)
				)
			)
		)
		(zone
			(layers "F.Cu" "B.Cu" "In1.Cu" "In2.Cu" "In3.Cu" "In4.Cu" "In5.Cu" "In6.Cu"
				"In7.Cu" "In8.Cu" "In9.Cu" "In10.Cu" "In11.Cu" "In12.Cu" "In13.Cu" "In14.Cu"
				"In15.Cu" "In16.Cu"
			)
			(hatch none 0.5)
			(connect_pads
				(clearance 0)
			)
			(min_thickness 0.25)
			(keepout
				(tracks not_allowed)
				(vias allowed)
				(pads allowed)
				(copperpour not_allowed)
				(footprints allowed)
			)
			(placement
				(enabled no)
				(sheetname "")
			)
			(fill
				(thermal_gap 0.5)
				(thermal_bridge_width 0.5)
				(island_removal_mode 0)
			)
			(polygon
				(pts
					(arc
						(start 404.763224 9.419844)
						(mid 402.909024 9.419844)
						(end 404.763224 9.419844)
					)
				)
			)
		)
	)
	(footprint ""
		(layer "F.Cu")
		(at 374.567958 -53.051456)
		(property "Reference" "R4467"
			(at 0 0 0)
			(layer "F.SilkS")
			(hide yes)
			(effects
				(font
					(size 1.27 1.27)
				)
			)
		)
		(property "Value" ""
			(at 0 0 0)
			(layer "F.Fab")
			(effects
				(font
					(size 1.27 1.27)
				)
			)
		)
		(duplicate_pad_numbers_are_jumpers no)
		(fp_line
			(start -0.7874 -0.4064)
			(end 0.7874 -0.4064)
			(stroke
				(width 0.1524)
				(type default)
			)
			(layer "F.SilkS")
		)
		(fp_line
			(start -0.7874 0.4064)
			(end -0.7874 -0.4064)
			(stroke
				(width 0.1524)
				(type default)
			)
			(layer "F.SilkS")
		)
		(fp_line
			(start 0.7874 -0.4064)
			(end 0.7874 0.4064)
			(stroke
				(width 0.1524)
				(type default)
			)
			(layer "F.SilkS")
		)
		(fp_line
			(start 0.7874 0.4064)
			(end -0.7874 0.4064)
			(stroke
				(width 0.1524)
				(type default)
			)
			(layer "F.SilkS")
		)
		(fp_line
			(start -0.67945 -0.305054)
			(end -0.12065 -0.305054)
			(stroke
				(width 0.1)
				(type default)
			)
			(layer "F.Fab")
		)
		(fp_line
			(start -0.67945 0.3048)
			(end -0.67945 -0.305054)
			(stroke
				(width 0.1)
				(type default)
			)
			(layer "F.Fab")
		)
		(fp_line
			(start -0.12065 -0.305054)
			(end -0.12065 -0.2794)
			(stroke
				(width 0.1)
				(type default)
			)
			(layer "F.Fab")
		)
		(fp_line
			(start -0.12065 -0.2794)
			(end 0.12065 -0.2794)
			(stroke
				(width 0.1)
				(type default)
			)
			(layer "F.Fab")
		)
		(fp_line
			(start -0.12065 0.2794)
			(end -0.12065 0.3048)
			(stroke
				(width 0.1)
				(type default)
			)
			(layer "F.Fab")
		)
		(fp_line
			(start -0.12065 0.3048)
			(end -0.67945 0.3048)
			(stroke
				(width 0.1)
				(type default)
			)
			(layer "F.Fab")
		)
		(fp_line
			(start 0.120396 0.2794)
			(end -0.12065 0.2794)
			(stroke
				(width 0.1)
				(type default)
			)
			(layer "F.Fab")
		)
		(fp_line
			(start 0.120396 0.3048)
			(end 0.120396 0.2794)
			(stroke
				(width 0.1)
				(type default)
			)
			(layer "F.Fab")
		)
		(fp_line
			(start 0.12065 -0.3048)
			(end 0.67945 -0.3048)
			(stroke
				(width 0.1)
				(type default)
			)
			(layer "F.Fab")
		)
		(fp_line
			(start 0.12065 -0.2794)
			(end 0.12065 -0.3048)
			(stroke
				(width 0.1)
				(type default)
			)
			(layer "F.Fab")
		)
		(fp_line
			(start 0.67945 -0.3048)
			(end 0.67945 0.3048)
			(stroke
				(width 0.1)
				(type default)
			)
			(layer "F.Fab")
		)
		(fp_line
			(start 0.67945 0.3048)
			(end 0.120396 0.3048)
			(stroke
				(width 0.1)
				(type default)
			)
			(layer "F.Fab")
		)
		(pad "1" smd circle
			(at -0.40005 0)
			(size 0 0)
			(layers "F.Cu" "F.Mask" "F.Paste")
			(net "PWRGD_P12V_SSD12")
		)
		(pad "2" smd circle
			(at 0.40005 0)
			(size 0 0)
			(layers "F.Cu" "F.Mask" "F.Paste")
			(net "PWRGD_P12V_SSD12_R")
		)
	)
	(footprint ""
		(layer "F.Cu")
		(at 299.875702 -356.244906 90)
		(property "Reference" "C2372"
			(at 0 0 90)
			(layer "F.SilkS")
			(hide yes)
			(effects
				(font
					(size 1.27 1.27)
				)
			)
		)
		(property "Value" ""
			(at 0 0 90)
			(layer "F.Fab")
			(effects
				(font
					(size 1.27 1.27)
				)
			)
		)
		(duplicate_pad_numbers_are_jumpers no)
		(fp_line
			(start 0.299974 -0.150114)
			(end 0.299974 0.150114)
			(stroke
				(width 0.1)
				(type default)
			)
			(layer "F.Fab")
		)
		(fp_line
			(start -0.299974 -0.150114)
			(end 0.299974 -0.150114)
			(stroke
				(width 0.1)
				(type default)
			)
			(layer "F.Fab")
		)
		(fp_line
			(start 0.299974 0.150114)
			(end -0.299974 0.150114)
			(stroke
				(width 0.1)
				(type default)
			)
			(layer "F.Fab")
		)
		(fp_line
			(start -0.299974 0.150114)
			(end -0.299974 -0.150114)
			(stroke
				(width 0.1)
				(type default)
			)
			(layer "F.Fab")
		)
		(pad "1" smd rect
			(at -0.2667 0 90)
			(size 0.3048 0.381)
			(layers "F.Cu" "F.Mask" "F.Paste")
			(net "P5E_PEX2_STN4_TX_DN<64>")
		)
		(pad "2" smd rect
			(at 0.2667 0 90)
			(size 0.3048 0.381)
			(layers "F.Cu" "F.Mask" "F.Paste")
			(net "P5E_PEX2_STN4_TX_C_DN<64>")
		)
	)
	(footprint ""
		(layer "F.Cu")
		(at 465.710524 -555.054008 90)
		(property "Reference" "HS_BP0"
			(at -0.5842 -1.31953 90)
			(unlocked yes)
			(layer "B.SilkS")
			(effects
				(font
					(size 0.7874 0.5842)
					(thickness 0.1524)
				)
				(justify left mirror)
			)
		)
		(property "Value" ""
			(at 0 0 90)
			(layer "F.Fab")
			(effects
				(font
					(size 1.27 1.27)
				)
			)
		)
		(duplicate_pad_numbers_are_jumpers no)
		(pad "1" thru_hole circle
			(at 0 0 90)
			(size 0.4572 0.4572)
			(drill 0.2032)
			(layers "*.Cu" "*.Mask")
			(remove_unused_layers no)
			(net "Net_9202")
			(clearance 0.127)
			(thermal_gap 0.127)
			(padstack
				(mode front_inner_back)
				(layer "Inner"
					(shape circle)
					(size 0.4572 0.4572)
					(clearance 0.127)
				)
				(layer "B.Cu"
					(shape circle)
					(size 0.508 0.508)
					(clearance 0.1016)
				)
			)
		)
	)
	(footprint ""
		(layer "F.Cu")
		(at 196.119242 -153.390346 180)
		(property "Reference" "C215"
			(at 0 0 180)
			(layer "F.SilkS")
			(hide yes)
			(effects
				(font
					(size 1.27 1.27)
				)
			)
		)
		(property "Value" ""
			(at 0 0 180)
			(layer "F.Fab")
			(effects
				(font
					(size 1.27 1.27)
				)
			)
		)
		(duplicate_pad_numbers_are_jumpers no)
		(fp_line
			(start 0.299974 0.150114)
			(end -0.299974 0.150114)
			(stroke
				(width 0.1)
				(type default)
			)
			(layer "F.Fab")
		)
		(fp_line
			(start 0.299974 -0.150114)
			(end 0.299974 0.150114)
			(stroke
				(width 0.1)
				(type default)
			)
			(layer "F.Fab")
		)
		(fp_line
			(start -0.299974 0.150114)
			(end -0.299974 -0.150114)
			(stroke
				(width 0.1)
				(type default)
			)
			(layer "F.Fab")
		)
		(fp_line
			(start -0.299974 -0.150114)
			(end 0.299974 -0.150114)
			(stroke
				(width 0.1)
				(type default)
			)
			(layer "F.Fab")
		)
		(pad "1" smd rect
			(at -0.2667 0 180)
			(size 0.3048 0.381)
			(layers "F.Cu" "F.Mask" "F.Paste")
			(net "P5E_PEX1_STN0_TX_DP<14>")
		)
		(pad "2" smd rect
			(at 0.2667 0 180)
			(size 0.3048 0.381)
			(layers "F.Cu" "F.Mask" "F.Paste")
			(net "P5E_PEX1_STN0_TX_C_DP<14>")
		)
	)
	(footprint ""
		(layer "F.Cu")
		(at 233.949494 -180.68163 -90)
		(property "Reference" "R5492"
			(at 0 0 270)
			(layer "F.SilkS")
			(hide yes)
			(effects
				(font
					(size 1.27 1.27)
				)
			)
		)
		(property "Value" ""
			(at 0 0 270)
			(layer "F.Fab")
			(effects
				(font
					(size 1.27 1.27)
				)
			)
		)
		(duplicate_pad_numbers_are_jumpers no)
		(fp_line
			(start -0.7874 0.4064)
			(end -0.7874 -0.4064)
			(stroke
				(width 0.1524)
				(type default)
			)
			(layer "F.SilkS")
		)
		(fp_line
			(start 0.7874 0.4064)
			(end -0.7874 0.4064)
			(stroke
				(width 0.1524)
				(type default)
			)
			(layer "F.SilkS")
		)
		(fp_line
			(start -0.7874 -0.4064)
			(end 0.7874 -0.4064)
			(stroke
				(width 0.1524)
				(type default)
			)
			(layer "F.SilkS")
		)
		(fp_line
			(start 0.7874 -0.4064)
			(end 0.7874 0.4064)
			(stroke
				(width 0.1524)
				(type default)
			)
			(layer "F.SilkS")
		)
		(fp_line
			(start -0.67945 0.3048)
			(end -0.67945 -0.305054)
			(stroke
				(width 0.1)
				(type default)
			)
			(layer "F.Fab")
		)
		(fp_line
			(start -0.12065 0.3048)
			(end -0.67945 0.3048)
			(stroke
				(width 0.1)
				(type default)
			)
			(layer "F.Fab")
		)
		(fp_line
			(start 0.120396 0.3048)
			(end 0.120396 0.2794)
			(stroke
				(width 0.1)
				(type default)
			)
			(layer "F.Fab")
		)
		(fp_line
			(start 0.67945 0.3048)
			(end 0.120396 0.3048)
			(stroke
				(width 0.1)
				(type default)
			)
			(layer "F.Fab")
		)
		(fp_line
			(start -0.12065 0.2794)
			(end -0.12065 0.3048)
			(stroke
				(width 0.1)
				(type default)
			)
			(layer "F.Fab")
		)
		(fp_line
			(start 0.120396 0.2794)
			(end -0.12065 0.2794)
			(stroke
				(width 0.1)
				(type default)
			)
			(layer "F.Fab")
		)
		(fp_line
			(start -0.12065 -0.2794)
			(end 0.12065 -0.2794)
			(stroke
				(width 0.1)
				(type default)
			)
			(layer "F.Fab")
		)
		(fp_line
			(start 0.12065 -0.2794)
			(end 0.12065 -0.3048)
			(stroke
				(width 0.1)
				(type default)
			)
			(layer "F.Fab")
		)
		(fp_line
			(start 0.12065 -0.3048)
			(end 0.67945 -0.3048)
			(stroke
				(width 0.1)
				(type default)
			)
			(layer "F.Fab")
		)
		(fp_line
			(start 0.67945 -0.3048)
			(end 0.67945 0.3048)
			(stroke
				(width 0.1)
				(type default)
			)
			(layer "F.Fab")
		)
		(fp_line
			(start -0.67945 -0.305054)
			(end -0.12065 -0.305054)
			(stroke
				(width 0.1)
				(type default)
			)
			(layer "F.Fab")
		)
		(fp_line
			(start -0.12065 -0.305054)
			(end -0.12065 -0.2794)
			(stroke
				(width 0.1)
				(type default)
			)
			(layer "F.Fab")
		)
		(pad "1" smd circle
			(at -0.40005 0 270)
			(size 0 0)
			(layers "F.Cu" "F.Mask" "F.Paste")
			(net "P3V3_AUX")
		)
		(pad "2" smd circle
			(at 0.40005 0 270)
			(size 0 0)
			(layers "F.Cu" "F.Mask" "F.Paste")
			(net "RST_BIC_EXTRST_R_N")
		)
	)
	(footprint ""
		(layer "F.Cu")
		(at 325.925942 -125.530864)
		(property "Reference" "PC487"
			(at 0 0 0)
			(layer "F.SilkS")
			(hide yes)
			(effects
				(font
					(size 1.27 1.27)
				)
			)
		)
		(property "Value" ""
			(at 0 0 0)
			(layer "F.Fab")
			(effects
				(font
					(size 1.27 1.27)
				)
			)
		)
		(duplicate_pad_numbers_are_jumpers no)
		(fp_line
			(start -1.524 -0.762)
			(end 1.524 -0.762)
			(stroke
				(width 0.1524)
				(type default)
			)
			(layer "F.SilkS")
		)
		(fp_line
			(start -1.524 0.762)
			(end -1.524 -0.762)
			(stroke
				(width 0.1524)
				(type default)
			)
			(layer "F.SilkS")
		)
		(fp_line
			(start 1.524 -0.762)
			(end 1.524 0.762)
			(stroke
				(width 0.1524)
				(type default)
			)
			(layer "F.SilkS")
		)
		(fp_line
			(start 1.524 0.762)
			(end -1.524 0.762)
			(stroke
				(width 0.1524)
				(type default)
			)
			(layer "F.SilkS")
		)
		(fp_line
			(start -1.1049 -0.724916)
			(end -1.1049 0.724916)
			(stroke
				(width 0.1)
				(type default)
			)
			(layer "F.Fab")
		)
		(fp_line
			(start -1.1049 0.724916)
			(end 1.1049 0.724916)
			(stroke
				(width 0.1)
				(type default)
			)
			(layer "F.Fab")
		)
		(fp_line
			(start 1.1049 -0.724916)
			(end -1.1049 -0.724916)
			(stroke
				(width 0.1)
				(type default)
			)
			(layer "F.Fab")
		)
		(fp_line
			(start 1.1049 0.724916)
			(end 1.1049 -0.724916)
			(stroke
				(width 0.1)
				(type default)
			)
			(layer "F.Fab")
		)
		(pad "1" smd rect
			(at -0.889 0 180)
			(size 1.016 1.27)
			(layers "F.Cu" "F.Mask" "F.Paste")
			(net "GND")
		)
		(pad "2" smd rect
			(at 0.889 0 180)
			(size 1.016 1.27)
			(layers "F.Cu" "F.Mask" "F.Paste")
			(net "P3V3_AUX")
		)
	)
	(footprint ""
		(layer "F.Cu")
		(at 219.626434 -368.957606 180)
		(property "Reference" "PU2"
			(at 3.927094 3.71983 0)
			(unlocked yes)
			(layer "F.SilkS")
			(effects
				(font
					(size 0.7874 0.5842)
					(thickness 0.1524)
				)
			)
		)
		(property "Value" ""
			(at 0 0 180)
			(layer "F.Fab")
			(effects
				(font
					(size 1.27 1.27)
				)
			)
		)
		(duplicate_pad_numbers_are_jumpers no)
		(fp_line
			(start 2.567686 2.567686)
			(end 2.567686 -2.567686)
			(stroke
				(width 0.1524)
				(type default)
			)
			(layer "F.SilkS")
		)
		(fp_line
			(start 2.567686 -2.567686)
			(end -2.567686 -2.567686)
			(stroke
				(width 0.1524)
				(type default)
			)
			(layer "F.SilkS")
		)
		(fp_line
			(start -2.567686 2.567686)
			(end 2.567686 2.567686)
			(stroke
				(width 0.1524)
				(type default)
			)
			(layer "F.SilkS")
		)
		(fp_line
			(start -2.567686 -2.567686)
			(end -2.567686 2.567686)
			(stroke
				(width 0.1524)
				(type default)
			)
			(layer "F.SilkS")
		)
		(fp_poly
			(pts
				(xy -3.02768 -3.181096) (xy -3.745992 -2.462784) (xy -2.668524 -2.103374)
			)
			(stroke
				(width 0)
				(type default)
			)
			(fill yes)
			(layer "F.SilkS")
		)
		(fp_line
			(start 2.549906 2.549906)
			(end 2.549906 -2.549906)
			(stroke
				(width 0.1)
				(type default)
			)
			(layer "F.Fab")
		)
		(fp_line
			(start 2.549906 -2.549906)
			(end -2.549906 -2.549906)
			(stroke
				(width 0.1)
				(type default)
			)
			(layer "F.Fab")
		)
		(fp_line
			(start -2.549906 2.549906)
			(end 2.549906 2.549906)
			(stroke
				(width 0.1)
				(type default)
			)
			(layer "F.Fab")
		)
		(fp_line
			(start -2.549906 -2.549906)
			(end -2.549906 2.549906)
			(stroke
				(width 0.1)
				(type default)
			)
			(layer "F.Fab")
		)
		(fp_poly
			(pts
				(xy -3.806698 -2.25806) (xy -3.806698 -1.24206) (xy -2.790698 -1.75006)
			)
			(stroke
				(width 0)
				(type default)
			)
			(fill yes)
			(layer "F.Fab")
		)
		(pad "1" smd rect
			(at -2.250186 -1.75006 270)
			(size 0.254 0.3556)
			(layers "F.Cu" "F.Mask" "F.Paste")
			(net "P12V_AUX")
		)
		(pad "2" smd rect
			(at -2.237486 -1.249934 270)
			(size 0.254 0.381)
			(layers "F.Cu" "F.Mask" "F.Paste")
			(net "P12V_AUX")
		)
		(pad "3" smd rect
			(at -2.237486 -0.750062 270)
			(size 0.254 0.381)
			(layers "F.Cu" "F.Mask" "F.Paste")
			(net "HSC_D_OC_1")
		)
		(pad "4" smd rect
			(at -2.237486 -0.249936 270)
			(size 0.254 0.381)
			(layers "F.Cu" "F.Mask" "F.Paste")
			(net "HSC_ON")
		)
		(pad "5" smd rect
			(at -2.237486 0.249936 270)
			(size 0.254 0.381)
			(layers "F.Cu" "F.Mask" "F.Paste")
			(net "HSC_FAULT_N_1")
		)
		(pad "6" smd rect
			(at -2.237486 0.750062 270)
			(size 0.254 0.381)
			(layers "F.Cu" "F.Mask" "F.Paste")
			(net "HSC_FLT_TYPE_1")
		)
		(pad "7" smd rect
			(at -2.237486 1.249934 270)
			(size 0.254 0.381)
			(layers "F.Cu" "F.Mask" "F.Paste")
			(net "Net_9084")
		)
		(pad "8" smd rect
			(at -2.250186 1.75006 270)
			(size 0.254 0.3556)
			(layers "F.Cu" "F.Mask" "F.Paste")
			(net "HSC_MODE_1")
		)
		(pad "9" smd rect
			(at -1.75006 2.250186 180)
			(size 0.254 0.3556)
			(layers "F.Cu" "F.Mask" "F.Paste")
			(net "P12V_STBY")
		)
		(pad "10" smd rect
			(at -1.249934 2.237486 180)
			(size 0.254 0.381)
			(layers "F.Cu" "F.Mask" "F.Paste")
			(net "P12V_STBY")
		)
		(pad "11" smd rect
			(at -0.750062 2.237486 180)
			(size 0.254 0.381)
			(layers "F.Cu" "F.Mask" "F.Paste")
			(net "P12V_STBY")
		)
		(pad "12" smd rect
			(at -0.249936 2.237486 180)
			(size 0.254 0.381)
			(layers "F.Cu" "F.Mask" "F.Paste")
			(net "P12V_STBY")
		)
		(pad "13" smd rect
			(at 0.249936 2.237486 180)
			(size 0.254 0.381)
			(layers "F.Cu" "F.Mask" "F.Paste")
			(net "P12V_STBY")
		)
		(pad "14" smd rect
			(at 0.750062 2.237486 180)
			(size 0.254 0.381)
			(layers "F.Cu" "F.Mask" "F.Paste")
			(net "P12V_STBY")
		)
		(pad "15" smd rect
			(at 1.249934 2.237486 180)
			(size 0.254 0.381)
			(layers "F.Cu" "F.Mask" "F.Paste")
			(net "P12V_STBY")
		)
		(pad "16" smd rect
			(at 1.75006 2.250186 180)
			(size 0.254 0.3556)
			(layers "F.Cu" "F.Mask" "F.Paste")
			(net "P12V_STBY")
		)
		(pad "17" smd rect
			(at 2.250186 1.75006 270)
			(size 0.254 0.3556)
			(layers "F.Cu" "F.Mask" "F.Paste")
			(net "HSC_SCREF_1")
		)
		(pad "18" smd rect
			(at 2.237486 1.249934 270)
			(size 0.254 0.381)
			(layers "F.Cu" "F.Mask" "F.Paste")
			(net "HSC_VTEMP")
		)
		(pad "19" smd rect
			(at 2.237486 0.750062 270)
			(size 0.254 0.381)
			(layers "F.Cu" "F.Mask" "F.Paste")
			(net "HSC_SS")
		)
		(pad "20" smd rect
			(at 2.237486 0.249936 270)
			(size 0.254 0.381)
			(layers "F.Cu" "F.Mask" "F.Paste")
			(net "AGND_HSC")
		)
		(pad "21" smd rect
			(at 2.237486 -0.249936 270)
			(size 0.254 0.381)
			(layers "F.Cu" "F.Mask" "F.Paste")
			(net "HSC_VDD_1")
		)
		(pad "22" smd rect
			(at 2.237486 -0.750062 270)
			(size 0.254 0.381)
			(layers "F.Cu" "F.Mask" "F.Paste")
			(net "HSC_IMON")
		)
		(pad "23" smd rect
			(at 2.237486 -1.249934 270)
			(size 0.254 0.381)
			(layers "F.Cu" "F.Mask" "F.Paste")
			(net "HSC_CS_1")
		)
		(pad "24" smd rect
			(at 2.250186 -1.75006 270)
			(size 0.254 0.3556)
			(layers "F.Cu" "F.Mask" "F.Paste")
			(net "HSC_OCREF")
		)
		(pad "25" smd rect
			(at 1.75006 -2.250186 180)
			(size 0.254 0.3556)
			(layers "F.Cu" "F.Mask" "F.Paste")
			(net "P12V_AUX")
		)
		(pad "26" smd rect
			(at 1.249934 -2.237486 180)
			(size 0.254 0.381)
			(layers "F.Cu" "F.Mask" "F.Paste")
			(net "P12V_AUX")
		)
		(pad "27" smd rect
			(at 0.750062 -2.237486 180)
			(size 0.254 0.381)
			(layers "F.Cu" "F.Mask" "F.Paste")
			(net "P12V_AUX")
		)
		(pad "28" smd rect
			(at 0.249936 -2.237486 180)
			(size 0.254 0.381)
			(layers "F.Cu" "F.Mask" "F.Paste")
			(net "P12V_AUX")
		)
		(pad "29" smd rect
			(at -0.249936 -2.237486 180)
			(size 0.254 0.381)
			(layers "F.Cu" "F.Mask" "F.Paste")
			(net "P12V_AUX")
		)
		(pad "30" smd rect
			(at -0.750062 -2.237486 180)
			(size 0.254 0.381)
			(layers "F.Cu" "F.Mask" "F.Paste")
			(net "P12V_AUX")
		)
		(pad "31" smd rect
			(at -1.249934 -2.237486 180)
			(size 0.254 0.381)
			(layers "F.Cu" "F.Mask" "F.Paste")
			(net "P12V_AUX")
		)
		(pad "32" smd rect
			(at -1.75006 -2.250186 180)
			(size 0.254 0.3556)
			(layers "F.Cu" "F.Mask" "F.Paste")
			(net "P12V_AUX")
		)
		(pad "33" smd rect
			(at 0 0 180)
			(size 3.4036 3.4036)
			(layers "F.Cu" "F.Mask" "F.Paste")
			(net "P12V_STBY")
		)
	)
	(footprint ""
		(layer "F.Cu")
		(at 226.331272 -254.18542 -90)
		(property "Reference" "C4297"
			(at 0 0 270)
			(layer "F.SilkS")
			(hide yes)
			(effects
				(font
					(size 1.27 1.27)
				)
			)
		)
		(property "Value" ""
			(at 0 0 270)
			(layer "F.Fab")
			(effects
				(font
					(size 1.27 1.27)
				)
			)
		)
		(duplicate_pad_numbers_are_jumpers no)
		(fp_line
			(start -1.2954 0.5842)
			(end -1.2954 -0.5842)
			(stroke
				(width 0.1524)
				(type default)
			)
			(layer "F.SilkS")
		)
		(fp_line
			(start 1.2954 0.5842)
			(end -1.2954 0.5842)
			(stroke
				(width 0.1524)
				(type default)
			)
			(layer "F.SilkS")
		)
		(fp_line
			(start -1.2954 -0.5842)
			(end 1.2954 -0.5842)
			(stroke
				(width 0.1524)
				(type default)
			)
			(layer "F.SilkS")
		)
		(fp_line
			(start 1.2954 -0.5842)
			(end 1.2954 0.5842)
			(stroke
				(width 0.1524)
				(type default)
			)
			(layer "F.SilkS")
		)
		(fp_line
			(start -0.8636 0.4572)
			(end -0.8636 0.4064)
			(stroke
				(width 0.1)
				(type default)
			)
			(layer "F.Fab")
		)
		(fp_line
			(start 0.8636 0.4572)
			(end -0.8636 0.4572)
			(stroke
				(width 0.1)
				(type default)
			)
			(layer "F.Fab")
		)
		(fp_line
			(start -1.1938 0.4064)
			(end -1.1938 -0.4064)
			(stroke
				(width 0.1)
				(type default)
			)
			(layer "F.Fab")
		)
		(fp_line
			(start -0.8636 0.4064)
			(end -1.1938 0.4064)
			(stroke
				(width 0.1)
				(type default)
			)
			(layer "F.Fab")
		)
		(fp_line
			(start 0.8636 0.4064)
			(end 0.8636 0.4572)
			(stroke
				(width 0.1)
				(type default)
			)
			(layer "F.Fab")
		)
		(fp_line
			(start 1.1938 0.4064)
			(end 0.8636 0.4064)
			(stroke
				(width 0.1)
				(type default)
			)
			(layer "F.Fab")
		)
		(fp_line
			(start -1.1938 -0.4064)
			(end -0.8636 -0.4064)
			(stroke
				(width 0.1)
				(type default)
			)
			(layer "F.Fab")
		)
		(fp_line
			(start -0.8636 -0.4064)
			(end -0.8636 -0.4572)
			(stroke
				(width 0.1)
				(type default)
			)
			(layer "F.Fab")
		)
		(fp_line
			(start 0.8636 -0.4064)
			(end 1.1938 -0.4064)
			(stroke
				(width 0.1)
				(type default)
			)
			(layer "F.Fab")
		)
		(fp_line
			(start 1.1938 -0.4064)
			(end 1.1938 0.4064)
			(stroke
				(width 0.1)
				(type default)
			)
			(layer "F.Fab")
		)
		(fp_line
			(start -0.8636 -0.4572)
			(end 0.8636 -0.4572)
			(stroke
				(width 0.1)
				(type default)
			)
			(layer "F.Fab")
		)
		(fp_line
			(start 0.8636 -0.4572)
			(end 0.8636 -0.4064)
			(stroke
				(width 0.1)
				(type default)
			)
			(layer "F.Fab")
		)
		(pad "1" smd rect
			(at -0.7366 0 180)
			(size 0.7112 0.8128)
			(layers "F.Cu" "F.Mask" "F.Paste")
			(net "P1V25_SERDES_VDDPLL_PEX1_C7")
		)
		(pad "2" smd rect
			(at 0.7366 0 180)
			(size 0.7112 0.8128)
			(layers "F.Cu" "F.Mask" "F.Paste")
			(net "GND")
		)
	)
	(footprint ""
		(layer "F.Cu")
		(at 450.19595 -113.547398 90)
		(property "Reference" "PR7049"
			(at 0 0 90)
			(layer "F.SilkS")
			(hide yes)
			(effects
				(font
					(size 1.27 1.27)
				)
			)
		)
		(property "Value" ""
			(at 0 0 90)
			(layer "F.Fab")
			(effects
				(font
					(size 1.27 1.27)
				)
			)
		)
		(duplicate_pad_numbers_are_jumpers no)
		(fp_line
			(start 0.7874 -0.4064)
			(end 0.7874 0.4064)
			(stroke
				(width 0.1524)
				(type default)
			)
			(layer "F.SilkS")
		)
		(fp_line
			(start -0.7874 -0.4064)
			(end 0.7874 -0.4064)
			(stroke
				(width 0.1524)
				(type default)
			)
			(layer "F.SilkS")
		)
		(fp_line
			(start 0.7874 0.4064)
			(end -0.7874 0.4064)
			(stroke
				(width 0.1524)
				(type default)
			)
			(layer "F.SilkS")
		)
		(fp_line
			(start -0.7874 0.4064)
			(end -0.7874 -0.4064)
			(stroke
				(width 0.1524)
				(type default)
			)
			(layer "F.SilkS")
		)
		(fp_line
			(start -0.12065 -0.305054)
			(end -0.12065 -0.2794)
			(stroke
				(width 0.1)
				(type default)
			)
			(layer "F.Fab")
		)
		(fp_line
			(start -0.67945 -0.305054)
			(end -0.12065 -0.305054)
			(stroke
				(width 0.1)
				(type default)
			)
			(layer "F.Fab")
		)
		(fp_line
			(start 0.67945 -0.3048)
			(end 0.67945 0.3048)
			(stroke
				(width 0.1)
				(type default)
			)
			(layer "F.Fab")
		)
		(fp_line
			(start 0.12065 -0.3048)
			(end 0.67945 -0.3048)
			(stroke
				(width 0.1)
				(type default)
			)
			(layer "F.Fab")
		)
		(fp_line
			(start 0.12065 -0.2794)
			(end 0.12065 -0.3048)
			(stroke
				(width 0.1)
				(type default)
			)
			(layer "F.Fab")
		)
		(fp_line
			(start -0.12065 -0.2794)
			(end 0.12065 -0.2794)
			(stroke
				(width 0.1)
				(type default)
			)
			(layer "F.Fab")
		)
		(fp_line
			(start 0.120396 0.2794)
			(end -0.12065 0.2794)
			(stroke
				(width 0.1)
				(type default)
			)
			(layer "F.Fab")
		)
		(fp_line
			(start -0.12065 0.2794)
			(end -0.12065 0.3048)
			(stroke
				(width 0.1)
				(type default)
			)
			(layer "F.Fab")
		)
		(fp_line
			(start 0.67945 0.3048)
			(end 0.120396 0.3048)
			(stroke
				(width 0.1)
				(type default)
			)
			(layer "F.Fab")
		)
		(fp_line
			(start 0.120396 0.3048)
			(end 0.120396 0.2794)
			(stroke
				(width 0.1)
				(type default)
			)
			(layer "F.Fab")
		)
		(fp_line
			(start -0.12065 0.3048)
			(end -0.67945 0.3048)
			(stroke
				(width 0.1)
				(type default)
			)
			(layer "F.Fab")
		)
		(fp_line
			(start -0.67945 0.3048)
			(end -0.67945 -0.305054)
			(stroke
				(width 0.1)
				(type default)
			)
			(layer "F.Fab")
		)
		(pad "1" smd circle
			(at -0.40005 0 90)
			(size 0 0)
			(layers "F.Cu" "F.Mask" "F.Paste")
			(net "P12V_NIC7_R")
		)
		(pad "2" smd circle
			(at 0.40005 0 90)
			(size 0 0)
			(layers "F.Cu" "F.Mask" "F.Paste")
			(net "P12V_NIC7_CO_AVIN_PD")
		)
	)
	(footprint ""
		(layer "F.Cu")
		(at 258.170426 -243.540788 180)
		(property "Reference" "R6578"
			(at 0 0 180)
			(layer "F.SilkS")
			(hide yes)
			(effects
				(font
					(size 1.27 1.27)
				)
			)
		)
		(property "Value" ""
			(at 0 0 180)
			(layer "F.Fab")
			(effects
				(font
					(size 1.27 1.27)
				)
			)
		)
		(duplicate_pad_numbers_are_jumpers no)
		(fp_line
			(start 0.7874 0.4064)
			(end -0.7874 0.4064)
			(stroke
				(width 0.1524)
				(type default)
			)
			(layer "F.SilkS")
		)
		(fp_line
			(start 0.7874 -0.4064)
			(end 0.7874 0.4064)
			(stroke
				(width 0.1524)
				(type default)
			)
			(layer "F.SilkS")
		)
		(fp_line
			(start -0.7874 0.4064)
			(end -0.7874 -0.4064)
			(stroke
				(width 0.1524)
				(type default)
			)
			(layer "F.SilkS")
		)
		(fp_line
			(start -0.7874 -0.4064)
			(end 0.7874 -0.4064)
			(stroke
				(width 0.1524)
				(type default)
			)
			(layer "F.SilkS")
		)
		(fp_line
			(start 0.67945 0.3048)
			(end 0.120396 0.3048)
			(stroke
				(width 0.1)
				(type default)
			)
			(layer "F.Fab")
		)
		(fp_line
			(start 0.67945 -0.3048)
			(end 0.67945 0.3048)
			(stroke
				(width 0.1)
				(type default)
			)
			(layer "F.Fab")
		)
		(fp_line
			(start 0.12065 -0.2794)
			(end 0.12065 -0.3048)
			(stroke
				(width 0.1)
				(type default)
			)
			(layer "F.Fab")
		)
		(fp_line
			(start 0.12065 -0.3048)
			(end 0.67945 -0.3048)
			(stroke
				(width 0.1)
				(type default)
			)
			(layer "F.Fab")
		)
		(fp_line
			(start 0.120396 0.3048)
			(end 0.120396 0.2794)
			(stroke
				(width 0.1)
				(type default)
			)
			(layer "F.Fab")
		)
		(fp_line
			(start 0.120396 0.2794)
			(end -0.12065 0.2794)
			(stroke
				(width 0.1)
				(type default)
			)
			(layer "F.Fab")
		)
		(fp_line
			(start -0.12065 0.3048)
			(end -0.67945 0.3048)
			(stroke
				(width 0.1)
				(type default)
			)
			(layer "F.Fab")
		)
		(fp_line
			(start -0.12065 0.2794)
			(end -0.12065 0.3048)
			(stroke
				(width 0.1)
				(type default)
			)
			(layer "F.Fab")
		)
		(fp_line
			(start -0.12065 -0.2794)
			(end 0.12065 -0.2794)
			(stroke
				(width 0.1)
				(type default)
			)
			(layer "F.Fab")
		)
		(fp_line
			(start -0.12065 -0.305054)
			(end -0.12065 -0.2794)
			(stroke
				(width 0.1)
				(type default)
			)
			(layer "F.Fab")
		)
		(fp_line
			(start -0.67945 0.3048)
			(end -0.67945 -0.305054)
			(stroke
				(width 0.1)
				(type default)
			)
			(layer "F.Fab")
		)
		(fp_line
			(start -0.67945 -0.305054)
			(end -0.12065 -0.305054)
			(stroke
				(width 0.1)
				(type default)
			)
			(layer "F.Fab")
		)
		(pad "1" smd circle
			(at -0.40005 0 180)
			(size 0 0)
			(layers "F.Cu" "F.Mask" "F.Paste")
			(net "PWR_EN_PEX_R")
		)
		(pad "2" smd circle
			(at 0.40005 0 180)
			(size 0 0)
			(layers "F.Cu" "F.Mask" "F.Paste")
			(net "PEX2_P1V8_PLL_EN")
		)
	)
	(footprint ""
		(layer "F.Cu")
		(at 357.619808 -162.003994 90)
		(property "Reference" "PR7057"
			(at 0 0 90)
			(layer "F.SilkS")
			(hide yes)
			(effects
				(font
					(size 1.27 1.27)
				)
			)
		)
		(property "Value" ""
			(at 0 0 90)
			(layer "F.Fab")
			(effects
				(font
					(size 1.27 1.27)
				)
			)
		)
		(duplicate_pad_numbers_are_jumpers no)
		(fp_line
			(start 0.7874 -0.4064)
			(end 0.7874 0.4064)
			(stroke
				(width 0.1524)
				(type default)
			)
			(layer "F.SilkS")
		)
		(fp_line
			(start -0.7874 -0.4064)
			(end 0.7874 -0.4064)
			(stroke
				(width 0.1524)
				(type default)
			)
			(layer "F.SilkS")
		)
		(fp_line
			(start 0.7874 0.4064)
			(end -0.7874 0.4064)
			(stroke
				(width 0.1524)
				(type default)
			)
			(layer "F.SilkS")
		)
		(fp_line
			(start -0.7874 0.4064)
			(end -0.7874 -0.4064)
			(stroke
				(width 0.1524)
				(type default)
			)
			(layer "F.SilkS")
		)
		(fp_line
			(start -0.12065 -0.305054)
			(end -0.12065 -0.2794)
			(stroke
				(width 0.1)
				(type default)
			)
			(layer "F.Fab")
		)
		(fp_line
			(start -0.67945 -0.305054)
			(end -0.12065 -0.305054)
			(stroke
				(width 0.1)
				(type default)
			)
			(layer "F.Fab")
		)
		(fp_line
			(start 0.67945 -0.3048)
			(end 0.67945 0.3048)
			(stroke
				(width 0.1)
				(type default)
			)
			(layer "F.Fab")
		)
		(fp_line
			(start 0.12065 -0.3048)
			(end 0.67945 -0.3048)
			(stroke
				(width 0.1)
				(type default)
			)
			(layer "F.Fab")
		)
		(fp_line
			(start 0.12065 -0.2794)
			(end 0.12065 -0.3048)
			(stroke
				(width 0.1)
				(type default)
			)
			(layer "F.Fab")
		)
		(fp_line
			(start -0.12065 -0.2794)
			(end 0.12065 -0.2794)
			(stroke
				(width 0.1)
				(type default)
			)
			(layer "F.Fab")
		)
		(fp_line
			(start 0.120396 0.2794)
			(end -0.12065 0.2794)
			(stroke
				(width 0.1)
				(type default)
			)
			(layer "F.Fab")
		)
		(fp_line
			(start -0.12065 0.2794)
			(end -0.12065 0.3048)
			(stroke
				(width 0.1)
				(type default)
			)
			(layer "F.Fab")
		)
		(fp_line
			(start 0.67945 0.3048)
			(end 0.120396 0.3048)
			(stroke
				(width 0.1)
				(type default)
			)
			(layer "F.Fab")
		)
		(fp_line
			(start 0.120396 0.3048)
			(end 0.120396 0.2794)
			(stroke
				(width 0.1)
				(type default)
			)
			(layer "F.Fab")
		)
		(fp_line
			(start -0.12065 0.3048)
			(end -0.67945 0.3048)
			(stroke
				(width 0.1)
				(type default)
			)
			(layer "F.Fab")
		)
		(fp_line
			(start -0.67945 0.3048)
			(end -0.67945 -0.305054)
			(stroke
				(width 0.1)
				(type default)
			)
			(layer "F.Fab")
		)
		(pad "1" smd circle
			(at -0.40005 0 90)
			(size 0 0)
			(layers "F.Cu" "F.Mask" "F.Paste")
			(net "P12V_NIC6_CO_IMON_VR")
		)
		(pad "2" smd circle
			(at 0.40005 0 90)
			(size 0 0)
			(layers "F.Cu" "F.Mask" "F.Paste")
			(net "GND")
		)
	)
	(footprint ""
		(layer "F.Cu")
		(at 426.543724 -48.93691 180)
		(property "Reference" "R666"
			(at 0 0 180)
			(layer "F.SilkS")
			(hide yes)
			(effects
				(font
					(size 1.27 1.27)
				)
			)
		)
		(property "Value" ""
			(at 0 0 180)
			(layer "F.Fab")
			(effects
				(font
					(size 1.27 1.27)
				)
			)
		)
		(duplicate_pad_numbers_are_jumpers no)
		(fp_line
			(start 0.7874 0.4064)
			(end -0.7874 0.4064)
			(stroke
				(width 0.1524)
				(type default)
			)
			(layer "F.SilkS")
		)
		(fp_line
			(start 0.7874 -0.4064)
			(end 0.7874 0.4064)
			(stroke
				(width 0.1524)
				(type default)
			)
			(layer "F.SilkS")
		)
		(fp_line
			(start -0.7874 0.4064)
			(end -0.7874 -0.4064)
			(stroke
				(width 0.1524)
				(type default)
			)
			(layer "F.SilkS")
		)
		(fp_line
			(start -0.7874 -0.4064)
			(end 0.7874 -0.4064)
			(stroke
				(width 0.1524)
				(type default)
			)
			(layer "F.SilkS")
		)
		(fp_line
			(start 0.67945 0.3048)
			(end 0.120396 0.3048)
			(stroke
				(width 0.1)
				(type default)
			)
			(layer "F.Fab")
		)
		(fp_line
			(start 0.67945 -0.3048)
			(end 0.67945 0.3048)
			(stroke
				(width 0.1)
				(type default)
			)
			(layer "F.Fab")
		)
		(fp_line
			(start 0.12065 -0.2794)
			(end 0.12065 -0.3048)
			(stroke
				(width 0.1)
				(type default)
			)
			(layer "F.Fab")
		)
		(fp_line
			(start 0.12065 -0.3048)
			(end 0.67945 -0.3048)
			(stroke
				(width 0.1)
				(type default)
			)
			(layer "F.Fab")
		)
		(fp_line
			(start 0.120396 0.3048)
			(end 0.120396 0.2794)
			(stroke
				(width 0.1)
				(type default)
			)
			(layer "F.Fab")
		)
		(fp_line
			(start 0.120396 0.2794)
			(end -0.12065 0.2794)
			(stroke
				(width 0.1)
				(type default)
			)
			(layer "F.Fab")
		)
		(fp_line
			(start -0.12065 0.3048)
			(end -0.67945 0.3048)
			(stroke
				(width 0.1)
				(type default)
			)
			(layer "F.Fab")
		)
		(fp_line
			(start -0.12065 0.2794)
			(end -0.12065 0.3048)
			(stroke
				(width 0.1)
				(type default)
			)
			(layer "F.Fab")
		)
		(fp_line
			(start -0.12065 -0.2794)
			(end 0.12065 -0.2794)
			(stroke
				(width 0.1)
				(type default)
			)
			(layer "F.Fab")
		)
		(fp_line
			(start -0.12065 -0.305054)
			(end -0.12065 -0.2794)
			(stroke
				(width 0.1)
				(type default)
			)
			(layer "F.Fab")
		)
		(fp_line
			(start -0.67945 0.3048)
			(end -0.67945 -0.305054)
			(stroke
				(width 0.1)
				(type default)
			)
			(layer "F.Fab")
		)
		(fp_line
			(start -0.67945 -0.305054)
			(end -0.12065 -0.305054)
			(stroke
				(width 0.1)
				(type default)
			)
			(layer "F.Fab")
		)
		(pad "1" smd circle
			(at -0.40005 0 180)
			(size 0 0)
			(layers "F.Cu" "F.Mask" "F.Paste")
			(net "SMB_BIC_I2C6_MUX_SSD_8_15_ADC_R_SDA")
		)
		(pad "2" smd circle
			(at 0.40005 0 180)
			(size 0 0)
			(layers "F.Cu" "F.Mask" "F.Paste")
			(net "SMB_SSD14_ADC_SDA")
		)
	)
	(footprint ""
		(layer "F.Cu")
		(at 99.35718 -219.559632)
		(property "Reference" "R850"
			(at 0 0 0)
			(layer "F.SilkS")
			(hide yes)
			(effects
				(font
					(size 1.27 1.27)
				)
			)
		)
		(property "Value" ""
			(at 0 0 0)
			(layer "F.Fab")
			(effects
				(font
					(size 1.27 1.27)
				)
			)
		)
		(duplicate_pad_numbers_are_jumpers no)
		(fp_line
			(start -0.7874 -0.4064)
			(end 0.7874 -0.4064)
			(stroke
				(width 0.1524)
				(type default)
			)
			(layer "F.SilkS")
		)
		(fp_line
			(start -0.7874 0.4064)
			(end -0.7874 -0.4064)
			(stroke
				(width 0.1524)
				(type default)
			)
			(layer "F.SilkS")
		)
		(fp_line
			(start 0.7874 -0.4064)
			(end 0.7874 0.4064)
			(stroke
				(width 0.1524)
				(type default)
			)
			(layer "F.SilkS")
		)
		(fp_line
			(start 0.7874 0.4064)
			(end -0.7874 0.4064)
			(stroke
				(width 0.1524)
				(type default)
			)
			(layer "F.SilkS")
		)
		(fp_line
			(start -0.67945 -0.305054)
			(end -0.12065 -0.305054)
			(stroke
				(width 0.1)
				(type default)
			)
			(layer "F.Fab")
		)
		(fp_line
			(start -0.67945 0.3048)
			(end -0.67945 -0.305054)
			(stroke
				(width 0.1)
				(type default)
			)
			(layer "F.Fab")
		)
		(fp_line
			(start -0.12065 -0.305054)
			(end -0.12065 -0.2794)
			(stroke
				(width 0.1)
				(type default)
			)
			(layer "F.Fab")
		)
		(fp_line
			(start -0.12065 -0.2794)
			(end 0.12065 -0.2794)
			(stroke
				(width 0.1)
				(type default)
			)
			(layer "F.Fab")
		)
		(fp_line
			(start -0.12065 0.2794)
			(end -0.12065 0.3048)
			(stroke
				(width 0.1)
				(type default)
			)
			(layer "F.Fab")
		)
		(fp_line
			(start -0.12065 0.3048)
			(end -0.67945 0.3048)
			(stroke
				(width 0.1)
				(type default)
			)
			(layer "F.Fab")
		)
		(fp_line
			(start 0.120396 0.2794)
			(end -0.12065 0.2794)
			(stroke
				(width 0.1)
				(type default)
			)
			(layer "F.Fab")
		)
		(fp_line
			(start 0.120396 0.3048)
			(end 0.120396 0.2794)
			(stroke
				(width 0.1)
				(type default)
			)
			(layer "F.Fab")
		)
		(fp_line
			(start 0.12065 -0.3048)
			(end 0.67945 -0.3048)
			(stroke
				(width 0.1)
				(type default)
			)
			(layer "F.Fab")
		)
		(fp_line
			(start 0.12065 -0.2794)
			(end 0.12065 -0.3048)
			(stroke
				(width 0.1)
				(type default)
			)
			(layer "F.Fab")
		)
		(fp_line
			(start 0.67945 -0.3048)
			(end 0.67945 0.3048)
			(stroke
				(width 0.1)
				(type default)
			)
			(layer "F.Fab")
		)
		(fp_line
			(start 0.67945 0.3048)
			(end 0.120396 0.3048)
			(stroke
				(width 0.1)
				(type default)
			)
			(layer "F.Fab")
		)
		(pad "1" smd circle
			(at -0.40005 0)
			(size 0 0)
			(layers "F.Cu" "F.Mask" "F.Paste")
			(net "P3V3_AUX")
		)
		(pad "2" smd circle
			(at 0.40005 0)
			(size 0 0)
			(layers "F.Cu" "F.Mask" "F.Paste")
			(net "PWR_EN_PEX_R")
		)
	)
	(footprint ""
		(layer "F.Cu")
		(at 10.04316 -45.111924)
		(property "Reference" "R5541"
			(at 0 0 0)
			(layer "F.SilkS")
			(hide yes)
			(effects
				(font
					(size 1.27 1.27)
				)
			)
		)
		(property "Value" ""
			(at 0 0 0)
			(layer "F.Fab")
			(effects
				(font
					(size 1.27 1.27)
				)
			)
		)
		(duplicate_pad_numbers_are_jumpers no)
		(fp_line
			(start -0.7874 -0.4064)
			(end 0.7874 -0.4064)
			(stroke
				(width 0.1524)
				(type default)
			)
			(layer "F.SilkS")
		)
		(fp_line
			(start -0.7874 0.4064)
			(end -0.7874 -0.4064)
			(stroke
				(width 0.1524)
				(type default)
			)
			(layer "F.SilkS")
		)
		(fp_line
			(start 0.7874 -0.4064)
			(end 0.7874 0.4064)
			(stroke
				(width 0.1524)
				(type default)
			)
			(layer "F.SilkS")
		)
		(fp_line
			(start 0.7874 0.4064)
			(end -0.7874 0.4064)
			(stroke
				(width 0.1524)
				(type default)
			)
			(layer "F.SilkS")
		)
		(fp_line
			(start -0.67945 -0.305054)
			(end -0.12065 -0.305054)
			(stroke
				(width 0.1)
				(type default)
			)
			(layer "F.Fab")
		)
		(fp_line
			(start -0.67945 0.3048)
			(end -0.67945 -0.305054)
			(stroke
				(width 0.1)
				(type default)
			)
			(layer "F.Fab")
		)
		(fp_line
			(start -0.12065 -0.305054)
			(end -0.12065 -0.2794)
			(stroke
				(width 0.1)
				(type default)
			)
			(layer "F.Fab")
		)
		(fp_line
			(start -0.12065 -0.2794)
			(end 0.12065 -0.2794)
			(stroke
				(width 0.1)
				(type default)
			)
			(layer "F.Fab")
		)
		(fp_line
			(start -0.12065 0.2794)
			(end -0.12065 0.3048)
			(stroke
				(width 0.1)
				(type default)
			)
			(layer "F.Fab")
		)
		(fp_line
			(start -0.12065 0.3048)
			(end -0.67945 0.3048)
			(stroke
				(width 0.1)
				(type default)
			)
			(layer "F.Fab")
		)
		(fp_line
			(start 0.120396 0.2794)
			(end -0.12065 0.2794)
			(stroke
				(width 0.1)
				(type default)
			)
			(layer "F.Fab")
		)
		(fp_line
			(start 0.120396 0.3048)
			(end 0.120396 0.2794)
			(stroke
				(width 0.1)
				(type default)
			)
			(layer "F.Fab")
		)
		(fp_line
			(start 0.12065 -0.3048)
			(end 0.67945 -0.3048)
			(stroke
				(width 0.1)
				(type default)
			)
			(layer "F.Fab")
		)
		(fp_line
			(start 0.12065 -0.2794)
			(end 0.12065 -0.3048)
			(stroke
				(width 0.1)
				(type default)
			)
			(layer "F.Fab")
		)
		(fp_line
			(start 0.67945 -0.3048)
			(end 0.67945 0.3048)
			(stroke
				(width 0.1)
				(type default)
			)
			(layer "F.Fab")
		)
		(fp_line
			(start 0.67945 0.3048)
			(end 0.120396 0.3048)
			(stroke
				(width 0.1)
				(type default)
			)
			(layer "F.Fab")
		)
		(pad "1" smd circle
			(at -0.40005 0)
			(size 0 0)
			(layers "F.Cu" "F.Mask" "F.Paste")
			(net "SSD0_AUX_P3V3_EN_R")
		)
		(pad "2" smd circle
			(at 0.40005 0)
			(size 0 0)
			(layers "F.Cu" "F.Mask" "F.Paste")
			(net "SSD0_AUX_P3V3_EN")
		)
	)
	(footprint ""
		(layer "F.Cu")
		(at 64.964818 -26.785062 180)
		(property "Reference" "J32"
			(at 4.986274 -10.940796 90)
			(unlocked yes)
			(layer "F.SilkS")
			(effects
				(font
					(size 0.7874 0.5842)
					(thickness 0.1524)
				)
			)
		)
		(property "Value" ""
			(at 0 0 180)
			(layer "F.Fab")
			(effects
				(font
					(size 1.27 1.27)
				)
			)
		)
		(duplicate_pad_numbers_are_jumpers no)
		(fp_line
			(start 3.150108 12.115038)
			(end 1.529334 12.115038)
			(stroke
				(width 0.1524)
				(type default)
			)
			(layer "F.SilkS")
		)
		(fp_line
			(start 3.074924 12.014962)
			(end 1.632204 12.014962)
			(stroke
				(width 0.1524)
				(type default)
			)
			(layer "F.SilkS")
		)
		(fp_line
			(start 1.632204 -12.014962)
			(end 3.074924 -12.014962)
			(stroke
				(width 0.1524)
				(type default)
			)
			(layer "F.SilkS")
		)
		(fp_line
			(start 1.529334 -12.115038)
			(end 3.150108 -12.115038)
			(stroke
				(width 0.1524)
				(type default)
			)
			(layer "F.SilkS")
		)
		(fp_line
			(start -1.529334 12.115038)
			(end -3.150108 12.115038)
			(stroke
				(width 0.1524)
				(type default)
			)
			(layer "F.SilkS")
		)
		(fp_line
			(start -1.632204 12.014962)
			(end -3.074924 12.014962)
			(stroke
				(width 0.1524)
				(type default)
			)
			(layer "F.SilkS")
		)
		(fp_line
			(start -3.074924 -12.014962)
			(end -1.632204 -12.014962)
			(stroke
				(width 0.1524)
				(type default)
			)
			(layer "F.SilkS")
		)
		(fp_line
			(start -3.150108 -12.115038)
			(end -1.529334 -12.115038)
			(stroke
				(width 0.1524)
				(type default)
			)
			(layer "F.SilkS")
		)
		(fp_poly
			(pts
				(xy 3.54711 -8.888476) (xy 3.969512 -10.15619) (xy 4.81457 -9.311132)
			)
			(stroke
				(width 0)
				(type default)
			)
			(fill yes)
			(layer "F.SilkS")
		)
		(fp_line
			(start 3.074924 12.014962)
			(end -3.074924 12.014962)
			(stroke
				(width 0.1)
				(type default)
			)
			(layer "F.Fab")
		)
		(fp_line
			(start 3.074924 -12.014962)
			(end 3.074924 12.014962)
			(stroke
				(width 0.1)
				(type default)
			)
			(layer "F.Fab")
		)
		(fp_line
			(start -3.074924 12.014962)
			(end -3.074924 -12.014962)
			(stroke
				(width 0.1)
				(type default)
			)
			(layer "F.Fab")
		)
		(fp_line
			(start -3.074924 -12.014962)
			(end 3.074924 -12.014962)
			(stroke
				(width 0.1)
				(type default)
			)
			(layer "F.Fab")
		)
		(fp_poly
			(pts
				(xy 3.348736 -7.994904) (xy 4.543806 -8.592566) (xy 4.543806 -7.397496)
			)
			(stroke
				(width 0)
				(type default)
			)
			(fill yes)
			(layer "F.Fab")
		)
		(pad "" np_thru_hole circle
			(at -1.75006 -9.815068 90)
			(size 1.1176 1.1176)
			(drill 1.1176)
			(layers "*.Cu" "*.Mask")
			(clearance 0.381)
			(thermal_gap 0.381)
		)
		(pad "" np_thru_hole circle
			(at 0 9.815068 90)
			(size 1.1176 1.1176)
			(drill 1.1176)
			(layers "*.Cu" "*.Mask")
			(clearance 0.381)
			(thermal_gap 0.381)
		)
		(pad "A1" smd rect
			(at 2.29997 -7.994904 90)
			(size 0.381 1.27)
			(layers "F.Cu" "F.Mask" "F.Paste")
			(net "GND")
		)
		(pad "A2" smd rect
			(at 2.29997 -7.394956 90)
			(size 0.381 1.27)
			(layers "F.Cu" "F.Mask" "F.Paste")
			(net "GND")
		)
		(pad "A3" smd rect
			(at 2.29997 -6.795008 90)
			(size 0.381 1.27)
			(layers "F.Cu" "F.Mask" "F.Paste")
			(net "GND")
		)
		(pad "A4" smd rect
			(at 2.29997 -6.19506 90)
			(size 0.381 1.27)
			(layers "F.Cu" "F.Mask" "F.Paste")
			(net "GND")
		)
		(pad "A5" smd rect
			(at 2.29997 -5.595112 90)
			(size 0.381 1.27)
			(layers "F.Cu" "F.Mask" "F.Paste")
			(net "GND")
		)
		(pad "A6" smd rect
			(at 2.29997 -4.99491 90)
			(size 0.381 1.27)
			(layers "F.Cu" "F.Mask" "F.Paste")
			(net "GND")
		)
		(pad "A7" smd rect
			(at 2.29997 -4.394962 90)
			(size 0.381 1.27)
			(layers "F.Cu" "F.Mask" "F.Paste")
			(net "SMB_ISO_SSD2_R_SCL")
		)
		(pad "A8" smd rect
			(at 2.29997 -3.795014 90)
			(size 0.381 1.27)
			(layers "F.Cu" "F.Mask" "F.Paste")
			(net "SMB_ISO_SSD2_R_SDA")
		)
		(pad "A9" smd rect
			(at 2.29997 -3.195066 90)
			(size 0.381 1.27)
			(layers "F.Cu" "F.Mask" "F.Paste")
			(net "RST_SMB_SSD2_ISO_R_N")
		)
		(pad "A10" smd rect
			(at 2.29997 -2.595118 90)
			(size 0.381 1.27)
			(layers "F.Cu" "F.Mask" "F.Paste")
			(net "SSD2_LED_ISO_R_N")
		)
		(pad "A11" smd rect
			(at 2.29997 -1.994916 90)
			(size 0.381 1.27)
			(layers "F.Cu" "F.Mask" "F.Paste")
			(net "PU_CLKREQ2")
		)
		(pad "A12" smd rect
			(at 2.29997 -1.394968 90)
			(size 0.381 1.27)
			(layers "F.Cu" "F.Mask" "F.Paste")
			(net "PRSNT_SSD2_N")
		)
		(pad "A13" smd rect
			(at 2.29997 -0.79502 90)
			(size 0.381 1.27)
			(layers "F.Cu" "F.Mask" "F.Paste")
			(net "GND")
		)
		(pad "A14" smd rect
			(at 2.29997 -0.195072 90)
			(size 0.381 1.27)
			(layers "F.Cu" "F.Mask" "F.Paste")
			(net "Net_8573")
		)
		(pad "A15" smd rect
			(at 2.29997 0.404876 90)
			(size 0.381 1.27)
			(layers "F.Cu" "F.Mask" "F.Paste")
			(net "Net_8572")
		)
		(pad "A16" smd rect
			(at 2.29997 1.005078 90)
			(size 0.381 1.27)
			(layers "F.Cu" "F.Mask" "F.Paste")
			(net "GND")
		)
		(pad "A17" smd rect
			(at 2.29997 1.605026 90)
			(size 0.381 1.27)
			(layers "F.Cu" "F.Mask" "F.Paste")
			(net "P5E_PEX0_STN2_RX_DN<36>")
		)
		(pad "A18" smd rect
			(at 2.29997 2.204974 90)
			(size 0.381 1.27)
			(layers "F.Cu" "F.Mask" "F.Paste")
			(net "P5E_PEX0_STN2_RX_DP<36>")
		)
		(pad "A19" smd rect
			(at 2.29997 2.804922 90)
			(size 0.381 1.27)
			(layers "F.Cu" "F.Mask" "F.Paste")
			(net "GND")
		)
		(pad "A20" smd rect
			(at 2.29997 3.405124 90)
			(size 0.381 1.27)
			(layers "F.Cu" "F.Mask" "F.Paste")
			(net "P5E_PEX0_STN2_RX_DN<37>")
		)
		(pad "A21" smd rect
			(at 2.29997 4.005072 90)
			(size 0.381 1.27)
			(layers "F.Cu" "F.Mask" "F.Paste")
			(net "P5E_PEX0_STN2_RX_DP<37>")
		)
		(pad "A22" smd rect
			(at 2.29997 4.60502 90)
			(size 0.381 1.27)
			(layers "F.Cu" "F.Mask" "F.Paste")
			(net "GND")
		)
		(pad "A23" smd rect
			(at 2.29997 5.204968 90)
			(size 0.381 1.27)
			(layers "F.Cu" "F.Mask" "F.Paste")
			(net "P5E_PEX0_STN2_RX_DN<38>")
		)
		(pad "A24" smd rect
			(at 2.29997 5.804916 90)
			(size 0.381 1.27)
			(layers "F.Cu" "F.Mask" "F.Paste")
			(net "P5E_PEX0_STN2_RX_DP<38>")
		)
		(pad "A25" smd rect
			(at 2.29997 6.405118 90)
			(size 0.381 1.27)
			(layers "F.Cu" "F.Mask" "F.Paste")
			(net "GND")
		)
		(pad "A26" smd rect
			(at 2.29997 7.005066 90)
			(size 0.381 1.27)
			(layers "F.Cu" "F.Mask" "F.Paste")
			(net "P5E_PEX0_STN2_RX_DN<39>")
		)
		(pad "A27" smd rect
			(at 2.29997 7.605014 90)
			(size 0.381 1.27)
			(layers "F.Cu" "F.Mask" "F.Paste")
			(net "P5E_PEX0_STN2_RX_DP<39>")
		)
		(pad "A28" smd rect
			(at 2.29997 8.204962 90)
			(size 0.381 1.27)
			(layers "F.Cu" "F.Mask" "F.Paste")
			(net "GND")
		)
		(pad "B1" smd rect
			(at -2.29997 -7.994904 90)
			(size 0.381 1.27)
			(layers "F.Cu" "F.Mask" "F.Paste")
			(net "P12V_SSD2")
		)
		(pad "B2" smd rect
			(at -2.29997 -7.394956 90)
			(size 0.381 1.27)
			(layers "F.Cu" "F.Mask" "F.Paste")
			(net "P12V_SSD2")
		)
		(pad "B3" smd rect
			(at -2.29997 -6.795008 90)
			(size 0.381 1.27)
			(layers "F.Cu" "F.Mask" "F.Paste")
			(net "P12V_SSD2")
		)
		(pad "B4" smd rect
			(at -2.29997 -6.19506 90)
			(size 0.381 1.27)
			(layers "F.Cu" "F.Mask" "F.Paste")
			(net "P12V_SSD2")
		)
		(pad "B5" smd rect
			(at -2.29997 -5.595112 90)
			(size 0.381 1.27)
			(layers "F.Cu" "F.Mask" "F.Paste")
			(net "P12V_SSD2")
		)
		(pad "B6" smd rect
			(at -2.29997 -4.99491 90)
			(size 0.381 1.27)
			(layers "F.Cu" "F.Mask" "F.Paste")
			(net "P12V_SSD2")
		)
		(pad "B7" smd rect
			(at -2.29997 -4.394962 90)
			(size 0.381 1.27)
			(layers "F.Cu" "F.Mask" "F.Paste")
			(net "Net_8574")
		)
		(pad "B8" smd rect
			(at -2.29997 -3.795014 90)
			(size 0.381 1.27)
			(layers "F.Cu" "F.Mask" "F.Paste")
			(net "Net_8571")
		)
		(pad "B9" smd rect
			(at -2.29997 -3.195066 90)
			(size 0.381 1.27)
			(layers "F.Cu" "F.Mask" "F.Paste")
			(net "DUALPORT_N_SSD2")
		)
		(pad "B10" smd rect
			(at -2.29997 -2.595118 90)
			(size 0.381 1.27)
			(layers "F.Cu" "F.Mask" "F.Paste")
			(net "RST_SSD2_PERST_R_N")
		)
		(pad "B11" smd rect
			(at -2.29997 -1.994916 90)
			(size 0.381 1.27)
			(layers "F.Cu" "F.Mask" "F.Paste")
			(net "P3V3_SSD2")
		)
		(pad "B12" smd rect
			(at -2.29997 -1.394968 90)
			(size 0.381 1.27)
			(layers "F.Cu" "F.Mask" "F.Paste")
			(net "SSD2_PWRDIS_R")
		)
		(pad "B13" smd rect
			(at -2.29997 -0.79502 90)
			(size 0.381 1.27)
			(layers "F.Cu" "F.Mask" "F.Paste")
			(net "GND")
		)
		(pad "B14" smd rect
			(at -2.29997 -0.195072 90)
			(size 0.381 1.27)
			(layers "F.Cu" "F.Mask" "F.Paste")
			(net "CLK_100M_DB800ZL_SSD2_R_DN")
		)
		(pad "B15" smd rect
			(at -2.29997 0.404876 90)
			(size 0.381 1.27)
			(layers "F.Cu" "F.Mask" "F.Paste")
			(net "CLK_100M_DB800ZL_SSD2_R_DP")
		)
		(pad "B16" smd rect
			(at -2.29997 1.005078 90)
			(size 0.381 1.27)
			(layers "F.Cu" "F.Mask" "F.Paste")
			(net "GND")
		)
		(pad "B17" smd rect
			(at -2.29997 1.605026 90)
			(size 0.381 1.27)
			(layers "F.Cu" "F.Mask" "F.Paste")
			(net "P5E_PEX0_STN2_TX_C_DN<36>")
		)
		(pad "B18" smd rect
			(at -2.29997 2.204974 90)
			(size 0.381 1.27)
			(layers "F.Cu" "F.Mask" "F.Paste")
			(net "P5E_PEX0_STN2_TX_C_DP<36>")
		)
		(pad "B19" smd rect
			(at -2.29997 2.804922 90)
			(size 0.381 1.27)
			(layers "F.Cu" "F.Mask" "F.Paste")
			(net "GND")
		)
		(pad "B20" smd rect
			(at -2.29997 3.405124 90)
			(size 0.381 1.27)
			(layers "F.Cu" "F.Mask" "F.Paste")
			(net "P5E_PEX0_STN2_TX_C_DN<37>")
		)
		(pad "B21" smd rect
			(at -2.29997 4.005072 90)
			(size 0.381 1.27)
			(layers "F.Cu" "F.Mask" "F.Paste")
			(net "P5E_PEX0_STN2_TX_C_DP<37>")
		)
		(pad "B22" smd rect
			(at -2.29997 4.60502 90)
			(size 0.381 1.27)
			(layers "F.Cu" "F.Mask" "F.Paste")
			(net "GND")
		)
		(pad "B23" smd rect
			(at -2.29997 5.204968 90)
			(size 0.381 1.27)
			(layers "F.Cu" "F.Mask" "F.Paste")
			(net "P5E_PEX0_STN2_TX_C_DN<38>")
		)
		(pad "B24" smd rect
			(at -2.29997 5.804916 90)
			(size 0.381 1.27)
			(layers "F.Cu" "F.Mask" "F.Paste")
			(net "P5E_PEX0_STN2_TX_C_DP<38>")
		)
		(pad "B25" smd rect
			(at -2.29997 6.405118 90)
			(size 0.381 1.27)
			(layers "F.Cu" "F.Mask" "F.Paste")
			(net "GND")
		)
		(pad "B26" smd rect
			(at -2.29997 7.005066 90)
			(size 0.381 1.27)
			(layers "F.Cu" "F.Mask" "F.Paste")
			(net "P5E_PEX0_STN2_TX_C_DN<39>")
		)
		(pad "B27" smd rect
			(at -2.29997 7.605014 90)
			(size 0.381 1.27)
			(layers "F.Cu" "F.Mask" "F.Paste")
			(net "P5E_PEX0_STN2_TX_C_DP<39>")
		)
		(pad "B28" smd rect
			(at -2.29997 8.204962 90)
			(size 0.381 1.27)
			(layers "F.Cu" "F.Mask" "F.Paste")
			(net "GND")
		)
		(pad "G1" thru_hole oval
			(at 0 -11.364976 90)
			(size 1.6256 3.4798)
			(drill oval 1.1176 2.4638)
			(layers "*.Cu" "*.Mask")
			(remove_unused_layers no)
			(net "GND")
			(clearance 0.127)
			(thermal_gap 0.127)
		)
		(pad "G2" thru_hole oval
			(at 0 11.364976 90)
			(size 1.6256 3.4798)
			(drill oval 1.1176 2.4638)
			(layers "*.Cu" "*.Mask")
			(remove_unused_layers no)
			(net "GND")
			(clearance 0.127)
			(thermal_gap 0.127)
		)
		(zone
			(layer "F.Cu")
			(hatch none 0.5)
			(connect_pads
				(clearance 0)
			)
			(min_thickness 0.25)
			(keepout
				(tracks not_allowed)
				(vias allowed)
				(pads allowed)
				(copperpour not_allowed)
				(footprints allowed)
			)
			(placement
				(enabled no)
				(sheetname "")
			)
			(fill
				(thermal_gap 0.5)
				(thermal_bridge_width 0.5)
				(island_removal_mode 0)
			)
			(polygon
				(pts
					(xy 66.3448 -38.850062) (xy 63.594742 -38.850062) (xy 63.594742 -35.900106) (xy 66.3448 -35.900106)
				)
			)
		)
		(zone
			(layer "F.Cu")
			(hatch none 0.5)
			(connect_pads
				(clearance 0)
			)
			(min_thickness 0.25)
			(keepout
				(tracks not_allowed)
				(vias allowed)
				(pads allowed)
				(copperpour not_allowed)
				(footprints allowed)
			)
			(placement
				(enabled no)
				(sheetname "")
			)
			(fill
				(thermal_gap 0.5)
				(thermal_bridge_width 0.5)
				(island_removal_mode 0)
			)
			(polygon
				(pts
					(xy 67.414902 -17.670018) (xy 63.584836 -17.670018) (xy 63.584836 -14.720062) (xy 67.414902 -14.720062)
				)
			)
		)
		(zone
			(layers "F.Cu" "B.Cu" "In1.Cu" "In2.Cu" "In3.Cu" "In4.Cu" "In5.Cu" "In6.Cu"
				"In7.Cu" "In8.Cu" "In9.Cu" "In10.Cu" "In11.Cu" "In12.Cu" "In13.Cu" "In14.Cu"
				"In15.Cu" "In16.Cu"
			)
			(hatch none 0.5)
			(connect_pads
				(clearance 0)
			)
			(min_thickness 0.25)
			(keepout
				(tracks not_allowed)
				(vias allowed)
				(pads allowed)
				(copperpour not_allowed)
				(footprints allowed)
			)
			(placement
				(enabled no)
				(sheetname "")
			)
			(fill
				(thermal_gap 0.5)
				(thermal_bridge_width 0.5)
				(island_removal_mode 0)
			)
			(polygon
				(pts
					(arc
						(start 65.930018 -36.60013)
						(mid 63.999618 -36.60013)
						(end 65.930018 -36.60013)
					)
				)
			)
		)
		(zone
			(layers "F.Cu" "B.Cu" "In1.Cu" "In2.Cu" "In3.Cu" "In4.Cu" "In5.Cu" "In6.Cu"
				"In7.Cu" "In8.Cu" "In9.Cu" "In10.Cu" "In11.Cu" "In12.Cu" "In13.Cu" "In14.Cu"
				"In15.Cu" "In16.Cu"
			)
			(hatch none 0.5)
			(connect_pads
				(clearance 0)
			)
			(min_thickness 0.25)
			(keepout
				(tracks not_allowed)
				(vias allowed)
				(pads allowed)
				(copperpour not_allowed)
				(footprints allowed)
			)
			(placement
				(enabled no)
				(sheetname "")
			)
			(fill
				(thermal_gap 0.5)
				(thermal_bridge_width 0.5)
				(island_removal_mode 0)
			)
			(polygon
				(pts
					(arc
						(start 67.680078 -16.969994)
						(mid 65.749678 -16.969994)
						(end 67.680078 -16.969994)
					)
				)
			)
		)
	)
	(footprint ""
		(layer "F.Cu")
		(at 79.314802 -79.58201 90)
		(property "Reference" "R100"
			(at 0 0 90)
			(layer "F.SilkS")
			(hide yes)
			(effects
				(font
					(size 1.27 1.27)
				)
			)
		)
		(property "Value" ""
			(at 0 0 90)
			(layer "F.Fab")
			(effects
				(font
					(size 1.27 1.27)
				)
			)
		)
		(duplicate_pad_numbers_are_jumpers no)
		(fp_line
			(start 0.7874 -0.4064)
			(end 0.7874 0.4064)
			(stroke
				(width 0.1524)
				(type default)
			)
			(layer "F.SilkS")
		)
		(fp_line
			(start -0.7874 -0.4064)
			(end 0.7874 -0.4064)
			(stroke
				(width 0.1524)
				(type default)
			)
			(layer "F.SilkS")
		)
		(fp_line
			(start 0.7874 0.4064)
			(end -0.7874 0.4064)
			(stroke
				(width 0.1524)
				(type default)
			)
			(layer "F.SilkS")
		)
		(fp_line
			(start -0.7874 0.4064)
			(end -0.7874 -0.4064)
			(stroke
				(width 0.1524)
				(type default)
			)
			(layer "F.SilkS")
		)
		(fp_line
			(start -0.12065 -0.305054)
			(end -0.12065 -0.2794)
			(stroke
				(width 0.1)
				(type default)
			)
			(layer "F.Fab")
		)
		(fp_line
			(start -0.67945 -0.305054)
			(end -0.12065 -0.305054)
			(stroke
				(width 0.1)
				(type default)
			)
			(layer "F.Fab")
		)
		(fp_line
			(start 0.67945 -0.3048)
			(end 0.67945 0.3048)
			(stroke
				(width 0.1)
				(type default)
			)
			(layer "F.Fab")
		)
		(fp_line
			(start 0.12065 -0.3048)
			(end 0.67945 -0.3048)
			(stroke
				(width 0.1)
				(type default)
			)
			(layer "F.Fab")
		)
		(fp_line
			(start 0.12065 -0.2794)
			(end 0.12065 -0.3048)
			(stroke
				(width 0.1)
				(type default)
			)
			(layer "F.Fab")
		)
		(fp_line
			(start -0.12065 -0.2794)
			(end 0.12065 -0.2794)
			(stroke
				(width 0.1)
				(type default)
			)
			(layer "F.Fab")
		)
		(fp_line
			(start 0.120396 0.2794)
			(end -0.12065 0.2794)
			(stroke
				(width 0.1)
				(type default)
			)
			(layer "F.Fab")
		)
		(fp_line
			(start -0.12065 0.2794)
			(end -0.12065 0.3048)
			(stroke
				(width 0.1)
				(type default)
			)
			(layer "F.Fab")
		)
		(fp_line
			(start 0.67945 0.3048)
			(end 0.120396 0.3048)
			(stroke
				(width 0.1)
				(type default)
			)
			(layer "F.Fab")
		)
		(fp_line
			(start 0.120396 0.3048)
			(end 0.120396 0.2794)
			(stroke
				(width 0.1)
				(type default)
			)
			(layer "F.Fab")
		)
		(fp_line
			(start -0.12065 0.3048)
			(end -0.67945 0.3048)
			(stroke
				(width 0.1)
				(type default)
			)
			(layer "F.Fab")
		)
		(fp_line
			(start -0.67945 0.3048)
			(end -0.67945 -0.305054)
			(stroke
				(width 0.1)
				(type default)
			)
			(layer "F.Fab")
		)
		(pad "1" smd circle
			(at -0.40005 0 90)
			(size 0 0)
			(layers "F.Cu" "F.Mask" "F.Paste")
			(net "P3V3_NIC1")
		)
		(pad "2" smd circle
			(at 0.40005 0 90)
			(size 0 0)
			(layers "F.Cu" "F.Mask" "F.Paste")
			(net "HP_NIC1_PWRGD")
		)
	)
	(footprint ""
		(layer "F.Cu")
		(at 71.247 -217.732356 90)
		(property "Reference" "R6633"
			(at 0 0 90)
			(layer "F.SilkS")
			(hide yes)
			(effects
				(font
					(size 1.27 1.27)
				)
			)
		)
		(property "Value" ""
			(at 0 0 90)
			(layer "F.Fab")
			(effects
				(font
					(size 1.27 1.27)
				)
			)
		)
		(duplicate_pad_numbers_are_jumpers no)
		(fp_line
			(start 0.7874 -0.4064)
			(end 0.7874 0.4064)
			(stroke
				(width 0.1524)
				(type default)
			)
			(layer "F.SilkS")
		)
		(fp_line
			(start -0.7874 -0.4064)
			(end 0.7874 -0.4064)
			(stroke
				(width 0.1524)
				(type default)
			)
			(layer "F.SilkS")
		)
		(fp_line
			(start 0.7874 0.4064)
			(end -0.7874 0.4064)
			(stroke
				(width 0.1524)
				(type default)
			)
			(layer "F.SilkS")
		)
		(fp_line
			(start -0.7874 0.4064)
			(end -0.7874 -0.4064)
			(stroke
				(width 0.1524)
				(type default)
			)
			(layer "F.SilkS")
		)
		(fp_line
			(start -0.12065 -0.305054)
			(end -0.12065 -0.2794)
			(stroke
				(width 0.1)
				(type default)
			)
			(layer "F.Fab")
		)
		(fp_line
			(start -0.67945 -0.305054)
			(end -0.12065 -0.305054)
			(stroke
				(width 0.1)
				(type default)
			)
			(layer "F.Fab")
		)
		(fp_line
			(start 0.67945 -0.3048)
			(end 0.67945 0.3048)
			(stroke
				(width 0.1)
				(type default)
			)
			(layer "F.Fab")
		)
		(fp_line
			(start 0.12065 -0.3048)
			(end 0.67945 -0.3048)
			(stroke
				(width 0.1)
				(type default)
			)
			(layer "F.Fab")
		)
		(fp_line
			(start 0.12065 -0.2794)
			(end 0.12065 -0.3048)
			(stroke
				(width 0.1)
				(type default)
			)
			(layer "F.Fab")
		)
		(fp_line
			(start -0.12065 -0.2794)
			(end 0.12065 -0.2794)
			(stroke
				(width 0.1)
				(type default)
			)
			(layer "F.Fab")
		)
		(fp_line
			(start 0.120396 0.2794)
			(end -0.12065 0.2794)
			(stroke
				(width 0.1)
				(type default)
			)
			(layer "F.Fab")
		)
		(fp_line
			(start -0.12065 0.2794)
			(end -0.12065 0.3048)
			(stroke
				(width 0.1)
				(type default)
			)
			(layer "F.Fab")
		)
		(fp_line
			(start 0.67945 0.3048)
			(end 0.120396 0.3048)
			(stroke
				(width 0.1)
				(type default)
			)
			(layer "F.Fab")
		)
		(fp_line
			(start 0.120396 0.3048)
			(end 0.120396 0.2794)
			(stroke
				(width 0.1)
				(type default)
			)
			(layer "F.Fab")
		)
		(fp_line
			(start -0.12065 0.3048)
			(end -0.67945 0.3048)
			(stroke
				(width 0.1)
				(type default)
			)
			(layer "F.Fab")
		)
		(fp_line
			(start -0.67945 0.3048)
			(end -0.67945 -0.305054)
			(stroke
				(width 0.1)
				(type default)
			)
			(layer "F.Fab")
		)
		(pad "1" smd circle
			(at -0.40005 0 90)
			(size 0 0)
			(layers "F.Cu" "F.Mask" "F.Paste")
			(net "UART_PEX3_CLI_R_RX")
		)
		(pad "2" smd circle
			(at 0.40005 0 90)
			(size 0 0)
			(layers "F.Cu" "F.Mask" "F.Paste")
			(net "UART_PEX3_CLI_R1_RX")
		)
	)
	(footprint ""
		(layer "F.Cu")
		(at 236.58195 -254.18542 -90)
		(property "Reference" "C4354"
			(at 0 0 270)
			(layer "F.SilkS")
			(hide yes)
			(effects
				(font
					(size 1.27 1.27)
				)
			)
		)
		(property "Value" ""
			(at 0 0 270)
			(layer "F.Fab")
			(effects
				(font
					(size 1.27 1.27)
				)
			)
		)
		(duplicate_pad_numbers_are_jumpers no)
		(fp_line
			(start -1.2954 0.5842)
			(end -1.2954 -0.5842)
			(stroke
				(width 0.1524)
				(type default)
			)
			(layer "F.SilkS")
		)
		(fp_line
			(start 1.2954 0.5842)
			(end -1.2954 0.5842)
			(stroke
				(width 0.1524)
				(type default)
			)
			(layer "F.SilkS")
		)
		(fp_line
			(start -1.2954 -0.5842)
			(end 1.2954 -0.5842)
			(stroke
				(width 0.1524)
				(type default)
			)
			(layer "F.SilkS")
		)
		(fp_line
			(start 1.2954 -0.5842)
			(end 1.2954 0.5842)
			(stroke
				(width 0.1524)
				(type default)
			)
			(layer "F.SilkS")
		)
		(fp_line
			(start -0.8636 0.4572)
			(end -0.8636 0.4064)
			(stroke
				(width 0.1)
				(type default)
			)
			(layer "F.Fab")
		)
		(fp_line
			(start 0.8636 0.4572)
			(end -0.8636 0.4572)
			(stroke
				(width 0.1)
				(type default)
			)
			(layer "F.Fab")
		)
		(fp_line
			(start -1.1938 0.4064)
			(end -1.1938 -0.4064)
			(stroke
				(width 0.1)
				(type default)
			)
			(layer "F.Fab")
		)
		(fp_line
			(start -0.8636 0.4064)
			(end -1.1938 0.4064)
			(stroke
				(width 0.1)
				(type default)
			)
			(layer "F.Fab")
		)
		(fp_line
			(start 0.8636 0.4064)
			(end 0.8636 0.4572)
			(stroke
				(width 0.1)
				(type default)
			)
			(layer "F.Fab")
		)
		(fp_line
			(start 1.1938 0.4064)
			(end 0.8636 0.4064)
			(stroke
				(width 0.1)
				(type default)
			)
			(layer "F.Fab")
		)
		(fp_line
			(start -1.1938 -0.4064)
			(end -0.8636 -0.4064)
			(stroke
				(width 0.1)
				(type default)
			)
			(layer "F.Fab")
		)
		(fp_line
			(start -0.8636 -0.4064)
			(end -0.8636 -0.4572)
			(stroke
				(width 0.1)
				(type default)
			)
			(layer "F.Fab")
		)
		(fp_line
			(start 0.8636 -0.4064)
			(end 1.1938 -0.4064)
			(stroke
				(width 0.1)
				(type default)
			)
			(layer "F.Fab")
		)
		(fp_line
			(start 1.1938 -0.4064)
			(end 1.1938 0.4064)
			(stroke
				(width 0.1)
				(type default)
			)
			(layer "F.Fab")
		)
		(fp_line
			(start -0.8636 -0.4572)
			(end 0.8636 -0.4572)
			(stroke
				(width 0.1)
				(type default)
			)
			(layer "F.Fab")
		)
		(fp_line
			(start 0.8636 -0.4572)
			(end 0.8636 -0.4064)
			(stroke
				(width 0.1)
				(type default)
			)
			(layer "F.Fab")
		)
		(pad "1" smd rect
			(at -0.7366 0 180)
			(size 0.7112 0.8128)
			(layers "F.Cu" "F.Mask" "F.Paste")
			(net "P1V25_SERDES_VDDPLL_PEX2_C8")
		)
		(pad "2" smd rect
			(at 0.7366 0 180)
			(size 0.7112 0.8128)
			(layers "F.Cu" "F.Mask" "F.Paste")
			(net "GND")
		)
	)
	(footprint ""
		(layer "F.Cu")
		(at 123.67514 -97.177606)
		(property "Reference" "R1575"
			(at 0 0 0)
			(layer "F.SilkS")
			(hide yes)
			(effects
				(font
					(size 1.27 1.27)
				)
			)
		)
		(property "Value" ""
			(at 0 0 0)
			(layer "F.Fab")
			(effects
				(font
					(size 1.27 1.27)
				)
			)
		)
		(duplicate_pad_numbers_are_jumpers no)
		(fp_line
			(start -0.7874 -0.4064)
			(end 0.7874 -0.4064)
			(stroke
				(width 0.1524)
				(type default)
			)
			(layer "F.SilkS")
		)
		(fp_line
			(start -0.7874 0.4064)
			(end -0.7874 -0.4064)
			(stroke
				(width 0.1524)
				(type default)
			)
			(layer "F.SilkS")
		)
		(fp_line
			(start 0.7874 -0.4064)
			(end 0.7874 0.4064)
			(stroke
				(width 0.1524)
				(type default)
			)
			(layer "F.SilkS")
		)
		(fp_line
			(start 0.7874 0.4064)
			(end -0.7874 0.4064)
			(stroke
				(width 0.1524)
				(type default)
			)
			(layer "F.SilkS")
		)
		(fp_line
			(start -0.67945 -0.305054)
			(end -0.12065 -0.305054)
			(stroke
				(width 0.1)
				(type default)
			)
			(layer "F.Fab")
		)
		(fp_line
			(start -0.67945 0.3048)
			(end -0.67945 -0.305054)
			(stroke
				(width 0.1)
				(type default)
			)
			(layer "F.Fab")
		)
		(fp_line
			(start -0.12065 -0.305054)
			(end -0.12065 -0.2794)
			(stroke
				(width 0.1)
				(type default)
			)
			(layer "F.Fab")
		)
		(fp_line
			(start -0.12065 -0.2794)
			(end 0.12065 -0.2794)
			(stroke
				(width 0.1)
				(type default)
			)
			(layer "F.Fab")
		)
		(fp_line
			(start -0.12065 0.2794)
			(end -0.12065 0.3048)
			(stroke
				(width 0.1)
				(type default)
			)
			(layer "F.Fab")
		)
		(fp_line
			(start -0.12065 0.3048)
			(end -0.67945 0.3048)
			(stroke
				(width 0.1)
				(type default)
			)
			(layer "F.Fab")
		)
		(fp_line
			(start 0.120396 0.2794)
			(end -0.12065 0.2794)
			(stroke
				(width 0.1)
				(type default)
			)
			(layer "F.Fab")
		)
		(fp_line
			(start 0.120396 0.3048)
			(end 0.120396 0.2794)
			(stroke
				(width 0.1)
				(type default)
			)
			(layer "F.Fab")
		)
		(fp_line
			(start 0.12065 -0.3048)
			(end 0.67945 -0.3048)
			(stroke
				(width 0.1)
				(type default)
			)
			(layer "F.Fab")
		)
		(fp_line
			(start 0.12065 -0.2794)
			(end 0.12065 -0.3048)
			(stroke
				(width 0.1)
				(type default)
			)
			(layer "F.Fab")
		)
		(fp_line
			(start 0.67945 -0.3048)
			(end 0.67945 0.3048)
			(stroke
				(width 0.1)
				(type default)
			)
			(layer "F.Fab")
		)
		(fp_line
			(start 0.67945 0.3048)
			(end 0.120396 0.3048)
			(stroke
				(width 0.1)
				(type default)
			)
			(layer "F.Fab")
		)
		(pad "1" smd circle
			(at -0.40005 0)
			(size 0 0)
			(layers "F.Cu" "F.Mask" "F.Paste")
			(net "SMB_BIC_I2C9_MUX0_SSD0_R_SDA")
		)
		(pad "2" smd circle
			(at 0.40005 0)
			(size 0 0)
			(layers "F.Cu" "F.Mask" "F.Paste")
			(net "SMB_BIC_I2C9_MUX0_SSD0_SDA")
		)
	)
	(footprint ""
		(layer "F.Cu")
		(at 137.985754 -27.092148 -90)
		(property "Reference" "R5739"
			(at 0 0 270)
			(layer "F.SilkS")
			(hide yes)
			(effects
				(font
					(size 1.27 1.27)
				)
			)
		)
		(property "Value" ""
			(at 0 0 270)
			(layer "F.Fab")
			(effects
				(font
					(size 1.27 1.27)
				)
			)
		)
		(duplicate_pad_numbers_are_jumpers no)
		(fp_line
			(start -0.7874 0.4064)
			(end -0.7874 -0.4064)
			(stroke
				(width 0.1524)
				(type default)
			)
			(layer "F.SilkS")
		)
		(fp_line
			(start 0.7874 0.4064)
			(end -0.7874 0.4064)
			(stroke
				(width 0.1524)
				(type default)
			)
			(layer "F.SilkS")
		)
		(fp_line
			(start -0.7874 -0.4064)
			(end 0.7874 -0.4064)
			(stroke
				(width 0.1524)
				(type default)
			)
			(layer "F.SilkS")
		)
		(fp_line
			(start 0.7874 -0.4064)
			(end 0.7874 0.4064)
			(stroke
				(width 0.1524)
				(type default)
			)
			(layer "F.SilkS")
		)
		(fp_line
			(start -0.67945 0.3048)
			(end -0.67945 -0.305054)
			(stroke
				(width 0.1)
				(type default)
			)
			(layer "F.Fab")
		)
		(fp_line
			(start -0.12065 0.3048)
			(end -0.67945 0.3048)
			(stroke
				(width 0.1)
				(type default)
			)
			(layer "F.Fab")
		)
		(fp_line
			(start 0.120396 0.3048)
			(end 0.120396 0.2794)
			(stroke
				(width 0.1)
				(type default)
			)
			(layer "F.Fab")
		)
		(fp_line
			(start 0.67945 0.3048)
			(end 0.120396 0.3048)
			(stroke
				(width 0.1)
				(type default)
			)
			(layer "F.Fab")
		)
		(fp_line
			(start -0.12065 0.2794)
			(end -0.12065 0.3048)
			(stroke
				(width 0.1)
				(type default)
			)
			(layer "F.Fab")
		)
		(fp_line
			(start 0.120396 0.2794)
			(end -0.12065 0.2794)
			(stroke
				(width 0.1)
				(type default)
			)
			(layer "F.Fab")
		)
		(fp_line
			(start -0.12065 -0.2794)
			(end 0.12065 -0.2794)
			(stroke
				(width 0.1)
				(type default)
			)
			(layer "F.Fab")
		)
		(fp_line
			(start 0.12065 -0.2794)
			(end 0.12065 -0.3048)
			(stroke
				(width 0.1)
				(type default)
			)
			(layer "F.Fab")
		)
		(fp_line
			(start 0.12065 -0.3048)
			(end 0.67945 -0.3048)
			(stroke
				(width 0.1)
				(type default)
			)
			(layer "F.Fab")
		)
		(fp_line
			(start 0.67945 -0.3048)
			(end 0.67945 0.3048)
			(stroke
				(width 0.1)
				(type default)
			)
			(layer "F.Fab")
		)
		(fp_line
			(start -0.67945 -0.305054)
			(end -0.12065 -0.305054)
			(stroke
				(width 0.1)
				(type default)
			)
			(layer "F.Fab")
		)
		(fp_line
			(start -0.12065 -0.305054)
			(end -0.12065 -0.2794)
			(stroke
				(width 0.1)
				(type default)
			)
			(layer "F.Fab")
		)
		(pad "1" smd circle
			(at -0.40005 0 270)
			(size 0 0)
			(layers "F.Cu" "F.Mask" "F.Paste")
			(net "P3V3_SSD4")
		)
		(pad "2" smd circle
			(at 0.40005 0 270)
			(size 0 0)
			(layers "F.Cu" "F.Mask" "F.Paste")
			(net "SSD4_LED_ISO_N")
		)
	)
	(footprint ""
		(layer "F.Cu")
		(at 242.232434 -250.759722 -90)
		(property "Reference" "R6220"
			(at 0 0 270)
			(layer "F.SilkS")
			(hide yes)
			(effects
				(font
					(size 1.27 1.27)
				)
			)
		)
		(property "Value" ""
			(at 0 0 270)
			(layer "F.Fab")
			(effects
				(font
					(size 1.27 1.27)
				)
			)
		)
		(duplicate_pad_numbers_are_jumpers no)
		(fp_line
			(start -0.7874 0.4064)
			(end -0.7874 -0.4064)
			(stroke
				(width 0.1524)
				(type default)
			)
			(layer "F.SilkS")
		)
		(fp_line
			(start 0.7874 0.4064)
			(end -0.7874 0.4064)
			(stroke
				(width 0.1524)
				(type default)
			)
			(layer "F.SilkS")
		)
		(fp_line
			(start -0.7874 -0.4064)
			(end 0.7874 -0.4064)
			(stroke
				(width 0.1524)
				(type default)
			)
			(layer "F.SilkS")
		)
		(fp_line
			(start 0.7874 -0.4064)
			(end 0.7874 0.4064)
			(stroke
				(width 0.1524)
				(type default)
			)
			(layer "F.SilkS")
		)
		(fp_line
			(start -0.67945 0.3048)
			(end -0.67945 -0.305054)
			(stroke
				(width 0.1)
				(type default)
			)
			(layer "F.Fab")
		)
		(fp_line
			(start -0.12065 0.3048)
			(end -0.67945 0.3048)
			(stroke
				(width 0.1)
				(type default)
			)
			(layer "F.Fab")
		)
		(fp_line
			(start 0.120396 0.3048)
			(end 0.120396 0.2794)
			(stroke
				(width 0.1)
				(type default)
			)
			(layer "F.Fab")
		)
		(fp_line
			(start 0.67945 0.3048)
			(end 0.120396 0.3048)
			(stroke
				(width 0.1)
				(type default)
			)
			(layer "F.Fab")
		)
		(fp_line
			(start -0.12065 0.2794)
			(end -0.12065 0.3048)
			(stroke
				(width 0.1)
				(type default)
			)
			(layer "F.Fab")
		)
		(fp_line
			(start 0.120396 0.2794)
			(end -0.12065 0.2794)
			(stroke
				(width 0.1)
				(type default)
			)
			(layer "F.Fab")
		)
		(fp_line
			(start -0.12065 -0.2794)
			(end 0.12065 -0.2794)
			(stroke
				(width 0.1)
				(type default)
			)
			(layer "F.Fab")
		)
		(fp_line
			(start 0.12065 -0.2794)
			(end 0.12065 -0.3048)
			(stroke
				(width 0.1)
				(type default)
			)
			(layer "F.Fab")
		)
		(fp_line
			(start 0.12065 -0.3048)
			(end 0.67945 -0.3048)
			(stroke
				(width 0.1)
				(type default)
			)
			(layer "F.Fab")
		)
		(fp_line
			(start 0.67945 -0.3048)
			(end 0.67945 0.3048)
			(stroke
				(width 0.1)
				(type default)
			)
			(layer "F.Fab")
		)
		(fp_line
			(start -0.67945 -0.305054)
			(end -0.12065 -0.305054)
			(stroke
				(width 0.1)
				(type default)
			)
			(layer "F.Fab")
		)
		(fp_line
			(start -0.12065 -0.305054)
			(end -0.12065 -0.2794)
			(stroke
				(width 0.1)
				(type default)
			)
			(layer "F.Fab")
		)
		(pad "1" smd circle
			(at -0.40005 0 270)
			(size 0 0)
			(layers "F.Cu" "F.Mask" "F.Paste")
			(net "P3V3_AUX")
		)
		(pad "2" smd circle
			(at 0.40005 0 270)
			(size 0 0)
			(layers "F.Cu" "F.Mask" "F.Paste")
			(net "RST_BIC_RECOVER_N")
		)
	)
	(footprint ""
		(layer "F.Cu")
		(at 268.838426 -105.609898)
		(property "Reference" "C480"
			(at 0 0 0)
			(layer "F.SilkS")
			(hide yes)
			(effects
				(font
					(size 1.27 1.27)
				)
			)
		)
		(property "Value" ""
			(at 0 0 0)
			(layer "F.Fab")
			(effects
				(font
					(size 1.27 1.27)
				)
			)
		)
		(duplicate_pad_numbers_are_jumpers no)
		(fp_line
			(start -0.299974 -0.150114)
			(end 0.299974 -0.150114)
			(stroke
				(width 0.1)
				(type default)
			)
			(layer "F.Fab")
		)
		(fp_line
			(start -0.299974 0.150114)
			(end -0.299974 -0.150114)
			(stroke
				(width 0.1)
				(type default)
			)
			(layer "F.Fab")
		)
		(fp_line
			(start 0.299974 -0.150114)
			(end 0.299974 0.150114)
			(stroke
				(width 0.1)
				(type default)
			)
			(layer "F.Fab")
		)
		(fp_line
			(start 0.299974 0.150114)
			(end -0.299974 0.150114)
			(stroke
				(width 0.1)
				(type default)
			)
			(layer "F.Fab")
		)
		(pad "1" smd rect
			(at -0.2667 0)
			(size 0.3048 0.381)
			(layers "F.Cu" "F.Mask" "F.Paste")
			(net "P5E_PEX2_STN1_TX_DP<19>")
		)
		(pad "2" smd rect
			(at 0.2667 0)
			(size 0.3048 0.381)
			(layers "F.Cu" "F.Mask" "F.Paste")
			(net "P5E_PEX2_STN1_TX_C_DP<19>")
		)
	)
	(footprint ""
		(layer "F.Cu")
		(at 431.594006 -35.264852)
		(property "Reference" "R5708"
			(at 0 0 0)
			(layer "F.SilkS")
			(hide yes)
			(effects
				(font
					(size 1.27 1.27)
				)
			)
		)
		(property "Value" ""
			(at 0 0 0)
			(layer "F.Fab")
			(effects
				(font
					(size 1.27 1.27)
				)
			)
		)
		(duplicate_pad_numbers_are_jumpers no)
		(fp_line
			(start -0.7874 -0.4064)
			(end 0.7874 -0.4064)
			(stroke
				(width 0.1524)
				(type default)
			)
			(layer "F.SilkS")
		)
		(fp_line
			(start -0.7874 0.4064)
			(end -0.7874 -0.4064)
			(stroke
				(width 0.1524)
				(type default)
			)
			(layer "F.SilkS")
		)
		(fp_line
			(start 0.7874 -0.4064)
			(end 0.7874 0.4064)
			(stroke
				(width 0.1524)
				(type default)
			)
			(layer "F.SilkS")
		)
		(fp_line
			(start 0.7874 0.4064)
			(end -0.7874 0.4064)
			(stroke
				(width 0.1524)
				(type default)
			)
			(layer "F.SilkS")
		)
		(fp_line
			(start -0.67945 -0.305054)
			(end -0.12065 -0.305054)
			(stroke
				(width 0.1)
				(type default)
			)
			(layer "F.Fab")
		)
		(fp_line
			(start -0.67945 0.3048)
			(end -0.67945 -0.305054)
			(stroke
				(width 0.1)
				(type default)
			)
			(layer "F.Fab")
		)
		(fp_line
			(start -0.12065 -0.305054)
			(end -0.12065 -0.2794)
			(stroke
				(width 0.1)
				(type default)
			)
			(layer "F.Fab")
		)
		(fp_line
			(start -0.12065 -0.2794)
			(end 0.12065 -0.2794)
			(stroke
				(width 0.1)
				(type default)
			)
			(layer "F.Fab")
		)
		(fp_line
			(start -0.12065 0.2794)
			(end -0.12065 0.3048)
			(stroke
				(width 0.1)
				(type default)
			)
			(layer "F.Fab")
		)
		(fp_line
			(start -0.12065 0.3048)
			(end -0.67945 0.3048)
			(stroke
				(width 0.1)
				(type default)
			)
			(layer "F.Fab")
		)
		(fp_line
			(start 0.120396 0.2794)
			(end -0.12065 0.2794)
			(stroke
				(width 0.1)
				(type default)
			)
			(layer "F.Fab")
		)
		(fp_line
			(start 0.120396 0.3048)
			(end 0.120396 0.2794)
			(stroke
				(width 0.1)
				(type default)
			)
			(layer "F.Fab")
		)
		(fp_line
			(start 0.12065 -0.3048)
			(end 0.67945 -0.3048)
			(stroke
				(width 0.1)
				(type default)
			)
			(layer "F.Fab")
		)
		(fp_line
			(start 0.12065 -0.2794)
			(end 0.12065 -0.3048)
			(stroke
				(width 0.1)
				(type default)
			)
			(layer "F.Fab")
		)
		(fp_line
			(start 0.67945 -0.3048)
			(end 0.67945 0.3048)
			(stroke
				(width 0.1)
				(type default)
			)
			(layer "F.Fab")
		)
		(fp_line
			(start 0.67945 0.3048)
			(end 0.120396 0.3048)
			(stroke
				(width 0.1)
				(type default)
			)
			(layer "F.Fab")
		)
		(pad "1" smd circle
			(at -0.40005 0)
			(size 0 0)
			(layers "F.Cu" "F.Mask" "F.Paste")
			(net "RST_SMB_SSD15_ISO_N")
		)
		(pad "2" smd circle
			(at 0.40005 0)
			(size 0 0)
			(layers "F.Cu" "F.Mask" "F.Paste")
			(net "GND")
		)
	)
	(footprint ""
		(layer "F.Cu")
		(at 400.543776 -48.93691 180)
		(property "Reference" "R655"
			(at 0 0 180)
			(layer "F.SilkS")
			(hide yes)
			(effects
				(font
					(size 1.27 1.27)
				)
			)
		)
		(property "Value" ""
			(at 0 0 180)
			(layer "F.Fab")
			(effects
				(font
					(size 1.27 1.27)
				)
			)
		)
		(duplicate_pad_numbers_are_jumpers no)
		(fp_line
			(start 0.7874 0.4064)
			(end -0.7874 0.4064)
			(stroke
				(width 0.1524)
				(type default)
			)
			(layer "F.SilkS")
		)
		(fp_line
			(start 0.7874 -0.4064)
			(end 0.7874 0.4064)
			(stroke
				(width 0.1524)
				(type default)
			)
			(layer "F.SilkS")
		)
		(fp_line
			(start -0.7874 0.4064)
			(end -0.7874 -0.4064)
			(stroke
				(width 0.1524)
				(type default)
			)
			(layer "F.SilkS")
		)
		(fp_line
			(start -0.7874 -0.4064)
			(end 0.7874 -0.4064)
			(stroke
				(width 0.1524)
				(type default)
			)
			(layer "F.SilkS")
		)
		(fp_line
			(start 0.67945 0.3048)
			(end 0.120396 0.3048)
			(stroke
				(width 0.1)
				(type default)
			)
			(layer "F.Fab")
		)
		(fp_line
			(start 0.67945 -0.3048)
			(end 0.67945 0.3048)
			(stroke
				(width 0.1)
				(type default)
			)
			(layer "F.Fab")
		)
		(fp_line
			(start 0.12065 -0.2794)
			(end 0.12065 -0.3048)
			(stroke
				(width 0.1)
				(type default)
			)
			(layer "F.Fab")
		)
		(fp_line
			(start 0.12065 -0.3048)
			(end 0.67945 -0.3048)
			(stroke
				(width 0.1)
				(type default)
			)
			(layer "F.Fab")
		)
		(fp_line
			(start 0.120396 0.3048)
			(end 0.120396 0.2794)
			(stroke
				(width 0.1)
				(type default)
			)
			(layer "F.Fab")
		)
		(fp_line
			(start 0.120396 0.2794)
			(end -0.12065 0.2794)
			(stroke
				(width 0.1)
				(type default)
			)
			(layer "F.Fab")
		)
		(fp_line
			(start -0.12065 0.3048)
			(end -0.67945 0.3048)
			(stroke
				(width 0.1)
				(type default)
			)
			(layer "F.Fab")
		)
		(fp_line
			(start -0.12065 0.2794)
			(end -0.12065 0.3048)
			(stroke
				(width 0.1)
				(type default)
			)
			(layer "F.Fab")
		)
		(fp_line
			(start -0.12065 -0.2794)
			(end 0.12065 -0.2794)
			(stroke
				(width 0.1)
				(type default)
			)
			(layer "F.Fab")
		)
		(fp_line
			(start -0.12065 -0.305054)
			(end -0.12065 -0.2794)
			(stroke
				(width 0.1)
				(type default)
			)
			(layer "F.Fab")
		)
		(fp_line
			(start -0.67945 0.3048)
			(end -0.67945 -0.305054)
			(stroke
				(width 0.1)
				(type default)
			)
			(layer "F.Fab")
		)
		(fp_line
			(start -0.67945 -0.305054)
			(end -0.12065 -0.305054)
			(stroke
				(width 0.1)
				(type default)
			)
			(layer "F.Fab")
		)
		(pad "1" smd circle
			(at -0.40005 0 180)
			(size 0 0)
			(layers "F.Cu" "F.Mask" "F.Paste")
			(net "SMB_BIC_I2C6_MUX_SSD_8_15_ADC_R_SDA")
		)
		(pad "2" smd circle
			(at 0.40005 0 180)
			(size 0 0)
			(layers "F.Cu" "F.Mask" "F.Paste")
			(net "SMB_SSD13_ADC_SDA")
		)
	)
	(footprint ""
		(layer "F.Cu")
		(at 440.838844 -122.798332 90)
		(property "Reference" "PC490"
			(at 0 0 90)
			(layer "F.SilkS")
			(hide yes)
			(effects
				(font
					(size 1.27 1.27)
				)
			)
		)
		(property "Value" ""
			(at 0 0 90)
			(layer "F.Fab")
			(effects
				(font
					(size 1.27 1.27)
				)
			)
		)
		(duplicate_pad_numbers_are_jumpers no)
		(fp_line
			(start 0.7874 -0.4064)
			(end 0.7874 0.4064)
			(stroke
				(width 0.1524)
				(type default)
			)
			(layer "F.SilkS")
		)
		(fp_line
			(start -0.7874 -0.4064)
			(end 0.7874 -0.4064)
			(stroke
				(width 0.1524)
				(type default)
			)
			(layer "F.SilkS")
		)
		(fp_line
			(start 0.7874 0.4064)
			(end -0.7874 0.4064)
			(stroke
				(width 0.1524)
				(type default)
			)
			(layer "F.SilkS")
		)
		(fp_line
			(start -0.7874 0.4064)
			(end -0.7874 -0.4064)
			(stroke
				(width 0.1524)
				(type default)
			)
			(layer "F.SilkS")
		)
		(fp_line
			(start -0.12065 -0.305054)
			(end -0.12065 -0.2794)
			(stroke
				(width 0.1)
				(type default)
			)
			(layer "F.Fab")
		)
		(fp_line
			(start -0.67945 -0.305054)
			(end -0.12065 -0.305054)
			(stroke
				(width 0.1)
				(type default)
			)
			(layer "F.Fab")
		)
		(fp_line
			(start 0.67945 -0.3048)
			(end 0.67945 0.3048)
			(stroke
				(width 0.1)
				(type default)
			)
			(layer "F.Fab")
		)
		(fp_line
			(start 0.12065 -0.3048)
			(end 0.67945 -0.3048)
			(stroke
				(width 0.1)
				(type default)
			)
			(layer "F.Fab")
		)
		(fp_line
			(start 0.12065 -0.2794)
			(end 0.12065 -0.3048)
			(stroke
				(width 0.1)
				(type default)
			)
			(layer "F.Fab")
		)
		(fp_line
			(start -0.12065 -0.2794)
			(end 0.12065 -0.2794)
			(stroke
				(width 0.1)
				(type default)
			)
			(layer "F.Fab")
		)
		(fp_line
			(start 0.120396 0.2794)
			(end -0.12065 0.2794)
			(stroke
				(width 0.1)
				(type default)
			)
			(layer "F.Fab")
		)
		(fp_line
			(start -0.12065 0.2794)
			(end -0.12065 0.3048)
			(stroke
				(width 0.1)
				(type default)
			)
			(layer "F.Fab")
		)
		(fp_line
			(start 0.67945 0.3048)
			(end 0.120396 0.3048)
			(stroke
				(width 0.1)
				(type default)
			)
			(layer "F.Fab")
		)
		(fp_line
			(start 0.120396 0.3048)
			(end 0.120396 0.2794)
			(stroke
				(width 0.1)
				(type default)
			)
			(layer "F.Fab")
		)
		(fp_line
			(start -0.12065 0.3048)
			(end -0.67945 0.3048)
			(stroke
				(width 0.1)
				(type default)
			)
			(layer "F.Fab")
		)
		(fp_line
			(start -0.67945 0.3048)
			(end -0.67945 -0.305054)
			(stroke
				(width 0.1)
				(type default)
			)
			(layer "F.Fab")
		)
		(pad "1" smd circle
			(at -0.40005 0 90)
			(size 0 0)
			(layers "F.Cu" "F.Mask" "F.Paste")
			(net "P3V3_NIC7")
		)
		(pad "2" smd circle
			(at 0.40005 0 90)
			(size 0 0)
			(layers "F.Cu" "F.Mask" "F.Paste")
			(net "GND")
		)
	)
	(footprint ""
		(layer "F.Cu")
		(at 342.835738 -111.896906 90)
		(property "Reference" "PR7034"
			(at 0 0 90)
			(layer "F.SilkS")
			(hide yes)
			(effects
				(font
					(size 1.27 1.27)
				)
			)
		)
		(property "Value" ""
			(at 0 0 90)
			(layer "F.Fab")
			(effects
				(font
					(size 1.27 1.27)
				)
			)
		)
		(duplicate_pad_numbers_are_jumpers no)
		(fp_line
			(start 0.7874 -0.4064)
			(end 0.7874 0.4064)
			(stroke
				(width 0.1524)
				(type default)
			)
			(layer "F.SilkS")
		)
		(fp_line
			(start -0.7874 -0.4064)
			(end 0.7874 -0.4064)
			(stroke
				(width 0.1524)
				(type default)
			)
			(layer "F.SilkS")
		)
		(fp_line
			(start 0.7874 0.4064)
			(end -0.7874 0.4064)
			(stroke
				(width 0.1524)
				(type default)
			)
			(layer "F.SilkS")
		)
		(fp_line
			(start -0.7874 0.4064)
			(end -0.7874 -0.4064)
			(stroke
				(width 0.1524)
				(type default)
			)
			(layer "F.SilkS")
		)
		(fp_line
			(start -0.12065 -0.305054)
			(end -0.12065 -0.2794)
			(stroke
				(width 0.1)
				(type default)
			)
			(layer "F.Fab")
		)
		(fp_line
			(start -0.67945 -0.305054)
			(end -0.12065 -0.305054)
			(stroke
				(width 0.1)
				(type default)
			)
			(layer "F.Fab")
		)
		(fp_line
			(start 0.67945 -0.3048)
			(end 0.67945 0.3048)
			(stroke
				(width 0.1)
				(type default)
			)
			(layer "F.Fab")
		)
		(fp_line
			(start 0.12065 -0.3048)
			(end 0.67945 -0.3048)
			(stroke
				(width 0.1)
				(type default)
			)
			(layer "F.Fab")
		)
		(fp_line
			(start 0.12065 -0.2794)
			(end 0.12065 -0.3048)
			(stroke
				(width 0.1)
				(type default)
			)
			(layer "F.Fab")
		)
		(fp_line
			(start -0.12065 -0.2794)
			(end 0.12065 -0.2794)
			(stroke
				(width 0.1)
				(type default)
			)
			(layer "F.Fab")
		)
		(fp_line
			(start 0.120396 0.2794)
			(end -0.12065 0.2794)
			(stroke
				(width 0.1)
				(type default)
			)
			(layer "F.Fab")
		)
		(fp_line
			(start -0.12065 0.2794)
			(end -0.12065 0.3048)
			(stroke
				(width 0.1)
				(type default)
			)
			(layer "F.Fab")
		)
		(fp_line
			(start 0.67945 0.3048)
			(end 0.120396 0.3048)
			(stroke
				(width 0.1)
				(type default)
			)
			(layer "F.Fab")
		)
		(fp_line
			(start 0.120396 0.3048)
			(end 0.120396 0.2794)
			(stroke
				(width 0.1)
				(type default)
			)
			(layer "F.Fab")
		)
		(fp_line
			(start -0.12065 0.3048)
			(end -0.67945 0.3048)
			(stroke
				(width 0.1)
				(type default)
			)
			(layer "F.Fab")
		)
		(fp_line
			(start -0.67945 0.3048)
			(end -0.67945 -0.305054)
			(stroke
				(width 0.1)
				(type default)
			)
			(layer "F.Fab")
		)
		(pad "1" smd circle
			(at -0.40005 0 90)
			(size 0 0)
			(layers "F.Cu" "F.Mask" "F.Paste")
			(net "P12V_NIC5_CO_ISET")
		)
		(pad "2" smd circle
			(at 0.40005 0 90)
			(size 0 0)
			(layers "F.Cu" "F.Mask" "F.Paste")
			(net "P12V_NIC5_CO_ISET_R")
		)
	)
	(footprint ""
		(layer "F.Cu")
		(at 10.180066 -386.496814 90)
		(property "Reference" "U442"
			(at -1.992376 6.412992 0)
			(unlocked yes)
			(layer "F.SilkS")
			(effects
				(font
					(size 0.7874 0.5842)
					(thickness 0.1524)
				)
				(justify left)
			)
		)
		(property "Value" ""
			(at 0 0 90)
			(layer "F.Fab")
			(effects
				(font
					(size 1.27 1.27)
				)
			)
		)
		(duplicate_pad_numbers_are_jumpers no)
		(fp_line
			(start 4.549902 -4.549902)
			(end 4.549902 -4.014724)
			(stroke
				(width 0.1524)
				(type default)
			)
			(layer "F.SilkS")
		)
		(fp_line
			(start 4.014724 -4.549902)
			(end 4.549902 -4.549902)
			(stroke
				(width 0.1524)
				(type default)
			)
			(layer "F.SilkS")
		)
		(fp_line
			(start -4.549902 -4.549902)
			(end -4.014724 -4.549902)
			(stroke
				(width 0.1524)
				(type default)
			)
			(layer "F.SilkS")
		)
		(fp_line
			(start -4.549902 -4.014724)
			(end -4.549902 -4.549902)
			(stroke
				(width 0.1524)
				(type default)
			)
			(layer "F.SilkS")
		)
		(fp_line
			(start 4.549902 4.014724)
			(end 4.549902 4.549902)
			(stroke
				(width 0.1524)
				(type default)
			)
			(layer "F.SilkS")
		)
		(fp_line
			(start 4.549902 4.549902)
			(end 4.014724 4.549902)
			(stroke
				(width 0.1524)
				(type default)
			)
			(layer "F.SilkS")
		)
		(fp_line
			(start -4.014724 4.549902)
			(end -4.549902 4.549902)
			(stroke
				(width 0.1524)
				(type default)
			)
			(layer "F.SilkS")
		)
		(fp_line
			(start -4.549902 4.549902)
			(end -4.549902 4.014724)
			(stroke
				(width 0.1524)
				(type default)
			)
			(layer "F.SilkS")
		)
		(fp_poly
			(pts
				(xy -5.134102 -4.041902) (xy -4.549902 -4.041902) (xy -4.549902 -4.626102) (xy -5.134102 -4.626102)
			)
			(stroke
				(width 0)
				(type default)
			)
			(fill yes)
			(layer "F.SilkS")
		)
		(fp_line
			(start 4.549902 -4.549902)
			(end 4.549902 4.549902)
			(stroke
				(width 0.1)
				(type default)
			)
			(layer "F.Fab")
		)
		(fp_line
			(start -4.549902 -4.549902)
			(end 4.549902 -4.549902)
			(stroke
				(width 0.1)
				(type default)
			)
			(layer "F.Fab")
		)
		(fp_line
			(start 4.549902 4.549902)
			(end -4.549902 4.549902)
			(stroke
				(width 0.1)
				(type default)
			)
			(layer "F.Fab")
		)
		(fp_line
			(start -4.549902 4.549902)
			(end -4.549902 -4.549902)
			(stroke
				(width 0.1)
				(type default)
			)
			(layer "F.Fab")
		)
		(fp_poly
			(pts
				(xy -5.134102 -4.041902) (xy -4.549902 -4.041902) (xy -4.549902 -4.626102) (xy -5.134102 -4.626102)
			)
			(stroke
				(width 0)
				(type default)
			)
			(fill yes)
			(layer "F.Fab")
		)
		(pad "1" smd circle
			(at -4.400042 -3.750056)
			(size 0 0)
			(layers "F.Cu" "F.Mask" "F.Paste")
			(net "Net_9318")
		)
		(pad "2" smd circle
			(at -4.400042 -3.24993)
			(size 0 0)
			(layers "F.Cu" "F.Mask" "F.Paste")
			(net "Net_9320")
		)
		(pad "3" smd circle
			(at -4.400042 -2.750058)
			(size 0 0)
			(layers "F.Cu" "F.Mask" "F.Paste")
			(net "Net_9301")
		)
		(pad "4" smd circle
			(at -4.400042 -2.249932)
			(size 0 0)
			(layers "F.Cu" "F.Mask" "F.Paste")
			(net "Net_9306")
		)
		(pad "5" smd circle
			(at -4.400042 -1.75006)
			(size 0 0)
			(layers "F.Cu" "F.Mask" "F.Paste")
			(net "P1V2_USB_8042")
		)
		(pad "6" smd circle
			(at -4.400042 -1.249934)
			(size 0 0)
			(layers "F.Cu" "F.Mask" "F.Paste")
			(net "Net_9311")
		)
		(pad "7" smd circle
			(at -4.400042 -0.750062)
			(size 0 0)
			(layers "F.Cu" "F.Mask" "F.Paste")
			(net "Net_9316")
		)
		(pad "8" smd circle
			(at -4.400042 -0.249936)
			(size 0 0)
			(layers "F.Cu" "F.Mask" "F.Paste")
			(net "P1V2_USB_8042")
		)
		(pad "9" smd circle
			(at -4.400042 0.249936)
			(size 0 0)
			(layers "F.Cu" "F.Mask" "F.Paste")
			(net "USB2_BIC_USB8042_DP")
		)
		(pad "10" smd circle
			(at -4.400042 0.750062)
			(size 0 0)
			(layers "F.Cu" "F.Mask" "F.Paste")
			(net "USB2_BIC_USB8042_DN")
		)
		(pad "11" smd circle
			(at -4.400042 1.249934)
			(size 0 0)
			(layers "F.Cu" "F.Mask" "F.Paste")
			(net "Net_9300")
		)
		(pad "12" smd circle
			(at -4.400042 1.75006)
			(size 0 0)
			(layers "F.Cu" "F.Mask" "F.Paste")
			(net "Net_9305")
		)
		(pad "13" smd circle
			(at -4.400042 2.249932)
			(size 0 0)
			(layers "F.Cu" "F.Mask" "F.Paste")
			(net "P1V2_USB_8042")
		)
		(pad "14" smd circle
			(at -4.400042 2.750058)
			(size 0 0)
			(layers "F.Cu" "F.Mask" "F.Paste")
			(net "Net_9310")
		)
		(pad "15" smd circle
			(at -4.400042 3.24993)
			(size 0 0)
			(layers "F.Cu" "F.Mask" "F.Paste")
			(net "Net_9315")
		)
		(pad "16" smd circle
			(at -4.400042 3.750056)
			(size 0 0)
			(layers "F.Cu" "F.Mask" "F.Paste")
			(net "P3V3_USB_8042")
		)
		(pad "17" smd circle
			(at -3.750056 4.400042 90)
			(size 0 0)
			(layers "F.Cu" "F.Mask" "F.Paste")
			(net "USB2_GPU_HMC_USB8042_DP")
		)
		(pad "18" smd circle
			(at -3.24993 4.400042 90)
			(size 0 0)
			(layers "F.Cu" "F.Mask" "F.Paste")
			(net "USB2_GPU_HMC_USB8042_DN")
		)
		(pad "19" smd circle
			(at -2.750058 4.400042 90)
			(size 0 0)
			(layers "F.Cu" "F.Mask" "F.Paste")
			(net "Net_9299")
		)
		(pad "20" smd circle
			(at -2.249932 4.400042 90)
			(size 0 0)
			(layers "F.Cu" "F.Mask" "F.Paste")
			(net "Net_9304")
		)
		(pad "21" smd circle
			(at -1.75006 4.400042 90)
			(size 0 0)
			(layers "F.Cu" "F.Mask" "F.Paste")
			(net "P1V2_USB_8042")
		)
		(pad "22" smd circle
			(at -1.249934 4.400042 90)
			(size 0 0)
			(layers "F.Cu" "F.Mask" "F.Paste")
			(net "Net_9309")
		)
		(pad "23" smd circle
			(at -0.750062 4.400042 90)
			(size 0 0)
			(layers "F.Cu" "F.Mask" "F.Paste")
			(net "Net_9314")
		)
		(pad "24" smd circle
			(at -0.249936 4.400042 90)
			(size 0 0)
			(layers "F.Cu" "F.Mask" "F.Paste")
			(net "Net_9317")
		)
		(pad "25" smd circle
			(at 0.249936 4.400042 90)
			(size 0 0)
			(layers "F.Cu" "F.Mask" "F.Paste")
			(net "Net_9319")
		)
		(pad "26" smd circle
			(at 0.750062 4.400042 90)
			(size 0 0)
			(layers "F.Cu" "F.Mask" "F.Paste")
			(net "Net_9298")
		)
		(pad "27" smd circle
			(at 1.249934 4.400042 90)
			(size 0 0)
			(layers "F.Cu" "F.Mask" "F.Paste")
			(net "Net_9303")
		)
		(pad "28" smd circle
			(at 1.75006 4.400042 90)
			(size 0 0)
			(layers "F.Cu" "F.Mask" "F.Paste")
			(net "P1V2_USB_8042")
		)
		(pad "29" smd circle
			(at 2.249932 4.400042 90)
			(size 0 0)
			(layers "F.Cu" "F.Mask" "F.Paste")
			(net "Net_9308")
		)
		(pad "30" smd circle
			(at 2.750058 4.400042 90)
			(size 0 0)
			(layers "F.Cu" "F.Mask" "F.Paste")
			(net "Net_9313")
		)
		(pad "31" smd circle
			(at 3.24993 4.400042 90)
			(size 0 0)
			(layers "F.Cu" "F.Mask" "F.Paste")
			(net "P1V2_USB_8042")
		)
		(pad "32" smd circle
			(at 3.750056 4.400042 90)
			(size 0 0)
			(layers "F.Cu" "F.Mask" "F.Paste")
			(net "Net_9322")
		)
		(pad "33" smd circle
			(at 4.400042 3.750056)
			(size 0 0)
			(layers "F.Cu" "F.Mask" "F.Paste")
			(net "BIC_USB_8042_HUB_PWRCTL3")
		)
		(pad "34" smd circle
			(at 4.400042 3.24993)
			(size 0 0)
			(layers "F.Cu" "F.Mask" "F.Paste")
			(net "P3V3_USB_8042")
		)
		(pad "35" smd circle
			(at 4.400042 2.750058)
			(size 0 0)
			(layers "F.Cu" "F.Mask" "F.Paste")
			(net "BIC_USB_8042_HUB_PWRCTL2")
		)
		(pad "36" smd circle
			(at 4.400042 2.249932)
			(size 0 0)
			(layers "F.Cu" "F.Mask" "F.Paste")
			(net "Net_9323")
		)
		(pad "37" smd circle
			(at 4.400042 1.75006)
			(size 0 0)
			(layers "F.Cu" "F.Mask" "F.Paste")
			(net "Net_9295")
		)
		(pad "38" smd circle
			(at 4.400042 1.249934)
			(size 0 0)
			(layers "F.Cu" "F.Mask" "F.Paste")
			(net "Net_9296")
		)
		(pad "39" smd circle
			(at 4.400042 0.750062)
			(size 0 0)
			(layers "F.Cu" "F.Mask" "F.Paste")
			(net "Net_9294")
		)
		(pad "40" smd circle
			(at 4.400042 0.249936)
			(size 0 0)
			(layers "F.Cu" "F.Mask" "F.Paste")
			(net "BIC_USB_8042_HUB_FULLPWRMGMTZ")
		)
		(pad "41" smd circle
			(at 4.400042 -0.249936)
			(size 0 0)
			(layers "F.Cu" "F.Mask" "F.Paste")
			(net "Net_9321")
		)
		(pad "42" smd circle
			(at 4.400042 -0.750062)
			(size 0 0)
			(layers "F.Cu" "F.Mask" "F.Paste")
			(net "BIC_USB_8042_HUB_GANGED")
		)
		(pad "43" smd circle
			(at 4.400042 -1.249934)
			(size 0 0)
			(layers "F.Cu" "F.Mask" "F.Paste")
			(net "BIC_USB_8042_HUB_OVCUR4")
		)
		(pad "44" smd circle
			(at 4.400042 -1.75006)
			(size 0 0)
			(layers "F.Cu" "F.Mask" "F.Paste")
			(net "BIC_USB_8042_HUB_OVCUR3")
		)
		(pad "45" smd circle
			(at 4.400042 -2.249932)
			(size 0 0)
			(layers "F.Cu" "F.Mask" "F.Paste")
			(net "BIC_USB_8042_HUB_HS_SUSPEND")
		)
		(pad "46" smd circle
			(at 4.400042 -2.750058)
			(size 0 0)
			(layers "F.Cu" "F.Mask" "F.Paste")
			(net "BIC_USB_8042_HUB_OVCUR1")
		)
		(pad "47" smd circle
			(at 4.400042 -3.24993)
			(size 0 0)
			(layers "F.Cu" "F.Mask" "F.Paste")
			(net "BIC_USB_8042_HUB_OVCUR2")
		)
		(pad "48" smd circle
			(at 4.400042 -3.750056)
			(size 0 0)
			(layers "F.Cu" "F.Mask" "F.Paste")
			(net "BIC_USB_8042_HUB_VBUS")
		)
		(pad "49" smd circle
			(at 3.750056 -4.400042 90)
			(size 0 0)
			(layers "F.Cu" "F.Mask" "F.Paste")
			(net "BIC_USB_8042_HUB_TEST")
		)
		(pad "50" smd circle
			(at 3.24993 -4.400042 90)
			(size 0 0)
			(layers "F.Cu" "F.Mask" "F.Paste")
			(net "BIC_USB_8042_HUB_GRSTZ")
		)
		(pad "51" smd circle
			(at 2.750058 -4.400042 90)
			(size 0 0)
			(layers "F.Cu" "F.Mask" "F.Paste")
			(net "P1V2_USB_8042")
		)
		(pad "52" smd circle
			(at 2.249932 -4.400042 90)
			(size 0 0)
			(layers "F.Cu" "F.Mask" "F.Paste")
			(net "P3V3_USB_8042")
		)
		(pad "53" smd circle
			(at 1.75006 -4.400042 90)
			(size 0 0)
			(layers "F.Cu" "F.Mask" "F.Paste")
			(net "USB2_MB_BMC_USB8042_DP")
		)
		(pad "54" smd circle
			(at 1.249934 -4.400042 90)
			(size 0 0)
			(layers "F.Cu" "F.Mask" "F.Paste")
			(net "USB2_MB_BMC_USB8042_DN")
		)
		(pad "55" smd circle
			(at 0.750062 -4.400042 90)
			(size 0 0)
			(layers "F.Cu" "F.Mask" "F.Paste")
			(net "Net_9297")
		)
		(pad "56" smd circle
			(at 0.249936 -4.400042 90)
			(size 0 0)
			(layers "F.Cu" "F.Mask" "F.Paste")
			(net "Net_9302")
		)
		(pad "57" smd circle
			(at -0.249936 -4.400042 90)
			(size 0 0)
			(layers "F.Cu" "F.Mask" "F.Paste")
			(net "P1V2_USB_8042")
		)
		(pad "58" smd circle
			(at -0.750062 -4.400042 90)
			(size 0 0)
			(layers "F.Cu" "F.Mask" "F.Paste")
			(net "Net_9307")
		)
		(pad "59" smd circle
			(at -1.249934 -4.400042 90)
			(size 0 0)
			(layers "F.Cu" "F.Mask" "F.Paste")
			(net "Net_9312")
		)
		(pad "60" smd circle
			(at -1.75006 -4.400042 90)
			(size 0 0)
			(layers "F.Cu" "F.Mask" "F.Paste")
			(net "Net_9324")
		)
		(pad "61" smd circle
			(at -2.249932 -4.400042 90)
			(size 0 0)
			(layers "F.Cu" "F.Mask" "F.Paste")
			(net "BIC_USB_8042_HUB_XOUT")
		)
		(pad "62" smd circle
			(at -2.750058 -4.400042 90)
			(size 0 0)
			(layers "F.Cu" "F.Mask" "F.Paste")
			(net "BIC_USB_8042_HUB_XIN")
		)
		(pad "63" smd circle
			(at -3.24993 -4.400042 90)
			(size 0 0)
			(layers "F.Cu" "F.Mask" "F.Paste")
			(net "P3V3_USB_8042")
		)
		(pad "64" smd circle
			(at -3.750056 -4.400042 90)
			(size 0 0)
			(layers "F.Cu" "F.Mask" "F.Paste")
			(net "BIC_USB_8042_HUB_R1")
		)
		(pad "TH" smd circle
			(at 0 0 90)
			(size 0 0)
			(layers "F.Cu" "F.Mask" "F.Paste")
			(net "GND")
		)
		(zone
			(layer "F.Cu")
			(hatch none 0.5)
			(connect_pads
				(clearance 0)
			)
			(min_thickness 0.25)
			(keepout
				(tracks not_allowed)
				(vias allowed)
				(pads allowed)
				(copperpour not_allowed)
				(footprints allowed)
			)
			(placement
				(enabled no)
				(sheetname "")
			)
			(fill
				(thermal_gap 0.5)
				(thermal_bridge_width 0.5)
				(island_removal_mode 0)
			)
			(polygon
				(pts
					(xy 14.218666 -382.458214) (xy 10.205466 -382.458214) (xy 10.205466 -383.44602)
					(arc
						(start 13.130022 -383.44602)
						(mid 13.201325 -383.475555)
						(end 13.23086 -383.546858)
					)
					(arc
						(start 13.23086 -389.44677)
						(mid 13.201325 -389.518073)
						(end 13.130022 -389.547608)
					)
					(arc
						(start 7.23011 -389.547608)
						(mid 7.158807 -389.518073)
						(end 7.129272 -389.44677)
					)
					(arc
						(start 7.129272 -383.546858)
						(mid 7.158807 -383.475555)
						(end 7.23011 -383.44602)
					)
					(xy 10.154666 -383.44602) (xy 10.180066 -383.44602) (xy 10.180066 -382.458214) (xy 10.154666 -382.458214)
					(xy 6.141466 -382.458214) (xy 6.141466 -390.535414) (xy 14.218666 -390.535414)
				)
			)
		)
	)
	(footprint ""
		(layer "F.Cu")
		(at 327.992232 -28.225242 180)
		(property "Reference" "C518"
			(at 0 0 180)
			(layer "F.SilkS")
			(hide yes)
			(effects
				(font
					(size 1.27 1.27)
				)
			)
		)
		(property "Value" ""
			(at 0 0 180)
			(layer "F.Fab")
			(effects
				(font
					(size 1.27 1.27)
				)
			)
		)
		(duplicate_pad_numbers_are_jumpers no)
		(fp_line
			(start 0.299974 0.150114)
			(end -0.299974 0.150114)
			(stroke
				(width 0.1)
				(type default)
			)
			(layer "F.Fab")
		)
		(fp_line
			(start 0.299974 -0.150114)
			(end 0.299974 0.150114)
			(stroke
				(width 0.1)
				(type default)
			)
			(layer "F.Fab")
		)
		(fp_line
			(start -0.299974 0.150114)
			(end -0.299974 -0.150114)
			(stroke
				(width 0.1)
				(type default)
			)
			(layer "F.Fab")
		)
		(fp_line
			(start -0.299974 -0.150114)
			(end 0.299974 -0.150114)
			(stroke
				(width 0.1)
				(type default)
			)
			(layer "F.Fab")
		)
		(pad "1" smd rect
			(at -0.2667 0 180)
			(size 0.3048 0.381)
			(layers "F.Cu" "F.Mask" "F.Paste")
			(net "P5E_PEX2_STN2_TX_DN<32>")
		)
		(pad "2" smd rect
			(at 0.2667 0 180)
			(size 0.3048 0.381)
			(layers "F.Cu" "F.Mask" "F.Paste")
			(net "P5E_PEX2_STN2_TX_C_DN<32>")
		)
	)
	(footprint ""
		(layer "F.Cu")
		(at 260.98246 -29.875734)
		(property "Reference" "PU128"
			(at -3.312414 -2.21742 90)
			(unlocked yes)
			(layer "F.SilkS")
			(effects
				(font
					(size 0.7874 0.5842)
					(thickness 0.1524)
				)
			)
		)
		(property "Value" ""
			(at 0 0 0)
			(layer "F.Fab")
			(effects
				(font
					(size 1.27 1.27)
				)
			)
		)
		(duplicate_pad_numbers_are_jumpers no)
		(fp_line
			(start -1.239774 -1.495298)
			(end 1.239774 -1.495298)
			(stroke
				(width 0.1524)
				(type default)
			)
			(layer "F.SilkS")
		)
		(fp_line
			(start -1.239774 1.495298)
			(end -1.239774 -1.495298)
			(stroke
				(width 0.1524)
				(type default)
			)
			(layer "F.SilkS")
		)
		(fp_line
			(start 1.239774 -1.495298)
			(end 1.239774 1.495298)
			(stroke
				(width 0.1524)
				(type default)
			)
			(layer "F.SilkS")
		)
		(fp_line
			(start 1.239774 1.495298)
			(end -1.239774 1.495298)
			(stroke
				(width 0.1524)
				(type default)
			)
			(layer "F.SilkS")
		)
		(fp_poly
			(pts
				(xy -1.923796 -1.318514) (xy -2.642108 -0.600202) (xy -1.56464 -0.241046)
			)
			(stroke
				(width 0)
				(type default)
			)
			(fill yes)
			(layer "F.SilkS")
		)
		(fp_line
			(start -0.8001 -1.050036)
			(end 0.8001 -1.050036)
			(stroke
				(width 0.1)
				(type default)
			)
			(layer "F.Fab")
		)
		(fp_line
			(start -0.8001 1.050036)
			(end -0.8001 -1.050036)
			(stroke
				(width 0.1)
				(type default)
			)
			(layer "F.Fab")
		)
		(fp_line
			(start 0.8001 -1.050036)
			(end 0.8001 1.050036)
			(stroke
				(width 0.1)
				(type default)
			)
			(layer "F.Fab")
		)
		(fp_line
			(start 0.8001 1.050036)
			(end -0.8001 1.050036)
			(stroke
				(width 0.1)
				(type default)
			)
			(layer "F.Fab")
		)
		(fp_poly
			(pts
				(xy -2.458974 -0.508) (xy -2.458974 0.508) (xy -1.442974 0)
			)
			(stroke
				(width 0)
				(type default)
			)
			(fill yes)
			(layer "F.Fab")
		)
		(pad "1_2" smd circle
			(at -0.374904 0 90)
			(size 0 0)
			(layers "F.Cu" "F.Mask" "F.Paste")
			(net "P3V3_AUX")
		)
		(pad "3" smd rect
			(at -0.499872 0.999998)
			(size 0.254 0.7112)
			(layers "F.Cu" "F.Mask" "F.Paste")
			(net "GND")
		)
		(pad "4" smd rect
			(at 0 0.999998)
			(size 0.254 0.7112)
			(layers "F.Cu" "F.Mask" "F.Paste")
			(net "P3V3_SSD9_CO_ILIMIT")
		)
		(pad "5" smd rect
			(at 0.499872 0.999998)
			(size 0.254 0.7112)
			(layers "F.Cu" "F.Mask" "F.Paste")
			(net "P3V3_SSD9_CO_MODE")
		)
		(pad "6_7" smd circle
			(at 0.374904 0 270)
			(size 0 0)
			(layers "F.Cu" "F.Mask" "F.Paste")
			(net "P3V3_SSD9")
		)
		(pad "8" smd rect
			(at 0.499872 -0.999998)
			(size 0.254 0.7112)
			(layers "F.Cu" "F.Mask" "F.Paste")
			(net "P3V3_SSD9_CO_GATE")
		)
		(pad "9" smd rect
			(at 0 -0.999998)
			(size 0.254 0.7112)
			(layers "F.Cu" "F.Mask" "F.Paste")
			(net "P3V3_SSD9_CO_EN")
		)
		(pad "10" smd rect
			(at -0.499872 -0.999998)
			(size 0.254 0.7112)
			(layers "F.Cu" "F.Mask" "F.Paste")
			(net "P3V3_SSD9_CO_DV_DT")
		)
	)
	(footprint ""
		(layer "F.Cu")
		(at 120.947942 -40.037258 90)
		(property "Reference" "U367"
			(at 0.247142 2.344928 90)
			(unlocked yes)
			(layer "F.SilkS")
			(effects
				(font
					(size 0.7874 0.5842)
					(thickness 0.1524)
				)
			)
		)
		(property "Value" ""
			(at 0 0 90)
			(layer "F.Fab")
			(effects
				(font
					(size 1.27 1.27)
				)
			)
		)
		(duplicate_pad_numbers_are_jumpers no)
		(fp_line
			(start -1.949958 -1.610106)
			(end 1.949958 -1.610106)
			(stroke
				(width 0.1524)
				(type default)
			)
			(layer "F.SilkS")
		)
		(fp_line
			(start 1.949958 -1.560068)
			(end 1.949958 1.610106)
			(stroke
				(width 0.1524)
				(type default)
			)
			(layer "F.SilkS")
		)
		(fp_line
			(start 1.949958 1.610106)
			(end -1.949958 1.610106)
			(stroke
				(width 0.1524)
				(type default)
			)
			(layer "F.SilkS")
		)
		(fp_line
			(start -1.949958 1.610106)
			(end -1.949958 -1.610106)
			(stroke
				(width 0.1524)
				(type default)
			)
			(layer "F.SilkS")
		)
		(fp_line
			(start 0.750062 -1.560068)
			(end 0.750062 1.560068)
			(stroke
				(width 0.1)
				(type default)
			)
			(layer "F.Fab")
		)
		(fp_line
			(start -0.750062 -1.560068)
			(end 0.750062 -1.560068)
			(stroke
				(width 0.1)
				(type default)
			)
			(layer "F.Fab")
		)
		(fp_line
			(start 0.750062 1.560068)
			(end -0.750062 1.560068)
			(stroke
				(width 0.1)
				(type default)
			)
			(layer "F.Fab")
		)
		(fp_line
			(start -0.750062 1.560068)
			(end -0.750062 -1.560068)
			(stroke
				(width 0.1)
				(type default)
			)
			(layer "F.Fab")
		)
		(pad "D" smd rect
			(at 1.100074 0)
			(size 1.016 1.4224)
			(layers "F.Cu" "F.Mask" "F.Paste")
			(net "SSD4_AUX_P3V3_EN")
		)
		(pad "G" smd rect
			(at -1.100074 -0.94996)
			(size 1.016 1.4224)
			(layers "F.Cu" "F.Mask" "F.Paste")
			(net "PRSNT_SSD4_R1_N")
		)
		(pad "S" smd rect
			(at -1.100074 0.94996)
			(size 1.016 1.4224)
			(layers "F.Cu" "F.Mask" "F.Paste")
			(net "GND")
		)
	)
	(footprint ""
		(layer "F.Cu")
		(at 98.575368 -69.47916 180)
		(property "Reference" "PU77"
			(at -1.959102 3.72364 90)
			(unlocked yes)
			(layer "F.SilkS")
			(effects
				(font
					(size 0.7874 0.5842)
					(thickness 0.1524)
				)
			)
		)
		(property "Value" ""
			(at 0 0 180)
			(layer "F.Fab")
			(effects
				(font
					(size 1.27 1.27)
				)
			)
		)
		(duplicate_pad_numbers_are_jumpers no)
		(fp_line
			(start 1.239774 1.495298)
			(end -1.239774 1.495298)
			(stroke
				(width 0.1524)
				(type default)
			)
			(layer "F.SilkS")
		)
		(fp_line
			(start 1.239774 -1.495298)
			(end 1.239774 1.495298)
			(stroke
				(width 0.1524)
				(type default)
			)
			(layer "F.SilkS")
		)
		(fp_line
			(start -1.239774 1.495298)
			(end -1.239774 -1.495298)
			(stroke
				(width 0.1524)
				(type default)
			)
			(layer "F.SilkS")
		)
		(fp_line
			(start -1.239774 -1.495298)
			(end 1.239774 -1.495298)
			(stroke
				(width 0.1524)
				(type default)
			)
			(layer "F.SilkS")
		)
		(fp_poly
			(pts
				(xy -1.720342 -1.176782) (xy -2.438654 -0.45847) (xy -1.361186 -0.099314)
			)
			(stroke
				(width 0)
				(type default)
			)
			(fill yes)
			(layer "F.SilkS")
		)
		(fp_line
			(start 0.8001 1.050036)
			(end -0.8001 1.050036)
			(stroke
				(width 0.1)
				(type default)
			)
			(layer "F.Fab")
		)
		(fp_line
			(start 0.8001 -1.050036)
			(end 0.8001 1.050036)
			(stroke
				(width 0.1)
				(type default)
			)
			(layer "F.Fab")
		)
		(fp_line
			(start -0.8001 1.050036)
			(end -0.8001 -1.050036)
			(stroke
				(width 0.1)
				(type default)
			)
			(layer "F.Fab")
		)
		(fp_line
			(start -0.8001 -1.050036)
			(end 0.8001 -1.050036)
			(stroke
				(width 0.1)
				(type default)
			)
			(layer "F.Fab")
		)
		(fp_poly
			(pts
				(xy -2.458974 -0.508) (xy -2.458974 0.508) (xy -1.442974 0)
			)
			(stroke
				(width 0)
				(type default)
			)
			(fill yes)
			(layer "F.Fab")
		)
		(pad "1_2" smd circle
			(at -0.374904 0 270)
			(size 0 0)
			(layers "F.Cu" "F.Mask" "F.Paste")
			(net "P12V_AUX")
		)
		(pad "3" smd rect
			(at -0.499872 0.999998 180)
			(size 0.254 0.7112)
			(layers "F.Cu" "F.Mask" "F.Paste")
			(net "GND")
		)
		(pad "4" smd rect
			(at 0 0.999998 180)
			(size 0.254 0.7112)
			(layers "F.Cu" "F.Mask" "F.Paste")
			(net "P12V_SSD3_CO_ILIMIT")
		)
		(pad "5" smd rect
			(at 0.499872 0.999998 180)
			(size 0.254 0.7112)
			(layers "F.Cu" "F.Mask" "F.Paste")
			(net "P12V_SSD3_CO_MODE")
		)
		(pad "6_7" smd circle
			(at 0.374904 0 90)
			(size 0 0)
			(layers "F.Cu" "F.Mask" "F.Paste")
			(net "P12V_SSD3_R")
		)
		(pad "8" smd rect
			(at 0.499872 -0.999998 180)
			(size 0.254 0.7112)
			(layers "F.Cu" "F.Mask" "F.Paste")
			(net "P12V_SSD3_CO_GATE")
		)
		(pad "9" smd rect
			(at 0 -0.999998 180)
			(size 0.254 0.7112)
			(layers "F.Cu" "F.Mask" "F.Paste")
			(net "P12V_SSD3_CO_EN")
		)
		(pad "10" smd rect
			(at -0.499872 -0.999998 180)
			(size 0.254 0.7112)
			(layers "F.Cu" "F.Mask" "F.Paste")
			(net "P12V_SSD3_CO_DV_DT")
		)
	)
	(footprint ""
		(layer "F.Cu")
		(at 241.624612 -60.845192 -90)
		(property "Reference" "R5994"
			(at 0 0 270)
			(layer "F.SilkS")
			(hide yes)
			(effects
				(font
					(size 1.27 1.27)
				)
			)
		)
		(property "Value" ""
			(at 0 0 270)
			(layer "F.Fab")
			(effects
				(font
					(size 1.27 1.27)
				)
			)
		)
		(duplicate_pad_numbers_are_jumpers no)
		(fp_line
			(start -0.7874 0.4064)
			(end -0.7874 -0.4064)
			(stroke
				(width 0.1524)
				(type default)
			)
			(layer "F.SilkS")
		)
		(fp_line
			(start 0.7874 0.4064)
			(end -0.7874 0.4064)
			(stroke
				(width 0.1524)
				(type default)
			)
			(layer "F.SilkS")
		)
		(fp_line
			(start -0.7874 -0.4064)
			(end 0.7874 -0.4064)
			(stroke
				(width 0.1524)
				(type default)
			)
			(layer "F.SilkS")
		)
		(fp_line
			(start 0.7874 -0.4064)
			(end 0.7874 0.4064)
			(stroke
				(width 0.1524)
				(type default)
			)
			(layer "F.SilkS")
		)
		(fp_line
			(start -0.67945 0.3048)
			(end -0.67945 -0.305054)
			(stroke
				(width 0.1)
				(type default)
			)
			(layer "F.Fab")
		)
		(fp_line
			(start -0.12065 0.3048)
			(end -0.67945 0.3048)
			(stroke
				(width 0.1)
				(type default)
			)
			(layer "F.Fab")
		)
		(fp_line
			(start 0.120396 0.3048)
			(end 0.120396 0.2794)
			(stroke
				(width 0.1)
				(type default)
			)
			(layer "F.Fab")
		)
		(fp_line
			(start 0.67945 0.3048)
			(end 0.120396 0.3048)
			(stroke
				(width 0.1)
				(type default)
			)
			(layer "F.Fab")
		)
		(fp_line
			(start -0.12065 0.2794)
			(end -0.12065 0.3048)
			(stroke
				(width 0.1)
				(type default)
			)
			(layer "F.Fab")
		)
		(fp_line
			(start 0.120396 0.2794)
			(end -0.12065 0.2794)
			(stroke
				(width 0.1)
				(type default)
			)
			(layer "F.Fab")
		)
		(fp_line
			(start -0.12065 -0.2794)
			(end 0.12065 -0.2794)
			(stroke
				(width 0.1)
				(type default)
			)
			(layer "F.Fab")
		)
		(fp_line
			(start 0.12065 -0.2794)
			(end 0.12065 -0.3048)
			(stroke
				(width 0.1)
				(type default)
			)
			(layer "F.Fab")
		)
		(fp_line
			(start 0.12065 -0.3048)
			(end 0.67945 -0.3048)
			(stroke
				(width 0.1)
				(type default)
			)
			(layer "F.Fab")
		)
		(fp_line
			(start 0.67945 -0.3048)
			(end 0.67945 0.3048)
			(stroke
				(width 0.1)
				(type default)
			)
			(layer "F.Fab")
		)
		(fp_line
			(start -0.67945 -0.305054)
			(end -0.12065 -0.305054)
			(stroke
				(width 0.1)
				(type default)
			)
			(layer "F.Fab")
		)
		(fp_line
			(start -0.12065 -0.305054)
			(end -0.12065 -0.2794)
			(stroke
				(width 0.1)
				(type default)
			)
			(layer "F.Fab")
		)
		(pad "1" smd circle
			(at -0.40005 0 270)
			(size 0 0)
			(layers "F.Cu" "F.Mask" "F.Paste")
			(net "PWRGD_P12V_SSD8_D")
		)
		(pad "2" smd circle
			(at 0.40005 0 270)
			(size 0 0)
			(layers "F.Cu" "F.Mask" "F.Paste")
			(net "PWRGD_P12V_SSD8_R")
		)
	)
	(footprint ""
		(layer "F.Cu")
		(at 118.94058 -122.123454)
		(property "Reference" "PC595"
			(at 0 0 0)
			(layer "F.SilkS")
			(hide yes)
			(effects
				(font
					(size 1.27 1.27)
				)
			)
		)
		(property "Value" ""
			(at 0 0 0)
			(layer "F.Fab")
			(effects
				(font
					(size 1.27 1.27)
				)
			)
		)
		(duplicate_pad_numbers_are_jumpers no)
		(fp_line
			(start -1.524 -0.762)
			(end 1.524 -0.762)
			(stroke
				(width 0.1524)
				(type default)
			)
			(layer "F.SilkS")
		)
		(fp_line
			(start -1.524 0.762)
			(end -1.524 -0.762)
			(stroke
				(width 0.1524)
				(type default)
			)
			(layer "F.SilkS")
		)
		(fp_line
			(start 1.524 -0.762)
			(end 1.524 0.762)
			(stroke
				(width 0.1524)
				(type default)
			)
			(layer "F.SilkS")
		)
		(fp_line
			(start 1.524 0.762)
			(end -1.524 0.762)
			(stroke
				(width 0.1524)
				(type default)
			)
			(layer "F.SilkS")
		)
		(fp_line
			(start -1.1049 -0.724916)
			(end -1.1049 0.724916)
			(stroke
				(width 0.1)
				(type default)
			)
			(layer "F.Fab")
		)
		(fp_line
			(start -1.1049 0.724916)
			(end 1.1049 0.724916)
			(stroke
				(width 0.1)
				(type default)
			)
			(layer "F.Fab")
		)
		(fp_line
			(start 1.1049 -0.724916)
			(end -1.1049 -0.724916)
			(stroke
				(width 0.1)
				(type default)
			)
			(layer "F.Fab")
		)
		(fp_line
			(start 1.1049 0.724916)
			(end 1.1049 -0.724916)
			(stroke
				(width 0.1)
				(type default)
			)
			(layer "F.Fab")
		)
		(pad "1" smd rect
			(at -0.889 0 180)
			(size 1.016 1.27)
			(layers "F.Cu" "F.Mask" "F.Paste")
			(net "P3V3")
		)
		(pad "2" smd rect
			(at 0.889 0 180)
			(size 1.016 1.27)
			(layers "F.Cu" "F.Mask" "F.Paste")
			(net "GND")
		)
	)
	(footprint ""
		(layer "F.Cu")
		(at 361.832652 -396.50035 180)
		(property "Reference" "Q246"
			(at -0.790448 -1.975358 0)
			(unlocked yes)
			(layer "F.SilkS")
			(effects
				(font
					(size 0.7874 0.5842)
					(thickness 0.1524)
				)
			)
		)
		(property "Value" ""
			(at 0 0 180)
			(layer "F.Fab")
			(effects
				(font
					(size 1.27 1.27)
				)
			)
		)
		(duplicate_pad_numbers_are_jumpers no)
		(fp_line
			(start 1.376172 1.199896)
			(end -1.376172 1.199896)
			(stroke
				(width 0.1524)
				(type default)
			)
			(layer "F.SilkS")
		)
		(fp_line
			(start 1.376172 -1.199896)
			(end 1.376172 1.199896)
			(stroke
				(width 0.1524)
				(type default)
			)
			(layer "F.SilkS")
		)
		(fp_line
			(start 0.508 -1.199896)
			(end 1.376172 -1.199896)
			(stroke
				(width 0.1524)
				(type default)
			)
			(layer "F.SilkS")
		)
		(fp_line
			(start 0 -0.762)
			(end 0.508 -1.199896)
			(stroke
				(width 0.1524)
				(type default)
			)
			(layer "F.SilkS")
		)
		(fp_line
			(start -0.508 -1.199896)
			(end 0 -0.762)
			(stroke
				(width 0.1524)
				(type default)
			)
			(layer "F.SilkS")
		)
		(fp_line
			(start -1.376172 1.199896)
			(end -1.376172 -1.199896)
			(stroke
				(width 0.1524)
				(type default)
			)
			(layer "F.SilkS")
		)
		(fp_line
			(start -1.376172 -1.199896)
			(end -0.508 -1.199896)
			(stroke
				(width 0.1524)
				(type default)
			)
			(layer "F.SilkS")
		)
		(fp_poly
			(pts
				(xy -1.4605 -0.7493) (xy -2.2225 -1.1303) (xy -2.2225 -0.3683)
			)
			(stroke
				(width 0)
				(type default)
			)
			(fill yes)
			(layer "F.SilkS")
		)
		(fp_line
			(start 0.674878 1.100074)
			(end -0.674878 1.100074)
			(stroke
				(width 0.1)
				(type default)
			)
			(layer "F.Fab")
		)
		(fp_line
			(start 0.674878 -1.100074)
			(end 0.674878 1.100074)
			(stroke
				(width 0.1)
				(type default)
			)
			(layer "F.Fab")
		)
		(fp_line
			(start -0.674878 1.100074)
			(end -0.674878 -1.100074)
			(stroke
				(width 0.1)
				(type default)
			)
			(layer "F.Fab")
		)
		(fp_line
			(start -0.674878 -1.100074)
			(end 0.674878 -1.100074)
			(stroke
				(width 0.1)
				(type default)
			)
			(layer "F.Fab")
		)
		(fp_poly
			(pts
				(xy -1.4605 -0.7493) (xy -2.2225 -1.1303) (xy -2.2225 -0.3683)
			)
			(stroke
				(width 0)
				(type default)
			)
			(fill yes)
			(layer "F.Fab")
		)
		(pad "1" smd rect
			(at -0.899922 -0.750062 90)
			(size 0.6096 0.6096)
			(layers "F.Cu" "F.Mask" "F.Paste")
			(net "GND")
		)
		(pad "2" smd rect
			(at -0.899922 0 90)
			(size 0.4064 0.6096)
			(layers "F.Cu" "F.Mask" "F.Paste")
			(net "MB_3V3IO_RSVD3")
		)
		(pad "3" smd rect
			(at -0.899922 0.750062 90)
			(size 0.6096 0.6096)
			(layers "F.Cu" "F.Mask" "F.Paste")
			(net "MB_3V3IO_RSVD3_ISO")
		)
		(pad "4" smd rect
			(at 0.899922 0.750062 90)
			(size 0.6096 0.6096)
			(layers "F.Cu" "F.Mask" "F.Paste")
			(net "GND")
		)
		(pad "5" smd rect
			(at 0.899922 0 90)
			(size 0.4064 0.6096)
			(layers "F.Cu" "F.Mask" "F.Paste")
			(net "MB_3V3IO_RSVD3_N")
		)
		(pad "6" smd rect
			(at 0.899922 -0.750062 90)
			(size 0.6096 0.6096)
			(layers "F.Cu" "F.Mask" "F.Paste")
			(net "MB_3V3IO_RSVD3_N")
		)
	)
	(footprint ""
		(layer "F.Cu")
		(at 205.822296 -213.593426)
		(property "Reference" "R5919"
			(at 0 0 0)
			(layer "F.SilkS")
			(hide yes)
			(effects
				(font
					(size 1.27 1.27)
				)
			)
		)
		(property "Value" ""
			(at 0 0 0)
			(layer "F.Fab")
			(effects
				(font
					(size 1.27 1.27)
				)
			)
		)
		(duplicate_pad_numbers_are_jumpers no)
		(fp_line
			(start -0.7874 -0.4064)
			(end 0.7874 -0.4064)
			(stroke
				(width 0.1524)
				(type default)
			)
			(layer "F.SilkS")
		)
		(fp_line
			(start -0.7874 0.4064)
			(end -0.7874 -0.4064)
			(stroke
				(width 0.1524)
				(type default)
			)
			(layer "F.SilkS")
		)
		(fp_line
			(start 0.7874 -0.4064)
			(end 0.7874 0.4064)
			(stroke
				(width 0.1524)
				(type default)
			)
			(layer "F.SilkS")
		)
		(fp_line
			(start 0.7874 0.4064)
			(end -0.7874 0.4064)
			(stroke
				(width 0.1524)
				(type default)
			)
			(layer "F.SilkS")
		)
		(fp_line
			(start -0.67945 -0.305054)
			(end -0.12065 -0.305054)
			(stroke
				(width 0.1)
				(type default)
			)
			(layer "F.Fab")
		)
		(fp_line
			(start -0.67945 0.3048)
			(end -0.67945 -0.305054)
			(stroke
				(width 0.1)
				(type default)
			)
			(layer "F.Fab")
		)
		(fp_line
			(start -0.12065 -0.305054)
			(end -0.12065 -0.2794)
			(stroke
				(width 0.1)
				(type default)
			)
			(layer "F.Fab")
		)
		(fp_line
			(start -0.12065 -0.2794)
			(end 0.12065 -0.2794)
			(stroke
				(width 0.1)
				(type default)
			)
			(layer "F.Fab")
		)
		(fp_line
			(start -0.12065 0.2794)
			(end -0.12065 0.3048)
			(stroke
				(width 0.1)
				(type default)
			)
			(layer "F.Fab")
		)
		(fp_line
			(start -0.12065 0.3048)
			(end -0.67945 0.3048)
			(stroke
				(width 0.1)
				(type default)
			)
			(layer "F.Fab")
		)
		(fp_line
			(start 0.120396 0.2794)
			(end -0.12065 0.2794)
			(stroke
				(width 0.1)
				(type default)
			)
			(layer "F.Fab")
		)
		(fp_line
			(start 0.120396 0.3048)
			(end 0.120396 0.2794)
			(stroke
				(width 0.1)
				(type default)
			)
			(layer "F.Fab")
		)
		(fp_line
			(start 0.12065 -0.3048)
			(end 0.67945 -0.3048)
			(stroke
				(width 0.1)
				(type default)
			)
			(layer "F.Fab")
		)
		(fp_line
			(start 0.12065 -0.2794)
			(end 0.12065 -0.3048)
			(stroke
				(width 0.1)
				(type default)
			)
			(layer "F.Fab")
		)
		(fp_line
			(start 0.67945 -0.3048)
			(end 0.67945 0.3048)
			(stroke
				(width 0.1)
				(type default)
			)
			(layer "F.Fab")
		)
		(fp_line
			(start 0.67945 0.3048)
			(end 0.120396 0.3048)
			(stroke
				(width 0.1)
				(type default)
			)
			(layer "F.Fab")
		)
		(pad "1" smd circle
			(at -0.40005 0)
			(size 0 0)
			(layers "F.Cu" "F.Mask" "F.Paste")
			(net "GND")
		)
		(pad "2" smd circle
			(at 0.40005 0)
			(size 0 0)
			(layers "F.Cu" "F.Mask" "F.Paste")
			(net "BIC_UART_SEL2")
		)
	)
	(footprint ""
		(layer "F.Cu")
		(at 231.499664 -204.44206 90)
		(property "Reference" "R5513"
			(at 0 0 90)
			(layer "F.SilkS")
			(hide yes)
			(effects
				(font
					(size 1.27 1.27)
				)
			)
		)
		(property "Value" ""
			(at 0 0 90)
			(layer "F.Fab")
			(effects
				(font
					(size 1.27 1.27)
				)
			)
		)
		(duplicate_pad_numbers_are_jumpers no)
		(fp_line
			(start 0.7874 -0.4064)
			(end 0.7874 0.4064)
			(stroke
				(width 0.1524)
				(type default)
			)
			(layer "F.SilkS")
		)
		(fp_line
			(start -0.7874 -0.4064)
			(end 0.7874 -0.4064)
			(stroke
				(width 0.1524)
				(type default)
			)
			(layer "F.SilkS")
		)
		(fp_line
			(start 0.7874 0.4064)
			(end -0.7874 0.4064)
			(stroke
				(width 0.1524)
				(type default)
			)
			(layer "F.SilkS")
		)
		(fp_line
			(start -0.7874 0.4064)
			(end -0.7874 -0.4064)
			(stroke
				(width 0.1524)
				(type default)
			)
			(layer "F.SilkS")
		)
		(fp_line
			(start -0.12065 -0.305054)
			(end -0.12065 -0.2794)
			(stroke
				(width 0.1)
				(type default)
			)
			(layer "F.Fab")
		)
		(fp_line
			(start -0.67945 -0.305054)
			(end -0.12065 -0.305054)
			(stroke
				(width 0.1)
				(type default)
			)
			(layer "F.Fab")
		)
		(fp_line
			(start 0.67945 -0.3048)
			(end 0.67945 0.3048)
			(stroke
				(width 0.1)
				(type default)
			)
			(layer "F.Fab")
		)
		(fp_line
			(start 0.12065 -0.3048)
			(end 0.67945 -0.3048)
			(stroke
				(width 0.1)
				(type default)
			)
			(layer "F.Fab")
		)
		(fp_line
			(start 0.12065 -0.2794)
			(end 0.12065 -0.3048)
			(stroke
				(width 0.1)
				(type default)
			)
			(layer "F.Fab")
		)
		(fp_line
			(start -0.12065 -0.2794)
			(end 0.12065 -0.2794)
			(stroke
				(width 0.1)
				(type default)
			)
			(layer "F.Fab")
		)
		(fp_line
			(start 0.120396 0.2794)
			(end -0.12065 0.2794)
			(stroke
				(width 0.1)
				(type default)
			)
			(layer "F.Fab")
		)
		(fp_line
			(start -0.12065 0.2794)
			(end -0.12065 0.3048)
			(stroke
				(width 0.1)
				(type default)
			)
			(layer "F.Fab")
		)
		(fp_line
			(start 0.67945 0.3048)
			(end 0.120396 0.3048)
			(stroke
				(width 0.1)
				(type default)
			)
			(layer "F.Fab")
		)
		(fp_line
			(start 0.120396 0.3048)
			(end 0.120396 0.2794)
			(stroke
				(width 0.1)
				(type default)
			)
			(layer "F.Fab")
		)
		(fp_line
			(start -0.12065 0.3048)
			(end -0.67945 0.3048)
			(stroke
				(width 0.1)
				(type default)
			)
			(layer "F.Fab")
		)
		(fp_line
			(start -0.67945 0.3048)
			(end -0.67945 -0.305054)
			(stroke
				(width 0.1)
				(type default)
			)
			(layer "F.Fab")
		)
		(pad "1" smd circle
			(at -0.40005 0 90)
			(size 0 0)
			(layers "F.Cu" "F.Mask" "F.Paste")
			(net "P3V3_AUX")
		)
		(pad "2" smd circle
			(at 0.40005 0 90)
			(size 0 0)
			(layers "F.Cu" "F.Mask" "F.Paste")
			(net "SPI_BIC1_CLK")
		)
	)
	(footprint ""
		(layer "F.Cu")
		(at 249.733562 -210.606386)
		(property "Reference" "R4433"
			(at 0 0 0)
			(layer "F.SilkS")
			(hide yes)
			(effects
				(font
					(size 1.27 1.27)
				)
			)
		)
		(property "Value" ""
			(at 0 0 0)
			(layer "F.Fab")
			(effects
				(font
					(size 1.27 1.27)
				)
			)
		)
		(duplicate_pad_numbers_are_jumpers no)
		(fp_line
			(start -0.7874 -0.4064)
			(end 0.7874 -0.4064)
			(stroke
				(width 0.1524)
				(type default)
			)
			(layer "F.SilkS")
		)
		(fp_line
			(start -0.7874 0.4064)
			(end -0.7874 -0.4064)
			(stroke
				(width 0.1524)
				(type default)
			)
			(layer "F.SilkS")
		)
		(fp_line
			(start 0.7874 -0.4064)
			(end 0.7874 0.4064)
			(stroke
				(width 0.1524)
				(type default)
			)
			(layer "F.SilkS")
		)
		(fp_line
			(start 0.7874 0.4064)
			(end -0.7874 0.4064)
			(stroke
				(width 0.1524)
				(type default)
			)
			(layer "F.SilkS")
		)
		(fp_line
			(start -0.67945 -0.305054)
			(end -0.12065 -0.305054)
			(stroke
				(width 0.1)
				(type default)
			)
			(layer "F.Fab")
		)
		(fp_line
			(start -0.67945 0.3048)
			(end -0.67945 -0.305054)
			(stroke
				(width 0.1)
				(type default)
			)
			(layer "F.Fab")
		)
		(fp_line
			(start -0.12065 -0.305054)
			(end -0.12065 -0.2794)
			(stroke
				(width 0.1)
				(type default)
			)
			(layer "F.Fab")
		)
		(fp_line
			(start -0.12065 -0.2794)
			(end 0.12065 -0.2794)
			(stroke
				(width 0.1)
				(type default)
			)
			(layer "F.Fab")
		)
		(fp_line
			(start -0.12065 0.2794)
			(end -0.12065 0.3048)
			(stroke
				(width 0.1)
				(type default)
			)
			(layer "F.Fab")
		)
		(fp_line
			(start -0.12065 0.3048)
			(end -0.67945 0.3048)
			(stroke
				(width 0.1)
				(type default)
			)
			(layer "F.Fab")
		)
		(fp_line
			(start 0.120396 0.2794)
			(end -0.12065 0.2794)
			(stroke
				(width 0.1)
				(type default)
			)
			(layer "F.Fab")
		)
		(fp_line
			(start 0.120396 0.3048)
			(end 0.120396 0.2794)
			(stroke
				(width 0.1)
				(type default)
			)
			(layer "F.Fab")
		)
		(fp_line
			(start 0.12065 -0.3048)
			(end 0.67945 -0.3048)
			(stroke
				(width 0.1)
				(type default)
			)
			(layer "F.Fab")
		)
		(fp_line
			(start 0.12065 -0.2794)
			(end 0.12065 -0.3048)
			(stroke
				(width 0.1)
				(type default)
			)
			(layer "F.Fab")
		)
		(fp_line
			(start 0.67945 -0.3048)
			(end 0.67945 0.3048)
			(stroke
				(width 0.1)
				(type default)
			)
			(layer "F.Fab")
		)
		(fp_line
			(start 0.67945 0.3048)
			(end 0.120396 0.3048)
			(stroke
				(width 0.1)
				(type default)
			)
			(layer "F.Fab")
		)
		(pad "1" smd circle
			(at -0.40005 0)
			(size 0 0)
			(layers "F.Cu" "F.Mask" "F.Paste")
			(net "P3V3_AUX")
		)
		(pad "2" smd circle
			(at 0.40005 0)
			(size 0 0)
			(layers "F.Cu" "F.Mask" "F.Paste")
			(net "PWRGD_P1V2_AUX")
		)
	)
	(footprint ""
		(layer "F.Cu")
		(at 480.78009 -547.47541 180)
		(property "Reference" "SCREW_SSD15_1"
			(at -5.6007 -1.402334 0)
			(unlocked yes)
			(layer "B.SilkS")
			(effects
				(font
					(size 0.7874 0.5842)
					(thickness 0.1524)
				)
				(justify mirror)
			)
		)
		(property "Value" ""
			(at 0 0 180)
			(layer "F.Fab")
			(effects
				(font
					(size 1.27 1.27)
				)
			)
		)
		(duplicate_pad_numbers_are_jumpers no)
		(pad "1" thru_hole circle
			(at 0 0 180)
			(size 0.4572 0.4572)
			(drill 0.2032)
			(layers "*.Cu" "*.Mask")
			(remove_unused_layers no)
			(net "Net_9144")
			(clearance 0.127)
			(thermal_gap 0.127)
			(padstack
				(mode front_inner_back)
				(layer "Inner"
					(shape circle)
					(size 0.4572 0.4572)
					(clearance 0.127)
				)
				(layer "B.Cu"
					(shape circle)
					(size 0.508 0.508)
					(clearance 0.1016)
				)
			)
		)
	)
	(footprint ""
		(layer "F.Cu")
		(at 315.493908 -34.248852)
		(property "Reference" "R5688"
			(at 0 0 0)
			(layer "F.SilkS")
			(hide yes)
			(effects
				(font
					(size 1.27 1.27)
				)
			)
		)
		(property "Value" ""
			(at 0 0 0)
			(layer "F.Fab")
			(effects
				(font
					(size 1.27 1.27)
				)
			)
		)
		(duplicate_pad_numbers_are_jumpers no)
		(fp_line
			(start -0.7874 -0.4064)
			(end 0.7874 -0.4064)
			(stroke
				(width 0.1524)
				(type default)
			)
			(layer "F.SilkS")
		)
		(fp_line
			(start -0.7874 0.4064)
			(end -0.7874 -0.4064)
			(stroke
				(width 0.1524)
				(type default)
			)
			(layer "F.SilkS")
		)
		(fp_line
			(start 0.7874 -0.4064)
			(end 0.7874 0.4064)
			(stroke
				(width 0.1524)
				(type default)
			)
			(layer "F.SilkS")
		)
		(fp_line
			(start 0.7874 0.4064)
			(end -0.7874 0.4064)
			(stroke
				(width 0.1524)
				(type default)
			)
			(layer "F.SilkS")
		)
		(fp_line
			(start -0.67945 -0.305054)
			(end -0.12065 -0.305054)
			(stroke
				(width 0.1)
				(type default)
			)
			(layer "F.Fab")
		)
		(fp_line
			(start -0.67945 0.3048)
			(end -0.67945 -0.305054)
			(stroke
				(width 0.1)
				(type default)
			)
			(layer "F.Fab")
		)
		(fp_line
			(start -0.12065 -0.305054)
			(end -0.12065 -0.2794)
			(stroke
				(width 0.1)
				(type default)
			)
			(layer "F.Fab")
		)
		(fp_line
			(start -0.12065 -0.2794)
			(end 0.12065 -0.2794)
			(stroke
				(width 0.1)
				(type default)
			)
			(layer "F.Fab")
		)
		(fp_line
			(start -0.12065 0.2794)
			(end -0.12065 0.3048)
			(stroke
				(width 0.1)
				(type default)
			)
			(layer "F.Fab")
		)
		(fp_line
			(start -0.12065 0.3048)
			(end -0.67945 0.3048)
			(stroke
				(width 0.1)
				(type default)
			)
			(layer "F.Fab")
		)
		(fp_line
			(start 0.120396 0.2794)
			(end -0.12065 0.2794)
			(stroke
				(width 0.1)
				(type default)
			)
			(layer "F.Fab")
		)
		(fp_line
			(start 0.120396 0.3048)
			(end 0.120396 0.2794)
			(stroke
				(width 0.1)
				(type default)
			)
			(layer "F.Fab")
		)
		(fp_line
			(start 0.12065 -0.3048)
			(end 0.67945 -0.3048)
			(stroke
				(width 0.1)
				(type default)
			)
			(layer "F.Fab")
		)
		(fp_line
			(start 0.12065 -0.2794)
			(end 0.12065 -0.3048)
			(stroke
				(width 0.1)
				(type default)
			)
			(layer "F.Fab")
		)
		(fp_line
			(start 0.67945 -0.3048)
			(end 0.67945 0.3048)
			(stroke
				(width 0.1)
				(type default)
			)
			(layer "F.Fab")
		)
		(fp_line
			(start 0.67945 0.3048)
			(end 0.120396 0.3048)
			(stroke
				(width 0.1)
				(type default)
			)
			(layer "F.Fab")
		)
		(pad "1" smd circle
			(at -0.40005 0)
			(size 0 0)
			(layers "F.Cu" "F.Mask" "F.Paste")
			(net "RST_SMB_SSD11_ISO_N")
		)
		(pad "2" smd circle
			(at 0.40005 0)
			(size 0 0)
			(layers "F.Cu" "F.Mask" "F.Paste")
			(net "P3V3_SSD11")
		)
	)
	(footprint ""
		(layer "F.Cu")
		(at 281.867864 -19.453098)
		(property "Reference" "R1696"
			(at 0 0 0)
			(layer "F.SilkS")
			(hide yes)
			(effects
				(font
					(size 1.27 1.27)
				)
			)
		)
		(property "Value" ""
			(at 0 0 0)
			(layer "F.Fab")
			(effects
				(font
					(size 1.27 1.27)
				)
			)
		)
		(duplicate_pad_numbers_are_jumpers no)
		(fp_line
			(start -0.7874 -0.4064)
			(end 0.7874 -0.4064)
			(stroke
				(width 0.1524)
				(type default)
			)
			(layer "F.SilkS")
		)
		(fp_line
			(start -0.7874 0.4064)
			(end -0.7874 -0.4064)
			(stroke
				(width 0.1524)
				(type default)
			)
			(layer "F.SilkS")
		)
		(fp_line
			(start 0.7874 -0.4064)
			(end 0.7874 0.4064)
			(stroke
				(width 0.1524)
				(type default)
			)
			(layer "F.SilkS")
		)
		(fp_line
			(start 0.7874 0.4064)
			(end -0.7874 0.4064)
			(stroke
				(width 0.1524)
				(type default)
			)
			(layer "F.SilkS")
		)
		(fp_line
			(start -0.67945 -0.305054)
			(end -0.12065 -0.305054)
			(stroke
				(width 0.1)
				(type default)
			)
			(layer "F.Fab")
		)
		(fp_line
			(start -0.67945 0.3048)
			(end -0.67945 -0.305054)
			(stroke
				(width 0.1)
				(type default)
			)
			(layer "F.Fab")
		)
		(fp_line
			(start -0.12065 -0.305054)
			(end -0.12065 -0.2794)
			(stroke
				(width 0.1)
				(type default)
			)
			(layer "F.Fab")
		)
		(fp_line
			(start -0.12065 -0.2794)
			(end 0.12065 -0.2794)
			(stroke
				(width 0.1)
				(type default)
			)
			(layer "F.Fab")
		)
		(fp_line
			(start -0.12065 0.2794)
			(end -0.12065 0.3048)
			(stroke
				(width 0.1)
				(type default)
			)
			(layer "F.Fab")
		)
		(fp_line
			(start -0.12065 0.3048)
			(end -0.67945 0.3048)
			(stroke
				(width 0.1)
				(type default)
			)
			(layer "F.Fab")
		)
		(fp_line
			(start 0.120396 0.2794)
			(end -0.12065 0.2794)
			(stroke
				(width 0.1)
				(type default)
			)
			(layer "F.Fab")
		)
		(fp_line
			(start 0.120396 0.3048)
			(end 0.120396 0.2794)
			(stroke
				(width 0.1)
				(type default)
			)
			(layer "F.Fab")
		)
		(fp_line
			(start 0.12065 -0.3048)
			(end 0.67945 -0.3048)
			(stroke
				(width 0.1)
				(type default)
			)
			(layer "F.Fab")
		)
		(fp_line
			(start 0.12065 -0.2794)
			(end 0.12065 -0.3048)
			(stroke
				(width 0.1)
				(type default)
			)
			(layer "F.Fab")
		)
		(fp_line
			(start 0.67945 -0.3048)
			(end 0.67945 0.3048)
			(stroke
				(width 0.1)
				(type default)
			)
			(layer "F.Fab")
		)
		(fp_line
			(start 0.67945 0.3048)
			(end 0.120396 0.3048)
			(stroke
				(width 0.1)
				(type default)
			)
			(layer "F.Fab")
		)
		(pad "1" smd circle
			(at -0.40005 0)
			(size 0 0)
			(layers "F.Cu" "F.Mask" "F.Paste")
			(net "SMB_ISO_SSD9_R_SDA")
		)
		(pad "2" smd circle
			(at 0.40005 0)
			(size 0 0)
			(layers "F.Cu" "F.Mask" "F.Paste")
			(net "SMB_ISO_SSD9_SDA")
		)
	)
	(footprint ""
		(layer "F.Cu")
		(at 235.882688 -175.78324 -90)
		(property "Reference" "U327"
			(at 1.74244 -2.370582 90)
			(unlocked yes)
			(layer "F.SilkS")
			(effects
				(font
					(size 0.7874 0.5842)
					(thickness 0.1524)
				)
				(justify left)
			)
		)
		(property "Value" ""
			(at 0 0 270)
			(layer "F.Fab")
			(effects
				(font
					(size 1.27 1.27)
				)
			)
		)
		(duplicate_pad_numbers_are_jumpers no)
		(fp_line
			(start -2.0574 1.651)
			(end -2.0574 -1.651)
			(stroke
				(width 0.1524)
				(type default)
			)
			(layer "F.SilkS")
		)
		(fp_line
			(start 2.0574 1.651)
			(end -2.0574 1.651)
			(stroke
				(width 0.1524)
				(type default)
			)
			(layer "F.SilkS")
		)
		(fp_line
			(start 0 -1.016)
			(end 0.381 -1.651)
			(stroke
				(width 0.1524)
				(type default)
			)
			(layer "F.SilkS")
		)
		(fp_line
			(start -2.0574 -1.651)
			(end -0.381 -1.651)
			(stroke
				(width 0.1524)
				(type default)
			)
			(layer "F.SilkS")
		)
		(fp_line
			(start -0.381 -1.651)
			(end 0 -1.016)
			(stroke
				(width 0.1524)
				(type default)
			)
			(layer "F.SilkS")
		)
		(fp_line
			(start 0.381 -1.651)
			(end 2.0574 -1.651)
			(stroke
				(width 0.1524)
				(type default)
			)
			(layer "F.SilkS")
		)
		(fp_line
			(start 2.0574 -1.651)
			(end 2.0574 1.651)
			(stroke
				(width 0.1524)
				(type default)
			)
			(layer "F.SilkS")
		)
		(fp_poly
			(pts
				(xy -2.71272 -0.719328) (xy -2.71272 -1.344168) (xy -2.159 -1.016)
			)
			(stroke
				(width 0)
				(type default)
			)
			(fill yes)
			(layer "F.SilkS")
		)
		(fp_line
			(start -0.899922 1.549908)
			(end -0.899922 1.199896)
			(stroke
				(width 0.1)
				(type default)
			)
			(layer "F.Fab")
		)
		(fp_line
			(start 0.899922 1.549908)
			(end -0.899922 1.549908)
			(stroke
				(width 0.1)
				(type default)
			)
			(layer "F.Fab")
		)
		(fp_line
			(start -1.599946 1.199896)
			(end -1.599946 -1.199896)
			(stroke
				(width 0.1)
				(type default)
			)
			(layer "F.Fab")
		)
		(fp_line
			(start -0.899922 1.199896)
			(end -1.599946 1.199896)
			(stroke
				(width 0.1)
				(type default)
			)
			(layer "F.Fab")
		)
		(fp_line
			(start 0.899922 1.199896)
			(end 0.899922 1.549908)
			(stroke
				(width 0.1)
				(type default)
			)
			(layer "F.Fab")
		)
		(fp_line
			(start 1.599946 1.199896)
			(end 0.899922 1.199896)
			(stroke
				(width 0.1)
				(type default)
			)
			(layer "F.Fab")
		)
		(fp_line
			(start -1.599946 -1.199896)
			(end -0.899922 -1.199896)
			(stroke
				(width 0.1)
				(type default)
			)
			(layer "F.Fab")
		)
		(fp_line
			(start -0.899922 -1.199896)
			(end -0.899922 -1.549908)
			(stroke
				(width 0.1)
				(type default)
			)
			(layer "F.Fab")
		)
		(fp_line
			(start 0.899922 -1.199896)
			(end 1.599946 -1.199896)
			(stroke
				(width 0.1)
				(type default)
			)
			(layer "F.Fab")
		)
		(fp_line
			(start 1.599946 -1.199896)
			(end 1.599946 1.199896)
			(stroke
				(width 0.1)
				(type default)
			)
			(layer "F.Fab")
		)
		(fp_line
			(start -0.899922 -1.549908)
			(end 0.899922 -1.549908)
			(stroke
				(width 0.1)
				(type default)
			)
			(layer "F.Fab")
		)
		(fp_line
			(start 0.899922 -1.549908)
			(end 0.899922 -1.199896)
			(stroke
				(width 0.1)
				(type default)
			)
			(layer "F.Fab")
		)
		(fp_poly
			(pts
				(xy -2.71272 -0.719328) (xy -2.71272 -1.344168) (xy -2.159 -1.016)
			)
			(stroke
				(width 0)
				(type default)
			)
			(fill yes)
			(layer "F.Fab")
		)
		(pad "1" smd rect
			(at -1.225042 -0.94996 180)
			(size 0.5588 1.3462)
			(layers "F.Cu" "F.Mask" "F.Paste")
			(net "BIC_RST_PWRGD_RSMRST")
		)
		(pad "2" smd rect
			(at -1.225042 0 180)
			(size 0.5588 1.3462)
			(layers "F.Cu" "F.Mask" "F.Paste")
			(net "RST_FPGA_BIC_R1_N")
		)
		(pad "3" smd rect
			(at -1.225042 0.94996 180)
			(size 0.5588 1.3462)
			(layers "F.Cu" "F.Mask" "F.Paste")
			(net "GND")
		)
		(pad "4" smd rect
			(at 1.225042 0.94996 180)
			(size 0.5588 1.3462)
			(layers "F.Cu" "F.Mask" "F.Paste")
			(net "RST_BIC_SRST_N")
		)
		(pad "5" smd rect
			(at 1.225042 -0.94996 180)
			(size 0.5588 1.3462)
			(layers "F.Cu" "F.Mask" "F.Paste")
			(net "P3V3_AUX")
		)
	)
	(footprint ""
		(layer "F.Cu")
		(at 249.20575 -84.320888 180)
		(property "Reference" "R1052"
			(at 0 0 180)
			(layer "F.SilkS")
			(hide yes)
			(effects
				(font
					(size 1.27 1.27)
				)
			)
		)
		(property "Value" ""
			(at 0 0 180)
			(layer "F.Fab")
			(effects
				(font
					(size 1.27 1.27)
				)
			)
		)
		(duplicate_pad_numbers_are_jumpers no)
		(fp_line
			(start 0.7874 0.4064)
			(end -0.7874 0.4064)
			(stroke
				(width 0.1524)
				(type default)
			)
			(layer "F.SilkS")
		)
		(fp_line
			(start 0.7874 -0.4064)
			(end 0.7874 0.4064)
			(stroke
				(width 0.1524)
				(type default)
			)
			(layer "F.SilkS")
		)
		(fp_line
			(start -0.7874 0.4064)
			(end -0.7874 -0.4064)
			(stroke
				(width 0.1524)
				(type default)
			)
			(layer "F.SilkS")
		)
		(fp_line
			(start -0.7874 -0.4064)
			(end 0.7874 -0.4064)
			(stroke
				(width 0.1524)
				(type default)
			)
			(layer "F.SilkS")
		)
		(fp_line
			(start 0.67945 0.3048)
			(end 0.120396 0.3048)
			(stroke
				(width 0.1)
				(type default)
			)
			(layer "F.Fab")
		)
		(fp_line
			(start 0.67945 -0.3048)
			(end 0.67945 0.3048)
			(stroke
				(width 0.1)
				(type default)
			)
			(layer "F.Fab")
		)
		(fp_line
			(start 0.12065 -0.2794)
			(end 0.12065 -0.3048)
			(stroke
				(width 0.1)
				(type default)
			)
			(layer "F.Fab")
		)
		(fp_line
			(start 0.12065 -0.3048)
			(end 0.67945 -0.3048)
			(stroke
				(width 0.1)
				(type default)
			)
			(layer "F.Fab")
		)
		(fp_line
			(start 0.120396 0.3048)
			(end 0.120396 0.2794)
			(stroke
				(width 0.1)
				(type default)
			)
			(layer "F.Fab")
		)
		(fp_line
			(start 0.120396 0.2794)
			(end -0.12065 0.2794)
			(stroke
				(width 0.1)
				(type default)
			)
			(layer "F.Fab")
		)
		(fp_line
			(start -0.12065 0.3048)
			(end -0.67945 0.3048)
			(stroke
				(width 0.1)
				(type default)
			)
			(layer "F.Fab")
		)
		(fp_line
			(start -0.12065 0.2794)
			(end -0.12065 0.3048)
			(stroke
				(width 0.1)
				(type default)
			)
			(layer "F.Fab")
		)
		(fp_line
			(start -0.12065 -0.2794)
			(end 0.12065 -0.2794)
			(stroke
				(width 0.1)
				(type default)
			)
			(layer "F.Fab")
		)
		(fp_line
			(start -0.12065 -0.305054)
			(end -0.12065 -0.2794)
			(stroke
				(width 0.1)
				(type default)
			)
			(layer "F.Fab")
		)
		(fp_line
			(start -0.67945 0.3048)
			(end -0.67945 -0.305054)
			(stroke
				(width 0.1)
				(type default)
			)
			(layer "F.Fab")
		)
		(fp_line
			(start -0.67945 -0.305054)
			(end -0.12065 -0.305054)
			(stroke
				(width 0.1)
				(type default)
			)
			(layer "F.Fab")
		)
		(pad "1" smd circle
			(at -0.40005 0 180)
			(size 0 0)
			(layers "F.Cu" "F.Mask" "F.Paste")
			(net "CLK_CK440_SMB_ADDR0")
		)
		(pad "2" smd circle
			(at 0.40005 0 180)
			(size 0 0)
			(layers "F.Cu" "F.Mask" "F.Paste")
			(net "P3V3")
		)
	)
	(footprint ""
		(layer "F.Cu")
		(at 437.250332 -343.952322 90)
		(property "Reference" "C2465"
			(at 0 0 90)
			(layer "F.SilkS")
			(hide yes)
			(effects
				(font
					(size 1.27 1.27)
				)
			)
		)
		(property "Value" ""
			(at 0 0 90)
			(layer "F.Fab")
			(effects
				(font
					(size 1.27 1.27)
				)
			)
		)
		(duplicate_pad_numbers_are_jumpers no)
		(fp_line
			(start 0.299974 -0.150114)
			(end 0.299974 0.150114)
			(stroke
				(width 0.1)
				(type default)
			)
			(layer "F.Fab")
		)
		(fp_line
			(start -0.299974 -0.150114)
			(end 0.299974 -0.150114)
			(stroke
				(width 0.1)
				(type default)
			)
			(layer "F.Fab")
		)
		(fp_line
			(start 0.299974 0.150114)
			(end -0.299974 0.150114)
			(stroke
				(width 0.1)
				(type default)
			)
			(layer "F.Fab")
		)
		(fp_line
			(start -0.299974 0.150114)
			(end -0.299974 -0.150114)
			(stroke
				(width 0.1)
				(type default)
			)
			(layer "F.Fab")
		)
		(pad "1" smd rect
			(at -0.2667 0 90)
			(size 0.3048 0.381)
			(layers "F.Cu" "F.Mask" "F.Paste")
			(net "P5E_PEX3_STN4_TX_DP<66>")
		)
		(pad "2" smd rect
			(at 0.2667 0 90)
			(size 0.3048 0.381)
			(layers "F.Cu" "F.Mask" "F.Paste")
			(net "P5E_PEX3_STN4_TX_C_DP<66>")
		)
	)
	(footprint ""
		(layer "F.Cu")
		(at 361.188 -193.294)
		(property "Reference" "R4638"
			(at 0 0 0)
			(layer "F.SilkS")
			(hide yes)
			(effects
				(font
					(size 1.27 1.27)
				)
			)
		)
		(property "Value" ""
			(at 0 0 0)
			(layer "F.Fab")
			(effects
				(font
					(size 1.27 1.27)
				)
			)
		)
		(duplicate_pad_numbers_are_jumpers no)
		(fp_line
			(start -0.7874 -0.4064)
			(end 0.7874 -0.4064)
			(stroke
				(width 0.1524)
				(type default)
			)
			(layer "F.SilkS")
		)
		(fp_line
			(start -0.7874 0.4064)
			(end -0.7874 -0.4064)
			(stroke
				(width 0.1524)
				(type default)
			)
			(layer "F.SilkS")
		)
		(fp_line
			(start 0.7874 -0.4064)
			(end 0.7874 0.4064)
			(stroke
				(width 0.1524)
				(type default)
			)
			(layer "F.SilkS")
		)
		(fp_line
			(start 0.7874 0.4064)
			(end -0.7874 0.4064)
			(stroke
				(width 0.1524)
				(type default)
			)
			(layer "F.SilkS")
		)
		(fp_line
			(start -0.67945 -0.305054)
			(end -0.12065 -0.305054)
			(stroke
				(width 0.1)
				(type default)
			)
			(layer "F.Fab")
		)
		(fp_line
			(start -0.67945 0.3048)
			(end -0.67945 -0.305054)
			(stroke
				(width 0.1)
				(type default)
			)
			(layer "F.Fab")
		)
		(fp_line
			(start -0.12065 -0.305054)
			(end -0.12065 -0.2794)
			(stroke
				(width 0.1)
				(type default)
			)
			(layer "F.Fab")
		)
		(fp_line
			(start -0.12065 -0.2794)
			(end 0.12065 -0.2794)
			(stroke
				(width 0.1)
				(type default)
			)
			(layer "F.Fab")
		)
		(fp_line
			(start -0.12065 0.2794)
			(end -0.12065 0.3048)
			(stroke
				(width 0.1)
				(type default)
			)
			(layer "F.Fab")
		)
		(fp_line
			(start -0.12065 0.3048)
			(end -0.67945 0.3048)
			(stroke
				(width 0.1)
				(type default)
			)
			(layer "F.Fab")
		)
		(fp_line
			(start 0.120396 0.2794)
			(end -0.12065 0.2794)
			(stroke
				(width 0.1)
				(type default)
			)
			(layer "F.Fab")
		)
		(fp_line
			(start 0.120396 0.3048)
			(end 0.120396 0.2794)
			(stroke
				(width 0.1)
				(type default)
			)
			(layer "F.Fab")
		)
		(fp_line
			(start 0.12065 -0.3048)
			(end 0.67945 -0.3048)
			(stroke
				(width 0.1)
				(type default)
			)
			(layer "F.Fab")
		)
		(fp_line
			(start 0.12065 -0.2794)
			(end 0.12065 -0.3048)
			(stroke
				(width 0.1)
				(type default)
			)
			(layer "F.Fab")
		)
		(fp_line
			(start 0.67945 -0.3048)
			(end 0.67945 0.3048)
			(stroke
				(width 0.1)
				(type default)
			)
			(layer "F.Fab")
		)
		(fp_line
			(start 0.67945 0.3048)
			(end 0.120396 0.3048)
			(stroke
				(width 0.1)
				(type default)
			)
			(layer "F.Fab")
		)
		(pad "1" smd circle
			(at -0.40005 0)
			(size 0 0)
			(layers "F.Cu" "F.Mask" "F.Paste")
			(net "PEX0_PCA9555_1_INT_N")
		)
		(pad "2" smd circle
			(at 0.40005 0)
			(size 0 0)
			(layers "F.Cu" "F.Mask" "F.Paste")
			(net "P1V8_PEX")
		)
	)
	(footprint ""
		(layer "F.Cu")
		(at 58.176922 -375.524268 180)
		(property "Reference" "R1822"
			(at 0 0 180)
			(layer "F.SilkS")
			(hide yes)
			(effects
				(font
					(size 1.27 1.27)
				)
			)
		)
		(property "Value" ""
			(at 0 0 180)
			(layer "F.Fab")
			(effects
				(font
					(size 1.27 1.27)
				)
			)
		)
		(duplicate_pad_numbers_are_jumpers no)
		(fp_line
			(start 0.7874 0.4064)
			(end -0.7874 0.4064)
			(stroke
				(width 0.1524)
				(type default)
			)
			(layer "F.SilkS")
		)
		(fp_line
			(start 0.7874 -0.4064)
			(end 0.7874 0.4064)
			(stroke
				(width 0.1524)
				(type default)
			)
			(layer "F.SilkS")
		)
		(fp_line
			(start -0.7874 0.4064)
			(end -0.7874 -0.4064)
			(stroke
				(width 0.1524)
				(type default)
			)
			(layer "F.SilkS")
		)
		(fp_line
			(start -0.7874 -0.4064)
			(end 0.7874 -0.4064)
			(stroke
				(width 0.1524)
				(type default)
			)
			(layer "F.SilkS")
		)
		(fp_line
			(start 0.67945 0.3048)
			(end 0.120396 0.3048)
			(stroke
				(width 0.1)
				(type default)
			)
			(layer "F.Fab")
		)
		(fp_line
			(start 0.67945 -0.3048)
			(end 0.67945 0.3048)
			(stroke
				(width 0.1)
				(type default)
			)
			(layer "F.Fab")
		)
		(fp_line
			(start 0.12065 -0.2794)
			(end 0.12065 -0.3048)
			(stroke
				(width 0.1)
				(type default)
			)
			(layer "F.Fab")
		)
		(fp_line
			(start 0.12065 -0.3048)
			(end 0.67945 -0.3048)
			(stroke
				(width 0.1)
				(type default)
			)
			(layer "F.Fab")
		)
		(fp_line
			(start 0.120396 0.3048)
			(end 0.120396 0.2794)
			(stroke
				(width 0.1)
				(type default)
			)
			(layer "F.Fab")
		)
		(fp_line
			(start 0.120396 0.2794)
			(end -0.12065 0.2794)
			(stroke
				(width 0.1)
				(type default)
			)
			(layer "F.Fab")
		)
		(fp_line
			(start -0.12065 0.3048)
			(end -0.67945 0.3048)
			(stroke
				(width 0.1)
				(type default)
			)
			(layer "F.Fab")
		)
		(fp_line
			(start -0.12065 0.2794)
			(end -0.12065 0.3048)
			(stroke
				(width 0.1)
				(type default)
			)
			(layer "F.Fab")
		)
		(fp_line
			(start -0.12065 -0.2794)
			(end 0.12065 -0.2794)
			(stroke
				(width 0.1)
				(type default)
			)
			(layer "F.Fab")
		)
		(fp_line
			(start -0.12065 -0.305054)
			(end -0.12065 -0.2794)
			(stroke
				(width 0.1)
				(type default)
			)
			(layer "F.Fab")
		)
		(fp_line
			(start -0.67945 0.3048)
			(end -0.67945 -0.305054)
			(stroke
				(width 0.1)
				(type default)
			)
			(layer "F.Fab")
		)
		(fp_line
			(start -0.67945 -0.305054)
			(end -0.12065 -0.305054)
			(stroke
				(width 0.1)
				(type default)
			)
			(layer "F.Fab")
		)
		(pad "1" smd circle
			(at -0.40005 0 180)
			(size 0 0)
			(layers "F.Cu" "F.Mask" "F.Paste")
			(net "PRSNT_GPU_D_R_N")
		)
		(pad "2" smd circle
			(at 0.40005 0 180)
			(size 0 0)
			(layers "F.Cu" "F.Mask" "F.Paste")
			(net "PRSNT_GPU_D_N")
		)
	)
	(footprint ""
		(layer "F.Cu")
		(at 358.043226 -396.80769 180)
		(property "Reference" "R6702"
			(at 0 0 180)
			(layer "F.SilkS")
			(hide yes)
			(effects
				(font
					(size 1.27 1.27)
				)
			)
		)
		(property "Value" ""
			(at 0 0 180)
			(layer "F.Fab")
			(effects
				(font
					(size 1.27 1.27)
				)
			)
		)
		(duplicate_pad_numbers_are_jumpers no)
		(fp_line
			(start 0.7874 0.4064)
			(end -0.7874 0.4064)
			(stroke
				(width 0.1524)
				(type default)
			)
			(layer "F.SilkS")
		)
		(fp_line
			(start 0.7874 -0.4064)
			(end 0.7874 0.4064)
			(stroke
				(width 0.1524)
				(type default)
			)
			(layer "F.SilkS")
		)
		(fp_line
			(start -0.7874 0.4064)
			(end -0.7874 -0.4064)
			(stroke
				(width 0.1524)
				(type default)
			)
			(layer "F.SilkS")
		)
		(fp_line
			(start -0.7874 -0.4064)
			(end 0.7874 -0.4064)
			(stroke
				(width 0.1524)
				(type default)
			)
			(layer "F.SilkS")
		)
		(fp_line
			(start 0.67945 0.3048)
			(end 0.120396 0.3048)
			(stroke
				(width 0.1)
				(type default)
			)
			(layer "F.Fab")
		)
		(fp_line
			(start 0.67945 -0.3048)
			(end 0.67945 0.3048)
			(stroke
				(width 0.1)
				(type default)
			)
			(layer "F.Fab")
		)
		(fp_line
			(start 0.12065 -0.2794)
			(end 0.12065 -0.3048)
			(stroke
				(width 0.1)
				(type default)
			)
			(layer "F.Fab")
		)
		(fp_line
			(start 0.12065 -0.3048)
			(end 0.67945 -0.3048)
			(stroke
				(width 0.1)
				(type default)
			)
			(layer "F.Fab")
		)
		(fp_line
			(start 0.120396 0.3048)
			(end 0.120396 0.2794)
			(stroke
				(width 0.1)
				(type default)
			)
			(layer "F.Fab")
		)
		(fp_line
			(start 0.120396 0.2794)
			(end -0.12065 0.2794)
			(stroke
				(width 0.1)
				(type default)
			)
			(layer "F.Fab")
		)
		(fp_line
			(start -0.12065 0.3048)
			(end -0.67945 0.3048)
			(stroke
				(width 0.1)
				(type default)
			)
			(layer "F.Fab")
		)
		(fp_line
			(start -0.12065 0.2794)
			(end -0.12065 0.3048)
			(stroke
				(width 0.1)
				(type default)
			)
			(layer "F.Fab")
		)
		(fp_line
			(start -0.12065 -0.2794)
			(end 0.12065 -0.2794)
			(stroke
				(width 0.1)
				(type default)
			)
			(layer "F.Fab")
		)
		(fp_line
			(start -0.12065 -0.305054)
			(end -0.12065 -0.2794)
			(stroke
				(width 0.1)
				(type default)
			)
			(layer "F.Fab")
		)
		(fp_line
			(start -0.67945 0.3048)
			(end -0.67945 -0.305054)
			(stroke
				(width 0.1)
				(type default)
			)
			(layer "F.Fab")
		)
		(fp_line
			(start -0.67945 -0.305054)
			(end -0.12065 -0.305054)
			(stroke
				(width 0.1)
				(type default)
			)
			(layer "F.Fab")
		)
		(pad "1" smd circle
			(at -0.40005 0 180)
			(size 0 0)
			(layers "F.Cu" "F.Mask" "F.Paste")
			(net "MB_3V3IO_RSVD3_N")
		)
		(pad "2" smd circle
			(at 0.40005 0 180)
			(size 0 0)
			(layers "F.Cu" "F.Mask" "F.Paste")
			(net "P3V3_AUX")
		)
	)
	(footprint ""
		(layer "F.Cu")
		(at 46.575472 -69.47916 180)
		(property "Reference" "PU75"
			(at -2.224786 -3.080004 90)
			(unlocked yes)
			(layer "F.SilkS")
			(effects
				(font
					(size 0.7874 0.5842)
					(thickness 0.1524)
				)
			)
		)
		(property "Value" ""
			(at 0 0 180)
			(layer "F.Fab")
			(effects
				(font
					(size 1.27 1.27)
				)
			)
		)
		(duplicate_pad_numbers_are_jumpers no)
		(fp_line
			(start 1.239774 1.495298)
			(end -1.239774 1.495298)
			(stroke
				(width 0.1524)
				(type default)
			)
			(layer "F.SilkS")
		)
		(fp_line
			(start 1.239774 -1.495298)
			(end 1.239774 1.495298)
			(stroke
				(width 0.1524)
				(type default)
			)
			(layer "F.SilkS")
		)
		(fp_line
			(start -1.239774 1.495298)
			(end -1.239774 -1.495298)
			(stroke
				(width 0.1524)
				(type default)
			)
			(layer "F.SilkS")
		)
		(fp_line
			(start -1.239774 -1.495298)
			(end 1.239774 -1.495298)
			(stroke
				(width 0.1524)
				(type default)
			)
			(layer "F.SilkS")
		)
		(fp_poly
			(pts
				(xy -1.718056 -1.180084) (xy -2.436622 -0.461518) (xy -1.3589 -0.102362)
			)
			(stroke
				(width 0)
				(type default)
			)
			(fill yes)
			(layer "F.SilkS")
		)
		(fp_line
			(start 0.8001 1.050036)
			(end -0.8001 1.050036)
			(stroke
				(width 0.1)
				(type default)
			)
			(layer "F.Fab")
		)
		(fp_line
			(start 0.8001 -1.050036)
			(end 0.8001 1.050036)
			(stroke
				(width 0.1)
				(type default)
			)
			(layer "F.Fab")
		)
		(fp_line
			(start -0.8001 1.050036)
			(end -0.8001 -1.050036)
			(stroke
				(width 0.1)
				(type default)
			)
			(layer "F.Fab")
		)
		(fp_line
			(start -0.8001 -1.050036)
			(end 0.8001 -1.050036)
			(stroke
				(width 0.1)
				(type default)
			)
			(layer "F.Fab")
		)
		(fp_poly
			(pts
				(xy -2.458974 -0.508) (xy -2.458974 0.508) (xy -1.442974 0)
			)
			(stroke
				(width 0)
				(type default)
			)
			(fill yes)
			(layer "F.Fab")
		)
		(pad "1_2" smd circle
			(at -0.374904 0 270)
			(size 0 0)
			(layers "F.Cu" "F.Mask" "F.Paste")
			(net "P12V_AUX")
		)
		(pad "3" smd rect
			(at -0.499872 0.999998 180)
			(size 0.254 0.7112)
			(layers "F.Cu" "F.Mask" "F.Paste")
			(net "GND")
		)
		(pad "4" smd rect
			(at 0 0.999998 180)
			(size 0.254 0.7112)
			(layers "F.Cu" "F.Mask" "F.Paste")
			(net "P12V_SSD1_CO_ILIMIT")
		)
		(pad "5" smd rect
			(at 0.499872 0.999998 180)
			(size 0.254 0.7112)
			(layers "F.Cu" "F.Mask" "F.Paste")
			(net "P12V_SSD1_CO_MODE")
		)
		(pad "6_7" smd circle
			(at 0.374904 0 90)
			(size 0 0)
			(layers "F.Cu" "F.Mask" "F.Paste")
			(net "P12V_SSD1_R")
		)
		(pad "8" smd rect
			(at 0.499872 -0.999998 180)
			(size 0.254 0.7112)
			(layers "F.Cu" "F.Mask" "F.Paste")
			(net "P12V_SSD1_CO_GATE")
		)
		(pad "9" smd rect
			(at 0 -0.999998 180)
			(size 0.254 0.7112)
			(layers "F.Cu" "F.Mask" "F.Paste")
			(net "P12V_SSD1_CO_EN")
		)
		(pad "10" smd rect
			(at -0.499872 -0.999998 180)
			(size 0.254 0.7112)
			(layers "F.Cu" "F.Mask" "F.Paste")
			(net "P12V_SSD1_CO_DV_DT")
		)
	)
	(footprint ""
		(layer "F.Cu")
		(at 188.22543 -42.849038 180)
		(property "Reference" "R579"
			(at 0 0 180)
			(layer "F.SilkS")
			(hide yes)
			(effects
				(font
					(size 1.27 1.27)
				)
			)
		)
		(property "Value" ""
			(at 0 0 180)
			(layer "F.Fab")
			(effects
				(font
					(size 1.27 1.27)
				)
			)
		)
		(duplicate_pad_numbers_are_jumpers no)
		(fp_line
			(start 0.7874 0.4064)
			(end -0.7874 0.4064)
			(stroke
				(width 0.1524)
				(type default)
			)
			(layer "F.SilkS")
		)
		(fp_line
			(start 0.7874 -0.4064)
			(end 0.7874 0.4064)
			(stroke
				(width 0.1524)
				(type default)
			)
			(layer "F.SilkS")
		)
		(fp_line
			(start -0.7874 0.4064)
			(end -0.7874 -0.4064)
			(stroke
				(width 0.1524)
				(type default)
			)
			(layer "F.SilkS")
		)
		(fp_line
			(start -0.7874 -0.4064)
			(end 0.7874 -0.4064)
			(stroke
				(width 0.1524)
				(type default)
			)
			(layer "F.SilkS")
		)
		(fp_line
			(start 0.67945 0.3048)
			(end 0.120396 0.3048)
			(stroke
				(width 0.1)
				(type default)
			)
			(layer "F.Fab")
		)
		(fp_line
			(start 0.67945 -0.3048)
			(end 0.67945 0.3048)
			(stroke
				(width 0.1)
				(type default)
			)
			(layer "F.Fab")
		)
		(fp_line
			(start 0.12065 -0.2794)
			(end 0.12065 -0.3048)
			(stroke
				(width 0.1)
				(type default)
			)
			(layer "F.Fab")
		)
		(fp_line
			(start 0.12065 -0.3048)
			(end 0.67945 -0.3048)
			(stroke
				(width 0.1)
				(type default)
			)
			(layer "F.Fab")
		)
		(fp_line
			(start 0.120396 0.3048)
			(end 0.120396 0.2794)
			(stroke
				(width 0.1)
				(type default)
			)
			(layer "F.Fab")
		)
		(fp_line
			(start 0.120396 0.2794)
			(end -0.12065 0.2794)
			(stroke
				(width 0.1)
				(type default)
			)
			(layer "F.Fab")
		)
		(fp_line
			(start -0.12065 0.3048)
			(end -0.67945 0.3048)
			(stroke
				(width 0.1)
				(type default)
			)
			(layer "F.Fab")
		)
		(fp_line
			(start -0.12065 0.2794)
			(end -0.12065 0.3048)
			(stroke
				(width 0.1)
				(type default)
			)
			(layer "F.Fab")
		)
		(fp_line
			(start -0.12065 -0.2794)
			(end 0.12065 -0.2794)
			(stroke
				(width 0.1)
				(type default)
			)
			(layer "F.Fab")
		)
		(fp_line
			(start -0.12065 -0.305054)
			(end -0.12065 -0.2794)
			(stroke
				(width 0.1)
				(type default)
			)
			(layer "F.Fab")
		)
		(fp_line
			(start -0.67945 0.3048)
			(end -0.67945 -0.305054)
			(stroke
				(width 0.1)
				(type default)
			)
			(layer "F.Fab")
		)
		(fp_line
			(start -0.67945 -0.305054)
			(end -0.12065 -0.305054)
			(stroke
				(width 0.1)
				(type default)
			)
			(layer "F.Fab")
		)
		(pad "1" smd circle
			(at -0.40005 0 180)
			(size 0 0)
			(layers "F.Cu" "F.Mask" "F.Paste")
			(net "P12V_SSD6_R")
		)
		(pad "2" smd circle
			(at 0.40005 0 180)
			(size 0 0)
			(layers "F.Cu" "F.Mask" "F.Paste")
			(net "P12V_SSD6_VIN_P")
		)
	)
	(footprint ""
		(layer "F.Cu")
		(at 411.825948 -165.670484 -90)
		(property "Reference" "R3311"
			(at 0 0 270)
			(layer "F.SilkS")
			(hide yes)
			(effects
				(font
					(size 1.27 1.27)
				)
			)
		)
		(property "Value" ""
			(at 0 0 270)
			(layer "F.Fab")
			(effects
				(font
					(size 1.27 1.27)
				)
			)
		)
		(duplicate_pad_numbers_are_jumpers no)
		(fp_line
			(start -0.7874 0.4064)
			(end -0.7874 -0.4064)
			(stroke
				(width 0.1524)
				(type default)
			)
			(layer "F.SilkS")
		)
		(fp_line
			(start 0.7874 0.4064)
			(end -0.7874 0.4064)
			(stroke
				(width 0.1524)
				(type default)
			)
			(layer "F.SilkS")
		)
		(fp_line
			(start -0.7874 -0.4064)
			(end 0.7874 -0.4064)
			(stroke
				(width 0.1524)
				(type default)
			)
			(layer "F.SilkS")
		)
		(fp_line
			(start 0.7874 -0.4064)
			(end 0.7874 0.4064)
			(stroke
				(width 0.1524)
				(type default)
			)
			(layer "F.SilkS")
		)
		(fp_line
			(start -0.67945 0.3048)
			(end -0.67945 -0.305054)
			(stroke
				(width 0.1)
				(type default)
			)
			(layer "F.Fab")
		)
		(fp_line
			(start -0.12065 0.3048)
			(end -0.67945 0.3048)
			(stroke
				(width 0.1)
				(type default)
			)
			(layer "F.Fab")
		)
		(fp_line
			(start 0.120396 0.3048)
			(end 0.120396 0.2794)
			(stroke
				(width 0.1)
				(type default)
			)
			(layer "F.Fab")
		)
		(fp_line
			(start 0.67945 0.3048)
			(end 0.120396 0.3048)
			(stroke
				(width 0.1)
				(type default)
			)
			(layer "F.Fab")
		)
		(fp_line
			(start -0.12065 0.2794)
			(end -0.12065 0.3048)
			(stroke
				(width 0.1)
				(type default)
			)
			(layer "F.Fab")
		)
		(fp_line
			(start 0.120396 0.2794)
			(end -0.12065 0.2794)
			(stroke
				(width 0.1)
				(type default)
			)
			(layer "F.Fab")
		)
		(fp_line
			(start -0.12065 -0.2794)
			(end 0.12065 -0.2794)
			(stroke
				(width 0.1)
				(type default)
			)
			(layer "F.Fab")
		)
		(fp_line
			(start 0.12065 -0.2794)
			(end 0.12065 -0.3048)
			(stroke
				(width 0.1)
				(type default)
			)
			(layer "F.Fab")
		)
		(fp_line
			(start 0.12065 -0.3048)
			(end 0.67945 -0.3048)
			(stroke
				(width 0.1)
				(type default)
			)
			(layer "F.Fab")
		)
		(fp_line
			(start 0.67945 -0.3048)
			(end 0.67945 0.3048)
			(stroke
				(width 0.1)
				(type default)
			)
			(layer "F.Fab")
		)
		(fp_line
			(start -0.67945 -0.305054)
			(end -0.12065 -0.305054)
			(stroke
				(width 0.1)
				(type default)
			)
			(layer "F.Fab")
		)
		(fp_line
			(start -0.12065 -0.305054)
			(end -0.12065 -0.2794)
			(stroke
				(width 0.1)
				(type default)
			)
			(layer "F.Fab")
		)
		(pad "1" smd circle
			(at -0.40005 0 270)
			(size 0 0)
			(layers "F.Cu" "F.Mask" "F.Paste")
			(net "FM_SYS_THROTTLE_R")
		)
		(pad "2" smd circle
			(at 0.40005 0 270)
			(size 0 0)
			(layers "F.Cu" "F.Mask" "F.Paste")
			(net "FM_SYS_THROTTLE_NIC7")
		)
	)
	(footprint ""
		(layer "F.Cu")
		(at 328.041 -82.042 90)
		(property "Reference" "C3993"
			(at 0 0 90)
			(layer "F.SilkS")
			(hide yes)
			(effects
				(font
					(size 1.27 1.27)
				)
			)
		)
		(property "Value" ""
			(at 0 0 90)
			(layer "F.Fab")
			(effects
				(font
					(size 1.27 1.27)
				)
			)
		)
		(duplicate_pad_numbers_are_jumpers no)
		(fp_line
			(start 0.7874 -0.4064)
			(end 0.7874 0.4064)
			(stroke
				(width 0.1524)
				(type default)
			)
			(layer "F.SilkS")
		)
		(fp_line
			(start -0.7874 -0.4064)
			(end 0.7874 -0.4064)
			(stroke
				(width 0.1524)
				(type default)
			)
			(layer "F.SilkS")
		)
		(fp_line
			(start 0.7874 0.4064)
			(end -0.7874 0.4064)
			(stroke
				(width 0.1524)
				(type default)
			)
			(layer "F.SilkS")
		)
		(fp_line
			(start -0.7874 0.4064)
			(end -0.7874 -0.4064)
			(stroke
				(width 0.1524)
				(type default)
			)
			(layer "F.SilkS")
		)
		(fp_line
			(start -0.12065 -0.305054)
			(end -0.12065 -0.2794)
			(stroke
				(width 0.1)
				(type default)
			)
			(layer "F.Fab")
		)
		(fp_line
			(start -0.67945 -0.305054)
			(end -0.12065 -0.305054)
			(stroke
				(width 0.1)
				(type default)
			)
			(layer "F.Fab")
		)
		(fp_line
			(start 0.67945 -0.3048)
			(end 0.67945 0.3048)
			(stroke
				(width 0.1)
				(type default)
			)
			(layer "F.Fab")
		)
		(fp_line
			(start 0.12065 -0.3048)
			(end 0.67945 -0.3048)
			(stroke
				(width 0.1)
				(type default)
			)
			(layer "F.Fab")
		)
		(fp_line
			(start 0.12065 -0.2794)
			(end 0.12065 -0.3048)
			(stroke
				(width 0.1)
				(type default)
			)
			(layer "F.Fab")
		)
		(fp_line
			(start -0.12065 -0.2794)
			(end 0.12065 -0.2794)
			(stroke
				(width 0.1)
				(type default)
			)
			(layer "F.Fab")
		)
		(fp_line
			(start 0.120396 0.2794)
			(end -0.12065 0.2794)
			(stroke
				(width 0.1)
				(type default)
			)
			(layer "F.Fab")
		)
		(fp_line
			(start -0.12065 0.2794)
			(end -0.12065 0.3048)
			(stroke
				(width 0.1)
				(type default)
			)
			(layer "F.Fab")
		)
		(fp_line
			(start 0.67945 0.3048)
			(end 0.120396 0.3048)
			(stroke
				(width 0.1)
				(type default)
			)
			(layer "F.Fab")
		)
		(fp_line
			(start 0.120396 0.3048)
			(end 0.120396 0.2794)
			(stroke
				(width 0.1)
				(type default)
			)
			(layer "F.Fab")
		)
		(fp_line
			(start -0.12065 0.3048)
			(end -0.67945 0.3048)
			(stroke
				(width 0.1)
				(type default)
			)
			(layer "F.Fab")
		)
		(fp_line
			(start -0.67945 0.3048)
			(end -0.67945 -0.305054)
			(stroke
				(width 0.1)
				(type default)
			)
			(layer "F.Fab")
		)
		(pad "1" smd circle
			(at -0.40005 0 90)
			(size 0 0)
			(layers "F.Cu" "F.Mask" "F.Paste")
			(net "GND")
		)
		(pad "2" smd circle
			(at 0.40005 0 90)
			(size 0 0)
			(layers "F.Cu" "F.Mask" "F.Paste")
			(net "P3V3")
		)
	)
	(footprint ""
		(layer "F.Cu")
		(at 117.522498 -293.816786 -90)
		(property "Reference" "PC67"
			(at 0 0 270)
			(layer "F.SilkS")
			(hide yes)
			(effects
				(font
					(size 1.27 1.27)
				)
			)
		)
		(property "Value" ""
			(at 0 0 270)
			(layer "F.Fab")
			(effects
				(font
					(size 1.27 1.27)
				)
			)
		)
		(duplicate_pad_numbers_are_jumpers no)
		(fp_line
			(start -0.7874 0.4064)
			(end -0.7874 -0.4064)
			(stroke
				(width 0.1524)
				(type default)
			)
			(layer "F.SilkS")
		)
		(fp_line
			(start 0.7874 0.4064)
			(end -0.7874 0.4064)
			(stroke
				(width 0.1524)
				(type default)
			)
			(layer "F.SilkS")
		)
		(fp_line
			(start -0.7874 -0.4064)
			(end 0.7874 -0.4064)
			(stroke
				(width 0.1524)
				(type default)
			)
			(layer "F.SilkS")
		)
		(fp_line
			(start 0.7874 -0.4064)
			(end 0.7874 0.4064)
			(stroke
				(width 0.1524)
				(type default)
			)
			(layer "F.SilkS")
		)
		(fp_line
			(start -0.67945 0.3048)
			(end -0.67945 -0.305054)
			(stroke
				(width 0.1)
				(type default)
			)
			(layer "F.Fab")
		)
		(fp_line
			(start -0.12065 0.3048)
			(end -0.67945 0.3048)
			(stroke
				(width 0.1)
				(type default)
			)
			(layer "F.Fab")
		)
		(fp_line
			(start 0.120396 0.3048)
			(end 0.120396 0.2794)
			(stroke
				(width 0.1)
				(type default)
			)
			(layer "F.Fab")
		)
		(fp_line
			(start 0.67945 0.3048)
			(end 0.120396 0.3048)
			(stroke
				(width 0.1)
				(type default)
			)
			(layer "F.Fab")
		)
		(fp_line
			(start -0.12065 0.2794)
			(end -0.12065 0.3048)
			(stroke
				(width 0.1)
				(type default)
			)
			(layer "F.Fab")
		)
		(fp_line
			(start 0.120396 0.2794)
			(end -0.12065 0.2794)
			(stroke
				(width 0.1)
				(type default)
			)
			(layer "F.Fab")
		)
		(fp_line
			(start -0.12065 -0.2794)
			(end 0.12065 -0.2794)
			(stroke
				(width 0.1)
				(type default)
			)
			(layer "F.Fab")
		)
		(fp_line
			(start 0.12065 -0.2794)
			(end 0.12065 -0.3048)
			(stroke
				(width 0.1)
				(type default)
			)
			(layer "F.Fab")
		)
		(fp_line
			(start 0.12065 -0.3048)
			(end 0.67945 -0.3048)
			(stroke
				(width 0.1)
				(type default)
			)
			(layer "F.Fab")
		)
		(fp_line
			(start 0.67945 -0.3048)
			(end 0.67945 0.3048)
			(stroke
				(width 0.1)
				(type default)
			)
			(layer "F.Fab")
		)
		(fp_line
			(start -0.67945 -0.305054)
			(end -0.12065 -0.305054)
			(stroke
				(width 0.1)
				(type default)
			)
			(layer "F.Fab")
		)
		(fp_line
			(start -0.12065 -0.305054)
			(end -0.12065 -0.2794)
			(stroke
				(width 0.1)
				(type default)
			)
			(layer "F.Fab")
		)
		(pad "1" smd circle
			(at -0.40005 0 270)
			(size 0 0)
			(layers "F.Cu" "F.Mask" "F.Paste")
			(net "P0V8_PEX0")
		)
		(pad "2" smd circle
			(at 0.40005 0 270)
			(size 0 0)
			(layers "F.Cu" "F.Mask" "F.Paste")
			(net "GND")
		)
	)
	(footprint ""
		(layer "F.Cu")
		(at 344.612976 -84.169758 180)
		(property "Reference" "R1177"
			(at 0 0 180)
			(layer "F.SilkS")
			(hide yes)
			(effects
				(font
					(size 1.27 1.27)
				)
			)
		)
		(property "Value" ""
			(at 0 0 180)
			(layer "F.Fab")
			(effects
				(font
					(size 1.27 1.27)
				)
			)
		)
		(duplicate_pad_numbers_are_jumpers no)
		(fp_line
			(start 0.7874 0.4064)
			(end -0.7874 0.4064)
			(stroke
				(width 0.1524)
				(type default)
			)
			(layer "F.SilkS")
		)
		(fp_line
			(start 0.67945 0.3048)
			(end 0.120396 0.3048)
			(stroke
				(width 0.1)
				(type default)
			)
			(layer "F.Fab")
		)
		(fp_line
			(start 0.67945 -0.3048)
			(end 0.67945 0.3048)
			(stroke
				(width 0.1)
				(type default)
			)
			(layer "F.Fab")
		)
		(fp_line
			(start 0.12065 -0.2794)
			(end 0.12065 -0.3048)
			(stroke
				(width 0.1)
				(type default)
			)
			(layer "F.Fab")
		)
		(fp_line
			(start 0.12065 -0.3048)
			(end 0.67945 -0.3048)
			(stroke
				(width 0.1)
				(type default)
			)
			(layer "F.Fab")
		)
		(fp_line
			(start 0.120396 0.3048)
			(end 0.120396 0.2794)
			(stroke
				(width 0.1)
				(type default)
			)
			(layer "F.Fab")
		)
		(fp_line
			(start 0.120396 0.2794)
			(end -0.12065 0.2794)
			(stroke
				(width 0.1)
				(type default)
			)
			(layer "F.Fab")
		)
		(fp_line
			(start -0.12065 0.3048)
			(end -0.67945 0.3048)
			(stroke
				(width 0.1)
				(type default)
			)
			(layer "F.Fab")
		)
		(fp_line
			(start -0.12065 0.2794)
			(end -0.12065 0.3048)
			(stroke
				(width 0.1)
				(type default)
			)
			(layer "F.Fab")
		)
		(fp_line
			(start -0.12065 -0.2794)
			(end 0.12065 -0.2794)
			(stroke
				(width 0.1)
				(type default)
			)
			(layer "F.Fab")
		)
		(fp_line
			(start -0.12065 -0.305054)
			(end -0.12065 -0.2794)
			(stroke
				(width 0.1)
				(type default)
			)
			(layer "F.Fab")
		)
		(fp_line
			(start -0.67945 0.3048)
			(end -0.67945 -0.305054)
			(stroke
				(width 0.1)
				(type default)
			)
			(layer "F.Fab")
		)
		(fp_line
			(start -0.67945 -0.305054)
			(end -0.12065 -0.305054)
			(stroke
				(width 0.1)
				(type default)
			)
			(layer "F.Fab")
		)
		(pad "1" smd circle
			(at -0.40005 0 180)
			(size 0 0)
			(layers "F.Cu" "F.Mask" "F.Paste")
			(net "CLK_100M_DB800ZL_SSD11_R_DN")
		)
		(pad "2" smd circle
			(at 0.40005 0 180)
			(size 0 0)
			(layers "F.Cu" "F.Mask" "F.Paste")
			(net "CLK_100M_DB800ZL_SSD11_DN")
		)
	)
	(footprint ""
		(layer "F.Cu")
		(at 46.947328 -19.33956)
		(property "Reference" "C3882"
			(at 0 0 0)
			(layer "F.SilkS")
			(hide yes)
			(effects
				(font
					(size 1.27 1.27)
				)
			)
		)
		(property "Value" ""
			(at 0 0 0)
			(layer "F.Fab")
			(effects
				(font
					(size 1.27 1.27)
				)
			)
		)
		(duplicate_pad_numbers_are_jumpers no)
		(fp_line
			(start -0.7874 -0.4064)
			(end 0.7874 -0.4064)
			(stroke
				(width 0.1524)
				(type default)
			)
			(layer "F.SilkS")
		)
		(fp_line
			(start -0.7874 0.4064)
			(end -0.7874 -0.4064)
			(stroke
				(width 0.1524)
				(type default)
			)
			(layer "F.SilkS")
		)
		(fp_line
			(start 0.7874 -0.4064)
			(end 0.7874 0.4064)
			(stroke
				(width 0.1524)
				(type default)
			)
			(layer "F.SilkS")
		)
		(fp_line
			(start 0.7874 0.4064)
			(end -0.7874 0.4064)
			(stroke
				(width 0.1524)
				(type default)
			)
			(layer "F.SilkS")
		)
		(fp_line
			(start -0.67945 -0.305054)
			(end -0.12065 -0.305054)
			(stroke
				(width 0.1)
				(type default)
			)
			(layer "F.Fab")
		)
		(fp_line
			(start -0.67945 0.3048)
			(end -0.67945 -0.305054)
			(stroke
				(width 0.1)
				(type default)
			)
			(layer "F.Fab")
		)
		(fp_line
			(start -0.12065 -0.305054)
			(end -0.12065 -0.2794)
			(stroke
				(width 0.1)
				(type default)
			)
			(layer "F.Fab")
		)
		(fp_line
			(start -0.12065 -0.2794)
			(end 0.12065 -0.2794)
			(stroke
				(width 0.1)
				(type default)
			)
			(layer "F.Fab")
		)
		(fp_line
			(start -0.12065 0.2794)
			(end -0.12065 0.3048)
			(stroke
				(width 0.1)
				(type default)
			)
			(layer "F.Fab")
		)
		(fp_line
			(start -0.12065 0.3048)
			(end -0.67945 0.3048)
			(stroke
				(width 0.1)
				(type default)
			)
			(layer "F.Fab")
		)
		(fp_line
			(start 0.120396 0.2794)
			(end -0.12065 0.2794)
			(stroke
				(width 0.1)
				(type default)
			)
			(layer "F.Fab")
		)
		(fp_line
			(start 0.120396 0.3048)
			(end 0.120396 0.2794)
			(stroke
				(width 0.1)
				(type default)
			)
			(layer "F.Fab")
		)
		(fp_line
			(start 0.12065 -0.3048)
			(end 0.67945 -0.3048)
			(stroke
				(width 0.1)
				(type default)
			)
			(layer "F.Fab")
		)
		(fp_line
			(start 0.12065 -0.2794)
			(end 0.12065 -0.3048)
			(stroke
				(width 0.1)
				(type default)
			)
			(layer "F.Fab")
		)
		(fp_line
			(start 0.67945 -0.3048)
			(end 0.67945 0.3048)
			(stroke
				(width 0.1)
				(type default)
			)
			(layer "F.Fab")
		)
		(fp_line
			(start 0.67945 0.3048)
			(end 0.120396 0.3048)
			(stroke
				(width 0.1)
				(type default)
			)
			(layer "F.Fab")
		)
		(pad "1" smd circle
			(at -0.40005 0)
			(size 0 0)
			(layers "F.Cu" "F.Mask" "F.Paste")
			(net "P12V_SSD1")
		)
		(pad "2" smd circle
			(at 0.40005 0)
			(size 0 0)
			(layers "F.Cu" "F.Mask" "F.Paste")
			(net "GND")
		)
	)
	(footprint ""
		(layer "F.Cu")
		(at 61.19495 -59.577986 90)
		(property "Reference" "PC530"
			(at 0 0 90)
			(layer "F.SilkS")
			(hide yes)
			(effects
				(font
					(size 1.27 1.27)
				)
			)
		)
		(property "Value" ""
			(at 0 0 90)
			(layer "F.Fab")
			(effects
				(font
					(size 1.27 1.27)
				)
			)
		)
		(duplicate_pad_numbers_are_jumpers no)
		(fp_line
			(start 0.7874 -0.4064)
			(end 0.7874 0.4064)
			(stroke
				(width 0.1524)
				(type default)
			)
			(layer "F.SilkS")
		)
		(fp_line
			(start -0.7874 -0.4064)
			(end 0.7874 -0.4064)
			(stroke
				(width 0.1524)
				(type default)
			)
			(layer "F.SilkS")
		)
		(fp_line
			(start 0.7874 0.4064)
			(end -0.7874 0.4064)
			(stroke
				(width 0.1524)
				(type default)
			)
			(layer "F.SilkS")
		)
		(fp_line
			(start -0.7874 0.4064)
			(end -0.7874 -0.4064)
			(stroke
				(width 0.1524)
				(type default)
			)
			(layer "F.SilkS")
		)
		(fp_line
			(start -0.12065 -0.305054)
			(end -0.12065 -0.2794)
			(stroke
				(width 0.1)
				(type default)
			)
			(layer "F.Fab")
		)
		(fp_line
			(start -0.67945 -0.305054)
			(end -0.12065 -0.305054)
			(stroke
				(width 0.1)
				(type default)
			)
			(layer "F.Fab")
		)
		(fp_line
			(start 0.67945 -0.3048)
			(end 0.67945 0.3048)
			(stroke
				(width 0.1)
				(type default)
			)
			(layer "F.Fab")
		)
		(fp_line
			(start 0.12065 -0.3048)
			(end 0.67945 -0.3048)
			(stroke
				(width 0.1)
				(type default)
			)
			(layer "F.Fab")
		)
		(fp_line
			(start 0.12065 -0.2794)
			(end 0.12065 -0.3048)
			(stroke
				(width 0.1)
				(type default)
			)
			(layer "F.Fab")
		)
		(fp_line
			(start -0.12065 -0.2794)
			(end 0.12065 -0.2794)
			(stroke
				(width 0.1)
				(type default)
			)
			(layer "F.Fab")
		)
		(fp_line
			(start 0.120396 0.2794)
			(end -0.12065 0.2794)
			(stroke
				(width 0.1)
				(type default)
			)
			(layer "F.Fab")
		)
		(fp_line
			(start -0.12065 0.2794)
			(end -0.12065 0.3048)
			(stroke
				(width 0.1)
				(type default)
			)
			(layer "F.Fab")
		)
		(fp_line
			(start 0.67945 0.3048)
			(end 0.120396 0.3048)
			(stroke
				(width 0.1)
				(type default)
			)
			(layer "F.Fab")
		)
		(fp_line
			(start 0.120396 0.3048)
			(end 0.120396 0.2794)
			(stroke
				(width 0.1)
				(type default)
			)
			(layer "F.Fab")
		)
		(fp_line
			(start -0.12065 0.3048)
			(end -0.67945 0.3048)
			(stroke
				(width 0.1)
				(type default)
			)
			(layer "F.Fab")
		)
		(fp_line
			(start -0.67945 0.3048)
			(end -0.67945 -0.305054)
			(stroke
				(width 0.1)
				(type default)
			)
			(layer "F.Fab")
		)
		(pad "1" smd circle
			(at -0.40005 0 90)
			(size 0 0)
			(layers "F.Cu" "F.Mask" "F.Paste")
			(net "P3V3_SSD2_SS")
		)
		(pad "2" smd circle
			(at 0.40005 0 90)
			(size 0 0)
			(layers "F.Cu" "F.Mask" "F.Paste")
			(net "GND")
		)
	)
	(footprint ""
		(layer "F.Cu")
		(at 111.836708 -350.098614 90)
		(property "Reference" "C356"
			(at 0 0 90)
			(layer "F.SilkS")
			(hide yes)
			(effects
				(font
					(size 1.27 1.27)
				)
			)
		)
		(property "Value" ""
			(at 0 0 90)
			(layer "F.Fab")
			(effects
				(font
					(size 1.27 1.27)
				)
			)
		)
		(duplicate_pad_numbers_are_jumpers no)
		(fp_line
			(start 0.299974 -0.150114)
			(end 0.299974 0.150114)
			(stroke
				(width 0.1)
				(type default)
			)
			(layer "F.Fab")
		)
		(fp_line
			(start -0.299974 -0.150114)
			(end 0.299974 -0.150114)
			(stroke
				(width 0.1)
				(type default)
			)
			(layer "F.Fab")
		)
		(fp_line
			(start 0.299974 0.150114)
			(end -0.299974 0.150114)
			(stroke
				(width 0.1)
				(type default)
			)
			(layer "F.Fab")
		)
		(fp_line
			(start -0.299974 0.150114)
			(end -0.299974 -0.150114)
			(stroke
				(width 0.1)
				(type default)
			)
			(layer "F.Fab")
		)
		(pad "1" smd rect
			(at -0.2667 0 90)
			(size 0.3048 0.381)
			(layers "F.Cu" "F.Mask" "F.Paste")
			(net "P5E_PEX1_STN6_TX_DP<103>")
		)
		(pad "2" smd rect
			(at 0.2667 0 90)
			(size 0.3048 0.381)
			(layers "F.Cu" "F.Mask" "F.Paste")
			(net "P5E_PEX1_STN6_TX_C_DP<103>")
		)
	)
	(footprint ""
		(layer "F.Cu")
		(at 428.319438 -122.270266 180)
		(property "Reference" "C661"
			(at 0 0 180)
			(layer "F.SilkS")
			(hide yes)
			(effects
				(font
					(size 1.27 1.27)
				)
			)
		)
		(property "Value" ""
			(at 0 0 180)
			(layer "F.Fab")
			(effects
				(font
					(size 1.27 1.27)
				)
			)
		)
		(duplicate_pad_numbers_are_jumpers no)
		(fp_line
			(start 0.299974 0.150114)
			(end -0.299974 0.150114)
			(stroke
				(width 0.1)
				(type default)
			)
			(layer "F.Fab")
		)
		(fp_line
			(start 0.299974 -0.150114)
			(end 0.299974 0.150114)
			(stroke
				(width 0.1)
				(type default)
			)
			(layer "F.Fab")
		)
		(fp_line
			(start -0.299974 0.150114)
			(end -0.299974 -0.150114)
			(stroke
				(width 0.1)
				(type default)
			)
			(layer "F.Fab")
		)
		(fp_line
			(start -0.299974 -0.150114)
			(end 0.299974 -0.150114)
			(stroke
				(width 0.1)
				(type default)
			)
			(layer "F.Fab")
		)
		(pad "1" smd rect
			(at -0.2667 0 180)
			(size 0.3048 0.381)
			(layers "F.Cu" "F.Mask" "F.Paste")
			(net "P5E_PEX3_STN0_TX_DN<2>")
		)
		(pad "2" smd rect
			(at 0.2667 0 180)
			(size 0.3048 0.381)
			(layers "F.Cu" "F.Mask" "F.Paste")
			(net "P5E_PEX3_STN0_TX_C_DN<2>")
		)
	)
	(footprint ""
		(layer "F.Cu")
		(at 412.124652 -158.080202 90)
		(property "Reference" "R2478"
			(at 0 0 90)
			(layer "F.SilkS")
			(hide yes)
			(effects
				(font
					(size 1.27 1.27)
				)
			)
		)
		(property "Value" ""
			(at 0 0 90)
			(layer "F.Fab")
			(effects
				(font
					(size 1.27 1.27)
				)
			)
		)
		(duplicate_pad_numbers_are_jumpers no)
		(fp_line
			(start 0.7874 -0.4064)
			(end 0.7874 0.4064)
			(stroke
				(width 0.1524)
				(type default)
			)
			(layer "F.SilkS")
		)
		(fp_line
			(start -0.7874 -0.4064)
			(end 0.7874 -0.4064)
			(stroke
				(width 0.1524)
				(type default)
			)
			(layer "F.SilkS")
		)
		(fp_line
			(start 0.7874 0.4064)
			(end -0.7874 0.4064)
			(stroke
				(width 0.1524)
				(type default)
			)
			(layer "F.SilkS")
		)
		(fp_line
			(start -0.7874 0.4064)
			(end -0.7874 -0.4064)
			(stroke
				(width 0.1524)
				(type default)
			)
			(layer "F.SilkS")
		)
		(fp_line
			(start -0.12065 -0.305054)
			(end -0.12065 -0.2794)
			(stroke
				(width 0.1)
				(type default)
			)
			(layer "F.Fab")
		)
		(fp_line
			(start -0.67945 -0.305054)
			(end -0.12065 -0.305054)
			(stroke
				(width 0.1)
				(type default)
			)
			(layer "F.Fab")
		)
		(fp_line
			(start 0.67945 -0.3048)
			(end 0.67945 0.3048)
			(stroke
				(width 0.1)
				(type default)
			)
			(layer "F.Fab")
		)
		(fp_line
			(start 0.12065 -0.3048)
			(end 0.67945 -0.3048)
			(stroke
				(width 0.1)
				(type default)
			)
			(layer "F.Fab")
		)
		(fp_line
			(start 0.12065 -0.2794)
			(end 0.12065 -0.3048)
			(stroke
				(width 0.1)
				(type default)
			)
			(layer "F.Fab")
		)
		(fp_line
			(start -0.12065 -0.2794)
			(end 0.12065 -0.2794)
			(stroke
				(width 0.1)
				(type default)
			)
			(layer "F.Fab")
		)
		(fp_line
			(start 0.120396 0.2794)
			(end -0.12065 0.2794)
			(stroke
				(width 0.1)
				(type default)
			)
			(layer "F.Fab")
		)
		(fp_line
			(start -0.12065 0.2794)
			(end -0.12065 0.3048)
			(stroke
				(width 0.1)
				(type default)
			)
			(layer "F.Fab")
		)
		(fp_line
			(start 0.67945 0.3048)
			(end 0.120396 0.3048)
			(stroke
				(width 0.1)
				(type default)
			)
			(layer "F.Fab")
		)
		(fp_line
			(start 0.120396 0.3048)
			(end 0.120396 0.2794)
			(stroke
				(width 0.1)
				(type default)
			)
			(layer "F.Fab")
		)
		(fp_line
			(start -0.12065 0.3048)
			(end -0.67945 0.3048)
			(stroke
				(width 0.1)
				(type default)
			)
			(layer "F.Fab")
		)
		(fp_line
			(start -0.67945 0.3048)
			(end -0.67945 -0.305054)
			(stroke
				(width 0.1)
				(type default)
			)
			(layer "F.Fab")
		)
		(pad "1" smd circle
			(at -0.40005 0 90)
			(size 0 0)
			(layers "F.Cu" "F.Mask" "F.Paste")
			(net "NIC7_PWRBRK_R_N")
		)
		(pad "2" smd circle
			(at 0.40005 0 90)
			(size 0 0)
			(layers "F.Cu" "F.Mask" "F.Paste")
			(net "NIC7_PWRBRK_N")
		)
	)
	(footprint ""
		(layer "F.Cu")
		(at 220.132656 -285.911544 180)
		(property "Reference" "PC238"
			(at 0 0 180)
			(layer "F.SilkS")
			(hide yes)
			(effects
				(font
					(size 1.27 1.27)
				)
			)
		)
		(property "Value" ""
			(at 0 0 180)
			(layer "F.Fab")
			(effects
				(font
					(size 1.27 1.27)
				)
			)
		)
		(duplicate_pad_numbers_are_jumpers no)
		(fp_line
			(start 2.750058 2.750058)
			(end 2.750058 0.9398)
			(stroke
				(width 0.1524)
				(type default)
			)
			(layer "F.SilkS")
		)
		(fp_line
			(start 2.750058 -0.9398)
			(end 2.750058 -2.750058)
			(stroke
				(width 0.1524)
				(type default)
			)
			(layer "F.SilkS")
		)
		(fp_line
			(start 2.750058 -2.750058)
			(end -1.988058 -2.750058)
			(stroke
				(width 0.1524)
				(type default)
			)
			(layer "F.SilkS")
		)
		(fp_line
			(start -1.988058 2.750058)
			(end 2.750058 2.750058)
			(stroke
				(width 0.1524)
				(type default)
			)
			(layer "F.SilkS")
		)
		(fp_line
			(start -1.988058 -2.750058)
			(end -2.750058 -1.988058)
			(stroke
				(width 0.1524)
				(type default)
			)
			(layer "F.SilkS")
		)
		(fp_line
			(start -2.750058 1.988058)
			(end -1.988058 2.750058)
			(stroke
				(width 0.1524)
				(type default)
			)
			(layer "F.SilkS")
		)
		(fp_line
			(start -2.750058 0.9398)
			(end -2.750058 1.988058)
			(stroke
				(width 0.1524)
				(type default)
			)
			(layer "F.SilkS")
		)
		(fp_line
			(start -2.750058 -1.988058)
			(end -2.750058 -0.9398)
			(stroke
				(width 0.1524)
				(type default)
			)
			(layer "F.SilkS")
		)
		(fp_line
			(start 2.750058 2.750058)
			(end 2.750058 -2.750058)
			(stroke
				(width 0.1)
				(type default)
			)
			(layer "F.Fab")
		)
		(fp_line
			(start 2.750058 -2.750058)
			(end -2.750058 -2.750058)
			(stroke
				(width 0.1)
				(type default)
			)
			(layer "F.Fab")
		)
		(fp_line
			(start -2.750058 2.750058)
			(end 2.750058 2.750058)
			(stroke
				(width 0.1)
				(type default)
			)
			(layer "F.Fab")
		)
		(fp_line
			(start -2.750058 -2.750058)
			(end -2.750058 2.750058)
			(stroke
				(width 0.1)
				(type default)
			)
			(layer "F.Fab")
		)
		(pad "1" smd rect
			(at -2.199894 0 270)
			(size 1.6002 3.0226)
			(layers "F.Cu" "F.Mask" "F.Paste")
			(net "P1V25_PEX1_R")
		)
		(pad "2" smd rect
			(at 2.199894 0 270)
			(size 1.6002 3.0226)
			(layers "F.Cu" "F.Mask" "F.Paste")
			(net "GND")
		)
	)
	(footprint ""
		(layer "F.Cu")
		(at 377.657868 -27.006296 -90)
		(property "Reference" "PR7125"
			(at 0 0 270)
			(layer "F.SilkS")
			(hide yes)
			(effects
				(font
					(size 1.27 1.27)
				)
			)
		)
		(property "Value" ""
			(at 0 0 270)
			(layer "F.Fab")
			(effects
				(font
					(size 1.27 1.27)
				)
			)
		)
		(duplicate_pad_numbers_are_jumpers no)
		(fp_line
			(start -0.7874 0.4064)
			(end -0.7874 -0.4064)
			(stroke
				(width 0.1524)
				(type default)
			)
			(layer "F.SilkS")
		)
		(fp_line
			(start 0.7874 0.4064)
			(end -0.7874 0.4064)
			(stroke
				(width 0.1524)
				(type default)
			)
			(layer "F.SilkS")
		)
		(fp_line
			(start -0.7874 -0.4064)
			(end 0.7874 -0.4064)
			(stroke
				(width 0.1524)
				(type default)
			)
			(layer "F.SilkS")
		)
		(fp_line
			(start 0.7874 -0.4064)
			(end 0.7874 0.4064)
			(stroke
				(width 0.1524)
				(type default)
			)
			(layer "F.SilkS")
		)
		(fp_line
			(start -0.67945 0.3048)
			(end -0.67945 -0.305054)
			(stroke
				(width 0.1)
				(type default)
			)
			(layer "F.Fab")
		)
		(fp_line
			(start -0.12065 0.3048)
			(end -0.67945 0.3048)
			(stroke
				(width 0.1)
				(type default)
			)
			(layer "F.Fab")
		)
		(fp_line
			(start 0.120396 0.3048)
			(end 0.120396 0.2794)
			(stroke
				(width 0.1)
				(type default)
			)
			(layer "F.Fab")
		)
		(fp_line
			(start 0.67945 0.3048)
			(end 0.120396 0.3048)
			(stroke
				(width 0.1)
				(type default)
			)
			(layer "F.Fab")
		)
		(fp_line
			(start -0.12065 0.2794)
			(end -0.12065 0.3048)
			(stroke
				(width 0.1)
				(type default)
			)
			(layer "F.Fab")
		)
		(fp_line
			(start 0.120396 0.2794)
			(end -0.12065 0.2794)
			(stroke
				(width 0.1)
				(type default)
			)
			(layer "F.Fab")
		)
		(fp_line
			(start -0.12065 -0.2794)
			(end 0.12065 -0.2794)
			(stroke
				(width 0.1)
				(type default)
			)
			(layer "F.Fab")
		)
		(fp_line
			(start 0.12065 -0.2794)
			(end 0.12065 -0.3048)
			(stroke
				(width 0.1)
				(type default)
			)
			(layer "F.Fab")
		)
		(fp_line
			(start 0.12065 -0.3048)
			(end 0.67945 -0.3048)
			(stroke
				(width 0.1)
				(type default)
			)
			(layer "F.Fab")
		)
		(fp_line
			(start 0.67945 -0.3048)
			(end 0.67945 0.3048)
			(stroke
				(width 0.1)
				(type default)
			)
			(layer "F.Fab")
		)
		(fp_line
			(start -0.67945 -0.305054)
			(end -0.12065 -0.305054)
			(stroke
				(width 0.1)
				(type default)
			)
			(layer "F.Fab")
		)
		(fp_line
			(start -0.12065 -0.305054)
			(end -0.12065 -0.2794)
			(stroke
				(width 0.1)
				(type default)
			)
			(layer "F.Fab")
		)
		(pad "1" smd circle
			(at -0.40005 0 270)
			(size 0 0)
			(layers "F.Cu" "F.Mask" "F.Paste")
			(net "P3V3_SSD13_CO_MODE")
		)
		(pad "2" smd circle
			(at 0.40005 0 270)
			(size 0 0)
			(layers "F.Cu" "F.Mask" "F.Paste")
			(net "GND")
		)
	)
	(footprint ""
		(layer "F.Cu")
		(at 223.586294 -175.50638)
		(property "Reference" "R3146"
			(at 0 0 0)
			(layer "F.SilkS")
			(hide yes)
			(effects
				(font
					(size 1.27 1.27)
				)
			)
		)
		(property "Value" ""
			(at 0 0 0)
			(layer "F.Fab")
			(effects
				(font
					(size 1.27 1.27)
				)
			)
		)
		(duplicate_pad_numbers_are_jumpers no)
		(fp_line
			(start -0.7874 -0.4064)
			(end 0.7874 -0.4064)
			(stroke
				(width 0.1524)
				(type default)
			)
			(layer "F.SilkS")
		)
		(fp_line
			(start -0.7874 0.4064)
			(end -0.7874 -0.4064)
			(stroke
				(width 0.1524)
				(type default)
			)
			(layer "F.SilkS")
		)
		(fp_line
			(start 0.7874 -0.4064)
			(end 0.7874 0.4064)
			(stroke
				(width 0.1524)
				(type default)
			)
			(layer "F.SilkS")
		)
		(fp_line
			(start 0.7874 0.4064)
			(end -0.7874 0.4064)
			(stroke
				(width 0.1524)
				(type default)
			)
			(layer "F.SilkS")
		)
		(fp_line
			(start -0.67945 -0.305054)
			(end -0.12065 -0.305054)
			(stroke
				(width 0.1)
				(type default)
			)
			(layer "F.Fab")
		)
		(fp_line
			(start -0.67945 0.3048)
			(end -0.67945 -0.305054)
			(stroke
				(width 0.1)
				(type default)
			)
			(layer "F.Fab")
		)
		(fp_line
			(start -0.12065 -0.305054)
			(end -0.12065 -0.2794)
			(stroke
				(width 0.1)
				(type default)
			)
			(layer "F.Fab")
		)
		(fp_line
			(start -0.12065 -0.2794)
			(end 0.12065 -0.2794)
			(stroke
				(width 0.1)
				(type default)
			)
			(layer "F.Fab")
		)
		(fp_line
			(start -0.12065 0.2794)
			(end -0.12065 0.3048)
			(stroke
				(width 0.1)
				(type default)
			)
			(layer "F.Fab")
		)
		(fp_line
			(start -0.12065 0.3048)
			(end -0.67945 0.3048)
			(stroke
				(width 0.1)
				(type default)
			)
			(layer "F.Fab")
		)
		(fp_line
			(start 0.120396 0.2794)
			(end -0.12065 0.2794)
			(stroke
				(width 0.1)
				(type default)
			)
			(layer "F.Fab")
		)
		(fp_line
			(start 0.120396 0.3048)
			(end 0.120396 0.2794)
			(stroke
				(width 0.1)
				(type default)
			)
			(layer "F.Fab")
		)
		(fp_line
			(start 0.12065 -0.3048)
			(end 0.67945 -0.3048)
			(stroke
				(width 0.1)
				(type default)
			)
			(layer "F.Fab")
		)
		(fp_line
			(start 0.12065 -0.2794)
			(end 0.12065 -0.3048)
			(stroke
				(width 0.1)
				(type default)
			)
			(layer "F.Fab")
		)
		(fp_line
			(start 0.67945 -0.3048)
			(end 0.67945 0.3048)
			(stroke
				(width 0.1)
				(type default)
			)
			(layer "F.Fab")
		)
		(fp_line
			(start 0.67945 0.3048)
			(end 0.120396 0.3048)
			(stroke
				(width 0.1)
				(type default)
			)
			(layer "F.Fab")
		)
		(pad "1" smd circle
			(at -0.40005 0)
			(size 0 0)
			(layers "F.Cu" "F.Mask" "F.Paste")
			(net "P12V_AUX")
		)
		(pad "2" smd circle
			(at 0.40005 0)
			(size 0 0)
			(layers "F.Cu" "F.Mask" "F.Paste")
			(net "ADM1085_IN")
		)
	)
	(footprint ""
		(layer "F.Cu")
		(at 402.25218 -356.244906 90)
		(property "Reference" "C730"
			(at 0 0 90)
			(layer "F.SilkS")
			(hide yes)
			(effects
				(font
					(size 1.27 1.27)
				)
			)
		)
		(property "Value" ""
			(at 0 0 90)
			(layer "F.Fab")
			(effects
				(font
					(size 1.27 1.27)
				)
			)
		)
		(duplicate_pad_numbers_are_jumpers no)
		(fp_line
			(start 0.299974 -0.150114)
			(end 0.299974 0.150114)
			(stroke
				(width 0.1)
				(type default)
			)
			(layer "F.Fab")
		)
		(fp_line
			(start -0.299974 -0.150114)
			(end 0.299974 -0.150114)
			(stroke
				(width 0.1)
				(type default)
			)
			(layer "F.Fab")
		)
		(fp_line
			(start 0.299974 0.150114)
			(end -0.299974 0.150114)
			(stroke
				(width 0.1)
				(type default)
			)
			(layer "F.Fab")
		)
		(fp_line
			(start -0.299974 0.150114)
			(end -0.299974 -0.150114)
			(stroke
				(width 0.1)
				(type default)
			)
			(layer "F.Fab")
		)
		(pad "1" smd rect
			(at -0.2667 0 90)
			(size 0.3048 0.381)
			(layers "F.Cu" "F.Mask" "F.Paste")
			(net "P5E_PEX3_STN5_TX_DP<95>")
		)
		(pad "2" smd rect
			(at 0.2667 0 90)
			(size 0.3048 0.381)
			(layers "F.Cu" "F.Mask" "F.Paste")
			(net "P5E_PEX3_STN5_TX_C_DP<95>")
		)
	)
	(footprint ""
		(layer "F.Cu")
		(at 265.487658 -298.020232)
		(property "Reference" "C3369"
			(at 0 0 0)
			(layer "F.SilkS")
			(hide yes)
			(effects
				(font
					(size 1.27 1.27)
				)
			)
		)
		(property "Value" ""
			(at 0 0 0)
			(layer "F.Fab")
			(effects
				(font
					(size 1.27 1.27)
				)
			)
		)
		(duplicate_pad_numbers_are_jumpers no)
		(fp_line
			(start -1.2954 -0.5842)
			(end 1.2954 -0.5842)
			(stroke
				(width 0.1524)
				(type default)
			)
			(layer "F.SilkS")
		)
		(fp_line
			(start -1.2954 0.5842)
			(end -1.2954 -0.5842)
			(stroke
				(width 0.1524)
				(type default)
			)
			(layer "F.SilkS")
		)
		(fp_line
			(start 1.2954 -0.5842)
			(end 1.2954 0.5842)
			(stroke
				(width 0.1524)
				(type default)
			)
			(layer "F.SilkS")
		)
		(fp_line
			(start 1.2954 0.5842)
			(end -1.2954 0.5842)
			(stroke
				(width 0.1524)
				(type default)
			)
			(layer "F.SilkS")
		)
		(fp_line
			(start -1.1938 -0.4064)
			(end -0.8636 -0.4064)
			(stroke
				(width 0.1)
				(type default)
			)
			(layer "F.Fab")
		)
		(fp_line
			(start -1.1938 0.4064)
			(end -1.1938 -0.4064)
			(stroke
				(width 0.1)
				(type default)
			)
			(layer "F.Fab")
		)
		(fp_line
			(start -0.8636 -0.4572)
			(end 0.8636 -0.4572)
			(stroke
				(width 0.1)
				(type default)
			)
			(layer "F.Fab")
		)
		(fp_line
			(start -0.8636 -0.4064)
			(end -0.8636 -0.4572)
			(stroke
				(width 0.1)
				(type default)
			)
			(layer "F.Fab")
		)
		(fp_line
			(start -0.8636 0.4064)
			(end -1.1938 0.4064)
			(stroke
				(width 0.1)
				(type default)
			)
			(layer "F.Fab")
		)
		(fp_line
			(start -0.8636 0.4572)
			(end -0.8636 0.4064)
			(stroke
				(width 0.1)
				(type default)
			)
			(layer "F.Fab")
		)
		(fp_line
			(start 0.8636 -0.4572)
			(end 0.8636 -0.4064)
			(stroke
				(width 0.1)
				(type default)
			)
			(layer "F.Fab")
		)
		(fp_line
			(start 0.8636 -0.4064)
			(end 1.1938 -0.4064)
			(stroke
				(width 0.1)
				(type default)
			)
			(layer "F.Fab")
		)
		(fp_line
			(start 0.8636 0.4064)
			(end 0.8636 0.4572)
			(stroke
				(width 0.1)
				(type default)
			)
			(layer "F.Fab")
		)
		(fp_line
			(start 0.8636 0.4572)
			(end -0.8636 0.4572)
			(stroke
				(width 0.1)
				(type default)
			)
			(layer "F.Fab")
		)
		(fp_line
			(start 1.1938 -0.4064)
			(end 1.1938 0.4064)
			(stroke
				(width 0.1)
				(type default)
			)
			(layer "F.Fab")
		)
		(fp_line
			(start 1.1938 0.4064)
			(end 0.8636 0.4064)
			(stroke
				(width 0.1)
				(type default)
			)
			(layer "F.Fab")
		)
		(pad "1" smd rect
			(at -0.7366 0 270)
			(size 0.7112 0.8128)
			(layers "F.Cu" "F.Mask" "F.Paste")
			(net "PCEPLL0_VDDA18_PEX2")
		)
		(pad "2" smd rect
			(at 0.7366 0 270)
			(size 0.7112 0.8128)
			(layers "F.Cu" "F.Mask" "F.Paste")
			(net "GND")
		)
	)
	(footprint ""
		(layer "F.Cu")
		(at 333.974186 -10.534142 -90)
		(property "Reference" "R1708"
			(at 0 0 270)
			(layer "F.SilkS")
			(hide yes)
			(effects
				(font
					(size 1.27 1.27)
				)
			)
		)
		(property "Value" ""
			(at 0 0 270)
			(layer "F.Fab")
			(effects
				(font
					(size 1.27 1.27)
				)
			)
		)
		(duplicate_pad_numbers_are_jumpers no)
		(fp_line
			(start -0.7874 0.4064)
			(end -0.7874 -0.4064)
			(stroke
				(width 0.1524)
				(type default)
			)
			(layer "F.SilkS")
		)
		(fp_line
			(start 0.7874 0.4064)
			(end -0.7874 0.4064)
			(stroke
				(width 0.1524)
				(type default)
			)
			(layer "F.SilkS")
		)
		(fp_line
			(start -0.7874 -0.4064)
			(end 0.7874 -0.4064)
			(stroke
				(width 0.1524)
				(type default)
			)
			(layer "F.SilkS")
		)
		(fp_line
			(start 0.7874 -0.4064)
			(end 0.7874 0.4064)
			(stroke
				(width 0.1524)
				(type default)
			)
			(layer "F.SilkS")
		)
		(fp_line
			(start -0.67945 0.3048)
			(end -0.67945 -0.305054)
			(stroke
				(width 0.1)
				(type default)
			)
			(layer "F.Fab")
		)
		(fp_line
			(start -0.12065 0.3048)
			(end -0.67945 0.3048)
			(stroke
				(width 0.1)
				(type default)
			)
			(layer "F.Fab")
		)
		(fp_line
			(start 0.120396 0.3048)
			(end 0.120396 0.2794)
			(stroke
				(width 0.1)
				(type default)
			)
			(layer "F.Fab")
		)
		(fp_line
			(start 0.67945 0.3048)
			(end 0.120396 0.3048)
			(stroke
				(width 0.1)
				(type default)
			)
			(layer "F.Fab")
		)
		(fp_line
			(start -0.12065 0.2794)
			(end -0.12065 0.3048)
			(stroke
				(width 0.1)
				(type default)
			)
			(layer "F.Fab")
		)
		(fp_line
			(start 0.120396 0.2794)
			(end -0.12065 0.2794)
			(stroke
				(width 0.1)
				(type default)
			)
			(layer "F.Fab")
		)
		(fp_line
			(start -0.12065 -0.2794)
			(end 0.12065 -0.2794)
			(stroke
				(width 0.1)
				(type default)
			)
			(layer "F.Fab")
		)
		(fp_line
			(start 0.12065 -0.2794)
			(end 0.12065 -0.3048)
			(stroke
				(width 0.1)
				(type default)
			)
			(layer "F.Fab")
		)
		(fp_line
			(start 0.12065 -0.3048)
			(end 0.67945 -0.3048)
			(stroke
				(width 0.1)
				(type default)
			)
			(layer "F.Fab")
		)
		(fp_line
			(start 0.67945 -0.3048)
			(end 0.67945 0.3048)
			(stroke
				(width 0.1)
				(type default)
			)
			(layer "F.Fab")
		)
		(fp_line
			(start -0.67945 -0.305054)
			(end -0.12065 -0.305054)
			(stroke
				(width 0.1)
				(type default)
			)
			(layer "F.Fab")
		)
		(fp_line
			(start -0.12065 -0.305054)
			(end -0.12065 -0.2794)
			(stroke
				(width 0.1)
				(type default)
			)
			(layer "F.Fab")
		)
		(pad "1" smd circle
			(at -0.40005 0 270)
			(size 0 0)
			(layers "F.Cu" "F.Mask" "F.Paste")
			(net "SMB_ISO_SSD11_R_SCL")
		)
		(pad "2" smd circle
			(at 0.40005 0 270)
			(size 0 0)
			(layers "F.Cu" "F.Mask" "F.Paste")
			(net "SMB_ISO_SSD11_SCL")
		)
	)
	(footprint ""
		(layer "F.Cu")
		(at 89.002108 -306.074572 90)
		(property "Reference" "R1236"
			(at 0 0 90)
			(layer "F.SilkS")
			(hide yes)
			(effects
				(font
					(size 1.27 1.27)
				)
			)
		)
		(property "Value" ""
			(at 0 0 90)
			(layer "F.Fab")
			(effects
				(font
					(size 1.27 1.27)
				)
			)
		)
		(duplicate_pad_numbers_are_jumpers no)
		(fp_line
			(start 0.7874 -0.4064)
			(end 0.7874 0.4064)
			(stroke
				(width 0.1524)
				(type default)
			)
			(layer "F.SilkS")
		)
		(fp_line
			(start -0.7874 -0.4064)
			(end 0.7874 -0.4064)
			(stroke
				(width 0.1524)
				(type default)
			)
			(layer "F.SilkS")
		)
		(fp_line
			(start 0.7874 0.4064)
			(end -0.7874 0.4064)
			(stroke
				(width 0.1524)
				(type default)
			)
			(layer "F.SilkS")
		)
		(fp_line
			(start -0.7874 0.4064)
			(end -0.7874 -0.4064)
			(stroke
				(width 0.1524)
				(type default)
			)
			(layer "F.SilkS")
		)
		(fp_line
			(start -0.12065 -0.305054)
			(end -0.12065 -0.2794)
			(stroke
				(width 0.1)
				(type default)
			)
			(layer "F.Fab")
		)
		(fp_line
			(start -0.67945 -0.305054)
			(end -0.12065 -0.305054)
			(stroke
				(width 0.1)
				(type default)
			)
			(layer "F.Fab")
		)
		(fp_line
			(start 0.67945 -0.3048)
			(end 0.67945 0.3048)
			(stroke
				(width 0.1)
				(type default)
			)
			(layer "F.Fab")
		)
		(fp_line
			(start 0.12065 -0.3048)
			(end 0.67945 -0.3048)
			(stroke
				(width 0.1)
				(type default)
			)
			(layer "F.Fab")
		)
		(fp_line
			(start 0.12065 -0.2794)
			(end 0.12065 -0.3048)
			(stroke
				(width 0.1)
				(type default)
			)
			(layer "F.Fab")
		)
		(fp_line
			(start -0.12065 -0.2794)
			(end 0.12065 -0.2794)
			(stroke
				(width 0.1)
				(type default)
			)
			(layer "F.Fab")
		)
		(fp_line
			(start 0.120396 0.2794)
			(end -0.12065 0.2794)
			(stroke
				(width 0.1)
				(type default)
			)
			(layer "F.Fab")
		)
		(fp_line
			(start -0.12065 0.2794)
			(end -0.12065 0.3048)
			(stroke
				(width 0.1)
				(type default)
			)
			(layer "F.Fab")
		)
		(fp_line
			(start 0.67945 0.3048)
			(end 0.120396 0.3048)
			(stroke
				(width 0.1)
				(type default)
			)
			(layer "F.Fab")
		)
		(fp_line
			(start 0.120396 0.3048)
			(end 0.120396 0.2794)
			(stroke
				(width 0.1)
				(type default)
			)
			(layer "F.Fab")
		)
		(fp_line
			(start -0.12065 0.3048)
			(end -0.67945 0.3048)
			(stroke
				(width 0.1)
				(type default)
			)
			(layer "F.Fab")
		)
		(fp_line
			(start -0.67945 0.3048)
			(end -0.67945 -0.305054)
			(stroke
				(width 0.1)
				(type default)
			)
			(layer "F.Fab")
		)
		(pad "1" smd circle
			(at -0.40005 0 90)
			(size 0 0)
			(layers "F.Cu" "F.Mask" "F.Paste")
			(net "PEX0_SPARE4")
		)
		(pad "2" smd circle
			(at 0.40005 0 90)
			(size 0 0)
			(layers "F.Cu" "F.Mask" "F.Paste")
			(net "P1V8_PEX")
		)
	)
	(footprint ""
		(layer "F.Cu")
		(at 259.190998 -255.359662)
		(property "Reference" "C3413"
			(at 0 0 0)
			(layer "F.SilkS")
			(hide yes)
			(effects
				(font
					(size 1.27 1.27)
				)
			)
		)
		(property "Value" ""
			(at 0 0 0)
			(layer "F.Fab")
			(effects
				(font
					(size 1.27 1.27)
				)
			)
		)
		(duplicate_pad_numbers_are_jumpers no)
		(fp_line
			(start -1.2954 -0.5842)
			(end 1.2954 -0.5842)
			(stroke
				(width 0.1524)
				(type default)
			)
			(layer "F.SilkS")
		)
		(fp_line
			(start -1.2954 0.5842)
			(end -1.2954 -0.5842)
			(stroke
				(width 0.1524)
				(type default)
			)
			(layer "F.SilkS")
		)
		(fp_line
			(start 1.2954 -0.5842)
			(end 1.2954 0.5842)
			(stroke
				(width 0.1524)
				(type default)
			)
			(layer "F.SilkS")
		)
		(fp_line
			(start 1.2954 0.5842)
			(end -1.2954 0.5842)
			(stroke
				(width 0.1524)
				(type default)
			)
			(layer "F.SilkS")
		)
		(fp_line
			(start -1.1938 -0.4064)
			(end -0.8636 -0.4064)
			(stroke
				(width 0.1)
				(type default)
			)
			(layer "F.Fab")
		)
		(fp_line
			(start -1.1938 0.4064)
			(end -1.1938 -0.4064)
			(stroke
				(width 0.1)
				(type default)
			)
			(layer "F.Fab")
		)
		(fp_line
			(start -0.8636 -0.4572)
			(end 0.8636 -0.4572)
			(stroke
				(width 0.1)
				(type default)
			)
			(layer "F.Fab")
		)
		(fp_line
			(start -0.8636 -0.4064)
			(end -0.8636 -0.4572)
			(stroke
				(width 0.1)
				(type default)
			)
			(layer "F.Fab")
		)
		(fp_line
			(start -0.8636 0.4064)
			(end -1.1938 0.4064)
			(stroke
				(width 0.1)
				(type default)
			)
			(layer "F.Fab")
		)
		(fp_line
			(start -0.8636 0.4572)
			(end -0.8636 0.4064)
			(stroke
				(width 0.1)
				(type default)
			)
			(layer "F.Fab")
		)
		(fp_line
			(start 0.8636 -0.4572)
			(end 0.8636 -0.4064)
			(stroke
				(width 0.1)
				(type default)
			)
			(layer "F.Fab")
		)
		(fp_line
			(start 0.8636 -0.4064)
			(end 1.1938 -0.4064)
			(stroke
				(width 0.1)
				(type default)
			)
			(layer "F.Fab")
		)
		(fp_line
			(start 0.8636 0.4064)
			(end 0.8636 0.4572)
			(stroke
				(width 0.1)
				(type default)
			)
			(layer "F.Fab")
		)
		(fp_line
			(start 0.8636 0.4572)
			(end -0.8636 0.4572)
			(stroke
				(width 0.1)
				(type default)
			)
			(layer "F.Fab")
		)
		(fp_line
			(start 1.1938 -0.4064)
			(end 1.1938 0.4064)
			(stroke
				(width 0.1)
				(type default)
			)
			(layer "F.Fab")
		)
		(fp_line
			(start 1.1938 0.4064)
			(end 0.8636 0.4064)
			(stroke
				(width 0.1)
				(type default)
			)
			(layer "F.Fab")
		)
		(pad "1" smd rect
			(at -0.7366 0 270)
			(size 0.7112 0.8128)
			(layers "F.Cu" "F.Mask" "F.Paste")
			(net "P1V8_PLL0_PEX2")
		)
		(pad "2" smd rect
			(at 0.7366 0 270)
			(size 0.7112 0.8128)
			(layers "F.Cu" "F.Mask" "F.Paste")
			(net "GND")
		)
	)
	(footprint ""
		(layer "F.Cu")
		(at 166.330884 -193.836798)
		(property "Reference" "R3409"
			(at 0 0 0)
			(layer "F.SilkS")
			(hide yes)
			(effects
				(font
					(size 1.27 1.27)
				)
			)
		)
		(property "Value" ""
			(at 0 0 0)
			(layer "F.Fab")
			(effects
				(font
					(size 1.27 1.27)
				)
			)
		)
		(duplicate_pad_numbers_are_jumpers no)
		(fp_line
			(start -0.7874 -0.4064)
			(end 0.7874 -0.4064)
			(stroke
				(width 0.1524)
				(type default)
			)
			(layer "F.SilkS")
		)
		(fp_line
			(start -0.7874 0.4064)
			(end -0.7874 -0.4064)
			(stroke
				(width 0.1524)
				(type default)
			)
			(layer "F.SilkS")
		)
		(fp_line
			(start 0.7874 -0.4064)
			(end 0.7874 0.4064)
			(stroke
				(width 0.1524)
				(type default)
			)
			(layer "F.SilkS")
		)
		(fp_line
			(start 0.7874 0.4064)
			(end -0.7874 0.4064)
			(stroke
				(width 0.1524)
				(type default)
			)
			(layer "F.SilkS")
		)
		(fp_line
			(start -0.67945 -0.305054)
			(end -0.12065 -0.305054)
			(stroke
				(width 0.1)
				(type default)
			)
			(layer "F.Fab")
		)
		(fp_line
			(start -0.67945 0.3048)
			(end -0.67945 -0.305054)
			(stroke
				(width 0.1)
				(type default)
			)
			(layer "F.Fab")
		)
		(fp_line
			(start -0.12065 -0.305054)
			(end -0.12065 -0.2794)
			(stroke
				(width 0.1)
				(type default)
			)
			(layer "F.Fab")
		)
		(fp_line
			(start -0.12065 -0.2794)
			(end 0.12065 -0.2794)
			(stroke
				(width 0.1)
				(type default)
			)
			(layer "F.Fab")
		)
		(fp_line
			(start -0.12065 0.2794)
			(end -0.12065 0.3048)
			(stroke
				(width 0.1)
				(type default)
			)
			(layer "F.Fab")
		)
		(fp_line
			(start -0.12065 0.3048)
			(end -0.67945 0.3048)
			(stroke
				(width 0.1)
				(type default)
			)
			(layer "F.Fab")
		)
		(fp_line
			(start 0.120396 0.2794)
			(end -0.12065 0.2794)
			(stroke
				(width 0.1)
				(type default)
			)
			(layer "F.Fab")
		)
		(fp_line
			(start 0.120396 0.3048)
			(end 0.120396 0.2794)
			(stroke
				(width 0.1)
				(type default)
			)
			(layer "F.Fab")
		)
		(fp_line
			(start 0.12065 -0.3048)
			(end 0.67945 -0.3048)
			(stroke
				(width 0.1)
				(type default)
			)
			(layer "F.Fab")
		)
		(fp_line
			(start 0.12065 -0.2794)
			(end 0.12065 -0.3048)
			(stroke
				(width 0.1)
				(type default)
			)
			(layer "F.Fab")
		)
		(fp_line
			(start 0.67945 -0.3048)
			(end 0.67945 0.3048)
			(stroke
				(width 0.1)
				(type default)
			)
			(layer "F.Fab")
		)
		(fp_line
			(start 0.67945 0.3048)
			(end 0.120396 0.3048)
			(stroke
				(width 0.1)
				(type default)
			)
			(layer "F.Fab")
		)
		(pad "1" smd circle
			(at -0.40005 0)
			(size 0 0)
			(layers "F.Cu" "F.Mask" "F.Paste")
			(net "SPI_BIC1_MISO_LS01_R2")
		)
		(pad "2" smd circle
			(at 0.40005 0)
			(size 0 0)
			(layers "F.Cu" "F.Mask" "F.Paste")
			(net "SPI_BIC1_MISO_LS01_R")
		)
	)
	(footprint ""
		(layer "F.Cu")
		(at 370.563648 -146.592798 -90)
		(property "Reference" "R755"
			(at 0 0 270)
			(layer "F.SilkS")
			(hide yes)
			(effects
				(font
					(size 1.27 1.27)
				)
			)
		)
		(property "Value" ""
			(at 0 0 270)
			(layer "F.Fab")
			(effects
				(font
					(size 1.27 1.27)
				)
			)
		)
		(duplicate_pad_numbers_are_jumpers no)
		(fp_line
			(start -0.7874 0.4064)
			(end -0.7874 -0.4064)
			(stroke
				(width 0.1524)
				(type default)
			)
			(layer "F.SilkS")
		)
		(fp_line
			(start 0.7874 0.4064)
			(end -0.7874 0.4064)
			(stroke
				(width 0.1524)
				(type default)
			)
			(layer "F.SilkS")
		)
		(fp_line
			(start -0.7874 -0.4064)
			(end 0.7874 -0.4064)
			(stroke
				(width 0.1524)
				(type default)
			)
			(layer "F.SilkS")
		)
		(fp_line
			(start 0.7874 -0.4064)
			(end 0.7874 0.4064)
			(stroke
				(width 0.1524)
				(type default)
			)
			(layer "F.SilkS")
		)
		(fp_line
			(start -0.67945 0.3048)
			(end -0.67945 -0.305054)
			(stroke
				(width 0.1)
				(type default)
			)
			(layer "F.Fab")
		)
		(fp_line
			(start -0.12065 0.3048)
			(end -0.67945 0.3048)
			(stroke
				(width 0.1)
				(type default)
			)
			(layer "F.Fab")
		)
		(fp_line
			(start 0.120396 0.3048)
			(end 0.120396 0.2794)
			(stroke
				(width 0.1)
				(type default)
			)
			(layer "F.Fab")
		)
		(fp_line
			(start 0.67945 0.3048)
			(end 0.120396 0.3048)
			(stroke
				(width 0.1)
				(type default)
			)
			(layer "F.Fab")
		)
		(fp_line
			(start -0.12065 0.2794)
			(end -0.12065 0.3048)
			(stroke
				(width 0.1)
				(type default)
			)
			(layer "F.Fab")
		)
		(fp_line
			(start 0.120396 0.2794)
			(end -0.12065 0.2794)
			(stroke
				(width 0.1)
				(type default)
			)
			(layer "F.Fab")
		)
		(fp_line
			(start -0.12065 -0.2794)
			(end 0.12065 -0.2794)
			(stroke
				(width 0.1)
				(type default)
			)
			(layer "F.Fab")
		)
		(fp_line
			(start 0.12065 -0.2794)
			(end 0.12065 -0.3048)
			(stroke
				(width 0.1)
				(type default)
			)
			(layer "F.Fab")
		)
		(fp_line
			(start 0.12065 -0.3048)
			(end 0.67945 -0.3048)
			(stroke
				(width 0.1)
				(type default)
			)
			(layer "F.Fab")
		)
		(fp_line
			(start 0.67945 -0.3048)
			(end 0.67945 0.3048)
			(stroke
				(width 0.1)
				(type default)
			)
			(layer "F.Fab")
		)
		(fp_line
			(start -0.67945 -0.305054)
			(end -0.12065 -0.305054)
			(stroke
				(width 0.1)
				(type default)
			)
			(layer "F.Fab")
		)
		(fp_line
			(start -0.12065 -0.305054)
			(end -0.12065 -0.2794)
			(stroke
				(width 0.1)
				(type default)
			)
			(layer "F.Fab")
		)
		(pad "1" smd circle
			(at -0.40005 0 270)
			(size 0 0)
			(layers "F.Cu" "F.Mask" "F.Paste")
			(net "P12V_NIC6_R")
		)
		(pad "2" smd circle
			(at 0.40005 0 270)
			(size 0 0)
			(layers "F.Cu" "F.Mask" "F.Paste")
			(net "P12V_NIC6_VIN_P")
		)
	)
	(footprint ""
		(layer "F.Cu")
		(at 265.240008 -256.634234 180)
		(property "Reference" "C3398"
			(at 0 0 180)
			(layer "F.SilkS")
			(hide yes)
			(effects
				(font
					(size 1.27 1.27)
				)
			)
		)
		(property "Value" ""
			(at 0 0 180)
			(layer "F.Fab")
			(effects
				(font
					(size 1.27 1.27)
				)
			)
		)
		(duplicate_pad_numbers_are_jumpers no)
		(fp_line
			(start 1.2954 0.5842)
			(end -1.2954 0.5842)
			(stroke
				(width 0.1524)
				(type default)
			)
			(layer "F.SilkS")
		)
		(fp_line
			(start 1.2954 -0.5842)
			(end 1.2954 0.5842)
			(stroke
				(width 0.1524)
				(type default)
			)
			(layer "F.SilkS")
		)
		(fp_line
			(start -1.2954 0.5842)
			(end -1.2954 -0.5842)
			(stroke
				(width 0.1524)
				(type default)
			)
			(layer "F.SilkS")
		)
		(fp_line
			(start -1.2954 -0.5842)
			(end 1.2954 -0.5842)
			(stroke
				(width 0.1524)
				(type default)
			)
			(layer "F.SilkS")
		)
		(fp_line
			(start 1.1938 0.4064)
			(end 0.8636 0.4064)
			(stroke
				(width 0.1)
				(type default)
			)
			(layer "F.Fab")
		)
		(fp_line
			(start 1.1938 -0.4064)
			(end 1.1938 0.4064)
			(stroke
				(width 0.1)
				(type default)
			)
			(layer "F.Fab")
		)
		(fp_line
			(start 0.8636 0.4572)
			(end -0.8636 0.4572)
			(stroke
				(width 0.1)
				(type default)
			)
			(layer "F.Fab")
		)
		(fp_line
			(start 0.8636 0.4064)
			(end 0.8636 0.4572)
			(stroke
				(width 0.1)
				(type default)
			)
			(layer "F.Fab")
		)
		(fp_line
			(start 0.8636 -0.4064)
			(end 1.1938 -0.4064)
			(stroke
				(width 0.1)
				(type default)
			)
			(layer "F.Fab")
		)
		(fp_line
			(start 0.8636 -0.4572)
			(end 0.8636 -0.4064)
			(stroke
				(width 0.1)
				(type default)
			)
			(layer "F.Fab")
		)
		(fp_line
			(start -0.8636 0.4572)
			(end -0.8636 0.4064)
			(stroke
				(width 0.1)
				(type default)
			)
			(layer "F.Fab")
		)
		(fp_line
			(start -0.8636 0.4064)
			(end -1.1938 0.4064)
			(stroke
				(width 0.1)
				(type default)
			)
			(layer "F.Fab")
		)
		(fp_line
			(start -0.8636 -0.4064)
			(end -0.8636 -0.4572)
			(stroke
				(width 0.1)
				(type default)
			)
			(layer "F.Fab")
		)
		(fp_line
			(start -0.8636 -0.4572)
			(end 0.8636 -0.4572)
			(stroke
				(width 0.1)
				(type default)
			)
			(layer "F.Fab")
		)
		(fp_line
			(start -1.1938 0.4064)
			(end -1.1938 -0.4064)
			(stroke
				(width 0.1)
				(type default)
			)
			(layer "F.Fab")
		)
		(fp_line
			(start -1.1938 -0.4064)
			(end -0.8636 -0.4064)
			(stroke
				(width 0.1)
				(type default)
			)
			(layer "F.Fab")
		)
		(pad "1" smd rect
			(at -0.7366 0 90)
			(size 0.7112 0.8128)
			(layers "F.Cu" "F.Mask" "F.Paste")
			(net "PCEPLL5_VDDA18_PEX2_R")
		)
		(pad "2" smd rect
			(at 0.7366 0 90)
			(size 0.7112 0.8128)
			(layers "F.Cu" "F.Mask" "F.Paste")
			(net "GND")
		)
	)
	(footprint ""
		(layer "F.Cu")
		(at 152.411938 -137.2489 -90)
		(property "Reference" "C889"
			(at 0 0 270)
			(layer "F.SilkS")
			(hide yes)
			(effects
				(font
					(size 1.27 1.27)
				)
			)
		)
		(property "Value" ""
			(at 0 0 270)
			(layer "F.Fab")
			(effects
				(font
					(size 1.27 1.27)
				)
			)
		)
		(duplicate_pad_numbers_are_jumpers no)
		(fp_line
			(start -0.7874 0.4064)
			(end -0.7874 -0.4064)
			(stroke
				(width 0.1524)
				(type default)
			)
			(layer "F.SilkS")
		)
		(fp_line
			(start 0.7874 0.4064)
			(end -0.7874 0.4064)
			(stroke
				(width 0.1524)
				(type default)
			)
			(layer "F.SilkS")
		)
		(fp_line
			(start -0.7874 -0.4064)
			(end 0.7874 -0.4064)
			(stroke
				(width 0.1524)
				(type default)
			)
			(layer "F.SilkS")
		)
		(fp_line
			(start 0.7874 -0.4064)
			(end 0.7874 0.4064)
			(stroke
				(width 0.1524)
				(type default)
			)
			(layer "F.SilkS")
		)
		(fp_line
			(start -0.67945 0.3048)
			(end -0.67945 -0.305054)
			(stroke
				(width 0.1)
				(type default)
			)
			(layer "F.Fab")
		)
		(fp_line
			(start -0.12065 0.3048)
			(end -0.67945 0.3048)
			(stroke
				(width 0.1)
				(type default)
			)
			(layer "F.Fab")
		)
		(fp_line
			(start 0.120396 0.3048)
			(end 0.120396 0.2794)
			(stroke
				(width 0.1)
				(type default)
			)
			(layer "F.Fab")
		)
		(fp_line
			(start 0.67945 0.3048)
			(end 0.120396 0.3048)
			(stroke
				(width 0.1)
				(type default)
			)
			(layer "F.Fab")
		)
		(fp_line
			(start -0.12065 0.2794)
			(end -0.12065 0.3048)
			(stroke
				(width 0.1)
				(type default)
			)
			(layer "F.Fab")
		)
		(fp_line
			(start 0.120396 0.2794)
			(end -0.12065 0.2794)
			(stroke
				(width 0.1)
				(type default)
			)
			(layer "F.Fab")
		)
		(fp_line
			(start -0.12065 -0.2794)
			(end 0.12065 -0.2794)
			(stroke
				(width 0.1)
				(type default)
			)
			(layer "F.Fab")
		)
		(fp_line
			(start 0.12065 -0.2794)
			(end 0.12065 -0.3048)
			(stroke
				(width 0.1)
				(type default)
			)
			(layer "F.Fab")
		)
		(fp_line
			(start 0.12065 -0.3048)
			(end 0.67945 -0.3048)
			(stroke
				(width 0.1)
				(type default)
			)
			(layer "F.Fab")
		)
		(fp_line
			(start 0.67945 -0.3048)
			(end 0.67945 0.3048)
			(stroke
				(width 0.1)
				(type default)
			)
			(layer "F.Fab")
		)
		(fp_line
			(start -0.67945 -0.305054)
			(end -0.12065 -0.305054)
			(stroke
				(width 0.1)
				(type default)
			)
			(layer "F.Fab")
		)
		(fp_line
			(start -0.12065 -0.305054)
			(end -0.12065 -0.2794)
			(stroke
				(width 0.1)
				(type default)
			)
			(layer "F.Fab")
		)
		(pad "1" smd circle
			(at -0.40005 0 270)
			(size 0 0)
			(layers "F.Cu" "F.Mask" "F.Paste")
			(net "P3V3_NIC2")
		)
		(pad "2" smd circle
			(at 0.40005 0 270)
			(size 0 0)
			(layers "F.Cu" "F.Mask" "F.Paste")
			(net "GND")
		)
	)
	(footprint ""
		(layer "F.Cu")
		(at 454.125838 -317.697358 180)
		(property "Reference" "PC1010"
			(at 0 0 180)
			(layer "F.SilkS")
			(hide yes)
			(effects
				(font
					(size 1.27 1.27)
				)
			)
		)
		(property "Value" ""
			(at 0 0 180)
			(layer "F.Fab")
			(effects
				(font
					(size 1.27 1.27)
				)
			)
		)
		(duplicate_pad_numbers_are_jumpers no)
		(fp_line
			(start 1.524 0.762)
			(end -1.524 0.762)
			(stroke
				(width 0.1524)
				(type default)
			)
			(layer "F.SilkS")
		)
		(fp_line
			(start 1.524 -0.762)
			(end 1.524 0.762)
			(stroke
				(width 0.1524)
				(type default)
			)
			(layer "F.SilkS")
		)
		(fp_line
			(start -1.524 0.762)
			(end -1.524 -0.762)
			(stroke
				(width 0.1524)
				(type default)
			)
			(layer "F.SilkS")
		)
		(fp_line
			(start -1.524 -0.762)
			(end 1.524 -0.762)
			(stroke
				(width 0.1524)
				(type default)
			)
			(layer "F.SilkS")
		)
		(fp_line
			(start 1.1049 0.724916)
			(end 1.1049 -0.724916)
			(stroke
				(width 0.1)
				(type default)
			)
			(layer "F.Fab")
		)
		(fp_line
			(start 1.1049 -0.724916)
			(end -1.1049 -0.724916)
			(stroke
				(width 0.1)
				(type default)
			)
			(layer "F.Fab")
		)
		(fp_line
			(start -1.1049 0.724916)
			(end 1.1049 0.724916)
			(stroke
				(width 0.1)
				(type default)
			)
			(layer "F.Fab")
		)
		(fp_line
			(start -1.1049 -0.724916)
			(end -1.1049 0.724916)
			(stroke
				(width 0.1)
				(type default)
			)
			(layer "F.Fab")
		)
		(pad "1" smd rect
			(at -0.889 0)
			(size 1.016 1.27)
			(layers "F.Cu" "F.Mask" "F.Paste")
			(net "SW_P12V_P1V25_PEX3_FLT")
		)
		(pad "2" smd rect
			(at 0.889 0)
			(size 1.016 1.27)
			(layers "F.Cu" "F.Mask" "F.Paste")
			(net "GND")
		)
	)
	(footprint ""
		(layer "F.Cu")
		(at 134.04723 -55.63489 90)
		(property "Reference" "PC359"
			(at 0 0 90)
			(layer "F.SilkS")
			(hide yes)
			(effects
				(font
					(size 1.27 1.27)
				)
			)
		)
		(property "Value" ""
			(at 0 0 90)
			(layer "F.Fab")
			(effects
				(font
					(size 1.27 1.27)
				)
			)
		)
		(duplicate_pad_numbers_are_jumpers no)
		(fp_line
			(start 1.524 -0.762)
			(end 1.524 0.762)
			(stroke
				(width 0.1524)
				(type default)
			)
			(layer "F.SilkS")
		)
		(fp_line
			(start -1.524 -0.762)
			(end 1.524 -0.762)
			(stroke
				(width 0.1524)
				(type default)
			)
			(layer "F.SilkS")
		)
		(fp_line
			(start 1.524 0.762)
			(end -1.524 0.762)
			(stroke
				(width 0.1524)
				(type default)
			)
			(layer "F.SilkS")
		)
		(fp_line
			(start -1.524 0.762)
			(end -1.524 -0.762)
			(stroke
				(width 0.1524)
				(type default)
			)
			(layer "F.SilkS")
		)
		(fp_line
			(start 1.1049 -0.724916)
			(end -1.1049 -0.724916)
			(stroke
				(width 0.1)
				(type default)
			)
			(layer "F.Fab")
		)
		(fp_line
			(start -1.1049 -0.724916)
			(end -1.1049 0.724916)
			(stroke
				(width 0.1)
				(type default)
			)
			(layer "F.Fab")
		)
		(fp_line
			(start 1.1049 0.724916)
			(end 1.1049 -0.724916)
			(stroke
				(width 0.1)
				(type default)
			)
			(layer "F.Fab")
		)
		(fp_line
			(start -1.1049 0.724916)
			(end 1.1049 0.724916)
			(stroke
				(width 0.1)
				(type default)
			)
			(layer "F.Fab")
		)
		(pad "1" smd rect
			(at -0.889 0 270)
			(size 1.016 1.27)
			(layers "F.Cu" "F.Mask" "F.Paste")
			(net "P12V_SSD4_R")
		)
		(pad "2" smd rect
			(at 0.889 0 270)
			(size 1.016 1.27)
			(layers "F.Cu" "F.Mask" "F.Paste")
			(net "GND")
		)
	)
	(footprint ""
		(layer "F.Cu")
		(at 337.349084 -350.098614 90)
		(property "Reference" "C525"
			(at 0 0 90)
			(layer "F.SilkS")
			(hide yes)
			(effects
				(font
					(size 1.27 1.27)
				)
			)
		)
		(property "Value" ""
			(at 0 0 90)
			(layer "F.Fab")
			(effects
				(font
					(size 1.27 1.27)
				)
			)
		)
		(duplicate_pad_numbers_are_jumpers no)
		(fp_line
			(start 0.299974 -0.150114)
			(end 0.299974 0.150114)
			(stroke
				(width 0.1)
				(type default)
			)
			(layer "F.Fab")
		)
		(fp_line
			(start -0.299974 -0.150114)
			(end 0.299974 -0.150114)
			(stroke
				(width 0.1)
				(type default)
			)
			(layer "F.Fab")
		)
		(fp_line
			(start 0.299974 0.150114)
			(end -0.299974 0.150114)
			(stroke
				(width 0.1)
				(type default)
			)
			(layer "F.Fab")
		)
		(fp_line
			(start -0.299974 0.150114)
			(end -0.299974 -0.150114)
			(stroke
				(width 0.1)
				(type default)
			)
			(layer "F.Fab")
		)
		(pad "1" smd rect
			(at -0.2667 0 90)
			(size 0.3048 0.381)
			(layers "F.Cu" "F.Mask" "F.Paste")
			(net "P5E_PEX2_STN5_TX_DP<92>")
		)
		(pad "2" smd rect
			(at 0.2667 0 90)
			(size 0.3048 0.381)
			(layers "F.Cu" "F.Mask" "F.Paste")
			(net "P5E_PEX2_STN5_TX_C_DP<92>")
		)
	)
	(footprint ""
		(layer "F.Cu")
		(at 343.567004 -350.098614 90)
		(property "Reference" "C519"
			(at 0 0 90)
			(layer "F.SilkS")
			(hide yes)
			(effects
				(font
					(size 1.27 1.27)
				)
			)
		)
		(property "Value" ""
			(at 0 0 90)
			(layer "F.Fab")
			(effects
				(font
					(size 1.27 1.27)
				)
			)
		)
		(duplicate_pad_numbers_are_jumpers no)
		(fp_line
			(start 0.299974 -0.150114)
			(end 0.299974 0.150114)
			(stroke
				(width 0.1)
				(type default)
			)
			(layer "F.Fab")
		)
		(fp_line
			(start -0.299974 -0.150114)
			(end 0.299974 -0.150114)
			(stroke
				(width 0.1)
				(type default)
			)
			(layer "F.Fab")
		)
		(fp_line
			(start 0.299974 0.150114)
			(end -0.299974 0.150114)
			(stroke
				(width 0.1)
				(type default)
			)
			(layer "F.Fab")
		)
		(fp_line
			(start -0.299974 0.150114)
			(end -0.299974 -0.150114)
			(stroke
				(width 0.1)
				(type default)
			)
			(layer "F.Fab")
		)
		(pad "1" smd rect
			(at -0.2667 0 90)
			(size 0.3048 0.381)
			(layers "F.Cu" "F.Mask" "F.Paste")
			(net "P5E_PEX2_STN5_TX_DP<95>")
		)
		(pad "2" smd rect
			(at 0.2667 0 90)
			(size 0.3048 0.381)
			(layers "F.Cu" "F.Mask" "F.Paste")
			(net "P5E_PEX2_STN5_TX_C_DP<95>")
		)
	)
	(footprint ""
		(layer "F.Cu")
		(at 198.76135 -124.991114 180)
		(property "Reference" "C236"
			(at 0 0 180)
			(layer "F.SilkS")
			(hide yes)
			(effects
				(font
					(size 1.27 1.27)
				)
			)
		)
		(property "Value" ""
			(at 0 0 180)
			(layer "F.Fab")
			(effects
				(font
					(size 1.27 1.27)
				)
			)
		)
		(duplicate_pad_numbers_are_jumpers no)
		(fp_line
			(start 0.299974 0.150114)
			(end -0.299974 0.150114)
			(stroke
				(width 0.1)
				(type default)
			)
			(layer "F.Fab")
		)
		(fp_line
			(start 0.299974 -0.150114)
			(end 0.299974 0.150114)
			(stroke
				(width 0.1)
				(type default)
			)
			(layer "F.Fab")
		)
		(fp_line
			(start -0.299974 0.150114)
			(end -0.299974 -0.150114)
			(stroke
				(width 0.1)
				(type default)
			)
			(layer "F.Fab")
		)
		(fp_line
			(start -0.299974 -0.150114)
			(end 0.299974 -0.150114)
			(stroke
				(width 0.1)
				(type default)
			)
			(layer "F.Fab")
		)
		(pad "1" smd rect
			(at -0.2667 0 180)
			(size 0.3048 0.381)
			(layers "F.Cu" "F.Mask" "F.Paste")
			(net "P5E_PEX1_STN0_TX_DP<3>")
		)
		(pad "2" smd rect
			(at 0.2667 0 180)
			(size 0.3048 0.381)
			(layers "F.Cu" "F.Mask" "F.Paste")
			(net "P5E_PEX1_STN0_TX_C_DP<3>")
		)
	)
	(footprint ""
		(layer "F.Cu")
		(at 195.226178 -37.929566 90)
		(property "Reference" "R5561"
			(at 0 0 90)
			(layer "F.SilkS")
			(hide yes)
			(effects
				(font
					(size 1.27 1.27)
				)
			)
		)
		(property "Value" ""
			(at 0 0 90)
			(layer "F.Fab")
			(effects
				(font
					(size 1.27 1.27)
				)
			)
		)
		(duplicate_pad_numbers_are_jumpers no)
		(fp_line
			(start 0.7874 -0.4064)
			(end 0.7874 0.4064)
			(stroke
				(width 0.1524)
				(type default)
			)
			(layer "F.SilkS")
		)
		(fp_line
			(start -0.7874 -0.4064)
			(end 0.7874 -0.4064)
			(stroke
				(width 0.1524)
				(type default)
			)
			(layer "F.SilkS")
		)
		(fp_line
			(start 0.7874 0.4064)
			(end -0.7874 0.4064)
			(stroke
				(width 0.1524)
				(type default)
			)
			(layer "F.SilkS")
		)
		(fp_line
			(start -0.7874 0.4064)
			(end -0.7874 -0.4064)
			(stroke
				(width 0.1524)
				(type default)
			)
			(layer "F.SilkS")
		)
		(fp_line
			(start -0.12065 -0.305054)
			(end -0.12065 -0.2794)
			(stroke
				(width 0.1)
				(type default)
			)
			(layer "F.Fab")
		)
		(fp_line
			(start -0.67945 -0.305054)
			(end -0.12065 -0.305054)
			(stroke
				(width 0.1)
				(type default)
			)
			(layer "F.Fab")
		)
		(fp_line
			(start 0.67945 -0.3048)
			(end 0.67945 0.3048)
			(stroke
				(width 0.1)
				(type default)
			)
			(layer "F.Fab")
		)
		(fp_line
			(start 0.12065 -0.3048)
			(end 0.67945 -0.3048)
			(stroke
				(width 0.1)
				(type default)
			)
			(layer "F.Fab")
		)
		(fp_line
			(start 0.12065 -0.2794)
			(end 0.12065 -0.3048)
			(stroke
				(width 0.1)
				(type default)
			)
			(layer "F.Fab")
		)
		(fp_line
			(start -0.12065 -0.2794)
			(end 0.12065 -0.2794)
			(stroke
				(width 0.1)
				(type default)
			)
			(layer "F.Fab")
		)
		(fp_line
			(start 0.120396 0.2794)
			(end -0.12065 0.2794)
			(stroke
				(width 0.1)
				(type default)
			)
			(layer "F.Fab")
		)
		(fp_line
			(start -0.12065 0.2794)
			(end -0.12065 0.3048)
			(stroke
				(width 0.1)
				(type default)
			)
			(layer "F.Fab")
		)
		(fp_line
			(start 0.67945 0.3048)
			(end 0.120396 0.3048)
			(stroke
				(width 0.1)
				(type default)
			)
			(layer "F.Fab")
		)
		(fp_line
			(start 0.120396 0.3048)
			(end 0.120396 0.2794)
			(stroke
				(width 0.1)
				(type default)
			)
			(layer "F.Fab")
		)
		(fp_line
			(start -0.12065 0.3048)
			(end -0.67945 0.3048)
			(stroke
				(width 0.1)
				(type default)
			)
			(layer "F.Fab")
		)
		(fp_line
			(start -0.67945 0.3048)
			(end -0.67945 -0.305054)
			(stroke
				(width 0.1)
				(type default)
			)
			(layer "F.Fab")
		)
		(pad "1" smd circle
			(at -0.40005 0 90)
			(size 0 0)
			(layers "F.Cu" "F.Mask" "F.Paste")
			(net "SSD7_AUX_P3V3_EN_R")
		)
		(pad "2" smd circle
			(at 0.40005 0 90)
			(size 0 0)
			(layers "F.Cu" "F.Mask" "F.Paste")
			(net "SSD7_AUX_P3V3_EN")
		)
	)
	(footprint ""
		(layer "F.Cu")
		(at 93.987874 -45.704252 90)
		(property "Reference" "R538"
			(at 0 0 90)
			(layer "F.SilkS")
			(hide yes)
			(effects
				(font
					(size 1.27 1.27)
				)
			)
		)
		(property "Value" ""
			(at 0 0 90)
			(layer "F.Fab")
			(effects
				(font
					(size 1.27 1.27)
				)
			)
		)
		(duplicate_pad_numbers_are_jumpers no)
		(fp_line
			(start 3.937508 -1.8796)
			(end -3.937508 -1.8796)
			(stroke
				(width 0.1524)
				(type default)
			)
			(layer "F.SilkS")
		)
		(fp_line
			(start -3.937508 -1.8796)
			(end -3.937508 1.8796)
			(stroke
				(width 0.1524)
				(type default)
			)
			(layer "F.SilkS")
		)
		(fp_line
			(start 3.937508 1.8796)
			(end 3.937508 -1.8796)
			(stroke
				(width 0.1524)
				(type default)
			)
			(layer "F.SilkS")
		)
		(fp_line
			(start -3.937508 1.8796)
			(end 3.937508 1.8796)
			(stroke
				(width 0.1524)
				(type default)
			)
			(layer "F.SilkS")
		)
		(fp_line
			(start 3.275076 -1.674876)
			(end -3.275076 -1.674876)
			(stroke
				(width 0.1)
				(type default)
			)
			(layer "F.Fab")
		)
		(fp_line
			(start -3.275076 -1.674876)
			(end -3.275076 1.674876)
			(stroke
				(width 0.1)
				(type default)
			)
			(layer "F.Fab")
		)
		(fp_line
			(start 3.275076 1.674876)
			(end 3.275076 -1.674876)
			(stroke
				(width 0.1)
				(type default)
			)
			(layer "F.Fab")
		)
		(fp_line
			(start -3.275076 1.674876)
			(end 3.275076 1.674876)
			(stroke
				(width 0.1)
				(type default)
			)
			(layer "F.Fab")
		)
		(pad "1" smd rect
			(at -2.350008 0 90)
			(size 2.921 3.5052)
			(layers "F.Cu" "F.Mask" "F.Paste")
			(net "P12V_SSD3")
		)
		(pad "2" smd rect
			(at 2.350008 0 90)
			(size 2.921 3.5052)
			(layers "F.Cu" "F.Mask" "F.Paste")
			(net "P12V_SSD3_R")
		)
	)
	(footprint ""
		(layer "F.Cu")
		(at 307.020468 -70.307454 90)
		(property "Reference" "PC868"
			(at 0 0 90)
			(layer "F.SilkS")
			(hide yes)
			(effects
				(font
					(size 1.27 1.27)
				)
			)
		)
		(property "Value" ""
			(at 0 0 90)
			(layer "F.Fab")
			(effects
				(font
					(size 1.27 1.27)
				)
			)
		)
		(duplicate_pad_numbers_are_jumpers no)
		(fp_line
			(start 0.7874 -0.4064)
			(end 0.7874 0.4064)
			(stroke
				(width 0.1524)
				(type default)
			)
			(layer "F.SilkS")
		)
		(fp_line
			(start -0.7874 -0.4064)
			(end 0.7874 -0.4064)
			(stroke
				(width 0.1524)
				(type default)
			)
			(layer "F.SilkS")
		)
		(fp_line
			(start 0.7874 0.4064)
			(end -0.7874 0.4064)
			(stroke
				(width 0.1524)
				(type default)
			)
			(layer "F.SilkS")
		)
		(fp_line
			(start -0.7874 0.4064)
			(end -0.7874 -0.4064)
			(stroke
				(width 0.1524)
				(type default)
			)
			(layer "F.SilkS")
		)
		(fp_line
			(start -0.12065 -0.305054)
			(end -0.12065 -0.2794)
			(stroke
				(width 0.1)
				(type default)
			)
			(layer "F.Fab")
		)
		(fp_line
			(start -0.67945 -0.305054)
			(end -0.12065 -0.305054)
			(stroke
				(width 0.1)
				(type default)
			)
			(layer "F.Fab")
		)
		(fp_line
			(start 0.67945 -0.3048)
			(end 0.67945 0.3048)
			(stroke
				(width 0.1)
				(type default)
			)
			(layer "F.Fab")
		)
		(fp_line
			(start 0.12065 -0.3048)
			(end 0.67945 -0.3048)
			(stroke
				(width 0.1)
				(type default)
			)
			(layer "F.Fab")
		)
		(fp_line
			(start 0.12065 -0.2794)
			(end 0.12065 -0.3048)
			(stroke
				(width 0.1)
				(type default)
			)
			(layer "F.Fab")
		)
		(fp_line
			(start -0.12065 -0.2794)
			(end 0.12065 -0.2794)
			(stroke
				(width 0.1)
				(type default)
			)
			(layer "F.Fab")
		)
		(fp_line
			(start 0.120396 0.2794)
			(end -0.12065 0.2794)
			(stroke
				(width 0.1)
				(type default)
			)
			(layer "F.Fab")
		)
		(fp_line
			(start -0.12065 0.2794)
			(end -0.12065 0.3048)
			(stroke
				(width 0.1)
				(type default)
			)
			(layer "F.Fab")
		)
		(fp_line
			(start 0.67945 0.3048)
			(end 0.120396 0.3048)
			(stroke
				(width 0.1)
				(type default)
			)
			(layer "F.Fab")
		)
		(fp_line
			(start 0.120396 0.3048)
			(end 0.120396 0.2794)
			(stroke
				(width 0.1)
				(type default)
			)
			(layer "F.Fab")
		)
		(fp_line
			(start -0.12065 0.3048)
			(end -0.67945 0.3048)
			(stroke
				(width 0.1)
				(type default)
			)
			(layer "F.Fab")
		)
		(fp_line
			(start -0.67945 0.3048)
			(end -0.67945 -0.305054)
			(stroke
				(width 0.1)
				(type default)
			)
			(layer "F.Fab")
		)
		(pad "1" smd circle
			(at -0.40005 0 90)
			(size 0 0)
			(layers "F.Cu" "F.Mask" "F.Paste")
			(net "P12V_AUX")
		)
		(pad "2" smd circle
			(at 0.40005 0 90)
			(size 0 0)
			(layers "F.Cu" "F.Mask" "F.Paste")
			(net "GND")
		)
	)
	(footprint ""
		(layer "F.Cu")
		(at 200.601834 -141.150848 -90)
		(property "Reference" "U24"
			(at 2.772918 -0.261366 0)
			(unlocked yes)
			(layer "F.SilkS")
			(effects
				(font
					(size 0.7874 0.5842)
					(thickness 0.1524)
				)
			)
		)
		(property "Value" ""
			(at 0 0 270)
			(layer "F.Fab")
			(effects
				(font
					(size 1.27 1.27)
				)
			)
		)
		(duplicate_pad_numbers_are_jumpers no)
		(fp_line
			(start -1.949958 1.610106)
			(end -1.949958 -1.610106)
			(stroke
				(width 0.1524)
				(type default)
			)
			(layer "F.SilkS")
		)
		(fp_line
			(start 1.949958 1.610106)
			(end -1.949958 1.610106)
			(stroke
				(width 0.1524)
				(type default)
			)
			(layer "F.SilkS")
		)
		(fp_line
			(start 1.949958 -1.560068)
			(end 1.949958 1.610106)
			(stroke
				(width 0.1524)
				(type default)
			)
			(layer "F.SilkS")
		)
		(fp_line
			(start -1.949958 -1.610106)
			(end 1.949958 -1.610106)
			(stroke
				(width 0.1524)
				(type default)
			)
			(layer "F.SilkS")
		)
		(fp_line
			(start -0.750062 1.560068)
			(end -0.750062 -1.560068)
			(stroke
				(width 0.1)
				(type default)
			)
			(layer "F.Fab")
		)
		(fp_line
			(start 0.750062 1.560068)
			(end -0.750062 1.560068)
			(stroke
				(width 0.1)
				(type default)
			)
			(layer "F.Fab")
		)
		(fp_line
			(start -0.750062 -1.560068)
			(end 0.750062 -1.560068)
			(stroke
				(width 0.1)
				(type default)
			)
			(layer "F.Fab")
		)
		(fp_line
			(start 0.750062 -1.560068)
			(end 0.750062 1.560068)
			(stroke
				(width 0.1)
				(type default)
			)
			(layer "F.Fab")
		)
		(pad "D" smd rect
			(at 1.100074 0 180)
			(size 1.016 1.4224)
			(layers "F.Cu" "F.Mask" "F.Paste")
			(net "HP_NIC3_EN")
		)
		(pad "G" smd rect
			(at -1.100074 -0.94996 180)
			(size 1.016 1.4224)
			(layers "F.Cu" "F.Mask" "F.Paste")
			(net "PRSNT_NIC3_R_N")
		)
		(pad "S" smd rect
			(at -1.100074 0.94996 180)
			(size 1.016 1.4224)
			(layers "F.Cu" "F.Mask" "F.Paste")
			(net "GND")
		)
	)
	(footprint ""
		(layer "F.Cu")
		(at 378.382022 -299.391832 180)
		(property "Reference" "C3553"
			(at 0 0 180)
			(layer "F.SilkS")
			(hide yes)
			(effects
				(font
					(size 1.27 1.27)
				)
			)
		)
		(property "Value" ""
			(at 0 0 180)
			(layer "F.Fab")
			(effects
				(font
					(size 1.27 1.27)
				)
			)
		)
		(duplicate_pad_numbers_are_jumpers no)
		(fp_line
			(start 1.2954 0.5842)
			(end -1.2954 0.5842)
			(stroke
				(width 0.1524)
				(type default)
			)
			(layer "F.SilkS")
		)
		(fp_line
			(start 1.2954 -0.5842)
			(end 1.2954 0.5842)
			(stroke
				(width 0.1524)
				(type default)
			)
			(layer "F.SilkS")
		)
		(fp_line
			(start -1.2954 0.5842)
			(end -1.2954 -0.5842)
			(stroke
				(width 0.1524)
				(type default)
			)
			(layer "F.SilkS")
		)
		(fp_line
			(start -1.2954 -0.5842)
			(end 1.2954 -0.5842)
			(stroke
				(width 0.1524)
				(type default)
			)
			(layer "F.SilkS")
		)
		(fp_line
			(start 1.1938 0.4064)
			(end 0.8636 0.4064)
			(stroke
				(width 0.1)
				(type default)
			)
			(layer "F.Fab")
		)
		(fp_line
			(start 1.1938 -0.4064)
			(end 1.1938 0.4064)
			(stroke
				(width 0.1)
				(type default)
			)
			(layer "F.Fab")
		)
		(fp_line
			(start 0.8636 0.4572)
			(end -0.8636 0.4572)
			(stroke
				(width 0.1)
				(type default)
			)
			(layer "F.Fab")
		)
		(fp_line
			(start 0.8636 0.4064)
			(end 0.8636 0.4572)
			(stroke
				(width 0.1)
				(type default)
			)
			(layer "F.Fab")
		)
		(fp_line
			(start 0.8636 -0.4064)
			(end 1.1938 -0.4064)
			(stroke
				(width 0.1)
				(type default)
			)
			(layer "F.Fab")
		)
		(fp_line
			(start 0.8636 -0.4572)
			(end 0.8636 -0.4064)
			(stroke
				(width 0.1)
				(type default)
			)
			(layer "F.Fab")
		)
		(fp_line
			(start -0.8636 0.4572)
			(end -0.8636 0.4064)
			(stroke
				(width 0.1)
				(type default)
			)
			(layer "F.Fab")
		)
		(fp_line
			(start -0.8636 0.4064)
			(end -1.1938 0.4064)
			(stroke
				(width 0.1)
				(type default)
			)
			(layer "F.Fab")
		)
		(fp_line
			(start -0.8636 -0.4064)
			(end -0.8636 -0.4572)
			(stroke
				(width 0.1)
				(type default)
			)
			(layer "F.Fab")
		)
		(fp_line
			(start -0.8636 -0.4572)
			(end 0.8636 -0.4572)
			(stroke
				(width 0.1)
				(type default)
			)
			(layer "F.Fab")
		)
		(fp_line
			(start -1.1938 0.4064)
			(end -1.1938 -0.4064)
			(stroke
				(width 0.1)
				(type default)
			)
			(layer "F.Fab")
		)
		(fp_line
			(start -1.1938 -0.4064)
			(end -0.8636 -0.4064)
			(stroke
				(width 0.1)
				(type default)
			)
			(layer "F.Fab")
		)
		(pad "1" smd rect
			(at -0.7366 0 90)
			(size 0.7112 0.8128)
			(layers "F.Cu" "F.Mask" "F.Paste")
			(net "PCEPLL1_VDDA18_PEX3_R")
		)
		(pad "2" smd rect
			(at 0.7366 0 90)
			(size 0.7112 0.8128)
			(layers "F.Cu" "F.Mask" "F.Paste")
			(net "GND")
		)
	)
	(footprint ""
		(layer "F.Cu")
		(at 105.287826 -319.420494 90)
		(property "Reference" "R5783"
			(at 0 0 90)
			(layer "F.SilkS")
			(hide yes)
			(effects
				(font
					(size 1.27 1.27)
				)
			)
		)
		(property "Value" ""
			(at 0 0 90)
			(layer "F.Fab")
			(effects
				(font
					(size 1.27 1.27)
				)
			)
		)
		(duplicate_pad_numbers_are_jumpers no)
		(fp_line
			(start 2.576322 -1.1303)
			(end 2.576322 1.1303)
			(stroke
				(width 0.1524)
				(type default)
			)
			(layer "F.SilkS")
		)
		(fp_line
			(start -2.576322 -1.1303)
			(end 2.576322 -1.1303)
			(stroke
				(width 0.1524)
				(type default)
			)
			(layer "F.SilkS")
		)
		(fp_line
			(start 2.576322 1.1303)
			(end -2.576322 1.1303)
			(stroke
				(width 0.1524)
				(type default)
			)
			(layer "F.SilkS")
		)
		(fp_line
			(start -2.576322 1.1303)
			(end -2.576322 -1.1303)
			(stroke
				(width 0.1524)
				(type default)
			)
			(layer "F.SilkS")
		)
		(fp_line
			(start 1.649984 -0.899922)
			(end -1.649984 -0.899922)
			(stroke
				(width 0.1)
				(type default)
			)
			(layer "F.Fab")
		)
		(fp_line
			(start -1.649984 -0.899922)
			(end -1.649984 0.899922)
			(stroke
				(width 0.1)
				(type default)
			)
			(layer "F.Fab")
		)
		(fp_line
			(start 1.649984 0.899922)
			(end 1.649984 -0.899922)
			(stroke
				(width 0.1)
				(type default)
			)
			(layer "F.Fab")
		)
		(fp_line
			(start -1.649984 0.899922)
			(end 1.649984 0.899922)
			(stroke
				(width 0.1)
				(type default)
			)
			(layer "F.Fab")
		)
		(pad "1A" smd rect
			(at -1.700022 0 90)
			(size 1.4986 2.0066)
			(layers "F.Cu" "F.Mask" "F.Paste")
			(net "P0V8_PEX0")
		)
		(pad "1B" smd rect
			(at -1.077722 0 90)
			(size 0.254 0.508)
			(layers "F.Cu" "F.Mask" "F.Paste")
			(net "P0V8_PEX0")
		)
		(pad "2A" smd rect
			(at 1.700022 0 90)
			(size 1.4986 2.0066)
			(layers "F.Cu" "F.Mask" "F.Paste")
			(net "P0V8_SERDES_VDDA_PEX0")
		)
		(pad "2B" smd rect
			(at 1.077722 0 90)
			(size 0.254 0.508)
			(layers "F.Cu" "F.Mask" "F.Paste")
			(net "P0V8_SERDES_VDDA_PEX0")
		)
	)
	(footprint ""
		(layer "F.Cu")
		(at 106.385106 -380.898908 -90)
		(property "Reference" "R5447"
			(at 0 0 270)
			(layer "F.SilkS")
			(hide yes)
			(effects
				(font
					(size 1.27 1.27)
				)
			)
		)
		(property "Value" ""
			(at 0 0 270)
			(layer "F.Fab")
			(effects
				(font
					(size 1.27 1.27)
				)
			)
		)
		(duplicate_pad_numbers_are_jumpers no)
		(fp_line
			(start 0.02794 0.4064)
			(end -0.7874 0.4064)
			(stroke
				(width 0.1524)
				(type default)
			)
			(layer "F.SilkS")
		)
		(fp_line
			(start -0.7874 -0.4064)
			(end 0.7874 -0.4064)
			(stroke
				(width 0.1524)
				(type default)
			)
			(layer "F.SilkS")
		)
		(fp_line
			(start 0.7874 -0.4064)
			(end 0.7874 0.4064)
			(stroke
				(width 0.1524)
				(type default)
			)
			(layer "F.SilkS")
		)
		(fp_line
			(start -0.67945 0.3048)
			(end -0.67945 -0.305054)
			(stroke
				(width 0.1)
				(type default)
			)
			(layer "F.Fab")
		)
		(fp_line
			(start -0.12065 0.3048)
			(end -0.67945 0.3048)
			(stroke
				(width 0.1)
				(type default)
			)
			(layer "F.Fab")
		)
		(fp_line
			(start 0.120396 0.3048)
			(end 0.120396 0.2794)
			(stroke
				(width 0.1)
				(type default)
			)
			(layer "F.Fab")
		)
		(fp_line
			(start 0.67945 0.3048)
			(end 0.120396 0.3048)
			(stroke
				(width 0.1)
				(type default)
			)
			(layer "F.Fab")
		)
		(fp_line
			(start -0.12065 0.2794)
			(end -0.12065 0.3048)
			(stroke
				(width 0.1)
				(type default)
			)
			(layer "F.Fab")
		)
		(fp_line
			(start 0.120396 0.2794)
			(end -0.12065 0.2794)
			(stroke
				(width 0.1)
				(type default)
			)
			(layer "F.Fab")
		)
		(fp_line
			(start -0.12065 -0.2794)
			(end 0.12065 -0.2794)
			(stroke
				(width 0.1)
				(type default)
			)
			(layer "F.Fab")
		)
		(fp_line
			(start 0.12065 -0.2794)
			(end 0.12065 -0.3048)
			(stroke
				(width 0.1)
				(type default)
			)
			(layer "F.Fab")
		)
		(fp_line
			(start 0.12065 -0.3048)
			(end 0.67945 -0.3048)
			(stroke
				(width 0.1)
				(type default)
			)
			(layer "F.Fab")
		)
		(fp_line
			(start 0.67945 -0.3048)
			(end 0.67945 0.3048)
			(stroke
				(width 0.1)
				(type default)
			)
			(layer "F.Fab")
		)
		(fp_line
			(start -0.67945 -0.305054)
			(end -0.12065 -0.305054)
			(stroke
				(width 0.1)
				(type default)
			)
			(layer "F.Fab")
		)
		(fp_line
			(start -0.12065 -0.305054)
			(end -0.12065 -0.2794)
			(stroke
				(width 0.1)
				(type default)
			)
			(layer "F.Fab")
		)
		(pad "1" smd rect
			(at -0.40005 0 90)
			(size 0.4572 0.508)
			(layers "F.Cu" "F.Mask" "F.Paste")
			(net "USB2_BIC_R_DP")
		)
		(pad "2" smd rect
			(at 0.40005 0 90)
			(size 0.4572 0.508)
			(layers "F.Cu" "F.Mask" "F.Paste")
			(net "USB2_BIC_DP")
		)
	)
	(footprint ""
		(layer "F.Cu")
		(at 215.075516 -120.239028)
		(property "Reference" "PR253"
			(at 0 0 0)
			(layer "F.SilkS")
			(hide yes)
			(effects
				(font
					(size 1.27 1.27)
				)
			)
		)
		(property "Value" ""
			(at 0 0 0)
			(layer "F.Fab")
			(effects
				(font
					(size 1.27 1.27)
				)
			)
		)
		(duplicate_pad_numbers_are_jumpers no)
		(fp_line
			(start -0.7874 -0.4064)
			(end 0.7874 -0.4064)
			(stroke
				(width 0.1524)
				(type default)
			)
			(layer "F.SilkS")
		)
		(fp_line
			(start -0.7874 0.4064)
			(end -0.7874 -0.4064)
			(stroke
				(width 0.1524)
				(type default)
			)
			(layer "F.SilkS")
		)
		(fp_line
			(start 0.7874 -0.4064)
			(end 0.7874 0.4064)
			(stroke
				(width 0.1524)
				(type default)
			)
			(layer "F.SilkS")
		)
		(fp_line
			(start 0.7874 0.4064)
			(end -0.7874 0.4064)
			(stroke
				(width 0.1524)
				(type default)
			)
			(layer "F.SilkS")
		)
		(fp_line
			(start -0.67945 -0.305054)
			(end -0.12065 -0.305054)
			(stroke
				(width 0.1)
				(type default)
			)
			(layer "F.Fab")
		)
		(fp_line
			(start -0.67945 0.3048)
			(end -0.67945 -0.305054)
			(stroke
				(width 0.1)
				(type default)
			)
			(layer "F.Fab")
		)
		(fp_line
			(start -0.12065 -0.305054)
			(end -0.12065 -0.2794)
			(stroke
				(width 0.1)
				(type default)
			)
			(layer "F.Fab")
		)
		(fp_line
			(start -0.12065 -0.2794)
			(end 0.12065 -0.2794)
			(stroke
				(width 0.1)
				(type default)
			)
			(layer "F.Fab")
		)
		(fp_line
			(start -0.12065 0.2794)
			(end -0.12065 0.3048)
			(stroke
				(width 0.1)
				(type default)
			)
			(layer "F.Fab")
		)
		(fp_line
			(start -0.12065 0.3048)
			(end -0.67945 0.3048)
			(stroke
				(width 0.1)
				(type default)
			)
			(layer "F.Fab")
		)
		(fp_line
			(start 0.120396 0.2794)
			(end -0.12065 0.2794)
			(stroke
				(width 0.1)
				(type default)
			)
			(layer "F.Fab")
		)
		(fp_line
			(start 0.120396 0.3048)
			(end 0.120396 0.2794)
			(stroke
				(width 0.1)
				(type default)
			)
			(layer "F.Fab")
		)
		(fp_line
			(start 0.12065 -0.3048)
			(end 0.67945 -0.3048)
			(stroke
				(width 0.1)
				(type default)
			)
			(layer "F.Fab")
		)
		(fp_line
			(start 0.12065 -0.2794)
			(end 0.12065 -0.3048)
			(stroke
				(width 0.1)
				(type default)
			)
			(layer "F.Fab")
		)
		(fp_line
			(start 0.67945 -0.3048)
			(end 0.67945 0.3048)
			(stroke
				(width 0.1)
				(type default)
			)
			(layer "F.Fab")
		)
		(fp_line
			(start 0.67945 0.3048)
			(end 0.120396 0.3048)
			(stroke
				(width 0.1)
				(type default)
			)
			(layer "F.Fab")
		)
		(pad "1" smd circle
			(at -0.40005 0)
			(size 0 0)
			(layers "F.Cu" "F.Mask" "F.Paste")
			(net "P3V3_NIC3_OCP")
		)
		(pad "2" smd circle
			(at 0.40005 0)
			(size 0 0)
			(layers "F.Cu" "F.Mask" "F.Paste")
			(net "GND")
		)
	)
	(footprint ""
		(layer "F.Cu")
		(at 440.359292 -356.244906 90)
		(property "Reference" "C794"
			(at 0 0 90)
			(layer "F.SilkS")
			(hide yes)
			(effects
				(font
					(size 1.27 1.27)
				)
			)
		)
		(property "Value" ""
			(at 0 0 90)
			(layer "F.Fab")
			(effects
				(font
					(size 1.27 1.27)
				)
			)
		)
		(duplicate_pad_numbers_are_jumpers no)
		(fp_line
			(start 0.299974 -0.150114)
			(end 0.299974 0.150114)
			(stroke
				(width 0.1)
				(type default)
			)
			(layer "F.Fab")
		)
		(fp_line
			(start -0.299974 -0.150114)
			(end 0.299974 -0.150114)
			(stroke
				(width 0.1)
				(type default)
			)
			(layer "F.Fab")
		)
		(fp_line
			(start 0.299974 0.150114)
			(end -0.299974 0.150114)
			(stroke
				(width 0.1)
				(type default)
			)
			(layer "F.Fab")
		)
		(fp_line
			(start -0.299974 0.150114)
			(end -0.299974 -0.150114)
			(stroke
				(width 0.1)
				(type default)
			)
			(layer "F.Fab")
		)
		(pad "1" smd rect
			(at -0.2667 0 90)
			(size 0.3048 0.381)
			(layers "F.Cu" "F.Mask" "F.Paste")
			(net "P5E_PEX3_STN7_TX_DP<127>")
		)
		(pad "2" smd rect
			(at 0.2667 0 90)
			(size 0.3048 0.381)
			(layers "F.Cu" "F.Mask" "F.Paste")
			(net "P5E_PEX3_STN7_TX_C_DP<127>")
		)
	)
	(footprint ""
		(layer "F.Cu")
		(at 491.839758 -549.60774 180)
		(property "Reference" "SCREW_2"
			(at -3.2385 -1.402334 0)
			(unlocked yes)
			(layer "B.SilkS")
			(effects
				(font
					(size 0.7874 0.5842)
					(thickness 0.1524)
				)
				(justify mirror)
			)
		)
		(property "Value" ""
			(at 0 0 180)
			(layer "F.Fab")
			(effects
				(font
					(size 1.27 1.27)
				)
			)
		)
		(duplicate_pad_numbers_are_jumpers no)
		(pad "1" thru_hole circle
			(at 0 0 180)
			(size 0.4572 0.4572)
			(drill 0.2032)
			(layers "*.Cu" "*.Mask")
			(remove_unused_layers no)
			(net "Net_9162")
			(clearance 0.127)
			(thermal_gap 0.127)
			(padstack
				(mode front_inner_back)
				(layer "Inner"
					(shape circle)
					(size 0.4572 0.4572)
					(clearance 0.127)
				)
				(layer "B.Cu"
					(shape circle)
					(size 0.508 0.508)
					(clearance 0.1016)
				)
			)
		)
	)
	(footprint ""
		(layer "F.Cu")
		(at 326.012556 -195.218304 180)
		(property "Reference" "R4234"
			(at 0 0 180)
			(layer "F.SilkS")
			(hide yes)
			(effects
				(font
					(size 1.27 1.27)
				)
			)
		)
		(property "Value" ""
			(at 0 0 180)
			(layer "F.Fab")
			(effects
				(font
					(size 1.27 1.27)
				)
			)
		)
		(duplicate_pad_numbers_are_jumpers no)
		(fp_line
			(start 0.7874 0.4064)
			(end -0.7874 0.4064)
			(stroke
				(width 0.1524)
				(type default)
			)
			(layer "F.SilkS")
		)
		(fp_line
			(start 0.7874 -0.4064)
			(end 0.7874 0.4064)
			(stroke
				(width 0.1524)
				(type default)
			)
			(layer "F.SilkS")
		)
		(fp_line
			(start -0.7874 0.4064)
			(end -0.7874 -0.4064)
			(stroke
				(width 0.1524)
				(type default)
			)
			(layer "F.SilkS")
		)
		(fp_line
			(start -0.7874 -0.4064)
			(end 0.7874 -0.4064)
			(stroke
				(width 0.1524)
				(type default)
			)
			(layer "F.SilkS")
		)
		(fp_line
			(start 0.67945 0.3048)
			(end 0.120396 0.3048)
			(stroke
				(width 0.1)
				(type default)
			)
			(layer "F.Fab")
		)
		(fp_line
			(start 0.67945 -0.3048)
			(end 0.67945 0.3048)
			(stroke
				(width 0.1)
				(type default)
			)
			(layer "F.Fab")
		)
		(fp_line
			(start 0.12065 -0.2794)
			(end 0.12065 -0.3048)
			(stroke
				(width 0.1)
				(type default)
			)
			(layer "F.Fab")
		)
		(fp_line
			(start 0.12065 -0.3048)
			(end 0.67945 -0.3048)
			(stroke
				(width 0.1)
				(type default)
			)
			(layer "F.Fab")
		)
		(fp_line
			(start 0.120396 0.3048)
			(end 0.120396 0.2794)
			(stroke
				(width 0.1)
				(type default)
			)
			(layer "F.Fab")
		)
		(fp_line
			(start 0.120396 0.2794)
			(end -0.12065 0.2794)
			(stroke
				(width 0.1)
				(type default)
			)
			(layer "F.Fab")
		)
		(fp_line
			(start -0.12065 0.3048)
			(end -0.67945 0.3048)
			(stroke
				(width 0.1)
				(type default)
			)
			(layer "F.Fab")
		)
		(fp_line
			(start -0.12065 0.2794)
			(end -0.12065 0.3048)
			(stroke
				(width 0.1)
				(type default)
			)
			(layer "F.Fab")
		)
		(fp_line
			(start -0.12065 -0.2794)
			(end 0.12065 -0.2794)
			(stroke
				(width 0.1)
				(type default)
			)
			(layer "F.Fab")
		)
		(fp_line
			(start -0.12065 -0.305054)
			(end -0.12065 -0.2794)
			(stroke
				(width 0.1)
				(type default)
			)
			(layer "F.Fab")
		)
		(fp_line
			(start -0.67945 0.3048)
			(end -0.67945 -0.305054)
			(stroke
				(width 0.1)
				(type default)
			)
			(layer "F.Fab")
		)
		(fp_line
			(start -0.67945 -0.305054)
			(end -0.12065 -0.305054)
			(stroke
				(width 0.1)
				(type default)
			)
			(layer "F.Fab")
		)
		(pad "1" smd circle
			(at -0.40005 0 180)
			(size 0 0)
			(layers "F.Cu" "F.Mask" "F.Paste")
			(net "IOEXP_DBV2_A2")
		)
		(pad "2" smd circle
			(at 0.40005 0 180)
			(size 0 0)
			(layers "F.Cu" "F.Mask" "F.Paste")
			(net "P3V3_AUX")
		)
	)
	(footprint ""
		(layer "F.Cu")
		(at 175.510952 -343.952322 90)
		(property "Reference" "C391"
			(at 0 0 90)
			(layer "F.SilkS")
			(hide yes)
			(effects
				(font
					(size 1.27 1.27)
				)
			)
		)
		(property "Value" ""
			(at 0 0 90)
			(layer "F.Fab")
			(effects
				(font
					(size 1.27 1.27)
				)
			)
		)
		(duplicate_pad_numbers_are_jumpers no)
		(fp_line
			(start 0.299974 -0.150114)
			(end 0.299974 0.150114)
			(stroke
				(width 0.1)
				(type default)
			)
			(layer "F.Fab")
		)
		(fp_line
			(start -0.299974 -0.150114)
			(end 0.299974 -0.150114)
			(stroke
				(width 0.1)
				(type default)
			)
			(layer "F.Fab")
		)
		(fp_line
			(start 0.299974 0.150114)
			(end -0.299974 0.150114)
			(stroke
				(width 0.1)
				(type default)
			)
			(layer "F.Fab")
		)
		(fp_line
			(start -0.299974 0.150114)
			(end -0.299974 -0.150114)
			(stroke
				(width 0.1)
				(type default)
			)
			(layer "F.Fab")
		)
		(pad "1" smd rect
			(at -0.2667 0 90)
			(size 0.3048 0.381)
			(layers "F.Cu" "F.Mask" "F.Paste")
			(net "P5E_PEX1_STN7_TX_DN<118>")
		)
		(pad "2" smd rect
			(at 0.2667 0 90)
			(size 0.3048 0.381)
			(layers "F.Cu" "F.Mask" "F.Paste")
			(net "P5E_PEX1_STN7_TX_C_DN<118>")
		)
	)
	(footprint ""
		(layer "F.Cu")
		(at 226.550982 -155.998672 90)
		(property "Reference" "R4196"
			(at 0 0 90)
			(layer "F.SilkS")
			(hide yes)
			(effects
				(font
					(size 1.27 1.27)
				)
			)
		)
		(property "Value" ""
			(at 0 0 90)
			(layer "F.Fab")
			(effects
				(font
					(size 1.27 1.27)
				)
			)
		)
		(duplicate_pad_numbers_are_jumpers no)
		(fp_line
			(start 0.7874 -0.4064)
			(end 0.7874 0.4064)
			(stroke
				(width 0.1524)
				(type default)
			)
			(layer "F.SilkS")
		)
		(fp_line
			(start -0.7874 -0.4064)
			(end 0.7874 -0.4064)
			(stroke
				(width 0.1524)
				(type default)
			)
			(layer "F.SilkS")
		)
		(fp_line
			(start 0.7874 0.4064)
			(end -0.7874 0.4064)
			(stroke
				(width 0.1524)
				(type default)
			)
			(layer "F.SilkS")
		)
		(fp_line
			(start -0.7874 0.4064)
			(end -0.7874 -0.4064)
			(stroke
				(width 0.1524)
				(type default)
			)
			(layer "F.SilkS")
		)
		(fp_line
			(start -0.12065 -0.305054)
			(end -0.12065 -0.2794)
			(stroke
				(width 0.1)
				(type default)
			)
			(layer "F.Fab")
		)
		(fp_line
			(start -0.67945 -0.305054)
			(end -0.12065 -0.305054)
			(stroke
				(width 0.1)
				(type default)
			)
			(layer "F.Fab")
		)
		(fp_line
			(start 0.67945 -0.3048)
			(end 0.67945 0.3048)
			(stroke
				(width 0.1)
				(type default)
			)
			(layer "F.Fab")
		)
		(fp_line
			(start 0.12065 -0.3048)
			(end 0.67945 -0.3048)
			(stroke
				(width 0.1)
				(type default)
			)
			(layer "F.Fab")
		)
		(fp_line
			(start 0.12065 -0.2794)
			(end 0.12065 -0.3048)
			(stroke
				(width 0.1)
				(type default)
			)
			(layer "F.Fab")
		)
		(fp_line
			(start -0.12065 -0.2794)
			(end 0.12065 -0.2794)
			(stroke
				(width 0.1)
				(type default)
			)
			(layer "F.Fab")
		)
		(fp_line
			(start 0.120396 0.2794)
			(end -0.12065 0.2794)
			(stroke
				(width 0.1)
				(type default)
			)
			(layer "F.Fab")
		)
		(fp_line
			(start -0.12065 0.2794)
			(end -0.12065 0.3048)
			(stroke
				(width 0.1)
				(type default)
			)
			(layer "F.Fab")
		)
		(fp_line
			(start 0.67945 0.3048)
			(end 0.120396 0.3048)
			(stroke
				(width 0.1)
				(type default)
			)
			(layer "F.Fab")
		)
		(fp_line
			(start 0.120396 0.3048)
			(end 0.120396 0.2794)
			(stroke
				(width 0.1)
				(type default)
			)
			(layer "F.Fab")
		)
		(fp_line
			(start -0.12065 0.3048)
			(end -0.67945 0.3048)
			(stroke
				(width 0.1)
				(type default)
			)
			(layer "F.Fab")
		)
		(fp_line
			(start -0.67945 0.3048)
			(end -0.67945 -0.305054)
			(stroke
				(width 0.1)
				(type default)
			)
			(layer "F.Fab")
		)
		(pad "1" smd circle
			(at -0.40005 0 90)
			(size 0 0)
			(layers "F.Cu" "F.Mask" "F.Paste")
			(net "PEX_REF_CLK_GEN_EN_N")
		)
		(pad "2" smd circle
			(at 0.40005 0 90)
			(size 0 0)
			(layers "F.Cu" "F.Mask" "F.Paste")
			(net "P3V3")
		)
	)
	(footprint ""
		(layer "F.Cu")
		(at 293.657782 -343.952322 90)
		(property "Reference" "C2364"
			(at 0 0 90)
			(layer "F.SilkS")
			(hide yes)
			(effects
				(font
					(size 1.27 1.27)
				)
			)
		)
		(property "Value" ""
			(at 0 0 90)
			(layer "F.Fab")
			(effects
				(font
					(size 1.27 1.27)
				)
			)
		)
		(duplicate_pad_numbers_are_jumpers no)
		(fp_line
			(start 0.299974 -0.150114)
			(end 0.299974 0.150114)
			(stroke
				(width 0.1)
				(type default)
			)
			(layer "F.Fab")
		)
		(fp_line
			(start -0.299974 -0.150114)
			(end 0.299974 -0.150114)
			(stroke
				(width 0.1)
				(type default)
			)
			(layer "F.Fab")
		)
		(fp_line
			(start 0.299974 0.150114)
			(end -0.299974 0.150114)
			(stroke
				(width 0.1)
				(type default)
			)
			(layer "F.Fab")
		)
		(fp_line
			(start -0.299974 0.150114)
			(end -0.299974 -0.150114)
			(stroke
				(width 0.1)
				(type default)
			)
			(layer "F.Fab")
		)
		(pad "1" smd rect
			(at -0.2667 0 90)
			(size 0.3048 0.381)
			(layers "F.Cu" "F.Mask" "F.Paste")
			(net "P5E_PEX2_STN4_TX_DN<68>")
		)
		(pad "2" smd rect
			(at 0.2667 0 90)
			(size 0.3048 0.381)
			(layers "F.Cu" "F.Mask" "F.Paste")
			(net "P5E_PEX2_STN4_TX_C_DN<68>")
		)
	)
	(footprint ""
		(layer "F.Cu")
		(at 338.796884 -115.646454 180)
		(property "Reference" "PR7036"
			(at 0 0 180)
			(layer "F.SilkS")
			(hide yes)
			(effects
				(font
					(size 1.27 1.27)
				)
			)
		)
		(property "Value" ""
			(at 0 0 180)
			(layer "F.Fab")
			(effects
				(font
					(size 1.27 1.27)
				)
			)
		)
		(duplicate_pad_numbers_are_jumpers no)
		(fp_line
			(start 0.7874 0.4064)
			(end -0.7874 0.4064)
			(stroke
				(width 0.1524)
				(type default)
			)
			(layer "F.SilkS")
		)
		(fp_line
			(start 0.7874 -0.4064)
			(end 0.7874 0.4064)
			(stroke
				(width 0.1524)
				(type default)
			)
			(layer "F.SilkS")
		)
		(fp_line
			(start -0.7874 0.4064)
			(end -0.7874 -0.4064)
			(stroke
				(width 0.1524)
				(type default)
			)
			(layer "F.SilkS")
		)
		(fp_line
			(start -0.7874 -0.4064)
			(end 0.7874 -0.4064)
			(stroke
				(width 0.1524)
				(type default)
			)
			(layer "F.SilkS")
		)
		(fp_line
			(start 0.67945 0.3048)
			(end 0.120396 0.3048)
			(stroke
				(width 0.1)
				(type default)
			)
			(layer "F.Fab")
		)
		(fp_line
			(start 0.67945 -0.3048)
			(end 0.67945 0.3048)
			(stroke
				(width 0.1)
				(type default)
			)
			(layer "F.Fab")
		)
		(fp_line
			(start 0.12065 -0.2794)
			(end 0.12065 -0.3048)
			(stroke
				(width 0.1)
				(type default)
			)
			(layer "F.Fab")
		)
		(fp_line
			(start 0.12065 -0.3048)
			(end 0.67945 -0.3048)
			(stroke
				(width 0.1)
				(type default)
			)
			(layer "F.Fab")
		)
		(fp_line
			(start 0.120396 0.3048)
			(end 0.120396 0.2794)
			(stroke
				(width 0.1)
				(type default)
			)
			(layer "F.Fab")
		)
		(fp_line
			(start 0.120396 0.2794)
			(end -0.12065 0.2794)
			(stroke
				(width 0.1)
				(type default)
			)
			(layer "F.Fab")
		)
		(fp_line
			(start -0.12065 0.3048)
			(end -0.67945 0.3048)
			(stroke
				(width 0.1)
				(type default)
			)
			(layer "F.Fab")
		)
		(fp_line
			(start -0.12065 0.2794)
			(end -0.12065 0.3048)
			(stroke
				(width 0.1)
				(type default)
			)
			(layer "F.Fab")
		)
		(fp_line
			(start -0.12065 -0.2794)
			(end 0.12065 -0.2794)
			(stroke
				(width 0.1)
				(type default)
			)
			(layer "F.Fab")
		)
		(fp_line
			(start -0.12065 -0.305054)
			(end -0.12065 -0.2794)
			(stroke
				(width 0.1)
				(type default)
			)
			(layer "F.Fab")
		)
		(fp_line
			(start -0.67945 0.3048)
			(end -0.67945 -0.305054)
			(stroke
				(width 0.1)
				(type default)
			)
			(layer "F.Fab")
		)
		(fp_line
			(start -0.67945 -0.305054)
			(end -0.12065 -0.305054)
			(stroke
				(width 0.1)
				(type default)
			)
			(layer "F.Fab")
		)
		(pad "1" smd circle
			(at -0.40005 0 180)
			(size 0 0)
			(layers "F.Cu" "F.Mask" "F.Paste")
			(net "P12V_NIC5_CO_OV_FB")
		)
		(pad "2" smd circle
			(at 0.40005 0 180)
			(size 0 0)
			(layers "F.Cu" "F.Mask" "F.Paste")
			(net "GND")
		)
	)
	(footprint ""
		(layer "F.Cu")
		(at 376.936 -185.801)
		(property "Reference" "R4651"
			(at 0 0 0)
			(layer "F.SilkS")
			(hide yes)
			(effects
				(font
					(size 1.27 1.27)
				)
			)
		)
		(property "Value" ""
			(at 0 0 0)
			(layer "F.Fab")
			(effects
				(font
					(size 1.27 1.27)
				)
			)
		)
		(duplicate_pad_numbers_are_jumpers no)
		(fp_line
			(start -0.7874 -0.4064)
			(end 0.7874 -0.4064)
			(stroke
				(width 0.1524)
				(type default)
			)
			(layer "F.SilkS")
		)
		(fp_line
			(start -0.7874 0.4064)
			(end -0.7874 -0.4064)
			(stroke
				(width 0.1524)
				(type default)
			)
			(layer "F.SilkS")
		)
		(fp_line
			(start 0.7874 -0.4064)
			(end 0.7874 0.4064)
			(stroke
				(width 0.1524)
				(type default)
			)
			(layer "F.SilkS")
		)
		(fp_line
			(start 0.7874 0.4064)
			(end -0.7874 0.4064)
			(stroke
				(width 0.1524)
				(type default)
			)
			(layer "F.SilkS")
		)
		(fp_line
			(start -0.67945 -0.305054)
			(end -0.12065 -0.305054)
			(stroke
				(width 0.1)
				(type default)
			)
			(layer "F.Fab")
		)
		(fp_line
			(start -0.67945 0.3048)
			(end -0.67945 -0.305054)
			(stroke
				(width 0.1)
				(type default)
			)
			(layer "F.Fab")
		)
		(fp_line
			(start -0.12065 -0.305054)
			(end -0.12065 -0.2794)
			(stroke
				(width 0.1)
				(type default)
			)
			(layer "F.Fab")
		)
		(fp_line
			(start -0.12065 -0.2794)
			(end 0.12065 -0.2794)
			(stroke
				(width 0.1)
				(type default)
			)
			(layer "F.Fab")
		)
		(fp_line
			(start -0.12065 0.2794)
			(end -0.12065 0.3048)
			(stroke
				(width 0.1)
				(type default)
			)
			(layer "F.Fab")
		)
		(fp_line
			(start -0.12065 0.3048)
			(end -0.67945 0.3048)
			(stroke
				(width 0.1)
				(type default)
			)
			(layer "F.Fab")
		)
		(fp_line
			(start 0.120396 0.2794)
			(end -0.12065 0.2794)
			(stroke
				(width 0.1)
				(type default)
			)
			(layer "F.Fab")
		)
		(fp_line
			(start 0.120396 0.3048)
			(end 0.120396 0.2794)
			(stroke
				(width 0.1)
				(type default)
			)
			(layer "F.Fab")
		)
		(fp_line
			(start 0.12065 -0.3048)
			(end 0.67945 -0.3048)
			(stroke
				(width 0.1)
				(type default)
			)
			(layer "F.Fab")
		)
		(fp_line
			(start 0.12065 -0.2794)
			(end 0.12065 -0.3048)
			(stroke
				(width 0.1)
				(type default)
			)
			(layer "F.Fab")
		)
		(fp_line
			(start 0.67945 -0.3048)
			(end 0.67945 0.3048)
			(stroke
				(width 0.1)
				(type default)
			)
			(layer "F.Fab")
		)
		(fp_line
			(start 0.67945 0.3048)
			(end 0.120396 0.3048)
			(stroke
				(width 0.1)
				(type default)
			)
			(layer "F.Fab")
		)
		(pad "1" smd circle
			(at -0.40005 0)
			(size 0 0)
			(layers "F.Cu" "F.Mask" "F.Paste")
			(net "NIC1_PEX_PWR_EN")
		)
		(pad "2" smd circle
			(at 0.40005 0)
			(size 0 0)
			(layers "F.Cu" "F.Mask" "F.Paste")
			(net "NIC1_PEX_PWR_EN_R")
		)
	)
	(footprint ""
		(layer "F.Cu")
		(at 289.49396 -35.264852)
		(property "Reference" "R5695"
			(at 0 0 0)
			(layer "F.SilkS")
			(hide yes)
			(effects
				(font
					(size 1.27 1.27)
				)
			)
		)
		(property "Value" ""
			(at 0 0 0)
			(layer "F.Fab")
			(effects
				(font
					(size 1.27 1.27)
				)
			)
		)
		(duplicate_pad_numbers_are_jumpers no)
		(fp_line
			(start -0.7874 -0.4064)
			(end 0.7874 -0.4064)
			(stroke
				(width 0.1524)
				(type default)
			)
			(layer "F.SilkS")
		)
		(fp_line
			(start -0.7874 0.4064)
			(end -0.7874 -0.4064)
			(stroke
				(width 0.1524)
				(type default)
			)
			(layer "F.SilkS")
		)
		(fp_line
			(start 0.7874 -0.4064)
			(end 0.7874 0.4064)
			(stroke
				(width 0.1524)
				(type default)
			)
			(layer "F.SilkS")
		)
		(fp_line
			(start 0.7874 0.4064)
			(end -0.7874 0.4064)
			(stroke
				(width 0.1524)
				(type default)
			)
			(layer "F.SilkS")
		)
		(fp_line
			(start -0.67945 -0.305054)
			(end -0.12065 -0.305054)
			(stroke
				(width 0.1)
				(type default)
			)
			(layer "F.Fab")
		)
		(fp_line
			(start -0.67945 0.3048)
			(end -0.67945 -0.305054)
			(stroke
				(width 0.1)
				(type default)
			)
			(layer "F.Fab")
		)
		(fp_line
			(start -0.12065 -0.305054)
			(end -0.12065 -0.2794)
			(stroke
				(width 0.1)
				(type default)
			)
			(layer "F.Fab")
		)
		(fp_line
			(start -0.12065 -0.2794)
			(end 0.12065 -0.2794)
			(stroke
				(width 0.1)
				(type default)
			)
			(layer "F.Fab")
		)
		(fp_line
			(start -0.12065 0.2794)
			(end -0.12065 0.3048)
			(stroke
				(width 0.1)
				(type default)
			)
			(layer "F.Fab")
		)
		(fp_line
			(start -0.12065 0.3048)
			(end -0.67945 0.3048)
			(stroke
				(width 0.1)
				(type default)
			)
			(layer "F.Fab")
		)
		(fp_line
			(start 0.120396 0.2794)
			(end -0.12065 0.2794)
			(stroke
				(width 0.1)
				(type default)
			)
			(layer "F.Fab")
		)
		(fp_line
			(start 0.120396 0.3048)
			(end 0.120396 0.2794)
			(stroke
				(width 0.1)
				(type default)
			)
			(layer "F.Fab")
		)
		(fp_line
			(start 0.12065 -0.3048)
			(end 0.67945 -0.3048)
			(stroke
				(width 0.1)
				(type default)
			)
			(layer "F.Fab")
		)
		(fp_line
			(start 0.12065 -0.2794)
			(end 0.12065 -0.3048)
			(stroke
				(width 0.1)
				(type default)
			)
			(layer "F.Fab")
		)
		(fp_line
			(start 0.67945 -0.3048)
			(end 0.67945 0.3048)
			(stroke
				(width 0.1)
				(type default)
			)
			(layer "F.Fab")
		)
		(fp_line
			(start 0.67945 0.3048)
			(end 0.120396 0.3048)
			(stroke
				(width 0.1)
				(type default)
			)
			(layer "F.Fab")
		)
		(pad "1" smd circle
			(at -0.40005 0)
			(size 0 0)
			(layers "F.Cu" "F.Mask" "F.Paste")
			(net "RST_SMB_SSD10_ISO_N")
		)
		(pad "2" smd circle
			(at 0.40005 0)
			(size 0 0)
			(layers "F.Cu" "F.Mask" "F.Paste")
			(net "GND")
		)
	)
	(footprint ""
		(layer "F.Cu")
		(at 378.382022 -289.790632 180)
		(property "Reference" "C3571"
			(at 0 0 180)
			(layer "F.SilkS")
			(hide yes)
			(effects
				(font
					(size 1.27 1.27)
				)
			)
		)
		(property "Value" ""
			(at 0 0 180)
			(layer "F.Fab")
			(effects
				(font
					(size 1.27 1.27)
				)
			)
		)
		(duplicate_pad_numbers_are_jumpers no)
		(fp_line
			(start 1.2954 0.5842)
			(end -1.2954 0.5842)
			(stroke
				(width 0.1524)
				(type default)
			)
			(layer "F.SilkS")
		)
		(fp_line
			(start 1.2954 -0.5842)
			(end 1.2954 0.5842)
			(stroke
				(width 0.1524)
				(type default)
			)
			(layer "F.SilkS")
		)
		(fp_line
			(start -1.2954 0.5842)
			(end -1.2954 -0.5842)
			(stroke
				(width 0.1524)
				(type default)
			)
			(layer "F.SilkS")
		)
		(fp_line
			(start -1.2954 -0.5842)
			(end 1.2954 -0.5842)
			(stroke
				(width 0.1524)
				(type default)
			)
			(layer "F.SilkS")
		)
		(fp_line
			(start 1.1938 0.4064)
			(end 0.8636 0.4064)
			(stroke
				(width 0.1)
				(type default)
			)
			(layer "F.Fab")
		)
		(fp_line
			(start 1.1938 -0.4064)
			(end 1.1938 0.4064)
			(stroke
				(width 0.1)
				(type default)
			)
			(layer "F.Fab")
		)
		(fp_line
			(start 0.8636 0.4572)
			(end -0.8636 0.4572)
			(stroke
				(width 0.1)
				(type default)
			)
			(layer "F.Fab")
		)
		(fp_line
			(start 0.8636 0.4064)
			(end 0.8636 0.4572)
			(stroke
				(width 0.1)
				(type default)
			)
			(layer "F.Fab")
		)
		(fp_line
			(start 0.8636 -0.4064)
			(end 1.1938 -0.4064)
			(stroke
				(width 0.1)
				(type default)
			)
			(layer "F.Fab")
		)
		(fp_line
			(start 0.8636 -0.4572)
			(end 0.8636 -0.4064)
			(stroke
				(width 0.1)
				(type default)
			)
			(layer "F.Fab")
		)
		(fp_line
			(start -0.8636 0.4572)
			(end -0.8636 0.4064)
			(stroke
				(width 0.1)
				(type default)
			)
			(layer "F.Fab")
		)
		(fp_line
			(start -0.8636 0.4064)
			(end -1.1938 0.4064)
			(stroke
				(width 0.1)
				(type default)
			)
			(layer "F.Fab")
		)
		(fp_line
			(start -0.8636 -0.4064)
			(end -0.8636 -0.4572)
			(stroke
				(width 0.1)
				(type default)
			)
			(layer "F.Fab")
		)
		(fp_line
			(start -0.8636 -0.4572)
			(end 0.8636 -0.4572)
			(stroke
				(width 0.1)
				(type default)
			)
			(layer "F.Fab")
		)
		(fp_line
			(start -1.1938 0.4064)
			(end -1.1938 -0.4064)
			(stroke
				(width 0.1)
				(type default)
			)
			(layer "F.Fab")
		)
		(fp_line
			(start -1.1938 -0.4064)
			(end -0.8636 -0.4064)
			(stroke
				(width 0.1)
				(type default)
			)
			(layer "F.Fab")
		)
		(pad "1" smd rect
			(at -0.7366 0 90)
			(size 0.7112 0.8128)
			(layers "F.Cu" "F.Mask" "F.Paste")
			(net "PCEPLL4_VDDA18_PEX3_R")
		)
		(pad "2" smd rect
			(at 0.7366 0 90)
			(size 0.7112 0.8128)
			(layers "F.Cu" "F.Mask" "F.Paste")
			(net "GND")
		)
	)
	(footprint ""
		(layer "F.Cu")
		(at 331.147166 -19.33956)
		(property "Reference" "C3954"
			(at 0 0 0)
			(layer "F.SilkS")
			(hide yes)
			(effects
				(font
					(size 1.27 1.27)
				)
			)
		)
		(property "Value" ""
			(at 0 0 0)
			(layer "F.Fab")
			(effects
				(font
					(size 1.27 1.27)
				)
			)
		)
		(duplicate_pad_numbers_are_jumpers no)
		(fp_line
			(start -0.7874 -0.4064)
			(end 0.7874 -0.4064)
			(stroke
				(width 0.1524)
				(type default)
			)
			(layer "F.SilkS")
		)
		(fp_line
			(start -0.7874 0.4064)
			(end -0.7874 -0.4064)
			(stroke
				(width 0.1524)
				(type default)
			)
			(layer "F.SilkS")
		)
		(fp_line
			(start 0.7874 -0.4064)
			(end 0.7874 0.4064)
			(stroke
				(width 0.1524)
				(type default)
			)
			(layer "F.SilkS")
		)
		(fp_line
			(start 0.7874 0.4064)
			(end -0.7874 0.4064)
			(stroke
				(width 0.1524)
				(type default)
			)
			(layer "F.SilkS")
		)
		(fp_line
			(start -0.67945 -0.305054)
			(end -0.12065 -0.305054)
			(stroke
				(width 0.1)
				(type default)
			)
			(layer "F.Fab")
		)
		(fp_line
			(start -0.67945 0.3048)
			(end -0.67945 -0.305054)
			(stroke
				(width 0.1)
				(type default)
			)
			(layer "F.Fab")
		)
		(fp_line
			(start -0.12065 -0.305054)
			(end -0.12065 -0.2794)
			(stroke
				(width 0.1)
				(type default)
			)
			(layer "F.Fab")
		)
		(fp_line
			(start -0.12065 -0.2794)
			(end 0.12065 -0.2794)
			(stroke
				(width 0.1)
				(type default)
			)
			(layer "F.Fab")
		)
		(fp_line
			(start -0.12065 0.2794)
			(end -0.12065 0.3048)
			(stroke
				(width 0.1)
				(type default)
			)
			(layer "F.Fab")
		)
		(fp_line
			(start -0.12065 0.3048)
			(end -0.67945 0.3048)
			(stroke
				(width 0.1)
				(type default)
			)
			(layer "F.Fab")
		)
		(fp_line
			(start 0.120396 0.2794)
			(end -0.12065 0.2794)
			(stroke
				(width 0.1)
				(type default)
			)
			(layer "F.Fab")
		)
		(fp_line
			(start 0.120396 0.3048)
			(end 0.120396 0.2794)
			(stroke
				(width 0.1)
				(type default)
			)
			(layer "F.Fab")
		)
		(fp_line
			(start 0.12065 -0.3048)
			(end 0.67945 -0.3048)
			(stroke
				(width 0.1)
				(type default)
			)
			(layer "F.Fab")
		)
		(fp_line
			(start 0.12065 -0.2794)
			(end 0.12065 -0.3048)
			(stroke
				(width 0.1)
				(type default)
			)
			(layer "F.Fab")
		)
		(fp_line
			(start 0.67945 -0.3048)
			(end 0.67945 0.3048)
			(stroke
				(width 0.1)
				(type default)
			)
			(layer "F.Fab")
		)
		(fp_line
			(start 0.67945 0.3048)
			(end 0.120396 0.3048)
			(stroke
				(width 0.1)
				(type default)
			)
			(layer "F.Fab")
		)
		(pad "1" smd circle
			(at -0.40005 0)
			(size 0 0)
			(layers "F.Cu" "F.Mask" "F.Paste")
			(net "P12V_SSD11")
		)
		(pad "2" smd circle
			(at 0.40005 0)
			(size 0 0)
			(layers "F.Cu" "F.Mask" "F.Paste")
			(net "GND")
		)
	)
	(footprint ""
		(layer "F.Cu")
		(at 260.54177 -27.006296 -90)
		(property "Reference" "PR7118"
			(at 0 0 270)
			(layer "F.SilkS")
			(hide yes)
			(effects
				(font
					(size 1.27 1.27)
				)
			)
		)
		(property "Value" ""
			(at 0 0 270)
			(layer "F.Fab")
			(effects
				(font
					(size 1.27 1.27)
				)
			)
		)
		(duplicate_pad_numbers_are_jumpers no)
		(fp_line
			(start -0.7874 0.4064)
			(end -0.7874 -0.4064)
			(stroke
				(width 0.1524)
				(type default)
			)
			(layer "F.SilkS")
		)
		(fp_line
			(start 0.7874 0.4064)
			(end -0.7874 0.4064)
			(stroke
				(width 0.1524)
				(type default)
			)
			(layer "F.SilkS")
		)
		(fp_line
			(start -0.7874 -0.4064)
			(end 0.7874 -0.4064)
			(stroke
				(width 0.1524)
				(type default)
			)
			(layer "F.SilkS")
		)
		(fp_line
			(start 0.7874 -0.4064)
			(end 0.7874 0.4064)
			(stroke
				(width 0.1524)
				(type default)
			)
			(layer "F.SilkS")
		)
		(fp_line
			(start -0.67945 0.3048)
			(end -0.67945 -0.305054)
			(stroke
				(width 0.1)
				(type default)
			)
			(layer "F.Fab")
		)
		(fp_line
			(start -0.12065 0.3048)
			(end -0.67945 0.3048)
			(stroke
				(width 0.1)
				(type default)
			)
			(layer "F.Fab")
		)
		(fp_line
			(start 0.120396 0.3048)
			(end 0.120396 0.2794)
			(stroke
				(width 0.1)
				(type default)
			)
			(layer "F.Fab")
		)
		(fp_line
			(start 0.67945 0.3048)
			(end 0.120396 0.3048)
			(stroke
				(width 0.1)
				(type default)
			)
			(layer "F.Fab")
		)
		(fp_line
			(start -0.12065 0.2794)
			(end -0.12065 0.3048)
			(stroke
				(width 0.1)
				(type default)
			)
			(layer "F.Fab")
		)
		(fp_line
			(start 0.120396 0.2794)
			(end -0.12065 0.2794)
			(stroke
				(width 0.1)
				(type default)
			)
			(layer "F.Fab")
		)
		(fp_line
			(start -0.12065 -0.2794)
			(end 0.12065 -0.2794)
			(stroke
				(width 0.1)
				(type default)
			)
			(layer "F.Fab")
		)
		(fp_line
			(start 0.12065 -0.2794)
			(end 0.12065 -0.3048)
			(stroke
				(width 0.1)
				(type default)
			)
			(layer "F.Fab")
		)
		(fp_line
			(start 0.12065 -0.3048)
			(end 0.67945 -0.3048)
			(stroke
				(width 0.1)
				(type default)
			)
			(layer "F.Fab")
		)
		(fp_line
			(start 0.67945 -0.3048)
			(end 0.67945 0.3048)
			(stroke
				(width 0.1)
				(type default)
			)
			(layer "F.Fab")
		)
		(fp_line
			(start -0.67945 -0.305054)
			(end -0.12065 -0.305054)
			(stroke
				(width 0.1)
				(type default)
			)
			(layer "F.Fab")
		)
		(fp_line
			(start -0.12065 -0.305054)
			(end -0.12065 -0.2794)
			(stroke
				(width 0.1)
				(type default)
			)
			(layer "F.Fab")
		)
		(pad "1" smd circle
			(at -0.40005 0 270)
			(size 0 0)
			(layers "F.Cu" "F.Mask" "F.Paste")
			(net "P3V3_SSD9_CO_ILIMIT")
		)
		(pad "2" smd circle
			(at 0.40005 0 270)
			(size 0 0)
			(layers "F.Cu" "F.Mask" "F.Paste")
			(net "GND")
		)
	)
	(footprint ""
		(layer "F.Cu")
		(at 313.202574 -89.1159)
		(property "Reference" "C932"
			(at 0 0 0)
			(layer "F.SilkS")
			(hide yes)
			(effects
				(font
					(size 1.27 1.27)
				)
			)
		)
		(property "Value" ""
			(at 0 0 0)
			(layer "F.Fab")
			(effects
				(font
					(size 1.27 1.27)
				)
			)
		)
		(duplicate_pad_numbers_are_jumpers no)
		(fp_line
			(start -0.7874 -0.4064)
			(end 0.7874 -0.4064)
			(stroke
				(width 0.1524)
				(type default)
			)
			(layer "F.SilkS")
		)
		(fp_line
			(start -0.7874 0.4064)
			(end -0.7874 -0.4064)
			(stroke
				(width 0.1524)
				(type default)
			)
			(layer "F.SilkS")
		)
		(fp_line
			(start 0.7874 -0.4064)
			(end 0.7874 0.4064)
			(stroke
				(width 0.1524)
				(type default)
			)
			(layer "F.SilkS")
		)
		(fp_line
			(start 0.7874 0.4064)
			(end -0.7874 0.4064)
			(stroke
				(width 0.1524)
				(type default)
			)
			(layer "F.SilkS")
		)
		(fp_line
			(start -0.67945 -0.305054)
			(end -0.12065 -0.305054)
			(stroke
				(width 0.1)
				(type default)
			)
			(layer "F.Fab")
		)
		(fp_line
			(start -0.67945 0.3048)
			(end -0.67945 -0.305054)
			(stroke
				(width 0.1)
				(type default)
			)
			(layer "F.Fab")
		)
		(fp_line
			(start -0.12065 -0.305054)
			(end -0.12065 -0.2794)
			(stroke
				(width 0.1)
				(type default)
			)
			(layer "F.Fab")
		)
		(fp_line
			(start -0.12065 -0.2794)
			(end 0.12065 -0.2794)
			(stroke
				(width 0.1)
				(type default)
			)
			(layer "F.Fab")
		)
		(fp_line
			(start -0.12065 0.2794)
			(end -0.12065 0.3048)
			(stroke
				(width 0.1)
				(type default)
			)
			(layer "F.Fab")
		)
		(fp_line
			(start -0.12065 0.3048)
			(end -0.67945 0.3048)
			(stroke
				(width 0.1)
				(type default)
			)
			(layer "F.Fab")
		)
		(fp_line
			(start 0.120396 0.2794)
			(end -0.12065 0.2794)
			(stroke
				(width 0.1)
				(type default)
			)
			(layer "F.Fab")
		)
		(fp_line
			(start 0.120396 0.3048)
			(end 0.120396 0.2794)
			(stroke
				(width 0.1)
				(type default)
			)
			(layer "F.Fab")
		)
		(fp_line
			(start 0.12065 -0.3048)
			(end 0.67945 -0.3048)
			(stroke
				(width 0.1)
				(type default)
			)
			(layer "F.Fab")
		)
		(fp_line
			(start 0.12065 -0.2794)
			(end 0.12065 -0.3048)
			(stroke
				(width 0.1)
				(type default)
			)
			(layer "F.Fab")
		)
		(fp_line
			(start 0.67945 -0.3048)
			(end 0.67945 0.3048)
			(stroke
				(width 0.1)
				(type default)
			)
			(layer "F.Fab")
		)
		(fp_line
			(start 0.67945 0.3048)
			(end 0.120396 0.3048)
			(stroke
				(width 0.1)
				(type default)
			)
			(layer "F.Fab")
		)
		(pad "1" smd circle
			(at -0.40005 0)
			(size 0 0)
			(layers "F.Cu" "F.Mask" "F.Paste")
			(net "P3V3_AUX")
		)
		(pad "2" smd circle
			(at 0.40005 0)
			(size 0 0)
			(layers "F.Cu" "F.Mask" "F.Paste")
			(net "GND")
		)
	)
	(footprint ""
		(layer "F.Cu")
		(at 79.12608 -39.73576 -90)
		(property "Reference" "R5548"
			(at 0 0 270)
			(layer "F.SilkS")
			(hide yes)
			(effects
				(font
					(size 1.27 1.27)
				)
			)
		)
		(property "Value" ""
			(at 0 0 270)
			(layer "F.Fab")
			(effects
				(font
					(size 1.27 1.27)
				)
			)
		)
		(duplicate_pad_numbers_are_jumpers no)
		(fp_line
			(start -0.7874 0.4064)
			(end -0.7874 -0.4064)
			(stroke
				(width 0.1524)
				(type default)
			)
			(layer "F.SilkS")
		)
		(fp_line
			(start 0.7874 0.4064)
			(end -0.7874 0.4064)
			(stroke
				(width 0.1524)
				(type default)
			)
			(layer "F.SilkS")
		)
		(fp_line
			(start -0.7874 -0.4064)
			(end 0.7874 -0.4064)
			(stroke
				(width 0.1524)
				(type default)
			)
			(layer "F.SilkS")
		)
		(fp_line
			(start 0.7874 -0.4064)
			(end 0.7874 0.4064)
			(stroke
				(width 0.1524)
				(type default)
			)
			(layer "F.SilkS")
		)
		(fp_line
			(start -0.67945 0.3048)
			(end -0.67945 -0.305054)
			(stroke
				(width 0.1)
				(type default)
			)
			(layer "F.Fab")
		)
		(fp_line
			(start -0.12065 0.3048)
			(end -0.67945 0.3048)
			(stroke
				(width 0.1)
				(type default)
			)
			(layer "F.Fab")
		)
		(fp_line
			(start 0.120396 0.3048)
			(end 0.120396 0.2794)
			(stroke
				(width 0.1)
				(type default)
			)
			(layer "F.Fab")
		)
		(fp_line
			(start 0.67945 0.3048)
			(end 0.120396 0.3048)
			(stroke
				(width 0.1)
				(type default)
			)
			(layer "F.Fab")
		)
		(fp_line
			(start -0.12065 0.2794)
			(end -0.12065 0.3048)
			(stroke
				(width 0.1)
				(type default)
			)
			(layer "F.Fab")
		)
		(fp_line
			(start 0.120396 0.2794)
			(end -0.12065 0.2794)
			(stroke
				(width 0.1)
				(type default)
			)
			(layer "F.Fab")
		)
		(fp_line
			(start -0.12065 -0.2794)
			(end 0.12065 -0.2794)
			(stroke
				(width 0.1)
				(type default)
			)
			(layer "F.Fab")
		)
		(fp_line
			(start 0.12065 -0.2794)
			(end 0.12065 -0.3048)
			(stroke
				(width 0.1)
				(type default)
			)
			(layer "F.Fab")
		)
		(fp_line
			(start 0.12065 -0.3048)
			(end 0.67945 -0.3048)
			(stroke
				(width 0.1)
				(type default)
			)
			(layer "F.Fab")
		)
		(fp_line
			(start 0.67945 -0.3048)
			(end 0.67945 0.3048)
			(stroke
				(width 0.1)
				(type default)
			)
			(layer "F.Fab")
		)
		(fp_line
			(start -0.67945 -0.305054)
			(end -0.12065 -0.305054)
			(stroke
				(width 0.1)
				(type default)
			)
			(layer "F.Fab")
		)
		(fp_line
			(start -0.12065 -0.305054)
			(end -0.12065 -0.2794)
			(stroke
				(width 0.1)
				(type default)
			)
			(layer "F.Fab")
		)
		(pad "1" smd circle
			(at -0.40005 0 270)
			(size 0 0)
			(layers "F.Cu" "F.Mask" "F.Paste")
			(net "P3V3_AUX")
		)
		(pad "2" smd circle
			(at 0.40005 0 270)
			(size 0 0)
			(layers "F.Cu" "F.Mask" "F.Paste")
			(net "SSD3_AUX_P3V3_EN")
		)
	)
	(footprint ""
		(layer "F.Cu")
		(at 15.697962 -122.780552)
		(property "Reference" "PC450"
			(at 0 0 0)
			(layer "F.SilkS")
			(hide yes)
			(effects
				(font
					(size 1.27 1.27)
				)
			)
		)
		(property "Value" ""
			(at 0 0 0)
			(layer "F.Fab")
			(effects
				(font
					(size 1.27 1.27)
				)
			)
		)
		(duplicate_pad_numbers_are_jumpers no)
		(fp_line
			(start -0.7874 -0.4064)
			(end 0.7874 -0.4064)
			(stroke
				(width 0.1524)
				(type default)
			)
			(layer "F.SilkS")
		)
		(fp_line
			(start -0.7874 0.4064)
			(end -0.7874 -0.4064)
			(stroke
				(width 0.1524)
				(type default)
			)
			(layer "F.SilkS")
		)
		(fp_line
			(start 0.7874 -0.4064)
			(end 0.7874 0.4064)
			(stroke
				(width 0.1524)
				(type default)
			)
			(layer "F.SilkS")
		)
		(fp_line
			(start 0.7874 0.4064)
			(end -0.7874 0.4064)
			(stroke
				(width 0.1524)
				(type default)
			)
			(layer "F.SilkS")
		)
		(fp_line
			(start -0.67945 -0.305054)
			(end -0.12065 -0.305054)
			(stroke
				(width 0.1)
				(type default)
			)
			(layer "F.Fab")
		)
		(fp_line
			(start -0.67945 0.3048)
			(end -0.67945 -0.305054)
			(stroke
				(width 0.1)
				(type default)
			)
			(layer "F.Fab")
		)
		(fp_line
			(start -0.12065 -0.305054)
			(end -0.12065 -0.2794)
			(stroke
				(width 0.1)
				(type default)
			)
			(layer "F.Fab")
		)
		(fp_line
			(start -0.12065 -0.2794)
			(end 0.12065 -0.2794)
			(stroke
				(width 0.1)
				(type default)
			)
			(layer "F.Fab")
		)
		(fp_line
			(start -0.12065 0.2794)
			(end -0.12065 0.3048)
			(stroke
				(width 0.1)
				(type default)
			)
			(layer "F.Fab")
		)
		(fp_line
			(start -0.12065 0.3048)
			(end -0.67945 0.3048)
			(stroke
				(width 0.1)
				(type default)
			)
			(layer "F.Fab")
		)
		(fp_line
			(start 0.120396 0.2794)
			(end -0.12065 0.2794)
			(stroke
				(width 0.1)
				(type default)
			)
			(layer "F.Fab")
		)
		(fp_line
			(start 0.120396 0.3048)
			(end 0.120396 0.2794)
			(stroke
				(width 0.1)
				(type default)
			)
			(layer "F.Fab")
		)
		(fp_line
			(start 0.12065 -0.3048)
			(end 0.67945 -0.3048)
			(stroke
				(width 0.1)
				(type default)
			)
			(layer "F.Fab")
		)
		(fp_line
			(start 0.12065 -0.2794)
			(end 0.12065 -0.3048)
			(stroke
				(width 0.1)
				(type default)
			)
			(layer "F.Fab")
		)
		(fp_line
			(start 0.67945 -0.3048)
			(end 0.67945 0.3048)
			(stroke
				(width 0.1)
				(type default)
			)
			(layer "F.Fab")
		)
		(fp_line
			(start 0.67945 0.3048)
			(end 0.120396 0.3048)
			(stroke
				(width 0.1)
				(type default)
			)
			(layer "F.Fab")
		)
		(pad "1" smd circle
			(at -0.40005 0)
			(size 0 0)
			(layers "F.Cu" "F.Mask" "F.Paste")
			(net "P3V3_AUX")
		)
		(pad "2" smd circle
			(at 0.40005 0)
			(size 0 0)
			(layers "F.Cu" "F.Mask" "F.Paste")
			(net "GND")
		)
	)
	(footprint ""
		(layer "F.Cu")
		(at 19.223736 -152.71115 90)
		(property "Reference" "R686"
			(at 0 0 90)
			(layer "F.SilkS")
			(hide yes)
			(effects
				(font
					(size 1.27 1.27)
				)
			)
		)
		(property "Value" ""
			(at 0 0 90)
			(layer "F.Fab")
			(effects
				(font
					(size 1.27 1.27)
				)
			)
		)
		(duplicate_pad_numbers_are_jumpers no)
		(fp_line
			(start 0.7874 -0.4064)
			(end 0.7874 0.4064)
			(stroke
				(width 0.1524)
				(type default)
			)
			(layer "F.SilkS")
		)
		(fp_line
			(start -0.7874 -0.4064)
			(end 0.7874 -0.4064)
			(stroke
				(width 0.1524)
				(type default)
			)
			(layer "F.SilkS")
		)
		(fp_line
			(start 0.7874 0.4064)
			(end -0.7874 0.4064)
			(stroke
				(width 0.1524)
				(type default)
			)
			(layer "F.SilkS")
		)
		(fp_line
			(start -0.7874 0.4064)
			(end -0.7874 -0.4064)
			(stroke
				(width 0.1524)
				(type default)
			)
			(layer "F.SilkS")
		)
		(fp_line
			(start -0.12065 -0.305054)
			(end -0.12065 -0.2794)
			(stroke
				(width 0.1)
				(type default)
			)
			(layer "F.Fab")
		)
		(fp_line
			(start -0.67945 -0.305054)
			(end -0.12065 -0.305054)
			(stroke
				(width 0.1)
				(type default)
			)
			(layer "F.Fab")
		)
		(fp_line
			(start 0.67945 -0.3048)
			(end 0.67945 0.3048)
			(stroke
				(width 0.1)
				(type default)
			)
			(layer "F.Fab")
		)
		(fp_line
			(start 0.12065 -0.3048)
			(end 0.67945 -0.3048)
			(stroke
				(width 0.1)
				(type default)
			)
			(layer "F.Fab")
		)
		(fp_line
			(start 0.12065 -0.2794)
			(end 0.12065 -0.3048)
			(stroke
				(width 0.1)
				(type default)
			)
			(layer "F.Fab")
		)
		(fp_line
			(start -0.12065 -0.2794)
			(end 0.12065 -0.2794)
			(stroke
				(width 0.1)
				(type default)
			)
			(layer "F.Fab")
		)
		(fp_line
			(start 0.120396 0.2794)
			(end -0.12065 0.2794)
			(stroke
				(width 0.1)
				(type default)
			)
			(layer "F.Fab")
		)
		(fp_line
			(start -0.12065 0.2794)
			(end -0.12065 0.3048)
			(stroke
				(width 0.1)
				(type default)
			)
			(layer "F.Fab")
		)
		(fp_line
			(start 0.67945 0.3048)
			(end 0.120396 0.3048)
			(stroke
				(width 0.1)
				(type default)
			)
			(layer "F.Fab")
		)
		(fp_line
			(start 0.120396 0.3048)
			(end 0.120396 0.2794)
			(stroke
				(width 0.1)
				(type default)
			)
			(layer "F.Fab")
		)
		(fp_line
			(start -0.12065 0.3048)
			(end -0.67945 0.3048)
			(stroke
				(width 0.1)
				(type default)
			)
			(layer "F.Fab")
		)
		(fp_line
			(start -0.67945 0.3048)
			(end -0.67945 -0.305054)
			(stroke
				(width 0.1)
				(type default)
			)
			(layer "F.Fab")
		)
		(pad "1" smd circle
			(at -0.40005 0 90)
			(size 0 0)
			(layers "F.Cu" "F.Mask" "F.Paste")
			(net "NIC0_ADC_A0")
		)
		(pad "2" smd circle
			(at 0.40005 0 90)
			(size 0 0)
			(layers "F.Cu" "F.Mask" "F.Paste")
			(net "GND")
		)
	)
	(footprint ""
		(layer "F.Cu")
		(at 230.749094 -177.74158 180)
		(property "Reference" "C3646"
			(at 0 0 180)
			(layer "F.SilkS")
			(hide yes)
			(effects
				(font
					(size 1.27 1.27)
				)
			)
		)
		(property "Value" ""
			(at 0 0 180)
			(layer "F.Fab")
			(effects
				(font
					(size 1.27 1.27)
				)
			)
		)
		(duplicate_pad_numbers_are_jumpers no)
		(fp_line
			(start 0.7874 0.4064)
			(end -0.7874 0.4064)
			(stroke
				(width 0.1524)
				(type default)
			)
			(layer "F.SilkS")
		)
		(fp_line
			(start 0.7874 -0.4064)
			(end 0.7874 0.4064)
			(stroke
				(width 0.1524)
				(type default)
			)
			(layer "F.SilkS")
		)
		(fp_line
			(start -0.7874 0.4064)
			(end -0.7874 -0.4064)
			(stroke
				(width 0.1524)
				(type default)
			)
			(layer "F.SilkS")
		)
		(fp_line
			(start -0.7874 -0.4064)
			(end 0.7874 -0.4064)
			(stroke
				(width 0.1524)
				(type default)
			)
			(layer "F.SilkS")
		)
		(fp_line
			(start 0.67945 0.3048)
			(end 0.120396 0.3048)
			(stroke
				(width 0.1)
				(type default)
			)
			(layer "F.Fab")
		)
		(fp_line
			(start 0.67945 -0.3048)
			(end 0.67945 0.3048)
			(stroke
				(width 0.1)
				(type default)
			)
			(layer "F.Fab")
		)
		(fp_line
			(start 0.12065 -0.2794)
			(end 0.12065 -0.3048)
			(stroke
				(width 0.1)
				(type default)
			)
			(layer "F.Fab")
		)
		(fp_line
			(start 0.12065 -0.3048)
			(end 0.67945 -0.3048)
			(stroke
				(width 0.1)
				(type default)
			)
			(layer "F.Fab")
		)
		(fp_line
			(start 0.120396 0.3048)
			(end 0.120396 0.2794)
			(stroke
				(width 0.1)
				(type default)
			)
			(layer "F.Fab")
		)
		(fp_line
			(start 0.120396 0.2794)
			(end -0.12065 0.2794)
			(stroke
				(width 0.1)
				(type default)
			)
			(layer "F.Fab")
		)
		(fp_line
			(start -0.12065 0.3048)
			(end -0.67945 0.3048)
			(stroke
				(width 0.1)
				(type default)
			)
			(layer "F.Fab")
		)
		(fp_line
			(start -0.12065 0.2794)
			(end -0.12065 0.3048)
			(stroke
				(width 0.1)
				(type default)
			)
			(layer "F.Fab")
		)
		(fp_line
			(start -0.12065 -0.2794)
			(end 0.12065 -0.2794)
			(stroke
				(width 0.1)
				(type default)
			)
			(layer "F.Fab")
		)
		(fp_line
			(start -0.12065 -0.305054)
			(end -0.12065 -0.2794)
			(stroke
				(width 0.1)
				(type default)
			)
			(layer "F.Fab")
		)
		(fp_line
			(start -0.67945 0.3048)
			(end -0.67945 -0.305054)
			(stroke
				(width 0.1)
				(type default)
			)
			(layer "F.Fab")
		)
		(fp_line
			(start -0.67945 -0.305054)
			(end -0.12065 -0.305054)
			(stroke
				(width 0.1)
				(type default)
			)
			(layer "F.Fab")
		)
		(pad "1" smd circle
			(at -0.40005 0 180)
			(size 0 0)
			(layers "F.Cu" "F.Mask" "F.Paste")
			(net "GND")
		)
		(pad "2" smd circle
			(at 0.40005 0 180)
			(size 0 0)
			(layers "F.Cu" "F.Mask" "F.Paste")
			(net "P3V3_AUX")
		)
	)
	(footprint ""
		(layer "F.Cu")
		(at 429.657764 -27.006296 -90)
		(property "Reference" "PR7128"
			(at 0 0 270)
			(layer "F.SilkS")
			(hide yes)
			(effects
				(font
					(size 1.27 1.27)
				)
			)
		)
		(property "Value" ""
			(at 0 0 270)
			(layer "F.Fab")
			(effects
				(font
					(size 1.27 1.27)
				)
			)
		)
		(duplicate_pad_numbers_are_jumpers no)
		(fp_line
			(start -0.7874 0.4064)
			(end -0.7874 -0.4064)
			(stroke
				(width 0.1524)
				(type default)
			)
			(layer "F.SilkS")
		)
		(fp_line
			(start 0.7874 0.4064)
			(end -0.7874 0.4064)
			(stroke
				(width 0.1524)
				(type default)
			)
			(layer "F.SilkS")
		)
		(fp_line
			(start -0.7874 -0.4064)
			(end 0.7874 -0.4064)
			(stroke
				(width 0.1524)
				(type default)
			)
			(layer "F.SilkS")
		)
		(fp_line
			(start 0.7874 -0.4064)
			(end 0.7874 0.4064)
			(stroke
				(width 0.1524)
				(type default)
			)
			(layer "F.SilkS")
		)
		(fp_line
			(start -0.67945 0.3048)
			(end -0.67945 -0.305054)
			(stroke
				(width 0.1)
				(type default)
			)
			(layer "F.Fab")
		)
		(fp_line
			(start -0.12065 0.3048)
			(end -0.67945 0.3048)
			(stroke
				(width 0.1)
				(type default)
			)
			(layer "F.Fab")
		)
		(fp_line
			(start 0.120396 0.3048)
			(end 0.120396 0.2794)
			(stroke
				(width 0.1)
				(type default)
			)
			(layer "F.Fab")
		)
		(fp_line
			(start 0.67945 0.3048)
			(end 0.120396 0.3048)
			(stroke
				(width 0.1)
				(type default)
			)
			(layer "F.Fab")
		)
		(fp_line
			(start -0.12065 0.2794)
			(end -0.12065 0.3048)
			(stroke
				(width 0.1)
				(type default)
			)
			(layer "F.Fab")
		)
		(fp_line
			(start 0.120396 0.2794)
			(end -0.12065 0.2794)
			(stroke
				(width 0.1)
				(type default)
			)
			(layer "F.Fab")
		)
		(fp_line
			(start -0.12065 -0.2794)
			(end 0.12065 -0.2794)
			(stroke
				(width 0.1)
				(type default)
			)
			(layer "F.Fab")
		)
		(fp_line
			(start 0.12065 -0.2794)
			(end 0.12065 -0.3048)
			(stroke
				(width 0.1)
				(type default)
			)
			(layer "F.Fab")
		)
		(fp_line
			(start 0.12065 -0.3048)
			(end 0.67945 -0.3048)
			(stroke
				(width 0.1)
				(type default)
			)
			(layer "F.Fab")
		)
		(fp_line
			(start 0.67945 -0.3048)
			(end 0.67945 0.3048)
			(stroke
				(width 0.1)
				(type default)
			)
			(layer "F.Fab")
		)
		(fp_line
			(start -0.67945 -0.305054)
			(end -0.12065 -0.305054)
			(stroke
				(width 0.1)
				(type default)
			)
			(layer "F.Fab")
		)
		(fp_line
			(start -0.12065 -0.305054)
			(end -0.12065 -0.2794)
			(stroke
				(width 0.1)
				(type default)
			)
			(layer "F.Fab")
		)
		(pad "1" smd circle
			(at -0.40005 0 270)
			(size 0 0)
			(layers "F.Cu" "F.Mask" "F.Paste")
			(net "P3V3_SSD15_CO_MODE")
		)
		(pad "2" smd circle
			(at 0.40005 0 270)
			(size 0 0)
			(layers "F.Cu" "F.Mask" "F.Paste")
			(net "GND")
		)
	)
	(footprint ""
		(layer "F.Cu")
		(at 189.77356 -402.66874 -90)
		(property "Reference" "R4414"
			(at 0 0 270)
			(layer "F.SilkS")
			(hide yes)
			(effects
				(font
					(size 1.27 1.27)
				)
			)
		)
		(property "Value" ""
			(at 0 0 270)
			(layer "F.Fab")
			(effects
				(font
					(size 1.27 1.27)
				)
			)
		)
		(duplicate_pad_numbers_are_jumpers no)
		(fp_line
			(start -0.7874 0.4064)
			(end -0.7874 -0.4064)
			(stroke
				(width 0.1524)
				(type default)
			)
			(layer "F.SilkS")
		)
		(fp_line
			(start 0.7874 0.4064)
			(end -0.7874 0.4064)
			(stroke
				(width 0.1524)
				(type default)
			)
			(layer "F.SilkS")
		)
		(fp_line
			(start -0.7874 -0.4064)
			(end 0.7874 -0.4064)
			(stroke
				(width 0.1524)
				(type default)
			)
			(layer "F.SilkS")
		)
		(fp_line
			(start 0.7874 -0.4064)
			(end 0.7874 0.4064)
			(stroke
				(width 0.1524)
				(type default)
			)
			(layer "F.SilkS")
		)
		(fp_line
			(start -0.67945 0.3048)
			(end -0.67945 -0.305054)
			(stroke
				(width 0.1)
				(type default)
			)
			(layer "F.Fab")
		)
		(fp_line
			(start -0.12065 0.3048)
			(end -0.67945 0.3048)
			(stroke
				(width 0.1)
				(type default)
			)
			(layer "F.Fab")
		)
		(fp_line
			(start 0.120396 0.3048)
			(end 0.120396 0.2794)
			(stroke
				(width 0.1)
				(type default)
			)
			(layer "F.Fab")
		)
		(fp_line
			(start 0.67945 0.3048)
			(end 0.120396 0.3048)
			(stroke
				(width 0.1)
				(type default)
			)
			(layer "F.Fab")
		)
		(fp_line
			(start -0.12065 0.2794)
			(end -0.12065 0.3048)
			(stroke
				(width 0.1)
				(type default)
			)
			(layer "F.Fab")
		)
		(fp_line
			(start 0.120396 0.2794)
			(end -0.12065 0.2794)
			(stroke
				(width 0.1)
				(type default)
			)
			(layer "F.Fab")
		)
		(fp_line
			(start -0.12065 -0.2794)
			(end 0.12065 -0.2794)
			(stroke
				(width 0.1)
				(type default)
			)
			(layer "F.Fab")
		)
		(fp_line
			(start 0.12065 -0.2794)
			(end 0.12065 -0.3048)
			(stroke
				(width 0.1)
				(type default)
			)
			(layer "F.Fab")
		)
		(fp_line
			(start 0.12065 -0.3048)
			(end 0.67945 -0.3048)
			(stroke
				(width 0.1)
				(type default)
			)
			(layer "F.Fab")
		)
		(fp_line
			(start 0.67945 -0.3048)
			(end 0.67945 0.3048)
			(stroke
				(width 0.1)
				(type default)
			)
			(layer "F.Fab")
		)
		(fp_line
			(start -0.67945 -0.305054)
			(end -0.12065 -0.305054)
			(stroke
				(width 0.1)
				(type default)
			)
			(layer "F.Fab")
		)
		(fp_line
			(start -0.12065 -0.305054)
			(end -0.12065 -0.2794)
			(stroke
				(width 0.1)
				(type default)
			)
			(layer "F.Fab")
		)
		(pad "1" smd circle
			(at -0.40005 0 270)
			(size 0 0)
			(layers "F.Cu" "F.Mask" "F.Paste")
			(net "A_P12V_AUX_ADR_TRIGGER")
		)
		(pad "2" smd circle
			(at 0.40005 0 270)
			(size 0 0)
			(layers "F.Cu" "F.Mask" "F.Paste")
			(net "P12V_AUX")
		)
	)
	(footprint ""
		(layer "F.Cu")
		(at 269.448026 -102.009702)
		(property "Reference" "C484"
			(at 0 0 0)
			(layer "F.SilkS")
			(hide yes)
			(effects
				(font
					(size 1.27 1.27)
				)
			)
		)
		(property "Value" ""
			(at 0 0 0)
			(layer "F.Fab")
			(effects
				(font
					(size 1.27 1.27)
				)
			)
		)
		(duplicate_pad_numbers_are_jumpers no)
		(fp_line
			(start -0.299974 -0.150114)
			(end 0.299974 -0.150114)
			(stroke
				(width 0.1)
				(type default)
			)
			(layer "F.Fab")
		)
		(fp_line
			(start -0.299974 0.150114)
			(end -0.299974 -0.150114)
			(stroke
				(width 0.1)
				(type default)
			)
			(layer "F.Fab")
		)
		(fp_line
			(start 0.299974 -0.150114)
			(end 0.299974 0.150114)
			(stroke
				(width 0.1)
				(type default)
			)
			(layer "F.Fab")
		)
		(fp_line
			(start 0.299974 0.150114)
			(end -0.299974 0.150114)
			(stroke
				(width 0.1)
				(type default)
			)
			(layer "F.Fab")
		)
		(pad "1" smd rect
			(at -0.2667 0)
			(size 0.3048 0.381)
			(layers "F.Cu" "F.Mask" "F.Paste")
			(net "P5E_PEX2_STN1_TX_DP<17>")
		)
		(pad "2" smd rect
			(at 0.2667 0)
			(size 0.3048 0.381)
			(layers "F.Cu" "F.Mask" "F.Paste")
			(net "P5E_PEX2_STN1_TX_C_DP<17>")
		)
	)
	(footprint ""
		(layer "F.Cu")
		(at 142.368016 -56.353456)
		(property "Reference" "C2862"
			(at 0 0 0)
			(layer "F.SilkS")
			(hide yes)
			(effects
				(font
					(size 1.27 1.27)
				)
			)
		)
		(property "Value" ""
			(at 0 0 0)
			(layer "F.Fab")
			(effects
				(font
					(size 1.27 1.27)
				)
			)
		)
		(duplicate_pad_numbers_are_jumpers no)
		(fp_line
			(start -0.7874 -0.4064)
			(end 0.7874 -0.4064)
			(stroke
				(width 0.1524)
				(type default)
			)
			(layer "F.SilkS")
		)
		(fp_line
			(start -0.7874 0.4064)
			(end -0.7874 -0.4064)
			(stroke
				(width 0.1524)
				(type default)
			)
			(layer "F.SilkS")
		)
		(fp_line
			(start 0.7874 -0.4064)
			(end 0.7874 0.4064)
			(stroke
				(width 0.1524)
				(type default)
			)
			(layer "F.SilkS")
		)
		(fp_line
			(start 0.7874 0.4064)
			(end -0.7874 0.4064)
			(stroke
				(width 0.1524)
				(type default)
			)
			(layer "F.SilkS")
		)
		(fp_line
			(start -0.67945 -0.305054)
			(end -0.12065 -0.305054)
			(stroke
				(width 0.1)
				(type default)
			)
			(layer "F.Fab")
		)
		(fp_line
			(start -0.67945 0.3048)
			(end -0.67945 -0.305054)
			(stroke
				(width 0.1)
				(type default)
			)
			(layer "F.Fab")
		)
		(fp_line
			(start -0.12065 -0.305054)
			(end -0.12065 -0.2794)
			(stroke
				(width 0.1)
				(type default)
			)
			(layer "F.Fab")
		)
		(fp_line
			(start -0.12065 -0.2794)
			(end 0.12065 -0.2794)
			(stroke
				(width 0.1)
				(type default)
			)
			(layer "F.Fab")
		)
		(fp_line
			(start -0.12065 0.2794)
			(end -0.12065 0.3048)
			(stroke
				(width 0.1)
				(type default)
			)
			(layer "F.Fab")
		)
		(fp_line
			(start -0.12065 0.3048)
			(end -0.67945 0.3048)
			(stroke
				(width 0.1)
				(type default)
			)
			(layer "F.Fab")
		)
		(fp_line
			(start 0.120396 0.2794)
			(end -0.12065 0.2794)
			(stroke
				(width 0.1)
				(type default)
			)
			(layer "F.Fab")
		)
		(fp_line
			(start 0.120396 0.3048)
			(end 0.120396 0.2794)
			(stroke
				(width 0.1)
				(type default)
			)
			(layer "F.Fab")
		)
		(fp_line
			(start 0.12065 -0.3048)
			(end 0.67945 -0.3048)
			(stroke
				(width 0.1)
				(type default)
			)
			(layer "F.Fab")
		)
		(fp_line
			(start 0.12065 -0.2794)
			(end 0.12065 -0.3048)
			(stroke
				(width 0.1)
				(type default)
			)
			(layer "F.Fab")
		)
		(fp_line
			(start 0.67945 -0.3048)
			(end 0.67945 0.3048)
			(stroke
				(width 0.1)
				(type default)
			)
			(layer "F.Fab")
		)
		(fp_line
			(start 0.67945 0.3048)
			(end 0.120396 0.3048)
			(stroke
				(width 0.1)
				(type default)
			)
			(layer "F.Fab")
		)
		(pad "1" smd circle
			(at -0.40005 0)
			(size 0 0)
			(layers "F.Cu" "F.Mask" "F.Paste")
			(net "SSD4_PWR_EN_R")
		)
		(pad "2" smd circle
			(at 0.40005 0)
			(size 0 0)
			(layers "F.Cu" "F.Mask" "F.Paste")
			(net "GND")
		)
	)
	(footprint ""
		(layer "F.Cu")
		(at 130.702304 -200.101962 90)
		(property "Reference" "C4494"
			(at 0 0 90)
			(layer "F.SilkS")
			(hide yes)
			(effects
				(font
					(size 1.27 1.27)
				)
			)
		)
		(property "Value" ""
			(at 0 0 90)
			(layer "F.Fab")
			(effects
				(font
					(size 1.27 1.27)
				)
			)
		)
		(duplicate_pad_numbers_are_jumpers no)
		(fp_line
			(start 0.7874 -0.4064)
			(end 0.7874 0.4064)
			(stroke
				(width 0.1524)
				(type default)
			)
			(layer "F.SilkS")
		)
		(fp_line
			(start -0.7874 -0.4064)
			(end 0.7874 -0.4064)
			(stroke
				(width 0.1524)
				(type default)
			)
			(layer "F.SilkS")
		)
		(fp_line
			(start 0.7874 0.4064)
			(end -0.7874 0.4064)
			(stroke
				(width 0.1524)
				(type default)
			)
			(layer "F.SilkS")
		)
		(fp_line
			(start -0.7874 0.4064)
			(end -0.7874 -0.4064)
			(stroke
				(width 0.1524)
				(type default)
			)
			(layer "F.SilkS")
		)
		(fp_line
			(start -0.12065 -0.305054)
			(end -0.12065 -0.2794)
			(stroke
				(width 0.1)
				(type default)
			)
			(layer "F.Fab")
		)
		(fp_line
			(start -0.67945 -0.305054)
			(end -0.12065 -0.305054)
			(stroke
				(width 0.1)
				(type default)
			)
			(layer "F.Fab")
		)
		(fp_line
			(start 0.67945 -0.3048)
			(end 0.67945 0.3048)
			(stroke
				(width 0.1)
				(type default)
			)
			(layer "F.Fab")
		)
		(fp_line
			(start 0.12065 -0.3048)
			(end 0.67945 -0.3048)
			(stroke
				(width 0.1)
				(type default)
			)
			(layer "F.Fab")
		)
		(fp_line
			(start 0.12065 -0.2794)
			(end 0.12065 -0.3048)
			(stroke
				(width 0.1)
				(type default)
			)
			(layer "F.Fab")
		)
		(fp_line
			(start -0.12065 -0.2794)
			(end 0.12065 -0.2794)
			(stroke
				(width 0.1)
				(type default)
			)
			(layer "F.Fab")
		)
		(fp_line
			(start 0.120396 0.2794)
			(end -0.12065 0.2794)
			(stroke
				(width 0.1)
				(type default)
			)
			(layer "F.Fab")
		)
		(fp_line
			(start -0.12065 0.2794)
			(end -0.12065 0.3048)
			(stroke
				(width 0.1)
				(type default)
			)
			(layer "F.Fab")
		)
		(fp_line
			(start 0.67945 0.3048)
			(end 0.120396 0.3048)
			(stroke
				(width 0.1)
				(type default)
			)
			(layer "F.Fab")
		)
		(fp_line
			(start 0.120396 0.3048)
			(end 0.120396 0.2794)
			(stroke
				(width 0.1)
				(type default)
			)
			(layer "F.Fab")
		)
		(fp_line
			(start -0.12065 0.3048)
			(end -0.67945 0.3048)
			(stroke
				(width 0.1)
				(type default)
			)
			(layer "F.Fab")
		)
		(fp_line
			(start -0.67945 0.3048)
			(end -0.67945 -0.305054)
			(stroke
				(width 0.1)
				(type default)
			)
			(layer "F.Fab")
		)
		(pad "1" smd circle
			(at -0.40005 0 90)
			(size 0 0)
			(layers "F.Cu" "F.Mask" "F.Paste")
			(net "NIC7_CLK_EN_R_N")
		)
		(pad "2" smd circle
			(at 0.40005 0 90)
			(size 0 0)
			(layers "F.Cu" "F.Mask" "F.Paste")
			(net "GND")
		)
	)
	(footprint ""
		(layer "F.Cu")
		(at 270.766286 -250.070874 -90)
		(property "Reference" "R1335"
			(at 0 0 270)
			(layer "F.SilkS")
			(hide yes)
			(effects
				(font
					(size 1.27 1.27)
				)
			)
		)
		(property "Value" ""
			(at 0 0 270)
			(layer "F.Fab")
			(effects
				(font
					(size 1.27 1.27)
				)
			)
		)
		(duplicate_pad_numbers_are_jumpers no)
		(fp_line
			(start -0.7874 0.4064)
			(end -0.7874 -0.4064)
			(stroke
				(width 0.1524)
				(type default)
			)
			(layer "F.SilkS")
		)
		(fp_line
			(start 0.7874 0.4064)
			(end -0.7874 0.4064)
			(stroke
				(width 0.1524)
				(type default)
			)
			(layer "F.SilkS")
		)
		(fp_line
			(start -0.7874 -0.4064)
			(end 0.7874 -0.4064)
			(stroke
				(width 0.1524)
				(type default)
			)
			(layer "F.SilkS")
		)
		(fp_line
			(start 0.7874 -0.4064)
			(end 0.7874 0.4064)
			(stroke
				(width 0.1524)
				(type default)
			)
			(layer "F.SilkS")
		)
		(fp_line
			(start -0.67945 0.3048)
			(end -0.67945 -0.305054)
			(stroke
				(width 0.1)
				(type default)
			)
			(layer "F.Fab")
		)
		(fp_line
			(start -0.12065 0.3048)
			(end -0.67945 0.3048)
			(stroke
				(width 0.1)
				(type default)
			)
			(layer "F.Fab")
		)
		(fp_line
			(start 0.120396 0.3048)
			(end 0.120396 0.2794)
			(stroke
				(width 0.1)
				(type default)
			)
			(layer "F.Fab")
		)
		(fp_line
			(start 0.67945 0.3048)
			(end 0.120396 0.3048)
			(stroke
				(width 0.1)
				(type default)
			)
			(layer "F.Fab")
		)
		(fp_line
			(start -0.12065 0.2794)
			(end -0.12065 0.3048)
			(stroke
				(width 0.1)
				(type default)
			)
			(layer "F.Fab")
		)
		(fp_line
			(start 0.120396 0.2794)
			(end -0.12065 0.2794)
			(stroke
				(width 0.1)
				(type default)
			)
			(layer "F.Fab")
		)
		(fp_line
			(start -0.12065 -0.2794)
			(end 0.12065 -0.2794)
			(stroke
				(width 0.1)
				(type default)
			)
			(layer "F.Fab")
		)
		(fp_line
			(start 0.12065 -0.2794)
			(end 0.12065 -0.3048)
			(stroke
				(width 0.1)
				(type default)
			)
			(layer "F.Fab")
		)
		(fp_line
			(start 0.12065 -0.3048)
			(end 0.67945 -0.3048)
			(stroke
				(width 0.1)
				(type default)
			)
			(layer "F.Fab")
		)
		(fp_line
			(start 0.67945 -0.3048)
			(end 0.67945 0.3048)
			(stroke
				(width 0.1)
				(type default)
			)
			(layer "F.Fab")
		)
		(fp_line
			(start -0.67945 -0.305054)
			(end -0.12065 -0.305054)
			(stroke
				(width 0.1)
				(type default)
			)
			(layer "F.Fab")
		)
		(fp_line
			(start -0.12065 -0.305054)
			(end -0.12065 -0.2794)
			(stroke
				(width 0.1)
				(type default)
			)
			(layer "F.Fab")
		)
		(pad "1" smd circle
			(at -0.40005 0 270)
			(size 0 0)
			(layers "F.Cu" "F.Mask" "F.Paste")
			(net "PEX2_DBG_MODE4")
		)
		(pad "2" smd circle
			(at 0.40005 0 270)
			(size 0 0)
			(layers "F.Cu" "F.Mask" "F.Paste")
			(net "P1V8_PEX")
		)
	)
	(footprint ""
		(layer "F.Cu")
		(at 379.633988 -6.868922)
		(property "Reference" "R5822"
			(at 0 0 0)
			(layer "F.SilkS")
			(hide yes)
			(effects
				(font
					(size 1.27 1.27)
				)
			)
		)
		(property "Value" ""
			(at 0 0 0)
			(layer "F.Fab")
			(effects
				(font
					(size 1.27 1.27)
				)
			)
		)
		(duplicate_pad_numbers_are_jumpers no)
		(fp_line
			(start -0.7874 -0.4064)
			(end 0.7874 -0.4064)
			(stroke
				(width 0.1524)
				(type default)
			)
			(layer "F.SilkS")
		)
		(fp_line
			(start -0.7874 0.4064)
			(end -0.7874 -0.4064)
			(stroke
				(width 0.1524)
				(type default)
			)
			(layer "F.SilkS")
		)
		(fp_line
			(start 0.7874 -0.4064)
			(end 0.7874 0.4064)
			(stroke
				(width 0.1524)
				(type default)
			)
			(layer "F.SilkS")
		)
		(fp_line
			(start 0.7874 0.4064)
			(end -0.7874 0.4064)
			(stroke
				(width 0.1524)
				(type default)
			)
			(layer "F.SilkS")
		)
		(fp_line
			(start -0.67945 -0.305054)
			(end -0.12065 -0.305054)
			(stroke
				(width 0.1)
				(type default)
			)
			(layer "F.Fab")
		)
		(fp_line
			(start -0.67945 0.3048)
			(end -0.67945 -0.305054)
			(stroke
				(width 0.1)
				(type default)
			)
			(layer "F.Fab")
		)
		(fp_line
			(start -0.12065 -0.305054)
			(end -0.12065 -0.2794)
			(stroke
				(width 0.1)
				(type default)
			)
			(layer "F.Fab")
		)
		(fp_line
			(start -0.12065 -0.2794)
			(end 0.12065 -0.2794)
			(stroke
				(width 0.1)
				(type default)
			)
			(layer "F.Fab")
		)
		(fp_line
			(start -0.12065 0.2794)
			(end -0.12065 0.3048)
			(stroke
				(width 0.1)
				(type default)
			)
			(layer "F.Fab")
		)
		(fp_line
			(start -0.12065 0.3048)
			(end -0.67945 0.3048)
			(stroke
				(width 0.1)
				(type default)
			)
			(layer "F.Fab")
		)
		(fp_line
			(start 0.120396 0.2794)
			(end -0.12065 0.2794)
			(stroke
				(width 0.1)
				(type default)
			)
			(layer "F.Fab")
		)
		(fp_line
			(start 0.120396 0.3048)
			(end 0.120396 0.2794)
			(stroke
				(width 0.1)
				(type default)
			)
			(layer "F.Fab")
		)
		(fp_line
			(start 0.12065 -0.3048)
			(end 0.67945 -0.3048)
			(stroke
				(width 0.1)
				(type default)
			)
			(layer "F.Fab")
		)
		(fp_line
			(start 0.12065 -0.2794)
			(end 0.12065 -0.3048)
			(stroke
				(width 0.1)
				(type default)
			)
			(layer "F.Fab")
		)
		(fp_line
			(start 0.67945 -0.3048)
			(end 0.67945 0.3048)
			(stroke
				(width 0.1)
				(type default)
			)
			(layer "F.Fab")
		)
		(fp_line
			(start 0.67945 0.3048)
			(end 0.120396 0.3048)
			(stroke
				(width 0.1)
				(type default)
			)
			(layer "F.Fab")
		)
		(pad "1" smd circle
			(at -0.40005 0)
			(size 0 0)
			(layers "F.Cu" "F.Mask" "F.Paste")
			(net "LM75_3_A1")
		)
		(pad "2" smd circle
			(at 0.40005 0)
			(size 0 0)
			(layers "F.Cu" "F.Mask" "F.Paste")
			(net "GND")
		)
	)
	(footprint ""
		(layer "F.Cu")
		(at 295.877742 -116.550186 180)
		(property "Reference" "R262"
			(at 0 0 180)
			(layer "F.SilkS")
			(hide yes)
			(effects
				(font
					(size 1.27 1.27)
				)
			)
		)
		(property "Value" ""
			(at 0 0 180)
			(layer "F.Fab")
			(effects
				(font
					(size 1.27 1.27)
				)
			)
		)
		(duplicate_pad_numbers_are_jumpers no)
		(fp_line
			(start 0.7874 0.4064)
			(end -0.7874 0.4064)
			(stroke
				(width 0.1524)
				(type default)
			)
			(layer "F.SilkS")
		)
		(fp_line
			(start 0.7874 -0.4064)
			(end 0.7874 0.4064)
			(stroke
				(width 0.1524)
				(type default)
			)
			(layer "F.SilkS")
		)
		(fp_line
			(start -0.7874 0.4064)
			(end -0.7874 -0.4064)
			(stroke
				(width 0.1524)
				(type default)
			)
			(layer "F.SilkS")
		)
		(fp_line
			(start -0.7874 -0.4064)
			(end 0.7874 -0.4064)
			(stroke
				(width 0.1524)
				(type default)
			)
			(layer "F.SilkS")
		)
		(fp_line
			(start 0.67945 0.3048)
			(end 0.120396 0.3048)
			(stroke
				(width 0.1)
				(type default)
			)
			(layer "F.Fab")
		)
		(fp_line
			(start 0.67945 -0.3048)
			(end 0.67945 0.3048)
			(stroke
				(width 0.1)
				(type default)
			)
			(layer "F.Fab")
		)
		(fp_line
			(start 0.12065 -0.2794)
			(end 0.12065 -0.3048)
			(stroke
				(width 0.1)
				(type default)
			)
			(layer "F.Fab")
		)
		(fp_line
			(start 0.12065 -0.3048)
			(end 0.67945 -0.3048)
			(stroke
				(width 0.1)
				(type default)
			)
			(layer "F.Fab")
		)
		(fp_line
			(start 0.120396 0.3048)
			(end 0.120396 0.2794)
			(stroke
				(width 0.1)
				(type default)
			)
			(layer "F.Fab")
		)
		(fp_line
			(start 0.120396 0.2794)
			(end -0.12065 0.2794)
			(stroke
				(width 0.1)
				(type default)
			)
			(layer "F.Fab")
		)
		(fp_line
			(start -0.12065 0.3048)
			(end -0.67945 0.3048)
			(stroke
				(width 0.1)
				(type default)
			)
			(layer "F.Fab")
		)
		(fp_line
			(start -0.12065 0.2794)
			(end -0.12065 0.3048)
			(stroke
				(width 0.1)
				(type default)
			)
			(layer "F.Fab")
		)
		(fp_line
			(start -0.12065 -0.2794)
			(end 0.12065 -0.2794)
			(stroke
				(width 0.1)
				(type default)
			)
			(layer "F.Fab")
		)
		(fp_line
			(start -0.12065 -0.305054)
			(end -0.12065 -0.2794)
			(stroke
				(width 0.1)
				(type default)
			)
			(layer "F.Fab")
		)
		(fp_line
			(start -0.67945 0.3048)
			(end -0.67945 -0.305054)
			(stroke
				(width 0.1)
				(type default)
			)
			(layer "F.Fab")
		)
		(fp_line
			(start -0.67945 -0.305054)
			(end -0.12065 -0.305054)
			(stroke
				(width 0.1)
				(type default)
			)
			(layer "F.Fab")
		)
		(pad "1" smd circle
			(at -0.40005 0 180)
			(size 0 0)
			(layers "F.Cu" "F.Mask" "F.Paste")
			(net "PRSNTB2_NIC5_N")
		)
		(pad "2" smd circle
			(at 0.40005 0 180)
			(size 0 0)
			(layers "F.Cu" "F.Mask" "F.Paste")
			(net "P3V3_AUX")
		)
	)
	(footprint ""
		(layer "F.Cu")
		(at 173.966886 -52.543456 180)
		(property "Reference" "PC526"
			(at 0 0 180)
			(layer "F.SilkS")
			(hide yes)
			(effects
				(font
					(size 1.27 1.27)
				)
			)
		)
		(property "Value" ""
			(at 0 0 180)
			(layer "F.Fab")
			(effects
				(font
					(size 1.27 1.27)
				)
			)
		)
		(duplicate_pad_numbers_are_jumpers no)
		(fp_line
			(start 0.7874 0.4064)
			(end -0.7874 0.4064)
			(stroke
				(width 0.1524)
				(type default)
			)
			(layer "F.SilkS")
		)
		(fp_line
			(start 0.7874 -0.4064)
			(end 0.7874 0.4064)
			(stroke
				(width 0.1524)
				(type default)
			)
			(layer "F.SilkS")
		)
		(fp_line
			(start -0.7874 0.4064)
			(end -0.7874 -0.4064)
			(stroke
				(width 0.1524)
				(type default)
			)
			(layer "F.SilkS")
		)
		(fp_line
			(start -0.7874 -0.4064)
			(end 0.7874 -0.4064)
			(stroke
				(width 0.1524)
				(type default)
			)
			(layer "F.SilkS")
		)
		(fp_line
			(start 0.67945 0.3048)
			(end 0.120396 0.3048)
			(stroke
				(width 0.1)
				(type default)
			)
			(layer "F.Fab")
		)
		(fp_line
			(start 0.67945 -0.3048)
			(end 0.67945 0.3048)
			(stroke
				(width 0.1)
				(type default)
			)
			(layer "F.Fab")
		)
		(fp_line
			(start 0.12065 -0.2794)
			(end 0.12065 -0.3048)
			(stroke
				(width 0.1)
				(type default)
			)
			(layer "F.Fab")
		)
		(fp_line
			(start 0.12065 -0.3048)
			(end 0.67945 -0.3048)
			(stroke
				(width 0.1)
				(type default)
			)
			(layer "F.Fab")
		)
		(fp_line
			(start 0.120396 0.3048)
			(end 0.120396 0.2794)
			(stroke
				(width 0.1)
				(type default)
			)
			(layer "F.Fab")
		)
		(fp_line
			(start 0.120396 0.2794)
			(end -0.12065 0.2794)
			(stroke
				(width 0.1)
				(type default)
			)
			(layer "F.Fab")
		)
		(fp_line
			(start -0.12065 0.3048)
			(end -0.67945 0.3048)
			(stroke
				(width 0.1)
				(type default)
			)
			(layer "F.Fab")
		)
		(fp_line
			(start -0.12065 0.2794)
			(end -0.12065 0.3048)
			(stroke
				(width 0.1)
				(type default)
			)
			(layer "F.Fab")
		)
		(fp_line
			(start -0.12065 -0.2794)
			(end 0.12065 -0.2794)
			(stroke
				(width 0.1)
				(type default)
			)
			(layer "F.Fab")
		)
		(fp_line
			(start -0.12065 -0.305054)
			(end -0.12065 -0.2794)
			(stroke
				(width 0.1)
				(type default)
			)
			(layer "F.Fab")
		)
		(fp_line
			(start -0.67945 0.3048)
			(end -0.67945 -0.305054)
			(stroke
				(width 0.1)
				(type default)
			)
			(layer "F.Fab")
		)
		(fp_line
			(start -0.67945 -0.305054)
			(end -0.12065 -0.305054)
			(stroke
				(width 0.1)
				(type default)
			)
			(layer "F.Fab")
		)
		(pad "1" smd circle
			(at -0.40005 0 180)
			(size 0 0)
			(layers "F.Cu" "F.Mask" "F.Paste")
			(net "P3V3_SSD6")
		)
		(pad "2" smd circle
			(at 0.40005 0 180)
			(size 0 0)
			(layers "F.Cu" "F.Mask" "F.Paste")
			(net "GND")
		)
	)
	(footprint ""
		(layer "F.Cu")
		(at 104.609138 -109.432598 -90)
		(property "Reference" "PC607"
			(at 0 0 270)
			(layer "F.SilkS")
			(hide yes)
			(effects
				(font
					(size 1.27 1.27)
				)
			)
		)
		(property "Value" ""
			(at 0 0 270)
			(layer "F.Fab")
			(effects
				(font
					(size 1.27 1.27)
				)
			)
		)
		(duplicate_pad_numbers_are_jumpers no)
		(fp_line
			(start -0.7874 0.4064)
			(end -0.7874 -0.4064)
			(stroke
				(width 0.1524)
				(type default)
			)
			(layer "F.SilkS")
		)
		(fp_line
			(start 0.7874 0.4064)
			(end -0.7874 0.4064)
			(stroke
				(width 0.1524)
				(type default)
			)
			(layer "F.SilkS")
		)
		(fp_line
			(start -0.7874 -0.4064)
			(end 0.7874 -0.4064)
			(stroke
				(width 0.1524)
				(type default)
			)
			(layer "F.SilkS")
		)
		(fp_line
			(start 0.7874 -0.4064)
			(end 0.7874 0.4064)
			(stroke
				(width 0.1524)
				(type default)
			)
			(layer "F.SilkS")
		)
		(fp_line
			(start -0.67945 0.3048)
			(end -0.67945 -0.305054)
			(stroke
				(width 0.1)
				(type default)
			)
			(layer "F.Fab")
		)
		(fp_line
			(start -0.12065 0.3048)
			(end -0.67945 0.3048)
			(stroke
				(width 0.1)
				(type default)
			)
			(layer "F.Fab")
		)
		(fp_line
			(start 0.120396 0.3048)
			(end 0.120396 0.2794)
			(stroke
				(width 0.1)
				(type default)
			)
			(layer "F.Fab")
		)
		(fp_line
			(start 0.67945 0.3048)
			(end 0.120396 0.3048)
			(stroke
				(width 0.1)
				(type default)
			)
			(layer "F.Fab")
		)
		(fp_line
			(start -0.12065 0.2794)
			(end -0.12065 0.3048)
			(stroke
				(width 0.1)
				(type default)
			)
			(layer "F.Fab")
		)
		(fp_line
			(start 0.120396 0.2794)
			(end -0.12065 0.2794)
			(stroke
				(width 0.1)
				(type default)
			)
			(layer "F.Fab")
		)
		(fp_line
			(start -0.12065 -0.2794)
			(end 0.12065 -0.2794)
			(stroke
				(width 0.1)
				(type default)
			)
			(layer "F.Fab")
		)
		(fp_line
			(start 0.12065 -0.2794)
			(end 0.12065 -0.3048)
			(stroke
				(width 0.1)
				(type default)
			)
			(layer "F.Fab")
		)
		(fp_line
			(start 0.12065 -0.3048)
			(end 0.67945 -0.3048)
			(stroke
				(width 0.1)
				(type default)
			)
			(layer "F.Fab")
		)
		(fp_line
			(start 0.67945 -0.3048)
			(end 0.67945 0.3048)
			(stroke
				(width 0.1)
				(type default)
			)
			(layer "F.Fab")
		)
		(fp_line
			(start -0.67945 -0.305054)
			(end -0.12065 -0.305054)
			(stroke
				(width 0.1)
				(type default)
			)
			(layer "F.Fab")
		)
		(fp_line
			(start -0.12065 -0.305054)
			(end -0.12065 -0.2794)
			(stroke
				(width 0.1)
				(type default)
			)
			(layer "F.Fab")
		)
		(pad "1" smd circle
			(at -0.40005 0 270)
			(size 0 0)
			(layers "F.Cu" "F.Mask" "F.Paste")
			(net "P12V_NIC1_R")
		)
		(pad "2" smd circle
			(at 0.40005 0 270)
			(size 0 0)
			(layers "F.Cu" "F.Mask" "F.Paste")
			(net "GND")
		)
	)
	(footprint ""
		(layer "F.Cu")
		(at 32.411416 -283.643832 -90)
		(property "Reference" "R4565"
			(at 0 0 270)
			(layer "F.SilkS")
			(hide yes)
			(effects
				(font
					(size 1.27 1.27)
				)
			)
		)
		(property "Value" ""
			(at 0 0 270)
			(layer "F.Fab")
			(effects
				(font
					(size 1.27 1.27)
				)
			)
		)
		(duplicate_pad_numbers_are_jumpers no)
		(fp_line
			(start -0.7874 0.4064)
			(end -0.7874 -0.4064)
			(stroke
				(width 0.1524)
				(type default)
			)
			(layer "F.SilkS")
		)
		(fp_line
			(start 0.7874 0.4064)
			(end -0.7874 0.4064)
			(stroke
				(width 0.1524)
				(type default)
			)
			(layer "F.SilkS")
		)
		(fp_line
			(start -0.7874 -0.4064)
			(end 0.7874 -0.4064)
			(stroke
				(width 0.1524)
				(type default)
			)
			(layer "F.SilkS")
		)
		(fp_line
			(start 0.7874 -0.4064)
			(end 0.7874 0.4064)
			(stroke
				(width 0.1524)
				(type default)
			)
			(layer "F.SilkS")
		)
		(fp_line
			(start -0.67945 0.3048)
			(end -0.67945 -0.305054)
			(stroke
				(width 0.1)
				(type default)
			)
			(layer "F.Fab")
		)
		(fp_line
			(start -0.12065 0.3048)
			(end -0.67945 0.3048)
			(stroke
				(width 0.1)
				(type default)
			)
			(layer "F.Fab")
		)
		(fp_line
			(start 0.120396 0.3048)
			(end 0.120396 0.2794)
			(stroke
				(width 0.1)
				(type default)
			)
			(layer "F.Fab")
		)
		(fp_line
			(start 0.67945 0.3048)
			(end 0.120396 0.3048)
			(stroke
				(width 0.1)
				(type default)
			)
			(layer "F.Fab")
		)
		(fp_line
			(start -0.12065 0.2794)
			(end -0.12065 0.3048)
			(stroke
				(width 0.1)
				(type default)
			)
			(layer "F.Fab")
		)
		(fp_line
			(start 0.120396 0.2794)
			(end -0.12065 0.2794)
			(stroke
				(width 0.1)
				(type default)
			)
			(layer "F.Fab")
		)
		(fp_line
			(start -0.12065 -0.2794)
			(end 0.12065 -0.2794)
			(stroke
				(width 0.1)
				(type default)
			)
			(layer "F.Fab")
		)
		(fp_line
			(start 0.12065 -0.2794)
			(end 0.12065 -0.3048)
			(stroke
				(width 0.1)
				(type default)
			)
			(layer "F.Fab")
		)
		(fp_line
			(start 0.12065 -0.3048)
			(end 0.67945 -0.3048)
			(stroke
				(width 0.1)
				(type default)
			)
			(layer "F.Fab")
		)
		(fp_line
			(start 0.67945 -0.3048)
			(end 0.67945 0.3048)
			(stroke
				(width 0.1)
				(type default)
			)
			(layer "F.Fab")
		)
		(fp_line
			(start -0.67945 -0.305054)
			(end -0.12065 -0.305054)
			(stroke
				(width 0.1)
				(type default)
			)
			(layer "F.Fab")
		)
		(fp_line
			(start -0.12065 -0.305054)
			(end -0.12065 -0.2794)
			(stroke
				(width 0.1)
				(type default)
			)
			(layer "F.Fab")
		)
		(pad "1" smd circle
			(at -0.40005 0 270)
			(size 0 0)
			(layers "F.Cu" "F.Mask" "F.Paste")
			(net "PCEPLL7_VDDA18_PEX0")
		)
		(pad "2" smd circle
			(at 0.40005 0 270)
			(size 0 0)
			(layers "F.Cu" "F.Mask" "F.Paste")
			(net "PCEPLL7_VDDA18_PEX0_R")
		)
	)
	(footprint ""
		(layer "F.Cu")
		(at 251.446792 -37.47516)
		(property "Reference" "R6087"
			(at 0 0 0)
			(layer "F.SilkS")
			(hide yes)
			(effects
				(font
					(size 1.27 1.27)
				)
			)
		)
		(property "Value" ""
			(at 0 0 0)
			(layer "F.Fab")
			(effects
				(font
					(size 1.27 1.27)
				)
			)
		)
		(duplicate_pad_numbers_are_jumpers no)
		(fp_line
			(start -0.7874 -0.4064)
			(end 0.7874 -0.4064)
			(stroke
				(width 0.1524)
				(type default)
			)
			(layer "F.SilkS")
		)
		(fp_line
			(start -0.7874 0.4064)
			(end -0.7874 -0.4064)
			(stroke
				(width 0.1524)
				(type default)
			)
			(layer "F.SilkS")
		)
		(fp_line
			(start 0.7874 -0.4064)
			(end 0.7874 0.4064)
			(stroke
				(width 0.1524)
				(type default)
			)
			(layer "F.SilkS")
		)
		(fp_line
			(start 0.7874 0.4064)
			(end -0.7874 0.4064)
			(stroke
				(width 0.1524)
				(type default)
			)
			(layer "F.SilkS")
		)
		(fp_line
			(start -0.67945 -0.305054)
			(end -0.12065 -0.305054)
			(stroke
				(width 0.1)
				(type default)
			)
			(layer "F.Fab")
		)
		(fp_line
			(start -0.67945 0.3048)
			(end -0.67945 -0.305054)
			(stroke
				(width 0.1)
				(type default)
			)
			(layer "F.Fab")
		)
		(fp_line
			(start -0.12065 -0.305054)
			(end -0.12065 -0.2794)
			(stroke
				(width 0.1)
				(type default)
			)
			(layer "F.Fab")
		)
		(fp_line
			(start -0.12065 -0.2794)
			(end 0.12065 -0.2794)
			(stroke
				(width 0.1)
				(type default)
			)
			(layer "F.Fab")
		)
		(fp_line
			(start -0.12065 0.2794)
			(end -0.12065 0.3048)
			(stroke
				(width 0.1)
				(type default)
			)
			(layer "F.Fab")
		)
		(fp_line
			(start -0.12065 0.3048)
			(end -0.67945 0.3048)
			(stroke
				(width 0.1)
				(type default)
			)
			(layer "F.Fab")
		)
		(fp_line
			(start 0.120396 0.2794)
			(end -0.12065 0.2794)
			(stroke
				(width 0.1)
				(type default)
			)
			(layer "F.Fab")
		)
		(fp_line
			(start 0.120396 0.3048)
			(end 0.120396 0.2794)
			(stroke
				(width 0.1)
				(type default)
			)
			(layer "F.Fab")
		)
		(fp_line
			(start 0.12065 -0.3048)
			(end 0.67945 -0.3048)
			(stroke
				(width 0.1)
				(type default)
			)
			(layer "F.Fab")
		)
		(fp_line
			(start 0.12065 -0.2794)
			(end 0.12065 -0.3048)
			(stroke
				(width 0.1)
				(type default)
			)
			(layer "F.Fab")
		)
		(fp_line
			(start 0.67945 -0.3048)
			(end 0.67945 0.3048)
			(stroke
				(width 0.1)
				(type default)
			)
			(layer "F.Fab")
		)
		(fp_line
			(start 0.67945 0.3048)
			(end 0.120396 0.3048)
			(stroke
				(width 0.1)
				(type default)
			)
			(layer "F.Fab")
		)
		(pad "1" smd circle
			(at -0.40005 0)
			(size 0 0)
			(layers "F.Cu" "F.Mask" "F.Paste")
			(net "P3V3_SSD9")
		)
		(pad "2" smd circle
			(at 0.40005 0)
			(size 0 0)
			(layers "F.Cu" "F.Mask" "F.Paste")
			(net "P3V3_SSD9_PG_G1")
		)
	)
	(footprint ""
		(layer "F.Cu")
		(at 268.402816 -92.526104 180)
		(property "Reference" "R1064"
			(at 0 0 180)
			(layer "F.SilkS")
			(hide yes)
			(effects
				(font
					(size 1.27 1.27)
				)
			)
		)
		(property "Value" ""
			(at 0 0 180)
			(layer "F.Fab")
			(effects
				(font
					(size 1.27 1.27)
				)
			)
		)
		(duplicate_pad_numbers_are_jumpers no)
		(fp_line
			(start 0.7874 0.4064)
			(end -0.7874 0.4064)
			(stroke
				(width 0.1524)
				(type default)
			)
			(layer "F.SilkS")
		)
		(fp_line
			(start 0.7874 -0.4064)
			(end 0.7874 0.4064)
			(stroke
				(width 0.1524)
				(type default)
			)
			(layer "F.SilkS")
		)
		(fp_line
			(start -0.7874 0.4064)
			(end -0.7874 -0.4064)
			(stroke
				(width 0.1524)
				(type default)
			)
			(layer "F.SilkS")
		)
		(fp_line
			(start -0.7874 -0.4064)
			(end 0.7874 -0.4064)
			(stroke
				(width 0.1524)
				(type default)
			)
			(layer "F.SilkS")
		)
		(fp_line
			(start 0.67945 0.3048)
			(end 0.120396 0.3048)
			(stroke
				(width 0.1)
				(type default)
			)
			(layer "F.Fab")
		)
		(fp_line
			(start 0.67945 -0.3048)
			(end 0.67945 0.3048)
			(stroke
				(width 0.1)
				(type default)
			)
			(layer "F.Fab")
		)
		(fp_line
			(start 0.12065 -0.2794)
			(end 0.12065 -0.3048)
			(stroke
				(width 0.1)
				(type default)
			)
			(layer "F.Fab")
		)
		(fp_line
			(start 0.12065 -0.3048)
			(end 0.67945 -0.3048)
			(stroke
				(width 0.1)
				(type default)
			)
			(layer "F.Fab")
		)
		(fp_line
			(start 0.120396 0.3048)
			(end 0.120396 0.2794)
			(stroke
				(width 0.1)
				(type default)
			)
			(layer "F.Fab")
		)
		(fp_line
			(start 0.120396 0.2794)
			(end -0.12065 0.2794)
			(stroke
				(width 0.1)
				(type default)
			)
			(layer "F.Fab")
		)
		(fp_line
			(start -0.12065 0.3048)
			(end -0.67945 0.3048)
			(stroke
				(width 0.1)
				(type default)
			)
			(layer "F.Fab")
		)
		(fp_line
			(start -0.12065 0.2794)
			(end -0.12065 0.3048)
			(stroke
				(width 0.1)
				(type default)
			)
			(layer "F.Fab")
		)
		(fp_line
			(start -0.12065 -0.2794)
			(end 0.12065 -0.2794)
			(stroke
				(width 0.1)
				(type default)
			)
			(layer "F.Fab")
		)
		(fp_line
			(start -0.12065 -0.305054)
			(end -0.12065 -0.2794)
			(stroke
				(width 0.1)
				(type default)
			)
			(layer "F.Fab")
		)
		(fp_line
			(start -0.67945 0.3048)
			(end -0.67945 -0.305054)
			(stroke
				(width 0.1)
				(type default)
			)
			(layer "F.Fab")
		)
		(fp_line
			(start -0.67945 -0.305054)
			(end -0.12065 -0.305054)
			(stroke
				(width 0.1)
				(type default)
			)
			(layer "F.Fab")
		)
		(pad "1" smd circle
			(at -0.40005 0 180)
			(size 0 0)
			(layers "F.Cu" "F.Mask" "F.Paste")
			(net "GND")
		)
		(pad "2" smd circle
			(at 0.40005 0 180)
			(size 0 0)
			(layers "F.Cu" "F.Mask" "F.Paste")
			(net "PU_CK440_SHFT_LD_N")
		)
	)
	(footprint ""
		(layer "F.Cu")
		(at 121.163588 -356.244906 90)
		(property "Reference" "C366"
			(at 0 0 90)
			(layer "F.SilkS")
			(hide yes)
			(effects
				(font
					(size 1.27 1.27)
				)
			)
		)
		(property "Value" ""
			(at 0 0 90)
			(layer "F.Fab")
			(effects
				(font
					(size 1.27 1.27)
				)
			)
		)
		(duplicate_pad_numbers_are_jumpers no)
		(fp_line
			(start 0.299974 -0.150114)
			(end 0.299974 0.150114)
			(stroke
				(width 0.1)
				(type default)
			)
			(layer "F.Fab")
		)
		(fp_line
			(start -0.299974 -0.150114)
			(end 0.299974 -0.150114)
			(stroke
				(width 0.1)
				(type default)
			)
			(layer "F.Fab")
		)
		(fp_line
			(start 0.299974 0.150114)
			(end -0.299974 0.150114)
			(stroke
				(width 0.1)
				(type default)
			)
			(layer "F.Fab")
		)
		(fp_line
			(start -0.299974 0.150114)
			(end -0.299974 -0.150114)
			(stroke
				(width 0.1)
				(type default)
			)
			(layer "F.Fab")
		)
		(pad "1" smd rect
			(at -0.2667 0 90)
			(size 0.3048 0.381)
			(layers "F.Cu" "F.Mask" "F.Paste")
			(net "P5E_PEX1_STN6_TX_DP<98>")
		)
		(pad "2" smd rect
			(at 0.2667 0 90)
			(size 0.3048 0.381)
			(layers "F.Cu" "F.Mask" "F.Paste")
			(net "P5E_PEX1_STN6_TX_C_DP<98>")
		)
	)
	(footprint ""
		(layer "F.Cu")
		(at 437.798464 -297.46448)
		(property "Reference" "R4006"
			(at 0 0 0)
			(layer "F.SilkS")
			(hide yes)
			(effects
				(font
					(size 1.27 1.27)
				)
			)
		)
		(property "Value" ""
			(at 0 0 0)
			(layer "F.Fab")
			(effects
				(font
					(size 1.27 1.27)
				)
			)
		)
		(duplicate_pad_numbers_are_jumpers no)
		(fp_line
			(start -0.7874 -0.4064)
			(end 0.7874 -0.4064)
			(stroke
				(width 0.1524)
				(type default)
			)
			(layer "F.SilkS")
		)
		(fp_line
			(start -0.7874 0.4064)
			(end -0.7874 -0.4064)
			(stroke
				(width 0.1524)
				(type default)
			)
			(layer "F.SilkS")
		)
		(fp_line
			(start 0.7874 -0.4064)
			(end 0.7874 0.4064)
			(stroke
				(width 0.1524)
				(type default)
			)
			(layer "F.SilkS")
		)
		(fp_line
			(start 0.7874 0.4064)
			(end -0.7874 0.4064)
			(stroke
				(width 0.1524)
				(type default)
			)
			(layer "F.SilkS")
		)
		(fp_line
			(start -0.67945 -0.305054)
			(end -0.12065 -0.305054)
			(stroke
				(width 0.1)
				(type default)
			)
			(layer "F.Fab")
		)
		(fp_line
			(start -0.67945 0.3048)
			(end -0.67945 -0.305054)
			(stroke
				(width 0.1)
				(type default)
			)
			(layer "F.Fab")
		)
		(fp_line
			(start -0.12065 -0.305054)
			(end -0.12065 -0.2794)
			(stroke
				(width 0.1)
				(type default)
			)
			(layer "F.Fab")
		)
		(fp_line
			(start -0.12065 -0.2794)
			(end 0.12065 -0.2794)
			(stroke
				(width 0.1)
				(type default)
			)
			(layer "F.Fab")
		)
		(fp_line
			(start -0.12065 0.2794)
			(end -0.12065 0.3048)
			(stroke
				(width 0.1)
				(type default)
			)
			(layer "F.Fab")
		)
		(fp_line
			(start -0.12065 0.3048)
			(end -0.67945 0.3048)
			(stroke
				(width 0.1)
				(type default)
			)
			(layer "F.Fab")
		)
		(fp_line
			(start 0.120396 0.2794)
			(end -0.12065 0.2794)
			(stroke
				(width 0.1)
				(type default)
			)
			(layer "F.Fab")
		)
		(fp_line
			(start 0.120396 0.3048)
			(end 0.120396 0.2794)
			(stroke
				(width 0.1)
				(type default)
			)
			(layer "F.Fab")
		)
		(fp_line
			(start 0.12065 -0.3048)
			(end 0.67945 -0.3048)
			(stroke
				(width 0.1)
				(type default)
			)
			(layer "F.Fab")
		)
		(fp_line
			(start 0.12065 -0.2794)
			(end 0.12065 -0.3048)
			(stroke
				(width 0.1)
				(type default)
			)
			(layer "F.Fab")
		)
		(fp_line
			(start 0.67945 -0.3048)
			(end 0.67945 0.3048)
			(stroke
				(width 0.1)
				(type default)
			)
			(layer "F.Fab")
		)
		(fp_line
			(start 0.67945 0.3048)
			(end 0.120396 0.3048)
			(stroke
				(width 0.1)
				(type default)
			)
			(layer "F.Fab")
		)
		(pad "1" smd circle
			(at -0.40005 0)
			(size 0 0)
			(layers "F.Cu" "F.Mask" "F.Paste")
			(net "SMB_PEX3_HOST_LS_SDA")
		)
		(pad "2" smd circle
			(at 0.40005 0)
			(size 0 0)
			(layers "F.Cu" "F.Mask" "F.Paste")
			(net "I2C_PEX3_HOST_R_SDA")
		)
	)
	(footprint ""
		(layer "F.Cu")
		(at 361.188 -181.102 180)
		(property "Reference" "R4718"
			(at 0 0 180)
			(layer "F.SilkS")
			(hide yes)
			(effects
				(font
					(size 1.27 1.27)
				)
			)
		)
		(property "Value" ""
			(at 0 0 180)
			(layer "F.Fab")
			(effects
				(font
					(size 1.27 1.27)
				)
			)
		)
		(duplicate_pad_numbers_are_jumpers no)
		(fp_line
			(start 0.7874 0.4064)
			(end -0.7874 0.4064)
			(stroke
				(width 0.1524)
				(type default)
			)
			(layer "F.SilkS")
		)
		(fp_line
			(start 0.7874 -0.4064)
			(end 0.7874 0.4064)
			(stroke
				(width 0.1524)
				(type default)
			)
			(layer "F.SilkS")
		)
		(fp_line
			(start -0.7874 0.4064)
			(end -0.7874 -0.4064)
			(stroke
				(width 0.1524)
				(type default)
			)
			(layer "F.SilkS")
		)
		(fp_line
			(start -0.7874 -0.4064)
			(end 0.7874 -0.4064)
			(stroke
				(width 0.1524)
				(type default)
			)
			(layer "F.SilkS")
		)
		(fp_line
			(start 0.67945 0.3048)
			(end 0.120396 0.3048)
			(stroke
				(width 0.1)
				(type default)
			)
			(layer "F.Fab")
		)
		(fp_line
			(start 0.67945 -0.3048)
			(end 0.67945 0.3048)
			(stroke
				(width 0.1)
				(type default)
			)
			(layer "F.Fab")
		)
		(fp_line
			(start 0.12065 -0.2794)
			(end 0.12065 -0.3048)
			(stroke
				(width 0.1)
				(type default)
			)
			(layer "F.Fab")
		)
		(fp_line
			(start 0.12065 -0.3048)
			(end 0.67945 -0.3048)
			(stroke
				(width 0.1)
				(type default)
			)
			(layer "F.Fab")
		)
		(fp_line
			(start 0.120396 0.3048)
			(end 0.120396 0.2794)
			(stroke
				(width 0.1)
				(type default)
			)
			(layer "F.Fab")
		)
		(fp_line
			(start 0.120396 0.2794)
			(end -0.12065 0.2794)
			(stroke
				(width 0.1)
				(type default)
			)
			(layer "F.Fab")
		)
		(fp_line
			(start -0.12065 0.3048)
			(end -0.67945 0.3048)
			(stroke
				(width 0.1)
				(type default)
			)
			(layer "F.Fab")
		)
		(fp_line
			(start -0.12065 0.2794)
			(end -0.12065 0.3048)
			(stroke
				(width 0.1)
				(type default)
			)
			(layer "F.Fab")
		)
		(fp_line
			(start -0.12065 -0.2794)
			(end 0.12065 -0.2794)
			(stroke
				(width 0.1)
				(type default)
			)
			(layer "F.Fab")
		)
		(fp_line
			(start -0.12065 -0.305054)
			(end -0.12065 -0.2794)
			(stroke
				(width 0.1)
				(type default)
			)
			(layer "F.Fab")
		)
		(fp_line
			(start -0.67945 0.3048)
			(end -0.67945 -0.305054)
			(stroke
				(width 0.1)
				(type default)
			)
			(layer "F.Fab")
		)
		(fp_line
			(start -0.67945 -0.305054)
			(end -0.12065 -0.305054)
			(stroke
				(width 0.1)
				(type default)
			)
			(layer "F.Fab")
		)
		(pad "1" smd circle
			(at -0.40005 0 180)
			(size 0 0)
			(layers "F.Cu" "F.Mask" "F.Paste")
			(net "GND")
		)
		(pad "2" smd circle
			(at 0.40005 0 180)
			(size 0 0)
			(layers "F.Cu" "F.Mask" "F.Paste")
			(net "PCA9555_1_PEX1_A1")
		)
	)
	(footprint ""
		(layer "F.Cu")
		(at 114.582194 -37.025072)
		(property "Reference" "R5669"
			(at 0 0 0)
			(layer "F.SilkS")
			(hide yes)
			(effects
				(font
					(size 1.27 1.27)
				)
			)
		)
		(property "Value" ""
			(at 0 0 0)
			(layer "F.Fab")
			(effects
				(font
					(size 1.27 1.27)
				)
			)
		)
		(duplicate_pad_numbers_are_jumpers no)
		(fp_line
			(start -0.7874 -0.4064)
			(end 0.7874 -0.4064)
			(stroke
				(width 0.1524)
				(type default)
			)
			(layer "F.SilkS")
		)
		(fp_line
			(start -0.7874 0.4064)
			(end -0.7874 -0.4064)
			(stroke
				(width 0.1524)
				(type default)
			)
			(layer "F.SilkS")
		)
		(fp_line
			(start 0.7874 -0.4064)
			(end 0.7874 0.4064)
			(stroke
				(width 0.1524)
				(type default)
			)
			(layer "F.SilkS")
		)
		(fp_line
			(start 0.7874 0.4064)
			(end -0.7874 0.4064)
			(stroke
				(width 0.1524)
				(type default)
			)
			(layer "F.SilkS")
		)
		(fp_line
			(start -0.67945 -0.305054)
			(end -0.12065 -0.305054)
			(stroke
				(width 0.1)
				(type default)
			)
			(layer "F.Fab")
		)
		(fp_line
			(start -0.67945 0.3048)
			(end -0.67945 -0.305054)
			(stroke
				(width 0.1)
				(type default)
			)
			(layer "F.Fab")
		)
		(fp_line
			(start -0.12065 -0.305054)
			(end -0.12065 -0.2794)
			(stroke
				(width 0.1)
				(type default)
			)
			(layer "F.Fab")
		)
		(fp_line
			(start -0.12065 -0.2794)
			(end 0.12065 -0.2794)
			(stroke
				(width 0.1)
				(type default)
			)
			(layer "F.Fab")
		)
		(fp_line
			(start -0.12065 0.2794)
			(end -0.12065 0.3048)
			(stroke
				(width 0.1)
				(type default)
			)
			(layer "F.Fab")
		)
		(fp_line
			(start -0.12065 0.3048)
			(end -0.67945 0.3048)
			(stroke
				(width 0.1)
				(type default)
			)
			(layer "F.Fab")
		)
		(fp_line
			(start 0.120396 0.2794)
			(end -0.12065 0.2794)
			(stroke
				(width 0.1)
				(type default)
			)
			(layer "F.Fab")
		)
		(fp_line
			(start 0.120396 0.3048)
			(end 0.120396 0.2794)
			(stroke
				(width 0.1)
				(type default)
			)
			(layer "F.Fab")
		)
		(fp_line
			(start 0.12065 -0.3048)
			(end 0.67945 -0.3048)
			(stroke
				(width 0.1)
				(type default)
			)
			(layer "F.Fab")
		)
		(fp_line
			(start 0.12065 -0.2794)
			(end 0.12065 -0.3048)
			(stroke
				(width 0.1)
				(type default)
			)
			(layer "F.Fab")
		)
		(fp_line
			(start 0.67945 -0.3048)
			(end 0.67945 0.3048)
			(stroke
				(width 0.1)
				(type default)
			)
			(layer "F.Fab")
		)
		(fp_line
			(start 0.67945 0.3048)
			(end 0.120396 0.3048)
			(stroke
				(width 0.1)
				(type default)
			)
			(layer "F.Fab")
		)
		(pad "1" smd circle
			(at -0.40005 0)
			(size 0 0)
			(layers "F.Cu" "F.Mask" "F.Paste")
			(net "RST_SMB_SSD_R_N")
		)
		(pad "2" smd circle
			(at 0.40005 0)
			(size 0 0)
			(layers "F.Cu" "F.Mask" "F.Paste")
			(net "RST_SMB_SSD4_N")
		)
	)
	(footprint ""
		(layer "F.Cu")
		(at 138.985244 -91.242642 180)
		(property "Reference" "R1565"
			(at 0 0 180)
			(layer "F.SilkS")
			(hide yes)
			(effects
				(font
					(size 1.27 1.27)
				)
			)
		)
		(property "Value" ""
			(at 0 0 180)
			(layer "F.Fab")
			(effects
				(font
					(size 1.27 1.27)
				)
			)
		)
		(duplicate_pad_numbers_are_jumpers no)
		(fp_line
			(start 0.7874 0.4064)
			(end -0.7874 0.4064)
			(stroke
				(width 0.1524)
				(type default)
			)
			(layer "F.SilkS")
		)
		(fp_line
			(start 0.7874 -0.4064)
			(end 0.7874 0.4064)
			(stroke
				(width 0.1524)
				(type default)
			)
			(layer "F.SilkS")
		)
		(fp_line
			(start -0.7874 0.4064)
			(end -0.7874 -0.4064)
			(stroke
				(width 0.1524)
				(type default)
			)
			(layer "F.SilkS")
		)
		(fp_line
			(start -0.7874 -0.4064)
			(end 0.7874 -0.4064)
			(stroke
				(width 0.1524)
				(type default)
			)
			(layer "F.SilkS")
		)
		(fp_line
			(start 0.67945 0.3048)
			(end 0.120396 0.3048)
			(stroke
				(width 0.1)
				(type default)
			)
			(layer "F.Fab")
		)
		(fp_line
			(start 0.67945 -0.3048)
			(end 0.67945 0.3048)
			(stroke
				(width 0.1)
				(type default)
			)
			(layer "F.Fab")
		)
		(fp_line
			(start 0.12065 -0.2794)
			(end 0.12065 -0.3048)
			(stroke
				(width 0.1)
				(type default)
			)
			(layer "F.Fab")
		)
		(fp_line
			(start 0.12065 -0.3048)
			(end 0.67945 -0.3048)
			(stroke
				(width 0.1)
				(type default)
			)
			(layer "F.Fab")
		)
		(fp_line
			(start 0.120396 0.3048)
			(end 0.120396 0.2794)
			(stroke
				(width 0.1)
				(type default)
			)
			(layer "F.Fab")
		)
		(fp_line
			(start 0.120396 0.2794)
			(end -0.12065 0.2794)
			(stroke
				(width 0.1)
				(type default)
			)
			(layer "F.Fab")
		)
		(fp_line
			(start -0.12065 0.3048)
			(end -0.67945 0.3048)
			(stroke
				(width 0.1)
				(type default)
			)
			(layer "F.Fab")
		)
		(fp_line
			(start -0.12065 0.2794)
			(end -0.12065 0.3048)
			(stroke
				(width 0.1)
				(type default)
			)
			(layer "F.Fab")
		)
		(fp_line
			(start -0.12065 -0.2794)
			(end 0.12065 -0.2794)
			(stroke
				(width 0.1)
				(type default)
			)
			(layer "F.Fab")
		)
		(fp_line
			(start -0.12065 -0.305054)
			(end -0.12065 -0.2794)
			(stroke
				(width 0.1)
				(type default)
			)
			(layer "F.Fab")
		)
		(fp_line
			(start -0.67945 0.3048)
			(end -0.67945 -0.305054)
			(stroke
				(width 0.1)
				(type default)
			)
			(layer "F.Fab")
		)
		(fp_line
			(start -0.67945 -0.305054)
			(end -0.12065 -0.305054)
			(stroke
				(width 0.1)
				(type default)
			)
			(layer "F.Fab")
		)
		(pad "1" smd circle
			(at -0.40005 0 180)
			(size 0 0)
			(layers "F.Cu" "F.Mask" "F.Paste")
			(net "P3V3_AUX")
		)
		(pad "2" smd circle
			(at 0.40005 0 180)
			(size 0 0)
			(layers "F.Cu" "F.Mask" "F.Paste")
			(net "SMB_BIC_I2C9_MUX0_SSD5_R_SCL")
		)
	)
	(footprint ""
		(layer "F.Cu")
		(at 129.310384 -192.35166 -90)
		(property "Reference" "R6676"
			(at 0 0 270)
			(layer "F.SilkS")
			(hide yes)
			(effects
				(font
					(size 1.27 1.27)
				)
			)
		)
		(property "Value" ""
			(at 0 0 270)
			(layer "F.Fab")
			(effects
				(font
					(size 1.27 1.27)
				)
			)
		)
		(duplicate_pad_numbers_are_jumpers no)
		(fp_line
			(start -0.7874 0.4064)
			(end -0.7874 -0.4064)
			(stroke
				(width 0.1524)
				(type default)
			)
			(layer "F.SilkS")
		)
		(fp_line
			(start 0.7874 0.4064)
			(end -0.7874 0.4064)
			(stroke
				(width 0.1524)
				(type default)
			)
			(layer "F.SilkS")
		)
		(fp_line
			(start -0.7874 -0.4064)
			(end 0.7874 -0.4064)
			(stroke
				(width 0.1524)
				(type default)
			)
			(layer "F.SilkS")
		)
		(fp_line
			(start 0.7874 -0.4064)
			(end 0.7874 0.4064)
			(stroke
				(width 0.1524)
				(type default)
			)
			(layer "F.SilkS")
		)
		(fp_line
			(start -0.67945 0.3048)
			(end -0.67945 -0.305054)
			(stroke
				(width 0.1)
				(type default)
			)
			(layer "F.Fab")
		)
		(fp_line
			(start -0.12065 0.3048)
			(end -0.67945 0.3048)
			(stroke
				(width 0.1)
				(type default)
			)
			(layer "F.Fab")
		)
		(fp_line
			(start 0.120396 0.3048)
			(end 0.120396 0.2794)
			(stroke
				(width 0.1)
				(type default)
			)
			(layer "F.Fab")
		)
		(fp_line
			(start 0.67945 0.3048)
			(end 0.120396 0.3048)
			(stroke
				(width 0.1)
				(type default)
			)
			(layer "F.Fab")
		)
		(fp_line
			(start -0.12065 0.2794)
			(end -0.12065 0.3048)
			(stroke
				(width 0.1)
				(type default)
			)
			(layer "F.Fab")
		)
		(fp_line
			(start 0.120396 0.2794)
			(end -0.12065 0.2794)
			(stroke
				(width 0.1)
				(type default)
			)
			(layer "F.Fab")
		)
		(fp_line
			(start -0.12065 -0.2794)
			(end 0.12065 -0.2794)
			(stroke
				(width 0.1)
				(type default)
			)
			(layer "F.Fab")
		)
		(fp_line
			(start 0.12065 -0.2794)
			(end 0.12065 -0.3048)
			(stroke
				(width 0.1)
				(type default)
			)
			(layer "F.Fab")
		)
		(fp_line
			(start 0.12065 -0.3048)
			(end 0.67945 -0.3048)
			(stroke
				(width 0.1)
				(type default)
			)
			(layer "F.Fab")
		)
		(fp_line
			(start 0.67945 -0.3048)
			(end 0.67945 0.3048)
			(stroke
				(width 0.1)
				(type default)
			)
			(layer "F.Fab")
		)
		(fp_line
			(start -0.67945 -0.305054)
			(end -0.12065 -0.305054)
			(stroke
				(width 0.1)
				(type default)
			)
			(layer "F.Fab")
		)
		(fp_line
			(start -0.12065 -0.305054)
			(end -0.12065 -0.2794)
			(stroke
				(width 0.1)
				(type default)
			)
			(layer "F.Fab")
		)
		(pad "1" smd circle
			(at -0.40005 0 270)
			(size 0 0)
			(layers "F.Cu" "F.Mask" "F.Paste")
			(net "NIC7_CLK_EN_BUF_R_N")
		)
		(pad "2" smd circle
			(at 0.40005 0 270)
			(size 0 0)
			(layers "F.Cu" "F.Mask" "F.Paste")
			(net "P3V3")
		)
	)
	(footprint ""
		(layer "F.Cu")
		(at 359.156 -193.294)
		(property "Reference" "R4618"
			(at 0 0 0)
			(layer "F.SilkS")
			(hide yes)
			(effects
				(font
					(size 1.27 1.27)
				)
			)
		)
		(property "Value" ""
			(at 0 0 0)
			(layer "F.Fab")
			(effects
				(font
					(size 1.27 1.27)
				)
			)
		)
		(duplicate_pad_numbers_are_jumpers no)
		(fp_line
			(start -0.7874 -0.4064)
			(end 0.7874 -0.4064)
			(stroke
				(width 0.1524)
				(type default)
			)
			(layer "F.SilkS")
		)
		(fp_line
			(start -0.7874 0.4064)
			(end -0.7874 -0.4064)
			(stroke
				(width 0.1524)
				(type default)
			)
			(layer "F.SilkS")
		)
		(fp_line
			(start 0.7874 -0.4064)
			(end 0.7874 0.4064)
			(stroke
				(width 0.1524)
				(type default)
			)
			(layer "F.SilkS")
		)
		(fp_line
			(start 0.7874 0.4064)
			(end -0.7874 0.4064)
			(stroke
				(width 0.1524)
				(type default)
			)
			(layer "F.SilkS")
		)
		(fp_line
			(start -0.67945 -0.305054)
			(end -0.12065 -0.305054)
			(stroke
				(width 0.1)
				(type default)
			)
			(layer "F.Fab")
		)
		(fp_line
			(start -0.67945 0.3048)
			(end -0.67945 -0.305054)
			(stroke
				(width 0.1)
				(type default)
			)
			(layer "F.Fab")
		)
		(fp_line
			(start -0.12065 -0.305054)
			(end -0.12065 -0.2794)
			(stroke
				(width 0.1)
				(type default)
			)
			(layer "F.Fab")
		)
		(fp_line
			(start -0.12065 -0.2794)
			(end 0.12065 -0.2794)
			(stroke
				(width 0.1)
				(type default)
			)
			(layer "F.Fab")
		)
		(fp_line
			(start -0.12065 0.2794)
			(end -0.12065 0.3048)
			(stroke
				(width 0.1)
				(type default)
			)
			(layer "F.Fab")
		)
		(fp_line
			(start -0.12065 0.3048)
			(end -0.67945 0.3048)
			(stroke
				(width 0.1)
				(type default)
			)
			(layer "F.Fab")
		)
		(fp_line
			(start 0.120396 0.2794)
			(end -0.12065 0.2794)
			(stroke
				(width 0.1)
				(type default)
			)
			(layer "F.Fab")
		)
		(fp_line
			(start 0.120396 0.3048)
			(end 0.120396 0.2794)
			(stroke
				(width 0.1)
				(type default)
			)
			(layer "F.Fab")
		)
		(fp_line
			(start 0.12065 -0.3048)
			(end 0.67945 -0.3048)
			(stroke
				(width 0.1)
				(type default)
			)
			(layer "F.Fab")
		)
		(fp_line
			(start 0.12065 -0.2794)
			(end 0.12065 -0.3048)
			(stroke
				(width 0.1)
				(type default)
			)
			(layer "F.Fab")
		)
		(fp_line
			(start 0.67945 -0.3048)
			(end 0.67945 0.3048)
			(stroke
				(width 0.1)
				(type default)
			)
			(layer "F.Fab")
		)
		(fp_line
			(start 0.67945 0.3048)
			(end 0.120396 0.3048)
			(stroke
				(width 0.1)
				(type default)
			)
			(layer "F.Fab")
		)
		(pad "1" smd circle
			(at -0.40005 0)
			(size 0 0)
			(layers "F.Cu" "F.Mask" "F.Paste")
			(net "PEX0_PCA9555_INT_N")
		)
		(pad "2" smd circle
			(at 0.40005 0)
			(size 0 0)
			(layers "F.Cu" "F.Mask" "F.Paste")
			(net "PEX0_PCA9555_1_INT_N")
		)
	)
	(footprint ""
		(layer "F.Cu")
		(at 126.63043 -146.099276 180)
		(property "Reference" "PC625"
			(at 0 0 180)
			(layer "F.SilkS")
			(hide yes)
			(effects
				(font
					(size 1.27 1.27)
				)
			)
		)
		(property "Value" ""
			(at 0 0 180)
			(layer "F.Fab")
			(effects
				(font
					(size 1.27 1.27)
				)
			)
		)
		(duplicate_pad_numbers_are_jumpers no)
		(fp_line
			(start 1.524 0.762)
			(end -1.524 0.762)
			(stroke
				(width 0.1524)
				(type default)
			)
			(layer "F.SilkS")
		)
		(fp_line
			(start 1.524 -0.762)
			(end 1.524 0.762)
			(stroke
				(width 0.1524)
				(type default)
			)
			(layer "F.SilkS")
		)
		(fp_line
			(start -1.524 0.762)
			(end -1.524 -0.762)
			(stroke
				(width 0.1524)
				(type default)
			)
			(layer "F.SilkS")
		)
		(fp_line
			(start -1.524 -0.762)
			(end 1.524 -0.762)
			(stroke
				(width 0.1524)
				(type default)
			)
			(layer "F.SilkS")
		)
		(fp_line
			(start 1.1049 0.724916)
			(end 1.1049 -0.724916)
			(stroke
				(width 0.1)
				(type default)
			)
			(layer "F.Fab")
		)
		(fp_line
			(start 1.1049 -0.724916)
			(end -1.1049 -0.724916)
			(stroke
				(width 0.1)
				(type default)
			)
			(layer "F.Fab")
		)
		(fp_line
			(start -1.1049 0.724916)
			(end 1.1049 0.724916)
			(stroke
				(width 0.1)
				(type default)
			)
			(layer "F.Fab")
		)
		(fp_line
			(start -1.1049 -0.724916)
			(end -1.1049 0.724916)
			(stroke
				(width 0.1)
				(type default)
			)
			(layer "F.Fab")
		)
		(pad "1" smd rect
			(at -0.889 0)
			(size 1.016 1.27)
			(layers "F.Cu" "F.Mask" "F.Paste")
			(net "P12V_NIC2_R")
		)
		(pad "2" smd rect
			(at 0.889 0)
			(size 1.016 1.27)
			(layers "F.Cu" "F.Mask" "F.Paste")
			(net "GND")
		)
	)
	(footprint ""
		(layer "F.Cu")
		(at 255.335024 8.083804)
		(property "Reference" "DE13T_2"
			(at -3.6068 -2.962148 0)
			(unlocked yes)
			(layer "F.SilkS")
			(effects
				(font
					(size 0.7874 0.5842)
					(thickness 0.1524)
				)
				(justify left)
			)
		)
		(property "Value" ""
			(at 0 0 0)
			(layer "F.Fab")
			(effects
				(font
					(size 1.27 1.27)
				)
			)
		)
		(duplicate_pad_numbers_are_jumpers no)
		(fp_line
			(start -1.2192 -2.1082)
			(end 1.2192 -2.1082)
			(stroke
				(width 0.1524)
				(type default)
			)
			(layer "F.SilkS")
		)
		(fp_line
			(start -1.2192 2.1082)
			(end -1.2192 -2.1082)
			(stroke
				(width 0.1524)
				(type default)
			)
			(layer "F.SilkS")
		)
		(fp_line
			(start 1.2192 -2.1082)
			(end 1.2192 2.1082)
			(stroke
				(width 0.1524)
				(type default)
			)
			(layer "F.SilkS")
		)
		(fp_line
			(start 1.2192 2.1082)
			(end -1.2192 2.1082)
			(stroke
				(width 0.1524)
				(type default)
			)
			(layer "F.SilkS")
		)
		(pad "" np_thru_hole circle
			(at -2.8829 -1.27 270)
			(size 1.0414 1.0414)
			(drill 1.0414)
			(layers "*.Cu" "*.Mask")
			(clearance 0.381)
			(thermal_gap 0.381)
		)
		(pad "" np_thru_hole circle
			(at -2.8829 1.27 270)
			(size 1.0414 1.0414)
			(drill 1.0414)
			(layers "*.Cu" "*.Mask")
			(clearance 0.381)
			(thermal_gap 0.381)
		)
		(pad "" np_thru_hole circle
			(at 3.4671 -1.27 270)
			(size 1.0414 1.0414)
			(drill 1.0414)
			(layers "*.Cu" "*.Mask")
			(clearance 0.381)
			(thermal_gap 0.381)
		)
		(pad "" np_thru_hole circle
			(at 3.4671 1.27 270)
			(size 1.0414 1.0414)
			(drill 1.0414)
			(layers "*.Cu" "*.Mask")
			(clearance 0.381)
			(thermal_gap 0.381)
		)
		(pad "1" smd rect
			(at 0.8255 -0.249936 270)
			(size 0.3048 0.508)
			(layers "F.Cu" "F.Mask" "F.Paste")
			(net "85_10INCH_IN1_DN")
		)
		(pad "2" smd rect
			(at 0.8255 0.249936 270)
			(size 0.3048 0.508)
			(layers "F.Cu" "F.Mask" "F.Paste")
			(net "85_10INCH_IN1_DP")
		)
		(pad "3" smd circle
			(at 0 0)
			(size 0 0)
			(layers "F.Cu" "F.Mask" "F.Paste")
			(net "COUPON_GND2")
		)
		(zone
			(layer "F.Cu")
			(hatch none 0.5)
			(connect_pads
				(clearance 0)
			)
			(min_thickness 0.25)
			(keepout
				(tracks not_allowed)
				(vias allowed)
				(pads allowed)
				(copperpour not_allowed)
				(footprints allowed)
			)
			(placement
				(enabled no)
				(sheetname "")
			)
			(fill
				(thermal_gap 0.5)
				(thermal_bridge_width 0.5)
				(island_removal_mode 0)
			)
			(polygon
				(pts
					(xy 256.452624 7.535164) (xy 256.452624 7.630668) (xy 255.855724 7.630668) (xy 255.855724 8.037068)
					(xy 256.452624 8.037068) (xy 256.452624 8.13054) (xy 255.855724 8.13054) (xy 255.855724 8.53694)
					(xy 256.452624 8.53694) (xy 256.452624 8.632444) (xy 255.754124 8.632444) (xy 255.754124 7.535164)
				)
			)
		)
		(zone
			(layers "F.Cu" "B.Cu" "In1.Cu" "In2.Cu" "In3.Cu" "In4.Cu" "In5.Cu" "In6.Cu"
				"In7.Cu" "In8.Cu" "In9.Cu" "In10.Cu" "In11.Cu" "In12.Cu" "In13.Cu" "In14.Cu"
				"In15.Cu" "In16.Cu"
			)
			(hatch none 0.5)
			(connect_pads
				(clearance 0)
			)
			(min_thickness 0.25)
			(keepout
				(tracks not_allowed)
				(vias allowed)
				(pads allowed)
				(copperpour not_allowed)
				(footprints allowed)
			)
			(placement
				(enabled no)
				(sheetname "")
			)
			(fill
				(thermal_gap 0.5)
				(thermal_bridge_width 0.5)
				(island_removal_mode 0)
			)
			(polygon
				(pts
					(arc
						(start 253.379224 6.813804)
						(mid 251.525024 6.813804)
						(end 253.379224 6.813804)
					)
				)
			)
		)
		(zone
			(layers "F.Cu" "B.Cu" "In1.Cu" "In2.Cu" "In3.Cu" "In4.Cu" "In5.Cu" "In6.Cu"
				"In7.Cu" "In8.Cu" "In9.Cu" "In10.Cu" "In11.Cu" "In12.Cu" "In13.Cu" "In14.Cu"
				"In15.Cu" "In16.Cu"
			)
			(hatch none 0.5)
			(connect_pads
				(clearance 0)
			)
			(min_thickness 0.25)
			(keepout
				(tracks not_allowed)
				(vias allowed)
				(pads allowed)
				(copperpour not_allowed)
				(footprints allowed)
			)
			(placement
				(enabled no)
				(sheetname "")
			)
			(fill
				(thermal_gap 0.5)
				(thermal_bridge_width 0.5)
				(island_removal_mode 0)
			)
			(polygon
				(pts
					(arc
						(start 253.379224 9.353804)
						(mid 251.525024 9.353804)
						(end 253.379224 9.353804)
					)
				)
			)
		)
		(zone
			(layers "F.Cu" "B.Cu" "In1.Cu" "In2.Cu" "In3.Cu" "In4.Cu" "In5.Cu" "In6.Cu"
				"In7.Cu" "In8.Cu" "In9.Cu" "In10.Cu" "In11.Cu" "In12.Cu" "In13.Cu" "In14.Cu"
				"In15.Cu" "In16.Cu"
			)
			(hatch none 0.5)
			(connect_pads
				(clearance 0)
			)
			(min_thickness 0.25)
			(keepout
				(tracks not_allowed)
				(vias allowed)
				(pads allowed)
				(copperpour not_allowed)
				(footprints allowed)
			)
			(placement
				(enabled no)
				(sheetname "")
			)
			(fill
				(thermal_gap 0.5)
				(thermal_bridge_width 0.5)
				(island_removal_mode 0)
			)
			(polygon
				(pts
					(arc
						(start 259.729224 6.813804)
						(mid 257.875024 6.813804)
						(end 259.729224 6.813804)
					)
				)
			)
		)
		(zone
			(layers "F.Cu" "B.Cu" "In1.Cu" "In2.Cu" "In3.Cu" "In4.Cu" "In5.Cu" "In6.Cu"
				"In7.Cu" "In8.Cu" "In9.Cu" "In10.Cu" "In11.Cu" "In12.Cu" "In13.Cu" "In14.Cu"
				"In15.Cu" "In16.Cu"
			)
			(hatch none 0.5)
			(connect_pads
				(clearance 0)
			)
			(min_thickness 0.25)
			(keepout
				(tracks not_allowed)
				(vias allowed)
				(pads allowed)
				(copperpour not_allowed)
				(footprints allowed)
			)
			(placement
				(enabled no)
				(sheetname "")
			)
			(fill
				(thermal_gap 0.5)
				(thermal_bridge_width 0.5)
				(island_removal_mode 0)
			)
			(polygon
				(pts
					(arc
						(start 259.729224 9.353804)
						(mid 257.875024 9.353804)
						(end 259.729224 9.353804)
					)
				)
			)
		)
	)
	(footprint ""
		(layer "F.Cu")
		(at 221.251272 -148.038312)
		(property "Reference" "R4203"
			(at 0 0 0)
			(layer "F.SilkS")
			(hide yes)
			(effects
				(font
					(size 1.27 1.27)
				)
			)
		)
		(property "Value" ""
			(at 0 0 0)
			(layer "F.Fab")
			(effects
				(font
					(size 1.27 1.27)
				)
			)
		)
		(duplicate_pad_numbers_are_jumpers no)
		(fp_line
			(start -0.7874 -0.4064)
			(end 0.7874 -0.4064)
			(stroke
				(width 0.1524)
				(type default)
			)
			(layer "F.SilkS")
		)
		(fp_line
			(start -0.7874 0.4064)
			(end -0.7874 -0.4064)
			(stroke
				(width 0.1524)
				(type default)
			)
			(layer "F.SilkS")
		)
		(fp_line
			(start 0.7874 -0.4064)
			(end 0.7874 0.4064)
			(stroke
				(width 0.1524)
				(type default)
			)
			(layer "F.SilkS")
		)
		(fp_line
			(start 0.7874 0.4064)
			(end -0.7874 0.4064)
			(stroke
				(width 0.1524)
				(type default)
			)
			(layer "F.SilkS")
		)
		(fp_line
			(start -0.67945 -0.305054)
			(end -0.12065 -0.305054)
			(stroke
				(width 0.1)
				(type default)
			)
			(layer "F.Fab")
		)
		(fp_line
			(start -0.67945 0.3048)
			(end -0.67945 -0.305054)
			(stroke
				(width 0.1)
				(type default)
			)
			(layer "F.Fab")
		)
		(fp_line
			(start -0.12065 -0.305054)
			(end -0.12065 -0.2794)
			(stroke
				(width 0.1)
				(type default)
			)
			(layer "F.Fab")
		)
		(fp_line
			(start -0.12065 -0.2794)
			(end 0.12065 -0.2794)
			(stroke
				(width 0.1)
				(type default)
			)
			(layer "F.Fab")
		)
		(fp_line
			(start -0.12065 0.2794)
			(end -0.12065 0.3048)
			(stroke
				(width 0.1)
				(type default)
			)
			(layer "F.Fab")
		)
		(fp_line
			(start -0.12065 0.3048)
			(end -0.67945 0.3048)
			(stroke
				(width 0.1)
				(type default)
			)
			(layer "F.Fab")
		)
		(fp_line
			(start 0.120396 0.2794)
			(end -0.12065 0.2794)
			(stroke
				(width 0.1)
				(type default)
			)
			(layer "F.Fab")
		)
		(fp_line
			(start 0.120396 0.3048)
			(end 0.120396 0.2794)
			(stroke
				(width 0.1)
				(type default)
			)
			(layer "F.Fab")
		)
		(fp_line
			(start 0.12065 -0.3048)
			(end 0.67945 -0.3048)
			(stroke
				(width 0.1)
				(type default)
			)
			(layer "F.Fab")
		)
		(fp_line
			(start 0.12065 -0.2794)
			(end 0.12065 -0.3048)
			(stroke
				(width 0.1)
				(type default)
			)
			(layer "F.Fab")
		)
		(fp_line
			(start 0.67945 -0.3048)
			(end 0.67945 0.3048)
			(stroke
				(width 0.1)
				(type default)
			)
			(layer "F.Fab")
		)
		(fp_line
			(start 0.67945 0.3048)
			(end 0.120396 0.3048)
			(stroke
				(width 0.1)
				(type default)
			)
			(layer "F.Fab")
		)
		(pad "1" smd circle
			(at -0.40005 0)
			(size 0 0)
			(layers "F.Cu" "F.Mask" "F.Paste")
			(net "GND")
		)
		(pad "2" smd circle
			(at 0.40005 0)
			(size 0 0)
			(layers "F.Cu" "F.Mask" "F.Paste")
			(net "FM_CK440_PEX_MXCK_25M_100M")
		)
	)
	(footprint ""
		(layer "F.Cu")
		(at 411.047438 -87.440008)
		(property "Reference" "R6267"
			(at 0 0 0)
			(layer "F.SilkS")
			(hide yes)
			(effects
				(font
					(size 1.27 1.27)
				)
			)
		)
		(property "Value" ""
			(at 0 0 0)
			(layer "F.Fab")
			(effects
				(font
					(size 1.27 1.27)
				)
			)
		)
		(duplicate_pad_numbers_are_jumpers no)
		(fp_line
			(start -0.7874 -0.4064)
			(end 0.7874 -0.4064)
			(stroke
				(width 0.1524)
				(type default)
			)
			(layer "F.SilkS")
		)
		(fp_line
			(start -0.7874 0.4064)
			(end -0.7874 -0.4064)
			(stroke
				(width 0.1524)
				(type default)
			)
			(layer "F.SilkS")
		)
		(fp_line
			(start 0.7874 -0.4064)
			(end 0.7874 0.4064)
			(stroke
				(width 0.1524)
				(type default)
			)
			(layer "F.SilkS")
		)
		(fp_line
			(start 0.7874 0.4064)
			(end -0.7874 0.4064)
			(stroke
				(width 0.1524)
				(type default)
			)
			(layer "F.SilkS")
		)
		(fp_line
			(start -0.67945 -0.305054)
			(end -0.12065 -0.305054)
			(stroke
				(width 0.1)
				(type default)
			)
			(layer "F.Fab")
		)
		(fp_line
			(start -0.67945 0.3048)
			(end -0.67945 -0.305054)
			(stroke
				(width 0.1)
				(type default)
			)
			(layer "F.Fab")
		)
		(fp_line
			(start -0.12065 -0.305054)
			(end -0.12065 -0.2794)
			(stroke
				(width 0.1)
				(type default)
			)
			(layer "F.Fab")
		)
		(fp_line
			(start -0.12065 -0.2794)
			(end 0.12065 -0.2794)
			(stroke
				(width 0.1)
				(type default)
			)
			(layer "F.Fab")
		)
		(fp_line
			(start -0.12065 0.2794)
			(end -0.12065 0.3048)
			(stroke
				(width 0.1)
				(type default)
			)
			(layer "F.Fab")
		)
		(fp_line
			(start -0.12065 0.3048)
			(end -0.67945 0.3048)
			(stroke
				(width 0.1)
				(type default)
			)
			(layer "F.Fab")
		)
		(fp_line
			(start 0.120396 0.2794)
			(end -0.12065 0.2794)
			(stroke
				(width 0.1)
				(type default)
			)
			(layer "F.Fab")
		)
		(fp_line
			(start 0.120396 0.3048)
			(end 0.120396 0.2794)
			(stroke
				(width 0.1)
				(type default)
			)
			(layer "F.Fab")
		)
		(fp_line
			(start 0.12065 -0.3048)
			(end 0.67945 -0.3048)
			(stroke
				(width 0.1)
				(type default)
			)
			(layer "F.Fab")
		)
		(fp_line
			(start 0.12065 -0.2794)
			(end 0.12065 -0.3048)
			(stroke
				(width 0.1)
				(type default)
			)
			(layer "F.Fab")
		)
		(fp_line
			(start 0.67945 -0.3048)
			(end 0.67945 0.3048)
			(stroke
				(width 0.1)
				(type default)
			)
			(layer "F.Fab")
		)
		(fp_line
			(start 0.67945 0.3048)
			(end 0.120396 0.3048)
			(stroke
				(width 0.1)
				(type default)
			)
			(layer "F.Fab")
		)
		(pad "1" smd circle
			(at -0.40005 0)
			(size 0 0)
			(layers "F.Cu" "F.Mask" "F.Paste")
			(net "SMB_CLK_ISO_R_SDA")
		)
		(pad "2" smd circle
			(at 0.40005 0)
			(size 0 0)
			(layers "F.Cu" "F.Mask" "F.Paste")
			(net "P3V3")
		)
	)
	(footprint ""
		(layer "F.Cu")
		(at 95.105728 -241.760248 180)
		(property "Reference" "R812"
			(at 0 0 180)
			(layer "F.SilkS")
			(hide yes)
			(effects
				(font
					(size 1.27 1.27)
				)
			)
		)
		(property "Value" ""
			(at 0 0 180)
			(layer "F.Fab")
			(effects
				(font
					(size 1.27 1.27)
				)
			)
		)
		(duplicate_pad_numbers_are_jumpers no)
		(fp_line
			(start 0.7874 0.4064)
			(end -0.7874 0.4064)
			(stroke
				(width 0.1524)
				(type default)
			)
			(layer "F.SilkS")
		)
		(fp_line
			(start 0.7874 -0.4064)
			(end 0.7874 0.4064)
			(stroke
				(width 0.1524)
				(type default)
			)
			(layer "F.SilkS")
		)
		(fp_line
			(start -0.7874 0.4064)
			(end -0.7874 -0.4064)
			(stroke
				(width 0.1524)
				(type default)
			)
			(layer "F.SilkS")
		)
		(fp_line
			(start -0.7874 -0.4064)
			(end 0.7874 -0.4064)
			(stroke
				(width 0.1524)
				(type default)
			)
			(layer "F.SilkS")
		)
		(fp_line
			(start 0.67945 0.3048)
			(end 0.120396 0.3048)
			(stroke
				(width 0.1)
				(type default)
			)
			(layer "F.Fab")
		)
		(fp_line
			(start 0.67945 -0.3048)
			(end 0.67945 0.3048)
			(stroke
				(width 0.1)
				(type default)
			)
			(layer "F.Fab")
		)
		(fp_line
			(start 0.12065 -0.2794)
			(end 0.12065 -0.3048)
			(stroke
				(width 0.1)
				(type default)
			)
			(layer "F.Fab")
		)
		(fp_line
			(start 0.12065 -0.3048)
			(end 0.67945 -0.3048)
			(stroke
				(width 0.1)
				(type default)
			)
			(layer "F.Fab")
		)
		(fp_line
			(start 0.120396 0.3048)
			(end 0.120396 0.2794)
			(stroke
				(width 0.1)
				(type default)
			)
			(layer "F.Fab")
		)
		(fp_line
			(start 0.120396 0.2794)
			(end -0.12065 0.2794)
			(stroke
				(width 0.1)
				(type default)
			)
			(layer "F.Fab")
		)
		(fp_line
			(start -0.12065 0.3048)
			(end -0.67945 0.3048)
			(stroke
				(width 0.1)
				(type default)
			)
			(layer "F.Fab")
		)
		(fp_line
			(start -0.12065 0.2794)
			(end -0.12065 0.3048)
			(stroke
				(width 0.1)
				(type default)
			)
			(layer "F.Fab")
		)
		(fp_line
			(start -0.12065 -0.2794)
			(end 0.12065 -0.2794)
			(stroke
				(width 0.1)
				(type default)
			)
			(layer "F.Fab")
		)
		(fp_line
			(start -0.12065 -0.305054)
			(end -0.12065 -0.2794)
			(stroke
				(width 0.1)
				(type default)
			)
			(layer "F.Fab")
		)
		(fp_line
			(start -0.67945 0.3048)
			(end -0.67945 -0.305054)
			(stroke
				(width 0.1)
				(type default)
			)
			(layer "F.Fab")
		)
		(fp_line
			(start -0.67945 -0.305054)
			(end -0.12065 -0.305054)
			(stroke
				(width 0.1)
				(type default)
			)
			(layer "F.Fab")
		)
		(pad "1" smd circle
			(at -0.40005 0 180)
			(size 0 0)
			(layers "F.Cu" "F.Mask" "F.Paste")
			(net "P3V3_AUX")
		)
		(pad "2" smd circle
			(at 0.40005 0 180)
			(size 0 0)
			(layers "F.Cu" "F.Mask" "F.Paste")
			(net "PEX_ADC_ALERT_N")
		)
	)
	(footprint ""
		(layer "F.Cu")
		(at 347.539564 -265.949938 180)
		(property "Reference" "PR7136"
			(at 0 0 180)
			(layer "F.SilkS")
			(hide yes)
			(effects
				(font
					(size 1.27 1.27)
				)
			)
		)
		(property "Value" ""
			(at 0 0 180)
			(layer "F.Fab")
			(effects
				(font
					(size 1.27 1.27)
				)
			)
		)
		(duplicate_pad_numbers_are_jumpers no)
		(fp_line
			(start 0.7874 0.4064)
			(end -0.7874 0.4064)
			(stroke
				(width 0.1524)
				(type default)
			)
			(layer "F.SilkS")
		)
		(fp_line
			(start 0.7874 -0.4064)
			(end 0.7874 0.4064)
			(stroke
				(width 0.1524)
				(type default)
			)
			(layer "F.SilkS")
		)
		(fp_line
			(start -0.7874 0.4064)
			(end -0.7874 -0.4064)
			(stroke
				(width 0.1524)
				(type default)
			)
			(layer "F.SilkS")
		)
		(fp_line
			(start -0.7874 -0.4064)
			(end 0.7874 -0.4064)
			(stroke
				(width 0.1524)
				(type default)
			)
			(layer "F.SilkS")
		)
		(fp_line
			(start 0.67945 0.3048)
			(end 0.120396 0.3048)
			(stroke
				(width 0.1)
				(type default)
			)
			(layer "F.Fab")
		)
		(fp_line
			(start 0.67945 -0.3048)
			(end 0.67945 0.3048)
			(stroke
				(width 0.1)
				(type default)
			)
			(layer "F.Fab")
		)
		(fp_line
			(start 0.12065 -0.2794)
			(end 0.12065 -0.3048)
			(stroke
				(width 0.1)
				(type default)
			)
			(layer "F.Fab")
		)
		(fp_line
			(start 0.12065 -0.3048)
			(end 0.67945 -0.3048)
			(stroke
				(width 0.1)
				(type default)
			)
			(layer "F.Fab")
		)
		(fp_line
			(start 0.120396 0.3048)
			(end 0.120396 0.2794)
			(stroke
				(width 0.1)
				(type default)
			)
			(layer "F.Fab")
		)
		(fp_line
			(start 0.120396 0.2794)
			(end -0.12065 0.2794)
			(stroke
				(width 0.1)
				(type default)
			)
			(layer "F.Fab")
		)
		(fp_line
			(start -0.12065 0.3048)
			(end -0.67945 0.3048)
			(stroke
				(width 0.1)
				(type default)
			)
			(layer "F.Fab")
		)
		(fp_line
			(start -0.12065 0.2794)
			(end -0.12065 0.3048)
			(stroke
				(width 0.1)
				(type default)
			)
			(layer "F.Fab")
		)
		(fp_line
			(start -0.12065 -0.2794)
			(end 0.12065 -0.2794)
			(stroke
				(width 0.1)
				(type default)
			)
			(layer "F.Fab")
		)
		(fp_line
			(start -0.12065 -0.305054)
			(end -0.12065 -0.2794)
			(stroke
				(width 0.1)
				(type default)
			)
			(layer "F.Fab")
		)
		(fp_line
			(start -0.67945 0.3048)
			(end -0.67945 -0.305054)
			(stroke
				(width 0.1)
				(type default)
			)
			(layer "F.Fab")
		)
		(fp_line
			(start -0.67945 -0.305054)
			(end -0.12065 -0.305054)
			(stroke
				(width 0.1)
				(type default)
			)
			(layer "F.Fab")
		)
		(pad "1" smd circle
			(at -0.40005 0 180)
			(size 0 0)
			(layers "F.Cu" "F.Mask" "F.Paste")
			(net "NC_P0V8_PEX2_ISEN6")
		)
		(pad "2" smd circle
			(at 0.40005 0 180)
			(size 0 0)
			(layers "F.Cu" "F.Mask" "F.Paste")
			(net "GND")
		)
	)
	(footprint ""
		(layer "F.Cu")
		(at 312.324496 -84.476336 180)
		(property "Reference" "U36"
			(at -2.890774 -0.503936 90)
			(unlocked yes)
			(layer "F.SilkS")
			(effects
				(font
					(size 0.7874 0.5842)
					(thickness 0.1524)
				)
				(justify left)
			)
		)
		(property "Value" ""
			(at 0 0 180)
			(layer "F.Fab")
			(effects
				(font
					(size 1.27 1.27)
				)
			)
		)
		(duplicate_pad_numbers_are_jumpers no)
		(fp_line
			(start 2.0574 1.651)
			(end -2.0574 1.651)
			(stroke
				(width 0.1524)
				(type default)
			)
			(layer "F.SilkS")
		)
		(fp_line
			(start 2.0574 -1.651)
			(end 2.0574 1.651)
			(stroke
				(width 0.1524)
				(type default)
			)
			(layer "F.SilkS")
		)
		(fp_line
			(start 0.381 -1.651)
			(end 2.0574 -1.651)
			(stroke
				(width 0.1524)
				(type default)
			)
			(layer "F.SilkS")
		)
		(fp_line
			(start 0 -1.016)
			(end 0.381 -1.651)
			(stroke
				(width 0.1524)
				(type default)
			)
			(layer "F.SilkS")
		)
		(fp_line
			(start -0.381 -1.651)
			(end 0 -1.016)
			(stroke
				(width 0.1524)
				(type default)
			)
			(layer "F.SilkS")
		)
		(fp_line
			(start -2.0574 1.651)
			(end -2.0574 -1.651)
			(stroke
				(width 0.1524)
				(type default)
			)
			(layer "F.SilkS")
		)
		(fp_line
			(start -2.0574 -1.651)
			(end -0.381 -1.651)
			(stroke
				(width 0.1524)
				(type default)
			)
			(layer "F.SilkS")
		)
		(fp_poly
			(pts
				(xy -2.71272 -0.719328) (xy -2.71272 -1.344168) (xy -2.159 -1.016)
			)
			(stroke
				(width 0)
				(type default)
			)
			(fill yes)
			(layer "F.SilkS")
		)
		(fp_line
			(start 1.599946 1.199896)
			(end 0.899922 1.199896)
			(stroke
				(width 0.1)
				(type default)
			)
			(layer "F.Fab")
		)
		(fp_line
			(start 1.599946 -1.199896)
			(end 1.599946 1.199896)
			(stroke
				(width 0.1)
				(type default)
			)
			(layer "F.Fab")
		)
		(fp_line
			(start 0.899922 1.549908)
			(end -0.899922 1.549908)
			(stroke
				(width 0.1)
				(type default)
			)
			(layer "F.Fab")
		)
		(fp_line
			(start 0.899922 1.199896)
			(end 0.899922 1.549908)
			(stroke
				(width 0.1)
				(type default)
			)
			(layer "F.Fab")
		)
		(fp_line
			(start 0.899922 -1.199896)
			(end 1.599946 -1.199896)
			(stroke
				(width 0.1)
				(type default)
			)
			(layer "F.Fab")
		)
		(fp_line
			(start 0.899922 -1.549908)
			(end 0.899922 -1.199896)
			(stroke
				(width 0.1)
				(type default)
			)
			(layer "F.Fab")
		)
		(fp_line
			(start -0.899922 1.549908)
			(end -0.899922 1.199896)
			(stroke
				(width 0.1)
				(type default)
			)
			(layer "F.Fab")
		)
		(fp_line
			(start -0.899922 1.199896)
			(end -1.599946 1.199896)
			(stroke
				(width 0.1)
				(type default)
			)
			(layer "F.Fab")
		)
		(fp_line
			(start -0.899922 -1.199896)
			(end -0.899922 -1.549908)
			(stroke
				(width 0.1)
				(type default)
			)
			(layer "F.Fab")
		)
		(fp_line
			(start -0.899922 -1.549908)
			(end 0.899922 -1.549908)
			(stroke
				(width 0.1)
				(type default)
			)
			(layer "F.Fab")
		)
		(fp_line
			(start -1.599946 1.199896)
			(end -1.599946 -1.199896)
			(stroke
				(width 0.1)
				(type default)
			)
			(layer "F.Fab")
		)
		(fp_line
			(start -1.599946 -1.199896)
			(end -0.899922 -1.199896)
			(stroke
				(width 0.1)
				(type default)
			)
			(layer "F.Fab")
		)
		(fp_poly
			(pts
				(xy -2.71272 -0.719328) (xy -2.71272 -1.344168) (xy -2.159 -1.016)
			)
			(stroke
				(width 0)
				(type default)
			)
			(fill yes)
			(layer "F.Fab")
		)
		(pad "1" smd rect
			(at -1.225042 -0.94996 90)
			(size 0.5588 1.3462)
			(layers "F.Cu" "F.Mask" "F.Paste")
			(net "HP_NIC5_PWRGD_R")
		)
		(pad "2" smd rect
			(at -1.225042 0 90)
			(size 0.5588 1.3462)
			(layers "F.Cu" "F.Mask" "F.Paste")
			(net "RST_NIC5_PERST_R_N")
		)
		(pad "3" smd rect
			(at -1.225042 0.94996 90)
			(size 0.5588 1.3462)
			(layers "F.Cu" "F.Mask" "F.Paste")
			(net "GND")
		)
		(pad "4" smd rect
			(at 1.225042 0.94996 90)
			(size 0.5588 1.3462)
			(layers "F.Cu" "F.Mask" "F.Paste")
			(net "RST_HP_NIC5_N")
		)
		(pad "5" smd rect
			(at 1.225042 -0.94996 90)
			(size 0.5588 1.3462)
			(layers "F.Cu" "F.Mask" "F.Paste")
			(net "P3V3_AUX")
		)
	)
	(footprint ""
		(layer "F.Cu")
		(at 131.797806 -122.780552)
		(property "Reference" "PC484"
			(at 0 0 0)
			(layer "F.SilkS")
			(hide yes)
			(effects
				(font
					(size 1.27 1.27)
				)
			)
		)
		(property "Value" ""
			(at 0 0 0)
			(layer "F.Fab")
			(effects
				(font
					(size 1.27 1.27)
				)
			)
		)
		(duplicate_pad_numbers_are_jumpers no)
		(fp_line
			(start -0.7874 -0.4064)
			(end 0.7874 -0.4064)
			(stroke
				(width 0.1524)
				(type default)
			)
			(layer "F.SilkS")
		)
		(fp_line
			(start -0.7874 0.4064)
			(end -0.7874 -0.4064)
			(stroke
				(width 0.1524)
				(type default)
			)
			(layer "F.SilkS")
		)
		(fp_line
			(start 0.7874 -0.4064)
			(end 0.7874 0.4064)
			(stroke
				(width 0.1524)
				(type default)
			)
			(layer "F.SilkS")
		)
		(fp_line
			(start 0.7874 0.4064)
			(end -0.7874 0.4064)
			(stroke
				(width 0.1524)
				(type default)
			)
			(layer "F.SilkS")
		)
		(fp_line
			(start -0.67945 -0.305054)
			(end -0.12065 -0.305054)
			(stroke
				(width 0.1)
				(type default)
			)
			(layer "F.Fab")
		)
		(fp_line
			(start -0.67945 0.3048)
			(end -0.67945 -0.305054)
			(stroke
				(width 0.1)
				(type default)
			)
			(layer "F.Fab")
		)
		(fp_line
			(start -0.12065 -0.305054)
			(end -0.12065 -0.2794)
			(stroke
				(width 0.1)
				(type default)
			)
			(layer "F.Fab")
		)
		(fp_line
			(start -0.12065 -0.2794)
			(end 0.12065 -0.2794)
			(stroke
				(width 0.1)
				(type default)
			)
			(layer "F.Fab")
		)
		(fp_line
			(start -0.12065 0.2794)
			(end -0.12065 0.3048)
			(stroke
				(width 0.1)
				(type default)
			)
			(layer "F.Fab")
		)
		(fp_line
			(start -0.12065 0.3048)
			(end -0.67945 0.3048)
			(stroke
				(width 0.1)
				(type default)
			)
			(layer "F.Fab")
		)
		(fp_line
			(start 0.120396 0.2794)
			(end -0.12065 0.2794)
			(stroke
				(width 0.1)
				(type default)
			)
			(layer "F.Fab")
		)
		(fp_line
			(start 0.120396 0.3048)
			(end 0.120396 0.2794)
			(stroke
				(width 0.1)
				(type default)
			)
			(layer "F.Fab")
		)
		(fp_line
			(start 0.12065 -0.3048)
			(end 0.67945 -0.3048)
			(stroke
				(width 0.1)
				(type default)
			)
			(layer "F.Fab")
		)
		(fp_line
			(start 0.12065 -0.2794)
			(end 0.12065 -0.3048)
			(stroke
				(width 0.1)
				(type default)
			)
			(layer "F.Fab")
		)
		(fp_line
			(start 0.67945 -0.3048)
			(end 0.67945 0.3048)
			(stroke
				(width 0.1)
				(type default)
			)
			(layer "F.Fab")
		)
		(fp_line
			(start 0.67945 0.3048)
			(end 0.120396 0.3048)
			(stroke
				(width 0.1)
				(type default)
			)
			(layer "F.Fab")
		)
		(pad "1" smd circle
			(at -0.40005 0)
			(size 0 0)
			(layers "F.Cu" "F.Mask" "F.Paste")
			(net "P3V3_AUX")
		)
		(pad "2" smd circle
			(at 0.40005 0)
			(size 0 0)
			(layers "F.Cu" "F.Mask" "F.Paste")
			(net "GND")
		)
	)
	(footprint ""
		(layer "F.Cu")
		(at 196.723508 -87.349076 -90)
		(property "Reference" "R199"
			(at 0 0 270)
			(layer "F.SilkS")
			(hide yes)
			(effects
				(font
					(size 1.27 1.27)
				)
			)
		)
		(property "Value" ""
			(at 0 0 270)
			(layer "F.Fab")
			(effects
				(font
					(size 1.27 1.27)
				)
			)
		)
		(duplicate_pad_numbers_are_jumpers no)
		(fp_line
			(start -0.7874 0.4064)
			(end -0.7874 -0.4064)
			(stroke
				(width 0.1524)
				(type default)
			)
			(layer "F.SilkS")
		)
		(fp_line
			(start 0.7874 0.4064)
			(end -0.7874 0.4064)
			(stroke
				(width 0.1524)
				(type default)
			)
			(layer "F.SilkS")
		)
		(fp_line
			(start -0.7874 -0.4064)
			(end 0.7874 -0.4064)
			(stroke
				(width 0.1524)
				(type default)
			)
			(layer "F.SilkS")
		)
		(fp_line
			(start 0.7874 -0.4064)
			(end 0.7874 0.4064)
			(stroke
				(width 0.1524)
				(type default)
			)
			(layer "F.SilkS")
		)
		(fp_line
			(start -0.67945 0.3048)
			(end -0.67945 -0.305054)
			(stroke
				(width 0.1)
				(type default)
			)
			(layer "F.Fab")
		)
		(fp_line
			(start -0.12065 0.3048)
			(end -0.67945 0.3048)
			(stroke
				(width 0.1)
				(type default)
			)
			(layer "F.Fab")
		)
		(fp_line
			(start 0.120396 0.3048)
			(end 0.120396 0.2794)
			(stroke
				(width 0.1)
				(type default)
			)
			(layer "F.Fab")
		)
		(fp_line
			(start 0.67945 0.3048)
			(end 0.120396 0.3048)
			(stroke
				(width 0.1)
				(type default)
			)
			(layer "F.Fab")
		)
		(fp_line
			(start -0.12065 0.2794)
			(end -0.12065 0.3048)
			(stroke
				(width 0.1)
				(type default)
			)
			(layer "F.Fab")
		)
		(fp_line
			(start 0.120396 0.2794)
			(end -0.12065 0.2794)
			(stroke
				(width 0.1)
				(type default)
			)
			(layer "F.Fab")
		)
		(fp_line
			(start -0.12065 -0.2794)
			(end 0.12065 -0.2794)
			(stroke
				(width 0.1)
				(type default)
			)
			(layer "F.Fab")
		)
		(fp_line
			(start 0.12065 -0.2794)
			(end 0.12065 -0.3048)
			(stroke
				(width 0.1)
				(type default)
			)
			(layer "F.Fab")
		)
		(fp_line
			(start 0.12065 -0.3048)
			(end 0.67945 -0.3048)
			(stroke
				(width 0.1)
				(type default)
			)
			(layer "F.Fab")
		)
		(fp_line
			(start 0.67945 -0.3048)
			(end 0.67945 0.3048)
			(stroke
				(width 0.1)
				(type default)
			)
			(layer "F.Fab")
		)
		(fp_line
			(start -0.67945 -0.305054)
			(end -0.12065 -0.305054)
			(stroke
				(width 0.1)
				(type default)
			)
			(layer "F.Fab")
		)
		(fp_line
			(start -0.12065 -0.305054)
			(end -0.12065 -0.2794)
			(stroke
				(width 0.1)
				(type default)
			)
			(layer "F.Fab")
		)
		(pad "1" smd circle
			(at -0.40005 0 270)
			(size 0 0)
			(layers "F.Cu" "F.Mask" "F.Paste")
			(net "RST_NIC3_PERST1_R_N")
		)
		(pad "2" smd circle
			(at 0.40005 0 270)
			(size 0 0)
			(layers "F.Cu" "F.Mask" "F.Paste")
			(net "RST_HP_NIC3_BUF_N")
		)
	)
	(footprint ""
		(layer "F.Cu")
		(at 78.45933 -22.955504 90)
		(property "Reference" "R1657"
			(at 0 0 90)
			(layer "F.SilkS")
			(hide yes)
			(effects
				(font
					(size 1.27 1.27)
				)
			)
		)
		(property "Value" ""
			(at 0 0 90)
			(layer "F.Fab")
			(effects
				(font
					(size 1.27 1.27)
				)
			)
		)
		(duplicate_pad_numbers_are_jumpers no)
		(fp_line
			(start 0.7874 -0.4064)
			(end 0.7874 0.4064)
			(stroke
				(width 0.1524)
				(type default)
			)
			(layer "F.SilkS")
		)
		(fp_line
			(start -0.7874 -0.4064)
			(end 0.7874 -0.4064)
			(stroke
				(width 0.1524)
				(type default)
			)
			(layer "F.SilkS")
		)
		(fp_line
			(start 0.7874 0.4064)
			(end -0.7874 0.4064)
			(stroke
				(width 0.1524)
				(type default)
			)
			(layer "F.SilkS")
		)
		(fp_line
			(start -0.7874 0.4064)
			(end -0.7874 -0.4064)
			(stroke
				(width 0.1524)
				(type default)
			)
			(layer "F.SilkS")
		)
		(fp_line
			(start -0.12065 -0.305054)
			(end -0.12065 -0.2794)
			(stroke
				(width 0.1)
				(type default)
			)
			(layer "F.Fab")
		)
		(fp_line
			(start -0.67945 -0.305054)
			(end -0.12065 -0.305054)
			(stroke
				(width 0.1)
				(type default)
			)
			(layer "F.Fab")
		)
		(fp_line
			(start 0.67945 -0.3048)
			(end 0.67945 0.3048)
			(stroke
				(width 0.1)
				(type default)
			)
			(layer "F.Fab")
		)
		(fp_line
			(start 0.12065 -0.3048)
			(end 0.67945 -0.3048)
			(stroke
				(width 0.1)
				(type default)
			)
			(layer "F.Fab")
		)
		(fp_line
			(start 0.12065 -0.2794)
			(end 0.12065 -0.3048)
			(stroke
				(width 0.1)
				(type default)
			)
			(layer "F.Fab")
		)
		(fp_line
			(start -0.12065 -0.2794)
			(end 0.12065 -0.2794)
			(stroke
				(width 0.1)
				(type default)
			)
			(layer "F.Fab")
		)
		(fp_line
			(start 0.120396 0.2794)
			(end -0.12065 0.2794)
			(stroke
				(width 0.1)
				(type default)
			)
			(layer "F.Fab")
		)
		(fp_line
			(start -0.12065 0.2794)
			(end -0.12065 0.3048)
			(stroke
				(width 0.1)
				(type default)
			)
			(layer "F.Fab")
		)
		(fp_line
			(start 0.67945 0.3048)
			(end 0.120396 0.3048)
			(stroke
				(width 0.1)
				(type default)
			)
			(layer "F.Fab")
		)
		(fp_line
			(start 0.120396 0.3048)
			(end 0.120396 0.2794)
			(stroke
				(width 0.1)
				(type default)
			)
			(layer "F.Fab")
		)
		(fp_line
			(start -0.12065 0.3048)
			(end -0.67945 0.3048)
			(stroke
				(width 0.1)
				(type default)
			)
			(layer "F.Fab")
		)
		(fp_line
			(start -0.67945 0.3048)
			(end -0.67945 -0.305054)
			(stroke
				(width 0.1)
				(type default)
			)
			(layer "F.Fab")
		)
		(pad "1" smd circle
			(at -0.40005 0 90)
			(size 0 0)
			(layers "F.Cu" "F.Mask" "F.Paste")
			(net "SMB_BIC_I2C9_MUX0_SSD2_R_SCL")
		)
		(pad "2" smd circle
			(at 0.40005 0 90)
			(size 0 0)
			(layers "F.Cu" "F.Mask" "F.Paste")
			(net "SMB_ISO_SSD2_SCL")
		)
	)
	(footprint ""
		(layer "F.Cu")
		(at 180.814472 -343.952322 90)
		(property "Reference" "C385"
			(at 0 0 90)
			(layer "F.SilkS")
			(hide yes)
			(effects
				(font
					(size 1.27 1.27)
				)
			)
		)
		(property "Value" ""
			(at 0 0 90)
			(layer "F.Fab")
			(effects
				(font
					(size 1.27 1.27)
				)
			)
		)
		(duplicate_pad_numbers_are_jumpers no)
		(fp_line
			(start 0.299974 -0.150114)
			(end 0.299974 0.150114)
			(stroke
				(width 0.1)
				(type default)
			)
			(layer "F.Fab")
		)
		(fp_line
			(start -0.299974 -0.150114)
			(end 0.299974 -0.150114)
			(stroke
				(width 0.1)
				(type default)
			)
			(layer "F.Fab")
		)
		(fp_line
			(start 0.299974 0.150114)
			(end -0.299974 0.150114)
			(stroke
				(width 0.1)
				(type default)
			)
			(layer "F.Fab")
		)
		(fp_line
			(start -0.299974 0.150114)
			(end -0.299974 -0.150114)
			(stroke
				(width 0.1)
				(type default)
			)
			(layer "F.Fab")
		)
		(pad "1" smd rect
			(at -0.2667 0 90)
			(size 0.3048 0.381)
			(layers "F.Cu" "F.Mask" "F.Paste")
			(net "P5E_PEX1_STN7_TX_DN<121>")
		)
		(pad "2" smd rect
			(at 0.2667 0 90)
			(size 0.3048 0.381)
			(layers "F.Cu" "F.Mask" "F.Paste")
			(net "P5E_PEX1_STN7_TX_C_DN<121>")
		)
	)
	(footprint ""
		(layer "F.Cu")
		(at 455.938128 -305.500024)
		(property "Reference" "PC270"
			(at 0 0 0)
			(layer "F.SilkS")
			(hide yes)
			(effects
				(font
					(size 1.27 1.27)
				)
			)
		)
		(property "Value" ""
			(at 0 0 0)
			(layer "F.Fab")
			(effects
				(font
					(size 1.27 1.27)
				)
			)
		)
		(duplicate_pad_numbers_are_jumpers no)
		(fp_line
			(start -0.7874 -0.4064)
			(end 0.7874 -0.4064)
			(stroke
				(width 0.1524)
				(type default)
			)
			(layer "F.SilkS")
		)
		(fp_line
			(start -0.7874 0.4064)
			(end -0.7874 -0.4064)
			(stroke
				(width 0.1524)
				(type default)
			)
			(layer "F.SilkS")
		)
		(fp_line
			(start 0.7874 -0.4064)
			(end 0.7874 0.4064)
			(stroke
				(width 0.1524)
				(type default)
			)
			(layer "F.SilkS")
		)
		(fp_line
			(start 0.7874 0.4064)
			(end -0.7874 0.4064)
			(stroke
				(width 0.1524)
				(type default)
			)
			(layer "F.SilkS")
		)
		(fp_line
			(start -0.67945 -0.305054)
			(end -0.12065 -0.305054)
			(stroke
				(width 0.1)
				(type default)
			)
			(layer "F.Fab")
		)
		(fp_line
			(start -0.67945 0.3048)
			(end -0.67945 -0.305054)
			(stroke
				(width 0.1)
				(type default)
			)
			(layer "F.Fab")
		)
		(fp_line
			(start -0.12065 -0.305054)
			(end -0.12065 -0.2794)
			(stroke
				(width 0.1)
				(type default)
			)
			(layer "F.Fab")
		)
		(fp_line
			(start -0.12065 -0.2794)
			(end 0.12065 -0.2794)
			(stroke
				(width 0.1)
				(type default)
			)
			(layer "F.Fab")
		)
		(fp_line
			(start -0.12065 0.2794)
			(end -0.12065 0.3048)
			(stroke
				(width 0.1)
				(type default)
			)
			(layer "F.Fab")
		)
		(fp_line
			(start -0.12065 0.3048)
			(end -0.67945 0.3048)
			(stroke
				(width 0.1)
				(type default)
			)
			(layer "F.Fab")
		)
		(fp_line
			(start 0.120396 0.2794)
			(end -0.12065 0.2794)
			(stroke
				(width 0.1)
				(type default)
			)
			(layer "F.Fab")
		)
		(fp_line
			(start 0.120396 0.3048)
			(end 0.120396 0.2794)
			(stroke
				(width 0.1)
				(type default)
			)
			(layer "F.Fab")
		)
		(fp_line
			(start 0.12065 -0.3048)
			(end 0.67945 -0.3048)
			(stroke
				(width 0.1)
				(type default)
			)
			(layer "F.Fab")
		)
		(fp_line
			(start 0.12065 -0.2794)
			(end 0.12065 -0.3048)
			(stroke
				(width 0.1)
				(type default)
			)
			(layer "F.Fab")
		)
		(fp_line
			(start 0.67945 -0.3048)
			(end 0.67945 0.3048)
			(stroke
				(width 0.1)
				(type default)
			)
			(layer "F.Fab")
		)
		(fp_line
			(start 0.67945 0.3048)
			(end 0.120396 0.3048)
			(stroke
				(width 0.1)
				(type default)
			)
			(layer "F.Fab")
		)
		(pad "1" smd circle
			(at -0.40005 0)
			(size 0 0)
			(layers "F.Cu" "F.Mask" "F.Paste")
			(net "SW_P12V_P1V25_PEX3_FLT")
		)
		(pad "2" smd circle
			(at 0.40005 0)
			(size 0 0)
			(layers "F.Cu" "F.Mask" "F.Paste")
			(net "GND")
		)
	)
	(footprint ""
		(layer "F.Cu")
		(at 221.990158 -82.643472)
		(property "Reference" "R5767"
			(at 0 0 0)
			(layer "F.SilkS")
			(hide yes)
			(effects
				(font
					(size 1.27 1.27)
				)
			)
		)
		(property "Value" ""
			(at 0 0 0)
			(layer "F.Fab")
			(effects
				(font
					(size 1.27 1.27)
				)
			)
		)
		(duplicate_pad_numbers_are_jumpers no)
		(fp_line
			(start -0.7874 -0.4064)
			(end 0.7874 -0.4064)
			(stroke
				(width 0.1524)
				(type default)
			)
			(layer "F.SilkS")
		)
		(fp_line
			(start -0.7874 0.4064)
			(end -0.7874 -0.4064)
			(stroke
				(width 0.1524)
				(type default)
			)
			(layer "F.SilkS")
		)
		(fp_line
			(start 0.7874 -0.4064)
			(end 0.7874 0.4064)
			(stroke
				(width 0.1524)
				(type default)
			)
			(layer "F.SilkS")
		)
		(fp_line
			(start 0.7874 0.4064)
			(end -0.7874 0.4064)
			(stroke
				(width 0.1524)
				(type default)
			)
			(layer "F.SilkS")
		)
		(fp_line
			(start -0.67945 -0.305054)
			(end -0.12065 -0.305054)
			(stroke
				(width 0.1)
				(type default)
			)
			(layer "F.Fab")
		)
		(fp_line
			(start -0.67945 0.3048)
			(end -0.67945 -0.305054)
			(stroke
				(width 0.1)
				(type default)
			)
			(layer "F.Fab")
		)
		(fp_line
			(start -0.12065 -0.305054)
			(end -0.12065 -0.2794)
			(stroke
				(width 0.1)
				(type default)
			)
			(layer "F.Fab")
		)
		(fp_line
			(start -0.12065 -0.2794)
			(end 0.12065 -0.2794)
			(stroke
				(width 0.1)
				(type default)
			)
			(layer "F.Fab")
		)
		(fp_line
			(start -0.12065 0.2794)
			(end -0.12065 0.3048)
			(stroke
				(width 0.1)
				(type default)
			)
			(layer "F.Fab")
		)
		(fp_line
			(start -0.12065 0.3048)
			(end -0.67945 0.3048)
			(stroke
				(width 0.1)
				(type default)
			)
			(layer "F.Fab")
		)
		(fp_line
			(start 0.120396 0.2794)
			(end -0.12065 0.2794)
			(stroke
				(width 0.1)
				(type default)
			)
			(layer "F.Fab")
		)
		(fp_line
			(start 0.120396 0.3048)
			(end 0.120396 0.2794)
			(stroke
				(width 0.1)
				(type default)
			)
			(layer "F.Fab")
		)
		(fp_line
			(start 0.12065 -0.3048)
			(end 0.67945 -0.3048)
			(stroke
				(width 0.1)
				(type default)
			)
			(layer "F.Fab")
		)
		(fp_line
			(start 0.12065 -0.2794)
			(end 0.12065 -0.3048)
			(stroke
				(width 0.1)
				(type default)
			)
			(layer "F.Fab")
		)
		(fp_line
			(start 0.67945 -0.3048)
			(end 0.67945 0.3048)
			(stroke
				(width 0.1)
				(type default)
			)
			(layer "F.Fab")
		)
		(fp_line
			(start 0.67945 0.3048)
			(end 0.120396 0.3048)
			(stroke
				(width 0.1)
				(type default)
			)
			(layer "F.Fab")
		)
		(pad "1" smd circle
			(at -0.40005 0)
			(size 0 0)
			(layers "F.Cu" "F.Mask" "F.Paste")
			(net "SSD13_LED")
		)
		(pad "2" smd circle
			(at 0.40005 0)
			(size 0 0)
			(layers "F.Cu" "F.Mask" "F.Paste")
			(net "SSD13_LED_R")
		)
	)
	(footprint ""
		(layer "F.Cu")
		(at 82.526632 -53.697124 -90)
		(property "Reference" "PC498"
			(at 0 0 270)
			(layer "F.SilkS")
			(hide yes)
			(effects
				(font
					(size 1.27 1.27)
				)
			)
		)
		(property "Value" ""
			(at 0 0 270)
			(layer "F.Fab")
			(effects
				(font
					(size 1.27 1.27)
				)
			)
		)
		(duplicate_pad_numbers_are_jumpers no)
		(fp_line
			(start -0.7874 0.4064)
			(end -0.7874 -0.4064)
			(stroke
				(width 0.1524)
				(type default)
			)
			(layer "F.SilkS")
		)
		(fp_line
			(start 0.7874 0.4064)
			(end -0.7874 0.4064)
			(stroke
				(width 0.1524)
				(type default)
			)
			(layer "F.SilkS")
		)
		(fp_line
			(start -0.7874 -0.4064)
			(end 0.7874 -0.4064)
			(stroke
				(width 0.1524)
				(type default)
			)
			(layer "F.SilkS")
		)
		(fp_line
			(start 0.7874 -0.4064)
			(end 0.7874 0.4064)
			(stroke
				(width 0.1524)
				(type default)
			)
			(layer "F.SilkS")
		)
		(fp_line
			(start -0.67945 0.3048)
			(end -0.67945 -0.305054)
			(stroke
				(width 0.1)
				(type default)
			)
			(layer "F.Fab")
		)
		(fp_line
			(start -0.12065 0.3048)
			(end -0.67945 0.3048)
			(stroke
				(width 0.1)
				(type default)
			)
			(layer "F.Fab")
		)
		(fp_line
			(start 0.120396 0.3048)
			(end 0.120396 0.2794)
			(stroke
				(width 0.1)
				(type default)
			)
			(layer "F.Fab")
		)
		(fp_line
			(start 0.67945 0.3048)
			(end 0.120396 0.3048)
			(stroke
				(width 0.1)
				(type default)
			)
			(layer "F.Fab")
		)
		(fp_line
			(start -0.12065 0.2794)
			(end -0.12065 0.3048)
			(stroke
				(width 0.1)
				(type default)
			)
			(layer "F.Fab")
		)
		(fp_line
			(start 0.120396 0.2794)
			(end -0.12065 0.2794)
			(stroke
				(width 0.1)
				(type default)
			)
			(layer "F.Fab")
		)
		(fp_line
			(start -0.12065 -0.2794)
			(end 0.12065 -0.2794)
			(stroke
				(width 0.1)
				(type default)
			)
			(layer "F.Fab")
		)
		(fp_line
			(start 0.12065 -0.2794)
			(end 0.12065 -0.3048)
			(stroke
				(width 0.1)
				(type default)
			)
			(layer "F.Fab")
		)
		(fp_line
			(start 0.12065 -0.3048)
			(end 0.67945 -0.3048)
			(stroke
				(width 0.1)
				(type default)
			)
			(layer "F.Fab")
		)
		(fp_line
			(start 0.67945 -0.3048)
			(end 0.67945 0.3048)
			(stroke
				(width 0.1)
				(type default)
			)
			(layer "F.Fab")
		)
		(fp_line
			(start -0.67945 -0.305054)
			(end -0.12065 -0.305054)
			(stroke
				(width 0.1)
				(type default)
			)
			(layer "F.Fab")
		)
		(fp_line
			(start -0.12065 -0.305054)
			(end -0.12065 -0.2794)
			(stroke
				(width 0.1)
				(type default)
			)
			(layer "F.Fab")
		)
		(pad "1" smd circle
			(at -0.40005 0 270)
			(size 0 0)
			(layers "F.Cu" "F.Mask" "F.Paste")
			(net "P3V3_AUX")
		)
		(pad "2" smd circle
			(at 0.40005 0 270)
			(size 0 0)
			(layers "F.Cu" "F.Mask" "F.Paste")
			(net "GND")
		)
	)
	(footprint ""
		(layer "F.Cu")
		(at 435.494938 -59.577986 90)
		(property "Reference" "PC590"
			(at 0 0 90)
			(layer "F.SilkS")
			(hide yes)
			(effects
				(font
					(size 1.27 1.27)
				)
			)
		)
		(property "Value" ""
			(at 0 0 90)
			(layer "F.Fab")
			(effects
				(font
					(size 1.27 1.27)
				)
			)
		)
		(duplicate_pad_numbers_are_jumpers no)
		(fp_line
			(start 0.7874 -0.4064)
			(end 0.7874 0.4064)
			(stroke
				(width 0.1524)
				(type default)
			)
			(layer "F.SilkS")
		)
		(fp_line
			(start -0.7874 -0.4064)
			(end 0.7874 -0.4064)
			(stroke
				(width 0.1524)
				(type default)
			)
			(layer "F.SilkS")
		)
		(fp_line
			(start 0.7874 0.4064)
			(end -0.7874 0.4064)
			(stroke
				(width 0.1524)
				(type default)
			)
			(layer "F.SilkS")
		)
		(fp_line
			(start -0.7874 0.4064)
			(end -0.7874 -0.4064)
			(stroke
				(width 0.1524)
				(type default)
			)
			(layer "F.SilkS")
		)
		(fp_line
			(start -0.12065 -0.305054)
			(end -0.12065 -0.2794)
			(stroke
				(width 0.1)
				(type default)
			)
			(layer "F.Fab")
		)
		(fp_line
			(start -0.67945 -0.305054)
			(end -0.12065 -0.305054)
			(stroke
				(width 0.1)
				(type default)
			)
			(layer "F.Fab")
		)
		(fp_line
			(start 0.67945 -0.3048)
			(end 0.67945 0.3048)
			(stroke
				(width 0.1)
				(type default)
			)
			(layer "F.Fab")
		)
		(fp_line
			(start 0.12065 -0.3048)
			(end 0.67945 -0.3048)
			(stroke
				(width 0.1)
				(type default)
			)
			(layer "F.Fab")
		)
		(fp_line
			(start 0.12065 -0.2794)
			(end 0.12065 -0.3048)
			(stroke
				(width 0.1)
				(type default)
			)
			(layer "F.Fab")
		)
		(fp_line
			(start -0.12065 -0.2794)
			(end 0.12065 -0.2794)
			(stroke
				(width 0.1)
				(type default)
			)
			(layer "F.Fab")
		)
		(fp_line
			(start 0.120396 0.2794)
			(end -0.12065 0.2794)
			(stroke
				(width 0.1)
				(type default)
			)
			(layer "F.Fab")
		)
		(fp_line
			(start -0.12065 0.2794)
			(end -0.12065 0.3048)
			(stroke
				(width 0.1)
				(type default)
			)
			(layer "F.Fab")
		)
		(fp_line
			(start 0.67945 0.3048)
			(end 0.120396 0.3048)
			(stroke
				(width 0.1)
				(type default)
			)
			(layer "F.Fab")
		)
		(fp_line
			(start 0.120396 0.3048)
			(end 0.120396 0.2794)
			(stroke
				(width 0.1)
				(type default)
			)
			(layer "F.Fab")
		)
		(fp_line
			(start -0.12065 0.3048)
			(end -0.67945 0.3048)
			(stroke
				(width 0.1)
				(type default)
			)
			(layer "F.Fab")
		)
		(fp_line
			(start -0.67945 0.3048)
			(end -0.67945 -0.305054)
			(stroke
				(width 0.1)
				(type default)
			)
			(layer "F.Fab")
		)
		(pad "1" smd circle
			(at -0.40005 0 90)
			(size 0 0)
			(layers "F.Cu" "F.Mask" "F.Paste")
			(net "P3V3_SSD15_SS")
		)
		(pad "2" smd circle
			(at 0.40005 0 90)
			(size 0 0)
			(layers "F.Cu" "F.Mask" "F.Paste")
			(net "GND")
		)
	)
	(footprint ""
		(layer "F.Cu")
		(at 252.455172 -35.876738)
		(property "Reference" "R6081"
			(at 0 0 0)
			(layer "F.SilkS")
			(hide yes)
			(effects
				(font
					(size 1.27 1.27)
				)
			)
		)
		(property "Value" ""
			(at 0 0 0)
			(layer "F.Fab")
			(effects
				(font
					(size 1.27 1.27)
				)
			)
		)
		(duplicate_pad_numbers_are_jumpers no)
		(fp_line
			(start -0.7874 -0.4064)
			(end 0.7874 -0.4064)
			(stroke
				(width 0.1524)
				(type default)
			)
			(layer "F.SilkS")
		)
		(fp_line
			(start -0.7874 0.4064)
			(end -0.7874 -0.4064)
			(stroke
				(width 0.1524)
				(type default)
			)
			(layer "F.SilkS")
		)
		(fp_line
			(start 0.7874 -0.4064)
			(end 0.7874 0.4064)
			(stroke
				(width 0.1524)
				(type default)
			)
			(layer "F.SilkS")
		)
		(fp_line
			(start 0.7874 0.4064)
			(end -0.7874 0.4064)
			(stroke
				(width 0.1524)
				(type default)
			)
			(layer "F.SilkS")
		)
		(fp_line
			(start -0.67945 -0.305054)
			(end -0.12065 -0.305054)
			(stroke
				(width 0.1)
				(type default)
			)
			(layer "F.Fab")
		)
		(fp_line
			(start -0.67945 0.3048)
			(end -0.67945 -0.305054)
			(stroke
				(width 0.1)
				(type default)
			)
			(layer "F.Fab")
		)
		(fp_line
			(start -0.12065 -0.305054)
			(end -0.12065 -0.2794)
			(stroke
				(width 0.1)
				(type default)
			)
			(layer "F.Fab")
		)
		(fp_line
			(start -0.12065 -0.2794)
			(end 0.12065 -0.2794)
			(stroke
				(width 0.1)
				(type default)
			)
			(layer "F.Fab")
		)
		(fp_line
			(start -0.12065 0.2794)
			(end -0.12065 0.3048)
			(stroke
				(width 0.1)
				(type default)
			)
			(layer "F.Fab")
		)
		(fp_line
			(start -0.12065 0.3048)
			(end -0.67945 0.3048)
			(stroke
				(width 0.1)
				(type default)
			)
			(layer "F.Fab")
		)
		(fp_line
			(start 0.120396 0.2794)
			(end -0.12065 0.2794)
			(stroke
				(width 0.1)
				(type default)
			)
			(layer "F.Fab")
		)
		(fp_line
			(start 0.120396 0.3048)
			(end 0.120396 0.2794)
			(stroke
				(width 0.1)
				(type default)
			)
			(layer "F.Fab")
		)
		(fp_line
			(start 0.12065 -0.3048)
			(end 0.67945 -0.3048)
			(stroke
				(width 0.1)
				(type default)
			)
			(layer "F.Fab")
		)
		(fp_line
			(start 0.12065 -0.2794)
			(end 0.12065 -0.3048)
			(stroke
				(width 0.1)
				(type default)
			)
			(layer "F.Fab")
		)
		(fp_line
			(start 0.67945 -0.3048)
			(end 0.67945 0.3048)
			(stroke
				(width 0.1)
				(type default)
			)
			(layer "F.Fab")
		)
		(fp_line
			(start 0.67945 0.3048)
			(end 0.120396 0.3048)
			(stroke
				(width 0.1)
				(type default)
			)
			(layer "F.Fab")
		)
		(pad "1" smd circle
			(at -0.40005 0)
			(size 0 0)
			(layers "F.Cu" "F.Mask" "F.Paste")
			(net "P3V3_AUX")
		)
		(pad "2" smd circle
			(at 0.40005 0)
			(size 0 0)
			(layers "F.Cu" "F.Mask" "F.Paste")
			(net "PWRGD_P3V3_SSD9_D")
		)
	)
	(footprint ""
		(layer "F.Cu")
		(at 245.164864 -26.785062 180)
		(property "Reference" "J38"
			(at 4.352036 -11.16457 90)
			(unlocked yes)
			(layer "F.SilkS")
			(effects
				(font
					(size 0.7874 0.5842)
					(thickness 0.1524)
				)
			)
		)
		(property "Value" ""
			(at 0 0 180)
			(layer "F.Fab")
			(effects
				(font
					(size 1.27 1.27)
				)
			)
		)
		(duplicate_pad_numbers_are_jumpers no)
		(fp_line
			(start 3.150108 12.115038)
			(end 1.529334 12.115038)
			(stroke
				(width 0.1524)
				(type default)
			)
			(layer "F.SilkS")
		)
		(fp_line
			(start 3.074924 12.014962)
			(end 1.632204 12.014962)
			(stroke
				(width 0.1524)
				(type default)
			)
			(layer "F.SilkS")
		)
		(fp_line
			(start 1.632204 -12.014962)
			(end 3.074924 -12.014962)
			(stroke
				(width 0.1524)
				(type default)
			)
			(layer "F.SilkS")
		)
		(fp_line
			(start 1.529334 -12.115038)
			(end 3.150108 -12.115038)
			(stroke
				(width 0.1524)
				(type default)
			)
			(layer "F.SilkS")
		)
		(fp_line
			(start -1.529334 12.115038)
			(end -3.150108 12.115038)
			(stroke
				(width 0.1524)
				(type default)
			)
			(layer "F.SilkS")
		)
		(fp_line
			(start -1.632204 12.014962)
			(end -3.074924 12.014962)
			(stroke
				(width 0.1524)
				(type default)
			)
			(layer "F.SilkS")
		)
		(fp_line
			(start -3.074924 -12.014962)
			(end -1.632204 -12.014962)
			(stroke
				(width 0.1524)
				(type default)
			)
			(layer "F.SilkS")
		)
		(fp_line
			(start -3.150108 -12.115038)
			(end -1.529334 -12.115038)
			(stroke
				(width 0.1524)
				(type default)
			)
			(layer "F.SilkS")
		)
		(fp_poly
			(pts
				(xy 3.264408 -8.838946) (xy 3.68681 -10.10666) (xy 4.531868 -9.261602)
			)
			(stroke
				(width 0)
				(type default)
			)
			(fill yes)
			(layer "F.SilkS")
		)
		(fp_line
			(start 3.074924 12.014962)
			(end -3.074924 12.014962)
			(stroke
				(width 0.1)
				(type default)
			)
			(layer "F.Fab")
		)
		(fp_line
			(start 3.074924 -12.014962)
			(end 3.074924 12.014962)
			(stroke
				(width 0.1)
				(type default)
			)
			(layer "F.Fab")
		)
		(fp_line
			(start -3.074924 12.014962)
			(end -3.074924 -12.014962)
			(stroke
				(width 0.1)
				(type default)
			)
			(layer "F.Fab")
		)
		(fp_line
			(start -3.074924 -12.014962)
			(end 3.074924 -12.014962)
			(stroke
				(width 0.1)
				(type default)
			)
			(layer "F.Fab")
		)
		(fp_poly
			(pts
				(xy 3.348736 -7.994904) (xy 4.543806 -8.592566) (xy 4.543806 -7.397496)
			)
			(stroke
				(width 0)
				(type default)
			)
			(fill yes)
			(layer "F.Fab")
		)
		(pad "" np_thru_hole circle
			(at -1.75006 -9.815068 90)
			(size 1.1176 1.1176)
			(drill 1.1176)
			(layers "*.Cu" "*.Mask")
			(clearance 0.381)
			(thermal_gap 0.381)
		)
		(pad "" np_thru_hole circle
			(at 0 9.815068 90)
			(size 1.1176 1.1176)
			(drill 1.1176)
			(layers "*.Cu" "*.Mask")
			(clearance 0.381)
			(thermal_gap 0.381)
		)
		(pad "A1" smd rect
			(at 2.29997 -7.994904 90)
			(size 0.381 1.27)
			(layers "F.Cu" "F.Mask" "F.Paste")
			(net "GND")
		)
		(pad "A2" smd rect
			(at 2.29997 -7.394956 90)
			(size 0.381 1.27)
			(layers "F.Cu" "F.Mask" "F.Paste")
			(net "GND")
		)
		(pad "A3" smd rect
			(at 2.29997 -6.795008 90)
			(size 0.381 1.27)
			(layers "F.Cu" "F.Mask" "F.Paste")
			(net "GND")
		)
		(pad "A4" smd rect
			(at 2.29997 -6.19506 90)
			(size 0.381 1.27)
			(layers "F.Cu" "F.Mask" "F.Paste")
			(net "GND")
		)
		(pad "A5" smd rect
			(at 2.29997 -5.595112 90)
			(size 0.381 1.27)
			(layers "F.Cu" "F.Mask" "F.Paste")
			(net "GND")
		)
		(pad "A6" smd rect
			(at 2.29997 -4.99491 90)
			(size 0.381 1.27)
			(layers "F.Cu" "F.Mask" "F.Paste")
			(net "GND")
		)
		(pad "A7" smd rect
			(at 2.29997 -4.394962 90)
			(size 0.381 1.27)
			(layers "F.Cu" "F.Mask" "F.Paste")
			(net "SMB_ISO_SSD8_R_SCL")
		)
		(pad "A8" smd rect
			(at 2.29997 -3.795014 90)
			(size 0.381 1.27)
			(layers "F.Cu" "F.Mask" "F.Paste")
			(net "SMB_ISO_SSD8_R_SDA")
		)
		(pad "A9" smd rect
			(at 2.29997 -3.195066 90)
			(size 0.381 1.27)
			(layers "F.Cu" "F.Mask" "F.Paste")
			(net "RST_SMB_SSD8_ISO_R_N")
		)
		(pad "A10" smd rect
			(at 2.29997 -2.595118 90)
			(size 0.381 1.27)
			(layers "F.Cu" "F.Mask" "F.Paste")
			(net "SSD8_LED_ISO_R_N")
		)
		(pad "A11" smd rect
			(at 2.29997 -1.994916 90)
			(size 0.381 1.27)
			(layers "F.Cu" "F.Mask" "F.Paste")
			(net "PU_CLKREQ8")
		)
		(pad "A12" smd rect
			(at 2.29997 -1.394968 90)
			(size 0.381 1.27)
			(layers "F.Cu" "F.Mask" "F.Paste")
			(net "PRSNT_SSD8_N")
		)
		(pad "A13" smd rect
			(at 2.29997 -0.79502 90)
			(size 0.381 1.27)
			(layers "F.Cu" "F.Mask" "F.Paste")
			(net "GND")
		)
		(pad "A14" smd rect
			(at 2.29997 -0.195072 90)
			(size 0.381 1.27)
			(layers "F.Cu" "F.Mask" "F.Paste")
			(net "Net_8501")
		)
		(pad "A15" smd rect
			(at 2.29997 0.404876 90)
			(size 0.381 1.27)
			(layers "F.Cu" "F.Mask" "F.Paste")
			(net "Net_8500")
		)
		(pad "A16" smd rect
			(at 2.29997 1.005078 90)
			(size 0.381 1.27)
			(layers "F.Cu" "F.Mask" "F.Paste")
			(net "GND")
		)
		(pad "A17" smd rect
			(at 2.29997 1.605026 90)
			(size 0.381 1.27)
			(layers "F.Cu" "F.Mask" "F.Paste")
			(net "P5E_PEX2_STN2_RX_DN<44>")
		)
		(pad "A18" smd rect
			(at 2.29997 2.204974 90)
			(size 0.381 1.27)
			(layers "F.Cu" "F.Mask" "F.Paste")
			(net "P5E_PEX2_STN2_RX_DP<44>")
		)
		(pad "A19" smd rect
			(at 2.29997 2.804922 90)
			(size 0.381 1.27)
			(layers "F.Cu" "F.Mask" "F.Paste")
			(net "GND")
		)
		(pad "A20" smd rect
			(at 2.29997 3.405124 90)
			(size 0.381 1.27)
			(layers "F.Cu" "F.Mask" "F.Paste")
			(net "P5E_PEX2_STN2_RX_DN<45>")
		)
		(pad "A21" smd rect
			(at 2.29997 4.005072 90)
			(size 0.381 1.27)
			(layers "F.Cu" "F.Mask" "F.Paste")
			(net "P5E_PEX2_STN2_RX_DP<45>")
		)
		(pad "A22" smd rect
			(at 2.29997 4.60502 90)
			(size 0.381 1.27)
			(layers "F.Cu" "F.Mask" "F.Paste")
			(net "GND")
		)
		(pad "A23" smd rect
			(at 2.29997 5.204968 90)
			(size 0.381 1.27)
			(layers "F.Cu" "F.Mask" "F.Paste")
			(net "P5E_PEX2_STN2_RX_DN<46>")
		)
		(pad "A24" smd rect
			(at 2.29997 5.804916 90)
			(size 0.381 1.27)
			(layers "F.Cu" "F.Mask" "F.Paste")
			(net "P5E_PEX2_STN2_RX_DP<46>")
		)
		(pad "A25" smd rect
			(at 2.29997 6.405118 90)
			(size 0.381 1.27)
			(layers "F.Cu" "F.Mask" "F.Paste")
			(net "GND")
		)
		(pad "A26" smd rect
			(at 2.29997 7.005066 90)
			(size 0.381 1.27)
			(layers "F.Cu" "F.Mask" "F.Paste")
			(net "P5E_PEX2_STN2_RX_DN<47>")
		)
		(pad "A27" smd rect
			(at 2.29997 7.605014 90)
			(size 0.381 1.27)
			(layers "F.Cu" "F.Mask" "F.Paste")
			(net "P5E_PEX2_STN2_RX_DP<47>")
		)
		(pad "A28" smd rect
			(at 2.29997 8.204962 90)
			(size 0.381 1.27)
			(layers "F.Cu" "F.Mask" "F.Paste")
			(net "GND")
		)
		(pad "B1" smd rect
			(at -2.29997 -7.994904 90)
			(size 0.381 1.27)
			(layers "F.Cu" "F.Mask" "F.Paste")
			(net "P12V_SSD8")
		)
		(pad "B2" smd rect
			(at -2.29997 -7.394956 90)
			(size 0.381 1.27)
			(layers "F.Cu" "F.Mask" "F.Paste")
			(net "P12V_SSD8")
		)
		(pad "B3" smd rect
			(at -2.29997 -6.795008 90)
			(size 0.381 1.27)
			(layers "F.Cu" "F.Mask" "F.Paste")
			(net "P12V_SSD8")
		)
		(pad "B4" smd rect
			(at -2.29997 -6.19506 90)
			(size 0.381 1.27)
			(layers "F.Cu" "F.Mask" "F.Paste")
			(net "P12V_SSD8")
		)
		(pad "B5" smd rect
			(at -2.29997 -5.595112 90)
			(size 0.381 1.27)
			(layers "F.Cu" "F.Mask" "F.Paste")
			(net "P12V_SSD8")
		)
		(pad "B6" smd rect
			(at -2.29997 -4.99491 90)
			(size 0.381 1.27)
			(layers "F.Cu" "F.Mask" "F.Paste")
			(net "P12V_SSD8")
		)
		(pad "B7" smd rect
			(at -2.29997 -4.394962 90)
			(size 0.381 1.27)
			(layers "F.Cu" "F.Mask" "F.Paste")
			(net "Net_8502")
		)
		(pad "B8" smd rect
			(at -2.29997 -3.795014 90)
			(size 0.381 1.27)
			(layers "F.Cu" "F.Mask" "F.Paste")
			(net "Net_8499")
		)
		(pad "B9" smd rect
			(at -2.29997 -3.195066 90)
			(size 0.381 1.27)
			(layers "F.Cu" "F.Mask" "F.Paste")
			(net "DUALPORT_N_SSD8")
		)
		(pad "B10" smd rect
			(at -2.29997 -2.595118 90)
			(size 0.381 1.27)
			(layers "F.Cu" "F.Mask" "F.Paste")
			(net "RST_SSD8_PERST_R_N")
		)
		(pad "B11" smd rect
			(at -2.29997 -1.994916 90)
			(size 0.381 1.27)
			(layers "F.Cu" "F.Mask" "F.Paste")
			(net "P3V3_SSD8")
		)
		(pad "B12" smd rect
			(at -2.29997 -1.394968 90)
			(size 0.381 1.27)
			(layers "F.Cu" "F.Mask" "F.Paste")
			(net "SSD8_PWRDIS_R")
		)
		(pad "B13" smd rect
			(at -2.29997 -0.79502 90)
			(size 0.381 1.27)
			(layers "F.Cu" "F.Mask" "F.Paste")
			(net "GND")
		)
		(pad "B14" smd rect
			(at -2.29997 -0.195072 90)
			(size 0.381 1.27)
			(layers "F.Cu" "F.Mask" "F.Paste")
			(net "CLK_100M_DB800ZL_SSD8_R_DN")
		)
		(pad "B15" smd rect
			(at -2.29997 0.404876 90)
			(size 0.381 1.27)
			(layers "F.Cu" "F.Mask" "F.Paste")
			(net "CLK_100M_DB800ZL_SSD8_R_DP")
		)
		(pad "B16" smd rect
			(at -2.29997 1.005078 90)
			(size 0.381 1.27)
			(layers "F.Cu" "F.Mask" "F.Paste")
			(net "GND")
		)
		(pad "B17" smd rect
			(at -2.29997 1.605026 90)
			(size 0.381 1.27)
			(layers "F.Cu" "F.Mask" "F.Paste")
			(net "P5E_PEX2_STN2_TX_C_DN<44>")
		)
		(pad "B18" smd rect
			(at -2.29997 2.204974 90)
			(size 0.381 1.27)
			(layers "F.Cu" "F.Mask" "F.Paste")
			(net "P5E_PEX2_STN2_TX_C_DP<44>")
		)
		(pad "B19" smd rect
			(at -2.29997 2.804922 90)
			(size 0.381 1.27)
			(layers "F.Cu" "F.Mask" "F.Paste")
			(net "GND")
		)
		(pad "B20" smd rect
			(at -2.29997 3.405124 90)
			(size 0.381 1.27)
			(layers "F.Cu" "F.Mask" "F.Paste")
			(net "P5E_PEX2_STN2_TX_C_DN<45>")
		)
		(pad "B21" smd rect
			(at -2.29997 4.005072 90)
			(size 0.381 1.27)
			(layers "F.Cu" "F.Mask" "F.Paste")
			(net "P5E_PEX2_STN2_TX_C_DP<45>")
		)
		(pad "B22" smd rect
			(at -2.29997 4.60502 90)
			(size 0.381 1.27)
			(layers "F.Cu" "F.Mask" "F.Paste")
			(net "GND")
		)
		(pad "B23" smd rect
			(at -2.29997 5.204968 90)
			(size 0.381 1.27)
			(layers "F.Cu" "F.Mask" "F.Paste")
			(net "P5E_PEX2_STN2_TX_C_DN<46>")
		)
		(pad "B24" smd rect
			(at -2.29997 5.804916 90)
			(size 0.381 1.27)
			(layers "F.Cu" "F.Mask" "F.Paste")
			(net "P5E_PEX2_STN2_TX_C_DP<46>")
		)
		(pad "B25" smd rect
			(at -2.29997 6.405118 90)
			(size 0.381 1.27)
			(layers "F.Cu" "F.Mask" "F.Paste")
			(net "GND")
		)
		(pad "B26" smd rect
			(at -2.29997 7.005066 90)
			(size 0.381 1.27)
			(layers "F.Cu" "F.Mask" "F.Paste")
			(net "P5E_PEX2_STN2_TX_C_DN<47>")
		)
		(pad "B27" smd rect
			(at -2.29997 7.605014 90)
			(size 0.381 1.27)
			(layers "F.Cu" "F.Mask" "F.Paste")
			(net "P5E_PEX2_STN2_TX_C_DP<47>")
		)
		(pad "B28" smd rect
			(at -2.29997 8.204962 90)
			(size 0.381 1.27)
			(layers "F.Cu" "F.Mask" "F.Paste")
			(net "GND")
		)
		(pad "G1" thru_hole oval
			(at 0 -11.364976 90)
			(size 1.6256 3.4798)
			(drill oval 1.1176 2.4638)
			(layers "*.Cu" "*.Mask")
			(remove_unused_layers no)
			(net "GND")
			(clearance 0.127)
			(thermal_gap 0.127)
		)
		(pad "G2" thru_hole oval
			(at 0 11.364976 90)
			(size 1.6256 3.4798)
			(drill oval 1.1176 2.4638)
			(layers "*.Cu" "*.Mask")
			(remove_unused_layers no)
			(net "GND")
			(clearance 0.127)
			(thermal_gap 0.127)
		)
		(zone
			(layer "F.Cu")
			(hatch none 0.5)
			(connect_pads
				(clearance 0)
			)
			(min_thickness 0.25)
			(keepout
				(tracks not_allowed)
				(vias allowed)
				(pads allowed)
				(copperpour not_allowed)
				(footprints allowed)
			)
			(placement
				(enabled no)
				(sheetname "")
			)
			(fill
				(thermal_gap 0.5)
				(thermal_bridge_width 0.5)
				(island_removal_mode 0)
			)
			(polygon
				(pts
					(xy 246.544846 -38.850062) (xy 243.794788 -38.850062) (xy 243.794788 -35.900106) (xy 246.544846 -35.900106)
				)
			)
		)
		(zone
			(layer "F.Cu")
			(hatch none 0.5)
			(connect_pads
				(clearance 0)
			)
			(min_thickness 0.25)
			(keepout
				(tracks not_allowed)
				(vias allowed)
				(pads allowed)
				(copperpour not_allowed)
				(footprints allowed)
			)
			(placement
				(enabled no)
				(sheetname "")
			)
			(fill
				(thermal_gap 0.5)
				(thermal_bridge_width 0.5)
				(island_removal_mode 0)
			)
			(polygon
				(pts
					(xy 247.614948 -17.670018) (xy 243.784882 -17.670018) (xy 243.784882 -14.720062) (xy 247.614948 -14.720062)
				)
			)
		)
		(zone
			(layers "F.Cu" "B.Cu" "In1.Cu" "In2.Cu" "In3.Cu" "In4.Cu" "In5.Cu" "In6.Cu"
				"In7.Cu" "In8.Cu" "In9.Cu" "In10.Cu" "In11.Cu" "In12.Cu" "In13.Cu" "In14.Cu"
				"In15.Cu" "In16.Cu"
			)
			(hatch none 0.5)
			(connect_pads
				(clearance 0)
			)
			(min_thickness 0.25)
			(keepout
				(tracks not_allowed)
				(vias allowed)
				(pads allowed)
				(copperpour not_allowed)
				(footprints allowed)
			)
			(placement
				(enabled no)
				(sheetname "")
			)
			(fill
				(thermal_gap 0.5)
				(thermal_bridge_width 0.5)
				(island_removal_mode 0)
			)
			(polygon
				(pts
					(arc
						(start 246.130064 -36.60013)
						(mid 244.199664 -36.60013)
						(end 246.130064 -36.60013)
					)
				)
			)
		)
		(zone
			(layers "F.Cu" "B.Cu" "In1.Cu" "In2.Cu" "In3.Cu" "In4.Cu" "In5.Cu" "In6.Cu"
				"In7.Cu" "In8.Cu" "In9.Cu" "In10.Cu" "In11.Cu" "In12.Cu" "In13.Cu" "In14.Cu"
				"In15.Cu" "In16.Cu"
			)
			(hatch none 0.5)
			(connect_pads
				(clearance 0)
			)
			(min_thickness 0.25)
			(keepout
				(tracks not_allowed)
				(vias allowed)
				(pads allowed)
				(copperpour not_allowed)
				(footprints allowed)
			)
			(placement
				(enabled no)
				(sheetname "")
			)
			(fill
				(thermal_gap 0.5)
				(thermal_bridge_width 0.5)
				(island_removal_mode 0)
			)
			(polygon
				(pts
					(arc
						(start 247.880124 -16.969994)
						(mid 245.949724 -16.969994)
						(end 247.880124 -16.969994)
					)
				)
			)
		)
	)
	(footprint ""
		(layer "F.Cu")
		(at 53.126132 -37.929566 90)
		(property "Reference" "R5546"
			(at 0 0 90)
			(layer "F.SilkS")
			(hide yes)
			(effects
				(font
					(size 1.27 1.27)
				)
			)
		)
		(property "Value" ""
			(at 0 0 90)
			(layer "F.Fab")
			(effects
				(font
					(size 1.27 1.27)
				)
			)
		)
		(duplicate_pad_numbers_are_jumpers no)
		(fp_line
			(start 0.7874 -0.4064)
			(end 0.7874 0.4064)
			(stroke
				(width 0.1524)
				(type default)
			)
			(layer "F.SilkS")
		)
		(fp_line
			(start -0.7874 -0.4064)
			(end 0.7874 -0.4064)
			(stroke
				(width 0.1524)
				(type default)
			)
			(layer "F.SilkS")
		)
		(fp_line
			(start 0.7874 0.4064)
			(end -0.7874 0.4064)
			(stroke
				(width 0.1524)
				(type default)
			)
			(layer "F.SilkS")
		)
		(fp_line
			(start -0.7874 0.4064)
			(end -0.7874 -0.4064)
			(stroke
				(width 0.1524)
				(type default)
			)
			(layer "F.SilkS")
		)
		(fp_line
			(start -0.12065 -0.305054)
			(end -0.12065 -0.2794)
			(stroke
				(width 0.1)
				(type default)
			)
			(layer "F.Fab")
		)
		(fp_line
			(start -0.67945 -0.305054)
			(end -0.12065 -0.305054)
			(stroke
				(width 0.1)
				(type default)
			)
			(layer "F.Fab")
		)
		(fp_line
			(start 0.67945 -0.3048)
			(end 0.67945 0.3048)
			(stroke
				(width 0.1)
				(type default)
			)
			(layer "F.Fab")
		)
		(fp_line
			(start 0.12065 -0.3048)
			(end 0.67945 -0.3048)
			(stroke
				(width 0.1)
				(type default)
			)
			(layer "F.Fab")
		)
		(fp_line
			(start 0.12065 -0.2794)
			(end 0.12065 -0.3048)
			(stroke
				(width 0.1)
				(type default)
			)
			(layer "F.Fab")
		)
		(fp_line
			(start -0.12065 -0.2794)
			(end 0.12065 -0.2794)
			(stroke
				(width 0.1)
				(type default)
			)
			(layer "F.Fab")
		)
		(fp_line
			(start 0.120396 0.2794)
			(end -0.12065 0.2794)
			(stroke
				(width 0.1)
				(type default)
			)
			(layer "F.Fab")
		)
		(fp_line
			(start -0.12065 0.2794)
			(end -0.12065 0.3048)
			(stroke
				(width 0.1)
				(type default)
			)
			(layer "F.Fab")
		)
		(fp_line
			(start 0.67945 0.3048)
			(end 0.120396 0.3048)
			(stroke
				(width 0.1)
				(type default)
			)
			(layer "F.Fab")
		)
		(fp_line
			(start 0.120396 0.3048)
			(end 0.120396 0.2794)
			(stroke
				(width 0.1)
				(type default)
			)
			(layer "F.Fab")
		)
		(fp_line
			(start -0.12065 0.3048)
			(end -0.67945 0.3048)
			(stroke
				(width 0.1)
				(type default)
			)
			(layer "F.Fab")
		)
		(fp_line
			(start -0.67945 0.3048)
			(end -0.67945 -0.305054)
			(stroke
				(width 0.1)
				(type default)
			)
			(layer "F.Fab")
		)
		(pad "1" smd circle
			(at -0.40005 0 90)
			(size 0 0)
			(layers "F.Cu" "F.Mask" "F.Paste")
			(net "SSD2_AUX_P3V3_EN_R")
		)
		(pad "2" smd circle
			(at 0.40005 0 90)
			(size 0 0)
			(layers "F.Cu" "F.Mask" "F.Paste")
			(net "SSD2_AUX_P3V3_EN")
		)
	)
	(footprint ""
		(layer "F.Cu")
		(at 453.151494 -99.177602 -90)
		(property "Reference" "PD13"
			(at 4.232402 -2.779776 90)
			(unlocked yes)
			(layer "F.SilkS")
			(effects
				(font
					(size 0.7874 0.5842)
					(thickness 0.1524)
				)
				(justify left)
			)
		)
		(property "Value" ""
			(at 0 0 270)
			(layer "F.Fab")
			(effects
				(font
					(size 1.27 1.27)
				)
			)
		)
		(duplicate_pad_numbers_are_jumpers no)
		(fp_line
			(start -3.656584 1.970024)
			(end 4.240784 1.970024)
			(stroke
				(width 0.1524)
				(type default)
			)
			(layer "F.SilkS")
		)
		(fp_line
			(start 4.240784 1.970024)
			(end 4.240784 -1.970024)
			(stroke
				(width 0.1524)
				(type default)
			)
			(layer "F.SilkS")
		)
		(fp_line
			(start -3.656584 -1.970024)
			(end -3.656584 1.970024)
			(stroke
				(width 0.1524)
				(type default)
			)
			(layer "F.SilkS")
		)
		(fp_line
			(start 4.240784 -1.970024)
			(end -3.656584 -1.970024)
			(stroke
				(width 0.1524)
				(type default)
			)
			(layer "F.SilkS")
		)
		(fp_rect
			(start 4.240784 1.970024)
			(end 3.580384 -1.970024)
			(stroke
				(width 0)
				(type default)
			)
			(fill yes)
			(layer "F.SilkS")
		)
		(fp_line
			(start -2.3749 1.970024)
			(end 2.3749 1.970024)
			(stroke
				(width 0.1)
				(type default)
			)
			(layer "F.Fab")
		)
		(fp_line
			(start 2.3749 1.970024)
			(end 2.3749 -1.970024)
			(stroke
				(width 0.1)
				(type default)
			)
			(layer "F.Fab")
		)
		(fp_line
			(start -2.3749 -1.970024)
			(end -2.3749 1.970024)
			(stroke
				(width 0.1)
				(type default)
			)
			(layer "F.Fab")
		)
		(fp_line
			(start 2.3749 -1.970024)
			(end -2.3749 -1.970024)
			(stroke
				(width 0.1)
				(type default)
			)
			(layer "F.Fab")
		)
		(fp_text user "+"
			(at -4.9784 -0.23495 270)
			(unlocked yes)
			(layer "F.Fab")
			(effects
				(font
					(size 1.905 1.4224)
					(thickness 0.1524)
				)
				(justify left)
			)
		)
		(fp_text user "-"
			(at 4.1656 -0.23495 270)
			(unlocked yes)
			(layer "F.Fab")
			(effects
				(font
					(size 1.905 1.4224)
					(thickness 0.1524)
				)
				(justify left)
			)
		)
		(pad "A" smd rect
			(at -2.450084 0 270)
			(size 2.159 2.2606)
			(layers "F.Cu" "F.Mask" "F.Paste")
			(net "GND")
		)
		(pad "C" smd rect
			(at 2.450084 0 270)
			(size 2.159 2.2606)
			(layers "F.Cu" "F.Mask" "F.Paste")
			(net "P12V_AUX")
		)
	)
	(footprint ""
		(layer "F.Cu")
		(at 299.875702 -343.952322 90)
		(property "Reference" "C2370"
			(at 0 0 90)
			(layer "F.SilkS")
			(hide yes)
			(effects
				(font
					(size 1.27 1.27)
				)
			)
		)
		(property "Value" ""
			(at 0 0 90)
			(layer "F.Fab")
			(effects
				(font
					(size 1.27 1.27)
				)
			)
		)
		(duplicate_pad_numbers_are_jumpers no)
		(fp_line
			(start 0.299974 -0.150114)
			(end 0.299974 0.150114)
			(stroke
				(width 0.1)
				(type default)
			)
			(layer "F.Fab")
		)
		(fp_line
			(start -0.299974 -0.150114)
			(end 0.299974 -0.150114)
			(stroke
				(width 0.1)
				(type default)
			)
			(layer "F.Fab")
		)
		(fp_line
			(start 0.299974 0.150114)
			(end -0.299974 0.150114)
			(stroke
				(width 0.1)
				(type default)
			)
			(layer "F.Fab")
		)
		(fp_line
			(start -0.299974 0.150114)
			(end -0.299974 -0.150114)
			(stroke
				(width 0.1)
				(type default)
			)
			(layer "F.Fab")
		)
		(pad "1" smd rect
			(at -0.2667 0 90)
			(size 0.3048 0.381)
			(layers "F.Cu" "F.Mask" "F.Paste")
			(net "P5E_PEX2_STN4_TX_DN<65>")
		)
		(pad "2" smd rect
			(at 0.2667 0 90)
			(size 0.3048 0.381)
			(layers "F.Cu" "F.Mask" "F.Paste")
			(net "P5E_PEX2_STN4_TX_C_DN<65>")
		)
	)
	(footprint ""
		(layer "F.Cu")
		(at 86.178898 -59.577986 -90)
		(property "Reference" "R893"
			(at 0 0 270)
			(layer "F.SilkS")
			(hide yes)
			(effects
				(font
					(size 1.27 1.27)
				)
			)
		)
		(property "Value" ""
			(at 0 0 270)
			(layer "F.Fab")
			(effects
				(font
					(size 1.27 1.27)
				)
			)
		)
		(duplicate_pad_numbers_are_jumpers no)
		(fp_line
			(start -0.7874 0.4064)
			(end -0.7874 -0.4064)
			(stroke
				(width 0.1524)
				(type default)
			)
			(layer "F.SilkS")
		)
		(fp_line
			(start 0.7874 0.4064)
			(end -0.7874 0.4064)
			(stroke
				(width 0.1524)
				(type default)
			)
			(layer "F.SilkS")
		)
		(fp_line
			(start -0.7874 -0.4064)
			(end 0.7874 -0.4064)
			(stroke
				(width 0.1524)
				(type default)
			)
			(layer "F.SilkS")
		)
		(fp_line
			(start 0.7874 -0.4064)
			(end 0.7874 0.4064)
			(stroke
				(width 0.1524)
				(type default)
			)
			(layer "F.SilkS")
		)
		(fp_line
			(start -0.67945 0.3048)
			(end -0.67945 -0.305054)
			(stroke
				(width 0.1)
				(type default)
			)
			(layer "F.Fab")
		)
		(fp_line
			(start -0.12065 0.3048)
			(end -0.67945 0.3048)
			(stroke
				(width 0.1)
				(type default)
			)
			(layer "F.Fab")
		)
		(fp_line
			(start 0.120396 0.3048)
			(end 0.120396 0.2794)
			(stroke
				(width 0.1)
				(type default)
			)
			(layer "F.Fab")
		)
		(fp_line
			(start 0.67945 0.3048)
			(end 0.120396 0.3048)
			(stroke
				(width 0.1)
				(type default)
			)
			(layer "F.Fab")
		)
		(fp_line
			(start -0.12065 0.2794)
			(end -0.12065 0.3048)
			(stroke
				(width 0.1)
				(type default)
			)
			(layer "F.Fab")
		)
		(fp_line
			(start 0.120396 0.2794)
			(end -0.12065 0.2794)
			(stroke
				(width 0.1)
				(type default)
			)
			(layer "F.Fab")
		)
		(fp_line
			(start -0.12065 -0.2794)
			(end 0.12065 -0.2794)
			(stroke
				(width 0.1)
				(type default)
			)
			(layer "F.Fab")
		)
		(fp_line
			(start 0.12065 -0.2794)
			(end 0.12065 -0.3048)
			(stroke
				(width 0.1)
				(type default)
			)
			(layer "F.Fab")
		)
		(fp_line
			(start 0.12065 -0.3048)
			(end 0.67945 -0.3048)
			(stroke
				(width 0.1)
				(type default)
			)
			(layer "F.Fab")
		)
		(fp_line
			(start 0.67945 -0.3048)
			(end 0.67945 0.3048)
			(stroke
				(width 0.1)
				(type default)
			)
			(layer "F.Fab")
		)
		(fp_line
			(start -0.67945 -0.305054)
			(end -0.12065 -0.305054)
			(stroke
				(width 0.1)
				(type default)
			)
			(layer "F.Fab")
		)
		(fp_line
			(start -0.12065 -0.305054)
			(end -0.12065 -0.2794)
			(stroke
				(width 0.1)
				(type default)
			)
			(layer "F.Fab")
		)
		(pad "1" smd circle
			(at -0.40005 0 270)
			(size 0 0)
			(layers "F.Cu" "F.Mask" "F.Paste")
			(net "P3V3_SSD3")
		)
		(pad "2" smd circle
			(at 0.40005 0 270)
			(size 0 0)
			(layers "F.Cu" "F.Mask" "F.Paste")
			(net "PWRGD_P3V3_SSD3")
		)
	)
	(footprint ""
		(layer "F.Cu")
		(at 417.158424 -241.83975 180)
		(property "Reference" "R6620"
			(at 0 0 180)
			(layer "F.SilkS")
			(hide yes)
			(effects
				(font
					(size 1.27 1.27)
				)
			)
		)
		(property "Value" ""
			(at 0 0 180)
			(layer "F.Fab")
			(effects
				(font
					(size 1.27 1.27)
				)
			)
		)
		(duplicate_pad_numbers_are_jumpers no)
		(fp_line
			(start 0.7874 0.4064)
			(end -0.7874 0.4064)
			(stroke
				(width 0.1524)
				(type default)
			)
			(layer "F.SilkS")
		)
		(fp_line
			(start 0.7874 -0.4064)
			(end 0.7874 0.4064)
			(stroke
				(width 0.1524)
				(type default)
			)
			(layer "F.SilkS")
		)
		(fp_line
			(start -0.7874 0.4064)
			(end -0.7874 -0.4064)
			(stroke
				(width 0.1524)
				(type default)
			)
			(layer "F.SilkS")
		)
		(fp_line
			(start -0.7874 -0.4064)
			(end 0.7874 -0.4064)
			(stroke
				(width 0.1524)
				(type default)
			)
			(layer "F.SilkS")
		)
		(fp_line
			(start 0.67945 0.3048)
			(end 0.120396 0.3048)
			(stroke
				(width 0.1)
				(type default)
			)
			(layer "F.Fab")
		)
		(fp_line
			(start 0.67945 -0.3048)
			(end 0.67945 0.3048)
			(stroke
				(width 0.1)
				(type default)
			)
			(layer "F.Fab")
		)
		(fp_line
			(start 0.12065 -0.2794)
			(end 0.12065 -0.3048)
			(stroke
				(width 0.1)
				(type default)
			)
			(layer "F.Fab")
		)
		(fp_line
			(start 0.12065 -0.3048)
			(end 0.67945 -0.3048)
			(stroke
				(width 0.1)
				(type default)
			)
			(layer "F.Fab")
		)
		(fp_line
			(start 0.120396 0.3048)
			(end 0.120396 0.2794)
			(stroke
				(width 0.1)
				(type default)
			)
			(layer "F.Fab")
		)
		(fp_line
			(start 0.120396 0.2794)
			(end -0.12065 0.2794)
			(stroke
				(width 0.1)
				(type default)
			)
			(layer "F.Fab")
		)
		(fp_line
			(start -0.12065 0.3048)
			(end -0.67945 0.3048)
			(stroke
				(width 0.1)
				(type default)
			)
			(layer "F.Fab")
		)
		(fp_line
			(start -0.12065 0.2794)
			(end -0.12065 0.3048)
			(stroke
				(width 0.1)
				(type default)
			)
			(layer "F.Fab")
		)
		(fp_line
			(start -0.12065 -0.2794)
			(end 0.12065 -0.2794)
			(stroke
				(width 0.1)
				(type default)
			)
			(layer "F.Fab")
		)
		(fp_line
			(start -0.12065 -0.305054)
			(end -0.12065 -0.2794)
			(stroke
				(width 0.1)
				(type default)
			)
			(layer "F.Fab")
		)
		(fp_line
			(start -0.67945 0.3048)
			(end -0.67945 -0.305054)
			(stroke
				(width 0.1)
				(type default)
			)
			(layer "F.Fab")
		)
		(fp_line
			(start -0.67945 -0.305054)
			(end -0.12065 -0.305054)
			(stroke
				(width 0.1)
				(type default)
			)
			(layer "F.Fab")
		)
		(pad "1" smd circle
			(at -0.40005 0 180)
			(size 0 0)
			(layers "F.Cu" "F.Mask" "F.Paste")
			(net "UART_PEX2_SDB_BUF_R_TX")
		)
		(pad "2" smd circle
			(at 0.40005 0 180)
			(size 0 0)
			(layers "F.Cu" "F.Mask" "F.Paste")
			(net "UART_PEX2_SDB_BUF_R1_TX")
		)
	)
	(footprint ""
		(layer "F.Cu")
		(at 112.311942 -112.547654)
		(property "Reference" "PC617"
			(at 0 0 0)
			(layer "F.SilkS")
			(hide yes)
			(effects
				(font
					(size 1.27 1.27)
				)
			)
		)
		(property "Value" ""
			(at 0 0 0)
			(layer "F.Fab")
			(effects
				(font
					(size 1.27 1.27)
				)
			)
		)
		(duplicate_pad_numbers_are_jumpers no)
		(fp_line
			(start -0.7874 -0.4064)
			(end 0.7874 -0.4064)
			(stroke
				(width 0.1524)
				(type default)
			)
			(layer "F.SilkS")
		)
		(fp_line
			(start -0.7874 0.4064)
			(end -0.7874 -0.4064)
			(stroke
				(width 0.1524)
				(type default)
			)
			(layer "F.SilkS")
		)
		(fp_line
			(start 0.7874 -0.4064)
			(end 0.7874 0.4064)
			(stroke
				(width 0.1524)
				(type default)
			)
			(layer "F.SilkS")
		)
		(fp_line
			(start 0.7874 0.4064)
			(end -0.7874 0.4064)
			(stroke
				(width 0.1524)
				(type default)
			)
			(layer "F.SilkS")
		)
		(fp_line
			(start -0.67945 -0.305054)
			(end -0.12065 -0.305054)
			(stroke
				(width 0.1)
				(type default)
			)
			(layer "F.Fab")
		)
		(fp_line
			(start -0.67945 0.3048)
			(end -0.67945 -0.305054)
			(stroke
				(width 0.1)
				(type default)
			)
			(layer "F.Fab")
		)
		(fp_line
			(start -0.12065 -0.305054)
			(end -0.12065 -0.2794)
			(stroke
				(width 0.1)
				(type default)
			)
			(layer "F.Fab")
		)
		(fp_line
			(start -0.12065 -0.2794)
			(end 0.12065 -0.2794)
			(stroke
				(width 0.1)
				(type default)
			)
			(layer "F.Fab")
		)
		(fp_line
			(start -0.12065 0.2794)
			(end -0.12065 0.3048)
			(stroke
				(width 0.1)
				(type default)
			)
			(layer "F.Fab")
		)
		(fp_line
			(start -0.12065 0.3048)
			(end -0.67945 0.3048)
			(stroke
				(width 0.1)
				(type default)
			)
			(layer "F.Fab")
		)
		(fp_line
			(start 0.120396 0.2794)
			(end -0.12065 0.2794)
			(stroke
				(width 0.1)
				(type default)
			)
			(layer "F.Fab")
		)
		(fp_line
			(start 0.120396 0.3048)
			(end 0.120396 0.2794)
			(stroke
				(width 0.1)
				(type default)
			)
			(layer "F.Fab")
		)
		(fp_line
			(start 0.12065 -0.3048)
			(end 0.67945 -0.3048)
			(stroke
				(width 0.1)
				(type default)
			)
			(layer "F.Fab")
		)
		(fp_line
			(start 0.12065 -0.2794)
			(end 0.12065 -0.3048)
			(stroke
				(width 0.1)
				(type default)
			)
			(layer "F.Fab")
		)
		(fp_line
			(start 0.67945 -0.3048)
			(end 0.67945 0.3048)
			(stroke
				(width 0.1)
				(type default)
			)
			(layer "F.Fab")
		)
		(fp_line
			(start 0.67945 0.3048)
			(end 0.120396 0.3048)
			(stroke
				(width 0.1)
				(type default)
			)
			(layer "F.Fab")
		)
		(pad "1" smd circle
			(at -0.40005 0)
			(size 0 0)
			(layers "F.Cu" "F.Mask" "F.Paste")
			(net "P12V_NIC1_CO_ISET_R")
		)
		(pad "2" smd circle
			(at 0.40005 0)
			(size 0 0)
			(layers "F.Cu" "F.Mask" "F.Paste")
			(net "GND")
		)
	)
	(footprint ""
		(layer "F.Cu")
		(at 424.683428 -49.94148)
		(property "Reference" "R665"
			(at 0 0 0)
			(layer "F.SilkS")
			(hide yes)
			(effects
				(font
					(size 1.27 1.27)
				)
			)
		)
		(property "Value" ""
			(at 0 0 0)
			(layer "F.Fab")
			(effects
				(font
					(size 1.27 1.27)
				)
			)
		)
		(duplicate_pad_numbers_are_jumpers no)
		(fp_line
			(start -0.7874 -0.4064)
			(end 0.7874 -0.4064)
			(stroke
				(width 0.1524)
				(type default)
			)
			(layer "F.SilkS")
		)
		(fp_line
			(start -0.7874 0.4064)
			(end -0.7874 -0.4064)
			(stroke
				(width 0.1524)
				(type default)
			)
			(layer "F.SilkS")
		)
		(fp_line
			(start 0.7874 -0.4064)
			(end 0.7874 0.4064)
			(stroke
				(width 0.1524)
				(type default)
			)
			(layer "F.SilkS")
		)
		(fp_line
			(start 0.7874 0.4064)
			(end -0.7874 0.4064)
			(stroke
				(width 0.1524)
				(type default)
			)
			(layer "F.SilkS")
		)
		(fp_line
			(start -0.67945 -0.305054)
			(end -0.12065 -0.305054)
			(stroke
				(width 0.1)
				(type default)
			)
			(layer "F.Fab")
		)
		(fp_line
			(start -0.67945 0.3048)
			(end -0.67945 -0.305054)
			(stroke
				(width 0.1)
				(type default)
			)
			(layer "F.Fab")
		)
		(fp_line
			(start -0.12065 -0.305054)
			(end -0.12065 -0.2794)
			(stroke
				(width 0.1)
				(type default)
			)
			(layer "F.Fab")
		)
		(fp_line
			(start -0.12065 -0.2794)
			(end 0.12065 -0.2794)
			(stroke
				(width 0.1)
				(type default)
			)
			(layer "F.Fab")
		)
		(fp_line
			(start -0.12065 0.2794)
			(end -0.12065 0.3048)
			(stroke
				(width 0.1)
				(type default)
			)
			(layer "F.Fab")
		)
		(fp_line
			(start -0.12065 0.3048)
			(end -0.67945 0.3048)
			(stroke
				(width 0.1)
				(type default)
			)
			(layer "F.Fab")
		)
		(fp_line
			(start 0.120396 0.2794)
			(end -0.12065 0.2794)
			(stroke
				(width 0.1)
				(type default)
			)
			(layer "F.Fab")
		)
		(fp_line
			(start 0.120396 0.3048)
			(end 0.120396 0.2794)
			(stroke
				(width 0.1)
				(type default)
			)
			(layer "F.Fab")
		)
		(fp_line
			(start 0.12065 -0.3048)
			(end 0.67945 -0.3048)
			(stroke
				(width 0.1)
				(type default)
			)
			(layer "F.Fab")
		)
		(fp_line
			(start 0.12065 -0.2794)
			(end 0.12065 -0.3048)
			(stroke
				(width 0.1)
				(type default)
			)
			(layer "F.Fab")
		)
		(fp_line
			(start 0.67945 -0.3048)
			(end 0.67945 0.3048)
			(stroke
				(width 0.1)
				(type default)
			)
			(layer "F.Fab")
		)
		(fp_line
			(start 0.67945 0.3048)
			(end 0.120396 0.3048)
			(stroke
				(width 0.1)
				(type default)
			)
			(layer "F.Fab")
		)
		(pad "1" smd circle
			(at -0.40005 0)
			(size 0 0)
			(layers "F.Cu" "F.Mask" "F.Paste")
			(net "SMB_BIC_I2C6_MUX_SSD_8_15_ADC_R_SCL")
		)
		(pad "2" smd circle
			(at 0.40005 0)
			(size 0 0)
			(layers "F.Cu" "F.Mask" "F.Paste")
			(net "SMB_SSD14_ADC_SCL")
		)
	)
	(footprint ""
		(layer "F.Cu")
		(at 110.01502 -17.999964)
		(property "Reference" "H51"
			(at -4.94157 -5.132578 0)
			(unlocked yes)
			(layer "F.SilkS")
			(effects
				(font
					(size 0.7874 0.5842)
					(thickness 0.1524)
				)
				(justify left)
			)
		)
		(property "Value" ""
			(at 0 0 0)
			(layer "F.Fab")
			(effects
				(font
					(size 1.27 1.27)
				)
			)
		)
		(duplicate_pad_numbers_are_jumpers no)
		(pad "1" thru_hole circle
			(at 0 0)
			(size 10.0076 10.0076)
			(drill 5.6134)
			(layers "*.Cu" "*.Mask")
			(remove_unused_layers no)
			(net "GND")
			(clearance -1.9431)
		)
	)
	(footprint ""
		(layer "F.Cu")
		(at 236.832648 -172.55998 -90)
		(property "Reference" "C2808"
			(at 0 0 270)
			(layer "F.SilkS")
			(hide yes)
			(effects
				(font
					(size 1.27 1.27)
				)
			)
		)
		(property "Value" ""
			(at 0 0 270)
			(layer "F.Fab")
			(effects
				(font
					(size 1.27 1.27)
				)
			)
		)
		(duplicate_pad_numbers_are_jumpers no)
		(fp_line
			(start -0.7874 0.4064)
			(end -0.7874 -0.4064)
			(stroke
				(width 0.1524)
				(type default)
			)
			(layer "F.SilkS")
		)
		(fp_line
			(start 0.7874 0.4064)
			(end -0.7874 0.4064)
			(stroke
				(width 0.1524)
				(type default)
			)
			(layer "F.SilkS")
		)
		(fp_line
			(start -0.7874 -0.4064)
			(end 0.7874 -0.4064)
			(stroke
				(width 0.1524)
				(type default)
			)
			(layer "F.SilkS")
		)
		(fp_line
			(start 0.7874 -0.4064)
			(end 0.7874 0.4064)
			(stroke
				(width 0.1524)
				(type default)
			)
			(layer "F.SilkS")
		)
		(fp_line
			(start -0.67945 0.3048)
			(end -0.67945 -0.305054)
			(stroke
				(width 0.1)
				(type default)
			)
			(layer "F.Fab")
		)
		(fp_line
			(start -0.12065 0.3048)
			(end -0.67945 0.3048)
			(stroke
				(width 0.1)
				(type default)
			)
			(layer "F.Fab")
		)
		(fp_line
			(start 0.120396 0.3048)
			(end 0.120396 0.2794)
			(stroke
				(width 0.1)
				(type default)
			)
			(layer "F.Fab")
		)
		(fp_line
			(start 0.67945 0.3048)
			(end 0.120396 0.3048)
			(stroke
				(width 0.1)
				(type default)
			)
			(layer "F.Fab")
		)
		(fp_line
			(start -0.12065 0.2794)
			(end -0.12065 0.3048)
			(stroke
				(width 0.1)
				(type default)
			)
			(layer "F.Fab")
		)
		(fp_line
			(start 0.120396 0.2794)
			(end -0.12065 0.2794)
			(stroke
				(width 0.1)
				(type default)
			)
			(layer "F.Fab")
		)
		(fp_line
			(start -0.12065 -0.2794)
			(end 0.12065 -0.2794)
			(stroke
				(width 0.1)
				(type default)
			)
			(layer "F.Fab")
		)
		(fp_line
			(start 0.12065 -0.2794)
			(end 0.12065 -0.3048)
			(stroke
				(width 0.1)
				(type default)
			)
			(layer "F.Fab")
		)
		(fp_line
			(start 0.12065 -0.3048)
			(end 0.67945 -0.3048)
			(stroke
				(width 0.1)
				(type default)
			)
			(layer "F.Fab")
		)
		(fp_line
			(start 0.67945 -0.3048)
			(end 0.67945 0.3048)
			(stroke
				(width 0.1)
				(type default)
			)
			(layer "F.Fab")
		)
		(fp_line
			(start -0.67945 -0.305054)
			(end -0.12065 -0.305054)
			(stroke
				(width 0.1)
				(type default)
			)
			(layer "F.Fab")
		)
		(fp_line
			(start -0.12065 -0.305054)
			(end -0.12065 -0.2794)
			(stroke
				(width 0.1)
				(type default)
			)
			(layer "F.Fab")
		)
		(pad "1" smd circle
			(at -0.40005 0 270)
			(size 0 0)
			(layers "F.Cu" "F.Mask" "F.Paste")
			(net "P3V3_AUX")
		)
		(pad "2" smd circle
			(at 0.40005 0 270)
			(size 0 0)
			(layers "F.Cu" "F.Mask" "F.Paste")
			(net "GND")
		)
	)
	(footprint ""
		(layer "F.Cu")
		(at 109.668056 -128.0541 90)
		(property "Reference" "PC301"
			(at 0 0 90)
			(layer "F.SilkS")
			(hide yes)
			(effects
				(font
					(size 1.27 1.27)
				)
			)
		)
		(property "Value" ""
			(at 0 0 90)
			(layer "F.Fab")
			(effects
				(font
					(size 1.27 1.27)
				)
			)
		)
		(duplicate_pad_numbers_are_jumpers no)
		(fp_line
			(start 1.524 -0.762)
			(end 1.524 0.762)
			(stroke
				(width 0.1524)
				(type default)
			)
			(layer "F.SilkS")
		)
		(fp_line
			(start -1.524 -0.762)
			(end 1.524 -0.762)
			(stroke
				(width 0.1524)
				(type default)
			)
			(layer "F.SilkS")
		)
		(fp_line
			(start 1.524 0.762)
			(end -1.524 0.762)
			(stroke
				(width 0.1524)
				(type default)
			)
			(layer "F.SilkS")
		)
		(fp_line
			(start -1.524 0.762)
			(end -1.524 -0.762)
			(stroke
				(width 0.1524)
				(type default)
			)
			(layer "F.SilkS")
		)
		(fp_line
			(start 1.1049 -0.724916)
			(end -1.1049 -0.724916)
			(stroke
				(width 0.1)
				(type default)
			)
			(layer "F.Fab")
		)
		(fp_line
			(start -1.1049 -0.724916)
			(end -1.1049 0.724916)
			(stroke
				(width 0.1)
				(type default)
			)
			(layer "F.Fab")
		)
		(fp_line
			(start 1.1049 0.724916)
			(end 1.1049 -0.724916)
			(stroke
				(width 0.1)
				(type default)
			)
			(layer "F.Fab")
		)
		(fp_line
			(start -1.1049 0.724916)
			(end 1.1049 0.724916)
			(stroke
				(width 0.1)
				(type default)
			)
			(layer "F.Fab")
		)
		(pad "1" smd rect
			(at -0.889 0 270)
			(size 1.016 1.27)
			(layers "F.Cu" "F.Mask" "F.Paste")
			(net "P3V3")
		)
		(pad "2" smd rect
			(at 0.889 0 270)
			(size 1.016 1.27)
			(layers "F.Cu" "F.Mask" "F.Paste")
			(net "GND")
		)
	)
	(footprint ""
		(layer "F.Cu")
		(at 123.71324 -140.392404 180)
		(property "Reference" "PC338"
			(at 0 0 180)
			(layer "F.SilkS")
			(hide yes)
			(effects
				(font
					(size 1.27 1.27)
				)
			)
		)
		(property "Value" ""
			(at 0 0 180)
			(layer "F.Fab")
			(effects
				(font
					(size 1.27 1.27)
				)
			)
		)
		(duplicate_pad_numbers_are_jumpers no)
		(fp_line
			(start 0.7874 0.4064)
			(end -0.7874 0.4064)
			(stroke
				(width 0.1524)
				(type default)
			)
			(layer "F.SilkS")
		)
		(fp_line
			(start 0.7874 -0.4064)
			(end 0.7874 0.4064)
			(stroke
				(width 0.1524)
				(type default)
			)
			(layer "F.SilkS")
		)
		(fp_line
			(start -0.7874 0.4064)
			(end -0.7874 -0.4064)
			(stroke
				(width 0.1524)
				(type default)
			)
			(layer "F.SilkS")
		)
		(fp_line
			(start -0.7874 -0.4064)
			(end 0.7874 -0.4064)
			(stroke
				(width 0.1524)
				(type default)
			)
			(layer "F.SilkS")
		)
		(fp_line
			(start 0.6858 0.3048)
			(end 0.1016 0.3048)
			(stroke
				(width 0.1)
				(type default)
			)
			(layer "F.Fab")
		)
		(fp_line
			(start 0.6858 -0.3048)
			(end 0.6858 0.3048)
			(stroke
				(width 0.1)
				(type default)
			)
			(layer "F.Fab")
		)
		(fp_line
			(start 0.1016 0.3048)
			(end 0.1016 0.2794)
			(stroke
				(width 0.1)
				(type default)
			)
			(layer "F.Fab")
		)
		(fp_line
			(start 0.1016 0.2794)
			(end -0.1016 0.2794)
			(stroke
				(width 0.1)
				(type default)
			)
			(layer "F.Fab")
		)
		(fp_line
			(start 0.1016 -0.2794)
			(end 0.1016 -0.3048)
			(stroke
				(width 0.1)
				(type default)
			)
			(layer "F.Fab")
		)
		(fp_line
			(start 0.1016 -0.3048)
			(end 0.6858 -0.3048)
			(stroke
				(width 0.1)
				(type default)
			)
			(layer "F.Fab")
		)
		(fp_line
			(start -0.1016 0.3048)
			(end -0.6858 0.3048)
			(stroke
				(width 0.1)
				(type default)
			)
			(layer "F.Fab")
		)
		(fp_line
			(start -0.1016 0.2794)
			(end -0.1016 0.3048)
			(stroke
				(width 0.1)
				(type default)
			)
			(layer "F.Fab")
		)
		(fp_line
			(start -0.1016 -0.2794)
			(end 0.1016 -0.2794)
			(stroke
				(width 0.1)
				(type default)
			)
			(layer "F.Fab")
		)
		(fp_line
			(start -0.1016 -0.3048)
			(end -0.1016 -0.2794)
			(stroke
				(width 0.1)
				(type default)
			)
			(layer "F.Fab")
		)
		(fp_line
			(start -0.6858 0.3048)
			(end -0.6858 -0.3048)
			(stroke
				(width 0.1)
				(type default)
			)
			(layer "F.Fab")
		)
		(fp_line
			(start -0.6858 -0.3048)
			(end -0.1016 -0.3048)
			(stroke
				(width 0.1)
				(type default)
			)
			(layer "F.Fab")
		)
		(pad "1" smd rect
			(at -0.40005 0)
			(size 0.4572 0.508)
			(layers "F.Cu" "F.Mask" "F.Paste")
			(net "P12V_NIC2_SS")
		)
		(pad "2" smd rect
			(at 0.40005 0)
			(size 0.4572 0.508)
			(layers "F.Cu" "F.Mask" "F.Paste")
			(net "GND")
		)
	)
	(footprint ""
		(layer "F.Cu")
		(at 4.526788 -53.697124 -90)
		(property "Reference" "PC510"
			(at 0 0 270)
			(layer "F.SilkS")
			(hide yes)
			(effects
				(font
					(size 1.27 1.27)
				)
			)
		)
		(property "Value" ""
			(at 0 0 270)
			(layer "F.Fab")
			(effects
				(font
					(size 1.27 1.27)
				)
			)
		)
		(duplicate_pad_numbers_are_jumpers no)
		(fp_line
			(start -0.7874 0.4064)
			(end -0.7874 -0.4064)
			(stroke
				(width 0.1524)
				(type default)
			)
			(layer "F.SilkS")
		)
		(fp_line
			(start 0.7874 0.4064)
			(end -0.7874 0.4064)
			(stroke
				(width 0.1524)
				(type default)
			)
			(layer "F.SilkS")
		)
		(fp_line
			(start -0.7874 -0.4064)
			(end 0.7874 -0.4064)
			(stroke
				(width 0.1524)
				(type default)
			)
			(layer "F.SilkS")
		)
		(fp_line
			(start 0.7874 -0.4064)
			(end 0.7874 0.4064)
			(stroke
				(width 0.1524)
				(type default)
			)
			(layer "F.SilkS")
		)
		(fp_line
			(start -0.67945 0.3048)
			(end -0.67945 -0.305054)
			(stroke
				(width 0.1)
				(type default)
			)
			(layer "F.Fab")
		)
		(fp_line
			(start -0.12065 0.3048)
			(end -0.67945 0.3048)
			(stroke
				(width 0.1)
				(type default)
			)
			(layer "F.Fab")
		)
		(fp_line
			(start 0.120396 0.3048)
			(end 0.120396 0.2794)
			(stroke
				(width 0.1)
				(type default)
			)
			(layer "F.Fab")
		)
		(fp_line
			(start 0.67945 0.3048)
			(end 0.120396 0.3048)
			(stroke
				(width 0.1)
				(type default)
			)
			(layer "F.Fab")
		)
		(fp_line
			(start -0.12065 0.2794)
			(end -0.12065 0.3048)
			(stroke
				(width 0.1)
				(type default)
			)
			(layer "F.Fab")
		)
		(fp_line
			(start 0.120396 0.2794)
			(end -0.12065 0.2794)
			(stroke
				(width 0.1)
				(type default)
			)
			(layer "F.Fab")
		)
		(fp_line
			(start -0.12065 -0.2794)
			(end 0.12065 -0.2794)
			(stroke
				(width 0.1)
				(type default)
			)
			(layer "F.Fab")
		)
		(fp_line
			(start 0.12065 -0.2794)
			(end 0.12065 -0.3048)
			(stroke
				(width 0.1)
				(type default)
			)
			(layer "F.Fab")
		)
		(fp_line
			(start 0.12065 -0.3048)
			(end 0.67945 -0.3048)
			(stroke
				(width 0.1)
				(type default)
			)
			(layer "F.Fab")
		)
		(fp_line
			(start 0.67945 -0.3048)
			(end 0.67945 0.3048)
			(stroke
				(width 0.1)
				(type default)
			)
			(layer "F.Fab")
		)
		(fp_line
			(start -0.67945 -0.305054)
			(end -0.12065 -0.305054)
			(stroke
				(width 0.1)
				(type default)
			)
			(layer "F.Fab")
		)
		(fp_line
			(start -0.12065 -0.305054)
			(end -0.12065 -0.2794)
			(stroke
				(width 0.1)
				(type default)
			)
			(layer "F.Fab")
		)
		(pad "1" smd circle
			(at -0.40005 0 270)
			(size 0 0)
			(layers "F.Cu" "F.Mask" "F.Paste")
			(net "P3V3_AUX")
		)
		(pad "2" smd circle
			(at 0.40005 0 270)
			(size 0 0)
			(layers "F.Cu" "F.Mask" "F.Paste")
			(net "GND")
		)
	)
	(footprint ""
		(layer "F.Cu")
		(at 323.917818 -218.309698 180)
		(property "Reference" "R2984"
			(at 0 0 180)
			(layer "F.SilkS")
			(hide yes)
			(effects
				(font
					(size 1.27 1.27)
				)
			)
		)
		(property "Value" ""
			(at 0 0 180)
			(layer "F.Fab")
			(effects
				(font
					(size 1.27 1.27)
				)
			)
		)
		(duplicate_pad_numbers_are_jumpers no)
		(fp_line
			(start 0.7874 0.4064)
			(end -0.7874 0.4064)
			(stroke
				(width 0.1524)
				(type default)
			)
			(layer "F.SilkS")
		)
		(fp_line
			(start 0.7874 -0.4064)
			(end 0.7874 0.4064)
			(stroke
				(width 0.1524)
				(type default)
			)
			(layer "F.SilkS")
		)
		(fp_line
			(start -0.7874 0.4064)
			(end -0.7874 -0.4064)
			(stroke
				(width 0.1524)
				(type default)
			)
			(layer "F.SilkS")
		)
		(fp_line
			(start -0.7874 -0.4064)
			(end 0.7874 -0.4064)
			(stroke
				(width 0.1524)
				(type default)
			)
			(layer "F.SilkS")
		)
		(fp_line
			(start 0.67945 0.3048)
			(end 0.120396 0.3048)
			(stroke
				(width 0.1)
				(type default)
			)
			(layer "F.Fab")
		)
		(fp_line
			(start 0.67945 -0.3048)
			(end 0.67945 0.3048)
			(stroke
				(width 0.1)
				(type default)
			)
			(layer "F.Fab")
		)
		(fp_line
			(start 0.12065 -0.2794)
			(end 0.12065 -0.3048)
			(stroke
				(width 0.1)
				(type default)
			)
			(layer "F.Fab")
		)
		(fp_line
			(start 0.12065 -0.3048)
			(end 0.67945 -0.3048)
			(stroke
				(width 0.1)
				(type default)
			)
			(layer "F.Fab")
		)
		(fp_line
			(start 0.120396 0.3048)
			(end 0.120396 0.2794)
			(stroke
				(width 0.1)
				(type default)
			)
			(layer "F.Fab")
		)
		(fp_line
			(start 0.120396 0.2794)
			(end -0.12065 0.2794)
			(stroke
				(width 0.1)
				(type default)
			)
			(layer "F.Fab")
		)
		(fp_line
			(start -0.12065 0.3048)
			(end -0.67945 0.3048)
			(stroke
				(width 0.1)
				(type default)
			)
			(layer "F.Fab")
		)
		(fp_line
			(start -0.12065 0.2794)
			(end -0.12065 0.3048)
			(stroke
				(width 0.1)
				(type default)
			)
			(layer "F.Fab")
		)
		(fp_line
			(start -0.12065 -0.2794)
			(end 0.12065 -0.2794)
			(stroke
				(width 0.1)
				(type default)
			)
			(layer "F.Fab")
		)
		(fp_line
			(start -0.12065 -0.305054)
			(end -0.12065 -0.2794)
			(stroke
				(width 0.1)
				(type default)
			)
			(layer "F.Fab")
		)
		(fp_line
			(start -0.67945 0.3048)
			(end -0.67945 -0.305054)
			(stroke
				(width 0.1)
				(type default)
			)
			(layer "F.Fab")
		)
		(fp_line
			(start -0.67945 -0.305054)
			(end -0.12065 -0.305054)
			(stroke
				(width 0.1)
				(type default)
			)
			(layer "F.Fab")
		)
		(pad "1" smd circle
			(at -0.40005 0 180)
			(size 0 0)
			(layers "F.Cu" "F.Mask" "F.Paste")
			(net "LED_POSTCODE_6")
		)
		(pad "2" smd circle
			(at 0.40005 0 180)
			(size 0 0)
			(layers "F.Cu" "F.Mask" "F.Paste")
			(net "LED_POSTCODE_R_6")
		)
	)
	(footprint ""
		(layer "F.Cu")
		(at 82.661506 -121.391172 180)
		(property "Reference" "C29"
			(at 0 0 180)
			(layer "F.SilkS")
			(hide yes)
			(effects
				(font
					(size 1.27 1.27)
				)
			)
		)
		(property "Value" ""
			(at 0 0 180)
			(layer "F.Fab")
			(effects
				(font
					(size 1.27 1.27)
				)
			)
		)
		(duplicate_pad_numbers_are_jumpers no)
		(fp_line
			(start 0.299974 0.150114)
			(end -0.299974 0.150114)
			(stroke
				(width 0.1)
				(type default)
			)
			(layer "F.Fab")
		)
		(fp_line
			(start 0.299974 -0.150114)
			(end 0.299974 0.150114)
			(stroke
				(width 0.1)
				(type default)
			)
			(layer "F.Fab")
		)
		(fp_line
			(start -0.299974 0.150114)
			(end -0.299974 -0.150114)
			(stroke
				(width 0.1)
				(type default)
			)
			(layer "F.Fab")
		)
		(fp_line
			(start -0.299974 -0.150114)
			(end 0.299974 -0.150114)
			(stroke
				(width 0.1)
				(type default)
			)
			(layer "F.Fab")
		)
		(pad "1" smd rect
			(at -0.2667 0 180)
			(size 0.3048 0.381)
			(layers "F.Cu" "F.Mask" "F.Paste")
			(net "P5E_PEX0_STN0_TX_DP<1>")
		)
		(pad "2" smd rect
			(at 0.2667 0 180)
			(size 0.3048 0.381)
			(layers "F.Cu" "F.Mask" "F.Paste")
			(net "P5E_PEX0_STN0_TX_C_DP<1>")
		)
	)
	(footprint ""
		(layer "F.Cu")
		(at 330.473812 -72.766682 90)
		(property "Reference" "PR7083"
			(at 0 0 90)
			(layer "F.SilkS")
			(hide yes)
			(effects
				(font
					(size 1.27 1.27)
				)
			)
		)
		(property "Value" ""
			(at 0 0 90)
			(layer "F.Fab")
			(effects
				(font
					(size 1.27 1.27)
				)
			)
		)
		(duplicate_pad_numbers_are_jumpers no)
		(fp_line
			(start 0.7874 -0.4064)
			(end 0.7874 0.4064)
			(stroke
				(width 0.1524)
				(type default)
			)
			(layer "F.SilkS")
		)
		(fp_line
			(start -0.7874 -0.4064)
			(end 0.7874 -0.4064)
			(stroke
				(width 0.1524)
				(type default)
			)
			(layer "F.SilkS")
		)
		(fp_line
			(start 0.7874 0.4064)
			(end -0.7874 0.4064)
			(stroke
				(width 0.1524)
				(type default)
			)
			(layer "F.SilkS")
		)
		(fp_line
			(start -0.7874 0.4064)
			(end -0.7874 -0.4064)
			(stroke
				(width 0.1524)
				(type default)
			)
			(layer "F.SilkS")
		)
		(fp_line
			(start -0.12065 -0.305054)
			(end -0.12065 -0.2794)
			(stroke
				(width 0.1)
				(type default)
			)
			(layer "F.Fab")
		)
		(fp_line
			(start -0.67945 -0.305054)
			(end -0.12065 -0.305054)
			(stroke
				(width 0.1)
				(type default)
			)
			(layer "F.Fab")
		)
		(fp_line
			(start 0.67945 -0.3048)
			(end 0.67945 0.3048)
			(stroke
				(width 0.1)
				(type default)
			)
			(layer "F.Fab")
		)
		(fp_line
			(start 0.12065 -0.3048)
			(end 0.67945 -0.3048)
			(stroke
				(width 0.1)
				(type default)
			)
			(layer "F.Fab")
		)
		(fp_line
			(start 0.12065 -0.2794)
			(end 0.12065 -0.3048)
			(stroke
				(width 0.1)
				(type default)
			)
			(layer "F.Fab")
		)
		(fp_line
			(start -0.12065 -0.2794)
			(end 0.12065 -0.2794)
			(stroke
				(width 0.1)
				(type default)
			)
			(layer "F.Fab")
		)
		(fp_line
			(start 0.120396 0.2794)
			(end -0.12065 0.2794)
			(stroke
				(width 0.1)
				(type default)
			)
			(layer "F.Fab")
		)
		(fp_line
			(start -0.12065 0.2794)
			(end -0.12065 0.3048)
			(stroke
				(width 0.1)
				(type default)
			)
			(layer "F.Fab")
		)
		(fp_line
			(start 0.67945 0.3048)
			(end 0.120396 0.3048)
			(stroke
				(width 0.1)
				(type default)
			)
			(layer "F.Fab")
		)
		(fp_line
			(start 0.120396 0.3048)
			(end 0.120396 0.2794)
			(stroke
				(width 0.1)
				(type default)
			)
			(layer "F.Fab")
		)
		(fp_line
			(start -0.12065 0.3048)
			(end -0.67945 0.3048)
			(stroke
				(width 0.1)
				(type default)
			)
			(layer "F.Fab")
		)
		(fp_line
			(start -0.67945 0.3048)
			(end -0.67945 -0.305054)
			(stroke
				(width 0.1)
				(type default)
			)
			(layer "F.Fab")
		)
		(pad "1" smd circle
			(at -0.40005 0 90)
			(size 0 0)
			(layers "F.Cu" "F.Mask" "F.Paste")
			(net "P12V_SSD11_CO_MODE")
		)
		(pad "2" smd circle
			(at 0.40005 0 90)
			(size 0 0)
			(layers "F.Cu" "F.Mask" "F.Paste")
			(net "GND")
		)
	)
	(footprint ""
		(layer "F.Cu")
		(at 188.806074 -414.583626 90)
		(property "Reference" "R6779"
			(at 0 0 90)
			(layer "F.SilkS")
			(hide yes)
			(effects
				(font
					(size 1.27 1.27)
				)
			)
		)
		(property "Value" ""
			(at 0 0 90)
			(layer "F.Fab")
			(effects
				(font
					(size 1.27 1.27)
				)
			)
		)
		(duplicate_pad_numbers_are_jumpers no)
		(fp_line
			(start 0.7874 -0.4064)
			(end 0.7874 0.4064)
			(stroke
				(width 0.1524)
				(type default)
			)
			(layer "F.SilkS")
		)
		(fp_line
			(start -0.7874 -0.4064)
			(end 0.7874 -0.4064)
			(stroke
				(width 0.1524)
				(type default)
			)
			(layer "F.SilkS")
		)
		(fp_line
			(start 0.7874 0.4064)
			(end -0.7874 0.4064)
			(stroke
				(width 0.1524)
				(type default)
			)
			(layer "F.SilkS")
		)
		(fp_line
			(start -0.7874 0.4064)
			(end -0.7874 -0.4064)
			(stroke
				(width 0.1524)
				(type default)
			)
			(layer "F.SilkS")
		)
		(fp_line
			(start -0.12065 -0.305054)
			(end -0.12065 -0.2794)
			(stroke
				(width 0.1)
				(type default)
			)
			(layer "F.Fab")
		)
		(fp_line
			(start -0.67945 -0.305054)
			(end -0.12065 -0.305054)
			(stroke
				(width 0.1)
				(type default)
			)
			(layer "F.Fab")
		)
		(fp_line
			(start 0.67945 -0.3048)
			(end 0.67945 0.3048)
			(stroke
				(width 0.1)
				(type default)
			)
			(layer "F.Fab")
		)
		(fp_line
			(start 0.12065 -0.3048)
			(end 0.67945 -0.3048)
			(stroke
				(width 0.1)
				(type default)
			)
			(layer "F.Fab")
		)
		(fp_line
			(start 0.12065 -0.2794)
			(end 0.12065 -0.3048)
			(stroke
				(width 0.1)
				(type default)
			)
			(layer "F.Fab")
		)
		(fp_line
			(start -0.12065 -0.2794)
			(end 0.12065 -0.2794)
			(stroke
				(width 0.1)
				(type default)
			)
			(layer "F.Fab")
		)
		(fp_line
			(start 0.120396 0.2794)
			(end -0.12065 0.2794)
			(stroke
				(width 0.1)
				(type default)
			)
			(layer "F.Fab")
		)
		(fp_line
			(start -0.12065 0.2794)
			(end -0.12065 0.3048)
			(stroke
				(width 0.1)
				(type default)
			)
			(layer "F.Fab")
		)
		(fp_line
			(start 0.67945 0.3048)
			(end 0.120396 0.3048)
			(stroke
				(width 0.1)
				(type default)
			)
			(layer "F.Fab")
		)
		(fp_line
			(start 0.120396 0.3048)
			(end 0.120396 0.2794)
			(stroke
				(width 0.1)
				(type default)
			)
			(layer "F.Fab")
		)
		(fp_line
			(start -0.12065 0.3048)
			(end -0.67945 0.3048)
			(stroke
				(width 0.1)
				(type default)
			)
			(layer "F.Fab")
		)
		(fp_line
			(start -0.67945 0.3048)
			(end -0.67945 -0.305054)
			(stroke
				(width 0.1)
				(type default)
			)
			(layer "F.Fab")
		)
		(pad "1" smd circle
			(at -0.40005 0 90)
			(size 0 0)
			(layers "F.Cu" "F.Mask" "F.Paste")
			(net "P12V_AUX")
		)
		(pad "2" smd circle
			(at 0.40005 0 90)
			(size 0 0)
			(layers "F.Cu" "F.Mask" "F.Paste")
			(net "P12V_AUX_FP_TRIGGER")
		)
	)
	(footprint ""
		(layer "F.Cu")
		(at 410.00299 -388.253732 180)
		(property "Reference" "C4160"
			(at 0 0 180)
			(layer "F.SilkS")
			(hide yes)
			(effects
				(font
					(size 1.27 1.27)
				)
			)
		)
		(property "Value" ""
			(at 0 0 180)
			(layer "F.Fab")
			(effects
				(font
					(size 1.27 1.27)
				)
			)
		)
		(duplicate_pad_numbers_are_jumpers no)
		(fp_line
			(start 0.7874 0.4064)
			(end -0.7874 0.4064)
			(stroke
				(width 0.1524)
				(type default)
			)
			(layer "F.SilkS")
		)
		(fp_line
			(start 0.7874 -0.4064)
			(end 0.7874 0.4064)
			(stroke
				(width 0.1524)
				(type default)
			)
			(layer "F.SilkS")
		)
		(fp_line
			(start -0.7874 0.4064)
			(end -0.7874 -0.4064)
			(stroke
				(width 0.1524)
				(type default)
			)
			(layer "F.SilkS")
		)
		(fp_line
			(start -0.7874 -0.4064)
			(end 0.7874 -0.4064)
			(stroke
				(width 0.1524)
				(type default)
			)
			(layer "F.SilkS")
		)
		(fp_line
			(start 0.67945 0.3048)
			(end 0.120396 0.3048)
			(stroke
				(width 0.1)
				(type default)
			)
			(layer "F.Fab")
		)
		(fp_line
			(start 0.67945 -0.3048)
			(end 0.67945 0.3048)
			(stroke
				(width 0.1)
				(type default)
			)
			(layer "F.Fab")
		)
		(fp_line
			(start 0.12065 -0.2794)
			(end 0.12065 -0.3048)
			(stroke
				(width 0.1)
				(type default)
			)
			(layer "F.Fab")
		)
		(fp_line
			(start 0.12065 -0.3048)
			(end 0.67945 -0.3048)
			(stroke
				(width 0.1)
				(type default)
			)
			(layer "F.Fab")
		)
		(fp_line
			(start 0.120396 0.3048)
			(end 0.120396 0.2794)
			(stroke
				(width 0.1)
				(type default)
			)
			(layer "F.Fab")
		)
		(fp_line
			(start 0.120396 0.2794)
			(end -0.12065 0.2794)
			(stroke
				(width 0.1)
				(type default)
			)
			(layer "F.Fab")
		)
		(fp_line
			(start -0.12065 0.3048)
			(end -0.67945 0.3048)
			(stroke
				(width 0.1)
				(type default)
			)
			(layer "F.Fab")
		)
		(fp_line
			(start -0.12065 0.2794)
			(end -0.12065 0.3048)
			(stroke
				(width 0.1)
				(type default)
			)
			(layer "F.Fab")
		)
		(fp_line
			(start -0.12065 -0.2794)
			(end 0.12065 -0.2794)
			(stroke
				(width 0.1)
				(type default)
			)
			(layer "F.Fab")
		)
		(fp_line
			(start -0.12065 -0.305054)
			(end -0.12065 -0.2794)
			(stroke
				(width 0.1)
				(type default)
			)
			(layer "F.Fab")
		)
		(fp_line
			(start -0.67945 0.3048)
			(end -0.67945 -0.305054)
			(stroke
				(width 0.1)
				(type default)
			)
			(layer "F.Fab")
		)
		(fp_line
			(start -0.67945 -0.305054)
			(end -0.12065 -0.305054)
			(stroke
				(width 0.1)
				(type default)
			)
			(layer "F.Fab")
		)
		(pad "1" smd circle
			(at -0.40005 0 180)
			(size 0 0)
			(layers "F.Cu" "F.Mask" "F.Paste")
			(net "GND")
		)
		(pad "2" smd circle
			(at 0.40005 0 180)
			(size 0 0)
			(layers "F.Cu" "F.Mask" "F.Paste")
			(net "GPU_3V3IO_RSVD3")
		)
	)
	(footprint ""
		(layer "F.Cu")
		(at 128.295908 -350.098614 90)
		(property "Reference" "C355"
			(at 0 0 90)
			(layer "F.SilkS")
			(hide yes)
			(effects
				(font
					(size 1.27 1.27)
				)
			)
		)
		(property "Value" ""
			(at 0 0 90)
			(layer "F.Fab")
			(effects
				(font
					(size 1.27 1.27)
				)
			)
		)
		(duplicate_pad_numbers_are_jumpers no)
		(fp_line
			(start 0.299974 -0.150114)
			(end 0.299974 0.150114)
			(stroke
				(width 0.1)
				(type default)
			)
			(layer "F.Fab")
		)
		(fp_line
			(start -0.299974 -0.150114)
			(end 0.299974 -0.150114)
			(stroke
				(width 0.1)
				(type default)
			)
			(layer "F.Fab")
		)
		(fp_line
			(start 0.299974 0.150114)
			(end -0.299974 0.150114)
			(stroke
				(width 0.1)
				(type default)
			)
			(layer "F.Fab")
		)
		(fp_line
			(start -0.299974 0.150114)
			(end -0.299974 -0.150114)
			(stroke
				(width 0.1)
				(type default)
			)
			(layer "F.Fab")
		)
		(pad "1" smd rect
			(at -0.2667 0 90)
			(size 0.3048 0.381)
			(layers "F.Cu" "F.Mask" "F.Paste")
			(net "P5E_PEX1_STN6_TX_DN<104>")
		)
		(pad "2" smd rect
			(at 0.2667 0 90)
			(size 0.3048 0.381)
			(layers "F.Cu" "F.Mask" "F.Paste")
			(net "P5E_PEX1_STN6_TX_C_DN<104>")
		)
	)
	(footprint ""
		(layer "F.Cu")
		(at 290.548822 -343.952322 90)
		(property "Reference" "C593"
			(at 0 0 90)
			(layer "F.SilkS")
			(hide yes)
			(effects
				(font
					(size 1.27 1.27)
				)
			)
		)
		(property "Value" ""
			(at 0 0 90)
			(layer "F.Fab")
			(effects
				(font
					(size 1.27 1.27)
				)
			)
		)
		(duplicate_pad_numbers_are_jumpers no)
		(fp_line
			(start 0.299974 -0.150114)
			(end 0.299974 0.150114)
			(stroke
				(width 0.1)
				(type default)
			)
			(layer "F.Fab")
		)
		(fp_line
			(start -0.299974 -0.150114)
			(end 0.299974 -0.150114)
			(stroke
				(width 0.1)
				(type default)
			)
			(layer "F.Fab")
		)
		(fp_line
			(start 0.299974 0.150114)
			(end -0.299974 0.150114)
			(stroke
				(width 0.1)
				(type default)
			)
			(layer "F.Fab")
		)
		(fp_line
			(start -0.299974 0.150114)
			(end -0.299974 -0.150114)
			(stroke
				(width 0.1)
				(type default)
			)
			(layer "F.Fab")
		)
		(pad "1" smd rect
			(at -0.2667 0 90)
			(size 0.3048 0.381)
			(layers "F.Cu" "F.Mask" "F.Paste")
			(net "P5E_PEX2_STN7_TX_DP<122>")
		)
		(pad "2" smd rect
			(at 0.2667 0 90)
			(size 0.3048 0.381)
			(layers "F.Cu" "F.Mask" "F.Paste")
			(net "P5E_PEX2_STN7_TX_C_DP<122>")
		)
	)
	(footprint ""
		(layer "F.Cu")
		(at 185.722768 -22.867366 90)
		(property "Reference" "C3917"
			(at 0 0 90)
			(layer "F.SilkS")
			(hide yes)
			(effects
				(font
					(size 1.27 1.27)
				)
			)
		)
		(property "Value" ""
			(at 0 0 90)
			(layer "F.Fab")
			(effects
				(font
					(size 1.27 1.27)
				)
			)
		)
		(duplicate_pad_numbers_are_jumpers no)
		(fp_line
			(start 0.7874 -0.4064)
			(end 0.7874 0.4064)
			(stroke
				(width 0.1524)
				(type default)
			)
			(layer "F.SilkS")
		)
		(fp_line
			(start -0.7874 -0.4064)
			(end 0.7874 -0.4064)
			(stroke
				(width 0.1524)
				(type default)
			)
			(layer "F.SilkS")
		)
		(fp_line
			(start 0.7874 0.4064)
			(end -0.7874 0.4064)
			(stroke
				(width 0.1524)
				(type default)
			)
			(layer "F.SilkS")
		)
		(fp_line
			(start -0.7874 0.4064)
			(end -0.7874 -0.4064)
			(stroke
				(width 0.1524)
				(type default)
			)
			(layer "F.SilkS")
		)
		(fp_line
			(start -0.12065 -0.305054)
			(end -0.12065 -0.2794)
			(stroke
				(width 0.1)
				(type default)
			)
			(layer "F.Fab")
		)
		(fp_line
			(start -0.67945 -0.305054)
			(end -0.12065 -0.305054)
			(stroke
				(width 0.1)
				(type default)
			)
			(layer "F.Fab")
		)
		(fp_line
			(start 0.67945 -0.3048)
			(end 0.67945 0.3048)
			(stroke
				(width 0.1)
				(type default)
			)
			(layer "F.Fab")
		)
		(fp_line
			(start 0.12065 -0.3048)
			(end 0.67945 -0.3048)
			(stroke
				(width 0.1)
				(type default)
			)
			(layer "F.Fab")
		)
		(fp_line
			(start 0.12065 -0.2794)
			(end 0.12065 -0.3048)
			(stroke
				(width 0.1)
				(type default)
			)
			(layer "F.Fab")
		)
		(fp_line
			(start -0.12065 -0.2794)
			(end 0.12065 -0.2794)
			(stroke
				(width 0.1)
				(type default)
			)
			(layer "F.Fab")
		)
		(fp_line
			(start 0.120396 0.2794)
			(end -0.12065 0.2794)
			(stroke
				(width 0.1)
				(type default)
			)
			(layer "F.Fab")
		)
		(fp_line
			(start -0.12065 0.2794)
			(end -0.12065 0.3048)
			(stroke
				(width 0.1)
				(type default)
			)
			(layer "F.Fab")
		)
		(fp_line
			(start 0.67945 0.3048)
			(end 0.120396 0.3048)
			(stroke
				(width 0.1)
				(type default)
			)
			(layer "F.Fab")
		)
		(fp_line
			(start 0.120396 0.3048)
			(end 0.120396 0.2794)
			(stroke
				(width 0.1)
				(type default)
			)
			(layer "F.Fab")
		)
		(fp_line
			(start -0.12065 0.3048)
			(end -0.67945 0.3048)
			(stroke
				(width 0.1)
				(type default)
			)
			(layer "F.Fab")
		)
		(fp_line
			(start -0.67945 0.3048)
			(end -0.67945 -0.305054)
			(stroke
				(width 0.1)
				(type default)
			)
			(layer "F.Fab")
		)
		(pad "1" smd circle
			(at -0.40005 0 90)
			(size 0 0)
			(layers "F.Cu" "F.Mask" "F.Paste")
			(net "P12V_SSD6")
		)
		(pad "2" smd circle
			(at 0.40005 0 90)
			(size 0 0)
			(layers "F.Cu" "F.Mask" "F.Paste")
			(net "GND")
		)
	)
	(footprint ""
		(layer "F.Cu")
		(at 101.689154 -220.544644)
		(property "Reference" "R851"
			(at 0 0 0)
			(layer "F.SilkS")
			(hide yes)
			(effects
				(font
					(size 1.27 1.27)
				)
			)
		)
		(property "Value" ""
			(at 0 0 0)
			(layer "F.Fab")
			(effects
				(font
					(size 1.27 1.27)
				)
			)
		)
		(duplicate_pad_numbers_are_jumpers no)
		(fp_line
			(start -0.7874 -0.4064)
			(end 0.7874 -0.4064)
			(stroke
				(width 0.1524)
				(type default)
			)
			(layer "F.SilkS")
		)
		(fp_line
			(start -0.7874 0.4064)
			(end -0.7874 -0.4064)
			(stroke
				(width 0.1524)
				(type default)
			)
			(layer "F.SilkS")
		)
		(fp_line
			(start 0.7874 -0.4064)
			(end 0.7874 0.4064)
			(stroke
				(width 0.1524)
				(type default)
			)
			(layer "F.SilkS")
		)
		(fp_line
			(start 0.7874 0.4064)
			(end -0.7874 0.4064)
			(stroke
				(width 0.1524)
				(type default)
			)
			(layer "F.SilkS")
		)
		(fp_line
			(start -0.67945 -0.305054)
			(end -0.12065 -0.305054)
			(stroke
				(width 0.1)
				(type default)
			)
			(layer "F.Fab")
		)
		(fp_line
			(start -0.67945 0.3048)
			(end -0.67945 -0.305054)
			(stroke
				(width 0.1)
				(type default)
			)
			(layer "F.Fab")
		)
		(fp_line
			(start -0.12065 -0.305054)
			(end -0.12065 -0.2794)
			(stroke
				(width 0.1)
				(type default)
			)
			(layer "F.Fab")
		)
		(fp_line
			(start -0.12065 -0.2794)
			(end 0.12065 -0.2794)
			(stroke
				(width 0.1)
				(type default)
			)
			(layer "F.Fab")
		)
		(fp_line
			(start -0.12065 0.2794)
			(end -0.12065 0.3048)
			(stroke
				(width 0.1)
				(type default)
			)
			(layer "F.Fab")
		)
		(fp_line
			(start -0.12065 0.3048)
			(end -0.67945 0.3048)
			(stroke
				(width 0.1)
				(type default)
			)
			(layer "F.Fab")
		)
		(fp_line
			(start 0.120396 0.2794)
			(end -0.12065 0.2794)
			(stroke
				(width 0.1)
				(type default)
			)
			(layer "F.Fab")
		)
		(fp_line
			(start 0.120396 0.3048)
			(end 0.120396 0.2794)
			(stroke
				(width 0.1)
				(type default)
			)
			(layer "F.Fab")
		)
		(fp_line
			(start 0.12065 -0.3048)
			(end 0.67945 -0.3048)
			(stroke
				(width 0.1)
				(type default)
			)
			(layer "F.Fab")
		)
		(fp_line
			(start 0.12065 -0.2794)
			(end 0.12065 -0.3048)
			(stroke
				(width 0.1)
				(type default)
			)
			(layer "F.Fab")
		)
		(fp_line
			(start 0.67945 -0.3048)
			(end 0.67945 0.3048)
			(stroke
				(width 0.1)
				(type default)
			)
			(layer "F.Fab")
		)
		(fp_line
			(start 0.67945 0.3048)
			(end 0.120396 0.3048)
			(stroke
				(width 0.1)
				(type default)
			)
			(layer "F.Fab")
		)
		(pad "1" smd circle
			(at -0.40005 0)
			(size 0 0)
			(layers "F.Cu" "F.Mask" "F.Paste")
			(net "PWR_EN_PEX_R")
		)
		(pad "2" smd circle
			(at 0.40005 0)
			(size 0 0)
			(layers "F.Cu" "F.Mask" "F.Paste")
			(net "P1V8_PEX_EN")
		)
	)
	(footprint ""
		(layer "F.Cu")
		(at 233.762804 -276.534118 180)
		(property "Reference" "C4334"
			(at 0 0 180)
			(layer "F.SilkS")
			(hide yes)
			(effects
				(font
					(size 1.27 1.27)
				)
			)
		)
		(property "Value" ""
			(at 0 0 180)
			(layer "F.Fab")
			(effects
				(font
					(size 1.27 1.27)
				)
			)
		)
		(duplicate_pad_numbers_are_jumpers no)
		(fp_line
			(start 0.299974 0.150114)
			(end -0.299974 0.150114)
			(stroke
				(width 0.1)
				(type default)
			)
			(layer "F.Fab")
		)
		(fp_line
			(start 0.299974 -0.150114)
			(end 0.299974 0.150114)
			(stroke
				(width 0.1)
				(type default)
			)
			(layer "F.Fab")
		)
		(fp_line
			(start -0.299974 0.150114)
			(end -0.299974 -0.150114)
			(stroke
				(width 0.1)
				(type default)
			)
			(layer "F.Fab")
		)
		(fp_line
			(start -0.299974 -0.150114)
			(end 0.299974 -0.150114)
			(stroke
				(width 0.1)
				(type default)
			)
			(layer "F.Fab")
		)
		(pad "1" smd rect
			(at -0.2667 0 180)
			(size 0.3048 0.381)
			(layers "F.Cu" "F.Mask" "F.Paste")
			(net "P1V25_PEX2")
		)
		(pad "2" smd rect
			(at 0.2667 0 180)
			(size 0.3048 0.381)
			(layers "F.Cu" "F.Mask" "F.Paste")
			(net "GND")
		)
	)
	(footprint ""
		(layer "F.Cu")
		(at 248.897902 -80.2894 180)
		(property "Reference" "Y6"
			(at 0.384302 -2.71907 0)
			(unlocked yes)
			(layer "F.SilkS")
			(effects
				(font
					(size 0.7874 0.5842)
					(thickness 0.1524)
				)
				(justify left)
			)
		)
		(property "Value" ""
			(at 0 0 180)
			(layer "F.Fab")
			(effects
				(font
					(size 1.27 1.27)
				)
			)
		)
		(duplicate_pad_numbers_are_jumpers no)
		(fp_line
			(start 1.538732 1.937004)
			(end -1.538732 1.937004)
			(stroke
				(width 0.1524)
				(type default)
			)
			(layer "F.SilkS")
		)
		(fp_line
			(start 1.538732 -1.937004)
			(end 1.538732 1.937004)
			(stroke
				(width 0.1524)
				(type default)
			)
			(layer "F.SilkS")
		)
		(fp_line
			(start -1.538732 1.937004)
			(end -1.538732 -1.937004)
			(stroke
				(width 0.1524)
				(type default)
			)
			(layer "F.SilkS")
		)
		(fp_line
			(start -1.538732 -1.937004)
			(end 1.538732 -1.937004)
			(stroke
				(width 0.1524)
				(type default)
			)
			(layer "F.SilkS")
		)
		(fp_poly
			(pts
				(xy -2.752598 -2.392934) (xy -2.13995 -3.005582) (xy -1.83388 -2.086356)
			)
			(stroke
				(width 0)
				(type default)
			)
			(fill yes)
			(layer "F.SilkS")
		)
		(fp_line
			(start 1.299972 1.649984)
			(end -1.299972 1.649984)
			(stroke
				(width 0.1)
				(type default)
			)
			(layer "F.Fab")
		)
		(fp_line
			(start 1.299972 -1.649984)
			(end 1.299972 1.649984)
			(stroke
				(width 0.1)
				(type default)
			)
			(layer "F.Fab")
		)
		(fp_line
			(start -1.299972 1.649984)
			(end -1.299972 -1.649984)
			(stroke
				(width 0.1)
				(type default)
			)
			(layer "F.Fab")
		)
		(fp_line
			(start -1.299972 -1.649984)
			(end 1.299972 -1.649984)
			(stroke
				(width 0.1)
				(type default)
			)
			(layer "F.Fab")
		)
		(fp_poly
			(pts
				(xy -2.5908 -0.626872) (xy -2.5908 -1.493266) (xy -1.724406 -1.059942)
			)
			(stroke
				(width 0)
				(type default)
			)
			(fill yes)
			(layer "F.Fab")
		)
		(pad "1" smd rect
			(at -0.8001 -1.059942 180)
			(size 1.2192 1.4986)
			(layers "F.Cu" "F.Mask" "F.Paste")
			(net "XTAL_CK440_25M_R_XIN")
		)
		(pad "2" smd rect
			(at -0.8001 1.059942 180)
			(size 1.2192 1.4986)
			(layers "F.Cu" "F.Mask" "F.Paste")
			(net "GND")
		)
		(pad "3" smd rect
			(at 0.8001 1.059942 180)
			(size 1.2192 1.4986)
			(layers "F.Cu" "F.Mask" "F.Paste")
			(net "XTAL_CK440_25M_XOUT")
		)
		(pad "4" smd rect
			(at 0.8001 -1.059942 180)
			(size 1.2192 1.4986)
			(layers "F.Cu" "F.Mask" "F.Paste")
			(net "GND")
		)
	)
	(footprint ""
		(layer "F.Cu")
		(at 259.022596 -311.156604 -90)
		(property "Reference" "R1394"
			(at 0 0 270)
			(layer "F.SilkS")
			(hide yes)
			(effects
				(font
					(size 1.27 1.27)
				)
			)
		)
		(property "Value" ""
			(at 0 0 270)
			(layer "F.Fab")
			(effects
				(font
					(size 1.27 1.27)
				)
			)
		)
		(duplicate_pad_numbers_are_jumpers no)
		(fp_line
			(start -0.7874 0.4064)
			(end -0.7874 -0.4064)
			(stroke
				(width 0.1524)
				(type default)
			)
			(layer "F.SilkS")
		)
		(fp_line
			(start 0.7874 0.4064)
			(end -0.7874 0.4064)
			(stroke
				(width 0.1524)
				(type default)
			)
			(layer "F.SilkS")
		)
		(fp_line
			(start -0.7874 -0.4064)
			(end 0.7874 -0.4064)
			(stroke
				(width 0.1524)
				(type default)
			)
			(layer "F.SilkS")
		)
		(fp_line
			(start 0.7874 -0.4064)
			(end 0.7874 0.4064)
			(stroke
				(width 0.1524)
				(type default)
			)
			(layer "F.SilkS")
		)
		(fp_line
			(start -0.67945 0.3048)
			(end -0.67945 -0.305054)
			(stroke
				(width 0.1)
				(type default)
			)
			(layer "F.Fab")
		)
		(fp_line
			(start -0.12065 0.3048)
			(end -0.67945 0.3048)
			(stroke
				(width 0.1)
				(type default)
			)
			(layer "F.Fab")
		)
		(fp_line
			(start 0.120396 0.3048)
			(end 0.120396 0.2794)
			(stroke
				(width 0.1)
				(type default)
			)
			(layer "F.Fab")
		)
		(fp_line
			(start 0.67945 0.3048)
			(end 0.120396 0.3048)
			(stroke
				(width 0.1)
				(type default)
			)
			(layer "F.Fab")
		)
		(fp_line
			(start -0.12065 0.2794)
			(end -0.12065 0.3048)
			(stroke
				(width 0.1)
				(type default)
			)
			(layer "F.Fab")
		)
		(fp_line
			(start 0.120396 0.2794)
			(end -0.12065 0.2794)
			(stroke
				(width 0.1)
				(type default)
			)
			(layer "F.Fab")
		)
		(fp_line
			(start -0.12065 -0.2794)
			(end 0.12065 -0.2794)
			(stroke
				(width 0.1)
				(type default)
			)
			(layer "F.Fab")
		)
		(fp_line
			(start 0.12065 -0.2794)
			(end 0.12065 -0.3048)
			(stroke
				(width 0.1)
				(type default)
			)
			(layer "F.Fab")
		)
		(fp_line
			(start 0.12065 -0.3048)
			(end 0.67945 -0.3048)
			(stroke
				(width 0.1)
				(type default)
			)
			(layer "F.Fab")
		)
		(fp_line
			(start 0.67945 -0.3048)
			(end 0.67945 0.3048)
			(stroke
				(width 0.1)
				(type default)
			)
			(layer "F.Fab")
		)
		(fp_line
			(start -0.67945 -0.305054)
			(end -0.12065 -0.305054)
			(stroke
				(width 0.1)
				(type default)
			)
			(layer "F.Fab")
		)
		(fp_line
			(start -0.12065 -0.305054)
			(end -0.12065 -0.2794)
			(stroke
				(width 0.1)
				(type default)
			)
			(layer "F.Fab")
		)
		(pad "1" smd circle
			(at -0.40005 0 270)
			(size 0 0)
			(layers "F.Cu" "F.Mask" "F.Paste")
			(net "PU_PEX2_TR_TCK")
		)
		(pad "2" smd circle
			(at 0.40005 0 270)
			(size 0 0)
			(layers "F.Cu" "F.Mask" "F.Paste")
			(net "P1V8_PEX")
		)
	)
	(footprint ""
		(layer "F.Cu")
		(at 171.972224 -32.848042 90)
		(property "Reference" "PC930"
			(at 0 0 90)
			(layer "F.SilkS")
			(hide yes)
			(effects
				(font
					(size 1.27 1.27)
				)
			)
		)
		(property "Value" ""
			(at 0 0 90)
			(layer "F.Fab")
			(effects
				(font
					(size 1.27 1.27)
				)
			)
		)
		(duplicate_pad_numbers_are_jumpers no)
		(fp_line
			(start 0.7874 -0.4064)
			(end 0.7874 0.4064)
			(stroke
				(width 0.1524)
				(type default)
			)
			(layer "F.SilkS")
		)
		(fp_line
			(start -0.7874 -0.4064)
			(end 0.7874 -0.4064)
			(stroke
				(width 0.1524)
				(type default)
			)
			(layer "F.SilkS")
		)
		(fp_line
			(start 0.7874 0.4064)
			(end -0.7874 0.4064)
			(stroke
				(width 0.1524)
				(type default)
			)
			(layer "F.SilkS")
		)
		(fp_line
			(start -0.7874 0.4064)
			(end -0.7874 -0.4064)
			(stroke
				(width 0.1524)
				(type default)
			)
			(layer "F.SilkS")
		)
		(fp_line
			(start -0.12065 -0.305054)
			(end -0.12065 -0.2794)
			(stroke
				(width 0.1)
				(type default)
			)
			(layer "F.Fab")
		)
		(fp_line
			(start -0.67945 -0.305054)
			(end -0.12065 -0.305054)
			(stroke
				(width 0.1)
				(type default)
			)
			(layer "F.Fab")
		)
		(fp_line
			(start 0.67945 -0.3048)
			(end 0.67945 0.3048)
			(stroke
				(width 0.1)
				(type default)
			)
			(layer "F.Fab")
		)
		(fp_line
			(start 0.12065 -0.3048)
			(end 0.67945 -0.3048)
			(stroke
				(width 0.1)
				(type default)
			)
			(layer "F.Fab")
		)
		(fp_line
			(start 0.12065 -0.2794)
			(end 0.12065 -0.3048)
			(stroke
				(width 0.1)
				(type default)
			)
			(layer "F.Fab")
		)
		(fp_line
			(start -0.12065 -0.2794)
			(end 0.12065 -0.2794)
			(stroke
				(width 0.1)
				(type default)
			)
			(layer "F.Fab")
		)
		(fp_line
			(start 0.120396 0.2794)
			(end -0.12065 0.2794)
			(stroke
				(width 0.1)
				(type default)
			)
			(layer "F.Fab")
		)
		(fp_line
			(start -0.12065 0.2794)
			(end -0.12065 0.3048)
			(stroke
				(width 0.1)
				(type default)
			)
			(layer "F.Fab")
		)
		(fp_line
			(start 0.67945 0.3048)
			(end 0.120396 0.3048)
			(stroke
				(width 0.1)
				(type default)
			)
			(layer "F.Fab")
		)
		(fp_line
			(start 0.120396 0.3048)
			(end 0.120396 0.2794)
			(stroke
				(width 0.1)
				(type default)
			)
			(layer "F.Fab")
		)
		(fp_line
			(start -0.12065 0.3048)
			(end -0.67945 0.3048)
			(stroke
				(width 0.1)
				(type default)
			)
			(layer "F.Fab")
		)
		(fp_line
			(start -0.67945 0.3048)
			(end -0.67945 -0.305054)
			(stroke
				(width 0.1)
				(type default)
			)
			(layer "F.Fab")
		)
		(pad "1" smd circle
			(at -0.40005 0 90)
			(size 0 0)
			(layers "F.Cu" "F.Mask" "F.Paste")
			(net "P3V3_SSD6_CO_GATE")
		)
		(pad "2" smd circle
			(at 0.40005 0 90)
			(size 0 0)
			(layers "F.Cu" "F.Mask" "F.Paste")
			(net "GND")
		)
	)
	(footprint ""
		(layer "F.Cu")
		(at 399.5928 -85.3948)
		(property "Reference" "C3994"
			(at 0 0 0)
			(layer "F.SilkS")
			(hide yes)
			(effects
				(font
					(size 1.27 1.27)
				)
			)
		)
		(property "Value" ""
			(at 0 0 0)
			(layer "F.Fab")
			(effects
				(font
					(size 1.27 1.27)
				)
			)
		)
		(duplicate_pad_numbers_are_jumpers no)
		(fp_line
			(start -0.7874 -0.4064)
			(end 0.7874 -0.4064)
			(stroke
				(width 0.1524)
				(type default)
			)
			(layer "F.SilkS")
		)
		(fp_line
			(start -0.7874 0.4064)
			(end -0.7874 -0.4064)
			(stroke
				(width 0.1524)
				(type default)
			)
			(layer "F.SilkS")
		)
		(fp_line
			(start 0.7874 -0.4064)
			(end 0.7874 0.4064)
			(stroke
				(width 0.1524)
				(type default)
			)
			(layer "F.SilkS")
		)
		(fp_line
			(start 0.7874 0.4064)
			(end -0.7874 0.4064)
			(stroke
				(width 0.1524)
				(type default)
			)
			(layer "F.SilkS")
		)
		(fp_line
			(start -0.67945 -0.305054)
			(end -0.12065 -0.305054)
			(stroke
				(width 0.1)
				(type default)
			)
			(layer "F.Fab")
		)
		(fp_line
			(start -0.67945 0.3048)
			(end -0.67945 -0.305054)
			(stroke
				(width 0.1)
				(type default)
			)
			(layer "F.Fab")
		)
		(fp_line
			(start -0.12065 -0.305054)
			(end -0.12065 -0.2794)
			(stroke
				(width 0.1)
				(type default)
			)
			(layer "F.Fab")
		)
		(fp_line
			(start -0.12065 -0.2794)
			(end 0.12065 -0.2794)
			(stroke
				(width 0.1)
				(type default)
			)
			(layer "F.Fab")
		)
		(fp_line
			(start -0.12065 0.2794)
			(end -0.12065 0.3048)
			(stroke
				(width 0.1)
				(type default)
			)
			(layer "F.Fab")
		)
		(fp_line
			(start -0.12065 0.3048)
			(end -0.67945 0.3048)
			(stroke
				(width 0.1)
				(type default)
			)
			(layer "F.Fab")
		)
		(fp_line
			(start 0.120396 0.2794)
			(end -0.12065 0.2794)
			(stroke
				(width 0.1)
				(type default)
			)
			(layer "F.Fab")
		)
		(fp_line
			(start 0.120396 0.3048)
			(end 0.120396 0.2794)
			(stroke
				(width 0.1)
				(type default)
			)
			(layer "F.Fab")
		)
		(fp_line
			(start 0.12065 -0.3048)
			(end 0.67945 -0.3048)
			(stroke
				(width 0.1)
				(type default)
			)
			(layer "F.Fab")
		)
		(fp_line
			(start 0.12065 -0.2794)
			(end 0.12065 -0.3048)
			(stroke
				(width 0.1)
				(type default)
			)
			(layer "F.Fab")
		)
		(fp_line
			(start 0.67945 -0.3048)
			(end 0.67945 0.3048)
			(stroke
				(width 0.1)
				(type default)
			)
			(layer "F.Fab")
		)
		(fp_line
			(start 0.67945 0.3048)
			(end 0.120396 0.3048)
			(stroke
				(width 0.1)
				(type default)
			)
			(layer "F.Fab")
		)
		(pad "1" smd circle
			(at -0.40005 0)
			(size 0 0)
			(layers "F.Cu" "F.Mask" "F.Paste")
			(net "GND")
		)
		(pad "2" smd circle
			(at 0.40005 0)
			(size 0 0)
			(layers "F.Cu" "F.Mask" "F.Paste")
			(net "P3V3_AUX")
		)
	)
	(footprint ""
		(layer "F.Cu")
		(at 219.202 -207.772)
		(property "Reference" "R1508"
			(at 0 0 0)
			(layer "F.SilkS")
			(hide yes)
			(effects
				(font
					(size 1.27 1.27)
				)
			)
		)
		(property "Value" ""
			(at 0 0 0)
			(layer "F.Fab")
			(effects
				(font
					(size 1.27 1.27)
				)
			)
		)
		(duplicate_pad_numbers_are_jumpers no)
		(fp_line
			(start -0.7874 -0.4064)
			(end 0.7874 -0.4064)
			(stroke
				(width 0.1524)
				(type default)
			)
			(layer "F.SilkS")
		)
		(fp_line
			(start -0.7874 0.4064)
			(end -0.7874 -0.4064)
			(stroke
				(width 0.1524)
				(type default)
			)
			(layer "F.SilkS")
		)
		(fp_line
			(start 0.7874 -0.4064)
			(end 0.7874 0.4064)
			(stroke
				(width 0.1524)
				(type default)
			)
			(layer "F.SilkS")
		)
		(fp_line
			(start 0.7874 0.4064)
			(end -0.7874 0.4064)
			(stroke
				(width 0.1524)
				(type default)
			)
			(layer "F.SilkS")
		)
		(fp_line
			(start -0.67945 -0.305054)
			(end -0.12065 -0.305054)
			(stroke
				(width 0.1)
				(type default)
			)
			(layer "F.Fab")
		)
		(fp_line
			(start -0.67945 0.3048)
			(end -0.67945 -0.305054)
			(stroke
				(width 0.1)
				(type default)
			)
			(layer "F.Fab")
		)
		(fp_line
			(start -0.12065 -0.305054)
			(end -0.12065 -0.2794)
			(stroke
				(width 0.1)
				(type default)
			)
			(layer "F.Fab")
		)
		(fp_line
			(start -0.12065 -0.2794)
			(end 0.12065 -0.2794)
			(stroke
				(width 0.1)
				(type default)
			)
			(layer "F.Fab")
		)
		(fp_line
			(start -0.12065 0.2794)
			(end -0.12065 0.3048)
			(stroke
				(width 0.1)
				(type default)
			)
			(layer "F.Fab")
		)
		(fp_line
			(start -0.12065 0.3048)
			(end -0.67945 0.3048)
			(stroke
				(width 0.1)
				(type default)
			)
			(layer "F.Fab")
		)
		(fp_line
			(start 0.120396 0.2794)
			(end -0.12065 0.2794)
			(stroke
				(width 0.1)
				(type default)
			)
			(layer "F.Fab")
		)
		(fp_line
			(start 0.120396 0.3048)
			(end 0.120396 0.2794)
			(stroke
				(width 0.1)
				(type default)
			)
			(layer "F.Fab")
		)
		(fp_line
			(start 0.12065 -0.3048)
			(end 0.67945 -0.3048)
			(stroke
				(width 0.1)
				(type default)
			)
			(layer "F.Fab")
		)
		(fp_line
			(start 0.12065 -0.2794)
			(end 0.12065 -0.3048)
			(stroke
				(width 0.1)
				(type default)
			)
			(layer "F.Fab")
		)
		(fp_line
			(start 0.67945 -0.3048)
			(end 0.67945 0.3048)
			(stroke
				(width 0.1)
				(type default)
			)
			(layer "F.Fab")
		)
		(fp_line
			(start 0.67945 0.3048)
			(end 0.120396 0.3048)
			(stroke
				(width 0.1)
				(type default)
			)
			(layer "F.Fab")
		)
		(pad "1" smd circle
			(at -0.40005 0)
			(size 0 0)
			(layers "F.Cu" "F.Mask" "F.Paste")
			(net "SMB_NIC4_LS_R_SDA")
		)
		(pad "2" smd circle
			(at 0.40005 0)
			(size 0 0)
			(layers "F.Cu" "F.Mask" "F.Paste")
			(net "P3V3_NIC4")
		)
	)
	(footprint ""
		(layer "F.Cu")
		(at 258.44373 -42.84091)
		(property "Reference" "R594"
			(at 0 0 0)
			(layer "F.SilkS")
			(hide yes)
			(effects
				(font
					(size 1.27 1.27)
				)
			)
		)
		(property "Value" ""
			(at 0 0 0)
			(layer "F.Fab")
			(effects
				(font
					(size 1.27 1.27)
				)
			)
		)
		(duplicate_pad_numbers_are_jumpers no)
		(fp_line
			(start -0.7874 -0.4064)
			(end 0.7874 -0.4064)
			(stroke
				(width 0.1524)
				(type default)
			)
			(layer "F.SilkS")
		)
		(fp_line
			(start -0.7874 0.4064)
			(end -0.7874 -0.4064)
			(stroke
				(width 0.1524)
				(type default)
			)
			(layer "F.SilkS")
		)
		(fp_line
			(start 0.7874 -0.4064)
			(end 0.7874 0.4064)
			(stroke
				(width 0.1524)
				(type default)
			)
			(layer "F.SilkS")
		)
		(fp_line
			(start 0.7874 0.4064)
			(end -0.7874 0.4064)
			(stroke
				(width 0.1524)
				(type default)
			)
			(layer "F.SilkS")
		)
		(fp_line
			(start -0.67945 -0.305054)
			(end -0.12065 -0.305054)
			(stroke
				(width 0.1)
				(type default)
			)
			(layer "F.Fab")
		)
		(fp_line
			(start -0.67945 0.3048)
			(end -0.67945 -0.305054)
			(stroke
				(width 0.1)
				(type default)
			)
			(layer "F.Fab")
		)
		(fp_line
			(start -0.12065 -0.305054)
			(end -0.12065 -0.2794)
			(stroke
				(width 0.1)
				(type default)
			)
			(layer "F.Fab")
		)
		(fp_line
			(start -0.12065 -0.2794)
			(end 0.12065 -0.2794)
			(stroke
				(width 0.1)
				(type default)
			)
			(layer "F.Fab")
		)
		(fp_line
			(start -0.12065 0.2794)
			(end -0.12065 0.3048)
			(stroke
				(width 0.1)
				(type default)
			)
			(layer "F.Fab")
		)
		(fp_line
			(start -0.12065 0.3048)
			(end -0.67945 0.3048)
			(stroke
				(width 0.1)
				(type default)
			)
			(layer "F.Fab")
		)
		(fp_line
			(start 0.120396 0.2794)
			(end -0.12065 0.2794)
			(stroke
				(width 0.1)
				(type default)
			)
			(layer "F.Fab")
		)
		(fp_line
			(start 0.120396 0.3048)
			(end 0.120396 0.2794)
			(stroke
				(width 0.1)
				(type default)
			)
			(layer "F.Fab")
		)
		(fp_line
			(start 0.12065 -0.3048)
			(end 0.67945 -0.3048)
			(stroke
				(width 0.1)
				(type default)
			)
			(layer "F.Fab")
		)
		(fp_line
			(start 0.12065 -0.2794)
			(end 0.12065 -0.3048)
			(stroke
				(width 0.1)
				(type default)
			)
			(layer "F.Fab")
		)
		(fp_line
			(start 0.67945 -0.3048)
			(end 0.67945 0.3048)
			(stroke
				(width 0.1)
				(type default)
			)
			(layer "F.Fab")
		)
		(fp_line
			(start 0.67945 0.3048)
			(end 0.120396 0.3048)
			(stroke
				(width 0.1)
				(type default)
			)
			(layer "F.Fab")
		)
		(pad "1" smd circle
			(at -0.40005 0)
			(size 0 0)
			(layers "F.Cu" "F.Mask" "F.Paste")
			(net "SSD8_ADC_A1")
		)
		(pad "2" smd circle
			(at 0.40005 0)
			(size 0 0)
			(layers "F.Cu" "F.Mask" "F.Paste")
			(net "P3V3_AUX")
		)
	)
	(footprint ""
		(layer "F.Cu")
		(at 208.149698 -304.036476 90)
		(property "Reference" "R1320"
			(at 0 0 90)
			(layer "F.SilkS")
			(hide yes)
			(effects
				(font
					(size 1.27 1.27)
				)
			)
		)
		(property "Value" ""
			(at 0 0 90)
			(layer "F.Fab")
			(effects
				(font
					(size 1.27 1.27)
				)
			)
		)
		(duplicate_pad_numbers_are_jumpers no)
		(fp_line
			(start 0.7874 -0.4064)
			(end 0.7874 0.4064)
			(stroke
				(width 0.1524)
				(type default)
			)
			(layer "F.SilkS")
		)
		(fp_line
			(start -0.7874 -0.4064)
			(end 0.7874 -0.4064)
			(stroke
				(width 0.1524)
				(type default)
			)
			(layer "F.SilkS")
		)
		(fp_line
			(start 0.7874 0.4064)
			(end -0.7874 0.4064)
			(stroke
				(width 0.1524)
				(type default)
			)
			(layer "F.SilkS")
		)
		(fp_line
			(start -0.7874 0.4064)
			(end -0.7874 -0.4064)
			(stroke
				(width 0.1524)
				(type default)
			)
			(layer "F.SilkS")
		)
		(fp_line
			(start -0.12065 -0.305054)
			(end -0.12065 -0.2794)
			(stroke
				(width 0.1)
				(type default)
			)
			(layer "F.Fab")
		)
		(fp_line
			(start -0.67945 -0.305054)
			(end -0.12065 -0.305054)
			(stroke
				(width 0.1)
				(type default)
			)
			(layer "F.Fab")
		)
		(fp_line
			(start 0.67945 -0.3048)
			(end 0.67945 0.3048)
			(stroke
				(width 0.1)
				(type default)
			)
			(layer "F.Fab")
		)
		(fp_line
			(start 0.12065 -0.3048)
			(end 0.67945 -0.3048)
			(stroke
				(width 0.1)
				(type default)
			)
			(layer "F.Fab")
		)
		(fp_line
			(start 0.12065 -0.2794)
			(end 0.12065 -0.3048)
			(stroke
				(width 0.1)
				(type default)
			)
			(layer "F.Fab")
		)
		(fp_line
			(start -0.12065 -0.2794)
			(end 0.12065 -0.2794)
			(stroke
				(width 0.1)
				(type default)
			)
			(layer "F.Fab")
		)
		(fp_line
			(start 0.120396 0.2794)
			(end -0.12065 0.2794)
			(stroke
				(width 0.1)
				(type default)
			)
			(layer "F.Fab")
		)
		(fp_line
			(start -0.12065 0.2794)
			(end -0.12065 0.3048)
			(stroke
				(width 0.1)
				(type default)
			)
			(layer "F.Fab")
		)
		(fp_line
			(start 0.67945 0.3048)
			(end 0.120396 0.3048)
			(stroke
				(width 0.1)
				(type default)
			)
			(layer "F.Fab")
		)
		(fp_line
			(start 0.120396 0.3048)
			(end 0.120396 0.2794)
			(stroke
				(width 0.1)
				(type default)
			)
			(layer "F.Fab")
		)
		(fp_line
			(start -0.12065 0.3048)
			(end -0.67945 0.3048)
			(stroke
				(width 0.1)
				(type default)
			)
			(layer "F.Fab")
		)
		(fp_line
			(start -0.67945 0.3048)
			(end -0.67945 -0.305054)
			(stroke
				(width 0.1)
				(type default)
			)
			(layer "F.Fab")
		)
		(pad "1" smd circle
			(at -0.40005 0 90)
			(size 0 0)
			(layers "F.Cu" "F.Mask" "F.Paste")
			(net "GND")
		)
		(pad "2" smd circle
			(at 0.40005 0 90)
			(size 0 0)
			(layers "F.Cu" "F.Mask" "F.Paste")
			(net "PEX1_SPARE6")
		)
	)
	(footprint ""
		(layer "F.Cu")
		(at 210.439 -201.803 180)
		(property "Reference" "R1519"
			(at 0 0 180)
			(layer "F.SilkS")
			(hide yes)
			(effects
				(font
					(size 1.27 1.27)
				)
			)
		)
		(property "Value" ""
			(at 0 0 180)
			(layer "F.Fab")
			(effects
				(font
					(size 1.27 1.27)
				)
			)
		)
		(duplicate_pad_numbers_are_jumpers no)
		(fp_line
			(start 0.7874 0.4064)
			(end -0.7874 0.4064)
			(stroke
				(width 0.1524)
				(type default)
			)
			(layer "F.SilkS")
		)
		(fp_line
			(start 0.7874 -0.4064)
			(end 0.7874 0.4064)
			(stroke
				(width 0.1524)
				(type default)
			)
			(layer "F.SilkS")
		)
		(fp_line
			(start -0.7874 0.4064)
			(end -0.7874 -0.4064)
			(stroke
				(width 0.1524)
				(type default)
			)
			(layer "F.SilkS")
		)
		(fp_line
			(start -0.7874 -0.4064)
			(end 0.7874 -0.4064)
			(stroke
				(width 0.1524)
				(type default)
			)
			(layer "F.SilkS")
		)
		(fp_line
			(start 0.67945 0.3048)
			(end 0.120396 0.3048)
			(stroke
				(width 0.1)
				(type default)
			)
			(layer "F.Fab")
		)
		(fp_line
			(start 0.67945 -0.3048)
			(end 0.67945 0.3048)
			(stroke
				(width 0.1)
				(type default)
			)
			(layer "F.Fab")
		)
		(fp_line
			(start 0.12065 -0.2794)
			(end 0.12065 -0.3048)
			(stroke
				(width 0.1)
				(type default)
			)
			(layer "F.Fab")
		)
		(fp_line
			(start 0.12065 -0.3048)
			(end 0.67945 -0.3048)
			(stroke
				(width 0.1)
				(type default)
			)
			(layer "F.Fab")
		)
		(fp_line
			(start 0.120396 0.3048)
			(end 0.120396 0.2794)
			(stroke
				(width 0.1)
				(type default)
			)
			(layer "F.Fab")
		)
		(fp_line
			(start 0.120396 0.2794)
			(end -0.12065 0.2794)
			(stroke
				(width 0.1)
				(type default)
			)
			(layer "F.Fab")
		)
		(fp_line
			(start -0.12065 0.3048)
			(end -0.67945 0.3048)
			(stroke
				(width 0.1)
				(type default)
			)
			(layer "F.Fab")
		)
		(fp_line
			(start -0.12065 0.2794)
			(end -0.12065 0.3048)
			(stroke
				(width 0.1)
				(type default)
			)
			(layer "F.Fab")
		)
		(fp_line
			(start -0.12065 -0.2794)
			(end 0.12065 -0.2794)
			(stroke
				(width 0.1)
				(type default)
			)
			(layer "F.Fab")
		)
		(fp_line
			(start -0.12065 -0.305054)
			(end -0.12065 -0.2794)
			(stroke
				(width 0.1)
				(type default)
			)
			(layer "F.Fab")
		)
		(fp_line
			(start -0.67945 0.3048)
			(end -0.67945 -0.305054)
			(stroke
				(width 0.1)
				(type default)
			)
			(layer "F.Fab")
		)
		(fp_line
			(start -0.67945 -0.305054)
			(end -0.12065 -0.305054)
			(stroke
				(width 0.1)
				(type default)
			)
			(layer "F.Fab")
		)
		(pad "1" smd circle
			(at -0.40005 0 180)
			(size 0 0)
			(layers "F.Cu" "F.Mask" "F.Paste")
			(net "SMB_NIC5_R_SCL")
		)
		(pad "2" smd circle
			(at 0.40005 0 180)
			(size 0 0)
			(layers "F.Cu" "F.Mask" "F.Paste")
			(net "P1V2_AUX")
		)
	)
	(footprint ""
		(layer "F.Cu")
		(at 483.329488 -553.346874 180)
		(property "Reference" "SCREW_SSD12_1"
			(at -5.6007 -1.402334 0)
			(unlocked yes)
			(layer "B.SilkS")
			(effects
				(font
					(size 0.7874 0.5842)
					(thickness 0.1524)
				)
				(justify mirror)
			)
		)
		(property "Value" ""
			(at 0 0 180)
			(layer "F.Fab")
			(effects
				(font
					(size 1.27 1.27)
				)
			)
		)
		(duplicate_pad_numbers_are_jumpers no)
		(pad "1" thru_hole circle
			(at 0 0 180)
			(size 0.4572 0.4572)
			(drill 0.2032)
			(layers "*.Cu" "*.Mask")
			(remove_unused_layers no)
			(net "Net_9150")
			(clearance 0.127)
			(thermal_gap 0.127)
			(padstack
				(mode front_inner_back)
				(layer "Inner"
					(shape circle)
					(size 0.4572 0.4572)
					(clearance 0.127)
				)
				(layer "B.Cu"
					(shape circle)
					(size 0.508 0.508)
					(clearance 0.1016)
				)
			)
		)
	)
	(footprint ""
		(layer "F.Cu")
		(at 354.952808 -156.288994 -90)
		(property "Reference" "PR7045"
			(at 0 0 270)
			(layer "F.SilkS")
			(hide yes)
			(effects
				(font
					(size 1.27 1.27)
				)
			)
		)
		(property "Value" ""
			(at 0 0 270)
			(layer "F.Fab")
			(effects
				(font
					(size 1.27 1.27)
				)
			)
		)
		(duplicate_pad_numbers_are_jumpers no)
		(fp_line
			(start -0.7874 0.4064)
			(end -0.7874 -0.4064)
			(stroke
				(width 0.1524)
				(type default)
			)
			(layer "F.SilkS")
		)
		(fp_line
			(start 0.7874 0.4064)
			(end -0.7874 0.4064)
			(stroke
				(width 0.1524)
				(type default)
			)
			(layer "F.SilkS")
		)
		(fp_line
			(start -0.7874 -0.4064)
			(end 0.7874 -0.4064)
			(stroke
				(width 0.1524)
				(type default)
			)
			(layer "F.SilkS")
		)
		(fp_line
			(start 0.7874 -0.4064)
			(end 0.7874 0.4064)
			(stroke
				(width 0.1524)
				(type default)
			)
			(layer "F.SilkS")
		)
		(fp_line
			(start -0.67945 0.3048)
			(end -0.67945 -0.305054)
			(stroke
				(width 0.1)
				(type default)
			)
			(layer "F.Fab")
		)
		(fp_line
			(start -0.12065 0.3048)
			(end -0.67945 0.3048)
			(stroke
				(width 0.1)
				(type default)
			)
			(layer "F.Fab")
		)
		(fp_line
			(start 0.120396 0.3048)
			(end 0.120396 0.2794)
			(stroke
				(width 0.1)
				(type default)
			)
			(layer "F.Fab")
		)
		(fp_line
			(start 0.67945 0.3048)
			(end 0.120396 0.3048)
			(stroke
				(width 0.1)
				(type default)
			)
			(layer "F.Fab")
		)
		(fp_line
			(start -0.12065 0.2794)
			(end -0.12065 0.3048)
			(stroke
				(width 0.1)
				(type default)
			)
			(layer "F.Fab")
		)
		(fp_line
			(start 0.120396 0.2794)
			(end -0.12065 0.2794)
			(stroke
				(width 0.1)
				(type default)
			)
			(layer "F.Fab")
		)
		(fp_line
			(start -0.12065 -0.2794)
			(end 0.12065 -0.2794)
			(stroke
				(width 0.1)
				(type default)
			)
			(layer "F.Fab")
		)
		(fp_line
			(start 0.12065 -0.2794)
			(end 0.12065 -0.3048)
			(stroke
				(width 0.1)
				(type default)
			)
			(layer "F.Fab")
		)
		(fp_line
			(start 0.12065 -0.3048)
			(end 0.67945 -0.3048)
			(stroke
				(width 0.1)
				(type default)
			)
			(layer "F.Fab")
		)
		(fp_line
			(start 0.67945 -0.3048)
			(end 0.67945 0.3048)
			(stroke
				(width 0.1)
				(type default)
			)
			(layer "F.Fab")
		)
		(fp_line
			(start -0.67945 -0.305054)
			(end -0.12065 -0.305054)
			(stroke
				(width 0.1)
				(type default)
			)
			(layer "F.Fab")
		)
		(fp_line
			(start -0.12065 -0.305054)
			(end -0.12065 -0.2794)
			(stroke
				(width 0.1)
				(type default)
			)
			(layer "F.Fab")
		)
		(pad "1" smd circle
			(at -0.40005 0 270)
			(size 0 0)
			(layers "F.Cu" "F.Mask" "F.Paste")
			(net "P12V_NIC6_CO_OV_FB")
		)
		(pad "2" smd circle
			(at 0.40005 0 270)
			(size 0 0)
			(layers "F.Cu" "F.Mask" "F.Paste")
			(net "P12V_NIC6_R")
		)
	)
	(footprint ""
		(layer "F.Cu")
		(at 222.180912 -201.733658)
		(property "Reference" "R5281"
			(at 0 0 0)
			(layer "F.SilkS")
			(hide yes)
			(effects
				(font
					(size 1.27 1.27)
				)
			)
		)
		(property "Value" ""
			(at 0 0 0)
			(layer "F.Fab")
			(effects
				(font
					(size 1.27 1.27)
				)
			)
		)
		(duplicate_pad_numbers_are_jumpers no)
		(fp_line
			(start -0.7874 -0.4064)
			(end 0.7874 -0.4064)
			(stroke
				(width 0.1524)
				(type default)
			)
			(layer "F.SilkS")
		)
		(fp_line
			(start -0.7874 0.4064)
			(end -0.7874 -0.4064)
			(stroke
				(width 0.1524)
				(type default)
			)
			(layer "F.SilkS")
		)
		(fp_line
			(start 0.7874 -0.4064)
			(end 0.7874 0.4064)
			(stroke
				(width 0.1524)
				(type default)
			)
			(layer "F.SilkS")
		)
		(fp_line
			(start 0.7874 0.4064)
			(end -0.7874 0.4064)
			(stroke
				(width 0.1524)
				(type default)
			)
			(layer "F.SilkS")
		)
		(fp_line
			(start -0.67945 -0.305054)
			(end -0.12065 -0.305054)
			(stroke
				(width 0.1)
				(type default)
			)
			(layer "F.Fab")
		)
		(fp_line
			(start -0.67945 0.3048)
			(end -0.67945 -0.305054)
			(stroke
				(width 0.1)
				(type default)
			)
			(layer "F.Fab")
		)
		(fp_line
			(start -0.12065 -0.305054)
			(end -0.12065 -0.2794)
			(stroke
				(width 0.1)
				(type default)
			)
			(layer "F.Fab")
		)
		(fp_line
			(start -0.12065 -0.2794)
			(end 0.12065 -0.2794)
			(stroke
				(width 0.1)
				(type default)
			)
			(layer "F.Fab")
		)
		(fp_line
			(start -0.12065 0.2794)
			(end -0.12065 0.3048)
			(stroke
				(width 0.1)
				(type default)
			)
			(layer "F.Fab")
		)
		(fp_line
			(start -0.12065 0.3048)
			(end -0.67945 0.3048)
			(stroke
				(width 0.1)
				(type default)
			)
			(layer "F.Fab")
		)
		(fp_line
			(start 0.120396 0.2794)
			(end -0.12065 0.2794)
			(stroke
				(width 0.1)
				(type default)
			)
			(layer "F.Fab")
		)
		(fp_line
			(start 0.120396 0.3048)
			(end 0.120396 0.2794)
			(stroke
				(width 0.1)
				(type default)
			)
			(layer "F.Fab")
		)
		(fp_line
			(start 0.12065 -0.3048)
			(end 0.67945 -0.3048)
			(stroke
				(width 0.1)
				(type default)
			)
			(layer "F.Fab")
		)
		(fp_line
			(start 0.12065 -0.2794)
			(end 0.12065 -0.3048)
			(stroke
				(width 0.1)
				(type default)
			)
			(layer "F.Fab")
		)
		(fp_line
			(start 0.67945 -0.3048)
			(end 0.67945 0.3048)
			(stroke
				(width 0.1)
				(type default)
			)
			(layer "F.Fab")
		)
		(fp_line
			(start 0.67945 0.3048)
			(end 0.120396 0.3048)
			(stroke
				(width 0.1)
				(type default)
			)
			(layer "F.Fab")
		)
		(pad "1" smd circle
			(at -0.40005 0)
			(size 0 0)
			(layers "F.Cu" "F.Mask" "F.Paste")
			(net "GND")
		)
		(pad "2" smd circle
			(at 0.40005 0)
			(size 0 0)
			(layers "F.Cu" "F.Mask" "F.Paste")
			(net "JTAG_BIC_NTRST_R_N")
		)
	)
	(footprint ""
		(layer "F.Cu")
		(at 194.234308 -87.599012)
		(property "Reference" "U25"
			(at -0.991108 -1.706118 0)
			(unlocked yes)
			(layer "F.SilkS")
			(effects
				(font
					(size 0.7874 0.5842)
					(thickness 0.1524)
				)
				(justify left)
			)
		)
		(property "Value" ""
			(at 0 0 0)
			(layer "F.Fab")
			(effects
				(font
					(size 1.27 1.27)
				)
			)
		)
		(duplicate_pad_numbers_are_jumpers no)
		(fp_line
			(start -1.684274 -1.074928)
			(end -0.381 -1.074928)
			(stroke
				(width 0.1524)
				(type default)
			)
			(layer "F.SilkS")
		)
		(fp_line
			(start -1.684274 1.074928)
			(end -1.684274 -1.074928)
			(stroke
				(width 0.1524)
				(type default)
			)
			(layer "F.SilkS")
		)
		(fp_line
			(start -0.381 -1.074928)
			(end 0 -0.625094)
			(stroke
				(width 0.1524)
				(type default)
			)
			(layer "F.SilkS")
		)
		(fp_line
			(start 0 -0.625094)
			(end 0.381 -1.074928)
			(stroke
				(width 0.1524)
				(type default)
			)
			(layer "F.SilkS")
		)
		(fp_line
			(start 0.381 -1.074928)
			(end 1.684274 -1.074928)
			(stroke
				(width 0.1524)
				(type default)
			)
			(layer "F.SilkS")
		)
		(fp_line
			(start 1.684274 -1.074928)
			(end 1.684274 1.074928)
			(stroke
				(width 0.1524)
				(type default)
			)
			(layer "F.SilkS")
		)
		(fp_line
			(start 1.684274 1.074928)
			(end -1.684274 1.074928)
			(stroke
				(width 0.1524)
				(type default)
			)
			(layer "F.SilkS")
		)
		(fp_poly
			(pts
				(xy -2.637282 -0.903986) (xy -2.637282 -0.395986) (xy -1.875282 -0.649986)
			)
			(stroke
				(width 0)
				(type default)
			)
			(fill yes)
			(layer "F.SilkS")
		)
		(fp_line
			(start -0.700024 -1.074928)
			(end -0.700024 1.074928)
			(stroke
				(width 0.1)
				(type default)
			)
			(layer "F.Fab")
		)
		(fp_line
			(start -0.700024 1.074928)
			(end 0.700024 1.074928)
			(stroke
				(width 0.1)
				(type default)
			)
			(layer "F.Fab")
		)
		(fp_line
			(start 0.700024 -1.074928)
			(end -0.700024 -1.074928)
			(stroke
				(width 0.1)
				(type default)
			)
			(layer "F.Fab")
		)
		(fp_line
			(start 0.700024 1.074928)
			(end 0.700024 -1.074928)
			(stroke
				(width 0.1)
				(type default)
			)
			(layer "F.Fab")
		)
		(fp_poly
			(pts
				(xy -2.637282 -0.903986) (xy -2.637282 -0.395986) (xy -1.875282 -0.649986)
			)
			(stroke
				(width 0)
				(type default)
			)
			(fill yes)
			(layer "F.Fab")
		)
		(pad "1" smd rect
			(at -1.100074 -0.649986 270)
			(size 0.4064 0.9144)
			(layers "F.Cu" "F.Mask" "F.Paste")
			(net "Net_8453")
		)
		(pad "2" smd rect
			(at -1.100074 0 270)
			(size 0.4064 0.9144)
			(layers "F.Cu" "F.Mask" "F.Paste")
			(net "RST_HP_NIC3_N")
		)
		(pad "3" smd rect
			(at -1.100074 0.649986 270)
			(size 0.4064 0.9144)
			(layers "F.Cu" "F.Mask" "F.Paste")
			(net "GND")
		)
		(pad "4" smd rect
			(at 1.100074 0.649986 270)
			(size 0.4064 0.9144)
			(layers "F.Cu" "F.Mask" "F.Paste")
			(net "RST_HP_NIC3_BUF_N")
		)
		(pad "5" smd rect
			(at 1.100074 -0.649986 270)
			(size 0.4064 0.9144)
			(layers "F.Cu" "F.Mask" "F.Paste")
			(net "P3V3_AUX")
		)
	)
	(footprint ""
		(layer "F.Cu")
		(at 329.457812 -72.766682 90)
		(property "Reference" "PC874"
			(at 0 0 90)
			(layer "F.SilkS")
			(hide yes)
			(effects
				(font
					(size 1.27 1.27)
				)
			)
		)
		(property "Value" ""
			(at 0 0 90)
			(layer "F.Fab")
			(effects
				(font
					(size 1.27 1.27)
				)
			)
		)
		(duplicate_pad_numbers_are_jumpers no)
		(fp_line
			(start 0.7874 -0.4064)
			(end 0.7874 0.4064)
			(stroke
				(width 0.1524)
				(type default)
			)
			(layer "F.SilkS")
		)
		(fp_line
			(start -0.7874 -0.4064)
			(end 0.7874 -0.4064)
			(stroke
				(width 0.1524)
				(type default)
			)
			(layer "F.SilkS")
		)
		(fp_line
			(start 0.7874 0.4064)
			(end -0.7874 0.4064)
			(stroke
				(width 0.1524)
				(type default)
			)
			(layer "F.SilkS")
		)
		(fp_line
			(start -0.7874 0.4064)
			(end -0.7874 -0.4064)
			(stroke
				(width 0.1524)
				(type default)
			)
			(layer "F.SilkS")
		)
		(fp_line
			(start -0.12065 -0.305054)
			(end -0.12065 -0.2794)
			(stroke
				(width 0.1)
				(type default)
			)
			(layer "F.Fab")
		)
		(fp_line
			(start -0.67945 -0.305054)
			(end -0.12065 -0.305054)
			(stroke
				(width 0.1)
				(type default)
			)
			(layer "F.Fab")
		)
		(fp_line
			(start 0.67945 -0.3048)
			(end 0.67945 0.3048)
			(stroke
				(width 0.1)
				(type default)
			)
			(layer "F.Fab")
		)
		(fp_line
			(start 0.12065 -0.3048)
			(end 0.67945 -0.3048)
			(stroke
				(width 0.1)
				(type default)
			)
			(layer "F.Fab")
		)
		(fp_line
			(start 0.12065 -0.2794)
			(end 0.12065 -0.3048)
			(stroke
				(width 0.1)
				(type default)
			)
			(layer "F.Fab")
		)
		(fp_line
			(start -0.12065 -0.2794)
			(end 0.12065 -0.2794)
			(stroke
				(width 0.1)
				(type default)
			)
			(layer "F.Fab")
		)
		(fp_line
			(start 0.120396 0.2794)
			(end -0.12065 0.2794)
			(stroke
				(width 0.1)
				(type default)
			)
			(layer "F.Fab")
		)
		(fp_line
			(start -0.12065 0.2794)
			(end -0.12065 0.3048)
			(stroke
				(width 0.1)
				(type default)
			)
			(layer "F.Fab")
		)
		(fp_line
			(start 0.67945 0.3048)
			(end 0.120396 0.3048)
			(stroke
				(width 0.1)
				(type default)
			)
			(layer "F.Fab")
		)
		(fp_line
			(start 0.120396 0.3048)
			(end 0.120396 0.2794)
			(stroke
				(width 0.1)
				(type default)
			)
			(layer "F.Fab")
		)
		(fp_line
			(start -0.12065 0.3048)
			(end -0.67945 0.3048)
			(stroke
				(width 0.1)
				(type default)
			)
			(layer "F.Fab")
		)
		(fp_line
			(start -0.67945 0.3048)
			(end -0.67945 -0.305054)
			(stroke
				(width 0.1)
				(type default)
			)
			(layer "F.Fab")
		)
		(pad "1" smd circle
			(at -0.40005 0 90)
			(size 0 0)
			(layers "F.Cu" "F.Mask" "F.Paste")
			(net "P12V_SSD11_CO_MODE")
		)
		(pad "2" smd circle
			(at 0.40005 0 90)
			(size 0 0)
			(layers "F.Cu" "F.Mask" "F.Paste")
			(net "GND")
		)
	)
	(footprint ""
		(layer "F.Cu")
		(at 381.191008 -55.663846 90)
		(property "Reference" "PU65"
			(at -1.1938 2.755392 90)
			(unlocked yes)
			(layer "F.SilkS")
			(effects
				(font
					(size 0.7874 0.5842)
					(thickness 0.1524)
				)
				(justify left)
			)
		)
		(property "Value" ""
			(at 0 0 90)
			(layer "F.Fab")
			(effects
				(font
					(size 1.27 1.27)
				)
			)
		)
		(duplicate_pad_numbers_are_jumpers no)
		(fp_line
			(start 1.943608 -1.549908)
			(end 1.943608 1.549908)
			(stroke
				(width 0.1524)
				(type default)
			)
			(layer "F.SilkS")
		)
		(fp_line
			(start -1.943608 -1.549908)
			(end 1.943608 -1.549908)
			(stroke
				(width 0.1524)
				(type default)
			)
			(layer "F.SilkS")
		)
		(fp_line
			(start 1.943608 1.549908)
			(end -1.943608 1.549908)
			(stroke
				(width 0.1524)
				(type default)
			)
			(layer "F.SilkS")
		)
		(fp_line
			(start -1.943608 1.549908)
			(end -1.943608 -1.549908)
			(stroke
				(width 0.1524)
				(type default)
			)
			(layer "F.SilkS")
		)
		(fp_poly
			(pts
				(xy -2.019808 -1.549908) (xy -1.257808 -1.549908) (xy -1.257808 -1.880108) (xy -2.019808 -1.880108)
			)
			(stroke
				(width 0)
				(type default)
			)
			(fill yes)
			(layer "F.SilkS")
		)
		(fp_line
			(start 1.549908 -1.549908)
			(end 1.549908 1.549908)
			(stroke
				(width 0.1)
				(type default)
			)
			(layer "F.Fab")
		)
		(fp_line
			(start -1.549908 -1.549908)
			(end 1.549908 -1.549908)
			(stroke
				(width 0.1)
				(type default)
			)
			(layer "F.Fab")
		)
		(fp_line
			(start 1.549908 1.549908)
			(end -1.549908 1.549908)
			(stroke
				(width 0.1)
				(type default)
			)
			(layer "F.Fab")
		)
		(fp_line
			(start -1.549908 1.549908)
			(end -1.549908 -1.549908)
			(stroke
				(width 0.1)
				(type default)
			)
			(layer "F.Fab")
		)
		(fp_poly
			(pts
				(xy -2.019808 -1.549908) (xy -1.257808 -1.549908) (xy -1.257808 -1.880108) (xy -2.019808 -1.880108)
			)
			(stroke
				(width 0)
				(type default)
			)
			(fill yes)
			(layer "F.Fab")
		)
		(pad "1" smd rect
			(at -1.500124 -1.249934)
			(size 0.2794 0.6096)
			(layers "F.Cu" "F.Mask" "F.Paste")
			(net "P3V3_SSD13")
		)
		(pad "2" smd rect
			(at -1.500124 -0.750062)
			(size 0.2794 0.6096)
			(layers "F.Cu" "F.Mask" "F.Paste")
			(net "P3V3_SSD13")
		)
		(pad "3" smd rect
			(at -1.500124 -0.249936)
			(size 0.2794 0.6096)
			(layers "F.Cu" "F.Mask" "F.Paste")
			(net "P3V3_SSD13")
		)
		(pad "4" smd rect
			(at -1.500124 0.249936)
			(size 0.2794 0.6096)
			(layers "F.Cu" "F.Mask" "F.Paste")
			(net "P3V3_SSD13")
		)
		(pad "5" smd rect
			(at -1.500124 0.750062)
			(size 0.2794 0.6096)
			(layers "F.Cu" "F.Mask" "F.Paste")
			(net "P3V3_SSD13")
		)
		(pad "6" smd rect
			(at -1.500124 1.249934)
			(size 0.2794 0.6096)
			(layers "F.Cu" "F.Mask" "F.Paste")
			(net "GND")
		)
		(pad "7" smd rect
			(at 1.500124 1.249934)
			(size 0.2794 0.6096)
			(layers "F.Cu" "F.Mask" "F.Paste")
			(net "P3V3_SSD13_SS")
		)
		(pad "8" smd rect
			(at 1.500124 0.750062)
			(size 0.2794 0.6096)
			(layers "F.Cu" "F.Mask" "F.Paste")
			(net "PWRGD_P3V3_SSD13")
		)
		(pad "9" smd rect
			(at 1.500124 0.249936)
			(size 0.2794 0.6096)
			(layers "F.Cu" "F.Mask" "F.Paste")
			(net "P3V3_SSD13_OCP")
		)
		(pad "10" smd rect
			(at 1.500124 -0.249936)
			(size 0.2794 0.6096)
			(layers "F.Cu" "F.Mask" "F.Paste")
			(net "P5V_AUX")
		)
		(pad "11" smd rect
			(at 1.500124 -0.750062)
			(size 0.2794 0.6096)
			(layers "F.Cu" "F.Mask" "F.Paste")
			(net "SSD13_AUX_P3V3_EN_R")
		)
		(pad "12" smd rect
			(at 1.500124 -1.249934)
			(size 0.2794 0.6096)
			(layers "F.Cu" "F.Mask" "F.Paste")
			(net "P3V3_AUX")
		)
		(pad "13" smd rect
			(at 0 0 90)
			(size 1.9812 2.7178)
			(layers "F.Cu" "F.Mask" "F.Paste")
			(net "P3V3_AUX")
		)
		(zone
			(layer "F.Cu")
			(hatch none 0.5)
			(connect_pads
				(clearance 0)
			)
			(min_thickness 0.25)
			(keepout
				(tracks not_allowed)
				(vias allowed)
				(pads allowed)
				(copperpour not_allowed)
				(footprints allowed)
			)
			(placement
				(enabled no)
				(sheetname "")
			)
			(fill
				(thermal_gap 0.5)
				(thermal_bridge_width 0.5)
				(island_removal_mode 0)
			)
			(polygon
				(pts
					(xy 379.641608 -56.806846) (xy 379.768608 -56.806846) (xy 382.740408 -56.806846) (xy 382.740916 -56.806846)
					(xy 382.740916 -54.520846) (xy 382.740408 -54.520846) (xy 382.613408 -54.520846) (xy 381.191008 -54.520846)
					(xy 381.191008 -54.622446) (xy 382.613408 -54.622446) (xy 382.613408 -56.705246) (xy 379.768608 -56.705246)
					(xy 379.768608 -54.622446) (xy 381.165608 -54.622446) (xy 381.165608 -54.520846) (xy 379.768608 -54.520846)
					(xy 379.641608 -54.520846) (xy 379.6411 -54.520846) (xy 379.6411 -56.806846)
				)
			)
		)
	)
	(footprint ""
		(layer "F.Cu")
		(at 108.007404 -166.252652 180)
		(property "Reference" "PC28"
			(at 0 0 180)
			(layer "F.SilkS")
			(hide yes)
			(effects
				(font
					(size 1.27 1.27)
				)
			)
		)
		(property "Value" ""
			(at 0 0 180)
			(layer "F.Fab")
			(effects
				(font
					(size 1.27 1.27)
				)
			)
		)
		(duplicate_pad_numbers_are_jumpers no)
		(fp_line
			(start 1.524 0.762)
			(end -1.524 0.762)
			(stroke
				(width 0.1524)
				(type default)
			)
			(layer "F.SilkS")
		)
		(fp_line
			(start 1.524 -0.762)
			(end 1.524 0.762)
			(stroke
				(width 0.1524)
				(type default)
			)
			(layer "F.SilkS")
		)
		(fp_line
			(start -1.524 0.762)
			(end -1.524 -0.762)
			(stroke
				(width 0.1524)
				(type default)
			)
			(layer "F.SilkS")
		)
		(fp_line
			(start -1.524 -0.762)
			(end 1.524 -0.762)
			(stroke
				(width 0.1524)
				(type default)
			)
			(layer "F.SilkS")
		)
		(fp_line
			(start 1.1049 0.724916)
			(end 1.1049 -0.724916)
			(stroke
				(width 0.1)
				(type default)
			)
			(layer "F.Fab")
		)
		(fp_line
			(start 1.1049 -0.724916)
			(end -1.1049 -0.724916)
			(stroke
				(width 0.1)
				(type default)
			)
			(layer "F.Fab")
		)
		(fp_line
			(start -1.1049 0.724916)
			(end 1.1049 0.724916)
			(stroke
				(width 0.1)
				(type default)
			)
			(layer "F.Fab")
		)
		(fp_line
			(start -1.1049 -0.724916)
			(end -1.1049 0.724916)
			(stroke
				(width 0.1)
				(type default)
			)
			(layer "F.Fab")
		)
		(pad "1" smd rect
			(at -0.889 0)
			(size 1.016 1.27)
			(layers "F.Cu" "F.Mask" "F.Paste")
			(net "SW_P12V_P3V3_AUX_FLT")
		)
		(pad "2" smd rect
			(at 0.889 0)
			(size 1.016 1.27)
			(layers "F.Cu" "F.Mask" "F.Paste")
			(net "GND")
		)
	)
	(footprint ""
		(layer "F.Cu")
		(at 340.561422 -192.44945 180)
		(property "Reference" "R4247"
			(at 0 0 180)
			(layer "F.SilkS")
			(hide yes)
			(effects
				(font
					(size 1.27 1.27)
				)
			)
		)
		(property "Value" ""
			(at 0 0 180)
			(layer "F.Fab")
			(effects
				(font
					(size 1.27 1.27)
				)
			)
		)
		(duplicate_pad_numbers_are_jumpers no)
		(fp_line
			(start 0.7874 0.4064)
			(end -0.7874 0.4064)
			(stroke
				(width 0.1524)
				(type default)
			)
			(layer "F.SilkS")
		)
		(fp_line
			(start 0.7874 -0.4064)
			(end 0.7874 0.4064)
			(stroke
				(width 0.1524)
				(type default)
			)
			(layer "F.SilkS")
		)
		(fp_line
			(start -0.7874 0.4064)
			(end -0.7874 -0.4064)
			(stroke
				(width 0.1524)
				(type default)
			)
			(layer "F.SilkS")
		)
		(fp_line
			(start -0.7874 -0.4064)
			(end 0.7874 -0.4064)
			(stroke
				(width 0.1524)
				(type default)
			)
			(layer "F.SilkS")
		)
		(fp_line
			(start 0.67945 0.3048)
			(end 0.120396 0.3048)
			(stroke
				(width 0.1)
				(type default)
			)
			(layer "F.Fab")
		)
		(fp_line
			(start 0.67945 -0.3048)
			(end 0.67945 0.3048)
			(stroke
				(width 0.1)
				(type default)
			)
			(layer "F.Fab")
		)
		(fp_line
			(start 0.12065 -0.2794)
			(end 0.12065 -0.3048)
			(stroke
				(width 0.1)
				(type default)
			)
			(layer "F.Fab")
		)
		(fp_line
			(start 0.12065 -0.3048)
			(end 0.67945 -0.3048)
			(stroke
				(width 0.1)
				(type default)
			)
			(layer "F.Fab")
		)
		(fp_line
			(start 0.120396 0.3048)
			(end 0.120396 0.2794)
			(stroke
				(width 0.1)
				(type default)
			)
			(layer "F.Fab")
		)
		(fp_line
			(start 0.120396 0.2794)
			(end -0.12065 0.2794)
			(stroke
				(width 0.1)
				(type default)
			)
			(layer "F.Fab")
		)
		(fp_line
			(start -0.12065 0.3048)
			(end -0.67945 0.3048)
			(stroke
				(width 0.1)
				(type default)
			)
			(layer "F.Fab")
		)
		(fp_line
			(start -0.12065 0.2794)
			(end -0.12065 0.3048)
			(stroke
				(width 0.1)
				(type default)
			)
			(layer "F.Fab")
		)
		(fp_line
			(start -0.12065 -0.2794)
			(end 0.12065 -0.2794)
			(stroke
				(width 0.1)
				(type default)
			)
			(layer "F.Fab")
		)
		(fp_line
			(start -0.12065 -0.305054)
			(end -0.12065 -0.2794)
			(stroke
				(width 0.1)
				(type default)
			)
			(layer "F.Fab")
		)
		(fp_line
			(start -0.67945 0.3048)
			(end -0.67945 -0.305054)
			(stroke
				(width 0.1)
				(type default)
			)
			(layer "F.Fab")
		)
		(fp_line
			(start -0.67945 -0.305054)
			(end -0.12065 -0.305054)
			(stroke
				(width 0.1)
				(type default)
			)
			(layer "F.Fab")
		)
		(pad "1" smd circle
			(at -0.40005 0 180)
			(size 0 0)
			(layers "F.Cu" "F.Mask" "F.Paste")
			(net "P3V3_AUX")
		)
		(pad "2" smd circle
			(at 0.40005 0 180)
			(size 0 0)
			(layers "F.Cu" "F.Mask" "F.Paste")
			(net "FM_CPU_CATERR_MSMI_LVT3_N")
		)
	)
	(footprint ""
		(layer "F.Cu")
		(at 370.947188 -54.3941)
		(property "Reference" "PU39"
			(at -1.560576 2.93878 0)
			(unlocked yes)
			(layer "F.SilkS")
			(effects
				(font
					(size 0.7874 0.5842)
					(thickness 0.1524)
				)
				(justify left)
			)
		)
		(property "Value" ""
			(at 0 0 0)
			(layer "F.Fab")
			(effects
				(font
					(size 1.27 1.27)
				)
			)
		)
		(duplicate_pad_numbers_are_jumpers no)
		(fp_line
			(start -1.943608 -1.549908)
			(end 1.943608 -1.549908)
			(stroke
				(width 0.1524)
				(type default)
			)
			(layer "F.SilkS")
		)
		(fp_line
			(start -1.943608 1.549908)
			(end -1.943608 -1.549908)
			(stroke
				(width 0.1524)
				(type default)
			)
			(layer "F.SilkS")
		)
		(fp_line
			(start 1.943608 -1.549908)
			(end 1.943608 1.549908)
			(stroke
				(width 0.1524)
				(type default)
			)
			(layer "F.SilkS")
		)
		(fp_line
			(start 1.943608 1.549908)
			(end -1.943608 1.549908)
			(stroke
				(width 0.1524)
				(type default)
			)
			(layer "F.SilkS")
		)
		(fp_poly
			(pts
				(xy -2.019808 -1.549908) (xy -1.257808 -1.549908) (xy -1.257808 -1.880108) (xy -2.019808 -1.880108)
			)
			(stroke
				(width 0)
				(type default)
			)
			(fill yes)
			(layer "F.SilkS")
		)
		(fp_line
			(start -1.549908 -1.549908)
			(end 1.549908 -1.549908)
			(stroke
				(width 0.1)
				(type default)
			)
			(layer "F.Fab")
		)
		(fp_line
			(start -1.549908 1.549908)
			(end -1.549908 -1.549908)
			(stroke
				(width 0.1)
				(type default)
			)
			(layer "F.Fab")
		)
		(fp_line
			(start 1.549908 -1.549908)
			(end 1.549908 1.549908)
			(stroke
				(width 0.1)
				(type default)
			)
			(layer "F.Fab")
		)
		(fp_line
			(start 1.549908 1.549908)
			(end -1.549908 1.549908)
			(stroke
				(width 0.1)
				(type default)
			)
			(layer "F.Fab")
		)
		(fp_poly
			(pts
				(xy -2.019808 -1.549908) (xy -1.257808 -1.549908) (xy -1.257808 -1.880108) (xy -2.019808 -1.880108)
			)
			(stroke
				(width 0)
				(type default)
			)
			(fill yes)
			(layer "F.Fab")
		)
		(pad "1" smd rect
			(at -1.500124 -1.249934 270)
			(size 0.2794 0.6096)
			(layers "F.Cu" "F.Mask" "F.Paste")
			(net "P12V_SSD12_R")
		)
		(pad "2" smd rect
			(at -1.500124 -0.750062 270)
			(size 0.2794 0.6096)
			(layers "F.Cu" "F.Mask" "F.Paste")
			(net "P12V_SSD12_R")
		)
		(pad "3" smd rect
			(at -1.500124 -0.249936 270)
			(size 0.2794 0.6096)
			(layers "F.Cu" "F.Mask" "F.Paste")
			(net "P12V_SSD12_R")
		)
		(pad "4" smd rect
			(at -1.500124 0.249936 270)
			(size 0.2794 0.6096)
			(layers "F.Cu" "F.Mask" "F.Paste")
			(net "P12V_SSD12_R")
		)
		(pad "5" smd rect
			(at -1.500124 0.750062 270)
			(size 0.2794 0.6096)
			(layers "F.Cu" "F.Mask" "F.Paste")
			(net "P12V_SSD12_R")
		)
		(pad "6" smd rect
			(at -1.500124 1.249934 270)
			(size 0.2794 0.6096)
			(layers "F.Cu" "F.Mask" "F.Paste")
			(net "GND")
		)
		(pad "7" smd rect
			(at 1.500124 1.249934 270)
			(size 0.2794 0.6096)
			(layers "F.Cu" "F.Mask" "F.Paste")
			(net "P12V_SSD12_SS")
		)
		(pad "8" smd rect
			(at 1.500124 0.750062 270)
			(size 0.2794 0.6096)
			(layers "F.Cu" "F.Mask" "F.Paste")
			(net "PWRGD_P12V_SSD12")
		)
		(pad "9" smd rect
			(at 1.500124 0.249936 270)
			(size 0.2794 0.6096)
			(layers "F.Cu" "F.Mask" "F.Paste")
			(net "P12V_SSD12_OCP")
		)
		(pad "10" smd rect
			(at 1.500124 -0.249936 270)
			(size 0.2794 0.6096)
			(layers "F.Cu" "F.Mask" "F.Paste")
			(net "P5V_AUX")
		)
		(pad "11" smd rect
			(at 1.500124 -0.750062 270)
			(size 0.2794 0.6096)
			(layers "F.Cu" "F.Mask" "F.Paste")
			(net "SSD12_PWR_EN_R")
		)
		(pad "12" smd rect
			(at 1.500124 -1.249934 270)
			(size 0.2794 0.6096)
			(layers "F.Cu" "F.Mask" "F.Paste")
			(net "P12V_AUX")
		)
		(pad "13" smd rect
			(at 0 0)
			(size 1.9812 2.7178)
			(layers "F.Cu" "F.Mask" "F.Paste")
			(net "P12V_AUX")
		)
		(zone
			(layer "F.Cu")
			(hatch none 0.5)
			(connect_pads
				(clearance 0)
			)
			(min_thickness 0.25)
			(keepout
				(tracks not_allowed)
				(vias allowed)
				(pads allowed)
				(copperpour not_allowed)
				(footprints allowed)
			)
			(placement
				(enabled no)
				(sheetname "")
			)
			(fill
				(thermal_gap 0.5)
				(thermal_bridge_width 0.5)
				(island_removal_mode 0)
			)
			(polygon
				(pts
					(xy 372.090188 -55.9435) (xy 372.090188 -55.8165) (xy 372.090188 -52.8447) (xy 372.090188 -52.844192)
					(xy 369.804188 -52.844192) (xy 369.804188 -52.8447) (xy 369.804188 -52.9717) (xy 369.804188 -54.3941)
					(xy 369.905788 -54.3941) (xy 369.905788 -52.9717) (xy 371.988588 -52.9717) (xy 371.988588 -55.8165)
					(xy 369.905788 -55.8165) (xy 369.905788 -54.4195) (xy 369.804188 -54.4195) (xy 369.804188 -55.8165)
					(xy 369.804188 -55.9435) (xy 369.804188 -55.944008) (xy 372.090188 -55.944008)
				)
			)
		)
	)
	(footprint ""
		(layer "F.Cu")
		(at 259.092446 -338.413344 -90)
		(property "Reference" "R6790"
			(at 0 0 270)
			(layer "F.SilkS")
			(hide yes)
			(effects
				(font
					(size 1.27 1.27)
				)
			)
		)
		(property "Value" ""
			(at 0 0 270)
			(layer "F.Fab")
			(effects
				(font
					(size 1.27 1.27)
				)
			)
		)
		(duplicate_pad_numbers_are_jumpers no)
		(fp_line
			(start -0.7874 0.4064)
			(end -0.7874 -0.4064)
			(stroke
				(width 0.1524)
				(type default)
			)
			(layer "F.SilkS")
		)
		(fp_line
			(start 0.7874 0.4064)
			(end -0.7874 0.4064)
			(stroke
				(width 0.1524)
				(type default)
			)
			(layer "F.SilkS")
		)
		(fp_line
			(start -0.7874 -0.4064)
			(end 0.7874 -0.4064)
			(stroke
				(width 0.1524)
				(type default)
			)
			(layer "F.SilkS")
		)
		(fp_line
			(start 0.7874 -0.4064)
			(end 0.7874 0.4064)
			(stroke
				(width 0.1524)
				(type default)
			)
			(layer "F.SilkS")
		)
		(fp_line
			(start -0.67945 0.3048)
			(end -0.67945 -0.305054)
			(stroke
				(width 0.1)
				(type default)
			)
			(layer "F.Fab")
		)
		(fp_line
			(start -0.12065 0.3048)
			(end -0.67945 0.3048)
			(stroke
				(width 0.1)
				(type default)
			)
			(layer "F.Fab")
		)
		(fp_line
			(start 0.120396 0.3048)
			(end 0.120396 0.2794)
			(stroke
				(width 0.1)
				(type default)
			)
			(layer "F.Fab")
		)
		(fp_line
			(start 0.67945 0.3048)
			(end 0.120396 0.3048)
			(stroke
				(width 0.1)
				(type default)
			)
			(layer "F.Fab")
		)
		(fp_line
			(start -0.12065 0.2794)
			(end -0.12065 0.3048)
			(stroke
				(width 0.1)
				(type default)
			)
			(layer "F.Fab")
		)
		(fp_line
			(start 0.120396 0.2794)
			(end -0.12065 0.2794)
			(stroke
				(width 0.1)
				(type default)
			)
			(layer "F.Fab")
		)
		(fp_line
			(start -0.12065 -0.2794)
			(end 0.12065 -0.2794)
			(stroke
				(width 0.1)
				(type default)
			)
			(layer "F.Fab")
		)
		(fp_line
			(start 0.12065 -0.2794)
			(end 0.12065 -0.3048)
			(stroke
				(width 0.1)
				(type default)
			)
			(layer "F.Fab")
		)
		(fp_line
			(start 0.12065 -0.3048)
			(end 0.67945 -0.3048)
			(stroke
				(width 0.1)
				(type default)
			)
			(layer "F.Fab")
		)
		(fp_line
			(start 0.67945 -0.3048)
			(end 0.67945 0.3048)
			(stroke
				(width 0.1)
				(type default)
			)
			(layer "F.Fab")
		)
		(fp_line
			(start -0.67945 -0.305054)
			(end -0.12065 -0.305054)
			(stroke
				(width 0.1)
				(type default)
			)
			(layer "F.Fab")
		)
		(fp_line
			(start -0.12065 -0.305054)
			(end -0.12065 -0.2794)
			(stroke
				(width 0.1)
				(type default)
			)
			(layer "F.Fab")
		)
		(pad "1" smd circle
			(at -0.40005 0 270)
			(size 0 0)
			(layers "F.Cu" "F.Mask" "F.Paste")
			(net "P3V3_AUX")
		)
		(pad "2" smd circle
			(at 0.40005 0 270)
			(size 0 0)
			(layers "F.Cu" "F.Mask" "F.Paste")
			(net "OC_P2V5_COMP")
		)
	)
	(footprint ""
		(layer "F.Cu")
		(at 261.55777 -27.006296 -90)
		(property "Reference" "PR7117"
			(at 0 0 270)
			(layer "F.SilkS")
			(hide yes)
			(effects
				(font
					(size 1.27 1.27)
				)
			)
		)
		(property "Value" ""
			(at 0 0 270)
			(layer "F.Fab")
			(effects
				(font
					(size 1.27 1.27)
				)
			)
		)
		(duplicate_pad_numbers_are_jumpers no)
		(fp_line
			(start -0.7874 0.4064)
			(end -0.7874 -0.4064)
			(stroke
				(width 0.1524)
				(type default)
			)
			(layer "F.SilkS")
		)
		(fp_line
			(start 0.7874 0.4064)
			(end -0.7874 0.4064)
			(stroke
				(width 0.1524)
				(type default)
			)
			(layer "F.SilkS")
		)
		(fp_line
			(start -0.7874 -0.4064)
			(end 0.7874 -0.4064)
			(stroke
				(width 0.1524)
				(type default)
			)
			(layer "F.SilkS")
		)
		(fp_line
			(start 0.7874 -0.4064)
			(end 0.7874 0.4064)
			(stroke
				(width 0.1524)
				(type default)
			)
			(layer "F.SilkS")
		)
		(fp_line
			(start -0.67945 0.3048)
			(end -0.67945 -0.305054)
			(stroke
				(width 0.1)
				(type default)
			)
			(layer "F.Fab")
		)
		(fp_line
			(start -0.12065 0.3048)
			(end -0.67945 0.3048)
			(stroke
				(width 0.1)
				(type default)
			)
			(layer "F.Fab")
		)
		(fp_line
			(start 0.120396 0.3048)
			(end 0.120396 0.2794)
			(stroke
				(width 0.1)
				(type default)
			)
			(layer "F.Fab")
		)
		(fp_line
			(start 0.67945 0.3048)
			(end 0.120396 0.3048)
			(stroke
				(width 0.1)
				(type default)
			)
			(layer "F.Fab")
		)
		(fp_line
			(start -0.12065 0.2794)
			(end -0.12065 0.3048)
			(stroke
				(width 0.1)
				(type default)
			)
			(layer "F.Fab")
		)
		(fp_line
			(start 0.120396 0.2794)
			(end -0.12065 0.2794)
			(stroke
				(width 0.1)
				(type default)
			)
			(layer "F.Fab")
		)
		(fp_line
			(start -0.12065 -0.2794)
			(end 0.12065 -0.2794)
			(stroke
				(width 0.1)
				(type default)
			)
			(layer "F.Fab")
		)
		(fp_line
			(start 0.12065 -0.2794)
			(end 0.12065 -0.3048)
			(stroke
				(width 0.1)
				(type default)
			)
			(layer "F.Fab")
		)
		(fp_line
			(start 0.12065 -0.3048)
			(end 0.67945 -0.3048)
			(stroke
				(width 0.1)
				(type default)
			)
			(layer "F.Fab")
		)
		(fp_line
			(start 0.67945 -0.3048)
			(end 0.67945 0.3048)
			(stroke
				(width 0.1)
				(type default)
			)
			(layer "F.Fab")
		)
		(fp_line
			(start -0.67945 -0.305054)
			(end -0.12065 -0.305054)
			(stroke
				(width 0.1)
				(type default)
			)
			(layer "F.Fab")
		)
		(fp_line
			(start -0.12065 -0.305054)
			(end -0.12065 -0.2794)
			(stroke
				(width 0.1)
				(type default)
			)
			(layer "F.Fab")
		)
		(pad "1" smd circle
			(at -0.40005 0 270)
			(size 0 0)
			(layers "F.Cu" "F.Mask" "F.Paste")
			(net "P3V3_SSD9_CO_MODE")
		)
		(pad "2" smd circle
			(at 0.40005 0 270)
			(size 0 0)
			(layers "F.Cu" "F.Mask" "F.Paste")
			(net "GND")
		)
	)
	(footprint ""
		(layer "F.Cu")
		(at 34.211006 -61.386974)
		(property "Reference" "R4486"
			(at 0 0 0)
			(layer "F.SilkS")
			(hide yes)
			(effects
				(font
					(size 1.27 1.27)
				)
			)
		)
		(property "Value" ""
			(at 0 0 0)
			(layer "F.Fab")
			(effects
				(font
					(size 1.27 1.27)
				)
			)
		)
		(duplicate_pad_numbers_are_jumpers no)
		(fp_line
			(start -0.7874 -0.4064)
			(end 0.7874 -0.4064)
			(stroke
				(width 0.1524)
				(type default)
			)
			(layer "F.SilkS")
		)
		(fp_line
			(start -0.7874 0.4064)
			(end -0.7874 -0.4064)
			(stroke
				(width 0.1524)
				(type default)
			)
			(layer "F.SilkS")
		)
		(fp_line
			(start 0.7874 -0.4064)
			(end 0.7874 0.4064)
			(stroke
				(width 0.1524)
				(type default)
			)
			(layer "F.SilkS")
		)
		(fp_line
			(start 0.7874 0.4064)
			(end -0.7874 0.4064)
			(stroke
				(width 0.1524)
				(type default)
			)
			(layer "F.SilkS")
		)
		(fp_line
			(start -0.67945 -0.305054)
			(end -0.12065 -0.305054)
			(stroke
				(width 0.1)
				(type default)
			)
			(layer "F.Fab")
		)
		(fp_line
			(start -0.67945 0.3048)
			(end -0.67945 -0.305054)
			(stroke
				(width 0.1)
				(type default)
			)
			(layer "F.Fab")
		)
		(fp_line
			(start -0.12065 -0.305054)
			(end -0.12065 -0.2794)
			(stroke
				(width 0.1)
				(type default)
			)
			(layer "F.Fab")
		)
		(fp_line
			(start -0.12065 -0.2794)
			(end 0.12065 -0.2794)
			(stroke
				(width 0.1)
				(type default)
			)
			(layer "F.Fab")
		)
		(fp_line
			(start -0.12065 0.2794)
			(end -0.12065 0.3048)
			(stroke
				(width 0.1)
				(type default)
			)
			(layer "F.Fab")
		)
		(fp_line
			(start -0.12065 0.3048)
			(end -0.67945 0.3048)
			(stroke
				(width 0.1)
				(type default)
			)
			(layer "F.Fab")
		)
		(fp_line
			(start 0.120396 0.2794)
			(end -0.12065 0.2794)
			(stroke
				(width 0.1)
				(type default)
			)
			(layer "F.Fab")
		)
		(fp_line
			(start 0.120396 0.3048)
			(end 0.120396 0.2794)
			(stroke
				(width 0.1)
				(type default)
			)
			(layer "F.Fab")
		)
		(fp_line
			(start 0.12065 -0.3048)
			(end 0.67945 -0.3048)
			(stroke
				(width 0.1)
				(type default)
			)
			(layer "F.Fab")
		)
		(fp_line
			(start 0.12065 -0.2794)
			(end 0.12065 -0.3048)
			(stroke
				(width 0.1)
				(type default)
			)
			(layer "F.Fab")
		)
		(fp_line
			(start 0.67945 -0.3048)
			(end 0.67945 0.3048)
			(stroke
				(width 0.1)
				(type default)
			)
			(layer "F.Fab")
		)
		(fp_line
			(start 0.67945 0.3048)
			(end 0.120396 0.3048)
			(stroke
				(width 0.1)
				(type default)
			)
			(layer "F.Fab")
		)
		(pad "1" smd circle
			(at -0.40005 0)
			(size 0 0)
			(layers "F.Cu" "F.Mask" "F.Paste")
			(net "PWRGD_P3V3_SSD1")
		)
		(pad "2" smd circle
			(at 0.40005 0)
			(size 0 0)
			(layers "F.Cu" "F.Mask" "F.Paste")
			(net "PWRGD_P3V3_SSD1_R")
		)
	)
	(footprint ""
		(layer "F.Cu")
		(at 399.5928 -86.7664 180)
		(property "Reference" "R6265"
			(at 0 0 180)
			(layer "F.SilkS")
			(hide yes)
			(effects
				(font
					(size 1.27 1.27)
				)
			)
		)
		(property "Value" ""
			(at 0 0 180)
			(layer "F.Fab")
			(effects
				(font
					(size 1.27 1.27)
				)
			)
		)
		(duplicate_pad_numbers_are_jumpers no)
		(fp_line
			(start 0.7874 0.4064)
			(end -0.7874 0.4064)
			(stroke
				(width 0.1524)
				(type default)
			)
			(layer "F.SilkS")
		)
		(fp_line
			(start 0.7874 -0.4064)
			(end 0.7874 0.4064)
			(stroke
				(width 0.1524)
				(type default)
			)
			(layer "F.SilkS")
		)
		(fp_line
			(start -0.7874 0.4064)
			(end -0.7874 -0.4064)
			(stroke
				(width 0.1524)
				(type default)
			)
			(layer "F.SilkS")
		)
		(fp_line
			(start -0.7874 -0.4064)
			(end 0.7874 -0.4064)
			(stroke
				(width 0.1524)
				(type default)
			)
			(layer "F.SilkS")
		)
		(fp_line
			(start 0.67945 0.3048)
			(end 0.120396 0.3048)
			(stroke
				(width 0.1)
				(type default)
			)
			(layer "F.Fab")
		)
		(fp_line
			(start 0.67945 -0.3048)
			(end 0.67945 0.3048)
			(stroke
				(width 0.1)
				(type default)
			)
			(layer "F.Fab")
		)
		(fp_line
			(start 0.12065 -0.2794)
			(end 0.12065 -0.3048)
			(stroke
				(width 0.1)
				(type default)
			)
			(layer "F.Fab")
		)
		(fp_line
			(start 0.12065 -0.3048)
			(end 0.67945 -0.3048)
			(stroke
				(width 0.1)
				(type default)
			)
			(layer "F.Fab")
		)
		(fp_line
			(start 0.120396 0.3048)
			(end 0.120396 0.2794)
			(stroke
				(width 0.1)
				(type default)
			)
			(layer "F.Fab")
		)
		(fp_line
			(start 0.120396 0.2794)
			(end -0.12065 0.2794)
			(stroke
				(width 0.1)
				(type default)
			)
			(layer "F.Fab")
		)
		(fp_line
			(start -0.12065 0.3048)
			(end -0.67945 0.3048)
			(stroke
				(width 0.1)
				(type default)
			)
			(layer "F.Fab")
		)
		(fp_line
			(start -0.12065 0.2794)
			(end -0.12065 0.3048)
			(stroke
				(width 0.1)
				(type default)
			)
			(layer "F.Fab")
		)
		(fp_line
			(start -0.12065 -0.2794)
			(end 0.12065 -0.2794)
			(stroke
				(width 0.1)
				(type default)
			)
			(layer "F.Fab")
		)
		(fp_line
			(start -0.12065 -0.305054)
			(end -0.12065 -0.2794)
			(stroke
				(width 0.1)
				(type default)
			)
			(layer "F.Fab")
		)
		(fp_line
			(start -0.67945 0.3048)
			(end -0.67945 -0.305054)
			(stroke
				(width 0.1)
				(type default)
			)
			(layer "F.Fab")
		)
		(fp_line
			(start -0.67945 -0.305054)
			(end -0.12065 -0.305054)
			(stroke
				(width 0.1)
				(type default)
			)
			(layer "F.Fab")
		)
		(pad "1" smd circle
			(at -0.40005 0 180)
			(size 0 0)
			(layers "F.Cu" "F.Mask" "F.Paste")
			(net "CLK_ISO_EN")
		)
		(pad "2" smd circle
			(at 0.40005 0 180)
			(size 0 0)
			(layers "F.Cu" "F.Mask" "F.Paste")
			(net "P3V3_AUX")
		)
	)
	(footprint ""
		(layer "F.Cu")
		(at 415.501328 -55.78475 -90)
		(property "Reference" "PD122"
			(at 4.07035 2.140458 90)
			(unlocked yes)
			(layer "F.SilkS")
			(effects
				(font
					(size 0.7874 0.5842)
					(thickness 0.1524)
				)
				(justify left)
			)
		)
		(property "Value" ""
			(at 0 0 270)
			(layer "F.Fab")
			(effects
				(font
					(size 1.27 1.27)
				)
			)
		)
		(duplicate_pad_numbers_are_jumpers no)
		(fp_line
			(start -3.400044 1.459992)
			(end -3.400044 -1.459992)
			(stroke
				(width 0.1524)
				(type default)
			)
			(layer "F.SilkS")
		)
		(fp_line
			(start 4.107942 1.459992)
			(end -3.400044 1.459992)
			(stroke
				(width 0.1524)
				(type default)
			)
			(layer "F.SilkS")
		)
		(fp_line
			(start -3.400044 -1.459992)
			(end 4.107942 -1.459992)
			(stroke
				(width 0.1524)
				(type default)
			)
			(layer "F.SilkS")
		)
		(fp_line
			(start 4.107942 -1.459992)
			(end 4.107942 1.459992)
			(stroke
				(width 0.1524)
				(type default)
			)
			(layer "F.SilkS")
		)
		(fp_poly
			(pts
				(xy 4.107942 -1.459992) (xy 4.107942 1.459992) (xy 3.308096 1.459992) (xy 3.308096 -1.459992)
			)
			(stroke
				(width 0)
				(type default)
			)
			(fill yes)
			(layer "F.SilkS")
		)
		(fp_line
			(start -2.29997 1.459992)
			(end -2.29997 -1.459992)
			(stroke
				(width 0.1)
				(type default)
			)
			(layer "F.Fab")
		)
		(fp_line
			(start 2.29997 1.459992)
			(end -2.29997 1.459992)
			(stroke
				(width 0.1)
				(type default)
			)
			(layer "F.Fab")
		)
		(fp_line
			(start -2.29997 -1.459992)
			(end 2.29997 -1.459992)
			(stroke
				(width 0.1)
				(type default)
			)
			(layer "F.Fab")
		)
		(fp_line
			(start 2.29997 -1.459992)
			(end 2.29997 1.459992)
			(stroke
				(width 0.1)
				(type default)
			)
			(layer "F.Fab")
		)
		(fp_text user "-"
			(at 5.4102 0.29845 90)
			(unlocked yes)
			(layer "F.SilkS")
			(effects
				(font
					(size 1.905 1.4224)
					(thickness 0.1524)
				)
				(justify left)
			)
		)
		(fp_text user "+"
			(at -4.7752 -0.12065 270)
			(unlocked yes)
			(layer "F.SilkS")
			(effects
				(font
					(size 1.905 1.4224)
					(thickness 0.1524)
				)
				(justify left)
			)
		)
		(fp_text user "-"
			(at 5.4102 0.29845 90)
			(unlocked yes)
			(layer "F.Fab")
			(effects
				(font
					(size 1.905 1.4224)
					(thickness 0.1524)
				)
				(justify left)
			)
		)
		(fp_text user "+"
			(at -4.7752 -0.12065 270)
			(unlocked yes)
			(layer "F.Fab")
			(effects
				(font
					(size 1.905 1.4224)
					(thickness 0.1524)
				)
				(justify left)
			)
		)
		(pad "A" smd rect
			(at -1.999996 0)
			(size 1.7018 2.5146)
			(layers "F.Cu" "F.Mask" "F.Paste")
			(net "GND")
		)
		(pad "C" smd rect
			(at 1.999996 0)
			(size 1.7018 2.5146)
			(layers "F.Cu" "F.Mask" "F.Paste")
			(net "P12V_SSD14_R")
		)
	)
	(footprint ""
		(layer "F.Cu")
		(at 129.831084 -125.144784 180)
		(property "Reference" "PU50"
			(at 2.573274 -2.85115 0)
			(unlocked yes)
			(layer "F.SilkS")
			(effects
				(font
					(size 0.7874 0.5842)
					(thickness 0.1524)
				)
				(justify left)
			)
		)
		(property "Value" ""
			(at 0 0 180)
			(layer "F.Fab")
			(effects
				(font
					(size 1.27 1.27)
				)
			)
		)
		(duplicate_pad_numbers_are_jumpers no)
		(fp_line
			(start 1.943608 1.549908)
			(end -1.943608 1.549908)
			(stroke
				(width 0.1524)
				(type default)
			)
			(layer "F.SilkS")
		)
		(fp_line
			(start 1.943608 -1.549908)
			(end 1.943608 1.549908)
			(stroke
				(width 0.1524)
				(type default)
			)
			(layer "F.SilkS")
		)
		(fp_line
			(start -1.943608 1.549908)
			(end -1.943608 -1.549908)
			(stroke
				(width 0.1524)
				(type default)
			)
			(layer "F.SilkS")
		)
		(fp_line
			(start -1.943608 -1.549908)
			(end 1.943608 -1.549908)
			(stroke
				(width 0.1524)
				(type default)
			)
			(layer "F.SilkS")
		)
		(fp_poly
			(pts
				(xy -2.019808 -1.549908) (xy -1.257808 -1.549908) (xy -1.257808 -1.880108) (xy -2.019808 -1.880108)
			)
			(stroke
				(width 0)
				(type default)
			)
			(fill yes)
			(layer "F.SilkS")
		)
		(fp_line
			(start 1.549908 1.549908)
			(end -1.549908 1.549908)
			(stroke
				(width 0.1)
				(type default)
			)
			(layer "F.Fab")
		)
		(fp_line
			(start 1.549908 -1.549908)
			(end 1.549908 1.549908)
			(stroke
				(width 0.1)
				(type default)
			)
			(layer "F.Fab")
		)
		(fp_line
			(start -1.549908 1.549908)
			(end -1.549908 -1.549908)
			(stroke
				(width 0.1)
				(type default)
			)
			(layer "F.Fab")
		)
		(fp_line
			(start -1.549908 -1.549908)
			(end 1.549908 -1.549908)
			(stroke
				(width 0.1)
				(type default)
			)
			(layer "F.Fab")
		)
		(fp_poly
			(pts
				(xy -2.019808 -1.549908) (xy -1.257808 -1.549908) (xy -1.257808 -1.880108) (xy -2.019808 -1.880108)
			)
			(stroke
				(width 0)
				(type default)
			)
			(fill yes)
			(layer "F.Fab")
		)
		(pad "1" smd rect
			(at -1.500124 -1.249934 90)
			(size 0.2794 0.6096)
			(layers "F.Cu" "F.Mask" "F.Paste")
			(net "P3V3_NIC2")
		)
		(pad "2" smd rect
			(at -1.500124 -0.750062 90)
			(size 0.2794 0.6096)
			(layers "F.Cu" "F.Mask" "F.Paste")
			(net "P3V3_NIC2")
		)
		(pad "3" smd rect
			(at -1.500124 -0.249936 90)
			(size 0.2794 0.6096)
			(layers "F.Cu" "F.Mask" "F.Paste")
			(net "P3V3_NIC2")
		)
		(pad "4" smd rect
			(at -1.500124 0.249936 90)
			(size 0.2794 0.6096)
			(layers "F.Cu" "F.Mask" "F.Paste")
			(net "P3V3_NIC2")
		)
		(pad "5" smd rect
			(at -1.500124 0.750062 90)
			(size 0.2794 0.6096)
			(layers "F.Cu" "F.Mask" "F.Paste")
			(net "P3V3_NIC2")
		)
		(pad "6" smd rect
			(at -1.500124 1.249934 90)
			(size 0.2794 0.6096)
			(layers "F.Cu" "F.Mask" "F.Paste")
			(net "GND")
		)
		(pad "7" smd rect
			(at 1.500124 1.249934 90)
			(size 0.2794 0.6096)
			(layers "F.Cu" "F.Mask" "F.Paste")
			(net "P3V3_NIC2_SS")
		)
		(pad "8" smd rect
			(at 1.500124 0.750062 90)
			(size 0.2794 0.6096)
			(layers "F.Cu" "F.Mask" "F.Paste")
			(net "PWRGD_P3V3_NIC2")
		)
		(pad "9" smd rect
			(at 1.500124 0.249936 90)
			(size 0.2794 0.6096)
			(layers "F.Cu" "F.Mask" "F.Paste")
			(net "P3V3_NIC2_OCP")
		)
		(pad "10" smd rect
			(at 1.500124 -0.249936 90)
			(size 0.2794 0.6096)
			(layers "F.Cu" "F.Mask" "F.Paste")
			(net "P5V_AUX")
		)
		(pad "11" smd rect
			(at 1.500124 -0.750062 90)
			(size 0.2794 0.6096)
			(layers "F.Cu" "F.Mask" "F.Paste")
			(net "HP_NIC2_EN")
		)
		(pad "12" smd rect
			(at 1.500124 -1.249934 90)
			(size 0.2794 0.6096)
			(layers "F.Cu" "F.Mask" "F.Paste")
			(net "P3V3_AUX")
		)
		(pad "13" smd rect
			(at 0 0 180)
			(size 1.9812 2.7178)
			(layers "F.Cu" "F.Mask" "F.Paste")
			(net "P3V3_AUX")
		)
		(zone
			(layer "F.Cu")
			(hatch none 0.5)
			(connect_pads
				(clearance 0)
			)
			(min_thickness 0.25)
			(keepout
				(tracks not_allowed)
				(vias allowed)
				(pads allowed)
				(copperpour not_allowed)
				(footprints allowed)
			)
			(placement
				(enabled no)
				(sheetname "")
			)
			(fill
				(thermal_gap 0.5)
				(thermal_bridge_width 0.5)
				(island_removal_mode 0)
			)
			(polygon
				(pts
					(xy 128.688084 -123.595384) (xy 128.688084 -123.722384) (xy 128.688084 -126.694184) (xy 128.688084 -126.694692)
					(xy 130.974084 -126.694692) (xy 130.974084 -126.694184) (xy 130.974084 -126.567184) (xy 130.974084 -125.144784)
					(xy 130.872484 -125.144784) (xy 130.872484 -126.567184) (xy 128.789684 -126.567184) (xy 128.789684 -123.722384)
					(xy 130.872484 -123.722384) (xy 130.872484 -125.119384) (xy 130.974084 -125.119384) (xy 130.974084 -123.722384)
					(xy 130.974084 -123.595384) (xy 130.974084 -123.594876) (xy 128.688084 -123.594876)
				)
			)
		)
	)
	(footprint ""
		(layer "F.Cu")
		(at 366.247172 -55.63489 90)
		(property "Reference" "PC407"
			(at 0 0 90)
			(layer "F.SilkS")
			(hide yes)
			(effects
				(font
					(size 1.27 1.27)
				)
			)
		)
		(property "Value" ""
			(at 0 0 90)
			(layer "F.Fab")
			(effects
				(font
					(size 1.27 1.27)
				)
			)
		)
		(duplicate_pad_numbers_are_jumpers no)
		(fp_line
			(start 1.524 -0.762)
			(end 1.524 0.762)
			(stroke
				(width 0.1524)
				(type default)
			)
			(layer "F.SilkS")
		)
		(fp_line
			(start -1.524 -0.762)
			(end 1.524 -0.762)
			(stroke
				(width 0.1524)
				(type default)
			)
			(layer "F.SilkS")
		)
		(fp_line
			(start 1.524 0.762)
			(end -1.524 0.762)
			(stroke
				(width 0.1524)
				(type default)
			)
			(layer "F.SilkS")
		)
		(fp_line
			(start -1.524 0.762)
			(end -1.524 -0.762)
			(stroke
				(width 0.1524)
				(type default)
			)
			(layer "F.SilkS")
		)
		(fp_line
			(start 1.1049 -0.724916)
			(end -1.1049 -0.724916)
			(stroke
				(width 0.1)
				(type default)
			)
			(layer "F.Fab")
		)
		(fp_line
			(start -1.1049 -0.724916)
			(end -1.1049 0.724916)
			(stroke
				(width 0.1)
				(type default)
			)
			(layer "F.Fab")
		)
		(fp_line
			(start 1.1049 0.724916)
			(end 1.1049 -0.724916)
			(stroke
				(width 0.1)
				(type default)
			)
			(layer "F.Fab")
		)
		(fp_line
			(start -1.1049 0.724916)
			(end 1.1049 0.724916)
			(stroke
				(width 0.1)
				(type default)
			)
			(layer "F.Fab")
		)
		(pad "1" smd rect
			(at -0.889 0 270)
			(size 1.016 1.27)
			(layers "F.Cu" "F.Mask" "F.Paste")
			(net "P12V_SSD12_R")
		)
		(pad "2" smd rect
			(at 0.889 0 270)
			(size 1.016 1.27)
			(layers "F.Cu" "F.Mask" "F.Paste")
			(net "GND")
		)
	)
	(footprint ""
		(layer "F.Cu")
		(at 447.247264 -21.37156)
		(property "Reference" "C3980"
			(at 0 0 0)
			(layer "F.SilkS")
			(hide yes)
			(effects
				(font
					(size 1.27 1.27)
				)
			)
		)
		(property "Value" ""
			(at 0 0 0)
			(layer "F.Fab")
			(effects
				(font
					(size 1.27 1.27)
				)
			)
		)
		(duplicate_pad_numbers_are_jumpers no)
		(fp_line
			(start -0.7874 -0.4064)
			(end 0.7874 -0.4064)
			(stroke
				(width 0.1524)
				(type default)
			)
			(layer "F.SilkS")
		)
		(fp_line
			(start -0.7874 0.4064)
			(end -0.7874 -0.4064)
			(stroke
				(width 0.1524)
				(type default)
			)
			(layer "F.SilkS")
		)
		(fp_line
			(start 0.7874 -0.4064)
			(end 0.7874 0.4064)
			(stroke
				(width 0.1524)
				(type default)
			)
			(layer "F.SilkS")
		)
		(fp_line
			(start 0.7874 0.4064)
			(end -0.7874 0.4064)
			(stroke
				(width 0.1524)
				(type default)
			)
			(layer "F.SilkS")
		)
		(fp_line
			(start -0.67945 -0.305054)
			(end -0.12065 -0.305054)
			(stroke
				(width 0.1)
				(type default)
			)
			(layer "F.Fab")
		)
		(fp_line
			(start -0.67945 0.3048)
			(end -0.67945 -0.305054)
			(stroke
				(width 0.1)
				(type default)
			)
			(layer "F.Fab")
		)
		(fp_line
			(start -0.12065 -0.305054)
			(end -0.12065 -0.2794)
			(stroke
				(width 0.1)
				(type default)
			)
			(layer "F.Fab")
		)
		(fp_line
			(start -0.12065 -0.2794)
			(end 0.12065 -0.2794)
			(stroke
				(width 0.1)
				(type default)
			)
			(layer "F.Fab")
		)
		(fp_line
			(start -0.12065 0.2794)
			(end -0.12065 0.3048)
			(stroke
				(width 0.1)
				(type default)
			)
			(layer "F.Fab")
		)
		(fp_line
			(start -0.12065 0.3048)
			(end -0.67945 0.3048)
			(stroke
				(width 0.1)
				(type default)
			)
			(layer "F.Fab")
		)
		(fp_line
			(start 0.120396 0.2794)
			(end -0.12065 0.2794)
			(stroke
				(width 0.1)
				(type default)
			)
			(layer "F.Fab")
		)
		(fp_line
			(start 0.120396 0.3048)
			(end 0.120396 0.2794)
			(stroke
				(width 0.1)
				(type default)
			)
			(layer "F.Fab")
		)
		(fp_line
			(start 0.12065 -0.3048)
			(end 0.67945 -0.3048)
			(stroke
				(width 0.1)
				(type default)
			)
			(layer "F.Fab")
		)
		(fp_line
			(start 0.12065 -0.2794)
			(end 0.12065 -0.3048)
			(stroke
				(width 0.1)
				(type default)
			)
			(layer "F.Fab")
		)
		(fp_line
			(start 0.67945 -0.3048)
			(end 0.67945 0.3048)
			(stroke
				(width 0.1)
				(type default)
			)
			(layer "F.Fab")
		)
		(fp_line
			(start 0.67945 0.3048)
			(end 0.120396 0.3048)
			(stroke
				(width 0.1)
				(type default)
			)
			(layer "F.Fab")
		)
		(pad "1" smd circle
			(at -0.40005 0)
			(size 0 0)
			(layers "F.Cu" "F.Mask" "F.Paste")
			(net "P12V_SSD15")
		)
		(pad "2" smd circle
			(at 0.40005 0)
			(size 0 0)
			(layers "F.Cu" "F.Mask" "F.Paste")
			(net "GND")
		)
	)
	(footprint ""
		(layer "F.Cu")
		(at 92.050108 -306.074572 90)
		(property "Reference" "R1242"
			(at 0 0 90)
			(layer "F.SilkS")
			(hide yes)
			(effects
				(font
					(size 1.27 1.27)
				)
			)
		)
		(property "Value" ""
			(at 0 0 90)
			(layer "F.Fab")
			(effects
				(font
					(size 1.27 1.27)
				)
			)
		)
		(duplicate_pad_numbers_are_jumpers no)
		(fp_line
			(start 0.7874 -0.4064)
			(end 0.7874 0.4064)
			(stroke
				(width 0.1524)
				(type default)
			)
			(layer "F.SilkS")
		)
		(fp_line
			(start -0.7874 -0.4064)
			(end 0.7874 -0.4064)
			(stroke
				(width 0.1524)
				(type default)
			)
			(layer "F.SilkS")
		)
		(fp_line
			(start 0.7874 0.4064)
			(end -0.7874 0.4064)
			(stroke
				(width 0.1524)
				(type default)
			)
			(layer "F.SilkS")
		)
		(fp_line
			(start -0.7874 0.4064)
			(end -0.7874 -0.4064)
			(stroke
				(width 0.1524)
				(type default)
			)
			(layer "F.SilkS")
		)
		(fp_line
			(start -0.12065 -0.305054)
			(end -0.12065 -0.2794)
			(stroke
				(width 0.1)
				(type default)
			)
			(layer "F.Fab")
		)
		(fp_line
			(start -0.67945 -0.305054)
			(end -0.12065 -0.305054)
			(stroke
				(width 0.1)
				(type default)
			)
			(layer "F.Fab")
		)
		(fp_line
			(start 0.67945 -0.3048)
			(end 0.67945 0.3048)
			(stroke
				(width 0.1)
				(type default)
			)
			(layer "F.Fab")
		)
		(fp_line
			(start 0.12065 -0.3048)
			(end 0.67945 -0.3048)
			(stroke
				(width 0.1)
				(type default)
			)
			(layer "F.Fab")
		)
		(fp_line
			(start 0.12065 -0.2794)
			(end 0.12065 -0.3048)
			(stroke
				(width 0.1)
				(type default)
			)
			(layer "F.Fab")
		)
		(fp_line
			(start -0.12065 -0.2794)
			(end 0.12065 -0.2794)
			(stroke
				(width 0.1)
				(type default)
			)
			(layer "F.Fab")
		)
		(fp_line
			(start 0.120396 0.2794)
			(end -0.12065 0.2794)
			(stroke
				(width 0.1)
				(type default)
			)
			(layer "F.Fab")
		)
		(fp_line
			(start -0.12065 0.2794)
			(end -0.12065 0.3048)
			(stroke
				(width 0.1)
				(type default)
			)
			(layer "F.Fab")
		)
		(fp_line
			(start 0.67945 0.3048)
			(end 0.120396 0.3048)
			(stroke
				(width 0.1)
				(type default)
			)
			(layer "F.Fab")
		)
		(fp_line
			(start 0.120396 0.3048)
			(end 0.120396 0.2794)
			(stroke
				(width 0.1)
				(type default)
			)
			(layer "F.Fab")
		)
		(fp_line
			(start -0.12065 0.3048)
			(end -0.67945 0.3048)
			(stroke
				(width 0.1)
				(type default)
			)
			(layer "F.Fab")
		)
		(fp_line
			(start -0.67945 0.3048)
			(end -0.67945 -0.305054)
			(stroke
				(width 0.1)
				(type default)
			)
			(layer "F.Fab")
		)
		(pad "1" smd circle
			(at -0.40005 0 90)
			(size 0 0)
			(layers "F.Cu" "F.Mask" "F.Paste")
			(net "PEX0_SPARE6")
		)
		(pad "2" smd circle
			(at 0.40005 0 90)
			(size 0 0)
			(layers "F.Cu" "F.Mask" "F.Paste")
			(net "P1V8_PEX")
		)
	)
	(footprint ""
		(layer "F.Cu")
		(at 342.352884 -116.230654 90)
		(property "Reference" "PR7035"
			(at 0 0 90)
			(layer "F.SilkS")
			(hide yes)
			(effects
				(font
					(size 1.27 1.27)
				)
			)
		)
		(property "Value" ""
			(at 0 0 90)
			(layer "F.Fab")
			(effects
				(font
					(size 1.27 1.27)
				)
			)
		)
		(duplicate_pad_numbers_are_jumpers no)
		(fp_line
			(start 0.7874 -0.4064)
			(end 0.7874 0.4064)
			(stroke
				(width 0.1524)
				(type default)
			)
			(layer "F.SilkS")
		)
		(fp_line
			(start -0.7874 -0.4064)
			(end 0.7874 -0.4064)
			(stroke
				(width 0.1524)
				(type default)
			)
			(layer "F.SilkS")
		)
		(fp_line
			(start 0.7874 0.4064)
			(end -0.7874 0.4064)
			(stroke
				(width 0.1524)
				(type default)
			)
			(layer "F.SilkS")
		)
		(fp_line
			(start -0.7874 0.4064)
			(end -0.7874 -0.4064)
			(stroke
				(width 0.1524)
				(type default)
			)
			(layer "F.SilkS")
		)
		(fp_line
			(start -0.12065 -0.305054)
			(end -0.12065 -0.2794)
			(stroke
				(width 0.1)
				(type default)
			)
			(layer "F.Fab")
		)
		(fp_line
			(start -0.67945 -0.305054)
			(end -0.12065 -0.305054)
			(stroke
				(width 0.1)
				(type default)
			)
			(layer "F.Fab")
		)
		(fp_line
			(start 0.67945 -0.3048)
			(end 0.67945 0.3048)
			(stroke
				(width 0.1)
				(type default)
			)
			(layer "F.Fab")
		)
		(fp_line
			(start 0.12065 -0.3048)
			(end 0.67945 -0.3048)
			(stroke
				(width 0.1)
				(type default)
			)
			(layer "F.Fab")
		)
		(fp_line
			(start 0.12065 -0.2794)
			(end 0.12065 -0.3048)
			(stroke
				(width 0.1)
				(type default)
			)
			(layer "F.Fab")
		)
		(fp_line
			(start -0.12065 -0.2794)
			(end 0.12065 -0.2794)
			(stroke
				(width 0.1)
				(type default)
			)
			(layer "F.Fab")
		)
		(fp_line
			(start 0.120396 0.2794)
			(end -0.12065 0.2794)
			(stroke
				(width 0.1)
				(type default)
			)
			(layer "F.Fab")
		)
		(fp_line
			(start -0.12065 0.2794)
			(end -0.12065 0.3048)
			(stroke
				(width 0.1)
				(type default)
			)
			(layer "F.Fab")
		)
		(fp_line
			(start 0.67945 0.3048)
			(end 0.120396 0.3048)
			(stroke
				(width 0.1)
				(type default)
			)
			(layer "F.Fab")
		)
		(fp_line
			(start 0.120396 0.3048)
			(end 0.120396 0.2794)
			(stroke
				(width 0.1)
				(type default)
			)
			(layer "F.Fab")
		)
		(fp_line
			(start -0.12065 0.3048)
			(end -0.67945 0.3048)
			(stroke
				(width 0.1)
				(type default)
			)
			(layer "F.Fab")
		)
		(fp_line
			(start -0.67945 0.3048)
			(end -0.67945 -0.305054)
			(stroke
				(width 0.1)
				(type default)
			)
			(layer "F.Fab")
		)
		(pad "1" smd circle
			(at -0.40005 0 90)
			(size 0 0)
			(layers "F.Cu" "F.Mask" "F.Paste")
			(net "P12V_NIC5_CO_FLTB")
		)
		(pad "2" smd circle
			(at 0.40005 0 90)
			(size 0 0)
			(layers "F.Cu" "F.Mask" "F.Paste")
			(net "P3V3_AUX")
		)
	)
	(footprint ""
		(layer "F.Cu")
		(at 400.364452 -166.302944 90)
		(property "Reference" "R352"
			(at 0 0 90)
			(layer "F.SilkS")
			(hide yes)
			(effects
				(font
					(size 1.27 1.27)
				)
			)
		)
		(property "Value" ""
			(at 0 0 90)
			(layer "F.Fab")
			(effects
				(font
					(size 1.27 1.27)
				)
			)
		)
		(duplicate_pad_numbers_are_jumpers no)
		(fp_line
			(start 0.7874 -0.4064)
			(end 0.7874 0.4064)
			(stroke
				(width 0.1524)
				(type default)
			)
			(layer "F.SilkS")
		)
		(fp_line
			(start -0.7874 -0.4064)
			(end 0.7874 -0.4064)
			(stroke
				(width 0.1524)
				(type default)
			)
			(layer "F.SilkS")
		)
		(fp_line
			(start 0.7874 0.4064)
			(end -0.7874 0.4064)
			(stroke
				(width 0.1524)
				(type default)
			)
			(layer "F.SilkS")
		)
		(fp_line
			(start -0.7874 0.4064)
			(end -0.7874 -0.4064)
			(stroke
				(width 0.1524)
				(type default)
			)
			(layer "F.SilkS")
		)
		(fp_line
			(start -0.12065 -0.305054)
			(end -0.12065 -0.2794)
			(stroke
				(width 0.1)
				(type default)
			)
			(layer "F.Fab")
		)
		(fp_line
			(start -0.67945 -0.305054)
			(end -0.12065 -0.305054)
			(stroke
				(width 0.1)
				(type default)
			)
			(layer "F.Fab")
		)
		(fp_line
			(start 0.67945 -0.3048)
			(end 0.67945 0.3048)
			(stroke
				(width 0.1)
				(type default)
			)
			(layer "F.Fab")
		)
		(fp_line
			(start 0.12065 -0.3048)
			(end 0.67945 -0.3048)
			(stroke
				(width 0.1)
				(type default)
			)
			(layer "F.Fab")
		)
		(fp_line
			(start 0.12065 -0.2794)
			(end 0.12065 -0.3048)
			(stroke
				(width 0.1)
				(type default)
			)
			(layer "F.Fab")
		)
		(fp_line
			(start -0.12065 -0.2794)
			(end 0.12065 -0.2794)
			(stroke
				(width 0.1)
				(type default)
			)
			(layer "F.Fab")
		)
		(fp_line
			(start 0.120396 0.2794)
			(end -0.12065 0.2794)
			(stroke
				(width 0.1)
				(type default)
			)
			(layer "F.Fab")
		)
		(fp_line
			(start -0.12065 0.2794)
			(end -0.12065 0.3048)
			(stroke
				(width 0.1)
				(type default)
			)
			(layer "F.Fab")
		)
		(fp_line
			(start 0.67945 0.3048)
			(end 0.120396 0.3048)
			(stroke
				(width 0.1)
				(type default)
			)
			(layer "F.Fab")
		)
		(fp_line
			(start 0.120396 0.3048)
			(end 0.120396 0.2794)
			(stroke
				(width 0.1)
				(type default)
			)
			(layer "F.Fab")
		)
		(fp_line
			(start -0.12065 0.3048)
			(end -0.67945 0.3048)
			(stroke
				(width 0.1)
				(type default)
			)
			(layer "F.Fab")
		)
		(fp_line
			(start -0.67945 0.3048)
			(end -0.67945 -0.305054)
			(stroke
				(width 0.1)
				(type default)
			)
			(layer "F.Fab")
		)
		(pad "1" smd circle
			(at -0.40005 0 90)
			(size 0 0)
			(layers "F.Cu" "F.Mask" "F.Paste")
			(net "RST_NIC6_PERST1_R_N")
		)
		(pad "2" smd circle
			(at 0.40005 0 90)
			(size 0 0)
			(layers "F.Cu" "F.Mask" "F.Paste")
			(net "RST_HP_NIC6_BUF_N")
		)
	)
	(footprint ""
		(layer "F.Cu")
		(at 121.441972 -120.087136)
		(property "Reference" "PR6853"
			(at 0 0 0)
			(layer "F.SilkS")
			(hide yes)
			(effects
				(font
					(size 1.27 1.27)
				)
			)
		)
		(property "Value" ""
			(at 0 0 0)
			(layer "F.Fab")
			(effects
				(font
					(size 1.27 1.27)
				)
			)
		)
		(duplicate_pad_numbers_are_jumpers no)
		(fp_line
			(start -0.7874 -0.4064)
			(end 0.7874 -0.4064)
			(stroke
				(width 0.1524)
				(type default)
			)
			(layer "F.SilkS")
		)
		(fp_line
			(start -0.7874 0.4064)
			(end -0.7874 -0.4064)
			(stroke
				(width 0.1524)
				(type default)
			)
			(layer "F.SilkS")
		)
		(fp_line
			(start 0.7874 -0.4064)
			(end 0.7874 0.4064)
			(stroke
				(width 0.1524)
				(type default)
			)
			(layer "F.SilkS")
		)
		(fp_line
			(start 0.7874 0.4064)
			(end -0.7874 0.4064)
			(stroke
				(width 0.1524)
				(type default)
			)
			(layer "F.SilkS")
		)
		(fp_line
			(start -0.67945 -0.305054)
			(end -0.12065 -0.305054)
			(stroke
				(width 0.1)
				(type default)
			)
			(layer "F.Fab")
		)
		(fp_line
			(start -0.67945 0.3048)
			(end -0.67945 -0.305054)
			(stroke
				(width 0.1)
				(type default)
			)
			(layer "F.Fab")
		)
		(fp_line
			(start -0.12065 -0.305054)
			(end -0.12065 -0.2794)
			(stroke
				(width 0.1)
				(type default)
			)
			(layer "F.Fab")
		)
		(fp_line
			(start -0.12065 -0.2794)
			(end 0.12065 -0.2794)
			(stroke
				(width 0.1)
				(type default)
			)
			(layer "F.Fab")
		)
		(fp_line
			(start -0.12065 0.2794)
			(end -0.12065 0.3048)
			(stroke
				(width 0.1)
				(type default)
			)
			(layer "F.Fab")
		)
		(fp_line
			(start -0.12065 0.3048)
			(end -0.67945 0.3048)
			(stroke
				(width 0.1)
				(type default)
			)
			(layer "F.Fab")
		)
		(fp_line
			(start 0.120396 0.2794)
			(end -0.12065 0.2794)
			(stroke
				(width 0.1)
				(type default)
			)
			(layer "F.Fab")
		)
		(fp_line
			(start 0.120396 0.3048)
			(end 0.120396 0.2794)
			(stroke
				(width 0.1)
				(type default)
			)
			(layer "F.Fab")
		)
		(fp_line
			(start 0.12065 -0.3048)
			(end 0.67945 -0.3048)
			(stroke
				(width 0.1)
				(type default)
			)
			(layer "F.Fab")
		)
		(fp_line
			(start 0.12065 -0.2794)
			(end 0.12065 -0.3048)
			(stroke
				(width 0.1)
				(type default)
			)
			(layer "F.Fab")
		)
		(fp_line
			(start 0.67945 -0.3048)
			(end 0.67945 0.3048)
			(stroke
				(width 0.1)
				(type default)
			)
			(layer "F.Fab")
		)
		(fp_line
			(start 0.67945 0.3048)
			(end 0.120396 0.3048)
			(stroke
				(width 0.1)
				(type default)
			)
			(layer "F.Fab")
		)
		(pad "1" smd circle
			(at -0.40005 0)
			(size 0 0)
			(layers "F.Cu" "F.Mask" "F.Paste")
			(net "P3V3_CO_MODE")
		)
		(pad "2" smd circle
			(at 0.40005 0)
			(size 0 0)
			(layers "F.Cu" "F.Mask" "F.Paste")
			(net "GND")
		)
	)
	(footprint ""
		(layer "F.Cu")
		(at 239.16894 -369.8113 90)
		(property "Reference" "PQ6601"
			(at -8.173466 -2.022094 0)
			(unlocked yes)
			(layer "F.SilkS")
			(effects
				(font
					(size 0.7874 0.5842)
					(thickness 0.1524)
				)
				(justify left)
			)
		)
		(property "Value" ""
			(at 0 0 90)
			(layer "F.Fab")
			(effects
				(font
					(size 1.27 1.27)
				)
			)
		)
		(duplicate_pad_numbers_are_jumpers no)
		(fp_line
			(start 2.350008 -2.649982)
			(end 2.350008 -2.4892)
			(stroke
				(width 0.1524)
				(type default)
			)
			(layer "F.SilkS")
		)
		(fp_line
			(start -2.350008 -2.649982)
			(end 2.350008 -2.649982)
			(stroke
				(width 0.1524)
				(type default)
			)
			(layer "F.SilkS")
		)
		(fp_line
			(start -2.350008 -2.4384)
			(end -2.350008 -2.649982)
			(stroke
				(width 0.1524)
				(type default)
			)
			(layer "F.SilkS")
		)
		(fp_line
			(start 2.350008 2.4892)
			(end 2.350008 2.649982)
			(stroke
				(width 0.1524)
				(type default)
			)
			(layer "F.SilkS")
		)
		(fp_line
			(start 2.350008 2.649982)
			(end -2.350008 2.649982)
			(stroke
				(width 0.1524)
				(type default)
			)
			(layer "F.SilkS")
		)
		(fp_line
			(start -2.350008 2.649982)
			(end -2.350008 2.413)
			(stroke
				(width 0.1524)
				(type default)
			)
			(layer "F.SilkS")
		)
		(fp_poly
			(pts
				(xy -4.69519 -2.031238) (xy -5.73659 -2.450338) (xy -5.73659 -1.650238)
			)
			(stroke
				(width 0)
				(type default)
			)
			(fill yes)
			(layer "F.SilkS")
		)
		(fp_line
			(start 2.350008 -2.649982)
			(end 2.350008 2.649982)
			(stroke
				(width 0.1)
				(type default)
			)
			(layer "F.Fab")
		)
		(fp_line
			(start -2.350008 -2.649982)
			(end 2.350008 -2.649982)
			(stroke
				(width 0.1)
				(type default)
			)
			(layer "F.Fab")
		)
		(fp_line
			(start 2.350008 2.649982)
			(end -2.350008 2.649982)
			(stroke
				(width 0.1)
				(type default)
			)
			(layer "F.Fab")
		)
		(fp_line
			(start -2.350008 2.649982)
			(end -2.350008 -2.649982)
			(stroke
				(width 0.1)
				(type default)
			)
			(layer "F.Fab")
		)
		(fp_poly
			(pts
				(xy -3.717544 -1.905) (xy -4.758944 -2.3241) (xy -4.758944 -1.524)
			)
			(stroke
				(width 0)
				(type default)
			)
			(fill yes)
			(layer "F.Fab")
		)
		(pad "1" smd rect
			(at -2.999994 -1.905)
			(size 0.7112 1.1684)
			(layers "F.Cu" "F.Mask" "F.Paste")
			(net "P12V_AUX")
		)
		(pad "2" smd rect
			(at -2.999994 -0.635)
			(size 0.7112 1.1684)
			(layers "F.Cu" "F.Mask" "F.Paste")
			(net "P12V_AUX")
		)
		(pad "3" smd rect
			(at -2.999994 0.635)
			(size 0.7112 1.1684)
			(layers "F.Cu" "F.Mask" "F.Paste")
			(net "P12V_AUX")
		)
		(pad "4" smd rect
			(at -2.999994 1.905)
			(size 0.7112 1.1684)
			(layers "F.Cu" "F.Mask" "F.Paste")
			(net "HS_GATE1_R_1")
		)
		(pad "5" smd circle
			(at 0.925068 0)
			(size 0 0)
			(layers "F.Cu" "F.Mask" "F.Paste")
			(net "P12V_STBY_R1")
		)
		(zone
			(layer "F.Cu")
			(hatch none 0.5)
			(connect_pads
				(clearance 0)
			)
			(min_thickness 0.25)
			(keepout
				(tracks not_allowed)
				(vias allowed)
				(pads allowed)
				(copperpour not_allowed)
				(footprints allowed)
			)
			(placement
				(enabled no)
				(sheetname "")
			)
			(fill
				(thermal_gap 0.5)
				(thermal_bridge_width 0.5)
				(island_removal_mode 0)
			)
			(polygon
				(pts
					(xy 237.00994 -368.3635) (xy 241.32794 -368.3635) (xy 241.81054 -368.3635) (xy 241.81054 -367.4618)
					(xy 236.52734 -367.4618) (xy 236.52734 -368.3635)
				)
			)
		)
	)
	(footprint ""
		(layer "F.Cu")
		(at 321.804284 -356.244906 90)
		(property "Reference" "C539"
			(at 0 0 90)
			(layer "F.SilkS")
			(hide yes)
			(effects
				(font
					(size 1.27 1.27)
				)
			)
		)
		(property "Value" ""
			(at 0 0 90)
			(layer "F.Fab")
			(effects
				(font
					(size 1.27 1.27)
				)
			)
		)
		(duplicate_pad_numbers_are_jumpers no)
		(fp_line
			(start 0.299974 -0.150114)
			(end 0.299974 0.150114)
			(stroke
				(width 0.1)
				(type default)
			)
			(layer "F.Fab")
		)
		(fp_line
			(start -0.299974 -0.150114)
			(end 0.299974 -0.150114)
			(stroke
				(width 0.1)
				(type default)
			)
			(layer "F.Fab")
		)
		(fp_line
			(start 0.299974 0.150114)
			(end -0.299974 0.150114)
			(stroke
				(width 0.1)
				(type default)
			)
			(layer "F.Fab")
		)
		(fp_line
			(start -0.299974 0.150114)
			(end -0.299974 -0.150114)
			(stroke
				(width 0.1)
				(type default)
			)
			(layer "F.Fab")
		)
		(pad "1" smd rect
			(at -0.2667 0 90)
			(size 0.3048 0.381)
			(layers "F.Cu" "F.Mask" "F.Paste")
			(net "P5E_PEX2_STN5_TX_DP<85>")
		)
		(pad "2" smd rect
			(at 0.2667 0 90)
			(size 0.3048 0.381)
			(layers "F.Cu" "F.Mask" "F.Paste")
			(net "P5E_PEX2_STN5_TX_C_DP<85>")
		)
	)
	(footprint ""
		(layer "F.Cu")
		(at 337.566 -201.168 -90)
		(property "Reference" "R4128"
			(at 0 0 270)
			(layer "F.SilkS")
			(hide yes)
			(effects
				(font
					(size 1.27 1.27)
				)
			)
		)
		(property "Value" ""
			(at 0 0 270)
			(layer "F.Fab")
			(effects
				(font
					(size 1.27 1.27)
				)
			)
		)
		(duplicate_pad_numbers_are_jumpers no)
		(fp_line
			(start -0.7874 0.4064)
			(end -0.7874 -0.4064)
			(stroke
				(width 0.1524)
				(type default)
			)
			(layer "F.SilkS")
		)
		(fp_line
			(start 0.7874 0.4064)
			(end -0.7874 0.4064)
			(stroke
				(width 0.1524)
				(type default)
			)
			(layer "F.SilkS")
		)
		(fp_line
			(start -0.7874 -0.4064)
			(end 0.7874 -0.4064)
			(stroke
				(width 0.1524)
				(type default)
			)
			(layer "F.SilkS")
		)
		(fp_line
			(start 0.7874 -0.4064)
			(end 0.7874 0.4064)
			(stroke
				(width 0.1524)
				(type default)
			)
			(layer "F.SilkS")
		)
		(fp_line
			(start -0.67945 0.3048)
			(end -0.67945 -0.305054)
			(stroke
				(width 0.1)
				(type default)
			)
			(layer "F.Fab")
		)
		(fp_line
			(start -0.12065 0.3048)
			(end -0.67945 0.3048)
			(stroke
				(width 0.1)
				(type default)
			)
			(layer "F.Fab")
		)
		(fp_line
			(start 0.120396 0.3048)
			(end 0.120396 0.2794)
			(stroke
				(width 0.1)
				(type default)
			)
			(layer "F.Fab")
		)
		(fp_line
			(start 0.67945 0.3048)
			(end 0.120396 0.3048)
			(stroke
				(width 0.1)
				(type default)
			)
			(layer "F.Fab")
		)
		(fp_line
			(start -0.12065 0.2794)
			(end -0.12065 0.3048)
			(stroke
				(width 0.1)
				(type default)
			)
			(layer "F.Fab")
		)
		(fp_line
			(start 0.120396 0.2794)
			(end -0.12065 0.2794)
			(stroke
				(width 0.1)
				(type default)
			)
			(layer "F.Fab")
		)
		(fp_line
			(start -0.12065 -0.2794)
			(end 0.12065 -0.2794)
			(stroke
				(width 0.1)
				(type default)
			)
			(layer "F.Fab")
		)
		(fp_line
			(start 0.12065 -0.2794)
			(end 0.12065 -0.3048)
			(stroke
				(width 0.1)
				(type default)
			)
			(layer "F.Fab")
		)
		(fp_line
			(start 0.12065 -0.3048)
			(end 0.67945 -0.3048)
			(stroke
				(width 0.1)
				(type default)
			)
			(layer "F.Fab")
		)
		(fp_line
			(start 0.67945 -0.3048)
			(end 0.67945 0.3048)
			(stroke
				(width 0.1)
				(type default)
			)
			(layer "F.Fab")
		)
		(fp_line
			(start -0.67945 -0.305054)
			(end -0.12065 -0.305054)
			(stroke
				(width 0.1)
				(type default)
			)
			(layer "F.Fab")
		)
		(fp_line
			(start -0.12065 -0.305054)
			(end -0.12065 -0.2794)
			(stroke
				(width 0.1)
				(type default)
			)
			(layer "F.Fab")
		)
		(pad "1" smd circle
			(at -0.40005 0 270)
			(size 0 0)
			(layers "F.Cu" "F.Mask" "F.Paste")
			(net "SSD11_PWRDIS")
		)
		(pad "2" smd circle
			(at 0.40005 0 270)
			(size 0 0)
			(layers "F.Cu" "F.Mask" "F.Paste")
			(net "SSD11_PWRDIS_R")
		)
	)
	(footprint ""
		(layer "F.Cu")
		(at 100.75672 -10.545572 90)
		(property "Reference" "R1649"
			(at 0 0 90)
			(layer "F.SilkS")
			(hide yes)
			(effects
				(font
					(size 1.27 1.27)
				)
			)
		)
		(property "Value" ""
			(at 0 0 90)
			(layer "F.Fab")
			(effects
				(font
					(size 1.27 1.27)
				)
			)
		)
		(duplicate_pad_numbers_are_jumpers no)
		(fp_line
			(start 0.7874 -0.4064)
			(end 0.7874 0.4064)
			(stroke
				(width 0.1524)
				(type default)
			)
			(layer "F.SilkS")
		)
		(fp_line
			(start -0.7874 -0.4064)
			(end 0.7874 -0.4064)
			(stroke
				(width 0.1524)
				(type default)
			)
			(layer "F.SilkS")
		)
		(fp_line
			(start 0.7874 0.4064)
			(end -0.7874 0.4064)
			(stroke
				(width 0.1524)
				(type default)
			)
			(layer "F.SilkS")
		)
		(fp_line
			(start -0.7874 0.4064)
			(end -0.7874 -0.4064)
			(stroke
				(width 0.1524)
				(type default)
			)
			(layer "F.SilkS")
		)
		(fp_line
			(start -0.12065 -0.305054)
			(end -0.12065 -0.2794)
			(stroke
				(width 0.1)
				(type default)
			)
			(layer "F.Fab")
		)
		(fp_line
			(start -0.67945 -0.305054)
			(end -0.12065 -0.305054)
			(stroke
				(width 0.1)
				(type default)
			)
			(layer "F.Fab")
		)
		(fp_line
			(start 0.67945 -0.3048)
			(end 0.67945 0.3048)
			(stroke
				(width 0.1)
				(type default)
			)
			(layer "F.Fab")
		)
		(fp_line
			(start 0.12065 -0.3048)
			(end 0.67945 -0.3048)
			(stroke
				(width 0.1)
				(type default)
			)
			(layer "F.Fab")
		)
		(fp_line
			(start 0.12065 -0.2794)
			(end 0.12065 -0.3048)
			(stroke
				(width 0.1)
				(type default)
			)
			(layer "F.Fab")
		)
		(fp_line
			(start -0.12065 -0.2794)
			(end 0.12065 -0.2794)
			(stroke
				(width 0.1)
				(type default)
			)
			(layer "F.Fab")
		)
		(fp_line
			(start 0.120396 0.2794)
			(end -0.12065 0.2794)
			(stroke
				(width 0.1)
				(type default)
			)
			(layer "F.Fab")
		)
		(fp_line
			(start -0.12065 0.2794)
			(end -0.12065 0.3048)
			(stroke
				(width 0.1)
				(type default)
			)
			(layer "F.Fab")
		)
		(fp_line
			(start 0.67945 0.3048)
			(end 0.120396 0.3048)
			(stroke
				(width 0.1)
				(type default)
			)
			(layer "F.Fab")
		)
		(fp_line
			(start 0.120396 0.3048)
			(end 0.120396 0.2794)
			(stroke
				(width 0.1)
				(type default)
			)
			(layer "F.Fab")
		)
		(fp_line
			(start -0.12065 0.3048)
			(end -0.67945 0.3048)
			(stroke
				(width 0.1)
				(type default)
			)
			(layer "F.Fab")
		)
		(fp_line
			(start -0.67945 0.3048)
			(end -0.67945 -0.305054)
			(stroke
				(width 0.1)
				(type default)
			)
			(layer "F.Fab")
		)
		(pad "1" smd circle
			(at -0.40005 0 90)
			(size 0 0)
			(layers "F.Cu" "F.Mask" "F.Paste")
			(net "P3V3_SSD3")
		)
		(pad "2" smd circle
			(at 0.40005 0 90)
			(size 0 0)
			(layers "F.Cu" "F.Mask" "F.Paste")
			(net "SMB_ISO_SSD3_SCL")
		)
	)
	(footprint ""
		(layer "F.Cu")
		(at 106.283252 -212.0392)
		(property "Reference" "PC283"
			(at 0 0 0)
			(layer "F.SilkS")
			(hide yes)
			(effects
				(font
					(size 1.27 1.27)
				)
			)
		)
		(property "Value" ""
			(at 0 0 0)
			(layer "F.Fab")
			(effects
				(font
					(size 1.27 1.27)
				)
			)
		)
		(duplicate_pad_numbers_are_jumpers no)
		(fp_line
			(start -0.7874 -0.4064)
			(end 0.7874 -0.4064)
			(stroke
				(width 0.1524)
				(type default)
			)
			(layer "F.SilkS")
		)
		(fp_line
			(start -0.7874 0.4064)
			(end -0.7874 -0.4064)
			(stroke
				(width 0.1524)
				(type default)
			)
			(layer "F.SilkS")
		)
		(fp_line
			(start 0.7874 -0.4064)
			(end 0.7874 0.4064)
			(stroke
				(width 0.1524)
				(type default)
			)
			(layer "F.SilkS")
		)
		(fp_line
			(start 0.7874 0.4064)
			(end -0.7874 0.4064)
			(stroke
				(width 0.1524)
				(type default)
			)
			(layer "F.SilkS")
		)
		(fp_line
			(start -0.67945 -0.305054)
			(end -0.12065 -0.305054)
			(stroke
				(width 0.1)
				(type default)
			)
			(layer "F.Fab")
		)
		(fp_line
			(start -0.67945 0.3048)
			(end -0.67945 -0.305054)
			(stroke
				(width 0.1)
				(type default)
			)
			(layer "F.Fab")
		)
		(fp_line
			(start -0.12065 -0.305054)
			(end -0.12065 -0.2794)
			(stroke
				(width 0.1)
				(type default)
			)
			(layer "F.Fab")
		)
		(fp_line
			(start -0.12065 -0.2794)
			(end 0.12065 -0.2794)
			(stroke
				(width 0.1)
				(type default)
			)
			(layer "F.Fab")
		)
		(fp_line
			(start -0.12065 0.2794)
			(end -0.12065 0.3048)
			(stroke
				(width 0.1)
				(type default)
			)
			(layer "F.Fab")
		)
		(fp_line
			(start -0.12065 0.3048)
			(end -0.67945 0.3048)
			(stroke
				(width 0.1)
				(type default)
			)
			(layer "F.Fab")
		)
		(fp_line
			(start 0.120396 0.2794)
			(end -0.12065 0.2794)
			(stroke
				(width 0.1)
				(type default)
			)
			(layer "F.Fab")
		)
		(fp_line
			(start 0.120396 0.3048)
			(end 0.120396 0.2794)
			(stroke
				(width 0.1)
				(type default)
			)
			(layer "F.Fab")
		)
		(fp_line
			(start 0.12065 -0.3048)
			(end 0.67945 -0.3048)
			(stroke
				(width 0.1)
				(type default)
			)
			(layer "F.Fab")
		)
		(fp_line
			(start 0.12065 -0.2794)
			(end 0.12065 -0.3048)
			(stroke
				(width 0.1)
				(type default)
			)
			(layer "F.Fab")
		)
		(fp_line
			(start 0.67945 -0.3048)
			(end 0.67945 0.3048)
			(stroke
				(width 0.1)
				(type default)
			)
			(layer "F.Fab")
		)
		(fp_line
			(start 0.67945 0.3048)
			(end 0.120396 0.3048)
			(stroke
				(width 0.1)
				(type default)
			)
			(layer "F.Fab")
		)
		(pad "1" smd circle
			(at -0.40005 0)
			(size 0 0)
			(layers "F.Cu" "F.Mask" "F.Paste")
			(net "P12V_AUX")
		)
		(pad "2" smd circle
			(at 0.40005 0)
			(size 0 0)
			(layers "F.Cu" "F.Mask" "F.Paste")
			(net "GND")
		)
	)
	(footprint ""
		(layer "F.Cu")
		(at 235.056172 -32.848042 -90)
		(property "Reference" "R6078"
			(at 0 0 270)
			(layer "F.SilkS")
			(hide yes)
			(effects
				(font
					(size 1.27 1.27)
				)
			)
		)
		(property "Value" ""
			(at 0 0 270)
			(layer "F.Fab")
			(effects
				(font
					(size 1.27 1.27)
				)
			)
		)
		(duplicate_pad_numbers_are_jumpers no)
		(fp_line
			(start -0.7874 0.4064)
			(end -0.7874 -0.4064)
			(stroke
				(width 0.1524)
				(type default)
			)
			(layer "F.SilkS")
		)
		(fp_line
			(start 0.7874 0.4064)
			(end -0.7874 0.4064)
			(stroke
				(width 0.1524)
				(type default)
			)
			(layer "F.SilkS")
		)
		(fp_line
			(start -0.7874 -0.4064)
			(end 0.7874 -0.4064)
			(stroke
				(width 0.1524)
				(type default)
			)
			(layer "F.SilkS")
		)
		(fp_line
			(start 0.7874 -0.4064)
			(end 0.7874 0.4064)
			(stroke
				(width 0.1524)
				(type default)
			)
			(layer "F.SilkS")
		)
		(fp_line
			(start -0.67945 0.3048)
			(end -0.67945 -0.305054)
			(stroke
				(width 0.1)
				(type default)
			)
			(layer "F.Fab")
		)
		(fp_line
			(start -0.12065 0.3048)
			(end -0.67945 0.3048)
			(stroke
				(width 0.1)
				(type default)
			)
			(layer "F.Fab")
		)
		(fp_line
			(start 0.120396 0.3048)
			(end 0.120396 0.2794)
			(stroke
				(width 0.1)
				(type default)
			)
			(layer "F.Fab")
		)
		(fp_line
			(start 0.67945 0.3048)
			(end 0.120396 0.3048)
			(stroke
				(width 0.1)
				(type default)
			)
			(layer "F.Fab")
		)
		(fp_line
			(start -0.12065 0.2794)
			(end -0.12065 0.3048)
			(stroke
				(width 0.1)
				(type default)
			)
			(layer "F.Fab")
		)
		(fp_line
			(start 0.120396 0.2794)
			(end -0.12065 0.2794)
			(stroke
				(width 0.1)
				(type default)
			)
			(layer "F.Fab")
		)
		(fp_line
			(start -0.12065 -0.2794)
			(end 0.12065 -0.2794)
			(stroke
				(width 0.1)
				(type default)
			)
			(layer "F.Fab")
		)
		(fp_line
			(start 0.12065 -0.2794)
			(end 0.12065 -0.3048)
			(stroke
				(width 0.1)
				(type default)
			)
			(layer "F.Fab")
		)
		(fp_line
			(start 0.12065 -0.3048)
			(end 0.67945 -0.3048)
			(stroke
				(width 0.1)
				(type default)
			)
			(layer "F.Fab")
		)
		(fp_line
			(start 0.67945 -0.3048)
			(end 0.67945 0.3048)
			(stroke
				(width 0.1)
				(type default)
			)
			(layer "F.Fab")
		)
		(fp_line
			(start -0.67945 -0.305054)
			(end -0.12065 -0.305054)
			(stroke
				(width 0.1)
				(type default)
			)
			(layer "F.Fab")
		)
		(fp_line
			(start -0.12065 -0.305054)
			(end -0.12065 -0.2794)
			(stroke
				(width 0.1)
				(type default)
			)
			(layer "F.Fab")
		)
		(pad "1" smd circle
			(at -0.40005 0 270)
			(size 0 0)
			(layers "F.Cu" "F.Mask" "F.Paste")
			(net "SSD8_AUX_P3V3_EN_R")
		)
		(pad "2" smd circle
			(at 0.40005 0 270)
			(size 0 0)
			(layers "F.Cu" "F.Mask" "F.Paste")
			(net "P3V3_SSD8_CO_EN")
		)
	)
	(footprint ""
		(layer "F.Cu")
		(at 479.076512 -527.283426)
		(property "Reference" "J58_12"
			(at -0.5842 -1.31953 0)
			(unlocked yes)
			(layer "B.SilkS")
			(effects
				(font
					(size 0.7874 0.5842)
					(thickness 0.1524)
				)
				(justify left mirror)
			)
		)
		(property "Value" ""
			(at 0 0 0)
			(layer "F.Fab")
			(effects
				(font
					(size 1.27 1.27)
				)
			)
		)
		(duplicate_pad_numbers_are_jumpers no)
		(pad "1" thru_hole circle
			(at 0 0)
			(size 0.4572 0.4572)
			(drill 0.2032)
			(layers "*.Cu" "*.Mask")
			(remove_unused_layers no)
			(net "Net_617")
			(clearance 0.127)
			(thermal_gap 0.127)
			(padstack
				(mode front_inner_back)
				(layer "Inner"
					(shape circle)
					(size 0.4572 0.4572)
					(clearance 0.127)
				)
				(layer "B.Cu"
					(shape circle)
					(size 0.508 0.508)
					(clearance 0.1016)
				)
			)
		)
	)
	(footprint ""
		(layer "F.Cu")
		(at 208.092548 -116.922804)
		(property "Reference" "PC793"
			(at 0 0 0)
			(layer "F.SilkS")
			(hide yes)
			(effects
				(font
					(size 1.27 1.27)
				)
			)
		)
		(property "Value" ""
			(at 0 0 0)
			(layer "F.Fab")
			(effects
				(font
					(size 1.27 1.27)
				)
			)
		)
		(duplicate_pad_numbers_are_jumpers no)
		(fp_line
			(start -1.524 -0.762)
			(end 1.524 -0.762)
			(stroke
				(width 0.1524)
				(type default)
			)
			(layer "F.SilkS")
		)
		(fp_line
			(start -1.524 0.762)
			(end -1.524 -0.762)
			(stroke
				(width 0.1524)
				(type default)
			)
			(layer "F.SilkS")
		)
		(fp_line
			(start 1.524 -0.762)
			(end 1.524 0.762)
			(stroke
				(width 0.1524)
				(type default)
			)
			(layer "F.SilkS")
		)
		(fp_line
			(start 1.524 0.762)
			(end -1.524 0.762)
			(stroke
				(width 0.1524)
				(type default)
			)
			(layer "F.SilkS")
		)
		(fp_line
			(start -1.1049 -0.724916)
			(end -1.1049 0.724916)
			(stroke
				(width 0.1)
				(type default)
			)
			(layer "F.Fab")
		)
		(fp_line
			(start -1.1049 0.724916)
			(end 1.1049 0.724916)
			(stroke
				(width 0.1)
				(type default)
			)
			(layer "F.Fab")
		)
		(fp_line
			(start 1.1049 -0.724916)
			(end -1.1049 -0.724916)
			(stroke
				(width 0.1)
				(type default)
			)
			(layer "F.Fab")
		)
		(fp_line
			(start 1.1049 0.724916)
			(end 1.1049 -0.724916)
			(stroke
				(width 0.1)
				(type default)
			)
			(layer "F.Fab")
		)
		(pad "1" smd rect
			(at -0.889 0 180)
			(size 1.016 1.27)
			(layers "F.Cu" "F.Mask" "F.Paste")
			(net "P3V3_NIC3")
		)
		(pad "2" smd rect
			(at 0.889 0 180)
			(size 1.016 1.27)
			(layers "F.Cu" "F.Mask" "F.Paste")
			(net "GND")
		)
	)
	(footprint ""
		(layer "F.Cu")
		(at 444.118238 -95.31477 90)
		(property "Reference" "R860"
			(at 0 0 90)
			(layer "F.SilkS")
			(hide yes)
			(effects
				(font
					(size 1.27 1.27)
				)
			)
		)
		(property "Value" ""
			(at 0 0 90)
			(layer "F.Fab")
			(effects
				(font
					(size 1.27 1.27)
				)
			)
		)
		(duplicate_pad_numbers_are_jumpers no)
		(fp_line
			(start 0.7874 -0.4064)
			(end 0.7874 0.4064)
			(stroke
				(width 0.1524)
				(type default)
			)
			(layer "F.SilkS")
		)
		(fp_line
			(start -0.7874 -0.4064)
			(end 0.7874 -0.4064)
			(stroke
				(width 0.1524)
				(type default)
			)
			(layer "F.SilkS")
		)
		(fp_line
			(start 0.7874 0.4064)
			(end -0.7874 0.4064)
			(stroke
				(width 0.1524)
				(type default)
			)
			(layer "F.SilkS")
		)
		(fp_line
			(start -0.7874 0.4064)
			(end -0.7874 -0.4064)
			(stroke
				(width 0.1524)
				(type default)
			)
			(layer "F.SilkS")
		)
		(fp_line
			(start -0.12065 -0.305054)
			(end -0.12065 -0.2794)
			(stroke
				(width 0.1)
				(type default)
			)
			(layer "F.Fab")
		)
		(fp_line
			(start -0.67945 -0.305054)
			(end -0.12065 -0.305054)
			(stroke
				(width 0.1)
				(type default)
			)
			(layer "F.Fab")
		)
		(fp_line
			(start 0.67945 -0.3048)
			(end 0.67945 0.3048)
			(stroke
				(width 0.1)
				(type default)
			)
			(layer "F.Fab")
		)
		(fp_line
			(start 0.12065 -0.3048)
			(end 0.67945 -0.3048)
			(stroke
				(width 0.1)
				(type default)
			)
			(layer "F.Fab")
		)
		(fp_line
			(start 0.12065 -0.2794)
			(end 0.12065 -0.3048)
			(stroke
				(width 0.1)
				(type default)
			)
			(layer "F.Fab")
		)
		(fp_line
			(start -0.12065 -0.2794)
			(end 0.12065 -0.2794)
			(stroke
				(width 0.1)
				(type default)
			)
			(layer "F.Fab")
		)
		(fp_line
			(start 0.120396 0.2794)
			(end -0.12065 0.2794)
			(stroke
				(width 0.1)
				(type default)
			)
			(layer "F.Fab")
		)
		(fp_line
			(start -0.12065 0.2794)
			(end -0.12065 0.3048)
			(stroke
				(width 0.1)
				(type default)
			)
			(layer "F.Fab")
		)
		(fp_line
			(start 0.67945 0.3048)
			(end 0.120396 0.3048)
			(stroke
				(width 0.1)
				(type default)
			)
			(layer "F.Fab")
		)
		(fp_line
			(start 0.120396 0.3048)
			(end 0.120396 0.2794)
			(stroke
				(width 0.1)
				(type default)
			)
			(layer "F.Fab")
		)
		(fp_line
			(start -0.12065 0.3048)
			(end -0.67945 0.3048)
			(stroke
				(width 0.1)
				(type default)
			)
			(layer "F.Fab")
		)
		(fp_line
			(start -0.67945 0.3048)
			(end -0.67945 -0.305054)
			(stroke
				(width 0.1)
				(type default)
			)
			(layer "F.Fab")
		)
		(pad "1" smd circle
			(at -0.40005 0 90)
			(size 0 0)
			(layers "F.Cu" "F.Mask" "F.Paste")
			(net "P3V3_AUX")
		)
		(pad "2" smd circle
			(at 0.40005 0 90)
			(size 0 0)
			(layers "F.Cu" "F.Mask" "F.Paste")
			(net "PWRGD_P12V_NIC7")
		)
	)
	(footprint ""
		(layer "F.Cu")
		(at 445.134238 -95.263716 -90)
		(property "Reference" "R4455"
			(at 0 0 270)
			(layer "F.SilkS")
			(hide yes)
			(effects
				(font
					(size 1.27 1.27)
				)
			)
		)
		(property "Value" ""
			(at 0 0 270)
			(layer "F.Fab")
			(effects
				(font
					(size 1.27 1.27)
				)
			)
		)
		(duplicate_pad_numbers_are_jumpers no)
		(fp_line
			(start -0.7874 0.4064)
			(end -0.7874 -0.4064)
			(stroke
				(width 0.1524)
				(type default)
			)
			(layer "F.SilkS")
		)
		(fp_line
			(start 0.7874 0.4064)
			(end -0.7874 0.4064)
			(stroke
				(width 0.1524)
				(type default)
			)
			(layer "F.SilkS")
		)
		(fp_line
			(start -0.7874 -0.4064)
			(end 0.7874 -0.4064)
			(stroke
				(width 0.1524)
				(type default)
			)
			(layer "F.SilkS")
		)
		(fp_line
			(start 0.7874 -0.4064)
			(end 0.7874 0.4064)
			(stroke
				(width 0.1524)
				(type default)
			)
			(layer "F.SilkS")
		)
		(fp_line
			(start -0.67945 0.3048)
			(end -0.67945 -0.305054)
			(stroke
				(width 0.1)
				(type default)
			)
			(layer "F.Fab")
		)
		(fp_line
			(start -0.12065 0.3048)
			(end -0.67945 0.3048)
			(stroke
				(width 0.1)
				(type default)
			)
			(layer "F.Fab")
		)
		(fp_line
			(start 0.120396 0.3048)
			(end 0.120396 0.2794)
			(stroke
				(width 0.1)
				(type default)
			)
			(layer "F.Fab")
		)
		(fp_line
			(start 0.67945 0.3048)
			(end 0.120396 0.3048)
			(stroke
				(width 0.1)
				(type default)
			)
			(layer "F.Fab")
		)
		(fp_line
			(start -0.12065 0.2794)
			(end -0.12065 0.3048)
			(stroke
				(width 0.1)
				(type default)
			)
			(layer "F.Fab")
		)
		(fp_line
			(start 0.120396 0.2794)
			(end -0.12065 0.2794)
			(stroke
				(width 0.1)
				(type default)
			)
			(layer "F.Fab")
		)
		(fp_line
			(start -0.12065 -0.2794)
			(end 0.12065 -0.2794)
			(stroke
				(width 0.1)
				(type default)
			)
			(layer "F.Fab")
		)
		(fp_line
			(start 0.12065 -0.2794)
			(end 0.12065 -0.3048)
			(stroke
				(width 0.1)
				(type default)
			)
			(layer "F.Fab")
		)
		(fp_line
			(start 0.12065 -0.3048)
			(end 0.67945 -0.3048)
			(stroke
				(width 0.1)
				(type default)
			)
			(layer "F.Fab")
		)
		(fp_line
			(start 0.67945 -0.3048)
			(end 0.67945 0.3048)
			(stroke
				(width 0.1)
				(type default)
			)
			(layer "F.Fab")
		)
		(fp_line
			(start -0.67945 -0.305054)
			(end -0.12065 -0.305054)
			(stroke
				(width 0.1)
				(type default)
			)
			(layer "F.Fab")
		)
		(fp_line
			(start -0.12065 -0.305054)
			(end -0.12065 -0.2794)
			(stroke
				(width 0.1)
				(type default)
			)
			(layer "F.Fab")
		)
		(pad "1" smd circle
			(at -0.40005 0 270)
			(size 0 0)
			(layers "F.Cu" "F.Mask" "F.Paste")
			(net "PWRGD_P12V_NIC7")
		)
		(pad "2" smd circle
			(at 0.40005 0 270)
			(size 0 0)
			(layers "F.Cu" "F.Mask" "F.Paste")
			(net "PWRGD_P12V_NIC7_R")
		)
	)
	(footprint ""
		(layer "F.Cu")
		(at 117.175026 -309.749952 -90)
		(property "Reference" "R6454"
			(at 0 0 270)
			(layer "F.SilkS")
			(hide yes)
			(effects
				(font
					(size 1.27 1.27)
				)
			)
		)
		(property "Value" ""
			(at 0 0 270)
			(layer "F.Fab")
			(effects
				(font
					(size 1.27 1.27)
				)
			)
		)
		(duplicate_pad_numbers_are_jumpers no)
		(fp_line
			(start -0.7874 0.4064)
			(end -0.7874 -0.4064)
			(stroke
				(width 0.1524)
				(type default)
			)
			(layer "F.SilkS")
		)
		(fp_line
			(start 0.7874 0.4064)
			(end -0.7874 0.4064)
			(stroke
				(width 0.1524)
				(type default)
			)
			(layer "F.SilkS")
		)
		(fp_line
			(start -0.7874 -0.4064)
			(end 0.7874 -0.4064)
			(stroke
				(width 0.1524)
				(type default)
			)
			(layer "F.SilkS")
		)
		(fp_line
			(start 0.7874 -0.4064)
			(end 0.7874 0.4064)
			(stroke
				(width 0.1524)
				(type default)
			)
			(layer "F.SilkS")
		)
		(fp_line
			(start -0.67945 0.3048)
			(end -0.67945 -0.305054)
			(stroke
				(width 0.1)
				(type default)
			)
			(layer "F.Fab")
		)
		(fp_line
			(start -0.12065 0.3048)
			(end -0.67945 0.3048)
			(stroke
				(width 0.1)
				(type default)
			)
			(layer "F.Fab")
		)
		(fp_line
			(start 0.120396 0.3048)
			(end 0.120396 0.2794)
			(stroke
				(width 0.1)
				(type default)
			)
			(layer "F.Fab")
		)
		(fp_line
			(start 0.67945 0.3048)
			(end 0.120396 0.3048)
			(stroke
				(width 0.1)
				(type default)
			)
			(layer "F.Fab")
		)
		(fp_line
			(start -0.12065 0.2794)
			(end -0.12065 0.3048)
			(stroke
				(width 0.1)
				(type default)
			)
			(layer "F.Fab")
		)
		(fp_line
			(start 0.120396 0.2794)
			(end -0.12065 0.2794)
			(stroke
				(width 0.1)
				(type default)
			)
			(layer "F.Fab")
		)
		(fp_line
			(start -0.12065 -0.2794)
			(end 0.12065 -0.2794)
			(stroke
				(width 0.1)
				(type default)
			)
			(layer "F.Fab")
		)
		(fp_line
			(start 0.12065 -0.2794)
			(end 0.12065 -0.3048)
			(stroke
				(width 0.1)
				(type default)
			)
			(layer "F.Fab")
		)
		(fp_line
			(start 0.12065 -0.3048)
			(end 0.67945 -0.3048)
			(stroke
				(width 0.1)
				(type default)
			)
			(layer "F.Fab")
		)
		(fp_line
			(start 0.67945 -0.3048)
			(end 0.67945 0.3048)
			(stroke
				(width 0.1)
				(type default)
			)
			(layer "F.Fab")
		)
		(fp_line
			(start -0.67945 -0.305054)
			(end -0.12065 -0.305054)
			(stroke
				(width 0.1)
				(type default)
			)
			(layer "F.Fab")
		)
		(fp_line
			(start -0.12065 -0.305054)
			(end -0.12065 -0.2794)
			(stroke
				(width 0.1)
				(type default)
			)
			(layer "F.Fab")
		)
		(pad "1" smd circle
			(at -0.40005 0 270)
			(size 0 0)
			(layers "F.Cu" "F.Mask" "F.Paste")
			(net "P0V8_SERDES_VDDA_PEX0")
		)
		(pad "2" smd circle
			(at 0.40005 0 270)
			(size 0 0)
			(layers "F.Cu" "F.Mask" "F.Paste")
			(net "P0V8_SERDES_VDDA_PEX0_C5")
		)
	)
	(footprint ""
		(layer "F.Cu")
		(at 56.271922 -362.556044 90)
		(property "Reference" "R6733"
			(at 0 0 90)
			(layer "F.SilkS")
			(hide yes)
			(effects
				(font
					(size 1.27 1.27)
				)
			)
		)
		(property "Value" ""
			(at 0 0 90)
			(layer "F.Fab")
			(effects
				(font
					(size 1.27 1.27)
				)
			)
		)
		(duplicate_pad_numbers_are_jumpers no)
		(fp_line
			(start 0.7874 -0.4064)
			(end 0.7874 0.4064)
			(stroke
				(width 0.1524)
				(type default)
			)
			(layer "F.SilkS")
		)
		(fp_line
			(start -0.7874 -0.4064)
			(end 0.037846 -0.4064)
			(stroke
				(width 0.1524)
				(type default)
			)
			(layer "F.SilkS")
		)
		(fp_line
			(start 0.7874 0.4064)
			(end -0.7874 0.4064)
			(stroke
				(width 0.1524)
				(type default)
			)
			(layer "F.SilkS")
		)
		(fp_line
			(start -0.12065 -0.305054)
			(end -0.12065 -0.2794)
			(stroke
				(width 0.1)
				(type default)
			)
			(layer "F.Fab")
		)
		(fp_line
			(start -0.67945 -0.305054)
			(end -0.12065 -0.305054)
			(stroke
				(width 0.1)
				(type default)
			)
			(layer "F.Fab")
		)
		(fp_line
			(start 0.67945 -0.3048)
			(end 0.67945 0.3048)
			(stroke
				(width 0.1)
				(type default)
			)
			(layer "F.Fab")
		)
		(fp_line
			(start 0.12065 -0.3048)
			(end 0.67945 -0.3048)
			(stroke
				(width 0.1)
				(type default)
			)
			(layer "F.Fab")
		)
		(fp_line
			(start 0.12065 -0.2794)
			(end 0.12065 -0.3048)
			(stroke
				(width 0.1)
				(type default)
			)
			(layer "F.Fab")
		)
		(fp_line
			(start -0.12065 -0.2794)
			(end 0.12065 -0.2794)
			(stroke
				(width 0.1)
				(type default)
			)
			(layer "F.Fab")
		)
		(fp_line
			(start 0.120396 0.2794)
			(end -0.12065 0.2794)
			(stroke
				(width 0.1)
				(type default)
			)
			(layer "F.Fab")
		)
		(fp_line
			(start -0.12065 0.2794)
			(end -0.12065 0.3048)
			(stroke
				(width 0.1)
				(type default)
			)
			(layer "F.Fab")
		)
		(fp_line
			(start 0.67945 0.3048)
			(end 0.120396 0.3048)
			(stroke
				(width 0.1)
				(type default)
			)
			(layer "F.Fab")
		)
		(fp_line
			(start 0.120396 0.3048)
			(end 0.120396 0.2794)
			(stroke
				(width 0.1)
				(type default)
			)
			(layer "F.Fab")
		)
		(fp_line
			(start -0.12065 0.3048)
			(end -0.67945 0.3048)
			(stroke
				(width 0.1)
				(type default)
			)
			(layer "F.Fab")
		)
		(fp_line
			(start -0.67945 0.3048)
			(end -0.67945 -0.305054)
			(stroke
				(width 0.1)
				(type default)
			)
			(layer "F.Fab")
		)
		(pad "1" smd rect
			(at -0.40005 0 270)
			(size 0.4572 0.508)
			(layers "F.Cu" "F.Mask" "F.Paste")
			(net "USB2_GPU_HMC_USB8042_DP")
		)
		(pad "2" smd rect
			(at 0.40005 0 270)
			(size 0.4572 0.508)
			(layers "F.Cu" "F.Mask" "F.Paste")
			(net "USB2_GPU_HMC_DP")
		)
	)
	(footprint ""
		(layer "F.Cu")
		(at 203.174854 -373.659654 -90)
		(property "Reference" "R6247"
			(at 0 0 270)
			(layer "F.SilkS")
			(hide yes)
			(effects
				(font
					(size 1.27 1.27)
				)
			)
		)
		(property "Value" ""
			(at 0 0 270)
			(layer "F.Fab")
			(effects
				(font
					(size 1.27 1.27)
				)
			)
		)
		(duplicate_pad_numbers_are_jumpers no)
		(fp_line
			(start -0.7874 0.4064)
			(end -0.7874 -0.4064)
			(stroke
				(width 0.1524)
				(type default)
			)
			(layer "F.SilkS")
		)
		(fp_line
			(start 0.7874 0.4064)
			(end -0.7874 0.4064)
			(stroke
				(width 0.1524)
				(type default)
			)
			(layer "F.SilkS")
		)
		(fp_line
			(start -0.7874 -0.4064)
			(end 0.7874 -0.4064)
			(stroke
				(width 0.1524)
				(type default)
			)
			(layer "F.SilkS")
		)
		(fp_line
			(start 0.7874 -0.4064)
			(end 0.7874 0.4064)
			(stroke
				(width 0.1524)
				(type default)
			)
			(layer "F.SilkS")
		)
		(fp_line
			(start -0.67945 0.3048)
			(end -0.67945 -0.305054)
			(stroke
				(width 0.1)
				(type default)
			)
			(layer "F.Fab")
		)
		(fp_line
			(start -0.12065 0.3048)
			(end -0.67945 0.3048)
			(stroke
				(width 0.1)
				(type default)
			)
			(layer "F.Fab")
		)
		(fp_line
			(start 0.120396 0.3048)
			(end 0.120396 0.2794)
			(stroke
				(width 0.1)
				(type default)
			)
			(layer "F.Fab")
		)
		(fp_line
			(start 0.67945 0.3048)
			(end 0.120396 0.3048)
			(stroke
				(width 0.1)
				(type default)
			)
			(layer "F.Fab")
		)
		(fp_line
			(start -0.12065 0.2794)
			(end -0.12065 0.3048)
			(stroke
				(width 0.1)
				(type default)
			)
			(layer "F.Fab")
		)
		(fp_line
			(start 0.120396 0.2794)
			(end -0.12065 0.2794)
			(stroke
				(width 0.1)
				(type default)
			)
			(layer "F.Fab")
		)
		(fp_line
			(start -0.12065 -0.2794)
			(end 0.12065 -0.2794)
			(stroke
				(width 0.1)
				(type default)
			)
			(layer "F.Fab")
		)
		(fp_line
			(start 0.12065 -0.2794)
			(end 0.12065 -0.3048)
			(stroke
				(width 0.1)
				(type default)
			)
			(layer "F.Fab")
		)
		(fp_line
			(start 0.12065 -0.3048)
			(end 0.67945 -0.3048)
			(stroke
				(width 0.1)
				(type default)
			)
			(layer "F.Fab")
		)
		(fp_line
			(start 0.67945 -0.3048)
			(end 0.67945 0.3048)
			(stroke
				(width 0.1)
				(type default)
			)
			(layer "F.Fab")
		)
		(fp_line
			(start -0.67945 -0.305054)
			(end -0.12065 -0.305054)
			(stroke
				(width 0.1)
				(type default)
			)
			(layer "F.Fab")
		)
		(fp_line
			(start -0.12065 -0.305054)
			(end -0.12065 -0.2794)
			(stroke
				(width 0.1)
				(type default)
			)
			(layer "F.Fab")
		)
		(pad "1" smd circle
			(at -0.40005 0 270)
			(size 0 0)
			(layers "F.Cu" "F.Mask" "F.Paste")
			(net "P3V3_AUX")
		)
		(pad "2" smd circle
			(at 0.40005 0 270)
			(size 0 0)
			(layers "F.Cu" "F.Mask" "F.Paste")
			(net "HSC_ALERT1_N")
		)
	)
	(footprint ""
		(layer "F.Cu")
		(at 171.487592 -350.098614 90)
		(property "Reference" "C392"
			(at 0 0 90)
			(layer "F.SilkS")
			(hide yes)
			(effects
				(font
					(size 1.27 1.27)
				)
			)
		)
		(property "Value" ""
			(at 0 0 90)
			(layer "F.Fab")
			(effects
				(font
					(size 1.27 1.27)
				)
			)
		)
		(duplicate_pad_numbers_are_jumpers no)
		(fp_line
			(start 0.299974 -0.150114)
			(end 0.299974 0.150114)
			(stroke
				(width 0.1)
				(type default)
			)
			(layer "F.Fab")
		)
		(fp_line
			(start -0.299974 -0.150114)
			(end 0.299974 -0.150114)
			(stroke
				(width 0.1)
				(type default)
			)
			(layer "F.Fab")
		)
		(fp_line
			(start 0.299974 0.150114)
			(end -0.299974 0.150114)
			(stroke
				(width 0.1)
				(type default)
			)
			(layer "F.Fab")
		)
		(fp_line
			(start -0.299974 0.150114)
			(end -0.299974 -0.150114)
			(stroke
				(width 0.1)
				(type default)
			)
			(layer "F.Fab")
		)
		(pad "1" smd rect
			(at -0.2667 0 90)
			(size 0.3048 0.381)
			(layers "F.Cu" "F.Mask" "F.Paste")
			(net "P5E_PEX1_STN7_TX_DP<117>")
		)
		(pad "2" smd rect
			(at 0.2667 0 90)
			(size 0.3048 0.381)
			(layers "F.Cu" "F.Mask" "F.Paste")
			(net "P5E_PEX1_STN7_TX_C_DP<117>")
		)
	)
	(footprint ""
		(layer "F.Cu")
		(at 445.933068 -98.968052 -90)
		(property "Reference" "PU29"
			(at 0.75692 2.485136 90)
			(unlocked yes)
			(layer "F.SilkS")
			(effects
				(font
					(size 0.7874 0.5842)
					(thickness 0.1524)
				)
				(justify left)
			)
		)
		(property "Value" ""
			(at 0 0 270)
			(layer "F.Fab")
			(effects
				(font
					(size 1.27 1.27)
				)
			)
		)
		(duplicate_pad_numbers_are_jumpers no)
		(fp_line
			(start -1.943608 1.549908)
			(end -1.943608 -1.549908)
			(stroke
				(width 0.1524)
				(type default)
			)
			(layer "F.SilkS")
		)
		(fp_line
			(start 1.943608 1.549908)
			(end -1.943608 1.549908)
			(stroke
				(width 0.1524)
				(type default)
			)
			(layer "F.SilkS")
		)
		(fp_line
			(start -1.943608 -1.549908)
			(end 1.943608 -1.549908)
			(stroke
				(width 0.1524)
				(type default)
			)
			(layer "F.SilkS")
		)
		(fp_line
			(start 1.943608 -1.549908)
			(end 1.943608 1.549908)
			(stroke
				(width 0.1524)
				(type default)
			)
			(layer "F.SilkS")
		)
		(fp_poly
			(pts
				(xy -2.019808 -1.549908) (xy -1.257808 -1.549908) (xy -1.257808 -1.880108) (xy -2.019808 -1.880108)
			)
			(stroke
				(width 0)
				(type default)
			)
			(fill yes)
			(layer "F.SilkS")
		)
		(fp_line
			(start -1.549908 1.549908)
			(end -1.549908 -1.549908)
			(stroke
				(width 0.1)
				(type default)
			)
			(layer "F.Fab")
		)
		(fp_line
			(start 1.549908 1.549908)
			(end -1.549908 1.549908)
			(stroke
				(width 0.1)
				(type default)
			)
			(layer "F.Fab")
		)
		(fp_line
			(start -1.549908 -1.549908)
			(end 1.549908 -1.549908)
			(stroke
				(width 0.1)
				(type default)
			)
			(layer "F.Fab")
		)
		(fp_line
			(start 1.549908 -1.549908)
			(end 1.549908 1.549908)
			(stroke
				(width 0.1)
				(type default)
			)
			(layer "F.Fab")
		)
		(fp_poly
			(pts
				(xy -2.019808 -1.549908) (xy -1.257808 -1.549908) (xy -1.257808 -1.880108) (xy -2.019808 -1.880108)
			)
			(stroke
				(width 0)
				(type default)
			)
			(fill yes)
			(layer "F.Fab")
		)
		(pad "1" smd rect
			(at -1.500124 -1.249934 180)
			(size 0.2794 0.6096)
			(layers "F.Cu" "F.Mask" "F.Paste")
			(net "P12V_NIC7_R")
		)
		(pad "2" smd rect
			(at -1.500124 -0.750062 180)
			(size 0.2794 0.6096)
			(layers "F.Cu" "F.Mask" "F.Paste")
			(net "P12V_NIC7_R")
		)
		(pad "3" smd rect
			(at -1.500124 -0.249936 180)
			(size 0.2794 0.6096)
			(layers "F.Cu" "F.Mask" "F.Paste")
			(net "P12V_NIC7_R")
		)
		(pad "4" smd rect
			(at -1.500124 0.249936 180)
			(size 0.2794 0.6096)
			(layers "F.Cu" "F.Mask" "F.Paste")
			(net "P12V_NIC7_R")
		)
		(pad "5" smd rect
			(at -1.500124 0.750062 180)
			(size 0.2794 0.6096)
			(layers "F.Cu" "F.Mask" "F.Paste")
			(net "P12V_NIC7_R")
		)
		(pad "6" smd rect
			(at -1.500124 1.249934 180)
			(size 0.2794 0.6096)
			(layers "F.Cu" "F.Mask" "F.Paste")
			(net "GND")
		)
		(pad "7" smd rect
			(at 1.500124 1.249934 180)
			(size 0.2794 0.6096)
			(layers "F.Cu" "F.Mask" "F.Paste")
			(net "P12V_NIC7_SS")
		)
		(pad "8" smd rect
			(at 1.500124 0.750062 180)
			(size 0.2794 0.6096)
			(layers "F.Cu" "F.Mask" "F.Paste")
			(net "PWRGD_P12V_NIC7")
		)
		(pad "9" smd rect
			(at 1.500124 0.249936 180)
			(size 0.2794 0.6096)
			(layers "F.Cu" "F.Mask" "F.Paste")
			(net "P12V_NIC7_OCP")
		)
		(pad "10" smd rect
			(at 1.500124 -0.249936 180)
			(size 0.2794 0.6096)
			(layers "F.Cu" "F.Mask" "F.Paste")
			(net "P5V_AUX")
		)
		(pad "11" smd rect
			(at 1.500124 -0.750062 180)
			(size 0.2794 0.6096)
			(layers "F.Cu" "F.Mask" "F.Paste")
			(net "P12V_NIC7_EN_R")
		)
		(pad "12" smd rect
			(at 1.500124 -1.249934 180)
			(size 0.2794 0.6096)
			(layers "F.Cu" "F.Mask" "F.Paste")
			(net "P12V_AUX")
		)
		(pad "13" smd rect
			(at 0 0 270)
			(size 1.9812 2.7178)
			(layers "F.Cu" "F.Mask" "F.Paste")
			(net "P12V_AUX")
		)
		(zone
			(layer "F.Cu")
			(hatch none 0.5)
			(connect_pads
				(clearance 0)
			)
			(min_thickness 0.25)
			(keepout
				(tracks not_allowed)
				(vias allowed)
				(pads allowed)
				(copperpour not_allowed)
				(footprints allowed)
			)
			(placement
				(enabled no)
				(sheetname "")
			)
			(fill
				(thermal_gap 0.5)
				(thermal_bridge_width 0.5)
				(island_removal_mode 0)
			)
			(polygon
				(pts
					(xy 447.482468 -97.825052) (xy 447.355468 -97.825052) (xy 444.383668 -97.825052) (xy 444.38316 -97.825052)
					(xy 444.38316 -100.111052) (xy 444.383668 -100.111052) (xy 444.510668 -100.111052) (xy 445.933068 -100.111052)
					(xy 445.933068 -100.009452) (xy 444.510668 -100.009452) (xy 444.510668 -97.926652) (xy 447.355468 -97.926652)
					(xy 447.355468 -100.009452) (xy 445.958468 -100.009452) (xy 445.958468 -100.111052) (xy 447.355468 -100.111052)
					(xy 447.482468 -100.111052) (xy 447.482976 -100.111052) (xy 447.482976 -97.825052)
				)
			)
		)
	)
	(footprint ""
		(layer "F.Cu")
		(at 18.638774 -22.867366 90)
		(property "Reference" "C3876"
			(at 0 0 90)
			(layer "F.SilkS")
			(hide yes)
			(effects
				(font
					(size 1.27 1.27)
				)
			)
		)
		(property "Value" ""
			(at 0 0 90)
			(layer "F.Fab")
			(effects
				(font
					(size 1.27 1.27)
				)
			)
		)
		(duplicate_pad_numbers_are_jumpers no)
		(fp_line
			(start 0.7874 -0.4064)
			(end 0.7874 0.4064)
			(stroke
				(width 0.1524)
				(type default)
			)
			(layer "F.SilkS")
		)
		(fp_line
			(start -0.7874 -0.4064)
			(end 0.7874 -0.4064)
			(stroke
				(width 0.1524)
				(type default)
			)
			(layer "F.SilkS")
		)
		(fp_line
			(start 0.7874 0.4064)
			(end -0.7874 0.4064)
			(stroke
				(width 0.1524)
				(type default)
			)
			(layer "F.SilkS")
		)
		(fp_line
			(start -0.7874 0.4064)
			(end -0.7874 -0.4064)
			(stroke
				(width 0.1524)
				(type default)
			)
			(layer "F.SilkS")
		)
		(fp_line
			(start -0.12065 -0.305054)
			(end -0.12065 -0.2794)
			(stroke
				(width 0.1)
				(type default)
			)
			(layer "F.Fab")
		)
		(fp_line
			(start -0.67945 -0.305054)
			(end -0.12065 -0.305054)
			(stroke
				(width 0.1)
				(type default)
			)
			(layer "F.Fab")
		)
		(fp_line
			(start 0.67945 -0.3048)
			(end 0.67945 0.3048)
			(stroke
				(width 0.1)
				(type default)
			)
			(layer "F.Fab")
		)
		(fp_line
			(start 0.12065 -0.3048)
			(end 0.67945 -0.3048)
			(stroke
				(width 0.1)
				(type default)
			)
			(layer "F.Fab")
		)
		(fp_line
			(start 0.12065 -0.2794)
			(end 0.12065 -0.3048)
			(stroke
				(width 0.1)
				(type default)
			)
			(layer "F.Fab")
		)
		(fp_line
			(start -0.12065 -0.2794)
			(end 0.12065 -0.2794)
			(stroke
				(width 0.1)
				(type default)
			)
			(layer "F.Fab")
		)
		(fp_line
			(start 0.120396 0.2794)
			(end -0.12065 0.2794)
			(stroke
				(width 0.1)
				(type default)
			)
			(layer "F.Fab")
		)
		(fp_line
			(start -0.12065 0.2794)
			(end -0.12065 0.3048)
			(stroke
				(width 0.1)
				(type default)
			)
			(layer "F.Fab")
		)
		(fp_line
			(start 0.67945 0.3048)
			(end 0.120396 0.3048)
			(stroke
				(width 0.1)
				(type default)
			)
			(layer "F.Fab")
		)
		(fp_line
			(start 0.120396 0.3048)
			(end 0.120396 0.2794)
			(stroke
				(width 0.1)
				(type default)
			)
			(layer "F.Fab")
		)
		(fp_line
			(start -0.12065 0.3048)
			(end -0.67945 0.3048)
			(stroke
				(width 0.1)
				(type default)
			)
			(layer "F.Fab")
		)
		(fp_line
			(start -0.67945 0.3048)
			(end -0.67945 -0.305054)
			(stroke
				(width 0.1)
				(type default)
			)
			(layer "F.Fab")
		)
		(pad "1" smd circle
			(at -0.40005 0 90)
			(size 0 0)
			(layers "F.Cu" "F.Mask" "F.Paste")
			(net "P12V_SSD0")
		)
		(pad "2" smd circle
			(at 0.40005 0 90)
			(size 0 0)
			(layers "F.Cu" "F.Mask" "F.Paste")
			(net "GND")
		)
	)
	(footprint ""
		(layer "F.Cu")
		(at 3.608578 -381.411226)
		(property "Reference" "R6735"
			(at 0 0 0)
			(layer "F.SilkS")
			(hide yes)
			(effects
				(font
					(size 1.27 1.27)
				)
			)
		)
		(property "Value" ""
			(at 0 0 0)
			(layer "F.Fab")
			(effects
				(font
					(size 1.27 1.27)
				)
			)
		)
		(duplicate_pad_numbers_are_jumpers no)
		(fp_line
			(start -0.7874 -0.4064)
			(end 0.7874 -0.4064)
			(stroke
				(width 0.1524)
				(type default)
			)
			(layer "F.SilkS")
		)
		(fp_line
			(start -0.7874 0.4064)
			(end -0.7874 -0.4064)
			(stroke
				(width 0.1524)
				(type default)
			)
			(layer "F.SilkS")
		)
		(fp_line
			(start 0.7874 -0.4064)
			(end 0.7874 0.4064)
			(stroke
				(width 0.1524)
				(type default)
			)
			(layer "F.SilkS")
		)
		(fp_line
			(start 0.7874 0.4064)
			(end -0.7874 0.4064)
			(stroke
				(width 0.1524)
				(type default)
			)
			(layer "F.SilkS")
		)
		(fp_line
			(start -0.67945 -0.305054)
			(end -0.12065 -0.305054)
			(stroke
				(width 0.1)
				(type default)
			)
			(layer "F.Fab")
		)
		(fp_line
			(start -0.67945 0.3048)
			(end -0.67945 -0.305054)
			(stroke
				(width 0.1)
				(type default)
			)
			(layer "F.Fab")
		)
		(fp_line
			(start -0.12065 -0.305054)
			(end -0.12065 -0.2794)
			(stroke
				(width 0.1)
				(type default)
			)
			(layer "F.Fab")
		)
		(fp_line
			(start -0.12065 -0.2794)
			(end 0.12065 -0.2794)
			(stroke
				(width 0.1)
				(type default)
			)
			(layer "F.Fab")
		)
		(fp_line
			(start -0.12065 0.2794)
			(end -0.12065 0.3048)
			(stroke
				(width 0.1)
				(type default)
			)
			(layer "F.Fab")
		)
		(fp_line
			(start -0.12065 0.3048)
			(end -0.67945 0.3048)
			(stroke
				(width 0.1)
				(type default)
			)
			(layer "F.Fab")
		)
		(fp_line
			(start 0.120396 0.2794)
			(end -0.12065 0.2794)
			(stroke
				(width 0.1)
				(type default)
			)
			(layer "F.Fab")
		)
		(fp_line
			(start 0.120396 0.3048)
			(end 0.120396 0.2794)
			(stroke
				(width 0.1)
				(type default)
			)
			(layer "F.Fab")
		)
		(fp_line
			(start 0.12065 -0.3048)
			(end 0.67945 -0.3048)
			(stroke
				(width 0.1)
				(type default)
			)
			(layer "F.Fab")
		)
		(fp_line
			(start 0.12065 -0.2794)
			(end 0.12065 -0.3048)
			(stroke
				(width 0.1)
				(type default)
			)
			(layer "F.Fab")
		)
		(fp_line
			(start 0.67945 -0.3048)
			(end 0.67945 0.3048)
			(stroke
				(width 0.1)
				(type default)
			)
			(layer "F.Fab")
		)
		(fp_line
			(start 0.67945 0.3048)
			(end 0.120396 0.3048)
			(stroke
				(width 0.1)
				(type default)
			)
			(layer "F.Fab")
		)
		(pad "1" smd circle
			(at -0.40005 0)
			(size 0 0)
			(layers "F.Cu" "F.Mask" "F.Paste")
			(net "BIC_USB_8042_HUB_XOUT")
		)
		(pad "2" smd circle
			(at 0.40005 0)
			(size 0 0)
			(layers "F.Cu" "F.Mask" "F.Paste")
			(net "BIC_USB_8042_HUB_XIN")
		)
	)
	(footprint ""
		(layer "F.Cu")
		(at 248.971562 -214.035386 180)
		(property "Reference" "C2850"
			(at 0 0 180)
			(layer "F.SilkS")
			(hide yes)
			(effects
				(font
					(size 1.27 1.27)
				)
			)
		)
		(property "Value" ""
			(at 0 0 180)
			(layer "F.Fab")
			(effects
				(font
					(size 1.27 1.27)
				)
			)
		)
		(duplicate_pad_numbers_are_jumpers no)
		(fp_line
			(start 1.524 0.762)
			(end -1.524 0.762)
			(stroke
				(width 0.1524)
				(type default)
			)
			(layer "F.SilkS")
		)
		(fp_line
			(start 1.524 -0.762)
			(end 1.524 0.762)
			(stroke
				(width 0.1524)
				(type default)
			)
			(layer "F.SilkS")
		)
		(fp_line
			(start -1.524 0.762)
			(end -1.524 -0.762)
			(stroke
				(width 0.1524)
				(type default)
			)
			(layer "F.SilkS")
		)
		(fp_line
			(start -1.524 -0.762)
			(end 1.524 -0.762)
			(stroke
				(width 0.1524)
				(type default)
			)
			(layer "F.SilkS")
		)
		(fp_line
			(start 1.1049 0.724916)
			(end 1.1049 -0.724916)
			(stroke
				(width 0.1)
				(type default)
			)
			(layer "F.Fab")
		)
		(fp_line
			(start 1.1049 -0.724916)
			(end -1.1049 -0.724916)
			(stroke
				(width 0.1)
				(type default)
			)
			(layer "F.Fab")
		)
		(fp_line
			(start -1.1049 0.724916)
			(end 1.1049 0.724916)
			(stroke
				(width 0.1)
				(type default)
			)
			(layer "F.Fab")
		)
		(fp_line
			(start -1.1049 -0.724916)
			(end -1.1049 0.724916)
			(stroke
				(width 0.1)
				(type default)
			)
			(layer "F.Fab")
		)
		(pad "1" smd rect
			(at -0.889 0)
			(size 1.016 1.27)
			(layers "F.Cu" "F.Mask" "F.Paste")
			(net "P1V2_AUX")
		)
		(pad "2" smd rect
			(at 0.889 0)
			(size 1.016 1.27)
			(layers "F.Cu" "F.Mask" "F.Paste")
			(net "GND")
		)
	)
	(footprint ""
		(layer "F.Cu")
		(at 21.961094 -37.951156)
		(property "Reference" "Q134"
			(at 0.06096 -2.232406 0)
			(unlocked yes)
			(layer "F.SilkS")
			(effects
				(font
					(size 0.7874 0.5842)
					(thickness 0.1524)
				)
			)
		)
		(property "Value" ""
			(at 0 0 0)
			(layer "F.Fab")
			(effects
				(font
					(size 1.27 1.27)
				)
			)
		)
		(duplicate_pad_numbers_are_jumpers no)
		(fp_line
			(start -1.376172 -1.199896)
			(end -0.508 -1.199896)
			(stroke
				(width 0.1524)
				(type default)
			)
			(layer "F.SilkS")
		)
		(fp_line
			(start -1.376172 1.199896)
			(end -1.376172 -1.199896)
			(stroke
				(width 0.1524)
				(type default)
			)
			(layer "F.SilkS")
		)
		(fp_line
			(start -0.508 -1.199896)
			(end 0 -0.762)
			(stroke
				(width 0.1524)
				(type default)
			)
			(layer "F.SilkS")
		)
		(fp_line
			(start 0 -0.762)
			(end 0.508 -1.199896)
			(stroke
				(width 0.1524)
				(type default)
			)
			(layer "F.SilkS")
		)
		(fp_line
			(start 0.508 -1.199896)
			(end 1.376172 -1.199896)
			(stroke
				(width 0.1524)
				(type default)
			)
			(layer "F.SilkS")
		)
		(fp_line
			(start 1.376172 -1.199896)
			(end 1.376172 1.199896)
			(stroke
				(width 0.1524)
				(type default)
			)
			(layer "F.SilkS")
		)
		(fp_line
			(start 1.376172 1.199896)
			(end -1.376172 1.199896)
			(stroke
				(width 0.1524)
				(type default)
			)
			(layer "F.SilkS")
		)
		(fp_poly
			(pts
				(xy -1.44399 -1.086104) (xy -1.71323 -1.894332) (xy -2.252218 -1.355598)
			)
			(stroke
				(width 0)
				(type default)
			)
			(fill yes)
			(layer "F.SilkS")
		)
		(fp_line
			(start -0.674878 -1.100074)
			(end 0.674878 -1.100074)
			(stroke
				(width 0.1)
				(type default)
			)
			(layer "F.Fab")
		)
		(fp_line
			(start -0.674878 1.100074)
			(end -0.674878 -1.100074)
			(stroke
				(width 0.1)
				(type default)
			)
			(layer "F.Fab")
		)
		(fp_line
			(start 0.674878 -1.100074)
			(end 0.674878 1.100074)
			(stroke
				(width 0.1)
				(type default)
			)
			(layer "F.Fab")
		)
		(fp_line
			(start 0.674878 1.100074)
			(end -0.674878 1.100074)
			(stroke
				(width 0.1)
				(type default)
			)
			(layer "F.Fab")
		)
		(fp_poly
			(pts
				(xy -1.4605 -0.7493) (xy -2.2225 -1.1303) (xy -2.2225 -0.3683)
			)
			(stroke
				(width 0)
				(type default)
			)
			(fill yes)
			(layer "F.Fab")
		)
		(pad "1" smd rect
			(at -0.899922 -0.750062 270)
			(size 0.6096 0.6096)
			(layers "F.Cu" "F.Mask" "F.Paste")
			(net "GND")
		)
		(pad "2" smd rect
			(at -0.899922 0 270)
			(size 0.4064 0.6096)
			(layers "F.Cu" "F.Mask" "F.Paste")
			(net "P3V3_SSD1_PG_G1")
		)
		(pad "3" smd rect
			(at -0.899922 0.750062 270)
			(size 0.6096 0.6096)
			(layers "F.Cu" "F.Mask" "F.Paste")
			(net "PWRGD_P3V3_SSD1_D")
		)
		(pad "4" smd rect
			(at 0.899922 0.750062 270)
			(size 0.6096 0.6096)
			(layers "F.Cu" "F.Mask" "F.Paste")
			(net "GND")
		)
		(pad "5" smd rect
			(at 0.899922 0 270)
			(size 0.4064 0.6096)
			(layers "F.Cu" "F.Mask" "F.Paste")
			(net "P3V3_SSD1_PG_G2")
		)
		(pad "6" smd rect
			(at 0.899922 -0.750062 270)
			(size 0.6096 0.6096)
			(layers "F.Cu" "F.Mask" "F.Paste")
			(net "P3V3_SSD1_PG_G2")
		)
	)
	(footprint ""
		(layer "F.Cu")
		(at 418.93871 -22.867366 90)
		(property "Reference" "C3971"
			(at 0 0 90)
			(layer "F.SilkS")
			(hide yes)
			(effects
				(font
					(size 1.27 1.27)
				)
			)
		)
		(property "Value" ""
			(at 0 0 90)
			(layer "F.Fab")
			(effects
				(font
					(size 1.27 1.27)
				)
			)
		)
		(duplicate_pad_numbers_are_jumpers no)
		(fp_line
			(start 0.7874 -0.4064)
			(end 0.7874 0.4064)
			(stroke
				(width 0.1524)
				(type default)
			)
			(layer "F.SilkS")
		)
		(fp_line
			(start -0.7874 -0.4064)
			(end 0.7874 -0.4064)
			(stroke
				(width 0.1524)
				(type default)
			)
			(layer "F.SilkS")
		)
		(fp_line
			(start 0.7874 0.4064)
			(end -0.7874 0.4064)
			(stroke
				(width 0.1524)
				(type default)
			)
			(layer "F.SilkS")
		)
		(fp_line
			(start -0.7874 0.4064)
			(end -0.7874 -0.4064)
			(stroke
				(width 0.1524)
				(type default)
			)
			(layer "F.SilkS")
		)
		(fp_line
			(start -0.12065 -0.305054)
			(end -0.12065 -0.2794)
			(stroke
				(width 0.1)
				(type default)
			)
			(layer "F.Fab")
		)
		(fp_line
			(start -0.67945 -0.305054)
			(end -0.12065 -0.305054)
			(stroke
				(width 0.1)
				(type default)
			)
			(layer "F.Fab")
		)
		(fp_line
			(start 0.67945 -0.3048)
			(end 0.67945 0.3048)
			(stroke
				(width 0.1)
				(type default)
			)
			(layer "F.Fab")
		)
		(fp_line
			(start 0.12065 -0.3048)
			(end 0.67945 -0.3048)
			(stroke
				(width 0.1)
				(type default)
			)
			(layer "F.Fab")
		)
		(fp_line
			(start 0.12065 -0.2794)
			(end 0.12065 -0.3048)
			(stroke
				(width 0.1)
				(type default)
			)
			(layer "F.Fab")
		)
		(fp_line
			(start -0.12065 -0.2794)
			(end 0.12065 -0.2794)
			(stroke
				(width 0.1)
				(type default)
			)
			(layer "F.Fab")
		)
		(fp_line
			(start 0.120396 0.2794)
			(end -0.12065 0.2794)
			(stroke
				(width 0.1)
				(type default)
			)
			(layer "F.Fab")
		)
		(fp_line
			(start -0.12065 0.2794)
			(end -0.12065 0.3048)
			(stroke
				(width 0.1)
				(type default)
			)
			(layer "F.Fab")
		)
		(fp_line
			(start 0.67945 0.3048)
			(end 0.120396 0.3048)
			(stroke
				(width 0.1)
				(type default)
			)
			(layer "F.Fab")
		)
		(fp_line
			(start 0.120396 0.3048)
			(end 0.120396 0.2794)
			(stroke
				(width 0.1)
				(type default)
			)
			(layer "F.Fab")
		)
		(fp_line
			(start -0.12065 0.3048)
			(end -0.67945 0.3048)
			(stroke
				(width 0.1)
				(type default)
			)
			(layer "F.Fab")
		)
		(fp_line
			(start -0.67945 0.3048)
			(end -0.67945 -0.305054)
			(stroke
				(width 0.1)
				(type default)
			)
			(layer "F.Fab")
		)
		(pad "1" smd circle
			(at -0.40005 0 90)
			(size 0 0)
			(layers "F.Cu" "F.Mask" "F.Paste")
			(net "P12V_SSD14")
		)
		(pad "2" smd circle
			(at 0.40005 0 90)
			(size 0 0)
			(layers "F.Cu" "F.Mask" "F.Paste")
			(net "GND")
		)
	)
	(footprint ""
		(layer "F.Cu")
		(at 303.854612 -22.867366 90)
		(property "Reference" "C3943"
			(at 0 0 90)
			(layer "F.SilkS")
			(hide yes)
			(effects
				(font
					(size 1.27 1.27)
				)
			)
		)
		(property "Value" ""
			(at 0 0 90)
			(layer "F.Fab")
			(effects
				(font
					(size 1.27 1.27)
				)
			)
		)
		(duplicate_pad_numbers_are_jumpers no)
		(fp_line
			(start 0.7874 -0.4064)
			(end 0.7874 0.4064)
			(stroke
				(width 0.1524)
				(type default)
			)
			(layer "F.SilkS")
		)
		(fp_line
			(start -0.7874 -0.4064)
			(end 0.7874 -0.4064)
			(stroke
				(width 0.1524)
				(type default)
			)
			(layer "F.SilkS")
		)
		(fp_line
			(start 0.7874 0.4064)
			(end -0.7874 0.4064)
			(stroke
				(width 0.1524)
				(type default)
			)
			(layer "F.SilkS")
		)
		(fp_line
			(start -0.7874 0.4064)
			(end -0.7874 -0.4064)
			(stroke
				(width 0.1524)
				(type default)
			)
			(layer "F.SilkS")
		)
		(fp_line
			(start -0.12065 -0.305054)
			(end -0.12065 -0.2794)
			(stroke
				(width 0.1)
				(type default)
			)
			(layer "F.Fab")
		)
		(fp_line
			(start -0.67945 -0.305054)
			(end -0.12065 -0.305054)
			(stroke
				(width 0.1)
				(type default)
			)
			(layer "F.Fab")
		)
		(fp_line
			(start 0.67945 -0.3048)
			(end 0.67945 0.3048)
			(stroke
				(width 0.1)
				(type default)
			)
			(layer "F.Fab")
		)
		(fp_line
			(start 0.12065 -0.3048)
			(end 0.67945 -0.3048)
			(stroke
				(width 0.1)
				(type default)
			)
			(layer "F.Fab")
		)
		(fp_line
			(start 0.12065 -0.2794)
			(end 0.12065 -0.3048)
			(stroke
				(width 0.1)
				(type default)
			)
			(layer "F.Fab")
		)
		(fp_line
			(start -0.12065 -0.2794)
			(end 0.12065 -0.2794)
			(stroke
				(width 0.1)
				(type default)
			)
			(layer "F.Fab")
		)
		(fp_line
			(start 0.120396 0.2794)
			(end -0.12065 0.2794)
			(stroke
				(width 0.1)
				(type default)
			)
			(layer "F.Fab")
		)
		(fp_line
			(start -0.12065 0.2794)
			(end -0.12065 0.3048)
			(stroke
				(width 0.1)
				(type default)
			)
			(layer "F.Fab")
		)
		(fp_line
			(start 0.67945 0.3048)
			(end 0.120396 0.3048)
			(stroke
				(width 0.1)
				(type default)
			)
			(layer "F.Fab")
		)
		(fp_line
			(start 0.120396 0.3048)
			(end 0.120396 0.2794)
			(stroke
				(width 0.1)
				(type default)
			)
			(layer "F.Fab")
		)
		(fp_line
			(start -0.12065 0.3048)
			(end -0.67945 0.3048)
			(stroke
				(width 0.1)
				(type default)
			)
			(layer "F.Fab")
		)
		(fp_line
			(start -0.67945 0.3048)
			(end -0.67945 -0.305054)
			(stroke
				(width 0.1)
				(type default)
			)
			(layer "F.Fab")
		)
		(pad "1" smd circle
			(at -0.40005 0 90)
			(size 0 0)
			(layers "F.Cu" "F.Mask" "F.Paste")
			(net "P12V_SSD10")
		)
		(pad "2" smd circle
			(at 0.40005 0 90)
			(size 0 0)
			(layers "F.Cu" "F.Mask" "F.Paste")
			(net "GND")
		)
	)
	(footprint ""
		(layer "F.Cu")
		(at 244.196616 -306.681632 -90)
		(property "Reference" "PR177"
			(at 0 0 270)
			(layer "F.SilkS")
			(hide yes)
			(effects
				(font
					(size 1.27 1.27)
				)
			)
		)
		(property "Value" ""
			(at 0 0 270)
			(layer "F.Fab")
			(effects
				(font
					(size 1.27 1.27)
				)
			)
		)
		(duplicate_pad_numbers_are_jumpers no)
		(fp_line
			(start -0.7874 0.4064)
			(end -0.7874 -0.4064)
			(stroke
				(width 0.1524)
				(type default)
			)
			(layer "F.SilkS")
		)
		(fp_line
			(start 0.7874 0.4064)
			(end -0.7874 0.4064)
			(stroke
				(width 0.1524)
				(type default)
			)
			(layer "F.SilkS")
		)
		(fp_line
			(start -0.7874 -0.4064)
			(end 0.7874 -0.4064)
			(stroke
				(width 0.1524)
				(type default)
			)
			(layer "F.SilkS")
		)
		(fp_line
			(start 0.7874 -0.4064)
			(end 0.7874 0.4064)
			(stroke
				(width 0.1524)
				(type default)
			)
			(layer "F.SilkS")
		)
		(fp_line
			(start -0.67945 0.3048)
			(end -0.67945 -0.305054)
			(stroke
				(width 0.1)
				(type default)
			)
			(layer "F.Fab")
		)
		(fp_line
			(start -0.12065 0.3048)
			(end -0.67945 0.3048)
			(stroke
				(width 0.1)
				(type default)
			)
			(layer "F.Fab")
		)
		(fp_line
			(start 0.120396 0.3048)
			(end 0.120396 0.2794)
			(stroke
				(width 0.1)
				(type default)
			)
			(layer "F.Fab")
		)
		(fp_line
			(start 0.67945 0.3048)
			(end 0.120396 0.3048)
			(stroke
				(width 0.1)
				(type default)
			)
			(layer "F.Fab")
		)
		(fp_line
			(start -0.12065 0.2794)
			(end -0.12065 0.3048)
			(stroke
				(width 0.1)
				(type default)
			)
			(layer "F.Fab")
		)
		(fp_line
			(start 0.120396 0.2794)
			(end -0.12065 0.2794)
			(stroke
				(width 0.1)
				(type default)
			)
			(layer "F.Fab")
		)
		(fp_line
			(start -0.12065 -0.2794)
			(end 0.12065 -0.2794)
			(stroke
				(width 0.1)
				(type default)
			)
			(layer "F.Fab")
		)
		(fp_line
			(start 0.12065 -0.2794)
			(end 0.12065 -0.3048)
			(stroke
				(width 0.1)
				(type default)
			)
			(layer "F.Fab")
		)
		(fp_line
			(start 0.12065 -0.3048)
			(end 0.67945 -0.3048)
			(stroke
				(width 0.1)
				(type default)
			)
			(layer "F.Fab")
		)
		(fp_line
			(start 0.67945 -0.3048)
			(end 0.67945 0.3048)
			(stroke
				(width 0.1)
				(type default)
			)
			(layer "F.Fab")
		)
		(fp_line
			(start -0.67945 -0.305054)
			(end -0.12065 -0.305054)
			(stroke
				(width 0.1)
				(type default)
			)
			(layer "F.Fab")
		)
		(fp_line
			(start -0.12065 -0.305054)
			(end -0.12065 -0.2794)
			(stroke
				(width 0.1)
				(type default)
			)
			(layer "F.Fab")
		)
		(pad "1" smd circle
			(at -0.40005 0 270)
			(size 0 0)
			(layers "F.Cu" "F.Mask" "F.Paste")
			(net "P1V25_PEX2_CS")
		)
		(pad "2" smd circle
			(at 0.40005 0 270)
			(size 0 0)
			(layers "F.Cu" "F.Mask" "F.Paste")
			(net "GND")
		)
	)
	(footprint ""
		(layer "F.Cu")
		(at 251.899674 -225.49993 180)
		(property "Reference" "JPEX2"
			(at -10.399522 -8.38454 0)
			(unlocked yes)
			(layer "F.SilkS")
			(effects
				(font
					(size 0.7874 0.5842)
					(thickness 0.1524)
				)
				(justify left)
			)
		)
		(property "Value" ""
			(at 0 0 180)
			(layer "F.Fab")
			(effects
				(font
					(size 1.27 1.27)
				)
			)
		)
		(duplicate_pad_numbers_are_jumpers no)
		(fp_line
			(start 12.46505 7.649972)
			(end -12.46505 7.649972)
			(stroke
				(width 0.1524)
				(type default)
			)
			(layer "F.SilkS")
		)
		(fp_line
			(start 12.46505 6.938264)
			(end 12.46505 7.649972)
			(stroke
				(width 0.1524)
				(type default)
			)
			(layer "F.SilkS")
		)
		(fp_line
			(start 12.46505 -4.827524)
			(end 12.46505 4.660138)
			(stroke
				(width 0.1524)
				(type default)
			)
			(layer "F.SilkS")
		)
		(fp_line
			(start 6.945122 7.649972)
			(end -6.945122 7.649972)
			(stroke
				(width 0.1524)
				(type default)
			)
			(layer "F.SilkS")
		)
		(fp_line
			(start 6.945122 -7.649972)
			(end 6.945122 7.649972)
			(stroke
				(width 0.1524)
				(type default)
			)
			(layer "F.SilkS")
		)
		(fp_line
			(start 6.945122 -7.649972)
			(end 0 -7.649972)
			(stroke
				(width 0.1524)
				(type default)
			)
			(layer "F.SilkS")
		)
		(fp_line
			(start 0 -7.649972)
			(end 9.858756 -7.649972)
			(stroke
				(width 0.1524)
				(type default)
			)
			(layer "F.SilkS")
		)
		(fp_line
			(start -6.945122 -7.649972)
			(end 0 -7.649972)
			(stroke
				(width 0.1524)
				(type default)
			)
			(layer "F.SilkS")
		)
		(fp_line
			(start -6.945122 -7.649972)
			(end -6.945122 7.649972)
			(stroke
				(width 0.1524)
				(type default)
			)
			(layer "F.SilkS")
		)
		(fp_line
			(start -12.46505 7.649972)
			(end -12.46505 -7.649972)
			(stroke
				(width 0.1524)
				(type default)
			)
			(layer "F.SilkS")
		)
		(fp_line
			(start -12.46505 -7.649972)
			(end 0 -7.649972)
			(stroke
				(width 0.1524)
				(type default)
			)
			(layer "F.SilkS")
		)
		(fp_poly
			(pts
				(xy -7.112 -4.445) (xy -8.128 -4.953) (xy -8.128 -3.937)
			)
			(stroke
				(width 0)
				(type default)
			)
			(fill yes)
			(layer "F.SilkS")
		)
		(fp_line
			(start 6.945122 7.649972)
			(end -6.945122 7.649972)
			(stroke
				(width 0.1)
				(type default)
			)
			(layer "F.Fab")
		)
		(fp_line
			(start 6.945122 -7.649972)
			(end 6.945122 7.649972)
			(stroke
				(width 0.1)
				(type default)
			)
			(layer "F.Fab")
		)
		(fp_line
			(start -6.945122 7.649972)
			(end -6.945122 -7.649972)
			(stroke
				(width 0.1)
				(type default)
			)
			(layer "F.Fab")
		)
		(fp_line
			(start -6.945122 -7.649972)
			(end 6.945122 -7.649972)
			(stroke
				(width 0.1)
				(type default)
			)
			(layer "F.Fab")
		)
		(fp_poly
			(pts
				(xy -7.112 -4.445) (xy -8.128 -4.953) (xy -8.128 -3.937)
			)
			(stroke
				(width 0)
				(type default)
			)
			(fill yes)
			(layer "F.Fab")
		)
		(fp_text user "9"
			(at 7.51713 4.1656 90)
			(unlocked yes)
			(layer "F.SilkS")
			(effects
				(font
					(size 0.7874 0.5842)
					(thickness 0.1524)
				)
				(justify left)
			)
		)
		(fp_text user "16"
			(at 7.49173 -5.2324 90)
			(unlocked yes)
			(layer "F.SilkS")
			(effects
				(font
					(size 0.7874 0.5842)
					(thickness 0.1524)
				)
				(justify left)
			)
		)
		(fp_text user "8"
			(at -7.77367 4.2164 90)
			(unlocked yes)
			(layer "F.SilkS")
			(effects
				(font
					(size 0.7874 0.5842)
					(thickness 0.1524)
				)
				(justify left)
			)
		)
		(fp_text user "9"
			(at 7.51713 4.1656 90)
			(unlocked yes)
			(layer "F.Fab")
			(effects
				(font
					(size 0.7874 0.5842)
					(thickness 0.1524)
				)
				(justify left)
			)
		)
		(fp_text user "16"
			(at 7.49173 -5.2324 90)
			(unlocked yes)
			(layer "F.Fab")
			(effects
				(font
					(size 0.7874 0.5842)
					(thickness 0.1524)
				)
				(justify left)
			)
		)
		(fp_text user "8"
			(at -7.77367 4.2164 90)
			(unlocked yes)
			(layer "F.Fab")
			(effects
				(font
					(size 0.7874 0.5842)
					(thickness 0.1524)
				)
				(justify left)
			)
		)
		(pad "1" smd rect
			(at -4.800092 -4.445 90)
			(size 0.508 1.524)
			(layers "F.Cu" "F.Mask" "F.Paste")
			(net "SPI_PEX2_SDIO3_R1")
		)
		(pad "2" smd rect
			(at -4.800092 -3.175 90)
			(size 0.508 1.524)
			(layers "F.Cu" "F.Mask" "F.Paste")
			(net "P1V8_PEX")
		)
		(pad "3" smd rect
			(at -4.800092 -1.905 90)
			(size 0.508 1.524)
			(layers "F.Cu" "F.Mask" "F.Paste")
			(net "SPI_PEX2_RST_R_N")
		)
		(pad "4" smd rect
			(at -4.800092 -0.635 90)
			(size 0.508 1.524)
			(layers "F.Cu" "F.Mask" "F.Paste")
			(net "Net_2698")
		)
		(pad "5" smd rect
			(at -4.800092 0.635 90)
			(size 0.508 1.524)
			(layers "F.Cu" "F.Mask" "F.Paste")
			(net "Net_2697")
		)
		(pad "6" smd rect
			(at -4.800092 1.905 90)
			(size 0.508 1.524)
			(layers "F.Cu" "F.Mask" "F.Paste")
			(net "Net_2696")
		)
		(pad "7" smd rect
			(at -4.800092 3.175 90)
			(size 0.508 1.524)
			(layers "F.Cu" "F.Mask" "F.Paste")
			(net "SPI_PEX2_CS_MUX_R_N")
		)
		(pad "8" smd rect
			(at -4.800092 4.445 90)
			(size 0.508 1.524)
			(layers "F.Cu" "F.Mask" "F.Paste")
			(net "SPI_PEX2_SDIO1_MUX_R")
		)
		(pad "9" smd rect
			(at 4.800092 4.445 90)
			(size 0.508 1.524)
			(layers "F.Cu" "F.Mask" "F.Paste")
			(net "SPI_PEX2_SDIO2_R1")
		)
		(pad "10" smd rect
			(at 4.800092 3.175 90)
			(size 0.508 1.524)
			(layers "F.Cu" "F.Mask" "F.Paste")
			(net "GND")
		)
		(pad "11" smd rect
			(at 4.800092 1.905 90)
			(size 0.508 1.524)
			(layers "F.Cu" "F.Mask" "F.Paste")
			(net "Net_2699")
		)
		(pad "12" smd rect
			(at 4.800092 0.635 90)
			(size 0.508 1.524)
			(layers "F.Cu" "F.Mask" "F.Paste")
			(net "Net_2700")
		)
		(pad "13" smd rect
			(at 4.800092 -0.635 90)
			(size 0.508 1.524)
			(layers "F.Cu" "F.Mask" "F.Paste")
			(net "Net_2701")
		)
		(pad "14" smd rect
			(at 4.800092 -1.905 90)
			(size 0.508 1.524)
			(layers "F.Cu" "F.Mask" "F.Paste")
			(net "Net_2702")
		)
		(pad "15" smd rect
			(at 4.800092 -3.175 90)
			(size 0.508 1.524)
			(layers "F.Cu" "F.Mask" "F.Paste")
			(net "SPI_PEX2_SDIO0_MUX_R")
		)
		(pad "16" smd rect
			(at 4.800092 -4.445 90)
			(size 0.508 1.524)
			(layers "F.Cu" "F.Mask" "F.Paste")
			(net "SPI_PEX2_CLK_MUX_R")
		)
	)
	(footprint ""
		(layer "F.Cu")
		(at 278.714454 -66.32194 90)
		(property "Reference" "R5991"
			(at 0 0 90)
			(layer "F.SilkS")
			(hide yes)
			(effects
				(font
					(size 1.27 1.27)
				)
			)
		)
		(property "Value" ""
			(at 0 0 90)
			(layer "F.Fab")
			(effects
				(font
					(size 1.27 1.27)
				)
			)
		)
		(duplicate_pad_numbers_are_jumpers no)
		(fp_line
			(start 0.7874 -0.4064)
			(end 0.7874 0.4064)
			(stroke
				(width 0.1524)
				(type default)
			)
			(layer "F.SilkS")
		)
		(fp_line
			(start -0.7874 -0.4064)
			(end 0.7874 -0.4064)
			(stroke
				(width 0.1524)
				(type default)
			)
			(layer "F.SilkS")
		)
		(fp_line
			(start 0.7874 0.4064)
			(end -0.7874 0.4064)
			(stroke
				(width 0.1524)
				(type default)
			)
			(layer "F.SilkS")
		)
		(fp_line
			(start -0.7874 0.4064)
			(end -0.7874 -0.4064)
			(stroke
				(width 0.1524)
				(type default)
			)
			(layer "F.SilkS")
		)
		(fp_line
			(start -0.12065 -0.305054)
			(end -0.12065 -0.2794)
			(stroke
				(width 0.1)
				(type default)
			)
			(layer "F.Fab")
		)
		(fp_line
			(start -0.67945 -0.305054)
			(end -0.12065 -0.305054)
			(stroke
				(width 0.1)
				(type default)
			)
			(layer "F.Fab")
		)
		(fp_line
			(start 0.67945 -0.3048)
			(end 0.67945 0.3048)
			(stroke
				(width 0.1)
				(type default)
			)
			(layer "F.Fab")
		)
		(fp_line
			(start 0.12065 -0.3048)
			(end 0.67945 -0.3048)
			(stroke
				(width 0.1)
				(type default)
			)
			(layer "F.Fab")
		)
		(fp_line
			(start 0.12065 -0.2794)
			(end 0.12065 -0.3048)
			(stroke
				(width 0.1)
				(type default)
			)
			(layer "F.Fab")
		)
		(fp_line
			(start -0.12065 -0.2794)
			(end 0.12065 -0.2794)
			(stroke
				(width 0.1)
				(type default)
			)
			(layer "F.Fab")
		)
		(fp_line
			(start 0.120396 0.2794)
			(end -0.12065 0.2794)
			(stroke
				(width 0.1)
				(type default)
			)
			(layer "F.Fab")
		)
		(fp_line
			(start -0.12065 0.2794)
			(end -0.12065 0.3048)
			(stroke
				(width 0.1)
				(type default)
			)
			(layer "F.Fab")
		)
		(fp_line
			(start 0.67945 0.3048)
			(end 0.120396 0.3048)
			(stroke
				(width 0.1)
				(type default)
			)
			(layer "F.Fab")
		)
		(fp_line
			(start 0.120396 0.3048)
			(end 0.120396 0.2794)
			(stroke
				(width 0.1)
				(type default)
			)
			(layer "F.Fab")
		)
		(fp_line
			(start -0.12065 0.3048)
			(end -0.67945 0.3048)
			(stroke
				(width 0.1)
				(type default)
			)
			(layer "F.Fab")
		)
		(fp_line
			(start -0.67945 0.3048)
			(end -0.67945 -0.305054)
			(stroke
				(width 0.1)
				(type default)
			)
			(layer "F.Fab")
		)
		(pad "1" smd circle
			(at -0.40005 0 90)
			(size 0 0)
			(layers "F.Cu" "F.Mask" "F.Paste")
			(net "SSD9_PWR_EN_R")
		)
		(pad "2" smd circle
			(at 0.40005 0 90)
			(size 0 0)
			(layers "F.Cu" "F.Mask" "F.Paste")
			(net "P12V_SSD9_CO_EN")
		)
	)
	(footprint ""
		(layer "F.Cu")
		(at 134.779766 -135.62711 90)
		(property "Reference" "PD14"
			(at -3.34391 2.178304 90)
			(unlocked yes)
			(layer "F.SilkS")
			(effects
				(font
					(size 0.7874 0.5842)
					(thickness 0.1524)
				)
				(justify left)
			)
		)
		(property "Value" ""
			(at 0 0 90)
			(layer "F.Fab")
			(effects
				(font
					(size 1.27 1.27)
				)
			)
		)
		(duplicate_pad_numbers_are_jumpers no)
		(fp_line
			(start 4.107942 -1.459992)
			(end 4.107942 1.459992)
			(stroke
				(width 0.1524)
				(type default)
			)
			(layer "F.SilkS")
		)
		(fp_line
			(start -3.400044 -1.459992)
			(end 4.107942 -1.459992)
			(stroke
				(width 0.1524)
				(type default)
			)
			(layer "F.SilkS")
		)
		(fp_line
			(start 4.107942 1.459992)
			(end -3.400044 1.459992)
			(stroke
				(width 0.1524)
				(type default)
			)
			(layer "F.SilkS")
		)
		(fp_line
			(start -3.400044 1.459992)
			(end -3.400044 -1.459992)
			(stroke
				(width 0.1524)
				(type default)
			)
			(layer "F.SilkS")
		)
		(fp_poly
			(pts
				(xy 4.107942 -1.459992) (xy 4.107942 1.459992) (xy 3.308096 1.459992) (xy 3.308096 -1.459992)
			)
			(stroke
				(width 0)
				(type default)
			)
			(fill yes)
			(layer "F.SilkS")
		)
		(fp_line
			(start 2.29997 -1.459992)
			(end 2.29997 1.459992)
			(stroke
				(width 0.1)
				(type default)
			)
			(layer "F.Fab")
		)
		(fp_line
			(start -2.29997 -1.459992)
			(end 2.29997 -1.459992)
			(stroke
				(width 0.1)
				(type default)
			)
			(layer "F.Fab")
		)
		(fp_line
			(start 2.29997 1.459992)
			(end -2.29997 1.459992)
			(stroke
				(width 0.1)
				(type default)
			)
			(layer "F.Fab")
		)
		(fp_line
			(start -2.29997 1.459992)
			(end -2.29997 -1.459992)
			(stroke
				(width 0.1)
				(type default)
			)
			(layer "F.Fab")
		)
		(fp_text user "+"
			(at -4.7752 -0.12065 90)
			(unlocked yes)
			(layer "F.SilkS")
			(effects
				(font
					(size 1.905 1.4224)
					(thickness 0.1524)
				)
				(justify left)
			)
		)
		(fp_text user "-"
			(at 4.8006 2.191766 270)
			(unlocked yes)
			(layer "F.SilkS")
			(effects
				(font
					(size 1.905 1.4224)
					(thickness 0.1524)
				)
				(justify left)
			)
		)
		(fp_text user "+"
			(at -4.7752 -0.12065 90)
			(unlocked yes)
			(layer "F.Fab")
			(effects
				(font
					(size 1.905 1.4224)
					(thickness 0.1524)
				)
				(justify left)
			)
		)
		(fp_text user "-"
			(at 5.4102 0.29845 270)
			(unlocked yes)
			(layer "F.Fab")
			(effects
				(font
					(size 1.905 1.4224)
					(thickness 0.1524)
				)
				(justify left)
			)
		)
		(pad "A" smd rect
			(at -1.999996 0 180)
			(size 1.7018 2.5146)
			(layers "F.Cu" "F.Mask" "F.Paste")
			(net "GND")
		)
		(pad "C" smd rect
			(at 1.999996 0 180)
			(size 1.7018 2.5146)
			(layers "F.Cu" "F.Mask" "F.Paste")
			(net "P12V_NIC2_R")
		)
	)
	(footprint ""
		(layer "F.Cu")
		(at 437.250332 -350.098614 90)
		(property "Reference" "C798"
			(at 0 0 90)
			(layer "F.SilkS")
			(hide yes)
			(effects
				(font
					(size 1.27 1.27)
				)
			)
		)
		(property "Value" ""
			(at 0 0 90)
			(layer "F.Fab")
			(effects
				(font
					(size 1.27 1.27)
				)
			)
		)
		(duplicate_pad_numbers_are_jumpers no)
		(fp_line
			(start 0.299974 -0.150114)
			(end 0.299974 0.150114)
			(stroke
				(width 0.1)
				(type default)
			)
			(layer "F.Fab")
		)
		(fp_line
			(start -0.299974 -0.150114)
			(end 0.299974 -0.150114)
			(stroke
				(width 0.1)
				(type default)
			)
			(layer "F.Fab")
		)
		(fp_line
			(start 0.299974 0.150114)
			(end -0.299974 0.150114)
			(stroke
				(width 0.1)
				(type default)
			)
			(layer "F.Fab")
		)
		(fp_line
			(start -0.299974 0.150114)
			(end -0.299974 -0.150114)
			(stroke
				(width 0.1)
				(type default)
			)
			(layer "F.Fab")
		)
		(pad "1" smd rect
			(at -0.2667 0 90)
			(size 0.3048 0.381)
			(layers "F.Cu" "F.Mask" "F.Paste")
			(net "P5E_PEX3_STN7_TX_DP<125>")
		)
		(pad "2" smd rect
			(at 0.2667 0 90)
			(size 0.3048 0.381)
			(layers "F.Cu" "F.Mask" "F.Paste")
			(net "P5E_PEX3_STN7_TX_C_DP<125>")
		)
	)
	(footprint ""
		(layer "F.Cu")
		(at 194.559428 -22.955504 90)
		(property "Reference" "R1685"
			(at 0 0 90)
			(layer "F.SilkS")
			(hide yes)
			(effects
				(font
					(size 1.27 1.27)
				)
			)
		)
		(property "Value" ""
			(at 0 0 90)
			(layer "F.Fab")
			(effects
				(font
					(size 1.27 1.27)
				)
			)
		)
		(duplicate_pad_numbers_are_jumpers no)
		(fp_line
			(start 0.7874 -0.4064)
			(end 0.7874 0.4064)
			(stroke
				(width 0.1524)
				(type default)
			)
			(layer "F.SilkS")
		)
		(fp_line
			(start -0.7874 -0.4064)
			(end 0.7874 -0.4064)
			(stroke
				(width 0.1524)
				(type default)
			)
			(layer "F.SilkS")
		)
		(fp_line
			(start 0.7874 0.4064)
			(end -0.7874 0.4064)
			(stroke
				(width 0.1524)
				(type default)
			)
			(layer "F.SilkS")
		)
		(fp_line
			(start -0.7874 0.4064)
			(end -0.7874 -0.4064)
			(stroke
				(width 0.1524)
				(type default)
			)
			(layer "F.SilkS")
		)
		(fp_line
			(start -0.12065 -0.305054)
			(end -0.12065 -0.2794)
			(stroke
				(width 0.1)
				(type default)
			)
			(layer "F.Fab")
		)
		(fp_line
			(start -0.67945 -0.305054)
			(end -0.12065 -0.305054)
			(stroke
				(width 0.1)
				(type default)
			)
			(layer "F.Fab")
		)
		(fp_line
			(start 0.67945 -0.3048)
			(end 0.67945 0.3048)
			(stroke
				(width 0.1)
				(type default)
			)
			(layer "F.Fab")
		)
		(fp_line
			(start 0.12065 -0.3048)
			(end 0.67945 -0.3048)
			(stroke
				(width 0.1)
				(type default)
			)
			(layer "F.Fab")
		)
		(fp_line
			(start 0.12065 -0.2794)
			(end 0.12065 -0.3048)
			(stroke
				(width 0.1)
				(type default)
			)
			(layer "F.Fab")
		)
		(fp_line
			(start -0.12065 -0.2794)
			(end 0.12065 -0.2794)
			(stroke
				(width 0.1)
				(type default)
			)
			(layer "F.Fab")
		)
		(fp_line
			(start 0.120396 0.2794)
			(end -0.12065 0.2794)
			(stroke
				(width 0.1)
				(type default)
			)
			(layer "F.Fab")
		)
		(fp_line
			(start -0.12065 0.2794)
			(end -0.12065 0.3048)
			(stroke
				(width 0.1)
				(type default)
			)
			(layer "F.Fab")
		)
		(fp_line
			(start 0.67945 0.3048)
			(end 0.120396 0.3048)
			(stroke
				(width 0.1)
				(type default)
			)
			(layer "F.Fab")
		)
		(fp_line
			(start 0.120396 0.3048)
			(end 0.120396 0.2794)
			(stroke
				(width 0.1)
				(type default)
			)
			(layer "F.Fab")
		)
		(fp_line
			(start -0.12065 0.3048)
			(end -0.67945 0.3048)
			(stroke
				(width 0.1)
				(type default)
			)
			(layer "F.Fab")
		)
		(fp_line
			(start -0.67945 0.3048)
			(end -0.67945 -0.305054)
			(stroke
				(width 0.1)
				(type default)
			)
			(layer "F.Fab")
		)
		(pad "1" smd circle
			(at -0.40005 0 90)
			(size 0 0)
			(layers "F.Cu" "F.Mask" "F.Paste")
			(net "SMB_BIC_I2C9_MUX0_SSD6_R_SCL")
		)
		(pad "2" smd circle
			(at 0.40005 0 90)
			(size 0 0)
			(layers "F.Cu" "F.Mask" "F.Paste")
			(net "SMB_ISO_SSD6_SCL")
		)
	)
	(footprint ""
		(layer "F.Cu")
		(at 286.385 -83.566 180)
		(property "Reference" "R491"
			(at 0 0 180)
			(layer "F.SilkS")
			(hide yes)
			(effects
				(font
					(size 1.27 1.27)
				)
			)
		)
		(property "Value" ""
			(at 0 0 180)
			(layer "F.Fab")
			(effects
				(font
					(size 1.27 1.27)
				)
			)
		)
		(duplicate_pad_numbers_are_jumpers no)
		(fp_line
			(start 0.7874 0.4064)
			(end -0.7874 0.4064)
			(stroke
				(width 0.1524)
				(type default)
			)
			(layer "F.SilkS")
		)
		(fp_line
			(start 0.7874 -0.4064)
			(end 0.7874 0.4064)
			(stroke
				(width 0.1524)
				(type default)
			)
			(layer "F.SilkS")
		)
		(fp_line
			(start -0.7874 0.4064)
			(end -0.7874 -0.4064)
			(stroke
				(width 0.1524)
				(type default)
			)
			(layer "F.SilkS")
		)
		(fp_line
			(start -0.7874 -0.4064)
			(end 0.7874 -0.4064)
			(stroke
				(width 0.1524)
				(type default)
			)
			(layer "F.SilkS")
		)
		(fp_line
			(start 0.67945 0.3048)
			(end 0.120396 0.3048)
			(stroke
				(width 0.1)
				(type default)
			)
			(layer "F.Fab")
		)
		(fp_line
			(start 0.67945 -0.3048)
			(end 0.67945 0.3048)
			(stroke
				(width 0.1)
				(type default)
			)
			(layer "F.Fab")
		)
		(fp_line
			(start 0.12065 -0.2794)
			(end 0.12065 -0.3048)
			(stroke
				(width 0.1)
				(type default)
			)
			(layer "F.Fab")
		)
		(fp_line
			(start 0.12065 -0.3048)
			(end 0.67945 -0.3048)
			(stroke
				(width 0.1)
				(type default)
			)
			(layer "F.Fab")
		)
		(fp_line
			(start 0.120396 0.3048)
			(end 0.120396 0.2794)
			(stroke
				(width 0.1)
				(type default)
			)
			(layer "F.Fab")
		)
		(fp_line
			(start 0.120396 0.2794)
			(end -0.12065 0.2794)
			(stroke
				(width 0.1)
				(type default)
			)
			(layer "F.Fab")
		)
		(fp_line
			(start -0.12065 0.3048)
			(end -0.67945 0.3048)
			(stroke
				(width 0.1)
				(type default)
			)
			(layer "F.Fab")
		)
		(fp_line
			(start -0.12065 0.2794)
			(end -0.12065 0.3048)
			(stroke
				(width 0.1)
				(type default)
			)
			(layer "F.Fab")
		)
		(fp_line
			(start -0.12065 -0.2794)
			(end 0.12065 -0.2794)
			(stroke
				(width 0.1)
				(type default)
			)
			(layer "F.Fab")
		)
		(fp_line
			(start -0.12065 -0.305054)
			(end -0.12065 -0.2794)
			(stroke
				(width 0.1)
				(type default)
			)
			(layer "F.Fab")
		)
		(fp_line
			(start -0.67945 0.3048)
			(end -0.67945 -0.305054)
			(stroke
				(width 0.1)
				(type default)
			)
			(layer "F.Fab")
		)
		(fp_line
			(start -0.67945 -0.305054)
			(end -0.12065 -0.305054)
			(stroke
				(width 0.1)
				(type default)
			)
			(layer "F.Fab")
		)
		(pad "1" smd circle
			(at -0.40005 0 180)
			(size 0 0)
			(layers "F.Cu" "F.Mask" "F.Paste")
			(net "BB_FRU_A2")
		)
		(pad "2" smd circle
			(at 0.40005 0 180)
			(size 0 0)
			(layers "F.Cu" "F.Mask" "F.Paste")
			(net "GND")
		)
	)
	(footprint ""
		(layer "F.Cu")
		(at 488.19054 -546.564566 180)
		(property "Reference" "SCREW_SSD9_1"
			(at -5.207 -1.402334 0)
			(unlocked yes)
			(layer "B.SilkS")
			(effects
				(font
					(size 0.7874 0.5842)
					(thickness 0.1524)
				)
				(justify mirror)
			)
		)
		(property "Value" ""
			(at 0 0 180)
			(layer "F.Fab")
			(effects
				(font
					(size 1.27 1.27)
				)
			)
		)
		(duplicate_pad_numbers_are_jumpers no)
		(pad "1" thru_hole circle
			(at 0 0 180)
			(size 0.4572 0.4572)
			(drill 0.2032)
			(layers "*.Cu" "*.Mask")
			(remove_unused_layers no)
			(net "Net_9126")
			(clearance 0.127)
			(thermal_gap 0.127)
			(padstack
				(mode front_inner_back)
				(layer "Inner"
					(shape circle)
					(size 0.4572 0.4572)
					(clearance 0.127)
				)
				(layer "B.Cu"
					(shape circle)
					(size 0.508 0.508)
					(clearance 0.1016)
				)
			)
		)
	)
	(footprint ""
		(layer "F.Cu")
		(at 354.889562 -313.620404 180)
		(property "Reference" "L78"
			(at 0 0 180)
			(layer "F.SilkS")
			(hide yes)
			(effects
				(font
					(size 1.27 1.27)
				)
			)
		)
		(property "Value" ""
			(at 0 0 180)
			(layer "F.Fab")
			(effects
				(font
					(size 1.27 1.27)
				)
			)
		)
		(duplicate_pad_numbers_are_jumpers no)
		(fp_line
			(start 2.248154 4.9911)
			(end 2.248154 1.787144)
			(stroke
				(width 0.1524)
				(type default)
			)
			(layer "F.SilkS")
		)
		(fp_line
			(start 2.248154 -1.814322)
			(end 2.248154 -4.9911)
			(stroke
				(width 0.1524)
				(type default)
			)
			(layer "F.SilkS")
		)
		(fp_line
			(start 2.248154 -4.9911)
			(end -2.248154 -4.9911)
			(stroke
				(width 0.1524)
				(type default)
			)
			(layer "F.SilkS")
		)
		(fp_line
			(start -2.248154 4.9911)
			(end 2.248154 4.9911)
			(stroke
				(width 0.1524)
				(type default)
			)
			(layer "F.SilkS")
		)
		(fp_line
			(start -2.248154 1.69926)
			(end -2.248154 4.9911)
			(stroke
				(width 0.1524)
				(type default)
			)
			(layer "F.SilkS")
		)
		(fp_line
			(start -2.248154 -4.9911)
			(end -2.248154 -1.880108)
			(stroke
				(width 0.1524)
				(type default)
			)
			(layer "F.SilkS")
		)
		(fp_line
			(start 1.700022 0.899922)
			(end 1.700022 -0.899922)
			(stroke
				(width 0.1)
				(type default)
			)
			(layer "F.Fab")
		)
		(fp_line
			(start 1.700022 -0.899922)
			(end -1.700022 -0.899922)
			(stroke
				(width 0.1)
				(type default)
			)
			(layer "F.Fab")
		)
		(fp_line
			(start -1.700022 0.899922)
			(end 1.700022 0.899922)
			(stroke
				(width 0.1)
				(type default)
			)
			(layer "F.Fab")
		)
		(fp_line
			(start -1.700022 -0.899922)
			(end -1.700022 0.899922)
			(stroke
				(width 0.1)
				(type default)
			)
			(layer "F.Fab")
		)
		(pad "1" smd rect
			(at -1.575054 0 180)
			(size 1.1684 9.8044)
			(layers "F.Cu" "F.Mask" "F.Paste")
			(net "P0V8_PEX3")
		)
		(pad "2" smd rect
			(at 1.575054 0 180)
			(size 1.1684 9.8044)
			(layers "F.Cu" "F.Mask" "F.Paste")
			(net "P0V8_SERDES_VDDA_PEX3")
		)
	)
	(footprint ""
		(layer "F.Cu")
		(at 155.380436 -111.003334)
		(property "Reference" "C263"
			(at 0 0 0)
			(layer "F.SilkS")
			(hide yes)
			(effects
				(font
					(size 1.27 1.27)
				)
			)
		)
		(property "Value" ""
			(at 0 0 0)
			(layer "F.Fab")
			(effects
				(font
					(size 1.27 1.27)
				)
			)
		)
		(duplicate_pad_numbers_are_jumpers no)
		(fp_line
			(start -0.299974 -0.150114)
			(end 0.299974 -0.150114)
			(stroke
				(width 0.1)
				(type default)
			)
			(layer "F.Fab")
		)
		(fp_line
			(start -0.299974 0.150114)
			(end -0.299974 -0.150114)
			(stroke
				(width 0.1)
				(type default)
			)
			(layer "F.Fab")
		)
		(fp_line
			(start 0.299974 -0.150114)
			(end 0.299974 0.150114)
			(stroke
				(width 0.1)
				(type default)
			)
			(layer "F.Fab")
		)
		(fp_line
			(start 0.299974 0.150114)
			(end -0.299974 0.150114)
			(stroke
				(width 0.1)
				(type default)
			)
			(layer "F.Fab")
		)
		(pad "1" smd rect
			(at -0.2667 0)
			(size 0.3048 0.381)
			(layers "F.Cu" "F.Mask" "F.Paste")
			(net "P5E_PEX1_STN1_TX_DN<22>")
		)
		(pad "2" smd rect
			(at 0.2667 0)
			(size 0.3048 0.381)
			(layers "F.Cu" "F.Mask" "F.Paste")
			(net "P5E_PEX1_STN1_TX_C_DN<22>")
		)
	)
	(footprint ""
		(layer "F.Cu")
		(at 242.201954 -178.519328 -90)
		(property "Reference" "R4249"
			(at 0 0 270)
			(layer "F.SilkS")
			(hide yes)
			(effects
				(font
					(size 1.27 1.27)
				)
			)
		)
		(property "Value" ""
			(at 0 0 270)
			(layer "F.Fab")
			(effects
				(font
					(size 1.27 1.27)
				)
			)
		)
		(duplicate_pad_numbers_are_jumpers no)
		(fp_line
			(start -0.7874 0.4064)
			(end -0.7874 -0.4064)
			(stroke
				(width 0.1524)
				(type default)
			)
			(layer "F.SilkS")
		)
		(fp_line
			(start 0.7874 0.4064)
			(end -0.7874 0.4064)
			(stroke
				(width 0.1524)
				(type default)
			)
			(layer "F.SilkS")
		)
		(fp_line
			(start -0.7874 -0.4064)
			(end 0.7874 -0.4064)
			(stroke
				(width 0.1524)
				(type default)
			)
			(layer "F.SilkS")
		)
		(fp_line
			(start 0.7874 -0.4064)
			(end 0.7874 0.4064)
			(stroke
				(width 0.1524)
				(type default)
			)
			(layer "F.SilkS")
		)
		(fp_line
			(start -0.67945 0.3048)
			(end -0.67945 -0.305054)
			(stroke
				(width 0.1)
				(type default)
			)
			(layer "F.Fab")
		)
		(fp_line
			(start -0.12065 0.3048)
			(end -0.67945 0.3048)
			(stroke
				(width 0.1)
				(type default)
			)
			(layer "F.Fab")
		)
		(fp_line
			(start 0.120396 0.3048)
			(end 0.120396 0.2794)
			(stroke
				(width 0.1)
				(type default)
			)
			(layer "F.Fab")
		)
		(fp_line
			(start 0.67945 0.3048)
			(end 0.120396 0.3048)
			(stroke
				(width 0.1)
				(type default)
			)
			(layer "F.Fab")
		)
		(fp_line
			(start -0.12065 0.2794)
			(end -0.12065 0.3048)
			(stroke
				(width 0.1)
				(type default)
			)
			(layer "F.Fab")
		)
		(fp_line
			(start 0.120396 0.2794)
			(end -0.12065 0.2794)
			(stroke
				(width 0.1)
				(type default)
			)
			(layer "F.Fab")
		)
		(fp_line
			(start -0.12065 -0.2794)
			(end 0.12065 -0.2794)
			(stroke
				(width 0.1)
				(type default)
			)
			(layer "F.Fab")
		)
		(fp_line
			(start 0.12065 -0.2794)
			(end 0.12065 -0.3048)
			(stroke
				(width 0.1)
				(type default)
			)
			(layer "F.Fab")
		)
		(fp_line
			(start 0.12065 -0.3048)
			(end 0.67945 -0.3048)
			(stroke
				(width 0.1)
				(type default)
			)
			(layer "F.Fab")
		)
		(fp_line
			(start 0.67945 -0.3048)
			(end 0.67945 0.3048)
			(stroke
				(width 0.1)
				(type default)
			)
			(layer "F.Fab")
		)
		(fp_line
			(start -0.67945 -0.305054)
			(end -0.12065 -0.305054)
			(stroke
				(width 0.1)
				(type default)
			)
			(layer "F.Fab")
		)
		(fp_line
			(start -0.12065 -0.305054)
			(end -0.12065 -0.2794)
			(stroke
				(width 0.1)
				(type default)
			)
			(layer "F.Fab")
		)
		(pad "1" smd circle
			(at -0.40005 0 270)
			(size 0 0)
			(layers "F.Cu" "F.Mask" "F.Paste")
			(net "BIC_RST_PWRGD_RSMRST_R")
		)
		(pad "2" smd circle
			(at 0.40005 0 270)
			(size 0 0)
			(layers "F.Cu" "F.Mask" "F.Paste")
			(net "BIC_RST_PWRGD_RSMRST")
		)
	)
	(footprint ""
		(layer "F.Cu")
		(at 154.860244 -117.7544 180)
		(property "Reference" "R108"
			(at 0 0 180)
			(layer "F.SilkS")
			(hide yes)
			(effects
				(font
					(size 1.27 1.27)
				)
			)
		)
		(property "Value" ""
			(at 0 0 180)
			(layer "F.Fab")
			(effects
				(font
					(size 1.27 1.27)
				)
			)
		)
		(duplicate_pad_numbers_are_jumpers no)
		(fp_line
			(start 0.7874 0.4064)
			(end -0.7874 0.4064)
			(stroke
				(width 0.1524)
				(type default)
			)
			(layer "F.SilkS")
		)
		(fp_line
			(start 0.7874 -0.4064)
			(end 0.7874 0.4064)
			(stroke
				(width 0.1524)
				(type default)
			)
			(layer "F.SilkS")
		)
		(fp_line
			(start -0.7874 0.4064)
			(end -0.7874 -0.4064)
			(stroke
				(width 0.1524)
				(type default)
			)
			(layer "F.SilkS")
		)
		(fp_line
			(start -0.7874 -0.4064)
			(end 0.7874 -0.4064)
			(stroke
				(width 0.1524)
				(type default)
			)
			(layer "F.SilkS")
		)
		(fp_line
			(start 0.67945 0.3048)
			(end 0.120396 0.3048)
			(stroke
				(width 0.1)
				(type default)
			)
			(layer "F.Fab")
		)
		(fp_line
			(start 0.67945 -0.3048)
			(end 0.67945 0.3048)
			(stroke
				(width 0.1)
				(type default)
			)
			(layer "F.Fab")
		)
		(fp_line
			(start 0.12065 -0.2794)
			(end 0.12065 -0.3048)
			(stroke
				(width 0.1)
				(type default)
			)
			(layer "F.Fab")
		)
		(fp_line
			(start 0.12065 -0.3048)
			(end 0.67945 -0.3048)
			(stroke
				(width 0.1)
				(type default)
			)
			(layer "F.Fab")
		)
		(fp_line
			(start 0.120396 0.3048)
			(end 0.120396 0.2794)
			(stroke
				(width 0.1)
				(type default)
			)
			(layer "F.Fab")
		)
		(fp_line
			(start 0.120396 0.2794)
			(end -0.12065 0.2794)
			(stroke
				(width 0.1)
				(type default)
			)
			(layer "F.Fab")
		)
		(fp_line
			(start -0.12065 0.3048)
			(end -0.67945 0.3048)
			(stroke
				(width 0.1)
				(type default)
			)
			(layer "F.Fab")
		)
		(fp_line
			(start -0.12065 0.2794)
			(end -0.12065 0.3048)
			(stroke
				(width 0.1)
				(type default)
			)
			(layer "F.Fab")
		)
		(fp_line
			(start -0.12065 -0.2794)
			(end 0.12065 -0.2794)
			(stroke
				(width 0.1)
				(type default)
			)
			(layer "F.Fab")
		)
		(fp_line
			(start -0.12065 -0.305054)
			(end -0.12065 -0.2794)
			(stroke
				(width 0.1)
				(type default)
			)
			(layer "F.Fab")
		)
		(fp_line
			(start -0.67945 0.3048)
			(end -0.67945 -0.305054)
			(stroke
				(width 0.1)
				(type default)
			)
			(layer "F.Fab")
		)
		(fp_line
			(start -0.67945 -0.305054)
			(end -0.12065 -0.305054)
			(stroke
				(width 0.1)
				(type default)
			)
			(layer "F.Fab")
		)
		(pad "1" smd circle
			(at -0.40005 0 180)
			(size 0 0)
			(layers "F.Cu" "F.Mask" "F.Paste")
			(net "PRSNTB0_NIC2_N")
		)
		(pad "2" smd circle
			(at 0.40005 0 180)
			(size 0 0)
			(layers "F.Cu" "F.Mask" "F.Paste")
			(net "P3V3_AUX")
		)
	)
	(footprint ""
		(layer "F.Cu")
		(at 444.908178 -223.316546 180)
		(property "Reference" "R6610"
			(at 0 0 180)
			(layer "F.SilkS")
			(hide yes)
			(effects
				(font
					(size 1.27 1.27)
				)
			)
		)
		(property "Value" ""
			(at 0 0 180)
			(layer "F.Fab")
			(effects
				(font
					(size 1.27 1.27)
				)
			)
		)
		(duplicate_pad_numbers_are_jumpers no)
		(fp_line
			(start 0.7874 0.4064)
			(end -0.7874 0.4064)
			(stroke
				(width 0.1524)
				(type default)
			)
			(layer "F.SilkS")
		)
		(fp_line
			(start 0.7874 -0.4064)
			(end 0.7874 0.4064)
			(stroke
				(width 0.1524)
				(type default)
			)
			(layer "F.SilkS")
		)
		(fp_line
			(start -0.7874 0.4064)
			(end -0.7874 -0.4064)
			(stroke
				(width 0.1524)
				(type default)
			)
			(layer "F.SilkS")
		)
		(fp_line
			(start -0.7874 -0.4064)
			(end 0.7874 -0.4064)
			(stroke
				(width 0.1524)
				(type default)
			)
			(layer "F.SilkS")
		)
		(fp_line
			(start 0.67945 0.3048)
			(end 0.120396 0.3048)
			(stroke
				(width 0.1)
				(type default)
			)
			(layer "F.Fab")
		)
		(fp_line
			(start 0.67945 -0.3048)
			(end 0.67945 0.3048)
			(stroke
				(width 0.1)
				(type default)
			)
			(layer "F.Fab")
		)
		(fp_line
			(start 0.12065 -0.2794)
			(end 0.12065 -0.3048)
			(stroke
				(width 0.1)
				(type default)
			)
			(layer "F.Fab")
		)
		(fp_line
			(start 0.12065 -0.3048)
			(end 0.67945 -0.3048)
			(stroke
				(width 0.1)
				(type default)
			)
			(layer "F.Fab")
		)
		(fp_line
			(start 0.120396 0.3048)
			(end 0.120396 0.2794)
			(stroke
				(width 0.1)
				(type default)
			)
			(layer "F.Fab")
		)
		(fp_line
			(start 0.120396 0.2794)
			(end -0.12065 0.2794)
			(stroke
				(width 0.1)
				(type default)
			)
			(layer "F.Fab")
		)
		(fp_line
			(start -0.12065 0.3048)
			(end -0.67945 0.3048)
			(stroke
				(width 0.1)
				(type default)
			)
			(layer "F.Fab")
		)
		(fp_line
			(start -0.12065 0.2794)
			(end -0.12065 0.3048)
			(stroke
				(width 0.1)
				(type default)
			)
			(layer "F.Fab")
		)
		(fp_line
			(start -0.12065 -0.2794)
			(end 0.12065 -0.2794)
			(stroke
				(width 0.1)
				(type default)
			)
			(layer "F.Fab")
		)
		(fp_line
			(start -0.12065 -0.305054)
			(end -0.12065 -0.2794)
			(stroke
				(width 0.1)
				(type default)
			)
			(layer "F.Fab")
		)
		(fp_line
			(start -0.67945 0.3048)
			(end -0.67945 -0.305054)
			(stroke
				(width 0.1)
				(type default)
			)
			(layer "F.Fab")
		)
		(fp_line
			(start -0.67945 -0.305054)
			(end -0.12065 -0.305054)
			(stroke
				(width 0.1)
				(type default)
			)
			(layer "F.Fab")
		)
		(pad "1" smd circle
			(at -0.40005 0 180)
			(size 0 0)
			(layers "F.Cu" "F.Mask" "F.Paste")
			(net "UART_PEX2_SDB_CP2108_RX")
		)
		(pad "2" smd circle
			(at 0.40005 0 180)
			(size 0 0)
			(layers "F.Cu" "F.Mask" "F.Paste")
			(net "UART_PEX2_SDB_R_RX")
		)
	)
	(footprint ""
		(layer "F.Cu")
		(at 268.838426 -120.113298)
		(property "Reference" "C470"
			(at 0 0 0)
			(layer "F.SilkS")
			(hide yes)
			(effects
				(font
					(size 1.27 1.27)
				)
			)
		)
		(property "Value" ""
			(at 0 0 0)
			(layer "F.Fab")
			(effects
				(font
					(size 1.27 1.27)
				)
			)
		)
		(duplicate_pad_numbers_are_jumpers no)
		(fp_line
			(start -0.299974 -0.150114)
			(end 0.299974 -0.150114)
			(stroke
				(width 0.1)
				(type default)
			)
			(layer "F.Fab")
		)
		(fp_line
			(start -0.299974 0.150114)
			(end -0.299974 -0.150114)
			(stroke
				(width 0.1)
				(type default)
			)
			(layer "F.Fab")
		)
		(fp_line
			(start 0.299974 -0.150114)
			(end 0.299974 0.150114)
			(stroke
				(width 0.1)
				(type default)
			)
			(layer "F.Fab")
		)
		(fp_line
			(start 0.299974 0.150114)
			(end -0.299974 0.150114)
			(stroke
				(width 0.1)
				(type default)
			)
			(layer "F.Fab")
		)
		(pad "1" smd rect
			(at -0.2667 0)
			(size 0.3048 0.381)
			(layers "F.Cu" "F.Mask" "F.Paste")
			(net "P5E_PEX2_STN1_TX_DN<24>")
		)
		(pad "2" smd rect
			(at 0.2667 0)
			(size 0.3048 0.381)
			(layers "F.Cu" "F.Mask" "F.Paste")
			(net "P5E_PEX2_STN1_TX_C_DN<24>")
		)
	)
	(footprint ""
		(layer "F.Cu")
		(at 393.826746 -55.418228 90)
		(property "Reference" "PC418"
			(at 0 0 90)
			(layer "F.SilkS")
			(hide yes)
			(effects
				(font
					(size 1.27 1.27)
				)
			)
		)
		(property "Value" ""
			(at 0 0 90)
			(layer "F.Fab")
			(effects
				(font
					(size 1.27 1.27)
				)
			)
		)
		(duplicate_pad_numbers_are_jumpers no)
		(fp_line
			(start 0.7874 -0.4064)
			(end 0.7874 0.4064)
			(stroke
				(width 0.1524)
				(type default)
			)
			(layer "F.SilkS")
		)
		(fp_line
			(start -0.7874 -0.4064)
			(end 0.7874 -0.4064)
			(stroke
				(width 0.1524)
				(type default)
			)
			(layer "F.SilkS")
		)
		(fp_line
			(start 0.7874 0.4064)
			(end -0.7874 0.4064)
			(stroke
				(width 0.1524)
				(type default)
			)
			(layer "F.SilkS")
		)
		(fp_line
			(start -0.7874 0.4064)
			(end -0.7874 -0.4064)
			(stroke
				(width 0.1524)
				(type default)
			)
			(layer "F.SilkS")
		)
		(fp_line
			(start -0.12065 -0.305054)
			(end -0.12065 -0.2794)
			(stroke
				(width 0.1)
				(type default)
			)
			(layer "F.Fab")
		)
		(fp_line
			(start -0.67945 -0.305054)
			(end -0.12065 -0.305054)
			(stroke
				(width 0.1)
				(type default)
			)
			(layer "F.Fab")
		)
		(fp_line
			(start 0.67945 -0.3048)
			(end 0.67945 0.3048)
			(stroke
				(width 0.1)
				(type default)
			)
			(layer "F.Fab")
		)
		(fp_line
			(start 0.12065 -0.3048)
			(end 0.67945 -0.3048)
			(stroke
				(width 0.1)
				(type default)
			)
			(layer "F.Fab")
		)
		(fp_line
			(start 0.12065 -0.2794)
			(end 0.12065 -0.3048)
			(stroke
				(width 0.1)
				(type default)
			)
			(layer "F.Fab")
		)
		(fp_line
			(start -0.12065 -0.2794)
			(end 0.12065 -0.2794)
			(stroke
				(width 0.1)
				(type default)
			)
			(layer "F.Fab")
		)
		(fp_line
			(start 0.120396 0.2794)
			(end -0.12065 0.2794)
			(stroke
				(width 0.1)
				(type default)
			)
			(layer "F.Fab")
		)
		(fp_line
			(start -0.12065 0.2794)
			(end -0.12065 0.3048)
			(stroke
				(width 0.1)
				(type default)
			)
			(layer "F.Fab")
		)
		(fp_line
			(start 0.67945 0.3048)
			(end 0.120396 0.3048)
			(stroke
				(width 0.1)
				(type default)
			)
			(layer "F.Fab")
		)
		(fp_line
			(start 0.120396 0.3048)
			(end 0.120396 0.2794)
			(stroke
				(width 0.1)
				(type default)
			)
			(layer "F.Fab")
		)
		(fp_line
			(start -0.12065 0.3048)
			(end -0.67945 0.3048)
			(stroke
				(width 0.1)
				(type default)
			)
			(layer "F.Fab")
		)
		(fp_line
			(start -0.67945 0.3048)
			(end -0.67945 -0.305054)
			(stroke
				(width 0.1)
				(type default)
			)
			(layer "F.Fab")
		)
		(pad "1" smd circle
			(at -0.40005 0 90)
			(size 0 0)
			(layers "F.Cu" "F.Mask" "F.Paste")
			(net "P12V_SSD13_R")
		)
		(pad "2" smd circle
			(at 0.40005 0 90)
			(size 0 0)
			(layers "F.Cu" "F.Mask" "F.Paste")
			(net "GND")
		)
	)
	(footprint ""
		(layer "F.Cu")
		(at 106.441494 -293.5351 90)
		(property "Reference" "PL6"
			(at -4.298442 29.039566 90)
			(unlocked yes)
			(layer "F.SilkS")
			(effects
				(font
					(size 0.7874 0.5842)
					(thickness 0.1524)
				)
				(justify left)
			)
		)
		(property "Value" ""
			(at 0 0 90)
			(layer "F.Fab")
			(effects
				(font
					(size 1.27 1.27)
				)
			)
		)
		(duplicate_pad_numbers_are_jumpers no)
		(fp_line
			(start 4.800092 -3.199892)
			(end 4.800092 -1.6764)
			(stroke
				(width 0.1524)
				(type default)
			)
			(layer "F.SilkS")
		)
		(fp_line
			(start -4.800092 -3.199892)
			(end 4.800092 -3.199892)
			(stroke
				(width 0.1524)
				(type default)
			)
			(layer "F.SilkS")
		)
		(fp_line
			(start -4.800092 -1.6764)
			(end -4.800092 -3.199892)
			(stroke
				(width 0.1524)
				(type default)
			)
			(layer "F.SilkS")
		)
		(fp_line
			(start 4.800092 1.6764)
			(end 4.800092 3.199892)
			(stroke
				(width 0.1524)
				(type default)
			)
			(layer "F.SilkS")
		)
		(fp_line
			(start 4.800092 3.199892)
			(end -4.800092 3.199892)
			(stroke
				(width 0.1524)
				(type default)
			)
			(layer "F.SilkS")
		)
		(fp_line
			(start -4.800092 3.199892)
			(end -4.800092 1.6764)
			(stroke
				(width 0.1524)
				(type default)
			)
			(layer "F.SilkS")
		)
		(fp_line
			(start 4.800092 -3.199892)
			(end 4.800092 3.199892)
			(stroke
				(width 0.1)
				(type default)
			)
			(layer "F.Fab")
		)
		(fp_line
			(start -4.800092 -3.199892)
			(end 4.800092 -3.199892)
			(stroke
				(width 0.1)
				(type default)
			)
			(layer "F.Fab")
		)
		(fp_line
			(start 4.800092 3.199892)
			(end -4.800092 3.199892)
			(stroke
				(width 0.1)
				(type default)
			)
			(layer "F.Fab")
		)
		(fp_line
			(start -4.800092 3.199892)
			(end -4.800092 -3.199892)
			(stroke
				(width 0.1)
				(type default)
			)
			(layer "F.Fab")
		)
		(pad "1" smd rect
			(at -3.074924 0 180)
			(size 3.0988 3.3528)
			(layers "F.Cu" "F.Mask" "F.Paste")
			(net "SW_P0V8_PEX0_PH1")
		)
		(pad "2" smd rect
			(at 3.074924 0 180)
			(size 3.0988 3.3528)
			(layers "F.Cu" "F.Mask" "F.Paste")
			(net "P0V8_PEX0")
		)
	)
	(footprint ""
		(layer "F.Cu")
		(at 144.149318 -287.395412 -90)
		(property "Reference" "C3208"
			(at 0 0 270)
			(layer "F.SilkS")
			(hide yes)
			(effects
				(font
					(size 1.27 1.27)
				)
			)
		)
		(property "Value" ""
			(at 0 0 270)
			(layer "F.Fab")
			(effects
				(font
					(size 1.27 1.27)
				)
			)
		)
		(duplicate_pad_numbers_are_jumpers no)
		(fp_line
			(start -0.299974 0.150114)
			(end -0.299974 -0.150114)
			(stroke
				(width 0.1)
				(type default)
			)
			(layer "F.Fab")
		)
		(fp_line
			(start 0.299974 0.150114)
			(end -0.299974 0.150114)
			(stroke
				(width 0.1)
				(type default)
			)
			(layer "F.Fab")
		)
		(fp_line
			(start -0.299974 -0.150114)
			(end 0.299974 -0.150114)
			(stroke
				(width 0.1)
				(type default)
			)
			(layer "F.Fab")
		)
		(fp_line
			(start 0.299974 -0.150114)
			(end 0.299974 0.150114)
			(stroke
				(width 0.1)
				(type default)
			)
			(layer "F.Fab")
		)
		(pad "1" smd rect
			(at -0.2667 0 270)
			(size 0.3048 0.381)
			(layers "F.Cu" "F.Mask" "F.Paste")
			(net "P1V8_PLL0_PEX1")
		)
		(pad "2" smd rect
			(at 0.2667 0 270)
			(size 0.3048 0.381)
			(layers "F.Cu" "F.Mask" "F.Paste")
			(net "GND")
		)
	)
	(footprint ""
		(layer "F.Cu")
		(at 344.511884 -111.531654)
		(property "Reference" "PR7037"
			(at 0 0 0)
			(layer "F.SilkS")
			(hide yes)
			(effects
				(font
					(size 1.27 1.27)
				)
			)
		)
		(property "Value" ""
			(at 0 0 0)
			(layer "F.Fab")
			(effects
				(font
					(size 1.27 1.27)
				)
			)
		)
		(duplicate_pad_numbers_are_jumpers no)
		(fp_line
			(start -0.7874 -0.4064)
			(end 0.7874 -0.4064)
			(stroke
				(width 0.1524)
				(type default)
			)
			(layer "F.SilkS")
		)
		(fp_line
			(start -0.7874 0.4064)
			(end -0.7874 -0.4064)
			(stroke
				(width 0.1524)
				(type default)
			)
			(layer "F.SilkS")
		)
		(fp_line
			(start 0.7874 -0.4064)
			(end 0.7874 0.4064)
			(stroke
				(width 0.1524)
				(type default)
			)
			(layer "F.SilkS")
		)
		(fp_line
			(start 0.7874 0.4064)
			(end -0.7874 0.4064)
			(stroke
				(width 0.1524)
				(type default)
			)
			(layer "F.SilkS")
		)
		(fp_line
			(start -0.67945 -0.305054)
			(end -0.12065 -0.305054)
			(stroke
				(width 0.1)
				(type default)
			)
			(layer "F.Fab")
		)
		(fp_line
			(start -0.67945 0.3048)
			(end -0.67945 -0.305054)
			(stroke
				(width 0.1)
				(type default)
			)
			(layer "F.Fab")
		)
		(fp_line
			(start -0.12065 -0.305054)
			(end -0.12065 -0.2794)
			(stroke
				(width 0.1)
				(type default)
			)
			(layer "F.Fab")
		)
		(fp_line
			(start -0.12065 -0.2794)
			(end 0.12065 -0.2794)
			(stroke
				(width 0.1)
				(type default)
			)
			(layer "F.Fab")
		)
		(fp_line
			(start -0.12065 0.2794)
			(end -0.12065 0.3048)
			(stroke
				(width 0.1)
				(type default)
			)
			(layer "F.Fab")
		)
		(fp_line
			(start -0.12065 0.3048)
			(end -0.67945 0.3048)
			(stroke
				(width 0.1)
				(type default)
			)
			(layer "F.Fab")
		)
		(fp_line
			(start 0.120396 0.2794)
			(end -0.12065 0.2794)
			(stroke
				(width 0.1)
				(type default)
			)
			(layer "F.Fab")
		)
		(fp_line
			(start 0.120396 0.3048)
			(end 0.120396 0.2794)
			(stroke
				(width 0.1)
				(type default)
			)
			(layer "F.Fab")
		)
		(fp_line
			(start 0.12065 -0.3048)
			(end 0.67945 -0.3048)
			(stroke
				(width 0.1)
				(type default)
			)
			(layer "F.Fab")
		)
		(fp_line
			(start 0.12065 -0.2794)
			(end 0.12065 -0.3048)
			(stroke
				(width 0.1)
				(type default)
			)
			(layer "F.Fab")
		)
		(fp_line
			(start 0.67945 -0.3048)
			(end 0.67945 0.3048)
			(stroke
				(width 0.1)
				(type default)
			)
			(layer "F.Fab")
		)
		(fp_line
			(start 0.67945 0.3048)
			(end 0.120396 0.3048)
			(stroke
				(width 0.1)
				(type default)
			)
			(layer "F.Fab")
		)
		(pad "1" smd circle
			(at -0.40005 0)
			(size 0 0)
			(layers "F.Cu" "F.Mask" "F.Paste")
			(net "P12V_NIC5_CO_ISET")
		)
		(pad "2" smd circle
			(at 0.40005 0)
			(size 0 0)
			(layers "F.Cu" "F.Mask" "F.Paste")
			(net "GND")
		)
	)
	(footprint ""
		(layer "F.Cu")
		(at 291.84981 -295.89984)
		(property "Reference" "PEX2"
			(at -3.35153 35.56762 0)
			(unlocked yes)
			(layer "F.SilkS")
			(effects
				(font
					(size 2.032 1.524)
					(thickness 0.1524)
				)
				(justify left)
			)
		)
		(property "Value" ""
			(at 0 0 0)
			(layer "F.Fab")
			(effects
				(font
					(size 1.27 1.27)
				)
			)
		)
		(duplicate_pad_numbers_are_jumpers no)
		(fp_line
			(start -23.750016 -23.750016)
			(end -23.750016 23.750016)
			(stroke
				(width 0.1524)
				(type default)
			)
			(layer "F.SilkS")
		)
		(fp_line
			(start -23.750016 23.750016)
			(end 23.750016 23.750016)
			(stroke
				(width 0.1524)
				(type default)
			)
			(layer "F.SilkS")
		)
		(fp_line
			(start 23.750016 -23.750016)
			(end -23.750016 -23.750016)
			(stroke
				(width 0.1524)
				(type default)
			)
			(layer "F.SilkS")
		)
		(fp_line
			(start 23.750016 23.750016)
			(end 23.750016 -23.750016)
			(stroke
				(width 0.1524)
				(type default)
			)
			(layer "F.SilkS")
		)
		(fp_poly
			(pts
				(xy -21.850096 -23.750016) (xy -21.850096 -24.512016) (xy -24.512016 -24.512016) (xy -24.512016 -21.850096)
				(xy -23.750016 -21.850096) (xy -23.750016 -23.750016)
			)
			(stroke
				(width 0)
				(type default)
			)
			(fill yes)
			(layer "F.SilkS")
		)
		(fp_line
			(start -23.750016 -23.750016)
			(end -23.750016 23.750016)
			(stroke
				(width 0.1)
				(type default)
			)
			(layer "F.Fab")
		)
		(fp_line
			(start -23.750016 23.750016)
			(end 23.750016 23.750016)
			(stroke
				(width 0.1)
				(type default)
			)
			(layer "F.Fab")
		)
		(fp_line
			(start 23.750016 -23.750016)
			(end -23.750016 -23.750016)
			(stroke
				(width 0.1)
				(type default)
			)
			(layer "F.Fab")
		)
		(fp_line
			(start 23.750016 23.750016)
			(end 23.750016 -23.750016)
			(stroke
				(width 0.1)
				(type default)
			)
			(layer "F.Fab")
		)
		(fp_poly
			(pts
				(xy -21.850096 -23.750016) (xy -21.850096 -24.512016) (xy -24.512016 -24.512016) (xy -24.512016 -21.850096)
				(xy -23.750016 -21.850096) (xy -23.750016 -23.750016)
			)
			(stroke
				(width 0)
				(type default)
			)
			(fill yes)
			(layer "F.Fab")
		)
		(pad "A2" smd circle
			(at -21.850096 -22.800056)
			(size 0.4572 0.4572)
			(layers "F.Cu" "F.Mask" "F.Paste")
			(net "GND")
		)
		(pad "A3" smd circle
			(at -20.899882 -22.800056)
			(size 0.4572 0.4572)
			(layers "F.Cu" "F.Mask" "F.Paste")
			(net "P5E_PEX2_STN7_RX_DN<123>")
		)
		(pad "A4" smd circle
			(at -19.949922 -22.800056)
			(size 0.4572 0.4572)
			(layers "F.Cu" "F.Mask" "F.Paste")
			(net "GND")
		)
		(pad "A5" smd circle
			(at -18.999962 -22.800056)
			(size 0.4572 0.4572)
			(layers "F.Cu" "F.Mask" "F.Paste")
			(net "P5E_PEX2_STN7_RX_DN<125>")
		)
		(pad "A6" smd circle
			(at -18.050002 -22.800056)
			(size 0.4572 0.4572)
			(layers "F.Cu" "F.Mask" "F.Paste")
			(net "GND")
		)
		(pad "A7" smd circle
			(at -17.100042 -22.800056)
			(size 0.4572 0.4572)
			(layers "F.Cu" "F.Mask" "F.Paste")
			(net "P5E_PEX2_STN7_RX_DN<127>")
		)
		(pad "A8" smd circle
			(at -16.150082 -22.800056)
			(size 0.4572 0.4572)
			(layers "F.Cu" "F.Mask" "F.Paste")
			(net "GND")
		)
		(pad "A9" smd circle
			(at -15.200122 -22.800056)
			(size 0.4572 0.4572)
			(layers "F.Cu" "F.Mask" "F.Paste")
			(net "P5E_PEX2_STN6_RX_DN<110>")
		)
		(pad "A10" smd circle
			(at -14.249908 -22.800056)
			(size 0.4572 0.4572)
			(layers "F.Cu" "F.Mask" "F.Paste")
			(net "GND")
		)
		(pad "A11" smd circle
			(at -13.299948 -22.800056)
			(size 0.4572 0.4572)
			(layers "F.Cu" "F.Mask" "F.Paste")
			(net "P5E_PEX2_STN6_RX_DN<108>")
		)
		(pad "A12" smd circle
			(at -12.349988 -22.800056)
			(size 0.4572 0.4572)
			(layers "F.Cu" "F.Mask" "F.Paste")
			(net "GND")
		)
		(pad "A13" smd circle
			(at -11.400028 -22.800056)
			(size 0.4572 0.4572)
			(layers "F.Cu" "F.Mask" "F.Paste")
			(net "P5E_PEX2_STN6_RX_DN<106>")
		)
		(pad "A14" smd circle
			(at -10.450068 -22.800056)
			(size 0.4572 0.4572)
			(layers "F.Cu" "F.Mask" "F.Paste")
			(net "GND")
		)
		(pad "A15" smd circle
			(at -9.500108 -22.800056)
			(size 0.4572 0.4572)
			(layers "F.Cu" "F.Mask" "F.Paste")
			(net "P5E_PEX2_STN6_RX_DN<104>")
		)
		(pad "A16" smd circle
			(at -8.549894 -22.800056)
			(size 0.4572 0.4572)
			(layers "F.Cu" "F.Mask" "F.Paste")
			(net "GND")
		)
		(pad "A17" smd circle
			(at -7.599934 -22.800056)
			(size 0.4572 0.4572)
			(layers "F.Cu" "F.Mask" "F.Paste")
			(net "P5E_PEX2_STN6_RX_DN<102>")
		)
		(pad "A18" smd circle
			(at -6.649974 -22.800056)
			(size 0.4572 0.4572)
			(layers "F.Cu" "F.Mask" "F.Paste")
			(net "GND")
		)
		(pad "A19" smd circle
			(at -5.700014 -22.800056)
			(size 0.4572 0.4572)
			(layers "F.Cu" "F.Mask" "F.Paste")
			(net "P5E_PEX2_STN6_RX_DN<100>")
		)
		(pad "A20" smd circle
			(at -4.750054 -22.800056)
			(size 0.4572 0.4572)
			(layers "F.Cu" "F.Mask" "F.Paste")
			(net "GND")
		)
		(pad "A21" smd circle
			(at -3.800094 -22.800056)
			(size 0.4572 0.4572)
			(layers "F.Cu" "F.Mask" "F.Paste")
			(net "P5E_PEX2_STN6_RX_DN<98>")
		)
		(pad "A22" smd circle
			(at -2.84988 -22.800056)
			(size 0.4572 0.4572)
			(layers "F.Cu" "F.Mask" "F.Paste")
			(net "GND")
		)
		(pad "A23" smd circle
			(at -1.89992 -22.800056)
			(size 0.4572 0.4572)
			(layers "F.Cu" "F.Mask" "F.Paste")
			(net "P5E_PEX2_STN6_RX_DN<96>")
		)
		(pad "A24" smd circle
			(at -0.94996 -22.800056)
			(size 0.4572 0.4572)
			(layers "F.Cu" "F.Mask" "F.Paste")
			(net "GND")
		)
		(pad "A25" smd circle
			(at 0 -22.800056)
			(size 0.4572 0.4572)
			(layers "F.Cu" "F.Mask" "F.Paste")
			(net "P5E_PEX2_STN5_RX_DN<81>")
		)
		(pad "A26" smd circle
			(at 0.94996 -22.800056)
			(size 0.4572 0.4572)
			(layers "F.Cu" "F.Mask" "F.Paste")
			(net "GND")
		)
		(pad "A27" smd circle
			(at 1.89992 -22.800056)
			(size 0.4572 0.4572)
			(layers "F.Cu" "F.Mask" "F.Paste")
			(net "P5E_PEX2_STN5_RX_DN<83>")
		)
		(pad "A28" smd circle
			(at 2.84988 -22.800056)
			(size 0.4572 0.4572)
			(layers "F.Cu" "F.Mask" "F.Paste")
			(net "GND")
		)
		(pad "A29" smd circle
			(at 3.800094 -22.800056)
			(size 0.4572 0.4572)
			(layers "F.Cu" "F.Mask" "F.Paste")
			(net "P5E_PEX2_STN5_RX_DN<85>")
		)
		(pad "A30" smd circle
			(at 4.750054 -22.800056)
			(size 0.4572 0.4572)
			(layers "F.Cu" "F.Mask" "F.Paste")
			(net "GND")
		)
		(pad "A31" smd circle
			(at 5.700014 -22.800056)
			(size 0.4572 0.4572)
			(layers "F.Cu" "F.Mask" "F.Paste")
			(net "P5E_PEX2_STN5_RX_DN<87>")
		)
		(pad "A32" smd circle
			(at 6.649974 -22.800056)
			(size 0.4572 0.4572)
			(layers "F.Cu" "F.Mask" "F.Paste")
			(net "GND")
		)
		(pad "A33" smd circle
			(at 7.599934 -22.800056)
			(size 0.4572 0.4572)
			(layers "F.Cu" "F.Mask" "F.Paste")
			(net "P5E_PEX2_STN5_RX_DN<89>")
		)
		(pad "A34" smd circle
			(at 8.549894 -22.800056)
			(size 0.4572 0.4572)
			(layers "F.Cu" "F.Mask" "F.Paste")
			(net "GND")
		)
		(pad "A35" smd circle
			(at 9.500108 -22.800056)
			(size 0.4572 0.4572)
			(layers "F.Cu" "F.Mask" "F.Paste")
			(net "P5E_PEX2_STN5_RX_DN<91>")
		)
		(pad "A36" smd circle
			(at 10.450068 -22.800056)
			(size 0.4572 0.4572)
			(layers "F.Cu" "F.Mask" "F.Paste")
			(net "GND")
		)
		(pad "A37" smd circle
			(at 11.400028 -22.800056)
			(size 0.4572 0.4572)
			(layers "F.Cu" "F.Mask" "F.Paste")
			(net "P5E_PEX2_STN5_RX_DN<93>")
		)
		(pad "A38" smd circle
			(at 12.349988 -22.800056)
			(size 0.4572 0.4572)
			(layers "F.Cu" "F.Mask" "F.Paste")
			(net "GND")
		)
		(pad "A39" smd circle
			(at 13.299948 -22.800056)
			(size 0.4572 0.4572)
			(layers "F.Cu" "F.Mask" "F.Paste")
			(net "P5E_PEX2_STN5_RX_DN<95>")
		)
		(pad "A40" smd circle
			(at 14.249908 -22.800056)
			(size 0.4572 0.4572)
			(layers "F.Cu" "F.Mask" "F.Paste")
			(net "GND")
		)
		(pad "A41" smd circle
			(at 15.200122 -22.800056)
			(size 0.4572 0.4572)
			(layers "F.Cu" "F.Mask" "F.Paste")
			(net "P5E_PEX2_STN4_RX_DN<78>")
		)
		(pad "A42" smd circle
			(at 16.150082 -22.800056)
			(size 0.4572 0.4572)
			(layers "F.Cu" "F.Mask" "F.Paste")
			(net "GND")
		)
		(pad "A43" smd circle
			(at 17.100042 -22.800056)
			(size 0.4572 0.4572)
			(layers "F.Cu" "F.Mask" "F.Paste")
			(net "P5E_PEX2_STN4_RX_DN<76>")
		)
		(pad "A44" smd circle
			(at 18.050002 -22.800056)
			(size 0.4572 0.4572)
			(layers "F.Cu" "F.Mask" "F.Paste")
			(net "GND")
		)
		(pad "A45" smd circle
			(at 18.999962 -22.800056)
			(size 0.4572 0.4572)
			(layers "F.Cu" "F.Mask" "F.Paste")
			(net "P5E_PEX2_STN4_RX_DN<74>")
		)
		(pad "A46" smd circle
			(at 19.949922 -22.800056)
			(size 0.4572 0.4572)
			(layers "F.Cu" "F.Mask" "F.Paste")
			(net "GND")
		)
		(pad "A47" smd circle
			(at 20.899882 -22.800056)
			(size 0.4572 0.4572)
			(layers "F.Cu" "F.Mask" "F.Paste")
			(net "P5E_PEX2_STN4_RX_DN<72>")
		)
		(pad "A48" smd circle
			(at 21.850096 -22.800056)
			(size 0.4572 0.4572)
			(layers "F.Cu" "F.Mask" "F.Paste")
			(net "GND")
		)
		(pad "AA1" smd circle
			(at -22.800056 -3.800094)
			(size 0.4572 0.4572)
			(layers "F.Cu" "F.Mask" "F.Paste")
			(net "CLK_100M_PEX2_REF_R_DN")
		)
		(pad "AA2" smd circle
			(at -21.850096 -3.800094)
			(size 0.4572 0.4572)
			(layers "F.Cu" "F.Mask" "F.Paste")
			(net "CLK_100M_PEX2_REF_R_DP")
		)
		(pad "AA3" smd circle
			(at -20.899882 -3.800094)
			(size 0.4572 0.4572)
			(layers "F.Cu" "F.Mask" "F.Paste")
			(net "GND")
		)
		(pad "AA4" smd circle
			(at -19.949922 -3.800094)
			(size 0.4572 0.4572)
			(layers "F.Cu" "F.Mask" "F.Paste")
			(net "GND")
		)
		(pad "AA5" smd circle
			(at -18.999962 -3.800094)
			(size 0.4572 0.4572)
			(layers "F.Cu" "F.Mask" "F.Paste")
			(net "GND")
		)
		(pad "AA6" smd circle
			(at -18.050002 -3.800094)
			(size 0.4572 0.4572)
			(layers "F.Cu" "F.Mask" "F.Paste")
			(net "GND")
		)
		(pad "AA7" smd circle
			(at -17.100042 -3.800094)
			(size 0.4572 0.4572)
			(layers "F.Cu" "F.Mask" "F.Paste")
			(net "GND")
		)
		(pad "AA8" smd circle
			(at -16.150082 -3.800094)
			(size 0.4572 0.4572)
			(layers "F.Cu" "F.Mask" "F.Paste")
			(net "GND")
		)
		(pad "AA9" smd circle
			(at -15.200122 -3.800094)
			(size 0.4572 0.4572)
			(layers "F.Cu" "F.Mask" "F.Paste")
			(net "GND")
		)
		(pad "AA10" smd circle
			(at -14.249908 -3.800094)
			(size 0.4572 0.4572)
			(layers "F.Cu" "F.Mask" "F.Paste")
			(net "P1V8_VDDA_PEX2")
		)
		(pad "AA11" smd circle
			(at -13.299948 -3.800094)
			(size 0.4572 0.4572)
			(layers "F.Cu" "F.Mask" "F.Paste")
			(net "GND")
		)
		(pad "AA12" smd circle
			(at -12.349988 -3.800094)
			(size 0.4572 0.4572)
			(layers "F.Cu" "F.Mask" "F.Paste")
			(net "GND")
		)
		(pad "AA13" smd circle
			(at -11.400028 -3.800094)
			(size 0.4572 0.4572)
			(layers "F.Cu" "F.Mask" "F.Paste")
			(net "PCEPLL0_VDDA18_PEX2")
		)
		(pad "AA14" smd circle
			(at -10.450068 -3.800094)
			(size 0.4572 0.4572)
			(layers "F.Cu" "F.Mask" "F.Paste")
			(net "GND")
		)
		(pad "AA15" smd circle
			(at -9.500108 -3.800094)
			(size 0.4572 0.4572)
			(layers "F.Cu" "F.Mask" "F.Paste")
			(net "P0V8_PEX2")
		)
		(pad "AA16" smd circle
			(at -8.549894 -3.800094)
			(size 0.4572 0.4572)
			(layers "F.Cu" "F.Mask" "F.Paste")
			(net "GND")
		)
		(pad "AA17" smd circle
			(at -7.599934 -3.800094)
			(size 0.4572 0.4572)
			(layers "F.Cu" "F.Mask" "F.Paste")
			(net "GND")
		)
		(pad "AA18" smd circle
			(at -6.649974 -3.800094)
			(size 0.4572 0.4572)
			(layers "F.Cu" "F.Mask" "F.Paste")
			(net "GND")
		)
		(pad "AA19" smd circle
			(at -5.700014 -3.800094)
			(size 0.4572 0.4572)
			(layers "F.Cu" "F.Mask" "F.Paste")
			(net "GND")
		)
		(pad "AA20" smd circle
			(at -4.750054 -3.800094)
			(size 0.4572 0.4572)
			(layers "F.Cu" "F.Mask" "F.Paste")
			(net "GND")
		)
		(pad "AA21" smd circle
			(at -3.800094 -3.800094)
			(size 0.4572 0.4572)
			(layers "F.Cu" "F.Mask" "F.Paste")
			(net "GND")
		)
		(pad "AA22" smd circle
			(at -2.84988 -3.800094)
			(size 0.4572 0.4572)
			(layers "F.Cu" "F.Mask" "F.Paste")
			(net "GND")
		)
		(pad "AA23" smd circle
			(at -1.89992 -3.800094)
			(size 0.4572 0.4572)
			(layers "F.Cu" "F.Mask" "F.Paste")
			(net "GND")
		)
		(pad "AA24" smd circle
			(at -0.94996 -3.800094)
			(size 0.4572 0.4572)
			(layers "F.Cu" "F.Mask" "F.Paste")
			(net "GND")
		)
		(pad "AA25" smd circle
			(at 0 -3.800094)
			(size 0.4572 0.4572)
			(layers "F.Cu" "F.Mask" "F.Paste")
			(net "GND")
		)
		(pad "AA26" smd circle
			(at 0.94996 -3.800094)
			(size 0.4572 0.4572)
			(layers "F.Cu" "F.Mask" "F.Paste")
			(net "GND")
		)
		(pad "AA27" smd circle
			(at 1.89992 -3.800094)
			(size 0.4572 0.4572)
			(layers "F.Cu" "F.Mask" "F.Paste")
			(net "GND")
		)
		(pad "AA28" smd circle
			(at 2.84988 -3.800094)
			(size 0.4572 0.4572)
			(layers "F.Cu" "F.Mask" "F.Paste")
			(net "GND")
		)
		(pad "AA29" smd circle
			(at 3.800094 -3.800094)
			(size 0.4572 0.4572)
			(layers "F.Cu" "F.Mask" "F.Paste")
			(net "GND")
		)
		(pad "AA30" smd circle
			(at 4.750054 -3.800094)
			(size 0.4572 0.4572)
			(layers "F.Cu" "F.Mask" "F.Paste")
			(net "GND")
		)
		(pad "AA31" smd circle
			(at 5.700014 -3.800094)
			(size 0.4572 0.4572)
			(layers "F.Cu" "F.Mask" "F.Paste")
			(net "GND")
		)
		(pad "AA32" smd circle
			(at 6.649974 -3.800094)
			(size 0.4572 0.4572)
			(layers "F.Cu" "F.Mask" "F.Paste")
			(net "GND")
		)
		(pad "AA33" smd circle
			(at 7.599934 -3.800094)
			(size 0.4572 0.4572)
			(layers "F.Cu" "F.Mask" "F.Paste")
			(net "GND")
		)
		(pad "AA34" smd circle
			(at 8.549894 -3.800094)
			(size 0.4572 0.4572)
			(layers "F.Cu" "F.Mask" "F.Paste")
			(net "P1V8_VDDA_PEX2")
		)
		(pad "AA35" smd circle
			(at 9.500108 -3.800094)
			(size 0.4572 0.4572)
			(layers "F.Cu" "F.Mask" "F.Paste")
			(net "Net_516")
		)
		(pad "AA36" smd circle
			(at 10.450068 -3.800094)
			(size 0.4572 0.4572)
			(layers "F.Cu" "F.Mask" "F.Paste")
			(net "GND")
		)
		(pad "AA37" smd circle
			(at 11.400028 -3.800094)
			(size 0.4572 0.4572)
			(layers "F.Cu" "F.Mask" "F.Paste")
			(net "P1V8_VDDA_PEX2")
		)
		(pad "AA38" smd circle
			(at 12.349988 -3.800094)
			(size 0.4572 0.4572)
			(layers "F.Cu" "F.Mask" "F.Paste")
			(net "GND")
		)
		(pad "AA39" smd circle
			(at 13.299948 -3.800094)
			(size 0.4572 0.4572)
			(layers "F.Cu" "F.Mask" "F.Paste")
			(net "PEX2_ADCTEMP_VINP1")
		)
		(pad "AA40" smd circle
			(at 14.249908 -3.800094)
			(size 0.4572 0.4572)
			(layers "F.Cu" "F.Mask" "F.Paste")
			(net "GND")
		)
		(pad "AA41" smd circle
			(at 15.200122 -3.800094)
			(size 0.4572 0.4572)
			(layers "F.Cu" "F.Mask" "F.Paste")
			(net "GND")
		)
		(pad "AA42" smd circle
			(at 16.150082 -3.800094)
			(size 0.4572 0.4572)
			(layers "F.Cu" "F.Mask" "F.Paste")
			(net "GND")
		)
		(pad "AA43" smd circle
			(at 17.100042 -3.800094)
			(size 0.4572 0.4572)
			(layers "F.Cu" "F.Mask" "F.Paste")
			(net "Net_1681")
		)
		(pad "AA44" smd circle
			(at 18.050002 -3.800094)
			(size 0.4572 0.4572)
			(layers "F.Cu" "F.Mask" "F.Paste")
			(net "Net_1694")
		)
		(pad "AA45" smd circle
			(at 18.999962 -3.800094)
			(size 0.4572 0.4572)
			(layers "F.Cu" "F.Mask" "F.Paste")
			(net "GND")
		)
		(pad "AA46" smd circle
			(at 19.949922 -3.800094)
			(size 0.4572 0.4572)
			(layers "F.Cu" "F.Mask" "F.Paste")
			(net "Net_1562")
		)
		(pad "AA47" smd circle
			(at 20.899882 -3.800094)
			(size 0.4572 0.4572)
			(layers "F.Cu" "F.Mask" "F.Paste")
			(net "Net_1581")
		)
		(pad "AA48" smd circle
			(at 21.850096 -3.800094)
			(size 0.4572 0.4572)
			(layers "F.Cu" "F.Mask" "F.Paste")
			(net "GND")
		)
		(pad "AA49" smd circle
			(at 22.800056 -3.800094)
			(size 0.4572 0.4572)
			(layers "F.Cu" "F.Mask" "F.Paste")
			(net "GND")
		)
		(pad "AB1" smd circle
			(at -22.800056 -2.84988)
			(size 0.4572 0.4572)
			(layers "F.Cu" "F.Mask" "F.Paste")
			(net "GND")
		)
		(pad "AB2" smd circle
			(at -21.850096 -2.84988)
			(size 0.4572 0.4572)
			(layers "F.Cu" "F.Mask" "F.Paste")
			(net "GND")
		)
		(pad "AB3" smd circle
			(at -20.899882 -2.84988)
			(size 0.4572 0.4572)
			(layers "F.Cu" "F.Mask" "F.Paste")
			(net "GND")
		)
		(pad "AB4" smd circle
			(at -19.949922 -2.84988)
			(size 0.4572 0.4572)
			(layers "F.Cu" "F.Mask" "F.Paste")
			(net "CLK_100M_DB800ZL_PEX2_S0_R_DN")
		)
		(pad "AB5" smd circle
			(at -18.999962 -2.84988)
			(size 0.4572 0.4572)
			(layers "F.Cu" "F.Mask" "F.Paste")
			(net "CLK_100M_DB800ZL_PEX2_S0_R_DP")
		)
		(pad "AB6" smd circle
			(at -18.050002 -2.84988)
			(size 0.4572 0.4572)
			(layers "F.Cu" "F.Mask" "F.Paste")
			(net "GND")
		)
		(pad "AB7" smd circle
			(at -17.100042 -2.84988)
			(size 0.4572 0.4572)
			(layers "F.Cu" "F.Mask" "F.Paste")
			(net "Net_5396")
		)
		(pad "AB8" smd circle
			(at -16.150082 -2.84988)
			(size 0.4572 0.4572)
			(layers "F.Cu" "F.Mask" "F.Paste")
			(net "Net_5395")
		)
		(pad "AB9" smd circle
			(at -15.200122 -2.84988)
			(size 0.4572 0.4572)
			(layers "F.Cu" "F.Mask" "F.Paste")
			(net "GND")
		)
		(pad "AB10" smd circle
			(at -14.249908 -2.84988)
			(size 0.4572 0.4572)
			(layers "F.Cu" "F.Mask" "F.Paste")
			(net "P1V8_VDDA_PEX2")
		)
		(pad "AB11" smd circle
			(at -13.299948 -2.84988)
			(size 0.4572 0.4572)
			(layers "F.Cu" "F.Mask" "F.Paste")
			(net "GND")
		)
		(pad "AB12" smd circle
			(at -12.349988 -2.84988)
			(size 0.4572 0.4572)
			(layers "F.Cu" "F.Mask" "F.Paste")
			(net "PCEPLL1_VDDA18_PEX2")
		)
		(pad "AB13" smd circle
			(at -11.400028 -2.84988)
			(size 0.4572 0.4572)
			(layers "F.Cu" "F.Mask" "F.Paste")
			(net "GND")
		)
		(pad "AB14" smd circle
			(at -10.450068 -2.84988)
			(size 0.4572 0.4572)
			(layers "F.Cu" "F.Mask" "F.Paste")
			(net "P0V8_PEX2")
		)
		(pad "AB15" smd circle
			(at -9.500108 -2.84988)
			(size 0.4572 0.4572)
			(layers "F.Cu" "F.Mask" "F.Paste")
			(net "GND")
		)
		(pad "AB16" smd circle
			(at -8.549894 -2.84988)
			(size 0.4572 0.4572)
			(layers "F.Cu" "F.Mask" "F.Paste")
			(net "P0V8_SERDES_VDDA_PEX2")
		)
		(pad "AB17" smd circle
			(at -7.599934 -2.84988)
			(size 0.4572 0.4572)
			(layers "F.Cu" "F.Mask" "F.Paste")
			(net "P0V8_SERDES_VDDA_PEX2")
		)
		(pad "AB18" smd circle
			(at -6.649974 -2.84988)
			(size 0.4572 0.4572)
			(layers "F.Cu" "F.Mask" "F.Paste")
			(net "P0V8_SERDES_VDDA_PEX2")
		)
		(pad "AB19" smd circle
			(at -5.700014 -2.84988)
			(size 0.4572 0.4572)
			(layers "F.Cu" "F.Mask" "F.Paste")
			(net "P0V8_SERDES_VDDA_PEX2")
		)
		(pad "AB20" smd circle
			(at -4.750054 -2.84988)
			(size 0.4572 0.4572)
			(layers "F.Cu" "F.Mask" "F.Paste")
			(net "P0V8_SERDES_VDDA_PEX2")
		)
		(pad "AB21" smd circle
			(at -3.800094 -2.84988)
			(size 0.4572 0.4572)
			(layers "F.Cu" "F.Mask" "F.Paste")
			(net "P0V8_SERDES_VDDA_PEX2")
		)
		(pad "AB22" smd circle
			(at -2.84988 -2.84988)
			(size 0.4572 0.4572)
			(layers "F.Cu" "F.Mask" "F.Paste")
			(net "P0V8_SERDES_VDDA_PEX2")
		)
		(pad "AB23" smd circle
			(at -1.89992 -2.84988)
			(size 0.4572 0.4572)
			(layers "F.Cu" "F.Mask" "F.Paste")
			(net "P0V8_SERDES_VDDA_PEX2")
		)
		(pad "AB24" smd circle
			(at -0.94996 -2.84988)
			(size 0.4572 0.4572)
			(layers "F.Cu" "F.Mask" "F.Paste")
			(net "P0V8_SERDES_VDDA_PEX2")
		)
		(pad "AB25" smd circle
			(at 0 -2.84988)
			(size 0.4572 0.4572)
			(layers "F.Cu" "F.Mask" "F.Paste")
			(net "P0V8_SERDES_VDDA_PEX2")
		)
		(pad "AB26" smd circle
			(at 0.94996 -2.84988)
			(size 0.4572 0.4572)
			(layers "F.Cu" "F.Mask" "F.Paste")
			(net "P0V8_SERDES_VDDA_PEX2")
		)
		(pad "AB27" smd circle
			(at 1.89992 -2.84988)
			(size 0.4572 0.4572)
			(layers "F.Cu" "F.Mask" "F.Paste")
			(net "P0V8_SERDES_VDDA_PEX2")
		)
		(pad "AB28" smd circle
			(at 2.84988 -2.84988)
			(size 0.4572 0.4572)
			(layers "F.Cu" "F.Mask" "F.Paste")
			(net "P0V8_SERDES_VDDA_PEX2")
		)
		(pad "AB29" smd circle
			(at 3.800094 -2.84988)
			(size 0.4572 0.4572)
			(layers "F.Cu" "F.Mask" "F.Paste")
			(net "P0V8_SERDES_VDDA_PEX2")
		)
		(pad "AB30" smd circle
			(at 4.750054 -2.84988)
			(size 0.4572 0.4572)
			(layers "F.Cu" "F.Mask" "F.Paste")
			(net "P0V8_SERDES_VDDA_PEX2")
		)
		(pad "AB31" smd circle
			(at 5.700014 -2.84988)
			(size 0.4572 0.4572)
			(layers "F.Cu" "F.Mask" "F.Paste")
			(net "P0V8_SERDES_VDDA_PEX2")
		)
		(pad "AB32" smd circle
			(at 6.649974 -2.84988)
			(size 0.4572 0.4572)
			(layers "F.Cu" "F.Mask" "F.Paste")
			(net "P0V8_SERDES_VDDA_PEX2")
		)
		(pad "AB33" smd circle
			(at 7.599934 -2.84988)
			(size 0.4572 0.4572)
			(layers "F.Cu" "F.Mask" "F.Paste")
			(net "P0V8_SERDES_VDDA_PEX2")
		)
		(pad "AB34" smd circle
			(at 8.549894 -2.84988)
			(size 0.4572 0.4572)
			(layers "F.Cu" "F.Mask" "F.Paste")
			(net "GND")
		)
		(pad "AB35" smd circle
			(at 9.500108 -2.84988)
			(size 0.4572 0.4572)
			(layers "F.Cu" "F.Mask" "F.Paste")
			(net "Net_524")
		)
		(pad "AB36" smd circle
			(at 10.450068 -2.84988)
			(size 0.4572 0.4572)
			(layers "F.Cu" "F.Mask" "F.Paste")
			(net "GND")
		)
		(pad "AB37" smd circle
			(at 11.400028 -2.84988)
			(size 0.4572 0.4572)
			(layers "F.Cu" "F.Mask" "F.Paste")
			(net "GND")
		)
		(pad "AB38" smd circle
			(at 12.349988 -2.84988)
			(size 0.4572 0.4572)
			(layers "F.Cu" "F.Mask" "F.Paste")
			(net "GND")
		)
		(pad "AB39" smd circle
			(at 13.299948 -2.84988)
			(size 0.4572 0.4572)
			(layers "F.Cu" "F.Mask" "F.Paste")
			(net "GND")
		)
		(pad "AB40" smd circle
			(at 14.249908 -2.84988)
			(size 0.4572 0.4572)
			(layers "F.Cu" "F.Mask" "F.Paste")
			(net "GND")
		)
		(pad "AB41" smd circle
			(at 15.200122 -2.84988)
			(size 0.4572 0.4572)
			(layers "F.Cu" "F.Mask" "F.Paste")
			(net "Net_1671")
		)
		(pad "AB42" smd circle
			(at 16.150082 -2.84988)
			(size 0.4572 0.4572)
			(layers "F.Cu" "F.Mask" "F.Paste")
			(net "Net_1696")
		)
		(pad "AB43" smd circle
			(at 17.100042 -2.84988)
			(size 0.4572 0.4572)
			(layers "F.Cu" "F.Mask" "F.Paste")
			(net "GND")
		)
		(pad "AB44" smd circle
			(at 18.050002 -2.84988)
			(size 0.4572 0.4572)
			(layers "F.Cu" "F.Mask" "F.Paste")
			(net "GND")
		)
		(pad "AB45" smd circle
			(at 18.999962 -2.84988)
			(size 0.4572 0.4572)
			(layers "F.Cu" "F.Mask" "F.Paste")
			(net "GND")
		)
		(pad "AB46" smd circle
			(at 19.949922 -2.84988)
			(size 0.4572 0.4572)
			(layers "F.Cu" "F.Mask" "F.Paste")
			(net "GND")
		)
		(pad "AB47" smd circle
			(at 20.899882 -2.84988)
			(size 0.4572 0.4572)
			(layers "F.Cu" "F.Mask" "F.Paste")
			(net "GND")
		)
		(pad "AB48" smd circle
			(at 21.850096 -2.84988)
			(size 0.4572 0.4572)
			(layers "F.Cu" "F.Mask" "F.Paste")
			(net "Net_1564")
		)
		(pad "AB49" smd circle
			(at 22.800056 -2.84988)
			(size 0.4572 0.4572)
			(layers "F.Cu" "F.Mask" "F.Paste")
			(net "Net_1636")
		)
		(pad "AC1" smd circle
			(at -22.800056 -1.89992)
			(size 0.4572 0.4572)
			(layers "F.Cu" "F.Mask" "F.Paste")
			(net "CLK_100M_DB2000QL_PEX2_S1_R_DN")
		)
		(pad "AC2" smd circle
			(at -21.850096 -1.89992)
			(size 0.4572 0.4572)
			(layers "F.Cu" "F.Mask" "F.Paste")
			(net "CLK_100M_DB2000QL_PEX2_S1_R_DP")
		)
		(pad "AC3" smd circle
			(at -20.899882 -1.89992)
			(size 0.4572 0.4572)
			(layers "F.Cu" "F.Mask" "F.Paste")
			(net "GND")
		)
		(pad "AC4" smd circle
			(at -19.949922 -1.89992)
			(size 0.4572 0.4572)
			(layers "F.Cu" "F.Mask" "F.Paste")
			(net "GND")
		)
		(pad "AC5" smd circle
			(at -18.999962 -1.89992)
			(size 0.4572 0.4572)
			(layers "F.Cu" "F.Mask" "F.Paste")
			(net "GND")
		)
		(pad "AC6" smd circle
			(at -18.050002 -1.89992)
			(size 0.4572 0.4572)
			(layers "F.Cu" "F.Mask" "F.Paste")
			(net "GND")
		)
		(pad "AC7" smd circle
			(at -17.100042 -1.89992)
			(size 0.4572 0.4572)
			(layers "F.Cu" "F.Mask" "F.Paste")
			(net "Net_5398")
		)
		(pad "AC8" smd circle
			(at -16.150082 -1.89992)
			(size 0.4572 0.4572)
			(layers "F.Cu" "F.Mask" "F.Paste")
			(net "Net_5400")
		)
		(pad "AC9" smd circle
			(at -15.200122 -1.89992)
			(size 0.4572 0.4572)
			(layers "F.Cu" "F.Mask" "F.Paste")
			(net "GND")
		)
		(pad "AC10" smd circle
			(at -14.249908 -1.89992)
			(size 0.4572 0.4572)
			(layers "F.Cu" "F.Mask" "F.Paste")
			(net "P1V8_VDDA_PEX2")
		)
		(pad "AC11" smd circle
			(at -13.299948 -1.89992)
			(size 0.4572 0.4572)
			(layers "F.Cu" "F.Mask" "F.Paste")
			(net "GND")
		)
		(pad "AC12" smd circle
			(at -12.349988 -1.89992)
			(size 0.4572 0.4572)
			(layers "F.Cu" "F.Mask" "F.Paste")
			(net "GND")
		)
		(pad "AC13" smd circle
			(at -11.400028 -1.89992)
			(size 0.4572 0.4572)
			(layers "F.Cu" "F.Mask" "F.Paste")
			(net "SYSPLL_VDDA18_PEX2")
		)
		(pad "AC14" smd circle
			(at -10.450068 -1.89992)
			(size 0.4572 0.4572)
			(layers "F.Cu" "F.Mask" "F.Paste")
			(net "GND")
		)
		(pad "AC15" smd circle
			(at -9.500108 -1.89992)
			(size 0.4572 0.4572)
			(layers "F.Cu" "F.Mask" "F.Paste")
			(net "P0V8_PEX2")
		)
		(pad "AC16" smd circle
			(at -8.549894 -1.89992)
			(size 0.4572 0.4572)
			(layers "F.Cu" "F.Mask" "F.Paste")
			(net "GND")
		)
		(pad "AC17" smd circle
			(at -7.599934 -1.89992)
			(size 0.4572 0.4572)
			(layers "F.Cu" "F.Mask" "F.Paste")
			(net "P0V8_PEX2")
		)
		(pad "AC18" smd circle
			(at -6.649974 -1.89992)
			(size 0.4572 0.4572)
			(layers "F.Cu" "F.Mask" "F.Paste")
			(net "GND")
		)
		(pad "AC19" smd circle
			(at -5.700014 -1.89992)
			(size 0.4572 0.4572)
			(layers "F.Cu" "F.Mask" "F.Paste")
			(net "P0V8_PEX2")
		)
		(pad "AC20" smd circle
			(at -4.750054 -1.89992)
			(size 0.4572 0.4572)
			(layers "F.Cu" "F.Mask" "F.Paste")
			(net "GND")
		)
		(pad "AC21" smd circle
			(at -3.800094 -1.89992)
			(size 0.4572 0.4572)
			(layers "F.Cu" "F.Mask" "F.Paste")
			(net "P0V8_PEX2")
		)
		(pad "AC22" smd circle
			(at -2.84988 -1.89992)
			(size 0.4572 0.4572)
			(layers "F.Cu" "F.Mask" "F.Paste")
			(net "GND")
		)
		(pad "AC23" smd circle
			(at -1.89992 -1.89992)
			(size 0.4572 0.4572)
			(layers "F.Cu" "F.Mask" "F.Paste")
			(net "P0V8_PEX2")
		)
		(pad "AC24" smd circle
			(at -0.94996 -1.89992)
			(size 0.4572 0.4572)
			(layers "F.Cu" "F.Mask" "F.Paste")
			(net "GND")
		)
		(pad "AC25" smd circle
			(at 0 -1.89992)
			(size 0.4572 0.4572)
			(layers "F.Cu" "F.Mask" "F.Paste")
			(net "P0V8_PEX2")
		)
		(pad "AC26" smd circle
			(at 0.94996 -1.89992)
			(size 0.4572 0.4572)
			(layers "F.Cu" "F.Mask" "F.Paste")
			(net "GND")
		)
		(pad "AC27" smd circle
			(at 1.89992 -1.89992)
			(size 0.4572 0.4572)
			(layers "F.Cu" "F.Mask" "F.Paste")
			(net "P0V8_PEX2")
		)
		(pad "AC28" smd circle
			(at 2.84988 -1.89992)
			(size 0.4572 0.4572)
			(layers "F.Cu" "F.Mask" "F.Paste")
			(net "GND")
		)
		(pad "AC29" smd circle
			(at 3.800094 -1.89992)
			(size 0.4572 0.4572)
			(layers "F.Cu" "F.Mask" "F.Paste")
			(net "P0V8_PEX2")
		)
		(pad "AC30" smd circle
			(at 4.750054 -1.89992)
			(size 0.4572 0.4572)
			(layers "F.Cu" "F.Mask" "F.Paste")
			(net "GND")
		)
		(pad "AC31" smd circle
			(at 5.700014 -1.89992)
			(size 0.4572 0.4572)
			(layers "F.Cu" "F.Mask" "F.Paste")
			(net "P0V8_PEX2")
		)
		(pad "AC32" smd circle
			(at 6.649974 -1.89992)
			(size 0.4572 0.4572)
			(layers "F.Cu" "F.Mask" "F.Paste")
			(net "GND")
		)
		(pad "AC33" smd circle
			(at 7.599934 -1.89992)
			(size 0.4572 0.4572)
			(layers "F.Cu" "F.Mask" "F.Paste")
			(net "P0V8_PEX2")
		)
		(pad "AC34" smd circle
			(at 8.549894 -1.89992)
			(size 0.4572 0.4572)
			(layers "F.Cu" "F.Mask" "F.Paste")
			(net "GND")
		)
		(pad "AC35" smd circle
			(at 9.500108 -1.89992)
			(size 0.4572 0.4572)
			(layers "F.Cu" "F.Mask" "F.Paste")
			(net "GND")
		)
		(pad "AC36" smd circle
			(at 10.450068 -1.89992)
			(size 0.4572 0.4572)
			(layers "F.Cu" "F.Mask" "F.Paste")
			(net "P1V25_PEX2")
		)
		(pad "AC37" smd circle
			(at 11.400028 -1.89992)
			(size 0.4572 0.4572)
			(layers "F.Cu" "F.Mask" "F.Paste")
			(net "GND")
		)
		(pad "AC38" smd circle
			(at 12.349988 -1.89992)
			(size 0.4572 0.4572)
			(layers "F.Cu" "F.Mask" "F.Paste")
			(net "P1V25_SERDES_VDDPLL_PEX2")
		)
		(pad "AC39" smd circle
			(at 13.299948 -1.89992)
			(size 0.4572 0.4572)
			(layers "F.Cu" "F.Mask" "F.Paste")
			(net "GND")
		)
		(pad "AC40" smd circle
			(at 14.249908 -1.89992)
			(size 0.4572 0.4572)
			(layers "F.Cu" "F.Mask" "F.Paste")
			(net "GND")
		)
		(pad "AC41" smd circle
			(at 15.200122 -1.89992)
			(size 0.4572 0.4572)
			(layers "F.Cu" "F.Mask" "F.Paste")
			(net "GND")
		)
		(pad "AC42" smd circle
			(at 16.150082 -1.89992)
			(size 0.4572 0.4572)
			(layers "F.Cu" "F.Mask" "F.Paste")
			(net "GND")
		)
		(pad "AC43" smd circle
			(at 17.100042 -1.89992)
			(size 0.4572 0.4572)
			(layers "F.Cu" "F.Mask" "F.Paste")
			(net "Net_1701")
		)
		(pad "AC44" smd circle
			(at 18.050002 -1.89992)
			(size 0.4572 0.4572)
			(layers "F.Cu" "F.Mask" "F.Paste")
			(net "Net_1692")
		)
		(pad "AC45" smd circle
			(at 18.999962 -1.89992)
			(size 0.4572 0.4572)
			(layers "F.Cu" "F.Mask" "F.Paste")
			(net "GND")
		)
		(pad "AC46" smd circle
			(at 19.949922 -1.89992)
			(size 0.4572 0.4572)
			(layers "F.Cu" "F.Mask" "F.Paste")
			(net "Net_1609")
		)
		(pad "AC47" smd circle
			(at 20.899882 -1.89992)
			(size 0.4572 0.4572)
			(layers "F.Cu" "F.Mask" "F.Paste")
			(net "Net_1625")
		)
		(pad "AC48" smd circle
			(at 21.850096 -1.89992)
			(size 0.4572 0.4572)
			(layers "F.Cu" "F.Mask" "F.Paste")
			(net "GND")
		)
		(pad "AC49" smd circle
			(at 22.800056 -1.89992)
			(size 0.4572 0.4572)
			(layers "F.Cu" "F.Mask" "F.Paste")
			(net "GND")
		)
		(pad "AD1" smd circle
			(at -22.800056 -0.94996)
			(size 0.4572 0.4572)
			(layers "F.Cu" "F.Mask" "F.Paste")
			(net "GND")
		)
		(pad "AD2" smd circle
			(at -21.850096 -0.94996)
			(size 0.4572 0.4572)
			(layers "F.Cu" "F.Mask" "F.Paste")
			(net "GND")
		)
		(pad "AD3" smd circle
			(at -20.899882 -0.94996)
			(size 0.4572 0.4572)
			(layers "F.Cu" "F.Mask" "F.Paste")
			(net "GND")
		)
		(pad "AD4" smd circle
			(at -19.949922 -0.94996)
			(size 0.4572 0.4572)
			(layers "F.Cu" "F.Mask" "F.Paste")
			(net "Net_382")
		)
		(pad "AD5" smd circle
			(at -18.999962 -0.94996)
			(size 0.4572 0.4572)
			(layers "F.Cu" "F.Mask" "F.Paste")
			(net "Net_383")
		)
		(pad "AD6" smd circle
			(at -18.050002 -0.94996)
			(size 0.4572 0.4572)
			(layers "F.Cu" "F.Mask" "F.Paste")
			(net "GND")
		)
		(pad "AD7" smd circle
			(at -17.100042 -0.94996)
			(size 0.4572 0.4572)
			(layers "F.Cu" "F.Mask" "F.Paste")
			(net "Net_5397")
		)
		(pad "AD8" smd circle
			(at -16.150082 -0.94996)
			(size 0.4572 0.4572)
			(layers "F.Cu" "F.Mask" "F.Paste")
			(net "Net_5399")
		)
		(pad "AD9" smd circle
			(at -15.200122 -0.94996)
			(size 0.4572 0.4572)
			(layers "F.Cu" "F.Mask" "F.Paste")
			(net "GND")
		)
		(pad "AD10" smd circle
			(at -14.249908 -0.94996)
			(size 0.4572 0.4572)
			(layers "F.Cu" "F.Mask" "F.Paste")
			(net "GND")
		)
		(pad "AD11" smd circle
			(at -13.299948 -0.94996)
			(size 0.4572 0.4572)
			(layers "F.Cu" "F.Mask" "F.Paste")
			(net "GND")
		)
		(pad "AD12" smd circle
			(at -12.349988 -0.94996)
			(size 0.4572 0.4572)
			(layers "F.Cu" "F.Mask" "F.Paste")
			(net "PCEPLL2_VDDA18_PEX2")
		)
		(pad "AD13" smd circle
			(at -11.400028 -0.94996)
			(size 0.4572 0.4572)
			(layers "F.Cu" "F.Mask" "F.Paste")
			(net "GND")
		)
		(pad "AD14" smd circle
			(at -10.450068 -0.94996)
			(size 0.4572 0.4572)
			(layers "F.Cu" "F.Mask" "F.Paste")
			(net "P0V8_PEX2")
		)
		(pad "AD15" smd circle
			(at -9.500108 -0.94996)
			(size 0.4572 0.4572)
			(layers "F.Cu" "F.Mask" "F.Paste")
			(net "GND")
		)
		(pad "AD16" smd circle
			(at -8.549894 -0.94996)
			(size 0.4572 0.4572)
			(layers "F.Cu" "F.Mask" "F.Paste")
			(net "P0V8_PEX2")
		)
		(pad "AD17" smd circle
			(at -7.599934 -0.94996)
			(size 0.4572 0.4572)
			(layers "F.Cu" "F.Mask" "F.Paste")
			(net "GND")
		)
		(pad "AD18" smd circle
			(at -6.649974 -0.94996)
			(size 0.4572 0.4572)
			(layers "F.Cu" "F.Mask" "F.Paste")
			(net "P0V8_PEX2")
		)
		(pad "AD19" smd circle
			(at -5.700014 -0.94996)
			(size 0.4572 0.4572)
			(layers "F.Cu" "F.Mask" "F.Paste")
			(net "GND")
		)
		(pad "AD20" smd circle
			(at -4.750054 -0.94996)
			(size 0.4572 0.4572)
			(layers "F.Cu" "F.Mask" "F.Paste")
			(net "P0V8_PEX2")
		)
		(pad "AD21" smd circle
			(at -3.800094 -0.94996)
			(size 0.4572 0.4572)
			(layers "F.Cu" "F.Mask" "F.Paste")
			(net "GND")
		)
		(pad "AD22" smd circle
			(at -2.84988 -0.94996)
			(size 0.4572 0.4572)
			(layers "F.Cu" "F.Mask" "F.Paste")
			(net "P0V8_PEX2")
		)
		(pad "AD23" smd circle
			(at -1.89992 -0.94996)
			(size 0.4572 0.4572)
			(layers "F.Cu" "F.Mask" "F.Paste")
			(net "GND")
		)
		(pad "AD24" smd circle
			(at -0.94996 -0.94996)
			(size 0.4572 0.4572)
			(layers "F.Cu" "F.Mask" "F.Paste")
			(net "P0V8_PEX2")
		)
		(pad "AD25" smd circle
			(at 0 -0.94996)
			(size 0.4572 0.4572)
			(layers "F.Cu" "F.Mask" "F.Paste")
			(net "GND")
		)
		(pad "AD26" smd circle
			(at 0.94996 -0.94996)
			(size 0.4572 0.4572)
			(layers "F.Cu" "F.Mask" "F.Paste")
			(net "P0V8_PEX2")
		)
		(pad "AD27" smd circle
			(at 1.89992 -0.94996)
			(size 0.4572 0.4572)
			(layers "F.Cu" "F.Mask" "F.Paste")
			(net "GND")
		)
		(pad "AD28" smd circle
			(at 2.84988 -0.94996)
			(size 0.4572 0.4572)
			(layers "F.Cu" "F.Mask" "F.Paste")
			(net "P0V8_PEX2")
		)
		(pad "AD29" smd circle
			(at 3.800094 -0.94996)
			(size 0.4572 0.4572)
			(layers "F.Cu" "F.Mask" "F.Paste")
			(net "GND")
		)
		(pad "AD30" smd circle
			(at 4.750054 -0.94996)
			(size 0.4572 0.4572)
			(layers "F.Cu" "F.Mask" "F.Paste")
			(net "P0V8_PEX2")
		)
		(pad "AD31" smd circle
			(at 5.700014 -0.94996)
			(size 0.4572 0.4572)
			(layers "F.Cu" "F.Mask" "F.Paste")
			(net "GND")
		)
		(pad "AD32" smd circle
			(at 6.649974 -0.94996)
			(size 0.4572 0.4572)
			(layers "F.Cu" "F.Mask" "F.Paste")
			(net "P0V8_SERDES_VDDA_PEX2")
		)
		(pad "AD33" smd circle
			(at 7.599934 -0.94996)
			(size 0.4572 0.4572)
			(layers "F.Cu" "F.Mask" "F.Paste")
			(net "P0V8_SERDES_VDDA_PEX2")
		)
		(pad "AD34" smd circle
			(at 8.549894 -0.94996)
			(size 0.4572 0.4572)
			(layers "F.Cu" "F.Mask" "F.Paste")
			(net "P0V8_SERDES_VDDA_PEX2")
		)
		(pad "AD35" smd circle
			(at 9.500108 -0.94996)
			(size 0.4572 0.4572)
			(layers "F.Cu" "F.Mask" "F.Paste")
			(net "GND")
		)
		(pad "AD36" smd circle
			(at 10.450068 -0.94996)
			(size 0.4572 0.4572)
			(layers "F.Cu" "F.Mask" "F.Paste")
			(net "P1V25_PEX2")
		)
		(pad "AD37" smd circle
			(at 11.400028 -0.94996)
			(size 0.4572 0.4572)
			(layers "F.Cu" "F.Mask" "F.Paste")
			(net "GND")
		)
		(pad "AD38" smd circle
			(at 12.349988 -0.94996)
			(size 0.4572 0.4572)
			(layers "F.Cu" "F.Mask" "F.Paste")
			(net "P1V25_SERDES_VDDPLL_PEX2")
		)
		(pad "AD39" smd circle
			(at 13.299948 -0.94996)
			(size 0.4572 0.4572)
			(layers "F.Cu" "F.Mask" "F.Paste")
			(net "GND")
		)
		(pad "AD40" smd circle
			(at 14.249908 -0.94996)
			(size 0.4572 0.4572)
			(layers "F.Cu" "F.Mask" "F.Paste")
			(net "GND")
		)
		(pad "AD41" smd circle
			(at 15.200122 -0.94996)
			(size 0.4572 0.4572)
			(layers "F.Cu" "F.Mask" "F.Paste")
			(net "Net_1657")
		)
		(pad "AD42" smd circle
			(at 16.150082 -0.94996)
			(size 0.4572 0.4572)
			(layers "F.Cu" "F.Mask" "F.Paste")
			(net "Net_1700")
		)
		(pad "AD43" smd circle
			(at 17.100042 -0.94996)
			(size 0.4572 0.4572)
			(layers "F.Cu" "F.Mask" "F.Paste")
			(net "GND")
		)
		(pad "AD44" smd circle
			(at 18.050002 -0.94996)
			(size 0.4572 0.4572)
			(layers "F.Cu" "F.Mask" "F.Paste")
			(net "GND")
		)
		(pad "AD45" smd circle
			(at 18.999962 -0.94996)
			(size 0.4572 0.4572)
			(layers "F.Cu" "F.Mask" "F.Paste")
			(net "GND")
		)
		(pad "AD46" smd circle
			(at 19.949922 -0.94996)
			(size 0.4572 0.4572)
			(layers "F.Cu" "F.Mask" "F.Paste")
			(net "GND")
		)
		(pad "AD47" smd circle
			(at 20.899882 -0.94996)
			(size 0.4572 0.4572)
			(layers "F.Cu" "F.Mask" "F.Paste")
			(net "GND")
		)
		(pad "AD48" smd circle
			(at 21.850096 -0.94996)
			(size 0.4572 0.4572)
			(layers "F.Cu" "F.Mask" "F.Paste")
			(net "Net_1650")
		)
		(pad "AD49" smd circle
			(at 22.800056 -0.94996)
			(size 0.4572 0.4572)
			(layers "F.Cu" "F.Mask" "F.Paste")
			(net "Net_1630")
		)
		(pad "AE1" smd circle
			(at -22.800056 0)
			(size 0.4572 0.4572)
			(layers "F.Cu" "F.Mask" "F.Paste")
			(net "CLK_100M_DB800ZL_PEX2_S3_R_DN")
		)
		(pad "AE2" smd circle
			(at -21.850096 0)
			(size 0.4572 0.4572)
			(layers "F.Cu" "F.Mask" "F.Paste")
			(net "CLK_100M_DB800ZL_PEX2_S3_R_DP")
		)
		(pad "AE3" smd circle
			(at -20.899882 0)
			(size 0.4572 0.4572)
			(layers "F.Cu" "F.Mask" "F.Paste")
			(net "GND")
		)
		(pad "AE4" smd circle
			(at -19.949922 0)
			(size 0.4572 0.4572)
			(layers "F.Cu" "F.Mask" "F.Paste")
			(net "GND")
		)
		(pad "AE5" smd circle
			(at -18.999962 0)
			(size 0.4572 0.4572)
			(layers "F.Cu" "F.Mask" "F.Paste")
			(net "GND")
		)
		(pad "AE6" smd circle
			(at -18.050002 0)
			(size 0.4572 0.4572)
			(layers "F.Cu" "F.Mask" "F.Paste")
			(net "GND")
		)
		(pad "AE7" smd circle
			(at -17.100042 0)
			(size 0.4572 0.4572)
			(layers "F.Cu" "F.Mask" "F.Paste")
			(net "Net_5394")
		)
		(pad "AE8" smd circle
			(at -16.150082 0)
			(size 0.4572 0.4572)
			(layers "F.Cu" "F.Mask" "F.Paste")
			(net "Net_5401")
		)
		(pad "AE9" smd circle
			(at -15.200122 0)
			(size 0.4572 0.4572)
			(layers "F.Cu" "F.Mask" "F.Paste")
			(net "GND")
		)
		(pad "AE10" smd circle
			(at -14.249908 0)
			(size 0.4572 0.4572)
			(layers "F.Cu" "F.Mask" "F.Paste")
			(net "P1V8_PEX")
		)
		(pad "AE11" smd circle
			(at -13.299948 0)
			(size 0.4572 0.4572)
			(layers "F.Cu" "F.Mask" "F.Paste")
			(net "GND")
		)
		(pad "AE12" smd circle
			(at -12.349988 0)
			(size 0.4572 0.4572)
			(layers "F.Cu" "F.Mask" "F.Paste")
			(net "GND")
		)
		(pad "AE13" smd circle
			(at -11.400028 0)
			(size 0.4572 0.4572)
			(layers "F.Cu" "F.Mask" "F.Paste")
			(net "PCEPLL3_VDDA18_PEX2")
		)
		(pad "AE14" smd circle
			(at -10.450068 0)
			(size 0.4572 0.4572)
			(layers "F.Cu" "F.Mask" "F.Paste")
			(net "GND")
		)
		(pad "AE15" smd circle
			(at -9.500108 0)
			(size 0.4572 0.4572)
			(layers "F.Cu" "F.Mask" "F.Paste")
			(net "P0V8_PEX2")
		)
		(pad "AE16" smd circle
			(at -8.549894 0)
			(size 0.4572 0.4572)
			(layers "F.Cu" "F.Mask" "F.Paste")
			(net "GND")
		)
		(pad "AE17" smd circle
			(at -7.599934 0)
			(size 0.4572 0.4572)
			(layers "F.Cu" "F.Mask" "F.Paste")
			(net "P0V8_PEX2")
		)
		(pad "AE18" smd circle
			(at -6.649974 0)
			(size 0.4572 0.4572)
			(layers "F.Cu" "F.Mask" "F.Paste")
			(net "GND")
		)
		(pad "AE19" smd circle
			(at -5.700014 0)
			(size 0.4572 0.4572)
			(layers "F.Cu" "F.Mask" "F.Paste")
			(net "P0V8_PEX2")
		)
		(pad "AE20" smd circle
			(at -4.750054 0)
			(size 0.4572 0.4572)
			(layers "F.Cu" "F.Mask" "F.Paste")
			(net "GND")
		)
		(pad "AE21" smd circle
			(at -3.800094 0)
			(size 0.4572 0.4572)
			(layers "F.Cu" "F.Mask" "F.Paste")
			(net "P0V8_PEX2")
		)
		(pad "AE22" smd circle
			(at -2.84988 0)
			(size 0.4572 0.4572)
			(layers "F.Cu" "F.Mask" "F.Paste")
			(net "GND")
		)
		(pad "AE23" smd circle
			(at -1.89992 0)
			(size 0.4572 0.4572)
			(layers "F.Cu" "F.Mask" "F.Paste")
			(net "P0V8_PEX2")
		)
		(pad "AE24" smd circle
			(at -0.94996 0)
			(size 0.4572 0.4572)
			(layers "F.Cu" "F.Mask" "F.Paste")
			(net "GND")
		)
		(pad "AE25" smd circle
			(at 0 0)
			(size 0.4572 0.4572)
			(layers "F.Cu" "F.Mask" "F.Paste")
			(net "P0V8_PEX2")
		)
		(pad "AE26" smd circle
			(at 0.94996 0)
			(size 0.4572 0.4572)
			(layers "F.Cu" "F.Mask" "F.Paste")
			(net "GND")
		)
		(pad "AE27" smd circle
			(at 1.89992 0)
			(size 0.4572 0.4572)
			(layers "F.Cu" "F.Mask" "F.Paste")
			(net "P0V8_PEX2")
		)
		(pad "AE28" smd circle
			(at 2.84988 0)
			(size 0.4572 0.4572)
			(layers "F.Cu" "F.Mask" "F.Paste")
			(net "GND")
		)
		(pad "AE29" smd circle
			(at 3.800094 0)
			(size 0.4572 0.4572)
			(layers "F.Cu" "F.Mask" "F.Paste")
			(net "P0V8_PEX2")
		)
		(pad "AE30" smd circle
			(at 4.750054 0)
			(size 0.4572 0.4572)
			(layers "F.Cu" "F.Mask" "F.Paste")
			(net "GND")
		)
		(pad "AE31" smd circle
			(at 5.700014 0)
			(size 0.4572 0.4572)
			(layers "F.Cu" "F.Mask" "F.Paste")
			(net "P0V8_PEX2")
		)
		(pad "AE32" smd circle
			(at 6.649974 0)
			(size 0.4572 0.4572)
			(layers "F.Cu" "F.Mask" "F.Paste")
			(net "GND")
		)
		(pad "AE33" smd circle
			(at 7.599934 0)
			(size 0.4572 0.4572)
			(layers "F.Cu" "F.Mask" "F.Paste")
			(net "P0V8_SERDES_VDDA_PEX2")
		)
		(pad "AE34" smd circle
			(at 8.549894 0)
			(size 0.4572 0.4572)
			(layers "F.Cu" "F.Mask" "F.Paste")
			(net "P0V8_SERDES_VDDA_PEX2")
		)
		(pad "AE35" smd circle
			(at 9.500108 0)
			(size 0.4572 0.4572)
			(layers "F.Cu" "F.Mask" "F.Paste")
			(net "GND")
		)
		(pad "AE36" smd circle
			(at 10.450068 0)
			(size 0.4572 0.4572)
			(layers "F.Cu" "F.Mask" "F.Paste")
			(net "P1V25_PEX2")
		)
		(pad "AE37" smd circle
			(at 11.400028 0)
			(size 0.4572 0.4572)
			(layers "F.Cu" "F.Mask" "F.Paste")
			(net "GND")
		)
		(pad "AE38" smd circle
			(at 12.349988 0)
			(size 0.4572 0.4572)
			(layers "F.Cu" "F.Mask" "F.Paste")
			(net "P1V25_SERDES_VDDPLL_PEX2")
		)
		(pad "AE39" smd circle
			(at 13.299948 0)
			(size 0.4572 0.4572)
			(layers "F.Cu" "F.Mask" "F.Paste")
			(net "GND")
		)
		(pad "AE40" smd circle
			(at 14.249908 0)
			(size 0.4572 0.4572)
			(layers "F.Cu" "F.Mask" "F.Paste")
			(net "GND")
		)
		(pad "AE41" smd circle
			(at 15.200122 0)
			(size 0.4572 0.4572)
			(layers "F.Cu" "F.Mask" "F.Paste")
			(net "GND")
		)
		(pad "AE42" smd circle
			(at 16.150082 0)
			(size 0.4572 0.4572)
			(layers "F.Cu" "F.Mask" "F.Paste")
			(net "GND")
		)
		(pad "AE43" smd circle
			(at 17.100042 0)
			(size 0.4572 0.4572)
			(layers "F.Cu" "F.Mask" "F.Paste")
			(net "Net_1689")
		)
		(pad "AE44" smd circle
			(at 18.050002 0)
			(size 0.4572 0.4572)
			(layers "F.Cu" "F.Mask" "F.Paste")
			(net "Net_1699")
		)
		(pad "AE45" smd circle
			(at 18.999962 0)
			(size 0.4572 0.4572)
			(layers "F.Cu" "F.Mask" "F.Paste")
			(net "GND")
		)
		(pad "AE46" smd circle
			(at 19.949922 0)
			(size 0.4572 0.4572)
			(layers "F.Cu" "F.Mask" "F.Paste")
			(net "Net_1538")
		)
		(pad "AE47" smd circle
			(at 20.899882 0)
			(size 0.4572 0.4572)
			(layers "F.Cu" "F.Mask" "F.Paste")
			(net "Net_1619")
		)
		(pad "AE48" smd circle
			(at 21.850096 0)
			(size 0.4572 0.4572)
			(layers "F.Cu" "F.Mask" "F.Paste")
			(net "GND")
		)
		(pad "AE49" smd circle
			(at 22.800056 0)
			(size 0.4572 0.4572)
			(layers "F.Cu" "F.Mask" "F.Paste")
			(net "GND")
		)
		(pad "AF1" smd circle
			(at -22.800056 0.94996)
			(size 0.4572 0.4572)
			(layers "F.Cu" "F.Mask" "F.Paste")
			(net "GND")
		)
		(pad "AF2" smd circle
			(at -21.850096 0.94996)
			(size 0.4572 0.4572)
			(layers "F.Cu" "F.Mask" "F.Paste")
			(net "GND")
		)
		(pad "AF3" smd circle
			(at -20.899882 0.94996)
			(size 0.4572 0.4572)
			(layers "F.Cu" "F.Mask" "F.Paste")
			(net "GND")
		)
		(pad "AF4" smd circle
			(at -19.949922 0.94996)
			(size 0.4572 0.4572)
			(layers "F.Cu" "F.Mask" "F.Paste")
			(net "Net_5313")
		)
		(pad "AF5" smd circle
			(at -18.999962 0.94996)
			(size 0.4572 0.4572)
			(layers "F.Cu" "F.Mask" "F.Paste")
			(net "Net_5314")
		)
		(pad "AF6" smd circle
			(at -18.050002 0.94996)
			(size 0.4572 0.4572)
			(layers "F.Cu" "F.Mask" "F.Paste")
			(net "GND")
		)
		(pad "AF7" smd circle
			(at -17.100042 0.94996)
			(size 0.4572 0.4572)
			(layers "F.Cu" "F.Mask" "F.Paste")
			(net "SPI_PEX2_SDIO0")
		)
		(pad "AF8" smd circle
			(at -16.150082 0.94996)
			(size 0.4572 0.4572)
			(layers "F.Cu" "F.Mask" "F.Paste")
			(net "SPI_PEX2_SDIO1")
		)
		(pad "AF9" smd circle
			(at -15.200122 0.94996)
			(size 0.4572 0.4572)
			(layers "F.Cu" "F.Mask" "F.Paste")
			(net "GND")
		)
		(pad "AF10" smd circle
			(at -14.249908 0.94996)
			(size 0.4572 0.4572)
			(layers "F.Cu" "F.Mask" "F.Paste")
			(net "P1V8_PEX")
		)
		(pad "AF11" smd circle
			(at -13.299948 0.94996)
			(size 0.4572 0.4572)
			(layers "F.Cu" "F.Mask" "F.Paste")
			(net "GND")
		)
		(pad "AF12" smd circle
			(at -12.349988 0.94996)
			(size 0.4572 0.4572)
			(layers "F.Cu" "F.Mask" "F.Paste")
			(net "PCEPLL4_VDDA18_PEX2")
		)
		(pad "AF13" smd circle
			(at -11.400028 0.94996)
			(size 0.4572 0.4572)
			(layers "F.Cu" "F.Mask" "F.Paste")
			(net "GND")
		)
		(pad "AF14" smd circle
			(at -10.450068 0.94996)
			(size 0.4572 0.4572)
			(layers "F.Cu" "F.Mask" "F.Paste")
			(net "P0V8_PEX2")
		)
		(pad "AF15" smd circle
			(at -9.500108 0.94996)
			(size 0.4572 0.4572)
			(layers "F.Cu" "F.Mask" "F.Paste")
			(net "GND")
		)
		(pad "AF16" smd circle
			(at -8.549894 0.94996)
			(size 0.4572 0.4572)
			(layers "F.Cu" "F.Mask" "F.Paste")
			(net "P0V8_PEX2")
		)
		(pad "AF17" smd circle
			(at -7.599934 0.94996)
			(size 0.4572 0.4572)
			(layers "F.Cu" "F.Mask" "F.Paste")
			(net "GND")
		)
		(pad "AF18" smd circle
			(at -6.649974 0.94996)
			(size 0.4572 0.4572)
			(layers "F.Cu" "F.Mask" "F.Paste")
			(net "P0V8_PEX2")
		)
		(pad "AF19" smd circle
			(at -5.700014 0.94996)
			(size 0.4572 0.4572)
			(layers "F.Cu" "F.Mask" "F.Paste")
			(net "GND")
		)
		(pad "AF20" smd circle
			(at -4.750054 0.94996)
			(size 0.4572 0.4572)
			(layers "F.Cu" "F.Mask" "F.Paste")
			(net "P0V8_PEX2")
		)
		(pad "AF21" smd circle
			(at -3.800094 0.94996)
			(size 0.4572 0.4572)
			(layers "F.Cu" "F.Mask" "F.Paste")
			(net "GND")
		)
		(pad "AF22" smd circle
			(at -2.84988 0.94996)
			(size 0.4572 0.4572)
			(layers "F.Cu" "F.Mask" "F.Paste")
			(net "P0V8_PEX2")
		)
		(pad "AF23" smd circle
			(at -1.89992 0.94996)
			(size 0.4572 0.4572)
			(layers "F.Cu" "F.Mask" "F.Paste")
			(net "GND")
		)
		(pad "AF24" smd circle
			(at -0.94996 0.94996)
			(size 0.4572 0.4572)
			(layers "F.Cu" "F.Mask" "F.Paste")
			(net "P0V8_PEX2")
		)
		(pad "AF25" smd circle
			(at 0 0.94996)
			(size 0.4572 0.4572)
			(layers "F.Cu" "F.Mask" "F.Paste")
			(net "GND")
		)
		(pad "AF26" smd circle
			(at 0.94996 0.94996)
			(size 0.4572 0.4572)
			(layers "F.Cu" "F.Mask" "F.Paste")
			(net "P0V8_PEX2")
		)
		(pad "AF27" smd circle
			(at 1.89992 0.94996)
			(size 0.4572 0.4572)
			(layers "F.Cu" "F.Mask" "F.Paste")
			(net "GND")
		)
		(pad "AF28" smd circle
			(at 2.84988 0.94996)
			(size 0.4572 0.4572)
			(layers "F.Cu" "F.Mask" "F.Paste")
			(net "P0V8_PEX2")
		)
		(pad "AF29" smd circle
			(at 3.800094 0.94996)
			(size 0.4572 0.4572)
			(layers "F.Cu" "F.Mask" "F.Paste")
			(net "GND")
		)
		(pad "AF30" smd circle
			(at 4.750054 0.94996)
			(size 0.4572 0.4572)
			(layers "F.Cu" "F.Mask" "F.Paste")
			(net "P0V8_PEX2")
		)
		(pad "AF31" smd circle
			(at 5.700014 0.94996)
			(size 0.4572 0.4572)
			(layers "F.Cu" "F.Mask" "F.Paste")
			(net "GND")
		)
		(pad "AF32" smd circle
			(at 6.649974 0.94996)
			(size 0.4572 0.4572)
			(layers "F.Cu" "F.Mask" "F.Paste")
			(net "P0V8_SERDES_VDDA_PEX2")
		)
		(pad "AF33" smd circle
			(at 7.599934 0.94996)
			(size 0.4572 0.4572)
			(layers "F.Cu" "F.Mask" "F.Paste")
			(net "P0V8_SERDES_VDDA_PEX2")
		)
		(pad "AF34" smd circle
			(at 8.549894 0.94996)
			(size 0.4572 0.4572)
			(layers "F.Cu" "F.Mask" "F.Paste")
			(net "P0V8_SERDES_VDDA_PEX2")
		)
		(pad "AF35" smd circle
			(at 9.500108 0.94996)
			(size 0.4572 0.4572)
			(layers "F.Cu" "F.Mask" "F.Paste")
			(net "GND")
		)
		(pad "AF36" smd circle
			(at 10.450068 0.94996)
			(size 0.4572 0.4572)
			(layers "F.Cu" "F.Mask" "F.Paste")
			(net "P1V25_PEX2")
		)
		(pad "AF37" smd circle
			(at 11.400028 0.94996)
			(size 0.4572 0.4572)
			(layers "F.Cu" "F.Mask" "F.Paste")
			(net "GND")
		)
		(pad "AF38" smd circle
			(at 12.349988 0.94996)
			(size 0.4572 0.4572)
			(layers "F.Cu" "F.Mask" "F.Paste")
			(net "P1V25_SERDES_VDDPLL_PEX2")
		)
		(pad "AF39" smd circle
			(at 13.299948 0.94996)
			(size 0.4572 0.4572)
			(layers "F.Cu" "F.Mask" "F.Paste")
			(net "GND")
		)
		(pad "AF40" smd circle
			(at 14.249908 0.94996)
			(size 0.4572 0.4572)
			(layers "F.Cu" "F.Mask" "F.Paste")
			(net "GND")
		)
		(pad "AF41" smd circle
			(at 15.200122 0.94996)
			(size 0.4572 0.4572)
			(layers "F.Cu" "F.Mask" "F.Paste")
			(net "Net_1675")
		)
		(pad "AF42" smd circle
			(at 16.150082 0.94996)
			(size 0.4572 0.4572)
			(layers "F.Cu" "F.Mask" "F.Paste")
			(net "Net_1667")
		)
		(pad "AF43" smd circle
			(at 17.100042 0.94996)
			(size 0.4572 0.4572)
			(layers "F.Cu" "F.Mask" "F.Paste")
			(net "GND")
		)
		(pad "AF44" smd circle
			(at 18.050002 0.94996)
			(size 0.4572 0.4572)
			(layers "F.Cu" "F.Mask" "F.Paste")
			(net "GND")
		)
		(pad "AF45" smd circle
			(at 18.999962 0.94996)
			(size 0.4572 0.4572)
			(layers "F.Cu" "F.Mask" "F.Paste")
			(net "GND")
		)
		(pad "AF46" smd circle
			(at 19.949922 0.94996)
			(size 0.4572 0.4572)
			(layers "F.Cu" "F.Mask" "F.Paste")
			(net "GND")
		)
		(pad "AF47" smd circle
			(at 20.899882 0.94996)
			(size 0.4572 0.4572)
			(layers "F.Cu" "F.Mask" "F.Paste")
			(net "GND")
		)
		(pad "AF48" smd circle
			(at 21.850096 0.94996)
			(size 0.4572 0.4572)
			(layers "F.Cu" "F.Mask" "F.Paste")
			(net "Net_1569")
		)
		(pad "AF49" smd circle
			(at 22.800056 0.94996)
			(size 0.4572 0.4572)
			(layers "F.Cu" "F.Mask" "F.Paste")
			(net "Net_1548")
		)
		(pad "AG1" smd circle
			(at -22.800056 1.89992)
			(size 0.4572 0.4572)
			(layers "F.Cu" "F.Mask" "F.Paste")
			(net "Net_5316")
		)
		(pad "AG2" smd circle
			(at -21.850096 1.89992)
			(size 0.4572 0.4572)
			(layers "F.Cu" "F.Mask" "F.Paste")
			(net "Net_5317")
		)
		(pad "AG3" smd circle
			(at -20.899882 1.89992)
			(size 0.4572 0.4572)
			(layers "F.Cu" "F.Mask" "F.Paste")
			(net "GND")
		)
		(pad "AG4" smd circle
			(at -19.949922 1.89992)
			(size 0.4572 0.4572)
			(layers "F.Cu" "F.Mask" "F.Paste")
			(net "GND")
		)
		(pad "AG5" smd circle
			(at -18.999962 1.89992)
			(size 0.4572 0.4572)
			(layers "F.Cu" "F.Mask" "F.Paste")
			(net "GND")
		)
		(pad "AG6" smd circle
			(at -18.050002 1.89992)
			(size 0.4572 0.4572)
			(layers "F.Cu" "F.Mask" "F.Paste")
			(net "GND")
		)
		(pad "AG7" smd circle
			(at -17.100042 1.89992)
			(size 0.4572 0.4572)
			(layers "F.Cu" "F.Mask" "F.Paste")
			(net "SPI_PEX2_RST_N")
		)
		(pad "AG8" smd circle
			(at -16.150082 1.89992)
			(size 0.4572 0.4572)
			(layers "F.Cu" "F.Mask" "F.Paste")
			(net "SPI_PEX2_SDIO2")
		)
		(pad "AG9" smd circle
			(at -15.200122 1.89992)
			(size 0.4572 0.4572)
			(layers "F.Cu" "F.Mask" "F.Paste")
			(net "GND")
		)
		(pad "AG10" smd circle
			(at -14.249908 1.89992)
			(size 0.4572 0.4572)
			(layers "F.Cu" "F.Mask" "F.Paste")
			(net "GND")
		)
		(pad "AG11" smd circle
			(at -13.299948 1.89992)
			(size 0.4572 0.4572)
			(layers "F.Cu" "F.Mask" "F.Paste")
			(net "GND")
		)
		(pad "AG12" smd circle
			(at -12.349988 1.89992)
			(size 0.4572 0.4572)
			(layers "F.Cu" "F.Mask" "F.Paste")
			(net "GND")
		)
		(pad "AG13" smd circle
			(at -11.400028 1.89992)
			(size 0.4572 0.4572)
			(layers "F.Cu" "F.Mask" "F.Paste")
			(net "PCEPLL5_VDDA18_PEX2")
		)
		(pad "AG14" smd circle
			(at -10.450068 1.89992)
			(size 0.4572 0.4572)
			(layers "F.Cu" "F.Mask" "F.Paste")
			(net "GND")
		)
		(pad "AG15" smd circle
			(at -9.500108 1.89992)
			(size 0.4572 0.4572)
			(layers "F.Cu" "F.Mask" "F.Paste")
			(net "P0V8_PEX2")
		)
		(pad "AG16" smd circle
			(at -8.549894 1.89992)
			(size 0.4572 0.4572)
			(layers "F.Cu" "F.Mask" "F.Paste")
			(net "GND")
		)
		(pad "AG17" smd circle
			(at -7.599934 1.89992)
			(size 0.4572 0.4572)
			(layers "F.Cu" "F.Mask" "F.Paste")
			(net "P0V8_PEX2")
		)
		(pad "AG18" smd circle
			(at -6.649974 1.89992)
			(size 0.4572 0.4572)
			(layers "F.Cu" "F.Mask" "F.Paste")
			(net "GND")
		)
		(pad "AG19" smd circle
			(at -5.700014 1.89992)
			(size 0.4572 0.4572)
			(layers "F.Cu" "F.Mask" "F.Paste")
			(net "P0V8_PEX2")
		)
		(pad "AG20" smd circle
			(at -4.750054 1.89992)
			(size 0.4572 0.4572)
			(layers "F.Cu" "F.Mask" "F.Paste")
			(net "GND")
		)
		(pad "AG21" smd circle
			(at -3.800094 1.89992)
			(size 0.4572 0.4572)
			(layers "F.Cu" "F.Mask" "F.Paste")
			(net "P0V8_PEX2")
		)
		(pad "AG22" smd circle
			(at -2.84988 1.89992)
			(size 0.4572 0.4572)
			(layers "F.Cu" "F.Mask" "F.Paste")
			(net "GND")
		)
		(pad "AG23" smd circle
			(at -1.89992 1.89992)
			(size 0.4572 0.4572)
			(layers "F.Cu" "F.Mask" "F.Paste")
			(net "P0V8_PEX2")
		)
		(pad "AG24" smd circle
			(at -0.94996 1.89992)
			(size 0.4572 0.4572)
			(layers "F.Cu" "F.Mask" "F.Paste")
			(net "GND")
		)
		(pad "AG25" smd circle
			(at 0 1.89992)
			(size 0.4572 0.4572)
			(layers "F.Cu" "F.Mask" "F.Paste")
			(net "P0V8_PEX2")
		)
		(pad "AG26" smd circle
			(at 0.94996 1.89992)
			(size 0.4572 0.4572)
			(layers "F.Cu" "F.Mask" "F.Paste")
			(net "GND")
		)
		(pad "AG27" smd circle
			(at 1.89992 1.89992)
			(size 0.4572 0.4572)
			(layers "F.Cu" "F.Mask" "F.Paste")
			(net "P0V8_PEX2")
		)
		(pad "AG28" smd circle
			(at 2.84988 1.89992)
			(size 0.4572 0.4572)
			(layers "F.Cu" "F.Mask" "F.Paste")
			(net "GND")
		)
		(pad "AG29" smd circle
			(at 3.800094 1.89992)
			(size 0.4572 0.4572)
			(layers "F.Cu" "F.Mask" "F.Paste")
			(net "P0V8_PEX2")
		)
		(pad "AG30" smd circle
			(at 4.750054 1.89992)
			(size 0.4572 0.4572)
			(layers "F.Cu" "F.Mask" "F.Paste")
			(net "GND")
		)
		(pad "AG31" smd circle
			(at 5.700014 1.89992)
			(size 0.4572 0.4572)
			(layers "F.Cu" "F.Mask" "F.Paste")
			(net "P0V8_PEX2")
		)
		(pad "AG32" smd circle
			(at 6.649974 1.89992)
			(size 0.4572 0.4572)
			(layers "F.Cu" "F.Mask" "F.Paste")
			(net "GND")
		)
		(pad "AG33" smd circle
			(at 7.599934 1.89992)
			(size 0.4572 0.4572)
			(layers "F.Cu" "F.Mask" "F.Paste")
			(net "P0V8_PEX2")
		)
		(pad "AG34" smd circle
			(at 8.549894 1.89992)
			(size 0.4572 0.4572)
			(layers "F.Cu" "F.Mask" "F.Paste")
			(net "GND")
		)
		(pad "AG35" smd circle
			(at 9.500108 1.89992)
			(size 0.4572 0.4572)
			(layers "F.Cu" "F.Mask" "F.Paste")
			(net "GND")
		)
		(pad "AG36" smd circle
			(at 10.450068 1.89992)
			(size 0.4572 0.4572)
			(layers "F.Cu" "F.Mask" "F.Paste")
			(net "P1V25_PEX2")
		)
		(pad "AG37" smd circle
			(at 11.400028 1.89992)
			(size 0.4572 0.4572)
			(layers "F.Cu" "F.Mask" "F.Paste")
			(net "GND")
		)
		(pad "AG38" smd circle
			(at 12.349988 1.89992)
			(size 0.4572 0.4572)
			(layers "F.Cu" "F.Mask" "F.Paste")
			(net "P1V25_SERDES_VDDPLL_PEX2")
		)
		(pad "AG39" smd circle
			(at 13.299948 1.89992)
			(size 0.4572 0.4572)
			(layers "F.Cu" "F.Mask" "F.Paste")
			(net "GND")
		)
		(pad "AG40" smd circle
			(at 14.249908 1.89992)
			(size 0.4572 0.4572)
			(layers "F.Cu" "F.Mask" "F.Paste")
			(net "GND")
		)
		(pad "AG41" smd circle
			(at 15.200122 1.89992)
			(size 0.4572 0.4572)
			(layers "F.Cu" "F.Mask" "F.Paste")
			(net "GND")
		)
		(pad "AG42" smd circle
			(at 16.150082 1.89992)
			(size 0.4572 0.4572)
			(layers "F.Cu" "F.Mask" "F.Paste")
			(net "GND")
		)
		(pad "AG43" smd circle
			(at 17.100042 1.89992)
			(size 0.4572 0.4572)
			(layers "F.Cu" "F.Mask" "F.Paste")
			(net "Net_1702")
		)
		(pad "AG44" smd circle
			(at 18.050002 1.89992)
			(size 0.4572 0.4572)
			(layers "F.Cu" "F.Mask" "F.Paste")
			(net "Net_1698")
		)
		(pad "AG45" smd circle
			(at 18.999962 1.89992)
			(size 0.4572 0.4572)
			(layers "F.Cu" "F.Mask" "F.Paste")
			(net "GND")
		)
		(pad "AG46" smd circle
			(at 19.949922 1.89992)
			(size 0.4572 0.4572)
			(layers "F.Cu" "F.Mask" "F.Paste")
			(net "Net_1592")
		)
		(pad "AG47" smd circle
			(at 20.899882 1.89992)
			(size 0.4572 0.4572)
			(layers "F.Cu" "F.Mask" "F.Paste")
			(net "Net_1556")
		)
		(pad "AG48" smd circle
			(at 21.850096 1.89992)
			(size 0.4572 0.4572)
			(layers "F.Cu" "F.Mask" "F.Paste")
			(net "GND")
		)
		(pad "AG49" smd circle
			(at 22.800056 1.89992)
			(size 0.4572 0.4572)
			(layers "F.Cu" "F.Mask" "F.Paste")
			(net "GND")
		)
		(pad "AH1" smd circle
			(at -22.800056 2.84988)
			(size 0.4572 0.4572)
			(layers "F.Cu" "F.Mask" "F.Paste")
			(net "GND")
		)
		(pad "AH2" smd circle
			(at -21.850096 2.84988)
			(size 0.4572 0.4572)
			(layers "F.Cu" "F.Mask" "F.Paste")
			(net "GND")
		)
		(pad "AH3" smd circle
			(at -20.899882 2.84988)
			(size 0.4572 0.4572)
			(layers "F.Cu" "F.Mask" "F.Paste")
			(net "GND")
		)
		(pad "AH4" smd circle
			(at -19.949922 2.84988)
			(size 0.4572 0.4572)
			(layers "F.Cu" "F.Mask" "F.Paste")
			(net "Net_5319")
		)
		(pad "AH5" smd circle
			(at -18.999962 2.84988)
			(size 0.4572 0.4572)
			(layers "F.Cu" "F.Mask" "F.Paste")
			(net "Net_5320")
		)
		(pad "AH6" smd circle
			(at -18.050002 2.84988)
			(size 0.4572 0.4572)
			(layers "F.Cu" "F.Mask" "F.Paste")
			(net "GND")
		)
		(pad "AH7" smd circle
			(at -17.100042 2.84988)
			(size 0.4572 0.4572)
			(layers "F.Cu" "F.Mask" "F.Paste")
			(net "SPI_PEX2_CLK")
		)
		(pad "AH8" smd circle
			(at -16.150082 2.84988)
			(size 0.4572 0.4572)
			(layers "F.Cu" "F.Mask" "F.Paste")
			(net "SPI_PEX2_SDIO3")
		)
		(pad "AH9" smd circle
			(at -15.200122 2.84988)
			(size 0.4572 0.4572)
			(layers "F.Cu" "F.Mask" "F.Paste")
			(net "GND")
		)
		(pad "AH10" smd circle
			(at -14.249908 2.84988)
			(size 0.4572 0.4572)
			(layers "F.Cu" "F.Mask" "F.Paste")
			(net "P1V8_PEX")
		)
		(pad "AH11" smd circle
			(at -13.299948 2.84988)
			(size 0.4572 0.4572)
			(layers "F.Cu" "F.Mask" "F.Paste")
			(net "GND")
		)
		(pad "AH12" smd circle
			(at -12.349988 2.84988)
			(size 0.4572 0.4572)
			(layers "F.Cu" "F.Mask" "F.Paste")
			(net "PCEPLL6_VDDA18_PEX2")
		)
		(pad "AH13" smd circle
			(at -11.400028 2.84988)
			(size 0.4572 0.4572)
			(layers "F.Cu" "F.Mask" "F.Paste")
			(net "GND")
		)
		(pad "AH14" smd circle
			(at -10.450068 2.84988)
			(size 0.4572 0.4572)
			(layers "F.Cu" "F.Mask" "F.Paste")
			(net "P0V8_PEX2")
		)
		(pad "AH15" smd circle
			(at -9.500108 2.84988)
			(size 0.4572 0.4572)
			(layers "F.Cu" "F.Mask" "F.Paste")
			(net "GND")
		)
		(pad "AH16" smd circle
			(at -8.549894 2.84988)
			(size 0.4572 0.4572)
			(layers "F.Cu" "F.Mask" "F.Paste")
			(net "P0V8_SERDES_VDDA_PEX2")
		)
		(pad "AH17" smd circle
			(at -7.599934 2.84988)
			(size 0.4572 0.4572)
			(layers "F.Cu" "F.Mask" "F.Paste")
			(net "P0V8_SERDES_VDDA_PEX2")
		)
		(pad "AH18" smd circle
			(at -6.649974 2.84988)
			(size 0.4572 0.4572)
			(layers "F.Cu" "F.Mask" "F.Paste")
			(net "P0V8_SERDES_VDDA_PEX2")
		)
		(pad "AH19" smd circle
			(at -5.700014 2.84988)
			(size 0.4572 0.4572)
			(layers "F.Cu" "F.Mask" "F.Paste")
			(net "P0V8_SERDES_VDDA_PEX2")
		)
		(pad "AH20" smd circle
			(at -4.750054 2.84988)
			(size 0.4572 0.4572)
			(layers "F.Cu" "F.Mask" "F.Paste")
			(net "P0V8_SERDES_VDDA_PEX2")
		)
		(pad "AH21" smd circle
			(at -3.800094 2.84988)
			(size 0.4572 0.4572)
			(layers "F.Cu" "F.Mask" "F.Paste")
			(net "P0V8_SERDES_VDDA_PEX2")
		)
		(pad "AH22" smd circle
			(at -2.84988 2.84988)
			(size 0.4572 0.4572)
			(layers "F.Cu" "F.Mask" "F.Paste")
			(net "P0V8_SERDES_VDDA_PEX2")
		)
		(pad "AH23" smd circle
			(at -1.89992 2.84988)
			(size 0.4572 0.4572)
			(layers "F.Cu" "F.Mask" "F.Paste")
			(net "P0V8_SERDES_VDDA_PEX2")
		)
		(pad "AH24" smd circle
			(at -0.94996 2.84988)
			(size 0.4572 0.4572)
			(layers "F.Cu" "F.Mask" "F.Paste")
			(net "P0V8_SERDES_VDDA_PEX2")
		)
		(pad "AH25" smd circle
			(at 0 2.84988)
			(size 0.4572 0.4572)
			(layers "F.Cu" "F.Mask" "F.Paste")
			(net "P0V8_SERDES_VDDA_PEX2")
		)
		(pad "AH26" smd circle
			(at 0.94996 2.84988)
			(size 0.4572 0.4572)
			(layers "F.Cu" "F.Mask" "F.Paste")
			(net "P0V8_SERDES_VDDA_PEX2")
		)
		(pad "AH27" smd circle
			(at 1.89992 2.84988)
			(size 0.4572 0.4572)
			(layers "F.Cu" "F.Mask" "F.Paste")
			(net "P0V8_SERDES_VDDA_PEX2")
		)
		(pad "AH28" smd circle
			(at 2.84988 2.84988)
			(size 0.4572 0.4572)
			(layers "F.Cu" "F.Mask" "F.Paste")
			(net "P0V8_SERDES_VDDA_PEX2")
		)
		(pad "AH29" smd circle
			(at 3.800094 2.84988)
			(size 0.4572 0.4572)
			(layers "F.Cu" "F.Mask" "F.Paste")
			(net "P0V8_SERDES_VDDA_PEX2")
		)
		(pad "AH30" smd circle
			(at 4.750054 2.84988)
			(size 0.4572 0.4572)
			(layers "F.Cu" "F.Mask" "F.Paste")
			(net "P0V8_SERDES_VDDA_PEX2")
		)
		(pad "AH31" smd circle
			(at 5.700014 2.84988)
			(size 0.4572 0.4572)
			(layers "F.Cu" "F.Mask" "F.Paste")
			(net "P0V8_SERDES_VDDA_PEX2")
		)
		(pad "AH32" smd circle
			(at 6.649974 2.84988)
			(size 0.4572 0.4572)
			(layers "F.Cu" "F.Mask" "F.Paste")
			(net "P0V8_SERDES_VDDA_PEX2")
		)
		(pad "AH33" smd circle
			(at 7.599934 2.84988)
			(size 0.4572 0.4572)
			(layers "F.Cu" "F.Mask" "F.Paste")
			(net "P0V8_SERDES_VDDA_PEX2")
		)
		(pad "AH34" smd circle
			(at 8.549894 2.84988)
			(size 0.4572 0.4572)
			(layers "F.Cu" "F.Mask" "F.Paste")
			(net "GND")
		)
		(pad "AH35" smd circle
			(at 9.500108 2.84988)
			(size 0.4572 0.4572)
			(layers "F.Cu" "F.Mask" "F.Paste")
			(net "GND")
		)
		(pad "AH36" smd circle
			(at 10.450068 2.84988)
			(size 0.4572 0.4572)
			(layers "F.Cu" "F.Mask" "F.Paste")
			(net "GND")
		)
		(pad "AH37" smd circle
			(at 11.400028 2.84988)
			(size 0.4572 0.4572)
			(layers "F.Cu" "F.Mask" "F.Paste")
			(net "GND")
		)
		(pad "AH38" smd circle
			(at 12.349988 2.84988)
			(size 0.4572 0.4572)
			(layers "F.Cu" "F.Mask" "F.Paste")
			(net "GND")
		)
		(pad "AH39" smd circle
			(at 13.299948 2.84988)
			(size 0.4572 0.4572)
			(layers "F.Cu" "F.Mask" "F.Paste")
			(net "GND")
		)
		(pad "AH40" smd circle
			(at 14.249908 2.84988)
			(size 0.4572 0.4572)
			(layers "F.Cu" "F.Mask" "F.Paste")
			(net "GND")
		)
		(pad "AH41" smd circle
			(at 15.200122 2.84988)
			(size 0.4572 0.4572)
			(layers "F.Cu" "F.Mask" "F.Paste")
			(net "Net_1695")
		)
		(pad "AH42" smd circle
			(at 16.150082 2.84988)
			(size 0.4572 0.4572)
			(layers "F.Cu" "F.Mask" "F.Paste")
			(net "Net_1683")
		)
		(pad "AH43" smd circle
			(at 17.100042 2.84988)
			(size 0.4572 0.4572)
			(layers "F.Cu" "F.Mask" "F.Paste")
			(net "GND")
		)
		(pad "AH44" smd circle
			(at 18.050002 2.84988)
			(size 0.4572 0.4572)
			(layers "F.Cu" "F.Mask" "F.Paste")
			(net "GND")
		)
		(pad "AH45" smd circle
			(at 18.999962 2.84988)
			(size 0.4572 0.4572)
			(layers "F.Cu" "F.Mask" "F.Paste")
			(net "GND")
		)
		(pad "AH46" smd circle
			(at 19.949922 2.84988)
			(size 0.4572 0.4572)
			(layers "F.Cu" "F.Mask" "F.Paste")
			(net "GND")
		)
		(pad "AH47" smd circle
			(at 20.899882 2.84988)
			(size 0.4572 0.4572)
			(layers "F.Cu" "F.Mask" "F.Paste")
			(net "GND")
		)
		(pad "AH48" smd circle
			(at 21.850096 2.84988)
			(size 0.4572 0.4572)
			(layers "F.Cu" "F.Mask" "F.Paste")
			(net "Net_1635")
		)
		(pad "AH49" smd circle
			(at 22.800056 2.84988)
			(size 0.4572 0.4572)
			(layers "F.Cu" "F.Mask" "F.Paste")
			(net "Net_1616")
		)
		(pad "AJ1" smd circle
			(at -22.800056 3.800094)
			(size 0.4572 0.4572)
			(layers "F.Cu" "F.Mask" "F.Paste")
			(net "Net_5322")
		)
		(pad "AJ2" smd circle
			(at -21.850096 3.800094)
			(size 0.4572 0.4572)
			(layers "F.Cu" "F.Mask" "F.Paste")
			(net "Net_5323")
		)
		(pad "AJ3" smd circle
			(at -20.899882 3.800094)
			(size 0.4572 0.4572)
			(layers "F.Cu" "F.Mask" "F.Paste")
			(net "GND")
		)
		(pad "AJ4" smd circle
			(at -19.949922 3.800094)
			(size 0.4572 0.4572)
			(layers "F.Cu" "F.Mask" "F.Paste")
			(net "GND")
		)
		(pad "AJ5" smd circle
			(at -18.999962 3.800094)
			(size 0.4572 0.4572)
			(layers "F.Cu" "F.Mask" "F.Paste")
			(net "GND")
		)
		(pad "AJ6" smd circle
			(at -18.050002 3.800094)
			(size 0.4572 0.4572)
			(layers "F.Cu" "F.Mask" "F.Paste")
			(net "GND")
		)
		(pad "AJ7" smd circle
			(at -17.100042 3.800094)
			(size 0.4572 0.4572)
			(layers "F.Cu" "F.Mask" "F.Paste")
			(net "SPI_PEX2_CS_N")
		)
		(pad "AJ8" smd circle
			(at -16.150082 3.800094)
			(size 0.4572 0.4572)
			(layers "F.Cu" "F.Mask" "F.Paste")
			(net "Net_5393")
		)
		(pad "AJ9" smd circle
			(at -15.200122 3.800094)
			(size 0.4572 0.4572)
			(layers "F.Cu" "F.Mask" "F.Paste")
			(net "GND")
		)
		(pad "AJ10" smd circle
			(at -14.249908 3.800094)
			(size 0.4572 0.4572)
			(layers "F.Cu" "F.Mask" "F.Paste")
			(net "P1V8_PEX")
		)
		(pad "AJ11" smd circle
			(at -13.299948 3.800094)
			(size 0.4572 0.4572)
			(layers "F.Cu" "F.Mask" "F.Paste")
			(net "GND")
		)
		(pad "AJ12" smd circle
			(at -12.349988 3.800094)
			(size 0.4572 0.4572)
			(layers "F.Cu" "F.Mask" "F.Paste")
			(net "GND")
		)
		(pad "AJ13" smd circle
			(at -11.400028 3.800094)
			(size 0.4572 0.4572)
			(layers "F.Cu" "F.Mask" "F.Paste")
			(net "PCEPLL7_VDDA18_PEX2")
		)
		(pad "AJ14" smd circle
			(at -10.450068 3.800094)
			(size 0.4572 0.4572)
			(layers "F.Cu" "F.Mask" "F.Paste")
			(net "GND")
		)
		(pad "AJ15" smd circle
			(at -9.500108 3.800094)
			(size 0.4572 0.4572)
			(layers "F.Cu" "F.Mask" "F.Paste")
			(net "P0V8_PEX2")
		)
		(pad "AJ16" smd circle
			(at -8.549894 3.800094)
			(size 0.4572 0.4572)
			(layers "F.Cu" "F.Mask" "F.Paste")
			(net "GND")
		)
		(pad "AJ17" smd circle
			(at -7.599934 3.800094)
			(size 0.4572 0.4572)
			(layers "F.Cu" "F.Mask" "F.Paste")
			(net "GND")
		)
		(pad "AJ18" smd circle
			(at -6.649974 3.800094)
			(size 0.4572 0.4572)
			(layers "F.Cu" "F.Mask" "F.Paste")
			(net "GND")
		)
		(pad "AJ19" smd circle
			(at -5.700014 3.800094)
			(size 0.4572 0.4572)
			(layers "F.Cu" "F.Mask" "F.Paste")
			(net "GND")
		)
		(pad "AJ20" smd circle
			(at -4.750054 3.800094)
			(size 0.4572 0.4572)
			(layers "F.Cu" "F.Mask" "F.Paste")
			(net "GND")
		)
		(pad "AJ21" smd circle
			(at -3.800094 3.800094)
			(size 0.4572 0.4572)
			(layers "F.Cu" "F.Mask" "F.Paste")
			(net "GND")
		)
		(pad "AJ22" smd circle
			(at -2.84988 3.800094)
			(size 0.4572 0.4572)
			(layers "F.Cu" "F.Mask" "F.Paste")
			(net "GND")
		)
		(pad "AJ23" smd circle
			(at -1.89992 3.800094)
			(size 0.4572 0.4572)
			(layers "F.Cu" "F.Mask" "F.Paste")
			(net "GND")
		)
		(pad "AJ24" smd circle
			(at -0.94996 3.800094)
			(size 0.4572 0.4572)
			(layers "F.Cu" "F.Mask" "F.Paste")
			(net "GND")
		)
		(pad "AJ25" smd circle
			(at 0 3.800094)
			(size 0.4572 0.4572)
			(layers "F.Cu" "F.Mask" "F.Paste")
			(net "GND")
		)
		(pad "AJ26" smd circle
			(at 0.94996 3.800094)
			(size 0.4572 0.4572)
			(layers "F.Cu" "F.Mask" "F.Paste")
			(net "GND")
		)
		(pad "AJ27" smd circle
			(at 1.89992 3.800094)
			(size 0.4572 0.4572)
			(layers "F.Cu" "F.Mask" "F.Paste")
			(net "GND")
		)
		(pad "AJ28" smd circle
			(at 2.84988 3.800094)
			(size 0.4572 0.4572)
			(layers "F.Cu" "F.Mask" "F.Paste")
			(net "GND")
		)
		(pad "AJ29" smd circle
			(at 3.800094 3.800094)
			(size 0.4572 0.4572)
			(layers "F.Cu" "F.Mask" "F.Paste")
			(net "GND")
		)
		(pad "AJ30" smd circle
			(at 4.750054 3.800094)
			(size 0.4572 0.4572)
			(layers "F.Cu" "F.Mask" "F.Paste")
			(net "GND")
		)
		(pad "AJ31" smd circle
			(at 5.700014 3.800094)
			(size 0.4572 0.4572)
			(layers "F.Cu" "F.Mask" "F.Paste")
			(net "GND")
		)
		(pad "AJ32" smd circle
			(at 6.649974 3.800094)
			(size 0.4572 0.4572)
			(layers "F.Cu" "F.Mask" "F.Paste")
			(net "GND")
		)
		(pad "AJ33" smd circle
			(at 7.599934 3.800094)
			(size 0.4572 0.4572)
			(layers "F.Cu" "F.Mask" "F.Paste")
			(net "GND")
		)
		(pad "AJ34" smd circle
			(at 8.549894 3.800094)
			(size 0.4572 0.4572)
			(layers "F.Cu" "F.Mask" "F.Paste")
			(net "GND")
		)
		(pad "AJ35" smd circle
			(at 9.500108 3.800094)
			(size 0.4572 0.4572)
			(layers "F.Cu" "F.Mask" "F.Paste")
			(net "GND")
		)
		(pad "AJ36" smd circle
			(at 10.450068 3.800094)
			(size 0.4572 0.4572)
			(layers "F.Cu" "F.Mask" "F.Paste")
			(net "GND")
		)
		(pad "AJ37" smd circle
			(at 11.400028 3.800094)
			(size 0.4572 0.4572)
			(layers "F.Cu" "F.Mask" "F.Paste")
			(net "GND")
		)
		(pad "AJ38" smd circle
			(at 12.349988 3.800094)
			(size 0.4572 0.4572)
			(layers "F.Cu" "F.Mask" "F.Paste")
			(net "UART_PEX2_CLI_TX")
		)
		(pad "AJ39" smd circle
			(at 13.299948 3.800094)
			(size 0.4572 0.4572)
			(layers "F.Cu" "F.Mask" "F.Paste")
			(net "Net_5328")
		)
		(pad "AJ40" smd circle
			(at 14.249908 3.800094)
			(size 0.4572 0.4572)
			(layers "F.Cu" "F.Mask" "F.Paste")
			(net "GND")
		)
		(pad "AJ41" smd circle
			(at 15.200122 3.800094)
			(size 0.4572 0.4572)
			(layers "F.Cu" "F.Mask" "F.Paste")
			(net "GND")
		)
		(pad "AJ42" smd circle
			(at 16.150082 3.800094)
			(size 0.4572 0.4572)
			(layers "F.Cu" "F.Mask" "F.Paste")
			(net "GND")
		)
		(pad "AJ43" smd circle
			(at 17.100042 3.800094)
			(size 0.4572 0.4572)
			(layers "F.Cu" "F.Mask" "F.Paste")
			(net "Net_1703")
		)
		(pad "AJ44" smd circle
			(at 18.050002 3.800094)
			(size 0.4572 0.4572)
			(layers "F.Cu" "F.Mask" "F.Paste")
			(net "Net_1673")
		)
		(pad "AJ45" smd circle
			(at 18.999962 3.800094)
			(size 0.4572 0.4572)
			(layers "F.Cu" "F.Mask" "F.Paste")
			(net "GND")
		)
		(pad "AJ46" smd circle
			(at 19.949922 3.800094)
			(size 0.4572 0.4572)
			(layers "F.Cu" "F.Mask" "F.Paste")
			(net "Net_1632")
		)
		(pad "AJ47" smd circle
			(at 20.899882 3.800094)
			(size 0.4572 0.4572)
			(layers "F.Cu" "F.Mask" "F.Paste")
			(net "Net_1595")
		)
		(pad "AJ48" smd circle
			(at 21.850096 3.800094)
			(size 0.4572 0.4572)
			(layers "F.Cu" "F.Mask" "F.Paste")
			(net "GND")
		)
		(pad "AJ49" smd circle
			(at 22.800056 3.800094)
			(size 0.4572 0.4572)
			(layers "F.Cu" "F.Mask" "F.Paste")
			(net "GND")
		)
		(pad "AK1" smd circle
			(at -22.800056 4.750054)
			(size 0.4572 0.4572)
			(layers "F.Cu" "F.Mask" "F.Paste")
			(net "GND")
		)
		(pad "AK2" smd circle
			(at -21.850096 4.750054)
			(size 0.4572 0.4572)
			(layers "F.Cu" "F.Mask" "F.Paste")
			(net "GND")
		)
		(pad "AK3" smd circle
			(at -20.899882 4.750054)
			(size 0.4572 0.4572)
			(layers "F.Cu" "F.Mask" "F.Paste")
			(net "GND")
		)
		(pad "AK4" smd circle
			(at -19.949922 4.750054)
			(size 0.4572 0.4572)
			(layers "F.Cu" "F.Mask" "F.Paste")
			(net "Net_512")
		)
		(pad "AK5" smd circle
			(at -18.999962 4.750054)
			(size 0.4572 0.4572)
			(layers "F.Cu" "F.Mask" "F.Paste")
			(net "Net_511")
		)
		(pad "AK6" smd circle
			(at -18.050002 4.750054)
			(size 0.4572 0.4572)
			(layers "F.Cu" "F.Mask" "F.Paste")
			(net "GND")
		)
		(pad "AK7" smd circle
			(at -17.100042 4.750054)
			(size 0.4572 0.4572)
			(layers "F.Cu" "F.Mask" "F.Paste")
			(net "Net_5392")
		)
		(pad "AK8" smd circle
			(at -16.150082 4.750054)
			(size 0.4572 0.4572)
			(layers "F.Cu" "F.Mask" "F.Paste")
			(net "GND")
		)
		(pad "AK9" smd circle
			(at -15.200122 4.750054)
			(size 0.4572 0.4572)
			(layers "F.Cu" "F.Mask" "F.Paste")
			(net "GND")
		)
		(pad "AK10" smd circle
			(at -14.249908 4.750054)
			(size 0.4572 0.4572)
			(layers "F.Cu" "F.Mask" "F.Paste")
			(net "P1V8_PEX")
		)
		(pad "AK11" smd circle
			(at -13.299948 4.750054)
			(size 0.4572 0.4572)
			(layers "F.Cu" "F.Mask" "F.Paste")
			(net "GND")
		)
		(pad "AK12" smd circle
			(at -12.349988 4.750054)
			(size 0.4572 0.4572)
			(layers "F.Cu" "F.Mask" "F.Paste")
			(net "P1V8_PEX")
		)
		(pad "AK13" smd circle
			(at -11.400028 4.750054)
			(size 0.4572 0.4572)
			(layers "F.Cu" "F.Mask" "F.Paste")
			(net "GND")
		)
		(pad "AK14" smd circle
			(at -10.450068 4.750054)
			(size 0.4572 0.4572)
			(layers "F.Cu" "F.Mask" "F.Paste")
			(net "P0V8_PEX2")
		)
		(pad "AK15" smd circle
			(at -9.500108 4.750054)
			(size 0.4572 0.4572)
			(layers "F.Cu" "F.Mask" "F.Paste")
			(net "GND")
		)
		(pad "AK16" smd circle
			(at -8.549894 4.750054)
			(size 0.4572 0.4572)
			(layers "F.Cu" "F.Mask" "F.Paste")
			(net "P0V8_SERDES_VDDA_PEX2")
		)
		(pad "AK17" smd circle
			(at -7.599934 4.750054)
			(size 0.4572 0.4572)
			(layers "F.Cu" "F.Mask" "F.Paste")
			(net "P0V8_SERDES_VDDA_PEX2")
		)
		(pad "AK18" smd circle
			(at -6.649974 4.750054)
			(size 0.4572 0.4572)
			(layers "F.Cu" "F.Mask" "F.Paste")
			(net "P0V8_SERDES_VDDA_PEX2")
		)
		(pad "AK19" smd circle
			(at -5.700014 4.750054)
			(size 0.4572 0.4572)
			(layers "F.Cu" "F.Mask" "F.Paste")
			(net "P0V8_SERDES_VDDA_PEX2")
		)
		(pad "AK20" smd circle
			(at -4.750054 4.750054)
			(size 0.4572 0.4572)
			(layers "F.Cu" "F.Mask" "F.Paste")
			(net "P0V8_SERDES_VDDA_PEX2")
		)
		(pad "AK21" smd circle
			(at -3.800094 4.750054)
			(size 0.4572 0.4572)
			(layers "F.Cu" "F.Mask" "F.Paste")
			(net "P0V8_SERDES_VDDA_PEX2")
		)
		(pad "AK22" smd circle
			(at -2.84988 4.750054)
			(size 0.4572 0.4572)
			(layers "F.Cu" "F.Mask" "F.Paste")
			(net "P0V8_SERDES_VDDA_PEX2")
		)
		(pad "AK23" smd circle
			(at -1.89992 4.750054)
			(size 0.4572 0.4572)
			(layers "F.Cu" "F.Mask" "F.Paste")
			(net "P0V8_SERDES_VDDA_PEX2")
		)
		(pad "AK24" smd circle
			(at -0.94996 4.750054)
			(size 0.4572 0.4572)
			(layers "F.Cu" "F.Mask" "F.Paste")
			(net "P0V8_SERDES_VDDA_PEX2")
		)
		(pad "AK25" smd circle
			(at 0 4.750054)
			(size 0.4572 0.4572)
			(layers "F.Cu" "F.Mask" "F.Paste")
			(net "P0V8_SERDES_VDDA_PEX2")
		)
		(pad "AK26" smd circle
			(at 0.94996 4.750054)
			(size 0.4572 0.4572)
			(layers "F.Cu" "F.Mask" "F.Paste")
			(net "P0V8_SERDES_VDDA_PEX2")
		)
		(pad "AK27" smd circle
			(at 1.89992 4.750054)
			(size 0.4572 0.4572)
			(layers "F.Cu" "F.Mask" "F.Paste")
			(net "P0V8_SERDES_VDDA_PEX2")
		)
		(pad "AK28" smd circle
			(at 2.84988 4.750054)
			(size 0.4572 0.4572)
			(layers "F.Cu" "F.Mask" "F.Paste")
			(net "P0V8_SERDES_VDDA_PEX2")
		)
		(pad "AK29" smd circle
			(at 3.800094 4.750054)
			(size 0.4572 0.4572)
			(layers "F.Cu" "F.Mask" "F.Paste")
			(net "P0V8_SERDES_VDDA_PEX2")
		)
		(pad "AK30" smd circle
			(at 4.750054 4.750054)
			(size 0.4572 0.4572)
			(layers "F.Cu" "F.Mask" "F.Paste")
			(net "P0V8_SERDES_VDDA_PEX2")
		)
		(pad "AK31" smd circle
			(at 5.700014 4.750054)
			(size 0.4572 0.4572)
			(layers "F.Cu" "F.Mask" "F.Paste")
			(net "P0V8_SERDES_VDDA_PEX2")
		)
		(pad "AK32" smd circle
			(at 6.649974 4.750054)
			(size 0.4572 0.4572)
			(layers "F.Cu" "F.Mask" "F.Paste")
			(net "P0V8_SERDES_VDDA_PEX2")
		)
		(pad "AK33" smd circle
			(at 7.599934 4.750054)
			(size 0.4572 0.4572)
			(layers "F.Cu" "F.Mask" "F.Paste")
			(net "P0V8_SERDES_VDDA_PEX2")
		)
		(pad "AK34" smd circle
			(at 8.549894 4.750054)
			(size 0.4572 0.4572)
			(layers "F.Cu" "F.Mask" "F.Paste")
			(net "GND")
		)
		(pad "AK35" smd circle
			(at 9.500108 4.750054)
			(size 0.4572 0.4572)
			(layers "F.Cu" "F.Mask" "F.Paste")
			(net "P1V8_PEX")
		)
		(pad "AK36" smd circle
			(at 10.450068 4.750054)
			(size 0.4572 0.4572)
			(layers "F.Cu" "F.Mask" "F.Paste")
			(net "GND")
		)
		(pad "AK37" smd circle
			(at 11.400028 4.750054)
			(size 0.4572 0.4572)
			(layers "F.Cu" "F.Mask" "F.Paste")
			(net "GND")
		)
		(pad "AK38" smd circle
			(at 12.349988 4.750054)
			(size 0.4572 0.4572)
			(layers "F.Cu" "F.Mask" "F.Paste")
			(net "UART_PEX2_CLI_BUF_RX")
		)
		(pad "AK39" smd circle
			(at 13.299948 4.750054)
			(size 0.4572 0.4572)
			(layers "F.Cu" "F.Mask" "F.Paste")
			(net "UART_PEX2_SDB_BUF_RX")
		)
		(pad "AK40" smd circle
			(at 14.249908 4.750054)
			(size 0.4572 0.4572)
			(layers "F.Cu" "F.Mask" "F.Paste")
			(net "GND")
		)
		(pad "AK41" smd circle
			(at 15.200122 4.750054)
			(size 0.4572 0.4572)
			(layers "F.Cu" "F.Mask" "F.Paste")
			(net "Net_1693")
		)
		(pad "AK42" smd circle
			(at 16.150082 4.750054)
			(size 0.4572 0.4572)
			(layers "F.Cu" "F.Mask" "F.Paste")
			(net "Net_1677")
		)
		(pad "AK43" smd circle
			(at 17.100042 4.750054)
			(size 0.4572 0.4572)
			(layers "F.Cu" "F.Mask" "F.Paste")
			(net "GND")
		)
		(pad "AK44" smd circle
			(at 18.050002 4.750054)
			(size 0.4572 0.4572)
			(layers "F.Cu" "F.Mask" "F.Paste")
			(net "GND")
		)
		(pad "AK45" smd circle
			(at 18.999962 4.750054)
			(size 0.4572 0.4572)
			(layers "F.Cu" "F.Mask" "F.Paste")
			(net "GND")
		)
		(pad "AK46" smd circle
			(at 19.949922 4.750054)
			(size 0.4572 0.4572)
			(layers "F.Cu" "F.Mask" "F.Paste")
			(net "GND")
		)
		(pad "AK47" smd circle
			(at 20.899882 4.750054)
			(size 0.4572 0.4572)
			(layers "F.Cu" "F.Mask" "F.Paste")
			(net "GND")
		)
		(pad "AK48" smd circle
			(at 21.850096 4.750054)
			(size 0.4572 0.4572)
			(layers "F.Cu" "F.Mask" "F.Paste")
			(net "Net_1574")
		)
		(pad "AK49" smd circle
			(at 22.800056 4.750054)
			(size 0.4572 0.4572)
			(layers "F.Cu" "F.Mask" "F.Paste")
			(net "Net_1594")
		)
		(pad "AL1" smd circle
			(at -22.800056 5.700014)
			(size 0.4572 0.4572)
			(layers "F.Cu" "F.Mask" "F.Paste")
			(net "GND")
		)
		(pad "AL2" smd circle
			(at -21.850096 5.700014)
			(size 0.4572 0.4572)
			(layers "F.Cu" "F.Mask" "F.Paste")
			(net "GND")
		)
		(pad "AL3" smd circle
			(at -20.899882 5.700014)
			(size 0.4572 0.4572)
			(layers "F.Cu" "F.Mask" "F.Paste")
			(net "GND")
		)
		(pad "AL4" smd circle
			(at -19.949922 5.700014)
			(size 0.4572 0.4572)
			(layers "F.Cu" "F.Mask" "F.Paste")
			(net "GND")
		)
		(pad "AL5" smd circle
			(at -18.999962 5.700014)
			(size 0.4572 0.4572)
			(layers "F.Cu" "F.Mask" "F.Paste")
			(net "GND")
		)
		(pad "AL6" smd circle
			(at -18.050002 5.700014)
			(size 0.4572 0.4572)
			(layers "F.Cu" "F.Mask" "F.Paste")
			(net "GND")
		)
		(pad "AL7" smd circle
			(at -17.100042 5.700014)
			(size 0.4572 0.4572)
			(layers "F.Cu" "F.Mask" "F.Paste")
			(net "GND")
		)
		(pad "AL8" smd circle
			(at -16.150082 5.700014)
			(size 0.4572 0.4572)
			(layers "F.Cu" "F.Mask" "F.Paste")
			(net "GND")
		)
		(pad "AL9" smd circle
			(at -15.200122 5.700014)
			(size 0.4572 0.4572)
			(layers "F.Cu" "F.Mask" "F.Paste")
			(net "GND")
		)
		(pad "AL10" smd circle
			(at -14.249908 5.700014)
			(size 0.4572 0.4572)
			(layers "F.Cu" "F.Mask" "F.Paste")
			(net "GND")
		)
		(pad "AL11" smd circle
			(at -13.299948 5.700014)
			(size 0.4572 0.4572)
			(layers "F.Cu" "F.Mask" "F.Paste")
			(net "GND")
		)
		(pad "AL12" smd circle
			(at -12.349988 5.700014)
			(size 0.4572 0.4572)
			(layers "F.Cu" "F.Mask" "F.Paste")
			(net "GND")
		)
		(pad "AL13" smd circle
			(at -11.400028 5.700014)
			(size 0.4572 0.4572)
			(layers "F.Cu" "F.Mask" "F.Paste")
			(net "GND")
		)
		(pad "AL14" smd circle
			(at -10.450068 5.700014)
			(size 0.4572 0.4572)
			(layers "F.Cu" "F.Mask" "F.Paste")
			(net "VSSA_SENSE")
		)
		(pad "AL15" smd circle
			(at -9.500108 5.700014)
			(size 0.4572 0.4572)
			(layers "F.Cu" "F.Mask" "F.Paste")
			(net "VDDA_SENSE")
		)
		(pad "AL16" smd circle
			(at -8.549894 5.700014)
			(size 0.4572 0.4572)
			(layers "F.Cu" "F.Mask" "F.Paste")
			(net "GND")
		)
		(pad "AL17" smd circle
			(at -7.599934 5.700014)
			(size 0.4572 0.4572)
			(layers "F.Cu" "F.Mask" "F.Paste")
			(net "GND")
		)
		(pad "AL18" smd circle
			(at -6.649974 5.700014)
			(size 0.4572 0.4572)
			(layers "F.Cu" "F.Mask" "F.Paste")
			(net "GND")
		)
		(pad "AL19" smd circle
			(at -5.700014 5.700014)
			(size 0.4572 0.4572)
			(layers "F.Cu" "F.Mask" "F.Paste")
			(net "GND")
		)
		(pad "AL20" smd circle
			(at -4.750054 5.700014)
			(size 0.4572 0.4572)
			(layers "F.Cu" "F.Mask" "F.Paste")
			(net "GND")
		)
		(pad "AL21" smd circle
			(at -3.800094 5.700014)
			(size 0.4572 0.4572)
			(layers "F.Cu" "F.Mask" "F.Paste")
			(net "GND")
		)
		(pad "AL22" smd circle
			(at -2.84988 5.700014)
			(size 0.4572 0.4572)
			(layers "F.Cu" "F.Mask" "F.Paste")
			(net "GND")
		)
		(pad "AL23" smd circle
			(at -1.89992 5.700014)
			(size 0.4572 0.4572)
			(layers "F.Cu" "F.Mask" "F.Paste")
			(net "GND")
		)
		(pad "AL24" smd circle
			(at -0.94996 5.700014)
			(size 0.4572 0.4572)
			(layers "F.Cu" "F.Mask" "F.Paste")
			(net "GND")
		)
		(pad "AL25" smd circle
			(at 0 5.700014)
			(size 0.4572 0.4572)
			(layers "F.Cu" "F.Mask" "F.Paste")
			(net "GND")
		)
		(pad "AL26" smd circle
			(at 0.94996 5.700014)
			(size 0.4572 0.4572)
			(layers "F.Cu" "F.Mask" "F.Paste")
			(net "GND")
		)
		(pad "AL27" smd circle
			(at 1.89992 5.700014)
			(size 0.4572 0.4572)
			(layers "F.Cu" "F.Mask" "F.Paste")
			(net "GND")
		)
		(pad "AL28" smd circle
			(at 2.84988 5.700014)
			(size 0.4572 0.4572)
			(layers "F.Cu" "F.Mask" "F.Paste")
			(net "GND")
		)
		(pad "AL29" smd circle
			(at 3.800094 5.700014)
			(size 0.4572 0.4572)
			(layers "F.Cu" "F.Mask" "F.Paste")
			(net "GND")
		)
		(pad "AL30" smd circle
			(at 4.750054 5.700014)
			(size 0.4572 0.4572)
			(layers "F.Cu" "F.Mask" "F.Paste")
			(net "GND")
		)
		(pad "AL31" smd circle
			(at 5.700014 5.700014)
			(size 0.4572 0.4572)
			(layers "F.Cu" "F.Mask" "F.Paste")
			(net "GND")
		)
		(pad "AL32" smd circle
			(at 6.649974 5.700014)
			(size 0.4572 0.4572)
			(layers "F.Cu" "F.Mask" "F.Paste")
			(net "GND")
		)
		(pad "AL33" smd circle
			(at 7.599934 5.700014)
			(size 0.4572 0.4572)
			(layers "F.Cu" "F.Mask" "F.Paste")
			(net "GND")
		)
		(pad "AL34" smd circle
			(at 8.549894 5.700014)
			(size 0.4572 0.4572)
			(layers "F.Cu" "F.Mask" "F.Paste")
			(net "GND")
		)
		(pad "AL35" smd circle
			(at 9.500108 5.700014)
			(size 0.4572 0.4572)
			(layers "F.Cu" "F.Mask" "F.Paste")
			(net "P1V8_PEX")
		)
		(pad "AL36" smd circle
			(at 10.450068 5.700014)
			(size 0.4572 0.4572)
			(layers "F.Cu" "F.Mask" "F.Paste")
			(net "GND")
		)
		(pad "AL37" smd circle
			(at 11.400028 5.700014)
			(size 0.4572 0.4572)
			(layers "F.Cu" "F.Mask" "F.Paste")
			(net "GND")
		)
		(pad "AL38" smd circle
			(at 12.349988 5.700014)
			(size 0.4572 0.4572)
			(layers "F.Cu" "F.Mask" "F.Paste")
			(net "Net_5359")
		)
		(pad "AL39" smd circle
			(at 13.299948 5.700014)
			(size 0.4572 0.4572)
			(layers "F.Cu" "F.Mask" "F.Paste")
			(net "UART_PEX2_SDB_TX")
		)
		(pad "AL40" smd circle
			(at 14.249908 5.700014)
			(size 0.4572 0.4572)
			(layers "F.Cu" "F.Mask" "F.Paste")
			(net "GND")
		)
		(pad "AL41" smd circle
			(at 15.200122 5.700014)
			(size 0.4572 0.4572)
			(layers "F.Cu" "F.Mask" "F.Paste")
			(net "GND")
		)
		(pad "AL42" smd circle
			(at 16.150082 5.700014)
			(size 0.4572 0.4572)
			(layers "F.Cu" "F.Mask" "F.Paste")
			(net "GND")
		)
		(pad "AL43" smd circle
			(at 17.100042 5.700014)
			(size 0.4572 0.4572)
			(layers "F.Cu" "F.Mask" "F.Paste")
			(net "Net_1704")
		)
		(pad "AL44" smd circle
			(at 18.050002 5.700014)
			(size 0.4572 0.4572)
			(layers "F.Cu" "F.Mask" "F.Paste")
			(net "Net_1659")
		)
		(pad "AL45" smd circle
			(at 18.999962 5.700014)
			(size 0.4572 0.4572)
			(layers "F.Cu" "F.Mask" "F.Paste")
			(net "GND")
		)
		(pad "AL46" smd circle
			(at 19.949922 5.700014)
			(size 0.4572 0.4572)
			(layers "F.Cu" "F.Mask" "F.Paste")
			(net "Net_1607")
		)
		(pad "AL47" smd circle
			(at 20.899882 5.700014)
			(size 0.4572 0.4572)
			(layers "F.Cu" "F.Mask" "F.Paste")
			(net "Net_1601")
		)
		(pad "AL48" smd circle
			(at 21.850096 5.700014)
			(size 0.4572 0.4572)
			(layers "F.Cu" "F.Mask" "F.Paste")
			(net "GND")
		)
		(pad "AL49" smd circle
			(at 22.800056 5.700014)
			(size 0.4572 0.4572)
			(layers "F.Cu" "F.Mask" "F.Paste")
			(net "GND")
		)
		(pad "AM1" smd circle
			(at -22.800056 6.649974)
			(size 0.4572 0.4572)
			(layers "F.Cu" "F.Mask" "F.Paste")
			(net "Net_1590")
		)
		(pad "AM2" smd circle
			(at -21.850096 6.649974)
			(size 0.4572 0.4572)
			(layers "F.Cu" "F.Mask" "F.Paste")
			(net "Net_1565")
		)
		(pad "AM3" smd circle
			(at -20.899882 6.649974)
			(size 0.4572 0.4572)
			(layers "F.Cu" "F.Mask" "F.Paste")
			(net "GND")
		)
		(pad "AM4" smd circle
			(at -19.949922 6.649974)
			(size 0.4572 0.4572)
			(layers "F.Cu" "F.Mask" "F.Paste")
			(net "GND")
		)
		(pad "AM5" smd circle
			(at -18.999962 6.649974)
			(size 0.4572 0.4572)
			(layers "F.Cu" "F.Mask" "F.Paste")
			(net "GND")
		)
		(pad "AM6" smd circle
			(at -18.050002 6.649974)
			(size 0.4572 0.4572)
			(layers "F.Cu" "F.Mask" "F.Paste")
			(net "GND")
		)
		(pad "AM7" smd circle
			(at -17.100042 6.649974)
			(size 0.4572 0.4572)
			(layers "F.Cu" "F.Mask" "F.Paste")
			(net "GND")
		)
		(pad "AM8" smd circle
			(at -16.150082 6.649974)
			(size 0.4572 0.4572)
			(layers "F.Cu" "F.Mask" "F.Paste")
			(net "Net_1431")
		)
		(pad "AM9" smd circle
			(at -15.200122 6.649974)
			(size 0.4572 0.4572)
			(layers "F.Cu" "F.Mask" "F.Paste")
			(net "Net_1445")
		)
		(pad "AM10" smd circle
			(at -14.249908 6.649974)
			(size 0.4572 0.4572)
			(layers "F.Cu" "F.Mask" "F.Paste")
			(net "GND")
		)
		(pad "AM11" smd circle
			(at -13.299948 6.649974)
			(size 0.4572 0.4572)
			(layers "F.Cu" "F.Mask" "F.Paste")
			(net "GND")
		)
		(pad "AM12" smd circle
			(at -12.349988 6.649974)
			(size 0.4572 0.4572)
			(layers "F.Cu" "F.Mask" "F.Paste")
			(net "TP_PEX2_VDDQ_EFUSE")
		)
		(pad "AM13" smd circle
			(at -11.400028 6.649974)
			(size 0.4572 0.4572)
			(layers "F.Cu" "F.Mask" "F.Paste")
			(net "GND")
		)
		(pad "AM14" smd circle
			(at -10.450068 6.649974)
			(size 0.4572 0.4572)
			(layers "F.Cu" "F.Mask" "F.Paste")
			(net "P1V8_VDDA_PEX2")
		)
		(pad "AM15" smd circle
			(at -9.500108 6.649974)
			(size 0.4572 0.4572)
			(layers "F.Cu" "F.Mask" "F.Paste")
			(net "GND")
		)
		(pad "AM16" smd circle
			(at -8.549894 6.649974)
			(size 0.4572 0.4572)
			(layers "F.Cu" "F.Mask" "F.Paste")
			(net "P1V25_PEX2")
		)
		(pad "AM17" smd circle
			(at -7.599934 6.649974)
			(size 0.4572 0.4572)
			(layers "F.Cu" "F.Mask" "F.Paste")
			(net "P1V25_PEX2")
		)
		(pad "AM18" smd circle
			(at -6.649974 6.649974)
			(size 0.4572 0.4572)
			(layers "F.Cu" "F.Mask" "F.Paste")
			(net "P1V25_PEX2")
		)
		(pad "AM19" smd circle
			(at -5.700014 6.649974)
			(size 0.4572 0.4572)
			(layers "F.Cu" "F.Mask" "F.Paste")
			(net "P1V25_PEX2")
		)
		(pad "AM20" smd circle
			(at -4.750054 6.649974)
			(size 0.4572 0.4572)
			(layers "F.Cu" "F.Mask" "F.Paste")
			(net "P1V25_PEX2")
		)
		(pad "AM21" smd circle
			(at -3.800094 6.649974)
			(size 0.4572 0.4572)
			(layers "F.Cu" "F.Mask" "F.Paste")
			(net "P1V25_PEX2")
		)
		(pad "AM22" smd circle
			(at -2.84988 6.649974)
			(size 0.4572 0.4572)
			(layers "F.Cu" "F.Mask" "F.Paste")
			(net "P1V25_PEX2")
		)
		(pad "AM23" smd circle
			(at -1.89992 6.649974)
			(size 0.4572 0.4572)
			(layers "F.Cu" "F.Mask" "F.Paste")
			(net "P1V25_PEX2")
		)
		(pad "AM24" smd circle
			(at -0.94996 6.649974)
			(size 0.4572 0.4572)
			(layers "F.Cu" "F.Mask" "F.Paste")
			(net "P1V25_PEX2")
		)
		(pad "AM25" smd circle
			(at 0 6.649974)
			(size 0.4572 0.4572)
			(layers "F.Cu" "F.Mask" "F.Paste")
			(net "P1V25_PEX2")
		)
		(pad "AM26" smd circle
			(at 0.94996 6.649974)
			(size 0.4572 0.4572)
			(layers "F.Cu" "F.Mask" "F.Paste")
			(net "P1V25_PEX2")
		)
		(pad "AM27" smd circle
			(at 1.89992 6.649974)
			(size 0.4572 0.4572)
			(layers "F.Cu" "F.Mask" "F.Paste")
			(net "P1V25_PEX2")
		)
		(pad "AM28" smd circle
			(at 2.84988 6.649974)
			(size 0.4572 0.4572)
			(layers "F.Cu" "F.Mask" "F.Paste")
			(net "P1V25_PEX2")
		)
		(pad "AM29" smd circle
			(at 3.800094 6.649974)
			(size 0.4572 0.4572)
			(layers "F.Cu" "F.Mask" "F.Paste")
			(net "P1V25_PEX2")
		)
		(pad "AM30" smd circle
			(at 4.750054 6.649974)
			(size 0.4572 0.4572)
			(layers "F.Cu" "F.Mask" "F.Paste")
			(net "P1V25_PEX2")
		)
		(pad "AM31" smd circle
			(at 5.700014 6.649974)
			(size 0.4572 0.4572)
			(layers "F.Cu" "F.Mask" "F.Paste")
			(net "P1V25_PEX2")
		)
		(pad "AM32" smd circle
			(at 6.649974 6.649974)
			(size 0.4572 0.4572)
			(layers "F.Cu" "F.Mask" "F.Paste")
			(net "P1V25_PEX2")
		)
		(pad "AM33" smd circle
			(at 7.599934 6.649974)
			(size 0.4572 0.4572)
			(layers "F.Cu" "F.Mask" "F.Paste")
			(net "P1V25_PEX2")
		)
		(pad "AM34" smd circle
			(at 8.549894 6.649974)
			(size 0.4572 0.4572)
			(layers "F.Cu" "F.Mask" "F.Paste")
			(net "GND")
		)
		(pad "AM35" smd circle
			(at 9.500108 6.649974)
			(size 0.4572 0.4572)
			(layers "F.Cu" "F.Mask" "F.Paste")
			(net "P1V8_PEX")
		)
		(pad "AM36" smd circle
			(at 10.450068 6.649974)
			(size 0.4572 0.4572)
			(layers "F.Cu" "F.Mask" "F.Paste")
			(net "GND")
		)
		(pad "AM37" smd circle
			(at 11.400028 6.649974)
			(size 0.4572 0.4572)
			(layers "F.Cu" "F.Mask" "F.Paste")
			(net "GND")
		)
		(pad "AM38" smd circle
			(at 12.349988 6.649974)
			(size 0.4572 0.4572)
			(layers "F.Cu" "F.Mask" "F.Paste")
			(net "Net_5326")
		)
		(pad "AM39" smd circle
			(at 13.299948 6.649974)
			(size 0.4572 0.4572)
			(layers "F.Cu" "F.Mask" "F.Paste")
			(net "Net_5369")
		)
		(pad "AM40" smd circle
			(at 14.249908 6.649974)
			(size 0.4572 0.4572)
			(layers "F.Cu" "F.Mask" "F.Paste")
			(net "GND")
		)
		(pad "AM41" smd circle
			(at 15.200122 6.649974)
			(size 0.4572 0.4572)
			(layers "F.Cu" "F.Mask" "F.Paste")
			(net "Net_1679")
		)
		(pad "AM42" smd circle
			(at 16.150082 6.649974)
			(size 0.4572 0.4572)
			(layers "F.Cu" "F.Mask" "F.Paste")
			(net "Net_1691")
		)
		(pad "AM43" smd circle
			(at 17.100042 6.649974)
			(size 0.4572 0.4572)
			(layers "F.Cu" "F.Mask" "F.Paste")
			(net "GND")
		)
		(pad "AM44" smd circle
			(at 18.050002 6.649974)
			(size 0.4572 0.4572)
			(layers "F.Cu" "F.Mask" "F.Paste")
			(net "GND")
		)
		(pad "AM45" smd circle
			(at 18.999962 6.649974)
			(size 0.4572 0.4572)
			(layers "F.Cu" "F.Mask" "F.Paste")
			(net "GND")
		)
		(pad "AM46" smd circle
			(at 19.949922 6.649974)
			(size 0.4572 0.4572)
			(layers "F.Cu" "F.Mask" "F.Paste")
			(net "GND")
		)
		(pad "AM47" smd circle
			(at 20.899882 6.649974)
			(size 0.4572 0.4572)
			(layers "F.Cu" "F.Mask" "F.Paste")
			(net "GND")
		)
		(pad "AM48" smd circle
			(at 21.850096 6.649974)
			(size 0.4572 0.4572)
			(layers "F.Cu" "F.Mask" "F.Paste")
			(net "Net_1622")
		)
		(pad "AM49" smd circle
			(at 22.800056 6.649974)
			(size 0.4572 0.4572)
			(layers "F.Cu" "F.Mask" "F.Paste")
			(net "Net_1639")
		)
		(pad "AN1" smd circle
			(at -22.800056 7.599934)
			(size 0.4572 0.4572)
			(layers "F.Cu" "F.Mask" "F.Paste")
			(net "GND")
		)
		(pad "AN2" smd circle
			(at -21.850096 7.599934)
			(size 0.4572 0.4572)
			(layers "F.Cu" "F.Mask" "F.Paste")
			(net "GND")
		)
		(pad "AN3" smd circle
			(at -20.899882 7.599934)
			(size 0.4572 0.4572)
			(layers "F.Cu" "F.Mask" "F.Paste")
			(net "Net_1583")
		)
		(pad "AN4" smd circle
			(at -19.949922 7.599934)
			(size 0.4572 0.4572)
			(layers "F.Cu" "F.Mask" "F.Paste")
			(net "Net_1620")
		)
		(pad "AN5" smd circle
			(at -18.999962 7.599934)
			(size 0.4572 0.4572)
			(layers "F.Cu" "F.Mask" "F.Paste")
			(net "GND")
		)
		(pad "AN6" smd circle
			(at -18.050002 7.599934)
			(size 0.4572 0.4572)
			(layers "F.Cu" "F.Mask" "F.Paste")
			(net "Net_1448")
		)
		(pad "AN7" smd circle
			(at -17.100042 7.599934)
			(size 0.4572 0.4572)
			(layers "F.Cu" "F.Mask" "F.Paste")
			(net "Net_1383")
		)
		(pad "AN8" smd circle
			(at -16.150082 7.599934)
			(size 0.4572 0.4572)
			(layers "F.Cu" "F.Mask" "F.Paste")
			(net "GND")
		)
		(pad "AN9" smd circle
			(at -15.200122 7.599934)
			(size 0.4572 0.4572)
			(layers "F.Cu" "F.Mask" "F.Paste")
			(net "GND")
		)
		(pad "AN10" smd circle
			(at -14.249908 7.599934)
			(size 0.4572 0.4572)
			(layers "F.Cu" "F.Mask" "F.Paste")
			(net "GND")
		)
		(pad "AN11" smd circle
			(at -13.299948 7.599934)
			(size 0.4572 0.4572)
			(layers "F.Cu" "F.Mask" "F.Paste")
			(net "GND")
		)
		(pad "AN12" smd circle
			(at -12.349988 7.599934)
			(size 0.4572 0.4572)
			(layers "F.Cu" "F.Mask" "F.Paste")
			(net "GND")
		)
		(pad "AN13" smd circle
			(at -11.400028 7.599934)
			(size 0.4572 0.4572)
			(layers "F.Cu" "F.Mask" "F.Paste")
			(net "GND")
		)
		(pad "AN14" smd circle
			(at -10.450068 7.599934)
			(size 0.4572 0.4572)
			(layers "F.Cu" "F.Mask" "F.Paste")
			(net "Net_519")
		)
		(pad "AN15" smd circle
			(at -9.500108 7.599934)
			(size 0.4572 0.4572)
			(layers "F.Cu" "F.Mask" "F.Paste")
			(net "GND")
		)
		(pad "AN16" smd circle
			(at -8.549894 7.599934)
			(size 0.4572 0.4572)
			(layers "F.Cu" "F.Mask" "F.Paste")
			(net "GND")
		)
		(pad "AN17" smd circle
			(at -7.599934 7.599934)
			(size 0.4572 0.4572)
			(layers "F.Cu" "F.Mask" "F.Paste")
			(net "GND")
		)
		(pad "AN18" smd circle
			(at -6.649974 7.599934)
			(size 0.4572 0.4572)
			(layers "F.Cu" "F.Mask" "F.Paste")
			(net "GND")
		)
		(pad "AN19" smd circle
			(at -5.700014 7.599934)
			(size 0.4572 0.4572)
			(layers "F.Cu" "F.Mask" "F.Paste")
			(net "GND")
		)
		(pad "AN20" smd circle
			(at -4.750054 7.599934)
			(size 0.4572 0.4572)
			(layers "F.Cu" "F.Mask" "F.Paste")
			(net "GND")
		)
		(pad "AN21" smd circle
			(at -3.800094 7.599934)
			(size 0.4572 0.4572)
			(layers "F.Cu" "F.Mask" "F.Paste")
			(net "GND")
		)
		(pad "AN22" smd circle
			(at -2.84988 7.599934)
			(size 0.4572 0.4572)
			(layers "F.Cu" "F.Mask" "F.Paste")
			(net "GND")
		)
		(pad "AN23" smd circle
			(at -1.89992 7.599934)
			(size 0.4572 0.4572)
			(layers "F.Cu" "F.Mask" "F.Paste")
			(net "GND")
		)
		(pad "AN24" smd circle
			(at -0.94996 7.599934)
			(size 0.4572 0.4572)
			(layers "F.Cu" "F.Mask" "F.Paste")
			(net "GND")
		)
		(pad "AN25" smd circle
			(at 0 7.599934)
			(size 0.4572 0.4572)
			(layers "F.Cu" "F.Mask" "F.Paste")
			(net "GND")
		)
		(pad "AN26" smd circle
			(at 0.94996 7.599934)
			(size 0.4572 0.4572)
			(layers "F.Cu" "F.Mask" "F.Paste")
			(net "GND")
		)
		(pad "AN27" smd circle
			(at 1.89992 7.599934)
			(size 0.4572 0.4572)
			(layers "F.Cu" "F.Mask" "F.Paste")
			(net "GND")
		)
		(pad "AN28" smd circle
			(at 2.84988 7.599934)
			(size 0.4572 0.4572)
			(layers "F.Cu" "F.Mask" "F.Paste")
			(net "GND")
		)
		(pad "AN29" smd circle
			(at 3.800094 7.599934)
			(size 0.4572 0.4572)
			(layers "F.Cu" "F.Mask" "F.Paste")
			(net "GND")
		)
		(pad "AN30" smd circle
			(at 4.750054 7.599934)
			(size 0.4572 0.4572)
			(layers "F.Cu" "F.Mask" "F.Paste")
			(net "GND")
		)
		(pad "AN31" smd circle
			(at 5.700014 7.599934)
			(size 0.4572 0.4572)
			(layers "F.Cu" "F.Mask" "F.Paste")
			(net "GND")
		)
		(pad "AN32" smd circle
			(at 6.649974 7.599934)
			(size 0.4572 0.4572)
			(layers "F.Cu" "F.Mask" "F.Paste")
			(net "GND")
		)
		(pad "AN33" smd circle
			(at 7.599934 7.599934)
			(size 0.4572 0.4572)
			(layers "F.Cu" "F.Mask" "F.Paste")
			(net "GND")
		)
		(pad "AN34" smd circle
			(at 8.549894 7.599934)
			(size 0.4572 0.4572)
			(layers "F.Cu" "F.Mask" "F.Paste")
			(net "GND")
		)
		(pad "AN35" smd circle
			(at 9.500108 7.599934)
			(size 0.4572 0.4572)
			(layers "F.Cu" "F.Mask" "F.Paste")
			(net "GND")
		)
		(pad "AN36" smd circle
			(at 10.450068 7.599934)
			(size 0.4572 0.4572)
			(layers "F.Cu" "F.Mask" "F.Paste")
			(net "Net_518")
		)
		(pad "AN37" smd circle
			(at 11.400028 7.599934)
			(size 0.4572 0.4572)
			(layers "F.Cu" "F.Mask" "F.Paste")
			(net "GND")
		)
		(pad "AN38" smd circle
			(at 12.349988 7.599934)
			(size 0.4572 0.4572)
			(layers "F.Cu" "F.Mask" "F.Paste")
			(net "Net_5360")
		)
		(pad "AN39" smd circle
			(at 13.299948 7.599934)
			(size 0.4572 0.4572)
			(layers "F.Cu" "F.Mask" "F.Paste")
			(net "Net_5327")
		)
		(pad "AN40" smd circle
			(at 14.249908 7.599934)
			(size 0.4572 0.4572)
			(layers "F.Cu" "F.Mask" "F.Paste")
			(net "GND")
		)
		(pad "AN41" smd circle
			(at 15.200122 7.599934)
			(size 0.4572 0.4572)
			(layers "F.Cu" "F.Mask" "F.Paste")
			(net "GND")
		)
		(pad "AN42" smd circle
			(at 16.150082 7.599934)
			(size 0.4572 0.4572)
			(layers "F.Cu" "F.Mask" "F.Paste")
			(net "GND")
		)
		(pad "AN43" smd circle
			(at 17.100042 7.599934)
			(size 0.4572 0.4572)
			(layers "F.Cu" "F.Mask" "F.Paste")
			(net "P5E_PEX2_STN0_TX_DP<0>")
		)
		(pad "AN44" smd circle
			(at 18.050002 7.599934)
			(size 0.4572 0.4572)
			(layers "F.Cu" "F.Mask" "F.Paste")
			(net "P5E_PEX2_STN0_TX_DN<0>")
		)
		(pad "AN45" smd circle
			(at 18.999962 7.599934)
			(size 0.4572 0.4572)
			(layers "F.Cu" "F.Mask" "F.Paste")
			(net "GND")
		)
		(pad "AN46" smd circle
			(at 19.949922 7.599934)
			(size 0.4572 0.4572)
			(layers "F.Cu" "F.Mask" "F.Paste")
			(net "P5E_PEX2_STN0_RX_DP<0>")
		)
		(pad "AN47" smd circle
			(at 20.899882 7.599934)
			(size 0.4572 0.4572)
			(layers "F.Cu" "F.Mask" "F.Paste")
			(net "P5E_PEX2_STN0_RX_DN<0>")
		)
		(pad "AN48" smd circle
			(at 21.850096 7.599934)
			(size 0.4572 0.4572)
			(layers "F.Cu" "F.Mask" "F.Paste")
			(net "GND")
		)
		(pad "AN49" smd circle
			(at 22.800056 7.599934)
			(size 0.4572 0.4572)
			(layers "F.Cu" "F.Mask" "F.Paste")
			(net "GND")
		)
		(pad "AP1" smd circle
			(at -22.800056 8.549894)
			(size 0.4572 0.4572)
			(layers "F.Cu" "F.Mask" "F.Paste")
			(net "Net_1598")
		)
		(pad "AP2" smd circle
			(at -21.850096 8.549894)
			(size 0.4572 0.4572)
			(layers "F.Cu" "F.Mask" "F.Paste")
			(net "Net_1593")
		)
		(pad "AP3" smd circle
			(at -20.899882 8.549894)
			(size 0.4572 0.4572)
			(layers "F.Cu" "F.Mask" "F.Paste")
			(net "GND")
		)
		(pad "AP4" smd circle
			(at -19.949922 8.549894)
			(size 0.4572 0.4572)
			(layers "F.Cu" "F.Mask" "F.Paste")
			(net "GND")
		)
		(pad "AP5" smd circle
			(at -18.999962 8.549894)
			(size 0.4572 0.4572)
			(layers "F.Cu" "F.Mask" "F.Paste")
			(net "GND")
		)
		(pad "AP6" smd circle
			(at -18.050002 8.549894)
			(size 0.4572 0.4572)
			(layers "F.Cu" "F.Mask" "F.Paste")
			(net "GND")
		)
		(pad "AP7" smd circle
			(at -17.100042 8.549894)
			(size 0.4572 0.4572)
			(layers "F.Cu" "F.Mask" "F.Paste")
			(net "GND")
		)
		(pad "AP8" smd circle
			(at -16.150082 8.549894)
			(size 0.4572 0.4572)
			(layers "F.Cu" "F.Mask" "F.Paste")
			(net "Net_1371")
		)
		(pad "AP9" smd circle
			(at -15.200122 8.549894)
			(size 0.4572 0.4572)
			(layers "F.Cu" "F.Mask" "F.Paste")
			(net "Net_1420")
		)
		(pad "AP10" smd circle
			(at -14.249908 8.549894)
			(size 0.4572 0.4572)
			(layers "F.Cu" "F.Mask" "F.Paste")
			(net "GND")
		)
		(pad "AP11" smd circle
			(at -13.299948 8.549894)
			(size 0.4572 0.4572)
			(layers "F.Cu" "F.Mask" "F.Paste")
			(net "GND")
		)
		(pad "AP12" smd circle
			(at -12.349988 8.549894)
			(size 0.4572 0.4572)
			(layers "F.Cu" "F.Mask" "F.Paste")
			(net "GND")
		)
		(pad "AP13" smd circle
			(at -11.400028 8.549894)
			(size 0.4572 0.4572)
			(layers "F.Cu" "F.Mask" "F.Paste")
			(net "GND")
		)
		(pad "AP14" smd circle
			(at -10.450068 8.549894)
			(size 0.4572 0.4572)
			(layers "F.Cu" "F.Mask" "F.Paste")
			(net "Net_521")
		)
		(pad "AP15" smd circle
			(at -9.500108 8.549894)
			(size 0.4572 0.4572)
			(layers "F.Cu" "F.Mask" "F.Paste")
			(net "GND")
		)
		(pad "AP16" smd circle
			(at -8.549894 8.549894)
			(size 0.4572 0.4572)
			(layers "F.Cu" "F.Mask" "F.Paste")
			(net "P1V25_SERDES_VDDPLL_PEX2")
		)
		(pad "AP17" smd circle
			(at -7.599934 8.549894)
			(size 0.4572 0.4572)
			(layers "F.Cu" "F.Mask" "F.Paste")
			(net "P1V25_SERDES_VDDPLL_PEX2")
		)
		(pad "AP18" smd circle
			(at -6.649974 8.549894)
			(size 0.4572 0.4572)
			(layers "F.Cu" "F.Mask" "F.Paste")
			(net "P1V25_SERDES_VDDPLL_PEX2")
		)
		(pad "AP19" smd circle
			(at -5.700014 8.549894)
			(size 0.4572 0.4572)
			(layers "F.Cu" "F.Mask" "F.Paste")
			(net "P1V25_SERDES_VDDPLL_PEX2")
		)
		(pad "AP20" smd circle
			(at -4.750054 8.549894)
			(size 0.4572 0.4572)
			(layers "F.Cu" "F.Mask" "F.Paste")
			(net "P1V25_SERDES_VDDPLL_PEX2")
		)
		(pad "AP21" smd circle
			(at -3.800094 8.549894)
			(size 0.4572 0.4572)
			(layers "F.Cu" "F.Mask" "F.Paste")
			(net "P1V25_SERDES_VDDPLL_PEX2")
		)
		(pad "AP22" smd circle
			(at -2.84988 8.549894)
			(size 0.4572 0.4572)
			(layers "F.Cu" "F.Mask" "F.Paste")
			(net "P1V25_SERDES_VDDPLL_PEX2")
		)
		(pad "AP23" smd circle
			(at -1.89992 8.549894)
			(size 0.4572 0.4572)
			(layers "F.Cu" "F.Mask" "F.Paste")
			(net "P1V25_SERDES_VDDPLL_PEX2")
		)
		(pad "AP24" smd circle
			(at -0.94996 8.549894)
			(size 0.4572 0.4572)
			(layers "F.Cu" "F.Mask" "F.Paste")
			(net "P1V25_SERDES_VDDPLL_PEX2")
		)
		(pad "AP25" smd circle
			(at 0 8.549894)
			(size 0.4572 0.4572)
			(layers "F.Cu" "F.Mask" "F.Paste")
			(net "P1V25_SERDES_VDDPLL_PEX2")
		)
		(pad "AP26" smd circle
			(at 0.94996 8.549894)
			(size 0.4572 0.4572)
			(layers "F.Cu" "F.Mask" "F.Paste")
			(net "P1V25_SERDES_VDDPLL_PEX2")
		)
		(pad "AP27" smd circle
			(at 1.89992 8.549894)
			(size 0.4572 0.4572)
			(layers "F.Cu" "F.Mask" "F.Paste")
			(net "P1V25_SERDES_VDDPLL_PEX2")
		)
		(pad "AP28" smd circle
			(at 2.84988 8.549894)
			(size 0.4572 0.4572)
			(layers "F.Cu" "F.Mask" "F.Paste")
			(net "P1V25_SERDES_VDDPLL_PEX2")
		)
		(pad "AP29" smd circle
			(at 3.800094 8.549894)
			(size 0.4572 0.4572)
			(layers "F.Cu" "F.Mask" "F.Paste")
			(net "P1V25_SERDES_VDDPLL_PEX2")
		)
		(pad "AP30" smd circle
			(at 4.750054 8.549894)
			(size 0.4572 0.4572)
			(layers "F.Cu" "F.Mask" "F.Paste")
			(net "P1V25_SERDES_VDDPLL_PEX2")
		)
		(pad "AP31" smd circle
			(at 5.700014 8.549894)
			(size 0.4572 0.4572)
			(layers "F.Cu" "F.Mask" "F.Paste")
			(net "P1V25_SERDES_VDDPLL_PEX2")
		)
		(pad "AP32" smd circle
			(at 6.649974 8.549894)
			(size 0.4572 0.4572)
			(layers "F.Cu" "F.Mask" "F.Paste")
			(net "P1V25_SERDES_VDDPLL_PEX2")
		)
		(pad "AP33" smd circle
			(at 7.599934 8.549894)
			(size 0.4572 0.4572)
			(layers "F.Cu" "F.Mask" "F.Paste")
			(net "P1V25_SERDES_VDDPLL_PEX2")
		)
		(pad "AP34" smd circle
			(at 8.549894 8.549894)
			(size 0.4572 0.4572)
			(layers "F.Cu" "F.Mask" "F.Paste")
			(net "GND")
		)
		(pad "AP35" smd circle
			(at 9.500108 8.549894)
			(size 0.4572 0.4572)
			(layers "F.Cu" "F.Mask" "F.Paste")
			(net "P1V8_VDDA_PEX2")
		)
		(pad "AP36" smd circle
			(at 10.450068 8.549894)
			(size 0.4572 0.4572)
			(layers "F.Cu" "F.Mask" "F.Paste")
			(net "Net_525")
		)
		(pad "AP37" smd circle
			(at 11.400028 8.549894)
			(size 0.4572 0.4572)
			(layers "F.Cu" "F.Mask" "F.Paste")
			(net "GND")
		)
		(pad "AP38" smd circle
			(at 12.349988 8.549894)
			(size 0.4572 0.4572)
			(layers "F.Cu" "F.Mask" "F.Paste")
			(net "Net_5380")
		)
		(pad "AP39" smd circle
			(at 13.299948 8.549894)
			(size 0.4572 0.4572)
			(layers "F.Cu" "F.Mask" "F.Paste")
			(net "Net_5386")
		)
		(pad "AP40" smd circle
			(at 14.249908 8.549894)
			(size 0.4572 0.4572)
			(layers "F.Cu" "F.Mask" "F.Paste")
			(net "GND")
		)
		(pad "AP41" smd circle
			(at 15.200122 8.549894)
			(size 0.4572 0.4572)
			(layers "F.Cu" "F.Mask" "F.Paste")
			(net "P5E_PEX2_STN0_TX_DP<1>")
		)
		(pad "AP42" smd circle
			(at 16.150082 8.549894)
			(size 0.4572 0.4572)
			(layers "F.Cu" "F.Mask" "F.Paste")
			(net "P5E_PEX2_STN0_TX_DN<1>")
		)
		(pad "AP43" smd circle
			(at 17.100042 8.549894)
			(size 0.4572 0.4572)
			(layers "F.Cu" "F.Mask" "F.Paste")
			(net "GND")
		)
		(pad "AP44" smd circle
			(at 18.050002 8.549894)
			(size 0.4572 0.4572)
			(layers "F.Cu" "F.Mask" "F.Paste")
			(net "GND")
		)
		(pad "AP45" smd circle
			(at 18.999962 8.549894)
			(size 0.4572 0.4572)
			(layers "F.Cu" "F.Mask" "F.Paste")
			(net "GND")
		)
		(pad "AP46" smd circle
			(at 19.949922 8.549894)
			(size 0.4572 0.4572)
			(layers "F.Cu" "F.Mask" "F.Paste")
			(net "GND")
		)
		(pad "AP47" smd circle
			(at 20.899882 8.549894)
			(size 0.4572 0.4572)
			(layers "F.Cu" "F.Mask" "F.Paste")
			(net "GND")
		)
		(pad "AP48" smd circle
			(at 21.850096 8.549894)
			(size 0.4572 0.4572)
			(layers "F.Cu" "F.Mask" "F.Paste")
			(net "P5E_PEX2_STN0_RX_DP<1>")
		)
		(pad "AP49" smd circle
			(at 22.800056 8.549894)
			(size 0.4572 0.4572)
			(layers "F.Cu" "F.Mask" "F.Paste")
			(net "P5E_PEX2_STN0_RX_DN<1>")
		)
		(pad "AR1" smd circle
			(at -22.800056 9.500108)
			(size 0.4572 0.4572)
			(layers "F.Cu" "F.Mask" "F.Paste")
			(net "GND")
		)
		(pad "AR2" smd circle
			(at -21.850096 9.500108)
			(size 0.4572 0.4572)
			(layers "F.Cu" "F.Mask" "F.Paste")
			(net "GND")
		)
		(pad "AR3" smd circle
			(at -20.899882 9.500108)
			(size 0.4572 0.4572)
			(layers "F.Cu" "F.Mask" "F.Paste")
			(net "Net_1642")
		)
		(pad "AR4" smd circle
			(at -19.949922 9.500108)
			(size 0.4572 0.4572)
			(layers "F.Cu" "F.Mask" "F.Paste")
			(net "Net_1626")
		)
		(pad "AR5" smd circle
			(at -18.999962 9.500108)
			(size 0.4572 0.4572)
			(layers "F.Cu" "F.Mask" "F.Paste")
			(net "GND")
		)
		(pad "AR6" smd circle
			(at -18.050002 9.500108)
			(size 0.4572 0.4572)
			(layers "F.Cu" "F.Mask" "F.Paste")
			(net "Net_1373")
		)
		(pad "AR7" smd circle
			(at -17.100042 9.500108)
			(size 0.4572 0.4572)
			(layers "F.Cu" "F.Mask" "F.Paste")
			(net "Net_1714")
		)
		(pad "AR8" smd circle
			(at -16.150082 9.500108)
			(size 0.4572 0.4572)
			(layers "F.Cu" "F.Mask" "F.Paste")
			(net "GND")
		)
		(pad "AR9" smd circle
			(at -15.200122 9.500108)
			(size 0.4572 0.4572)
			(layers "F.Cu" "F.Mask" "F.Paste")
			(net "GND")
		)
		(pad "AR10" smd circle
			(at -14.249908 9.500108)
			(size 0.4572 0.4572)
			(layers "F.Cu" "F.Mask" "F.Paste")
			(net "GND")
		)
		(pad "AR11" smd circle
			(at -13.299948 9.500108)
			(size 0.4572 0.4572)
			(layers "F.Cu" "F.Mask" "F.Paste")
			(net "GND")
		)
		(pad "AR12" smd circle
			(at -12.349988 9.500108)
			(size 0.4572 0.4572)
			(layers "F.Cu" "F.Mask" "F.Paste")
			(net "GND")
		)
		(pad "AR13" smd circle
			(at -11.400028 9.500108)
			(size 0.4572 0.4572)
			(layers "F.Cu" "F.Mask" "F.Paste")
			(net "GND")
		)
		(pad "AR14" smd circle
			(at -10.450068 9.500108)
			(size 0.4572 0.4572)
			(layers "F.Cu" "F.Mask" "F.Paste")
			(net "GND")
		)
		(pad "AR15" smd circle
			(at -9.500108 9.500108)
			(size 0.4572 0.4572)
			(layers "F.Cu" "F.Mask" "F.Paste")
			(net "GND")
		)
		(pad "AR16" smd circle
			(at -8.549894 9.500108)
			(size 0.4572 0.4572)
			(layers "F.Cu" "F.Mask" "F.Paste")
			(net "GND")
		)
		(pad "AR17" smd circle
			(at -7.599934 9.500108)
			(size 0.4572 0.4572)
			(layers "F.Cu" "F.Mask" "F.Paste")
			(net "GND")
		)
		(pad "AR18" smd circle
			(at -6.649974 9.500108)
			(size 0.4572 0.4572)
			(layers "F.Cu" "F.Mask" "F.Paste")
			(net "GND")
		)
		(pad "AR19" smd circle
			(at -5.700014 9.500108)
			(size 0.4572 0.4572)
			(layers "F.Cu" "F.Mask" "F.Paste")
			(net "GND")
		)
		(pad "AR20" smd circle
			(at -4.750054 9.500108)
			(size 0.4572 0.4572)
			(layers "F.Cu" "F.Mask" "F.Paste")
			(net "GND")
		)
		(pad "AR21" smd circle
			(at -3.800094 9.500108)
			(size 0.4572 0.4572)
			(layers "F.Cu" "F.Mask" "F.Paste")
			(net "GND")
		)
		(pad "AR22" smd circle
			(at -2.84988 9.500108)
			(size 0.4572 0.4572)
			(layers "F.Cu" "F.Mask" "F.Paste")
			(net "GND")
		)
		(pad "AR23" smd circle
			(at -1.89992 9.500108)
			(size 0.4572 0.4572)
			(layers "F.Cu" "F.Mask" "F.Paste")
			(net "GND")
		)
		(pad "AR24" smd circle
			(at -0.94996 9.500108)
			(size 0.4572 0.4572)
			(layers "F.Cu" "F.Mask" "F.Paste")
			(net "GND")
		)
		(pad "AR25" smd circle
			(at 0 9.500108)
			(size 0.4572 0.4572)
			(layers "F.Cu" "F.Mask" "F.Paste")
			(net "GND")
		)
		(pad "AR26" smd circle
			(at 0.94996 9.500108)
			(size 0.4572 0.4572)
			(layers "F.Cu" "F.Mask" "F.Paste")
			(net "GND")
		)
		(pad "AR27" smd circle
			(at 1.89992 9.500108)
			(size 0.4572 0.4572)
			(layers "F.Cu" "F.Mask" "F.Paste")
			(net "GND")
		)
		(pad "AR28" smd circle
			(at 2.84988 9.500108)
			(size 0.4572 0.4572)
			(layers "F.Cu" "F.Mask" "F.Paste")
			(net "GND")
		)
		(pad "AR29" smd circle
			(at 3.800094 9.500108)
			(size 0.4572 0.4572)
			(layers "F.Cu" "F.Mask" "F.Paste")
			(net "GND")
		)
		(pad "AR30" smd circle
			(at 4.750054 9.500108)
			(size 0.4572 0.4572)
			(layers "F.Cu" "F.Mask" "F.Paste")
			(net "GND")
		)
		(pad "AR31" smd circle
			(at 5.700014 9.500108)
			(size 0.4572 0.4572)
			(layers "F.Cu" "F.Mask" "F.Paste")
			(net "GND")
		)
		(pad "AR32" smd circle
			(at 6.649974 9.500108)
			(size 0.4572 0.4572)
			(layers "F.Cu" "F.Mask" "F.Paste")
			(net "GND")
		)
		(pad "AR33" smd circle
			(at 7.599934 9.500108)
			(size 0.4572 0.4572)
			(layers "F.Cu" "F.Mask" "F.Paste")
			(net "GND")
		)
		(pad "AR34" smd circle
			(at 8.549894 9.500108)
			(size 0.4572 0.4572)
			(layers "F.Cu" "F.Mask" "F.Paste")
			(net "GND")
		)
		(pad "AR35" smd circle
			(at 9.500108 9.500108)
			(size 0.4572 0.4572)
			(layers "F.Cu" "F.Mask" "F.Paste")
			(net "GND")
		)
		(pad "AR36" smd circle
			(at 10.450068 9.500108)
			(size 0.4572 0.4572)
			(layers "F.Cu" "F.Mask" "F.Paste")
			(net "Net_514")
		)
		(pad "AR37" smd circle
			(at 11.400028 9.500108)
			(size 0.4572 0.4572)
			(layers "F.Cu" "F.Mask" "F.Paste")
			(net "GND")
		)
		(pad "AR38" smd circle
			(at 12.349988 9.500108)
			(size 0.4572 0.4572)
			(layers "F.Cu" "F.Mask" "F.Paste")
			(net "Net_5385")
		)
		(pad "AR39" smd circle
			(at 13.299948 9.500108)
			(size 0.4572 0.4572)
			(layers "F.Cu" "F.Mask" "F.Paste")
			(net "Net_5387")
		)
		(pad "AR40" smd circle
			(at 14.249908 9.500108)
			(size 0.4572 0.4572)
			(layers "F.Cu" "F.Mask" "F.Paste")
			(net "GND")
		)
		(pad "AR41" smd circle
			(at 15.200122 9.500108)
			(size 0.4572 0.4572)
			(layers "F.Cu" "F.Mask" "F.Paste")
			(net "GND")
		)
		(pad "AR42" smd circle
			(at 16.150082 9.500108)
			(size 0.4572 0.4572)
			(layers "F.Cu" "F.Mask" "F.Paste")
			(net "GND")
		)
		(pad "AR43" smd circle
			(at 17.100042 9.500108)
			(size 0.4572 0.4572)
			(layers "F.Cu" "F.Mask" "F.Paste")
			(net "P5E_PEX2_STN0_TX_DP<2>")
		)
		(pad "AR44" smd circle
			(at 18.050002 9.500108)
			(size 0.4572 0.4572)
			(layers "F.Cu" "F.Mask" "F.Paste")
			(net "P5E_PEX2_STN0_TX_DN<2>")
		)
		(pad "AR45" smd circle
			(at 18.999962 9.500108)
			(size 0.4572 0.4572)
			(layers "F.Cu" "F.Mask" "F.Paste")
			(net "GND")
		)
		(pad "AR46" smd circle
			(at 19.949922 9.500108)
			(size 0.4572 0.4572)
			(layers "F.Cu" "F.Mask" "F.Paste")
			(net "P5E_PEX2_STN0_RX_DP<2>")
		)
		(pad "AR47" smd circle
			(at 20.899882 9.500108)
			(size 0.4572 0.4572)
			(layers "F.Cu" "F.Mask" "F.Paste")
			(net "P5E_PEX2_STN0_RX_DN<2>")
		)
		(pad "AR48" smd circle
			(at 21.850096 9.500108)
			(size 0.4572 0.4572)
			(layers "F.Cu" "F.Mask" "F.Paste")
			(net "GND")
		)
		(pad "AR49" smd circle
			(at 22.800056 9.500108)
			(size 0.4572 0.4572)
			(layers "F.Cu" "F.Mask" "F.Paste")
			(net "GND")
		)
		(pad "AT1" smd circle
			(at -22.800056 10.450068)
			(size 0.4572 0.4572)
			(layers "F.Cu" "F.Mask" "F.Paste")
			(net "Net_1578")
		)
		(pad "AT2" smd circle
			(at -21.850096 10.450068)
			(size 0.4572 0.4572)
			(layers "F.Cu" "F.Mask" "F.Paste")
			(net "Net_1570")
		)
		(pad "AT3" smd circle
			(at -20.899882 10.450068)
			(size 0.4572 0.4572)
			(layers "F.Cu" "F.Mask" "F.Paste")
			(net "GND")
		)
		(pad "AT4" smd circle
			(at -19.949922 10.450068)
			(size 0.4572 0.4572)
			(layers "F.Cu" "F.Mask" "F.Paste")
			(net "GND")
		)
		(pad "AT5" smd circle
			(at -18.999962 10.450068)
			(size 0.4572 0.4572)
			(layers "F.Cu" "F.Mask" "F.Paste")
			(net "GND")
		)
		(pad "AT6" smd circle
			(at -18.050002 10.450068)
			(size 0.4572 0.4572)
			(layers "F.Cu" "F.Mask" "F.Paste")
			(net "GND")
		)
		(pad "AT7" smd circle
			(at -17.100042 10.450068)
			(size 0.4572 0.4572)
			(layers "F.Cu" "F.Mask" "F.Paste")
			(net "GND")
		)
		(pad "AT8" smd circle
			(at -16.150082 10.450068)
			(size 0.4572 0.4572)
			(layers "F.Cu" "F.Mask" "F.Paste")
			(net "Net_1718")
		)
		(pad "AT9" smd circle
			(at -15.200122 10.450068)
			(size 0.4572 0.4572)
			(layers "F.Cu" "F.Mask" "F.Paste")
			(net "Net_1414")
		)
		(pad "AT10" smd circle
			(at -14.249908 10.450068)
			(size 0.4572 0.4572)
			(layers "F.Cu" "F.Mask" "F.Paste")
			(net "GND")
		)
		(pad "AT11" smd circle
			(at -13.299948 10.450068)
			(size 0.4572 0.4572)
			(layers "F.Cu" "F.Mask" "F.Paste")
			(net "GND")
		)
		(pad "AT12" smd circle
			(at -12.349988 10.450068)
			(size 0.4572 0.4572)
			(layers "F.Cu" "F.Mask" "F.Paste")
			(net "GND")
		)
		(pad "AT13" smd circle
			(at -11.400028 10.450068)
			(size 0.4572 0.4572)
			(layers "F.Cu" "F.Mask" "F.Paste")
			(net "GND")
		)
		(pad "AT14" smd circle
			(at -10.450068 10.450068)
			(size 0.4572 0.4572)
			(layers "F.Cu" "F.Mask" "F.Paste")
			(net "GND")
		)
		(pad "AT15" smd circle
			(at -9.500108 10.450068)
			(size 0.4572 0.4572)
			(layers "F.Cu" "F.Mask" "F.Paste")
			(net "GND")
		)
		(pad "AT16" smd circle
			(at -8.549894 10.450068)
			(size 0.4572 0.4572)
			(layers "F.Cu" "F.Mask" "F.Paste")
			(net "GND")
		)
		(pad "AT17" smd circle
			(at -7.599934 10.450068)
			(size 0.4572 0.4572)
			(layers "F.Cu" "F.Mask" "F.Paste")
			(net "GND")
		)
		(pad "AT18" smd circle
			(at -6.649974 10.450068)
			(size 0.4572 0.4572)
			(layers "F.Cu" "F.Mask" "F.Paste")
			(net "GND")
		)
		(pad "AT19" smd circle
			(at -5.700014 10.450068)
			(size 0.4572 0.4572)
			(layers "F.Cu" "F.Mask" "F.Paste")
			(net "GND")
		)
		(pad "AT20" smd circle
			(at -4.750054 10.450068)
			(size 0.4572 0.4572)
			(layers "F.Cu" "F.Mask" "F.Paste")
			(net "GND")
		)
		(pad "AT21" smd circle
			(at -3.800094 10.450068)
			(size 0.4572 0.4572)
			(layers "F.Cu" "F.Mask" "F.Paste")
			(net "GND")
		)
		(pad "AT22" smd circle
			(at -2.84988 10.450068)
			(size 0.4572 0.4572)
			(layers "F.Cu" "F.Mask" "F.Paste")
			(net "GND")
		)
		(pad "AT23" smd circle
			(at -1.89992 10.450068)
			(size 0.4572 0.4572)
			(layers "F.Cu" "F.Mask" "F.Paste")
			(net "GND")
		)
		(pad "AT24" smd circle
			(at -0.94996 10.450068)
			(size 0.4572 0.4572)
			(layers "F.Cu" "F.Mask" "F.Paste")
			(net "GND")
		)
		(pad "AT25" smd circle
			(at 0 10.450068)
			(size 0.4572 0.4572)
			(layers "F.Cu" "F.Mask" "F.Paste")
			(net "GND")
		)
		(pad "AT26" smd circle
			(at 0.94996 10.450068)
			(size 0.4572 0.4572)
			(layers "F.Cu" "F.Mask" "F.Paste")
			(net "GND")
		)
		(pad "AT27" smd circle
			(at 1.89992 10.450068)
			(size 0.4572 0.4572)
			(layers "F.Cu" "F.Mask" "F.Paste")
			(net "GND")
		)
		(pad "AT28" smd circle
			(at 2.84988 10.450068)
			(size 0.4572 0.4572)
			(layers "F.Cu" "F.Mask" "F.Paste")
			(net "GND")
		)
		(pad "AT29" smd circle
			(at 3.800094 10.450068)
			(size 0.4572 0.4572)
			(layers "F.Cu" "F.Mask" "F.Paste")
			(net "GND")
		)
		(pad "AT30" smd circle
			(at 4.750054 10.450068)
			(size 0.4572 0.4572)
			(layers "F.Cu" "F.Mask" "F.Paste")
			(net "GND")
		)
		(pad "AT31" smd circle
			(at 5.700014 10.450068)
			(size 0.4572 0.4572)
			(layers "F.Cu" "F.Mask" "F.Paste")
			(net "GND")
		)
		(pad "AT32" smd circle
			(at 6.649974 10.450068)
			(size 0.4572 0.4572)
			(layers "F.Cu" "F.Mask" "F.Paste")
			(net "GND")
		)
		(pad "AT33" smd circle
			(at 7.599934 10.450068)
			(size 0.4572 0.4572)
			(layers "F.Cu" "F.Mask" "F.Paste")
			(net "GND")
		)
		(pad "AT34" smd circle
			(at 8.549894 10.450068)
			(size 0.4572 0.4572)
			(layers "F.Cu" "F.Mask" "F.Paste")
			(net "GND")
		)
		(pad "AT35" smd circle
			(at 9.500108 10.450068)
			(size 0.4572 0.4572)
			(layers "F.Cu" "F.Mask" "F.Paste")
			(net "GND")
		)
		(pad "AT36" smd circle
			(at 10.450068 10.450068)
			(size 0.4572 0.4572)
			(layers "F.Cu" "F.Mask" "F.Paste")
			(net "Net_515")
		)
		(pad "AT37" smd circle
			(at 11.400028 10.450068)
			(size 0.4572 0.4572)
			(layers "F.Cu" "F.Mask" "F.Paste")
			(net "GND")
		)
		(pad "AT38" smd circle
			(at 12.349988 10.450068)
			(size 0.4572 0.4572)
			(layers "F.Cu" "F.Mask" "F.Paste")
			(net "Net_5351")
		)
		(pad "AT39" smd circle
			(at 13.299948 10.450068)
			(size 0.4572 0.4572)
			(layers "F.Cu" "F.Mask" "F.Paste")
			(net "Net_5336")
		)
		(pad "AT40" smd circle
			(at 14.249908 10.450068)
			(size 0.4572 0.4572)
			(layers "F.Cu" "F.Mask" "F.Paste")
			(net "GND")
		)
		(pad "AT41" smd circle
			(at 15.200122 10.450068)
			(size 0.4572 0.4572)
			(layers "F.Cu" "F.Mask" "F.Paste")
			(net "P5E_PEX2_STN0_TX_DP<3>")
		)
		(pad "AT42" smd circle
			(at 16.150082 10.450068)
			(size 0.4572 0.4572)
			(layers "F.Cu" "F.Mask" "F.Paste")
			(net "P5E_PEX2_STN0_TX_DN<3>")
		)
		(pad "AT43" smd circle
			(at 17.100042 10.450068)
			(size 0.4572 0.4572)
			(layers "F.Cu" "F.Mask" "F.Paste")
			(net "GND")
		)
		(pad "AT44" smd circle
			(at 18.050002 10.450068)
			(size 0.4572 0.4572)
			(layers "F.Cu" "F.Mask" "F.Paste")
			(net "GND")
		)
		(pad "AT45" smd circle
			(at 18.999962 10.450068)
			(size 0.4572 0.4572)
			(layers "F.Cu" "F.Mask" "F.Paste")
			(net "GND")
		)
		(pad "AT46" smd circle
			(at 19.949922 10.450068)
			(size 0.4572 0.4572)
			(layers "F.Cu" "F.Mask" "F.Paste")
			(net "GND")
		)
		(pad "AT47" smd circle
			(at 20.899882 10.450068)
			(size 0.4572 0.4572)
			(layers "F.Cu" "F.Mask" "F.Paste")
			(net "GND")
		)
		(pad "AT48" smd circle
			(at 21.850096 10.450068)
			(size 0.4572 0.4572)
			(layers "F.Cu" "F.Mask" "F.Paste")
			(net "P5E_PEX2_STN0_RX_DP<3>")
		)
		(pad "AT49" smd circle
			(at 22.800056 10.450068)
			(size 0.4572 0.4572)
			(layers "F.Cu" "F.Mask" "F.Paste")
			(net "P5E_PEX2_STN0_RX_DN<3>")
		)
		(pad "AU1" smd circle
			(at -22.800056 11.400028)
			(size 0.4572 0.4572)
			(layers "F.Cu" "F.Mask" "F.Paste")
			(net "GND")
		)
		(pad "AU2" smd circle
			(at -21.850096 11.400028)
			(size 0.4572 0.4572)
			(layers "F.Cu" "F.Mask" "F.Paste")
			(net "GND")
		)
		(pad "AU3" smd circle
			(at -20.899882 11.400028)
			(size 0.4572 0.4572)
			(layers "F.Cu" "F.Mask" "F.Paste")
			(net "Net_1602")
		)
		(pad "AU4" smd circle
			(at -19.949922 11.400028)
			(size 0.4572 0.4572)
			(layers "F.Cu" "F.Mask" "F.Paste")
			(net "Net_1614")
		)
		(pad "AU5" smd circle
			(at -18.999962 11.400028)
			(size 0.4572 0.4572)
			(layers "F.Cu" "F.Mask" "F.Paste")
			(net "GND")
		)
		(pad "AU6" smd circle
			(at -18.050002 11.400028)
			(size 0.4572 0.4572)
			(layers "F.Cu" "F.Mask" "F.Paste")
			(net "Net_1724")
		)
		(pad "AU7" smd circle
			(at -17.100042 11.400028)
			(size 0.4572 0.4572)
			(layers "F.Cu" "F.Mask" "F.Paste")
			(net "Net_1442")
		)
		(pad "AU8" smd circle
			(at -16.150082 11.400028)
			(size 0.4572 0.4572)
			(layers "F.Cu" "F.Mask" "F.Paste")
			(net "GND")
		)
		(pad "AU9" smd circle
			(at -15.200122 11.400028)
			(size 0.4572 0.4572)
			(layers "F.Cu" "F.Mask" "F.Paste")
			(net "GND")
		)
		(pad "AU10" smd circle
			(at -14.249908 11.400028)
			(size 0.4572 0.4572)
			(layers "F.Cu" "F.Mask" "F.Paste")
			(net "GND")
		)
		(pad "AU11" smd circle
			(at -13.299948 11.400028)
			(size 0.4572 0.4572)
			(layers "F.Cu" "F.Mask" "F.Paste")
			(net "GND")
		)
		(pad "AU12" smd circle
			(at -12.349988 11.400028)
			(size 0.4572 0.4572)
			(layers "F.Cu" "F.Mask" "F.Paste")
			(net "GND")
		)
		(pad "AU13" smd circle
			(at -11.400028 11.400028)
			(size 0.4572 0.4572)
			(layers "F.Cu" "F.Mask" "F.Paste")
			(net "GND")
		)
		(pad "AU14" smd circle
			(at -10.450068 11.400028)
			(size 0.4572 0.4572)
			(layers "F.Cu" "F.Mask" "F.Paste")
			(net "GND")
		)
		(pad "AU15" smd circle
			(at -9.500108 11.400028)
			(size 0.4572 0.4572)
			(layers "F.Cu" "F.Mask" "F.Paste")
			(net "GND")
		)
		(pad "AU16" smd circle
			(at -8.549894 11.400028)
			(size 0.4572 0.4572)
			(layers "F.Cu" "F.Mask" "F.Paste")
			(net "GND")
		)
		(pad "AU17" smd circle
			(at -7.599934 11.400028)
			(size 0.4572 0.4572)
			(layers "F.Cu" "F.Mask" "F.Paste")
			(net "GND")
		)
		(pad "AU18" smd circle
			(at -6.649974 11.400028)
			(size 0.4572 0.4572)
			(layers "F.Cu" "F.Mask" "F.Paste")
			(net "GND")
		)
		(pad "AU19" smd circle
			(at -5.700014 11.400028)
			(size 0.4572 0.4572)
			(layers "F.Cu" "F.Mask" "F.Paste")
			(net "GND")
		)
		(pad "AU20" smd circle
			(at -4.750054 11.400028)
			(size 0.4572 0.4572)
			(layers "F.Cu" "F.Mask" "F.Paste")
			(net "GND")
		)
		(pad "AU21" smd circle
			(at -3.800094 11.400028)
			(size 0.4572 0.4572)
			(layers "F.Cu" "F.Mask" "F.Paste")
			(net "GND")
		)
		(pad "AU22" smd circle
			(at -2.84988 11.400028)
			(size 0.4572 0.4572)
			(layers "F.Cu" "F.Mask" "F.Paste")
			(net "GND")
		)
		(pad "AU23" smd circle
			(at -1.89992 11.400028)
			(size 0.4572 0.4572)
			(layers "F.Cu" "F.Mask" "F.Paste")
			(net "GND")
		)
		(pad "AU24" smd circle
			(at -0.94996 11.400028)
			(size 0.4572 0.4572)
			(layers "F.Cu" "F.Mask" "F.Paste")
			(net "GND")
		)
		(pad "AU25" smd circle
			(at 0 11.400028)
			(size 0.4572 0.4572)
			(layers "F.Cu" "F.Mask" "F.Paste")
			(net "GND")
		)
		(pad "AU26" smd circle
			(at 0.94996 11.400028)
			(size 0.4572 0.4572)
			(layers "F.Cu" "F.Mask" "F.Paste")
			(net "GND")
		)
		(pad "AU27" smd circle
			(at 1.89992 11.400028)
			(size 0.4572 0.4572)
			(layers "F.Cu" "F.Mask" "F.Paste")
			(net "GND")
		)
		(pad "AU28" smd circle
			(at 2.84988 11.400028)
			(size 0.4572 0.4572)
			(layers "F.Cu" "F.Mask" "F.Paste")
			(net "GND")
		)
		(pad "AU29" smd circle
			(at 3.800094 11.400028)
			(size 0.4572 0.4572)
			(layers "F.Cu" "F.Mask" "F.Paste")
			(net "GND")
		)
		(pad "AU30" smd circle
			(at 4.750054 11.400028)
			(size 0.4572 0.4572)
			(layers "F.Cu" "F.Mask" "F.Paste")
			(net "GND")
		)
		(pad "AU31" smd circle
			(at 5.700014 11.400028)
			(size 0.4572 0.4572)
			(layers "F.Cu" "F.Mask" "F.Paste")
			(net "GND")
		)
		(pad "AU32" smd circle
			(at 6.649974 11.400028)
			(size 0.4572 0.4572)
			(layers "F.Cu" "F.Mask" "F.Paste")
			(net "GND")
		)
		(pad "AU33" smd circle
			(at 7.599934 11.400028)
			(size 0.4572 0.4572)
			(layers "F.Cu" "F.Mask" "F.Paste")
			(net "GND")
		)
		(pad "AU34" smd circle
			(at 8.549894 11.400028)
			(size 0.4572 0.4572)
			(layers "F.Cu" "F.Mask" "F.Paste")
			(net "GND")
		)
		(pad "AU35" smd circle
			(at 9.500108 11.400028)
			(size 0.4572 0.4572)
			(layers "F.Cu" "F.Mask" "F.Paste")
			(net "GND")
		)
		(pad "AU36" smd circle
			(at 10.450068 11.400028)
			(size 0.4572 0.4572)
			(layers "F.Cu" "F.Mask" "F.Paste")
			(net "GND")
		)
		(pad "AU37" smd circle
			(at 11.400028 11.400028)
			(size 0.4572 0.4572)
			(layers "F.Cu" "F.Mask" "F.Paste")
			(net "GND")
		)
		(pad "AU38" smd circle
			(at 12.349988 11.400028)
			(size 0.4572 0.4572)
			(layers "F.Cu" "F.Mask" "F.Paste")
			(net "Net_5358")
		)
		(pad "AU39" smd circle
			(at 13.299948 11.400028)
			(size 0.4572 0.4572)
			(layers "F.Cu" "F.Mask" "F.Paste")
			(net "Net_5330")
		)
		(pad "AU40" smd circle
			(at 14.249908 11.400028)
			(size 0.4572 0.4572)
			(layers "F.Cu" "F.Mask" "F.Paste")
			(net "GND")
		)
		(pad "AU41" smd circle
			(at 15.200122 11.400028)
			(size 0.4572 0.4572)
			(layers "F.Cu" "F.Mask" "F.Paste")
			(net "GND")
		)
		(pad "AU42" smd circle
			(at 16.150082 11.400028)
			(size 0.4572 0.4572)
			(layers "F.Cu" "F.Mask" "F.Paste")
			(net "GND")
		)
		(pad "AU43" smd circle
			(at 17.100042 11.400028)
			(size 0.4572 0.4572)
			(layers "F.Cu" "F.Mask" "F.Paste")
			(net "P5E_PEX2_STN0_TX_DP<4>")
		)
		(pad "AU44" smd circle
			(at 18.050002 11.400028)
			(size 0.4572 0.4572)
			(layers "F.Cu" "F.Mask" "F.Paste")
			(net "P5E_PEX2_STN0_TX_DN<4>")
		)
		(pad "AU45" smd circle
			(at 18.999962 11.400028)
			(size 0.4572 0.4572)
			(layers "F.Cu" "F.Mask" "F.Paste")
			(net "GND")
		)
		(pad "AU46" smd circle
			(at 19.949922 11.400028)
			(size 0.4572 0.4572)
			(layers "F.Cu" "F.Mask" "F.Paste")
			(net "P5E_PEX2_STN0_RX_DP<4>")
		)
		(pad "AU47" smd circle
			(at 20.899882 11.400028)
			(size 0.4572 0.4572)
			(layers "F.Cu" "F.Mask" "F.Paste")
			(net "P5E_PEX2_STN0_RX_DN<4>")
		)
		(pad "AU48" smd circle
			(at 21.850096 11.400028)
			(size 0.4572 0.4572)
			(layers "F.Cu" "F.Mask" "F.Paste")
			(net "GND")
		)
		(pad "AU49" smd circle
			(at 22.800056 11.400028)
			(size 0.4572 0.4572)
			(layers "F.Cu" "F.Mask" "F.Paste")
			(net "GND")
		)
		(pad "AV1" smd circle
			(at -22.800056 12.349988)
			(size 0.4572 0.4572)
			(layers "F.Cu" "F.Mask" "F.Paste")
			(net "Net_1633")
		)
		(pad "AV2" smd circle
			(at -21.850096 12.349988)
			(size 0.4572 0.4572)
			(layers "F.Cu" "F.Mask" "F.Paste")
			(net "Net_1629")
		)
		(pad "AV3" smd circle
			(at -20.899882 12.349988)
			(size 0.4572 0.4572)
			(layers "F.Cu" "F.Mask" "F.Paste")
			(net "GND")
		)
		(pad "AV4" smd circle
			(at -19.949922 12.349988)
			(size 0.4572 0.4572)
			(layers "F.Cu" "F.Mask" "F.Paste")
			(net "GND")
		)
		(pad "AV5" smd circle
			(at -18.999962 12.349988)
			(size 0.4572 0.4572)
			(layers "F.Cu" "F.Mask" "F.Paste")
			(net "GND")
		)
		(pad "AV6" smd circle
			(at -18.050002 12.349988)
			(size 0.4572 0.4572)
			(layers "F.Cu" "F.Mask" "F.Paste")
			(net "GND")
		)
		(pad "AV7" smd circle
			(at -17.100042 12.349988)
			(size 0.4572 0.4572)
			(layers "F.Cu" "F.Mask" "F.Paste")
			(net "GND")
		)
		(pad "AV8" smd circle
			(at -16.150082 12.349988)
			(size 0.4572 0.4572)
			(layers "F.Cu" "F.Mask" "F.Paste")
			(net "Net_1449")
		)
		(pad "AV9" smd circle
			(at -15.200122 12.349988)
			(size 0.4572 0.4572)
			(layers "F.Cu" "F.Mask" "F.Paste")
			(net "Net_1368")
		)
		(pad "AV10" smd circle
			(at -14.249908 12.349988)
			(size 0.4572 0.4572)
			(layers "F.Cu" "F.Mask" "F.Paste")
			(net "GND")
		)
		(pad "AV11" smd circle
			(at -13.299948 12.349988)
			(size 0.4572 0.4572)
			(layers "F.Cu" "F.Mask" "F.Paste")
			(net "GND")
		)
		(pad "AV12" smd circle
			(at -12.349988 12.349988)
			(size 0.4572 0.4572)
			(layers "F.Cu" "F.Mask" "F.Paste")
			(net "Net_5348")
		)
		(pad "AV13" smd circle
			(at -11.400028 12.349988)
			(size 0.4572 0.4572)
			(layers "F.Cu" "F.Mask" "F.Paste")
			(net "Net_5349")
		)
		(pad "AV14" smd circle
			(at -10.450068 12.349988)
			(size 0.4572 0.4572)
			(layers "F.Cu" "F.Mask" "F.Paste")
			(net "Net_5340")
		)
		(pad "AV15" smd circle
			(at -9.500108 12.349988)
			(size 0.4572 0.4572)
			(layers "F.Cu" "F.Mask" "F.Paste")
			(net "Net_5334")
		)
		(pad "AV16" smd circle
			(at -8.549894 12.349988)
			(size 0.4572 0.4572)
			(layers "F.Cu" "F.Mask" "F.Paste")
			(net "Net_5343")
		)
		(pad "AV17" smd circle
			(at -7.599934 12.349988)
			(size 0.4572 0.4572)
			(layers "F.Cu" "F.Mask" "F.Paste")
			(net "Net_5344")
		)
		(pad "AV18" smd circle
			(at -6.649974 12.349988)
			(size 0.4572 0.4572)
			(layers "F.Cu" "F.Mask" "F.Paste")
			(net "Net_5339")
		)
		(pad "AV19" smd circle
			(at -5.700014 12.349988)
			(size 0.4572 0.4572)
			(layers "F.Cu" "F.Mask" "F.Paste")
			(net "Net_5335")
		)
		(pad "AV20" smd circle
			(at -4.750054 12.349988)
			(size 0.4572 0.4572)
			(layers "F.Cu" "F.Mask" "F.Paste")
			(net "GND")
		)
		(pad "AV21" smd circle
			(at -3.800094 12.349988)
			(size 0.4572 0.4572)
			(layers "F.Cu" "F.Mask" "F.Paste")
			(net "Net_5374")
		)
		(pad "AV22" smd circle
			(at -2.84988 12.349988)
			(size 0.4572 0.4572)
			(layers "F.Cu" "F.Mask" "F.Paste")
			(net "Net_5375")
		)
		(pad "AV23" smd circle
			(at -1.89992 12.349988)
			(size 0.4572 0.4572)
			(layers "F.Cu" "F.Mask" "F.Paste")
			(net "Net_5377")
		)
		(pad "AV24" smd circle
			(at -0.94996 12.349988)
			(size 0.4572 0.4572)
			(layers "F.Cu" "F.Mask" "F.Paste")
			(net "GND")
		)
		(pad "AV25" smd circle
			(at 0 12.349988)
			(size 0.4572 0.4572)
			(layers "F.Cu" "F.Mask" "F.Paste")
			(net "PEX2_MODE_SEL2")
		)
		(pad "AV26" smd circle
			(at 0.94996 12.349988)
			(size 0.4572 0.4572)
			(layers "F.Cu" "F.Mask" "F.Paste")
			(net "PEX2_MODE_SEL7")
		)
		(pad "AV27" smd circle
			(at 1.89992 12.349988)
			(size 0.4572 0.4572)
			(layers "F.Cu" "F.Mask" "F.Paste")
			(net "PEX2_MODE_SEL3")
		)
		(pad "AV28" smd circle
			(at 2.84988 12.349988)
			(size 0.4572 0.4572)
			(layers "F.Cu" "F.Mask" "F.Paste")
			(net "PEX2_MODE_SEL9")
		)
		(pad "AV29" smd circle
			(at 3.800094 12.349988)
			(size 0.4572 0.4572)
			(layers "F.Cu" "F.Mask" "F.Paste")
			(net "PEX2_PCA9555_INT_R_N")
		)
		(pad "AV30" smd circle
			(at 4.750054 12.349988)
			(size 0.4572 0.4572)
			(layers "F.Cu" "F.Mask" "F.Paste")
			(net "PEX2_SYS_ERR_N")
		)
		(pad "AV31" smd circle
			(at 5.700014 12.349988)
			(size 0.4572 0.4572)
			(layers "F.Cu" "F.Mask" "F.Paste")
			(net "PEX2_MODE_SEL6")
		)
		(pad "AV32" smd circle
			(at 6.649974 12.349988)
			(size 0.4572 0.4572)
			(layers "F.Cu" "F.Mask" "F.Paste")
			(net "PEX2_MODE_SEL10")
		)
		(pad "AV33" smd circle
			(at 7.599934 12.349988)
			(size 0.4572 0.4572)
			(layers "F.Cu" "F.Mask" "F.Paste")
			(net "Net_5352")
		)
		(pad "AV34" smd circle
			(at 8.549894 12.349988)
			(size 0.4572 0.4572)
			(layers "F.Cu" "F.Mask" "F.Paste")
			(net "Net_5325")
		)
		(pad "AV35" smd circle
			(at 9.500108 12.349988)
			(size 0.4572 0.4572)
			(layers "F.Cu" "F.Mask" "F.Paste")
			(net "Net_5354")
		)
		(pad "AV36" smd circle
			(at 10.450068 12.349988)
			(size 0.4572 0.4572)
			(layers "F.Cu" "F.Mask" "F.Paste")
			(net "Net_5331")
		)
		(pad "AV37" smd circle
			(at 11.400028 12.349988)
			(size 0.4572 0.4572)
			(layers "F.Cu" "F.Mask" "F.Paste")
			(net "Net_5356")
		)
		(pad "AV38" smd circle
			(at 12.349988 12.349988)
			(size 0.4572 0.4572)
			(layers "F.Cu" "F.Mask" "F.Paste")
			(net "Net_5355")
		)
		(pad "AV39" smd circle
			(at 13.299948 12.349988)
			(size 0.4572 0.4572)
			(layers "F.Cu" "F.Mask" "F.Paste")
			(net "Net_5347")
		)
		(pad "AV40" smd circle
			(at 14.249908 12.349988)
			(size 0.4572 0.4572)
			(layers "F.Cu" "F.Mask" "F.Paste")
			(net "GND")
		)
		(pad "AV41" smd circle
			(at 15.200122 12.349988)
			(size 0.4572 0.4572)
			(layers "F.Cu" "F.Mask" "F.Paste")
			(net "P5E_PEX2_STN0_TX_DP<5>")
		)
		(pad "AV42" smd circle
			(at 16.150082 12.349988)
			(size 0.4572 0.4572)
			(layers "F.Cu" "F.Mask" "F.Paste")
			(net "P5E_PEX2_STN0_TX_DN<5>")
		)
		(pad "AV43" smd circle
			(at 17.100042 12.349988)
			(size 0.4572 0.4572)
			(layers "F.Cu" "F.Mask" "F.Paste")
			(net "GND")
		)
		(pad "AV44" smd circle
			(at 18.050002 12.349988)
			(size 0.4572 0.4572)
			(layers "F.Cu" "F.Mask" "F.Paste")
			(net "GND")
		)
		(pad "AV45" smd circle
			(at 18.999962 12.349988)
			(size 0.4572 0.4572)
			(layers "F.Cu" "F.Mask" "F.Paste")
			(net "GND")
		)
		(pad "AV46" smd circle
			(at 19.949922 12.349988)
			(size 0.4572 0.4572)
			(layers "F.Cu" "F.Mask" "F.Paste")
			(net "GND")
		)
		(pad "AV47" smd circle
			(at 20.899882 12.349988)
			(size 0.4572 0.4572)
			(layers "F.Cu" "F.Mask" "F.Paste")
			(net "GND")
		)
		(pad "AV48" smd circle
			(at 21.850096 12.349988)
			(size 0.4572 0.4572)
			(layers "F.Cu" "F.Mask" "F.Paste")
			(net "P5E_PEX2_STN0_RX_DP<5>")
		)
		(pad "AV49" smd circle
			(at 22.800056 12.349988)
			(size 0.4572 0.4572)
			(layers "F.Cu" "F.Mask" "F.Paste")
			(net "P5E_PEX2_STN0_RX_DN<5>")
		)
		(pad "AW1" smd circle
			(at -22.800056 13.299948)
			(size 0.4572 0.4572)
			(layers "F.Cu" "F.Mask" "F.Paste")
			(net "GND")
		)
		(pad "AW2" smd circle
			(at -21.850096 13.299948)
			(size 0.4572 0.4572)
			(layers "F.Cu" "F.Mask" "F.Paste")
			(net "GND")
		)
		(pad "AW3" smd circle
			(at -20.899882 13.299948)
			(size 0.4572 0.4572)
			(layers "F.Cu" "F.Mask" "F.Paste")
			(net "Net_1605")
		)
		(pad "AW4" smd circle
			(at -19.949922 13.299948)
			(size 0.4572 0.4572)
			(layers "F.Cu" "F.Mask" "F.Paste")
			(net "Net_1623")
		)
		(pad "AW5" smd circle
			(at -18.999962 13.299948)
			(size 0.4572 0.4572)
			(layers "F.Cu" "F.Mask" "F.Paste")
			(net "GND")
		)
		(pad "AW6" smd circle
			(at -18.050002 13.299948)
			(size 0.4572 0.4572)
			(layers "F.Cu" "F.Mask" "F.Paste")
			(net "Net_1355")
		)
		(pad "AW7" smd circle
			(at -17.100042 13.299948)
			(size 0.4572 0.4572)
			(layers "F.Cu" "F.Mask" "F.Paste")
			(net "Net_1720")
		)
		(pad "AW8" smd circle
			(at -16.150082 13.299948)
			(size 0.4572 0.4572)
			(layers "F.Cu" "F.Mask" "F.Paste")
			(net "GND")
		)
		(pad "AW9" smd circle
			(at -15.200122 13.299948)
			(size 0.4572 0.4572)
			(layers "F.Cu" "F.Mask" "F.Paste")
			(net "GND")
		)
		(pad "AW10" smd circle
			(at -14.249908 13.299948)
			(size 0.4572 0.4572)
			(layers "F.Cu" "F.Mask" "F.Paste")
			(net "GND")
		)
		(pad "AW11" smd circle
			(at -13.299948 13.299948)
			(size 0.4572 0.4572)
			(layers "F.Cu" "F.Mask" "F.Paste")
			(net "GND")
		)
		(pad "AW12" smd circle
			(at -12.349988 13.299948)
			(size 0.4572 0.4572)
			(layers "F.Cu" "F.Mask" "F.Paste")
			(net "Net_5346")
		)
		(pad "AW13" smd circle
			(at -11.400028 13.299948)
			(size 0.4572 0.4572)
			(layers "F.Cu" "F.Mask" "F.Paste")
			(net "Net_5342")
		)
		(pad "AW14" smd circle
			(at -10.450068 13.299948)
			(size 0.4572 0.4572)
			(layers "F.Cu" "F.Mask" "F.Paste")
			(net "Net_5338")
		)
		(pad "AW15" smd circle
			(at -9.500108 13.299948)
			(size 0.4572 0.4572)
			(layers "F.Cu" "F.Mask" "F.Paste")
			(net "Net_5333")
		)
		(pad "AW16" smd circle
			(at -8.549894 13.299948)
			(size 0.4572 0.4572)
			(layers "F.Cu" "F.Mask" "F.Paste")
			(net "Net_5345")
		)
		(pad "AW17" smd circle
			(at -7.599934 13.299948)
			(size 0.4572 0.4572)
			(layers "F.Cu" "F.Mask" "F.Paste")
			(net "Net_5341")
		)
		(pad "AW18" smd circle
			(at -6.649974 13.299948)
			(size 0.4572 0.4572)
			(layers "F.Cu" "F.Mask" "F.Paste")
			(net "Net_5337")
		)
		(pad "AW19" smd circle
			(at -5.700014 13.299948)
			(size 0.4572 0.4572)
			(layers "F.Cu" "F.Mask" "F.Paste")
			(net "Net_5332")
		)
		(pad "AW20" smd circle
			(at -4.750054 13.299948)
			(size 0.4572 0.4572)
			(layers "F.Cu" "F.Mask" "F.Paste")
			(net "GND")
		)
		(pad "AW21" smd circle
			(at -3.800094 13.299948)
			(size 0.4572 0.4572)
			(layers "F.Cu" "F.Mask" "F.Paste")
			(net "Net_5366")
		)
		(pad "AW22" smd circle
			(at -2.84988 13.299948)
			(size 0.4572 0.4572)
			(layers "F.Cu" "F.Mask" "F.Paste")
			(net "Net_5376")
		)
		(pad "AW23" smd circle
			(at -1.89992 13.299948)
			(size 0.4572 0.4572)
			(layers "F.Cu" "F.Mask" "F.Paste")
			(net "Net_5365")
		)
		(pad "AW24" smd circle
			(at -0.94996 13.299948)
			(size 0.4572 0.4572)
			(layers "F.Cu" "F.Mask" "F.Paste")
			(net "GND")
		)
		(pad "AW25" smd circle
			(at 0 13.299948)
			(size 0.4572 0.4572)
			(layers "F.Cu" "F.Mask" "F.Paste")
			(net "PEX2_MODE_SEL5")
		)
		(pad "AW26" smd circle
			(at 0.94996 13.299948)
			(size 0.4572 0.4572)
			(layers "F.Cu" "F.Mask" "F.Paste")
			(net "PEX2_DBG_MODE3")
		)
		(pad "AW27" smd circle
			(at 1.89992 13.299948)
			(size 0.4572 0.4572)
			(layers "F.Cu" "F.Mask" "F.Paste")
			(net "PEX2_MODE_SEL0")
		)
		(pad "AW28" smd circle
			(at 2.84988 13.299948)
			(size 0.4572 0.4572)
			(layers "F.Cu" "F.Mask" "F.Paste")
			(net "PEX2_MODE_SEL4")
		)
		(pad "AW29" smd circle
			(at 3.800094 13.299948)
			(size 0.4572 0.4572)
			(layers "F.Cu" "F.Mask" "F.Paste")
			(net "PEX2_MODE_SEL8")
		)
		(pad "AW30" smd circle
			(at 4.750054 13.299948)
			(size 0.4572 0.4572)
			(layers "F.Cu" "F.Mask" "F.Paste")
			(net "PEX2_DBG_MODE2")
		)
		(pad "AW31" smd circle
			(at 5.700014 13.299948)
			(size 0.4572 0.4572)
			(layers "F.Cu" "F.Mask" "F.Paste")
			(net "PEX2_MODE_SEL11")
		)
		(pad "AW32" smd circle
			(at 6.649974 13.299948)
			(size 0.4572 0.4572)
			(layers "F.Cu" "F.Mask" "F.Paste")
			(net "PEX2_MODE_SEL12")
		)
		(pad "AW33" smd circle
			(at 7.599934 13.299948)
			(size 0.4572 0.4572)
			(layers "F.Cu" "F.Mask" "F.Paste")
			(net "Net_5350")
		)
		(pad "AW34" smd circle
			(at 8.549894 13.299948)
			(size 0.4572 0.4572)
			(layers "F.Cu" "F.Mask" "F.Paste")
			(net "PEX2_DBG_MODE4")
		)
		(pad "AW35" smd circle
			(at 9.500108 13.299948)
			(size 0.4572 0.4572)
			(layers "F.Cu" "F.Mask" "F.Paste")
			(net "Net_5329")
		)
		(pad "AW36" smd circle
			(at 10.450068 13.299948)
			(size 0.4572 0.4572)
			(layers "F.Cu" "F.Mask" "F.Paste")
			(net "Net_5353")
		)
		(pad "AW37" smd circle
			(at 11.400028 13.299948)
			(size 0.4572 0.4572)
			(layers "F.Cu" "F.Mask" "F.Paste")
			(net "Net_5357")
		)
		(pad "AW38" smd circle
			(at 12.349988 13.299948)
			(size 0.4572 0.4572)
			(layers "F.Cu" "F.Mask" "F.Paste")
			(net "PEX2_MODE_SEL1")
		)
		(pad "AW39" smd circle
			(at 13.299948 13.299948)
			(size 0.4572 0.4572)
			(layers "F.Cu" "F.Mask" "F.Paste")
			(net "Net_5324")
		)
		(pad "AW40" smd circle
			(at 14.249908 13.299948)
			(size 0.4572 0.4572)
			(layers "F.Cu" "F.Mask" "F.Paste")
			(net "GND")
		)
		(pad "AW41" smd circle
			(at 15.200122 13.299948)
			(size 0.4572 0.4572)
			(layers "F.Cu" "F.Mask" "F.Paste")
			(net "GND")
		)
		(pad "AW42" smd circle
			(at 16.150082 13.299948)
			(size 0.4572 0.4572)
			(layers "F.Cu" "F.Mask" "F.Paste")
			(net "GND")
		)
		(pad "AW43" smd circle
			(at 17.100042 13.299948)
			(size 0.4572 0.4572)
			(layers "F.Cu" "F.Mask" "F.Paste")
			(net "P5E_PEX2_STN0_TX_DP<6>")
		)
		(pad "AW44" smd circle
			(at 18.050002 13.299948)
			(size 0.4572 0.4572)
			(layers "F.Cu" "F.Mask" "F.Paste")
			(net "P5E_PEX2_STN0_TX_DN<6>")
		)
		(pad "AW45" smd circle
			(at 18.999962 13.299948)
			(size 0.4572 0.4572)
			(layers "F.Cu" "F.Mask" "F.Paste")
			(net "GND")
		)
		(pad "AW46" smd circle
			(at 19.949922 13.299948)
			(size 0.4572 0.4572)
			(layers "F.Cu" "F.Mask" "F.Paste")
			(net "P5E_PEX2_STN0_RX_DP<6>")
		)
		(pad "AW47" smd circle
			(at 20.899882 13.299948)
			(size 0.4572 0.4572)
			(layers "F.Cu" "F.Mask" "F.Paste")
			(net "P5E_PEX2_STN0_RX_DN<6>")
		)
		(pad "AW48" smd circle
			(at 21.850096 13.299948)
			(size 0.4572 0.4572)
			(layers "F.Cu" "F.Mask" "F.Paste")
			(net "GND")
		)
		(pad "AW49" smd circle
			(at 22.800056 13.299948)
			(size 0.4572 0.4572)
			(layers "F.Cu" "F.Mask" "F.Paste")
			(net "GND")
		)
		(pad "AY1" smd circle
			(at -22.800056 14.249908)
			(size 0.4572 0.4572)
			(layers "F.Cu" "F.Mask" "F.Paste")
			(net "Net_1600")
		)
		(pad "AY2" smd circle
			(at -21.850096 14.249908)
			(size 0.4572 0.4572)
			(layers "F.Cu" "F.Mask" "F.Paste")
			(net "Net_1588")
		)
		(pad "AY3" smd circle
			(at -20.899882 14.249908)
			(size 0.4572 0.4572)
			(layers "F.Cu" "F.Mask" "F.Paste")
			(net "GND")
		)
		(pad "AY4" smd circle
			(at -19.949922 14.249908)
			(size 0.4572 0.4572)
			(layers "F.Cu" "F.Mask" "F.Paste")
			(net "GND")
		)
		(pad "AY5" smd circle
			(at -18.999962 14.249908)
			(size 0.4572 0.4572)
			(layers "F.Cu" "F.Mask" "F.Paste")
			(net "GND")
		)
		(pad "AY6" smd circle
			(at -18.050002 14.249908)
			(size 0.4572 0.4572)
			(layers "F.Cu" "F.Mask" "F.Paste")
			(net "GND")
		)
		(pad "AY7" smd circle
			(at -17.100042 14.249908)
			(size 0.4572 0.4572)
			(layers "F.Cu" "F.Mask" "F.Paste")
			(net "GND")
		)
		(pad "AY8" smd circle
			(at -16.150082 14.249908)
			(size 0.4572 0.4572)
			(layers "F.Cu" "F.Mask" "F.Paste")
			(net "GND")
		)
		(pad "AY9" smd circle
			(at -15.200122 14.249908)
			(size 0.4572 0.4572)
			(layers "F.Cu" "F.Mask" "F.Paste")
			(net "GND")
		)
		(pad "AY10" smd circle
			(at -14.249908 14.249908)
			(size 0.4572 0.4572)
			(layers "F.Cu" "F.Mask" "F.Paste")
			(net "GND")
		)
		(pad "AY11" smd circle
			(at -13.299948 14.249908)
			(size 0.4572 0.4572)
			(layers "F.Cu" "F.Mask" "F.Paste")
			(net "GND")
		)
		(pad "AY12" smd circle
			(at -12.349988 14.249908)
			(size 0.4572 0.4572)
			(layers "F.Cu" "F.Mask" "F.Paste")
			(net "GND")
		)
		(pad "AY13" smd circle
			(at -11.400028 14.249908)
			(size 0.4572 0.4572)
			(layers "F.Cu" "F.Mask" "F.Paste")
			(net "GND")
		)
		(pad "AY14" smd circle
			(at -10.450068 14.249908)
			(size 0.4572 0.4572)
			(layers "F.Cu" "F.Mask" "F.Paste")
			(net "GND")
		)
		(pad "AY15" smd circle
			(at -9.500108 14.249908)
			(size 0.4572 0.4572)
			(layers "F.Cu" "F.Mask" "F.Paste")
			(net "GND")
		)
		(pad "AY16" smd circle
			(at -8.549894 14.249908)
			(size 0.4572 0.4572)
			(layers "F.Cu" "F.Mask" "F.Paste")
			(net "GND")
		)
		(pad "AY17" smd circle
			(at -7.599934 14.249908)
			(size 0.4572 0.4572)
			(layers "F.Cu" "F.Mask" "F.Paste")
			(net "GND")
		)
		(pad "AY18" smd circle
			(at -6.649974 14.249908)
			(size 0.4572 0.4572)
			(layers "F.Cu" "F.Mask" "F.Paste")
			(net "GND")
		)
		(pad "AY19" smd circle
			(at -5.700014 14.249908)
			(size 0.4572 0.4572)
			(layers "F.Cu" "F.Mask" "F.Paste")
			(net "GND")
		)
		(pad "AY20" smd circle
			(at -4.750054 14.249908)
			(size 0.4572 0.4572)
			(layers "F.Cu" "F.Mask" "F.Paste")
			(net "GND")
		)
		(pad "AY21" smd circle
			(at -3.800094 14.249908)
			(size 0.4572 0.4572)
			(layers "F.Cu" "F.Mask" "F.Paste")
			(net "GND")
		)
		(pad "AY22" smd circle
			(at -2.84988 14.249908)
			(size 0.4572 0.4572)
			(layers "F.Cu" "F.Mask" "F.Paste")
			(net "GND")
		)
		(pad "AY23" smd circle
			(at -1.89992 14.249908)
			(size 0.4572 0.4572)
			(layers "F.Cu" "F.Mask" "F.Paste")
			(net "GND")
		)
		(pad "AY24" smd circle
			(at -0.94996 14.249908)
			(size 0.4572 0.4572)
			(layers "F.Cu" "F.Mask" "F.Paste")
			(net "GND")
		)
		(pad "AY25" smd circle
			(at 0 14.249908)
			(size 0.4572 0.4572)
			(layers "F.Cu" "F.Mask" "F.Paste")
			(net "GND")
		)
		(pad "AY26" smd circle
			(at 0.94996 14.249908)
			(size 0.4572 0.4572)
			(layers "F.Cu" "F.Mask" "F.Paste")
			(net "GND")
		)
		(pad "AY27" smd circle
			(at 1.89992 14.249908)
			(size 0.4572 0.4572)
			(layers "F.Cu" "F.Mask" "F.Paste")
			(net "GND")
		)
		(pad "AY28" smd circle
			(at 2.84988 14.249908)
			(size 0.4572 0.4572)
			(layers "F.Cu" "F.Mask" "F.Paste")
			(net "GND")
		)
		(pad "AY29" smd circle
			(at 3.800094 14.249908)
			(size 0.4572 0.4572)
			(layers "F.Cu" "F.Mask" "F.Paste")
			(net "GND")
		)
		(pad "AY30" smd circle
			(at 4.750054 14.249908)
			(size 0.4572 0.4572)
			(layers "F.Cu" "F.Mask" "F.Paste")
			(net "GND")
		)
		(pad "AY31" smd circle
			(at 5.700014 14.249908)
			(size 0.4572 0.4572)
			(layers "F.Cu" "F.Mask" "F.Paste")
			(net "GND")
		)
		(pad "AY32" smd circle
			(at 6.649974 14.249908)
			(size 0.4572 0.4572)
			(layers "F.Cu" "F.Mask" "F.Paste")
			(net "GND")
		)
		(pad "AY33" smd circle
			(at 7.599934 14.249908)
			(size 0.4572 0.4572)
			(layers "F.Cu" "F.Mask" "F.Paste")
			(net "GND")
		)
		(pad "AY34" smd circle
			(at 8.549894 14.249908)
			(size 0.4572 0.4572)
			(layers "F.Cu" "F.Mask" "F.Paste")
			(net "GND")
		)
		(pad "AY35" smd circle
			(at 9.500108 14.249908)
			(size 0.4572 0.4572)
			(layers "F.Cu" "F.Mask" "F.Paste")
			(net "GND")
		)
		(pad "AY36" smd circle
			(at 10.450068 14.249908)
			(size 0.4572 0.4572)
			(layers "F.Cu" "F.Mask" "F.Paste")
			(net "GND")
		)
		(pad "AY37" smd circle
			(at 11.400028 14.249908)
			(size 0.4572 0.4572)
			(layers "F.Cu" "F.Mask" "F.Paste")
			(net "GND")
		)
		(pad "AY38" smd circle
			(at 12.349988 14.249908)
			(size 0.4572 0.4572)
			(layers "F.Cu" "F.Mask" "F.Paste")
			(net "GND")
		)
		(pad "AY39" smd circle
			(at 13.299948 14.249908)
			(size 0.4572 0.4572)
			(layers "F.Cu" "F.Mask" "F.Paste")
			(net "GND")
		)
		(pad "AY40" smd circle
			(at 14.249908 14.249908)
			(size 0.4572 0.4572)
			(layers "F.Cu" "F.Mask" "F.Paste")
			(net "GND")
		)
		(pad "AY41" smd circle
			(at 15.200122 14.249908)
			(size 0.4572 0.4572)
			(layers "F.Cu" "F.Mask" "F.Paste")
			(net "GND")
		)
		(pad "AY42" smd circle
			(at 16.150082 14.249908)
			(size 0.4572 0.4572)
			(layers "F.Cu" "F.Mask" "F.Paste")
			(net "GND")
		)
		(pad "AY43" smd circle
			(at 17.100042 14.249908)
			(size 0.4572 0.4572)
			(layers "F.Cu" "F.Mask" "F.Paste")
			(net "GND")
		)
		(pad "AY44" smd circle
			(at 18.050002 14.249908)
			(size 0.4572 0.4572)
			(layers "F.Cu" "F.Mask" "F.Paste")
			(net "GND")
		)
		(pad "AY45" smd circle
			(at 18.999962 14.249908)
			(size 0.4572 0.4572)
			(layers "F.Cu" "F.Mask" "F.Paste")
			(net "GND")
		)
		(pad "AY46" smd circle
			(at 19.949922 14.249908)
			(size 0.4572 0.4572)
			(layers "F.Cu" "F.Mask" "F.Paste")
			(net "GND")
		)
		(pad "AY47" smd circle
			(at 20.899882 14.249908)
			(size 0.4572 0.4572)
			(layers "F.Cu" "F.Mask" "F.Paste")
			(net "GND")
		)
		(pad "AY48" smd circle
			(at 21.850096 14.249908)
			(size 0.4572 0.4572)
			(layers "F.Cu" "F.Mask" "F.Paste")
			(net "P5E_PEX2_STN0_RX_DP<7>")
		)
		(pad "AY49" smd circle
			(at 22.800056 14.249908)
			(size 0.4572 0.4572)
			(layers "F.Cu" "F.Mask" "F.Paste")
			(net "P5E_PEX2_STN0_RX_DN<7>")
		)
		(pad "B1" smd circle
			(at -22.800056 -21.850096)
			(size 0.4572 0.4572)
			(layers "F.Cu" "F.Mask" "F.Paste")
			(net "GND")
		)
		(pad "B2" smd circle
			(at -21.850096 -21.850096)
			(size 0.4572 0.4572)
			(layers "F.Cu" "F.Mask" "F.Paste")
			(net "GND")
		)
		(pad "B3" smd circle
			(at -20.899882 -21.850096)
			(size 0.4572 0.4572)
			(layers "F.Cu" "F.Mask" "F.Paste")
			(net "P5E_PEX2_STN7_RX_DP<123>")
		)
		(pad "B4" smd circle
			(at -19.949922 -21.850096)
			(size 0.4572 0.4572)
			(layers "F.Cu" "F.Mask" "F.Paste")
			(net "GND")
		)
		(pad "B5" smd circle
			(at -18.999962 -21.850096)
			(size 0.4572 0.4572)
			(layers "F.Cu" "F.Mask" "F.Paste")
			(net "P5E_PEX2_STN7_RX_DP<125>")
		)
		(pad "B6" smd circle
			(at -18.050002 -21.850096)
			(size 0.4572 0.4572)
			(layers "F.Cu" "F.Mask" "F.Paste")
			(net "GND")
		)
		(pad "B7" smd circle
			(at -17.100042 -21.850096)
			(size 0.4572 0.4572)
			(layers "F.Cu" "F.Mask" "F.Paste")
			(net "P5E_PEX2_STN7_RX_DP<127>")
		)
		(pad "B8" smd circle
			(at -16.150082 -21.850096)
			(size 0.4572 0.4572)
			(layers "F.Cu" "F.Mask" "F.Paste")
			(net "GND")
		)
		(pad "B9" smd circle
			(at -15.200122 -21.850096)
			(size 0.4572 0.4572)
			(layers "F.Cu" "F.Mask" "F.Paste")
			(net "P5E_PEX2_STN6_RX_DP<110>")
		)
		(pad "B10" smd circle
			(at -14.249908 -21.850096)
			(size 0.4572 0.4572)
			(layers "F.Cu" "F.Mask" "F.Paste")
			(net "GND")
		)
		(pad "B11" smd circle
			(at -13.299948 -21.850096)
			(size 0.4572 0.4572)
			(layers "F.Cu" "F.Mask" "F.Paste")
			(net "P5E_PEX2_STN6_RX_DP<108>")
		)
		(pad "B12" smd circle
			(at -12.349988 -21.850096)
			(size 0.4572 0.4572)
			(layers "F.Cu" "F.Mask" "F.Paste")
			(net "GND")
		)
		(pad "B13" smd circle
			(at -11.400028 -21.850096)
			(size 0.4572 0.4572)
			(layers "F.Cu" "F.Mask" "F.Paste")
			(net "P5E_PEX2_STN6_RX_DP<106>")
		)
		(pad "B14" smd circle
			(at -10.450068 -21.850096)
			(size 0.4572 0.4572)
			(layers "F.Cu" "F.Mask" "F.Paste")
			(net "GND")
		)
		(pad "B15" smd circle
			(at -9.500108 -21.850096)
			(size 0.4572 0.4572)
			(layers "F.Cu" "F.Mask" "F.Paste")
			(net "P5E_PEX2_STN6_RX_DP<104>")
		)
		(pad "B16" smd circle
			(at -8.549894 -21.850096)
			(size 0.4572 0.4572)
			(layers "F.Cu" "F.Mask" "F.Paste")
			(net "GND")
		)
		(pad "B17" smd circle
			(at -7.599934 -21.850096)
			(size 0.4572 0.4572)
			(layers "F.Cu" "F.Mask" "F.Paste")
			(net "P5E_PEX2_STN6_RX_DP<102>")
		)
		(pad "B18" smd circle
			(at -6.649974 -21.850096)
			(size 0.4572 0.4572)
			(layers "F.Cu" "F.Mask" "F.Paste")
			(net "GND")
		)
		(pad "B19" smd circle
			(at -5.700014 -21.850096)
			(size 0.4572 0.4572)
			(layers "F.Cu" "F.Mask" "F.Paste")
			(net "P5E_PEX2_STN6_RX_DP<100>")
		)
		(pad "B20" smd circle
			(at -4.750054 -21.850096)
			(size 0.4572 0.4572)
			(layers "F.Cu" "F.Mask" "F.Paste")
			(net "GND")
		)
		(pad "B21" smd circle
			(at -3.800094 -21.850096)
			(size 0.4572 0.4572)
			(layers "F.Cu" "F.Mask" "F.Paste")
			(net "P5E_PEX2_STN6_RX_DP<98>")
		)
		(pad "B22" smd circle
			(at -2.84988 -21.850096)
			(size 0.4572 0.4572)
			(layers "F.Cu" "F.Mask" "F.Paste")
			(net "GND")
		)
		(pad "B23" smd circle
			(at -1.89992 -21.850096)
			(size 0.4572 0.4572)
			(layers "F.Cu" "F.Mask" "F.Paste")
			(net "P5E_PEX2_STN6_RX_DP<96>")
		)
		(pad "B24" smd circle
			(at -0.94996 -21.850096)
			(size 0.4572 0.4572)
			(layers "F.Cu" "F.Mask" "F.Paste")
			(net "GND")
		)
		(pad "B25" smd circle
			(at 0 -21.850096)
			(size 0.4572 0.4572)
			(layers "F.Cu" "F.Mask" "F.Paste")
			(net "P5E_PEX2_STN5_RX_DP<81>")
		)
		(pad "B26" smd circle
			(at 0.94996 -21.850096)
			(size 0.4572 0.4572)
			(layers "F.Cu" "F.Mask" "F.Paste")
			(net "GND")
		)
		(pad "B27" smd circle
			(at 1.89992 -21.850096)
			(size 0.4572 0.4572)
			(layers "F.Cu" "F.Mask" "F.Paste")
			(net "P5E_PEX2_STN5_RX_DP<83>")
		)
		(pad "B28" smd circle
			(at 2.84988 -21.850096)
			(size 0.4572 0.4572)
			(layers "F.Cu" "F.Mask" "F.Paste")
			(net "GND")
		)
		(pad "B29" smd circle
			(at 3.800094 -21.850096)
			(size 0.4572 0.4572)
			(layers "F.Cu" "F.Mask" "F.Paste")
			(net "P5E_PEX2_STN5_RX_DP<85>")
		)
		(pad "B30" smd circle
			(at 4.750054 -21.850096)
			(size 0.4572 0.4572)
			(layers "F.Cu" "F.Mask" "F.Paste")
			(net "GND")
		)
		(pad "B31" smd circle
			(at 5.700014 -21.850096)
			(size 0.4572 0.4572)
			(layers "F.Cu" "F.Mask" "F.Paste")
			(net "P5E_PEX2_STN5_RX_DP<87>")
		)
		(pad "B32" smd circle
			(at 6.649974 -21.850096)
			(size 0.4572 0.4572)
			(layers "F.Cu" "F.Mask" "F.Paste")
			(net "GND")
		)
		(pad "B33" smd circle
			(at 7.599934 -21.850096)
			(size 0.4572 0.4572)
			(layers "F.Cu" "F.Mask" "F.Paste")
			(net "P5E_PEX2_STN5_RX_DP<89>")
		)
		(pad "B34" smd circle
			(at 8.549894 -21.850096)
			(size 0.4572 0.4572)
			(layers "F.Cu" "F.Mask" "F.Paste")
			(net "GND")
		)
		(pad "B35" smd circle
			(at 9.500108 -21.850096)
			(size 0.4572 0.4572)
			(layers "F.Cu" "F.Mask" "F.Paste")
			(net "P5E_PEX2_STN5_RX_DP<91>")
		)
		(pad "B36" smd circle
			(at 10.450068 -21.850096)
			(size 0.4572 0.4572)
			(layers "F.Cu" "F.Mask" "F.Paste")
			(net "GND")
		)
		(pad "B37" smd circle
			(at 11.400028 -21.850096)
			(size 0.4572 0.4572)
			(layers "F.Cu" "F.Mask" "F.Paste")
			(net "P5E_PEX2_STN5_RX_DP<93>")
		)
		(pad "B38" smd circle
			(at 12.349988 -21.850096)
			(size 0.4572 0.4572)
			(layers "F.Cu" "F.Mask" "F.Paste")
			(net "GND")
		)
		(pad "B39" smd circle
			(at 13.299948 -21.850096)
			(size 0.4572 0.4572)
			(layers "F.Cu" "F.Mask" "F.Paste")
			(net "P5E_PEX2_STN5_RX_DP<95>")
		)
		(pad "B40" smd circle
			(at 14.249908 -21.850096)
			(size 0.4572 0.4572)
			(layers "F.Cu" "F.Mask" "F.Paste")
			(net "GND")
		)
		(pad "B41" smd circle
			(at 15.200122 -21.850096)
			(size 0.4572 0.4572)
			(layers "F.Cu" "F.Mask" "F.Paste")
			(net "P5E_PEX2_STN4_RX_DP<78>")
		)
		(pad "B42" smd circle
			(at 16.150082 -21.850096)
			(size 0.4572 0.4572)
			(layers "F.Cu" "F.Mask" "F.Paste")
			(net "GND")
		)
		(pad "B43" smd circle
			(at 17.100042 -21.850096)
			(size 0.4572 0.4572)
			(layers "F.Cu" "F.Mask" "F.Paste")
			(net "P5E_PEX2_STN4_RX_DP<76>")
		)
		(pad "B44" smd circle
			(at 18.050002 -21.850096)
			(size 0.4572 0.4572)
			(layers "F.Cu" "F.Mask" "F.Paste")
			(net "GND")
		)
		(pad "B45" smd circle
			(at 18.999962 -21.850096)
			(size 0.4572 0.4572)
			(layers "F.Cu" "F.Mask" "F.Paste")
			(net "P5E_PEX2_STN4_RX_DP<74>")
		)
		(pad "B46" smd circle
			(at 19.949922 -21.850096)
			(size 0.4572 0.4572)
			(layers "F.Cu" "F.Mask" "F.Paste")
			(net "GND")
		)
		(pad "B47" smd circle
			(at 20.899882 -21.850096)
			(size 0.4572 0.4572)
			(layers "F.Cu" "F.Mask" "F.Paste")
			(net "P5E_PEX2_STN4_RX_DP<72>")
		)
		(pad "B48" smd circle
			(at 21.850096 -21.850096)
			(size 0.4572 0.4572)
			(layers "F.Cu" "F.Mask" "F.Paste")
			(net "GND")
		)
		(pad "B49" smd circle
			(at 22.800056 -21.850096)
			(size 0.4572 0.4572)
			(layers "F.Cu" "F.Mask" "F.Paste")
			(net "GND")
		)
		(pad "BA1" smd circle
			(at -22.800056 15.200122)
			(size 0.4572 0.4572)
			(layers "F.Cu" "F.Mask" "F.Paste")
			(net "GND")
		)
		(pad "BA2" smd circle
			(at -21.850096 15.200122)
			(size 0.4572 0.4572)
			(layers "F.Cu" "F.Mask" "F.Paste")
			(net "GND")
		)
		(pad "BA3" smd circle
			(at -20.899882 15.200122)
			(size 0.4572 0.4572)
			(layers "F.Cu" "F.Mask" "F.Paste")
			(net "GND")
		)
		(pad "BA4" smd circle
			(at -19.949922 15.200122)
			(size 0.4572 0.4572)
			(layers "F.Cu" "F.Mask" "F.Paste")
			(net "Net_1416")
		)
		(pad "BA5" smd circle
			(at -18.999962 15.200122)
			(size 0.4572 0.4572)
			(layers "F.Cu" "F.Mask" "F.Paste")
			(net "GND")
		)
		(pad "BA6" smd circle
			(at -18.050002 15.200122)
			(size 0.4572 0.4572)
			(layers "F.Cu" "F.Mask" "F.Paste")
			(net "Net_1736")
		)
		(pad "BA7" smd circle
			(at -17.100042 15.200122)
			(size 0.4572 0.4572)
			(layers "F.Cu" "F.Mask" "F.Paste")
			(net "GND")
		)
		(pad "BA8" smd circle
			(at -16.150082 15.200122)
			(size 0.4572 0.4572)
			(layers "F.Cu" "F.Mask" "F.Paste")
			(net "Net_1359")
		)
		(pad "BA9" smd circle
			(at -15.200122 15.200122)
			(size 0.4572 0.4572)
			(layers "F.Cu" "F.Mask" "F.Paste")
			(net "GND")
		)
		(pad "BA10" smd circle
			(at -14.249908 15.200122)
			(size 0.4572 0.4572)
			(layers "F.Cu" "F.Mask" "F.Paste")
			(net "P5E_PEX2_STN2_TX_DP<46>")
		)
		(pad "BA11" smd circle
			(at -13.299948 15.200122)
			(size 0.4572 0.4572)
			(layers "F.Cu" "F.Mask" "F.Paste")
			(net "GND")
		)
		(pad "BA12" smd circle
			(at -12.349988 15.200122)
			(size 0.4572 0.4572)
			(layers "F.Cu" "F.Mask" "F.Paste")
			(net "P5E_PEX2_STN2_TX_DP<44>")
		)
		(pad "BA13" smd circle
			(at -11.400028 15.200122)
			(size 0.4572 0.4572)
			(layers "F.Cu" "F.Mask" "F.Paste")
			(net "GND")
		)
		(pad "BA14" smd circle
			(at -10.450068 15.200122)
			(size 0.4572 0.4572)
			(layers "F.Cu" "F.Mask" "F.Paste")
			(net "P5E_PEX2_STN2_TX_DP<42>")
		)
		(pad "BA15" smd circle
			(at -9.500108 15.200122)
			(size 0.4572 0.4572)
			(layers "F.Cu" "F.Mask" "F.Paste")
			(net "GND")
		)
		(pad "BA16" smd circle
			(at -8.549894 15.200122)
			(size 0.4572 0.4572)
			(layers "F.Cu" "F.Mask" "F.Paste")
			(net "P5E_PEX2_STN2_TX_DP<40>")
		)
		(pad "BA17" smd circle
			(at -7.599934 15.200122)
			(size 0.4572 0.4572)
			(layers "F.Cu" "F.Mask" "F.Paste")
			(net "GND")
		)
		(pad "BA18" smd circle
			(at -6.649974 15.200122)
			(size 0.4572 0.4572)
			(layers "F.Cu" "F.Mask" "F.Paste")
			(net "P5E_PEX2_STN2_TX_DP<38>")
		)
		(pad "BA19" smd circle
			(at -5.700014 15.200122)
			(size 0.4572 0.4572)
			(layers "F.Cu" "F.Mask" "F.Paste")
			(net "GND")
		)
		(pad "BA20" smd circle
			(at -4.750054 15.200122)
			(size 0.4572 0.4572)
			(layers "F.Cu" "F.Mask" "F.Paste")
			(net "P5E_PEX2_STN2_TX_DP<36>")
		)
		(pad "BA21" smd circle
			(at -3.800094 15.200122)
			(size 0.4572 0.4572)
			(layers "F.Cu" "F.Mask" "F.Paste")
			(net "GND")
		)
		(pad "BA22" smd circle
			(at -2.84988 15.200122)
			(size 0.4572 0.4572)
			(layers "F.Cu" "F.Mask" "F.Paste")
			(net "P5E_PEX2_STN2_TX_DP<34>")
		)
		(pad "BA23" smd circle
			(at -1.89992 15.200122)
			(size 0.4572 0.4572)
			(layers "F.Cu" "F.Mask" "F.Paste")
			(net "GND")
		)
		(pad "BA24" smd circle
			(at -0.94996 15.200122)
			(size 0.4572 0.4572)
			(layers "F.Cu" "F.Mask" "F.Paste")
			(net "P5E_PEX2_STN2_TX_DP<32>")
		)
		(pad "BA25" smd circle
			(at 0 15.200122)
			(size 0.4572 0.4572)
			(layers "F.Cu" "F.Mask" "F.Paste")
			(net "GND")
		)
		(pad "BA26" smd circle
			(at 0.94996 15.200122)
			(size 0.4572 0.4572)
			(layers "F.Cu" "F.Mask" "F.Paste")
			(net "P5E_PEX2_STN1_TX_DN<17>")
		)
		(pad "BA27" smd circle
			(at 1.89992 15.200122)
			(size 0.4572 0.4572)
			(layers "F.Cu" "F.Mask" "F.Paste")
			(net "GND")
		)
		(pad "BA28" smd circle
			(at 2.84988 15.200122)
			(size 0.4572 0.4572)
			(layers "F.Cu" "F.Mask" "F.Paste")
			(net "P5E_PEX2_STN1_TX_DN<19>")
		)
		(pad "BA29" smd circle
			(at 3.800094 15.200122)
			(size 0.4572 0.4572)
			(layers "F.Cu" "F.Mask" "F.Paste")
			(net "GND")
		)
		(pad "BA30" smd circle
			(at 4.750054 15.200122)
			(size 0.4572 0.4572)
			(layers "F.Cu" "F.Mask" "F.Paste")
			(net "P5E_PEX2_STN1_TX_DN<21>")
		)
		(pad "BA31" smd circle
			(at 5.700014 15.200122)
			(size 0.4572 0.4572)
			(layers "F.Cu" "F.Mask" "F.Paste")
			(net "GND")
		)
		(pad "BA32" smd circle
			(at 6.649974 15.200122)
			(size 0.4572 0.4572)
			(layers "F.Cu" "F.Mask" "F.Paste")
			(net "P5E_PEX2_STN1_TX_DN<23>")
		)
		(pad "BA33" smd circle
			(at 7.599934 15.200122)
			(size 0.4572 0.4572)
			(layers "F.Cu" "F.Mask" "F.Paste")
			(net "GND")
		)
		(pad "BA34" smd circle
			(at 8.549894 15.200122)
			(size 0.4572 0.4572)
			(layers "F.Cu" "F.Mask" "F.Paste")
			(net "P5E_PEX2_STN1_TX_DN<25>")
		)
		(pad "BA35" smd circle
			(at 9.500108 15.200122)
			(size 0.4572 0.4572)
			(layers "F.Cu" "F.Mask" "F.Paste")
			(net "GND")
		)
		(pad "BA36" smd circle
			(at 10.450068 15.200122)
			(size 0.4572 0.4572)
			(layers "F.Cu" "F.Mask" "F.Paste")
			(net "P5E_PEX2_STN1_TX_DN<27>")
		)
		(pad "BA37" smd circle
			(at 11.400028 15.200122)
			(size 0.4572 0.4572)
			(layers "F.Cu" "F.Mask" "F.Paste")
			(net "GND")
		)
		(pad "BA38" smd circle
			(at 12.349988 15.200122)
			(size 0.4572 0.4572)
			(layers "F.Cu" "F.Mask" "F.Paste")
			(net "P5E_PEX2_STN1_TX_DN<29>")
		)
		(pad "BA39" smd circle
			(at 13.299948 15.200122)
			(size 0.4572 0.4572)
			(layers "F.Cu" "F.Mask" "F.Paste")
			(net "GND")
		)
		(pad "BA40" smd circle
			(at 14.249908 15.200122)
			(size 0.4572 0.4572)
			(layers "F.Cu" "F.Mask" "F.Paste")
			(net "P5E_PEX2_STN1_TX_DN<31>")
		)
		(pad "BA41" smd circle
			(at 15.200122 15.200122)
			(size 0.4572 0.4572)
			(layers "F.Cu" "F.Mask" "F.Paste")
			(net "GND")
		)
		(pad "BA42" smd circle
			(at 16.150082 15.200122)
			(size 0.4572 0.4572)
			(layers "F.Cu" "F.Mask" "F.Paste")
			(net "P5E_PEX2_STN0_TX_DN<14>")
		)
		(pad "BA43" smd circle
			(at 17.100042 15.200122)
			(size 0.4572 0.4572)
			(layers "F.Cu" "F.Mask" "F.Paste")
			(net "GND")
		)
		(pad "BA44" smd circle
			(at 18.050002 15.200122)
			(size 0.4572 0.4572)
			(layers "F.Cu" "F.Mask" "F.Paste")
			(net "P5E_PEX2_STN0_TX_DN<12>")
		)
		(pad "BA45" smd circle
			(at 18.999962 15.200122)
			(size 0.4572 0.4572)
			(layers "F.Cu" "F.Mask" "F.Paste")
			(net "GND")
		)
		(pad "BA46" smd circle
			(at 19.949922 15.200122)
			(size 0.4572 0.4572)
			(layers "F.Cu" "F.Mask" "F.Paste")
			(net "P5E_PEX2_STN0_TX_DP<10>")
		)
		(pad "BA47" smd circle
			(at 20.899882 15.200122)
			(size 0.4572 0.4572)
			(layers "F.Cu" "F.Mask" "F.Paste")
			(net "GND")
		)
		(pad "BA48" smd circle
			(at 21.850096 15.200122)
			(size 0.4572 0.4572)
			(layers "F.Cu" "F.Mask" "F.Paste")
			(net "GND")
		)
		(pad "BA49" smd circle
			(at 22.800056 15.200122)
			(size 0.4572 0.4572)
			(layers "F.Cu" "F.Mask" "F.Paste")
			(net "GND")
		)
		(pad "BB1" smd circle
			(at -22.800056 16.150082)
			(size 0.4572 0.4572)
			(layers "F.Cu" "F.Mask" "F.Paste")
			(net "Net_1439")
		)
		(pad "BB2" smd circle
			(at -21.850096 16.150082)
			(size 0.4572 0.4572)
			(layers "F.Cu" "F.Mask" "F.Paste")
			(net "Net_1387")
		)
		(pad "BB3" smd circle
			(at -20.899882 16.150082)
			(size 0.4572 0.4572)
			(layers "F.Cu" "F.Mask" "F.Paste")
			(net "GND")
		)
		(pad "BB4" smd circle
			(at -19.949922 16.150082)
			(size 0.4572 0.4572)
			(layers "F.Cu" "F.Mask" "F.Paste")
			(net "Net_1733")
		)
		(pad "BB5" smd circle
			(at -18.999962 16.150082)
			(size 0.4572 0.4572)
			(layers "F.Cu" "F.Mask" "F.Paste")
			(net "GND")
		)
		(pad "BB6" smd circle
			(at -18.050002 16.150082)
			(size 0.4572 0.4572)
			(layers "F.Cu" "F.Mask" "F.Paste")
			(net "Net_1391")
		)
		(pad "BB7" smd circle
			(at -17.100042 16.150082)
			(size 0.4572 0.4572)
			(layers "F.Cu" "F.Mask" "F.Paste")
			(net "GND")
		)
		(pad "BB8" smd circle
			(at -16.150082 16.150082)
			(size 0.4572 0.4572)
			(layers "F.Cu" "F.Mask" "F.Paste")
			(net "Net_1726")
		)
		(pad "BB9" smd circle
			(at -15.200122 16.150082)
			(size 0.4572 0.4572)
			(layers "F.Cu" "F.Mask" "F.Paste")
			(net "GND")
		)
		(pad "BB10" smd circle
			(at -14.249908 16.150082)
			(size 0.4572 0.4572)
			(layers "F.Cu" "F.Mask" "F.Paste")
			(net "P5E_PEX2_STN2_TX_DN<46>")
		)
		(pad "BB11" smd circle
			(at -13.299948 16.150082)
			(size 0.4572 0.4572)
			(layers "F.Cu" "F.Mask" "F.Paste")
			(net "GND")
		)
		(pad "BB12" smd circle
			(at -12.349988 16.150082)
			(size 0.4572 0.4572)
			(layers "F.Cu" "F.Mask" "F.Paste")
			(net "P5E_PEX2_STN2_TX_DN<44>")
		)
		(pad "BB13" smd circle
			(at -11.400028 16.150082)
			(size 0.4572 0.4572)
			(layers "F.Cu" "F.Mask" "F.Paste")
			(net "GND")
		)
		(pad "BB14" smd circle
			(at -10.450068 16.150082)
			(size 0.4572 0.4572)
			(layers "F.Cu" "F.Mask" "F.Paste")
			(net "P5E_PEX2_STN2_TX_DN<42>")
		)
		(pad "BB15" smd circle
			(at -9.500108 16.150082)
			(size 0.4572 0.4572)
			(layers "F.Cu" "F.Mask" "F.Paste")
			(net "GND")
		)
		(pad "BB16" smd circle
			(at -8.549894 16.150082)
			(size 0.4572 0.4572)
			(layers "F.Cu" "F.Mask" "F.Paste")
			(net "P5E_PEX2_STN2_TX_DN<40>")
		)
		(pad "BB17" smd circle
			(at -7.599934 16.150082)
			(size 0.4572 0.4572)
			(layers "F.Cu" "F.Mask" "F.Paste")
			(net "GND")
		)
		(pad "BB18" smd circle
			(at -6.649974 16.150082)
			(size 0.4572 0.4572)
			(layers "F.Cu" "F.Mask" "F.Paste")
			(net "P5E_PEX2_STN2_TX_DN<38>")
		)
		(pad "BB19" smd circle
			(at -5.700014 16.150082)
			(size 0.4572 0.4572)
			(layers "F.Cu" "F.Mask" "F.Paste")
			(net "GND")
		)
		(pad "BB20" smd circle
			(at -4.750054 16.150082)
			(size 0.4572 0.4572)
			(layers "F.Cu" "F.Mask" "F.Paste")
			(net "P5E_PEX2_STN2_TX_DN<36>")
		)
		(pad "BB21" smd circle
			(at -3.800094 16.150082)
			(size 0.4572 0.4572)
			(layers "F.Cu" "F.Mask" "F.Paste")
			(net "GND")
		)
		(pad "BB22" smd circle
			(at -2.84988 16.150082)
			(size 0.4572 0.4572)
			(layers "F.Cu" "F.Mask" "F.Paste")
			(net "P5E_PEX2_STN2_TX_DN<34>")
		)
		(pad "BB23" smd circle
			(at -1.89992 16.150082)
			(size 0.4572 0.4572)
			(layers "F.Cu" "F.Mask" "F.Paste")
			(net "GND")
		)
		(pad "BB24" smd circle
			(at -0.94996 16.150082)
			(size 0.4572 0.4572)
			(layers "F.Cu" "F.Mask" "F.Paste")
			(net "P5E_PEX2_STN2_TX_DN<32>")
		)
		(pad "BB25" smd circle
			(at 0 16.150082)
			(size 0.4572 0.4572)
			(layers "F.Cu" "F.Mask" "F.Paste")
			(net "GND")
		)
		(pad "BB26" smd circle
			(at 0.94996 16.150082)
			(size 0.4572 0.4572)
			(layers "F.Cu" "F.Mask" "F.Paste")
			(net "P5E_PEX2_STN1_TX_DP<17>")
		)
		(pad "BB27" smd circle
			(at 1.89992 16.150082)
			(size 0.4572 0.4572)
			(layers "F.Cu" "F.Mask" "F.Paste")
			(net "GND")
		)
		(pad "BB28" smd circle
			(at 2.84988 16.150082)
			(size 0.4572 0.4572)
			(layers "F.Cu" "F.Mask" "F.Paste")
			(net "P5E_PEX2_STN1_TX_DP<19>")
		)
		(pad "BB29" smd circle
			(at 3.800094 16.150082)
			(size 0.4572 0.4572)
			(layers "F.Cu" "F.Mask" "F.Paste")
			(net "GND")
		)
		(pad "BB30" smd circle
			(at 4.750054 16.150082)
			(size 0.4572 0.4572)
			(layers "F.Cu" "F.Mask" "F.Paste")
			(net "P5E_PEX2_STN1_TX_DP<21>")
		)
		(pad "BB31" smd circle
			(at 5.700014 16.150082)
			(size 0.4572 0.4572)
			(layers "F.Cu" "F.Mask" "F.Paste")
			(net "GND")
		)
		(pad "BB32" smd circle
			(at 6.649974 16.150082)
			(size 0.4572 0.4572)
			(layers "F.Cu" "F.Mask" "F.Paste")
			(net "P5E_PEX2_STN1_TX_DP<23>")
		)
		(pad "BB33" smd circle
			(at 7.599934 16.150082)
			(size 0.4572 0.4572)
			(layers "F.Cu" "F.Mask" "F.Paste")
			(net "GND")
		)
		(pad "BB34" smd circle
			(at 8.549894 16.150082)
			(size 0.4572 0.4572)
			(layers "F.Cu" "F.Mask" "F.Paste")
			(net "P5E_PEX2_STN1_TX_DP<25>")
		)
		(pad "BB35" smd circle
			(at 9.500108 16.150082)
			(size 0.4572 0.4572)
			(layers "F.Cu" "F.Mask" "F.Paste")
			(net "GND")
		)
		(pad "BB36" smd circle
			(at 10.450068 16.150082)
			(size 0.4572 0.4572)
			(layers "F.Cu" "F.Mask" "F.Paste")
			(net "P5E_PEX2_STN1_TX_DP<27>")
		)
		(pad "BB37" smd circle
			(at 11.400028 16.150082)
			(size 0.4572 0.4572)
			(layers "F.Cu" "F.Mask" "F.Paste")
			(net "GND")
		)
		(pad "BB38" smd circle
			(at 12.349988 16.150082)
			(size 0.4572 0.4572)
			(layers "F.Cu" "F.Mask" "F.Paste")
			(net "P5E_PEX2_STN1_TX_DP<29>")
		)
		(pad "BB39" smd circle
			(at 13.299948 16.150082)
			(size 0.4572 0.4572)
			(layers "F.Cu" "F.Mask" "F.Paste")
			(net "GND")
		)
		(pad "BB40" smd circle
			(at 14.249908 16.150082)
			(size 0.4572 0.4572)
			(layers "F.Cu" "F.Mask" "F.Paste")
			(net "P5E_PEX2_STN1_TX_DP<31>")
		)
		(pad "BB41" smd circle
			(at 15.200122 16.150082)
			(size 0.4572 0.4572)
			(layers "F.Cu" "F.Mask" "F.Paste")
			(net "GND")
		)
		(pad "BB42" smd circle
			(at 16.150082 16.150082)
			(size 0.4572 0.4572)
			(layers "F.Cu" "F.Mask" "F.Paste")
			(net "P5E_PEX2_STN0_TX_DP<14>")
		)
		(pad "BB43" smd circle
			(at 17.100042 16.150082)
			(size 0.4572 0.4572)
			(layers "F.Cu" "F.Mask" "F.Paste")
			(net "GND")
		)
		(pad "BB44" smd circle
			(at 18.050002 16.150082)
			(size 0.4572 0.4572)
			(layers "F.Cu" "F.Mask" "F.Paste")
			(net "P5E_PEX2_STN0_TX_DP<12>")
		)
		(pad "BB45" smd circle
			(at 18.999962 16.150082)
			(size 0.4572 0.4572)
			(layers "F.Cu" "F.Mask" "F.Paste")
			(net "GND")
		)
		(pad "BB46" smd circle
			(at 19.949922 16.150082)
			(size 0.4572 0.4572)
			(layers "F.Cu" "F.Mask" "F.Paste")
			(net "P5E_PEX2_STN0_TX_DN<10>")
		)
		(pad "BB47" smd circle
			(at 20.899882 16.150082)
			(size 0.4572 0.4572)
			(layers "F.Cu" "F.Mask" "F.Paste")
			(net "GND")
		)
		(pad "BB48" smd circle
			(at 21.850096 16.150082)
			(size 0.4572 0.4572)
			(layers "F.Cu" "F.Mask" "F.Paste")
			(net "P5E_PEX2_STN0_TX_DP<7>")
		)
		(pad "BB49" smd circle
			(at 22.800056 16.150082)
			(size 0.4572 0.4572)
			(layers "F.Cu" "F.Mask" "F.Paste")
			(net "P5E_PEX2_STN0_TX_DN<7>")
		)
		(pad "BC1" smd circle
			(at -22.800056 17.100042)
			(size 0.4572 0.4572)
			(layers "F.Cu" "F.Mask" "F.Paste")
			(net "GND")
		)
		(pad "BC2" smd circle
			(at -21.850096 17.100042)
			(size 0.4572 0.4572)
			(layers "F.Cu" "F.Mask" "F.Paste")
			(net "GND")
		)
		(pad "BC3" smd circle
			(at -20.899882 17.100042)
			(size 0.4572 0.4572)
			(layers "F.Cu" "F.Mask" "F.Paste")
			(net "Net_1402")
		)
		(pad "BC4" smd circle
			(at -19.949922 17.100042)
			(size 0.4572 0.4572)
			(layers "F.Cu" "F.Mask" "F.Paste")
			(net "GND")
		)
		(pad "BC5" smd circle
			(at -18.999962 17.100042)
			(size 0.4572 0.4572)
			(layers "F.Cu" "F.Mask" "F.Paste")
			(net "Net_1722")
		)
		(pad "BC6" smd circle
			(at -18.050002 17.100042)
			(size 0.4572 0.4572)
			(layers "F.Cu" "F.Mask" "F.Paste")
			(net "GND")
		)
		(pad "BC7" smd circle
			(at -17.100042 17.100042)
			(size 0.4572 0.4572)
			(layers "F.Cu" "F.Mask" "F.Paste")
			(net "Net_1735")
		)
		(pad "BC8" smd circle
			(at -16.150082 17.100042)
			(size 0.4572 0.4572)
			(layers "F.Cu" "F.Mask" "F.Paste")
			(net "GND")
		)
		(pad "BC9" smd circle
			(at -15.200122 17.100042)
			(size 0.4572 0.4572)
			(layers "F.Cu" "F.Mask" "F.Paste")
			(net "P5E_PEX2_STN2_TX_DP<47>")
		)
		(pad "BC10" smd circle
			(at -14.249908 17.100042)
			(size 0.4572 0.4572)
			(layers "F.Cu" "F.Mask" "F.Paste")
			(net "GND")
		)
		(pad "BC11" smd circle
			(at -13.299948 17.100042)
			(size 0.4572 0.4572)
			(layers "F.Cu" "F.Mask" "F.Paste")
			(net "P5E_PEX2_STN2_TX_DP<45>")
		)
		(pad "BC12" smd circle
			(at -12.349988 17.100042)
			(size 0.4572 0.4572)
			(layers "F.Cu" "F.Mask" "F.Paste")
			(net "GND")
		)
		(pad "BC13" smd circle
			(at -11.400028 17.100042)
			(size 0.4572 0.4572)
			(layers "F.Cu" "F.Mask" "F.Paste")
			(net "P5E_PEX2_STN2_TX_DP<43>")
		)
		(pad "BC14" smd circle
			(at -10.450068 17.100042)
			(size 0.4572 0.4572)
			(layers "F.Cu" "F.Mask" "F.Paste")
			(net "GND")
		)
		(pad "BC15" smd circle
			(at -9.500108 17.100042)
			(size 0.4572 0.4572)
			(layers "F.Cu" "F.Mask" "F.Paste")
			(net "P5E_PEX2_STN2_TX_DP<41>")
		)
		(pad "BC16" smd circle
			(at -8.549894 17.100042)
			(size 0.4572 0.4572)
			(layers "F.Cu" "F.Mask" "F.Paste")
			(net "GND")
		)
		(pad "BC17" smd circle
			(at -7.599934 17.100042)
			(size 0.4572 0.4572)
			(layers "F.Cu" "F.Mask" "F.Paste")
			(net "P5E_PEX2_STN2_TX_DP<39>")
		)
		(pad "BC18" smd circle
			(at -6.649974 17.100042)
			(size 0.4572 0.4572)
			(layers "F.Cu" "F.Mask" "F.Paste")
			(net "GND")
		)
		(pad "BC19" smd circle
			(at -5.700014 17.100042)
			(size 0.4572 0.4572)
			(layers "F.Cu" "F.Mask" "F.Paste")
			(net "P5E_PEX2_STN2_TX_DP<37>")
		)
		(pad "BC20" smd circle
			(at -4.750054 17.100042)
			(size 0.4572 0.4572)
			(layers "F.Cu" "F.Mask" "F.Paste")
			(net "GND")
		)
		(pad "BC21" smd circle
			(at -3.800094 17.100042)
			(size 0.4572 0.4572)
			(layers "F.Cu" "F.Mask" "F.Paste")
			(net "P5E_PEX2_STN2_TX_DP<35>")
		)
		(pad "BC22" smd circle
			(at -2.84988 17.100042)
			(size 0.4572 0.4572)
			(layers "F.Cu" "F.Mask" "F.Paste")
			(net "GND")
		)
		(pad "BC23" smd circle
			(at -1.89992 17.100042)
			(size 0.4572 0.4572)
			(layers "F.Cu" "F.Mask" "F.Paste")
			(net "P5E_PEX2_STN2_TX_DP<33>")
		)
		(pad "BC24" smd circle
			(at -0.94996 17.100042)
			(size 0.4572 0.4572)
			(layers "F.Cu" "F.Mask" "F.Paste")
			(net "GND")
		)
		(pad "BC25" smd circle
			(at 0 17.100042)
			(size 0.4572 0.4572)
			(layers "F.Cu" "F.Mask" "F.Paste")
			(net "P5E_PEX2_STN1_TX_DP<16>")
		)
		(pad "BC26" smd circle
			(at 0.94996 17.100042)
			(size 0.4572 0.4572)
			(layers "F.Cu" "F.Mask" "F.Paste")
			(net "GND")
		)
		(pad "BC27" smd circle
			(at 1.89992 17.100042)
			(size 0.4572 0.4572)
			(layers "F.Cu" "F.Mask" "F.Paste")
			(net "P5E_PEX2_STN1_TX_DP<18>")
		)
		(pad "BC28" smd circle
			(at 2.84988 17.100042)
			(size 0.4572 0.4572)
			(layers "F.Cu" "F.Mask" "F.Paste")
			(net "GND")
		)
		(pad "BC29" smd circle
			(at 3.800094 17.100042)
			(size 0.4572 0.4572)
			(layers "F.Cu" "F.Mask" "F.Paste")
			(net "P5E_PEX2_STN1_TX_DP<20>")
		)
		(pad "BC30" smd circle
			(at 4.750054 17.100042)
			(size 0.4572 0.4572)
			(layers "F.Cu" "F.Mask" "F.Paste")
			(net "GND")
		)
		(pad "BC31" smd circle
			(at 5.700014 17.100042)
			(size 0.4572 0.4572)
			(layers "F.Cu" "F.Mask" "F.Paste")
			(net "P5E_PEX2_STN1_TX_DP<22>")
		)
		(pad "BC32" smd circle
			(at 6.649974 17.100042)
			(size 0.4572 0.4572)
			(layers "F.Cu" "F.Mask" "F.Paste")
			(net "GND")
		)
		(pad "BC33" smd circle
			(at 7.599934 17.100042)
			(size 0.4572 0.4572)
			(layers "F.Cu" "F.Mask" "F.Paste")
			(net "P5E_PEX2_STN1_TX_DP<24>")
		)
		(pad "BC34" smd circle
			(at 8.549894 17.100042)
			(size 0.4572 0.4572)
			(layers "F.Cu" "F.Mask" "F.Paste")
			(net "GND")
		)
		(pad "BC35" smd circle
			(at 9.500108 17.100042)
			(size 0.4572 0.4572)
			(layers "F.Cu" "F.Mask" "F.Paste")
			(net "P5E_PEX2_STN1_TX_DP<26>")
		)
		(pad "BC36" smd circle
			(at 10.450068 17.100042)
			(size 0.4572 0.4572)
			(layers "F.Cu" "F.Mask" "F.Paste")
			(net "GND")
		)
		(pad "BC37" smd circle
			(at 11.400028 17.100042)
			(size 0.4572 0.4572)
			(layers "F.Cu" "F.Mask" "F.Paste")
			(net "P5E_PEX2_STN1_TX_DP<28>")
		)
		(pad "BC38" smd circle
			(at 12.349988 17.100042)
			(size 0.4572 0.4572)
			(layers "F.Cu" "F.Mask" "F.Paste")
			(net "GND")
		)
		(pad "BC39" smd circle
			(at 13.299948 17.100042)
			(size 0.4572 0.4572)
			(layers "F.Cu" "F.Mask" "F.Paste")
			(net "P5E_PEX2_STN1_TX_DP<30>")
		)
		(pad "BC40" smd circle
			(at 14.249908 17.100042)
			(size 0.4572 0.4572)
			(layers "F.Cu" "F.Mask" "F.Paste")
			(net "GND")
		)
		(pad "BC41" smd circle
			(at 15.200122 17.100042)
			(size 0.4572 0.4572)
			(layers "F.Cu" "F.Mask" "F.Paste")
			(net "P5E_PEX2_STN0_TX_DP<15>")
		)
		(pad "BC42" smd circle
			(at 16.150082 17.100042)
			(size 0.4572 0.4572)
			(layers "F.Cu" "F.Mask" "F.Paste")
			(net "GND")
		)
		(pad "BC43" smd circle
			(at 17.100042 17.100042)
			(size 0.4572 0.4572)
			(layers "F.Cu" "F.Mask" "F.Paste")
			(net "P5E_PEX2_STN0_TX_DP<13>")
		)
		(pad "BC44" smd circle
			(at 18.050002 17.100042)
			(size 0.4572 0.4572)
			(layers "F.Cu" "F.Mask" "F.Paste")
			(net "GND")
		)
		(pad "BC45" smd circle
			(at 18.999962 17.100042)
			(size 0.4572 0.4572)
			(layers "F.Cu" "F.Mask" "F.Paste")
			(net "P5E_PEX2_STN0_TX_DP<11>")
		)
		(pad "BC46" smd circle
			(at 19.949922 17.100042)
			(size 0.4572 0.4572)
			(layers "F.Cu" "F.Mask" "F.Paste")
			(net "GND")
		)
		(pad "BC47" smd circle
			(at 20.899882 17.100042)
			(size 0.4572 0.4572)
			(layers "F.Cu" "F.Mask" "F.Paste")
			(net "P5E_PEX2_STN0_TX_DP<9>")
		)
		(pad "BC48" smd circle
			(at 21.850096 17.100042)
			(size 0.4572 0.4572)
			(layers "F.Cu" "F.Mask" "F.Paste")
			(net "GND")
		)
		(pad "BC49" smd circle
			(at 22.800056 17.100042)
			(size 0.4572 0.4572)
			(layers "F.Cu" "F.Mask" "F.Paste")
			(net "GND")
		)
		(pad "BD1" smd circle
			(at -22.800056 18.050002)
			(size 0.4572 0.4572)
			(layers "F.Cu" "F.Mask" "F.Paste")
			(net "GND")
		)
		(pad "BD2" smd circle
			(at -21.850096 18.050002)
			(size 0.4572 0.4572)
			(layers "F.Cu" "F.Mask" "F.Paste")
			(net "GND")
		)
		(pad "BD3" smd circle
			(at -20.899882 18.050002)
			(size 0.4572 0.4572)
			(layers "F.Cu" "F.Mask" "F.Paste")
			(net "Net_1729")
		)
		(pad "BD4" smd circle
			(at -19.949922 18.050002)
			(size 0.4572 0.4572)
			(layers "F.Cu" "F.Mask" "F.Paste")
			(net "GND")
		)
		(pad "BD5" smd circle
			(at -18.999962 18.050002)
			(size 0.4572 0.4572)
			(layers "F.Cu" "F.Mask" "F.Paste")
			(net "Net_1396")
		)
		(pad "BD6" smd circle
			(at -18.050002 18.050002)
			(size 0.4572 0.4572)
			(layers "F.Cu" "F.Mask" "F.Paste")
			(net "GND")
		)
		(pad "BD7" smd circle
			(at -17.100042 18.050002)
			(size 0.4572 0.4572)
			(layers "F.Cu" "F.Mask" "F.Paste")
			(net "Net_1716")
		)
		(pad "BD8" smd circle
			(at -16.150082 18.050002)
			(size 0.4572 0.4572)
			(layers "F.Cu" "F.Mask" "F.Paste")
			(net "GND")
		)
		(pad "BD9" smd circle
			(at -15.200122 18.050002)
			(size 0.4572 0.4572)
			(layers "F.Cu" "F.Mask" "F.Paste")
			(net "P5E_PEX2_STN2_TX_DN<47>")
		)
		(pad "BD10" smd circle
			(at -14.249908 18.050002)
			(size 0.4572 0.4572)
			(layers "F.Cu" "F.Mask" "F.Paste")
			(net "GND")
		)
		(pad "BD11" smd circle
			(at -13.299948 18.050002)
			(size 0.4572 0.4572)
			(layers "F.Cu" "F.Mask" "F.Paste")
			(net "P5E_PEX2_STN2_TX_DN<45>")
		)
		(pad "BD12" smd circle
			(at -12.349988 18.050002)
			(size 0.4572 0.4572)
			(layers "F.Cu" "F.Mask" "F.Paste")
			(net "GND")
		)
		(pad "BD13" smd circle
			(at -11.400028 18.050002)
			(size 0.4572 0.4572)
			(layers "F.Cu" "F.Mask" "F.Paste")
			(net "P5E_PEX2_STN2_TX_DN<43>")
		)
		(pad "BD14" smd circle
			(at -10.450068 18.050002)
			(size 0.4572 0.4572)
			(layers "F.Cu" "F.Mask" "F.Paste")
			(net "GND")
		)
		(pad "BD15" smd circle
			(at -9.500108 18.050002)
			(size 0.4572 0.4572)
			(layers "F.Cu" "F.Mask" "F.Paste")
			(net "P5E_PEX2_STN2_TX_DN<41>")
		)
		(pad "BD16" smd circle
			(at -8.549894 18.050002)
			(size 0.4572 0.4572)
			(layers "F.Cu" "F.Mask" "F.Paste")
			(net "GND")
		)
		(pad "BD17" smd circle
			(at -7.599934 18.050002)
			(size 0.4572 0.4572)
			(layers "F.Cu" "F.Mask" "F.Paste")
			(net "P5E_PEX2_STN2_TX_DN<39>")
		)
		(pad "BD18" smd circle
			(at -6.649974 18.050002)
			(size 0.4572 0.4572)
			(layers "F.Cu" "F.Mask" "F.Paste")
			(net "GND")
		)
		(pad "BD19" smd circle
			(at -5.700014 18.050002)
			(size 0.4572 0.4572)
			(layers "F.Cu" "F.Mask" "F.Paste")
			(net "P5E_PEX2_STN2_TX_DN<37>")
		)
		(pad "BD20" smd circle
			(at -4.750054 18.050002)
			(size 0.4572 0.4572)
			(layers "F.Cu" "F.Mask" "F.Paste")
			(net "GND")
		)
		(pad "BD21" smd circle
			(at -3.800094 18.050002)
			(size 0.4572 0.4572)
			(layers "F.Cu" "F.Mask" "F.Paste")
			(net "P5E_PEX2_STN2_TX_DN<35>")
		)
		(pad "BD22" smd circle
			(at -2.84988 18.050002)
			(size 0.4572 0.4572)
			(layers "F.Cu" "F.Mask" "F.Paste")
			(net "GND")
		)
		(pad "BD23" smd circle
			(at -1.89992 18.050002)
			(size 0.4572 0.4572)
			(layers "F.Cu" "F.Mask" "F.Paste")
			(net "P5E_PEX2_STN2_TX_DN<33>")
		)
		(pad "BD24" smd circle
			(at -0.94996 18.050002)
			(size 0.4572 0.4572)
			(layers "F.Cu" "F.Mask" "F.Paste")
			(net "GND")
		)
		(pad "BD25" smd circle
			(at 0 18.050002)
			(size 0.4572 0.4572)
			(layers "F.Cu" "F.Mask" "F.Paste")
			(net "P5E_PEX2_STN1_TX_DN<16>")
		)
		(pad "BD26" smd circle
			(at 0.94996 18.050002)
			(size 0.4572 0.4572)
			(layers "F.Cu" "F.Mask" "F.Paste")
			(net "GND")
		)
		(pad "BD27" smd circle
			(at 1.89992 18.050002)
			(size 0.4572 0.4572)
			(layers "F.Cu" "F.Mask" "F.Paste")
			(net "P5E_PEX2_STN1_TX_DN<18>")
		)
		(pad "BD28" smd circle
			(at 2.84988 18.050002)
			(size 0.4572 0.4572)
			(layers "F.Cu" "F.Mask" "F.Paste")
			(net "GND")
		)
		(pad "BD29" smd circle
			(at 3.800094 18.050002)
			(size 0.4572 0.4572)
			(layers "F.Cu" "F.Mask" "F.Paste")
			(net "P5E_PEX2_STN1_TX_DN<20>")
		)
		(pad "BD30" smd circle
			(at 4.750054 18.050002)
			(size 0.4572 0.4572)
			(layers "F.Cu" "F.Mask" "F.Paste")
			(net "GND")
		)
		(pad "BD31" smd circle
			(at 5.700014 18.050002)
			(size 0.4572 0.4572)
			(layers "F.Cu" "F.Mask" "F.Paste")
			(net "P5E_PEX2_STN1_TX_DN<22>")
		)
		(pad "BD32" smd circle
			(at 6.649974 18.050002)
			(size 0.4572 0.4572)
			(layers "F.Cu" "F.Mask" "F.Paste")
			(net "GND")
		)
		(pad "BD33" smd circle
			(at 7.599934 18.050002)
			(size 0.4572 0.4572)
			(layers "F.Cu" "F.Mask" "F.Paste")
			(net "P5E_PEX2_STN1_TX_DN<24>")
		)
		(pad "BD34" smd circle
			(at 8.549894 18.050002)
			(size 0.4572 0.4572)
			(layers "F.Cu" "F.Mask" "F.Paste")
			(net "GND")
		)
		(pad "BD35" smd circle
			(at 9.500108 18.050002)
			(size 0.4572 0.4572)
			(layers "F.Cu" "F.Mask" "F.Paste")
			(net "P5E_PEX2_STN1_TX_DN<26>")
		)
		(pad "BD36" smd circle
			(at 10.450068 18.050002)
			(size 0.4572 0.4572)
			(layers "F.Cu" "F.Mask" "F.Paste")
			(net "GND")
		)
		(pad "BD37" smd circle
			(at 11.400028 18.050002)
			(size 0.4572 0.4572)
			(layers "F.Cu" "F.Mask" "F.Paste")
			(net "P5E_PEX2_STN1_TX_DN<28>")
		)
		(pad "BD38" smd circle
			(at 12.349988 18.050002)
			(size 0.4572 0.4572)
			(layers "F.Cu" "F.Mask" "F.Paste")
			(net "GND")
		)
		(pad "BD39" smd circle
			(at 13.299948 18.050002)
			(size 0.4572 0.4572)
			(layers "F.Cu" "F.Mask" "F.Paste")
			(net "P5E_PEX2_STN1_TX_DN<30>")
		)
		(pad "BD40" smd circle
			(at 14.249908 18.050002)
			(size 0.4572 0.4572)
			(layers "F.Cu" "F.Mask" "F.Paste")
			(net "GND")
		)
		(pad "BD41" smd circle
			(at 15.200122 18.050002)
			(size 0.4572 0.4572)
			(layers "F.Cu" "F.Mask" "F.Paste")
			(net "P5E_PEX2_STN0_TX_DN<15>")
		)
		(pad "BD42" smd circle
			(at 16.150082 18.050002)
			(size 0.4572 0.4572)
			(layers "F.Cu" "F.Mask" "F.Paste")
			(net "GND")
		)
		(pad "BD43" smd circle
			(at 17.100042 18.050002)
			(size 0.4572 0.4572)
			(layers "F.Cu" "F.Mask" "F.Paste")
			(net "P5E_PEX2_STN0_TX_DN<13>")
		)
		(pad "BD44" smd circle
			(at 18.050002 18.050002)
			(size 0.4572 0.4572)
			(layers "F.Cu" "F.Mask" "F.Paste")
			(net "GND")
		)
		(pad "BD45" smd circle
			(at 18.999962 18.050002)
			(size 0.4572 0.4572)
			(layers "F.Cu" "F.Mask" "F.Paste")
			(net "P5E_PEX2_STN0_TX_DN<11>")
		)
		(pad "BD46" smd circle
			(at 19.949922 18.050002)
			(size 0.4572 0.4572)
			(layers "F.Cu" "F.Mask" "F.Paste")
			(net "GND")
		)
		(pad "BD47" smd circle
			(at 20.899882 18.050002)
			(size 0.4572 0.4572)
			(layers "F.Cu" "F.Mask" "F.Paste")
			(net "P5E_PEX2_STN0_TX_DN<9>")
		)
		(pad "BD48" smd circle
			(at 21.850096 18.050002)
			(size 0.4572 0.4572)
			(layers "F.Cu" "F.Mask" "F.Paste")
			(net "GND")
		)
		(pad "BD49" smd circle
			(at 22.800056 18.050002)
			(size 0.4572 0.4572)
			(layers "F.Cu" "F.Mask" "F.Paste")
			(net "GND")
		)
		(pad "BE1" smd circle
			(at -22.800056 18.999962)
			(size 0.4572 0.4572)
			(layers "F.Cu" "F.Mask" "F.Paste")
			(net "Net_1457")
		)
		(pad "BE2" smd circle
			(at -21.850096 18.999962)
			(size 0.4572 0.4572)
			(layers "F.Cu" "F.Mask" "F.Paste")
			(net "Net_1454")
		)
		(pad "BE3" smd circle
			(at -20.899882 18.999962)
			(size 0.4572 0.4572)
			(layers "F.Cu" "F.Mask" "F.Paste")
			(net "GND")
		)
		(pad "BE4" smd circle
			(at -19.949922 18.999962)
			(size 0.4572 0.4572)
			(layers "F.Cu" "F.Mask" "F.Paste")
			(net "GND")
		)
		(pad "BE5" smd circle
			(at -18.999962 18.999962)
			(size 0.4572 0.4572)
			(layers "F.Cu" "F.Mask" "F.Paste")
			(net "GND")
		)
		(pad "BE6" smd circle
			(at -18.050002 18.999962)
			(size 0.4572 0.4572)
			(layers "F.Cu" "F.Mask" "F.Paste")
			(net "GND")
		)
		(pad "BE7" smd circle
			(at -17.100042 18.999962)
			(size 0.4572 0.4572)
			(layers "F.Cu" "F.Mask" "F.Paste")
			(net "GND")
		)
		(pad "BE8" smd circle
			(at -16.150082 18.999962)
			(size 0.4572 0.4572)
			(layers "F.Cu" "F.Mask" "F.Paste")
			(net "GND")
		)
		(pad "BE9" smd circle
			(at -15.200122 18.999962)
			(size 0.4572 0.4572)
			(layers "F.Cu" "F.Mask" "F.Paste")
			(net "GND")
		)
		(pad "BE10" smd circle
			(at -14.249908 18.999962)
			(size 0.4572 0.4572)
			(layers "F.Cu" "F.Mask" "F.Paste")
			(net "GND")
		)
		(pad "BE11" smd circle
			(at -13.299948 18.999962)
			(size 0.4572 0.4572)
			(layers "F.Cu" "F.Mask" "F.Paste")
			(net "GND")
		)
		(pad "BE12" smd circle
			(at -12.349988 18.999962)
			(size 0.4572 0.4572)
			(layers "F.Cu" "F.Mask" "F.Paste")
			(net "GND")
		)
		(pad "BE13" smd circle
			(at -11.400028 18.999962)
			(size 0.4572 0.4572)
			(layers "F.Cu" "F.Mask" "F.Paste")
			(net "GND")
		)
		(pad "BE14" smd circle
			(at -10.450068 18.999962)
			(size 0.4572 0.4572)
			(layers "F.Cu" "F.Mask" "F.Paste")
			(net "GND")
		)
		(pad "BE15" smd circle
			(at -9.500108 18.999962)
			(size 0.4572 0.4572)
			(layers "F.Cu" "F.Mask" "F.Paste")
			(net "GND")
		)
		(pad "BE16" smd circle
			(at -8.549894 18.999962)
			(size 0.4572 0.4572)
			(layers "F.Cu" "F.Mask" "F.Paste")
			(net "GND")
		)
		(pad "BE17" smd circle
			(at -7.599934 18.999962)
			(size 0.4572 0.4572)
			(layers "F.Cu" "F.Mask" "F.Paste")
			(net "GND")
		)
		(pad "BE18" smd circle
			(at -6.649974 18.999962)
			(size 0.4572 0.4572)
			(layers "F.Cu" "F.Mask" "F.Paste")
			(net "GND")
		)
		(pad "BE19" smd circle
			(at -5.700014 18.999962)
			(size 0.4572 0.4572)
			(layers "F.Cu" "F.Mask" "F.Paste")
			(net "GND")
		)
		(pad "BE20" smd circle
			(at -4.750054 18.999962)
			(size 0.4572 0.4572)
			(layers "F.Cu" "F.Mask" "F.Paste")
			(net "GND")
		)
		(pad "BE21" smd circle
			(at -3.800094 18.999962)
			(size 0.4572 0.4572)
			(layers "F.Cu" "F.Mask" "F.Paste")
			(net "GND")
		)
		(pad "BE22" smd circle
			(at -2.84988 18.999962)
			(size 0.4572 0.4572)
			(layers "F.Cu" "F.Mask" "F.Paste")
			(net "GND")
		)
		(pad "BE23" smd circle
			(at -1.89992 18.999962)
			(size 0.4572 0.4572)
			(layers "F.Cu" "F.Mask" "F.Paste")
			(net "GND")
		)
		(pad "BE24" smd circle
			(at -0.94996 18.999962)
			(size 0.4572 0.4572)
			(layers "F.Cu" "F.Mask" "F.Paste")
			(net "GND")
		)
		(pad "BE25" smd circle
			(at 0 18.999962)
			(size 0.4572 0.4572)
			(layers "F.Cu" "F.Mask" "F.Paste")
			(net "GND")
		)
		(pad "BE26" smd circle
			(at 0.94996 18.999962)
			(size 0.4572 0.4572)
			(layers "F.Cu" "F.Mask" "F.Paste")
			(net "GND")
		)
		(pad "BE27" smd circle
			(at 1.89992 18.999962)
			(size 0.4572 0.4572)
			(layers "F.Cu" "F.Mask" "F.Paste")
			(net "GND")
		)
		(pad "BE28" smd circle
			(at 2.84988 18.999962)
			(size 0.4572 0.4572)
			(layers "F.Cu" "F.Mask" "F.Paste")
			(net "GND")
		)
		(pad "BE29" smd circle
			(at 3.800094 18.999962)
			(size 0.4572 0.4572)
			(layers "F.Cu" "F.Mask" "F.Paste")
			(net "GND")
		)
		(pad "BE30" smd circle
			(at 4.750054 18.999962)
			(size 0.4572 0.4572)
			(layers "F.Cu" "F.Mask" "F.Paste")
			(net "GND")
		)
		(pad "BE31" smd circle
			(at 5.700014 18.999962)
			(size 0.4572 0.4572)
			(layers "F.Cu" "F.Mask" "F.Paste")
			(net "GND")
		)
		(pad "BE32" smd circle
			(at 6.649974 18.999962)
			(size 0.4572 0.4572)
			(layers "F.Cu" "F.Mask" "F.Paste")
			(net "GND")
		)
		(pad "BE33" smd circle
			(at 7.599934 18.999962)
			(size 0.4572 0.4572)
			(layers "F.Cu" "F.Mask" "F.Paste")
			(net "GND")
		)
		(pad "BE34" smd circle
			(at 8.549894 18.999962)
			(size 0.4572 0.4572)
			(layers "F.Cu" "F.Mask" "F.Paste")
			(net "GND")
		)
		(pad "BE35" smd circle
			(at 9.500108 18.999962)
			(size 0.4572 0.4572)
			(layers "F.Cu" "F.Mask" "F.Paste")
			(net "GND")
		)
		(pad "BE36" smd circle
			(at 10.450068 18.999962)
			(size 0.4572 0.4572)
			(layers "F.Cu" "F.Mask" "F.Paste")
			(net "GND")
		)
		(pad "BE37" smd circle
			(at 11.400028 18.999962)
			(size 0.4572 0.4572)
			(layers "F.Cu" "F.Mask" "F.Paste")
			(net "GND")
		)
		(pad "BE38" smd circle
			(at 12.349988 18.999962)
			(size 0.4572 0.4572)
			(layers "F.Cu" "F.Mask" "F.Paste")
			(net "GND")
		)
		(pad "BE39" smd circle
			(at 13.299948 18.999962)
			(size 0.4572 0.4572)
			(layers "F.Cu" "F.Mask" "F.Paste")
			(net "GND")
		)
		(pad "BE40" smd circle
			(at 14.249908 18.999962)
			(size 0.4572 0.4572)
			(layers "F.Cu" "F.Mask" "F.Paste")
			(net "GND")
		)
		(pad "BE41" smd circle
			(at 15.200122 18.999962)
			(size 0.4572 0.4572)
			(layers "F.Cu" "F.Mask" "F.Paste")
			(net "GND")
		)
		(pad "BE42" smd circle
			(at 16.150082 18.999962)
			(size 0.4572 0.4572)
			(layers "F.Cu" "F.Mask" "F.Paste")
			(net "GND")
		)
		(pad "BE43" smd circle
			(at 17.100042 18.999962)
			(size 0.4572 0.4572)
			(layers "F.Cu" "F.Mask" "F.Paste")
			(net "GND")
		)
		(pad "BE44" smd circle
			(at 18.050002 18.999962)
			(size 0.4572 0.4572)
			(layers "F.Cu" "F.Mask" "F.Paste")
			(net "GND")
		)
		(pad "BE45" smd circle
			(at 18.999962 18.999962)
			(size 0.4572 0.4572)
			(layers "F.Cu" "F.Mask" "F.Paste")
			(net "GND")
		)
		(pad "BE46" smd circle
			(at 19.949922 18.999962)
			(size 0.4572 0.4572)
			(layers "F.Cu" "F.Mask" "F.Paste")
			(net "GND")
		)
		(pad "BE47" smd circle
			(at 20.899882 18.999962)
			(size 0.4572 0.4572)
			(layers "F.Cu" "F.Mask" "F.Paste")
			(net "GND")
		)
		(pad "BE48" smd circle
			(at 21.850096 18.999962)
			(size 0.4572 0.4572)
			(layers "F.Cu" "F.Mask" "F.Paste")
			(net "P5E_PEX2_STN0_TX_DP<8>")
		)
		(pad "BE49" smd circle
			(at 22.800056 18.999962)
			(size 0.4572 0.4572)
			(layers "F.Cu" "F.Mask" "F.Paste")
			(net "P5E_PEX2_STN0_TX_DN<8>")
		)
		(pad "BF1" smd circle
			(at -22.800056 19.949922)
			(size 0.4572 0.4572)
			(layers "F.Cu" "F.Mask" "F.Paste")
			(net "GND")
		)
		(pad "BF2" smd circle
			(at -21.850096 19.949922)
			(size 0.4572 0.4572)
			(layers "F.Cu" "F.Mask" "F.Paste")
			(net "GND")
		)
		(pad "BF3" smd circle
			(at -20.899882 19.949922)
			(size 0.4572 0.4572)
			(layers "F.Cu" "F.Mask" "F.Paste")
			(net "GND")
		)
		(pad "BF4" smd circle
			(at -19.949922 19.949922)
			(size 0.4572 0.4572)
			(layers "F.Cu" "F.Mask" "F.Paste")
			(net "Net_1617")
		)
		(pad "BF5" smd circle
			(at -18.999962 19.949922)
			(size 0.4572 0.4572)
			(layers "F.Cu" "F.Mask" "F.Paste")
			(net "GND")
		)
		(pad "BF6" smd circle
			(at -18.050002 19.949922)
			(size 0.4572 0.4572)
			(layers "F.Cu" "F.Mask" "F.Paste")
			(net "Net_1552")
		)
		(pad "BF7" smd circle
			(at -17.100042 19.949922)
			(size 0.4572 0.4572)
			(layers "F.Cu" "F.Mask" "F.Paste")
			(net "GND")
		)
		(pad "BF8" smd circle
			(at -16.150082 19.949922)
			(size 0.4572 0.4572)
			(layers "F.Cu" "F.Mask" "F.Paste")
			(net "Net_1644")
		)
		(pad "BF9" smd circle
			(at -15.200122 19.949922)
			(size 0.4572 0.4572)
			(layers "F.Cu" "F.Mask" "F.Paste")
			(net "GND")
		)
		(pad "BF10" smd circle
			(at -14.249908 19.949922)
			(size 0.4572 0.4572)
			(layers "F.Cu" "F.Mask" "F.Paste")
			(net "P5E_PEX2_STN2_RX_DP<46>")
		)
		(pad "BF11" smd circle
			(at -13.299948 19.949922)
			(size 0.4572 0.4572)
			(layers "F.Cu" "F.Mask" "F.Paste")
			(net "GND")
		)
		(pad "BF12" smd circle
			(at -12.349988 19.949922)
			(size 0.4572 0.4572)
			(layers "F.Cu" "F.Mask" "F.Paste")
			(net "P5E_PEX2_STN2_RX_DP<44>")
		)
		(pad "BF13" smd circle
			(at -11.400028 19.949922)
			(size 0.4572 0.4572)
			(layers "F.Cu" "F.Mask" "F.Paste")
			(net "GND")
		)
		(pad "BF14" smd circle
			(at -10.450068 19.949922)
			(size 0.4572 0.4572)
			(layers "F.Cu" "F.Mask" "F.Paste")
			(net "P5E_PEX2_STN2_RX_DP<42>")
		)
		(pad "BF15" smd circle
			(at -9.500108 19.949922)
			(size 0.4572 0.4572)
			(layers "F.Cu" "F.Mask" "F.Paste")
			(net "GND")
		)
		(pad "BF16" smd circle
			(at -8.549894 19.949922)
			(size 0.4572 0.4572)
			(layers "F.Cu" "F.Mask" "F.Paste")
			(net "P5E_PEX2_STN2_RX_DP<40>")
		)
		(pad "BF17" smd circle
			(at -7.599934 19.949922)
			(size 0.4572 0.4572)
			(layers "F.Cu" "F.Mask" "F.Paste")
			(net "GND")
		)
		(pad "BF18" smd circle
			(at -6.649974 19.949922)
			(size 0.4572 0.4572)
			(layers "F.Cu" "F.Mask" "F.Paste")
			(net "P5E_PEX2_STN2_RX_DP<38>")
		)
		(pad "BF19" smd circle
			(at -5.700014 19.949922)
			(size 0.4572 0.4572)
			(layers "F.Cu" "F.Mask" "F.Paste")
			(net "GND")
		)
		(pad "BF20" smd circle
			(at -4.750054 19.949922)
			(size 0.4572 0.4572)
			(layers "F.Cu" "F.Mask" "F.Paste")
			(net "P5E_PEX2_STN2_RX_DP<36>")
		)
		(pad "BF21" smd circle
			(at -3.800094 19.949922)
			(size 0.4572 0.4572)
			(layers "F.Cu" "F.Mask" "F.Paste")
			(net "GND")
		)
		(pad "BF22" smd circle
			(at -2.84988 19.949922)
			(size 0.4572 0.4572)
			(layers "F.Cu" "F.Mask" "F.Paste")
			(net "P5E_PEX2_STN2_RX_DP<34>")
		)
		(pad "BF23" smd circle
			(at -1.89992 19.949922)
			(size 0.4572 0.4572)
			(layers "F.Cu" "F.Mask" "F.Paste")
			(net "GND")
		)
		(pad "BF24" smd circle
			(at -0.94996 19.949922)
			(size 0.4572 0.4572)
			(layers "F.Cu" "F.Mask" "F.Paste")
			(net "P5E_PEX2_STN2_RX_DP<32>")
		)
		(pad "BF25" smd circle
			(at 0 19.949922)
			(size 0.4572 0.4572)
			(layers "F.Cu" "F.Mask" "F.Paste")
			(net "GND")
		)
		(pad "BF26" smd circle
			(at 0.94996 19.949922)
			(size 0.4572 0.4572)
			(layers "F.Cu" "F.Mask" "F.Paste")
			(net "P5E_PEX2_STN1_RX_DP<17>")
		)
		(pad "BF27" smd circle
			(at 1.89992 19.949922)
			(size 0.4572 0.4572)
			(layers "F.Cu" "F.Mask" "F.Paste")
			(net "GND")
		)
		(pad "BF28" smd circle
			(at 2.84988 19.949922)
			(size 0.4572 0.4572)
			(layers "F.Cu" "F.Mask" "F.Paste")
			(net "P5E_PEX2_STN1_RX_DP<19>")
		)
		(pad "BF29" smd circle
			(at 3.800094 19.949922)
			(size 0.4572 0.4572)
			(layers "F.Cu" "F.Mask" "F.Paste")
			(net "GND")
		)
		(pad "BF30" smd circle
			(at 4.750054 19.949922)
			(size 0.4572 0.4572)
			(layers "F.Cu" "F.Mask" "F.Paste")
			(net "P5E_PEX2_STN1_RX_DP<21>")
		)
		(pad "BF31" smd circle
			(at 5.700014 19.949922)
			(size 0.4572 0.4572)
			(layers "F.Cu" "F.Mask" "F.Paste")
			(net "GND")
		)
		(pad "BF32" smd circle
			(at 6.649974 19.949922)
			(size 0.4572 0.4572)
			(layers "F.Cu" "F.Mask" "F.Paste")
			(net "P5E_PEX2_STN1_RX_DP<23>")
		)
		(pad "BF33" smd circle
			(at 7.599934 19.949922)
			(size 0.4572 0.4572)
			(layers "F.Cu" "F.Mask" "F.Paste")
			(net "GND")
		)
		(pad "BF34" smd circle
			(at 8.549894 19.949922)
			(size 0.4572 0.4572)
			(layers "F.Cu" "F.Mask" "F.Paste")
			(net "P5E_PEX2_STN1_RX_DP<25>")
		)
		(pad "BF35" smd circle
			(at 9.500108 19.949922)
			(size 0.4572 0.4572)
			(layers "F.Cu" "F.Mask" "F.Paste")
			(net "GND")
		)
		(pad "BF36" smd circle
			(at 10.450068 19.949922)
			(size 0.4572 0.4572)
			(layers "F.Cu" "F.Mask" "F.Paste")
			(net "P5E_PEX2_STN1_RX_DP<27>")
		)
		(pad "BF37" smd circle
			(at 11.400028 19.949922)
			(size 0.4572 0.4572)
			(layers "F.Cu" "F.Mask" "F.Paste")
			(net "GND")
		)
		(pad "BF38" smd circle
			(at 12.349988 19.949922)
			(size 0.4572 0.4572)
			(layers "F.Cu" "F.Mask" "F.Paste")
			(net "P5E_PEX2_STN1_RX_DP<29>")
		)
		(pad "BF39" smd circle
			(at 13.299948 19.949922)
			(size 0.4572 0.4572)
			(layers "F.Cu" "F.Mask" "F.Paste")
			(net "GND")
		)
		(pad "BF40" smd circle
			(at 14.249908 19.949922)
			(size 0.4572 0.4572)
			(layers "F.Cu" "F.Mask" "F.Paste")
			(net "P5E_PEX2_STN1_RX_DP<31>")
		)
		(pad "BF41" smd circle
			(at 15.200122 19.949922)
			(size 0.4572 0.4572)
			(layers "F.Cu" "F.Mask" "F.Paste")
			(net "GND")
		)
		(pad "BF42" smd circle
			(at 16.150082 19.949922)
			(size 0.4572 0.4572)
			(layers "F.Cu" "F.Mask" "F.Paste")
			(net "P5E_PEX2_STN0_RX_DP<14>")
		)
		(pad "BF43" smd circle
			(at 17.100042 19.949922)
			(size 0.4572 0.4572)
			(layers "F.Cu" "F.Mask" "F.Paste")
			(net "GND")
		)
		(pad "BF44" smd circle
			(at 18.050002 19.949922)
			(size 0.4572 0.4572)
			(layers "F.Cu" "F.Mask" "F.Paste")
			(net "P5E_PEX2_STN0_RX_DP<12>")
		)
		(pad "BF45" smd circle
			(at 18.999962 19.949922)
			(size 0.4572 0.4572)
			(layers "F.Cu" "F.Mask" "F.Paste")
			(net "GND")
		)
		(pad "BF46" smd circle
			(at 19.949922 19.949922)
			(size 0.4572 0.4572)
			(layers "F.Cu" "F.Mask" "F.Paste")
			(net "P5E_PEX2_STN0_RX_DP<10>")
		)
		(pad "BF47" smd circle
			(at 20.899882 19.949922)
			(size 0.4572 0.4572)
			(layers "F.Cu" "F.Mask" "F.Paste")
			(net "GND")
		)
		(pad "BF48" smd circle
			(at 21.850096 19.949922)
			(size 0.4572 0.4572)
			(layers "F.Cu" "F.Mask" "F.Paste")
			(net "GND")
		)
		(pad "BF49" smd circle
			(at 22.800056 19.949922)
			(size 0.4572 0.4572)
			(layers "F.Cu" "F.Mask" "F.Paste")
			(net "GND")
		)
		(pad "BG1" smd circle
			(at -22.800056 20.899882)
			(size 0.4572 0.4572)
			(layers "F.Cu" "F.Mask" "F.Paste")
			(net "Net_1542")
		)
		(pad "BG2" smd circle
			(at -21.850096 20.899882)
			(size 0.4572 0.4572)
			(layers "F.Cu" "F.Mask" "F.Paste")
			(net "Net_1576")
		)
		(pad "BG3" smd circle
			(at -20.899882 20.899882)
			(size 0.4572 0.4572)
			(layers "F.Cu" "F.Mask" "F.Paste")
			(net "GND")
		)
		(pad "BG4" smd circle
			(at -19.949922 20.899882)
			(size 0.4572 0.4572)
			(layers "F.Cu" "F.Mask" "F.Paste")
			(net "Net_1559")
		)
		(pad "BG5" smd circle
			(at -18.999962 20.899882)
			(size 0.4572 0.4572)
			(layers "F.Cu" "F.Mask" "F.Paste")
			(net "GND")
		)
		(pad "BG6" smd circle
			(at -18.050002 20.899882)
			(size 0.4572 0.4572)
			(layers "F.Cu" "F.Mask" "F.Paste")
			(net "Net_1545")
		)
		(pad "BG7" smd circle
			(at -17.100042 20.899882)
			(size 0.4572 0.4572)
			(layers "F.Cu" "F.Mask" "F.Paste")
			(net "GND")
		)
		(pad "BG8" smd circle
			(at -16.150082 20.899882)
			(size 0.4572 0.4572)
			(layers "F.Cu" "F.Mask" "F.Paste")
			(net "Net_1528")
		)
		(pad "BG9" smd circle
			(at -15.200122 20.899882)
			(size 0.4572 0.4572)
			(layers "F.Cu" "F.Mask" "F.Paste")
			(net "GND")
		)
		(pad "BG10" smd circle
			(at -14.249908 20.899882)
			(size 0.4572 0.4572)
			(layers "F.Cu" "F.Mask" "F.Paste")
			(net "P5E_PEX2_STN2_RX_DN<46>")
		)
		(pad "BG11" smd circle
			(at -13.299948 20.899882)
			(size 0.4572 0.4572)
			(layers "F.Cu" "F.Mask" "F.Paste")
			(net "GND")
		)
		(pad "BG12" smd circle
			(at -12.349988 20.899882)
			(size 0.4572 0.4572)
			(layers "F.Cu" "F.Mask" "F.Paste")
			(net "P5E_PEX2_STN2_RX_DN<44>")
		)
		(pad "BG13" smd circle
			(at -11.400028 20.899882)
			(size 0.4572 0.4572)
			(layers "F.Cu" "F.Mask" "F.Paste")
			(net "GND")
		)
		(pad "BG14" smd circle
			(at -10.450068 20.899882)
			(size 0.4572 0.4572)
			(layers "F.Cu" "F.Mask" "F.Paste")
			(net "P5E_PEX2_STN2_RX_DN<42>")
		)
		(pad "BG15" smd circle
			(at -9.500108 20.899882)
			(size 0.4572 0.4572)
			(layers "F.Cu" "F.Mask" "F.Paste")
			(net "GND")
		)
		(pad "BG16" smd circle
			(at -8.549894 20.899882)
			(size 0.4572 0.4572)
			(layers "F.Cu" "F.Mask" "F.Paste")
			(net "P5E_PEX2_STN2_RX_DN<40>")
		)
		(pad "BG17" smd circle
			(at -7.599934 20.899882)
			(size 0.4572 0.4572)
			(layers "F.Cu" "F.Mask" "F.Paste")
			(net "GND")
		)
		(pad "BG18" smd circle
			(at -6.649974 20.899882)
			(size 0.4572 0.4572)
			(layers "F.Cu" "F.Mask" "F.Paste")
			(net "P5E_PEX2_STN2_RX_DN<38>")
		)
		(pad "BG19" smd circle
			(at -5.700014 20.899882)
			(size 0.4572 0.4572)
			(layers "F.Cu" "F.Mask" "F.Paste")
			(net "GND")
		)
		(pad "BG20" smd circle
			(at -4.750054 20.899882)
			(size 0.4572 0.4572)
			(layers "F.Cu" "F.Mask" "F.Paste")
			(net "P5E_PEX2_STN2_RX_DN<36>")
		)
		(pad "BG21" smd circle
			(at -3.800094 20.899882)
			(size 0.4572 0.4572)
			(layers "F.Cu" "F.Mask" "F.Paste")
			(net "GND")
		)
		(pad "BG22" smd circle
			(at -2.84988 20.899882)
			(size 0.4572 0.4572)
			(layers "F.Cu" "F.Mask" "F.Paste")
			(net "P5E_PEX2_STN2_RX_DN<34>")
		)
		(pad "BG23" smd circle
			(at -1.89992 20.899882)
			(size 0.4572 0.4572)
			(layers "F.Cu" "F.Mask" "F.Paste")
			(net "GND")
		)
		(pad "BG24" smd circle
			(at -0.94996 20.899882)
			(size 0.4572 0.4572)
			(layers "F.Cu" "F.Mask" "F.Paste")
			(net "P5E_PEX2_STN2_RX_DN<32>")
		)
		(pad "BG25" smd circle
			(at 0 20.899882)
			(size 0.4572 0.4572)
			(layers "F.Cu" "F.Mask" "F.Paste")
			(net "GND")
		)
		(pad "BG26" smd circle
			(at 0.94996 20.899882)
			(size 0.4572 0.4572)
			(layers "F.Cu" "F.Mask" "F.Paste")
			(net "P5E_PEX2_STN1_RX_DN<17>")
		)
		(pad "BG27" smd circle
			(at 1.89992 20.899882)
			(size 0.4572 0.4572)
			(layers "F.Cu" "F.Mask" "F.Paste")
			(net "GND")
		)
		(pad "BG28" smd circle
			(at 2.84988 20.899882)
			(size 0.4572 0.4572)
			(layers "F.Cu" "F.Mask" "F.Paste")
			(net "P5E_PEX2_STN1_RX_DN<19>")
		)
		(pad "BG29" smd circle
			(at 3.800094 20.899882)
			(size 0.4572 0.4572)
			(layers "F.Cu" "F.Mask" "F.Paste")
			(net "GND")
		)
		(pad "BG30" smd circle
			(at 4.750054 20.899882)
			(size 0.4572 0.4572)
			(layers "F.Cu" "F.Mask" "F.Paste")
			(net "P5E_PEX2_STN1_RX_DN<21>")
		)
		(pad "BG31" smd circle
			(at 5.700014 20.899882)
			(size 0.4572 0.4572)
			(layers "F.Cu" "F.Mask" "F.Paste")
			(net "GND")
		)
		(pad "BG32" smd circle
			(at 6.649974 20.899882)
			(size 0.4572 0.4572)
			(layers "F.Cu" "F.Mask" "F.Paste")
			(net "P5E_PEX2_STN1_RX_DN<23>")
		)
		(pad "BG33" smd circle
			(at 7.599934 20.899882)
			(size 0.4572 0.4572)
			(layers "F.Cu" "F.Mask" "F.Paste")
			(net "GND")
		)
		(pad "BG34" smd circle
			(at 8.549894 20.899882)
			(size 0.4572 0.4572)
			(layers "F.Cu" "F.Mask" "F.Paste")
			(net "P5E_PEX2_STN1_RX_DN<25>")
		)
		(pad "BG35" smd circle
			(at 9.500108 20.899882)
			(size 0.4572 0.4572)
			(layers "F.Cu" "F.Mask" "F.Paste")
			(net "GND")
		)
		(pad "BG36" smd circle
			(at 10.450068 20.899882)
			(size 0.4572 0.4572)
			(layers "F.Cu" "F.Mask" "F.Paste")
			(net "P5E_PEX2_STN1_RX_DN<27>")
		)
		(pad "BG37" smd circle
			(at 11.400028 20.899882)
			(size 0.4572 0.4572)
			(layers "F.Cu" "F.Mask" "F.Paste")
			(net "GND")
		)
		(pad "BG38" smd circle
			(at 12.349988 20.899882)
			(size 0.4572 0.4572)
			(layers "F.Cu" "F.Mask" "F.Paste")
			(net "P5E_PEX2_STN1_RX_DN<29>")
		)
		(pad "BG39" smd circle
			(at 13.299948 20.899882)
			(size 0.4572 0.4572)
			(layers "F.Cu" "F.Mask" "F.Paste")
			(net "GND")
		)
		(pad "BG40" smd circle
			(at 14.249908 20.899882)
			(size 0.4572 0.4572)
			(layers "F.Cu" "F.Mask" "F.Paste")
			(net "P5E_PEX2_STN1_RX_DN<31>")
		)
		(pad "BG41" smd circle
			(at 15.200122 20.899882)
			(size 0.4572 0.4572)
			(layers "F.Cu" "F.Mask" "F.Paste")
			(net "GND")
		)
		(pad "BG42" smd circle
			(at 16.150082 20.899882)
			(size 0.4572 0.4572)
			(layers "F.Cu" "F.Mask" "F.Paste")
			(net "P5E_PEX2_STN0_RX_DN<14>")
		)
		(pad "BG43" smd circle
			(at 17.100042 20.899882)
			(size 0.4572 0.4572)
			(layers "F.Cu" "F.Mask" "F.Paste")
			(net "GND")
		)
		(pad "BG44" smd circle
			(at 18.050002 20.899882)
			(size 0.4572 0.4572)
			(layers "F.Cu" "F.Mask" "F.Paste")
			(net "P5E_PEX2_STN0_RX_DN<12>")
		)
		(pad "BG45" smd circle
			(at 18.999962 20.899882)
			(size 0.4572 0.4572)
			(layers "F.Cu" "F.Mask" "F.Paste")
			(net "GND")
		)
		(pad "BG46" smd circle
			(at 19.949922 20.899882)
			(size 0.4572 0.4572)
			(layers "F.Cu" "F.Mask" "F.Paste")
			(net "P5E_PEX2_STN0_RX_DN<10>")
		)
		(pad "BG47" smd circle
			(at 20.899882 20.899882)
			(size 0.4572 0.4572)
			(layers "F.Cu" "F.Mask" "F.Paste")
			(net "GND")
		)
		(pad "BG48" smd circle
			(at 21.850096 20.899882)
			(size 0.4572 0.4572)
			(layers "F.Cu" "F.Mask" "F.Paste")
			(net "P5E_PEX2_STN0_RX_DP<8>")
		)
		(pad "BG49" smd circle
			(at 22.800056 20.899882)
			(size 0.4572 0.4572)
			(layers "F.Cu" "F.Mask" "F.Paste")
			(net "P5E_PEX2_STN0_RX_DN<8>")
		)
		(pad "BH1" smd circle
			(at -22.800056 21.850096)
			(size 0.4572 0.4572)
			(layers "F.Cu" "F.Mask" "F.Paste")
			(net "GND")
		)
		(pad "BH2" smd circle
			(at -21.850096 21.850096)
			(size 0.4572 0.4572)
			(layers "F.Cu" "F.Mask" "F.Paste")
			(net "GND")
		)
		(pad "BH3" smd circle
			(at -20.899882 21.850096)
			(size 0.4572 0.4572)
			(layers "F.Cu" "F.Mask" "F.Paste")
			(net "Net_1608")
		)
		(pad "BH4" smd circle
			(at -19.949922 21.850096)
			(size 0.4572 0.4572)
			(layers "F.Cu" "F.Mask" "F.Paste")
			(net "GND")
		)
		(pad "BH5" smd circle
			(at -18.999962 21.850096)
			(size 0.4572 0.4572)
			(layers "F.Cu" "F.Mask" "F.Paste")
			(net "Net_1637")
		)
		(pad "BH6" smd circle
			(at -18.050002 21.850096)
			(size 0.4572 0.4572)
			(layers "F.Cu" "F.Mask" "F.Paste")
			(net "GND")
		)
		(pad "BH7" smd circle
			(at -17.100042 21.850096)
			(size 0.4572 0.4572)
			(layers "F.Cu" "F.Mask" "F.Paste")
			(net "Net_1611")
		)
		(pad "BH8" smd circle
			(at -16.150082 21.850096)
			(size 0.4572 0.4572)
			(layers "F.Cu" "F.Mask" "F.Paste")
			(net "GND")
		)
		(pad "BH9" smd circle
			(at -15.200122 21.850096)
			(size 0.4572 0.4572)
			(layers "F.Cu" "F.Mask" "F.Paste")
			(net "P5E_PEX2_STN2_RX_DP<47>")
		)
		(pad "BH10" smd circle
			(at -14.249908 21.850096)
			(size 0.4572 0.4572)
			(layers "F.Cu" "F.Mask" "F.Paste")
			(net "GND")
		)
		(pad "BH11" smd circle
			(at -13.299948 21.850096)
			(size 0.4572 0.4572)
			(layers "F.Cu" "F.Mask" "F.Paste")
			(net "P5E_PEX2_STN2_RX_DP<45>")
		)
		(pad "BH12" smd circle
			(at -12.349988 21.850096)
			(size 0.4572 0.4572)
			(layers "F.Cu" "F.Mask" "F.Paste")
			(net "GND")
		)
		(pad "BH13" smd circle
			(at -11.400028 21.850096)
			(size 0.4572 0.4572)
			(layers "F.Cu" "F.Mask" "F.Paste")
			(net "P5E_PEX2_STN2_RX_DP<43>")
		)
		(pad "BH14" smd circle
			(at -10.450068 21.850096)
			(size 0.4572 0.4572)
			(layers "F.Cu" "F.Mask" "F.Paste")
			(net "GND")
		)
		(pad "BH15" smd circle
			(at -9.500108 21.850096)
			(size 0.4572 0.4572)
			(layers "F.Cu" "F.Mask" "F.Paste")
			(net "P5E_PEX2_STN2_RX_DP<41>")
		)
		(pad "BH16" smd circle
			(at -8.549894 21.850096)
			(size 0.4572 0.4572)
			(layers "F.Cu" "F.Mask" "F.Paste")
			(net "GND")
		)
		(pad "BH17" smd circle
			(at -7.599934 21.850096)
			(size 0.4572 0.4572)
			(layers "F.Cu" "F.Mask" "F.Paste")
			(net "P5E_PEX2_STN2_RX_DP<39>")
		)
		(pad "BH18" smd circle
			(at -6.649974 21.850096)
			(size 0.4572 0.4572)
			(layers "F.Cu" "F.Mask" "F.Paste")
			(net "GND")
		)
		(pad "BH19" smd circle
			(at -5.700014 21.850096)
			(size 0.4572 0.4572)
			(layers "F.Cu" "F.Mask" "F.Paste")
			(net "P5E_PEX2_STN2_RX_DP<37>")
		)
		(pad "BH20" smd circle
			(at -4.750054 21.850096)
			(size 0.4572 0.4572)
			(layers "F.Cu" "F.Mask" "F.Paste")
			(net "GND")
		)
		(pad "BH21" smd circle
			(at -3.800094 21.850096)
			(size 0.4572 0.4572)
			(layers "F.Cu" "F.Mask" "F.Paste")
			(net "P5E_PEX2_STN2_RX_DP<35>")
		)
		(pad "BH22" smd circle
			(at -2.84988 21.850096)
			(size 0.4572 0.4572)
			(layers "F.Cu" "F.Mask" "F.Paste")
			(net "GND")
		)
		(pad "BH23" smd circle
			(at -1.89992 21.850096)
			(size 0.4572 0.4572)
			(layers "F.Cu" "F.Mask" "F.Paste")
			(net "P5E_PEX2_STN2_RX_DP<33>")
		)
		(pad "BH24" smd circle
			(at -0.94996 21.850096)
			(size 0.4572 0.4572)
			(layers "F.Cu" "F.Mask" "F.Paste")
			(net "GND")
		)
		(pad "BH25" smd circle
			(at 0 21.850096)
			(size 0.4572 0.4572)
			(layers "F.Cu" "F.Mask" "F.Paste")
			(net "P5E_PEX2_STN1_RX_DP<16>")
		)
		(pad "BH26" smd circle
			(at 0.94996 21.850096)
			(size 0.4572 0.4572)
			(layers "F.Cu" "F.Mask" "F.Paste")
			(net "GND")
		)
		(pad "BH27" smd circle
			(at 1.89992 21.850096)
			(size 0.4572 0.4572)
			(layers "F.Cu" "F.Mask" "F.Paste")
			(net "P5E_PEX2_STN1_RX_DP<18>")
		)
		(pad "BH28" smd circle
			(at 2.84988 21.850096)
			(size 0.4572 0.4572)
			(layers "F.Cu" "F.Mask" "F.Paste")
			(net "GND")
		)
		(pad "BH29" smd circle
			(at 3.800094 21.850096)
			(size 0.4572 0.4572)
			(layers "F.Cu" "F.Mask" "F.Paste")
			(net "P5E_PEX2_STN1_RX_DP<20>")
		)
		(pad "BH30" smd circle
			(at 4.750054 21.850096)
			(size 0.4572 0.4572)
			(layers "F.Cu" "F.Mask" "F.Paste")
			(net "GND")
		)
		(pad "BH31" smd circle
			(at 5.700014 21.850096)
			(size 0.4572 0.4572)
			(layers "F.Cu" "F.Mask" "F.Paste")
			(net "P5E_PEX2_STN1_RX_DP<22>")
		)
		(pad "BH32" smd circle
			(at 6.649974 21.850096)
			(size 0.4572 0.4572)
			(layers "F.Cu" "F.Mask" "F.Paste")
			(net "GND")
		)
		(pad "BH33" smd circle
			(at 7.599934 21.850096)
			(size 0.4572 0.4572)
			(layers "F.Cu" "F.Mask" "F.Paste")
			(net "P5E_PEX2_STN1_RX_DP<24>")
		)
		(pad "BH34" smd circle
			(at 8.549894 21.850096)
			(size 0.4572 0.4572)
			(layers "F.Cu" "F.Mask" "F.Paste")
			(net "GND")
		)
		(pad "BH35" smd circle
			(at 9.500108 21.850096)
			(size 0.4572 0.4572)
			(layers "F.Cu" "F.Mask" "F.Paste")
			(net "P5E_PEX2_STN1_RX_DP<26>")
		)
		(pad "BH36" smd circle
			(at 10.450068 21.850096)
			(size 0.4572 0.4572)
			(layers "F.Cu" "F.Mask" "F.Paste")
			(net "GND")
		)
		(pad "BH37" smd circle
			(at 11.400028 21.850096)
			(size 0.4572 0.4572)
			(layers "F.Cu" "F.Mask" "F.Paste")
			(net "P5E_PEX2_STN1_RX_DP<28>")
		)
		(pad "BH38" smd circle
			(at 12.349988 21.850096)
			(size 0.4572 0.4572)
			(layers "F.Cu" "F.Mask" "F.Paste")
			(net "GND")
		)
		(pad "BH39" smd circle
			(at 13.299948 21.850096)
			(size 0.4572 0.4572)
			(layers "F.Cu" "F.Mask" "F.Paste")
			(net "P5E_PEX2_STN1_RX_DP<30>")
		)
		(pad "BH40" smd circle
			(at 14.249908 21.850096)
			(size 0.4572 0.4572)
			(layers "F.Cu" "F.Mask" "F.Paste")
			(net "GND")
		)
		(pad "BH41" smd circle
			(at 15.200122 21.850096)
			(size 0.4572 0.4572)
			(layers "F.Cu" "F.Mask" "F.Paste")
			(net "P5E_PEX2_STN0_RX_DP<15>")
		)
		(pad "BH42" smd circle
			(at 16.150082 21.850096)
			(size 0.4572 0.4572)
			(layers "F.Cu" "F.Mask" "F.Paste")
			(net "GND")
		)
		(pad "BH43" smd circle
			(at 17.100042 21.850096)
			(size 0.4572 0.4572)
			(layers "F.Cu" "F.Mask" "F.Paste")
			(net "P5E_PEX2_STN0_RX_DP<13>")
		)
		(pad "BH44" smd circle
			(at 18.050002 21.850096)
			(size 0.4572 0.4572)
			(layers "F.Cu" "F.Mask" "F.Paste")
			(net "GND")
		)
		(pad "BH45" smd circle
			(at 18.999962 21.850096)
			(size 0.4572 0.4572)
			(layers "F.Cu" "F.Mask" "F.Paste")
			(net "P5E_PEX2_STN0_RX_DP<11>")
		)
		(pad "BH46" smd circle
			(at 19.949922 21.850096)
			(size 0.4572 0.4572)
			(layers "F.Cu" "F.Mask" "F.Paste")
			(net "GND")
		)
		(pad "BH47" smd circle
			(at 20.899882 21.850096)
			(size 0.4572 0.4572)
			(layers "F.Cu" "F.Mask" "F.Paste")
			(net "P5E_PEX2_STN0_RX_DP<9>")
		)
		(pad "BH48" smd circle
			(at 21.850096 21.850096)
			(size 0.4572 0.4572)
			(layers "F.Cu" "F.Mask" "F.Paste")
			(net "GND")
		)
		(pad "BH49" smd circle
			(at 22.800056 21.850096)
			(size 0.4572 0.4572)
			(layers "F.Cu" "F.Mask" "F.Paste")
			(net "GND")
		)
		(pad "BJ2" smd circle
			(at -21.850096 22.800056)
			(size 0.4572 0.4572)
			(layers "F.Cu" "F.Mask" "F.Paste")
			(net "GND")
		)
		(pad "BJ3" smd circle
			(at -20.899882 22.800056)
			(size 0.4572 0.4572)
			(layers "F.Cu" "F.Mask" "F.Paste")
			(net "Net_1536")
		)
		(pad "BJ4" smd circle
			(at -19.949922 22.800056)
			(size 0.4572 0.4572)
			(layers "F.Cu" "F.Mask" "F.Paste")
			(net "GND")
		)
		(pad "BJ5" smd circle
			(at -18.999962 22.800056)
			(size 0.4572 0.4572)
			(layers "F.Cu" "F.Mask" "F.Paste")
			(net "Net_1539")
		)
		(pad "BJ6" smd circle
			(at -18.050002 22.800056)
			(size 0.4572 0.4572)
			(layers "F.Cu" "F.Mask" "F.Paste")
			(net "GND")
		)
		(pad "BJ7" smd circle
			(at -17.100042 22.800056)
			(size 0.4572 0.4572)
			(layers "F.Cu" "F.Mask" "F.Paste")
			(net "Net_1534")
		)
		(pad "BJ8" smd circle
			(at -16.150082 22.800056)
			(size 0.4572 0.4572)
			(layers "F.Cu" "F.Mask" "F.Paste")
			(net "GND")
		)
		(pad "BJ9" smd circle
			(at -15.200122 22.800056)
			(size 0.4572 0.4572)
			(layers "F.Cu" "F.Mask" "F.Paste")
			(net "P5E_PEX2_STN2_RX_DN<47>")
		)
		(pad "BJ10" smd circle
			(at -14.249908 22.800056)
			(size 0.4572 0.4572)
			(layers "F.Cu" "F.Mask" "F.Paste")
			(net "GND")
		)
		(pad "BJ11" smd circle
			(at -13.299948 22.800056)
			(size 0.4572 0.4572)
			(layers "F.Cu" "F.Mask" "F.Paste")
			(net "P5E_PEX2_STN2_RX_DN<45>")
		)
		(pad "BJ12" smd circle
			(at -12.349988 22.800056)
			(size 0.4572 0.4572)
			(layers "F.Cu" "F.Mask" "F.Paste")
			(net "GND")
		)
		(pad "BJ13" smd circle
			(at -11.400028 22.800056)
			(size 0.4572 0.4572)
			(layers "F.Cu" "F.Mask" "F.Paste")
			(net "P5E_PEX2_STN2_RX_DN<43>")
		)
		(pad "BJ14" smd circle
			(at -10.450068 22.800056)
			(size 0.4572 0.4572)
			(layers "F.Cu" "F.Mask" "F.Paste")
			(net "GND")
		)
		(pad "BJ15" smd circle
			(at -9.500108 22.800056)
			(size 0.4572 0.4572)
			(layers "F.Cu" "F.Mask" "F.Paste")
			(net "P5E_PEX2_STN2_RX_DN<41>")
		)
		(pad "BJ16" smd circle
			(at -8.549894 22.800056)
			(size 0.4572 0.4572)
			(layers "F.Cu" "F.Mask" "F.Paste")
			(net "GND")
		)
		(pad "BJ17" smd circle
			(at -7.599934 22.800056)
			(size 0.4572 0.4572)
			(layers "F.Cu" "F.Mask" "F.Paste")
			(net "P5E_PEX2_STN2_RX_DN<39>")
		)
		(pad "BJ18" smd circle
			(at -6.649974 22.800056)
			(size 0.4572 0.4572)
			(layers "F.Cu" "F.Mask" "F.Paste")
			(net "GND")
		)
		(pad "BJ19" smd circle
			(at -5.700014 22.800056)
			(size 0.4572 0.4572)
			(layers "F.Cu" "F.Mask" "F.Paste")
			(net "P5E_PEX2_STN2_RX_DN<37>")
		)
		(pad "BJ20" smd circle
			(at -4.750054 22.800056)
			(size 0.4572 0.4572)
			(layers "F.Cu" "F.Mask" "F.Paste")
			(net "GND")
		)
		(pad "BJ21" smd circle
			(at -3.800094 22.800056)
			(size 0.4572 0.4572)
			(layers "F.Cu" "F.Mask" "F.Paste")
			(net "P5E_PEX2_STN2_RX_DN<35>")
		)
		(pad "BJ22" smd circle
			(at -2.84988 22.800056)
			(size 0.4572 0.4572)
			(layers "F.Cu" "F.Mask" "F.Paste")
			(net "GND")
		)
		(pad "BJ23" smd circle
			(at -1.89992 22.800056)
			(size 0.4572 0.4572)
			(layers "F.Cu" "F.Mask" "F.Paste")
			(net "P5E_PEX2_STN2_RX_DN<33>")
		)
		(pad "BJ24" smd circle
			(at -0.94996 22.800056)
			(size 0.4572 0.4572)
			(layers "F.Cu" "F.Mask" "F.Paste")
			(net "GND")
		)
		(pad "BJ25" smd circle
			(at 0 22.800056)
			(size 0.4572 0.4572)
			(layers "F.Cu" "F.Mask" "F.Paste")
			(net "P5E_PEX2_STN1_RX_DN<16>")
		)
		(pad "BJ26" smd circle
			(at 0.94996 22.800056)
			(size 0.4572 0.4572)
			(layers "F.Cu" "F.Mask" "F.Paste")
			(net "GND")
		)
		(pad "BJ27" smd circle
			(at 1.89992 22.800056)
			(size 0.4572 0.4572)
			(layers "F.Cu" "F.Mask" "F.Paste")
			(net "P5E_PEX2_STN1_RX_DN<18>")
		)
		(pad "BJ28" smd circle
			(at 2.84988 22.800056)
			(size 0.4572 0.4572)
			(layers "F.Cu" "F.Mask" "F.Paste")
			(net "GND")
		)
		(pad "BJ29" smd circle
			(at 3.800094 22.800056)
			(size 0.4572 0.4572)
			(layers "F.Cu" "F.Mask" "F.Paste")
			(net "P5E_PEX2_STN1_RX_DN<20>")
		)
		(pad "BJ30" smd circle
			(at 4.750054 22.800056)
			(size 0.4572 0.4572)
			(layers "F.Cu" "F.Mask" "F.Paste")
			(net "GND")
		)
		(pad "BJ31" smd circle
			(at 5.700014 22.800056)
			(size 0.4572 0.4572)
			(layers "F.Cu" "F.Mask" "F.Paste")
			(net "P5E_PEX2_STN1_RX_DN<22>")
		)
		(pad "BJ32" smd circle
			(at 6.649974 22.800056)
			(size 0.4572 0.4572)
			(layers "F.Cu" "F.Mask" "F.Paste")
			(net "GND")
		)
		(pad "BJ33" smd circle
			(at 7.599934 22.800056)
			(size 0.4572 0.4572)
			(layers "F.Cu" "F.Mask" "F.Paste")
			(net "P5E_PEX2_STN1_RX_DN<24>")
		)
		(pad "BJ34" smd circle
			(at 8.549894 22.800056)
			(size 0.4572 0.4572)
			(layers "F.Cu" "F.Mask" "F.Paste")
			(net "GND")
		)
		(pad "BJ35" smd circle
			(at 9.500108 22.800056)
			(size 0.4572 0.4572)
			(layers "F.Cu" "F.Mask" "F.Paste")
			(net "P5E_PEX2_STN1_RX_DN<26>")
		)
		(pad "BJ36" smd circle
			(at 10.450068 22.800056)
			(size 0.4572 0.4572)
			(layers "F.Cu" "F.Mask" "F.Paste")
			(net "GND")
		)
		(pad "BJ37" smd circle
			(at 11.400028 22.800056)
			(size 0.4572 0.4572)
			(layers "F.Cu" "F.Mask" "F.Paste")
			(net "P5E_PEX2_STN1_RX_DN<28>")
		)
		(pad "BJ38" smd circle
			(at 12.349988 22.800056)
			(size 0.4572 0.4572)
			(layers "F.Cu" "F.Mask" "F.Paste")
			(net "GND")
		)
		(pad "BJ39" smd circle
			(at 13.299948 22.800056)
			(size 0.4572 0.4572)
			(layers "F.Cu" "F.Mask" "F.Paste")
			(net "P5E_PEX2_STN1_RX_DN<30>")
		)
		(pad "BJ40" smd circle
			(at 14.249908 22.800056)
			(size 0.4572 0.4572)
			(layers "F.Cu" "F.Mask" "F.Paste")
			(net "GND")
		)
		(pad "BJ41" smd circle
			(at 15.200122 22.800056)
			(size 0.4572 0.4572)
			(layers "F.Cu" "F.Mask" "F.Paste")
			(net "P5E_PEX2_STN0_RX_DN<15>")
		)
		(pad "BJ42" smd circle
			(at 16.150082 22.800056)
			(size 0.4572 0.4572)
			(layers "F.Cu" "F.Mask" "F.Paste")
			(net "GND")
		)
		(pad "BJ43" smd circle
			(at 17.100042 22.800056)
			(size 0.4572 0.4572)
			(layers "F.Cu" "F.Mask" "F.Paste")
			(net "P5E_PEX2_STN0_RX_DN<13>")
		)
		(pad "BJ44" smd circle
			(at 18.050002 22.800056)
			(size 0.4572 0.4572)
			(layers "F.Cu" "F.Mask" "F.Paste")
			(net "GND")
		)
		(pad "BJ45" smd circle
			(at 18.999962 22.800056)
			(size 0.4572 0.4572)
			(layers "F.Cu" "F.Mask" "F.Paste")
			(net "P5E_PEX2_STN0_RX_DN<11>")
		)
		(pad "BJ46" smd circle
			(at 19.949922 22.800056)
			(size 0.4572 0.4572)
			(layers "F.Cu" "F.Mask" "F.Paste")
			(net "GND")
		)
		(pad "BJ47" smd circle
			(at 20.899882 22.800056)
			(size 0.4572 0.4572)
			(layers "F.Cu" "F.Mask" "F.Paste")
			(net "P5E_PEX2_STN0_RX_DN<9>")
		)
		(pad "BJ48" smd circle
			(at 21.850096 22.800056)
			(size 0.4572 0.4572)
			(layers "F.Cu" "F.Mask" "F.Paste")
			(net "GND")
		)
		(pad "C1" smd circle
			(at -22.800056 -20.899882)
			(size 0.4572 0.4572)
			(layers "F.Cu" "F.Mask" "F.Paste")
			(net "P5E_PEX2_STN7_RX_DN<122>")
		)
		(pad "C2" smd circle
			(at -21.850096 -20.899882)
			(size 0.4572 0.4572)
			(layers "F.Cu" "F.Mask" "F.Paste")
			(net "P5E_PEX2_STN7_RX_DP<122>")
		)
		(pad "C3" smd circle
			(at -20.899882 -20.899882)
			(size 0.4572 0.4572)
			(layers "F.Cu" "F.Mask" "F.Paste")
			(net "GND")
		)
		(pad "C4" smd circle
			(at -19.949922 -20.899882)
			(size 0.4572 0.4572)
			(layers "F.Cu" "F.Mask" "F.Paste")
			(net "P5E_PEX2_STN7_RX_DN<124>")
		)
		(pad "C5" smd circle
			(at -18.999962 -20.899882)
			(size 0.4572 0.4572)
			(layers "F.Cu" "F.Mask" "F.Paste")
			(net "GND")
		)
		(pad "C6" smd circle
			(at -18.050002 -20.899882)
			(size 0.4572 0.4572)
			(layers "F.Cu" "F.Mask" "F.Paste")
			(net "P5E_PEX2_STN7_RX_DN<126>")
		)
		(pad "C7" smd circle
			(at -17.100042 -20.899882)
			(size 0.4572 0.4572)
			(layers "F.Cu" "F.Mask" "F.Paste")
			(net "GND")
		)
		(pad "C8" smd circle
			(at -16.150082 -20.899882)
			(size 0.4572 0.4572)
			(layers "F.Cu" "F.Mask" "F.Paste")
			(net "P5E_PEX2_STN6_RX_DN<111>")
		)
		(pad "C9" smd circle
			(at -15.200122 -20.899882)
			(size 0.4572 0.4572)
			(layers "F.Cu" "F.Mask" "F.Paste")
			(net "GND")
		)
		(pad "C10" smd circle
			(at -14.249908 -20.899882)
			(size 0.4572 0.4572)
			(layers "F.Cu" "F.Mask" "F.Paste")
			(net "P5E_PEX2_STN6_RX_DN<109>")
		)
		(pad "C11" smd circle
			(at -13.299948 -20.899882)
			(size 0.4572 0.4572)
			(layers "F.Cu" "F.Mask" "F.Paste")
			(net "GND")
		)
		(pad "C12" smd circle
			(at -12.349988 -20.899882)
			(size 0.4572 0.4572)
			(layers "F.Cu" "F.Mask" "F.Paste")
			(net "P5E_PEX2_STN6_RX_DN<107>")
		)
		(pad "C13" smd circle
			(at -11.400028 -20.899882)
			(size 0.4572 0.4572)
			(layers "F.Cu" "F.Mask" "F.Paste")
			(net "GND")
		)
		(pad "C14" smd circle
			(at -10.450068 -20.899882)
			(size 0.4572 0.4572)
			(layers "F.Cu" "F.Mask" "F.Paste")
			(net "P5E_PEX2_STN6_RX_DN<105>")
		)
		(pad "C15" smd circle
			(at -9.500108 -20.899882)
			(size 0.4572 0.4572)
			(layers "F.Cu" "F.Mask" "F.Paste")
			(net "GND")
		)
		(pad "C16" smd circle
			(at -8.549894 -20.899882)
			(size 0.4572 0.4572)
			(layers "F.Cu" "F.Mask" "F.Paste")
			(net "P5E_PEX2_STN6_RX_DN<103>")
		)
		(pad "C17" smd circle
			(at -7.599934 -20.899882)
			(size 0.4572 0.4572)
			(layers "F.Cu" "F.Mask" "F.Paste")
			(net "GND")
		)
		(pad "C18" smd circle
			(at -6.649974 -20.899882)
			(size 0.4572 0.4572)
			(layers "F.Cu" "F.Mask" "F.Paste")
			(net "P5E_PEX2_STN6_RX_DN<101>")
		)
		(pad "C19" smd circle
			(at -5.700014 -20.899882)
			(size 0.4572 0.4572)
			(layers "F.Cu" "F.Mask" "F.Paste")
			(net "GND")
		)
		(pad "C20" smd circle
			(at -4.750054 -20.899882)
			(size 0.4572 0.4572)
			(layers "F.Cu" "F.Mask" "F.Paste")
			(net "P5E_PEX2_STN6_RX_DN<99>")
		)
		(pad "C21" smd circle
			(at -3.800094 -20.899882)
			(size 0.4572 0.4572)
			(layers "F.Cu" "F.Mask" "F.Paste")
			(net "GND")
		)
		(pad "C22" smd circle
			(at -2.84988 -20.899882)
			(size 0.4572 0.4572)
			(layers "F.Cu" "F.Mask" "F.Paste")
			(net "P5E_PEX2_STN6_RX_DN<97>")
		)
		(pad "C23" smd circle
			(at -1.89992 -20.899882)
			(size 0.4572 0.4572)
			(layers "F.Cu" "F.Mask" "F.Paste")
			(net "GND")
		)
		(pad "C24" smd circle
			(at -0.94996 -20.899882)
			(size 0.4572 0.4572)
			(layers "F.Cu" "F.Mask" "F.Paste")
			(net "P5E_PEX2_STN5_RX_DN<80>")
		)
		(pad "C25" smd circle
			(at 0 -20.899882)
			(size 0.4572 0.4572)
			(layers "F.Cu" "F.Mask" "F.Paste")
			(net "GND")
		)
		(pad "C26" smd circle
			(at 0.94996 -20.899882)
			(size 0.4572 0.4572)
			(layers "F.Cu" "F.Mask" "F.Paste")
			(net "P5E_PEX2_STN5_RX_DN<82>")
		)
		(pad "C27" smd circle
			(at 1.89992 -20.899882)
			(size 0.4572 0.4572)
			(layers "F.Cu" "F.Mask" "F.Paste")
			(net "GND")
		)
		(pad "C28" smd circle
			(at 2.84988 -20.899882)
			(size 0.4572 0.4572)
			(layers "F.Cu" "F.Mask" "F.Paste")
			(net "P5E_PEX2_STN5_RX_DN<84>")
		)
		(pad "C29" smd circle
			(at 3.800094 -20.899882)
			(size 0.4572 0.4572)
			(layers "F.Cu" "F.Mask" "F.Paste")
			(net "GND")
		)
		(pad "C30" smd circle
			(at 4.750054 -20.899882)
			(size 0.4572 0.4572)
			(layers "F.Cu" "F.Mask" "F.Paste")
			(net "P5E_PEX2_STN5_RX_DN<86>")
		)
		(pad "C31" smd circle
			(at 5.700014 -20.899882)
			(size 0.4572 0.4572)
			(layers "F.Cu" "F.Mask" "F.Paste")
			(net "GND")
		)
		(pad "C32" smd circle
			(at 6.649974 -20.899882)
			(size 0.4572 0.4572)
			(layers "F.Cu" "F.Mask" "F.Paste")
			(net "P5E_PEX2_STN5_RX_DN<88>")
		)
		(pad "C33" smd circle
			(at 7.599934 -20.899882)
			(size 0.4572 0.4572)
			(layers "F.Cu" "F.Mask" "F.Paste")
			(net "GND")
		)
		(pad "C34" smd circle
			(at 8.549894 -20.899882)
			(size 0.4572 0.4572)
			(layers "F.Cu" "F.Mask" "F.Paste")
			(net "P5E_PEX2_STN5_RX_DN<90>")
		)
		(pad "C35" smd circle
			(at 9.500108 -20.899882)
			(size 0.4572 0.4572)
			(layers "F.Cu" "F.Mask" "F.Paste")
			(net "GND")
		)
		(pad "C36" smd circle
			(at 10.450068 -20.899882)
			(size 0.4572 0.4572)
			(layers "F.Cu" "F.Mask" "F.Paste")
			(net "P5E_PEX2_STN5_RX_DN<92>")
		)
		(pad "C37" smd circle
			(at 11.400028 -20.899882)
			(size 0.4572 0.4572)
			(layers "F.Cu" "F.Mask" "F.Paste")
			(net "GND")
		)
		(pad "C38" smd circle
			(at 12.349988 -20.899882)
			(size 0.4572 0.4572)
			(layers "F.Cu" "F.Mask" "F.Paste")
			(net "P5E_PEX2_STN5_RX_DN<94>")
		)
		(pad "C39" smd circle
			(at 13.299948 -20.899882)
			(size 0.4572 0.4572)
			(layers "F.Cu" "F.Mask" "F.Paste")
			(net "GND")
		)
		(pad "C40" smd circle
			(at 14.249908 -20.899882)
			(size 0.4572 0.4572)
			(layers "F.Cu" "F.Mask" "F.Paste")
			(net "P5E_PEX2_STN4_RX_DN<79>")
		)
		(pad "C41" smd circle
			(at 15.200122 -20.899882)
			(size 0.4572 0.4572)
			(layers "F.Cu" "F.Mask" "F.Paste")
			(net "GND")
		)
		(pad "C42" smd circle
			(at 16.150082 -20.899882)
			(size 0.4572 0.4572)
			(layers "F.Cu" "F.Mask" "F.Paste")
			(net "P5E_PEX2_STN4_RX_DN<77>")
		)
		(pad "C43" smd circle
			(at 17.100042 -20.899882)
			(size 0.4572 0.4572)
			(layers "F.Cu" "F.Mask" "F.Paste")
			(net "GND")
		)
		(pad "C44" smd circle
			(at 18.050002 -20.899882)
			(size 0.4572 0.4572)
			(layers "F.Cu" "F.Mask" "F.Paste")
			(net "P5E_PEX2_STN4_RX_DN<75>")
		)
		(pad "C45" smd circle
			(at 18.999962 -20.899882)
			(size 0.4572 0.4572)
			(layers "F.Cu" "F.Mask" "F.Paste")
			(net "GND")
		)
		(pad "C46" smd circle
			(at 19.949922 -20.899882)
			(size 0.4572 0.4572)
			(layers "F.Cu" "F.Mask" "F.Paste")
			(net "P5E_PEX2_STN4_RX_DN<73>")
		)
		(pad "C47" smd circle
			(at 20.899882 -20.899882)
			(size 0.4572 0.4572)
			(layers "F.Cu" "F.Mask" "F.Paste")
			(net "GND")
		)
		(pad "C48" smd circle
			(at 21.850096 -20.899882)
			(size 0.4572 0.4572)
			(layers "F.Cu" "F.Mask" "F.Paste")
			(net "P5E_PEX2_STN4_RX_DP<71>")
		)
		(pad "C49" smd circle
			(at 22.800056 -20.899882)
			(size 0.4572 0.4572)
			(layers "F.Cu" "F.Mask" "F.Paste")
			(net "P5E_PEX2_STN4_RX_DN<71>")
		)
		(pad "D1" smd circle
			(at -22.800056 -19.949922)
			(size 0.4572 0.4572)
			(layers "F.Cu" "F.Mask" "F.Paste")
			(net "GND")
		)
		(pad "D2" smd circle
			(at -21.850096 -19.949922)
			(size 0.4572 0.4572)
			(layers "F.Cu" "F.Mask" "F.Paste")
			(net "GND")
		)
		(pad "D3" smd circle
			(at -20.899882 -19.949922)
			(size 0.4572 0.4572)
			(layers "F.Cu" "F.Mask" "F.Paste")
			(net "GND")
		)
		(pad "D4" smd circle
			(at -19.949922 -19.949922)
			(size 0.4572 0.4572)
			(layers "F.Cu" "F.Mask" "F.Paste")
			(net "P5E_PEX2_STN7_RX_DP<124>")
		)
		(pad "D5" smd circle
			(at -18.999962 -19.949922)
			(size 0.4572 0.4572)
			(layers "F.Cu" "F.Mask" "F.Paste")
			(net "GND")
		)
		(pad "D6" smd circle
			(at -18.050002 -19.949922)
			(size 0.4572 0.4572)
			(layers "F.Cu" "F.Mask" "F.Paste")
			(net "P5E_PEX2_STN7_RX_DP<126>")
		)
		(pad "D7" smd circle
			(at -17.100042 -19.949922)
			(size 0.4572 0.4572)
			(layers "F.Cu" "F.Mask" "F.Paste")
			(net "GND")
		)
		(pad "D8" smd circle
			(at -16.150082 -19.949922)
			(size 0.4572 0.4572)
			(layers "F.Cu" "F.Mask" "F.Paste")
			(net "P5E_PEX2_STN6_RX_DP<111>")
		)
		(pad "D9" smd circle
			(at -15.200122 -19.949922)
			(size 0.4572 0.4572)
			(layers "F.Cu" "F.Mask" "F.Paste")
			(net "GND")
		)
		(pad "D10" smd circle
			(at -14.249908 -19.949922)
			(size 0.4572 0.4572)
			(layers "F.Cu" "F.Mask" "F.Paste")
			(net "P5E_PEX2_STN6_RX_DP<109>")
		)
		(pad "D11" smd circle
			(at -13.299948 -19.949922)
			(size 0.4572 0.4572)
			(layers "F.Cu" "F.Mask" "F.Paste")
			(net "GND")
		)
		(pad "D12" smd circle
			(at -12.349988 -19.949922)
			(size 0.4572 0.4572)
			(layers "F.Cu" "F.Mask" "F.Paste")
			(net "P5E_PEX2_STN6_RX_DP<107>")
		)
		(pad "D13" smd circle
			(at -11.400028 -19.949922)
			(size 0.4572 0.4572)
			(layers "F.Cu" "F.Mask" "F.Paste")
			(net "GND")
		)
		(pad "D14" smd circle
			(at -10.450068 -19.949922)
			(size 0.4572 0.4572)
			(layers "F.Cu" "F.Mask" "F.Paste")
			(net "P5E_PEX2_STN6_RX_DP<105>")
		)
		(pad "D15" smd circle
			(at -9.500108 -19.949922)
			(size 0.4572 0.4572)
			(layers "F.Cu" "F.Mask" "F.Paste")
			(net "GND")
		)
		(pad "D16" smd circle
			(at -8.549894 -19.949922)
			(size 0.4572 0.4572)
			(layers "F.Cu" "F.Mask" "F.Paste")
			(net "P5E_PEX2_STN6_RX_DP<103>")
		)
		(pad "D17" smd circle
			(at -7.599934 -19.949922)
			(size 0.4572 0.4572)
			(layers "F.Cu" "F.Mask" "F.Paste")
			(net "GND")
		)
		(pad "D18" smd circle
			(at -6.649974 -19.949922)
			(size 0.4572 0.4572)
			(layers "F.Cu" "F.Mask" "F.Paste")
			(net "P5E_PEX2_STN6_RX_DP<101>")
		)
		(pad "D19" smd circle
			(at -5.700014 -19.949922)
			(size 0.4572 0.4572)
			(layers "F.Cu" "F.Mask" "F.Paste")
			(net "GND")
		)
		(pad "D20" smd circle
			(at -4.750054 -19.949922)
			(size 0.4572 0.4572)
			(layers "F.Cu" "F.Mask" "F.Paste")
			(net "P5E_PEX2_STN6_RX_DP<99>")
		)
		(pad "D21" smd circle
			(at -3.800094 -19.949922)
			(size 0.4572 0.4572)
			(layers "F.Cu" "F.Mask" "F.Paste")
			(net "GND")
		)
		(pad "D22" smd circle
			(at -2.84988 -19.949922)
			(size 0.4572 0.4572)
			(layers "F.Cu" "F.Mask" "F.Paste")
			(net "P5E_PEX2_STN6_RX_DP<97>")
		)
		(pad "D23" smd circle
			(at -1.89992 -19.949922)
			(size 0.4572 0.4572)
			(layers "F.Cu" "F.Mask" "F.Paste")
			(net "GND")
		)
		(pad "D24" smd circle
			(at -0.94996 -19.949922)
			(size 0.4572 0.4572)
			(layers "F.Cu" "F.Mask" "F.Paste")
			(net "P5E_PEX2_STN5_RX_DP<80>")
		)
		(pad "D25" smd circle
			(at 0 -19.949922)
			(size 0.4572 0.4572)
			(layers "F.Cu" "F.Mask" "F.Paste")
			(net "GND")
		)
		(pad "D26" smd circle
			(at 0.94996 -19.949922)
			(size 0.4572 0.4572)
			(layers "F.Cu" "F.Mask" "F.Paste")
			(net "P5E_PEX2_STN5_RX_DP<82>")
		)
		(pad "D27" smd circle
			(at 1.89992 -19.949922)
			(size 0.4572 0.4572)
			(layers "F.Cu" "F.Mask" "F.Paste")
			(net "GND")
		)
		(pad "D28" smd circle
			(at 2.84988 -19.949922)
			(size 0.4572 0.4572)
			(layers "F.Cu" "F.Mask" "F.Paste")
			(net "P5E_PEX2_STN5_RX_DP<84>")
		)
		(pad "D29" smd circle
			(at 3.800094 -19.949922)
			(size 0.4572 0.4572)
			(layers "F.Cu" "F.Mask" "F.Paste")
			(net "GND")
		)
		(pad "D30" smd circle
			(at 4.750054 -19.949922)
			(size 0.4572 0.4572)
			(layers "F.Cu" "F.Mask" "F.Paste")
			(net "P5E_PEX2_STN5_RX_DP<86>")
		)
		(pad "D31" smd circle
			(at 5.700014 -19.949922)
			(size 0.4572 0.4572)
			(layers "F.Cu" "F.Mask" "F.Paste")
			(net "GND")
		)
		(pad "D32" smd circle
			(at 6.649974 -19.949922)
			(size 0.4572 0.4572)
			(layers "F.Cu" "F.Mask" "F.Paste")
			(net "P5E_PEX2_STN5_RX_DP<88>")
		)
		(pad "D33" smd circle
			(at 7.599934 -19.949922)
			(size 0.4572 0.4572)
			(layers "F.Cu" "F.Mask" "F.Paste")
			(net "GND")
		)
		(pad "D34" smd circle
			(at 8.549894 -19.949922)
			(size 0.4572 0.4572)
			(layers "F.Cu" "F.Mask" "F.Paste")
			(net "P5E_PEX2_STN5_RX_DP<90>")
		)
		(pad "D35" smd circle
			(at 9.500108 -19.949922)
			(size 0.4572 0.4572)
			(layers "F.Cu" "F.Mask" "F.Paste")
			(net "GND")
		)
		(pad "D36" smd circle
			(at 10.450068 -19.949922)
			(size 0.4572 0.4572)
			(layers "F.Cu" "F.Mask" "F.Paste")
			(net "P5E_PEX2_STN5_RX_DP<92>")
		)
		(pad "D37" smd circle
			(at 11.400028 -19.949922)
			(size 0.4572 0.4572)
			(layers "F.Cu" "F.Mask" "F.Paste")
			(net "GND")
		)
		(pad "D38" smd circle
			(at 12.349988 -19.949922)
			(size 0.4572 0.4572)
			(layers "F.Cu" "F.Mask" "F.Paste")
			(net "P5E_PEX2_STN5_RX_DP<94>")
		)
		(pad "D39" smd circle
			(at 13.299948 -19.949922)
			(size 0.4572 0.4572)
			(layers "F.Cu" "F.Mask" "F.Paste")
			(net "GND")
		)
		(pad "D40" smd circle
			(at 14.249908 -19.949922)
			(size 0.4572 0.4572)
			(layers "F.Cu" "F.Mask" "F.Paste")
			(net "P5E_PEX2_STN4_RX_DP<79>")
		)
		(pad "D41" smd circle
			(at 15.200122 -19.949922)
			(size 0.4572 0.4572)
			(layers "F.Cu" "F.Mask" "F.Paste")
			(net "GND")
		)
		(pad "D42" smd circle
			(at 16.150082 -19.949922)
			(size 0.4572 0.4572)
			(layers "F.Cu" "F.Mask" "F.Paste")
			(net "P5E_PEX2_STN4_RX_DP<77>")
		)
		(pad "D43" smd circle
			(at 17.100042 -19.949922)
			(size 0.4572 0.4572)
			(layers "F.Cu" "F.Mask" "F.Paste")
			(net "GND")
		)
		(pad "D44" smd circle
			(at 18.050002 -19.949922)
			(size 0.4572 0.4572)
			(layers "F.Cu" "F.Mask" "F.Paste")
			(net "P5E_PEX2_STN4_RX_DP<75>")
		)
		(pad "D45" smd circle
			(at 18.999962 -19.949922)
			(size 0.4572 0.4572)
			(layers "F.Cu" "F.Mask" "F.Paste")
			(net "GND")
		)
		(pad "D46" smd circle
			(at 19.949922 -19.949922)
			(size 0.4572 0.4572)
			(layers "F.Cu" "F.Mask" "F.Paste")
			(net "P5E_PEX2_STN4_RX_DP<73>")
		)
		(pad "D47" smd circle
			(at 20.899882 -19.949922)
			(size 0.4572 0.4572)
			(layers "F.Cu" "F.Mask" "F.Paste")
			(net "GND")
		)
		(pad "D48" smd circle
			(at 21.850096 -19.949922)
			(size 0.4572 0.4572)
			(layers "F.Cu" "F.Mask" "F.Paste")
			(net "GND")
		)
		(pad "D49" smd circle
			(at 22.800056 -19.949922)
			(size 0.4572 0.4572)
			(layers "F.Cu" "F.Mask" "F.Paste")
			(net "GND")
		)
		(pad "E1" smd circle
			(at -22.800056 -18.999962)
			(size 0.4572 0.4572)
			(layers "F.Cu" "F.Mask" "F.Paste")
			(net "P5E_PEX2_STN7_TX_DN<122>")
		)
		(pad "E2" smd circle
			(at -21.850096 -18.999962)
			(size 0.4572 0.4572)
			(layers "F.Cu" "F.Mask" "F.Paste")
			(net "P5E_PEX2_STN7_TX_DP<122>")
		)
		(pad "E3" smd circle
			(at -20.899882 -18.999962)
			(size 0.4572 0.4572)
			(layers "F.Cu" "F.Mask" "F.Paste")
			(net "GND")
		)
		(pad "E4" smd circle
			(at -19.949922 -18.999962)
			(size 0.4572 0.4572)
			(layers "F.Cu" "F.Mask" "F.Paste")
			(net "GND")
		)
		(pad "E5" smd circle
			(at -18.999962 -18.999962)
			(size 0.4572 0.4572)
			(layers "F.Cu" "F.Mask" "F.Paste")
			(net "GND")
		)
		(pad "E6" smd circle
			(at -18.050002 -18.999962)
			(size 0.4572 0.4572)
			(layers "F.Cu" "F.Mask" "F.Paste")
			(net "GND")
		)
		(pad "E7" smd circle
			(at -17.100042 -18.999962)
			(size 0.4572 0.4572)
			(layers "F.Cu" "F.Mask" "F.Paste")
			(net "GND")
		)
		(pad "E8" smd circle
			(at -16.150082 -18.999962)
			(size 0.4572 0.4572)
			(layers "F.Cu" "F.Mask" "F.Paste")
			(net "GND")
		)
		(pad "E9" smd circle
			(at -15.200122 -18.999962)
			(size 0.4572 0.4572)
			(layers "F.Cu" "F.Mask" "F.Paste")
			(net "GND")
		)
		(pad "E10" smd circle
			(at -14.249908 -18.999962)
			(size 0.4572 0.4572)
			(layers "F.Cu" "F.Mask" "F.Paste")
			(net "GND")
		)
		(pad "E11" smd circle
			(at -13.299948 -18.999962)
			(size 0.4572 0.4572)
			(layers "F.Cu" "F.Mask" "F.Paste")
			(net "GND")
		)
		(pad "E12" smd circle
			(at -12.349988 -18.999962)
			(size 0.4572 0.4572)
			(layers "F.Cu" "F.Mask" "F.Paste")
			(net "GND")
		)
		(pad "E13" smd circle
			(at -11.400028 -18.999962)
			(size 0.4572 0.4572)
			(layers "F.Cu" "F.Mask" "F.Paste")
			(net "GND")
		)
		(pad "E14" smd circle
			(at -10.450068 -18.999962)
			(size 0.4572 0.4572)
			(layers "F.Cu" "F.Mask" "F.Paste")
			(net "GND")
		)
		(pad "E15" smd circle
			(at -9.500108 -18.999962)
			(size 0.4572 0.4572)
			(layers "F.Cu" "F.Mask" "F.Paste")
			(net "GND")
		)
		(pad "E16" smd circle
			(at -8.549894 -18.999962)
			(size 0.4572 0.4572)
			(layers "F.Cu" "F.Mask" "F.Paste")
			(net "GND")
		)
		(pad "E17" smd circle
			(at -7.599934 -18.999962)
			(size 0.4572 0.4572)
			(layers "F.Cu" "F.Mask" "F.Paste")
			(net "GND")
		)
		(pad "E18" smd circle
			(at -6.649974 -18.999962)
			(size 0.4572 0.4572)
			(layers "F.Cu" "F.Mask" "F.Paste")
			(net "GND")
		)
		(pad "E19" smd circle
			(at -5.700014 -18.999962)
			(size 0.4572 0.4572)
			(layers "F.Cu" "F.Mask" "F.Paste")
			(net "GND")
		)
		(pad "E20" smd circle
			(at -4.750054 -18.999962)
			(size 0.4572 0.4572)
			(layers "F.Cu" "F.Mask" "F.Paste")
			(net "GND")
		)
		(pad "E21" smd circle
			(at -3.800094 -18.999962)
			(size 0.4572 0.4572)
			(layers "F.Cu" "F.Mask" "F.Paste")
			(net "GND")
		)
		(pad "E22" smd circle
			(at -2.84988 -18.999962)
			(size 0.4572 0.4572)
			(layers "F.Cu" "F.Mask" "F.Paste")
			(net "GND")
		)
		(pad "E23" smd circle
			(at -1.89992 -18.999962)
			(size 0.4572 0.4572)
			(layers "F.Cu" "F.Mask" "F.Paste")
			(net "GND")
		)
		(pad "E24" smd circle
			(at -0.94996 -18.999962)
			(size 0.4572 0.4572)
			(layers "F.Cu" "F.Mask" "F.Paste")
			(net "GND")
		)
		(pad "E25" smd circle
			(at 0 -18.999962)
			(size 0.4572 0.4572)
			(layers "F.Cu" "F.Mask" "F.Paste")
			(net "GND")
		)
		(pad "E26" smd circle
			(at 0.94996 -18.999962)
			(size 0.4572 0.4572)
			(layers "F.Cu" "F.Mask" "F.Paste")
			(net "GND")
		)
		(pad "E27" smd circle
			(at 1.89992 -18.999962)
			(size 0.4572 0.4572)
			(layers "F.Cu" "F.Mask" "F.Paste")
			(net "GND")
		)
		(pad "E28" smd circle
			(at 2.84988 -18.999962)
			(size 0.4572 0.4572)
			(layers "F.Cu" "F.Mask" "F.Paste")
			(net "GND")
		)
		(pad "E29" smd circle
			(at 3.800094 -18.999962)
			(size 0.4572 0.4572)
			(layers "F.Cu" "F.Mask" "F.Paste")
			(net "GND")
		)
		(pad "E30" smd circle
			(at 4.750054 -18.999962)
			(size 0.4572 0.4572)
			(layers "F.Cu" "F.Mask" "F.Paste")
			(net "GND")
		)
		(pad "E31" smd circle
			(at 5.700014 -18.999962)
			(size 0.4572 0.4572)
			(layers "F.Cu" "F.Mask" "F.Paste")
			(net "GND")
		)
		(pad "E32" smd circle
			(at 6.649974 -18.999962)
			(size 0.4572 0.4572)
			(layers "F.Cu" "F.Mask" "F.Paste")
			(net "GND")
		)
		(pad "E33" smd circle
			(at 7.599934 -18.999962)
			(size 0.4572 0.4572)
			(layers "F.Cu" "F.Mask" "F.Paste")
			(net "GND")
		)
		(pad "E34" smd circle
			(at 8.549894 -18.999962)
			(size 0.4572 0.4572)
			(layers "F.Cu" "F.Mask" "F.Paste")
			(net "GND")
		)
		(pad "E35" smd circle
			(at 9.500108 -18.999962)
			(size 0.4572 0.4572)
			(layers "F.Cu" "F.Mask" "F.Paste")
			(net "GND")
		)
		(pad "E36" smd circle
			(at 10.450068 -18.999962)
			(size 0.4572 0.4572)
			(layers "F.Cu" "F.Mask" "F.Paste")
			(net "GND")
		)
		(pad "E37" smd circle
			(at 11.400028 -18.999962)
			(size 0.4572 0.4572)
			(layers "F.Cu" "F.Mask" "F.Paste")
			(net "GND")
		)
		(pad "E38" smd circle
			(at 12.349988 -18.999962)
			(size 0.4572 0.4572)
			(layers "F.Cu" "F.Mask" "F.Paste")
			(net "GND")
		)
		(pad "E39" smd circle
			(at 13.299948 -18.999962)
			(size 0.4572 0.4572)
			(layers "F.Cu" "F.Mask" "F.Paste")
			(net "GND")
		)
		(pad "E40" smd circle
			(at 14.249908 -18.999962)
			(size 0.4572 0.4572)
			(layers "F.Cu" "F.Mask" "F.Paste")
			(net "GND")
		)
		(pad "E41" smd circle
			(at 15.200122 -18.999962)
			(size 0.4572 0.4572)
			(layers "F.Cu" "F.Mask" "F.Paste")
			(net "GND")
		)
		(pad "E42" smd circle
			(at 16.150082 -18.999962)
			(size 0.4572 0.4572)
			(layers "F.Cu" "F.Mask" "F.Paste")
			(net "GND")
		)
		(pad "E43" smd circle
			(at 17.100042 -18.999962)
			(size 0.4572 0.4572)
			(layers "F.Cu" "F.Mask" "F.Paste")
			(net "GND")
		)
		(pad "E44" smd circle
			(at 18.050002 -18.999962)
			(size 0.4572 0.4572)
			(layers "F.Cu" "F.Mask" "F.Paste")
			(net "GND")
		)
		(pad "E45" smd circle
			(at 18.999962 -18.999962)
			(size 0.4572 0.4572)
			(layers "F.Cu" "F.Mask" "F.Paste")
			(net "GND")
		)
		(pad "E46" smd circle
			(at 19.949922 -18.999962)
			(size 0.4572 0.4572)
			(layers "F.Cu" "F.Mask" "F.Paste")
			(net "GND")
		)
		(pad "E47" smd circle
			(at 20.899882 -18.999962)
			(size 0.4572 0.4572)
			(layers "F.Cu" "F.Mask" "F.Paste")
			(net "GND")
		)
		(pad "E48" smd circle
			(at 21.850096 -18.999962)
			(size 0.4572 0.4572)
			(layers "F.Cu" "F.Mask" "F.Paste")
			(net "P5E_PEX2_STN4_TX_DP<71>")
		)
		(pad "E49" smd circle
			(at 22.800056 -18.999962)
			(size 0.4572 0.4572)
			(layers "F.Cu" "F.Mask" "F.Paste")
			(net "P5E_PEX2_STN4_TX_DN<71>")
		)
		(pad "F1" smd circle
			(at -22.800056 -18.050002)
			(size 0.4572 0.4572)
			(layers "F.Cu" "F.Mask" "F.Paste")
			(net "GND")
		)
		(pad "F2" smd circle
			(at -21.850096 -18.050002)
			(size 0.4572 0.4572)
			(layers "F.Cu" "F.Mask" "F.Paste")
			(net "GND")
		)
		(pad "F3" smd circle
			(at -20.899882 -18.050002)
			(size 0.4572 0.4572)
			(layers "F.Cu" "F.Mask" "F.Paste")
			(net "P5E_PEX2_STN7_TX_DN<123>")
		)
		(pad "F4" smd circle
			(at -19.949922 -18.050002)
			(size 0.4572 0.4572)
			(layers "F.Cu" "F.Mask" "F.Paste")
			(net "GND")
		)
		(pad "F5" smd circle
			(at -18.999962 -18.050002)
			(size 0.4572 0.4572)
			(layers "F.Cu" "F.Mask" "F.Paste")
			(net "P5E_PEX2_STN7_TX_DN<125>")
		)
		(pad "F6" smd circle
			(at -18.050002 -18.050002)
			(size 0.4572 0.4572)
			(layers "F.Cu" "F.Mask" "F.Paste")
			(net "GND")
		)
		(pad "F7" smd circle
			(at -17.100042 -18.050002)
			(size 0.4572 0.4572)
			(layers "F.Cu" "F.Mask" "F.Paste")
			(net "P5E_PEX2_STN7_TX_DN<127>")
		)
		(pad "F8" smd circle
			(at -16.150082 -18.050002)
			(size 0.4572 0.4572)
			(layers "F.Cu" "F.Mask" "F.Paste")
			(net "GND")
		)
		(pad "F9" smd circle
			(at -15.200122 -18.050002)
			(size 0.4572 0.4572)
			(layers "F.Cu" "F.Mask" "F.Paste")
			(net "P5E_PEX2_STN6_TX_DN<110>")
		)
		(pad "F10" smd circle
			(at -14.249908 -18.050002)
			(size 0.4572 0.4572)
			(layers "F.Cu" "F.Mask" "F.Paste")
			(net "GND")
		)
		(pad "F11" smd circle
			(at -13.299948 -18.050002)
			(size 0.4572 0.4572)
			(layers "F.Cu" "F.Mask" "F.Paste")
			(net "P5E_PEX2_STN6_TX_DN<108>")
		)
		(pad "F12" smd circle
			(at -12.349988 -18.050002)
			(size 0.4572 0.4572)
			(layers "F.Cu" "F.Mask" "F.Paste")
			(net "GND")
		)
		(pad "F13" smd circle
			(at -11.400028 -18.050002)
			(size 0.4572 0.4572)
			(layers "F.Cu" "F.Mask" "F.Paste")
			(net "P5E_PEX2_STN6_TX_DN<106>")
		)
		(pad "F14" smd circle
			(at -10.450068 -18.050002)
			(size 0.4572 0.4572)
			(layers "F.Cu" "F.Mask" "F.Paste")
			(net "GND")
		)
		(pad "F15" smd circle
			(at -9.500108 -18.050002)
			(size 0.4572 0.4572)
			(layers "F.Cu" "F.Mask" "F.Paste")
			(net "P5E_PEX2_STN6_TX_DN<104>")
		)
		(pad "F16" smd circle
			(at -8.549894 -18.050002)
			(size 0.4572 0.4572)
			(layers "F.Cu" "F.Mask" "F.Paste")
			(net "GND")
		)
		(pad "F17" smd circle
			(at -7.599934 -18.050002)
			(size 0.4572 0.4572)
			(layers "F.Cu" "F.Mask" "F.Paste")
			(net "P5E_PEX2_STN6_TX_DN<102>")
		)
		(pad "F18" smd circle
			(at -6.649974 -18.050002)
			(size 0.4572 0.4572)
			(layers "F.Cu" "F.Mask" "F.Paste")
			(net "GND")
		)
		(pad "F19" smd circle
			(at -5.700014 -18.050002)
			(size 0.4572 0.4572)
			(layers "F.Cu" "F.Mask" "F.Paste")
			(net "P5E_PEX2_STN6_TX_DN<100>")
		)
		(pad "F20" smd circle
			(at -4.750054 -18.050002)
			(size 0.4572 0.4572)
			(layers "F.Cu" "F.Mask" "F.Paste")
			(net "GND")
		)
		(pad "F21" smd circle
			(at -3.800094 -18.050002)
			(size 0.4572 0.4572)
			(layers "F.Cu" "F.Mask" "F.Paste")
			(net "P5E_PEX2_STN6_TX_DN<98>")
		)
		(pad "F22" smd circle
			(at -2.84988 -18.050002)
			(size 0.4572 0.4572)
			(layers "F.Cu" "F.Mask" "F.Paste")
			(net "GND")
		)
		(pad "F23" smd circle
			(at -1.89992 -18.050002)
			(size 0.4572 0.4572)
			(layers "F.Cu" "F.Mask" "F.Paste")
			(net "P5E_PEX2_STN6_TX_DN<96>")
		)
		(pad "F24" smd circle
			(at -0.94996 -18.050002)
			(size 0.4572 0.4572)
			(layers "F.Cu" "F.Mask" "F.Paste")
			(net "GND")
		)
		(pad "F25" smd circle
			(at 0 -18.050002)
			(size 0.4572 0.4572)
			(layers "F.Cu" "F.Mask" "F.Paste")
			(net "P5E_PEX2_STN5_TX_DN<81>")
		)
		(pad "F26" smd circle
			(at 0.94996 -18.050002)
			(size 0.4572 0.4572)
			(layers "F.Cu" "F.Mask" "F.Paste")
			(net "GND")
		)
		(pad "F27" smd circle
			(at 1.89992 -18.050002)
			(size 0.4572 0.4572)
			(layers "F.Cu" "F.Mask" "F.Paste")
			(net "P5E_PEX2_STN5_TX_DN<83>")
		)
		(pad "F28" smd circle
			(at 2.84988 -18.050002)
			(size 0.4572 0.4572)
			(layers "F.Cu" "F.Mask" "F.Paste")
			(net "GND")
		)
		(pad "F29" smd circle
			(at 3.800094 -18.050002)
			(size 0.4572 0.4572)
			(layers "F.Cu" "F.Mask" "F.Paste")
			(net "P5E_PEX2_STN5_TX_DN<85>")
		)
		(pad "F30" smd circle
			(at 4.750054 -18.050002)
			(size 0.4572 0.4572)
			(layers "F.Cu" "F.Mask" "F.Paste")
			(net "GND")
		)
		(pad "F31" smd circle
			(at 5.700014 -18.050002)
			(size 0.4572 0.4572)
			(layers "F.Cu" "F.Mask" "F.Paste")
			(net "P5E_PEX2_STN5_TX_DN<87>")
		)
		(pad "F32" smd circle
			(at 6.649974 -18.050002)
			(size 0.4572 0.4572)
			(layers "F.Cu" "F.Mask" "F.Paste")
			(net "GND")
		)
		(pad "F33" smd circle
			(at 7.599934 -18.050002)
			(size 0.4572 0.4572)
			(layers "F.Cu" "F.Mask" "F.Paste")
			(net "P5E_PEX2_STN5_TX_DN<89>")
		)
		(pad "F34" smd circle
			(at 8.549894 -18.050002)
			(size 0.4572 0.4572)
			(layers "F.Cu" "F.Mask" "F.Paste")
			(net "GND")
		)
		(pad "F35" smd circle
			(at 9.500108 -18.050002)
			(size 0.4572 0.4572)
			(layers "F.Cu" "F.Mask" "F.Paste")
			(net "P5E_PEX2_STN5_TX_DN<91>")
		)
		(pad "F36" smd circle
			(at 10.450068 -18.050002)
			(size 0.4572 0.4572)
			(layers "F.Cu" "F.Mask" "F.Paste")
			(net "GND")
		)
		(pad "F37" smd circle
			(at 11.400028 -18.050002)
			(size 0.4572 0.4572)
			(layers "F.Cu" "F.Mask" "F.Paste")
			(net "P5E_PEX2_STN5_TX_DN<93>")
		)
		(pad "F38" smd circle
			(at 12.349988 -18.050002)
			(size 0.4572 0.4572)
			(layers "F.Cu" "F.Mask" "F.Paste")
			(net "GND")
		)
		(pad "F39" smd circle
			(at 13.299948 -18.050002)
			(size 0.4572 0.4572)
			(layers "F.Cu" "F.Mask" "F.Paste")
			(net "P5E_PEX2_STN5_TX_DN<95>")
		)
		(pad "F40" smd circle
			(at 14.249908 -18.050002)
			(size 0.4572 0.4572)
			(layers "F.Cu" "F.Mask" "F.Paste")
			(net "GND")
		)
		(pad "F41" smd circle
			(at 15.200122 -18.050002)
			(size 0.4572 0.4572)
			(layers "F.Cu" "F.Mask" "F.Paste")
			(net "P5E_PEX2_STN4_TX_DN<78>")
		)
		(pad "F42" smd circle
			(at 16.150082 -18.050002)
			(size 0.4572 0.4572)
			(layers "F.Cu" "F.Mask" "F.Paste")
			(net "GND")
		)
		(pad "F43" smd circle
			(at 17.100042 -18.050002)
			(size 0.4572 0.4572)
			(layers "F.Cu" "F.Mask" "F.Paste")
			(net "P5E_PEX2_STN4_TX_DN<76>")
		)
		(pad "F44" smd circle
			(at 18.050002 -18.050002)
			(size 0.4572 0.4572)
			(layers "F.Cu" "F.Mask" "F.Paste")
			(net "GND")
		)
		(pad "F45" smd circle
			(at 18.999962 -18.050002)
			(size 0.4572 0.4572)
			(layers "F.Cu" "F.Mask" "F.Paste")
			(net "P5E_PEX2_STN4_TX_DN<74>")
		)
		(pad "F46" smd circle
			(at 19.949922 -18.050002)
			(size 0.4572 0.4572)
			(layers "F.Cu" "F.Mask" "F.Paste")
			(net "GND")
		)
		(pad "F47" smd circle
			(at 20.899882 -18.050002)
			(size 0.4572 0.4572)
			(layers "F.Cu" "F.Mask" "F.Paste")
			(net "P5E_PEX2_STN4_TX_DN<72>")
		)
		(pad "F48" smd circle
			(at 21.850096 -18.050002)
			(size 0.4572 0.4572)
			(layers "F.Cu" "F.Mask" "F.Paste")
			(net "GND")
		)
		(pad "F49" smd circle
			(at 22.800056 -18.050002)
			(size 0.4572 0.4572)
			(layers "F.Cu" "F.Mask" "F.Paste")
			(net "GND")
		)
		(pad "G1" smd circle
			(at -22.800056 -17.100042)
			(size 0.4572 0.4572)
			(layers "F.Cu" "F.Mask" "F.Paste")
			(net "GND")
		)
		(pad "G2" smd circle
			(at -21.850096 -17.100042)
			(size 0.4572 0.4572)
			(layers "F.Cu" "F.Mask" "F.Paste")
			(net "GND")
		)
		(pad "G3" smd circle
			(at -20.899882 -17.100042)
			(size 0.4572 0.4572)
			(layers "F.Cu" "F.Mask" "F.Paste")
			(net "P5E_PEX2_STN7_TX_DP<123>")
		)
		(pad "G4" smd circle
			(at -19.949922 -17.100042)
			(size 0.4572 0.4572)
			(layers "F.Cu" "F.Mask" "F.Paste")
			(net "GND")
		)
		(pad "G5" smd circle
			(at -18.999962 -17.100042)
			(size 0.4572 0.4572)
			(layers "F.Cu" "F.Mask" "F.Paste")
			(net "P5E_PEX2_STN7_TX_DP<125>")
		)
		(pad "G6" smd circle
			(at -18.050002 -17.100042)
			(size 0.4572 0.4572)
			(layers "F.Cu" "F.Mask" "F.Paste")
			(net "GND")
		)
		(pad "G7" smd circle
			(at -17.100042 -17.100042)
			(size 0.4572 0.4572)
			(layers "F.Cu" "F.Mask" "F.Paste")
			(net "P5E_PEX2_STN7_TX_DP<127>")
		)
		(pad "G8" smd circle
			(at -16.150082 -17.100042)
			(size 0.4572 0.4572)
			(layers "F.Cu" "F.Mask" "F.Paste")
			(net "GND")
		)
		(pad "G9" smd circle
			(at -15.200122 -17.100042)
			(size 0.4572 0.4572)
			(layers "F.Cu" "F.Mask" "F.Paste")
			(net "P5E_PEX2_STN6_TX_DP<110>")
		)
		(pad "G10" smd circle
			(at -14.249908 -17.100042)
			(size 0.4572 0.4572)
			(layers "F.Cu" "F.Mask" "F.Paste")
			(net "GND")
		)
		(pad "G11" smd circle
			(at -13.299948 -17.100042)
			(size 0.4572 0.4572)
			(layers "F.Cu" "F.Mask" "F.Paste")
			(net "P5E_PEX2_STN6_TX_DP<108>")
		)
		(pad "G12" smd circle
			(at -12.349988 -17.100042)
			(size 0.4572 0.4572)
			(layers "F.Cu" "F.Mask" "F.Paste")
			(net "GND")
		)
		(pad "G13" smd circle
			(at -11.400028 -17.100042)
			(size 0.4572 0.4572)
			(layers "F.Cu" "F.Mask" "F.Paste")
			(net "P5E_PEX2_STN6_TX_DP<106>")
		)
		(pad "G14" smd circle
			(at -10.450068 -17.100042)
			(size 0.4572 0.4572)
			(layers "F.Cu" "F.Mask" "F.Paste")
			(net "GND")
		)
		(pad "G15" smd circle
			(at -9.500108 -17.100042)
			(size 0.4572 0.4572)
			(layers "F.Cu" "F.Mask" "F.Paste")
			(net "P5E_PEX2_STN6_TX_DP<104>")
		)
		(pad "G16" smd circle
			(at -8.549894 -17.100042)
			(size 0.4572 0.4572)
			(layers "F.Cu" "F.Mask" "F.Paste")
			(net "GND")
		)
		(pad "G17" smd circle
			(at -7.599934 -17.100042)
			(size 0.4572 0.4572)
			(layers "F.Cu" "F.Mask" "F.Paste")
			(net "P5E_PEX2_STN6_TX_DP<102>")
		)
		(pad "G18" smd circle
			(at -6.649974 -17.100042)
			(size 0.4572 0.4572)
			(layers "F.Cu" "F.Mask" "F.Paste")
			(net "GND")
		)
		(pad "G19" smd circle
			(at -5.700014 -17.100042)
			(size 0.4572 0.4572)
			(layers "F.Cu" "F.Mask" "F.Paste")
			(net "P5E_PEX2_STN6_TX_DP<100>")
		)
		(pad "G20" smd circle
			(at -4.750054 -17.100042)
			(size 0.4572 0.4572)
			(layers "F.Cu" "F.Mask" "F.Paste")
			(net "GND")
		)
		(pad "G21" smd circle
			(at -3.800094 -17.100042)
			(size 0.4572 0.4572)
			(layers "F.Cu" "F.Mask" "F.Paste")
			(net "P5E_PEX2_STN6_TX_DP<98>")
		)
		(pad "G22" smd circle
			(at -2.84988 -17.100042)
			(size 0.4572 0.4572)
			(layers "F.Cu" "F.Mask" "F.Paste")
			(net "GND")
		)
		(pad "G23" smd circle
			(at -1.89992 -17.100042)
			(size 0.4572 0.4572)
			(layers "F.Cu" "F.Mask" "F.Paste")
			(net "P5E_PEX2_STN6_TX_DP<96>")
		)
		(pad "G24" smd circle
			(at -0.94996 -17.100042)
			(size 0.4572 0.4572)
			(layers "F.Cu" "F.Mask" "F.Paste")
			(net "GND")
		)
		(pad "G25" smd circle
			(at 0 -17.100042)
			(size 0.4572 0.4572)
			(layers "F.Cu" "F.Mask" "F.Paste")
			(net "P5E_PEX2_STN5_TX_DP<81>")
		)
		(pad "G26" smd circle
			(at 0.94996 -17.100042)
			(size 0.4572 0.4572)
			(layers "F.Cu" "F.Mask" "F.Paste")
			(net "GND")
		)
		(pad "G27" smd circle
			(at 1.89992 -17.100042)
			(size 0.4572 0.4572)
			(layers "F.Cu" "F.Mask" "F.Paste")
			(net "P5E_PEX2_STN5_TX_DP<83>")
		)
		(pad "G28" smd circle
			(at 2.84988 -17.100042)
			(size 0.4572 0.4572)
			(layers "F.Cu" "F.Mask" "F.Paste")
			(net "GND")
		)
		(pad "G29" smd circle
			(at 3.800094 -17.100042)
			(size 0.4572 0.4572)
			(layers "F.Cu" "F.Mask" "F.Paste")
			(net "P5E_PEX2_STN5_TX_DP<85>")
		)
		(pad "G30" smd circle
			(at 4.750054 -17.100042)
			(size 0.4572 0.4572)
			(layers "F.Cu" "F.Mask" "F.Paste")
			(net "GND")
		)
		(pad "G31" smd circle
			(at 5.700014 -17.100042)
			(size 0.4572 0.4572)
			(layers "F.Cu" "F.Mask" "F.Paste")
			(net "P5E_PEX2_STN5_TX_DP<87>")
		)
		(pad "G32" smd circle
			(at 6.649974 -17.100042)
			(size 0.4572 0.4572)
			(layers "F.Cu" "F.Mask" "F.Paste")
			(net "GND")
		)
		(pad "G33" smd circle
			(at 7.599934 -17.100042)
			(size 0.4572 0.4572)
			(layers "F.Cu" "F.Mask" "F.Paste")
			(net "P5E_PEX2_STN5_TX_DP<89>")
		)
		(pad "G34" smd circle
			(at 8.549894 -17.100042)
			(size 0.4572 0.4572)
			(layers "F.Cu" "F.Mask" "F.Paste")
			(net "GND")
		)
		(pad "G35" smd circle
			(at 9.500108 -17.100042)
			(size 0.4572 0.4572)
			(layers "F.Cu" "F.Mask" "F.Paste")
			(net "P5E_PEX2_STN5_TX_DP<91>")
		)
		(pad "G36" smd circle
			(at 10.450068 -17.100042)
			(size 0.4572 0.4572)
			(layers "F.Cu" "F.Mask" "F.Paste")
			(net "GND")
		)
		(pad "G37" smd circle
			(at 11.400028 -17.100042)
			(size 0.4572 0.4572)
			(layers "F.Cu" "F.Mask" "F.Paste")
			(net "P5E_PEX2_STN5_TX_DP<93>")
		)
		(pad "G38" smd circle
			(at 12.349988 -17.100042)
			(size 0.4572 0.4572)
			(layers "F.Cu" "F.Mask" "F.Paste")
			(net "GND")
		)
		(pad "G39" smd circle
			(at 13.299948 -17.100042)
			(size 0.4572 0.4572)
			(layers "F.Cu" "F.Mask" "F.Paste")
			(net "P5E_PEX2_STN5_TX_DP<95>")
		)
		(pad "G40" smd circle
			(at 14.249908 -17.100042)
			(size 0.4572 0.4572)
			(layers "F.Cu" "F.Mask" "F.Paste")
			(net "GND")
		)
		(pad "G41" smd circle
			(at 15.200122 -17.100042)
			(size 0.4572 0.4572)
			(layers "F.Cu" "F.Mask" "F.Paste")
			(net "P5E_PEX2_STN4_TX_DP<78>")
		)
		(pad "G42" smd circle
			(at 16.150082 -17.100042)
			(size 0.4572 0.4572)
			(layers "F.Cu" "F.Mask" "F.Paste")
			(net "GND")
		)
		(pad "G43" smd circle
			(at 17.100042 -17.100042)
			(size 0.4572 0.4572)
			(layers "F.Cu" "F.Mask" "F.Paste")
			(net "P5E_PEX2_STN4_TX_DP<76>")
		)
		(pad "G44" smd circle
			(at 18.050002 -17.100042)
			(size 0.4572 0.4572)
			(layers "F.Cu" "F.Mask" "F.Paste")
			(net "GND")
		)
		(pad "G45" smd circle
			(at 18.999962 -17.100042)
			(size 0.4572 0.4572)
			(layers "F.Cu" "F.Mask" "F.Paste")
			(net "P5E_PEX2_STN4_TX_DP<74>")
		)
		(pad "G46" smd circle
			(at 19.949922 -17.100042)
			(size 0.4572 0.4572)
			(layers "F.Cu" "F.Mask" "F.Paste")
			(net "GND")
		)
		(pad "G47" smd circle
			(at 20.899882 -17.100042)
			(size 0.4572 0.4572)
			(layers "F.Cu" "F.Mask" "F.Paste")
			(net "P5E_PEX2_STN4_TX_DP<72>")
		)
		(pad "G48" smd circle
			(at 21.850096 -17.100042)
			(size 0.4572 0.4572)
			(layers "F.Cu" "F.Mask" "F.Paste")
			(net "GND")
		)
		(pad "G49" smd circle
			(at 22.800056 -17.100042)
			(size 0.4572 0.4572)
			(layers "F.Cu" "F.Mask" "F.Paste")
			(net "GND")
		)
		(pad "H1" smd circle
			(at -22.800056 -16.150082)
			(size 0.4572 0.4572)
			(layers "F.Cu" "F.Mask" "F.Paste")
			(net "P5E_PEX2_STN7_TX_DN<121>")
		)
		(pad "H2" smd circle
			(at -21.850096 -16.150082)
			(size 0.4572 0.4572)
			(layers "F.Cu" "F.Mask" "F.Paste")
			(net "P5E_PEX2_STN7_TX_DP<121>")
		)
		(pad "H3" smd circle
			(at -20.899882 -16.150082)
			(size 0.4572 0.4572)
			(layers "F.Cu" "F.Mask" "F.Paste")
			(net "GND")
		)
		(pad "H4" smd circle
			(at -19.949922 -16.150082)
			(size 0.4572 0.4572)
			(layers "F.Cu" "F.Mask" "F.Paste")
			(net "P5E_PEX2_STN7_TX_DN<124>")
		)
		(pad "H5" smd circle
			(at -18.999962 -16.150082)
			(size 0.4572 0.4572)
			(layers "F.Cu" "F.Mask" "F.Paste")
			(net "GND")
		)
		(pad "H6" smd circle
			(at -18.050002 -16.150082)
			(size 0.4572 0.4572)
			(layers "F.Cu" "F.Mask" "F.Paste")
			(net "P5E_PEX2_STN7_TX_DN<126>")
		)
		(pad "H7" smd circle
			(at -17.100042 -16.150082)
			(size 0.4572 0.4572)
			(layers "F.Cu" "F.Mask" "F.Paste")
			(net "GND")
		)
		(pad "H8" smd circle
			(at -16.150082 -16.150082)
			(size 0.4572 0.4572)
			(layers "F.Cu" "F.Mask" "F.Paste")
			(net "P5E_PEX2_STN6_TX_DN<111>")
		)
		(pad "H9" smd circle
			(at -15.200122 -16.150082)
			(size 0.4572 0.4572)
			(layers "F.Cu" "F.Mask" "F.Paste")
			(net "GND")
		)
		(pad "H10" smd circle
			(at -14.249908 -16.150082)
			(size 0.4572 0.4572)
			(layers "F.Cu" "F.Mask" "F.Paste")
			(net "P5E_PEX2_STN6_TX_DN<109>")
		)
		(pad "H11" smd circle
			(at -13.299948 -16.150082)
			(size 0.4572 0.4572)
			(layers "F.Cu" "F.Mask" "F.Paste")
			(net "GND")
		)
		(pad "H12" smd circle
			(at -12.349988 -16.150082)
			(size 0.4572 0.4572)
			(layers "F.Cu" "F.Mask" "F.Paste")
			(net "P5E_PEX2_STN6_TX_DN<107>")
		)
		(pad "H13" smd circle
			(at -11.400028 -16.150082)
			(size 0.4572 0.4572)
			(layers "F.Cu" "F.Mask" "F.Paste")
			(net "GND")
		)
		(pad "H14" smd circle
			(at -10.450068 -16.150082)
			(size 0.4572 0.4572)
			(layers "F.Cu" "F.Mask" "F.Paste")
			(net "P5E_PEX2_STN6_TX_DN<105>")
		)
		(pad "H15" smd circle
			(at -9.500108 -16.150082)
			(size 0.4572 0.4572)
			(layers "F.Cu" "F.Mask" "F.Paste")
			(net "GND")
		)
		(pad "H16" smd circle
			(at -8.549894 -16.150082)
			(size 0.4572 0.4572)
			(layers "F.Cu" "F.Mask" "F.Paste")
			(net "P5E_PEX2_STN6_TX_DN<103>")
		)
		(pad "H17" smd circle
			(at -7.599934 -16.150082)
			(size 0.4572 0.4572)
			(layers "F.Cu" "F.Mask" "F.Paste")
			(net "GND")
		)
		(pad "H18" smd circle
			(at -6.649974 -16.150082)
			(size 0.4572 0.4572)
			(layers "F.Cu" "F.Mask" "F.Paste")
			(net "P5E_PEX2_STN6_TX_DN<101>")
		)
		(pad "H19" smd circle
			(at -5.700014 -16.150082)
			(size 0.4572 0.4572)
			(layers "F.Cu" "F.Mask" "F.Paste")
			(net "GND")
		)
		(pad "H20" smd circle
			(at -4.750054 -16.150082)
			(size 0.4572 0.4572)
			(layers "F.Cu" "F.Mask" "F.Paste")
			(net "P5E_PEX2_STN6_TX_DN<99>")
		)
		(pad "H21" smd circle
			(at -3.800094 -16.150082)
			(size 0.4572 0.4572)
			(layers "F.Cu" "F.Mask" "F.Paste")
			(net "GND")
		)
		(pad "H22" smd circle
			(at -2.84988 -16.150082)
			(size 0.4572 0.4572)
			(layers "F.Cu" "F.Mask" "F.Paste")
			(net "P5E_PEX2_STN6_TX_DN<97>")
		)
		(pad "H23" smd circle
			(at -1.89992 -16.150082)
			(size 0.4572 0.4572)
			(layers "F.Cu" "F.Mask" "F.Paste")
			(net "GND")
		)
		(pad "H24" smd circle
			(at -0.94996 -16.150082)
			(size 0.4572 0.4572)
			(layers "F.Cu" "F.Mask" "F.Paste")
			(net "P5E_PEX2_STN5_TX_DN<80>")
		)
		(pad "H25" smd circle
			(at 0 -16.150082)
			(size 0.4572 0.4572)
			(layers "F.Cu" "F.Mask" "F.Paste")
			(net "GND")
		)
		(pad "H26" smd circle
			(at 0.94996 -16.150082)
			(size 0.4572 0.4572)
			(layers "F.Cu" "F.Mask" "F.Paste")
			(net "P5E_PEX2_STN5_TX_DN<82>")
		)
		(pad "H27" smd circle
			(at 1.89992 -16.150082)
			(size 0.4572 0.4572)
			(layers "F.Cu" "F.Mask" "F.Paste")
			(net "GND")
		)
		(pad "H28" smd circle
			(at 2.84988 -16.150082)
			(size 0.4572 0.4572)
			(layers "F.Cu" "F.Mask" "F.Paste")
			(net "P5E_PEX2_STN5_TX_DN<84>")
		)
		(pad "H29" smd circle
			(at 3.800094 -16.150082)
			(size 0.4572 0.4572)
			(layers "F.Cu" "F.Mask" "F.Paste")
			(net "GND")
		)
		(pad "H30" smd circle
			(at 4.750054 -16.150082)
			(size 0.4572 0.4572)
			(layers "F.Cu" "F.Mask" "F.Paste")
			(net "P5E_PEX2_STN5_TX_DN<86>")
		)
		(pad "H31" smd circle
			(at 5.700014 -16.150082)
			(size 0.4572 0.4572)
			(layers "F.Cu" "F.Mask" "F.Paste")
			(net "GND")
		)
		(pad "H32" smd circle
			(at 6.649974 -16.150082)
			(size 0.4572 0.4572)
			(layers "F.Cu" "F.Mask" "F.Paste")
			(net "P5E_PEX2_STN5_TX_DN<88>")
		)
		(pad "H33" smd circle
			(at 7.599934 -16.150082)
			(size 0.4572 0.4572)
			(layers "F.Cu" "F.Mask" "F.Paste")
			(net "GND")
		)
		(pad "H34" smd circle
			(at 8.549894 -16.150082)
			(size 0.4572 0.4572)
			(layers "F.Cu" "F.Mask" "F.Paste")
			(net "P5E_PEX2_STN5_TX_DN<90>")
		)
		(pad "H35" smd circle
			(at 9.500108 -16.150082)
			(size 0.4572 0.4572)
			(layers "F.Cu" "F.Mask" "F.Paste")
			(net "GND")
		)
		(pad "H36" smd circle
			(at 10.450068 -16.150082)
			(size 0.4572 0.4572)
			(layers "F.Cu" "F.Mask" "F.Paste")
			(net "P5E_PEX2_STN5_TX_DN<92>")
		)
		(pad "H37" smd circle
			(at 11.400028 -16.150082)
			(size 0.4572 0.4572)
			(layers "F.Cu" "F.Mask" "F.Paste")
			(net "GND")
		)
		(pad "H38" smd circle
			(at 12.349988 -16.150082)
			(size 0.4572 0.4572)
			(layers "F.Cu" "F.Mask" "F.Paste")
			(net "P5E_PEX2_STN5_TX_DN<94>")
		)
		(pad "H39" smd circle
			(at 13.299948 -16.150082)
			(size 0.4572 0.4572)
			(layers "F.Cu" "F.Mask" "F.Paste")
			(net "GND")
		)
		(pad "H40" smd circle
			(at 14.249908 -16.150082)
			(size 0.4572 0.4572)
			(layers "F.Cu" "F.Mask" "F.Paste")
			(net "P5E_PEX2_STN4_TX_DN<79>")
		)
		(pad "H41" smd circle
			(at 15.200122 -16.150082)
			(size 0.4572 0.4572)
			(layers "F.Cu" "F.Mask" "F.Paste")
			(net "GND")
		)
		(pad "H42" smd circle
			(at 16.150082 -16.150082)
			(size 0.4572 0.4572)
			(layers "F.Cu" "F.Mask" "F.Paste")
			(net "P5E_PEX2_STN4_TX_DN<77>")
		)
		(pad "H43" smd circle
			(at 17.100042 -16.150082)
			(size 0.4572 0.4572)
			(layers "F.Cu" "F.Mask" "F.Paste")
			(net "GND")
		)
		(pad "H44" smd circle
			(at 18.050002 -16.150082)
			(size 0.4572 0.4572)
			(layers "F.Cu" "F.Mask" "F.Paste")
			(net "P5E_PEX2_STN4_TX_DN<75>")
		)
		(pad "H45" smd circle
			(at 18.999962 -16.150082)
			(size 0.4572 0.4572)
			(layers "F.Cu" "F.Mask" "F.Paste")
			(net "GND")
		)
		(pad "H46" smd circle
			(at 19.949922 -16.150082)
			(size 0.4572 0.4572)
			(layers "F.Cu" "F.Mask" "F.Paste")
			(net "P5E_PEX2_STN4_TX_DN<73>")
		)
		(pad "H47" smd circle
			(at 20.899882 -16.150082)
			(size 0.4572 0.4572)
			(layers "F.Cu" "F.Mask" "F.Paste")
			(net "GND")
		)
		(pad "H48" smd circle
			(at 21.850096 -16.150082)
			(size 0.4572 0.4572)
			(layers "F.Cu" "F.Mask" "F.Paste")
			(net "P5E_PEX2_STN4_TX_DP<70>")
		)
		(pad "H49" smd circle
			(at 22.800056 -16.150082)
			(size 0.4572 0.4572)
			(layers "F.Cu" "F.Mask" "F.Paste")
			(net "P5E_PEX2_STN4_TX_DN<70>")
		)
		(pad "J1" smd circle
			(at -22.800056 -15.200122)
			(size 0.4572 0.4572)
			(layers "F.Cu" "F.Mask" "F.Paste")
			(net "GND")
		)
		(pad "J2" smd circle
			(at -21.850096 -15.200122)
			(size 0.4572 0.4572)
			(layers "F.Cu" "F.Mask" "F.Paste")
			(net "GND")
		)
		(pad "J3" smd circle
			(at -20.899882 -15.200122)
			(size 0.4572 0.4572)
			(layers "F.Cu" "F.Mask" "F.Paste")
			(net "GND")
		)
		(pad "J4" smd circle
			(at -19.949922 -15.200122)
			(size 0.4572 0.4572)
			(layers "F.Cu" "F.Mask" "F.Paste")
			(net "P5E_PEX2_STN7_TX_DP<124>")
		)
		(pad "J5" smd circle
			(at -18.999962 -15.200122)
			(size 0.4572 0.4572)
			(layers "F.Cu" "F.Mask" "F.Paste")
			(net "GND")
		)
		(pad "J6" smd circle
			(at -18.050002 -15.200122)
			(size 0.4572 0.4572)
			(layers "F.Cu" "F.Mask" "F.Paste")
			(net "P5E_PEX2_STN7_TX_DP<126>")
		)
		(pad "J7" smd circle
			(at -17.100042 -15.200122)
			(size 0.4572 0.4572)
			(layers "F.Cu" "F.Mask" "F.Paste")
			(net "GND")
		)
		(pad "J8" smd circle
			(at -16.150082 -15.200122)
			(size 0.4572 0.4572)
			(layers "F.Cu" "F.Mask" "F.Paste")
			(net "P5E_PEX2_STN6_TX_DP<111>")
		)
		(pad "J9" smd circle
			(at -15.200122 -15.200122)
			(size 0.4572 0.4572)
			(layers "F.Cu" "F.Mask" "F.Paste")
			(net "GND")
		)
		(pad "J10" smd circle
			(at -14.249908 -15.200122)
			(size 0.4572 0.4572)
			(layers "F.Cu" "F.Mask" "F.Paste")
			(net "P5E_PEX2_STN6_TX_DP<109>")
		)
		(pad "J11" smd circle
			(at -13.299948 -15.200122)
			(size 0.4572 0.4572)
			(layers "F.Cu" "F.Mask" "F.Paste")
			(net "GND")
		)
		(pad "J12" smd circle
			(at -12.349988 -15.200122)
			(size 0.4572 0.4572)
			(layers "F.Cu" "F.Mask" "F.Paste")
			(net "P5E_PEX2_STN6_TX_DP<107>")
		)
		(pad "J13" smd circle
			(at -11.400028 -15.200122)
			(size 0.4572 0.4572)
			(layers "F.Cu" "F.Mask" "F.Paste")
			(net "GND")
		)
		(pad "J14" smd circle
			(at -10.450068 -15.200122)
			(size 0.4572 0.4572)
			(layers "F.Cu" "F.Mask" "F.Paste")
			(net "P5E_PEX2_STN6_TX_DP<105>")
		)
		(pad "J15" smd circle
			(at -9.500108 -15.200122)
			(size 0.4572 0.4572)
			(layers "F.Cu" "F.Mask" "F.Paste")
			(net "GND")
		)
		(pad "J16" smd circle
			(at -8.549894 -15.200122)
			(size 0.4572 0.4572)
			(layers "F.Cu" "F.Mask" "F.Paste")
			(net "P5E_PEX2_STN6_TX_DP<103>")
		)
		(pad "J17" smd circle
			(at -7.599934 -15.200122)
			(size 0.4572 0.4572)
			(layers "F.Cu" "F.Mask" "F.Paste")
			(net "GND")
		)
		(pad "J18" smd circle
			(at -6.649974 -15.200122)
			(size 0.4572 0.4572)
			(layers "F.Cu" "F.Mask" "F.Paste")
			(net "P5E_PEX2_STN6_TX_DP<101>")
		)
		(pad "J19" smd circle
			(at -5.700014 -15.200122)
			(size 0.4572 0.4572)
			(layers "F.Cu" "F.Mask" "F.Paste")
			(net "GND")
		)
		(pad "J20" smd circle
			(at -4.750054 -15.200122)
			(size 0.4572 0.4572)
			(layers "F.Cu" "F.Mask" "F.Paste")
			(net "P5E_PEX2_STN6_TX_DP<99>")
		)
		(pad "J21" smd circle
			(at -3.800094 -15.200122)
			(size 0.4572 0.4572)
			(layers "F.Cu" "F.Mask" "F.Paste")
			(net "GND")
		)
		(pad "J22" smd circle
			(at -2.84988 -15.200122)
			(size 0.4572 0.4572)
			(layers "F.Cu" "F.Mask" "F.Paste")
			(net "P5E_PEX2_STN6_TX_DP<97>")
		)
		(pad "J23" smd circle
			(at -1.89992 -15.200122)
			(size 0.4572 0.4572)
			(layers "F.Cu" "F.Mask" "F.Paste")
			(net "GND")
		)
		(pad "J24" smd circle
			(at -0.94996 -15.200122)
			(size 0.4572 0.4572)
			(layers "F.Cu" "F.Mask" "F.Paste")
			(net "P5E_PEX2_STN5_TX_DP<80>")
		)
		(pad "J25" smd circle
			(at 0 -15.200122)
			(size 0.4572 0.4572)
			(layers "F.Cu" "F.Mask" "F.Paste")
			(net "GND")
		)
		(pad "J26" smd circle
			(at 0.94996 -15.200122)
			(size 0.4572 0.4572)
			(layers "F.Cu" "F.Mask" "F.Paste")
			(net "P5E_PEX2_STN5_TX_DP<82>")
		)
		(pad "J27" smd circle
			(at 1.89992 -15.200122)
			(size 0.4572 0.4572)
			(layers "F.Cu" "F.Mask" "F.Paste")
			(net "GND")
		)
		(pad "J28" smd circle
			(at 2.84988 -15.200122)
			(size 0.4572 0.4572)
			(layers "F.Cu" "F.Mask" "F.Paste")
			(net "P5E_PEX2_STN5_TX_DP<84>")
		)
		(pad "J29" smd circle
			(at 3.800094 -15.200122)
			(size 0.4572 0.4572)
			(layers "F.Cu" "F.Mask" "F.Paste")
			(net "GND")
		)
		(pad "J30" smd circle
			(at 4.750054 -15.200122)
			(size 0.4572 0.4572)
			(layers "F.Cu" "F.Mask" "F.Paste")
			(net "P5E_PEX2_STN5_TX_DP<86>")
		)
		(pad "J31" smd circle
			(at 5.700014 -15.200122)
			(size 0.4572 0.4572)
			(layers "F.Cu" "F.Mask" "F.Paste")
			(net "GND")
		)
		(pad "J32" smd circle
			(at 6.649974 -15.200122)
			(size 0.4572 0.4572)
			(layers "F.Cu" "F.Mask" "F.Paste")
			(net "P5E_PEX2_STN5_TX_DP<88>")
		)
		(pad "J33" smd circle
			(at 7.599934 -15.200122)
			(size 0.4572 0.4572)
			(layers "F.Cu" "F.Mask" "F.Paste")
			(net "GND")
		)
		(pad "J34" smd circle
			(at 8.549894 -15.200122)
			(size 0.4572 0.4572)
			(layers "F.Cu" "F.Mask" "F.Paste")
			(net "P5E_PEX2_STN5_TX_DP<90>")
		)
		(pad "J35" smd circle
			(at 9.500108 -15.200122)
			(size 0.4572 0.4572)
			(layers "F.Cu" "F.Mask" "F.Paste")
			(net "GND")
		)
		(pad "J36" smd circle
			(at 10.450068 -15.200122)
			(size 0.4572 0.4572)
			(layers "F.Cu" "F.Mask" "F.Paste")
			(net "P5E_PEX2_STN5_TX_DP<92>")
		)
		(pad "J37" smd circle
			(at 11.400028 -15.200122)
			(size 0.4572 0.4572)
			(layers "F.Cu" "F.Mask" "F.Paste")
			(net "GND")
		)
		(pad "J38" smd circle
			(at 12.349988 -15.200122)
			(size 0.4572 0.4572)
			(layers "F.Cu" "F.Mask" "F.Paste")
			(net "P5E_PEX2_STN5_TX_DP<94>")
		)
		(pad "J39" smd circle
			(at 13.299948 -15.200122)
			(size 0.4572 0.4572)
			(layers "F.Cu" "F.Mask" "F.Paste")
			(net "GND")
		)
		(pad "J40" smd circle
			(at 14.249908 -15.200122)
			(size 0.4572 0.4572)
			(layers "F.Cu" "F.Mask" "F.Paste")
			(net "P5E_PEX2_STN4_TX_DP<79>")
		)
		(pad "J41" smd circle
			(at 15.200122 -15.200122)
			(size 0.4572 0.4572)
			(layers "F.Cu" "F.Mask" "F.Paste")
			(net "GND")
		)
		(pad "J42" smd circle
			(at 16.150082 -15.200122)
			(size 0.4572 0.4572)
			(layers "F.Cu" "F.Mask" "F.Paste")
			(net "P5E_PEX2_STN4_TX_DP<77>")
		)
		(pad "J43" smd circle
			(at 17.100042 -15.200122)
			(size 0.4572 0.4572)
			(layers "F.Cu" "F.Mask" "F.Paste")
			(net "GND")
		)
		(pad "J44" smd circle
			(at 18.050002 -15.200122)
			(size 0.4572 0.4572)
			(layers "F.Cu" "F.Mask" "F.Paste")
			(net "P5E_PEX2_STN4_TX_DP<75>")
		)
		(pad "J45" smd circle
			(at 18.999962 -15.200122)
			(size 0.4572 0.4572)
			(layers "F.Cu" "F.Mask" "F.Paste")
			(net "GND")
		)
		(pad "J46" smd circle
			(at 19.949922 -15.200122)
			(size 0.4572 0.4572)
			(layers "F.Cu" "F.Mask" "F.Paste")
			(net "P5E_PEX2_STN4_TX_DP<73>")
		)
		(pad "J47" smd circle
			(at 20.899882 -15.200122)
			(size 0.4572 0.4572)
			(layers "F.Cu" "F.Mask" "F.Paste")
			(net "GND")
		)
		(pad "J48" smd circle
			(at 21.850096 -15.200122)
			(size 0.4572 0.4572)
			(layers "F.Cu" "F.Mask" "F.Paste")
			(net "GND")
		)
		(pad "J49" smd circle
			(at 22.800056 -15.200122)
			(size 0.4572 0.4572)
			(layers "F.Cu" "F.Mask" "F.Paste")
			(net "GND")
		)
		(pad "K1" smd circle
			(at -22.800056 -14.249908)
			(size 0.4572 0.4572)
			(layers "F.Cu" "F.Mask" "F.Paste")
			(net "P5E_PEX2_STN7_RX_DN<121>")
		)
		(pad "K2" smd circle
			(at -21.850096 -14.249908)
			(size 0.4572 0.4572)
			(layers "F.Cu" "F.Mask" "F.Paste")
			(net "P5E_PEX2_STN7_RX_DP<121>")
		)
		(pad "K3" smd circle
			(at -20.899882 -14.249908)
			(size 0.4572 0.4572)
			(layers "F.Cu" "F.Mask" "F.Paste")
			(net "GND")
		)
		(pad "K4" smd circle
			(at -19.949922 -14.249908)
			(size 0.4572 0.4572)
			(layers "F.Cu" "F.Mask" "F.Paste")
			(net "GND")
		)
		(pad "K5" smd circle
			(at -18.999962 -14.249908)
			(size 0.4572 0.4572)
			(layers "F.Cu" "F.Mask" "F.Paste")
			(net "GND")
		)
		(pad "K6" smd circle
			(at -18.050002 -14.249908)
			(size 0.4572 0.4572)
			(layers "F.Cu" "F.Mask" "F.Paste")
			(net "GND")
		)
		(pad "K7" smd circle
			(at -17.100042 -14.249908)
			(size 0.4572 0.4572)
			(layers "F.Cu" "F.Mask" "F.Paste")
			(net "GND")
		)
		(pad "K8" smd circle
			(at -16.150082 -14.249908)
			(size 0.4572 0.4572)
			(layers "F.Cu" "F.Mask" "F.Paste")
			(net "GND")
		)
		(pad "K9" smd circle
			(at -15.200122 -14.249908)
			(size 0.4572 0.4572)
			(layers "F.Cu" "F.Mask" "F.Paste")
			(net "GND")
		)
		(pad "K10" smd circle
			(at -14.249908 -14.249908)
			(size 0.4572 0.4572)
			(layers "F.Cu" "F.Mask" "F.Paste")
			(net "GND")
		)
		(pad "K11" smd circle
			(at -13.299948 -14.249908)
			(size 0.4572 0.4572)
			(layers "F.Cu" "F.Mask" "F.Paste")
			(net "GND")
		)
		(pad "K12" smd circle
			(at -12.349988 -14.249908)
			(size 0.4572 0.4572)
			(layers "F.Cu" "F.Mask" "F.Paste")
			(net "GND")
		)
		(pad "K13" smd circle
			(at -11.400028 -14.249908)
			(size 0.4572 0.4572)
			(layers "F.Cu" "F.Mask" "F.Paste")
			(net "GND")
		)
		(pad "K14" smd circle
			(at -10.450068 -14.249908)
			(size 0.4572 0.4572)
			(layers "F.Cu" "F.Mask" "F.Paste")
			(net "GND")
		)
		(pad "K15" smd circle
			(at -9.500108 -14.249908)
			(size 0.4572 0.4572)
			(layers "F.Cu" "F.Mask" "F.Paste")
			(net "GND")
		)
		(pad "K16" smd circle
			(at -8.549894 -14.249908)
			(size 0.4572 0.4572)
			(layers "F.Cu" "F.Mask" "F.Paste")
			(net "GND")
		)
		(pad "K17" smd circle
			(at -7.599934 -14.249908)
			(size 0.4572 0.4572)
			(layers "F.Cu" "F.Mask" "F.Paste")
			(net "GND")
		)
		(pad "K18" smd circle
			(at -6.649974 -14.249908)
			(size 0.4572 0.4572)
			(layers "F.Cu" "F.Mask" "F.Paste")
			(net "GND")
		)
		(pad "K19" smd circle
			(at -5.700014 -14.249908)
			(size 0.4572 0.4572)
			(layers "F.Cu" "F.Mask" "F.Paste")
			(net "GND")
		)
		(pad "K20" smd circle
			(at -4.750054 -14.249908)
			(size 0.4572 0.4572)
			(layers "F.Cu" "F.Mask" "F.Paste")
			(net "GND")
		)
		(pad "K21" smd circle
			(at -3.800094 -14.249908)
			(size 0.4572 0.4572)
			(layers "F.Cu" "F.Mask" "F.Paste")
			(net "GND")
		)
		(pad "K22" smd circle
			(at -2.84988 -14.249908)
			(size 0.4572 0.4572)
			(layers "F.Cu" "F.Mask" "F.Paste")
			(net "GND")
		)
		(pad "K23" smd circle
			(at -1.89992 -14.249908)
			(size 0.4572 0.4572)
			(layers "F.Cu" "F.Mask" "F.Paste")
			(net "GND")
		)
		(pad "K24" smd circle
			(at -0.94996 -14.249908)
			(size 0.4572 0.4572)
			(layers "F.Cu" "F.Mask" "F.Paste")
			(net "GND")
		)
		(pad "K25" smd circle
			(at 0 -14.249908)
			(size 0.4572 0.4572)
			(layers "F.Cu" "F.Mask" "F.Paste")
			(net "GND")
		)
		(pad "K26" smd circle
			(at 0.94996 -14.249908)
			(size 0.4572 0.4572)
			(layers "F.Cu" "F.Mask" "F.Paste")
			(net "GND")
		)
		(pad "K27" smd circle
			(at 1.89992 -14.249908)
			(size 0.4572 0.4572)
			(layers "F.Cu" "F.Mask" "F.Paste")
			(net "GND")
		)
		(pad "K28" smd circle
			(at 2.84988 -14.249908)
			(size 0.4572 0.4572)
			(layers "F.Cu" "F.Mask" "F.Paste")
			(net "GND")
		)
		(pad "K29" smd circle
			(at 3.800094 -14.249908)
			(size 0.4572 0.4572)
			(layers "F.Cu" "F.Mask" "F.Paste")
			(net "GND")
		)
		(pad "K30" smd circle
			(at 4.750054 -14.249908)
			(size 0.4572 0.4572)
			(layers "F.Cu" "F.Mask" "F.Paste")
			(net "GND")
		)
		(pad "K31" smd circle
			(at 5.700014 -14.249908)
			(size 0.4572 0.4572)
			(layers "F.Cu" "F.Mask" "F.Paste")
			(net "GND")
		)
		(pad "K32" smd circle
			(at 6.649974 -14.249908)
			(size 0.4572 0.4572)
			(layers "F.Cu" "F.Mask" "F.Paste")
			(net "GND")
		)
		(pad "K33" smd circle
			(at 7.599934 -14.249908)
			(size 0.4572 0.4572)
			(layers "F.Cu" "F.Mask" "F.Paste")
			(net "GND")
		)
		(pad "K34" smd circle
			(at 8.549894 -14.249908)
			(size 0.4572 0.4572)
			(layers "F.Cu" "F.Mask" "F.Paste")
			(net "GND")
		)
		(pad "K35" smd circle
			(at 9.500108 -14.249908)
			(size 0.4572 0.4572)
			(layers "F.Cu" "F.Mask" "F.Paste")
			(net "GND")
		)
		(pad "K36" smd circle
			(at 10.450068 -14.249908)
			(size 0.4572 0.4572)
			(layers "F.Cu" "F.Mask" "F.Paste")
			(net "GND")
		)
		(pad "K37" smd circle
			(at 11.400028 -14.249908)
			(size 0.4572 0.4572)
			(layers "F.Cu" "F.Mask" "F.Paste")
			(net "GND")
		)
		(pad "K38" smd circle
			(at 12.349988 -14.249908)
			(size 0.4572 0.4572)
			(layers "F.Cu" "F.Mask" "F.Paste")
			(net "GND")
		)
		(pad "K39" smd circle
			(at 13.299948 -14.249908)
			(size 0.4572 0.4572)
			(layers "F.Cu" "F.Mask" "F.Paste")
			(net "GND")
		)
		(pad "K40" smd circle
			(at 14.249908 -14.249908)
			(size 0.4572 0.4572)
			(layers "F.Cu" "F.Mask" "F.Paste")
			(net "GND")
		)
		(pad "K41" smd circle
			(at 15.200122 -14.249908)
			(size 0.4572 0.4572)
			(layers "F.Cu" "F.Mask" "F.Paste")
			(net "GND")
		)
		(pad "K42" smd circle
			(at 16.150082 -14.249908)
			(size 0.4572 0.4572)
			(layers "F.Cu" "F.Mask" "F.Paste")
			(net "GND")
		)
		(pad "K43" smd circle
			(at 17.100042 -14.249908)
			(size 0.4572 0.4572)
			(layers "F.Cu" "F.Mask" "F.Paste")
			(net "GND")
		)
		(pad "K44" smd circle
			(at 18.050002 -14.249908)
			(size 0.4572 0.4572)
			(layers "F.Cu" "F.Mask" "F.Paste")
			(net "GND")
		)
		(pad "K45" smd circle
			(at 18.999962 -14.249908)
			(size 0.4572 0.4572)
			(layers "F.Cu" "F.Mask" "F.Paste")
			(net "GND")
		)
		(pad "K46" smd circle
			(at 19.949922 -14.249908)
			(size 0.4572 0.4572)
			(layers "F.Cu" "F.Mask" "F.Paste")
			(net "GND")
		)
		(pad "K47" smd circle
			(at 20.899882 -14.249908)
			(size 0.4572 0.4572)
			(layers "F.Cu" "F.Mask" "F.Paste")
			(net "GND")
		)
		(pad "K48" smd circle
			(at 21.850096 -14.249908)
			(size 0.4572 0.4572)
			(layers "F.Cu" "F.Mask" "F.Paste")
			(net "P5E_PEX2_STN4_RX_DP<70>")
		)
		(pad "K49" smd circle
			(at 22.800056 -14.249908)
			(size 0.4572 0.4572)
			(layers "F.Cu" "F.Mask" "F.Paste")
			(net "P5E_PEX2_STN4_RX_DN<70>")
		)
		(pad "L1" smd circle
			(at -22.800056 -13.299948)
			(size 0.4572 0.4572)
			(layers "F.Cu" "F.Mask" "F.Paste")
			(net "GND")
		)
		(pad "L2" smd circle
			(at -21.850096 -13.299948)
			(size 0.4572 0.4572)
			(layers "F.Cu" "F.Mask" "F.Paste")
			(net "GND")
		)
		(pad "L3" smd circle
			(at -20.899882 -13.299948)
			(size 0.4572 0.4572)
			(layers "F.Cu" "F.Mask" "F.Paste")
			(net "P5E_PEX2_STN7_RX_DN<120>")
		)
		(pad "L4" smd circle
			(at -19.949922 -13.299948)
			(size 0.4572 0.4572)
			(layers "F.Cu" "F.Mask" "F.Paste")
			(net "P5E_PEX2_STN7_RX_DP<120>")
		)
		(pad "L5" smd circle
			(at -18.999962 -13.299948)
			(size 0.4572 0.4572)
			(layers "F.Cu" "F.Mask" "F.Paste")
			(net "GND")
		)
		(pad "L6" smd circle
			(at -18.050002 -13.299948)
			(size 0.4572 0.4572)
			(layers "F.Cu" "F.Mask" "F.Paste")
			(net "P5E_PEX2_STN7_TX_DN<120>")
		)
		(pad "L7" smd circle
			(at -17.100042 -13.299948)
			(size 0.4572 0.4572)
			(layers "F.Cu" "F.Mask" "F.Paste")
			(net "P5E_PEX2_STN7_TX_DP<120>")
		)
		(pad "L8" smd circle
			(at -16.150082 -13.299948)
			(size 0.4572 0.4572)
			(layers "F.Cu" "F.Mask" "F.Paste")
			(net "GND")
		)
		(pad "L9" smd circle
			(at -15.200122 -13.299948)
			(size 0.4572 0.4572)
			(layers "F.Cu" "F.Mask" "F.Paste")
			(net "GND")
		)
		(pad "L10" smd circle
			(at -14.249908 -13.299948)
			(size 0.4572 0.4572)
			(layers "F.Cu" "F.Mask" "F.Paste")
			(net "GND")
		)
		(pad "L11" smd circle
			(at -13.299948 -13.299948)
			(size 0.4572 0.4572)
			(layers "F.Cu" "F.Mask" "F.Paste")
			(net "GND")
		)
		(pad "L12" smd circle
			(at -12.349988 -13.299948)
			(size 0.4572 0.4572)
			(layers "F.Cu" "F.Mask" "F.Paste")
			(net "PEX2_DBG_MODE0")
		)
		(pad "L13" smd circle
			(at -11.400028 -13.299948)
			(size 0.4572 0.4572)
			(layers "F.Cu" "F.Mask" "F.Paste")
			(net "PEX2_DBG_MODE1")
		)
		(pad "L14" smd circle
			(at -10.450068 -13.299948)
			(size 0.4572 0.4572)
			(layers "F.Cu" "F.Mask" "F.Paste")
			(net "GND")
		)
		(pad "L15" smd circle
			(at -9.500108 -13.299948)
			(size 0.4572 0.4572)
			(layers "F.Cu" "F.Mask" "F.Paste")
			(net "PU_PEX2_ATPG_MODE_L")
		)
		(pad "L16" smd circle
			(at -8.549894 -13.299948)
			(size 0.4572 0.4572)
			(layers "F.Cu" "F.Mask" "F.Paste")
			(net "PU_PEX2_PAD_TRI_L")
		)
		(pad "L17" smd circle
			(at -7.599934 -13.299948)
			(size 0.4572 0.4572)
			(layers "F.Cu" "F.Mask" "F.Paste")
			(net "TP_PEX2_TDI")
		)
		(pad "L18" smd circle
			(at -6.649974 -13.299948)
			(size 0.4572 0.4572)
			(layers "F.Cu" "F.Mask" "F.Paste")
			(net "PEX2_DBG_SEL0")
		)
		(pad "L19" smd circle
			(at -5.700014 -13.299948)
			(size 0.4572 0.4572)
			(layers "F.Cu" "F.Mask" "F.Paste")
			(net "TP_PEX2_TDO")
		)
		(pad "L20" smd circle
			(at -4.750054 -13.299948)
			(size 0.4572 0.4572)
			(layers "F.Cu" "F.Mask" "F.Paste")
			(net "PU_PEX2_TR_TCK")
		)
		(pad "L21" smd circle
			(at -3.800094 -13.299948)
			(size 0.4572 0.4572)
			(layers "F.Cu" "F.Mask" "F.Paste")
			(net "GND")
		)
		(pad "L22" smd circle
			(at -2.84988 -13.299948)
			(size 0.4572 0.4572)
			(layers "F.Cu" "F.Mask" "F.Paste")
			(net "Net_5379")
		)
		(pad "L23" smd circle
			(at -1.89992 -13.299948)
			(size 0.4572 0.4572)
			(layers "F.Cu" "F.Mask" "F.Paste")
			(net "Net_5383")
		)
		(pad "L24" smd circle
			(at -0.94996 -13.299948)
			(size 0.4572 0.4572)
			(layers "F.Cu" "F.Mask" "F.Paste")
			(net "Net_5378")
		)
		(pad "L25" smd circle
			(at 0 -13.299948)
			(size 0.4572 0.4572)
			(layers "F.Cu" "F.Mask" "F.Paste")
			(net "PEX2_SPARE5")
		)
		(pad "L26" smd circle
			(at 0.94996 -13.299948)
			(size 0.4572 0.4572)
			(layers "F.Cu" "F.Mask" "F.Paste")
			(net "PU_PEX2_SIO_BLINK")
		)
		(pad "L27" smd circle
			(at 1.89992 -13.299948)
			(size 0.4572 0.4572)
			(layers "F.Cu" "F.Mask" "F.Paste")
			(net "PEX2_SPARE2")
		)
		(pad "L28" smd circle
			(at 2.84988 -13.299948)
			(size 0.4572 0.4572)
			(layers "F.Cu" "F.Mask" "F.Paste")
			(net "PEX2_SPARE6")
		)
		(pad "L29" smd circle
			(at 3.800094 -13.299948)
			(size 0.4572 0.4572)
			(layers "F.Cu" "F.Mask" "F.Paste")
			(net "Net_5368")
		)
		(pad "L30" smd circle
			(at 4.750054 -13.299948)
			(size 0.4572 0.4572)
			(layers "F.Cu" "F.Mask" "F.Paste")
			(net "PEX2_SPARE1")
		)
		(pad "L31" smd circle
			(at 5.700014 -13.299948)
			(size 0.4572 0.4572)
			(layers "F.Cu" "F.Mask" "F.Paste")
			(net "Net_5372")
		)
		(pad "L32" smd circle
			(at 6.649974 -13.299948)
			(size 0.4572 0.4572)
			(layers "F.Cu" "F.Mask" "F.Paste")
			(net "PEX2_SPARE3")
		)
		(pad "L33" smd circle
			(at 7.599934 -13.299948)
			(size 0.4572 0.4572)
			(layers "F.Cu" "F.Mask" "F.Paste")
			(net "Net_5364")
		)
		(pad "L34" smd circle
			(at 8.549894 -13.299948)
			(size 0.4572 0.4572)
			(layers "F.Cu" "F.Mask" "F.Paste")
			(net "SMB_PEX2_SLAVE1_SCL")
		)
		(pad "L35" smd circle
			(at 9.500108 -13.299948)
			(size 0.4572 0.4572)
			(layers "F.Cu" "F.Mask" "F.Paste")
			(net "Net_5361")
		)
		(pad "L36" smd circle
			(at 10.450068 -13.299948)
			(size 0.4572 0.4572)
			(layers "F.Cu" "F.Mask" "F.Paste")
			(net "Net_5391")
		)
		(pad "L37" smd circle
			(at 11.400028 -13.299948)
			(size 0.4572 0.4572)
			(layers "F.Cu" "F.Mask" "F.Paste")
			(net "PEX2_EXT_GPIO_LATCH_N")
		)
		(pad "L38" smd circle
			(at 12.349988 -13.299948)
			(size 0.4572 0.4572)
			(layers "F.Cu" "F.Mask" "F.Paste")
			(net "Net_5388")
		)
		(pad "L39" smd circle
			(at 13.299948 -13.299948)
			(size 0.4572 0.4572)
			(layers "F.Cu" "F.Mask" "F.Paste")
			(net "SMB_PEX2_SLAVE_SDA")
		)
		(pad "L40" smd circle
			(at 14.249908 -13.299948)
			(size 0.4572 0.4572)
			(layers "F.Cu" "F.Mask" "F.Paste")
			(net "GND")
		)
		(pad "L41" smd circle
			(at 15.200122 -13.299948)
			(size 0.4572 0.4572)
			(layers "F.Cu" "F.Mask" "F.Paste")
			(net "GND")
		)
		(pad "L42" smd circle
			(at 16.150082 -13.299948)
			(size 0.4572 0.4572)
			(layers "F.Cu" "F.Mask" "F.Paste")
			(net "GND")
		)
		(pad "L43" smd circle
			(at 17.100042 -13.299948)
			(size 0.4572 0.4572)
			(layers "F.Cu" "F.Mask" "F.Paste")
			(net "P5E_PEX2_STN4_TX_DP<69>")
		)
		(pad "L44" smd circle
			(at 18.050002 -13.299948)
			(size 0.4572 0.4572)
			(layers "F.Cu" "F.Mask" "F.Paste")
			(net "P5E_PEX2_STN4_TX_DN<69>")
		)
		(pad "L45" smd circle
			(at 18.999962 -13.299948)
			(size 0.4572 0.4572)
			(layers "F.Cu" "F.Mask" "F.Paste")
			(net "GND")
		)
		(pad "L46" smd circle
			(at 19.949922 -13.299948)
			(size 0.4572 0.4572)
			(layers "F.Cu" "F.Mask" "F.Paste")
			(net "P5E_PEX2_STN4_RX_DP<69>")
		)
		(pad "L47" smd circle
			(at 20.899882 -13.299948)
			(size 0.4572 0.4572)
			(layers "F.Cu" "F.Mask" "F.Paste")
			(net "P5E_PEX2_STN4_RX_DN<69>")
		)
		(pad "L48" smd circle
			(at 21.850096 -13.299948)
			(size 0.4572 0.4572)
			(layers "F.Cu" "F.Mask" "F.Paste")
			(net "GND")
		)
		(pad "L49" smd circle
			(at 22.800056 -13.299948)
			(size 0.4572 0.4572)
			(layers "F.Cu" "F.Mask" "F.Paste")
			(net "GND")
		)
		(pad "M1" smd circle
			(at -22.800056 -12.349988)
			(size 0.4572 0.4572)
			(layers "F.Cu" "F.Mask" "F.Paste")
			(net "P5E_PEX2_STN7_RX_DN<119>")
		)
		(pad "M2" smd circle
			(at -21.850096 -12.349988)
			(size 0.4572 0.4572)
			(layers "F.Cu" "F.Mask" "F.Paste")
			(net "P5E_PEX2_STN7_RX_DP<119>")
		)
		(pad "M3" smd circle
			(at -20.899882 -12.349988)
			(size 0.4572 0.4572)
			(layers "F.Cu" "F.Mask" "F.Paste")
			(net "GND")
		)
		(pad "M4" smd circle
			(at -19.949922 -12.349988)
			(size 0.4572 0.4572)
			(layers "F.Cu" "F.Mask" "F.Paste")
			(net "GND")
		)
		(pad "M5" smd circle
			(at -18.999962 -12.349988)
			(size 0.4572 0.4572)
			(layers "F.Cu" "F.Mask" "F.Paste")
			(net "GND")
		)
		(pad "M6" smd circle
			(at -18.050002 -12.349988)
			(size 0.4572 0.4572)
			(layers "F.Cu" "F.Mask" "F.Paste")
			(net "GND")
		)
		(pad "M7" smd circle
			(at -17.100042 -12.349988)
			(size 0.4572 0.4572)
			(layers "F.Cu" "F.Mask" "F.Paste")
			(net "GND")
		)
		(pad "M8" smd circle
			(at -16.150082 -12.349988)
			(size 0.4572 0.4572)
			(layers "F.Cu" "F.Mask" "F.Paste")
			(net "P5E_PEX2_STN7_TX_DN<119>")
		)
		(pad "M9" smd circle
			(at -15.200122 -12.349988)
			(size 0.4572 0.4572)
			(layers "F.Cu" "F.Mask" "F.Paste")
			(net "P5E_PEX2_STN7_TX_DP<119>")
		)
		(pad "M10" smd circle
			(at -14.249908 -12.349988)
			(size 0.4572 0.4572)
			(layers "F.Cu" "F.Mask" "F.Paste")
			(net "GND")
		)
		(pad "M11" smd circle
			(at -13.299948 -12.349988)
			(size 0.4572 0.4572)
			(layers "F.Cu" "F.Mask" "F.Paste")
			(net "GND")
		)
		(pad "M12" smd circle
			(at -12.349988 -12.349988)
			(size 0.4572 0.4572)
			(layers "F.Cu" "F.Mask" "F.Paste")
			(net "GND")
		)
		(pad "M13" smd circle
			(at -11.400028 -12.349988)
			(size 0.4572 0.4572)
			(layers "F.Cu" "F.Mask" "F.Paste")
			(net "IRQ_PEX2_CLKREQ_INT_N")
		)
		(pad "M14" smd circle
			(at -10.450068 -12.349988)
			(size 0.4572 0.4572)
			(layers "F.Cu" "F.Mask" "F.Paste")
			(net "GND")
		)
		(pad "M15" smd circle
			(at -9.500108 -12.349988)
			(size 0.4572 0.4572)
			(layers "F.Cu" "F.Mask" "F.Paste")
			(net "TP_PEX2_TCK")
		)
		(pad "M16" smd circle
			(at -8.549894 -12.349988)
			(size 0.4572 0.4572)
			(layers "F.Cu" "F.Mask" "F.Paste")
			(net "PEX2_DFT_IDDT")
		)
		(pad "M17" smd circle
			(at -7.599934 -12.349988)
			(size 0.4572 0.4572)
			(layers "F.Cu" "F.Mask" "F.Paste")
			(net "RST_PEX2_SYS_N")
		)
		(pad "M18" smd circle
			(at -6.649974 -12.349988)
			(size 0.4572 0.4572)
			(layers "F.Cu" "F.Mask" "F.Paste")
			(net "TP_PEX2_TRST_L")
		)
		(pad "M19" smd circle
			(at -5.700014 -12.349988)
			(size 0.4572 0.4572)
			(layers "F.Cu" "F.Mask" "F.Paste")
			(net "PEX2_DBG_SEL1")
		)
		(pad "M20" smd circle
			(at -4.750054 -12.349988)
			(size 0.4572 0.4572)
			(layers "F.Cu" "F.Mask" "F.Paste")
			(net "TP_PEX2_TMS")
		)
		(pad "M21" smd circle
			(at -3.800094 -12.349988)
			(size 0.4572 0.4572)
			(layers "F.Cu" "F.Mask" "F.Paste")
			(net "GND")
		)
		(pad "M22" smd circle
			(at -2.84988 -12.349988)
			(size 0.4572 0.4572)
			(layers "F.Cu" "F.Mask" "F.Paste")
			(net "Net_5381")
		)
		(pad "M23" smd circle
			(at -1.89992 -12.349988)
			(size 0.4572 0.4572)
			(layers "F.Cu" "F.Mask" "F.Paste")
			(net "Net_5382")
		)
		(pad "M24" smd circle
			(at -0.94996 -12.349988)
			(size 0.4572 0.4572)
			(layers "F.Cu" "F.Mask" "F.Paste")
			(net "Net_5384")
		)
		(pad "M25" smd circle
			(at 0 -12.349988)
			(size 0.4572 0.4572)
			(layers "F.Cu" "F.Mask" "F.Paste")
			(net "PEX2_SPARE4")
		)
		(pad "M26" smd circle
			(at 0.94996 -12.349988)
			(size 0.4572 0.4572)
			(layers "F.Cu" "F.Mask" "F.Paste")
			(net "PEX2_SPARE0")
		)
		(pad "M27" smd circle
			(at 1.89992 -12.349988)
			(size 0.4572 0.4572)
			(layers "F.Cu" "F.Mask" "F.Paste")
			(net "PEX2_SPARE7")
		)
		(pad "M28" smd circle
			(at 2.84988 -12.349988)
			(size 0.4572 0.4572)
			(layers "F.Cu" "F.Mask" "F.Paste")
			(net "I2C0_PEX2_SHPC_SDA")
		)
		(pad "M29" smd circle
			(at 3.800094 -12.349988)
			(size 0.4572 0.4572)
			(layers "F.Cu" "F.Mask" "F.Paste")
			(net "I2C0_PEX2_SHPC_SCL")
		)
		(pad "M30" smd circle
			(at 4.750054 -12.349988)
			(size 0.4572 0.4572)
			(layers "F.Cu" "F.Mask" "F.Paste")
			(net "Net_5362")
		)
		(pad "M31" smd circle
			(at 5.700014 -12.349988)
			(size 0.4572 0.4572)
			(layers "F.Cu" "F.Mask" "F.Paste")
			(net "Net_5363")
		)
		(pad "M32" smd circle
			(at 6.649974 -12.349988)
			(size 0.4572 0.4572)
			(layers "F.Cu" "F.Mask" "F.Paste")
			(net "Net_5373")
		)
		(pad "M33" smd circle
			(at 7.599934 -12.349988)
			(size 0.4572 0.4572)
			(layers "F.Cu" "F.Mask" "F.Paste")
			(net "Net_5367")
		)
		(pad "M34" smd circle
			(at 8.549894 -12.349988)
			(size 0.4572 0.4572)
			(layers "F.Cu" "F.Mask" "F.Paste")
			(net "Net_5371")
		)
		(pad "M35" smd circle
			(at 9.500108 -12.349988)
			(size 0.4572 0.4572)
			(layers "F.Cu" "F.Mask" "F.Paste")
			(net "I2C0_PEX2_SCL")
		)
		(pad "M36" smd circle
			(at 10.450068 -12.349988)
			(size 0.4572 0.4572)
			(layers "F.Cu" "F.Mask" "F.Paste")
			(net "Net_5390")
		)
		(pad "M37" smd circle
			(at 11.400028 -12.349988)
			(size 0.4572 0.4572)
			(layers "F.Cu" "F.Mask" "F.Paste")
			(net "Net_5389")
		)
		(pad "M38" smd circle
			(at 12.349988 -12.349988)
			(size 0.4572 0.4572)
			(layers "F.Cu" "F.Mask" "F.Paste")
			(net "SMB_PEX2_SLAVE1_SDA")
		)
		(pad "M39" smd circle
			(at 13.299948 -12.349988)
			(size 0.4572 0.4572)
			(layers "F.Cu" "F.Mask" "F.Paste")
			(net "I2C0_PEX2_SDA")
		)
		(pad "M40" smd circle
			(at 14.249908 -12.349988)
			(size 0.4572 0.4572)
			(layers "F.Cu" "F.Mask" "F.Paste")
			(net "GND")
		)
		(pad "M41" smd circle
			(at 15.200122 -12.349988)
			(size 0.4572 0.4572)
			(layers "F.Cu" "F.Mask" "F.Paste")
			(net "P5E_PEX2_STN4_TX_DP<68>")
		)
		(pad "M42" smd circle
			(at 16.150082 -12.349988)
			(size 0.4572 0.4572)
			(layers "F.Cu" "F.Mask" "F.Paste")
			(net "P5E_PEX2_STN4_TX_DN<68>")
		)
		(pad "M43" smd circle
			(at 17.100042 -12.349988)
			(size 0.4572 0.4572)
			(layers "F.Cu" "F.Mask" "F.Paste")
			(net "GND")
		)
		(pad "M44" smd circle
			(at 18.050002 -12.349988)
			(size 0.4572 0.4572)
			(layers "F.Cu" "F.Mask" "F.Paste")
			(net "GND")
		)
		(pad "M45" smd circle
			(at 18.999962 -12.349988)
			(size 0.4572 0.4572)
			(layers "F.Cu" "F.Mask" "F.Paste")
			(net "GND")
		)
		(pad "M46" smd circle
			(at 19.949922 -12.349988)
			(size 0.4572 0.4572)
			(layers "F.Cu" "F.Mask" "F.Paste")
			(net "GND")
		)
		(pad "M47" smd circle
			(at 20.899882 -12.349988)
			(size 0.4572 0.4572)
			(layers "F.Cu" "F.Mask" "F.Paste")
			(net "GND")
		)
		(pad "M48" smd circle
			(at 21.850096 -12.349988)
			(size 0.4572 0.4572)
			(layers "F.Cu" "F.Mask" "F.Paste")
			(net "P5E_PEX2_STN4_RX_DP<68>")
		)
		(pad "M49" smd circle
			(at 22.800056 -12.349988)
			(size 0.4572 0.4572)
			(layers "F.Cu" "F.Mask" "F.Paste")
			(net "P5E_PEX2_STN4_RX_DN<68>")
		)
		(pad "N1" smd circle
			(at -22.800056 -11.400028)
			(size 0.4572 0.4572)
			(layers "F.Cu" "F.Mask" "F.Paste")
			(net "GND")
		)
		(pad "N2" smd circle
			(at -21.850096 -11.400028)
			(size 0.4572 0.4572)
			(layers "F.Cu" "F.Mask" "F.Paste")
			(net "GND")
		)
		(pad "N3" smd circle
			(at -20.899882 -11.400028)
			(size 0.4572 0.4572)
			(layers "F.Cu" "F.Mask" "F.Paste")
			(net "P5E_PEX2_STN7_RX_DN<118>")
		)
		(pad "N4" smd circle
			(at -19.949922 -11.400028)
			(size 0.4572 0.4572)
			(layers "F.Cu" "F.Mask" "F.Paste")
			(net "P5E_PEX2_STN7_RX_DP<118>")
		)
		(pad "N5" smd circle
			(at -18.999962 -11.400028)
			(size 0.4572 0.4572)
			(layers "F.Cu" "F.Mask" "F.Paste")
			(net "GND")
		)
		(pad "N6" smd circle
			(at -18.050002 -11.400028)
			(size 0.4572 0.4572)
			(layers "F.Cu" "F.Mask" "F.Paste")
			(net "P5E_PEX2_STN7_TX_DN<118>")
		)
		(pad "N7" smd circle
			(at -17.100042 -11.400028)
			(size 0.4572 0.4572)
			(layers "F.Cu" "F.Mask" "F.Paste")
			(net "P5E_PEX2_STN7_TX_DP<118>")
		)
		(pad "N8" smd circle
			(at -16.150082 -11.400028)
			(size 0.4572 0.4572)
			(layers "F.Cu" "F.Mask" "F.Paste")
			(net "GND")
		)
		(pad "N9" smd circle
			(at -15.200122 -11.400028)
			(size 0.4572 0.4572)
			(layers "F.Cu" "F.Mask" "F.Paste")
			(net "GND")
		)
		(pad "N10" smd circle
			(at -14.249908 -11.400028)
			(size 0.4572 0.4572)
			(layers "F.Cu" "F.Mask" "F.Paste")
			(net "GND")
		)
		(pad "N11" smd circle
			(at -13.299948 -11.400028)
			(size 0.4572 0.4572)
			(layers "F.Cu" "F.Mask" "F.Paste")
			(net "GND")
		)
		(pad "N12" smd circle
			(at -12.349988 -11.400028)
			(size 0.4572 0.4572)
			(layers "F.Cu" "F.Mask" "F.Paste")
			(net "GND")
		)
		(pad "N13" smd circle
			(at -11.400028 -11.400028)
			(size 0.4572 0.4572)
			(layers "F.Cu" "F.Mask" "F.Paste")
			(net "GND")
		)
		(pad "N14" smd circle
			(at -10.450068 -11.400028)
			(size 0.4572 0.4572)
			(layers "F.Cu" "F.Mask" "F.Paste")
			(net "GND")
		)
		(pad "N15" smd circle
			(at -9.500108 -11.400028)
			(size 0.4572 0.4572)
			(layers "F.Cu" "F.Mask" "F.Paste")
			(net "GND")
		)
		(pad "N16" smd circle
			(at -8.549894 -11.400028)
			(size 0.4572 0.4572)
			(layers "F.Cu" "F.Mask" "F.Paste")
			(net "GND")
		)
		(pad "N17" smd circle
			(at -7.599934 -11.400028)
			(size 0.4572 0.4572)
			(layers "F.Cu" "F.Mask" "F.Paste")
			(net "GND")
		)
		(pad "N18" smd circle
			(at -6.649974 -11.400028)
			(size 0.4572 0.4572)
			(layers "F.Cu" "F.Mask" "F.Paste")
			(net "GND")
		)
		(pad "N19" smd circle
			(at -5.700014 -11.400028)
			(size 0.4572 0.4572)
			(layers "F.Cu" "F.Mask" "F.Paste")
			(net "GND")
		)
		(pad "N20" smd circle
			(at -4.750054 -11.400028)
			(size 0.4572 0.4572)
			(layers "F.Cu" "F.Mask" "F.Paste")
			(net "GND")
		)
		(pad "N21" smd circle
			(at -3.800094 -11.400028)
			(size 0.4572 0.4572)
			(layers "F.Cu" "F.Mask" "F.Paste")
			(net "GND")
		)
		(pad "N22" smd circle
			(at -2.84988 -11.400028)
			(size 0.4572 0.4572)
			(layers "F.Cu" "F.Mask" "F.Paste")
			(net "GND")
		)
		(pad "N23" smd circle
			(at -1.89992 -11.400028)
			(size 0.4572 0.4572)
			(layers "F.Cu" "F.Mask" "F.Paste")
			(net "GND")
		)
		(pad "N24" smd circle
			(at -0.94996 -11.400028)
			(size 0.4572 0.4572)
			(layers "F.Cu" "F.Mask" "F.Paste")
			(net "GND")
		)
		(pad "N25" smd circle
			(at 0 -11.400028)
			(size 0.4572 0.4572)
			(layers "F.Cu" "F.Mask" "F.Paste")
			(net "GND")
		)
		(pad "N26" smd circle
			(at 0.94996 -11.400028)
			(size 0.4572 0.4572)
			(layers "F.Cu" "F.Mask" "F.Paste")
			(net "GND")
		)
		(pad "N27" smd circle
			(at 1.89992 -11.400028)
			(size 0.4572 0.4572)
			(layers "F.Cu" "F.Mask" "F.Paste")
			(net "GND")
		)
		(pad "N28" smd circle
			(at 2.84988 -11.400028)
			(size 0.4572 0.4572)
			(layers "F.Cu" "F.Mask" "F.Paste")
			(net "GND")
		)
		(pad "N29" smd circle
			(at 3.800094 -11.400028)
			(size 0.4572 0.4572)
			(layers "F.Cu" "F.Mask" "F.Paste")
			(net "GND")
		)
		(pad "N30" smd circle
			(at 4.750054 -11.400028)
			(size 0.4572 0.4572)
			(layers "F.Cu" "F.Mask" "F.Paste")
			(net "GND")
		)
		(pad "N31" smd circle
			(at 5.700014 -11.400028)
			(size 0.4572 0.4572)
			(layers "F.Cu" "F.Mask" "F.Paste")
			(net "GND")
		)
		(pad "N32" smd circle
			(at 6.649974 -11.400028)
			(size 0.4572 0.4572)
			(layers "F.Cu" "F.Mask" "F.Paste")
			(net "GND")
		)
		(pad "N33" smd circle
			(at 7.599934 -11.400028)
			(size 0.4572 0.4572)
			(layers "F.Cu" "F.Mask" "F.Paste")
			(net "GND")
		)
		(pad "N34" smd circle
			(at 8.549894 -11.400028)
			(size 0.4572 0.4572)
			(layers "F.Cu" "F.Mask" "F.Paste")
			(net "GND")
		)
		(pad "N35" smd circle
			(at 9.500108 -11.400028)
			(size 0.4572 0.4572)
			(layers "F.Cu" "F.Mask" "F.Paste")
			(net "GND")
		)
		(pad "N36" smd circle
			(at 10.450068 -11.400028)
			(size 0.4572 0.4572)
			(layers "F.Cu" "F.Mask" "F.Paste")
			(net "GND")
		)
		(pad "N37" smd circle
			(at 11.400028 -11.400028)
			(size 0.4572 0.4572)
			(layers "F.Cu" "F.Mask" "F.Paste")
			(net "GND")
		)
		(pad "N38" smd circle
			(at 12.349988 -11.400028)
			(size 0.4572 0.4572)
			(layers "F.Cu" "F.Mask" "F.Paste")
			(net "SMB_PEX2_SLAVE_SCL")
		)
		(pad "N39" smd circle
			(at 13.299948 -11.400028)
			(size 0.4572 0.4572)
			(layers "F.Cu" "F.Mask" "F.Paste")
			(net "Net_5370")
		)
		(pad "N40" smd circle
			(at 14.249908 -11.400028)
			(size 0.4572 0.4572)
			(layers "F.Cu" "F.Mask" "F.Paste")
			(net "GND")
		)
		(pad "N41" smd circle
			(at 15.200122 -11.400028)
			(size 0.4572 0.4572)
			(layers "F.Cu" "F.Mask" "F.Paste")
			(net "GND")
		)
		(pad "N42" smd circle
			(at 16.150082 -11.400028)
			(size 0.4572 0.4572)
			(layers "F.Cu" "F.Mask" "F.Paste")
			(net "GND")
		)
		(pad "N43" smd circle
			(at 17.100042 -11.400028)
			(size 0.4572 0.4572)
			(layers "F.Cu" "F.Mask" "F.Paste")
			(net "P5E_PEX2_STN4_TX_DP<67>")
		)
		(pad "N44" smd circle
			(at 18.050002 -11.400028)
			(size 0.4572 0.4572)
			(layers "F.Cu" "F.Mask" "F.Paste")
			(net "P5E_PEX2_STN4_TX_DN<67>")
		)
		(pad "N45" smd circle
			(at 18.999962 -11.400028)
			(size 0.4572 0.4572)
			(layers "F.Cu" "F.Mask" "F.Paste")
			(net "GND")
		)
		(pad "N46" smd circle
			(at 19.949922 -11.400028)
			(size 0.4572 0.4572)
			(layers "F.Cu" "F.Mask" "F.Paste")
			(net "P5E_PEX2_STN4_RX_DP<67>")
		)
		(pad "N47" smd circle
			(at 20.899882 -11.400028)
			(size 0.4572 0.4572)
			(layers "F.Cu" "F.Mask" "F.Paste")
			(net "P5E_PEX2_STN4_RX_DN<67>")
		)
		(pad "N48" smd circle
			(at 21.850096 -11.400028)
			(size 0.4572 0.4572)
			(layers "F.Cu" "F.Mask" "F.Paste")
			(net "GND")
		)
		(pad "N49" smd circle
			(at 22.800056 -11.400028)
			(size 0.4572 0.4572)
			(layers "F.Cu" "F.Mask" "F.Paste")
			(net "GND")
		)
		(pad "P1" smd circle
			(at -22.800056 -10.450068)
			(size 0.4572 0.4572)
			(layers "F.Cu" "F.Mask" "F.Paste")
			(net "P5E_PEX2_STN7_RX_DN<117>")
		)
		(pad "P2" smd circle
			(at -21.850096 -10.450068)
			(size 0.4572 0.4572)
			(layers "F.Cu" "F.Mask" "F.Paste")
			(net "P5E_PEX2_STN7_RX_DP<117>")
		)
		(pad "P3" smd circle
			(at -20.899882 -10.450068)
			(size 0.4572 0.4572)
			(layers "F.Cu" "F.Mask" "F.Paste")
			(net "GND")
		)
		(pad "P4" smd circle
			(at -19.949922 -10.450068)
			(size 0.4572 0.4572)
			(layers "F.Cu" "F.Mask" "F.Paste")
			(net "GND")
		)
		(pad "P5" smd circle
			(at -18.999962 -10.450068)
			(size 0.4572 0.4572)
			(layers "F.Cu" "F.Mask" "F.Paste")
			(net "GND")
		)
		(pad "P6" smd circle
			(at -18.050002 -10.450068)
			(size 0.4572 0.4572)
			(layers "F.Cu" "F.Mask" "F.Paste")
			(net "GND")
		)
		(pad "P7" smd circle
			(at -17.100042 -10.450068)
			(size 0.4572 0.4572)
			(layers "F.Cu" "F.Mask" "F.Paste")
			(net "GND")
		)
		(pad "P8" smd circle
			(at -16.150082 -10.450068)
			(size 0.4572 0.4572)
			(layers "F.Cu" "F.Mask" "F.Paste")
			(net "P5E_PEX2_STN7_TX_DN<117>")
		)
		(pad "P9" smd circle
			(at -15.200122 -10.450068)
			(size 0.4572 0.4572)
			(layers "F.Cu" "F.Mask" "F.Paste")
			(net "P5E_PEX2_STN7_TX_DP<117>")
		)
		(pad "P10" smd circle
			(at -14.249908 -10.450068)
			(size 0.4572 0.4572)
			(layers "F.Cu" "F.Mask" "F.Paste")
			(net "GND")
		)
		(pad "P11" smd circle
			(at -13.299948 -10.450068)
			(size 0.4572 0.4572)
			(layers "F.Cu" "F.Mask" "F.Paste")
			(net "GND")
		)
		(pad "P12" smd circle
			(at -12.349988 -10.450068)
			(size 0.4572 0.4572)
			(layers "F.Cu" "F.Mask" "F.Paste")
			(net "GND")
		)
		(pad "P13" smd circle
			(at -11.400028 -10.450068)
			(size 0.4572 0.4572)
			(layers "F.Cu" "F.Mask" "F.Paste")
			(net "GND")
		)
		(pad "P14" smd circle
			(at -10.450068 -10.450068)
			(size 0.4572 0.4572)
			(layers "F.Cu" "F.Mask" "F.Paste")
			(net "GND")
		)
		(pad "P15" smd circle
			(at -9.500108 -10.450068)
			(size 0.4572 0.4572)
			(layers "F.Cu" "F.Mask" "F.Paste")
			(net "GND")
		)
		(pad "P16" smd circle
			(at -8.549894 -10.450068)
			(size 0.4572 0.4572)
			(layers "F.Cu" "F.Mask" "F.Paste")
			(net "GND")
		)
		(pad "P17" smd circle
			(at -7.599934 -10.450068)
			(size 0.4572 0.4572)
			(layers "F.Cu" "F.Mask" "F.Paste")
			(net "GND")
		)
		(pad "P18" smd circle
			(at -6.649974 -10.450068)
			(size 0.4572 0.4572)
			(layers "F.Cu" "F.Mask" "F.Paste")
			(net "GND")
		)
		(pad "P19" smd circle
			(at -5.700014 -10.450068)
			(size 0.4572 0.4572)
			(layers "F.Cu" "F.Mask" "F.Paste")
			(net "GND")
		)
		(pad "P20" smd circle
			(at -4.750054 -10.450068)
			(size 0.4572 0.4572)
			(layers "F.Cu" "F.Mask" "F.Paste")
			(net "GND")
		)
		(pad "P21" smd circle
			(at -3.800094 -10.450068)
			(size 0.4572 0.4572)
			(layers "F.Cu" "F.Mask" "F.Paste")
			(net "GND")
		)
		(pad "P22" smd circle
			(at -2.84988 -10.450068)
			(size 0.4572 0.4572)
			(layers "F.Cu" "F.Mask" "F.Paste")
			(net "GND")
		)
		(pad "P23" smd circle
			(at -1.89992 -10.450068)
			(size 0.4572 0.4572)
			(layers "F.Cu" "F.Mask" "F.Paste")
			(net "GND")
		)
		(pad "P24" smd circle
			(at -0.94996 -10.450068)
			(size 0.4572 0.4572)
			(layers "F.Cu" "F.Mask" "F.Paste")
			(net "GND")
		)
		(pad "P25" smd circle
			(at 0 -10.450068)
			(size 0.4572 0.4572)
			(layers "F.Cu" "F.Mask" "F.Paste")
			(net "GND")
		)
		(pad "P26" smd circle
			(at 0.94996 -10.450068)
			(size 0.4572 0.4572)
			(layers "F.Cu" "F.Mask" "F.Paste")
			(net "GND")
		)
		(pad "P27" smd circle
			(at 1.89992 -10.450068)
			(size 0.4572 0.4572)
			(layers "F.Cu" "F.Mask" "F.Paste")
			(net "GND")
		)
		(pad "P28" smd circle
			(at 2.84988 -10.450068)
			(size 0.4572 0.4572)
			(layers "F.Cu" "F.Mask" "F.Paste")
			(net "GND")
		)
		(pad "P29" smd circle
			(at 3.800094 -10.450068)
			(size 0.4572 0.4572)
			(layers "F.Cu" "F.Mask" "F.Paste")
			(net "GND")
		)
		(pad "P30" smd circle
			(at 4.750054 -10.450068)
			(size 0.4572 0.4572)
			(layers "F.Cu" "F.Mask" "F.Paste")
			(net "GND")
		)
		(pad "P31" smd circle
			(at 5.700014 -10.450068)
			(size 0.4572 0.4572)
			(layers "F.Cu" "F.Mask" "F.Paste")
			(net "GND")
		)
		(pad "P32" smd circle
			(at 6.649974 -10.450068)
			(size 0.4572 0.4572)
			(layers "F.Cu" "F.Mask" "F.Paste")
			(net "GND")
		)
		(pad "P33" smd circle
			(at 7.599934 -10.450068)
			(size 0.4572 0.4572)
			(layers "F.Cu" "F.Mask" "F.Paste")
			(net "GND")
		)
		(pad "P34" smd circle
			(at 8.549894 -10.450068)
			(size 0.4572 0.4572)
			(layers "F.Cu" "F.Mask" "F.Paste")
			(net "GND")
		)
		(pad "P35" smd circle
			(at 9.500108 -10.450068)
			(size 0.4572 0.4572)
			(layers "F.Cu" "F.Mask" "F.Paste")
			(net "GND")
		)
		(pad "P36" smd circle
			(at 10.450068 -10.450068)
			(size 0.4572 0.4572)
			(layers "F.Cu" "F.Mask" "F.Paste")
			(net "Net_517")
		)
		(pad "P37" smd circle
			(at 11.400028 -10.450068)
			(size 0.4572 0.4572)
			(layers "F.Cu" "F.Mask" "F.Paste")
			(net "GND")
		)
		(pad "P38" smd circle
			(at 12.349988 -10.450068)
			(size 0.4572 0.4572)
			(layers "F.Cu" "F.Mask" "F.Paste")
			(net "RST_PEX2_S3_PERST_R_N")
		)
		(pad "P39" smd circle
			(at 13.299948 -10.450068)
			(size 0.4572 0.4572)
			(layers "F.Cu" "F.Mask" "F.Paste")
			(net "RST_PEX2_S1_PERST_R_N")
		)
		(pad "P40" smd circle
			(at 14.249908 -10.450068)
			(size 0.4572 0.4572)
			(layers "F.Cu" "F.Mask" "F.Paste")
			(net "GND")
		)
		(pad "P41" smd circle
			(at 15.200122 -10.450068)
			(size 0.4572 0.4572)
			(layers "F.Cu" "F.Mask" "F.Paste")
			(net "P5E_PEX2_STN4_TX_DP<66>")
		)
		(pad "P42" smd circle
			(at 16.150082 -10.450068)
			(size 0.4572 0.4572)
			(layers "F.Cu" "F.Mask" "F.Paste")
			(net "P5E_PEX2_STN4_TX_DN<66>")
		)
		(pad "P43" smd circle
			(at 17.100042 -10.450068)
			(size 0.4572 0.4572)
			(layers "F.Cu" "F.Mask" "F.Paste")
			(net "GND")
		)
		(pad "P44" smd circle
			(at 18.050002 -10.450068)
			(size 0.4572 0.4572)
			(layers "F.Cu" "F.Mask" "F.Paste")
			(net "GND")
		)
		(pad "P45" smd circle
			(at 18.999962 -10.450068)
			(size 0.4572 0.4572)
			(layers "F.Cu" "F.Mask" "F.Paste")
			(net "GND")
		)
		(pad "P46" smd circle
			(at 19.949922 -10.450068)
			(size 0.4572 0.4572)
			(layers "F.Cu" "F.Mask" "F.Paste")
			(net "GND")
		)
		(pad "P47" smd circle
			(at 20.899882 -10.450068)
			(size 0.4572 0.4572)
			(layers "F.Cu" "F.Mask" "F.Paste")
			(net "GND")
		)
		(pad "P48" smd circle
			(at 21.850096 -10.450068)
			(size 0.4572 0.4572)
			(layers "F.Cu" "F.Mask" "F.Paste")
			(net "P5E_PEX2_STN4_RX_DP<66>")
		)
		(pad "P49" smd circle
			(at 22.800056 -10.450068)
			(size 0.4572 0.4572)
			(layers "F.Cu" "F.Mask" "F.Paste")
			(net "P5E_PEX2_STN4_RX_DN<66>")
		)
		(pad "R1" smd circle
			(at -22.800056 -9.500108)
			(size 0.4572 0.4572)
			(layers "F.Cu" "F.Mask" "F.Paste")
			(net "GND")
		)
		(pad "R2" smd circle
			(at -21.850096 -9.500108)
			(size 0.4572 0.4572)
			(layers "F.Cu" "F.Mask" "F.Paste")
			(net "GND")
		)
		(pad "R3" smd circle
			(at -20.899882 -9.500108)
			(size 0.4572 0.4572)
			(layers "F.Cu" "F.Mask" "F.Paste")
			(net "P5E_PEX2_STN7_RX_DN<116>")
		)
		(pad "R4" smd circle
			(at -19.949922 -9.500108)
			(size 0.4572 0.4572)
			(layers "F.Cu" "F.Mask" "F.Paste")
			(net "P5E_PEX2_STN7_RX_DP<116>")
		)
		(pad "R5" smd circle
			(at -18.999962 -9.500108)
			(size 0.4572 0.4572)
			(layers "F.Cu" "F.Mask" "F.Paste")
			(net "GND")
		)
		(pad "R6" smd circle
			(at -18.050002 -9.500108)
			(size 0.4572 0.4572)
			(layers "F.Cu" "F.Mask" "F.Paste")
			(net "P5E_PEX2_STN7_TX_DN<116>")
		)
		(pad "R7" smd circle
			(at -17.100042 -9.500108)
			(size 0.4572 0.4572)
			(layers "F.Cu" "F.Mask" "F.Paste")
			(net "P5E_PEX2_STN7_TX_DP<116>")
		)
		(pad "R8" smd circle
			(at -16.150082 -9.500108)
			(size 0.4572 0.4572)
			(layers "F.Cu" "F.Mask" "F.Paste")
			(net "GND")
		)
		(pad "R9" smd circle
			(at -15.200122 -9.500108)
			(size 0.4572 0.4572)
			(layers "F.Cu" "F.Mask" "F.Paste")
			(net "GND")
		)
		(pad "R10" smd circle
			(at -14.249908 -9.500108)
			(size 0.4572 0.4572)
			(layers "F.Cu" "F.Mask" "F.Paste")
			(net "GND")
		)
		(pad "R11" smd circle
			(at -13.299948 -9.500108)
			(size 0.4572 0.4572)
			(layers "F.Cu" "F.Mask" "F.Paste")
			(net "GND")
		)
		(pad "R12" smd circle
			(at -12.349988 -9.500108)
			(size 0.4572 0.4572)
			(layers "F.Cu" "F.Mask" "F.Paste")
			(net "GND")
		)
		(pad "R13" smd circle
			(at -11.400028 -9.500108)
			(size 0.4572 0.4572)
			(layers "F.Cu" "F.Mask" "F.Paste")
			(net "GND")
		)
		(pad "R14" smd circle
			(at -10.450068 -9.500108)
			(size 0.4572 0.4572)
			(layers "F.Cu" "F.Mask" "F.Paste")
			(net "GND")
		)
		(pad "R15" smd circle
			(at -9.500108 -9.500108)
			(size 0.4572 0.4572)
			(layers "F.Cu" "F.Mask" "F.Paste")
			(net "GND")
		)
		(pad "R16" smd circle
			(at -8.549894 -9.500108)
			(size 0.4572 0.4572)
			(layers "F.Cu" "F.Mask" "F.Paste")
			(net "GND")
		)
		(pad "R17" smd circle
			(at -7.599934 -9.500108)
			(size 0.4572 0.4572)
			(layers "F.Cu" "F.Mask" "F.Paste")
			(net "GND")
		)
		(pad "R18" smd circle
			(at -6.649974 -9.500108)
			(size 0.4572 0.4572)
			(layers "F.Cu" "F.Mask" "F.Paste")
			(net "GND")
		)
		(pad "R19" smd circle
			(at -5.700014 -9.500108)
			(size 0.4572 0.4572)
			(layers "F.Cu" "F.Mask" "F.Paste")
			(net "GND")
		)
		(pad "R20" smd circle
			(at -4.750054 -9.500108)
			(size 0.4572 0.4572)
			(layers "F.Cu" "F.Mask" "F.Paste")
			(net "GND")
		)
		(pad "R21" smd circle
			(at -3.800094 -9.500108)
			(size 0.4572 0.4572)
			(layers "F.Cu" "F.Mask" "F.Paste")
			(net "GND")
		)
		(pad "R22" smd circle
			(at -2.84988 -9.500108)
			(size 0.4572 0.4572)
			(layers "F.Cu" "F.Mask" "F.Paste")
			(net "GND")
		)
		(pad "R23" smd circle
			(at -1.89992 -9.500108)
			(size 0.4572 0.4572)
			(layers "F.Cu" "F.Mask" "F.Paste")
			(net "GND")
		)
		(pad "R24" smd circle
			(at -0.94996 -9.500108)
			(size 0.4572 0.4572)
			(layers "F.Cu" "F.Mask" "F.Paste")
			(net "GND")
		)
		(pad "R25" smd circle
			(at 0 -9.500108)
			(size 0.4572 0.4572)
			(layers "F.Cu" "F.Mask" "F.Paste")
			(net "GND")
		)
		(pad "R26" smd circle
			(at 0.94996 -9.500108)
			(size 0.4572 0.4572)
			(layers "F.Cu" "F.Mask" "F.Paste")
			(net "GND")
		)
		(pad "R27" smd circle
			(at 1.89992 -9.500108)
			(size 0.4572 0.4572)
			(layers "F.Cu" "F.Mask" "F.Paste")
			(net "GND")
		)
		(pad "R28" smd circle
			(at 2.84988 -9.500108)
			(size 0.4572 0.4572)
			(layers "F.Cu" "F.Mask" "F.Paste")
			(net "GND")
		)
		(pad "R29" smd circle
			(at 3.800094 -9.500108)
			(size 0.4572 0.4572)
			(layers "F.Cu" "F.Mask" "F.Paste")
			(net "GND")
		)
		(pad "R30" smd circle
			(at 4.750054 -9.500108)
			(size 0.4572 0.4572)
			(layers "F.Cu" "F.Mask" "F.Paste")
			(net "GND")
		)
		(pad "R31" smd circle
			(at 5.700014 -9.500108)
			(size 0.4572 0.4572)
			(layers "F.Cu" "F.Mask" "F.Paste")
			(net "GND")
		)
		(pad "R32" smd circle
			(at 6.649974 -9.500108)
			(size 0.4572 0.4572)
			(layers "F.Cu" "F.Mask" "F.Paste")
			(net "GND")
		)
		(pad "R33" smd circle
			(at 7.599934 -9.500108)
			(size 0.4572 0.4572)
			(layers "F.Cu" "F.Mask" "F.Paste")
			(net "GND")
		)
		(pad "R34" smd circle
			(at 8.549894 -9.500108)
			(size 0.4572 0.4572)
			(layers "F.Cu" "F.Mask" "F.Paste")
			(net "GND")
		)
		(pad "R35" smd circle
			(at 9.500108 -9.500108)
			(size 0.4572 0.4572)
			(layers "F.Cu" "F.Mask" "F.Paste")
			(net "GND")
		)
		(pad "R36" smd circle
			(at 10.450068 -9.500108)
			(size 0.4572 0.4572)
			(layers "F.Cu" "F.Mask" "F.Paste")
			(net "Net_513")
		)
		(pad "R37" smd circle
			(at 11.400028 -9.500108)
			(size 0.4572 0.4572)
			(layers "F.Cu" "F.Mask" "F.Paste")
			(net "GND")
		)
		(pad "R38" smd circle
			(at 12.349988 -9.500108)
			(size 0.4572 0.4572)
			(layers "F.Cu" "F.Mask" "F.Paste")
			(net "Net_5318")
		)
		(pad "R39" smd circle
			(at 13.299948 -9.500108)
			(size 0.4572 0.4572)
			(layers "F.Cu" "F.Mask" "F.Paste")
			(net "Net_5312")
		)
		(pad "R40" smd circle
			(at 14.249908 -9.500108)
			(size 0.4572 0.4572)
			(layers "F.Cu" "F.Mask" "F.Paste")
			(net "GND")
		)
		(pad "R41" smd circle
			(at 15.200122 -9.500108)
			(size 0.4572 0.4572)
			(layers "F.Cu" "F.Mask" "F.Paste")
			(net "GND")
		)
		(pad "R42" smd circle
			(at 16.150082 -9.500108)
			(size 0.4572 0.4572)
			(layers "F.Cu" "F.Mask" "F.Paste")
			(net "GND")
		)
		(pad "R43" smd circle
			(at 17.100042 -9.500108)
			(size 0.4572 0.4572)
			(layers "F.Cu" "F.Mask" "F.Paste")
			(net "P5E_PEX2_STN4_TX_DP<65>")
		)
		(pad "R44" smd circle
			(at 18.050002 -9.500108)
			(size 0.4572 0.4572)
			(layers "F.Cu" "F.Mask" "F.Paste")
			(net "P5E_PEX2_STN4_TX_DN<65>")
		)
		(pad "R45" smd circle
			(at 18.999962 -9.500108)
			(size 0.4572 0.4572)
			(layers "F.Cu" "F.Mask" "F.Paste")
			(net "GND")
		)
		(pad "R46" smd circle
			(at 19.949922 -9.500108)
			(size 0.4572 0.4572)
			(layers "F.Cu" "F.Mask" "F.Paste")
			(net "P5E_PEX2_STN4_RX_DP<65>")
		)
		(pad "R47" smd circle
			(at 20.899882 -9.500108)
			(size 0.4572 0.4572)
			(layers "F.Cu" "F.Mask" "F.Paste")
			(net "P5E_PEX2_STN4_RX_DN<65>")
		)
		(pad "R48" smd circle
			(at 21.850096 -9.500108)
			(size 0.4572 0.4572)
			(layers "F.Cu" "F.Mask" "F.Paste")
			(net "GND")
		)
		(pad "R49" smd circle
			(at 22.800056 -9.500108)
			(size 0.4572 0.4572)
			(layers "F.Cu" "F.Mask" "F.Paste")
			(net "GND")
		)
		(pad "T1" smd circle
			(at -22.800056 -8.549894)
			(size 0.4572 0.4572)
			(layers "F.Cu" "F.Mask" "F.Paste")
			(net "P5E_PEX2_STN7_RX_DN<115>")
		)
		(pad "T2" smd circle
			(at -21.850096 -8.549894)
			(size 0.4572 0.4572)
			(layers "F.Cu" "F.Mask" "F.Paste")
			(net "P5E_PEX2_STN7_RX_DP<115>")
		)
		(pad "T3" smd circle
			(at -20.899882 -8.549894)
			(size 0.4572 0.4572)
			(layers "F.Cu" "F.Mask" "F.Paste")
			(net "GND")
		)
		(pad "T4" smd circle
			(at -19.949922 -8.549894)
			(size 0.4572 0.4572)
			(layers "F.Cu" "F.Mask" "F.Paste")
			(net "GND")
		)
		(pad "T5" smd circle
			(at -18.999962 -8.549894)
			(size 0.4572 0.4572)
			(layers "F.Cu" "F.Mask" "F.Paste")
			(net "GND")
		)
		(pad "T6" smd circle
			(at -18.050002 -8.549894)
			(size 0.4572 0.4572)
			(layers "F.Cu" "F.Mask" "F.Paste")
			(net "GND")
		)
		(pad "T7" smd circle
			(at -17.100042 -8.549894)
			(size 0.4572 0.4572)
			(layers "F.Cu" "F.Mask" "F.Paste")
			(net "GND")
		)
		(pad "T8" smd circle
			(at -16.150082 -8.549894)
			(size 0.4572 0.4572)
			(layers "F.Cu" "F.Mask" "F.Paste")
			(net "P5E_PEX2_STN7_TX_DN<115>")
		)
		(pad "T9" smd circle
			(at -15.200122 -8.549894)
			(size 0.4572 0.4572)
			(layers "F.Cu" "F.Mask" "F.Paste")
			(net "P5E_PEX2_STN7_TX_DP<115>")
		)
		(pad "T10" smd circle
			(at -14.249908 -8.549894)
			(size 0.4572 0.4572)
			(layers "F.Cu" "F.Mask" "F.Paste")
			(net "GND")
		)
		(pad "T11" smd circle
			(at -13.299948 -8.549894)
			(size 0.4572 0.4572)
			(layers "F.Cu" "F.Mask" "F.Paste")
			(net "GND")
		)
		(pad "T12" smd circle
			(at -12.349988 -8.549894)
			(size 0.4572 0.4572)
			(layers "F.Cu" "F.Mask" "F.Paste")
			(net "GND")
		)
		(pad "T13" smd circle
			(at -11.400028 -8.549894)
			(size 0.4572 0.4572)
			(layers "F.Cu" "F.Mask" "F.Paste")
			(net "GND")
		)
		(pad "T14" smd circle
			(at -10.450068 -8.549894)
			(size 0.4572 0.4572)
			(layers "F.Cu" "F.Mask" "F.Paste")
			(net "Net_520")
		)
		(pad "T15" smd circle
			(at -9.500108 -8.549894)
			(size 0.4572 0.4572)
			(layers "F.Cu" "F.Mask" "F.Paste")
			(net "GND")
		)
		(pad "T16" smd circle
			(at -8.549894 -8.549894)
			(size 0.4572 0.4572)
			(layers "F.Cu" "F.Mask" "F.Paste")
			(net "P1V25_SERDES_VDDPLL_PEX2")
		)
		(pad "T17" smd circle
			(at -7.599934 -8.549894)
			(size 0.4572 0.4572)
			(layers "F.Cu" "F.Mask" "F.Paste")
			(net "P1V25_SERDES_VDDPLL_PEX2")
		)
		(pad "T18" smd circle
			(at -6.649974 -8.549894)
			(size 0.4572 0.4572)
			(layers "F.Cu" "F.Mask" "F.Paste")
			(net "P1V25_SERDES_VDDPLL_PEX2")
		)
		(pad "T19" smd circle
			(at -5.700014 -8.549894)
			(size 0.4572 0.4572)
			(layers "F.Cu" "F.Mask" "F.Paste")
			(net "P1V25_SERDES_VDDPLL_PEX2")
		)
		(pad "T20" smd circle
			(at -4.750054 -8.549894)
			(size 0.4572 0.4572)
			(layers "F.Cu" "F.Mask" "F.Paste")
			(net "P1V25_SERDES_VDDPLL_PEX2")
		)
		(pad "T21" smd circle
			(at -3.800094 -8.549894)
			(size 0.4572 0.4572)
			(layers "F.Cu" "F.Mask" "F.Paste")
			(net "P1V25_SERDES_VDDPLL_PEX2")
		)
		(pad "T22" smd circle
			(at -2.84988 -8.549894)
			(size 0.4572 0.4572)
			(layers "F.Cu" "F.Mask" "F.Paste")
			(net "P1V25_SERDES_VDDPLL_PEX2")
		)
		(pad "T23" smd circle
			(at -1.89992 -8.549894)
			(size 0.4572 0.4572)
			(layers "F.Cu" "F.Mask" "F.Paste")
			(net "P1V25_SERDES_VDDPLL_PEX2")
		)
		(pad "T24" smd circle
			(at -0.94996 -8.549894)
			(size 0.4572 0.4572)
			(layers "F.Cu" "F.Mask" "F.Paste")
			(net "P1V25_SERDES_VDDPLL_PEX2")
		)
		(pad "T25" smd circle
			(at 0 -8.549894)
			(size 0.4572 0.4572)
			(layers "F.Cu" "F.Mask" "F.Paste")
			(net "P1V25_SERDES_VDDPLL_PEX2")
		)
		(pad "T26" smd circle
			(at 0.94996 -8.549894)
			(size 0.4572 0.4572)
			(layers "F.Cu" "F.Mask" "F.Paste")
			(net "P1V25_SERDES_VDDPLL_PEX2")
		)
		(pad "T27" smd circle
			(at 1.89992 -8.549894)
			(size 0.4572 0.4572)
			(layers "F.Cu" "F.Mask" "F.Paste")
			(net "P1V25_SERDES_VDDPLL_PEX2")
		)
		(pad "T28" smd circle
			(at 2.84988 -8.549894)
			(size 0.4572 0.4572)
			(layers "F.Cu" "F.Mask" "F.Paste")
			(net "P1V25_SERDES_VDDPLL_PEX2")
		)
		(pad "T29" smd circle
			(at 3.800094 -8.549894)
			(size 0.4572 0.4572)
			(layers "F.Cu" "F.Mask" "F.Paste")
			(net "P1V25_SERDES_VDDPLL_PEX2")
		)
		(pad "T30" smd circle
			(at 4.750054 -8.549894)
			(size 0.4572 0.4572)
			(layers "F.Cu" "F.Mask" "F.Paste")
			(net "P1V25_SERDES_VDDPLL_PEX2")
		)
		(pad "T31" smd circle
			(at 5.700014 -8.549894)
			(size 0.4572 0.4572)
			(layers "F.Cu" "F.Mask" "F.Paste")
			(net "P1V25_SERDES_VDDPLL_PEX2")
		)
		(pad "T32" smd circle
			(at 6.649974 -8.549894)
			(size 0.4572 0.4572)
			(layers "F.Cu" "F.Mask" "F.Paste")
			(net "P1V25_SERDES_VDDPLL_PEX2")
		)
		(pad "T33" smd circle
			(at 7.599934 -8.549894)
			(size 0.4572 0.4572)
			(layers "F.Cu" "F.Mask" "F.Paste")
			(net "P1V25_SERDES_VDDPLL_PEX2")
		)
		(pad "T34" smd circle
			(at 8.549894 -8.549894)
			(size 0.4572 0.4572)
			(layers "F.Cu" "F.Mask" "F.Paste")
			(net "GND")
		)
		(pad "T35" smd circle
			(at 9.500108 -8.549894)
			(size 0.4572 0.4572)
			(layers "F.Cu" "F.Mask" "F.Paste")
			(net "P1V8_VDDA_PEX2")
		)
		(pad "T36" smd circle
			(at 10.450068 -8.549894)
			(size 0.4572 0.4572)
			(layers "F.Cu" "F.Mask" "F.Paste")
			(net "Net_522")
		)
		(pad "T37" smd circle
			(at 11.400028 -8.549894)
			(size 0.4572 0.4572)
			(layers "F.Cu" "F.Mask" "F.Paste")
			(net "GND")
		)
		(pad "T38" smd circle
			(at 12.349988 -8.549894)
			(size 0.4572 0.4572)
			(layers "F.Cu" "F.Mask" "F.Paste")
			(net "RST_PEX2_S0_PERST_R_N")
		)
		(pad "T39" smd circle
			(at 13.299948 -8.549894)
			(size 0.4572 0.4572)
			(layers "F.Cu" "F.Mask" "F.Paste")
			(net "Net_380")
		)
		(pad "T40" smd circle
			(at 14.249908 -8.549894)
			(size 0.4572 0.4572)
			(layers "F.Cu" "F.Mask" "F.Paste")
			(net "GND")
		)
		(pad "T41" smd circle
			(at 15.200122 -8.549894)
			(size 0.4572 0.4572)
			(layers "F.Cu" "F.Mask" "F.Paste")
			(net "P5E_PEX2_STN4_TX_DP<64>")
		)
		(pad "T42" smd circle
			(at 16.150082 -8.549894)
			(size 0.4572 0.4572)
			(layers "F.Cu" "F.Mask" "F.Paste")
			(net "P5E_PEX2_STN4_TX_DN<64>")
		)
		(pad "T43" smd circle
			(at 17.100042 -8.549894)
			(size 0.4572 0.4572)
			(layers "F.Cu" "F.Mask" "F.Paste")
			(net "GND")
		)
		(pad "T44" smd circle
			(at 18.050002 -8.549894)
			(size 0.4572 0.4572)
			(layers "F.Cu" "F.Mask" "F.Paste")
			(net "GND")
		)
		(pad "T45" smd circle
			(at 18.999962 -8.549894)
			(size 0.4572 0.4572)
			(layers "F.Cu" "F.Mask" "F.Paste")
			(net "GND")
		)
		(pad "T46" smd circle
			(at 19.949922 -8.549894)
			(size 0.4572 0.4572)
			(layers "F.Cu" "F.Mask" "F.Paste")
			(net "GND")
		)
		(pad "T47" smd circle
			(at 20.899882 -8.549894)
			(size 0.4572 0.4572)
			(layers "F.Cu" "F.Mask" "F.Paste")
			(net "GND")
		)
		(pad "T48" smd circle
			(at 21.850096 -8.549894)
			(size 0.4572 0.4572)
			(layers "F.Cu" "F.Mask" "F.Paste")
			(net "P5E_PEX2_STN4_RX_DP<64>")
		)
		(pad "T49" smd circle
			(at 22.800056 -8.549894)
			(size 0.4572 0.4572)
			(layers "F.Cu" "F.Mask" "F.Paste")
			(net "P5E_PEX2_STN4_RX_DN<64>")
		)
		(pad "U1" smd circle
			(at -22.800056 -7.599934)
			(size 0.4572 0.4572)
			(layers "F.Cu" "F.Mask" "F.Paste")
			(net "GND")
		)
		(pad "U2" smd circle
			(at -21.850096 -7.599934)
			(size 0.4572 0.4572)
			(layers "F.Cu" "F.Mask" "F.Paste")
			(net "GND")
		)
		(pad "U3" smd circle
			(at -20.899882 -7.599934)
			(size 0.4572 0.4572)
			(layers "F.Cu" "F.Mask" "F.Paste")
			(net "P5E_PEX2_STN7_RX_DN<114>")
		)
		(pad "U4" smd circle
			(at -19.949922 -7.599934)
			(size 0.4572 0.4572)
			(layers "F.Cu" "F.Mask" "F.Paste")
			(net "P5E_PEX2_STN7_RX_DP<114>")
		)
		(pad "U5" smd circle
			(at -18.999962 -7.599934)
			(size 0.4572 0.4572)
			(layers "F.Cu" "F.Mask" "F.Paste")
			(net "GND")
		)
		(pad "U6" smd circle
			(at -18.050002 -7.599934)
			(size 0.4572 0.4572)
			(layers "F.Cu" "F.Mask" "F.Paste")
			(net "P5E_PEX2_STN7_TX_DN<114>")
		)
		(pad "U7" smd circle
			(at -17.100042 -7.599934)
			(size 0.4572 0.4572)
			(layers "F.Cu" "F.Mask" "F.Paste")
			(net "P5E_PEX2_STN7_TX_DP<114>")
		)
		(pad "U8" smd circle
			(at -16.150082 -7.599934)
			(size 0.4572 0.4572)
			(layers "F.Cu" "F.Mask" "F.Paste")
			(net "GND")
		)
		(pad "U9" smd circle
			(at -15.200122 -7.599934)
			(size 0.4572 0.4572)
			(layers "F.Cu" "F.Mask" "F.Paste")
			(net "GND")
		)
		(pad "U10" smd circle
			(at -14.249908 -7.599934)
			(size 0.4572 0.4572)
			(layers "F.Cu" "F.Mask" "F.Paste")
			(net "GND")
		)
		(pad "U11" smd circle
			(at -13.299948 -7.599934)
			(size 0.4572 0.4572)
			(layers "F.Cu" "F.Mask" "F.Paste")
			(net "GND")
		)
		(pad "U12" smd circle
			(at -12.349988 -7.599934)
			(size 0.4572 0.4572)
			(layers "F.Cu" "F.Mask" "F.Paste")
			(net "GND")
		)
		(pad "U13" smd circle
			(at -11.400028 -7.599934)
			(size 0.4572 0.4572)
			(layers "F.Cu" "F.Mask" "F.Paste")
			(net "GND")
		)
		(pad "U14" smd circle
			(at -10.450068 -7.599934)
			(size 0.4572 0.4572)
			(layers "F.Cu" "F.Mask" "F.Paste")
			(net "Net_526")
		)
		(pad "U15" smd circle
			(at -9.500108 -7.599934)
			(size 0.4572 0.4572)
			(layers "F.Cu" "F.Mask" "F.Paste")
			(net "GND")
		)
		(pad "U16" smd circle
			(at -8.549894 -7.599934)
			(size 0.4572 0.4572)
			(layers "F.Cu" "F.Mask" "F.Paste")
			(net "GND")
		)
		(pad "U17" smd circle
			(at -7.599934 -7.599934)
			(size 0.4572 0.4572)
			(layers "F.Cu" "F.Mask" "F.Paste")
			(net "GND")
		)
		(pad "U18" smd circle
			(at -6.649974 -7.599934)
			(size 0.4572 0.4572)
			(layers "F.Cu" "F.Mask" "F.Paste")
			(net "GND")
		)
		(pad "U19" smd circle
			(at -5.700014 -7.599934)
			(size 0.4572 0.4572)
			(layers "F.Cu" "F.Mask" "F.Paste")
			(net "GND")
		)
		(pad "U20" smd circle
			(at -4.750054 -7.599934)
			(size 0.4572 0.4572)
			(layers "F.Cu" "F.Mask" "F.Paste")
			(net "GND")
		)
		(pad "U21" smd circle
			(at -3.800094 -7.599934)
			(size 0.4572 0.4572)
			(layers "F.Cu" "F.Mask" "F.Paste")
			(net "GND")
		)
		(pad "U22" smd circle
			(at -2.84988 -7.599934)
			(size 0.4572 0.4572)
			(layers "F.Cu" "F.Mask" "F.Paste")
			(net "GND")
		)
		(pad "U23" smd circle
			(at -1.89992 -7.599934)
			(size 0.4572 0.4572)
			(layers "F.Cu" "F.Mask" "F.Paste")
			(net "GND")
		)
		(pad "U24" smd circle
			(at -0.94996 -7.599934)
			(size 0.4572 0.4572)
			(layers "F.Cu" "F.Mask" "F.Paste")
			(net "GND")
		)
		(pad "U25" smd circle
			(at 0 -7.599934)
			(size 0.4572 0.4572)
			(layers "F.Cu" "F.Mask" "F.Paste")
			(net "GND")
		)
		(pad "U26" smd circle
			(at 0.94996 -7.599934)
			(size 0.4572 0.4572)
			(layers "F.Cu" "F.Mask" "F.Paste")
			(net "GND")
		)
		(pad "U27" smd circle
			(at 1.89992 -7.599934)
			(size 0.4572 0.4572)
			(layers "F.Cu" "F.Mask" "F.Paste")
			(net "GND")
		)
		(pad "U28" smd circle
			(at 2.84988 -7.599934)
			(size 0.4572 0.4572)
			(layers "F.Cu" "F.Mask" "F.Paste")
			(net "GND")
		)
		(pad "U29" smd circle
			(at 3.800094 -7.599934)
			(size 0.4572 0.4572)
			(layers "F.Cu" "F.Mask" "F.Paste")
			(net "GND")
		)
		(pad "U30" smd circle
			(at 4.750054 -7.599934)
			(size 0.4572 0.4572)
			(layers "F.Cu" "F.Mask" "F.Paste")
			(net "GND")
		)
		(pad "U31" smd circle
			(at 5.700014 -7.599934)
			(size 0.4572 0.4572)
			(layers "F.Cu" "F.Mask" "F.Paste")
			(net "GND")
		)
		(pad "U32" smd circle
			(at 6.649974 -7.599934)
			(size 0.4572 0.4572)
			(layers "F.Cu" "F.Mask" "F.Paste")
			(net "GND")
		)
		(pad "U33" smd circle
			(at 7.599934 -7.599934)
			(size 0.4572 0.4572)
			(layers "F.Cu" "F.Mask" "F.Paste")
			(net "GND")
		)
		(pad "U34" smd circle
			(at 8.549894 -7.599934)
			(size 0.4572 0.4572)
			(layers "F.Cu" "F.Mask" "F.Paste")
			(net "GND")
		)
		(pad "U35" smd circle
			(at 9.500108 -7.599934)
			(size 0.4572 0.4572)
			(layers "F.Cu" "F.Mask" "F.Paste")
			(net "GND")
		)
		(pad "U36" smd circle
			(at 10.450068 -7.599934)
			(size 0.4572 0.4572)
			(layers "F.Cu" "F.Mask" "F.Paste")
			(net "Net_523")
		)
		(pad "U37" smd circle
			(at 11.400028 -7.599934)
			(size 0.4572 0.4572)
			(layers "F.Cu" "F.Mask" "F.Paste")
			(net "GND")
		)
		(pad "U38" smd circle
			(at 12.349988 -7.599934)
			(size 0.4572 0.4572)
			(layers "F.Cu" "F.Mask" "F.Paste")
			(net "Net_5321")
		)
		(pad "U39" smd circle
			(at 13.299948 -7.599934)
			(size 0.4572 0.4572)
			(layers "F.Cu" "F.Mask" "F.Paste")
			(net "Net_5315")
		)
		(pad "U40" smd circle
			(at 14.249908 -7.599934)
			(size 0.4572 0.4572)
			(layers "F.Cu" "F.Mask" "F.Paste")
			(net "GND")
		)
		(pad "U41" smd circle
			(at 15.200122 -7.599934)
			(size 0.4572 0.4572)
			(layers "F.Cu" "F.Mask" "F.Paste")
			(net "GND")
		)
		(pad "U42" smd circle
			(at 16.150082 -7.599934)
			(size 0.4572 0.4572)
			(layers "F.Cu" "F.Mask" "F.Paste")
			(net "GND")
		)
		(pad "U43" smd circle
			(at 17.100042 -7.599934)
			(size 0.4572 0.4572)
			(layers "F.Cu" "F.Mask" "F.Paste")
			(net "Net_1697")
		)
		(pad "U44" smd circle
			(at 18.050002 -7.599934)
			(size 0.4572 0.4572)
			(layers "F.Cu" "F.Mask" "F.Paste")
			(net "Net_1687")
		)
		(pad "U45" smd circle
			(at 18.999962 -7.599934)
			(size 0.4572 0.4572)
			(layers "F.Cu" "F.Mask" "F.Paste")
			(net "GND")
		)
		(pad "U46" smd circle
			(at 19.949922 -7.599934)
			(size 0.4572 0.4572)
			(layers "F.Cu" "F.Mask" "F.Paste")
			(net "Net_1577")
		)
		(pad "U47" smd circle
			(at 20.899882 -7.599934)
			(size 0.4572 0.4572)
			(layers "F.Cu" "F.Mask" "F.Paste")
			(net "Net_1572")
		)
		(pad "U48" smd circle
			(at 21.850096 -7.599934)
			(size 0.4572 0.4572)
			(layers "F.Cu" "F.Mask" "F.Paste")
			(net "GND")
		)
		(pad "U49" smd circle
			(at 22.800056 -7.599934)
			(size 0.4572 0.4572)
			(layers "F.Cu" "F.Mask" "F.Paste")
			(net "GND")
		)
		(pad "V1" smd circle
			(at -22.800056 -6.649974)
			(size 0.4572 0.4572)
			(layers "F.Cu" "F.Mask" "F.Paste")
			(net "P5E_PEX2_STN7_RX_DN<113>")
		)
		(pad "V2" smd circle
			(at -21.850096 -6.649974)
			(size 0.4572 0.4572)
			(layers "F.Cu" "F.Mask" "F.Paste")
			(net "P5E_PEX2_STN7_RX_DP<113>")
		)
		(pad "V3" smd circle
			(at -20.899882 -6.649974)
			(size 0.4572 0.4572)
			(layers "F.Cu" "F.Mask" "F.Paste")
			(net "GND")
		)
		(pad "V4" smd circle
			(at -19.949922 -6.649974)
			(size 0.4572 0.4572)
			(layers "F.Cu" "F.Mask" "F.Paste")
			(net "GND")
		)
		(pad "V5" smd circle
			(at -18.999962 -6.649974)
			(size 0.4572 0.4572)
			(layers "F.Cu" "F.Mask" "F.Paste")
			(net "GND")
		)
		(pad "V6" smd circle
			(at -18.050002 -6.649974)
			(size 0.4572 0.4572)
			(layers "F.Cu" "F.Mask" "F.Paste")
			(net "GND")
		)
		(pad "V7" smd circle
			(at -17.100042 -6.649974)
			(size 0.4572 0.4572)
			(layers "F.Cu" "F.Mask" "F.Paste")
			(net "GND")
		)
		(pad "V8" smd circle
			(at -16.150082 -6.649974)
			(size 0.4572 0.4572)
			(layers "F.Cu" "F.Mask" "F.Paste")
			(net "P5E_PEX2_STN7_TX_DN<113>")
		)
		(pad "V9" smd circle
			(at -15.200122 -6.649974)
			(size 0.4572 0.4572)
			(layers "F.Cu" "F.Mask" "F.Paste")
			(net "P5E_PEX2_STN7_TX_DP<113>")
		)
		(pad "V10" smd circle
			(at -14.249908 -6.649974)
			(size 0.4572 0.4572)
			(layers "F.Cu" "F.Mask" "F.Paste")
			(net "GND")
		)
		(pad "V11" smd circle
			(at -13.299948 -6.649974)
			(size 0.4572 0.4572)
			(layers "F.Cu" "F.Mask" "F.Paste")
			(net "GND")
		)
		(pad "V12" smd circle
			(at -12.349988 -6.649974)
			(size 0.4572 0.4572)
			(layers "F.Cu" "F.Mask" "F.Paste")
			(net "GND")
		)
		(pad "V13" smd circle
			(at -11.400028 -6.649974)
			(size 0.4572 0.4572)
			(layers "F.Cu" "F.Mask" "F.Paste")
			(net "GND")
		)
		(pad "V14" smd circle
			(at -10.450068 -6.649974)
			(size 0.4572 0.4572)
			(layers "F.Cu" "F.Mask" "F.Paste")
			(net "P1V8_VDDA_PEX2")
		)
		(pad "V15" smd circle
			(at -9.500108 -6.649974)
			(size 0.4572 0.4572)
			(layers "F.Cu" "F.Mask" "F.Paste")
			(net "GND")
		)
		(pad "V16" smd circle
			(at -8.549894 -6.649974)
			(size 0.4572 0.4572)
			(layers "F.Cu" "F.Mask" "F.Paste")
			(net "P1V25_PEX2")
		)
		(pad "V17" smd circle
			(at -7.599934 -6.649974)
			(size 0.4572 0.4572)
			(layers "F.Cu" "F.Mask" "F.Paste")
			(net "P1V25_PEX2")
		)
		(pad "V18" smd circle
			(at -6.649974 -6.649974)
			(size 0.4572 0.4572)
			(layers "F.Cu" "F.Mask" "F.Paste")
			(net "P1V25_PEX2")
		)
		(pad "V19" smd circle
			(at -5.700014 -6.649974)
			(size 0.4572 0.4572)
			(layers "F.Cu" "F.Mask" "F.Paste")
			(net "P1V25_PEX2")
		)
		(pad "V20" smd circle
			(at -4.750054 -6.649974)
			(size 0.4572 0.4572)
			(layers "F.Cu" "F.Mask" "F.Paste")
			(net "P1V25_PEX2")
		)
		(pad "V21" smd circle
			(at -3.800094 -6.649974)
			(size 0.4572 0.4572)
			(layers "F.Cu" "F.Mask" "F.Paste")
			(net "P1V25_PEX2")
		)
		(pad "V22" smd circle
			(at -2.84988 -6.649974)
			(size 0.4572 0.4572)
			(layers "F.Cu" "F.Mask" "F.Paste")
			(net "P1V25_PEX2")
		)
		(pad "V23" smd circle
			(at -1.89992 -6.649974)
			(size 0.4572 0.4572)
			(layers "F.Cu" "F.Mask" "F.Paste")
			(net "P1V25_PEX2")
		)
		(pad "V24" smd circle
			(at -0.94996 -6.649974)
			(size 0.4572 0.4572)
			(layers "F.Cu" "F.Mask" "F.Paste")
			(net "P1V25_PEX2")
		)
		(pad "V25" smd circle
			(at 0 -6.649974)
			(size 0.4572 0.4572)
			(layers "F.Cu" "F.Mask" "F.Paste")
			(net "P1V25_PEX2")
		)
		(pad "V26" smd circle
			(at 0.94996 -6.649974)
			(size 0.4572 0.4572)
			(layers "F.Cu" "F.Mask" "F.Paste")
			(net "P1V25_PEX2")
		)
		(pad "V27" smd circle
			(at 1.89992 -6.649974)
			(size 0.4572 0.4572)
			(layers "F.Cu" "F.Mask" "F.Paste")
			(net "P1V25_PEX2")
		)
		(pad "V28" smd circle
			(at 2.84988 -6.649974)
			(size 0.4572 0.4572)
			(layers "F.Cu" "F.Mask" "F.Paste")
			(net "P1V25_PEX2")
		)
		(pad "V29" smd circle
			(at 3.800094 -6.649974)
			(size 0.4572 0.4572)
			(layers "F.Cu" "F.Mask" "F.Paste")
			(net "P1V25_PEX2")
		)
		(pad "V30" smd circle
			(at 4.750054 -6.649974)
			(size 0.4572 0.4572)
			(layers "F.Cu" "F.Mask" "F.Paste")
			(net "P1V25_PEX2")
		)
		(pad "V31" smd circle
			(at 5.700014 -6.649974)
			(size 0.4572 0.4572)
			(layers "F.Cu" "F.Mask" "F.Paste")
			(net "P1V25_PEX2")
		)
		(pad "V32" smd circle
			(at 6.649974 -6.649974)
			(size 0.4572 0.4572)
			(layers "F.Cu" "F.Mask" "F.Paste")
			(net "P1V25_PEX2")
		)
		(pad "V33" smd circle
			(at 7.599934 -6.649974)
			(size 0.4572 0.4572)
			(layers "F.Cu" "F.Mask" "F.Paste")
			(net "P1V25_PEX2")
		)
		(pad "V34" smd circle
			(at 8.549894 -6.649974)
			(size 0.4572 0.4572)
			(layers "F.Cu" "F.Mask" "F.Paste")
			(net "GND")
		)
		(pad "V35" smd circle
			(at 9.500108 -6.649974)
			(size 0.4572 0.4572)
			(layers "F.Cu" "F.Mask" "F.Paste")
			(net "P1V8_PEX")
		)
		(pad "V36" smd circle
			(at 10.450068 -6.649974)
			(size 0.4572 0.4572)
			(layers "F.Cu" "F.Mask" "F.Paste")
			(net "GND")
		)
		(pad "V37" smd circle
			(at 11.400028 -6.649974)
			(size 0.4572 0.4572)
			(layers "F.Cu" "F.Mask" "F.Paste")
			(net "GND")
		)
		(pad "V38" smd circle
			(at 12.349988 -6.649974)
			(size 0.4572 0.4572)
			(layers "F.Cu" "F.Mask" "F.Paste")
			(net "GND")
		)
		(pad "V39" smd circle
			(at 13.299948 -6.649974)
			(size 0.4572 0.4572)
			(layers "F.Cu" "F.Mask" "F.Paste")
			(net "VSENSE_P0V8_PEX2_SKT_VSEN")
		)
		(pad "V40" smd circle
			(at 14.249908 -6.649974)
			(size 0.4572 0.4572)
			(layers "F.Cu" "F.Mask" "F.Paste")
			(net "GND")
		)
		(pad "V41" smd circle
			(at 15.200122 -6.649974)
			(size 0.4572 0.4572)
			(layers "F.Cu" "F.Mask" "F.Paste")
			(net "Net_1663")
		)
		(pad "V42" smd circle
			(at 16.150082 -6.649974)
			(size 0.4572 0.4572)
			(layers "F.Cu" "F.Mask" "F.Paste")
			(net "Net_1661")
		)
		(pad "V43" smd circle
			(at 17.100042 -6.649974)
			(size 0.4572 0.4572)
			(layers "F.Cu" "F.Mask" "F.Paste")
			(net "GND")
		)
		(pad "V44" smd circle
			(at 18.050002 -6.649974)
			(size 0.4572 0.4572)
			(layers "F.Cu" "F.Mask" "F.Paste")
			(net "GND")
		)
		(pad "V45" smd circle
			(at 18.999962 -6.649974)
			(size 0.4572 0.4572)
			(layers "F.Cu" "F.Mask" "F.Paste")
			(net "GND")
		)
		(pad "V46" smd circle
			(at 19.949922 -6.649974)
			(size 0.4572 0.4572)
			(layers "F.Cu" "F.Mask" "F.Paste")
			(net "GND")
		)
		(pad "V47" smd circle
			(at 20.899882 -6.649974)
			(size 0.4572 0.4572)
			(layers "F.Cu" "F.Mask" "F.Paste")
			(net "GND")
		)
		(pad "V48" smd circle
			(at 21.850096 -6.649974)
			(size 0.4572 0.4572)
			(layers "F.Cu" "F.Mask" "F.Paste")
			(net "Net_1582")
		)
		(pad "V49" smd circle
			(at 22.800056 -6.649974)
			(size 0.4572 0.4572)
			(layers "F.Cu" "F.Mask" "F.Paste")
			(net "Net_1585")
		)
		(pad "W1" smd circle
			(at -22.800056 -5.700014)
			(size 0.4572 0.4572)
			(layers "F.Cu" "F.Mask" "F.Paste")
			(net "GND")
		)
		(pad "W2" smd circle
			(at -21.850096 -5.700014)
			(size 0.4572 0.4572)
			(layers "F.Cu" "F.Mask" "F.Paste")
			(net "GND")
		)
		(pad "W3" smd circle
			(at -20.899882 -5.700014)
			(size 0.4572 0.4572)
			(layers "F.Cu" "F.Mask" "F.Paste")
			(net "P5E_PEX2_STN7_RX_DN<112>")
		)
		(pad "W4" smd circle
			(at -19.949922 -5.700014)
			(size 0.4572 0.4572)
			(layers "F.Cu" "F.Mask" "F.Paste")
			(net "P5E_PEX2_STN7_RX_DP<112>")
		)
		(pad "W5" smd circle
			(at -18.999962 -5.700014)
			(size 0.4572 0.4572)
			(layers "F.Cu" "F.Mask" "F.Paste")
			(net "GND")
		)
		(pad "W6" smd circle
			(at -18.050002 -5.700014)
			(size 0.4572 0.4572)
			(layers "F.Cu" "F.Mask" "F.Paste")
			(net "P5E_PEX2_STN7_TX_DN<112>")
		)
		(pad "W7" smd circle
			(at -17.100042 -5.700014)
			(size 0.4572 0.4572)
			(layers "F.Cu" "F.Mask" "F.Paste")
			(net "P5E_PEX2_STN7_TX_DP<112>")
		)
		(pad "W8" smd circle
			(at -16.150082 -5.700014)
			(size 0.4572 0.4572)
			(layers "F.Cu" "F.Mask" "F.Paste")
			(net "GND")
		)
		(pad "W9" smd circle
			(at -15.200122 -5.700014)
			(size 0.4572 0.4572)
			(layers "F.Cu" "F.Mask" "F.Paste")
			(net "GND")
		)
		(pad "W10" smd circle
			(at -14.249908 -5.700014)
			(size 0.4572 0.4572)
			(layers "F.Cu" "F.Mask" "F.Paste")
			(net "GND")
		)
		(pad "W11" smd circle
			(at -13.299948 -5.700014)
			(size 0.4572 0.4572)
			(layers "F.Cu" "F.Mask" "F.Paste")
			(net "GND")
		)
		(pad "W12" smd circle
			(at -12.349988 -5.700014)
			(size 0.4572 0.4572)
			(layers "F.Cu" "F.Mask" "F.Paste")
			(net "GND")
		)
		(pad "W13" smd circle
			(at -11.400028 -5.700014)
			(size 0.4572 0.4572)
			(layers "F.Cu" "F.Mask" "F.Paste")
			(net "GND")
		)
		(pad "W14" smd circle
			(at -10.450068 -5.700014)
			(size 0.4572 0.4572)
			(layers "F.Cu" "F.Mask" "F.Paste")
			(net "GND")
		)
		(pad "W15" smd circle
			(at -9.500108 -5.700014)
			(size 0.4572 0.4572)
			(layers "F.Cu" "F.Mask" "F.Paste")
			(net "GND")
		)
		(pad "W16" smd circle
			(at -8.549894 -5.700014)
			(size 0.4572 0.4572)
			(layers "F.Cu" "F.Mask" "F.Paste")
			(net "GND")
		)
		(pad "W17" smd circle
			(at -7.599934 -5.700014)
			(size 0.4572 0.4572)
			(layers "F.Cu" "F.Mask" "F.Paste")
			(net "GND")
		)
		(pad "W18" smd circle
			(at -6.649974 -5.700014)
			(size 0.4572 0.4572)
			(layers "F.Cu" "F.Mask" "F.Paste")
			(net "GND")
		)
		(pad "W19" smd circle
			(at -5.700014 -5.700014)
			(size 0.4572 0.4572)
			(layers "F.Cu" "F.Mask" "F.Paste")
			(net "GND")
		)
		(pad "W20" smd circle
			(at -4.750054 -5.700014)
			(size 0.4572 0.4572)
			(layers "F.Cu" "F.Mask" "F.Paste")
			(net "GND")
		)
		(pad "W21" smd circle
			(at -3.800094 -5.700014)
			(size 0.4572 0.4572)
			(layers "F.Cu" "F.Mask" "F.Paste")
			(net "GND")
		)
		(pad "W22" smd circle
			(at -2.84988 -5.700014)
			(size 0.4572 0.4572)
			(layers "F.Cu" "F.Mask" "F.Paste")
			(net "GND")
		)
		(pad "W23" smd circle
			(at -1.89992 -5.700014)
			(size 0.4572 0.4572)
			(layers "F.Cu" "F.Mask" "F.Paste")
			(net "GND")
		)
		(pad "W24" smd circle
			(at -0.94996 -5.700014)
			(size 0.4572 0.4572)
			(layers "F.Cu" "F.Mask" "F.Paste")
			(net "GND")
		)
		(pad "W25" smd circle
			(at 0 -5.700014)
			(size 0.4572 0.4572)
			(layers "F.Cu" "F.Mask" "F.Paste")
			(net "GND")
		)
		(pad "W26" smd circle
			(at 0.94996 -5.700014)
			(size 0.4572 0.4572)
			(layers "F.Cu" "F.Mask" "F.Paste")
			(net "GND")
		)
		(pad "W27" smd circle
			(at 1.89992 -5.700014)
			(size 0.4572 0.4572)
			(layers "F.Cu" "F.Mask" "F.Paste")
			(net "GND")
		)
		(pad "W28" smd circle
			(at 2.84988 -5.700014)
			(size 0.4572 0.4572)
			(layers "F.Cu" "F.Mask" "F.Paste")
			(net "GND")
		)
		(pad "W29" smd circle
			(at 3.800094 -5.700014)
			(size 0.4572 0.4572)
			(layers "F.Cu" "F.Mask" "F.Paste")
			(net "GND")
		)
		(pad "W30" smd circle
			(at 4.750054 -5.700014)
			(size 0.4572 0.4572)
			(layers "F.Cu" "F.Mask" "F.Paste")
			(net "GND")
		)
		(pad "W31" smd circle
			(at 5.700014 -5.700014)
			(size 0.4572 0.4572)
			(layers "F.Cu" "F.Mask" "F.Paste")
			(net "GND")
		)
		(pad "W32" smd circle
			(at 6.649974 -5.700014)
			(size 0.4572 0.4572)
			(layers "F.Cu" "F.Mask" "F.Paste")
			(net "GND")
		)
		(pad "W33" smd circle
			(at 7.599934 -5.700014)
			(size 0.4572 0.4572)
			(layers "F.Cu" "F.Mask" "F.Paste")
			(net "GND")
		)
		(pad "W34" smd circle
			(at 8.549894 -5.700014)
			(size 0.4572 0.4572)
			(layers "F.Cu" "F.Mask" "F.Paste")
			(net "GND")
		)
		(pad "W35" smd circle
			(at 9.500108 -5.700014)
			(size 0.4572 0.4572)
			(layers "F.Cu" "F.Mask" "F.Paste")
			(net "P1V8_PEX")
		)
		(pad "W36" smd circle
			(at 10.450068 -5.700014)
			(size 0.4572 0.4572)
			(layers "F.Cu" "F.Mask" "F.Paste")
			(net "GND")
		)
		(pad "W37" smd circle
			(at 11.400028 -5.700014)
			(size 0.4572 0.4572)
			(layers "F.Cu" "F.Mask" "F.Paste")
			(net "GND")
		)
		(pad "W38" smd circle
			(at 12.349988 -5.700014)
			(size 0.4572 0.4572)
			(layers "F.Cu" "F.Mask" "F.Paste")
			(net "GND")
		)
		(pad "W39" smd circle
			(at 13.299948 -5.700014)
			(size 0.4572 0.4572)
			(layers "F.Cu" "F.Mask" "F.Paste")
			(net "VSENSE_P0V8_PEX2_SKT_VRTN")
		)
		(pad "W40" smd circle
			(at 14.249908 -5.700014)
			(size 0.4572 0.4572)
			(layers "F.Cu" "F.Mask" "F.Paste")
			(net "GND")
		)
		(pad "W41" smd circle
			(at 15.200122 -5.700014)
			(size 0.4572 0.4572)
			(layers "F.Cu" "F.Mask" "F.Paste")
			(net "GND")
		)
		(pad "W42" smd circle
			(at 16.150082 -5.700014)
			(size 0.4572 0.4572)
			(layers "F.Cu" "F.Mask" "F.Paste")
			(net "GND")
		)
		(pad "W43" smd circle
			(at 17.100042 -5.700014)
			(size 0.4572 0.4572)
			(layers "F.Cu" "F.Mask" "F.Paste")
			(net "Net_1705")
		)
		(pad "W44" smd circle
			(at 18.050002 -5.700014)
			(size 0.4572 0.4572)
			(layers "F.Cu" "F.Mask" "F.Paste")
			(net "Net_1669")
		)
		(pad "W45" smd circle
			(at 18.999962 -5.700014)
			(size 0.4572 0.4572)
			(layers "F.Cu" "F.Mask" "F.Paste")
			(net "GND")
		)
		(pad "W46" smd circle
			(at 19.949922 -5.700014)
			(size 0.4572 0.4572)
			(layers "F.Cu" "F.Mask" "F.Paste")
			(net "Net_1589")
		)
		(pad "W47" smd circle
			(at 20.899882 -5.700014)
			(size 0.4572 0.4572)
			(layers "F.Cu" "F.Mask" "F.Paste")
			(net "Net_1575")
		)
		(pad "W48" smd circle
			(at 21.850096 -5.700014)
			(size 0.4572 0.4572)
			(layers "F.Cu" "F.Mask" "F.Paste")
			(net "GND")
		)
		(pad "W49" smd circle
			(at 22.800056 -5.700014)
			(size 0.4572 0.4572)
			(layers "F.Cu" "F.Mask" "F.Paste")
			(net "GND")
		)
		(pad "Y1" smd circle
			(at -22.800056 -4.750054)
			(size 0.4572 0.4572)
			(layers "F.Cu" "F.Mask" "F.Paste")
			(net "GND")
		)
		(pad "Y2" smd circle
			(at -21.850096 -4.750054)
			(size 0.4572 0.4572)
			(layers "F.Cu" "F.Mask" "F.Paste")
			(net "GND")
		)
		(pad "Y3" smd circle
			(at -20.899882 -4.750054)
			(size 0.4572 0.4572)
			(layers "F.Cu" "F.Mask" "F.Paste")
			(net "GND")
		)
		(pad "Y4" smd circle
			(at -19.949922 -4.750054)
			(size 0.4572 0.4572)
			(layers "F.Cu" "F.Mask" "F.Paste")
			(net "GND")
		)
		(pad "Y5" smd circle
			(at -18.999962 -4.750054)
			(size 0.4572 0.4572)
			(layers "F.Cu" "F.Mask" "F.Paste")
			(net "GND")
		)
		(pad "Y6" smd circle
			(at -18.050002 -4.750054)
			(size 0.4572 0.4572)
			(layers "F.Cu" "F.Mask" "F.Paste")
			(net "GND")
		)
		(pad "Y7" smd circle
			(at -17.100042 -4.750054)
			(size 0.4572 0.4572)
			(layers "F.Cu" "F.Mask" "F.Paste")
			(net "GND")
		)
		(pad "Y8" smd circle
			(at -16.150082 -4.750054)
			(size 0.4572 0.4572)
			(layers "F.Cu" "F.Mask" "F.Paste")
			(net "GND")
		)
		(pad "Y9" smd circle
			(at -15.200122 -4.750054)
			(size 0.4572 0.4572)
			(layers "F.Cu" "F.Mask" "F.Paste")
			(net "GND")
		)
		(pad "Y10" smd circle
			(at -14.249908 -4.750054)
			(size 0.4572 0.4572)
			(layers "F.Cu" "F.Mask" "F.Paste")
			(net "GND")
		)
		(pad "Y11" smd circle
			(at -13.299948 -4.750054)
			(size 0.4572 0.4572)
			(layers "F.Cu" "F.Mask" "F.Paste")
			(net "GND")
		)
		(pad "Y12" smd circle
			(at -12.349988 -4.750054)
			(size 0.4572 0.4572)
			(layers "F.Cu" "F.Mask" "F.Paste")
			(net "P1V8_PEX")
		)
		(pad "Y13" smd circle
			(at -11.400028 -4.750054)
			(size 0.4572 0.4572)
			(layers "F.Cu" "F.Mask" "F.Paste")
			(net "GND")
		)
		(pad "Y14" smd circle
			(at -10.450068 -4.750054)
			(size 0.4572 0.4572)
			(layers "F.Cu" "F.Mask" "F.Paste")
			(net "P0V8_PEX2")
		)
		(pad "Y15" smd circle
			(at -9.500108 -4.750054)
			(size 0.4572 0.4572)
			(layers "F.Cu" "F.Mask" "F.Paste")
			(net "GND")
		)
		(pad "Y16" smd circle
			(at -8.549894 -4.750054)
			(size 0.4572 0.4572)
			(layers "F.Cu" "F.Mask" "F.Paste")
			(net "P0V8_SERDES_VDDA_PEX2")
		)
		(pad "Y17" smd circle
			(at -7.599934 -4.750054)
			(size 0.4572 0.4572)
			(layers "F.Cu" "F.Mask" "F.Paste")
			(net "P0V8_SERDES_VDDA_PEX2")
		)
		(pad "Y18" smd circle
			(at -6.649974 -4.750054)
			(size 0.4572 0.4572)
			(layers "F.Cu" "F.Mask" "F.Paste")
			(net "P0V8_SERDES_VDDA_PEX2")
		)
		(pad "Y19" smd circle
			(at -5.700014 -4.750054)
			(size 0.4572 0.4572)
			(layers "F.Cu" "F.Mask" "F.Paste")
			(net "P0V8_SERDES_VDDA_PEX2")
		)
		(pad "Y20" smd circle
			(at -4.750054 -4.750054)
			(size 0.4572 0.4572)
			(layers "F.Cu" "F.Mask" "F.Paste")
			(net "P0V8_SERDES_VDDA_PEX2")
		)
		(pad "Y21" smd circle
			(at -3.800094 -4.750054)
			(size 0.4572 0.4572)
			(layers "F.Cu" "F.Mask" "F.Paste")
			(net "P0V8_SERDES_VDDA_PEX2")
		)
		(pad "Y22" smd circle
			(at -2.84988 -4.750054)
			(size 0.4572 0.4572)
			(layers "F.Cu" "F.Mask" "F.Paste")
			(net "P0V8_SERDES_VDDA_PEX2")
		)
		(pad "Y23" smd circle
			(at -1.89992 -4.750054)
			(size 0.4572 0.4572)
			(layers "F.Cu" "F.Mask" "F.Paste")
			(net "P0V8_SERDES_VDDA_PEX2")
		)
		(pad "Y24" smd circle
			(at -0.94996 -4.750054)
			(size 0.4572 0.4572)
			(layers "F.Cu" "F.Mask" "F.Paste")
			(net "P0V8_SERDES_VDDA_PEX2")
		)
		(pad "Y25" smd circle
			(at 0 -4.750054)
			(size 0.4572 0.4572)
			(layers "F.Cu" "F.Mask" "F.Paste")
			(net "P0V8_SERDES_VDDA_PEX2")
		)
		(pad "Y26" smd circle
			(at 0.94996 -4.750054)
			(size 0.4572 0.4572)
			(layers "F.Cu" "F.Mask" "F.Paste")
			(net "P0V8_SERDES_VDDA_PEX2")
		)
		(pad "Y27" smd circle
			(at 1.89992 -4.750054)
			(size 0.4572 0.4572)
			(layers "F.Cu" "F.Mask" "F.Paste")
			(net "P0V8_SERDES_VDDA_PEX2")
		)
		(pad "Y28" smd circle
			(at 2.84988 -4.750054)
			(size 0.4572 0.4572)
			(layers "F.Cu" "F.Mask" "F.Paste")
			(net "P0V8_SERDES_VDDA_PEX2")
		)
		(pad "Y29" smd circle
			(at 3.800094 -4.750054)
			(size 0.4572 0.4572)
			(layers "F.Cu" "F.Mask" "F.Paste")
			(net "P0V8_SERDES_VDDA_PEX2")
		)
		(pad "Y30" smd circle
			(at 4.750054 -4.750054)
			(size 0.4572 0.4572)
			(layers "F.Cu" "F.Mask" "F.Paste")
			(net "P0V8_SERDES_VDDA_PEX2")
		)
		(pad "Y31" smd circle
			(at 5.700014 -4.750054)
			(size 0.4572 0.4572)
			(layers "F.Cu" "F.Mask" "F.Paste")
			(net "P0V8_SERDES_VDDA_PEX2")
		)
		(pad "Y32" smd circle
			(at 6.649974 -4.750054)
			(size 0.4572 0.4572)
			(layers "F.Cu" "F.Mask" "F.Paste")
			(net "P0V8_SERDES_VDDA_PEX2")
		)
		(pad "Y33" smd circle
			(at 7.599934 -4.750054)
			(size 0.4572 0.4572)
			(layers "F.Cu" "F.Mask" "F.Paste")
			(net "P0V8_SERDES_VDDA_PEX2")
		)
		(pad "Y34" smd circle
			(at 8.549894 -4.750054)
			(size 0.4572 0.4572)
			(layers "F.Cu" "F.Mask" "F.Paste")
			(net "GND")
		)
		(pad "Y35" smd circle
			(at 9.500108 -4.750054)
			(size 0.4572 0.4572)
			(layers "F.Cu" "F.Mask" "F.Paste")
			(net "P1V8_PEX")
		)
		(pad "Y36" smd circle
			(at 10.450068 -4.750054)
			(size 0.4572 0.4572)
			(layers "F.Cu" "F.Mask" "F.Paste")
			(net "GND")
		)
		(pad "Y37" smd circle
			(at 11.400028 -4.750054)
			(size 0.4572 0.4572)
			(layers "F.Cu" "F.Mask" "F.Paste")
			(net "GND")
		)
		(pad "Y38" smd circle
			(at 12.349988 -4.750054)
			(size 0.4572 0.4572)
			(layers "F.Cu" "F.Mask" "F.Paste")
			(net "GND")
		)
		(pad "Y39" smd circle
			(at 13.299948 -4.750054)
			(size 0.4572 0.4572)
			(layers "F.Cu" "F.Mask" "F.Paste")
			(net "PEX2_ADCTEMP_VINP0")
		)
		(pad "Y40" smd circle
			(at 14.249908 -4.750054)
			(size 0.4572 0.4572)
			(layers "F.Cu" "F.Mask" "F.Paste")
			(net "GND")
		)
		(pad "Y41" smd circle
			(at 15.200122 -4.750054)
			(size 0.4572 0.4572)
			(layers "F.Cu" "F.Mask" "F.Paste")
			(net "Net_1665")
		)
		(pad "Y42" smd circle
			(at 16.150082 -4.750054)
			(size 0.4572 0.4572)
			(layers "F.Cu" "F.Mask" "F.Paste")
			(net "Net_1685")
		)
		(pad "Y43" smd circle
			(at 17.100042 -4.750054)
			(size 0.4572 0.4572)
			(layers "F.Cu" "F.Mask" "F.Paste")
			(net "GND")
		)
		(pad "Y44" smd circle
			(at 18.050002 -4.750054)
			(size 0.4572 0.4572)
			(layers "F.Cu" "F.Mask" "F.Paste")
			(net "GND")
		)
		(pad "Y45" smd circle
			(at 18.999962 -4.750054)
			(size 0.4572 0.4572)
			(layers "F.Cu" "F.Mask" "F.Paste")
			(net "GND")
		)
		(pad "Y46" smd circle
			(at 19.949922 -4.750054)
			(size 0.4572 0.4572)
			(layers "F.Cu" "F.Mask" "F.Paste")
			(net "GND")
		)
		(pad "Y47" smd circle
			(at 20.899882 -4.750054)
			(size 0.4572 0.4572)
			(layers "F.Cu" "F.Mask" "F.Paste")
			(net "GND")
		)
		(pad "Y48" smd circle
			(at 21.850096 -4.750054)
			(size 0.4572 0.4572)
			(layers "F.Cu" "F.Mask" "F.Paste")
			(net "Net_1597")
		)
		(pad "Y49" smd circle
			(at 22.800056 -4.750054)
			(size 0.4572 0.4572)
			(layers "F.Cu" "F.Mask" "F.Paste")
			(net "Net_1604")
		)
		(zone
			(layer "F.Cu")
			(hatch none 0.5)
			(connect_pads
				(clearance 0)
			)
			(min_thickness 0.25)
			(keepout
				(tracks allowed)
				(vias not_allowed)
				(pads allowed)
				(copperpour not_allowed)
				(footprints allowed)
			)
			(placement
				(enabled no)
				(sheetname "")
			)
			(fill
				(thermal_gap 0.5)
				(thermal_bridge_width 0.5)
				(island_removal_mode 0)
			)
			(polygon
				(pts
					(xy 292.12921 -319.741296) (xy 292.52037 -319.741296) (xy 292.52037 -295.62044) (xy 315.691266 -295.62044)
					(xy 315.691266 -295.22928) (xy 292.52037 -295.22928) (xy 292.52037 -272.058384) (xy 292.12921 -272.058384)
					(xy 292.12921 -295.22928) (xy 268.008354 -295.22928) (xy 268.008354 -295.62044) (xy 292.12921 -295.62044)
				)
			)
		)
	)
	(footprint ""
		(layer "F.Cu")
		(at 264.775696 -36.915598 -90)
		(property "Reference" "R5571"
			(at 0 0 270)
			(layer "F.SilkS")
			(hide yes)
			(effects
				(font
					(size 1.27 1.27)
				)
			)
		)
		(property "Value" ""
			(at 0 0 270)
			(layer "F.Fab")
			(effects
				(font
					(size 1.27 1.27)
				)
			)
		)
		(duplicate_pad_numbers_are_jumpers no)
		(fp_line
			(start -0.7874 0.4064)
			(end -0.7874 -0.4064)
			(stroke
				(width 0.1524)
				(type default)
			)
			(layer "F.SilkS")
		)
		(fp_line
			(start 0.7874 0.4064)
			(end -0.7874 0.4064)
			(stroke
				(width 0.1524)
				(type default)
			)
			(layer "F.SilkS")
		)
		(fp_line
			(start -0.7874 -0.4064)
			(end 0.7874 -0.4064)
			(stroke
				(width 0.1524)
				(type default)
			)
			(layer "F.SilkS")
		)
		(fp_line
			(start 0.7874 -0.4064)
			(end 0.7874 0.4064)
			(stroke
				(width 0.1524)
				(type default)
			)
			(layer "F.SilkS")
		)
		(fp_line
			(start -0.67945 0.3048)
			(end -0.67945 -0.305054)
			(stroke
				(width 0.1)
				(type default)
			)
			(layer "F.Fab")
		)
		(fp_line
			(start -0.12065 0.3048)
			(end -0.67945 0.3048)
			(stroke
				(width 0.1)
				(type default)
			)
			(layer "F.Fab")
		)
		(fp_line
			(start 0.120396 0.3048)
			(end 0.120396 0.2794)
			(stroke
				(width 0.1)
				(type default)
			)
			(layer "F.Fab")
		)
		(fp_line
			(start 0.67945 0.3048)
			(end 0.120396 0.3048)
			(stroke
				(width 0.1)
				(type default)
			)
			(layer "F.Fab")
		)
		(fp_line
			(start -0.12065 0.2794)
			(end -0.12065 0.3048)
			(stroke
				(width 0.1)
				(type default)
			)
			(layer "F.Fab")
		)
		(fp_line
			(start 0.120396 0.2794)
			(end -0.12065 0.2794)
			(stroke
				(width 0.1)
				(type default)
			)
			(layer "F.Fab")
		)
		(fp_line
			(start -0.12065 -0.2794)
			(end 0.12065 -0.2794)
			(stroke
				(width 0.1)
				(type default)
			)
			(layer "F.Fab")
		)
		(fp_line
			(start 0.12065 -0.2794)
			(end 0.12065 -0.3048)
			(stroke
				(width 0.1)
				(type default)
			)
			(layer "F.Fab")
		)
		(fp_line
			(start 0.12065 -0.3048)
			(end 0.67945 -0.3048)
			(stroke
				(width 0.1)
				(type default)
			)
			(layer "F.Fab")
		)
		(fp_line
			(start 0.67945 -0.3048)
			(end 0.67945 0.3048)
			(stroke
				(width 0.1)
				(type default)
			)
			(layer "F.Fab")
		)
		(fp_line
			(start -0.67945 -0.305054)
			(end -0.12065 -0.305054)
			(stroke
				(width 0.1)
				(type default)
			)
			(layer "F.Fab")
		)
		(fp_line
			(start -0.12065 -0.305054)
			(end -0.12065 -0.2794)
			(stroke
				(width 0.1)
				(type default)
			)
			(layer "F.Fab")
		)
		(pad "1" smd circle
			(at -0.40005 0 270)
			(size 0 0)
			(layers "F.Cu" "F.Mask" "F.Paste")
			(net "PRSNT_SSD9_R1_N")
		)
		(pad "2" smd circle
			(at 0.40005 0 270)
			(size 0 0)
			(layers "F.Cu" "F.Mask" "F.Paste")
			(net "PRSNT_SSD9_R_N")
		)
	)
	(footprint ""
		(layer "F.Cu")
		(at 82.661506 -152.511252 180)
		(property "Reference" "C5"
			(at 0 0 180)
			(layer "F.SilkS")
			(hide yes)
			(effects
				(font
					(size 1.27 1.27)
				)
			)
		)
		(property "Value" ""
			(at 0 0 180)
			(layer "F.Fab")
			(effects
				(font
					(size 1.27 1.27)
				)
			)
		)
		(duplicate_pad_numbers_are_jumpers no)
		(fp_line
			(start 0.299974 0.150114)
			(end -0.299974 0.150114)
			(stroke
				(width 0.1)
				(type default)
			)
			(layer "F.Fab")
		)
		(fp_line
			(start 0.299974 -0.150114)
			(end 0.299974 0.150114)
			(stroke
				(width 0.1)
				(type default)
			)
			(layer "F.Fab")
		)
		(fp_line
			(start -0.299974 0.150114)
			(end -0.299974 -0.150114)
			(stroke
				(width 0.1)
				(type default)
			)
			(layer "F.Fab")
		)
		(fp_line
			(start -0.299974 -0.150114)
			(end 0.299974 -0.150114)
			(stroke
				(width 0.1)
				(type default)
			)
			(layer "F.Fab")
		)
		(pad "1" smd rect
			(at -0.2667 0 180)
			(size 0.3048 0.381)
			(layers "F.Cu" "F.Mask" "F.Paste")
			(net "P5E_PEX0_STN0_TX_DP<13>")
		)
		(pad "2" smd rect
			(at 0.2667 0 180)
			(size 0.3048 0.381)
			(layers "F.Cu" "F.Mask" "F.Paste")
			(net "P5E_PEX0_STN0_TX_C_DP<13>")
		)
	)
	(footprint ""
		(layer "F.Cu")
		(at 55.356506 -155.819856 90)
		(property "Reference" "R46"
			(at 0 0 90)
			(layer "F.SilkS")
			(hide yes)
			(effects
				(font
					(size 1.27 1.27)
				)
			)
		)
		(property "Value" ""
			(at 0 0 90)
			(layer "F.Fab")
			(effects
				(font
					(size 1.27 1.27)
				)
			)
		)
		(duplicate_pad_numbers_are_jumpers no)
		(fp_line
			(start 0.7874 -0.4064)
			(end 0.7874 0.4064)
			(stroke
				(width 0.1524)
				(type default)
			)
			(layer "F.SilkS")
		)
		(fp_line
			(start -0.7874 -0.4064)
			(end 0.7874 -0.4064)
			(stroke
				(width 0.1524)
				(type default)
			)
			(layer "F.SilkS")
		)
		(fp_line
			(start 0.7874 0.4064)
			(end -0.7874 0.4064)
			(stroke
				(width 0.1524)
				(type default)
			)
			(layer "F.SilkS")
		)
		(fp_line
			(start -0.7874 0.4064)
			(end -0.7874 -0.4064)
			(stroke
				(width 0.1524)
				(type default)
			)
			(layer "F.SilkS")
		)
		(fp_line
			(start -0.12065 -0.305054)
			(end -0.12065 -0.2794)
			(stroke
				(width 0.1)
				(type default)
			)
			(layer "F.Fab")
		)
		(fp_line
			(start -0.67945 -0.305054)
			(end -0.12065 -0.305054)
			(stroke
				(width 0.1)
				(type default)
			)
			(layer "F.Fab")
		)
		(fp_line
			(start 0.67945 -0.3048)
			(end 0.67945 0.3048)
			(stroke
				(width 0.1)
				(type default)
			)
			(layer "F.Fab")
		)
		(fp_line
			(start 0.12065 -0.3048)
			(end 0.67945 -0.3048)
			(stroke
				(width 0.1)
				(type default)
			)
			(layer "F.Fab")
		)
		(fp_line
			(start 0.12065 -0.2794)
			(end 0.12065 -0.3048)
			(stroke
				(width 0.1)
				(type default)
			)
			(layer "F.Fab")
		)
		(fp_line
			(start -0.12065 -0.2794)
			(end 0.12065 -0.2794)
			(stroke
				(width 0.1)
				(type default)
			)
			(layer "F.Fab")
		)
		(fp_line
			(start 0.120396 0.2794)
			(end -0.12065 0.2794)
			(stroke
				(width 0.1)
				(type default)
			)
			(layer "F.Fab")
		)
		(fp_line
			(start -0.12065 0.2794)
			(end -0.12065 0.3048)
			(stroke
				(width 0.1)
				(type default)
			)
			(layer "F.Fab")
		)
		(fp_line
			(start 0.67945 0.3048)
			(end 0.120396 0.3048)
			(stroke
				(width 0.1)
				(type default)
			)
			(layer "F.Fab")
		)
		(fp_line
			(start 0.120396 0.3048)
			(end 0.120396 0.2794)
			(stroke
				(width 0.1)
				(type default)
			)
			(layer "F.Fab")
		)
		(fp_line
			(start -0.12065 0.3048)
			(end -0.67945 0.3048)
			(stroke
				(width 0.1)
				(type default)
			)
			(layer "F.Fab")
		)
		(fp_line
			(start -0.67945 0.3048)
			(end -0.67945 -0.305054)
			(stroke
				(width 0.1)
				(type default)
			)
			(layer "F.Fab")
		)
		(pad "1" smd circle
			(at -0.40005 0 90)
			(size 0 0)
			(layers "F.Cu" "F.Mask" "F.Paste")
			(net "RST_NIC0_PERST1_R_N")
		)
		(pad "2" smd circle
			(at 0.40005 0 90)
			(size 0 0)
			(layers "F.Cu" "F.Mask" "F.Paste")
			(net "RST_HP_NIC0_BUF_N")
		)
	)
	(footprint ""
		(layer "F.Cu")
		(at 242.730528 -142.035276 180)
		(property "Reference" "PC801"
			(at 0 0 180)
			(layer "F.SilkS")
			(hide yes)
			(effects
				(font
					(size 1.27 1.27)
				)
			)
		)
		(property "Value" ""
			(at 0 0 180)
			(layer "F.Fab")
			(effects
				(font
					(size 1.27 1.27)
				)
			)
		)
		(duplicate_pad_numbers_are_jumpers no)
		(fp_line
			(start 1.524 0.762)
			(end -1.524 0.762)
			(stroke
				(width 0.1524)
				(type default)
			)
			(layer "F.SilkS")
		)
		(fp_line
			(start 1.524 -0.762)
			(end 1.524 0.762)
			(stroke
				(width 0.1524)
				(type default)
			)
			(layer "F.SilkS")
		)
		(fp_line
			(start -1.524 0.762)
			(end -1.524 -0.762)
			(stroke
				(width 0.1524)
				(type default)
			)
			(layer "F.SilkS")
		)
		(fp_line
			(start -1.524 -0.762)
			(end 1.524 -0.762)
			(stroke
				(width 0.1524)
				(type default)
			)
			(layer "F.SilkS")
		)
		(fp_line
			(start 1.1049 0.724916)
			(end 1.1049 -0.724916)
			(stroke
				(width 0.1)
				(type default)
			)
			(layer "F.Fab")
		)
		(fp_line
			(start 1.1049 -0.724916)
			(end -1.1049 -0.724916)
			(stroke
				(width 0.1)
				(type default)
			)
			(layer "F.Fab")
		)
		(fp_line
			(start -1.1049 0.724916)
			(end 1.1049 0.724916)
			(stroke
				(width 0.1)
				(type default)
			)
			(layer "F.Fab")
		)
		(fp_line
			(start -1.1049 -0.724916)
			(end -1.1049 0.724916)
			(stroke
				(width 0.1)
				(type default)
			)
			(layer "F.Fab")
		)
		(pad "1" smd rect
			(at -0.889 0)
			(size 1.016 1.27)
			(layers "F.Cu" "F.Mask" "F.Paste")
			(net "P12V_NIC4_R")
		)
		(pad "2" smd rect
			(at 0.889 0)
			(size 1.016 1.27)
			(layers "F.Cu" "F.Mask" "F.Paste")
			(net "GND")
		)
	)
	(footprint ""
		(layer "F.Cu")
		(at 80.875124 -64.102234 180)
		(property "Reference" "PR6914"
			(at 0 0 180)
			(layer "F.SilkS")
			(hide yes)
			(effects
				(font
					(size 1.27 1.27)
				)
			)
		)
		(property "Value" ""
			(at 0 0 180)
			(layer "F.Fab")
			(effects
				(font
					(size 1.27 1.27)
				)
			)
		)
		(duplicate_pad_numbers_are_jumpers no)
		(fp_line
			(start 0.7874 0.4064)
			(end -0.7874 0.4064)
			(stroke
				(width 0.1524)
				(type default)
			)
			(layer "F.SilkS")
		)
		(fp_line
			(start 0.7874 -0.4064)
			(end 0.7874 0.4064)
			(stroke
				(width 0.1524)
				(type default)
			)
			(layer "F.SilkS")
		)
		(fp_line
			(start -0.7874 0.4064)
			(end -0.7874 -0.4064)
			(stroke
				(width 0.1524)
				(type default)
			)
			(layer "F.SilkS")
		)
		(fp_line
			(start -0.7874 -0.4064)
			(end 0.7874 -0.4064)
			(stroke
				(width 0.1524)
				(type default)
			)
			(layer "F.SilkS")
		)
		(fp_line
			(start 0.67945 0.3048)
			(end 0.120396 0.3048)
			(stroke
				(width 0.1)
				(type default)
			)
			(layer "F.Fab")
		)
		(fp_line
			(start 0.67945 -0.3048)
			(end 0.67945 0.3048)
			(stroke
				(width 0.1)
				(type default)
			)
			(layer "F.Fab")
		)
		(fp_line
			(start 0.12065 -0.2794)
			(end 0.12065 -0.3048)
			(stroke
				(width 0.1)
				(type default)
			)
			(layer "F.Fab")
		)
		(fp_line
			(start 0.12065 -0.3048)
			(end 0.67945 -0.3048)
			(stroke
				(width 0.1)
				(type default)
			)
			(layer "F.Fab")
		)
		(fp_line
			(start 0.120396 0.3048)
			(end 0.120396 0.2794)
			(stroke
				(width 0.1)
				(type default)
			)
			(layer "F.Fab")
		)
		(fp_line
			(start 0.120396 0.2794)
			(end -0.12065 0.2794)
			(stroke
				(width 0.1)
				(type default)
			)
			(layer "F.Fab")
		)
		(fp_line
			(start -0.12065 0.3048)
			(end -0.67945 0.3048)
			(stroke
				(width 0.1)
				(type default)
			)
			(layer "F.Fab")
		)
		(fp_line
			(start -0.12065 0.2794)
			(end -0.12065 0.3048)
			(stroke
				(width 0.1)
				(type default)
			)
			(layer "F.Fab")
		)
		(fp_line
			(start -0.12065 -0.2794)
			(end 0.12065 -0.2794)
			(stroke
				(width 0.1)
				(type default)
			)
			(layer "F.Fab")
		)
		(fp_line
			(start -0.12065 -0.305054)
			(end -0.12065 -0.2794)
			(stroke
				(width 0.1)
				(type default)
			)
			(layer "F.Fab")
		)
		(fp_line
			(start -0.67945 0.3048)
			(end -0.67945 -0.305054)
			(stroke
				(width 0.1)
				(type default)
			)
			(layer "F.Fab")
		)
		(fp_line
			(start -0.67945 -0.305054)
			(end -0.12065 -0.305054)
			(stroke
				(width 0.1)
				(type default)
			)
			(layer "F.Fab")
		)
		(pad "1" smd circle
			(at -0.40005 0 180)
			(size 0 0)
			(layers "F.Cu" "F.Mask" "F.Paste")
			(net "P12V_SSD3_PG_G1")
		)
		(pad "2" smd circle
			(at 0.40005 0 180)
			(size 0 0)
			(layers "F.Cu" "F.Mask" "F.Paste")
			(net "GND")
		)
	)
	(footprint ""
		(layer "F.Cu")
		(at 133.892544 -32.739584 180)
		(property "Reference" "C278"
			(at 0 0 180)
			(layer "F.SilkS")
			(hide yes)
			(effects
				(font
					(size 1.27 1.27)
				)
			)
		)
		(property "Value" ""
			(at 0 0 180)
			(layer "F.Fab")
			(effects
				(font
					(size 1.27 1.27)
				)
			)
		)
		(duplicate_pad_numbers_are_jumpers no)
		(fp_line
			(start 0.299974 0.150114)
			(end -0.299974 0.150114)
			(stroke
				(width 0.1)
				(type default)
			)
			(layer "F.Fab")
		)
		(fp_line
			(start 0.299974 -0.150114)
			(end 0.299974 0.150114)
			(stroke
				(width 0.1)
				(type default)
			)
			(layer "F.Fab")
		)
		(fp_line
			(start -0.299974 0.150114)
			(end -0.299974 -0.150114)
			(stroke
				(width 0.1)
				(type default)
			)
			(layer "F.Fab")
		)
		(fp_line
			(start -0.299974 -0.150114)
			(end 0.299974 -0.150114)
			(stroke
				(width 0.1)
				(type default)
			)
			(layer "F.Fab")
		)
		(pad "1" smd rect
			(at -0.2667 0 180)
			(size 0.3048 0.381)
			(layers "F.Cu" "F.Mask" "F.Paste")
			(net "P5E_PEX1_STN2_TX_DP<46>")
		)
		(pad "2" smd rect
			(at 0.2667 0 180)
			(size 0.3048 0.381)
			(layers "F.Cu" "F.Mask" "F.Paste")
			(net "P5E_PEX1_STN2_TX_C_DP<46>")
		)
	)
	(footprint ""
		(layer "F.Cu")
		(at 136.708388 -343.952322 90)
		(property "Reference" "C2251"
			(at 0 0 90)
			(layer "F.SilkS")
			(hide yes)
			(effects
				(font
					(size 1.27 1.27)
				)
			)
		)
		(property "Value" ""
			(at 0 0 90)
			(layer "F.Fab")
			(effects
				(font
					(size 1.27 1.27)
				)
			)
		)
		(duplicate_pad_numbers_are_jumpers no)
		(fp_line
			(start 0.299974 -0.150114)
			(end 0.299974 0.150114)
			(stroke
				(width 0.1)
				(type default)
			)
			(layer "F.Fab")
		)
		(fp_line
			(start -0.299974 -0.150114)
			(end 0.299974 -0.150114)
			(stroke
				(width 0.1)
				(type default)
			)
			(layer "F.Fab")
		)
		(fp_line
			(start 0.299974 0.150114)
			(end -0.299974 0.150114)
			(stroke
				(width 0.1)
				(type default)
			)
			(layer "F.Fab")
		)
		(fp_line
			(start -0.299974 0.150114)
			(end -0.299974 -0.150114)
			(stroke
				(width 0.1)
				(type default)
			)
			(layer "F.Fab")
		)
		(pad "1" smd rect
			(at -0.2667 0 90)
			(size 0.3048 0.381)
			(layers "F.Cu" "F.Mask" "F.Paste")
			(net "P5E_PEX1_STN5_TX_DP<91>")
		)
		(pad "2" smd rect
			(at 0.2667 0 90)
			(size 0.3048 0.381)
			(layers "F.Cu" "F.Mask" "F.Paste")
			(net "P5E_PEX1_STN5_TX_C_DP<91>")
		)
	)
	(footprint ""
		(layer "F.Cu")
		(at 406.36444 -140.6398 180)
		(property "Reference" "R344"
			(at 0 0 180)
			(layer "F.SilkS")
			(hide yes)
			(effects
				(font
					(size 1.27 1.27)
				)
			)
		)
		(property "Value" ""
			(at 0 0 180)
			(layer "F.Fab")
			(effects
				(font
					(size 1.27 1.27)
				)
			)
		)
		(duplicate_pad_numbers_are_jumpers no)
		(fp_line
			(start 0.7874 0.4064)
			(end -0.7874 0.4064)
			(stroke
				(width 0.1524)
				(type default)
			)
			(layer "F.SilkS")
		)
		(fp_line
			(start 0.7874 -0.4064)
			(end 0.7874 0.4064)
			(stroke
				(width 0.1524)
				(type default)
			)
			(layer "F.SilkS")
		)
		(fp_line
			(start -0.7874 0.4064)
			(end -0.7874 -0.4064)
			(stroke
				(width 0.1524)
				(type default)
			)
			(layer "F.SilkS")
		)
		(fp_line
			(start -0.7874 -0.4064)
			(end 0.7874 -0.4064)
			(stroke
				(width 0.1524)
				(type default)
			)
			(layer "F.SilkS")
		)
		(fp_line
			(start 0.67945 0.3048)
			(end 0.120396 0.3048)
			(stroke
				(width 0.1)
				(type default)
			)
			(layer "F.Fab")
		)
		(fp_line
			(start 0.67945 -0.3048)
			(end 0.67945 0.3048)
			(stroke
				(width 0.1)
				(type default)
			)
			(layer "F.Fab")
		)
		(fp_line
			(start 0.12065 -0.2794)
			(end 0.12065 -0.3048)
			(stroke
				(width 0.1)
				(type default)
			)
			(layer "F.Fab")
		)
		(fp_line
			(start 0.12065 -0.3048)
			(end 0.67945 -0.3048)
			(stroke
				(width 0.1)
				(type default)
			)
			(layer "F.Fab")
		)
		(fp_line
			(start 0.120396 0.3048)
			(end 0.120396 0.2794)
			(stroke
				(width 0.1)
				(type default)
			)
			(layer "F.Fab")
		)
		(fp_line
			(start 0.120396 0.2794)
			(end -0.12065 0.2794)
			(stroke
				(width 0.1)
				(type default)
			)
			(layer "F.Fab")
		)
		(fp_line
			(start -0.12065 0.3048)
			(end -0.67945 0.3048)
			(stroke
				(width 0.1)
				(type default)
			)
			(layer "F.Fab")
		)
		(fp_line
			(start -0.12065 0.2794)
			(end -0.12065 0.3048)
			(stroke
				(width 0.1)
				(type default)
			)
			(layer "F.Fab")
		)
		(fp_line
			(start -0.12065 -0.2794)
			(end 0.12065 -0.2794)
			(stroke
				(width 0.1)
				(type default)
			)
			(layer "F.Fab")
		)
		(fp_line
			(start -0.12065 -0.305054)
			(end -0.12065 -0.2794)
			(stroke
				(width 0.1)
				(type default)
			)
			(layer "F.Fab")
		)
		(fp_line
			(start -0.67945 0.3048)
			(end -0.67945 -0.305054)
			(stroke
				(width 0.1)
				(type default)
			)
			(layer "F.Fab")
		)
		(fp_line
			(start -0.67945 -0.305054)
			(end -0.12065 -0.305054)
			(stroke
				(width 0.1)
				(type default)
			)
			(layer "F.Fab")
		)
		(pad "1" smd circle
			(at -0.40005 0 180)
			(size 0 0)
			(layers "F.Cu" "F.Mask" "F.Paste")
			(net "RST_SMB_NIC6_MUX_ISO_N")
		)
		(pad "2" smd circle
			(at 0.40005 0 180)
			(size 0 0)
			(layers "F.Cu" "F.Mask" "F.Paste")
			(net "GND")
		)
	)
	(footprint ""
		(layer "F.Cu")
		(at 451.122034 -212.063076 90)
		(property "Reference" "C2613"
			(at 0 0 90)
			(layer "F.SilkS")
			(hide yes)
			(effects
				(font
					(size 1.27 1.27)
				)
			)
		)
		(property "Value" ""
			(at 0 0 90)
			(layer "F.Fab")
			(effects
				(font
					(size 1.27 1.27)
				)
			)
		)
		(duplicate_pad_numbers_are_jumpers no)
		(fp_line
			(start 0.7874 -0.4064)
			(end 0.7874 0.4064)
			(stroke
				(width 0.1524)
				(type default)
			)
			(layer "F.SilkS")
		)
		(fp_line
			(start -0.7874 -0.4064)
			(end 0.7874 -0.4064)
			(stroke
				(width 0.1524)
				(type default)
			)
			(layer "F.SilkS")
		)
		(fp_line
			(start 0.7874 0.4064)
			(end -0.7874 0.4064)
			(stroke
				(width 0.1524)
				(type default)
			)
			(layer "F.SilkS")
		)
		(fp_line
			(start -0.7874 0.4064)
			(end -0.7874 -0.4064)
			(stroke
				(width 0.1524)
				(type default)
			)
			(layer "F.SilkS")
		)
		(fp_line
			(start -0.12065 -0.305054)
			(end -0.12065 -0.2794)
			(stroke
				(width 0.1)
				(type default)
			)
			(layer "F.Fab")
		)
		(fp_line
			(start -0.67945 -0.305054)
			(end -0.12065 -0.305054)
			(stroke
				(width 0.1)
				(type default)
			)
			(layer "F.Fab")
		)
		(fp_line
			(start 0.67945 -0.3048)
			(end 0.67945 0.3048)
			(stroke
				(width 0.1)
				(type default)
			)
			(layer "F.Fab")
		)
		(fp_line
			(start 0.12065 -0.3048)
			(end 0.67945 -0.3048)
			(stroke
				(width 0.1)
				(type default)
			)
			(layer "F.Fab")
		)
		(fp_line
			(start 0.12065 -0.2794)
			(end 0.12065 -0.3048)
			(stroke
				(width 0.1)
				(type default)
			)
			(layer "F.Fab")
		)
		(fp_line
			(start -0.12065 -0.2794)
			(end 0.12065 -0.2794)
			(stroke
				(width 0.1)
				(type default)
			)
			(layer "F.Fab")
		)
		(fp_line
			(start 0.120396 0.2794)
			(end -0.12065 0.2794)
			(stroke
				(width 0.1)
				(type default)
			)
			(layer "F.Fab")
		)
		(fp_line
			(start -0.12065 0.2794)
			(end -0.12065 0.3048)
			(stroke
				(width 0.1)
				(type default)
			)
			(layer "F.Fab")
		)
		(fp_line
			(start 0.67945 0.3048)
			(end 0.120396 0.3048)
			(stroke
				(width 0.1)
				(type default)
			)
			(layer "F.Fab")
		)
		(fp_line
			(start 0.120396 0.3048)
			(end 0.120396 0.2794)
			(stroke
				(width 0.1)
				(type default)
			)
			(layer "F.Fab")
		)
		(fp_line
			(start -0.12065 0.3048)
			(end -0.67945 0.3048)
			(stroke
				(width 0.1)
				(type default)
			)
			(layer "F.Fab")
		)
		(fp_line
			(start -0.67945 0.3048)
			(end -0.67945 -0.305054)
			(stroke
				(width 0.1)
				(type default)
			)
			(layer "F.Fab")
		)
		(pad "1" smd circle
			(at -0.40005 0 90)
			(size 0 0)
			(layers "F.Cu" "F.Mask" "F.Paste")
			(net "USB_VBUS_CONN")
		)
		(pad "2" smd circle
			(at 0.40005 0 90)
			(size 0 0)
			(layers "F.Cu" "F.Mask" "F.Paste")
			(net "GND")
		)
	)
	(footprint ""
		(layer "F.Cu")
		(at 248.819924 -87.150448 180)
		(property "Reference" "R1465"
			(at 0 0 180)
			(layer "F.SilkS")
			(hide yes)
			(effects
				(font
					(size 1.27 1.27)
				)
			)
		)
		(property "Value" ""
			(at 0 0 180)
			(layer "F.Fab")
			(effects
				(font
					(size 1.27 1.27)
				)
			)
		)
		(duplicate_pad_numbers_are_jumpers no)
		(fp_line
			(start 0.7874 0.4064)
			(end -0.7874 0.4064)
			(stroke
				(width 0.1524)
				(type default)
			)
			(layer "F.SilkS")
		)
		(fp_line
			(start 0.7874 -0.4064)
			(end 0.7874 0.4064)
			(stroke
				(width 0.1524)
				(type default)
			)
			(layer "F.SilkS")
		)
		(fp_line
			(start -0.7874 0.4064)
			(end -0.7874 -0.4064)
			(stroke
				(width 0.1524)
				(type default)
			)
			(layer "F.SilkS")
		)
		(fp_line
			(start -0.7874 -0.4064)
			(end 0.7874 -0.4064)
			(stroke
				(width 0.1524)
				(type default)
			)
			(layer "F.SilkS")
		)
		(fp_line
			(start 0.67945 0.3048)
			(end 0.120396 0.3048)
			(stroke
				(width 0.1)
				(type default)
			)
			(layer "F.Fab")
		)
		(fp_line
			(start 0.67945 -0.3048)
			(end 0.67945 0.3048)
			(stroke
				(width 0.1)
				(type default)
			)
			(layer "F.Fab")
		)
		(fp_line
			(start 0.12065 -0.2794)
			(end 0.12065 -0.3048)
			(stroke
				(width 0.1)
				(type default)
			)
			(layer "F.Fab")
		)
		(fp_line
			(start 0.12065 -0.3048)
			(end 0.67945 -0.3048)
			(stroke
				(width 0.1)
				(type default)
			)
			(layer "F.Fab")
		)
		(fp_line
			(start 0.120396 0.3048)
			(end 0.120396 0.2794)
			(stroke
				(width 0.1)
				(type default)
			)
			(layer "F.Fab")
		)
		(fp_line
			(start 0.120396 0.2794)
			(end -0.12065 0.2794)
			(stroke
				(width 0.1)
				(type default)
			)
			(layer "F.Fab")
		)
		(fp_line
			(start -0.12065 0.3048)
			(end -0.67945 0.3048)
			(stroke
				(width 0.1)
				(type default)
			)
			(layer "F.Fab")
		)
		(fp_line
			(start -0.12065 0.2794)
			(end -0.12065 0.3048)
			(stroke
				(width 0.1)
				(type default)
			)
			(layer "F.Fab")
		)
		(fp_line
			(start -0.12065 -0.2794)
			(end 0.12065 -0.2794)
			(stroke
				(width 0.1)
				(type default)
			)
			(layer "F.Fab")
		)
		(fp_line
			(start -0.12065 -0.305054)
			(end -0.12065 -0.2794)
			(stroke
				(width 0.1)
				(type default)
			)
			(layer "F.Fab")
		)
		(fp_line
			(start -0.67945 0.3048)
			(end -0.67945 -0.305054)
			(stroke
				(width 0.1)
				(type default)
			)
			(layer "F.Fab")
		)
		(fp_line
			(start -0.67945 -0.305054)
			(end -0.12065 -0.305054)
			(stroke
				(width 0.1)
				(type default)
			)
			(layer "F.Fab")
		)
		(pad "1" smd circle
			(at -0.40005 0 180)
			(size 0 0)
			(layers "F.Cu" "F.Mask" "F.Paste")
			(net "SMB_CK440_CLK_SCL")
		)
		(pad "2" smd circle
			(at 0.40005 0 180)
			(size 0 0)
			(layers "F.Cu" "F.Mask" "F.Paste")
			(net "SMB_CLK_ISO_R_SCL_R1")
		)
	)
	(footprint ""
		(layer "F.Cu")
		(at 275.710396 -414.88995 90)
		(property "Reference" "R1810"
			(at 0 0 90)
			(layer "F.SilkS")
			(hide yes)
			(effects
				(font
					(size 1.27 1.27)
				)
			)
		)
		(property "Value" ""
			(at 0 0 90)
			(layer "F.Fab")
			(effects
				(font
					(size 1.27 1.27)
				)
			)
		)
		(duplicate_pad_numbers_are_jumpers no)
		(fp_line
			(start 0.7874 -0.4064)
			(end 0.7874 0.4064)
			(stroke
				(width 0.1524)
				(type default)
			)
			(layer "F.SilkS")
		)
		(fp_line
			(start -0.7874 -0.4064)
			(end 0.7874 -0.4064)
			(stroke
				(width 0.1524)
				(type default)
			)
			(layer "F.SilkS")
		)
		(fp_line
			(start 0.7874 0.4064)
			(end -0.7874 0.4064)
			(stroke
				(width 0.1524)
				(type default)
			)
			(layer "F.SilkS")
		)
		(fp_line
			(start -0.7874 0.4064)
			(end -0.7874 -0.4064)
			(stroke
				(width 0.1524)
				(type default)
			)
			(layer "F.SilkS")
		)
		(fp_line
			(start -0.12065 -0.305054)
			(end -0.12065 -0.2794)
			(stroke
				(width 0.1)
				(type default)
			)
			(layer "F.Fab")
		)
		(fp_line
			(start -0.67945 -0.305054)
			(end -0.12065 -0.305054)
			(stroke
				(width 0.1)
				(type default)
			)
			(layer "F.Fab")
		)
		(fp_line
			(start 0.67945 -0.3048)
			(end 0.67945 0.3048)
			(stroke
				(width 0.1)
				(type default)
			)
			(layer "F.Fab")
		)
		(fp_line
			(start 0.12065 -0.3048)
			(end 0.67945 -0.3048)
			(stroke
				(width 0.1)
				(type default)
			)
			(layer "F.Fab")
		)
		(fp_line
			(start 0.12065 -0.2794)
			(end 0.12065 -0.3048)
			(stroke
				(width 0.1)
				(type default)
			)
			(layer "F.Fab")
		)
		(fp_line
			(start -0.12065 -0.2794)
			(end 0.12065 -0.2794)
			(stroke
				(width 0.1)
				(type default)
			)
			(layer "F.Fab")
		)
		(fp_line
			(start 0.120396 0.2794)
			(end -0.12065 0.2794)
			(stroke
				(width 0.1)
				(type default)
			)
			(layer "F.Fab")
		)
		(fp_line
			(start -0.12065 0.2794)
			(end -0.12065 0.3048)
			(stroke
				(width 0.1)
				(type default)
			)
			(layer "F.Fab")
		)
		(fp_line
			(start 0.67945 0.3048)
			(end 0.120396 0.3048)
			(stroke
				(width 0.1)
				(type default)
			)
			(layer "F.Fab")
		)
		(fp_line
			(start 0.120396 0.3048)
			(end 0.120396 0.2794)
			(stroke
				(width 0.1)
				(type default)
			)
			(layer "F.Fab")
		)
		(fp_line
			(start -0.12065 0.3048)
			(end -0.67945 0.3048)
			(stroke
				(width 0.1)
				(type default)
			)
			(layer "F.Fab")
		)
		(fp_line
			(start -0.67945 0.3048)
			(end -0.67945 -0.305054)
			(stroke
				(width 0.1)
				(type default)
			)
			(layer "F.Fab")
		)
		(pad "1" smd circle
			(at -0.40005 0 90)
			(size 0 0)
			(layers "F.Cu" "F.Mask" "F.Paste")
			(net "P3V3_AUX")
		)
		(pad "2" smd circle
			(at 0.40005 0 90)
			(size 0 0)
			(layers "F.Cu" "F.Mask" "F.Paste")
			(net "RST_MB_BMC_N")
		)
	)
	(footprint ""
		(layer "F.Cu")
		(at 224.022158 -81.627472 180)
		(property "Reference" "R4350"
			(at 0 0 180)
			(layer "F.SilkS")
			(hide yes)
			(effects
				(font
					(size 1.27 1.27)
				)
			)
		)
		(property "Value" ""
			(at 0 0 180)
			(layer "F.Fab")
			(effects
				(font
					(size 1.27 1.27)
				)
			)
		)
		(duplicate_pad_numbers_are_jumpers no)
		(fp_line
			(start 0.7874 0.4064)
			(end -0.7874 0.4064)
			(stroke
				(width 0.1524)
				(type default)
			)
			(layer "F.SilkS")
		)
		(fp_line
			(start 0.7874 -0.4064)
			(end 0.7874 0.4064)
			(stroke
				(width 0.1524)
				(type default)
			)
			(layer "F.SilkS")
		)
		(fp_line
			(start -0.7874 0.4064)
			(end -0.7874 -0.4064)
			(stroke
				(width 0.1524)
				(type default)
			)
			(layer "F.SilkS")
		)
		(fp_line
			(start -0.7874 -0.4064)
			(end 0.7874 -0.4064)
			(stroke
				(width 0.1524)
				(type default)
			)
			(layer "F.SilkS")
		)
		(fp_line
			(start 0.67945 0.3048)
			(end 0.120396 0.3048)
			(stroke
				(width 0.1)
				(type default)
			)
			(layer "F.Fab")
		)
		(fp_line
			(start 0.67945 -0.3048)
			(end 0.67945 0.3048)
			(stroke
				(width 0.1)
				(type default)
			)
			(layer "F.Fab")
		)
		(fp_line
			(start 0.12065 -0.2794)
			(end 0.12065 -0.3048)
			(stroke
				(width 0.1)
				(type default)
			)
			(layer "F.Fab")
		)
		(fp_line
			(start 0.12065 -0.3048)
			(end 0.67945 -0.3048)
			(stroke
				(width 0.1)
				(type default)
			)
			(layer "F.Fab")
		)
		(fp_line
			(start 0.120396 0.3048)
			(end 0.120396 0.2794)
			(stroke
				(width 0.1)
				(type default)
			)
			(layer "F.Fab")
		)
		(fp_line
			(start 0.120396 0.2794)
			(end -0.12065 0.2794)
			(stroke
				(width 0.1)
				(type default)
			)
			(layer "F.Fab")
		)
		(fp_line
			(start -0.12065 0.3048)
			(end -0.67945 0.3048)
			(stroke
				(width 0.1)
				(type default)
			)
			(layer "F.Fab")
		)
		(fp_line
			(start -0.12065 0.2794)
			(end -0.12065 0.3048)
			(stroke
				(width 0.1)
				(type default)
			)
			(layer "F.Fab")
		)
		(fp_line
			(start -0.12065 -0.2794)
			(end 0.12065 -0.2794)
			(stroke
				(width 0.1)
				(type default)
			)
			(layer "F.Fab")
		)
		(fp_line
			(start -0.12065 -0.305054)
			(end -0.12065 -0.2794)
			(stroke
				(width 0.1)
				(type default)
			)
			(layer "F.Fab")
		)
		(fp_line
			(start -0.67945 0.3048)
			(end -0.67945 -0.305054)
			(stroke
				(width 0.1)
				(type default)
			)
			(layer "F.Fab")
		)
		(fp_line
			(start -0.67945 -0.305054)
			(end -0.12065 -0.305054)
			(stroke
				(width 0.1)
				(type default)
			)
			(layer "F.Fab")
		)
		(pad "1" smd circle
			(at -0.40005 0 180)
			(size 0 0)
			(layers "F.Cu" "F.Mask" "F.Paste")
			(net "P3V3_AUX")
		)
		(pad "2" smd circle
			(at 0.40005 0 180)
			(size 0 0)
			(layers "F.Cu" "F.Mask" "F.Paste")
			(net "SSD12_LED_R")
		)
	)
	(footprint ""
		(layer "F.Cu")
		(at 355.61524 -20.72513)
		(property "Reference" "H104"
			(at 1.45288 -2.643886 0)
			(unlocked yes)
			(layer "B.SilkS")
			(effects
				(font
					(size 0.7874 0.5842)
					(thickness 0.1524)
				)
				(justify left mirror)
			)
		)
		(property "Value" ""
			(at 0 0 0)
			(layer "F.Fab")
			(effects
				(font
					(size 1.27 1.27)
				)
			)
		)
		(duplicate_pad_numbers_are_jumpers no)
		(pad "1" thru_hole rect
			(at 0 0)
			(size 4.2164 5.0038)
			(drill 2.0066
				(offset 0.099822 0)
			)
			(layers "*.Cu" "*.Mask")
			(remove_unused_layers no)
			(net "Net_8559")
			(clearance -0.8509)
			(padstack
				(mode front_inner_back)
				(layer "Inner"
					(shape circle)
					(size 4.0132 4.0132)
					(clearance -0.7493)
				)
				(layer "B.Cu"
					(shape circle)
					(size 4.0132 4.0132)
					(clearance -0.7493)
				)
			)
		)
	)
	(footprint ""
		(layer "F.Cu")
		(at 313.354974 -53.468524 90)
		(property "Reference" "PC583"
			(at 0 0 90)
			(layer "F.SilkS")
			(hide yes)
			(effects
				(font
					(size 1.27 1.27)
				)
			)
		)
		(property "Value" ""
			(at 0 0 90)
			(layer "F.Fab")
			(effects
				(font
					(size 1.27 1.27)
				)
			)
		)
		(duplicate_pad_numbers_are_jumpers no)
		(fp_line
			(start 1.524 -0.762)
			(end 1.524 0.762)
			(stroke
				(width 0.1524)
				(type default)
			)
			(layer "F.SilkS")
		)
		(fp_line
			(start -1.524 -0.762)
			(end 1.524 -0.762)
			(stroke
				(width 0.1524)
				(type default)
			)
			(layer "F.SilkS")
		)
		(fp_line
			(start 1.524 0.762)
			(end -1.524 0.762)
			(stroke
				(width 0.1524)
				(type default)
			)
			(layer "F.SilkS")
		)
		(fp_line
			(start -1.524 0.762)
			(end -1.524 -0.762)
			(stroke
				(width 0.1524)
				(type default)
			)
			(layer "F.SilkS")
		)
		(fp_line
			(start 1.1049 -0.724916)
			(end -1.1049 -0.724916)
			(stroke
				(width 0.1)
				(type default)
			)
			(layer "F.Fab")
		)
		(fp_line
			(start -1.1049 -0.724916)
			(end -1.1049 0.724916)
			(stroke
				(width 0.1)
				(type default)
			)
			(layer "F.Fab")
		)
		(fp_line
			(start 1.1049 0.724916)
			(end 1.1049 -0.724916)
			(stroke
				(width 0.1)
				(type default)
			)
			(layer "F.Fab")
		)
		(fp_line
			(start -1.1049 0.724916)
			(end 1.1049 0.724916)
			(stroke
				(width 0.1)
				(type default)
			)
			(layer "F.Fab")
		)
		(pad "1" smd rect
			(at -0.889 0 270)
			(size 1.016 1.27)
			(layers "F.Cu" "F.Mask" "F.Paste")
			(net "GND")
		)
		(pad "2" smd rect
			(at 0.889 0 270)
			(size 1.016 1.27)
			(layers "F.Cu" "F.Mask" "F.Paste")
			(net "P3V3_AUX")
		)
	)
	(footprint ""
		(layer "F.Cu")
		(at 238.219488 -225.427032 180)
		(property "Reference" "R6596"
			(at 0 0 180)
			(layer "F.SilkS")
			(hide yes)
			(effects
				(font
					(size 1.27 1.27)
				)
			)
		)
		(property "Value" ""
			(at 0 0 180)
			(layer "F.Fab")
			(effects
				(font
					(size 1.27 1.27)
				)
			)
		)
		(duplicate_pad_numbers_are_jumpers no)
		(fp_line
			(start 0.7874 0.4064)
			(end -0.7874 0.4064)
			(stroke
				(width 0.1524)
				(type default)
			)
			(layer "F.SilkS")
		)
		(fp_line
			(start 0.7874 -0.4064)
			(end 0.7874 0.4064)
			(stroke
				(width 0.1524)
				(type default)
			)
			(layer "F.SilkS")
		)
		(fp_line
			(start -0.7874 0.4064)
			(end -0.7874 -0.4064)
			(stroke
				(width 0.1524)
				(type default)
			)
			(layer "F.SilkS")
		)
		(fp_line
			(start -0.7874 -0.4064)
			(end 0.7874 -0.4064)
			(stroke
				(width 0.1524)
				(type default)
			)
			(layer "F.SilkS")
		)
		(fp_line
			(start 0.67945 0.3048)
			(end 0.120396 0.3048)
			(stroke
				(width 0.1)
				(type default)
			)
			(layer "F.Fab")
		)
		(fp_line
			(start 0.67945 -0.3048)
			(end 0.67945 0.3048)
			(stroke
				(width 0.1)
				(type default)
			)
			(layer "F.Fab")
		)
		(fp_line
			(start 0.12065 -0.2794)
			(end 0.12065 -0.3048)
			(stroke
				(width 0.1)
				(type default)
			)
			(layer "F.Fab")
		)
		(fp_line
			(start 0.12065 -0.3048)
			(end 0.67945 -0.3048)
			(stroke
				(width 0.1)
				(type default)
			)
			(layer "F.Fab")
		)
		(fp_line
			(start 0.120396 0.3048)
			(end 0.120396 0.2794)
			(stroke
				(width 0.1)
				(type default)
			)
			(layer "F.Fab")
		)
		(fp_line
			(start 0.120396 0.2794)
			(end -0.12065 0.2794)
			(stroke
				(width 0.1)
				(type default)
			)
			(layer "F.Fab")
		)
		(fp_line
			(start -0.12065 0.3048)
			(end -0.67945 0.3048)
			(stroke
				(width 0.1)
				(type default)
			)
			(layer "F.Fab")
		)
		(fp_line
			(start -0.12065 0.2794)
			(end -0.12065 0.3048)
			(stroke
				(width 0.1)
				(type default)
			)
			(layer "F.Fab")
		)
		(fp_line
			(start -0.12065 -0.2794)
			(end 0.12065 -0.2794)
			(stroke
				(width 0.1)
				(type default)
			)
			(layer "F.Fab")
		)
		(fp_line
			(start -0.12065 -0.305054)
			(end -0.12065 -0.2794)
			(stroke
				(width 0.1)
				(type default)
			)
			(layer "F.Fab")
		)
		(fp_line
			(start -0.67945 0.3048)
			(end -0.67945 -0.305054)
			(stroke
				(width 0.1)
				(type default)
			)
			(layer "F.Fab")
		)
		(fp_line
			(start -0.67945 -0.305054)
			(end -0.12065 -0.305054)
			(stroke
				(width 0.1)
				(type default)
			)
			(layer "F.Fab")
		)
		(pad "1" smd circle
			(at -0.40005 0 180)
			(size 0 0)
			(layers "F.Cu" "F.Mask" "F.Paste")
			(net "P1V8_PLL0_PEX3_SCALED")
		)
		(pad "2" smd circle
			(at 0.40005 0 180)
			(size 0 0)
			(layers "F.Cu" "F.Mask" "F.Paste")
			(net "GND")
		)
	)
	(footprint ""
		(layer "F.Cu")
		(at 199.756268 -61.487812 180)
		(property "Reference" "R5983"
			(at 0 0 180)
			(layer "F.SilkS")
			(hide yes)
			(effects
				(font
					(size 1.27 1.27)
				)
			)
		)
		(property "Value" ""
			(at 0 0 180)
			(layer "F.Fab")
			(effects
				(font
					(size 1.27 1.27)
				)
			)
		)
		(duplicate_pad_numbers_are_jumpers no)
		(fp_line
			(start 0.7874 0.4064)
			(end -0.7874 0.4064)
			(stroke
				(width 0.1524)
				(type default)
			)
			(layer "F.SilkS")
		)
		(fp_line
			(start 0.7874 -0.4064)
			(end 0.7874 0.4064)
			(stroke
				(width 0.1524)
				(type default)
			)
			(layer "F.SilkS")
		)
		(fp_line
			(start -0.7874 0.4064)
			(end -0.7874 -0.4064)
			(stroke
				(width 0.1524)
				(type default)
			)
			(layer "F.SilkS")
		)
		(fp_line
			(start -0.7874 -0.4064)
			(end 0.7874 -0.4064)
			(stroke
				(width 0.1524)
				(type default)
			)
			(layer "F.SilkS")
		)
		(fp_line
			(start 0.67945 0.3048)
			(end 0.120396 0.3048)
			(stroke
				(width 0.1)
				(type default)
			)
			(layer "F.Fab")
		)
		(fp_line
			(start 0.67945 -0.3048)
			(end 0.67945 0.3048)
			(stroke
				(width 0.1)
				(type default)
			)
			(layer "F.Fab")
		)
		(fp_line
			(start 0.12065 -0.2794)
			(end 0.12065 -0.3048)
			(stroke
				(width 0.1)
				(type default)
			)
			(layer "F.Fab")
		)
		(fp_line
			(start 0.12065 -0.3048)
			(end 0.67945 -0.3048)
			(stroke
				(width 0.1)
				(type default)
			)
			(layer "F.Fab")
		)
		(fp_line
			(start 0.120396 0.3048)
			(end 0.120396 0.2794)
			(stroke
				(width 0.1)
				(type default)
			)
			(layer "F.Fab")
		)
		(fp_line
			(start 0.120396 0.2794)
			(end -0.12065 0.2794)
			(stroke
				(width 0.1)
				(type default)
			)
			(layer "F.Fab")
		)
		(fp_line
			(start -0.12065 0.3048)
			(end -0.67945 0.3048)
			(stroke
				(width 0.1)
				(type default)
			)
			(layer "F.Fab")
		)
		(fp_line
			(start -0.12065 0.2794)
			(end -0.12065 0.3048)
			(stroke
				(width 0.1)
				(type default)
			)
			(layer "F.Fab")
		)
		(fp_line
			(start -0.12065 -0.2794)
			(end 0.12065 -0.2794)
			(stroke
				(width 0.1)
				(type default)
			)
			(layer "F.Fab")
		)
		(fp_line
			(start -0.12065 -0.305054)
			(end -0.12065 -0.2794)
			(stroke
				(width 0.1)
				(type default)
			)
			(layer "F.Fab")
		)
		(fp_line
			(start -0.67945 0.3048)
			(end -0.67945 -0.305054)
			(stroke
				(width 0.1)
				(type default)
			)
			(layer "F.Fab")
		)
		(fp_line
			(start -0.67945 -0.305054)
			(end -0.12065 -0.305054)
			(stroke
				(width 0.1)
				(type default)
			)
			(layer "F.Fab")
		)
		(pad "1" smd circle
			(at -0.40005 0 180)
			(size 0 0)
			(layers "F.Cu" "F.Mask" "F.Paste")
			(net "P3V3_AUX")
		)
		(pad "2" smd circle
			(at 0.40005 0 180)
			(size 0 0)
			(layers "F.Cu" "F.Mask" "F.Paste")
			(net "PWRGD_P12V_SSD7_D")
		)
	)
	(footprint ""
		(layer "F.Cu")
		(at 214.75954 -61.612526)
		(property "Reference" "PD20"
			(at -3.7084 -2.733548 0)
			(unlocked yes)
			(layer "F.SilkS")
			(effects
				(font
					(size 0.7874 0.5842)
					(thickness 0.1524)
				)
				(justify left)
			)
		)
		(property "Value" ""
			(at 0 0 0)
			(layer "F.Fab")
			(effects
				(font
					(size 1.27 1.27)
				)
			)
		)
		(duplicate_pad_numbers_are_jumpers no)
		(fp_line
			(start -3.656584 -1.970024)
			(end -3.656584 1.970024)
			(stroke
				(width 0.1524)
				(type default)
			)
			(layer "F.SilkS")
		)
		(fp_line
			(start -3.656584 1.970024)
			(end 4.240784 1.970024)
			(stroke
				(width 0.1524)
				(type default)
			)
			(layer "F.SilkS")
		)
		(fp_line
			(start 4.240784 -1.970024)
			(end -3.656584 -1.970024)
			(stroke
				(width 0.1524)
				(type default)
			)
			(layer "F.SilkS")
		)
		(fp_line
			(start 4.240784 1.970024)
			(end 4.240784 -1.970024)
			(stroke
				(width 0.1524)
				(type default)
			)
			(layer "F.SilkS")
		)
		(fp_poly
			(pts
				(xy 3.580384 1.970024) (xy 3.580384 -1.970024) (xy 4.240784 -1.970024) (xy 4.240784 1.970024)
			)
			(stroke
				(width 0)
				(type default)
			)
			(fill yes)
			(layer "F.SilkS")
		)
		(fp_line
			(start -2.3749 -1.970024)
			(end -2.3749 1.970024)
			(stroke
				(width 0.1)
				(type default)
			)
			(layer "F.Fab")
		)
		(fp_line
			(start -2.3749 1.970024)
			(end 2.3749 1.970024)
			(stroke
				(width 0.1)
				(type default)
			)
			(layer "F.Fab")
		)
		(fp_line
			(start 2.3749 -1.970024)
			(end -2.3749 -1.970024)
			(stroke
				(width 0.1)
				(type default)
			)
			(layer "F.Fab")
		)
		(fp_line
			(start 2.3749 1.970024)
			(end 2.3749 -1.970024)
			(stroke
				(width 0.1)
				(type default)
			)
			(layer "F.Fab")
		)
		(fp_text user "+"
			(at -4.9784 -0.23495 0)
			(unlocked yes)
			(layer "F.Fab")
			(effects
				(font
					(size 1.905 1.4224)
					(thickness 0.1524)
				)
				(justify left)
			)
		)
		(fp_text user "-"
			(at 4.1656 -0.23495 0)
			(unlocked yes)
			(layer "F.Fab")
			(effects
				(font
					(size 1.905 1.4224)
					(thickness 0.1524)
				)
				(justify left)
			)
		)
		(pad "A" smd rect
			(at -2.450084 0)
			(size 2.159 2.2606)
			(layers "F.Cu" "F.Mask" "F.Paste")
			(net "GND")
		)
		(pad "C" smd rect
			(at 2.450084 0)
			(size 2.159 2.2606)
			(layers "F.Cu" "F.Mask" "F.Paste")
			(net "P12V_AUX")
		)
	)
	(footprint ""
		(layer "F.Cu")
		(at 98.947224 -21.37156)
		(property "Reference" "C3896"
			(at 0 0 0)
			(layer "F.SilkS")
			(hide yes)
			(effects
				(font
					(size 1.27 1.27)
				)
			)
		)
		(property "Value" ""
			(at 0 0 0)
			(layer "F.Fab")
			(effects
				(font
					(size 1.27 1.27)
				)
			)
		)
		(duplicate_pad_numbers_are_jumpers no)
		(fp_line
			(start -0.7874 -0.4064)
			(end 0.7874 -0.4064)
			(stroke
				(width 0.1524)
				(type default)
			)
			(layer "F.SilkS")
		)
		(fp_line
			(start -0.7874 0.4064)
			(end -0.7874 -0.4064)
			(stroke
				(width 0.1524)
				(type default)
			)
			(layer "F.SilkS")
		)
		(fp_line
			(start 0.7874 -0.4064)
			(end 0.7874 0.4064)
			(stroke
				(width 0.1524)
				(type default)
			)
			(layer "F.SilkS")
		)
		(fp_line
			(start 0.7874 0.4064)
			(end -0.7874 0.4064)
			(stroke
				(width 0.1524)
				(type default)
			)
			(layer "F.SilkS")
		)
		(fp_line
			(start -0.67945 -0.305054)
			(end -0.12065 -0.305054)
			(stroke
				(width 0.1)
				(type default)
			)
			(layer "F.Fab")
		)
		(fp_line
			(start -0.67945 0.3048)
			(end -0.67945 -0.305054)
			(stroke
				(width 0.1)
				(type default)
			)
			(layer "F.Fab")
		)
		(fp_line
			(start -0.12065 -0.305054)
			(end -0.12065 -0.2794)
			(stroke
				(width 0.1)
				(type default)
			)
			(layer "F.Fab")
		)
		(fp_line
			(start -0.12065 -0.2794)
			(end 0.12065 -0.2794)
			(stroke
				(width 0.1)
				(type default)
			)
			(layer "F.Fab")
		)
		(fp_line
			(start -0.12065 0.2794)
			(end -0.12065 0.3048)
			(stroke
				(width 0.1)
				(type default)
			)
			(layer "F.Fab")
		)
		(fp_line
			(start -0.12065 0.3048)
			(end -0.67945 0.3048)
			(stroke
				(width 0.1)
				(type default)
			)
			(layer "F.Fab")
		)
		(fp_line
			(start 0.120396 0.2794)
			(end -0.12065 0.2794)
			(stroke
				(width 0.1)
				(type default)
			)
			(layer "F.Fab")
		)
		(fp_line
			(start 0.120396 0.3048)
			(end 0.120396 0.2794)
			(stroke
				(width 0.1)
				(type default)
			)
			(layer "F.Fab")
		)
		(fp_line
			(start 0.12065 -0.3048)
			(end 0.67945 -0.3048)
			(stroke
				(width 0.1)
				(type default)
			)
			(layer "F.Fab")
		)
		(fp_line
			(start 0.12065 -0.2794)
			(end 0.12065 -0.3048)
			(stroke
				(width 0.1)
				(type default)
			)
			(layer "F.Fab")
		)
		(fp_line
			(start 0.67945 -0.3048)
			(end 0.67945 0.3048)
			(stroke
				(width 0.1)
				(type default)
			)
			(layer "F.Fab")
		)
		(fp_line
			(start 0.67945 0.3048)
			(end 0.120396 0.3048)
			(stroke
				(width 0.1)
				(type default)
			)
			(layer "F.Fab")
		)
		(pad "1" smd circle
			(at -0.40005 0)
			(size 0 0)
			(layers "F.Cu" "F.Mask" "F.Paste")
			(net "P12V_SSD3")
		)
		(pad "2" smd circle
			(at 0.40005 0)
			(size 0 0)
			(layers "F.Cu" "F.Mask" "F.Paste")
			(net "GND")
		)
	)
	(footprint ""
		(layer "F.Cu")
		(at 235.623608 -141.640814)
		(property "Reference" "R4195"
			(at 0 0 0)
			(layer "F.SilkS")
			(hide yes)
			(effects
				(font
					(size 1.27 1.27)
				)
			)
		)
		(property "Value" ""
			(at 0 0 0)
			(layer "F.Fab")
			(effects
				(font
					(size 1.27 1.27)
				)
			)
		)
		(duplicate_pad_numbers_are_jumpers no)
		(fp_line
			(start -0.7874 -0.4064)
			(end 0.7874 -0.4064)
			(stroke
				(width 0.1524)
				(type default)
			)
			(layer "F.SilkS")
		)
		(fp_line
			(start -0.7874 0.4064)
			(end -0.7874 -0.4064)
			(stroke
				(width 0.1524)
				(type default)
			)
			(layer "F.SilkS")
		)
		(fp_line
			(start 0.7874 -0.4064)
			(end 0.7874 0.4064)
			(stroke
				(width 0.1524)
				(type default)
			)
			(layer "F.SilkS")
		)
		(fp_line
			(start 0.7874 0.4064)
			(end -0.7874 0.4064)
			(stroke
				(width 0.1524)
				(type default)
			)
			(layer "F.SilkS")
		)
		(fp_line
			(start -0.67945 -0.305054)
			(end -0.12065 -0.305054)
			(stroke
				(width 0.1)
				(type default)
			)
			(layer "F.Fab")
		)
		(fp_line
			(start -0.67945 0.3048)
			(end -0.67945 -0.305054)
			(stroke
				(width 0.1)
				(type default)
			)
			(layer "F.Fab")
		)
		(fp_line
			(start -0.12065 -0.305054)
			(end -0.12065 -0.2794)
			(stroke
				(width 0.1)
				(type default)
			)
			(layer "F.Fab")
		)
		(fp_line
			(start -0.12065 -0.2794)
			(end 0.12065 -0.2794)
			(stroke
				(width 0.1)
				(type default)
			)
			(layer "F.Fab")
		)
		(fp_line
			(start -0.12065 0.2794)
			(end -0.12065 0.3048)
			(stroke
				(width 0.1)
				(type default)
			)
			(layer "F.Fab")
		)
		(fp_line
			(start -0.12065 0.3048)
			(end -0.67945 0.3048)
			(stroke
				(width 0.1)
				(type default)
			)
			(layer "F.Fab")
		)
		(fp_line
			(start 0.120396 0.2794)
			(end -0.12065 0.2794)
			(stroke
				(width 0.1)
				(type default)
			)
			(layer "F.Fab")
		)
		(fp_line
			(start 0.120396 0.3048)
			(end 0.120396 0.2794)
			(stroke
				(width 0.1)
				(type default)
			)
			(layer "F.Fab")
		)
		(fp_line
			(start 0.12065 -0.3048)
			(end 0.67945 -0.3048)
			(stroke
				(width 0.1)
				(type default)
			)
			(layer "F.Fab")
		)
		(fp_line
			(start 0.12065 -0.2794)
			(end 0.12065 -0.3048)
			(stroke
				(width 0.1)
				(type default)
			)
			(layer "F.Fab")
		)
		(fp_line
			(start 0.67945 -0.3048)
			(end 0.67945 0.3048)
			(stroke
				(width 0.1)
				(type default)
			)
			(layer "F.Fab")
		)
		(fp_line
			(start 0.67945 0.3048)
			(end 0.120396 0.3048)
			(stroke
				(width 0.1)
				(type default)
			)
			(layer "F.Fab")
		)
		(pad "1" smd circle
			(at -0.40005 0)
			(size 0 0)
			(layers "F.Cu" "F.Mask" "F.Paste")
			(net "CK440_PEX_SS_EN")
		)
		(pad "2" smd circle
			(at 0.40005 0)
			(size 0 0)
			(layers "F.Cu" "F.Mask" "F.Paste")
			(net "P3V3")
		)
	)
	(footprint ""
		(layer "F.Cu")
		(at 263.147302 -36.686998 90)
		(property "Reference" "C3669"
			(at 0 0 90)
			(layer "F.SilkS")
			(hide yes)
			(effects
				(font
					(size 1.27 1.27)
				)
			)
		)
		(property "Value" ""
			(at 0 0 90)
			(layer "F.Fab")
			(effects
				(font
					(size 1.27 1.27)
				)
			)
		)
		(duplicate_pad_numbers_are_jumpers no)
		(fp_line
			(start 0.7874 -0.4064)
			(end 0.7874 0.4064)
			(stroke
				(width 0.1524)
				(type default)
			)
			(layer "F.SilkS")
		)
		(fp_line
			(start -0.7874 -0.4064)
			(end 0.7874 -0.4064)
			(stroke
				(width 0.1524)
				(type default)
			)
			(layer "F.SilkS")
		)
		(fp_line
			(start 0.7874 0.4064)
			(end -0.7874 0.4064)
			(stroke
				(width 0.1524)
				(type default)
			)
			(layer "F.SilkS")
		)
		(fp_line
			(start -0.7874 0.4064)
			(end -0.7874 -0.4064)
			(stroke
				(width 0.1524)
				(type default)
			)
			(layer "F.SilkS")
		)
		(fp_line
			(start -0.12065 -0.305054)
			(end -0.12065 -0.2794)
			(stroke
				(width 0.1)
				(type default)
			)
			(layer "F.Fab")
		)
		(fp_line
			(start -0.67945 -0.305054)
			(end -0.12065 -0.305054)
			(stroke
				(width 0.1)
				(type default)
			)
			(layer "F.Fab")
		)
		(fp_line
			(start 0.67945 -0.3048)
			(end 0.67945 0.3048)
			(stroke
				(width 0.1)
				(type default)
			)
			(layer "F.Fab")
		)
		(fp_line
			(start 0.12065 -0.3048)
			(end 0.67945 -0.3048)
			(stroke
				(width 0.1)
				(type default)
			)
			(layer "F.Fab")
		)
		(fp_line
			(start 0.12065 -0.2794)
			(end 0.12065 -0.3048)
			(stroke
				(width 0.1)
				(type default)
			)
			(layer "F.Fab")
		)
		(fp_line
			(start -0.12065 -0.2794)
			(end 0.12065 -0.2794)
			(stroke
				(width 0.1)
				(type default)
			)
			(layer "F.Fab")
		)
		(fp_line
			(start 0.120396 0.2794)
			(end -0.12065 0.2794)
			(stroke
				(width 0.1)
				(type default)
			)
			(layer "F.Fab")
		)
		(fp_line
			(start -0.12065 0.2794)
			(end -0.12065 0.3048)
			(stroke
				(width 0.1)
				(type default)
			)
			(layer "F.Fab")
		)
		(fp_line
			(start 0.67945 0.3048)
			(end 0.120396 0.3048)
			(stroke
				(width 0.1)
				(type default)
			)
			(layer "F.Fab")
		)
		(fp_line
			(start 0.120396 0.3048)
			(end 0.120396 0.2794)
			(stroke
				(width 0.1)
				(type default)
			)
			(layer "F.Fab")
		)
		(fp_line
			(start -0.12065 0.3048)
			(end -0.67945 0.3048)
			(stroke
				(width 0.1)
				(type default)
			)
			(layer "F.Fab")
		)
		(fp_line
			(start -0.67945 0.3048)
			(end -0.67945 -0.305054)
			(stroke
				(width 0.1)
				(type default)
			)
			(layer "F.Fab")
		)
		(pad "1" smd circle
			(at -0.40005 0 90)
			(size 0 0)
			(layers "F.Cu" "F.Mask" "F.Paste")
			(net "P3V3_AUX")
		)
		(pad "2" smd circle
			(at 0.40005 0 90)
			(size 0 0)
			(layers "F.Cu" "F.Mask" "F.Paste")
			(net "GND")
		)
	)
	(footprint ""
		(layer "F.Cu")
		(at 449.967858 -18.437098)
		(property "Reference" "R1736"
			(at 0 0 0)
			(layer "F.SilkS")
			(hide yes)
			(effects
				(font
					(size 1.27 1.27)
				)
			)
		)
		(property "Value" ""
			(at 0 0 0)
			(layer "F.Fab")
			(effects
				(font
					(size 1.27 1.27)
				)
			)
		)
		(duplicate_pad_numbers_are_jumpers no)
		(fp_line
			(start -0.7874 -0.4064)
			(end 0.7874 -0.4064)
			(stroke
				(width 0.1524)
				(type default)
			)
			(layer "F.SilkS")
		)
		(fp_line
			(start -0.7874 0.4064)
			(end -0.7874 -0.4064)
			(stroke
				(width 0.1524)
				(type default)
			)
			(layer "F.SilkS")
		)
		(fp_line
			(start 0.7874 -0.4064)
			(end 0.7874 0.4064)
			(stroke
				(width 0.1524)
				(type default)
			)
			(layer "F.SilkS")
		)
		(fp_line
			(start 0.7874 0.4064)
			(end -0.7874 0.4064)
			(stroke
				(width 0.1524)
				(type default)
			)
			(layer "F.SilkS")
		)
		(fp_line
			(start -0.67945 -0.305054)
			(end -0.12065 -0.305054)
			(stroke
				(width 0.1)
				(type default)
			)
			(layer "F.Fab")
		)
		(fp_line
			(start -0.67945 0.3048)
			(end -0.67945 -0.305054)
			(stroke
				(width 0.1)
				(type default)
			)
			(layer "F.Fab")
		)
		(fp_line
			(start -0.12065 -0.305054)
			(end -0.12065 -0.2794)
			(stroke
				(width 0.1)
				(type default)
			)
			(layer "F.Fab")
		)
		(fp_line
			(start -0.12065 -0.2794)
			(end 0.12065 -0.2794)
			(stroke
				(width 0.1)
				(type default)
			)
			(layer "F.Fab")
		)
		(fp_line
			(start -0.12065 0.2794)
			(end -0.12065 0.3048)
			(stroke
				(width 0.1)
				(type default)
			)
			(layer "F.Fab")
		)
		(fp_line
			(start -0.12065 0.3048)
			(end -0.67945 0.3048)
			(stroke
				(width 0.1)
				(type default)
			)
			(layer "F.Fab")
		)
		(fp_line
			(start 0.120396 0.2794)
			(end -0.12065 0.2794)
			(stroke
				(width 0.1)
				(type default)
			)
			(layer "F.Fab")
		)
		(fp_line
			(start 0.120396 0.3048)
			(end 0.120396 0.2794)
			(stroke
				(width 0.1)
				(type default)
			)
			(layer "F.Fab")
		)
		(fp_line
			(start 0.12065 -0.3048)
			(end 0.67945 -0.3048)
			(stroke
				(width 0.1)
				(type default)
			)
			(layer "F.Fab")
		)
		(fp_line
			(start 0.12065 -0.2794)
			(end 0.12065 -0.3048)
			(stroke
				(width 0.1)
				(type default)
			)
			(layer "F.Fab")
		)
		(fp_line
			(start 0.67945 -0.3048)
			(end 0.67945 0.3048)
			(stroke
				(width 0.1)
				(type default)
			)
			(layer "F.Fab")
		)
		(fp_line
			(start 0.67945 0.3048)
			(end 0.120396 0.3048)
			(stroke
				(width 0.1)
				(type default)
			)
			(layer "F.Fab")
		)
		(pad "1" smd circle
			(at -0.40005 0)
			(size 0 0)
			(layers "F.Cu" "F.Mask" "F.Paste")
			(net "SMB_ISO_SSD15_R_SCL")
		)
		(pad "2" smd circle
			(at 0.40005 0)
			(size 0 0)
			(layers "F.Cu" "F.Mask" "F.Paste")
			(net "SMB_ISO_SSD15_SCL")
		)
	)
	(footprint ""
		(layer "F.Cu")
		(at 452.567802 -55.083456)
		(property "Reference" "PC589"
			(at 0 0 0)
			(layer "F.SilkS")
			(hide yes)
			(effects
				(font
					(size 1.27 1.27)
				)
			)
		)
		(property "Value" ""
			(at 0 0 0)
			(layer "F.Fab")
			(effects
				(font
					(size 1.27 1.27)
				)
			)
		)
		(duplicate_pad_numbers_are_jumpers no)
		(fp_line
			(start -0.7874 -0.4064)
			(end 0.7874 -0.4064)
			(stroke
				(width 0.1524)
				(type default)
			)
			(layer "F.SilkS")
		)
		(fp_line
			(start -0.7874 0.4064)
			(end -0.7874 -0.4064)
			(stroke
				(width 0.1524)
				(type default)
			)
			(layer "F.SilkS")
		)
		(fp_line
			(start 0.7874 -0.4064)
			(end 0.7874 0.4064)
			(stroke
				(width 0.1524)
				(type default)
			)
			(layer "F.SilkS")
		)
		(fp_line
			(start 0.7874 0.4064)
			(end -0.7874 0.4064)
			(stroke
				(width 0.1524)
				(type default)
			)
			(layer "F.SilkS")
		)
		(fp_line
			(start -0.67945 -0.305054)
			(end -0.12065 -0.305054)
			(stroke
				(width 0.1)
				(type default)
			)
			(layer "F.Fab")
		)
		(fp_line
			(start -0.67945 0.3048)
			(end -0.67945 -0.305054)
			(stroke
				(width 0.1)
				(type default)
			)
			(layer "F.Fab")
		)
		(fp_line
			(start -0.12065 -0.305054)
			(end -0.12065 -0.2794)
			(stroke
				(width 0.1)
				(type default)
			)
			(layer "F.Fab")
		)
		(fp_line
			(start -0.12065 -0.2794)
			(end 0.12065 -0.2794)
			(stroke
				(width 0.1)
				(type default)
			)
			(layer "F.Fab")
		)
		(fp_line
			(start -0.12065 0.2794)
			(end -0.12065 0.3048)
			(stroke
				(width 0.1)
				(type default)
			)
			(layer "F.Fab")
		)
		(fp_line
			(start -0.12065 0.3048)
			(end -0.67945 0.3048)
			(stroke
				(width 0.1)
				(type default)
			)
			(layer "F.Fab")
		)
		(fp_line
			(start 0.120396 0.2794)
			(end -0.12065 0.2794)
			(stroke
				(width 0.1)
				(type default)
			)
			(layer "F.Fab")
		)
		(fp_line
			(start 0.120396 0.3048)
			(end 0.120396 0.2794)
			(stroke
				(width 0.1)
				(type default)
			)
			(layer "F.Fab")
		)
		(fp_line
			(start 0.12065 -0.3048)
			(end 0.67945 -0.3048)
			(stroke
				(width 0.1)
				(type default)
			)
			(layer "F.Fab")
		)
		(fp_line
			(start 0.12065 -0.2794)
			(end 0.12065 -0.3048)
			(stroke
				(width 0.1)
				(type default)
			)
			(layer "F.Fab")
		)
		(fp_line
			(start 0.67945 -0.3048)
			(end 0.67945 0.3048)
			(stroke
				(width 0.1)
				(type default)
			)
			(layer "F.Fab")
		)
		(fp_line
			(start 0.67945 0.3048)
			(end 0.120396 0.3048)
			(stroke
				(width 0.1)
				(type default)
			)
			(layer "F.Fab")
		)
		(pad "1" smd circle
			(at -0.40005 0)
			(size 0 0)
			(layers "F.Cu" "F.Mask" "F.Paste")
			(net "P5V_AUX")
		)
		(pad "2" smd circle
			(at 0.40005 0)
			(size 0 0)
			(layers "F.Cu" "F.Mask" "F.Paste")
			(net "GND")
		)
	)
	(footprint ""
		(layer "F.Cu")
		(at 411.403292 -204.364082)
		(property "Reference" "Q237"
			(at 3.431286 -2.287016 0)
			(unlocked yes)
			(layer "F.SilkS")
			(effects
				(font
					(size 0.7874 0.5842)
					(thickness 0.1524)
				)
			)
		)
		(property "Value" ""
			(at 0 0 0)
			(layer "F.Fab")
			(effects
				(font
					(size 1.27 1.27)
				)
			)
		)
		(duplicate_pad_numbers_are_jumpers no)
		(fp_line
			(start -1.376172 -1.199896)
			(end -0.508 -1.199896)
			(stroke
				(width 0.1524)
				(type default)
			)
			(layer "F.SilkS")
		)
		(fp_line
			(start -1.376172 1.199896)
			(end -1.376172 -1.199896)
			(stroke
				(width 0.1524)
				(type default)
			)
			(layer "F.SilkS")
		)
		(fp_line
			(start -0.508 -1.199896)
			(end 0 -0.762)
			(stroke
				(width 0.1524)
				(type default)
			)
			(layer "F.SilkS")
		)
		(fp_line
			(start 0 -0.762)
			(end 0.508 -1.199896)
			(stroke
				(width 0.1524)
				(type default)
			)
			(layer "F.SilkS")
		)
		(fp_line
			(start 0.508 -1.199896)
			(end 1.376172 -1.199896)
			(stroke
				(width 0.1524)
				(type default)
			)
			(layer "F.SilkS")
		)
		(fp_line
			(start 1.376172 -1.199896)
			(end 1.376172 1.199896)
			(stroke
				(width 0.1524)
				(type default)
			)
			(layer "F.SilkS")
		)
		(fp_line
			(start 1.376172 1.199896)
			(end -1.376172 1.199896)
			(stroke
				(width 0.1524)
				(type default)
			)
			(layer "F.SilkS")
		)
		(fp_poly
			(pts
				(xy -1.4605 -0.7493) (xy -2.2225 -1.1303) (xy -2.2225 -0.3683)
			)
			(stroke
				(width 0)
				(type default)
			)
			(fill yes)
			(layer "F.SilkS")
		)
		(fp_line
			(start -0.674878 -1.100074)
			(end 0.674878 -1.100074)
			(stroke
				(width 0.1)
				(type default)
			)
			(layer "F.Fab")
		)
		(fp_line
			(start -0.674878 1.100074)
			(end -0.674878 -1.100074)
			(stroke
				(width 0.1)
				(type default)
			)
			(layer "F.Fab")
		)
		(fp_line
			(start 0.674878 -1.100074)
			(end 0.674878 1.100074)
			(stroke
				(width 0.1)
				(type default)
			)
			(layer "F.Fab")
		)
		(fp_line
			(start 0.674878 1.100074)
			(end -0.674878 1.100074)
			(stroke
				(width 0.1)
				(type default)
			)
			(layer "F.Fab")
		)
		(fp_poly
			(pts
				(xy -1.4605 -0.7493) (xy -2.2225 -1.1303) (xy -2.2225 -0.3683)
			)
			(stroke
				(width 0)
				(type default)
			)
			(fill yes)
			(layer "F.Fab")
		)
		(pad "1" smd rect
			(at -0.899922 -0.750062 270)
			(size 0.6096 0.6096)
			(layers "F.Cu" "F.Mask" "F.Paste")
			(net "GND")
		)
		(pad "2" smd rect
			(at -0.899922 0 270)
			(size 0.4064 0.6096)
			(layers "F.Cu" "F.Mask" "F.Paste")
			(net "FPGA_PEX2_MODE_SEL2_R")
		)
		(pad "3" smd rect
			(at -0.899922 0.750062 270)
			(size 0.6096 0.6096)
			(layers "F.Cu" "F.Mask" "F.Paste")
			(net "FPGA_PEX2_MODE_SEL2_ISO")
		)
		(pad "4" smd rect
			(at 0.899922 0.750062 270)
			(size 0.6096 0.6096)
			(layers "F.Cu" "F.Mask" "F.Paste")
			(net "GND")
		)
		(pad "5" smd rect
			(at 0.899922 0 270)
			(size 0.4064 0.6096)
			(layers "F.Cu" "F.Mask" "F.Paste")
			(net "FPGA_PEX2_MODE_SEL2_D_N")
		)
		(pad "6" smd rect
			(at 0.899922 -0.750062 270)
			(size 0.6096 0.6096)
			(layers "F.Cu" "F.Mask" "F.Paste")
			(net "FPGA_PEX2_MODE_SEL2_D_N")
		)
	)
	(footprint ""
		(layer "F.Cu")
		(at 148.511514 -293.245032 -90)
		(property "Reference" "R4570"
			(at 0 0 270)
			(layer "F.SilkS")
			(hide yes)
			(effects
				(font
					(size 1.27 1.27)
				)
			)
		)
		(property "Value" ""
			(at 0 0 270)
			(layer "F.Fab")
			(effects
				(font
					(size 1.27 1.27)
				)
			)
		)
		(duplicate_pad_numbers_are_jumpers no)
		(fp_line
			(start -0.7874 0.4064)
			(end -0.7874 -0.4064)
			(stroke
				(width 0.1524)
				(type default)
			)
			(layer "F.SilkS")
		)
		(fp_line
			(start 0.7874 0.4064)
			(end -0.7874 0.4064)
			(stroke
				(width 0.1524)
				(type default)
			)
			(layer "F.SilkS")
		)
		(fp_line
			(start -0.7874 -0.4064)
			(end 0.7874 -0.4064)
			(stroke
				(width 0.1524)
				(type default)
			)
			(layer "F.SilkS")
		)
		(fp_line
			(start 0.7874 -0.4064)
			(end 0.7874 0.4064)
			(stroke
				(width 0.1524)
				(type default)
			)
			(layer "F.SilkS")
		)
		(fp_line
			(start -0.67945 0.3048)
			(end -0.67945 -0.305054)
			(stroke
				(width 0.1)
				(type default)
			)
			(layer "F.Fab")
		)
		(fp_line
			(start -0.12065 0.3048)
			(end -0.67945 0.3048)
			(stroke
				(width 0.1)
				(type default)
			)
			(layer "F.Fab")
		)
		(fp_line
			(start 0.120396 0.3048)
			(end 0.120396 0.2794)
			(stroke
				(width 0.1)
				(type default)
			)
			(layer "F.Fab")
		)
		(fp_line
			(start 0.67945 0.3048)
			(end 0.120396 0.3048)
			(stroke
				(width 0.1)
				(type default)
			)
			(layer "F.Fab")
		)
		(fp_line
			(start -0.12065 0.2794)
			(end -0.12065 0.3048)
			(stroke
				(width 0.1)
				(type default)
			)
			(layer "F.Fab")
		)
		(fp_line
			(start 0.120396 0.2794)
			(end -0.12065 0.2794)
			(stroke
				(width 0.1)
				(type default)
			)
			(layer "F.Fab")
		)
		(fp_line
			(start -0.12065 -0.2794)
			(end 0.12065 -0.2794)
			(stroke
				(width 0.1)
				(type default)
			)
			(layer "F.Fab")
		)
		(fp_line
			(start 0.12065 -0.2794)
			(end 0.12065 -0.3048)
			(stroke
				(width 0.1)
				(type default)
			)
			(layer "F.Fab")
		)
		(fp_line
			(start 0.12065 -0.3048)
			(end 0.67945 -0.3048)
			(stroke
				(width 0.1)
				(type default)
			)
			(layer "F.Fab")
		)
		(fp_line
			(start 0.67945 -0.3048)
			(end 0.67945 0.3048)
			(stroke
				(width 0.1)
				(type default)
			)
			(layer "F.Fab")
		)
		(fp_line
			(start -0.67945 -0.305054)
			(end -0.12065 -0.305054)
			(stroke
				(width 0.1)
				(type default)
			)
			(layer "F.Fab")
		)
		(fp_line
			(start -0.12065 -0.305054)
			(end -0.12065 -0.2794)
			(stroke
				(width 0.1)
				(type default)
			)
			(layer "F.Fab")
		)
		(pad "1" smd circle
			(at -0.40005 0 270)
			(size 0 0)
			(layers "F.Cu" "F.Mask" "F.Paste")
			(net "PCEPLL2_VDDA18_PEX1")
		)
		(pad "2" smd circle
			(at 0.40005 0 270)
			(size 0 0)
			(layers "F.Cu" "F.Mask" "F.Paste")
			(net "PCEPLL2_VDDA18_PEX1_R")
		)
	)
	(footprint ""
		(layer "F.Cu")
		(at 146.94789 -40.037258 90)
		(property "Reference" "U368"
			(at 0.247142 2.40538 90)
			(unlocked yes)
			(layer "F.SilkS")
			(effects
				(font
					(size 0.7874 0.5842)
					(thickness 0.1524)
				)
			)
		)
		(property "Value" ""
			(at 0 0 90)
			(layer "F.Fab")
			(effects
				(font
					(size 1.27 1.27)
				)
			)
		)
		(duplicate_pad_numbers_are_jumpers no)
		(fp_line
			(start -1.949958 -1.610106)
			(end 1.949958 -1.610106)
			(stroke
				(width 0.1524)
				(type default)
			)
			(layer "F.SilkS")
		)
		(fp_line
			(start 1.949958 -1.560068)
			(end 1.949958 1.610106)
			(stroke
				(width 0.1524)
				(type default)
			)
			(layer "F.SilkS")
		)
		(fp_line
			(start 1.949958 1.610106)
			(end -1.949958 1.610106)
			(stroke
				(width 0.1524)
				(type default)
			)
			(layer "F.SilkS")
		)
		(fp_line
			(start -1.949958 1.610106)
			(end -1.949958 -1.610106)
			(stroke
				(width 0.1524)
				(type default)
			)
			(layer "F.SilkS")
		)
		(fp_line
			(start 0.750062 -1.560068)
			(end 0.750062 1.560068)
			(stroke
				(width 0.1)
				(type default)
			)
			(layer "F.Fab")
		)
		(fp_line
			(start -0.750062 -1.560068)
			(end 0.750062 -1.560068)
			(stroke
				(width 0.1)
				(type default)
			)
			(layer "F.Fab")
		)
		(fp_line
			(start 0.750062 1.560068)
			(end -0.750062 1.560068)
			(stroke
				(width 0.1)
				(type default)
			)
			(layer "F.Fab")
		)
		(fp_line
			(start -0.750062 1.560068)
			(end -0.750062 -1.560068)
			(stroke
				(width 0.1)
				(type default)
			)
			(layer "F.Fab")
		)
		(pad "D" smd rect
			(at 1.100074 0)
			(size 1.016 1.4224)
			(layers "F.Cu" "F.Mask" "F.Paste")
			(net "SSD5_AUX_P3V3_EN")
		)
		(pad "G" smd rect
			(at -1.100074 -0.94996)
			(size 1.016 1.4224)
			(layers "F.Cu" "F.Mask" "F.Paste")
			(net "PRSNT_SSD5_R1_N")
		)
		(pad "S" smd rect
			(at -1.100074 0.94996)
			(size 1.016 1.4224)
			(layers "F.Cu" "F.Mask" "F.Paste")
			(net "GND")
		)
	)
	(footprint ""
		(layer "F.Cu")
		(at 345.057476 -313.620404)
		(property "Reference" "L62"
			(at 0 0 0)
			(layer "F.SilkS")
			(hide yes)
			(effects
				(font
					(size 1.27 1.27)
				)
			)
		)
		(property "Value" ""
			(at 0 0 0)
			(layer "F.Fab")
			(effects
				(font
					(size 1.27 1.27)
				)
			)
		)
		(duplicate_pad_numbers_are_jumpers no)
		(fp_line
			(start -2.248154 -4.9911)
			(end -2.248154 -1.677416)
			(stroke
				(width 0.1524)
				(type default)
			)
			(layer "F.SilkS")
		)
		(fp_line
			(start -2.248154 1.660398)
			(end -2.248154 4.9911)
			(stroke
				(width 0.1524)
				(type default)
			)
			(layer "F.SilkS")
		)
		(fp_line
			(start -2.248154 4.9911)
			(end 2.248154 4.9911)
			(stroke
				(width 0.1524)
				(type default)
			)
			(layer "F.SilkS")
		)
		(fp_line
			(start 2.248154 -4.9911)
			(end -2.248154 -4.9911)
			(stroke
				(width 0.1524)
				(type default)
			)
			(layer "F.SilkS")
		)
		(fp_line
			(start 2.248154 -1.787144)
			(end 2.248154 -4.9911)
			(stroke
				(width 0.1524)
				(type default)
			)
			(layer "F.SilkS")
		)
		(fp_line
			(start 2.248154 4.9911)
			(end 2.248154 1.70434)
			(stroke
				(width 0.1524)
				(type default)
			)
			(layer "F.SilkS")
		)
		(fp_line
			(start -1.700022 -0.899922)
			(end -1.700022 0.899922)
			(stroke
				(width 0.1)
				(type default)
			)
			(layer "F.Fab")
		)
		(fp_line
			(start -1.700022 0.899922)
			(end 1.700022 0.899922)
			(stroke
				(width 0.1)
				(type default)
			)
			(layer "F.Fab")
		)
		(fp_line
			(start 1.700022 -0.899922)
			(end -1.700022 -0.899922)
			(stroke
				(width 0.1)
				(type default)
			)
			(layer "F.Fab")
		)
		(fp_line
			(start 1.700022 0.899922)
			(end 1.700022 -0.899922)
			(stroke
				(width 0.1)
				(type default)
			)
			(layer "F.Fab")
		)
		(pad "1" smd rect
			(at -1.575054 0)
			(size 1.1684 9.8044)
			(layers "F.Cu" "F.Mask" "F.Paste")
			(net "P0V8_PEX2")
		)
		(pad "2" smd rect
			(at 1.575054 0)
			(size 1.1684 9.8044)
			(layers "F.Cu" "F.Mask" "F.Paste")
			(net "P0V8_SERDES_VDDA_PEX2")
		)
	)
	(footprint ""
		(layer "F.Cu")
		(at 96.4692 -196.4944 90)
		(property "Reference" "C4444"
			(at 0 0 90)
			(layer "F.SilkS")
			(hide yes)
			(effects
				(font
					(size 1.27 1.27)
				)
			)
		)
		(property "Value" ""
			(at 0 0 90)
			(layer "F.Fab")
			(effects
				(font
					(size 1.27 1.27)
				)
			)
		)
		(duplicate_pad_numbers_are_jumpers no)
		(fp_line
			(start 0.7874 -0.4064)
			(end 0.7874 0.4064)
			(stroke
				(width 0.1524)
				(type default)
			)
			(layer "F.SilkS")
		)
		(fp_line
			(start -0.7874 -0.4064)
			(end 0.7874 -0.4064)
			(stroke
				(width 0.1524)
				(type default)
			)
			(layer "F.SilkS")
		)
		(fp_line
			(start 0.7874 0.4064)
			(end -0.7874 0.4064)
			(stroke
				(width 0.1524)
				(type default)
			)
			(layer "F.SilkS")
		)
		(fp_line
			(start -0.7874 0.4064)
			(end -0.7874 -0.4064)
			(stroke
				(width 0.1524)
				(type default)
			)
			(layer "F.SilkS")
		)
		(fp_line
			(start -0.12065 -0.305054)
			(end -0.12065 -0.2794)
			(stroke
				(width 0.1)
				(type default)
			)
			(layer "F.Fab")
		)
		(fp_line
			(start -0.67945 -0.305054)
			(end -0.12065 -0.305054)
			(stroke
				(width 0.1)
				(type default)
			)
			(layer "F.Fab")
		)
		(fp_line
			(start 0.67945 -0.3048)
			(end 0.67945 0.3048)
			(stroke
				(width 0.1)
				(type default)
			)
			(layer "F.Fab")
		)
		(fp_line
			(start 0.12065 -0.3048)
			(end 0.67945 -0.3048)
			(stroke
				(width 0.1)
				(type default)
			)
			(layer "F.Fab")
		)
		(fp_line
			(start 0.12065 -0.2794)
			(end 0.12065 -0.3048)
			(stroke
				(width 0.1)
				(type default)
			)
			(layer "F.Fab")
		)
		(fp_line
			(start -0.12065 -0.2794)
			(end 0.12065 -0.2794)
			(stroke
				(width 0.1)
				(type default)
			)
			(layer "F.Fab")
		)
		(fp_line
			(start 0.120396 0.2794)
			(end -0.12065 0.2794)
			(stroke
				(width 0.1)
				(type default)
			)
			(layer "F.Fab")
		)
		(fp_line
			(start -0.12065 0.2794)
			(end -0.12065 0.3048)
			(stroke
				(width 0.1)
				(type default)
			)
			(layer "F.Fab")
		)
		(fp_line
			(start 0.67945 0.3048)
			(end 0.120396 0.3048)
			(stroke
				(width 0.1)
				(type default)
			)
			(layer "F.Fab")
		)
		(fp_line
			(start 0.120396 0.3048)
			(end 0.120396 0.2794)
			(stroke
				(width 0.1)
				(type default)
			)
			(layer "F.Fab")
		)
		(fp_line
			(start -0.12065 0.3048)
			(end -0.67945 0.3048)
			(stroke
				(width 0.1)
				(type default)
			)
			(layer "F.Fab")
		)
		(fp_line
			(start -0.67945 0.3048)
			(end -0.67945 -0.305054)
			(stroke
				(width 0.1)
				(type default)
			)
			(layer "F.Fab")
		)
		(pad "1" smd circle
			(at -0.40005 0 90)
			(size 0 0)
			(layers "F.Cu" "F.Mask" "F.Paste")
			(net "P3V3_AUX")
		)
		(pad "2" smd circle
			(at 0.40005 0 90)
			(size 0 0)
			(layers "F.Cu" "F.Mask" "F.Paste")
			(net "GND")
		)
	)
	(footprint ""
		(layer "F.Cu")
		(at 101.17455 -240.928144)
		(property "Reference" "C829"
			(at 0 0 0)
			(layer "F.SilkS")
			(hide yes)
			(effects
				(font
					(size 1.27 1.27)
				)
			)
		)
		(property "Value" ""
			(at 0 0 0)
			(layer "F.Fab")
			(effects
				(font
					(size 1.27 1.27)
				)
			)
		)
		(duplicate_pad_numbers_are_jumpers no)
		(fp_line
			(start -0.7874 -0.4064)
			(end 0.7874 -0.4064)
			(stroke
				(width 0.1524)
				(type default)
			)
			(layer "F.SilkS")
		)
		(fp_line
			(start -0.7874 0.4064)
			(end -0.7874 -0.4064)
			(stroke
				(width 0.1524)
				(type default)
			)
			(layer "F.SilkS")
		)
		(fp_line
			(start 0.7874 -0.4064)
			(end 0.7874 0.4064)
			(stroke
				(width 0.1524)
				(type default)
			)
			(layer "F.SilkS")
		)
		(fp_line
			(start 0.7874 0.4064)
			(end -0.7874 0.4064)
			(stroke
				(width 0.1524)
				(type default)
			)
			(layer "F.SilkS")
		)
		(fp_line
			(start -0.67945 -0.305054)
			(end -0.12065 -0.305054)
			(stroke
				(width 0.1)
				(type default)
			)
			(layer "F.Fab")
		)
		(fp_line
			(start -0.67945 0.3048)
			(end -0.67945 -0.305054)
			(stroke
				(width 0.1)
				(type default)
			)
			(layer "F.Fab")
		)
		(fp_line
			(start -0.12065 -0.305054)
			(end -0.12065 -0.2794)
			(stroke
				(width 0.1)
				(type default)
			)
			(layer "F.Fab")
		)
		(fp_line
			(start -0.12065 -0.2794)
			(end 0.12065 -0.2794)
			(stroke
				(width 0.1)
				(type default)
			)
			(layer "F.Fab")
		)
		(fp_line
			(start -0.12065 0.2794)
			(end -0.12065 0.3048)
			(stroke
				(width 0.1)
				(type default)
			)
			(layer "F.Fab")
		)
		(fp_line
			(start -0.12065 0.3048)
			(end -0.67945 0.3048)
			(stroke
				(width 0.1)
				(type default)
			)
			(layer "F.Fab")
		)
		(fp_line
			(start 0.120396 0.2794)
			(end -0.12065 0.2794)
			(stroke
				(width 0.1)
				(type default)
			)
			(layer "F.Fab")
		)
		(fp_line
			(start 0.120396 0.3048)
			(end 0.120396 0.2794)
			(stroke
				(width 0.1)
				(type default)
			)
			(layer "F.Fab")
		)
		(fp_line
			(start 0.12065 -0.3048)
			(end 0.67945 -0.3048)
			(stroke
				(width 0.1)
				(type default)
			)
			(layer "F.Fab")
		)
		(fp_line
			(start 0.12065 -0.2794)
			(end 0.12065 -0.3048)
			(stroke
				(width 0.1)
				(type default)
			)
			(layer "F.Fab")
		)
		(fp_line
			(start 0.67945 -0.3048)
			(end 0.67945 0.3048)
			(stroke
				(width 0.1)
				(type default)
			)
			(layer "F.Fab")
		)
		(fp_line
			(start 0.67945 0.3048)
			(end 0.120396 0.3048)
			(stroke
				(width 0.1)
				(type default)
			)
			(layer "F.Fab")
		)
		(pad "1" smd circle
			(at -0.40005 0)
			(size 0 0)
			(layers "F.Cu" "F.Mask" "F.Paste")
			(net "P3V3_AUX")
		)
		(pad "2" smd circle
			(at 0.40005 0)
			(size 0 0)
			(layers "F.Cu" "F.Mask" "F.Paste")
			(net "GND")
		)
	)
	(footprint ""
		(layer "F.Cu")
		(at 58.0644 -140.6398 180)
		(property "Reference" "R38"
			(at 0 0 180)
			(layer "F.SilkS")
			(hide yes)
			(effects
				(font
					(size 1.27 1.27)
				)
			)
		)
		(property "Value" ""
			(at 0 0 180)
			(layer "F.Fab")
			(effects
				(font
					(size 1.27 1.27)
				)
			)
		)
		(duplicate_pad_numbers_are_jumpers no)
		(fp_line
			(start 0.7874 0.4064)
			(end -0.7874 0.4064)
			(stroke
				(width 0.1524)
				(type default)
			)
			(layer "F.SilkS")
		)
		(fp_line
			(start 0.7874 -0.4064)
			(end 0.7874 0.4064)
			(stroke
				(width 0.1524)
				(type default)
			)
			(layer "F.SilkS")
		)
		(fp_line
			(start -0.7874 0.4064)
			(end -0.7874 -0.4064)
			(stroke
				(width 0.1524)
				(type default)
			)
			(layer "F.SilkS")
		)
		(fp_line
			(start -0.7874 -0.4064)
			(end 0.7874 -0.4064)
			(stroke
				(width 0.1524)
				(type default)
			)
			(layer "F.SilkS")
		)
		(fp_line
			(start 0.67945 0.3048)
			(end 0.120396 0.3048)
			(stroke
				(width 0.1)
				(type default)
			)
			(layer "F.Fab")
		)
		(fp_line
			(start 0.67945 -0.3048)
			(end 0.67945 0.3048)
			(stroke
				(width 0.1)
				(type default)
			)
			(layer "F.Fab")
		)
		(fp_line
			(start 0.12065 -0.2794)
			(end 0.12065 -0.3048)
			(stroke
				(width 0.1)
				(type default)
			)
			(layer "F.Fab")
		)
		(fp_line
			(start 0.12065 -0.3048)
			(end 0.67945 -0.3048)
			(stroke
				(width 0.1)
				(type default)
			)
			(layer "F.Fab")
		)
		(fp_line
			(start 0.120396 0.3048)
			(end 0.120396 0.2794)
			(stroke
				(width 0.1)
				(type default)
			)
			(layer "F.Fab")
		)
		(fp_line
			(start 0.120396 0.2794)
			(end -0.12065 0.2794)
			(stroke
				(width 0.1)
				(type default)
			)
			(layer "F.Fab")
		)
		(fp_line
			(start -0.12065 0.3048)
			(end -0.67945 0.3048)
			(stroke
				(width 0.1)
				(type default)
			)
			(layer "F.Fab")
		)
		(fp_line
			(start -0.12065 0.2794)
			(end -0.12065 0.3048)
			(stroke
				(width 0.1)
				(type default)
			)
			(layer "F.Fab")
		)
		(fp_line
			(start -0.12065 -0.2794)
			(end 0.12065 -0.2794)
			(stroke
				(width 0.1)
				(type default)
			)
			(layer "F.Fab")
		)
		(fp_line
			(start -0.12065 -0.305054)
			(end -0.12065 -0.2794)
			(stroke
				(width 0.1)
				(type default)
			)
			(layer "F.Fab")
		)
		(fp_line
			(start -0.67945 0.3048)
			(end -0.67945 -0.305054)
			(stroke
				(width 0.1)
				(type default)
			)
			(layer "F.Fab")
		)
		(fp_line
			(start -0.67945 -0.305054)
			(end -0.12065 -0.305054)
			(stroke
				(width 0.1)
				(type default)
			)
			(layer "F.Fab")
		)
		(pad "1" smd circle
			(at -0.40005 0 180)
			(size 0 0)
			(layers "F.Cu" "F.Mask" "F.Paste")
			(net "RST_SMB_NIC0_MUX_ISO_N")
		)
		(pad "2" smd circle
			(at 0.40005 0 180)
			(size 0 0)
			(layers "F.Cu" "F.Mask" "F.Paste")
			(net "GND")
		)
	)
	(footprint ""
		(layer "F.Cu")
		(at 187.838588 -44.341542 90)
		(property "Reference" "C317"
			(at 0 0 90)
			(layer "F.SilkS")
			(hide yes)
			(effects
				(font
					(size 1.27 1.27)
				)
			)
		)
		(property "Value" ""
			(at 0 0 90)
			(layer "F.Fab")
			(effects
				(font
					(size 1.27 1.27)
				)
			)
		)
		(duplicate_pad_numbers_are_jumpers no)
		(fp_line
			(start 0.7874 -0.4064)
			(end 0.7874 0.4064)
			(stroke
				(width 0.1524)
				(type default)
			)
			(layer "F.SilkS")
		)
		(fp_line
			(start -0.7874 -0.4064)
			(end 0.7874 -0.4064)
			(stroke
				(width 0.1524)
				(type default)
			)
			(layer "F.SilkS")
		)
		(fp_line
			(start 0.7874 0.4064)
			(end -0.7874 0.4064)
			(stroke
				(width 0.1524)
				(type default)
			)
			(layer "F.SilkS")
		)
		(fp_line
			(start -0.7874 0.4064)
			(end -0.7874 -0.4064)
			(stroke
				(width 0.1524)
				(type default)
			)
			(layer "F.SilkS")
		)
		(fp_line
			(start -0.12065 -0.305054)
			(end -0.12065 -0.2794)
			(stroke
				(width 0.1)
				(type default)
			)
			(layer "F.Fab")
		)
		(fp_line
			(start -0.67945 -0.305054)
			(end -0.12065 -0.305054)
			(stroke
				(width 0.1)
				(type default)
			)
			(layer "F.Fab")
		)
		(fp_line
			(start 0.67945 -0.3048)
			(end 0.67945 0.3048)
			(stroke
				(width 0.1)
				(type default)
			)
			(layer "F.Fab")
		)
		(fp_line
			(start 0.12065 -0.3048)
			(end 0.67945 -0.3048)
			(stroke
				(width 0.1)
				(type default)
			)
			(layer "F.Fab")
		)
		(fp_line
			(start 0.12065 -0.2794)
			(end 0.12065 -0.3048)
			(stroke
				(width 0.1)
				(type default)
			)
			(layer "F.Fab")
		)
		(fp_line
			(start -0.12065 -0.2794)
			(end 0.12065 -0.2794)
			(stroke
				(width 0.1)
				(type default)
			)
			(layer "F.Fab")
		)
		(fp_line
			(start 0.120396 0.2794)
			(end -0.12065 0.2794)
			(stroke
				(width 0.1)
				(type default)
			)
			(layer "F.Fab")
		)
		(fp_line
			(start -0.12065 0.2794)
			(end -0.12065 0.3048)
			(stroke
				(width 0.1)
				(type default)
			)
			(layer "F.Fab")
		)
		(fp_line
			(start 0.67945 0.3048)
			(end 0.120396 0.3048)
			(stroke
				(width 0.1)
				(type default)
			)
			(layer "F.Fab")
		)
		(fp_line
			(start 0.120396 0.3048)
			(end 0.120396 0.2794)
			(stroke
				(width 0.1)
				(type default)
			)
			(layer "F.Fab")
		)
		(fp_line
			(start -0.12065 0.3048)
			(end -0.67945 0.3048)
			(stroke
				(width 0.1)
				(type default)
			)
			(layer "F.Fab")
		)
		(fp_line
			(start -0.67945 0.3048)
			(end -0.67945 -0.305054)
			(stroke
				(width 0.1)
				(type default)
			)
			(layer "F.Fab")
		)
		(pad "1" smd circle
			(at -0.40005 0 90)
			(size 0 0)
			(layers "F.Cu" "F.Mask" "F.Paste")
			(net "P12V_SSD6_VIN_P")
		)
		(pad "2" smd circle
			(at 0.40005 0 90)
			(size 0 0)
			(layers "F.Cu" "F.Mask" "F.Paste")
			(net "P12V_SSD6_VIN_N")
		)
	)
	(footprint ""
		(layer "F.Cu")
		(at 94.494096 -116.410486)
		(property "Reference" "PR6917"
			(at 0 0 0)
			(layer "F.SilkS")
			(hide yes)
			(effects
				(font
					(size 1.27 1.27)
				)
			)
		)
		(property "Value" ""
			(at 0 0 0)
			(layer "F.Fab")
			(effects
				(font
					(size 1.27 1.27)
				)
			)
		)
		(duplicate_pad_numbers_are_jumpers no)
		(fp_line
			(start -0.7874 -0.4064)
			(end 0.7874 -0.4064)
			(stroke
				(width 0.1524)
				(type default)
			)
			(layer "F.SilkS")
		)
		(fp_line
			(start -0.7874 0.4064)
			(end -0.7874 -0.4064)
			(stroke
				(width 0.1524)
				(type default)
			)
			(layer "F.SilkS")
		)
		(fp_line
			(start 0.7874 -0.4064)
			(end 0.7874 0.4064)
			(stroke
				(width 0.1524)
				(type default)
			)
			(layer "F.SilkS")
		)
		(fp_line
			(start 0.7874 0.4064)
			(end -0.7874 0.4064)
			(stroke
				(width 0.1524)
				(type default)
			)
			(layer "F.SilkS")
		)
		(fp_line
			(start -0.67945 -0.305054)
			(end -0.12065 -0.305054)
			(stroke
				(width 0.1)
				(type default)
			)
			(layer "F.Fab")
		)
		(fp_line
			(start -0.67945 0.3048)
			(end -0.67945 -0.305054)
			(stroke
				(width 0.1)
				(type default)
			)
			(layer "F.Fab")
		)
		(fp_line
			(start -0.12065 -0.305054)
			(end -0.12065 -0.2794)
			(stroke
				(width 0.1)
				(type default)
			)
			(layer "F.Fab")
		)
		(fp_line
			(start -0.12065 -0.2794)
			(end 0.12065 -0.2794)
			(stroke
				(width 0.1)
				(type default)
			)
			(layer "F.Fab")
		)
		(fp_line
			(start -0.12065 0.2794)
			(end -0.12065 0.3048)
			(stroke
				(width 0.1)
				(type default)
			)
			(layer "F.Fab")
		)
		(fp_line
			(start -0.12065 0.3048)
			(end -0.67945 0.3048)
			(stroke
				(width 0.1)
				(type default)
			)
			(layer "F.Fab")
		)
		(fp_line
			(start 0.120396 0.2794)
			(end -0.12065 0.2794)
			(stroke
				(width 0.1)
				(type default)
			)
			(layer "F.Fab")
		)
		(fp_line
			(start 0.120396 0.3048)
			(end 0.120396 0.2794)
			(stroke
				(width 0.1)
				(type default)
			)
			(layer "F.Fab")
		)
		(fp_line
			(start 0.12065 -0.3048)
			(end 0.67945 -0.3048)
			(stroke
				(width 0.1)
				(type default)
			)
			(layer "F.Fab")
		)
		(fp_line
			(start 0.12065 -0.2794)
			(end 0.12065 -0.3048)
			(stroke
				(width 0.1)
				(type default)
			)
			(layer "F.Fab")
		)
		(fp_line
			(start 0.67945 -0.3048)
			(end 0.67945 0.3048)
			(stroke
				(width 0.1)
				(type default)
			)
			(layer "F.Fab")
		)
		(fp_line
			(start 0.67945 0.3048)
			(end 0.120396 0.3048)
			(stroke
				(width 0.1)
				(type default)
			)
			(layer "F.Fab")
		)
		(pad "1" smd circle
			(at -0.40005 0)
			(size 0 0)
			(layers "F.Cu" "F.Mask" "F.Paste")
			(net "P3V3_NIC1_CO_MODE")
		)
		(pad "2" smd circle
			(at 0.40005 0)
			(size 0 0)
			(layers "F.Cu" "F.Mask" "F.Paste")
			(net "GND")
		)
	)
	(footprint ""
		(layer "F.Cu")
		(at 376.34926 -293.796212 -90)
		(property "Reference" "C3542"
			(at 0 0 270)
			(layer "F.SilkS")
			(hide yes)
			(effects
				(font
					(size 1.27 1.27)
				)
			)
		)
		(property "Value" ""
			(at 0 0 270)
			(layer "F.Fab")
			(effects
				(font
					(size 1.27 1.27)
				)
			)
		)
		(duplicate_pad_numbers_are_jumpers no)
		(fp_line
			(start -0.299974 0.150114)
			(end -0.299974 -0.150114)
			(stroke
				(width 0.1)
				(type default)
			)
			(layer "F.Fab")
		)
		(fp_line
			(start 0.299974 0.150114)
			(end -0.299974 0.150114)
			(stroke
				(width 0.1)
				(type default)
			)
			(layer "F.Fab")
		)
		(fp_line
			(start -0.299974 -0.150114)
			(end 0.299974 -0.150114)
			(stroke
				(width 0.1)
				(type default)
			)
			(layer "F.Fab")
		)
		(fp_line
			(start 0.299974 -0.150114)
			(end 0.299974 0.150114)
			(stroke
				(width 0.1)
				(type default)
			)
			(layer "F.Fab")
		)
		(pad "1" smd rect
			(at -0.2667 0 270)
			(size 0.3048 0.381)
			(layers "F.Cu" "F.Mask" "F.Paste")
			(net "P1V8_PLL0_PEX3")
		)
		(pad "2" smd rect
			(at 0.2667 0 270)
			(size 0.3048 0.381)
			(layers "F.Cu" "F.Mask" "F.Paste")
			(net "GND")
		)
	)
	(footprint ""
		(layer "F.Cu")
		(at 240.862612 -242.808506 -90)
		(property "Reference" "U419"
			(at 1.406906 -4.807458 90)
			(unlocked yes)
			(layer "F.SilkS")
			(effects
				(font
					(size 0.7874 0.5842)
					(thickness 0.1524)
				)
				(justify left)
			)
		)
		(property "Value" ""
			(at 0 0 270)
			(layer "F.Fab")
			(effects
				(font
					(size 1.27 1.27)
				)
			)
		)
		(duplicate_pad_numbers_are_jumpers no)
		(fp_line
			(start -2.097532 3.949954)
			(end 2.097532 3.949954)
			(stroke
				(width 0.1524)
				(type default)
			)
			(layer "F.SilkS")
		)
		(fp_line
			(start 2.097532 3.949954)
			(end 2.097532 -3.949954)
			(stroke
				(width 0.1524)
				(type default)
			)
			(layer "F.SilkS")
		)
		(fp_line
			(start 0 -2.54)
			(end -1.409954 -3.949954)
			(stroke
				(width 0.1524)
				(type default)
			)
			(layer "F.SilkS")
		)
		(fp_line
			(start -2.097532 -3.949954)
			(end -2.097532 3.949954)
			(stroke
				(width 0.1524)
				(type default)
			)
			(layer "F.SilkS")
		)
		(fp_line
			(start -1.409954 -3.949954)
			(end -2.097532 -3.949954)
			(stroke
				(width 0.1524)
				(type default)
			)
			(layer "F.SilkS")
		)
		(fp_line
			(start 1.409954 -3.949954)
			(end 0 -2.54)
			(stroke
				(width 0.1524)
				(type default)
			)
			(layer "F.SilkS")
		)
		(fp_line
			(start 2.097532 -3.949954)
			(end 1.409954 -3.949954)
			(stroke
				(width 0.1524)
				(type default)
			)
			(layer "F.SilkS")
		)
		(fp_poly
			(pts
				(xy -4.7498 -4.182872) (xy -4.7498 -3.166872) (xy -3.7338 -3.674872)
			)
			(stroke
				(width 0)
				(type default)
			)
			(fill yes)
			(layer "F.SilkS")
		)
		(fp_line
			(start -2.249932 3.949954)
			(end 2.249932 3.949954)
			(stroke
				(width 0.1)
				(type default)
			)
			(layer "F.Fab")
		)
		(fp_line
			(start 2.249932 3.949954)
			(end 2.249932 -3.949954)
			(stroke
				(width 0.1)
				(type default)
			)
			(layer "F.Fab")
		)
		(fp_line
			(start -2.249932 -3.949954)
			(end -2.249932 3.949954)
			(stroke
				(width 0.1)
				(type default)
			)
			(layer "F.Fab")
		)
		(fp_line
			(start 2.249932 -3.949954)
			(end -2.249932 -3.949954)
			(stroke
				(width 0.1)
				(type default)
			)
			(layer "F.Fab")
		)
		(fp_poly
			(pts
				(xy -4.7498 -4.182872) (xy -4.7498 -3.166872) (xy -3.7338 -3.674872)
			)
			(stroke
				(width 0)
				(type default)
			)
			(fill yes)
			(layer "F.Fab")
		)
		(pad "1" smd rect
			(at -2.925064 -3.674872 180)
			(size 0.6096 1.3716)
			(layers "F.Cu" "F.Mask" "F.Paste")
			(net "IRQ_BIC_RECOVER_IOEXP_N")
		)
		(pad "2" smd rect
			(at -2.925064 -2.925064 180)
			(size 0.4064 1.3716)
			(layers "F.Cu" "F.Mask" "F.Paste")
			(net "BIC_RECOVER_IOEXP_A1")
		)
		(pad "3" smd rect
			(at -2.925064 -2.275078 180)
			(size 0.4064 1.3716)
			(layers "F.Cu" "F.Mask" "F.Paste")
			(net "RST_BIC_RECOVER_N")
		)
		(pad "4" smd rect
			(at -2.925064 -1.625092 180)
			(size 0.4064 1.3716)
			(layers "F.Cu" "F.Mask" "F.Paste")
			(net "BIC_FWSPICK_IOEXP")
		)
		(pad "5" smd rect
			(at -2.925064 -0.975106 180)
			(size 0.4064 1.3716)
			(layers "F.Cu" "F.Mask" "F.Paste")
			(net "BIC_UART_BMC_SEL")
		)
		(pad "6" smd rect
			(at -2.925064 -0.32512 180)
			(size 0.4064 1.3716)
			(layers "F.Cu" "F.Mask" "F.Paste")
			(net "Net_9120")
		)
		(pad "7" smd rect
			(at -2.925064 0.32512 180)
			(size 0.4064 1.3716)
			(layers "F.Cu" "F.Mask" "F.Paste")
			(net "Net_9119")
		)
		(pad "8" smd rect
			(at -2.925064 0.975106 180)
			(size 0.4064 1.3716)
			(layers "F.Cu" "F.Mask" "F.Paste")
			(net "Net_9118")
		)
		(pad "9" smd rect
			(at -2.925064 1.625092 180)
			(size 0.4064 1.3716)
			(layers "F.Cu" "F.Mask" "F.Paste")
			(net "Net_9117")
		)
		(pad "10" smd rect
			(at -2.925064 2.275078 180)
			(size 0.4064 1.3716)
			(layers "F.Cu" "F.Mask" "F.Paste")
			(net "Net_9116")
		)
		(pad "11" smd rect
			(at -2.925064 2.925064 180)
			(size 0.4064 1.3716)
			(layers "F.Cu" "F.Mask" "F.Paste")
			(net "Net_9115")
		)
		(pad "12" smd rect
			(at -2.925064 3.674872 180)
			(size 0.6096 1.3716)
			(layers "F.Cu" "F.Mask" "F.Paste")
			(net "GND")
		)
		(pad "13" smd rect
			(at 2.925064 3.674872 180)
			(size 0.6096 1.3716)
			(layers "F.Cu" "F.Mask" "F.Paste")
			(net "Net_9114")
		)
		(pad "14" smd rect
			(at 2.925064 2.925064 180)
			(size 0.4064 1.3716)
			(layers "F.Cu" "F.Mask" "F.Paste")
			(net "Net_9113")
		)
		(pad "15" smd rect
			(at 2.925064 2.275078 180)
			(size 0.4064 1.3716)
			(layers "F.Cu" "F.Mask" "F.Paste")
			(net "Net_9112")
		)
		(pad "16" smd rect
			(at 2.925064 1.625092 180)
			(size 0.4064 1.3716)
			(layers "F.Cu" "F.Mask" "F.Paste")
			(net "Net_9111")
		)
		(pad "17" smd rect
			(at 2.925064 0.975106 180)
			(size 0.4064 1.3716)
			(layers "F.Cu" "F.Mask" "F.Paste")
			(net "Net_9110")
		)
		(pad "18" smd rect
			(at 2.925064 0.32512 180)
			(size 0.4064 1.3716)
			(layers "F.Cu" "F.Mask" "F.Paste")
			(net "Net_9109")
		)
		(pad "19" smd rect
			(at 2.925064 -0.32512 180)
			(size 0.4064 1.3716)
			(layers "F.Cu" "F.Mask" "F.Paste")
			(net "Net_9108")
		)
		(pad "20" smd rect
			(at 2.925064 -0.975106 180)
			(size 0.4064 1.3716)
			(layers "F.Cu" "F.Mask" "F.Paste")
			(net "Net_9107")
		)
		(pad "21" smd rect
			(at 2.925064 -1.625092 180)
			(size 0.4064 1.3716)
			(layers "F.Cu" "F.Mask" "F.Paste")
			(net "BIC_RECOVER_IOEXP_A0")
		)
		(pad "22" smd rect
			(at 2.925064 -2.275078 180)
			(size 0.4064 1.3716)
			(layers "F.Cu" "F.Mask" "F.Paste")
			(net "SMB_BIC_RECOVER_IOEXP_SCL")
		)
		(pad "23" smd rect
			(at 2.925064 -2.925064 180)
			(size 0.4064 1.3716)
			(layers "F.Cu" "F.Mask" "F.Paste")
			(net "SMB_BIC_RECOVER_IOEXP_SDA")
		)
		(pad "24" smd rect
			(at 2.925064 -3.674872 180)
			(size 0.6096 1.3716)
			(layers "F.Cu" "F.Mask" "F.Paste")
			(net "P3V3_AUX")
		)
	)
	(footprint ""
		(layer "F.Cu")
		(at 213.801198 -219.306902)
		(property "Reference" "R4873"
			(at 0 0 0)
			(layer "F.SilkS")
			(hide yes)
			(effects
				(font
					(size 1.27 1.27)
				)
			)
		)
		(property "Value" ""
			(at 0 0 0)
			(layer "F.Fab")
			(effects
				(font
					(size 1.27 1.27)
				)
			)
		)
		(duplicate_pad_numbers_are_jumpers no)
		(fp_line
			(start -0.7874 -0.4064)
			(end 0.7874 -0.4064)
			(stroke
				(width 0.1524)
				(type default)
			)
			(layer "F.SilkS")
		)
		(fp_line
			(start -0.7874 0.4064)
			(end -0.7874 -0.4064)
			(stroke
				(width 0.1524)
				(type default)
			)
			(layer "F.SilkS")
		)
		(fp_line
			(start 0.7874 -0.4064)
			(end 0.7874 0.4064)
			(stroke
				(width 0.1524)
				(type default)
			)
			(layer "F.SilkS")
		)
		(fp_line
			(start 0.7874 0.4064)
			(end -0.7874 0.4064)
			(stroke
				(width 0.1524)
				(type default)
			)
			(layer "F.SilkS")
		)
		(fp_line
			(start -0.67945 -0.305054)
			(end -0.12065 -0.305054)
			(stroke
				(width 0.1)
				(type default)
			)
			(layer "F.Fab")
		)
		(fp_line
			(start -0.67945 0.3048)
			(end -0.67945 -0.305054)
			(stroke
				(width 0.1)
				(type default)
			)
			(layer "F.Fab")
		)
		(fp_line
			(start -0.12065 -0.305054)
			(end -0.12065 -0.2794)
			(stroke
				(width 0.1)
				(type default)
			)
			(layer "F.Fab")
		)
		(fp_line
			(start -0.12065 -0.2794)
			(end 0.12065 -0.2794)
			(stroke
				(width 0.1)
				(type default)
			)
			(layer "F.Fab")
		)
		(fp_line
			(start -0.12065 0.2794)
			(end -0.12065 0.3048)
			(stroke
				(width 0.1)
				(type default)
			)
			(layer "F.Fab")
		)
		(fp_line
			(start -0.12065 0.3048)
			(end -0.67945 0.3048)
			(stroke
				(width 0.1)
				(type default)
			)
			(layer "F.Fab")
		)
		(fp_line
			(start 0.120396 0.2794)
			(end -0.12065 0.2794)
			(stroke
				(width 0.1)
				(type default)
			)
			(layer "F.Fab")
		)
		(fp_line
			(start 0.120396 0.3048)
			(end 0.120396 0.2794)
			(stroke
				(width 0.1)
				(type default)
			)
			(layer "F.Fab")
		)
		(fp_line
			(start 0.12065 -0.3048)
			(end 0.67945 -0.3048)
			(stroke
				(width 0.1)
				(type default)
			)
			(layer "F.Fab")
		)
		(fp_line
			(start 0.12065 -0.2794)
			(end 0.12065 -0.3048)
			(stroke
				(width 0.1)
				(type default)
			)
			(layer "F.Fab")
		)
		(fp_line
			(start 0.67945 -0.3048)
			(end 0.67945 0.3048)
			(stroke
				(width 0.1)
				(type default)
			)
			(layer "F.Fab")
		)
		(fp_line
			(start 0.67945 0.3048)
			(end 0.120396 0.3048)
			(stroke
				(width 0.1)
				(type default)
			)
			(layer "F.Fab")
		)
		(pad "1" smd circle
			(at -0.40005 0)
			(size 0 0)
			(layers "F.Cu" "F.Mask" "F.Paste")
			(net "P1V2_AUX")
		)
		(pad "2" smd circle
			(at 0.40005 0)
			(size 0 0)
			(layers "F.Cu" "F.Mask" "F.Paste")
			(net "SMB_NIC4_SCL")
		)
	)
	(footprint ""
		(layer "F.Cu")
		(at 106.298492 -5.747258)
		(property "Reference" "R1648"
			(at 0 0 0)
			(layer "F.SilkS")
			(hide yes)
			(effects
				(font
					(size 1.27 1.27)
				)
			)
		)
		(property "Value" ""
			(at 0 0 0)
			(layer "F.Fab")
			(effects
				(font
					(size 1.27 1.27)
				)
			)
		)
		(duplicate_pad_numbers_are_jumpers no)
		(fp_line
			(start -0.7874 -0.4064)
			(end 0.7874 -0.4064)
			(stroke
				(width 0.1524)
				(type default)
			)
			(layer "F.SilkS")
		)
		(fp_line
			(start -0.7874 0.4064)
			(end -0.7874 -0.4064)
			(stroke
				(width 0.1524)
				(type default)
			)
			(layer "F.SilkS")
		)
		(fp_line
			(start 0.7874 -0.4064)
			(end 0.7874 0.4064)
			(stroke
				(width 0.1524)
				(type default)
			)
			(layer "F.SilkS")
		)
		(fp_line
			(start 0.7874 0.4064)
			(end -0.7874 0.4064)
			(stroke
				(width 0.1524)
				(type default)
			)
			(layer "F.SilkS")
		)
		(fp_line
			(start -0.67945 -0.305054)
			(end -0.12065 -0.305054)
			(stroke
				(width 0.1)
				(type default)
			)
			(layer "F.Fab")
		)
		(fp_line
			(start -0.67945 0.3048)
			(end -0.67945 -0.305054)
			(stroke
				(width 0.1)
				(type default)
			)
			(layer "F.Fab")
		)
		(fp_line
			(start -0.12065 -0.305054)
			(end -0.12065 -0.2794)
			(stroke
				(width 0.1)
				(type default)
			)
			(layer "F.Fab")
		)
		(fp_line
			(start -0.12065 -0.2794)
			(end 0.12065 -0.2794)
			(stroke
				(width 0.1)
				(type default)
			)
			(layer "F.Fab")
		)
		(fp_line
			(start -0.12065 0.2794)
			(end -0.12065 0.3048)
			(stroke
				(width 0.1)
				(type default)
			)
			(layer "F.Fab")
		)
		(fp_line
			(start -0.12065 0.3048)
			(end -0.67945 0.3048)
			(stroke
				(width 0.1)
				(type default)
			)
			(layer "F.Fab")
		)
		(fp_line
			(start 0.120396 0.2794)
			(end -0.12065 0.2794)
			(stroke
				(width 0.1)
				(type default)
			)
			(layer "F.Fab")
		)
		(fp_line
			(start 0.120396 0.3048)
			(end 0.120396 0.2794)
			(stroke
				(width 0.1)
				(type default)
			)
			(layer "F.Fab")
		)
		(fp_line
			(start 0.12065 -0.3048)
			(end 0.67945 -0.3048)
			(stroke
				(width 0.1)
				(type default)
			)
			(layer "F.Fab")
		)
		(fp_line
			(start 0.12065 -0.2794)
			(end 0.12065 -0.3048)
			(stroke
				(width 0.1)
				(type default)
			)
			(layer "F.Fab")
		)
		(fp_line
			(start 0.67945 -0.3048)
			(end 0.67945 0.3048)
			(stroke
				(width 0.1)
				(type default)
			)
			(layer "F.Fab")
		)
		(fp_line
			(start 0.67945 0.3048)
			(end 0.120396 0.3048)
			(stroke
				(width 0.1)
				(type default)
			)
			(layer "F.Fab")
		)
		(pad "1" smd circle
			(at -0.40005 0)
			(size 0 0)
			(layers "F.Cu" "F.Mask" "F.Paste")
			(net "SMB_SSD3_ISO_EN")
		)
		(pad "2" smd circle
			(at 0.40005 0)
			(size 0 0)
			(layers "F.Cu" "F.Mask" "F.Paste")
			(net "P3V3_AUX")
		)
	)
	(footprint ""
		(layer "F.Cu")
		(at 52.267866 -51.019456)
		(property "Reference" "PC374"
			(at 0 0 0)
			(layer "F.SilkS")
			(hide yes)
			(effects
				(font
					(size 1.27 1.27)
				)
			)
		)
		(property "Value" ""
			(at 0 0 0)
			(layer "F.Fab")
			(effects
				(font
					(size 1.27 1.27)
				)
			)
		)
		(duplicate_pad_numbers_are_jumpers no)
		(fp_line
			(start -0.7874 -0.4064)
			(end 0.7874 -0.4064)
			(stroke
				(width 0.1524)
				(type default)
			)
			(layer "F.SilkS")
		)
		(fp_line
			(start -0.7874 0.4064)
			(end -0.7874 -0.4064)
			(stroke
				(width 0.1524)
				(type default)
			)
			(layer "F.SilkS")
		)
		(fp_line
			(start 0.7874 -0.4064)
			(end 0.7874 0.4064)
			(stroke
				(width 0.1524)
				(type default)
			)
			(layer "F.SilkS")
		)
		(fp_line
			(start 0.7874 0.4064)
			(end -0.7874 0.4064)
			(stroke
				(width 0.1524)
				(type default)
			)
			(layer "F.SilkS")
		)
		(fp_line
			(start -0.6858 -0.3048)
			(end -0.1016 -0.3048)
			(stroke
				(width 0.1)
				(type default)
			)
			(layer "F.Fab")
		)
		(fp_line
			(start -0.6858 0.3048)
			(end -0.6858 -0.3048)
			(stroke
				(width 0.1)
				(type default)
			)
			(layer "F.Fab")
		)
		(fp_line
			(start -0.1016 -0.3048)
			(end -0.1016 -0.2794)
			(stroke
				(width 0.1)
				(type default)
			)
			(layer "F.Fab")
		)
		(fp_line
			(start -0.1016 -0.2794)
			(end 0.1016 -0.2794)
			(stroke
				(width 0.1)
				(type default)
			)
			(layer "F.Fab")
		)
		(fp_line
			(start -0.1016 0.2794)
			(end -0.1016 0.3048)
			(stroke
				(width 0.1)
				(type default)
			)
			(layer "F.Fab")
		)
		(fp_line
			(start -0.1016 0.3048)
			(end -0.6858 0.3048)
			(stroke
				(width 0.1)
				(type default)
			)
			(layer "F.Fab")
		)
		(fp_line
			(start 0.1016 -0.3048)
			(end 0.6858 -0.3048)
			(stroke
				(width 0.1)
				(type default)
			)
			(layer "F.Fab")
		)
		(fp_line
			(start 0.1016 -0.2794)
			(end 0.1016 -0.3048)
			(stroke
				(width 0.1)
				(type default)
			)
			(layer "F.Fab")
		)
		(fp_line
			(start 0.1016 0.2794)
			(end -0.1016 0.2794)
			(stroke
				(width 0.1)
				(type default)
			)
			(layer "F.Fab")
		)
		(fp_line
			(start 0.1016 0.3048)
			(end 0.1016 0.2794)
			(stroke
				(width 0.1)
				(type default)
			)
			(layer "F.Fab")
		)
		(fp_line
			(start 0.6858 -0.3048)
			(end 0.6858 0.3048)
			(stroke
				(width 0.1)
				(type default)
			)
			(layer "F.Fab")
		)
		(fp_line
			(start 0.6858 0.3048)
			(end 0.1016 0.3048)
			(stroke
				(width 0.1)
				(type default)
			)
			(layer "F.Fab")
		)
		(pad "1" smd rect
			(at -0.40005 0 180)
			(size 0.4572 0.508)
			(layers "F.Cu" "F.Mask" "F.Paste")
			(net "P12V_SSD1_SS")
		)
		(pad "2" smd rect
			(at 0.40005 0 180)
			(size 0.4572 0.508)
			(layers "F.Cu" "F.Mask" "F.Paste")
			(net "GND")
		)
	)
	(footprint ""
		(layer "F.Cu")
		(at 223.586294 -177.53838 180)
		(property "Reference" "R3144"
			(at 0 0 180)
			(layer "F.SilkS")
			(hide yes)
			(effects
				(font
					(size 1.27 1.27)
				)
			)
		)
		(property "Value" ""
			(at 0 0 180)
			(layer "F.Fab")
			(effects
				(font
					(size 1.27 1.27)
				)
			)
		)
		(duplicate_pad_numbers_are_jumpers no)
		(fp_line
			(start 0.7874 0.4064)
			(end -0.7874 0.4064)
			(stroke
				(width 0.1524)
				(type default)
			)
			(layer "F.SilkS")
		)
		(fp_line
			(start 0.7874 -0.4064)
			(end 0.7874 0.4064)
			(stroke
				(width 0.1524)
				(type default)
			)
			(layer "F.SilkS")
		)
		(fp_line
			(start -0.7874 0.4064)
			(end -0.7874 -0.4064)
			(stroke
				(width 0.1524)
				(type default)
			)
			(layer "F.SilkS")
		)
		(fp_line
			(start -0.7874 -0.4064)
			(end 0.7874 -0.4064)
			(stroke
				(width 0.1524)
				(type default)
			)
			(layer "F.SilkS")
		)
		(fp_line
			(start 0.67945 0.3048)
			(end 0.120396 0.3048)
			(stroke
				(width 0.1)
				(type default)
			)
			(layer "F.Fab")
		)
		(fp_line
			(start 0.67945 -0.3048)
			(end 0.67945 0.3048)
			(stroke
				(width 0.1)
				(type default)
			)
			(layer "F.Fab")
		)
		(fp_line
			(start 0.12065 -0.2794)
			(end 0.12065 -0.3048)
			(stroke
				(width 0.1)
				(type default)
			)
			(layer "F.Fab")
		)
		(fp_line
			(start 0.12065 -0.3048)
			(end 0.67945 -0.3048)
			(stroke
				(width 0.1)
				(type default)
			)
			(layer "F.Fab")
		)
		(fp_line
			(start 0.120396 0.3048)
			(end 0.120396 0.2794)
			(stroke
				(width 0.1)
				(type default)
			)
			(layer "F.Fab")
		)
		(fp_line
			(start 0.120396 0.2794)
			(end -0.12065 0.2794)
			(stroke
				(width 0.1)
				(type default)
			)
			(layer "F.Fab")
		)
		(fp_line
			(start -0.12065 0.3048)
			(end -0.67945 0.3048)
			(stroke
				(width 0.1)
				(type default)
			)
			(layer "F.Fab")
		)
		(fp_line
			(start -0.12065 0.2794)
			(end -0.12065 0.3048)
			(stroke
				(width 0.1)
				(type default)
			)
			(layer "F.Fab")
		)
		(fp_line
			(start -0.12065 -0.2794)
			(end 0.12065 -0.2794)
			(stroke
				(width 0.1)
				(type default)
			)
			(layer "F.Fab")
		)
		(fp_line
			(start -0.12065 -0.305054)
			(end -0.12065 -0.2794)
			(stroke
				(width 0.1)
				(type default)
			)
			(layer "F.Fab")
		)
		(fp_line
			(start -0.67945 0.3048)
			(end -0.67945 -0.305054)
			(stroke
				(width 0.1)
				(type default)
			)
			(layer "F.Fab")
		)
		(fp_line
			(start -0.67945 -0.305054)
			(end -0.12065 -0.305054)
			(stroke
				(width 0.1)
				(type default)
			)
			(layer "F.Fab")
		)
		(pad "1" smd circle
			(at -0.40005 0 180)
			(size 0 0)
			(layers "F.Cu" "F.Mask" "F.Paste")
			(net "ADM1085_CEXT")
		)
		(pad "2" smd circle
			(at 0.40005 0 180)
			(size 0 0)
			(layers "F.Cu" "F.Mask" "F.Paste")
			(net "PWRGD_P1V2_AUX_R")
		)
	)
	(footprint ""
		(layer "F.Cu")
		(at 223.967294 -453.501252)
		(property "Reference" "X70"
			(at -0.1778 -1.92913 0)
			(unlocked yes)
			(layer "F.SilkS")
			(effects
				(font
					(size 0.7874 0.5842)
					(thickness 0.1524)
				)
				(justify left)
			)
		)
		(property "Value" ""
			(at 0 0 0)
			(layer "F.Fab")
			(effects
				(font
					(size 1.27 1.27)
				)
			)
		)
		(property "Device Type" "TP_TDR_4P_FTS_MPKT4_H025P0200_IO_TP15_TP_TDR_4P_DIP"
			(at 1.30175 1.27 90)
			(unlocked yes)
			(layer "F.Fab")
			(hide yes)
			(effects
				(font
					(size 0.635 0.4064)
					(thickness 0.1524)
				)
			)
		)
		(property "User Part Number" "TP15"
			(at 1.30175 1.27 90)
			(unlocked yes)
			(layer "Cmts.User")
			(hide yes)
			(effects
				(font
					(size 0.635 0.4064)
					(thickness 0.1524)
				)
			)
		)
		(duplicate_pad_numbers_are_jumpers no)
		(fp_line
			(start 0 -1.27)
			(end 0 -0.635)
			(stroke
				(width 0.1524)
				(type default)
			)
			(layer "F.SilkS")
		)
		(fp_line
			(start 0 0.635)
			(end 0 1.905)
			(stroke
				(width 0.1524)
				(type default)
			)
			(layer "F.SilkS")
		)
		(fp_line
			(start 0 3.175)
			(end 0 3.81)
			(stroke
				(width 0.1524)
				(type default)
			)
			(layer "F.SilkS")
		)
		(fp_line
			(start 0 3.81)
			(end 2.54 3.81)
			(stroke
				(width 0.1524)
				(type default)
			)
			(layer "F.SilkS")
		)
		(fp_line
			(start 2.54 -1.27)
			(end 0 -1.27)
			(stroke
				(width 0.1524)
				(type default)
			)
			(layer "F.SilkS")
		)
		(fp_line
			(start 2.54 -1.1303)
			(end 2.54 -1.27)
			(stroke
				(width 0.1524)
				(type default)
			)
			(layer "F.SilkS")
		)
		(fp_line
			(start 2.54 1.4097)
			(end 2.54 1.1303)
			(stroke
				(width 0.1524)
				(type default)
			)
			(layer "F.SilkS")
		)
		(fp_line
			(start 2.54 3.81)
			(end 2.54 3.6703)
			(stroke
				(width 0.1524)
				(type default)
			)
			(layer "F.SilkS")
		)
		(fp_poly
			(pts
				(xy -0.761746 0) (xy -2.285746 -0.762) (xy -2.285746 0.762)
			)
			(stroke
				(width 0)
				(type default)
			)
			(fill yes)
			(layer "F.SilkS")
		)
		(fp_line
			(start 0 -1.27)
			(end 0 3.81)
			(stroke
				(width 0.1)
				(type default)
			)
			(layer "F.Fab")
		)
		(fp_line
			(start 0 3.81)
			(end 2.54 3.81)
			(stroke
				(width 0.1)
				(type default)
			)
			(layer "F.Fab")
		)
		(fp_line
			(start 2.54 -1.27)
			(end 0 -1.27)
			(stroke
				(width 0.1)
				(type default)
			)
			(layer "F.Fab")
		)
		(fp_line
			(start 2.54 3.81)
			(end 2.54 -1.27)
			(stroke
				(width 0.1)
				(type default)
			)
			(layer "F.Fab")
		)
		(fp_poly
			(pts
				(xy -0.761746 0) (xy -2.285746 -0.762) (xy -2.285746 0.762)
			)
			(stroke
				(width 0)
				(type default)
			)
			(fill yes)
			(layer "F.Fab")
		)
		(pad "1" thru_hole circle
			(at 0 0)
			(size 1.0033 1.0033)
			(drill 0.249936)
			(layers "*.Cu" "*.Mask")
			(remove_unused_layers no)
			(net "TDR_DIFF_100_IN2_DIP")
			(clearance 0.10795)
			(thermal_gap 0.10795)
			(padstack
				(mode front_inner_back)
				(layer "Inner"
					(shape circle)
					(size 0.8001 0.8001)
					(clearance 0.1524)
				)
				(layer "B.Cu"
					(shape circle)
					(size 1.0033 1.0033)
					(clearance 0.10795)
				)
			)
		)
		(pad "2" thru_hole circle
			(at 2.54 0)
			(size 1.9939 1.9939)
			(drill 0.249936)
			(layers "*.Cu" "*.Mask")
			(remove_unused_layers no)
			(net "COUPON_GND1")
			(clearance 0.10795)
			(thermal_gap 0.10795)
			(padstack
				(mode front_inner_back)
				(layer "Inner"
					(shape circle)
					(size 0.8001 0.8001)
					(clearance 0.1524)
				)
				(layer "B.Cu"
					(shape circle)
					(size 1.9939 1.9939)
					(clearance 0.10795)
				)
			)
		)
		(pad "3" thru_hole circle
			(at 2.54 2.54)
			(size 1.9939 1.9939)
			(drill 0.249936)
			(layers "*.Cu" "*.Mask")
			(remove_unused_layers no)
			(net "COUPON_GND1")
			(clearance 0.10795)
			(thermal_gap 0.10795)
			(padstack
				(mode front_inner_back)
				(layer "Inner"
					(shape circle)
					(size 0.8001 0.8001)
					(clearance 0.1524)
				)
				(layer "B.Cu"
					(shape circle)
					(size 1.9939 1.9939)
					(clearance 0.10795)
				)
			)
		)
		(pad "4" thru_hole circle
			(at 0 2.54)
			(size 1.0033 1.0033)
			(drill 0.249936)
			(layers "*.Cu" "*.Mask")
			(remove_unused_layers no)
			(net "TDR_DIFF_100_IN2_DIN")
			(clearance 0.10795)
			(thermal_gap 0.10795)
			(padstack
				(mode front_inner_back)
				(layer "Inner"
					(shape circle)
					(size 0.8001 0.8001)
					(clearance 0.1524)
				)
				(layer "B.Cu"
					(shape circle)
					(size 1.0033 1.0033)
					(clearance 0.10795)
				)
			)
		)
	)
	(footprint ""
		(layer "F.Cu")
		(at 349.762318 -205.231492 90)
		(property "Reference" "R6421"
			(at 0 0 90)
			(layer "F.SilkS")
			(hide yes)
			(effects
				(font
					(size 1.27 1.27)
				)
			)
		)
		(property "Value" ""
			(at 0 0 90)
			(layer "F.Fab")
			(effects
				(font
					(size 1.27 1.27)
				)
			)
		)
		(duplicate_pad_numbers_are_jumpers no)
		(fp_line
			(start 0.7874 -0.4064)
			(end 0.7874 0.4064)
			(stroke
				(width 0.1524)
				(type default)
			)
			(layer "F.SilkS")
		)
		(fp_line
			(start -0.7874 -0.4064)
			(end 0.7874 -0.4064)
			(stroke
				(width 0.1524)
				(type default)
			)
			(layer "F.SilkS")
		)
		(fp_line
			(start 0.7874 0.4064)
			(end -0.7874 0.4064)
			(stroke
				(width 0.1524)
				(type default)
			)
			(layer "F.SilkS")
		)
		(fp_line
			(start -0.7874 0.4064)
			(end -0.7874 -0.4064)
			(stroke
				(width 0.1524)
				(type default)
			)
			(layer "F.SilkS")
		)
		(fp_line
			(start -0.12065 -0.305054)
			(end -0.12065 -0.2794)
			(stroke
				(width 0.1)
				(type default)
			)
			(layer "F.Fab")
		)
		(fp_line
			(start -0.67945 -0.305054)
			(end -0.12065 -0.305054)
			(stroke
				(width 0.1)
				(type default)
			)
			(layer "F.Fab")
		)
		(fp_line
			(start 0.67945 -0.3048)
			(end 0.67945 0.3048)
			(stroke
				(width 0.1)
				(type default)
			)
			(layer "F.Fab")
		)
		(fp_line
			(start 0.12065 -0.3048)
			(end 0.67945 -0.3048)
			(stroke
				(width 0.1)
				(type default)
			)
			(layer "F.Fab")
		)
		(fp_line
			(start 0.12065 -0.2794)
			(end 0.12065 -0.3048)
			(stroke
				(width 0.1)
				(type default)
			)
			(layer "F.Fab")
		)
		(fp_line
			(start -0.12065 -0.2794)
			(end 0.12065 -0.2794)
			(stroke
				(width 0.1)
				(type default)
			)
			(layer "F.Fab")
		)
		(fp_line
			(start 0.120396 0.2794)
			(end -0.12065 0.2794)
			(stroke
				(width 0.1)
				(type default)
			)
			(layer "F.Fab")
		)
		(fp_line
			(start -0.12065 0.2794)
			(end -0.12065 0.3048)
			(stroke
				(width 0.1)
				(type default)
			)
			(layer "F.Fab")
		)
		(fp_line
			(start 0.67945 0.3048)
			(end 0.120396 0.3048)
			(stroke
				(width 0.1)
				(type default)
			)
			(layer "F.Fab")
		)
		(fp_line
			(start 0.120396 0.3048)
			(end 0.120396 0.2794)
			(stroke
				(width 0.1)
				(type default)
			)
			(layer "F.Fab")
		)
		(fp_line
			(start -0.12065 0.3048)
			(end -0.67945 0.3048)
			(stroke
				(width 0.1)
				(type default)
			)
			(layer "F.Fab")
		)
		(fp_line
			(start -0.67945 0.3048)
			(end -0.67945 -0.305054)
			(stroke
				(width 0.1)
				(type default)
			)
			(layer "F.Fab")
		)
		(pad "1" smd circle
			(at -0.40005 0 90)
			(size 0 0)
			(layers "F.Cu" "F.Mask" "F.Paste")
			(net "FPGA_PEX2_MODE_SEL1_R")
		)
		(pad "2" smd circle
			(at 0.40005 0 90)
			(size 0 0)
			(layers "F.Cu" "F.Mask" "F.Paste")
			(net "FPGA_PEX2_MODE_SEL1")
		)
	)
	(footprint ""
		(layer "F.Cu")
		(at 314.165234 -435.658006 -90)
		(property "Reference" "J53"
			(at -2.4257 -5.635752 90)
			(unlocked yes)
			(layer "F.SilkS")
			(effects
				(font
					(size 0.7874 0.5842)
					(thickness 0.1524)
				)
			)
		)
		(property "Value" ""
			(at 0 0 270)
			(layer "F.Fab")
			(effects
				(font
					(size 1.27 1.27)
				)
			)
		)
		(duplicate_pad_numbers_are_jumpers no)
		(fp_line
			(start 0 4.011168)
			(end -3.330702 -4.771136)
			(stroke
				(width 0.1524)
				(type default)
			)
			(layer "F.SilkS")
		)
		(fp_line
			(start -3.330702 -4.771136)
			(end 3.330702 -4.771136)
			(stroke
				(width 0.1524)
				(type default)
			)
			(layer "F.SilkS")
		)
		(fp_line
			(start 3.330702 -4.771136)
			(end 0 4.011168)
			(stroke
				(width 0.1524)
				(type default)
			)
			(layer "F.SilkS")
		)
		(fp_line
			(start 0 4.011168)
			(end -3.330702 -4.771136)
			(stroke
				(width 0.1)
				(type default)
			)
			(layer "F.Fab")
		)
		(fp_line
			(start -3.330702 -4.771136)
			(end 3.330702 -4.771136)
			(stroke
				(width 0.1)
				(type default)
			)
			(layer "F.Fab")
		)
		(fp_line
			(start 3.330702 -4.771136)
			(end 0 4.011168)
			(stroke
				(width 0.1)
				(type default)
			)
			(layer "F.Fab")
		)
		(pad "1" thru_hole circle
			(at 0 0 270)
			(size 2.159 2.159)
			(drill 1.7018)
			(layers "*.Cu" "*.Mask")
			(remove_unused_layers no)
			(net "COUPON_GND1")
			(clearance 0.0254)
			(thermal_gap 0.0254)
		)
		(pad "2" thru_hole circle
			(at -1.27 -3.348736 270)
			(size 2.159 2.159)
			(drill 1.7018)
			(layers "*.Cu" "*.Mask")
			(remove_unused_layers no)
			(net "TDR_SE_50_OHM_BOT")
			(clearance 0.0254)
			(thermal_gap 0.0254)
		)
		(pad "3" thru_hole circle
			(at 1.27 -3.348736 270)
			(size 2.159 2.159)
			(drill 1.7018)
			(layers "*.Cu" "*.Mask")
			(remove_unused_layers no)
			(net "TDR_SE_50_OHM_BOT")
			(clearance 0.0254)
			(thermal_gap 0.0254)
		)
	)
	(footprint ""
		(layer "F.Cu")
		(at 357.246682 -205.160118 90)
		(property "Reference" "R6420"
			(at 0 0 90)
			(layer "F.SilkS")
			(hide yes)
			(effects
				(font
					(size 1.27 1.27)
				)
			)
		)
		(property "Value" ""
			(at 0 0 90)
			(layer "F.Fab")
			(effects
				(font
					(size 1.27 1.27)
				)
			)
		)
		(duplicate_pad_numbers_are_jumpers no)
		(fp_line
			(start 0.7874 -0.4064)
			(end 0.7874 0.4064)
			(stroke
				(width 0.1524)
				(type default)
			)
			(layer "F.SilkS")
		)
		(fp_line
			(start -0.7874 -0.4064)
			(end 0.7874 -0.4064)
			(stroke
				(width 0.1524)
				(type default)
			)
			(layer "F.SilkS")
		)
		(fp_line
			(start 0.7874 0.4064)
			(end -0.7874 0.4064)
			(stroke
				(width 0.1524)
				(type default)
			)
			(layer "F.SilkS")
		)
		(fp_line
			(start -0.7874 0.4064)
			(end -0.7874 -0.4064)
			(stroke
				(width 0.1524)
				(type default)
			)
			(layer "F.SilkS")
		)
		(fp_line
			(start -0.12065 -0.305054)
			(end -0.12065 -0.2794)
			(stroke
				(width 0.1)
				(type default)
			)
			(layer "F.Fab")
		)
		(fp_line
			(start -0.67945 -0.305054)
			(end -0.12065 -0.305054)
			(stroke
				(width 0.1)
				(type default)
			)
			(layer "F.Fab")
		)
		(fp_line
			(start 0.67945 -0.3048)
			(end 0.67945 0.3048)
			(stroke
				(width 0.1)
				(type default)
			)
			(layer "F.Fab")
		)
		(fp_line
			(start 0.12065 -0.3048)
			(end 0.67945 -0.3048)
			(stroke
				(width 0.1)
				(type default)
			)
			(layer "F.Fab")
		)
		(fp_line
			(start 0.12065 -0.2794)
			(end 0.12065 -0.3048)
			(stroke
				(width 0.1)
				(type default)
			)
			(layer "F.Fab")
		)
		(fp_line
			(start -0.12065 -0.2794)
			(end 0.12065 -0.2794)
			(stroke
				(width 0.1)
				(type default)
			)
			(layer "F.Fab")
		)
		(fp_line
			(start 0.120396 0.2794)
			(end -0.12065 0.2794)
			(stroke
				(width 0.1)
				(type default)
			)
			(layer "F.Fab")
		)
		(fp_line
			(start -0.12065 0.2794)
			(end -0.12065 0.3048)
			(stroke
				(width 0.1)
				(type default)
			)
			(layer "F.Fab")
		)
		(fp_line
			(start 0.67945 0.3048)
			(end 0.120396 0.3048)
			(stroke
				(width 0.1)
				(type default)
			)
			(layer "F.Fab")
		)
		(fp_line
			(start 0.120396 0.3048)
			(end 0.120396 0.2794)
			(stroke
				(width 0.1)
				(type default)
			)
			(layer "F.Fab")
		)
		(fp_line
			(start -0.12065 0.3048)
			(end -0.67945 0.3048)
			(stroke
				(width 0.1)
				(type default)
			)
			(layer "F.Fab")
		)
		(fp_line
			(start -0.67945 0.3048)
			(end -0.67945 -0.305054)
			(stroke
				(width 0.1)
				(type default)
			)
			(layer "F.Fab")
		)
		(pad "1" smd circle
			(at -0.40005 0 90)
			(size 0 0)
			(layers "F.Cu" "F.Mask" "F.Paste")
			(net "FPGA_PEX2_MODE_SEL2_R")
		)
		(pad "2" smd circle
			(at 0.40005 0 90)
			(size 0 0)
			(layers "F.Cu" "F.Mask" "F.Paste")
			(net "FPGA_PEX2_MODE_SEL2")
		)
	)
	(footprint ""
		(layer "F.Cu")
		(at 232.46969 -83.318858 90)
		(property "Reference" "R1013"
			(at 0 0 90)
			(layer "F.SilkS")
			(hide yes)
			(effects
				(font
					(size 1.27 1.27)
				)
			)
		)
		(property "Value" ""
			(at 0 0 90)
			(layer "F.Fab")
			(effects
				(font
					(size 1.27 1.27)
				)
			)
		)
		(duplicate_pad_numbers_are_jumpers no)
		(fp_line
			(start -0.7874 -0.4064)
			(end 0.7874 -0.4064)
			(stroke
				(width 0.1524)
				(type default)
			)
			(layer "F.SilkS")
		)
		(fp_line
			(start 0.7874 0.4064)
			(end 0.009652 0.4064)
			(stroke
				(width 0.1524)
				(type default)
			)
			(layer "F.SilkS")
		)
		(fp_line
			(start -0.7874 0.4064)
			(end -0.7874 -0.4064)
			(stroke
				(width 0.1524)
				(type default)
			)
			(layer "F.SilkS")
		)
		(fp_line
			(start -0.12065 -0.305054)
			(end -0.12065 -0.2794)
			(stroke
				(width 0.1)
				(type default)
			)
			(layer "F.Fab")
		)
		(fp_line
			(start -0.67945 -0.305054)
			(end -0.12065 -0.305054)
			(stroke
				(width 0.1)
				(type default)
			)
			(layer "F.Fab")
		)
		(fp_line
			(start 0.67945 -0.3048)
			(end 0.67945 0.3048)
			(stroke
				(width 0.1)
				(type default)
			)
			(layer "F.Fab")
		)
		(fp_line
			(start 0.12065 -0.3048)
			(end 0.67945 -0.3048)
			(stroke
				(width 0.1)
				(type default)
			)
			(layer "F.Fab")
		)
		(fp_line
			(start 0.12065 -0.2794)
			(end 0.12065 -0.3048)
			(stroke
				(width 0.1)
				(type default)
			)
			(layer "F.Fab")
		)
		(fp_line
			(start -0.12065 -0.2794)
			(end 0.12065 -0.2794)
			(stroke
				(width 0.1)
				(type default)
			)
			(layer "F.Fab")
		)
		(fp_line
			(start 0.120396 0.2794)
			(end -0.12065 0.2794)
			(stroke
				(width 0.1)
				(type default)
			)
			(layer "F.Fab")
		)
		(fp_line
			(start -0.12065 0.2794)
			(end -0.12065 0.3048)
			(stroke
				(width 0.1)
				(type default)
			)
			(layer "F.Fab")
		)
		(fp_line
			(start 0.67945 0.3048)
			(end 0.120396 0.3048)
			(stroke
				(width 0.1)
				(type default)
			)
			(layer "F.Fab")
		)
		(fp_line
			(start 0.120396 0.3048)
			(end 0.120396 0.2794)
			(stroke
				(width 0.1)
				(type default)
			)
			(layer "F.Fab")
		)
		(fp_line
			(start -0.12065 0.3048)
			(end -0.67945 0.3048)
			(stroke
				(width 0.1)
				(type default)
			)
			(layer "F.Fab")
		)
		(fp_line
			(start -0.67945 0.3048)
			(end -0.67945 -0.305054)
			(stroke
				(width 0.1)
				(type default)
			)
			(layer "F.Fab")
		)
		(pad "1" smd rect
			(at -0.40005 0 270)
			(size 0.4572 0.508)
			(layers "F.Cu" "F.Mask" "F.Paste")
			(net "USB2_FT4232_SDB_R_DN")
		)
		(pad "2" smd rect
			(at 0.40005 0 270)
			(size 0.4572 0.508)
			(layers "F.Cu" "F.Mask" "F.Paste")
			(net "USB2_FT4232_SDB_DN")
		)
	)
	(footprint ""
		(layer "F.Cu")
		(at 95.4786 -199.7456)
		(property "Reference" "R6625"
			(at 0 0 0)
			(layer "F.SilkS")
			(hide yes)
			(effects
				(font
					(size 1.27 1.27)
				)
			)
		)
		(property "Value" ""
			(at 0 0 0)
			(layer "F.Fab")
			(effects
				(font
					(size 1.27 1.27)
				)
			)
		)
		(duplicate_pad_numbers_are_jumpers no)
		(fp_line
			(start -0.7874 -0.4064)
			(end 0.7874 -0.4064)
			(stroke
				(width 0.1524)
				(type default)
			)
			(layer "F.SilkS")
		)
		(fp_line
			(start -0.7874 0.4064)
			(end -0.7874 -0.4064)
			(stroke
				(width 0.1524)
				(type default)
			)
			(layer "F.SilkS")
		)
		(fp_line
			(start 0.7874 -0.4064)
			(end 0.7874 0.4064)
			(stroke
				(width 0.1524)
				(type default)
			)
			(layer "F.SilkS")
		)
		(fp_line
			(start 0.7874 0.4064)
			(end -0.7874 0.4064)
			(stroke
				(width 0.1524)
				(type default)
			)
			(layer "F.SilkS")
		)
		(fp_line
			(start -0.67945 -0.305054)
			(end -0.12065 -0.305054)
			(stroke
				(width 0.1)
				(type default)
			)
			(layer "F.Fab")
		)
		(fp_line
			(start -0.67945 0.3048)
			(end -0.67945 -0.305054)
			(stroke
				(width 0.1)
				(type default)
			)
			(layer "F.Fab")
		)
		(fp_line
			(start -0.12065 -0.305054)
			(end -0.12065 -0.2794)
			(stroke
				(width 0.1)
				(type default)
			)
			(layer "F.Fab")
		)
		(fp_line
			(start -0.12065 -0.2794)
			(end 0.12065 -0.2794)
			(stroke
				(width 0.1)
				(type default)
			)
			(layer "F.Fab")
		)
		(fp_line
			(start -0.12065 0.2794)
			(end -0.12065 0.3048)
			(stroke
				(width 0.1)
				(type default)
			)
			(layer "F.Fab")
		)
		(fp_line
			(start -0.12065 0.3048)
			(end -0.67945 0.3048)
			(stroke
				(width 0.1)
				(type default)
			)
			(layer "F.Fab")
		)
		(fp_line
			(start 0.120396 0.2794)
			(end -0.12065 0.2794)
			(stroke
				(width 0.1)
				(type default)
			)
			(layer "F.Fab")
		)
		(fp_line
			(start 0.120396 0.3048)
			(end 0.120396 0.2794)
			(stroke
				(width 0.1)
				(type default)
			)
			(layer "F.Fab")
		)
		(fp_line
			(start 0.12065 -0.3048)
			(end 0.67945 -0.3048)
			(stroke
				(width 0.1)
				(type default)
			)
			(layer "F.Fab")
		)
		(fp_line
			(start 0.12065 -0.2794)
			(end 0.12065 -0.3048)
			(stroke
				(width 0.1)
				(type default)
			)
			(layer "F.Fab")
		)
		(fp_line
			(start 0.67945 -0.3048)
			(end 0.67945 0.3048)
			(stroke
				(width 0.1)
				(type default)
			)
			(layer "F.Fab")
		)
		(fp_line
			(start 0.67945 0.3048)
			(end 0.120396 0.3048)
			(stroke
				(width 0.1)
				(type default)
			)
			(layer "F.Fab")
		)
		(pad "1" smd circle
			(at -0.40005 0)
			(size 0 0)
			(layers "F.Cu" "F.Mask" "F.Paste")
			(net "UART_PEX3_CLI_BUF_R_TX")
		)
		(pad "2" smd circle
			(at 0.40005 0)
			(size 0 0)
			(layers "F.Cu" "F.Mask" "F.Paste")
			(net "UART_PEX3_CLI_CP2108_TX")
		)
	)
	(footprint ""
		(layer "F.Cu")
		(at 258.46786 -53.051456)
		(property "Reference" "R4466"
			(at 0 0 0)
			(layer "F.SilkS")
			(hide yes)
			(effects
				(font
					(size 1.27 1.27)
				)
			)
		)
		(property "Value" ""
			(at 0 0 0)
			(layer "F.Fab")
			(effects
				(font
					(size 1.27 1.27)
				)
			)
		)
		(duplicate_pad_numbers_are_jumpers no)
		(fp_line
			(start -0.7874 -0.4064)
			(end 0.7874 -0.4064)
			(stroke
				(width 0.1524)
				(type default)
			)
			(layer "F.SilkS")
		)
		(fp_line
			(start -0.7874 0.4064)
			(end -0.7874 -0.4064)
			(stroke
				(width 0.1524)
				(type default)
			)
			(layer "F.SilkS")
		)
		(fp_line
			(start 0.7874 -0.4064)
			(end 0.7874 0.4064)
			(stroke
				(width 0.1524)
				(type default)
			)
			(layer "F.SilkS")
		)
		(fp_line
			(start 0.7874 0.4064)
			(end -0.7874 0.4064)
			(stroke
				(width 0.1524)
				(type default)
			)
			(layer "F.SilkS")
		)
		(fp_line
			(start -0.67945 -0.305054)
			(end -0.12065 -0.305054)
			(stroke
				(width 0.1)
				(type default)
			)
			(layer "F.Fab")
		)
		(fp_line
			(start -0.67945 0.3048)
			(end -0.67945 -0.305054)
			(stroke
				(width 0.1)
				(type default)
			)
			(layer "F.Fab")
		)
		(fp_line
			(start -0.12065 -0.305054)
			(end -0.12065 -0.2794)
			(stroke
				(width 0.1)
				(type default)
			)
			(layer "F.Fab")
		)
		(fp_line
			(start -0.12065 -0.2794)
			(end 0.12065 -0.2794)
			(stroke
				(width 0.1)
				(type default)
			)
			(layer "F.Fab")
		)
		(fp_line
			(start -0.12065 0.2794)
			(end -0.12065 0.3048)
			(stroke
				(width 0.1)
				(type default)
			)
			(layer "F.Fab")
		)
		(fp_line
			(start -0.12065 0.3048)
			(end -0.67945 0.3048)
			(stroke
				(width 0.1)
				(type default)
			)
			(layer "F.Fab")
		)
		(fp_line
			(start 0.120396 0.2794)
			(end -0.12065 0.2794)
			(stroke
				(width 0.1)
				(type default)
			)
			(layer "F.Fab")
		)
		(fp_line
			(start 0.120396 0.3048)
			(end 0.120396 0.2794)
			(stroke
				(width 0.1)
				(type default)
			)
			(layer "F.Fab")
		)
		(fp_line
			(start 0.12065 -0.3048)
			(end 0.67945 -0.3048)
			(stroke
				(width 0.1)
				(type default)
			)
			(layer "F.Fab")
		)
		(fp_line
			(start 0.12065 -0.2794)
			(end 0.12065 -0.3048)
			(stroke
				(width 0.1)
				(type default)
			)
			(layer "F.Fab")
		)
		(fp_line
			(start 0.67945 -0.3048)
			(end 0.67945 0.3048)
			(stroke
				(width 0.1)
				(type default)
			)
			(layer "F.Fab")
		)
		(fp_line
			(start 0.67945 0.3048)
			(end 0.120396 0.3048)
			(stroke
				(width 0.1)
				(type default)
			)
			(layer "F.Fab")
		)
		(pad "1" smd circle
			(at -0.40005 0)
			(size 0 0)
			(layers "F.Cu" "F.Mask" "F.Paste")
			(net "PWRGD_P12V_SSD8")
		)
		(pad "2" smd circle
			(at 0.40005 0)
			(size 0 0)
			(layers "F.Cu" "F.Mask" "F.Paste")
			(net "PWRGD_P12V_SSD8_R")
		)
	)
	(footprint ""
		(layer "F.Cu")
		(at 142.368016 -53.051456)
		(property "Reference" "R4459"
			(at 0 0 0)
			(layer "F.SilkS")
			(hide yes)
			(effects
				(font
					(size 1.27 1.27)
				)
			)
		)
		(property "Value" ""
			(at 0 0 0)
			(layer "F.Fab")
			(effects
				(font
					(size 1.27 1.27)
				)
			)
		)
		(duplicate_pad_numbers_are_jumpers no)
		(fp_line
			(start -0.7874 -0.4064)
			(end 0.7874 -0.4064)
			(stroke
				(width 0.1524)
				(type default)
			)
			(layer "F.SilkS")
		)
		(fp_line
			(start -0.7874 0.4064)
			(end -0.7874 -0.4064)
			(stroke
				(width 0.1524)
				(type default)
			)
			(layer "F.SilkS")
		)
		(fp_line
			(start 0.7874 -0.4064)
			(end 0.7874 0.4064)
			(stroke
				(width 0.1524)
				(type default)
			)
			(layer "F.SilkS")
		)
		(fp_line
			(start 0.7874 0.4064)
			(end -0.7874 0.4064)
			(stroke
				(width 0.1524)
				(type default)
			)
			(layer "F.SilkS")
		)
		(fp_line
			(start -0.67945 -0.305054)
			(end -0.12065 -0.305054)
			(stroke
				(width 0.1)
				(type default)
			)
			(layer "F.Fab")
		)
		(fp_line
			(start -0.67945 0.3048)
			(end -0.67945 -0.305054)
			(stroke
				(width 0.1)
				(type default)
			)
			(layer "F.Fab")
		)
		(fp_line
			(start -0.12065 -0.305054)
			(end -0.12065 -0.2794)
			(stroke
				(width 0.1)
				(type default)
			)
			(layer "F.Fab")
		)
		(fp_line
			(start -0.12065 -0.2794)
			(end 0.12065 -0.2794)
			(stroke
				(width 0.1)
				(type default)
			)
			(layer "F.Fab")
		)
		(fp_line
			(start -0.12065 0.2794)
			(end -0.12065 0.3048)
			(stroke
				(width 0.1)
				(type default)
			)
			(layer "F.Fab")
		)
		(fp_line
			(start -0.12065 0.3048)
			(end -0.67945 0.3048)
			(stroke
				(width 0.1)
				(type default)
			)
			(layer "F.Fab")
		)
		(fp_line
			(start 0.120396 0.2794)
			(end -0.12065 0.2794)
			(stroke
				(width 0.1)
				(type default)
			)
			(layer "F.Fab")
		)
		(fp_line
			(start 0.120396 0.3048)
			(end 0.120396 0.2794)
			(stroke
				(width 0.1)
				(type default)
			)
			(layer "F.Fab")
		)
		(fp_line
			(start 0.12065 -0.3048)
			(end 0.67945 -0.3048)
			(stroke
				(width 0.1)
				(type default)
			)
			(layer "F.Fab")
		)
		(fp_line
			(start 0.12065 -0.2794)
			(end 0.12065 -0.3048)
			(stroke
				(width 0.1)
				(type default)
			)
			(layer "F.Fab")
		)
		(fp_line
			(start 0.67945 -0.3048)
			(end 0.67945 0.3048)
			(stroke
				(width 0.1)
				(type default)
			)
			(layer "F.Fab")
		)
		(fp_line
			(start 0.67945 0.3048)
			(end 0.120396 0.3048)
			(stroke
				(width 0.1)
				(type default)
			)
			(layer "F.Fab")
		)
		(pad "1" smd circle
			(at -0.40005 0)
			(size 0 0)
			(layers "F.Cu" "F.Mask" "F.Paste")
			(net "PWRGD_P12V_SSD4")
		)
		(pad "2" smd circle
			(at 0.40005 0)
			(size 0 0)
			(layers "F.Cu" "F.Mask" "F.Paste")
			(net "PWRGD_P12V_SSD4_R")
		)
	)
	(footprint ""
		(layer "F.Cu")
		(at 78.267814 -52.035456 180)
		(property "Reference" "R865"
			(at 0 0 180)
			(layer "F.SilkS")
			(hide yes)
			(effects
				(font
					(size 1.27 1.27)
				)
			)
		)
		(property "Value" ""
			(at 0 0 180)
			(layer "F.Fab")
			(effects
				(font
					(size 1.27 1.27)
				)
			)
		)
		(duplicate_pad_numbers_are_jumpers no)
		(fp_line
			(start 0.7874 0.4064)
			(end -0.7874 0.4064)
			(stroke
				(width 0.1524)
				(type default)
			)
			(layer "F.SilkS")
		)
		(fp_line
			(start 0.7874 -0.4064)
			(end 0.7874 0.4064)
			(stroke
				(width 0.1524)
				(type default)
			)
			(layer "F.SilkS")
		)
		(fp_line
			(start -0.7874 0.4064)
			(end -0.7874 -0.4064)
			(stroke
				(width 0.1524)
				(type default)
			)
			(layer "F.SilkS")
		)
		(fp_line
			(start -0.7874 -0.4064)
			(end 0.7874 -0.4064)
			(stroke
				(width 0.1524)
				(type default)
			)
			(layer "F.SilkS")
		)
		(fp_line
			(start 0.67945 0.3048)
			(end 0.120396 0.3048)
			(stroke
				(width 0.1)
				(type default)
			)
			(layer "F.Fab")
		)
		(fp_line
			(start 0.67945 -0.3048)
			(end 0.67945 0.3048)
			(stroke
				(width 0.1)
				(type default)
			)
			(layer "F.Fab")
		)
		(fp_line
			(start 0.12065 -0.2794)
			(end 0.12065 -0.3048)
			(stroke
				(width 0.1)
				(type default)
			)
			(layer "F.Fab")
		)
		(fp_line
			(start 0.12065 -0.3048)
			(end 0.67945 -0.3048)
			(stroke
				(width 0.1)
				(type default)
			)
			(layer "F.Fab")
		)
		(fp_line
			(start 0.120396 0.3048)
			(end 0.120396 0.2794)
			(stroke
				(width 0.1)
				(type default)
			)
			(layer "F.Fab")
		)
		(fp_line
			(start 0.120396 0.2794)
			(end -0.12065 0.2794)
			(stroke
				(width 0.1)
				(type default)
			)
			(layer "F.Fab")
		)
		(fp_line
			(start -0.12065 0.3048)
			(end -0.67945 0.3048)
			(stroke
				(width 0.1)
				(type default)
			)
			(layer "F.Fab")
		)
		(fp_line
			(start -0.12065 0.2794)
			(end -0.12065 0.3048)
			(stroke
				(width 0.1)
				(type default)
			)
			(layer "F.Fab")
		)
		(fp_line
			(start -0.12065 -0.2794)
			(end 0.12065 -0.2794)
			(stroke
				(width 0.1)
				(type default)
			)
			(layer "F.Fab")
		)
		(fp_line
			(start -0.12065 -0.305054)
			(end -0.12065 -0.2794)
			(stroke
				(width 0.1)
				(type default)
			)
			(layer "F.Fab")
		)
		(fp_line
			(start -0.67945 0.3048)
			(end -0.67945 -0.305054)
			(stroke
				(width 0.1)
				(type default)
			)
			(layer "F.Fab")
		)
		(fp_line
			(start -0.67945 -0.305054)
			(end -0.12065 -0.305054)
			(stroke
				(width 0.1)
				(type default)
			)
			(layer "F.Fab")
		)
		(pad "1" smd circle
			(at -0.40005 0 180)
			(size 0 0)
			(layers "F.Cu" "F.Mask" "F.Paste")
			(net "P3V3_AUX")
		)
		(pad "2" smd circle
			(at 0.40005 0 180)
			(size 0 0)
			(layers "F.Cu" "F.Mask" "F.Paste")
			(net "PWRGD_P12V_SSD2")
		)
	)
	(footprint ""
		(layer "F.Cu")
		(at 148.809202 -27.04973 180)
		(property "Reference" "C2768"
			(at 0 0 180)
			(layer "F.SilkS")
			(hide yes)
			(effects
				(font
					(size 1.27 1.27)
				)
			)
		)
		(property "Value" ""
			(at 0 0 180)
			(layer "F.Fab")
			(effects
				(font
					(size 1.27 1.27)
				)
			)
		)
		(duplicate_pad_numbers_are_jumpers no)
		(fp_line
			(start 0.7874 0.4064)
			(end -0.7874 0.4064)
			(stroke
				(width 0.1524)
				(type default)
			)
			(layer "F.SilkS")
		)
		(fp_line
			(start 0.7874 -0.4064)
			(end 0.7874 0.4064)
			(stroke
				(width 0.1524)
				(type default)
			)
			(layer "F.SilkS")
		)
		(fp_line
			(start -0.7874 0.4064)
			(end -0.7874 -0.4064)
			(stroke
				(width 0.1524)
				(type default)
			)
			(layer "F.SilkS")
		)
		(fp_line
			(start -0.7874 -0.4064)
			(end 0.7874 -0.4064)
			(stroke
				(width 0.1524)
				(type default)
			)
			(layer "F.SilkS")
		)
		(fp_line
			(start 0.67945 0.3048)
			(end 0.120396 0.3048)
			(stroke
				(width 0.1)
				(type default)
			)
			(layer "F.Fab")
		)
		(fp_line
			(start 0.67945 -0.3048)
			(end 0.67945 0.3048)
			(stroke
				(width 0.1)
				(type default)
			)
			(layer "F.Fab")
		)
		(fp_line
			(start 0.12065 -0.2794)
			(end 0.12065 -0.3048)
			(stroke
				(width 0.1)
				(type default)
			)
			(layer "F.Fab")
		)
		(fp_line
			(start 0.12065 -0.3048)
			(end 0.67945 -0.3048)
			(stroke
				(width 0.1)
				(type default)
			)
			(layer "F.Fab")
		)
		(fp_line
			(start 0.120396 0.3048)
			(end 0.120396 0.2794)
			(stroke
				(width 0.1)
				(type default)
			)
			(layer "F.Fab")
		)
		(fp_line
			(start 0.120396 0.2794)
			(end -0.12065 0.2794)
			(stroke
				(width 0.1)
				(type default)
			)
			(layer "F.Fab")
		)
		(fp_line
			(start -0.12065 0.3048)
			(end -0.67945 0.3048)
			(stroke
				(width 0.1)
				(type default)
			)
			(layer "F.Fab")
		)
		(fp_line
			(start -0.12065 0.2794)
			(end -0.12065 0.3048)
			(stroke
				(width 0.1)
				(type default)
			)
			(layer "F.Fab")
		)
		(fp_line
			(start -0.12065 -0.2794)
			(end 0.12065 -0.2794)
			(stroke
				(width 0.1)
				(type default)
			)
			(layer "F.Fab")
		)
		(fp_line
			(start -0.12065 -0.305054)
			(end -0.12065 -0.2794)
			(stroke
				(width 0.1)
				(type default)
			)
			(layer "F.Fab")
		)
		(fp_line
			(start -0.67945 0.3048)
			(end -0.67945 -0.305054)
			(stroke
				(width 0.1)
				(type default)
			)
			(layer "F.Fab")
		)
		(fp_line
			(start -0.67945 -0.305054)
			(end -0.12065 -0.305054)
			(stroke
				(width 0.1)
				(type default)
			)
			(layer "F.Fab")
		)
		(pad "1" smd circle
			(at -0.40005 0 180)
			(size 0 0)
			(layers "F.Cu" "F.Mask" "F.Paste")
			(net "PRSNT_SSD5_R_N")
		)
		(pad "2" smd circle
			(at 0.40005 0 180)
			(size 0 0)
			(layers "F.Cu" "F.Mask" "F.Paste")
			(net "GND")
		)
	)
	(footprint ""
		(layer "F.Cu")
		(at 196.119242 -123.184666 180)
		(property "Reference" "C238"
			(at 0 0 180)
			(layer "F.SilkS")
			(hide yes)
			(effects
				(font
					(size 1.27 1.27)
				)
			)
		)
		(property "Value" ""
			(at 0 0 180)
			(layer "F.Fab")
			(effects
				(font
					(size 1.27 1.27)
				)
			)
		)
		(duplicate_pad_numbers_are_jumpers no)
		(fp_line
			(start 0.299974 0.150114)
			(end -0.299974 0.150114)
			(stroke
				(width 0.1)
				(type default)
			)
			(layer "F.Fab")
		)
		(fp_line
			(start 0.299974 -0.150114)
			(end 0.299974 0.150114)
			(stroke
				(width 0.1)
				(type default)
			)
			(layer "F.Fab")
		)
		(fp_line
			(start -0.299974 0.150114)
			(end -0.299974 -0.150114)
			(stroke
				(width 0.1)
				(type default)
			)
			(layer "F.Fab")
		)
		(fp_line
			(start -0.299974 -0.150114)
			(end 0.299974 -0.150114)
			(stroke
				(width 0.1)
				(type default)
			)
			(layer "F.Fab")
		)
		(pad "1" smd rect
			(at -0.2667 0 180)
			(size 0.3048 0.381)
			(layers "F.Cu" "F.Mask" "F.Paste")
			(net "P5E_PEX1_STN0_TX_DP<2>")
		)
		(pad "2" smd rect
			(at 0.2667 0 180)
			(size 0.3048 0.381)
			(layers "F.Cu" "F.Mask" "F.Paste")
			(net "P5E_PEX1_STN0_TX_C_DP<2>")
		)
	)
	(footprint ""
		(layer "F.Cu")
		(at 372.07698 -343.952322 90)
		(property "Reference" "C763"
			(at 0 0 90)
			(layer "F.SilkS")
			(hide yes)
			(effects
				(font
					(size 1.27 1.27)
				)
			)
		)
		(property "Value" ""
			(at 0 0 90)
			(layer "F.Fab")
			(effects
				(font
					(size 1.27 1.27)
				)
			)
		)
		(duplicate_pad_numbers_are_jumpers no)
		(fp_line
			(start 0.299974 -0.150114)
			(end 0.299974 0.150114)
			(stroke
				(width 0.1)
				(type default)
			)
			(layer "F.Fab")
		)
		(fp_line
			(start -0.299974 -0.150114)
			(end 0.299974 -0.150114)
			(stroke
				(width 0.1)
				(type default)
			)
			(layer "F.Fab")
		)
		(fp_line
			(start 0.299974 0.150114)
			(end -0.299974 0.150114)
			(stroke
				(width 0.1)
				(type default)
			)
			(layer "F.Fab")
		)
		(fp_line
			(start -0.299974 0.150114)
			(end -0.299974 -0.150114)
			(stroke
				(width 0.1)
				(type default)
			)
			(layer "F.Fab")
		)
		(pad "1" smd rect
			(at -0.2667 0 90)
			(size 0.3048 0.381)
			(layers "F.Cu" "F.Mask" "F.Paste")
			(net "P5E_PEX3_STN6_TX_DN<111>")
		)
		(pad "2" smd rect
			(at 0.2667 0 90)
			(size 0.3048 0.381)
			(layers "F.Cu" "F.Mask" "F.Paste")
			(net "P5E_PEX3_STN6_TX_C_DN<111>")
		)
	)
	(footprint ""
		(layer "F.Cu")
		(at 154.707844 -160.380934)
		(property "Reference" "R125"
			(at 0 0 0)
			(layer "F.SilkS")
			(hide yes)
			(effects
				(font
					(size 1.27 1.27)
				)
			)
		)
		(property "Value" ""
			(at 0 0 0)
			(layer "F.Fab")
			(effects
				(font
					(size 1.27 1.27)
				)
			)
		)
		(duplicate_pad_numbers_are_jumpers no)
		(fp_line
			(start -0.7874 -0.4064)
			(end 0.7874 -0.4064)
			(stroke
				(width 0.1524)
				(type default)
			)
			(layer "F.SilkS")
		)
		(fp_line
			(start -0.7874 0.4064)
			(end -0.7874 -0.4064)
			(stroke
				(width 0.1524)
				(type default)
			)
			(layer "F.SilkS")
		)
		(fp_line
			(start 0.7874 -0.4064)
			(end 0.7874 0.4064)
			(stroke
				(width 0.1524)
				(type default)
			)
			(layer "F.SilkS")
		)
		(fp_line
			(start 0.7874 0.4064)
			(end -0.7874 0.4064)
			(stroke
				(width 0.1524)
				(type default)
			)
			(layer "F.SilkS")
		)
		(fp_line
			(start -0.67945 -0.305054)
			(end -0.12065 -0.305054)
			(stroke
				(width 0.1)
				(type default)
			)
			(layer "F.Fab")
		)
		(fp_line
			(start -0.67945 0.3048)
			(end -0.67945 -0.305054)
			(stroke
				(width 0.1)
				(type default)
			)
			(layer "F.Fab")
		)
		(fp_line
			(start -0.12065 -0.305054)
			(end -0.12065 -0.2794)
			(stroke
				(width 0.1)
				(type default)
			)
			(layer "F.Fab")
		)
		(fp_line
			(start -0.12065 -0.2794)
			(end 0.12065 -0.2794)
			(stroke
				(width 0.1)
				(type default)
			)
			(layer "F.Fab")
		)
		(fp_line
			(start -0.12065 0.2794)
			(end -0.12065 0.3048)
			(stroke
				(width 0.1)
				(type default)
			)
			(layer "F.Fab")
		)
		(fp_line
			(start -0.12065 0.3048)
			(end -0.67945 0.3048)
			(stroke
				(width 0.1)
				(type default)
			)
			(layer "F.Fab")
		)
		(fp_line
			(start 0.120396 0.2794)
			(end -0.12065 0.2794)
			(stroke
				(width 0.1)
				(type default)
			)
			(layer "F.Fab")
		)
		(fp_line
			(start 0.120396 0.3048)
			(end 0.120396 0.2794)
			(stroke
				(width 0.1)
				(type default)
			)
			(layer "F.Fab")
		)
		(fp_line
			(start 0.12065 -0.3048)
			(end 0.67945 -0.3048)
			(stroke
				(width 0.1)
				(type default)
			)
			(layer "F.Fab")
		)
		(fp_line
			(start 0.12065 -0.2794)
			(end 0.12065 -0.3048)
			(stroke
				(width 0.1)
				(type default)
			)
			(layer "F.Fab")
		)
		(fp_line
			(start 0.67945 -0.3048)
			(end 0.67945 0.3048)
			(stroke
				(width 0.1)
				(type default)
			)
			(layer "F.Fab")
		)
		(fp_line
			(start 0.67945 0.3048)
			(end 0.120396 0.3048)
			(stroke
				(width 0.1)
				(type default)
			)
			(layer "F.Fab")
		)
		(pad "1" smd circle
			(at -0.40005 0)
			(size 0 0)
			(layers "F.Cu" "F.Mask" "F.Paste")
			(net "NIC2_MAIN_PWR_EN")
		)
		(pad "2" smd circle
			(at 0.40005 0)
			(size 0 0)
			(layers "F.Cu" "F.Mask" "F.Paste")
			(net "GND")
		)
	)
	(footprint ""
		(layer "F.Cu")
		(at 35.518344 -250.070874 -90)
		(property "Reference" "R1166"
			(at 0 0 270)
			(layer "F.SilkS")
			(hide yes)
			(effects
				(font
					(size 1.27 1.27)
				)
			)
		)
		(property "Value" ""
			(at 0 0 270)
			(layer "F.Fab")
			(effects
				(font
					(size 1.27 1.27)
				)
			)
		)
		(duplicate_pad_numbers_are_jumpers no)
		(fp_line
			(start -0.7874 0.4064)
			(end -0.7874 -0.4064)
			(stroke
				(width 0.1524)
				(type default)
			)
			(layer "F.SilkS")
		)
		(fp_line
			(start 0.7874 0.4064)
			(end -0.7874 0.4064)
			(stroke
				(width 0.1524)
				(type default)
			)
			(layer "F.SilkS")
		)
		(fp_line
			(start -0.7874 -0.4064)
			(end 0.7874 -0.4064)
			(stroke
				(width 0.1524)
				(type default)
			)
			(layer "F.SilkS")
		)
		(fp_line
			(start 0.7874 -0.4064)
			(end 0.7874 0.4064)
			(stroke
				(width 0.1524)
				(type default)
			)
			(layer "F.SilkS")
		)
		(fp_line
			(start -0.67945 0.3048)
			(end -0.67945 -0.305054)
			(stroke
				(width 0.1)
				(type default)
			)
			(layer "F.Fab")
		)
		(fp_line
			(start -0.12065 0.3048)
			(end -0.67945 0.3048)
			(stroke
				(width 0.1)
				(type default)
			)
			(layer "F.Fab")
		)
		(fp_line
			(start 0.120396 0.3048)
			(end 0.120396 0.2794)
			(stroke
				(width 0.1)
				(type default)
			)
			(layer "F.Fab")
		)
		(fp_line
			(start 0.67945 0.3048)
			(end 0.120396 0.3048)
			(stroke
				(width 0.1)
				(type default)
			)
			(layer "F.Fab")
		)
		(fp_line
			(start -0.12065 0.2794)
			(end -0.12065 0.3048)
			(stroke
				(width 0.1)
				(type default)
			)
			(layer "F.Fab")
		)
		(fp_line
			(start 0.120396 0.2794)
			(end -0.12065 0.2794)
			(stroke
				(width 0.1)
				(type default)
			)
			(layer "F.Fab")
		)
		(fp_line
			(start -0.12065 -0.2794)
			(end 0.12065 -0.2794)
			(stroke
				(width 0.1)
				(type default)
			)
			(layer "F.Fab")
		)
		(fp_line
			(start 0.12065 -0.2794)
			(end 0.12065 -0.3048)
			(stroke
				(width 0.1)
				(type default)
			)
			(layer "F.Fab")
		)
		(fp_line
			(start 0.12065 -0.3048)
			(end 0.67945 -0.3048)
			(stroke
				(width 0.1)
				(type default)
			)
			(layer "F.Fab")
		)
		(fp_line
			(start 0.67945 -0.3048)
			(end 0.67945 0.3048)
			(stroke
				(width 0.1)
				(type default)
			)
			(layer "F.Fab")
		)
		(fp_line
			(start -0.67945 -0.305054)
			(end -0.12065 -0.305054)
			(stroke
				(width 0.1)
				(type default)
			)
			(layer "F.Fab")
		)
		(fp_line
			(start -0.12065 -0.305054)
			(end -0.12065 -0.2794)
			(stroke
				(width 0.1)
				(type default)
			)
			(layer "F.Fab")
		)
		(pad "1" smd circle
			(at -0.40005 0 270)
			(size 0 0)
			(layers "F.Cu" "F.Mask" "F.Paste")
			(net "PEX0_MODE_SEL12")
		)
		(pad "2" smd circle
			(at 0.40005 0 270)
			(size 0 0)
			(layers "F.Cu" "F.Mask" "F.Paste")
			(net "P1V8_PEX")
		)
	)
	(footprint ""
		(layer "F.Cu")
		(at 333.045816 -46.4439 180)
		(property "Reference" "U74"
			(at 0.356616 -2.40157 0)
			(unlocked yes)
			(layer "F.SilkS")
			(effects
				(font
					(size 0.7874 0.5842)
					(thickness 0.1524)
				)
			)
		)
		(property "Value" ""
			(at 0 0 180)
			(layer "F.Fab")
			(effects
				(font
					(size 1.27 1.27)
				)
			)
		)
		(duplicate_pad_numbers_are_jumpers no)
		(fp_line
			(start 1.500124 1.500124)
			(end 1.004062 1.500124)
			(stroke
				(width 0.1524)
				(type default)
			)
			(layer "F.SilkS")
		)
		(fp_line
			(start 1.500124 1.004062)
			(end 1.500124 1.500124)
			(stroke
				(width 0.1524)
				(type default)
			)
			(layer "F.SilkS")
		)
		(fp_line
			(start 1.500124 -1.500124)
			(end 1.500124 -1.004062)
			(stroke
				(width 0.1524)
				(type default)
			)
			(layer "F.SilkS")
		)
		(fp_line
			(start 1.004062 -1.500124)
			(end 1.500124 -1.500124)
			(stroke
				(width 0.1524)
				(type default)
			)
			(layer "F.SilkS")
		)
		(fp_line
			(start -1.004062 1.500124)
			(end -1.500124 1.500124)
			(stroke
				(width 0.1524)
				(type default)
			)
			(layer "F.SilkS")
		)
		(fp_line
			(start -1.500124 1.500124)
			(end -1.500124 1.004062)
			(stroke
				(width 0.1524)
				(type default)
			)
			(layer "F.SilkS")
		)
		(fp_line
			(start -1.500124 -1.004062)
			(end -1.500124 -1.500124)
			(stroke
				(width 0.1524)
				(type default)
			)
			(layer "F.SilkS")
		)
		(fp_line
			(start -1.500124 -1.500124)
			(end -1.004062 -1.500124)
			(stroke
				(width 0.1524)
				(type default)
			)
			(layer "F.SilkS")
		)
		(fp_poly
			(pts
				(xy -1.926844 -2.242058) (xy -2.645156 -1.523492) (xy -1.567688 -1.164336)
			)
			(stroke
				(width 0)
				(type default)
			)
			(fill yes)
			(layer "F.SilkS")
		)
		(fp_line
			(start 1.500124 1.500124)
			(end -1.500124 1.500124)
			(stroke
				(width 0.1)
				(type default)
			)
			(layer "F.Fab")
		)
		(fp_line
			(start 1.500124 -1.500124)
			(end 1.500124 1.500124)
			(stroke
				(width 0.1)
				(type default)
			)
			(layer "F.Fab")
		)
		(fp_line
			(start -1.500124 1.500124)
			(end -1.500124 -1.500124)
			(stroke
				(width 0.1)
				(type default)
			)
			(layer "F.Fab")
		)
		(fp_line
			(start -1.500124 -1.500124)
			(end 1.500124 -1.500124)
			(stroke
				(width 0.1)
				(type default)
			)
			(layer "F.Fab")
		)
		(fp_poly
			(pts
				(xy -2.847848 -1.258062) (xy -2.847848 -0.242062) (xy -1.831848 -0.750062)
			)
			(stroke
				(width 0)
				(type default)
			)
			(fill yes)
			(layer "F.Fab")
		)
		(pad "1" smd rect
			(at -1.400048 -0.750062 90)
			(size 0.2286 0.6096)
			(layers "F.Cu" "F.Mask" "F.Paste")
			(net "SSD11_ADC_A1")
		)
		(pad "2" smd rect
			(at -1.400048 -0.249936 90)
			(size 0.2286 0.6096)
			(layers "F.Cu" "F.Mask" "F.Paste")
			(net "SSD11_ADC_A0")
		)
		(pad "3" smd rect
			(at -1.400048 0.249936 90)
			(size 0.2286 0.6096)
			(layers "F.Cu" "F.Mask" "F.Paste")
			(net "SSD11_ADC_ALERT_N")
		)
		(pad "4" smd rect
			(at -1.400048 0.750062 90)
			(size 0.2286 0.6096)
			(layers "F.Cu" "F.Mask" "F.Paste")
			(net "SMB_SSD11_ADC_SDA")
		)
		(pad "5" smd rect
			(at -0.750062 1.400048 180)
			(size 0.2286 0.6096)
			(layers "F.Cu" "F.Mask" "F.Paste")
			(net "SMB_SSD11_ADC_SCL")
		)
		(pad "6" smd rect
			(at -0.249936 1.400048 180)
			(size 0.2286 0.6096)
			(layers "F.Cu" "F.Mask" "F.Paste")
			(net "Net_8696")
		)
		(pad "7" smd rect
			(at 0.249936 1.400048 180)
			(size 0.2286 0.6096)
			(layers "F.Cu" "F.Mask" "F.Paste")
			(net "Net_8695")
		)
		(pad "8" smd rect
			(at 0.750062 1.400048 180)
			(size 0.2286 0.6096)
			(layers "F.Cu" "F.Mask" "F.Paste")
			(net "Net_8694")
		)
		(pad "9" smd rect
			(at 1.400048 0.750062 90)
			(size 0.2286 0.6096)
			(layers "F.Cu" "F.Mask" "F.Paste")
			(net "P3V3_AUX")
		)
		(pad "10" smd rect
			(at 1.400048 0.249936 90)
			(size 0.2286 0.6096)
			(layers "F.Cu" "F.Mask" "F.Paste")
			(net "GND")
		)
		(pad "11" smd rect
			(at 1.400048 -0.249936 90)
			(size 0.2286 0.6096)
			(layers "F.Cu" "F.Mask" "F.Paste")
			(net "P12V_SSD11_R")
		)
		(pad "12" smd rect
			(at 1.400048 -0.750062 90)
			(size 0.2286 0.6096)
			(layers "F.Cu" "F.Mask" "F.Paste")
			(net "P12V_SSD11_VIN_N")
		)
		(pad "13" smd rect
			(at 0.750062 -1.400048 180)
			(size 0.2286 0.6096)
			(layers "F.Cu" "F.Mask" "F.Paste")
			(net "P12V_SSD11_VIN_P")
		)
		(pad "14" smd rect
			(at 0.249936 -1.400048 180)
			(size 0.2286 0.6096)
			(layers "F.Cu" "F.Mask" "F.Paste")
			(net "Net_8693")
		)
		(pad "15" smd rect
			(at -0.249936 -1.400048 180)
			(size 0.2286 0.6096)
			(layers "F.Cu" "F.Mask" "F.Paste")
			(net "Net_8692")
		)
		(pad "16" smd rect
			(at -0.750062 -1.400048 180)
			(size 0.2286 0.6096)
			(layers "F.Cu" "F.Mask" "F.Paste")
			(net "Net_8691")
		)
		(pad "TH" smd rect
			(at 0 0 180)
			(size 1.7018 1.7018)
			(layers "F.Cu" "F.Mask" "F.Paste")
			(net "GND")
		)
		(zone
			(layer "F.Cu")
			(hatch none 0.5)
			(connect_pads
				(clearance 0)
			)
			(min_thickness 0.25)
			(keepout
				(tracks not_allowed)
				(vias allowed)
				(pads allowed)
				(copperpour not_allowed)
				(footprints allowed)
			)
			(placement
				(enabled no)
				(sheetname "")
			)
			(fill
				(thermal_gap 0.5)
				(thermal_bridge_width 0.5)
				(island_removal_mode 0)
			)
			(polygon
				(pts
					(xy 334.090264 -46.4185) (xy 334.090264 -45.399452) (xy 332.001368 -45.399452) (xy 332.001368 -47.488348)
					(xy 334.090264 -47.488348) (xy 334.090264 -46.4439) (xy 333.947516 -46.4439) (xy 333.947516 -47.3456)
					(xy 332.144116 -47.3456) (xy 332.144116 -45.5422) (xy 333.947516 -45.5422) (xy 333.947516 -46.4185)
				)
			)
		)
	)
	(footprint ""
		(layer "F.Cu")
		(at 143.490442 -252.356874 -90)
		(property "Reference" "R1294"
			(at 0 0 270)
			(layer "F.SilkS")
			(hide yes)
			(effects
				(font
					(size 1.27 1.27)
				)
			)
		)
		(property "Value" ""
			(at 0 0 270)
			(layer "F.Fab")
			(effects
				(font
					(size 1.27 1.27)
				)
			)
		)
		(duplicate_pad_numbers_are_jumpers no)
		(fp_line
			(start -0.7874 0.4064)
			(end -0.7874 -0.4064)
			(stroke
				(width 0.1524)
				(type default)
			)
			(layer "F.SilkS")
		)
		(fp_line
			(start 0.7874 0.4064)
			(end -0.7874 0.4064)
			(stroke
				(width 0.1524)
				(type default)
			)
			(layer "F.SilkS")
		)
		(fp_line
			(start -0.7874 -0.4064)
			(end 0.7874 -0.4064)
			(stroke
				(width 0.1524)
				(type default)
			)
			(layer "F.SilkS")
		)
		(fp_line
			(start 0.7874 -0.4064)
			(end 0.7874 0.4064)
			(stroke
				(width 0.1524)
				(type default)
			)
			(layer "F.SilkS")
		)
		(fp_line
			(start -0.67945 0.3048)
			(end -0.67945 -0.305054)
			(stroke
				(width 0.1)
				(type default)
			)
			(layer "F.Fab")
		)
		(fp_line
			(start -0.12065 0.3048)
			(end -0.67945 0.3048)
			(stroke
				(width 0.1)
				(type default)
			)
			(layer "F.Fab")
		)
		(fp_line
			(start 0.120396 0.3048)
			(end 0.120396 0.2794)
			(stroke
				(width 0.1)
				(type default)
			)
			(layer "F.Fab")
		)
		(fp_line
			(start 0.67945 0.3048)
			(end 0.120396 0.3048)
			(stroke
				(width 0.1)
				(type default)
			)
			(layer "F.Fab")
		)
		(fp_line
			(start -0.12065 0.2794)
			(end -0.12065 0.3048)
			(stroke
				(width 0.1)
				(type default)
			)
			(layer "F.Fab")
		)
		(fp_line
			(start 0.120396 0.2794)
			(end -0.12065 0.2794)
			(stroke
				(width 0.1)
				(type default)
			)
			(layer "F.Fab")
		)
		(fp_line
			(start -0.12065 -0.2794)
			(end 0.12065 -0.2794)
			(stroke
				(width 0.1)
				(type default)
			)
			(layer "F.Fab")
		)
		(fp_line
			(start 0.12065 -0.2794)
			(end 0.12065 -0.3048)
			(stroke
				(width 0.1)
				(type default)
			)
			(layer "F.Fab")
		)
		(fp_line
			(start 0.12065 -0.3048)
			(end 0.67945 -0.3048)
			(stroke
				(width 0.1)
				(type default)
			)
			(layer "F.Fab")
		)
		(fp_line
			(start 0.67945 -0.3048)
			(end 0.67945 0.3048)
			(stroke
				(width 0.1)
				(type default)
			)
			(layer "F.Fab")
		)
		(fp_line
			(start -0.67945 -0.305054)
			(end -0.12065 -0.305054)
			(stroke
				(width 0.1)
				(type default)
			)
			(layer "F.Fab")
		)
		(fp_line
			(start -0.12065 -0.305054)
			(end -0.12065 -0.2794)
			(stroke
				(width 0.1)
				(type default)
			)
			(layer "F.Fab")
		)
		(pad "1" smd circle
			(at -0.40005 0 270)
			(size 0 0)
			(layers "F.Cu" "F.Mask" "F.Paste")
			(net "GND")
		)
		(pad "2" smd circle
			(at 0.40005 0 270)
			(size 0 0)
			(layers "F.Cu" "F.Mask" "F.Paste")
			(net "PEX1_MODE_SEL5")
		)
	)
	(footprint ""
		(layer "F.Cu")
		(at 426.567854 -51.019456)
		(property "Reference" "PC435"
			(at 0 0 0)
			(layer "F.SilkS")
			(hide yes)
			(effects
				(font
					(size 1.27 1.27)
				)
			)
		)
		(property "Value" ""
			(at 0 0 0)
			(layer "F.Fab")
			(effects
				(font
					(size 1.27 1.27)
				)
			)
		)
		(duplicate_pad_numbers_are_jumpers no)
		(fp_line
			(start -0.7874 -0.4064)
			(end 0.7874 -0.4064)
			(stroke
				(width 0.1524)
				(type default)
			)
			(layer "F.SilkS")
		)
		(fp_line
			(start -0.7874 0.4064)
			(end -0.7874 -0.4064)
			(stroke
				(width 0.1524)
				(type default)
			)
			(layer "F.SilkS")
		)
		(fp_line
			(start 0.7874 -0.4064)
			(end 0.7874 0.4064)
			(stroke
				(width 0.1524)
				(type default)
			)
			(layer "F.SilkS")
		)
		(fp_line
			(start 0.7874 0.4064)
			(end -0.7874 0.4064)
			(stroke
				(width 0.1524)
				(type default)
			)
			(layer "F.SilkS")
		)
		(fp_line
			(start -0.67945 -0.305054)
			(end -0.12065 -0.305054)
			(stroke
				(width 0.1)
				(type default)
			)
			(layer "F.Fab")
		)
		(fp_line
			(start -0.67945 0.3048)
			(end -0.67945 -0.305054)
			(stroke
				(width 0.1)
				(type default)
			)
			(layer "F.Fab")
		)
		(fp_line
			(start -0.12065 -0.305054)
			(end -0.12065 -0.2794)
			(stroke
				(width 0.1)
				(type default)
			)
			(layer "F.Fab")
		)
		(fp_line
			(start -0.12065 -0.2794)
			(end 0.12065 -0.2794)
			(stroke
				(width 0.1)
				(type default)
			)
			(layer "F.Fab")
		)
		(fp_line
			(start -0.12065 0.2794)
			(end -0.12065 0.3048)
			(stroke
				(width 0.1)
				(type default)
			)
			(layer "F.Fab")
		)
		(fp_line
			(start -0.12065 0.3048)
			(end -0.67945 0.3048)
			(stroke
				(width 0.1)
				(type default)
			)
			(layer "F.Fab")
		)
		(fp_line
			(start 0.120396 0.2794)
			(end -0.12065 0.2794)
			(stroke
				(width 0.1)
				(type default)
			)
			(layer "F.Fab")
		)
		(fp_line
			(start 0.120396 0.3048)
			(end 0.120396 0.2794)
			(stroke
				(width 0.1)
				(type default)
			)
			(layer "F.Fab")
		)
		(fp_line
			(start 0.12065 -0.3048)
			(end 0.67945 -0.3048)
			(stroke
				(width 0.1)
				(type default)
			)
			(layer "F.Fab")
		)
		(fp_line
			(start 0.12065 -0.2794)
			(end 0.12065 -0.3048)
			(stroke
				(width 0.1)
				(type default)
			)
			(layer "F.Fab")
		)
		(fp_line
			(start 0.67945 -0.3048)
			(end 0.67945 0.3048)
			(stroke
				(width 0.1)
				(type default)
			)
			(layer "F.Fab")
		)
		(fp_line
			(start 0.67945 0.3048)
			(end 0.120396 0.3048)
			(stroke
				(width 0.1)
				(type default)
			)
			(layer "F.Fab")
		)
		(pad "1" smd circle
			(at -0.40005 0)
			(size 0 0)
			(layers "F.Cu" "F.Mask" "F.Paste")
			(net "P12V_SSD14_SS")
		)
		(pad "2" smd circle
			(at 0.40005 0)
			(size 0 0)
			(layers "F.Cu" "F.Mask" "F.Paste")
			(net "GND")
		)
	)
	(footprint ""
		(layer "F.Cu")
		(at 2.040128 -395.448282 180)
		(property "Reference" "R6740"
			(at 0 0 180)
			(layer "F.SilkS")
			(hide yes)
			(effects
				(font
					(size 1.27 1.27)
				)
			)
		)
		(property "Value" ""
			(at 0 0 180)
			(layer "F.Fab")
			(effects
				(font
					(size 1.27 1.27)
				)
			)
		)
		(duplicate_pad_numbers_are_jumpers no)
		(fp_line
			(start 0.7874 0.4064)
			(end -0.7874 0.4064)
			(stroke
				(width 0.1524)
				(type default)
			)
			(layer "F.SilkS")
		)
		(fp_line
			(start 0.7874 -0.4064)
			(end 0.7874 0.4064)
			(stroke
				(width 0.1524)
				(type default)
			)
			(layer "F.SilkS")
		)
		(fp_line
			(start -0.7874 0.4064)
			(end -0.7874 -0.4064)
			(stroke
				(width 0.1524)
				(type default)
			)
			(layer "F.SilkS")
		)
		(fp_line
			(start -0.7874 -0.4064)
			(end 0.7874 -0.4064)
			(stroke
				(width 0.1524)
				(type default)
			)
			(layer "F.SilkS")
		)
		(fp_line
			(start 0.67945 0.3048)
			(end 0.120396 0.3048)
			(stroke
				(width 0.1)
				(type default)
			)
			(layer "F.Fab")
		)
		(fp_line
			(start 0.67945 -0.3048)
			(end 0.67945 0.3048)
			(stroke
				(width 0.1)
				(type default)
			)
			(layer "F.Fab")
		)
		(fp_line
			(start 0.12065 -0.2794)
			(end 0.12065 -0.3048)
			(stroke
				(width 0.1)
				(type default)
			)
			(layer "F.Fab")
		)
		(fp_line
			(start 0.12065 -0.3048)
			(end 0.67945 -0.3048)
			(stroke
				(width 0.1)
				(type default)
			)
			(layer "F.Fab")
		)
		(fp_line
			(start 0.120396 0.3048)
			(end 0.120396 0.2794)
			(stroke
				(width 0.1)
				(type default)
			)
			(layer "F.Fab")
		)
		(fp_line
			(start 0.120396 0.2794)
			(end -0.12065 0.2794)
			(stroke
				(width 0.1)
				(type default)
			)
			(layer "F.Fab")
		)
		(fp_line
			(start -0.12065 0.3048)
			(end -0.67945 0.3048)
			(stroke
				(width 0.1)
				(type default)
			)
			(layer "F.Fab")
		)
		(fp_line
			(start -0.12065 0.2794)
			(end -0.12065 0.3048)
			(stroke
				(width 0.1)
				(type default)
			)
			(layer "F.Fab")
		)
		(fp_line
			(start -0.12065 -0.2794)
			(end 0.12065 -0.2794)
			(stroke
				(width 0.1)
				(type default)
			)
			(layer "F.Fab")
		)
		(fp_line
			(start -0.12065 -0.305054)
			(end -0.12065 -0.2794)
			(stroke
				(width 0.1)
				(type default)
			)
			(layer "F.Fab")
		)
		(fp_line
			(start -0.67945 0.3048)
			(end -0.67945 -0.305054)
			(stroke
				(width 0.1)
				(type default)
			)
			(layer "F.Fab")
		)
		(fp_line
			(start -0.67945 -0.305054)
			(end -0.12065 -0.305054)
			(stroke
				(width 0.1)
				(type default)
			)
			(layer "F.Fab")
		)
		(pad "1" smd circle
			(at -0.40005 0 180)
			(size 0 0)
			(layers "F.Cu" "F.Mask" "F.Paste")
			(net "P3V3_USB_8042")
		)
		(pad "2" smd circle
			(at 0.40005 0 180)
			(size 0 0)
			(layers "F.Cu" "F.Mask" "F.Paste")
			(net "BIC_USB_8042_HUB_OVCUR1")
		)
	)
	(footprint ""
		(layer "F.Cu")
		(at 413.293052 -356.244906 90)
		(property "Reference" "C2444"
			(at 0 0 90)
			(layer "F.SilkS")
			(hide yes)
			(effects
				(font
					(size 1.27 1.27)
				)
			)
		)
		(property "Value" ""
			(at 0 0 90)
			(layer "F.Fab")
			(effects
				(font
					(size 1.27 1.27)
				)
			)
		)
		(duplicate_pad_numbers_are_jumpers no)
		(fp_line
			(start 0.299974 -0.150114)
			(end 0.299974 0.150114)
			(stroke
				(width 0.1)
				(type default)
			)
			(layer "F.Fab")
		)
		(fp_line
			(start -0.299974 -0.150114)
			(end 0.299974 -0.150114)
			(stroke
				(width 0.1)
				(type default)
			)
			(layer "F.Fab")
		)
		(fp_line
			(start 0.299974 0.150114)
			(end -0.299974 0.150114)
			(stroke
				(width 0.1)
				(type default)
			)
			(layer "F.Fab")
		)
		(fp_line
			(start -0.299974 0.150114)
			(end -0.299974 -0.150114)
			(stroke
				(width 0.1)
				(type default)
			)
			(layer "F.Fab")
		)
		(pad "1" smd rect
			(at -0.2667 0 90)
			(size 0.3048 0.381)
			(layers "F.Cu" "F.Mask" "F.Paste")
			(net "P5E_PEX3_STN4_TX_DN<77>")
		)
		(pad "2" smd rect
			(at 0.2667 0 90)
			(size 0.3048 0.381)
			(layers "F.Cu" "F.Mask" "F.Paste")
			(net "P5E_PEX3_STN4_TX_C_DN<77>")
		)
	)
	(footprint ""
		(layer "F.Cu")
		(at 338.582 -205.232 -90)
		(property "Reference" "R4126"
			(at 0 0 270)
			(layer "F.SilkS")
			(hide yes)
			(effects
				(font
					(size 1.27 1.27)
				)
			)
		)
		(property "Value" ""
			(at 0 0 270)
			(layer "F.Fab")
			(effects
				(font
					(size 1.27 1.27)
				)
			)
		)
		(duplicate_pad_numbers_are_jumpers no)
		(fp_line
			(start -0.7874 0.4064)
			(end -0.7874 -0.4064)
			(stroke
				(width 0.1524)
				(type default)
			)
			(layer "F.SilkS")
		)
		(fp_line
			(start 0.7874 0.4064)
			(end -0.7874 0.4064)
			(stroke
				(width 0.1524)
				(type default)
			)
			(layer "F.SilkS")
		)
		(fp_line
			(start -0.7874 -0.4064)
			(end 0.7874 -0.4064)
			(stroke
				(width 0.1524)
				(type default)
			)
			(layer "F.SilkS")
		)
		(fp_line
			(start 0.7874 -0.4064)
			(end 0.7874 0.4064)
			(stroke
				(width 0.1524)
				(type default)
			)
			(layer "F.SilkS")
		)
		(fp_line
			(start -0.67945 0.3048)
			(end -0.67945 -0.305054)
			(stroke
				(width 0.1)
				(type default)
			)
			(layer "F.Fab")
		)
		(fp_line
			(start -0.12065 0.3048)
			(end -0.67945 0.3048)
			(stroke
				(width 0.1)
				(type default)
			)
			(layer "F.Fab")
		)
		(fp_line
			(start 0.120396 0.3048)
			(end 0.120396 0.2794)
			(stroke
				(width 0.1)
				(type default)
			)
			(layer "F.Fab")
		)
		(fp_line
			(start 0.67945 0.3048)
			(end 0.120396 0.3048)
			(stroke
				(width 0.1)
				(type default)
			)
			(layer "F.Fab")
		)
		(fp_line
			(start -0.12065 0.2794)
			(end -0.12065 0.3048)
			(stroke
				(width 0.1)
				(type default)
			)
			(layer "F.Fab")
		)
		(fp_line
			(start 0.120396 0.2794)
			(end -0.12065 0.2794)
			(stroke
				(width 0.1)
				(type default)
			)
			(layer "F.Fab")
		)
		(fp_line
			(start -0.12065 -0.2794)
			(end 0.12065 -0.2794)
			(stroke
				(width 0.1)
				(type default)
			)
			(layer "F.Fab")
		)
		(fp_line
			(start 0.12065 -0.2794)
			(end 0.12065 -0.3048)
			(stroke
				(width 0.1)
				(type default)
			)
			(layer "F.Fab")
		)
		(fp_line
			(start 0.12065 -0.3048)
			(end 0.67945 -0.3048)
			(stroke
				(width 0.1)
				(type default)
			)
			(layer "F.Fab")
		)
		(fp_line
			(start 0.67945 -0.3048)
			(end 0.67945 0.3048)
			(stroke
				(width 0.1)
				(type default)
			)
			(layer "F.Fab")
		)
		(fp_line
			(start -0.67945 -0.305054)
			(end -0.12065 -0.305054)
			(stroke
				(width 0.1)
				(type default)
			)
			(layer "F.Fab")
		)
		(fp_line
			(start -0.12065 -0.305054)
			(end -0.12065 -0.2794)
			(stroke
				(width 0.1)
				(type default)
			)
			(layer "F.Fab")
		)
		(pad "1" smd circle
			(at -0.40005 0 270)
			(size 0 0)
			(layers "F.Cu" "F.Mask" "F.Paste")
			(net "SSD10_CLK_EN_N")
		)
		(pad "2" smd circle
			(at 0.40005 0 270)
			(size 0 0)
			(layers "F.Cu" "F.Mask" "F.Paste")
			(net "SSD10_CLK_EN_R_N")
		)
	)
	(footprint ""
		(layer "F.Cu")
		(at 278.473916 -72.766682 90)
		(property "Reference" "PR7077"
			(at 0 0 90)
			(layer "F.SilkS")
			(hide yes)
			(effects
				(font
					(size 1.27 1.27)
				)
			)
		)
		(property "Value" ""
			(at 0 0 90)
			(layer "F.Fab")
			(effects
				(font
					(size 1.27 1.27)
				)
			)
		)
		(duplicate_pad_numbers_are_jumpers no)
		(fp_line
			(start 0.7874 -0.4064)
			(end 0.7874 0.4064)
			(stroke
				(width 0.1524)
				(type default)
			)
			(layer "F.SilkS")
		)
		(fp_line
			(start -0.7874 -0.4064)
			(end 0.7874 -0.4064)
			(stroke
				(width 0.1524)
				(type default)
			)
			(layer "F.SilkS")
		)
		(fp_line
			(start 0.7874 0.4064)
			(end -0.7874 0.4064)
			(stroke
				(width 0.1524)
				(type default)
			)
			(layer "F.SilkS")
		)
		(fp_line
			(start -0.7874 0.4064)
			(end -0.7874 -0.4064)
			(stroke
				(width 0.1524)
				(type default)
			)
			(layer "F.SilkS")
		)
		(fp_line
			(start -0.12065 -0.305054)
			(end -0.12065 -0.2794)
			(stroke
				(width 0.1)
				(type default)
			)
			(layer "F.Fab")
		)
		(fp_line
			(start -0.67945 -0.305054)
			(end -0.12065 -0.305054)
			(stroke
				(width 0.1)
				(type default)
			)
			(layer "F.Fab")
		)
		(fp_line
			(start 0.67945 -0.3048)
			(end 0.67945 0.3048)
			(stroke
				(width 0.1)
				(type default)
			)
			(layer "F.Fab")
		)
		(fp_line
			(start 0.12065 -0.3048)
			(end 0.67945 -0.3048)
			(stroke
				(width 0.1)
				(type default)
			)
			(layer "F.Fab")
		)
		(fp_line
			(start 0.12065 -0.2794)
			(end 0.12065 -0.3048)
			(stroke
				(width 0.1)
				(type default)
			)
			(layer "F.Fab")
		)
		(fp_line
			(start -0.12065 -0.2794)
			(end 0.12065 -0.2794)
			(stroke
				(width 0.1)
				(type default)
			)
			(layer "F.Fab")
		)
		(fp_line
			(start 0.120396 0.2794)
			(end -0.12065 0.2794)
			(stroke
				(width 0.1)
				(type default)
			)
			(layer "F.Fab")
		)
		(fp_line
			(start -0.12065 0.2794)
			(end -0.12065 0.3048)
			(stroke
				(width 0.1)
				(type default)
			)
			(layer "F.Fab")
		)
		(fp_line
			(start 0.67945 0.3048)
			(end 0.120396 0.3048)
			(stroke
				(width 0.1)
				(type default)
			)
			(layer "F.Fab")
		)
		(fp_line
			(start 0.120396 0.3048)
			(end 0.120396 0.2794)
			(stroke
				(width 0.1)
				(type default)
			)
			(layer "F.Fab")
		)
		(fp_line
			(start -0.12065 0.3048)
			(end -0.67945 0.3048)
			(stroke
				(width 0.1)
				(type default)
			)
			(layer "F.Fab")
		)
		(fp_line
			(start -0.67945 0.3048)
			(end -0.67945 -0.305054)
			(stroke
				(width 0.1)
				(type default)
			)
			(layer "F.Fab")
		)
		(pad "1" smd circle
			(at -0.40005 0 90)
			(size 0 0)
			(layers "F.Cu" "F.Mask" "F.Paste")
			(net "P12V_SSD9_CO_MODE")
		)
		(pad "2" smd circle
			(at 0.40005 0 90)
			(size 0 0)
			(layers "F.Cu" "F.Mask" "F.Paste")
			(net "GND")
		)
	)
	(footprint ""
		(layer "F.Cu")
		(at 291.194998 -103.814372 180)
		(property "Reference" "R273"
			(at 0 0 180)
			(layer "F.SilkS")
			(hide yes)
			(effects
				(font
					(size 1.27 1.27)
				)
			)
		)
		(property "Value" ""
			(at 0 0 180)
			(layer "F.Fab")
			(effects
				(font
					(size 1.27 1.27)
				)
			)
		)
		(duplicate_pad_numbers_are_jumpers no)
		(fp_line
			(start 0.7874 0.4064)
			(end -0.7874 0.4064)
			(stroke
				(width 0.1524)
				(type default)
			)
			(layer "F.SilkS")
		)
		(fp_line
			(start 0.7874 -0.4064)
			(end 0.7874 0.4064)
			(stroke
				(width 0.1524)
				(type default)
			)
			(layer "F.SilkS")
		)
		(fp_line
			(start -0.7874 0.4064)
			(end -0.7874 -0.4064)
			(stroke
				(width 0.1524)
				(type default)
			)
			(layer "F.SilkS")
		)
		(fp_line
			(start -0.7874 -0.4064)
			(end 0.7874 -0.4064)
			(stroke
				(width 0.1524)
				(type default)
			)
			(layer "F.SilkS")
		)
		(fp_line
			(start 0.67945 0.3048)
			(end 0.120396 0.3048)
			(stroke
				(width 0.1)
				(type default)
			)
			(layer "F.Fab")
		)
		(fp_line
			(start 0.67945 -0.3048)
			(end 0.67945 0.3048)
			(stroke
				(width 0.1)
				(type default)
			)
			(layer "F.Fab")
		)
		(fp_line
			(start 0.12065 -0.2794)
			(end 0.12065 -0.3048)
			(stroke
				(width 0.1)
				(type default)
			)
			(layer "F.Fab")
		)
		(fp_line
			(start 0.12065 -0.3048)
			(end 0.67945 -0.3048)
			(stroke
				(width 0.1)
				(type default)
			)
			(layer "F.Fab")
		)
		(fp_line
			(start 0.120396 0.3048)
			(end 0.120396 0.2794)
			(stroke
				(width 0.1)
				(type default)
			)
			(layer "F.Fab")
		)
		(fp_line
			(start 0.120396 0.2794)
			(end -0.12065 0.2794)
			(stroke
				(width 0.1)
				(type default)
			)
			(layer "F.Fab")
		)
		(fp_line
			(start -0.12065 0.3048)
			(end -0.67945 0.3048)
			(stroke
				(width 0.1)
				(type default)
			)
			(layer "F.Fab")
		)
		(fp_line
			(start -0.12065 0.2794)
			(end -0.12065 0.3048)
			(stroke
				(width 0.1)
				(type default)
			)
			(layer "F.Fab")
		)
		(fp_line
			(start -0.12065 -0.2794)
			(end 0.12065 -0.2794)
			(stroke
				(width 0.1)
				(type default)
			)
			(layer "F.Fab")
		)
		(fp_line
			(start -0.12065 -0.305054)
			(end -0.12065 -0.2794)
			(stroke
				(width 0.1)
				(type default)
			)
			(layer "F.Fab")
		)
		(fp_line
			(start -0.67945 0.3048)
			(end -0.67945 -0.305054)
			(stroke
				(width 0.1)
				(type default)
			)
			(layer "F.Fab")
		)
		(fp_line
			(start -0.67945 -0.305054)
			(end -0.12065 -0.305054)
			(stroke
				(width 0.1)
				(type default)
			)
			(layer "F.Fab")
		)
		(pad "1" smd circle
			(at -0.40005 0 180)
			(size 0 0)
			(layers "F.Cu" "F.Mask" "F.Paste")
			(net "NCSI_NIC5_TXD0")
		)
		(pad "2" smd circle
			(at 0.40005 0 180)
			(size 0 0)
			(layers "F.Cu" "F.Mask" "F.Paste")
			(net "GND")
		)
	)
	(footprint ""
		(layer "F.Cu")
		(at 173.750224 -50.96383 180)
		(property "Reference" "PC527"
			(at 0 0 180)
			(layer "F.SilkS")
			(hide yes)
			(effects
				(font
					(size 1.27 1.27)
				)
			)
		)
		(property "Value" ""
			(at 0 0 180)
			(layer "F.Fab")
			(effects
				(font
					(size 1.27 1.27)
				)
			)
		)
		(duplicate_pad_numbers_are_jumpers no)
		(fp_line
			(start 1.524 0.762)
			(end -1.524 0.762)
			(stroke
				(width 0.1524)
				(type default)
			)
			(layer "F.SilkS")
		)
		(fp_line
			(start 1.524 -0.762)
			(end 1.524 0.762)
			(stroke
				(width 0.1524)
				(type default)
			)
			(layer "F.SilkS")
		)
		(fp_line
			(start -1.524 0.762)
			(end -1.524 -0.762)
			(stroke
				(width 0.1524)
				(type default)
			)
			(layer "F.SilkS")
		)
		(fp_line
			(start -1.524 -0.762)
			(end 1.524 -0.762)
			(stroke
				(width 0.1524)
				(type default)
			)
			(layer "F.SilkS")
		)
		(fp_line
			(start 1.1049 0.724916)
			(end 1.1049 -0.724916)
			(stroke
				(width 0.1)
				(type default)
			)
			(layer "F.Fab")
		)
		(fp_line
			(start 1.1049 -0.724916)
			(end -1.1049 -0.724916)
			(stroke
				(width 0.1)
				(type default)
			)
			(layer "F.Fab")
		)
		(fp_line
			(start -1.1049 0.724916)
			(end 1.1049 0.724916)
			(stroke
				(width 0.1)
				(type default)
			)
			(layer "F.Fab")
		)
		(fp_line
			(start -1.1049 -0.724916)
			(end -1.1049 0.724916)
			(stroke
				(width 0.1)
				(type default)
			)
			(layer "F.Fab")
		)
		(pad "1" smd rect
			(at -0.889 0)
			(size 1.016 1.27)
			(layers "F.Cu" "F.Mask" "F.Paste")
			(net "P3V3_SSD6")
		)
		(pad "2" smd rect
			(at 0.889 0)
			(size 1.016 1.27)
			(layers "F.Cu" "F.Mask" "F.Paste")
			(net "GND")
		)
	)
	(footprint ""
		(layer "F.Cu")
		(at 197.739 -406.908 90)
		(property "Reference" "Q123"
			(at 0.822706 2.829052 0)
			(unlocked yes)
			(layer "F.SilkS")
			(effects
				(font
					(size 0.7874 0.5842)
					(thickness 0.1524)
				)
			)
		)
		(property "Value" ""
			(at 0 0 90)
			(layer "F.Fab")
			(effects
				(font
					(size 1.27 1.27)
				)
			)
		)
		(duplicate_pad_numbers_are_jumpers no)
		(fp_line
			(start 1.38176 -1.100074)
			(end 0.592074 -1.100074)
			(stroke
				(width 0.1524)
				(type default)
			)
			(layer "F.SilkS")
		)
		(fp_line
			(start 0.592074 -1.100074)
			(end 0 -0.508)
			(stroke
				(width 0.1524)
				(type default)
			)
			(layer "F.SilkS")
		)
		(fp_line
			(start -0.592074 -1.100074)
			(end -1.38176 -1.100074)
			(stroke
				(width 0.1524)
				(type default)
			)
			(layer "F.SilkS")
		)
		(fp_line
			(start -1.38176 -1.100074)
			(end -1.38176 1.100074)
			(stroke
				(width 0.1524)
				(type default)
			)
			(layer "F.SilkS")
		)
		(fp_line
			(start 0 -0.508)
			(end -0.592074 -1.100074)
			(stroke
				(width 0.1524)
				(type default)
			)
			(layer "F.SilkS")
		)
		(fp_line
			(start 1.38176 1.100074)
			(end 1.38176 -1.100074)
			(stroke
				(width 0.1524)
				(type default)
			)
			(layer "F.SilkS")
		)
		(fp_line
			(start -1.38176 1.100074)
			(end 1.38176 1.100074)
			(stroke
				(width 0.1524)
				(type default)
			)
			(layer "F.SilkS")
		)
		(fp_poly
			(pts
				(xy -1.70434 -1.32334) (xy -1.548384 -0.85598) (xy -2.015744 -1.011936)
			)
			(stroke
				(width 0)
				(type default)
			)
			(fill yes)
			(layer "F.SilkS")
		)
		(fp_line
			(start 0.674878 -1.100074)
			(end -0.674878 -1.100074)
			(stroke
				(width 0.1)
				(type default)
			)
			(layer "F.Fab")
		)
		(fp_line
			(start -0.674878 -1.100074)
			(end -0.674878 1.100074)
			(stroke
				(width 0.1)
				(type default)
			)
			(layer "F.Fab")
		)
		(fp_line
			(start 0.674878 1.100074)
			(end 0.674878 -1.100074)
			(stroke
				(width 0.1)
				(type default)
			)
			(layer "F.Fab")
		)
		(fp_line
			(start -0.674878 1.100074)
			(end 0.674878 1.100074)
			(stroke
				(width 0.1)
				(type default)
			)
			(layer "F.Fab")
		)
		(fp_poly
			(pts
				(xy -1.9431 -0.870204) (xy -1.50241 -0.649986) (xy -1.9431 -0.429768)
			)
			(stroke
				(width 0)
				(type default)
			)
			(fill yes)
			(layer "F.Fab")
		)
		(pad "1" smd rect
			(at -0.94996 -0.649986)
			(size 0.4318 0.6096)
			(layers "F.Cu" "F.Mask" "F.Paste")
			(net "GND")
		)
		(pad "2" smd rect
			(at -0.94996 0)
			(size 0.4318 0.6096)
			(layers "F.Cu" "F.Mask" "F.Paste")
			(net "MB_HSC_EN")
		)
		(pad "3" smd rect
			(at -0.94996 0.649986)
			(size 0.4318 0.6096)
			(layers "F.Cu" "F.Mask" "F.Paste")
			(net "MB_HSC_ISO_D2_EN")
		)
		(pad "4" smd rect
			(at 0.94996 0.649986)
			(size 0.4318 0.6096)
			(layers "F.Cu" "F.Mask" "F.Paste")
			(net "GND")
		)
		(pad "5" smd rect
			(at 0.94996 0)
			(size 0.4318 0.6096)
			(layers "F.Cu" "F.Mask" "F.Paste")
			(net "MB_HSC_ISO_D1_EN")
		)
		(pad "6" smd rect
			(at 0.94996 -0.649986)
			(size 0.4318 0.6096)
			(layers "F.Cu" "F.Mask" "F.Paste")
			(net "MB_HSC_ISO_D1_EN")
		)
	)
	(footprint ""
		(layer "F.Cu")
		(at 288.079942 -141.9352 180)
		(property "Reference" "R214"
			(at 0 0 180)
			(layer "F.SilkS")
			(hide yes)
			(effects
				(font
					(size 1.27 1.27)
				)
			)
		)
		(property "Value" ""
			(at 0 0 180)
			(layer "F.Fab")
			(effects
				(font
					(size 1.27 1.27)
				)
			)
		)
		(duplicate_pad_numbers_are_jumpers no)
		(fp_line
			(start 0.7874 0.4064)
			(end -0.7874 0.4064)
			(stroke
				(width 0.1524)
				(type default)
			)
			(layer "F.SilkS")
		)
		(fp_line
			(start 0.7874 -0.4064)
			(end 0.7874 0.4064)
			(stroke
				(width 0.1524)
				(type default)
			)
			(layer "F.SilkS")
		)
		(fp_line
			(start -0.7874 0.4064)
			(end -0.7874 -0.4064)
			(stroke
				(width 0.1524)
				(type default)
			)
			(layer "F.SilkS")
		)
		(fp_line
			(start -0.7874 -0.4064)
			(end 0.7874 -0.4064)
			(stroke
				(width 0.1524)
				(type default)
			)
			(layer "F.SilkS")
		)
		(fp_line
			(start 0.67945 0.3048)
			(end 0.120396 0.3048)
			(stroke
				(width 0.1)
				(type default)
			)
			(layer "F.Fab")
		)
		(fp_line
			(start 0.67945 -0.3048)
			(end 0.67945 0.3048)
			(stroke
				(width 0.1)
				(type default)
			)
			(layer "F.Fab")
		)
		(fp_line
			(start 0.12065 -0.2794)
			(end 0.12065 -0.3048)
			(stroke
				(width 0.1)
				(type default)
			)
			(layer "F.Fab")
		)
		(fp_line
			(start 0.12065 -0.3048)
			(end 0.67945 -0.3048)
			(stroke
				(width 0.1)
				(type default)
			)
			(layer "F.Fab")
		)
		(fp_line
			(start 0.120396 0.3048)
			(end 0.120396 0.2794)
			(stroke
				(width 0.1)
				(type default)
			)
			(layer "F.Fab")
		)
		(fp_line
			(start 0.120396 0.2794)
			(end -0.12065 0.2794)
			(stroke
				(width 0.1)
				(type default)
			)
			(layer "F.Fab")
		)
		(fp_line
			(start -0.12065 0.3048)
			(end -0.67945 0.3048)
			(stroke
				(width 0.1)
				(type default)
			)
			(layer "F.Fab")
		)
		(fp_line
			(start -0.12065 0.2794)
			(end -0.12065 0.3048)
			(stroke
				(width 0.1)
				(type default)
			)
			(layer "F.Fab")
		)
		(fp_line
			(start -0.12065 -0.2794)
			(end 0.12065 -0.2794)
			(stroke
				(width 0.1)
				(type default)
			)
			(layer "F.Fab")
		)
		(fp_line
			(start -0.12065 -0.305054)
			(end -0.12065 -0.2794)
			(stroke
				(width 0.1)
				(type default)
			)
			(layer "F.Fab")
		)
		(fp_line
			(start -0.67945 0.3048)
			(end -0.67945 -0.305054)
			(stroke
				(width 0.1)
				(type default)
			)
			(layer "F.Fab")
		)
		(fp_line
			(start -0.67945 -0.305054)
			(end -0.12065 -0.305054)
			(stroke
				(width 0.1)
				(type default)
			)
			(layer "F.Fab")
		)
		(pad "1" smd circle
			(at -0.40005 0 180)
			(size 0 0)
			(layers "F.Cu" "F.Mask" "F.Paste")
			(net "P3V3_NIC4")
		)
		(pad "2" smd circle
			(at 0.40005 0 180)
			(size 0 0)
			(layers "F.Cu" "F.Mask" "F.Paste")
			(net "SMB_NIC4_LS_SDA")
		)
	)
	(footprint ""
		(layer "F.Cu")
		(at 190.226696 -409.795472 -90)
		(property "Reference" "R4419"
			(at 0 0 270)
			(layer "F.SilkS")
			(hide yes)
			(effects
				(font
					(size 1.27 1.27)
				)
			)
		)
		(property "Value" ""
			(at 0 0 270)
			(layer "F.Fab")
			(effects
				(font
					(size 1.27 1.27)
				)
			)
		)
		(duplicate_pad_numbers_are_jumpers no)
		(fp_line
			(start -0.7874 0.4064)
			(end -0.7874 -0.4064)
			(stroke
				(width 0.1524)
				(type default)
			)
			(layer "F.SilkS")
		)
		(fp_line
			(start 0.7874 0.4064)
			(end -0.7874 0.4064)
			(stroke
				(width 0.1524)
				(type default)
			)
			(layer "F.SilkS")
		)
		(fp_line
			(start -0.7874 -0.4064)
			(end 0.7874 -0.4064)
			(stroke
				(width 0.1524)
				(type default)
			)
			(layer "F.SilkS")
		)
		(fp_line
			(start 0.7874 -0.4064)
			(end 0.7874 0.4064)
			(stroke
				(width 0.1524)
				(type default)
			)
			(layer "F.SilkS")
		)
		(fp_line
			(start -0.67945 0.3048)
			(end -0.67945 -0.305054)
			(stroke
				(width 0.1)
				(type default)
			)
			(layer "F.Fab")
		)
		(fp_line
			(start -0.12065 0.3048)
			(end -0.67945 0.3048)
			(stroke
				(width 0.1)
				(type default)
			)
			(layer "F.Fab")
		)
		(fp_line
			(start 0.120396 0.3048)
			(end 0.120396 0.2794)
			(stroke
				(width 0.1)
				(type default)
			)
			(layer "F.Fab")
		)
		(fp_line
			(start 0.67945 0.3048)
			(end 0.120396 0.3048)
			(stroke
				(width 0.1)
				(type default)
			)
			(layer "F.Fab")
		)
		(fp_line
			(start -0.12065 0.2794)
			(end -0.12065 0.3048)
			(stroke
				(width 0.1)
				(type default)
			)
			(layer "F.Fab")
		)
		(fp_line
			(start 0.120396 0.2794)
			(end -0.12065 0.2794)
			(stroke
				(width 0.1)
				(type default)
			)
			(layer "F.Fab")
		)
		(fp_line
			(start -0.12065 -0.2794)
			(end 0.12065 -0.2794)
			(stroke
				(width 0.1)
				(type default)
			)
			(layer "F.Fab")
		)
		(fp_line
			(start 0.12065 -0.2794)
			(end 0.12065 -0.3048)
			(stroke
				(width 0.1)
				(type default)
			)
			(layer "F.Fab")
		)
		(fp_line
			(start 0.12065 -0.3048)
			(end 0.67945 -0.3048)
			(stroke
				(width 0.1)
				(type default)
			)
			(layer "F.Fab")
		)
		(fp_line
			(start 0.67945 -0.3048)
			(end 0.67945 0.3048)
			(stroke
				(width 0.1)
				(type default)
			)
			(layer "F.Fab")
		)
		(fp_line
			(start -0.67945 -0.305054)
			(end -0.12065 -0.305054)
			(stroke
				(width 0.1)
				(type default)
			)
			(layer "F.Fab")
		)
		(fp_line
			(start -0.12065 -0.305054)
			(end -0.12065 -0.2794)
			(stroke
				(width 0.1)
				(type default)
			)
			(layer "F.Fab")
		)
		(pad "1" smd circle
			(at -0.40005 0 270)
			(size 0 0)
			(layers "F.Cu" "F.Mask" "F.Paste")
			(net "GND")
		)
		(pad "2" smd circle
			(at 0.40005 0 270)
			(size 0 0)
			(layers "F.Cu" "F.Mask" "F.Paste")
			(net "A_P12V_AUX_FP_TRIGGER")
		)
	)
	(footprint ""
		(layer "F.Cu")
		(at 434.420518 -26.666444 -90)
		(property "Reference" "R4083"
			(at 0 0 270)
			(layer "F.SilkS")
			(hide yes)
			(effects
				(font
					(size 1.27 1.27)
				)
			)
		)
		(property "Value" ""
			(at 0 0 270)
			(layer "F.Fab")
			(effects
				(font
					(size 1.27 1.27)
				)
			)
		)
		(duplicate_pad_numbers_are_jumpers no)
		(fp_line
			(start -0.7874 0.4064)
			(end -0.7874 -0.4064)
			(stroke
				(width 0.1524)
				(type default)
			)
			(layer "F.SilkS")
		)
		(fp_line
			(start 0.7874 0.4064)
			(end -0.7874 0.4064)
			(stroke
				(width 0.1524)
				(type default)
			)
			(layer "F.SilkS")
		)
		(fp_line
			(start -0.7874 -0.4064)
			(end 0.7874 -0.4064)
			(stroke
				(width 0.1524)
				(type default)
			)
			(layer "F.SilkS")
		)
		(fp_line
			(start 0.7874 -0.4064)
			(end 0.7874 0.4064)
			(stroke
				(width 0.1524)
				(type default)
			)
			(layer "F.SilkS")
		)
		(fp_line
			(start -0.67945 0.3048)
			(end -0.67945 -0.305054)
			(stroke
				(width 0.1)
				(type default)
			)
			(layer "F.Fab")
		)
		(fp_line
			(start -0.12065 0.3048)
			(end -0.67945 0.3048)
			(stroke
				(width 0.1)
				(type default)
			)
			(layer "F.Fab")
		)
		(fp_line
			(start 0.120396 0.3048)
			(end 0.120396 0.2794)
			(stroke
				(width 0.1)
				(type default)
			)
			(layer "F.Fab")
		)
		(fp_line
			(start 0.67945 0.3048)
			(end 0.120396 0.3048)
			(stroke
				(width 0.1)
				(type default)
			)
			(layer "F.Fab")
		)
		(fp_line
			(start -0.12065 0.2794)
			(end -0.12065 0.3048)
			(stroke
				(width 0.1)
				(type default)
			)
			(layer "F.Fab")
		)
		(fp_line
			(start 0.120396 0.2794)
			(end -0.12065 0.2794)
			(stroke
				(width 0.1)
				(type default)
			)
			(layer "F.Fab")
		)
		(fp_line
			(start -0.12065 -0.2794)
			(end 0.12065 -0.2794)
			(stroke
				(width 0.1)
				(type default)
			)
			(layer "F.Fab")
		)
		(fp_line
			(start 0.12065 -0.2794)
			(end 0.12065 -0.3048)
			(stroke
				(width 0.1)
				(type default)
			)
			(layer "F.Fab")
		)
		(fp_line
			(start 0.12065 -0.3048)
			(end 0.67945 -0.3048)
			(stroke
				(width 0.1)
				(type default)
			)
			(layer "F.Fab")
		)
		(fp_line
			(start 0.67945 -0.3048)
			(end 0.67945 0.3048)
			(stroke
				(width 0.1)
				(type default)
			)
			(layer "F.Fab")
		)
		(fp_line
			(start -0.67945 -0.305054)
			(end -0.12065 -0.305054)
			(stroke
				(width 0.1)
				(type default)
			)
			(layer "F.Fab")
		)
		(fp_line
			(start -0.12065 -0.305054)
			(end -0.12065 -0.2794)
			(stroke
				(width 0.1)
				(type default)
			)
			(layer "F.Fab")
		)
		(pad "1" smd circle
			(at -0.40005 0 270)
			(size 0 0)
			(layers "F.Cu" "F.Mask" "F.Paste")
			(net "PRSNT_SSD15_R_N")
		)
		(pad "2" smd circle
			(at 0.40005 0 270)
			(size 0 0)
			(layers "F.Cu" "F.Mask" "F.Paste")
			(net "PRSNT_SSD15_N")
		)
	)
	(footprint ""
		(layer "F.Cu")
		(at 277.742396 -414.88995 -90)
		(property "Reference" "R1814"
			(at 0 0 270)
			(layer "F.SilkS")
			(hide yes)
			(effects
				(font
					(size 1.27 1.27)
				)
			)
		)
		(property "Value" ""
			(at 0 0 270)
			(layer "F.Fab")
			(effects
				(font
					(size 1.27 1.27)
				)
			)
		)
		(duplicate_pad_numbers_are_jumpers no)
		(fp_line
			(start -0.7874 0.4064)
			(end -0.7874 -0.4064)
			(stroke
				(width 0.1524)
				(type default)
			)
			(layer "F.SilkS")
		)
		(fp_line
			(start 0.7874 0.4064)
			(end -0.7874 0.4064)
			(stroke
				(width 0.1524)
				(type default)
			)
			(layer "F.SilkS")
		)
		(fp_line
			(start -0.7874 -0.4064)
			(end 0.7874 -0.4064)
			(stroke
				(width 0.1524)
				(type default)
			)
			(layer "F.SilkS")
		)
		(fp_line
			(start 0.7874 -0.4064)
			(end 0.7874 0.4064)
			(stroke
				(width 0.1524)
				(type default)
			)
			(layer "F.SilkS")
		)
		(fp_line
			(start -0.67945 0.3048)
			(end -0.67945 -0.305054)
			(stroke
				(width 0.1)
				(type default)
			)
			(layer "F.Fab")
		)
		(fp_line
			(start -0.12065 0.3048)
			(end -0.67945 0.3048)
			(stroke
				(width 0.1)
				(type default)
			)
			(layer "F.Fab")
		)
		(fp_line
			(start 0.120396 0.3048)
			(end 0.120396 0.2794)
			(stroke
				(width 0.1)
				(type default)
			)
			(layer "F.Fab")
		)
		(fp_line
			(start 0.67945 0.3048)
			(end 0.120396 0.3048)
			(stroke
				(width 0.1)
				(type default)
			)
			(layer "F.Fab")
		)
		(fp_line
			(start -0.12065 0.2794)
			(end -0.12065 0.3048)
			(stroke
				(width 0.1)
				(type default)
			)
			(layer "F.Fab")
		)
		(fp_line
			(start 0.120396 0.2794)
			(end -0.12065 0.2794)
			(stroke
				(width 0.1)
				(type default)
			)
			(layer "F.Fab")
		)
		(fp_line
			(start -0.12065 -0.2794)
			(end 0.12065 -0.2794)
			(stroke
				(width 0.1)
				(type default)
			)
			(layer "F.Fab")
		)
		(fp_line
			(start 0.12065 -0.2794)
			(end 0.12065 -0.3048)
			(stroke
				(width 0.1)
				(type default)
			)
			(layer "F.Fab")
		)
		(fp_line
			(start 0.12065 -0.3048)
			(end 0.67945 -0.3048)
			(stroke
				(width 0.1)
				(type default)
			)
			(layer "F.Fab")
		)
		(fp_line
			(start 0.67945 -0.3048)
			(end 0.67945 0.3048)
			(stroke
				(width 0.1)
				(type default)
			)
			(layer "F.Fab")
		)
		(fp_line
			(start -0.67945 -0.305054)
			(end -0.12065 -0.305054)
			(stroke
				(width 0.1)
				(type default)
			)
			(layer "F.Fab")
		)
		(fp_line
			(start -0.12065 -0.305054)
			(end -0.12065 -0.2794)
			(stroke
				(width 0.1)
				(type default)
			)
			(layer "F.Fab")
		)
		(pad "1" smd circle
			(at -0.40005 0 270)
			(size 0 0)
			(layers "F.Cu" "F.Mask" "F.Paste")
			(net "P3V3_AUX")
		)
		(pad "2" smd circle
			(at 0.40005 0 270)
			(size 0 0)
			(layers "F.Cu" "F.Mask" "F.Paste")
			(net "MB_BIC_READY_BUF_N")
		)
	)
	(footprint ""
		(layer "F.Cu")
		(at 63.824612 -158.080202 90)
		(property "Reference" "R2472"
			(at 0 0 90)
			(layer "F.SilkS")
			(hide yes)
			(effects
				(font
					(size 1.27 1.27)
				)
			)
		)
		(property "Value" ""
			(at 0 0 90)
			(layer "F.Fab")
			(effects
				(font
					(size 1.27 1.27)
				)
			)
		)
		(duplicate_pad_numbers_are_jumpers no)
		(fp_line
			(start 0.7874 -0.4064)
			(end 0.7874 0.4064)
			(stroke
				(width 0.1524)
				(type default)
			)
			(layer "F.SilkS")
		)
		(fp_line
			(start -0.7874 -0.4064)
			(end 0.7874 -0.4064)
			(stroke
				(width 0.1524)
				(type default)
			)
			(layer "F.SilkS")
		)
		(fp_line
			(start 0.7874 0.4064)
			(end -0.7874 0.4064)
			(stroke
				(width 0.1524)
				(type default)
			)
			(layer "F.SilkS")
		)
		(fp_line
			(start -0.7874 0.4064)
			(end -0.7874 -0.4064)
			(stroke
				(width 0.1524)
				(type default)
			)
			(layer "F.SilkS")
		)
		(fp_line
			(start -0.12065 -0.305054)
			(end -0.12065 -0.2794)
			(stroke
				(width 0.1)
				(type default)
			)
			(layer "F.Fab")
		)
		(fp_line
			(start -0.67945 -0.305054)
			(end -0.12065 -0.305054)
			(stroke
				(width 0.1)
				(type default)
			)
			(layer "F.Fab")
		)
		(fp_line
			(start 0.67945 -0.3048)
			(end 0.67945 0.3048)
			(stroke
				(width 0.1)
				(type default)
			)
			(layer "F.Fab")
		)
		(fp_line
			(start 0.12065 -0.3048)
			(end 0.67945 -0.3048)
			(stroke
				(width 0.1)
				(type default)
			)
			(layer "F.Fab")
		)
		(fp_line
			(start 0.12065 -0.2794)
			(end 0.12065 -0.3048)
			(stroke
				(width 0.1)
				(type default)
			)
			(layer "F.Fab")
		)
		(fp_line
			(start -0.12065 -0.2794)
			(end 0.12065 -0.2794)
			(stroke
				(width 0.1)
				(type default)
			)
			(layer "F.Fab")
		)
		(fp_line
			(start 0.120396 0.2794)
			(end -0.12065 0.2794)
			(stroke
				(width 0.1)
				(type default)
			)
			(layer "F.Fab")
		)
		(fp_line
			(start -0.12065 0.2794)
			(end -0.12065 0.3048)
			(stroke
				(width 0.1)
				(type default)
			)
			(layer "F.Fab")
		)
		(fp_line
			(start 0.67945 0.3048)
			(end 0.120396 0.3048)
			(stroke
				(width 0.1)
				(type default)
			)
			(layer "F.Fab")
		)
		(fp_line
			(start 0.120396 0.3048)
			(end 0.120396 0.2794)
			(stroke
				(width 0.1)
				(type default)
			)
			(layer "F.Fab")
		)
		(fp_line
			(start -0.12065 0.3048)
			(end -0.67945 0.3048)
			(stroke
				(width 0.1)
				(type default)
			)
			(layer "F.Fab")
		)
		(fp_line
			(start -0.67945 0.3048)
			(end -0.67945 -0.305054)
			(stroke
				(width 0.1)
				(type default)
			)
			(layer "F.Fab")
		)
		(pad "1" smd circle
			(at -0.40005 0 90)
			(size 0 0)
			(layers "F.Cu" "F.Mask" "F.Paste")
			(net "NIC1_PWRBRK_R_N")
		)
		(pad "2" smd circle
			(at 0.40005 0 90)
			(size 0 0)
			(layers "F.Cu" "F.Mask" "F.Paste")
			(net "NIC1_PWRBRK_N")
		)
	)
	(footprint ""
		(layer "F.Cu")
		(at 15.98803 -45.704252 90)
		(property "Reference" "R506"
			(at 0 0 90)
			(layer "F.SilkS")
			(hide yes)
			(effects
				(font
					(size 1.27 1.27)
				)
			)
		)
		(property "Value" ""
			(at 0 0 90)
			(layer "F.Fab")
			(effects
				(font
					(size 1.27 1.27)
				)
			)
		)
		(duplicate_pad_numbers_are_jumpers no)
		(fp_line
			(start 3.937508 -1.8796)
			(end -3.937508 -1.8796)
			(stroke
				(width 0.1524)
				(type default)
			)
			(layer "F.SilkS")
		)
		(fp_line
			(start -3.937508 -1.8796)
			(end -3.937508 1.8796)
			(stroke
				(width 0.1524)
				(type default)
			)
			(layer "F.SilkS")
		)
		(fp_line
			(start 3.937508 1.8796)
			(end 3.937508 -1.8796)
			(stroke
				(width 0.1524)
				(type default)
			)
			(layer "F.SilkS")
		)
		(fp_line
			(start -3.937508 1.8796)
			(end 3.937508 1.8796)
			(stroke
				(width 0.1524)
				(type default)
			)
			(layer "F.SilkS")
		)
		(fp_line
			(start 3.275076 -1.674876)
			(end -3.275076 -1.674876)
			(stroke
				(width 0.1)
				(type default)
			)
			(layer "F.Fab")
		)
		(fp_line
			(start -3.275076 -1.674876)
			(end -3.275076 1.674876)
			(stroke
				(width 0.1)
				(type default)
			)
			(layer "F.Fab")
		)
		(fp_line
			(start 3.275076 1.674876)
			(end 3.275076 -1.674876)
			(stroke
				(width 0.1)
				(type default)
			)
			(layer "F.Fab")
		)
		(fp_line
			(start -3.275076 1.674876)
			(end 3.275076 1.674876)
			(stroke
				(width 0.1)
				(type default)
			)
			(layer "F.Fab")
		)
		(pad "1" smd rect
			(at -2.350008 0 90)
			(size 2.921 3.5052)
			(layers "F.Cu" "F.Mask" "F.Paste")
			(net "P12V_SSD0")
		)
		(pad "2" smd rect
			(at 2.350008 0 90)
			(size 2.921 3.5052)
			(layers "F.Cu" "F.Mask" "F.Paste")
			(net "P12V_SSD0_R")
		)
	)
	(footprint ""
		(layer "F.Cu")
		(at 98.672904 -22.867366 90)
		(property "Reference" "C3893"
			(at 0 0 90)
			(layer "F.SilkS")
			(hide yes)
			(effects
				(font
					(size 1.27 1.27)
				)
			)
		)
		(property "Value" ""
			(at 0 0 90)
			(layer "F.Fab")
			(effects
				(font
					(size 1.27 1.27)
				)
			)
		)
		(duplicate_pad_numbers_are_jumpers no)
		(fp_line
			(start 0.7874 -0.4064)
			(end 0.7874 0.4064)
			(stroke
				(width 0.1524)
				(type default)
			)
			(layer "F.SilkS")
		)
		(fp_line
			(start -0.7874 -0.4064)
			(end 0.7874 -0.4064)
			(stroke
				(width 0.1524)
				(type default)
			)
			(layer "F.SilkS")
		)
		(fp_line
			(start 0.7874 0.4064)
			(end -0.7874 0.4064)
			(stroke
				(width 0.1524)
				(type default)
			)
			(layer "F.SilkS")
		)
		(fp_line
			(start -0.7874 0.4064)
			(end -0.7874 -0.4064)
			(stroke
				(width 0.1524)
				(type default)
			)
			(layer "F.SilkS")
		)
		(fp_line
			(start -0.12065 -0.305054)
			(end -0.12065 -0.2794)
			(stroke
				(width 0.1)
				(type default)
			)
			(layer "F.Fab")
		)
		(fp_line
			(start -0.67945 -0.305054)
			(end -0.12065 -0.305054)
			(stroke
				(width 0.1)
				(type default)
			)
			(layer "F.Fab")
		)
		(fp_line
			(start 0.67945 -0.3048)
			(end 0.67945 0.3048)
			(stroke
				(width 0.1)
				(type default)
			)
			(layer "F.Fab")
		)
		(fp_line
			(start 0.12065 -0.3048)
			(end 0.67945 -0.3048)
			(stroke
				(width 0.1)
				(type default)
			)
			(layer "F.Fab")
		)
		(fp_line
			(start 0.12065 -0.2794)
			(end 0.12065 -0.3048)
			(stroke
				(width 0.1)
				(type default)
			)
			(layer "F.Fab")
		)
		(fp_line
			(start -0.12065 -0.2794)
			(end 0.12065 -0.2794)
			(stroke
				(width 0.1)
				(type default)
			)
			(layer "F.Fab")
		)
		(fp_line
			(start 0.120396 0.2794)
			(end -0.12065 0.2794)
			(stroke
				(width 0.1)
				(type default)
			)
			(layer "F.Fab")
		)
		(fp_line
			(start -0.12065 0.2794)
			(end -0.12065 0.3048)
			(stroke
				(width 0.1)
				(type default)
			)
			(layer "F.Fab")
		)
		(fp_line
			(start 0.67945 0.3048)
			(end 0.120396 0.3048)
			(stroke
				(width 0.1)
				(type default)
			)
			(layer "F.Fab")
		)
		(fp_line
			(start 0.120396 0.3048)
			(end 0.120396 0.2794)
			(stroke
				(width 0.1)
				(type default)
			)
			(layer "F.Fab")
		)
		(fp_line
			(start -0.12065 0.3048)
			(end -0.67945 0.3048)
			(stroke
				(width 0.1)
				(type default)
			)
			(layer "F.Fab")
		)
		(fp_line
			(start -0.67945 0.3048)
			(end -0.67945 -0.305054)
			(stroke
				(width 0.1)
				(type default)
			)
			(layer "F.Fab")
		)
		(pad "1" smd circle
			(at -0.40005 0 90)
			(size 0 0)
			(layers "F.Cu" "F.Mask" "F.Paste")
			(net "P12V_SSD3")
		)
		(pad "2" smd circle
			(at 0.40005 0 90)
			(size 0 0)
			(layers "F.Cu" "F.Mask" "F.Paste")
			(net "GND")
		)
	)
	(footprint ""
		(layer "F.Cu")
		(at 433.615084 -20.72513)
		(property "Reference" "H103"
			(at 1.573022 -2.614168 0)
			(unlocked yes)
			(layer "B.SilkS")
			(effects
				(font
					(size 0.7874 0.5842)
					(thickness 0.1524)
				)
				(justify left mirror)
			)
		)
		(property "Value" ""
			(at 0 0 0)
			(layer "F.Fab")
			(effects
				(font
					(size 1.27 1.27)
				)
			)
		)
		(duplicate_pad_numbers_are_jumpers no)
		(pad "1" thru_hole rect
			(at 0 0)
			(size 4.2164 5.0038)
			(drill 2.0066
				(offset 0.099822 0)
			)
			(layers "*.Cu" "*.Mask")
			(remove_unused_layers no)
			(net "Net_8560")
			(clearance -0.8509)
			(padstack
				(mode front_inner_back)
				(layer "Inner"
					(shape circle)
					(size 4.0132 4.0132)
					(clearance -0.7493)
				)
				(layer "B.Cu"
					(shape circle)
					(size 4.0132 4.0132)
					(clearance -0.7493)
				)
			)
		)
	)
	(footprint ""
		(layer "F.Cu")
		(at 452.111872 -234.834684)
		(property "Reference" "C4439"
			(at 0 0 0)
			(layer "F.SilkS")
			(hide yes)
			(effects
				(font
					(size 1.27 1.27)
				)
			)
		)
		(property "Value" ""
			(at 0 0 0)
			(layer "F.Fab")
			(effects
				(font
					(size 1.27 1.27)
				)
			)
		)
		(duplicate_pad_numbers_are_jumpers no)
		(fp_line
			(start -0.7874 -0.4064)
			(end 0.7874 -0.4064)
			(stroke
				(width 0.1524)
				(type default)
			)
			(layer "F.SilkS")
		)
		(fp_line
			(start -0.7874 0.4064)
			(end -0.7874 -0.4064)
			(stroke
				(width 0.1524)
				(type default)
			)
			(layer "F.SilkS")
		)
		(fp_line
			(start 0.7874 -0.4064)
			(end 0.7874 0.4064)
			(stroke
				(width 0.1524)
				(type default)
			)
			(layer "F.SilkS")
		)
		(fp_line
			(start 0.7874 0.4064)
			(end -0.7874 0.4064)
			(stroke
				(width 0.1524)
				(type default)
			)
			(layer "F.SilkS")
		)
		(fp_line
			(start -0.67945 -0.305054)
			(end -0.12065 -0.305054)
			(stroke
				(width 0.1)
				(type default)
			)
			(layer "F.Fab")
		)
		(fp_line
			(start -0.67945 0.3048)
			(end -0.67945 -0.305054)
			(stroke
				(width 0.1)
				(type default)
			)
			(layer "F.Fab")
		)
		(fp_line
			(start -0.12065 -0.305054)
			(end -0.12065 -0.2794)
			(stroke
				(width 0.1)
				(type default)
			)
			(layer "F.Fab")
		)
		(fp_line
			(start -0.12065 -0.2794)
			(end 0.12065 -0.2794)
			(stroke
				(width 0.1)
				(type default)
			)
			(layer "F.Fab")
		)
		(fp_line
			(start -0.12065 0.2794)
			(end -0.12065 0.3048)
			(stroke
				(width 0.1)
				(type default)
			)
			(layer "F.Fab")
		)
		(fp_line
			(start -0.12065 0.3048)
			(end -0.67945 0.3048)
			(stroke
				(width 0.1)
				(type default)
			)
			(layer "F.Fab")
		)
		(fp_line
			(start 0.120396 0.2794)
			(end -0.12065 0.2794)
			(stroke
				(width 0.1)
				(type default)
			)
			(layer "F.Fab")
		)
		(fp_line
			(start 0.120396 0.3048)
			(end 0.120396 0.2794)
			(stroke
				(width 0.1)
				(type default)
			)
			(layer "F.Fab")
		)
		(fp_line
			(start 0.12065 -0.3048)
			(end 0.67945 -0.3048)
			(stroke
				(width 0.1)
				(type default)
			)
			(layer "F.Fab")
		)
		(fp_line
			(start 0.12065 -0.2794)
			(end 0.12065 -0.3048)
			(stroke
				(width 0.1)
				(type default)
			)
			(layer "F.Fab")
		)
		(fp_line
			(start 0.67945 -0.3048)
			(end 0.67945 0.3048)
			(stroke
				(width 0.1)
				(type default)
			)
			(layer "F.Fab")
		)
		(fp_line
			(start 0.67945 0.3048)
			(end 0.120396 0.3048)
			(stroke
				(width 0.1)
				(type default)
			)
			(layer "F.Fab")
		)
		(pad "1" smd circle
			(at -0.40005 0)
			(size 0 0)
			(layers "F.Cu" "F.Mask" "F.Paste")
			(net "P3V3_AUX")
		)
		(pad "2" smd circle
			(at 0.40005 0)
			(size 0 0)
			(layers "F.Cu" "F.Mask" "F.Paste")
			(net "GND")
		)
	)
	(footprint ""
		(layer "F.Cu")
		(at 453.795892 -374.87987)
		(property "Reference" "Q243"
			(at -0.6604 -1.793748 0)
			(unlocked yes)
			(layer "F.SilkS")
			(effects
				(font
					(size 0.7874 0.5842)
					(thickness 0.1524)
				)
			)
		)
		(property "Value" ""
			(at 0 0 0)
			(layer "F.Fab")
			(effects
				(font
					(size 1.27 1.27)
				)
			)
		)
		(duplicate_pad_numbers_are_jumpers no)
		(fp_line
			(start -1.376172 -1.199896)
			(end -0.508 -1.199896)
			(stroke
				(width 0.1524)
				(type default)
			)
			(layer "F.SilkS")
		)
		(fp_line
			(start -1.376172 1.199896)
			(end -1.376172 -1.199896)
			(stroke
				(width 0.1524)
				(type default)
			)
			(layer "F.SilkS")
		)
		(fp_line
			(start -0.508 -1.199896)
			(end 0 -0.762)
			(stroke
				(width 0.1524)
				(type default)
			)
			(layer "F.SilkS")
		)
		(fp_line
			(start 0 -0.762)
			(end 0.508 -1.199896)
			(stroke
				(width 0.1524)
				(type default)
			)
			(layer "F.SilkS")
		)
		(fp_line
			(start 0.508 -1.199896)
			(end 1.376172 -1.199896)
			(stroke
				(width 0.1524)
				(type default)
			)
			(layer "F.SilkS")
		)
		(fp_line
			(start 1.376172 -1.199896)
			(end 1.376172 1.199896)
			(stroke
				(width 0.1524)
				(type default)
			)
			(layer "F.SilkS")
		)
		(fp_line
			(start 1.376172 1.199896)
			(end -1.376172 1.199896)
			(stroke
				(width 0.1524)
				(type default)
			)
			(layer "F.SilkS")
		)
		(fp_poly
			(pts
				(xy -1.4605 -0.7493) (xy -2.2225 -1.1303) (xy -2.2225 -0.3683)
			)
			(stroke
				(width 0)
				(type default)
			)
			(fill yes)
			(layer "F.SilkS")
		)
		(fp_line
			(start -0.674878 -1.100074)
			(end 0.674878 -1.100074)
			(stroke
				(width 0.1)
				(type default)
			)
			(layer "F.Fab")
		)
		(fp_line
			(start -0.674878 1.100074)
			(end -0.674878 -1.100074)
			(stroke
				(width 0.1)
				(type default)
			)
			(layer "F.Fab")
		)
		(fp_line
			(start 0.674878 -1.100074)
			(end 0.674878 1.100074)
			(stroke
				(width 0.1)
				(type default)
			)
			(layer "F.Fab")
		)
		(fp_line
			(start 0.674878 1.100074)
			(end -0.674878 1.100074)
			(stroke
				(width 0.1)
				(type default)
			)
			(layer "F.Fab")
		)
		(fp_poly
			(pts
				(xy -1.4605 -0.7493) (xy -2.2225 -1.1303) (xy -2.2225 -0.3683)
			)
			(stroke
				(width 0)
				(type default)
			)
			(fill yes)
			(layer "F.Fab")
		)
		(pad "1" smd rect
			(at -0.899922 -0.750062 270)
			(size 0.6096 0.6096)
			(layers "F.Cu" "F.Mask" "F.Paste")
			(net "GND")
		)
		(pad "2" smd rect
			(at -0.899922 0 270)
			(size 0.4064 0.6096)
			(layers "F.Cu" "F.Mask" "F.Paste")
			(net "GPU_3V3IO_RSVD3")
		)
		(pad "3" smd rect
			(at -0.899922 0.750062 270)
			(size 0.6096 0.6096)
			(layers "F.Cu" "F.Mask" "F.Paste")
			(net "GPU_3V3IO_RSVD3_ISO")
		)
		(pad "4" smd rect
			(at 0.899922 0.750062 270)
			(size 0.6096 0.6096)
			(layers "F.Cu" "F.Mask" "F.Paste")
			(net "GND")
		)
		(pad "5" smd rect
			(at 0.899922 0 270)
			(size 0.4064 0.6096)
			(layers "F.Cu" "F.Mask" "F.Paste")
			(net "GPU_3V3IO_RSVD3_N")
		)
		(pad "6" smd rect
			(at 0.899922 -0.750062 270)
			(size 0.6096 0.6096)
			(layers "F.Cu" "F.Mask" "F.Paste")
			(net "GPU_3V3IO_RSVD3_N")
		)
	)
	(footprint ""
		(layer "F.Cu")
		(at 149.140164 -256.634234 180)
		(property "Reference" "C3224"
			(at 0 0 180)
			(layer "F.SilkS")
			(hide yes)
			(effects
				(font
					(size 1.27 1.27)
				)
			)
		)
		(property "Value" ""
			(at 0 0 180)
			(layer "F.Fab")
			(effects
				(font
					(size 1.27 1.27)
				)
			)
		)
		(duplicate_pad_numbers_are_jumpers no)
		(fp_line
			(start 1.2954 0.5842)
			(end -1.2954 0.5842)
			(stroke
				(width 0.1524)
				(type default)
			)
			(layer "F.SilkS")
		)
		(fp_line
			(start 1.2954 -0.5842)
			(end 1.2954 0.5842)
			(stroke
				(width 0.1524)
				(type default)
			)
			(layer "F.SilkS")
		)
		(fp_line
			(start -1.2954 0.5842)
			(end -1.2954 -0.5842)
			(stroke
				(width 0.1524)
				(type default)
			)
			(layer "F.SilkS")
		)
		(fp_line
			(start -1.2954 -0.5842)
			(end 1.2954 -0.5842)
			(stroke
				(width 0.1524)
				(type default)
			)
			(layer "F.SilkS")
		)
		(fp_line
			(start 1.1938 0.4064)
			(end 0.8636 0.4064)
			(stroke
				(width 0.1)
				(type default)
			)
			(layer "F.Fab")
		)
		(fp_line
			(start 1.1938 -0.4064)
			(end 1.1938 0.4064)
			(stroke
				(width 0.1)
				(type default)
			)
			(layer "F.Fab")
		)
		(fp_line
			(start 0.8636 0.4572)
			(end -0.8636 0.4572)
			(stroke
				(width 0.1)
				(type default)
			)
			(layer "F.Fab")
		)
		(fp_line
			(start 0.8636 0.4064)
			(end 0.8636 0.4572)
			(stroke
				(width 0.1)
				(type default)
			)
			(layer "F.Fab")
		)
		(fp_line
			(start 0.8636 -0.4064)
			(end 1.1938 -0.4064)
			(stroke
				(width 0.1)
				(type default)
			)
			(layer "F.Fab")
		)
		(fp_line
			(start 0.8636 -0.4572)
			(end 0.8636 -0.4064)
			(stroke
				(width 0.1)
				(type default)
			)
			(layer "F.Fab")
		)
		(fp_line
			(start -0.8636 0.4572)
			(end -0.8636 0.4064)
			(stroke
				(width 0.1)
				(type default)
			)
			(layer "F.Fab")
		)
		(fp_line
			(start -0.8636 0.4064)
			(end -1.1938 0.4064)
			(stroke
				(width 0.1)
				(type default)
			)
			(layer "F.Fab")
		)
		(fp_line
			(start -0.8636 -0.4064)
			(end -0.8636 -0.4572)
			(stroke
				(width 0.1)
				(type default)
			)
			(layer "F.Fab")
		)
		(fp_line
			(start -0.8636 -0.4572)
			(end 0.8636 -0.4572)
			(stroke
				(width 0.1)
				(type default)
			)
			(layer "F.Fab")
		)
		(fp_line
			(start -1.1938 0.4064)
			(end -1.1938 -0.4064)
			(stroke
				(width 0.1)
				(type default)
			)
			(layer "F.Fab")
		)
		(fp_line
			(start -1.1938 -0.4064)
			(end -0.8636 -0.4064)
			(stroke
				(width 0.1)
				(type default)
			)
			(layer "F.Fab")
		)
		(pad "1" smd rect
			(at -0.7366 0 90)
			(size 0.7112 0.8128)
			(layers "F.Cu" "F.Mask" "F.Paste")
			(net "PCEPLL5_VDDA18_PEX1_R")
		)
		(pad "2" smd rect
			(at 0.7366 0 90)
			(size 0.7112 0.8128)
			(layers "F.Cu" "F.Mask" "F.Paste")
			(net "GND")
		)
	)
	(footprint ""
		(layer "F.Cu")
		(at 340.561422 -195.49745 180)
		(property "Reference" "R4246"
			(at 0 0 180)
			(layer "F.SilkS")
			(hide yes)
			(effects
				(font
					(size 1.27 1.27)
				)
			)
		)
		(property "Value" ""
			(at 0 0 180)
			(layer "F.Fab")
			(effects
				(font
					(size 1.27 1.27)
				)
			)
		)
		(duplicate_pad_numbers_are_jumpers no)
		(fp_line
			(start 0.7874 0.4064)
			(end -0.7874 0.4064)
			(stroke
				(width 0.1524)
				(type default)
			)
			(layer "F.SilkS")
		)
		(fp_line
			(start 0.7874 -0.4064)
			(end 0.7874 0.4064)
			(stroke
				(width 0.1524)
				(type default)
			)
			(layer "F.SilkS")
		)
		(fp_line
			(start -0.7874 0.4064)
			(end -0.7874 -0.4064)
			(stroke
				(width 0.1524)
				(type default)
			)
			(layer "F.SilkS")
		)
		(fp_line
			(start -0.7874 -0.4064)
			(end 0.7874 -0.4064)
			(stroke
				(width 0.1524)
				(type default)
			)
			(layer "F.SilkS")
		)
		(fp_line
			(start 0.67945 0.3048)
			(end 0.120396 0.3048)
			(stroke
				(width 0.1)
				(type default)
			)
			(layer "F.Fab")
		)
		(fp_line
			(start 0.67945 -0.3048)
			(end 0.67945 0.3048)
			(stroke
				(width 0.1)
				(type default)
			)
			(layer "F.Fab")
		)
		(fp_line
			(start 0.12065 -0.2794)
			(end 0.12065 -0.3048)
			(stroke
				(width 0.1)
				(type default)
			)
			(layer "F.Fab")
		)
		(fp_line
			(start 0.12065 -0.3048)
			(end 0.67945 -0.3048)
			(stroke
				(width 0.1)
				(type default)
			)
			(layer "F.Fab")
		)
		(fp_line
			(start 0.120396 0.3048)
			(end 0.120396 0.2794)
			(stroke
				(width 0.1)
				(type default)
			)
			(layer "F.Fab")
		)
		(fp_line
			(start 0.120396 0.2794)
			(end -0.12065 0.2794)
			(stroke
				(width 0.1)
				(type default)
			)
			(layer "F.Fab")
		)
		(fp_line
			(start -0.12065 0.3048)
			(end -0.67945 0.3048)
			(stroke
				(width 0.1)
				(type default)
			)
			(layer "F.Fab")
		)
		(fp_line
			(start -0.12065 0.2794)
			(end -0.12065 0.3048)
			(stroke
				(width 0.1)
				(type default)
			)
			(layer "F.Fab")
		)
		(fp_line
			(start -0.12065 -0.2794)
			(end 0.12065 -0.2794)
			(stroke
				(width 0.1)
				(type default)
			)
			(layer "F.Fab")
		)
		(fp_line
			(start -0.12065 -0.305054)
			(end -0.12065 -0.2794)
			(stroke
				(width 0.1)
				(type default)
			)
			(layer "F.Fab")
		)
		(fp_line
			(start -0.67945 0.3048)
			(end -0.67945 -0.305054)
			(stroke
				(width 0.1)
				(type default)
			)
			(layer "F.Fab")
		)
		(fp_line
			(start -0.67945 -0.305054)
			(end -0.12065 -0.305054)
			(stroke
				(width 0.1)
				(type default)
			)
			(layer "F.Fab")
		)
		(pad "1" smd circle
			(at -0.40005 0 180)
			(size 0 0)
			(layers "F.Cu" "F.Mask" "F.Paste")
			(net "GND")
		)
		(pad "2" smd circle
			(at 0.40005 0 180)
			(size 0 0)
			(layers "F.Cu" "F.Mask" "F.Paste")
			(net "IOEXP_DBV2_A0")
		)
	)
	(footprint ""
		(layer "F.Cu")
		(at 10.530586 -144.067276 180)
		(property "Reference" "PC602"
			(at 0 0 180)
			(layer "F.SilkS")
			(hide yes)
			(effects
				(font
					(size 1.27 1.27)
				)
			)
		)
		(property "Value" ""
			(at 0 0 180)
			(layer "F.Fab")
			(effects
				(font
					(size 1.27 1.27)
				)
			)
		)
		(duplicate_pad_numbers_are_jumpers no)
		(fp_line
			(start 1.524 0.762)
			(end -1.524 0.762)
			(stroke
				(width 0.1524)
				(type default)
			)
			(layer "F.SilkS")
		)
		(fp_line
			(start 1.524 -0.762)
			(end 1.524 0.762)
			(stroke
				(width 0.1524)
				(type default)
			)
			(layer "F.SilkS")
		)
		(fp_line
			(start -1.524 0.762)
			(end -1.524 -0.762)
			(stroke
				(width 0.1524)
				(type default)
			)
			(layer "F.SilkS")
		)
		(fp_line
			(start -1.524 -0.762)
			(end 1.524 -0.762)
			(stroke
				(width 0.1524)
				(type default)
			)
			(layer "F.SilkS")
		)
		(fp_line
			(start 1.1049 0.724916)
			(end 1.1049 -0.724916)
			(stroke
				(width 0.1)
				(type default)
			)
			(layer "F.Fab")
		)
		(fp_line
			(start 1.1049 -0.724916)
			(end -1.1049 -0.724916)
			(stroke
				(width 0.1)
				(type default)
			)
			(layer "F.Fab")
		)
		(fp_line
			(start -1.1049 0.724916)
			(end 1.1049 0.724916)
			(stroke
				(width 0.1)
				(type default)
			)
			(layer "F.Fab")
		)
		(fp_line
			(start -1.1049 -0.724916)
			(end -1.1049 0.724916)
			(stroke
				(width 0.1)
				(type default)
			)
			(layer "F.Fab")
		)
		(pad "1" smd rect
			(at -0.889 0)
			(size 1.016 1.27)
			(layers "F.Cu" "F.Mask" "F.Paste")
			(net "P12V_NIC0_R")
		)
		(pad "2" smd rect
			(at 0.889 0)
			(size 1.016 1.27)
			(layers "F.Cu" "F.Mask" "F.Paste")
			(net "GND")
		)
	)
	(footprint ""
		(layer "F.Cu")
		(at 423.96791 -18.437098)
		(property "Reference" "R1735"
			(at 0 0 0)
			(layer "F.SilkS")
			(hide yes)
			(effects
				(font
					(size 1.27 1.27)
				)
			)
		)
		(property "Value" ""
			(at 0 0 0)
			(layer "F.Fab")
			(effects
				(font
					(size 1.27 1.27)
				)
			)
		)
		(duplicate_pad_numbers_are_jumpers no)
		(fp_line
			(start -0.7874 -0.4064)
			(end 0.7874 -0.4064)
			(stroke
				(width 0.1524)
				(type default)
			)
			(layer "F.SilkS")
		)
		(fp_line
			(start -0.7874 0.4064)
			(end -0.7874 -0.4064)
			(stroke
				(width 0.1524)
				(type default)
			)
			(layer "F.SilkS")
		)
		(fp_line
			(start 0.7874 -0.4064)
			(end 0.7874 0.4064)
			(stroke
				(width 0.1524)
				(type default)
			)
			(layer "F.SilkS")
		)
		(fp_line
			(start 0.7874 0.4064)
			(end -0.7874 0.4064)
			(stroke
				(width 0.1524)
				(type default)
			)
			(layer "F.SilkS")
		)
		(fp_line
			(start -0.67945 -0.305054)
			(end -0.12065 -0.305054)
			(stroke
				(width 0.1)
				(type default)
			)
			(layer "F.Fab")
		)
		(fp_line
			(start -0.67945 0.3048)
			(end -0.67945 -0.305054)
			(stroke
				(width 0.1)
				(type default)
			)
			(layer "F.Fab")
		)
		(fp_line
			(start -0.12065 -0.305054)
			(end -0.12065 -0.2794)
			(stroke
				(width 0.1)
				(type default)
			)
			(layer "F.Fab")
		)
		(fp_line
			(start -0.12065 -0.2794)
			(end 0.12065 -0.2794)
			(stroke
				(width 0.1)
				(type default)
			)
			(layer "F.Fab")
		)
		(fp_line
			(start -0.12065 0.2794)
			(end -0.12065 0.3048)
			(stroke
				(width 0.1)
				(type default)
			)
			(layer "F.Fab")
		)
		(fp_line
			(start -0.12065 0.3048)
			(end -0.67945 0.3048)
			(stroke
				(width 0.1)
				(type default)
			)
			(layer "F.Fab")
		)
		(fp_line
			(start 0.120396 0.2794)
			(end -0.12065 0.2794)
			(stroke
				(width 0.1)
				(type default)
			)
			(layer "F.Fab")
		)
		(fp_line
			(start 0.120396 0.3048)
			(end 0.120396 0.2794)
			(stroke
				(width 0.1)
				(type default)
			)
			(layer "F.Fab")
		)
		(fp_line
			(start 0.12065 -0.3048)
			(end 0.67945 -0.3048)
			(stroke
				(width 0.1)
				(type default)
			)
			(layer "F.Fab")
		)
		(fp_line
			(start 0.12065 -0.2794)
			(end 0.12065 -0.3048)
			(stroke
				(width 0.1)
				(type default)
			)
			(layer "F.Fab")
		)
		(fp_line
			(start 0.67945 -0.3048)
			(end 0.67945 0.3048)
			(stroke
				(width 0.1)
				(type default)
			)
			(layer "F.Fab")
		)
		(fp_line
			(start 0.67945 0.3048)
			(end 0.120396 0.3048)
			(stroke
				(width 0.1)
				(type default)
			)
			(layer "F.Fab")
		)
		(pad "1" smd circle
			(at -0.40005 0)
			(size 0 0)
			(layers "F.Cu" "F.Mask" "F.Paste")
			(net "SMB_ISO_SSD14_R_SCL")
		)
		(pad "2" smd circle
			(at 0.40005 0)
			(size 0 0)
			(layers "F.Cu" "F.Mask" "F.Paste")
			(net "SMB_ISO_SSD14_SCL")
		)
	)
	(footprint ""
		(layer "F.Cu")
		(at 424.415458 -42.853102 180)
		(property "Reference" "R5906"
			(at 0 0 180)
			(layer "F.SilkS")
			(hide yes)
			(effects
				(font
					(size 1.27 1.27)
				)
			)
		)
		(property "Value" ""
			(at 0 0 180)
			(layer "F.Fab")
			(effects
				(font
					(size 1.27 1.27)
				)
			)
		)
		(duplicate_pad_numbers_are_jumpers no)
		(fp_line
			(start 0.7874 0.4064)
			(end -0.7874 0.4064)
			(stroke
				(width 0.1524)
				(type default)
			)
			(layer "F.SilkS")
		)
		(fp_line
			(start 0.7874 -0.4064)
			(end 0.7874 0.4064)
			(stroke
				(width 0.1524)
				(type default)
			)
			(layer "F.SilkS")
		)
		(fp_line
			(start -0.7874 0.4064)
			(end -0.7874 -0.4064)
			(stroke
				(width 0.1524)
				(type default)
			)
			(layer "F.SilkS")
		)
		(fp_line
			(start -0.7874 -0.4064)
			(end 0.7874 -0.4064)
			(stroke
				(width 0.1524)
				(type default)
			)
			(layer "F.SilkS")
		)
		(fp_line
			(start 0.67945 0.3048)
			(end 0.120396 0.3048)
			(stroke
				(width 0.1)
				(type default)
			)
			(layer "F.Fab")
		)
		(fp_line
			(start 0.67945 -0.3048)
			(end 0.67945 0.3048)
			(stroke
				(width 0.1)
				(type default)
			)
			(layer "F.Fab")
		)
		(fp_line
			(start 0.12065 -0.2794)
			(end 0.12065 -0.3048)
			(stroke
				(width 0.1)
				(type default)
			)
			(layer "F.Fab")
		)
		(fp_line
			(start 0.12065 -0.3048)
			(end 0.67945 -0.3048)
			(stroke
				(width 0.1)
				(type default)
			)
			(layer "F.Fab")
		)
		(fp_line
			(start 0.120396 0.3048)
			(end 0.120396 0.2794)
			(stroke
				(width 0.1)
				(type default)
			)
			(layer "F.Fab")
		)
		(fp_line
			(start 0.120396 0.2794)
			(end -0.12065 0.2794)
			(stroke
				(width 0.1)
				(type default)
			)
			(layer "F.Fab")
		)
		(fp_line
			(start -0.12065 0.3048)
			(end -0.67945 0.3048)
			(stroke
				(width 0.1)
				(type default)
			)
			(layer "F.Fab")
		)
		(fp_line
			(start -0.12065 0.2794)
			(end -0.12065 0.3048)
			(stroke
				(width 0.1)
				(type default)
			)
			(layer "F.Fab")
		)
		(fp_line
			(start -0.12065 -0.2794)
			(end 0.12065 -0.2794)
			(stroke
				(width 0.1)
				(type default)
			)
			(layer "F.Fab")
		)
		(fp_line
			(start -0.12065 -0.305054)
			(end -0.12065 -0.2794)
			(stroke
				(width 0.1)
				(type default)
			)
			(layer "F.Fab")
		)
		(fp_line
			(start -0.67945 0.3048)
			(end -0.67945 -0.305054)
			(stroke
				(width 0.1)
				(type default)
			)
			(layer "F.Fab")
		)
		(fp_line
			(start -0.67945 -0.305054)
			(end -0.12065 -0.305054)
			(stroke
				(width 0.1)
				(type default)
			)
			(layer "F.Fab")
		)
		(pad "1" smd circle
			(at -0.40005 0 180)
			(size 0 0)
			(layers "F.Cu" "F.Mask" "F.Paste")
			(net "SSD14_ADC_A1")
		)
		(pad "2" smd circle
			(at 0.40005 0 180)
			(size 0 0)
			(layers "F.Cu" "F.Mask" "F.Paste")
			(net "SMB_SSD14_ADC_SCL")
		)
	)
	(footprint ""
		(layer "F.Cu")
		(at 14.689836 -255.046734 -90)
		(property "Reference" "R6473"
			(at 0 0 270)
			(layer "F.SilkS")
			(hide yes)
			(effects
				(font
					(size 1.27 1.27)
				)
			)
		)
		(property "Value" ""
			(at 0 0 270)
			(layer "F.Fab")
			(effects
				(font
					(size 1.27 1.27)
				)
			)
		)
		(duplicate_pad_numbers_are_jumpers no)
		(fp_line
			(start -0.7874 0.4064)
			(end -0.7874 -0.4064)
			(stroke
				(width 0.1524)
				(type default)
			)
			(layer "F.SilkS")
		)
		(fp_line
			(start 0.7874 0.4064)
			(end -0.7874 0.4064)
			(stroke
				(width 0.1524)
				(type default)
			)
			(layer "F.SilkS")
		)
		(fp_line
			(start -0.7874 -0.4064)
			(end 0.7874 -0.4064)
			(stroke
				(width 0.1524)
				(type default)
			)
			(layer "F.SilkS")
		)
		(fp_line
			(start 0.7874 -0.4064)
			(end 0.7874 0.4064)
			(stroke
				(width 0.1524)
				(type default)
			)
			(layer "F.SilkS")
		)
		(fp_line
			(start -0.67945 0.3048)
			(end -0.67945 -0.305054)
			(stroke
				(width 0.1)
				(type default)
			)
			(layer "F.Fab")
		)
		(fp_line
			(start -0.12065 0.3048)
			(end -0.67945 0.3048)
			(stroke
				(width 0.1)
				(type default)
			)
			(layer "F.Fab")
		)
		(fp_line
			(start 0.120396 0.3048)
			(end 0.120396 0.2794)
			(stroke
				(width 0.1)
				(type default)
			)
			(layer "F.Fab")
		)
		(fp_line
			(start 0.67945 0.3048)
			(end 0.120396 0.3048)
			(stroke
				(width 0.1)
				(type default)
			)
			(layer "F.Fab")
		)
		(fp_line
			(start -0.12065 0.2794)
			(end -0.12065 0.3048)
			(stroke
				(width 0.1)
				(type default)
			)
			(layer "F.Fab")
		)
		(fp_line
			(start 0.120396 0.2794)
			(end -0.12065 0.2794)
			(stroke
				(width 0.1)
				(type default)
			)
			(layer "F.Fab")
		)
		(fp_line
			(start -0.12065 -0.2794)
			(end 0.12065 -0.2794)
			(stroke
				(width 0.1)
				(type default)
			)
			(layer "F.Fab")
		)
		(fp_line
			(start 0.12065 -0.2794)
			(end 0.12065 -0.3048)
			(stroke
				(width 0.1)
				(type default)
			)
			(layer "F.Fab")
		)
		(fp_line
			(start 0.12065 -0.3048)
			(end 0.67945 -0.3048)
			(stroke
				(width 0.1)
				(type default)
			)
			(layer "F.Fab")
		)
		(fp_line
			(start 0.67945 -0.3048)
			(end 0.67945 0.3048)
			(stroke
				(width 0.1)
				(type default)
			)
			(layer "F.Fab")
		)
		(fp_line
			(start -0.67945 -0.305054)
			(end -0.12065 -0.305054)
			(stroke
				(width 0.1)
				(type default)
			)
			(layer "F.Fab")
		)
		(fp_line
			(start -0.12065 -0.305054)
			(end -0.12065 -0.2794)
			(stroke
				(width 0.1)
				(type default)
			)
			(layer "F.Fab")
		)
		(pad "1" smd circle
			(at -0.40005 0 270)
			(size 0 0)
			(layers "F.Cu" "F.Mask" "F.Paste")
			(net "P1V25_SERDES_VDDPLL_PEX0")
		)
		(pad "2" smd circle
			(at 0.40005 0 270)
			(size 0 0)
			(layers "F.Cu" "F.Mask" "F.Paste")
			(net "P1V25_SERDES_VDDPLL_PEX0_C10")
		)
	)
	(footprint ""
		(layer "F.Cu")
		(at 8.049768 -159.844994 180)
		(property "Reference" "PR6870"
			(at 0 0 180)
			(layer "F.SilkS")
			(hide yes)
			(effects
				(font
					(size 1.27 1.27)
				)
			)
		)
		(property "Value" ""
			(at 0 0 180)
			(layer "F.Fab")
			(effects
				(font
					(size 1.27 1.27)
				)
			)
		)
		(duplicate_pad_numbers_are_jumpers no)
		(fp_line
			(start 0.7874 0.4064)
			(end -0.7874 0.4064)
			(stroke
				(width 0.1524)
				(type default)
			)
			(layer "F.SilkS")
		)
		(fp_line
			(start 0.7874 -0.4064)
			(end 0.7874 0.4064)
			(stroke
				(width 0.1524)
				(type default)
			)
			(layer "F.SilkS")
		)
		(fp_line
			(start -0.7874 0.4064)
			(end -0.7874 -0.4064)
			(stroke
				(width 0.1524)
				(type default)
			)
			(layer "F.SilkS")
		)
		(fp_line
			(start -0.7874 -0.4064)
			(end 0.7874 -0.4064)
			(stroke
				(width 0.1524)
				(type default)
			)
			(layer "F.SilkS")
		)
		(fp_line
			(start 0.67945 0.3048)
			(end 0.120396 0.3048)
			(stroke
				(width 0.1)
				(type default)
			)
			(layer "F.Fab")
		)
		(fp_line
			(start 0.67945 -0.3048)
			(end 0.67945 0.3048)
			(stroke
				(width 0.1)
				(type default)
			)
			(layer "F.Fab")
		)
		(fp_line
			(start 0.12065 -0.2794)
			(end 0.12065 -0.3048)
			(stroke
				(width 0.1)
				(type default)
			)
			(layer "F.Fab")
		)
		(fp_line
			(start 0.12065 -0.3048)
			(end 0.67945 -0.3048)
			(stroke
				(width 0.1)
				(type default)
			)
			(layer "F.Fab")
		)
		(fp_line
			(start 0.120396 0.3048)
			(end 0.120396 0.2794)
			(stroke
				(width 0.1)
				(type default)
			)
			(layer "F.Fab")
		)
		(fp_line
			(start 0.120396 0.2794)
			(end -0.12065 0.2794)
			(stroke
				(width 0.1)
				(type default)
			)
			(layer "F.Fab")
		)
		(fp_line
			(start -0.12065 0.3048)
			(end -0.67945 0.3048)
			(stroke
				(width 0.1)
				(type default)
			)
			(layer "F.Fab")
		)
		(fp_line
			(start -0.12065 0.2794)
			(end -0.12065 0.3048)
			(stroke
				(width 0.1)
				(type default)
			)
			(layer "F.Fab")
		)
		(fp_line
			(start -0.12065 -0.2794)
			(end 0.12065 -0.2794)
			(stroke
				(width 0.1)
				(type default)
			)
			(layer "F.Fab")
		)
		(fp_line
			(start -0.12065 -0.305054)
			(end -0.12065 -0.2794)
			(stroke
				(width 0.1)
				(type default)
			)
			(layer "F.Fab")
		)
		(fp_line
			(start -0.67945 0.3048)
			(end -0.67945 -0.305054)
			(stroke
				(width 0.1)
				(type default)
			)
			(layer "F.Fab")
		)
		(fp_line
			(start -0.67945 -0.305054)
			(end -0.12065 -0.305054)
			(stroke
				(width 0.1)
				(type default)
			)
			(layer "F.Fab")
		)
		(pad "1" smd circle
			(at -0.40005 0 180)
			(size 0 0)
			(layers "F.Cu" "F.Mask" "F.Paste")
			(net "P12V_NIC0_CO_FLTB")
		)
		(pad "2" smd circle
			(at 0.40005 0 180)
			(size 0 0)
			(layers "F.Cu" "F.Mask" "F.Paste")
			(net "P3V3_AUX")
		)
	)
	(footprint ""
		(layer "F.Cu")
		(at 374.543828 -44.87291)
		(property "Reference" "R639"
			(at 0 0 0)
			(layer "F.SilkS")
			(hide yes)
			(effects
				(font
					(size 1.27 1.27)
				)
			)
		)
		(property "Value" ""
			(at 0 0 0)
			(layer "F.Fab")
			(effects
				(font
					(size 1.27 1.27)
				)
			)
		)
		(duplicate_pad_numbers_are_jumpers no)
		(fp_line
			(start -0.7874 -0.4064)
			(end 0.7874 -0.4064)
			(stroke
				(width 0.1524)
				(type default)
			)
			(layer "F.SilkS")
		)
		(fp_line
			(start -0.7874 0.4064)
			(end -0.7874 -0.4064)
			(stroke
				(width 0.1524)
				(type default)
			)
			(layer "F.SilkS")
		)
		(fp_line
			(start 0.7874 -0.4064)
			(end 0.7874 0.4064)
			(stroke
				(width 0.1524)
				(type default)
			)
			(layer "F.SilkS")
		)
		(fp_line
			(start 0.7874 0.4064)
			(end -0.7874 0.4064)
			(stroke
				(width 0.1524)
				(type default)
			)
			(layer "F.SilkS")
		)
		(fp_line
			(start -0.67945 -0.305054)
			(end -0.12065 -0.305054)
			(stroke
				(width 0.1)
				(type default)
			)
			(layer "F.Fab")
		)
		(fp_line
			(start -0.67945 0.3048)
			(end -0.67945 -0.305054)
			(stroke
				(width 0.1)
				(type default)
			)
			(layer "F.Fab")
		)
		(fp_line
			(start -0.12065 -0.305054)
			(end -0.12065 -0.2794)
			(stroke
				(width 0.1)
				(type default)
			)
			(layer "F.Fab")
		)
		(fp_line
			(start -0.12065 -0.2794)
			(end 0.12065 -0.2794)
			(stroke
				(width 0.1)
				(type default)
			)
			(layer "F.Fab")
		)
		(fp_line
			(start -0.12065 0.2794)
			(end -0.12065 0.3048)
			(stroke
				(width 0.1)
				(type default)
			)
			(layer "F.Fab")
		)
		(fp_line
			(start -0.12065 0.3048)
			(end -0.67945 0.3048)
			(stroke
				(width 0.1)
				(type default)
			)
			(layer "F.Fab")
		)
		(fp_line
			(start 0.120396 0.2794)
			(end -0.12065 0.2794)
			(stroke
				(width 0.1)
				(type default)
			)
			(layer "F.Fab")
		)
		(fp_line
			(start 0.120396 0.3048)
			(end 0.120396 0.2794)
			(stroke
				(width 0.1)
				(type default)
			)
			(layer "F.Fab")
		)
		(fp_line
			(start 0.12065 -0.3048)
			(end 0.67945 -0.3048)
			(stroke
				(width 0.1)
				(type default)
			)
			(layer "F.Fab")
		)
		(fp_line
			(start 0.12065 -0.2794)
			(end 0.12065 -0.3048)
			(stroke
				(width 0.1)
				(type default)
			)
			(layer "F.Fab")
		)
		(fp_line
			(start 0.67945 -0.3048)
			(end 0.67945 0.3048)
			(stroke
				(width 0.1)
				(type default)
			)
			(layer "F.Fab")
		)
		(fp_line
			(start 0.67945 0.3048)
			(end 0.120396 0.3048)
			(stroke
				(width 0.1)
				(type default)
			)
			(layer "F.Fab")
		)
		(pad "1" smd circle
			(at -0.40005 0)
			(size 0 0)
			(layers "F.Cu" "F.Mask" "F.Paste")
			(net "SSD12_ADC_A0")
		)
		(pad "2" smd circle
			(at 0.40005 0)
			(size 0 0)
			(layers "F.Cu" "F.Mask" "F.Paste")
			(net "P3V3_AUX")
		)
	)
	(footprint ""
		(layer "F.Cu")
		(at 316.908942 -26.03373)
		(property "Reference" "R4074"
			(at 0 0 0)
			(layer "F.SilkS")
			(hide yes)
			(effects
				(font
					(size 1.27 1.27)
				)
			)
		)
		(property "Value" ""
			(at 0 0 0)
			(layer "F.Fab")
			(effects
				(font
					(size 1.27 1.27)
				)
			)
		)
		(duplicate_pad_numbers_are_jumpers no)
		(fp_line
			(start -0.7874 -0.4064)
			(end 0.7874 -0.4064)
			(stroke
				(width 0.1524)
				(type default)
			)
			(layer "F.SilkS")
		)
		(fp_line
			(start -0.7874 0.4064)
			(end -0.7874 -0.4064)
			(stroke
				(width 0.1524)
				(type default)
			)
			(layer "F.SilkS")
		)
		(fp_line
			(start 0.7874 -0.4064)
			(end 0.7874 0.4064)
			(stroke
				(width 0.1524)
				(type default)
			)
			(layer "F.SilkS")
		)
		(fp_line
			(start 0.7874 0.4064)
			(end -0.7874 0.4064)
			(stroke
				(width 0.1524)
				(type default)
			)
			(layer "F.SilkS")
		)
		(fp_line
			(start -0.67945 -0.305054)
			(end -0.12065 -0.305054)
			(stroke
				(width 0.1)
				(type default)
			)
			(layer "F.Fab")
		)
		(fp_line
			(start -0.67945 0.3048)
			(end -0.67945 -0.305054)
			(stroke
				(width 0.1)
				(type default)
			)
			(layer "F.Fab")
		)
		(fp_line
			(start -0.12065 -0.305054)
			(end -0.12065 -0.2794)
			(stroke
				(width 0.1)
				(type default)
			)
			(layer "F.Fab")
		)
		(fp_line
			(start -0.12065 -0.2794)
			(end 0.12065 -0.2794)
			(stroke
				(width 0.1)
				(type default)
			)
			(layer "F.Fab")
		)
		(fp_line
			(start -0.12065 0.2794)
			(end -0.12065 0.3048)
			(stroke
				(width 0.1)
				(type default)
			)
			(layer "F.Fab")
		)
		(fp_line
			(start -0.12065 0.3048)
			(end -0.67945 0.3048)
			(stroke
				(width 0.1)
				(type default)
			)
			(layer "F.Fab")
		)
		(fp_line
			(start 0.120396 0.2794)
			(end -0.12065 0.2794)
			(stroke
				(width 0.1)
				(type default)
			)
			(layer "F.Fab")
		)
		(fp_line
			(start 0.120396 0.3048)
			(end 0.120396 0.2794)
			(stroke
				(width 0.1)
				(type default)
			)
			(layer "F.Fab")
		)
		(fp_line
			(start 0.12065 -0.3048)
			(end 0.67945 -0.3048)
			(stroke
				(width 0.1)
				(type default)
			)
			(layer "F.Fab")
		)
		(fp_line
			(start 0.12065 -0.2794)
			(end 0.12065 -0.3048)
			(stroke
				(width 0.1)
				(type default)
			)
			(layer "F.Fab")
		)
		(fp_line
			(start 0.67945 -0.3048)
			(end 0.67945 0.3048)
			(stroke
				(width 0.1)
				(type default)
			)
			(layer "F.Fab")
		)
		(fp_line
			(start 0.67945 0.3048)
			(end 0.120396 0.3048)
			(stroke
				(width 0.1)
				(type default)
			)
			(layer "F.Fab")
		)
		(pad "1" smd circle
			(at -0.40005 0)
			(size 0 0)
			(layers "F.Cu" "F.Mask" "F.Paste")
			(net "P3V3_AUX")
		)
		(pad "2" smd circle
			(at 0.40005 0)
			(size 0 0)
			(layers "F.Cu" "F.Mask" "F.Paste")
			(net "PRSNT_SSD11_R_N")
		)
	)
	(footprint ""
		(layer "F.Cu")
		(at 175.0949 -104.830372 180)
		(property "Reference" "R173"
			(at 0 0 180)
			(layer "F.SilkS")
			(hide yes)
			(effects
				(font
					(size 1.27 1.27)
				)
			)
		)
		(property "Value" ""
			(at 0 0 180)
			(layer "F.Fab")
			(effects
				(font
					(size 1.27 1.27)
				)
			)
		)
		(duplicate_pad_numbers_are_jumpers no)
		(fp_line
			(start 0.7874 0.4064)
			(end -0.7874 0.4064)
			(stroke
				(width 0.1524)
				(type default)
			)
			(layer "F.SilkS")
		)
		(fp_line
			(start 0.7874 -0.4064)
			(end 0.7874 0.4064)
			(stroke
				(width 0.1524)
				(type default)
			)
			(layer "F.SilkS")
		)
		(fp_line
			(start -0.7874 0.4064)
			(end -0.7874 -0.4064)
			(stroke
				(width 0.1524)
				(type default)
			)
			(layer "F.SilkS")
		)
		(fp_line
			(start -0.7874 -0.4064)
			(end 0.7874 -0.4064)
			(stroke
				(width 0.1524)
				(type default)
			)
			(layer "F.SilkS")
		)
		(fp_line
			(start 0.67945 0.3048)
			(end 0.120396 0.3048)
			(stroke
				(width 0.1)
				(type default)
			)
			(layer "F.Fab")
		)
		(fp_line
			(start 0.67945 -0.3048)
			(end 0.67945 0.3048)
			(stroke
				(width 0.1)
				(type default)
			)
			(layer "F.Fab")
		)
		(fp_line
			(start 0.12065 -0.2794)
			(end 0.12065 -0.3048)
			(stroke
				(width 0.1)
				(type default)
			)
			(layer "F.Fab")
		)
		(fp_line
			(start 0.12065 -0.3048)
			(end 0.67945 -0.3048)
			(stroke
				(width 0.1)
				(type default)
			)
			(layer "F.Fab")
		)
		(fp_line
			(start 0.120396 0.3048)
			(end 0.120396 0.2794)
			(stroke
				(width 0.1)
				(type default)
			)
			(layer "F.Fab")
		)
		(fp_line
			(start 0.120396 0.2794)
			(end -0.12065 0.2794)
			(stroke
				(width 0.1)
				(type default)
			)
			(layer "F.Fab")
		)
		(fp_line
			(start -0.12065 0.3048)
			(end -0.67945 0.3048)
			(stroke
				(width 0.1)
				(type default)
			)
			(layer "F.Fab")
		)
		(fp_line
			(start -0.12065 0.2794)
			(end -0.12065 0.3048)
			(stroke
				(width 0.1)
				(type default)
			)
			(layer "F.Fab")
		)
		(fp_line
			(start -0.12065 -0.2794)
			(end 0.12065 -0.2794)
			(stroke
				(width 0.1)
				(type default)
			)
			(layer "F.Fab")
		)
		(fp_line
			(start -0.12065 -0.305054)
			(end -0.12065 -0.2794)
			(stroke
				(width 0.1)
				(type default)
			)
			(layer "F.Fab")
		)
		(fp_line
			(start -0.67945 0.3048)
			(end -0.67945 -0.305054)
			(stroke
				(width 0.1)
				(type default)
			)
			(layer "F.Fab")
		)
		(fp_line
			(start -0.67945 -0.305054)
			(end -0.12065 -0.305054)
			(stroke
				(width 0.1)
				(type default)
			)
			(layer "F.Fab")
		)
		(pad "1" smd circle
			(at -0.40005 0 180)
			(size 0 0)
			(layers "F.Cu" "F.Mask" "F.Paste")
			(net "CLK_50M_NIC3_RBT_REF")
		)
		(pad "2" smd circle
			(at 0.40005 0 180)
			(size 0 0)
			(layers "F.Cu" "F.Mask" "F.Paste")
			(net "GND")
		)
	)
	(footprint ""
		(layer "F.Cu")
		(at 395.590014 -72.766682 90)
		(property "Reference" "PR7090"
			(at 0 0 90)
			(layer "F.SilkS")
			(hide yes)
			(effects
				(font
					(size 1.27 1.27)
				)
			)
		)
		(property "Value" ""
			(at 0 0 90)
			(layer "F.Fab")
			(effects
				(font
					(size 1.27 1.27)
				)
			)
		)
		(duplicate_pad_numbers_are_jumpers no)
		(fp_line
			(start 0.7874 -0.4064)
			(end 0.7874 0.4064)
			(stroke
				(width 0.1524)
				(type default)
			)
			(layer "F.SilkS")
		)
		(fp_line
			(start -0.7874 -0.4064)
			(end 0.7874 -0.4064)
			(stroke
				(width 0.1524)
				(type default)
			)
			(layer "F.SilkS")
		)
		(fp_line
			(start 0.7874 0.4064)
			(end -0.7874 0.4064)
			(stroke
				(width 0.1524)
				(type default)
			)
			(layer "F.SilkS")
		)
		(fp_line
			(start -0.7874 0.4064)
			(end -0.7874 -0.4064)
			(stroke
				(width 0.1524)
				(type default)
			)
			(layer "F.SilkS")
		)
		(fp_line
			(start -0.12065 -0.305054)
			(end -0.12065 -0.2794)
			(stroke
				(width 0.1)
				(type default)
			)
			(layer "F.Fab")
		)
		(fp_line
			(start -0.67945 -0.305054)
			(end -0.12065 -0.305054)
			(stroke
				(width 0.1)
				(type default)
			)
			(layer "F.Fab")
		)
		(fp_line
			(start 0.67945 -0.3048)
			(end 0.67945 0.3048)
			(stroke
				(width 0.1)
				(type default)
			)
			(layer "F.Fab")
		)
		(fp_line
			(start 0.12065 -0.3048)
			(end 0.67945 -0.3048)
			(stroke
				(width 0.1)
				(type default)
			)
			(layer "F.Fab")
		)
		(fp_line
			(start 0.12065 -0.2794)
			(end 0.12065 -0.3048)
			(stroke
				(width 0.1)
				(type default)
			)
			(layer "F.Fab")
		)
		(fp_line
			(start -0.12065 -0.2794)
			(end 0.12065 -0.2794)
			(stroke
				(width 0.1)
				(type default)
			)
			(layer "F.Fab")
		)
		(fp_line
			(start 0.120396 0.2794)
			(end -0.12065 0.2794)
			(stroke
				(width 0.1)
				(type default)
			)
			(layer "F.Fab")
		)
		(fp_line
			(start -0.12065 0.2794)
			(end -0.12065 0.3048)
			(stroke
				(width 0.1)
				(type default)
			)
			(layer "F.Fab")
		)
		(fp_line
			(start 0.67945 0.3048)
			(end 0.120396 0.3048)
			(stroke
				(width 0.1)
				(type default)
			)
			(layer "F.Fab")
		)
		(fp_line
			(start 0.120396 0.3048)
			(end 0.120396 0.2794)
			(stroke
				(width 0.1)
				(type default)
			)
			(layer "F.Fab")
		)
		(fp_line
			(start -0.12065 0.3048)
			(end -0.67945 0.3048)
			(stroke
				(width 0.1)
				(type default)
			)
			(layer "F.Fab")
		)
		(fp_line
			(start -0.67945 0.3048)
			(end -0.67945 -0.305054)
			(stroke
				(width 0.1)
				(type default)
			)
			(layer "F.Fab")
		)
		(pad "1" smd circle
			(at -0.40005 0 90)
			(size 0 0)
			(layers "F.Cu" "F.Mask" "F.Paste")
			(net "P12V_SSD13_CO_ILIMIT")
		)
		(pad "2" smd circle
			(at 0.40005 0 90)
			(size 0 0)
			(layers "F.Cu" "F.Mask" "F.Paste")
			(net "GND")
		)
	)
	(footprint ""
		(layer "F.Cu")
		(at 57.294018 -34.248852)
		(property "Reference" "R5660"
			(at 0 0 0)
			(layer "F.SilkS")
			(hide yes)
			(effects
				(font
					(size 1.27 1.27)
				)
			)
		)
		(property "Value" ""
			(at 0 0 0)
			(layer "F.Fab")
			(effects
				(font
					(size 1.27 1.27)
				)
			)
		)
		(duplicate_pad_numbers_are_jumpers no)
		(fp_line
			(start -0.7874 -0.4064)
			(end 0.7874 -0.4064)
			(stroke
				(width 0.1524)
				(type default)
			)
			(layer "F.SilkS")
		)
		(fp_line
			(start -0.7874 0.4064)
			(end -0.7874 -0.4064)
			(stroke
				(width 0.1524)
				(type default)
			)
			(layer "F.SilkS")
		)
		(fp_line
			(start 0.7874 -0.4064)
			(end 0.7874 0.4064)
			(stroke
				(width 0.1524)
				(type default)
			)
			(layer "F.SilkS")
		)
		(fp_line
			(start 0.7874 0.4064)
			(end -0.7874 0.4064)
			(stroke
				(width 0.1524)
				(type default)
			)
			(layer "F.SilkS")
		)
		(fp_line
			(start -0.67945 -0.305054)
			(end -0.12065 -0.305054)
			(stroke
				(width 0.1)
				(type default)
			)
			(layer "F.Fab")
		)
		(fp_line
			(start -0.67945 0.3048)
			(end -0.67945 -0.305054)
			(stroke
				(width 0.1)
				(type default)
			)
			(layer "F.Fab")
		)
		(fp_line
			(start -0.12065 -0.305054)
			(end -0.12065 -0.2794)
			(stroke
				(width 0.1)
				(type default)
			)
			(layer "F.Fab")
		)
		(fp_line
			(start -0.12065 -0.2794)
			(end 0.12065 -0.2794)
			(stroke
				(width 0.1)
				(type default)
			)
			(layer "F.Fab")
		)
		(fp_line
			(start -0.12065 0.2794)
			(end -0.12065 0.3048)
			(stroke
				(width 0.1)
				(type default)
			)
			(layer "F.Fab")
		)
		(fp_line
			(start -0.12065 0.3048)
			(end -0.67945 0.3048)
			(stroke
				(width 0.1)
				(type default)
			)
			(layer "F.Fab")
		)
		(fp_line
			(start 0.120396 0.2794)
			(end -0.12065 0.2794)
			(stroke
				(width 0.1)
				(type default)
			)
			(layer "F.Fab")
		)
		(fp_line
			(start 0.120396 0.3048)
			(end 0.120396 0.2794)
			(stroke
				(width 0.1)
				(type default)
			)
			(layer "F.Fab")
		)
		(fp_line
			(start 0.12065 -0.3048)
			(end 0.67945 -0.3048)
			(stroke
				(width 0.1)
				(type default)
			)
			(layer "F.Fab")
		)
		(fp_line
			(start 0.12065 -0.2794)
			(end 0.12065 -0.3048)
			(stroke
				(width 0.1)
				(type default)
			)
			(layer "F.Fab")
		)
		(fp_line
			(start 0.67945 -0.3048)
			(end 0.67945 0.3048)
			(stroke
				(width 0.1)
				(type default)
			)
			(layer "F.Fab")
		)
		(fp_line
			(start 0.67945 0.3048)
			(end 0.120396 0.3048)
			(stroke
				(width 0.1)
				(type default)
			)
			(layer "F.Fab")
		)
		(pad "1" smd circle
			(at -0.40005 0)
			(size 0 0)
			(layers "F.Cu" "F.Mask" "F.Paste")
			(net "RST_SMB_SSD2_ISO_N")
		)
		(pad "2" smd circle
			(at 0.40005 0)
			(size 0 0)
			(layers "F.Cu" "F.Mask" "F.Paste")
			(net "P3V3_SSD2")
		)
	)
	(footprint ""
		(layer "F.Cu")
		(at 215.075516 -122.525028)
		(property "Reference" "C2883"
			(at 0 0 0)
			(layer "F.SilkS")
			(hide yes)
			(effects
				(font
					(size 1.27 1.27)
				)
			)
		)
		(property "Value" ""
			(at 0 0 0)
			(layer "F.Fab")
			(effects
				(font
					(size 1.27 1.27)
				)
			)
		)
		(duplicate_pad_numbers_are_jumpers no)
		(fp_line
			(start -0.7874 -0.4064)
			(end 0.7874 -0.4064)
			(stroke
				(width 0.1524)
				(type default)
			)
			(layer "F.SilkS")
		)
		(fp_line
			(start -0.7874 0.4064)
			(end -0.7874 -0.4064)
			(stroke
				(width 0.1524)
				(type default)
			)
			(layer "F.SilkS")
		)
		(fp_line
			(start 0.7874 -0.4064)
			(end 0.7874 0.4064)
			(stroke
				(width 0.1524)
				(type default)
			)
			(layer "F.SilkS")
		)
		(fp_line
			(start 0.7874 0.4064)
			(end -0.7874 0.4064)
			(stroke
				(width 0.1524)
				(type default)
			)
			(layer "F.SilkS")
		)
		(fp_line
			(start -0.67945 -0.305054)
			(end -0.12065 -0.305054)
			(stroke
				(width 0.1)
				(type default)
			)
			(layer "F.Fab")
		)
		(fp_line
			(start -0.67945 0.3048)
			(end -0.67945 -0.305054)
			(stroke
				(width 0.1)
				(type default)
			)
			(layer "F.Fab")
		)
		(fp_line
			(start -0.12065 -0.305054)
			(end -0.12065 -0.2794)
			(stroke
				(width 0.1)
				(type default)
			)
			(layer "F.Fab")
		)
		(fp_line
			(start -0.12065 -0.2794)
			(end 0.12065 -0.2794)
			(stroke
				(width 0.1)
				(type default)
			)
			(layer "F.Fab")
		)
		(fp_line
			(start -0.12065 0.2794)
			(end -0.12065 0.3048)
			(stroke
				(width 0.1)
				(type default)
			)
			(layer "F.Fab")
		)
		(fp_line
			(start -0.12065 0.3048)
			(end -0.67945 0.3048)
			(stroke
				(width 0.1)
				(type default)
			)
			(layer "F.Fab")
		)
		(fp_line
			(start 0.120396 0.2794)
			(end -0.12065 0.2794)
			(stroke
				(width 0.1)
				(type default)
			)
			(layer "F.Fab")
		)
		(fp_line
			(start 0.120396 0.3048)
			(end 0.120396 0.2794)
			(stroke
				(width 0.1)
				(type default)
			)
			(layer "F.Fab")
		)
		(fp_line
			(start 0.12065 -0.3048)
			(end 0.67945 -0.3048)
			(stroke
				(width 0.1)
				(type default)
			)
			(layer "F.Fab")
		)
		(fp_line
			(start 0.12065 -0.2794)
			(end 0.12065 -0.3048)
			(stroke
				(width 0.1)
				(type default)
			)
			(layer "F.Fab")
		)
		(fp_line
			(start 0.67945 -0.3048)
			(end 0.67945 0.3048)
			(stroke
				(width 0.1)
				(type default)
			)
			(layer "F.Fab")
		)
		(fp_line
			(start 0.67945 0.3048)
			(end 0.120396 0.3048)
			(stroke
				(width 0.1)
				(type default)
			)
			(layer "F.Fab")
		)
		(pad "1" smd circle
			(at -0.40005 0)
			(size 0 0)
			(layers "F.Cu" "F.Mask" "F.Paste")
			(net "HP_NIC3_EN")
		)
		(pad "2" smd circle
			(at 0.40005 0)
			(size 0 0)
			(layers "F.Cu" "F.Mask" "F.Paste")
			(net "GND")
		)
	)
	(footprint ""
		(layer "F.Cu")
		(at 26.57856 -308.611524 45)
		(property "Reference" "R4360"
			(at 0 0 45)
			(layer "F.SilkS")
			(hide yes)
			(effects
				(font
					(size 1.27 1.27)
				)
			)
		)
		(property "Value" ""
			(at 0 0 45)
			(layer "F.Fab")
			(effects
				(font
					(size 1.27 1.27)
				)
			)
		)
		(duplicate_pad_numbers_are_jumpers no)
		(fp_line
			(start -0.787389 -0.406267)
			(end 0.787389 -0.406267)
			(stroke
				(width 0.1524)
				(type default)
			)
			(layer "F.SilkS")
		)
		(fp_line
			(start -0.787389 0.406267)
			(end -0.787389 -0.406267)
			(stroke
				(width 0.1524)
				(type default)
			)
			(layer "F.SilkS")
		)
		(fp_line
			(start 0.787389 -0.406267)
			(end 0.787389 0.406267)
			(stroke
				(width 0.1524)
				(type default)
			)
			(layer "F.SilkS")
		)
		(fp_line
			(start 0.787389 0.406267)
			(end -0.787389 0.406267)
			(stroke
				(width 0.1524)
				(type default)
			)
			(layer "F.SilkS")
		)
		(fp_line
			(start -0.679446 -0.305149)
			(end -0.120695 -0.304969)
			(stroke
				(width 0.1)
				(type default)
			)
			(layer "F.Fab")
		)
		(fp_line
			(start -0.120695 -0.304969)
			(end -0.120695 -0.279466)
			(stroke
				(width 0.1)
				(type default)
			)
			(layer "F.Fab")
		)
		(fp_line
			(start -0.120695 -0.279466)
			(end 0.120695 -0.279466)
			(stroke
				(width 0.1)
				(type default)
			)
			(layer "F.Fab")
		)
		(fp_line
			(start -0.679446 0.30479)
			(end -0.679446 -0.305149)
			(stroke
				(width 0.1)
				(type default)
			)
			(layer "F.Fab")
		)
		(fp_line
			(start 0.120515 -0.30479)
			(end 0.679446 -0.30479)
			(stroke
				(width 0.1)
				(type default)
			)
			(layer "F.Fab")
		)
		(fp_line
			(start 0.120695 -0.279466)
			(end 0.120515 -0.30479)
			(stroke
				(width 0.1)
				(type default)
			)
			(layer "F.Fab")
		)
		(fp_line
			(start -0.120695 0.279466)
			(end -0.120515 0.30479)
			(stroke
				(width 0.1)
				(type default)
			)
			(layer "F.Fab")
		)
		(fp_line
			(start -0.120515 0.30479)
			(end -0.679446 0.30479)
			(stroke
				(width 0.1)
				(type default)
			)
			(layer "F.Fab")
		)
		(fp_line
			(start 0.679446 -0.30479)
			(end 0.679446 0.30479)
			(stroke
				(width 0.1)
				(type default)
			)
			(layer "F.Fab")
		)
		(fp_line
			(start 0.120335 0.279466)
			(end -0.120695 0.279466)
			(stroke
				(width 0.1)
				(type default)
			)
			(layer "F.Fab")
		)
		(fp_line
			(start 0.120515 0.30479)
			(end 0.120335 0.279466)
			(stroke
				(width 0.1)
				(type default)
			)
			(layer "F.Fab")
		)
		(fp_line
			(start 0.679446 0.30479)
			(end 0.120515 0.30479)
			(stroke
				(width 0.1)
				(type default)
			)
			(layer "F.Fab")
		)
		(pad "1" smd circle
			(at -0.40005 0 45)
			(size 0 0)
			(layers "F.Cu" "F.Mask" "F.Paste")
			(net "P1V8_PEX")
		)
		(pad "2" smd circle
			(at 0.40005 0 45)
			(size 0 0)
			(layers "F.Cu" "F.Mask" "F.Paste")
			(net "IRQ_PEX0_CLKREQ_INT_N")
		)
	)
	(footprint ""
		(layer "F.Cu")
		(at 103.7082 -193.7512)
		(property "Reference" "U435"
			(at -4.172458 -9.46658 0)
			(unlocked yes)
			(layer "F.SilkS")
			(effects
				(font
					(size 0.7874 0.5842)
					(thickness 0.1524)
				)
				(justify left)
			)
		)
		(property "Value" ""
			(at 0 0 0)
			(layer "F.Fab")
			(effects
				(font
					(size 1.27 1.27)
				)
			)
		)
		(duplicate_pad_numbers_are_jumpers no)
		(fp_line
			(start -6.1214 0.750062)
			(end -5.1054 0.750062)
			(stroke
				(width 0.1524)
				(type default)
			)
			(layer "F.SilkS")
		)
		(fp_line
			(start -5.08 -1.75006)
			(end -5.588 -1.75006)
			(stroke
				(width 0.1524)
				(type default)
			)
			(layer "F.SilkS")
		)
		(fp_line
			(start -5.08 3.24993)
			(end -5.588 3.24993)
			(stroke
				(width 0.1524)
				(type default)
			)
			(layer "F.SilkS")
		)
		(fp_line
			(start -4.500118 -4.500118)
			(end -4.500118 -4.0386)
			(stroke
				(width 0.1524)
				(type default)
			)
			(layer "F.SilkS")
		)
		(fp_line
			(start -4.500118 4.0386)
			(end -4.500118 4.500118)
			(stroke
				(width 0.1524)
				(type default)
			)
			(layer "F.SilkS")
		)
		(fp_line
			(start -4.500118 4.500118)
			(end -4.0386 4.500118)
			(stroke
				(width 0.1524)
				(type default)
			)
			(layer "F.SilkS")
		)
		(fp_line
			(start -4.0386 -4.500118)
			(end -4.500118 -4.500118)
			(stroke
				(width 0.1524)
				(type default)
			)
			(layer "F.SilkS")
		)
		(fp_line
			(start -2.249932 5.0292)
			(end -2.249932 6.0452)
			(stroke
				(width 0.1524)
				(type default)
			)
			(layer "F.SilkS")
		)
		(fp_line
			(start -1.75006 -6.0706)
			(end -1.75006 -5.0546)
			(stroke
				(width 0.1524)
				(type default)
			)
			(layer "F.SilkS")
		)
		(fp_line
			(start 0.249936 5.0292)
			(end 0.249936 5.5372)
			(stroke
				(width 0.1524)
				(type default)
			)
			(layer "F.SilkS")
		)
		(fp_line
			(start 0.750062 -5.588)
			(end 0.750062 -5.08)
			(stroke
				(width 0.1524)
				(type default)
			)
			(layer "F.SilkS")
		)
		(fp_line
			(start 2.750058 5.0546)
			(end 2.750058 6.0706)
			(stroke
				(width 0.1524)
				(type default)
			)
			(layer "F.SilkS")
		)
		(fp_line
			(start 3.24993 -6.0706)
			(end 3.24993 -5.0546)
			(stroke
				(width 0.1524)
				(type default)
			)
			(layer "F.SilkS")
		)
		(fp_line
			(start 4.0386 4.500118)
			(end 4.500118 4.500118)
			(stroke
				(width 0.1524)
				(type default)
			)
			(layer "F.SilkS")
		)
		(fp_line
			(start 4.500118 -4.500118)
			(end 4.0386 -4.500118)
			(stroke
				(width 0.1524)
				(type default)
			)
			(layer "F.SilkS")
		)
		(fp_line
			(start 4.500118 -4.0386)
			(end 4.500118 -4.500118)
			(stroke
				(width 0.1524)
				(type default)
			)
			(layer "F.SilkS")
		)
		(fp_line
			(start 4.500118 4.500118)
			(end 4.500118 4.0386)
			(stroke
				(width 0.1524)
				(type default)
			)
			(layer "F.SilkS")
		)
		(fp_line
			(start 5.0292 0.249936)
			(end 6.0452 0.249936)
			(stroke
				(width 0.1524)
				(type default)
			)
			(layer "F.SilkS")
		)
		(fp_line
			(start 5.5372 -2.249932)
			(end 5.0292 -2.249932)
			(stroke
				(width 0.1524)
				(type default)
			)
			(layer "F.SilkS")
		)
		(fp_line
			(start 5.5372 2.750058)
			(end 5.0292 2.750058)
			(stroke
				(width 0.1524)
				(type default)
			)
			(layer "F.SilkS")
		)
		(fp_poly
			(pts
				(xy -6.0452 -4.258056) (xy -6.0452 -3.242056) (xy -5.0292 -3.750056)
			)
			(stroke
				(width 0)
				(type default)
			)
			(fill yes)
			(layer "F.SilkS")
		)
		(fp_line
			(start -6.1214 0.750062)
			(end -5.1054 0.750062)
			(stroke
				(width 0.1)
				(type default)
			)
			(layer "F.Fab")
		)
		(fp_line
			(start -5.08 -1.75006)
			(end -5.588 -1.75006)
			(stroke
				(width 0.1)
				(type default)
			)
			(layer "F.Fab")
		)
		(fp_line
			(start -5.08 3.24993)
			(end -5.588 3.24993)
			(stroke
				(width 0.1)
				(type default)
			)
			(layer "F.Fab")
		)
		(fp_line
			(start -4.500118 -4.500118)
			(end -4.500118 4.500118)
			(stroke
				(width 0.1)
				(type default)
			)
			(layer "F.Fab")
		)
		(fp_line
			(start -4.500118 4.500118)
			(end 4.500118 4.500118)
			(stroke
				(width 0.1)
				(type default)
			)
			(layer "F.Fab")
		)
		(fp_line
			(start -2.249932 5.0292)
			(end -2.249932 6.0452)
			(stroke
				(width 0.1)
				(type default)
			)
			(layer "F.Fab")
		)
		(fp_line
			(start -1.75006 -6.0706)
			(end -1.75006 -5.0546)
			(stroke
				(width 0.1)
				(type default)
			)
			(layer "F.Fab")
		)
		(fp_line
			(start 0.249936 5.0292)
			(end 0.249936 5.5372)
			(stroke
				(width 0.1)
				(type default)
			)
			(layer "F.Fab")
		)
		(fp_line
			(start 0.750062 -5.588)
			(end 0.750062 -5.08)
			(stroke
				(width 0.1)
				(type default)
			)
			(layer "F.Fab")
		)
		(fp_line
			(start 2.750058 5.0546)
			(end 2.750058 6.0706)
			(stroke
				(width 0.1)
				(type default)
			)
			(layer "F.Fab")
		)
		(fp_line
			(start 3.24993 -6.0706)
			(end 3.24993 -5.0546)
			(stroke
				(width 0.1)
				(type default)
			)
			(layer "F.Fab")
		)
		(fp_line
			(start 4.500118 -4.500118)
			(end -4.500118 -4.500118)
			(stroke
				(width 0.1)
				(type default)
			)
			(layer "F.Fab")
		)
		(fp_line
			(start 4.500118 4.500118)
			(end 4.500118 -4.500118)
			(stroke
				(width 0.1)
				(type default)
			)
			(layer "F.Fab")
		)
		(fp_line
			(start 5.0292 0.249936)
			(end 6.0452 0.249936)
			(stroke
				(width 0.1)
				(type default)
			)
			(layer "F.Fab")
		)
		(fp_line
			(start 5.5372 -2.249932)
			(end 5.0292 -2.249932)
			(stroke
				(width 0.1)
				(type default)
			)
			(layer "F.Fab")
		)
		(fp_line
			(start 5.5372 2.750058)
			(end 5.0292 2.750058)
			(stroke
				(width 0.1)
				(type default)
			)
			(layer "F.Fab")
		)
		(fp_poly
			(pts
				(xy -6.0452 -4.258056) (xy -6.0452 -3.242056) (xy -5.0292 -3.750056)
			)
			(stroke
				(width 0)
				(type default)
			)
			(fill yes)
			(layer "F.Fab")
		)
		(fp_text user "64"
			(at -5.334 -5.878068 0)
			(unlocked yes)
			(layer "F.SilkS")
			(effects
				(font
					(size 0.7874 0.5842)
					(thickness 0.1524)
				)
			)
		)
		(fp_text user "16"
			(at -5.182616 5.540248 270)
			(unlocked yes)
			(layer "F.SilkS")
			(effects
				(font
					(size 0.7874 0.5842)
					(thickness 0.1524)
				)
			)
		)
		(fp_text user "17"
			(at -3.945128 5.684266 0)
			(unlocked yes)
			(layer "F.SilkS")
			(effects
				(font
					(size 0.7874 0.5842)
					(thickness 0.1524)
				)
			)
		)
		(fp_text user "32"
			(at 4.445 5.496052 0)
			(unlocked yes)
			(layer "F.SilkS")
			(effects
				(font
					(size 0.7874 0.5842)
					(thickness 0.1524)
				)
			)
		)
		(fp_text user "33"
			(at 5.425948 4.318 270)
			(unlocked yes)
			(layer "F.SilkS")
			(effects
				(font
					(size 0.7874 0.5842)
					(thickness 0.1524)
				)
			)
		)
		(fp_text user "49"
			(at 5.761482 -6.223508 0)
			(unlocked yes)
			(layer "F.SilkS")
			(effects
				(font
					(size 0.7874 0.5842)
					(thickness 0.1524)
				)
			)
		)
		(fp_text user "48"
			(at 6.319266 -4.930902 270)
			(unlocked yes)
			(layer "F.SilkS")
			(effects
				(font
					(size 0.7874 0.5842)
					(thickness 0.1524)
				)
			)
		)
		(fp_text user "16"
			(at -5.496052 4.318 270)
			(unlocked yes)
			(layer "F.Fab")
			(effects
				(font
					(size 0.7874 0.5842)
					(thickness 0.1524)
				)
			)
		)
		(fp_text user "64"
			(at -4.572 -5.298948 0)
			(unlocked yes)
			(layer "F.Fab")
			(effects
				(font
					(size 0.7874 0.5842)
					(thickness 0.1524)
				)
			)
		)
		(fp_text user "17"
			(at -4.572 5.496052 0)
			(unlocked yes)
			(layer "F.Fab")
			(effects
				(font
					(size 0.7874 0.5842)
					(thickness 0.1524)
				)
			)
		)
		(fp_text user "49"
			(at 4.445 -5.298948 0)
			(unlocked yes)
			(layer "F.Fab")
			(effects
				(font
					(size 0.7874 0.5842)
					(thickness 0.1524)
				)
			)
		)
		(fp_text user "32"
			(at 4.445 5.496052 0)
			(unlocked yes)
			(layer "F.Fab")
			(effects
				(font
					(size 0.7874 0.5842)
					(thickness 0.1524)
				)
			)
		)
		(fp_text user "48"
			(at 5.425948 -4.445 270)
			(unlocked yes)
			(layer "F.Fab")
			(effects
				(font
					(size 0.7874 0.5842)
					(thickness 0.1524)
				)
			)
		)
		(fp_text user "33"
			(at 5.425948 4.318 270)
			(unlocked yes)
			(layer "F.Fab")
			(effects
				(font
					(size 0.7874 0.5842)
					(thickness 0.1524)
				)
			)
		)
		(pad "1" smd circle
			(at -4.45008 -3.750056 270)
			(size 0 0)
			(layers "F.Cu" "F.Mask" "F.Paste")
			(net "UART_PEX3_CLI_CP2108_TX")
		)
		(pad "2" smd circle
			(at -4.45008 -3.24993 270)
			(size 0 0)
			(layers "F.Cu" "F.Mask" "F.Paste")
			(net "GND")
		)
		(pad "3" smd circle
			(at -4.45008 -2.750058 270)
			(size 0 0)
			(layers "F.Cu" "F.Mask" "F.Paste")
			(net "P3V3_AUX")
		)
		(pad "4" smd circle
			(at -4.45008 -2.249932 270)
			(size 0 0)
			(layers "F.Cu" "F.Mask" "F.Paste")
			(net "UART_PEX3_CLI_CP2108_RX")
		)
		(pad "5" smd circle
			(at -4.45008 -1.75006 270)
			(size 0 0)
			(layers "F.Cu" "F.Mask" "F.Paste")
			(net "Net_9243")
		)
		(pad "6" smd circle
			(at -4.45008 -1.249934 270)
			(size 0 0)
			(layers "F.Cu" "F.Mask" "F.Paste")
			(net "Net_9205")
		)
		(pad "7" smd circle
			(at -4.45008 -0.750062 270)
			(size 0 0)
			(layers "F.Cu" "F.Mask" "F.Paste")
			(net "Net_9209")
		)
		(pad "8" smd circle
			(at -4.45008 -0.249936 270)
			(size 0 0)
			(layers "F.Cu" "F.Mask" "F.Paste")
			(net "Net_9239")
		)
		(pad "9" smd circle
			(at -4.45008 0.249936 270)
			(size 0 0)
			(layers "F.Cu" "F.Mask" "F.Paste")
			(net "Net_9235")
		)
		(pad "10" smd circle
			(at -4.45008 0.750062 270)
			(size 0 0)
			(layers "F.Cu" "F.Mask" "F.Paste")
			(net "Net_9231")
		)
		(pad "11" smd circle
			(at -4.45008 1.249934 270)
			(size 0 0)
			(layers "F.Cu" "F.Mask" "F.Paste")
			(net "Net_9210")
		)
		(pad "12" smd circle
			(at -4.45008 1.75006 270)
			(size 0 0)
			(layers "F.Cu" "F.Mask" "F.Paste")
			(net "Net_9240")
		)
		(pad "13" smd circle
			(at -4.45008 2.249932 270)
			(size 0 0)
			(layers "F.Cu" "F.Mask" "F.Paste")
			(net "Net_9244")
		)
		(pad "14" smd circle
			(at -4.45008 2.750058 270)
			(size 0 0)
			(layers "F.Cu" "F.Mask" "F.Paste")
			(net "Net_9206")
		)
		(pad "15" smd circle
			(at -4.45008 3.24993 270)
			(size 0 0)
			(layers "F.Cu" "F.Mask" "F.Paste")
			(net "UART_PEX2_CLI_CP2108_TX")
		)
		(pad "16" smd circle
			(at -4.45008 3.750056 270)
			(size 0 0)
			(layers "F.Cu" "F.Mask" "F.Paste")
			(net "UART_PEX2_CLI_CP2108_RX")
		)
		(pad "17" smd circle
			(at -3.750056 4.45008)
			(size 0 0)
			(layers "F.Cu" "F.Mask" "F.Paste")
			(net "Net_9236")
		)
		(pad "18" smd circle
			(at -3.24993 4.45008)
			(size 0 0)
			(layers "F.Cu" "F.Mask" "F.Paste")
			(net "Net_9232")
		)
		(pad "19" smd circle
			(at -2.750058 4.45008)
			(size 0 0)
			(layers "F.Cu" "F.Mask" "F.Paste")
			(net "Net_9203")
		)
		(pad "20" smd circle
			(at -2.249932 4.45008)
			(size 0 0)
			(layers "F.Cu" "F.Mask" "F.Paste")
			(net "Net_9204")
		)
		(pad "21" smd circle
			(at -1.75006 4.45008)
			(size 0 0)
			(layers "F.Cu" "F.Mask" "F.Paste")
			(net "Net_9223")
		)
		(pad "22" smd circle
			(at -1.249934 4.45008)
			(size 0 0)
			(layers "F.Cu" "F.Mask" "F.Paste")
			(net "Net_9224")
		)
		(pad "23" smd circle
			(at -0.750062 4.45008)
			(size 0 0)
			(layers "F.Cu" "F.Mask" "F.Paste")
			(net "Net_9225")
		)
		(pad "24" smd circle
			(at -0.249936 4.45008)
			(size 0 0)
			(layers "F.Cu" "F.Mask" "F.Paste")
			(net "P3V3_AUX")
		)
		(pad "25" smd circle
			(at 0.249936 4.45008)
			(size 0 0)
			(layers "F.Cu" "F.Mask" "F.Paste")
			(net "GND")
		)
		(pad "26" smd circle
			(at 0.750062 4.45008)
			(size 0 0)
			(layers "F.Cu" "F.Mask" "F.Paste")
			(net "Net_9226")
		)
		(pad "27" smd circle
			(at 1.249934 4.45008)
			(size 0 0)
			(layers "F.Cu" "F.Mask" "F.Paste")
			(net "Net_9227")
		)
		(pad "28" smd circle
			(at 1.75006 4.45008)
			(size 0 0)
			(layers "F.Cu" "F.Mask" "F.Paste")
			(net "Net_9228")
		)
		(pad "29" smd circle
			(at 2.249932 4.45008)
			(size 0 0)
			(layers "F.Cu" "F.Mask" "F.Paste")
			(net "Net_9215")
		)
		(pad "30" smd circle
			(at 2.750058 4.45008)
			(size 0 0)
			(layers "F.Cu" "F.Mask" "F.Paste")
			(net "Net_9216")
		)
		(pad "31" smd circle
			(at 3.24993 4.45008)
			(size 0 0)
			(layers "F.Cu" "F.Mask" "F.Paste")
			(net "Net_9217")
		)
		(pad "32" smd circle
			(at 3.750056 4.45008)
			(size 0 0)
			(layers "F.Cu" "F.Mask" "F.Paste")
			(net "Net_9218")
		)
		(pad "33" smd circle
			(at 4.45008 3.750056 90)
			(size 0 0)
			(layers "F.Cu" "F.Mask" "F.Paste")
			(net "Net_9219")
		)
		(pad "34" smd circle
			(at 4.45008 3.24993 90)
			(size 0 0)
			(layers "F.Cu" "F.Mask" "F.Paste")
			(net "Net_9220")
		)
		(pad "35" smd circle
			(at 4.45008 2.750058 90)
			(size 0 0)
			(layers "F.Cu" "F.Mask" "F.Paste")
			(net "Net_9214")
		)
		(pad "36" smd circle
			(at 4.45008 2.249932 90)
			(size 0 0)
			(layers "F.Cu" "F.Mask" "F.Paste")
			(net "Net_9213")
		)
		(pad "37" smd circle
			(at 4.45008 1.75006 90)
			(size 0 0)
			(layers "F.Cu" "F.Mask" "F.Paste")
			(net "Net_9221")
		)
		(pad "38" smd circle
			(at 4.45008 1.249934 90)
			(size 0 0)
			(layers "F.Cu" "F.Mask" "F.Paste")
			(net "Net_9222")
		)
		(pad "39" smd circle
			(at 4.45008 0.750062 90)
			(size 0 0)
			(layers "F.Cu" "F.Mask" "F.Paste")
			(net "P3V3_AUX")
		)
		(pad "40" smd circle
			(at 4.45008 0.249936 90)
			(size 0 0)
			(layers "F.Cu" "F.Mask" "F.Paste")
			(net "Net_9229")
		)
		(pad "41" smd circle
			(at 4.45008 -0.249936 90)
			(size 0 0)
			(layers "F.Cu" "F.Mask" "F.Paste")
			(net "Net_9230")
		)
		(pad "42" smd circle
			(at 4.45008 -0.750062 90)
			(size 0 0)
			(layers "F.Cu" "F.Mask" "F.Paste")
			(net "Net_9211")
		)
		(pad "43" smd circle
			(at 4.45008 -1.249934 90)
			(size 0 0)
			(layers "F.Cu" "F.Mask" "F.Paste")
			(net "Net_9241")
		)
		(pad "44" smd circle
			(at 4.45008 -1.75006 90)
			(size 0 0)
			(layers "F.Cu" "F.Mask" "F.Paste")
			(net "Net_9237")
		)
		(pad "45" smd circle
			(at 4.45008 -2.249932 90)
			(size 0 0)
			(layers "F.Cu" "F.Mask" "F.Paste")
			(net "Net_9233")
		)
		(pad "46" smd circle
			(at 4.45008 -2.750058 90)
			(size 0 0)
			(layers "F.Cu" "F.Mask" "F.Paste")
			(net "Net_9245")
		)
		(pad "47" smd circle
			(at 4.45008 -3.24993 90)
			(size 0 0)
			(layers "F.Cu" "F.Mask" "F.Paste")
			(net "Net_9207")
		)
		(pad "48" smd circle
			(at 4.45008 -3.750056 90)
			(size 0 0)
			(layers "F.Cu" "F.Mask" "F.Paste")
			(net "UART_PEX1_CLI_CP2108_TX")
		)
		(pad "49" smd circle
			(at 3.750056 -4.45008 180)
			(size 0 0)
			(layers "F.Cu" "F.Mask" "F.Paste")
			(net "UART_PEX1_CLI_CP2108_RX")
		)
		(pad "50" smd circle
			(at 3.24993 -4.45008 180)
			(size 0 0)
			(layers "F.Cu" "F.Mask" "F.Paste")
			(net "Net_9212")
		)
		(pad "51" smd circle
			(at 2.750058 -4.45008 180)
			(size 0 0)
			(layers "F.Cu" "F.Mask" "F.Paste")
			(net "Net_9242")
		)
		(pad "52" smd circle
			(at 2.249932 -4.45008 180)
			(size 0 0)
			(layers "F.Cu" "F.Mask" "F.Paste")
			(net "Net_9238")
		)
		(pad "53" smd circle
			(at 1.75006 -4.45008 180)
			(size 0 0)
			(layers "F.Cu" "F.Mask" "F.Paste")
			(net "Net_9234")
		)
		(pad "54" smd circle
			(at 1.249934 -4.45008 180)
			(size 0 0)
			(layers "F.Cu" "F.Mask" "F.Paste")
			(net "Net_9246")
		)
		(pad "55" smd circle
			(at 0.750062 -4.45008 180)
			(size 0 0)
			(layers "F.Cu" "F.Mask" "F.Paste")
			(net "Net_9208")
		)
		(pad "56" smd circle
			(at 0.249936 -4.45008 180)
			(size 0 0)
			(layers "F.Cu" "F.Mask" "F.Paste")
			(net "UART_PEX0_CLI_CP2108_TX")
		)
		(pad "57" smd circle
			(at -0.249936 -4.45008 180)
			(size 0 0)
			(layers "F.Cu" "F.Mask" "F.Paste")
			(net "UART_PEX0_CLI_CP2108_RX")
		)
		(pad "58" smd circle
			(at -0.750062 -4.45008 180)
			(size 0 0)
			(layers "F.Cu" "F.Mask" "F.Paste")
			(net "P3V3_AUX")
		)
		(pad "59" smd circle
			(at -1.249934 -4.45008 180)
			(size 0 0)
			(layers "F.Cu" "F.Mask" "F.Paste")
			(net "GND")
		)
		(pad "60" smd circle
			(at -1.75006 -4.45008 180)
			(size 0 0)
			(layers "F.Cu" "F.Mask" "F.Paste")
			(net "P3V3_AUX")
		)
		(pad "61" smd circle
			(at -2.249932 -4.45008 180)
			(size 0 0)
			(layers "F.Cu" "F.Mask" "F.Paste")
			(net "P3V3_AUX")
		)
		(pad "62" smd circle
			(at -2.750058 -4.45008 180)
			(size 0 0)
			(layers "F.Cu" "F.Mask" "F.Paste")
			(net "USB2_CP2108_CLI_DP")
		)
		(pad "63" smd circle
			(at -3.24993 -4.45008 180)
			(size 0 0)
			(layers "F.Cu" "F.Mask" "F.Paste")
			(net "USB2_CP2108_CLI_DN")
		)
		(pad "64" smd circle
			(at -3.750056 -4.45008 180)
			(size 0 0)
			(layers "F.Cu" "F.Mask" "F.Paste")
			(net "RST_CP2108_CLI_R_N")
		)
		(pad "TH" smd rect
			(at 0 0)
			(size 4.2672 4.2672)
			(layers "F.Cu" "F.Mask" "F.Paste")
			(net "GND")
		)
		(zone
			(layer "F.Cu")
			(hatch none 0.5)
			(connect_pads
				(clearance 0)
			)
			(min_thickness 0.25)
			(keepout
				(tracks not_allowed)
				(vias allowed)
				(pads allowed)
				(copperpour not_allowed)
				(footprints allowed)
			)
			(placement
				(enabled no)
				(sheetname "")
			)
			(fill
				(thermal_gap 0.5)
				(thermal_bridge_width 0.5)
				(island_removal_mode 0)
			)
			(polygon
				(pts
					(xy 99.7458 -194.5132) (xy 99.7458 -189.7888) (xy 107.6706 -189.7888) (xy 107.6706 -197.7136) (xy 99.7458 -197.7136)
					(xy 99.7458 -194.5386) (xy 101.5238 -194.5386) (xy 101.5238 -195.9356) (xy 105.8926 -195.9356)
					(xy 105.8926 -191.5668) (xy 101.5238 -191.5668) (xy 101.5238 -194.5132)
				)
			)
		)
	)
	(footprint ""
		(layer "F.Cu")
		(at 304.714402 -66.32194 90)
		(property "Reference" "R6000"
			(at 0 0 90)
			(layer "F.SilkS")
			(hide yes)
			(effects
				(font
					(size 1.27 1.27)
				)
			)
		)
		(property "Value" ""
			(at 0 0 90)
			(layer "F.Fab")
			(effects
				(font
					(size 1.27 1.27)
				)
			)
		)
		(duplicate_pad_numbers_are_jumpers no)
		(fp_line
			(start 0.7874 -0.4064)
			(end 0.7874 0.4064)
			(stroke
				(width 0.1524)
				(type default)
			)
			(layer "F.SilkS")
		)
		(fp_line
			(start -0.7874 -0.4064)
			(end 0.7874 -0.4064)
			(stroke
				(width 0.1524)
				(type default)
			)
			(layer "F.SilkS")
		)
		(fp_line
			(start 0.7874 0.4064)
			(end -0.7874 0.4064)
			(stroke
				(width 0.1524)
				(type default)
			)
			(layer "F.SilkS")
		)
		(fp_line
			(start -0.7874 0.4064)
			(end -0.7874 -0.4064)
			(stroke
				(width 0.1524)
				(type default)
			)
			(layer "F.SilkS")
		)
		(fp_line
			(start -0.12065 -0.305054)
			(end -0.12065 -0.2794)
			(stroke
				(width 0.1)
				(type default)
			)
			(layer "F.Fab")
		)
		(fp_line
			(start -0.67945 -0.305054)
			(end -0.12065 -0.305054)
			(stroke
				(width 0.1)
				(type default)
			)
			(layer "F.Fab")
		)
		(fp_line
			(start 0.67945 -0.3048)
			(end 0.67945 0.3048)
			(stroke
				(width 0.1)
				(type default)
			)
			(layer "F.Fab")
		)
		(fp_line
			(start 0.12065 -0.3048)
			(end 0.67945 -0.3048)
			(stroke
				(width 0.1)
				(type default)
			)
			(layer "F.Fab")
		)
		(fp_line
			(start 0.12065 -0.2794)
			(end 0.12065 -0.3048)
			(stroke
				(width 0.1)
				(type default)
			)
			(layer "F.Fab")
		)
		(fp_line
			(start -0.12065 -0.2794)
			(end 0.12065 -0.2794)
			(stroke
				(width 0.1)
				(type default)
			)
			(layer "F.Fab")
		)
		(fp_line
			(start 0.120396 0.2794)
			(end -0.12065 0.2794)
			(stroke
				(width 0.1)
				(type default)
			)
			(layer "F.Fab")
		)
		(fp_line
			(start -0.12065 0.2794)
			(end -0.12065 0.3048)
			(stroke
				(width 0.1)
				(type default)
			)
			(layer "F.Fab")
		)
		(fp_line
			(start 0.67945 0.3048)
			(end 0.120396 0.3048)
			(stroke
				(width 0.1)
				(type default)
			)
			(layer "F.Fab")
		)
		(fp_line
			(start 0.120396 0.3048)
			(end 0.120396 0.2794)
			(stroke
				(width 0.1)
				(type default)
			)
			(layer "F.Fab")
		)
		(fp_line
			(start -0.12065 0.3048)
			(end -0.67945 0.3048)
			(stroke
				(width 0.1)
				(type default)
			)
			(layer "F.Fab")
		)
		(fp_line
			(start -0.67945 0.3048)
			(end -0.67945 -0.305054)
			(stroke
				(width 0.1)
				(type default)
			)
			(layer "F.Fab")
		)
		(pad "1" smd circle
			(at -0.40005 0 90)
			(size 0 0)
			(layers "F.Cu" "F.Mask" "F.Paste")
			(net "SSD10_PWR_EN_R")
		)
		(pad "2" smd circle
			(at 0.40005 0 90)
			(size 0 0)
			(layers "F.Cu" "F.Mask" "F.Paste")
			(net "P12V_SSD10_CO_EN")
		)
	)
	(footprint ""
		(layer "F.Cu")
		(at 357.549196 -279.486868 -90)
		(property "Reference" "PC186"
			(at 0 0 270)
			(layer "F.SilkS")
			(hide yes)
			(effects
				(font
					(size 1.27 1.27)
				)
			)
		)
		(property "Value" ""
			(at 0 0 270)
			(layer "F.Fab")
			(effects
				(font
					(size 1.27 1.27)
				)
			)
		)
		(duplicate_pad_numbers_are_jumpers no)
		(fp_line
			(start -0.7874 0.4064)
			(end -0.7874 -0.4064)
			(stroke
				(width 0.1524)
				(type default)
			)
			(layer "F.SilkS")
		)
		(fp_line
			(start 0.7874 0.4064)
			(end -0.7874 0.4064)
			(stroke
				(width 0.1524)
				(type default)
			)
			(layer "F.SilkS")
		)
		(fp_line
			(start -0.7874 -0.4064)
			(end 0.7874 -0.4064)
			(stroke
				(width 0.1524)
				(type default)
			)
			(layer "F.SilkS")
		)
		(fp_line
			(start 0.7874 -0.4064)
			(end 0.7874 0.4064)
			(stroke
				(width 0.1524)
				(type default)
			)
			(layer "F.SilkS")
		)
		(fp_line
			(start -0.67945 0.3048)
			(end -0.67945 -0.305054)
			(stroke
				(width 0.1)
				(type default)
			)
			(layer "F.Fab")
		)
		(fp_line
			(start -0.12065 0.3048)
			(end -0.67945 0.3048)
			(stroke
				(width 0.1)
				(type default)
			)
			(layer "F.Fab")
		)
		(fp_line
			(start 0.120396 0.3048)
			(end 0.120396 0.2794)
			(stroke
				(width 0.1)
				(type default)
			)
			(layer "F.Fab")
		)
		(fp_line
			(start 0.67945 0.3048)
			(end 0.120396 0.3048)
			(stroke
				(width 0.1)
				(type default)
			)
			(layer "F.Fab")
		)
		(fp_line
			(start -0.12065 0.2794)
			(end -0.12065 0.3048)
			(stroke
				(width 0.1)
				(type default)
			)
			(layer "F.Fab")
		)
		(fp_line
			(start 0.120396 0.2794)
			(end -0.12065 0.2794)
			(stroke
				(width 0.1)
				(type default)
			)
			(layer "F.Fab")
		)
		(fp_line
			(start -0.12065 -0.2794)
			(end 0.12065 -0.2794)
			(stroke
				(width 0.1)
				(type default)
			)
			(layer "F.Fab")
		)
		(fp_line
			(start 0.12065 -0.2794)
			(end 0.12065 -0.3048)
			(stroke
				(width 0.1)
				(type default)
			)
			(layer "F.Fab")
		)
		(fp_line
			(start 0.12065 -0.3048)
			(end 0.67945 -0.3048)
			(stroke
				(width 0.1)
				(type default)
			)
			(layer "F.Fab")
		)
		(fp_line
			(start 0.67945 -0.3048)
			(end 0.67945 0.3048)
			(stroke
				(width 0.1)
				(type default)
			)
			(layer "F.Fab")
		)
		(fp_line
			(start -0.67945 -0.305054)
			(end -0.12065 -0.305054)
			(stroke
				(width 0.1)
				(type default)
			)
			(layer "F.Fab")
		)
		(fp_line
			(start -0.12065 -0.305054)
			(end -0.12065 -0.2794)
			(stroke
				(width 0.1)
				(type default)
			)
			(layer "F.Fab")
		)
		(pad "1" smd circle
			(at -0.40005 0 270)
			(size 0 0)
			(layers "F.Cu" "F.Mask" "F.Paste")
			(net "P0V8_PEX2_VREF")
		)
		(pad "2" smd circle
			(at 0.40005 0 270)
			(size 0 0)
			(layers "F.Cu" "F.Mask" "F.Paste")
			(net "GND")
		)
	)
	(footprint ""
		(layer "F.Cu")
		(at 60.12053 -26.666444 -90)
		(property "Reference" "R4057"
			(at 0 0 270)
			(layer "F.SilkS")
			(hide yes)
			(effects
				(font
					(size 1.27 1.27)
				)
			)
		)
		(property "Value" ""
			(at 0 0 270)
			(layer "F.Fab")
			(effects
				(font
					(size 1.27 1.27)
				)
			)
		)
		(duplicate_pad_numbers_are_jumpers no)
		(fp_line
			(start -0.7874 0.4064)
			(end -0.7874 -0.4064)
			(stroke
				(width 0.1524)
				(type default)
			)
			(layer "F.SilkS")
		)
		(fp_line
			(start 0.7874 0.4064)
			(end -0.7874 0.4064)
			(stroke
				(width 0.1524)
				(type default)
			)
			(layer "F.SilkS")
		)
		(fp_line
			(start -0.7874 -0.4064)
			(end 0.7874 -0.4064)
			(stroke
				(width 0.1524)
				(type default)
			)
			(layer "F.SilkS")
		)
		(fp_line
			(start 0.7874 -0.4064)
			(end 0.7874 0.4064)
			(stroke
				(width 0.1524)
				(type default)
			)
			(layer "F.SilkS")
		)
		(fp_line
			(start -0.67945 0.3048)
			(end -0.67945 -0.305054)
			(stroke
				(width 0.1)
				(type default)
			)
			(layer "F.Fab")
		)
		(fp_line
			(start -0.12065 0.3048)
			(end -0.67945 0.3048)
			(stroke
				(width 0.1)
				(type default)
			)
			(layer "F.Fab")
		)
		(fp_line
			(start 0.120396 0.3048)
			(end 0.120396 0.2794)
			(stroke
				(width 0.1)
				(type default)
			)
			(layer "F.Fab")
		)
		(fp_line
			(start 0.67945 0.3048)
			(end 0.120396 0.3048)
			(stroke
				(width 0.1)
				(type default)
			)
			(layer "F.Fab")
		)
		(fp_line
			(start -0.12065 0.2794)
			(end -0.12065 0.3048)
			(stroke
				(width 0.1)
				(type default)
			)
			(layer "F.Fab")
		)
		(fp_line
			(start 0.120396 0.2794)
			(end -0.12065 0.2794)
			(stroke
				(width 0.1)
				(type default)
			)
			(layer "F.Fab")
		)
		(fp_line
			(start -0.12065 -0.2794)
			(end 0.12065 -0.2794)
			(stroke
				(width 0.1)
				(type default)
			)
			(layer "F.Fab")
		)
		(fp_line
			(start 0.12065 -0.2794)
			(end 0.12065 -0.3048)
			(stroke
				(width 0.1)
				(type default)
			)
			(layer "F.Fab")
		)
		(fp_line
			(start 0.12065 -0.3048)
			(end 0.67945 -0.3048)
			(stroke
				(width 0.1)
				(type default)
			)
			(layer "F.Fab")
		)
		(fp_line
			(start 0.67945 -0.3048)
			(end 0.67945 0.3048)
			(stroke
				(width 0.1)
				(type default)
			)
			(layer "F.Fab")
		)
		(fp_line
			(start -0.67945 -0.305054)
			(end -0.12065 -0.305054)
			(stroke
				(width 0.1)
				(type default)
			)
			(layer "F.Fab")
		)
		(fp_line
			(start -0.12065 -0.305054)
			(end -0.12065 -0.2794)
			(stroke
				(width 0.1)
				(type default)
			)
			(layer "F.Fab")
		)
		(pad "1" smd circle
			(at -0.40005 0 270)
			(size 0 0)
			(layers "F.Cu" "F.Mask" "F.Paste")
			(net "PRSNT_SSD2_R_N")
		)
		(pad "2" smd circle
			(at 0.40005 0 270)
			(size 0 0)
			(layers "F.Cu" "F.Mask" "F.Paste")
			(net "PRSNT_SSD2_N")
		)
	)
	(footprint ""
		(layer "F.Cu")
		(at 278.634444 -33.631886 180)
		(property "Reference" "C496"
			(at 0 0 180)
			(layer "F.SilkS")
			(hide yes)
			(effects
				(font
					(size 1.27 1.27)
				)
			)
		)
		(property "Value" ""
			(at 0 0 180)
			(layer "F.Fab")
			(effects
				(font
					(size 1.27 1.27)
				)
			)
		)
		(duplicate_pad_numbers_are_jumpers no)
		(fp_line
			(start 0.299974 0.150114)
			(end -0.299974 0.150114)
			(stroke
				(width 0.1)
				(type default)
			)
			(layer "F.Fab")
		)
		(fp_line
			(start 0.299974 -0.150114)
			(end 0.299974 0.150114)
			(stroke
				(width 0.1)
				(type default)
			)
			(layer "F.Fab")
		)
		(fp_line
			(start -0.299974 0.150114)
			(end -0.299974 -0.150114)
			(stroke
				(width 0.1)
				(type default)
			)
			(layer "F.Fab")
		)
		(fp_line
			(start -0.299974 -0.150114)
			(end 0.299974 -0.150114)
			(stroke
				(width 0.1)
				(type default)
			)
			(layer "F.Fab")
		)
		(pad "1" smd rect
			(at -0.2667 0 180)
			(size 0.3048 0.381)
			(layers "F.Cu" "F.Mask" "F.Paste")
			(net "P5E_PEX2_STN2_TX_DN<43>")
		)
		(pad "2" smd rect
			(at 0.2667 0 180)
			(size 0.3048 0.381)
			(layers "F.Cu" "F.Mask" "F.Paste")
			(net "P5E_PEX2_STN2_TX_C_DN<43>")
		)
	)
	(footprint ""
		(layer "F.Cu")
		(at 234.64266 -204.44206 90)
		(property "Reference" "R5534"
			(at 0 0 90)
			(layer "F.SilkS")
			(hide yes)
			(effects
				(font
					(size 1.27 1.27)
				)
			)
		)
		(property "Value" ""
			(at 0 0 90)
			(layer "F.Fab")
			(effects
				(font
					(size 1.27 1.27)
				)
			)
		)
		(duplicate_pad_numbers_are_jumpers no)
		(fp_line
			(start 0.7874 -0.4064)
			(end 0.7874 0.4064)
			(stroke
				(width 0.1524)
				(type default)
			)
			(layer "F.SilkS")
		)
		(fp_line
			(start -0.7874 -0.4064)
			(end 0.7874 -0.4064)
			(stroke
				(width 0.1524)
				(type default)
			)
			(layer "F.SilkS")
		)
		(fp_line
			(start 0.7874 0.4064)
			(end -0.7874 0.4064)
			(stroke
				(width 0.1524)
				(type default)
			)
			(layer "F.SilkS")
		)
		(fp_line
			(start -0.7874 0.4064)
			(end -0.7874 -0.4064)
			(stroke
				(width 0.1524)
				(type default)
			)
			(layer "F.SilkS")
		)
		(fp_line
			(start -0.12065 -0.305054)
			(end -0.12065 -0.2794)
			(stroke
				(width 0.1)
				(type default)
			)
			(layer "F.Fab")
		)
		(fp_line
			(start -0.67945 -0.305054)
			(end -0.12065 -0.305054)
			(stroke
				(width 0.1)
				(type default)
			)
			(layer "F.Fab")
		)
		(fp_line
			(start 0.67945 -0.3048)
			(end 0.67945 0.3048)
			(stroke
				(width 0.1)
				(type default)
			)
			(layer "F.Fab")
		)
		(fp_line
			(start 0.12065 -0.3048)
			(end 0.67945 -0.3048)
			(stroke
				(width 0.1)
				(type default)
			)
			(layer "F.Fab")
		)
		(fp_line
			(start 0.12065 -0.2794)
			(end 0.12065 -0.3048)
			(stroke
				(width 0.1)
				(type default)
			)
			(layer "F.Fab")
		)
		(fp_line
			(start -0.12065 -0.2794)
			(end 0.12065 -0.2794)
			(stroke
				(width 0.1)
				(type default)
			)
			(layer "F.Fab")
		)
		(fp_line
			(start 0.120396 0.2794)
			(end -0.12065 0.2794)
			(stroke
				(width 0.1)
				(type default)
			)
			(layer "F.Fab")
		)
		(fp_line
			(start -0.12065 0.2794)
			(end -0.12065 0.3048)
			(stroke
				(width 0.1)
				(type default)
			)
			(layer "F.Fab")
		)
		(fp_line
			(start 0.67945 0.3048)
			(end 0.120396 0.3048)
			(stroke
				(width 0.1)
				(type default)
			)
			(layer "F.Fab")
		)
		(fp_line
			(start 0.120396 0.3048)
			(end 0.120396 0.2794)
			(stroke
				(width 0.1)
				(type default)
			)
			(layer "F.Fab")
		)
		(fp_line
			(start -0.12065 0.3048)
			(end -0.67945 0.3048)
			(stroke
				(width 0.1)
				(type default)
			)
			(layer "F.Fab")
		)
		(fp_line
			(start -0.67945 0.3048)
			(end -0.67945 -0.305054)
			(stroke
				(width 0.1)
				(type default)
			)
			(layer "F.Fab")
		)
		(pad "1" smd circle
			(at -0.40005 0 90)
			(size 0 0)
			(layers "F.Cu" "F.Mask" "F.Paste")
			(net "P3V3_AUX")
		)
		(pad "2" smd circle
			(at 0.40005 0 90)
			(size 0 0)
			(layers "F.Cu" "F.Mask" "F.Paste")
			(net "SPI_BIC1_MISO")
		)
	)
	(footprint ""
		(layer "F.Cu")
		(at 299.58919 -213.523068 -90)
		(property "Reference" "R3398"
			(at 0 0 270)
			(layer "F.SilkS")
			(hide yes)
			(effects
				(font
					(size 1.27 1.27)
				)
			)
		)
		(property "Value" ""
			(at 0 0 270)
			(layer "F.Fab")
			(effects
				(font
					(size 1.27 1.27)
				)
			)
		)
		(duplicate_pad_numbers_are_jumpers no)
		(fp_line
			(start -0.7874 0.4064)
			(end -0.7874 -0.4064)
			(stroke
				(width 0.1524)
				(type default)
			)
			(layer "F.SilkS")
		)
		(fp_line
			(start 0.7874 0.4064)
			(end -0.7874 0.4064)
			(stroke
				(width 0.1524)
				(type default)
			)
			(layer "F.SilkS")
		)
		(fp_line
			(start -0.7874 -0.4064)
			(end 0.7874 -0.4064)
			(stroke
				(width 0.1524)
				(type default)
			)
			(layer "F.SilkS")
		)
		(fp_line
			(start 0.7874 -0.4064)
			(end 0.7874 0.4064)
			(stroke
				(width 0.1524)
				(type default)
			)
			(layer "F.SilkS")
		)
		(fp_line
			(start -0.67945 0.3048)
			(end -0.67945 -0.305054)
			(stroke
				(width 0.1)
				(type default)
			)
			(layer "F.Fab")
		)
		(fp_line
			(start -0.12065 0.3048)
			(end -0.67945 0.3048)
			(stroke
				(width 0.1)
				(type default)
			)
			(layer "F.Fab")
		)
		(fp_line
			(start 0.120396 0.3048)
			(end 0.120396 0.2794)
			(stroke
				(width 0.1)
				(type default)
			)
			(layer "F.Fab")
		)
		(fp_line
			(start 0.67945 0.3048)
			(end 0.120396 0.3048)
			(stroke
				(width 0.1)
				(type default)
			)
			(layer "F.Fab")
		)
		(fp_line
			(start -0.12065 0.2794)
			(end -0.12065 0.3048)
			(stroke
				(width 0.1)
				(type default)
			)
			(layer "F.Fab")
		)
		(fp_line
			(start 0.120396 0.2794)
			(end -0.12065 0.2794)
			(stroke
				(width 0.1)
				(type default)
			)
			(layer "F.Fab")
		)
		(fp_line
			(start -0.12065 -0.2794)
			(end 0.12065 -0.2794)
			(stroke
				(width 0.1)
				(type default)
			)
			(layer "F.Fab")
		)
		(fp_line
			(start 0.12065 -0.2794)
			(end 0.12065 -0.3048)
			(stroke
				(width 0.1)
				(type default)
			)
			(layer "F.Fab")
		)
		(fp_line
			(start 0.12065 -0.3048)
			(end 0.67945 -0.3048)
			(stroke
				(width 0.1)
				(type default)
			)
			(layer "F.Fab")
		)
		(fp_line
			(start 0.67945 -0.3048)
			(end 0.67945 0.3048)
			(stroke
				(width 0.1)
				(type default)
			)
			(layer "F.Fab")
		)
		(fp_line
			(start -0.67945 -0.305054)
			(end -0.12065 -0.305054)
			(stroke
				(width 0.1)
				(type default)
			)
			(layer "F.Fab")
		)
		(fp_line
			(start -0.12065 -0.305054)
			(end -0.12065 -0.2794)
			(stroke
				(width 0.1)
				(type default)
			)
			(layer "F.Fab")
		)
		(pad "1" smd circle
			(at -0.40005 0 270)
			(size 0 0)
			(layers "F.Cu" "F.Mask" "F.Paste")
			(net "SPI_BIC1_CS0_LS23_R2_N")
		)
		(pad "2" smd circle
			(at 0.40005 0 270)
			(size 0 0)
			(layers "F.Cu" "F.Mask" "F.Paste")
			(net "SPI_BIC1_CS0_LS23_R_N")
		)
	)
	(footprint ""
		(layer "F.Cu")
		(at 217.227912 -211.193126 180)
		(property "Reference" "R6412"
			(at 0 0 180)
			(layer "F.SilkS")
			(hide yes)
			(effects
				(font
					(size 1.27 1.27)
				)
			)
		)
		(property "Value" ""
			(at 0 0 180)
			(layer "F.Fab")
			(effects
				(font
					(size 1.27 1.27)
				)
			)
		)
		(duplicate_pad_numbers_are_jumpers no)
		(fp_line
			(start 0.7874 0.4064)
			(end -0.7874 0.4064)
			(stroke
				(width 0.1524)
				(type default)
			)
			(layer "F.SilkS")
		)
		(fp_line
			(start 0.7874 -0.4064)
			(end 0.7874 0.4064)
			(stroke
				(width 0.1524)
				(type default)
			)
			(layer "F.SilkS")
		)
		(fp_line
			(start -0.7874 0.4064)
			(end -0.7874 -0.4064)
			(stroke
				(width 0.1524)
				(type default)
			)
			(layer "F.SilkS")
		)
		(fp_line
			(start -0.7874 -0.4064)
			(end 0.7874 -0.4064)
			(stroke
				(width 0.1524)
				(type default)
			)
			(layer "F.SilkS")
		)
		(fp_line
			(start 0.67945 0.3048)
			(end 0.120396 0.3048)
			(stroke
				(width 0.1)
				(type default)
			)
			(layer "F.Fab")
		)
		(fp_line
			(start 0.67945 -0.3048)
			(end 0.67945 0.3048)
			(stroke
				(width 0.1)
				(type default)
			)
			(layer "F.Fab")
		)
		(fp_line
			(start 0.12065 -0.2794)
			(end 0.12065 -0.3048)
			(stroke
				(width 0.1)
				(type default)
			)
			(layer "F.Fab")
		)
		(fp_line
			(start 0.12065 -0.3048)
			(end 0.67945 -0.3048)
			(stroke
				(width 0.1)
				(type default)
			)
			(layer "F.Fab")
		)
		(fp_line
			(start 0.120396 0.3048)
			(end 0.120396 0.2794)
			(stroke
				(width 0.1)
				(type default)
			)
			(layer "F.Fab")
		)
		(fp_line
			(start 0.120396 0.2794)
			(end -0.12065 0.2794)
			(stroke
				(width 0.1)
				(type default)
			)
			(layer "F.Fab")
		)
		(fp_line
			(start -0.12065 0.3048)
			(end -0.67945 0.3048)
			(stroke
				(width 0.1)
				(type default)
			)
			(layer "F.Fab")
		)
		(fp_line
			(start -0.12065 0.2794)
			(end -0.12065 0.3048)
			(stroke
				(width 0.1)
				(type default)
			)
			(layer "F.Fab")
		)
		(fp_line
			(start -0.12065 -0.2794)
			(end 0.12065 -0.2794)
			(stroke
				(width 0.1)
				(type default)
			)
			(layer "F.Fab")
		)
		(fp_line
			(start -0.12065 -0.305054)
			(end -0.12065 -0.2794)
			(stroke
				(width 0.1)
				(type default)
			)
			(layer "F.Fab")
		)
		(fp_line
			(start -0.67945 0.3048)
			(end -0.67945 -0.305054)
			(stroke
				(width 0.1)
				(type default)
			)
			(layer "F.Fab")
		)
		(fp_line
			(start -0.67945 -0.305054)
			(end -0.12065 -0.305054)
			(stroke
				(width 0.1)
				(type default)
			)
			(layer "F.Fab")
		)
		(pad "1" smd circle
			(at -0.40005 0 180)
			(size 0 0)
			(layers "F.Cu" "F.Mask" "F.Paste")
			(net "RST_BIC_I2C9_SSD_MUX0_N")
		)
		(pad "2" smd circle
			(at 0.40005 0 180)
			(size 0 0)
			(layers "F.Cu" "F.Mask" "F.Paste")
			(net "P3V3_AUX")
		)
	)
	(footprint ""
		(layer "F.Cu")
		(at 136.97839 -184.656984 -90)
		(property "Reference" "R1109"
			(at 0 0 270)
			(layer "F.SilkS")
			(hide yes)
			(effects
				(font
					(size 1.27 1.27)
				)
			)
		)
		(property "Value" ""
			(at 0 0 270)
			(layer "F.Fab")
			(effects
				(font
					(size 1.27 1.27)
				)
			)
		)
		(duplicate_pad_numbers_are_jumpers no)
		(fp_line
			(start -0.7874 -0.4064)
			(end 0.7874 -0.4064)
			(stroke
				(width 0.1524)
				(type default)
			)
			(layer "F.SilkS")
		)
		(fp_line
			(start -0.67945 0.3048)
			(end -0.67945 -0.305054)
			(stroke
				(width 0.1)
				(type default)
			)
			(layer "F.Fab")
		)
		(fp_line
			(start -0.12065 0.3048)
			(end -0.67945 0.3048)
			(stroke
				(width 0.1)
				(type default)
			)
			(layer "F.Fab")
		)
		(fp_line
			(start 0.120396 0.3048)
			(end 0.120396 0.2794)
			(stroke
				(width 0.1)
				(type default)
			)
			(layer "F.Fab")
		)
		(fp_line
			(start 0.67945 0.3048)
			(end 0.120396 0.3048)
			(stroke
				(width 0.1)
				(type default)
			)
			(layer "F.Fab")
		)
		(fp_line
			(start -0.12065 0.2794)
			(end -0.12065 0.3048)
			(stroke
				(width 0.1)
				(type default)
			)
			(layer "F.Fab")
		)
		(fp_line
			(start 0.120396 0.2794)
			(end -0.12065 0.2794)
			(stroke
				(width 0.1)
				(type default)
			)
			(layer "F.Fab")
		)
		(fp_line
			(start -0.12065 -0.2794)
			(end 0.12065 -0.2794)
			(stroke
				(width 0.1)
				(type default)
			)
			(layer "F.Fab")
		)
		(fp_line
			(start 0.12065 -0.2794)
			(end 0.12065 -0.3048)
			(stroke
				(width 0.1)
				(type default)
			)
			(layer "F.Fab")
		)
		(fp_line
			(start 0.12065 -0.3048)
			(end 0.67945 -0.3048)
			(stroke
				(width 0.1)
				(type default)
			)
			(layer "F.Fab")
		)
		(fp_line
			(start 0.67945 -0.3048)
			(end 0.67945 0.3048)
			(stroke
				(width 0.1)
				(type default)
			)
			(layer "F.Fab")
		)
		(fp_line
			(start -0.67945 -0.305054)
			(end -0.12065 -0.305054)
			(stroke
				(width 0.1)
				(type default)
			)
			(layer "F.Fab")
		)
		(fp_line
			(start -0.12065 -0.305054)
			(end -0.12065 -0.2794)
			(stroke
				(width 0.1)
				(type default)
			)
			(layer "F.Fab")
		)
		(pad "1" smd circle
			(at -0.40005 0 270)
			(size 0 0)
			(layers "F.Cu" "F.Mask" "F.Paste")
			(net "CLK_100M_DB2000QL_NIC7_R_DP")
		)
		(pad "2" smd circle
			(at 0.40005 0 270)
			(size 0 0)
			(layers "F.Cu" "F.Mask" "F.Paste")
			(net "CLK_100M_DB2000QL_NIC7_DP")
		)
	)
	(footprint ""
		(layer "F.Cu")
		(at 5.866892 -52.543456 180)
		(property "Reference" "PC500"
			(at 0 0 180)
			(layer "F.SilkS")
			(hide yes)
			(effects
				(font
					(size 1.27 1.27)
				)
			)
		)
		(property "Value" ""
			(at 0 0 180)
			(layer "F.Fab")
			(effects
				(font
					(size 1.27 1.27)
				)
			)
		)
		(duplicate_pad_numbers_are_jumpers no)
		(fp_line
			(start 0.7874 0.4064)
			(end -0.7874 0.4064)
			(stroke
				(width 0.1524)
				(type default)
			)
			(layer "F.SilkS")
		)
		(fp_line
			(start 0.7874 -0.4064)
			(end 0.7874 0.4064)
			(stroke
				(width 0.1524)
				(type default)
			)
			(layer "F.SilkS")
		)
		(fp_line
			(start -0.7874 0.4064)
			(end -0.7874 -0.4064)
			(stroke
				(width 0.1524)
				(type default)
			)
			(layer "F.SilkS")
		)
		(fp_line
			(start -0.7874 -0.4064)
			(end 0.7874 -0.4064)
			(stroke
				(width 0.1524)
				(type default)
			)
			(layer "F.SilkS")
		)
		(fp_line
			(start 0.67945 0.3048)
			(end 0.120396 0.3048)
			(stroke
				(width 0.1)
				(type default)
			)
			(layer "F.Fab")
		)
		(fp_line
			(start 0.67945 -0.3048)
			(end 0.67945 0.3048)
			(stroke
				(width 0.1)
				(type default)
			)
			(layer "F.Fab")
		)
		(fp_line
			(start 0.12065 -0.2794)
			(end 0.12065 -0.3048)
			(stroke
				(width 0.1)
				(type default)
			)
			(layer "F.Fab")
		)
		(fp_line
			(start 0.12065 -0.3048)
			(end 0.67945 -0.3048)
			(stroke
				(width 0.1)
				(type default)
			)
			(layer "F.Fab")
		)
		(fp_line
			(start 0.120396 0.3048)
			(end 0.120396 0.2794)
			(stroke
				(width 0.1)
				(type default)
			)
			(layer "F.Fab")
		)
		(fp_line
			(start 0.120396 0.2794)
			(end -0.12065 0.2794)
			(stroke
				(width 0.1)
				(type default)
			)
			(layer "F.Fab")
		)
		(fp_line
			(start -0.12065 0.3048)
			(end -0.67945 0.3048)
			(stroke
				(width 0.1)
				(type default)
			)
			(layer "F.Fab")
		)
		(fp_line
			(start -0.12065 0.2794)
			(end -0.12065 0.3048)
			(stroke
				(width 0.1)
				(type default)
			)
			(layer "F.Fab")
		)
		(fp_line
			(start -0.12065 -0.2794)
			(end 0.12065 -0.2794)
			(stroke
				(width 0.1)
				(type default)
			)
			(layer "F.Fab")
		)
		(fp_line
			(start -0.12065 -0.305054)
			(end -0.12065 -0.2794)
			(stroke
				(width 0.1)
				(type default)
			)
			(layer "F.Fab")
		)
		(fp_line
			(start -0.67945 0.3048)
			(end -0.67945 -0.305054)
			(stroke
				(width 0.1)
				(type default)
			)
			(layer "F.Fab")
		)
		(fp_line
			(start -0.67945 -0.305054)
			(end -0.12065 -0.305054)
			(stroke
				(width 0.1)
				(type default)
			)
			(layer "F.Fab")
		)
		(pad "1" smd circle
			(at -0.40005 0 180)
			(size 0 0)
			(layers "F.Cu" "F.Mask" "F.Paste")
			(net "P3V3_SSD0")
		)
		(pad "2" smd circle
			(at 0.40005 0 180)
			(size 0 0)
			(layers "F.Cu" "F.Mask" "F.Paste")
			(net "GND")
		)
	)
	(footprint ""
		(layer "F.Cu")
		(at 238.124746 -111.999268 180)
		(property "Reference" "R949"
			(at 0 0 180)
			(layer "F.SilkS")
			(hide yes)
			(effects
				(font
					(size 1.27 1.27)
				)
			)
		)
		(property "Value" ""
			(at 0 0 180)
			(layer "F.Fab")
			(effects
				(font
					(size 1.27 1.27)
				)
			)
		)
		(duplicate_pad_numbers_are_jumpers no)
		(fp_line
			(start 0.7874 0.4064)
			(end -0.7874 0.4064)
			(stroke
				(width 0.1524)
				(type default)
			)
			(layer "F.SilkS")
		)
		(fp_line
			(start 0.7874 -0.4064)
			(end 0.7874 0.4064)
			(stroke
				(width 0.1524)
				(type default)
			)
			(layer "F.SilkS")
		)
		(fp_line
			(start -0.7874 0.4064)
			(end -0.7874 -0.4064)
			(stroke
				(width 0.1524)
				(type default)
			)
			(layer "F.SilkS")
		)
		(fp_line
			(start -0.7874 -0.4064)
			(end 0.7874 -0.4064)
			(stroke
				(width 0.1524)
				(type default)
			)
			(layer "F.SilkS")
		)
		(fp_line
			(start 0.67945 0.3048)
			(end 0.120396 0.3048)
			(stroke
				(width 0.1)
				(type default)
			)
			(layer "F.Fab")
		)
		(fp_line
			(start 0.67945 -0.3048)
			(end 0.67945 0.3048)
			(stroke
				(width 0.1)
				(type default)
			)
			(layer "F.Fab")
		)
		(fp_line
			(start 0.12065 -0.2794)
			(end 0.12065 -0.3048)
			(stroke
				(width 0.1)
				(type default)
			)
			(layer "F.Fab")
		)
		(fp_line
			(start 0.12065 -0.3048)
			(end 0.67945 -0.3048)
			(stroke
				(width 0.1)
				(type default)
			)
			(layer "F.Fab")
		)
		(fp_line
			(start 0.120396 0.3048)
			(end 0.120396 0.2794)
			(stroke
				(width 0.1)
				(type default)
			)
			(layer "F.Fab")
		)
		(fp_line
			(start 0.120396 0.2794)
			(end -0.12065 0.2794)
			(stroke
				(width 0.1)
				(type default)
			)
			(layer "F.Fab")
		)
		(fp_line
			(start -0.12065 0.3048)
			(end -0.67945 0.3048)
			(stroke
				(width 0.1)
				(type default)
			)
			(layer "F.Fab")
		)
		(fp_line
			(start -0.12065 0.2794)
			(end -0.12065 0.3048)
			(stroke
				(width 0.1)
				(type default)
			)
			(layer "F.Fab")
		)
		(fp_line
			(start -0.12065 -0.2794)
			(end 0.12065 -0.2794)
			(stroke
				(width 0.1)
				(type default)
			)
			(layer "F.Fab")
		)
		(fp_line
			(start -0.12065 -0.305054)
			(end -0.12065 -0.2794)
			(stroke
				(width 0.1)
				(type default)
			)
			(layer "F.Fab")
		)
		(fp_line
			(start -0.67945 0.3048)
			(end -0.67945 -0.305054)
			(stroke
				(width 0.1)
				(type default)
			)
			(layer "F.Fab")
		)
		(fp_line
			(start -0.67945 -0.305054)
			(end -0.12065 -0.305054)
			(stroke
				(width 0.1)
				(type default)
			)
			(layer "F.Fab")
		)
		(pad "1" smd circle
			(at -0.40005 0 180)
			(size 0 0)
			(layers "F.Cu" "F.Mask" "F.Paste")
			(net "HP_NIC3_EN")
		)
		(pad "2" smd circle
			(at 0.40005 0 180)
			(size 0 0)
			(layers "F.Cu" "F.Mask" "F.Paste")
			(net "P12V_NIC3_CO_EN")
		)
	)
	(footprint ""
		(layer "F.Cu")
		(at 451.090792 -254.5969 -90)
		(property "Reference" "C4410"
			(at 0 0 270)
			(layer "F.SilkS")
			(hide yes)
			(effects
				(font
					(size 1.27 1.27)
				)
			)
		)
		(property "Value" ""
			(at 0 0 270)
			(layer "F.Fab")
			(effects
				(font
					(size 1.27 1.27)
				)
			)
		)
		(duplicate_pad_numbers_are_jumpers no)
		(fp_line
			(start -1.2954 0.5842)
			(end -1.2954 -0.5842)
			(stroke
				(width 0.1524)
				(type default)
			)
			(layer "F.SilkS")
		)
		(fp_line
			(start 1.2954 0.5842)
			(end -1.2954 0.5842)
			(stroke
				(width 0.1524)
				(type default)
			)
			(layer "F.SilkS")
		)
		(fp_line
			(start -1.2954 -0.5842)
			(end 1.2954 -0.5842)
			(stroke
				(width 0.1524)
				(type default)
			)
			(layer "F.SilkS")
		)
		(fp_line
			(start 1.2954 -0.5842)
			(end 1.2954 0.5842)
			(stroke
				(width 0.1524)
				(type default)
			)
			(layer "F.SilkS")
		)
		(fp_line
			(start -0.8636 0.4572)
			(end -0.8636 0.4064)
			(stroke
				(width 0.1)
				(type default)
			)
			(layer "F.Fab")
		)
		(fp_line
			(start 0.8636 0.4572)
			(end -0.8636 0.4572)
			(stroke
				(width 0.1)
				(type default)
			)
			(layer "F.Fab")
		)
		(fp_line
			(start -1.1938 0.4064)
			(end -1.1938 -0.4064)
			(stroke
				(width 0.1)
				(type default)
			)
			(layer "F.Fab")
		)
		(fp_line
			(start -0.8636 0.4064)
			(end -1.1938 0.4064)
			(stroke
				(width 0.1)
				(type default)
			)
			(layer "F.Fab")
		)
		(fp_line
			(start 0.8636 0.4064)
			(end 0.8636 0.4572)
			(stroke
				(width 0.1)
				(type default)
			)
			(layer "F.Fab")
		)
		(fp_line
			(start 1.1938 0.4064)
			(end 0.8636 0.4064)
			(stroke
				(width 0.1)
				(type default)
			)
			(layer "F.Fab")
		)
		(fp_line
			(start -1.1938 -0.4064)
			(end -0.8636 -0.4064)
			(stroke
				(width 0.1)
				(type default)
			)
			(layer "F.Fab")
		)
		(fp_line
			(start -0.8636 -0.4064)
			(end -0.8636 -0.4572)
			(stroke
				(width 0.1)
				(type default)
			)
			(layer "F.Fab")
		)
		(fp_line
			(start 0.8636 -0.4064)
			(end 1.1938 -0.4064)
			(stroke
				(width 0.1)
				(type default)
			)
			(layer "F.Fab")
		)
		(fp_line
			(start 1.1938 -0.4064)
			(end 1.1938 0.4064)
			(stroke
				(width 0.1)
				(type default)
			)
			(layer "F.Fab")
		)
		(fp_line
			(start -0.8636 -0.4572)
			(end 0.8636 -0.4572)
			(stroke
				(width 0.1)
				(type default)
			)
			(layer "F.Fab")
		)
		(fp_line
			(start 0.8636 -0.4572)
			(end 0.8636 -0.4064)
			(stroke
				(width 0.1)
				(type default)
			)
			(layer "F.Fab")
		)
		(pad "1" smd rect
			(at -0.7366 0 180)
			(size 0.7112 0.8128)
			(layers "F.Cu" "F.Mask" "F.Paste")
			(net "P1V25_SERDES_VDDPLL_PEX3_C8")
		)
		(pad "2" smd rect
			(at 0.7366 0 180)
			(size 0.7112 0.8128)
			(layers "F.Cu" "F.Mask" "F.Paste")
			(net "GND")
		)
	)
	(footprint ""
		(layer "F.Cu")
		(at 378.183648 -61.487812 180)
		(property "Reference" "R6015"
			(at 0 0 180)
			(layer "F.SilkS")
			(hide yes)
			(effects
				(font
					(size 1.27 1.27)
				)
			)
		)
		(property "Value" ""
			(at 0 0 180)
			(layer "F.Fab")
			(effects
				(font
					(size 1.27 1.27)
				)
			)
		)
		(duplicate_pad_numbers_are_jumpers no)
		(fp_line
			(start 0.7874 0.4064)
			(end -0.7874 0.4064)
			(stroke
				(width 0.1524)
				(type default)
			)
			(layer "F.SilkS")
		)
		(fp_line
			(start 0.7874 -0.4064)
			(end 0.7874 0.4064)
			(stroke
				(width 0.1524)
				(type default)
			)
			(layer "F.SilkS")
		)
		(fp_line
			(start -0.7874 0.4064)
			(end -0.7874 -0.4064)
			(stroke
				(width 0.1524)
				(type default)
			)
			(layer "F.SilkS")
		)
		(fp_line
			(start -0.7874 -0.4064)
			(end 0.7874 -0.4064)
			(stroke
				(width 0.1524)
				(type default)
			)
			(layer "F.SilkS")
		)
		(fp_line
			(start 0.67945 0.3048)
			(end 0.120396 0.3048)
			(stroke
				(width 0.1)
				(type default)
			)
			(layer "F.Fab")
		)
		(fp_line
			(start 0.67945 -0.3048)
			(end 0.67945 0.3048)
			(stroke
				(width 0.1)
				(type default)
			)
			(layer "F.Fab")
		)
		(fp_line
			(start 0.12065 -0.2794)
			(end 0.12065 -0.3048)
			(stroke
				(width 0.1)
				(type default)
			)
			(layer "F.Fab")
		)
		(fp_line
			(start 0.12065 -0.3048)
			(end 0.67945 -0.3048)
			(stroke
				(width 0.1)
				(type default)
			)
			(layer "F.Fab")
		)
		(fp_line
			(start 0.120396 0.3048)
			(end 0.120396 0.2794)
			(stroke
				(width 0.1)
				(type default)
			)
			(layer "F.Fab")
		)
		(fp_line
			(start 0.120396 0.2794)
			(end -0.12065 0.2794)
			(stroke
				(width 0.1)
				(type default)
			)
			(layer "F.Fab")
		)
		(fp_line
			(start -0.12065 0.3048)
			(end -0.67945 0.3048)
			(stroke
				(width 0.1)
				(type default)
			)
			(layer "F.Fab")
		)
		(fp_line
			(start -0.12065 0.2794)
			(end -0.12065 0.3048)
			(stroke
				(width 0.1)
				(type default)
			)
			(layer "F.Fab")
		)
		(fp_line
			(start -0.12065 -0.2794)
			(end 0.12065 -0.2794)
			(stroke
				(width 0.1)
				(type default)
			)
			(layer "F.Fab")
		)
		(fp_line
			(start -0.12065 -0.305054)
			(end -0.12065 -0.2794)
			(stroke
				(width 0.1)
				(type default)
			)
			(layer "F.Fab")
		)
		(fp_line
			(start -0.67945 0.3048)
			(end -0.67945 -0.305054)
			(stroke
				(width 0.1)
				(type default)
			)
			(layer "F.Fab")
		)
		(fp_line
			(start -0.67945 -0.305054)
			(end -0.12065 -0.305054)
			(stroke
				(width 0.1)
				(type default)
			)
			(layer "F.Fab")
		)
		(pad "1" smd circle
			(at -0.40005 0 180)
			(size 0 0)
			(layers "F.Cu" "F.Mask" "F.Paste")
			(net "PWRGD_P12V_SSD13_D")
		)
		(pad "2" smd circle
			(at 0.40005 0 180)
			(size 0 0)
			(layers "F.Cu" "F.Mask" "F.Paste")
			(net "PWRGD_P12V_SSD13_R")
		)
	)
	(footprint ""
		(layer "F.Cu")
		(at 351.08261 -29.875734)
		(property "Reference" "PU131"
			(at -3.011678 -2.076704 90)
			(unlocked yes)
			(layer "F.SilkS")
			(effects
				(font
					(size 0.7874 0.5842)
					(thickness 0.1524)
				)
			)
		)
		(property "Value" ""
			(at 0 0 0)
			(layer "F.Fab")
			(effects
				(font
					(size 1.27 1.27)
				)
			)
		)
		(duplicate_pad_numbers_are_jumpers no)
		(fp_line
			(start -1.239774 -1.495298)
			(end 1.239774 -1.495298)
			(stroke
				(width 0.1524)
				(type default)
			)
			(layer "F.SilkS")
		)
		(fp_line
			(start -1.239774 1.495298)
			(end -1.239774 -1.495298)
			(stroke
				(width 0.1524)
				(type default)
			)
			(layer "F.SilkS")
		)
		(fp_line
			(start 1.239774 -1.495298)
			(end 1.239774 1.495298)
			(stroke
				(width 0.1524)
				(type default)
			)
			(layer "F.SilkS")
		)
		(fp_line
			(start 1.239774 1.495298)
			(end -1.239774 1.495298)
			(stroke
				(width 0.1524)
				(type default)
			)
			(layer "F.SilkS")
		)
		(fp_poly
			(pts
				(xy -1.904238 -1.263904) (xy -2.62255 -0.545338) (xy -1.545082 -0.186182)
			)
			(stroke
				(width 0)
				(type default)
			)
			(fill yes)
			(layer "F.SilkS")
		)
		(fp_line
			(start -0.8001 -1.050036)
			(end 0.8001 -1.050036)
			(stroke
				(width 0.1)
				(type default)
			)
			(layer "F.Fab")
		)
		(fp_line
			(start -0.8001 1.050036)
			(end -0.8001 -1.050036)
			(stroke
				(width 0.1)
				(type default)
			)
			(layer "F.Fab")
		)
		(fp_line
			(start 0.8001 -1.050036)
			(end 0.8001 1.050036)
			(stroke
				(width 0.1)
				(type default)
			)
			(layer "F.Fab")
		)
		(fp_line
			(start 0.8001 1.050036)
			(end -0.8001 1.050036)
			(stroke
				(width 0.1)
				(type default)
			)
			(layer "F.Fab")
		)
		(fp_poly
			(pts
				(xy -2.458974 -0.508) (xy -2.458974 0.508) (xy -1.442974 0)
			)
			(stroke
				(width 0)
				(type default)
			)
			(fill yes)
			(layer "F.Fab")
		)
		(pad "1_2" smd circle
			(at -0.374904 0 90)
			(size 0 0)
			(layers "F.Cu" "F.Mask" "F.Paste")
			(net "P3V3_AUX")
		)
		(pad "3" smd rect
			(at -0.499872 0.999998)
			(size 0.254 0.7112)
			(layers "F.Cu" "F.Mask" "F.Paste")
			(net "GND")
		)
		(pad "4" smd rect
			(at 0 0.999998)
			(size 0.254 0.7112)
			(layers "F.Cu" "F.Mask" "F.Paste")
			(net "P3V3_SSD12_CO_ILIMIT")
		)
		(pad "5" smd rect
			(at 0.499872 0.999998)
			(size 0.254 0.7112)
			(layers "F.Cu" "F.Mask" "F.Paste")
			(net "P3V3_SSD12_CO_MODE")
		)
		(pad "6_7" smd circle
			(at 0.374904 0 270)
			(size 0 0)
			(layers "F.Cu" "F.Mask" "F.Paste")
			(net "P3V3_SSD12")
		)
		(pad "8" smd rect
			(at 0.499872 -0.999998)
			(size 0.254 0.7112)
			(layers "F.Cu" "F.Mask" "F.Paste")
			(net "P3V3_SSD12_CO_GATE")
		)
		(pad "9" smd rect
			(at 0 -0.999998)
			(size 0.254 0.7112)
			(layers "F.Cu" "F.Mask" "F.Paste")
			(net "P3V3_SSD12_CO_EN")
		)
		(pad "10" smd rect
			(at -0.499872 -0.999998)
			(size 0.254 0.7112)
			(layers "F.Cu" "F.Mask" "F.Paste")
			(net "P3V3_SSD12_CO_DV_DT")
		)
	)
	(footprint ""
		(layer "F.Cu")
		(at 78.267814 -53.051456)
		(property "Reference" "R4462"
			(at 0 0 0)
			(layer "F.SilkS")
			(hide yes)
			(effects
				(font
					(size 1.27 1.27)
				)
			)
		)
		(property "Value" ""
			(at 0 0 0)
			(layer "F.Fab")
			(effects
				(font
					(size 1.27 1.27)
				)
			)
		)
		(duplicate_pad_numbers_are_jumpers no)
		(fp_line
			(start -0.7874 -0.4064)
			(end 0.7874 -0.4064)
			(stroke
				(width 0.1524)
				(type default)
			)
			(layer "F.SilkS")
		)
		(fp_line
			(start -0.7874 0.4064)
			(end -0.7874 -0.4064)
			(stroke
				(width 0.1524)
				(type default)
			)
			(layer "F.SilkS")
		)
		(fp_line
			(start 0.7874 -0.4064)
			(end 0.7874 0.4064)
			(stroke
				(width 0.1524)
				(type default)
			)
			(layer "F.SilkS")
		)
		(fp_line
			(start 0.7874 0.4064)
			(end -0.7874 0.4064)
			(stroke
				(width 0.1524)
				(type default)
			)
			(layer "F.SilkS")
		)
		(fp_line
			(start -0.67945 -0.305054)
			(end -0.12065 -0.305054)
			(stroke
				(width 0.1)
				(type default)
			)
			(layer "F.Fab")
		)
		(fp_line
			(start -0.67945 0.3048)
			(end -0.67945 -0.305054)
			(stroke
				(width 0.1)
				(type default)
			)
			(layer "F.Fab")
		)
		(fp_line
			(start -0.12065 -0.305054)
			(end -0.12065 -0.2794)
			(stroke
				(width 0.1)
				(type default)
			)
			(layer "F.Fab")
		)
		(fp_line
			(start -0.12065 -0.2794)
			(end 0.12065 -0.2794)
			(stroke
				(width 0.1)
				(type default)
			)
			(layer "F.Fab")
		)
		(fp_line
			(start -0.12065 0.2794)
			(end -0.12065 0.3048)
			(stroke
				(width 0.1)
				(type default)
			)
			(layer "F.Fab")
		)
		(fp_line
			(start -0.12065 0.3048)
			(end -0.67945 0.3048)
			(stroke
				(width 0.1)
				(type default)
			)
			(layer "F.Fab")
		)
		(fp_line
			(start 0.120396 0.2794)
			(end -0.12065 0.2794)
			(stroke
				(width 0.1)
				(type default)
			)
			(layer "F.Fab")
		)
		(fp_line
			(start 0.120396 0.3048)
			(end 0.120396 0.2794)
			(stroke
				(width 0.1)
				(type default)
			)
			(layer "F.Fab")
		)
		(fp_line
			(start 0.12065 -0.3048)
			(end 0.67945 -0.3048)
			(stroke
				(width 0.1)
				(type default)
			)
			(layer "F.Fab")
		)
		(fp_line
			(start 0.12065 -0.2794)
			(end 0.12065 -0.3048)
			(stroke
				(width 0.1)
				(type default)
			)
			(layer "F.Fab")
		)
		(fp_line
			(start 0.67945 -0.3048)
			(end 0.67945 0.3048)
			(stroke
				(width 0.1)
				(type default)
			)
			(layer "F.Fab")
		)
		(fp_line
			(start 0.67945 0.3048)
			(end 0.120396 0.3048)
			(stroke
				(width 0.1)
				(type default)
			)
			(layer "F.Fab")
		)
		(pad "1" smd circle
			(at -0.40005 0)
			(size 0 0)
			(layers "F.Cu" "F.Mask" "F.Paste")
			(net "PWRGD_P12V_SSD2")
		)
		(pad "2" smd circle
			(at 0.40005 0)
			(size 0 0)
			(layers "F.Cu" "F.Mask" "F.Paste")
			(net "PWRGD_P12V_SSD2_R")
		)
	)
	(footprint ""
		(layer "F.Cu")
		(at 80.019398 -142.590266 180)
		(property "Reference" "C16"
			(at 0 0 180)
			(layer "F.SilkS")
			(hide yes)
			(effects
				(font
					(size 1.27 1.27)
				)
			)
		)
		(property "Value" ""
			(at 0 0 180)
			(layer "F.Fab")
			(effects
				(font
					(size 1.27 1.27)
				)
			)
		)
		(duplicate_pad_numbers_are_jumpers no)
		(fp_line
			(start 0.299974 0.150114)
			(end -0.299974 0.150114)
			(stroke
				(width 0.1)
				(type default)
			)
			(layer "F.Fab")
		)
		(fp_line
			(start 0.299974 -0.150114)
			(end 0.299974 0.150114)
			(stroke
				(width 0.1)
				(type default)
			)
			(layer "F.Fab")
		)
		(fp_line
			(start -0.299974 0.150114)
			(end -0.299974 -0.150114)
			(stroke
				(width 0.1)
				(type default)
			)
			(layer "F.Fab")
		)
		(fp_line
			(start -0.299974 -0.150114)
			(end 0.299974 -0.150114)
			(stroke
				(width 0.1)
				(type default)
			)
			(layer "F.Fab")
		)
		(pad "1" smd rect
			(at -0.2667 0 180)
			(size 0.3048 0.381)
			(layers "F.Cu" "F.Mask" "F.Paste")
			(net "P5E_PEX0_STN0_TX_DN<8>")
		)
		(pad "2" smd rect
			(at 0.2667 0 180)
			(size 0.3048 0.381)
			(layers "F.Cu" "F.Mask" "F.Paste")
			(net "P5E_PEX0_STN0_TX_C_DN<8>")
		)
	)
	(footprint ""
		(layer "F.Cu")
		(at 227.946458 -306.681632 -90)
		(property "Reference" "PR172"
			(at 0 0 270)
			(layer "F.SilkS")
			(hide yes)
			(effects
				(font
					(size 1.27 1.27)
				)
			)
		)
		(property "Value" ""
			(at 0 0 270)
			(layer "F.Fab")
			(effects
				(font
					(size 1.27 1.27)
				)
			)
		)
		(duplicate_pad_numbers_are_jumpers no)
		(fp_line
			(start -0.7874 0.4064)
			(end -0.7874 -0.4064)
			(stroke
				(width 0.1524)
				(type default)
			)
			(layer "F.SilkS")
		)
		(fp_line
			(start 0.7874 0.4064)
			(end -0.7874 0.4064)
			(stroke
				(width 0.1524)
				(type default)
			)
			(layer "F.SilkS")
		)
		(fp_line
			(start -0.7874 -0.4064)
			(end 0.7874 -0.4064)
			(stroke
				(width 0.1524)
				(type default)
			)
			(layer "F.SilkS")
		)
		(fp_line
			(start 0.7874 -0.4064)
			(end 0.7874 0.4064)
			(stroke
				(width 0.1524)
				(type default)
			)
			(layer "F.SilkS")
		)
		(fp_line
			(start -0.67945 0.3048)
			(end -0.67945 -0.305054)
			(stroke
				(width 0.1)
				(type default)
			)
			(layer "F.Fab")
		)
		(fp_line
			(start -0.12065 0.3048)
			(end -0.67945 0.3048)
			(stroke
				(width 0.1)
				(type default)
			)
			(layer "F.Fab")
		)
		(fp_line
			(start 0.120396 0.3048)
			(end 0.120396 0.2794)
			(stroke
				(width 0.1)
				(type default)
			)
			(layer "F.Fab")
		)
		(fp_line
			(start 0.67945 0.3048)
			(end 0.120396 0.3048)
			(stroke
				(width 0.1)
				(type default)
			)
			(layer "F.Fab")
		)
		(fp_line
			(start -0.12065 0.2794)
			(end -0.12065 0.3048)
			(stroke
				(width 0.1)
				(type default)
			)
			(layer "F.Fab")
		)
		(fp_line
			(start 0.120396 0.2794)
			(end -0.12065 0.2794)
			(stroke
				(width 0.1)
				(type default)
			)
			(layer "F.Fab")
		)
		(fp_line
			(start -0.12065 -0.2794)
			(end 0.12065 -0.2794)
			(stroke
				(width 0.1)
				(type default)
			)
			(layer "F.Fab")
		)
		(fp_line
			(start 0.12065 -0.2794)
			(end 0.12065 -0.3048)
			(stroke
				(width 0.1)
				(type default)
			)
			(layer "F.Fab")
		)
		(fp_line
			(start 0.12065 -0.3048)
			(end 0.67945 -0.3048)
			(stroke
				(width 0.1)
				(type default)
			)
			(layer "F.Fab")
		)
		(fp_line
			(start 0.67945 -0.3048)
			(end 0.67945 0.3048)
			(stroke
				(width 0.1)
				(type default)
			)
			(layer "F.Fab")
		)
		(fp_line
			(start -0.67945 -0.305054)
			(end -0.12065 -0.305054)
			(stroke
				(width 0.1)
				(type default)
			)
			(layer "F.Fab")
		)
		(fp_line
			(start -0.12065 -0.305054)
			(end -0.12065 -0.2794)
			(stroke
				(width 0.1)
				(type default)
			)
			(layer "F.Fab")
		)
		(pad "1" smd circle
			(at -0.40005 0 270)
			(size 0 0)
			(layers "F.Cu" "F.Mask" "F.Paste")
			(net "P1V25_PEX1_CS")
		)
		(pad "2" smd circle
			(at 0.40005 0 270)
			(size 0 0)
			(layers "F.Cu" "F.Mask" "F.Paste")
			(net "GND")
		)
	)
	(footprint ""
		(layer "F.Cu")
		(at 169.22623 -39.73576 -90)
		(property "Reference" "R5557"
			(at 0 0 270)
			(layer "F.SilkS")
			(hide yes)
			(effects
				(font
					(size 1.27 1.27)
				)
			)
		)
		(property "Value" ""
			(at 0 0 270)
			(layer "F.Fab")
			(effects
				(font
					(size 1.27 1.27)
				)
			)
		)
		(duplicate_pad_numbers_are_jumpers no)
		(fp_line
			(start -0.7874 0.4064)
			(end -0.7874 -0.4064)
			(stroke
				(width 0.1524)
				(type default)
			)
			(layer "F.SilkS")
		)
		(fp_line
			(start 0.7874 0.4064)
			(end -0.7874 0.4064)
			(stroke
				(width 0.1524)
				(type default)
			)
			(layer "F.SilkS")
		)
		(fp_line
			(start -0.7874 -0.4064)
			(end 0.7874 -0.4064)
			(stroke
				(width 0.1524)
				(type default)
			)
			(layer "F.SilkS")
		)
		(fp_line
			(start 0.7874 -0.4064)
			(end 0.7874 0.4064)
			(stroke
				(width 0.1524)
				(type default)
			)
			(layer "F.SilkS")
		)
		(fp_line
			(start -0.67945 0.3048)
			(end -0.67945 -0.305054)
			(stroke
				(width 0.1)
				(type default)
			)
			(layer "F.Fab")
		)
		(fp_line
			(start -0.12065 0.3048)
			(end -0.67945 0.3048)
			(stroke
				(width 0.1)
				(type default)
			)
			(layer "F.Fab")
		)
		(fp_line
			(start 0.120396 0.3048)
			(end 0.120396 0.2794)
			(stroke
				(width 0.1)
				(type default)
			)
			(layer "F.Fab")
		)
		(fp_line
			(start 0.67945 0.3048)
			(end 0.120396 0.3048)
			(stroke
				(width 0.1)
				(type default)
			)
			(layer "F.Fab")
		)
		(fp_line
			(start -0.12065 0.2794)
			(end -0.12065 0.3048)
			(stroke
				(width 0.1)
				(type default)
			)
			(layer "F.Fab")
		)
		(fp_line
			(start 0.120396 0.2794)
			(end -0.12065 0.2794)
			(stroke
				(width 0.1)
				(type default)
			)
			(layer "F.Fab")
		)
		(fp_line
			(start -0.12065 -0.2794)
			(end 0.12065 -0.2794)
			(stroke
				(width 0.1)
				(type default)
			)
			(layer "F.Fab")
		)
		(fp_line
			(start 0.12065 -0.2794)
			(end 0.12065 -0.3048)
			(stroke
				(width 0.1)
				(type default)
			)
			(layer "F.Fab")
		)
		(fp_line
			(start 0.12065 -0.3048)
			(end 0.67945 -0.3048)
			(stroke
				(width 0.1)
				(type default)
			)
			(layer "F.Fab")
		)
		(fp_line
			(start 0.67945 -0.3048)
			(end 0.67945 0.3048)
			(stroke
				(width 0.1)
				(type default)
			)
			(layer "F.Fab")
		)
		(fp_line
			(start -0.67945 -0.305054)
			(end -0.12065 -0.305054)
			(stroke
				(width 0.1)
				(type default)
			)
			(layer "F.Fab")
		)
		(fp_line
			(start -0.12065 -0.305054)
			(end -0.12065 -0.2794)
			(stroke
				(width 0.1)
				(type default)
			)
			(layer "F.Fab")
		)
		(pad "1" smd circle
			(at -0.40005 0 270)
			(size 0 0)
			(layers "F.Cu" "F.Mask" "F.Paste")
			(net "P3V3_AUX")
		)
		(pad "2" smd circle
			(at 0.40005 0 270)
			(size 0 0)
			(layers "F.Cu" "F.Mask" "F.Paste")
			(net "SSD6_AUX_P3V3_EN")
		)
	)
	(footprint ""
		(layer "F.Cu")
		(at 458.818234 -274.8915 180)
		(property "Reference" "R810"
			(at 0 0 180)
			(layer "F.SilkS")
			(hide yes)
			(effects
				(font
					(size 1.27 1.27)
				)
			)
		)
		(property "Value" ""
			(at 0 0 180)
			(layer "F.Fab")
			(effects
				(font
					(size 1.27 1.27)
				)
			)
		)
		(duplicate_pad_numbers_are_jumpers no)
		(fp_line
			(start 0.7874 0.4064)
			(end -0.7874 0.4064)
			(stroke
				(width 0.1524)
				(type default)
			)
			(layer "F.SilkS")
		)
		(fp_line
			(start 0.7874 -0.4064)
			(end 0.7874 0.4064)
			(stroke
				(width 0.1524)
				(type default)
			)
			(layer "F.SilkS")
		)
		(fp_line
			(start -0.7874 0.4064)
			(end -0.7874 -0.4064)
			(stroke
				(width 0.1524)
				(type default)
			)
			(layer "F.SilkS")
		)
		(fp_line
			(start -0.7874 -0.4064)
			(end 0.7874 -0.4064)
			(stroke
				(width 0.1524)
				(type default)
			)
			(layer "F.SilkS")
		)
		(fp_line
			(start 0.67945 0.3048)
			(end 0.120396 0.3048)
			(stroke
				(width 0.1)
				(type default)
			)
			(layer "F.Fab")
		)
		(fp_line
			(start 0.67945 -0.3048)
			(end 0.67945 0.3048)
			(stroke
				(width 0.1)
				(type default)
			)
			(layer "F.Fab")
		)
		(fp_line
			(start 0.12065 -0.2794)
			(end 0.12065 -0.3048)
			(stroke
				(width 0.1)
				(type default)
			)
			(layer "F.Fab")
		)
		(fp_line
			(start 0.12065 -0.3048)
			(end 0.67945 -0.3048)
			(stroke
				(width 0.1)
				(type default)
			)
			(layer "F.Fab")
		)
		(fp_line
			(start 0.120396 0.3048)
			(end 0.120396 0.2794)
			(stroke
				(width 0.1)
				(type default)
			)
			(layer "F.Fab")
		)
		(fp_line
			(start 0.120396 0.2794)
			(end -0.12065 0.2794)
			(stroke
				(width 0.1)
				(type default)
			)
			(layer "F.Fab")
		)
		(fp_line
			(start -0.12065 0.3048)
			(end -0.67945 0.3048)
			(stroke
				(width 0.1)
				(type default)
			)
			(layer "F.Fab")
		)
		(fp_line
			(start -0.12065 0.2794)
			(end -0.12065 0.3048)
			(stroke
				(width 0.1)
				(type default)
			)
			(layer "F.Fab")
		)
		(fp_line
			(start -0.12065 -0.2794)
			(end 0.12065 -0.2794)
			(stroke
				(width 0.1)
				(type default)
			)
			(layer "F.Fab")
		)
		(fp_line
			(start -0.12065 -0.305054)
			(end -0.12065 -0.2794)
			(stroke
				(width 0.1)
				(type default)
			)
			(layer "F.Fab")
		)
		(fp_line
			(start -0.67945 0.3048)
			(end -0.67945 -0.305054)
			(stroke
				(width 0.1)
				(type default)
			)
			(layer "F.Fab")
		)
		(fp_line
			(start -0.67945 -0.305054)
			(end -0.12065 -0.305054)
			(stroke
				(width 0.1)
				(type default)
			)
			(layer "F.Fab")
		)
		(pad "1" smd circle
			(at -0.40005 0 180)
			(size 0 0)
			(layers "F.Cu" "F.Mask" "F.Paste")
			(net "P1V25_PEX3_R")
		)
		(pad "2" smd circle
			(at 0.40005 0 180)
			(size 0 0)
			(layers "F.Cu" "F.Mask" "F.Paste")
			(net "P12V_PEX3_P1V25_VIN_P")
		)
	)
	(footprint ""
		(layer "F.Cu")
		(at 104.243632 -48.93691 180)
		(property "Reference" "R545"
			(at 0 0 180)
			(layer "F.SilkS")
			(hide yes)
			(effects
				(font
					(size 1.27 1.27)
				)
			)
		)
		(property "Value" ""
			(at 0 0 180)
			(layer "F.Fab")
			(effects
				(font
					(size 1.27 1.27)
				)
			)
		)
		(duplicate_pad_numbers_are_jumpers no)
		(fp_line
			(start 0.7874 0.4064)
			(end -0.7874 0.4064)
			(stroke
				(width 0.1524)
				(type default)
			)
			(layer "F.SilkS")
		)
		(fp_line
			(start 0.7874 -0.4064)
			(end 0.7874 0.4064)
			(stroke
				(width 0.1524)
				(type default)
			)
			(layer "F.SilkS")
		)
		(fp_line
			(start -0.7874 0.4064)
			(end -0.7874 -0.4064)
			(stroke
				(width 0.1524)
				(type default)
			)
			(layer "F.SilkS")
		)
		(fp_line
			(start -0.7874 -0.4064)
			(end 0.7874 -0.4064)
			(stroke
				(width 0.1524)
				(type default)
			)
			(layer "F.SilkS")
		)
		(fp_line
			(start 0.67945 0.3048)
			(end 0.120396 0.3048)
			(stroke
				(width 0.1)
				(type default)
			)
			(layer "F.Fab")
		)
		(fp_line
			(start 0.67945 -0.3048)
			(end 0.67945 0.3048)
			(stroke
				(width 0.1)
				(type default)
			)
			(layer "F.Fab")
		)
		(fp_line
			(start 0.12065 -0.2794)
			(end 0.12065 -0.3048)
			(stroke
				(width 0.1)
				(type default)
			)
			(layer "F.Fab")
		)
		(fp_line
			(start 0.12065 -0.3048)
			(end 0.67945 -0.3048)
			(stroke
				(width 0.1)
				(type default)
			)
			(layer "F.Fab")
		)
		(fp_line
			(start 0.120396 0.3048)
			(end 0.120396 0.2794)
			(stroke
				(width 0.1)
				(type default)
			)
			(layer "F.Fab")
		)
		(fp_line
			(start 0.120396 0.2794)
			(end -0.12065 0.2794)
			(stroke
				(width 0.1)
				(type default)
			)
			(layer "F.Fab")
		)
		(fp_line
			(start -0.12065 0.3048)
			(end -0.67945 0.3048)
			(stroke
				(width 0.1)
				(type default)
			)
			(layer "F.Fab")
		)
		(fp_line
			(start -0.12065 0.2794)
			(end -0.12065 0.3048)
			(stroke
				(width 0.1)
				(type default)
			)
			(layer "F.Fab")
		)
		(fp_line
			(start -0.12065 -0.2794)
			(end 0.12065 -0.2794)
			(stroke
				(width 0.1)
				(type default)
			)
			(layer "F.Fab")
		)
		(fp_line
			(start -0.12065 -0.305054)
			(end -0.12065 -0.2794)
			(stroke
				(width 0.1)
				(type default)
			)
			(layer "F.Fab")
		)
		(fp_line
			(start -0.67945 0.3048)
			(end -0.67945 -0.305054)
			(stroke
				(width 0.1)
				(type default)
			)
			(layer "F.Fab")
		)
		(fp_line
			(start -0.67945 -0.305054)
			(end -0.12065 -0.305054)
			(stroke
				(width 0.1)
				(type default)
			)
			(layer "F.Fab")
		)
		(pad "1" smd circle
			(at -0.40005 0 180)
			(size 0 0)
			(layers "F.Cu" "F.Mask" "F.Paste")
			(net "SMB_BIC_I2C6_MUX_SSD_0_7_ADC_R_SDA")
		)
		(pad "2" smd circle
			(at 0.40005 0 180)
			(size 0 0)
			(layers "F.Cu" "F.Mask" "F.Paste")
			(net "SMB_SSD3_ADC_SDA")
		)
	)
	(footprint ""
		(layer "F.Cu")
		(at 377.842018 -305.648106 -135)
		(property "Reference" "R1444"
			(at 0 0 225)
			(layer "F.SilkS")
			(hide yes)
			(effects
				(font
					(size 1.27 1.27)
				)
			)
		)
		(property "Value" ""
			(at 0 0 225)
			(layer "F.Fab")
			(effects
				(font
					(size 1.27 1.27)
				)
			)
		)
		(duplicate_pad_numbers_are_jumpers no)
		(fp_line
			(start 0.787389 0.406267)
			(end -0.787389 0.406267)
			(stroke
				(width 0.1524)
				(type default)
			)
			(layer "F.SilkS")
		)
		(fp_line
			(start 0.787389 -0.406267)
			(end 0.787389 0.406267)
			(stroke
				(width 0.1524)
				(type default)
			)
			(layer "F.SilkS")
		)
		(fp_line
			(start -0.787389 0.406267)
			(end -0.787389 -0.406267)
			(stroke
				(width 0.1524)
				(type default)
			)
			(layer "F.SilkS")
		)
		(fp_line
			(start -0.787389 -0.406267)
			(end 0.787389 -0.406267)
			(stroke
				(width 0.1524)
				(type default)
			)
			(layer "F.SilkS")
		)
		(fp_line
			(start 0.679446 0.30479)
			(end 0.120515 0.30479)
			(stroke
				(width 0.1)
				(type default)
			)
			(layer "F.Fab")
		)
		(fp_line
			(start 0.120515 0.30479)
			(end 0.120335 0.279466)
			(stroke
				(width 0.1)
				(type default)
			)
			(layer "F.Fab")
		)
		(fp_line
			(start 0.120335 0.279466)
			(end -0.120695 0.279466)
			(stroke
				(width 0.1)
				(type default)
			)
			(layer "F.Fab")
		)
		(fp_line
			(start 0.679446 -0.30479)
			(end 0.679446 0.30479)
			(stroke
				(width 0.1)
				(type default)
			)
			(layer "F.Fab")
		)
		(fp_line
			(start -0.120515 0.30479)
			(end -0.679446 0.30479)
			(stroke
				(width 0.1)
				(type default)
			)
			(layer "F.Fab")
		)
		(fp_line
			(start -0.120695 0.279466)
			(end -0.120515 0.30479)
			(stroke
				(width 0.1)
				(type default)
			)
			(layer "F.Fab")
		)
		(fp_line
			(start 0.120695 -0.279466)
			(end 0.120515 -0.30479)
			(stroke
				(width 0.1)
				(type default)
			)
			(layer "F.Fab")
		)
		(fp_line
			(start 0.120515 -0.30479)
			(end 0.679446 -0.30479)
			(stroke
				(width 0.1)
				(type default)
			)
			(layer "F.Fab")
		)
		(fp_line
			(start -0.679446 0.30479)
			(end -0.679446 -0.305149)
			(stroke
				(width 0.1)
				(type default)
			)
			(layer "F.Fab")
		)
		(fp_line
			(start -0.120695 -0.279466)
			(end 0.120695 -0.279466)
			(stroke
				(width 0.1)
				(type default)
			)
			(layer "F.Fab")
		)
		(fp_line
			(start -0.120695 -0.304969)
			(end -0.120695 -0.279466)
			(stroke
				(width 0.1)
				(type default)
			)
			(layer "F.Fab")
		)
		(fp_line
			(start -0.679446 -0.305149)
			(end -0.120695 -0.304969)
			(stroke
				(width 0.1)
				(type default)
			)
			(layer "F.Fab")
		)
		(pad "1" smd circle
			(at -0.40005 0 225)
			(size 0 0)
			(layers "F.Cu" "F.Mask" "F.Paste")
			(net "PEX3_DFT_IDDT")
		)
		(pad "2" smd circle
			(at 0.40005 0 225)
			(size 0 0)
			(layers "F.Cu" "F.Mask" "F.Paste")
			(net "P1V8_PEX")
		)
	)
	(footprint ""
		(layer "F.Cu")
		(at 365.506 -198.755 180)
		(property "Reference" "R4688"
			(at 0 0 180)
			(layer "F.SilkS")
			(hide yes)
			(effects
				(font
					(size 1.27 1.27)
				)
			)
		)
		(property "Value" ""
			(at 0 0 180)
			(layer "F.Fab")
			(effects
				(font
					(size 1.27 1.27)
				)
			)
		)
		(duplicate_pad_numbers_are_jumpers no)
		(fp_line
			(start 0.7874 0.4064)
			(end -0.7874 0.4064)
			(stroke
				(width 0.1524)
				(type default)
			)
			(layer "F.SilkS")
		)
		(fp_line
			(start 0.7874 -0.4064)
			(end 0.7874 0.4064)
			(stroke
				(width 0.1524)
				(type default)
			)
			(layer "F.SilkS")
		)
		(fp_line
			(start -0.7874 0.4064)
			(end -0.7874 -0.4064)
			(stroke
				(width 0.1524)
				(type default)
			)
			(layer "F.SilkS")
		)
		(fp_line
			(start -0.7874 -0.4064)
			(end 0.7874 -0.4064)
			(stroke
				(width 0.1524)
				(type default)
			)
			(layer "F.SilkS")
		)
		(fp_line
			(start 0.67945 0.3048)
			(end 0.120396 0.3048)
			(stroke
				(width 0.1)
				(type default)
			)
			(layer "F.Fab")
		)
		(fp_line
			(start 0.67945 -0.3048)
			(end 0.67945 0.3048)
			(stroke
				(width 0.1)
				(type default)
			)
			(layer "F.Fab")
		)
		(fp_line
			(start 0.12065 -0.2794)
			(end 0.12065 -0.3048)
			(stroke
				(width 0.1)
				(type default)
			)
			(layer "F.Fab")
		)
		(fp_line
			(start 0.12065 -0.3048)
			(end 0.67945 -0.3048)
			(stroke
				(width 0.1)
				(type default)
			)
			(layer "F.Fab")
		)
		(fp_line
			(start 0.120396 0.3048)
			(end 0.120396 0.2794)
			(stroke
				(width 0.1)
				(type default)
			)
			(layer "F.Fab")
		)
		(fp_line
			(start 0.120396 0.2794)
			(end -0.12065 0.2794)
			(stroke
				(width 0.1)
				(type default)
			)
			(layer "F.Fab")
		)
		(fp_line
			(start -0.12065 0.3048)
			(end -0.67945 0.3048)
			(stroke
				(width 0.1)
				(type default)
			)
			(layer "F.Fab")
		)
		(fp_line
			(start -0.12065 0.2794)
			(end -0.12065 0.3048)
			(stroke
				(width 0.1)
				(type default)
			)
			(layer "F.Fab")
		)
		(fp_line
			(start -0.12065 -0.2794)
			(end 0.12065 -0.2794)
			(stroke
				(width 0.1)
				(type default)
			)
			(layer "F.Fab")
		)
		(fp_line
			(start -0.12065 -0.305054)
			(end -0.12065 -0.2794)
			(stroke
				(width 0.1)
				(type default)
			)
			(layer "F.Fab")
		)
		(fp_line
			(start -0.67945 0.3048)
			(end -0.67945 -0.305054)
			(stroke
				(width 0.1)
				(type default)
			)
			(layer "F.Fab")
		)
		(fp_line
			(start -0.67945 -0.305054)
			(end -0.12065 -0.305054)
			(stroke
				(width 0.1)
				(type default)
			)
			(layer "F.Fab")
		)
		(pad "1" smd circle
			(at -0.40005 0 180)
			(size 0 0)
			(layers "F.Cu" "F.Mask" "F.Paste")
			(net "RST_PEX_SSD4_PERST_N")
		)
		(pad "2" smd circle
			(at 0.40005 0 180)
			(size 0 0)
			(layers "F.Cu" "F.Mask" "F.Paste")
			(net "RST_PEX_SSD4_PERST_R_N")
		)
	)
	(footprint ""
		(layer "F.Cu")
		(at 246.137938 -308.095396 -90)
		(property "Reference" "PC980"
			(at 0 0 270)
			(layer "F.SilkS")
			(hide yes)
			(effects
				(font
					(size 1.27 1.27)
				)
			)
		)
		(property "Value" ""
			(at 0 0 270)
			(layer "F.Fab")
			(effects
				(font
					(size 1.27 1.27)
				)
			)
		)
		(duplicate_pad_numbers_are_jumpers no)
		(fp_line
			(start -0.7874 0.4064)
			(end -0.7874 -0.4064)
			(stroke
				(width 0.1524)
				(type default)
			)
			(layer "F.SilkS")
		)
		(fp_line
			(start 0.7874 0.4064)
			(end -0.7874 0.4064)
			(stroke
				(width 0.1524)
				(type default)
			)
			(layer "F.SilkS")
		)
		(fp_line
			(start -0.7874 -0.4064)
			(end 0.7874 -0.4064)
			(stroke
				(width 0.1524)
				(type default)
			)
			(layer "F.SilkS")
		)
		(fp_line
			(start 0.7874 -0.4064)
			(end 0.7874 0.4064)
			(stroke
				(width 0.1524)
				(type default)
			)
			(layer "F.SilkS")
		)
		(fp_line
			(start -0.67945 0.3048)
			(end -0.67945 -0.305054)
			(stroke
				(width 0.1)
				(type default)
			)
			(layer "F.Fab")
		)
		(fp_line
			(start -0.12065 0.3048)
			(end -0.67945 0.3048)
			(stroke
				(width 0.1)
				(type default)
			)
			(layer "F.Fab")
		)
		(fp_line
			(start 0.120396 0.3048)
			(end 0.120396 0.2794)
			(stroke
				(width 0.1)
				(type default)
			)
			(layer "F.Fab")
		)
		(fp_line
			(start 0.67945 0.3048)
			(end 0.120396 0.3048)
			(stroke
				(width 0.1)
				(type default)
			)
			(layer "F.Fab")
		)
		(fp_line
			(start -0.12065 0.2794)
			(end -0.12065 0.3048)
			(stroke
				(width 0.1)
				(type default)
			)
			(layer "F.Fab")
		)
		(fp_line
			(start 0.120396 0.2794)
			(end -0.12065 0.2794)
			(stroke
				(width 0.1)
				(type default)
			)
			(layer "F.Fab")
		)
		(fp_line
			(start -0.12065 -0.2794)
			(end 0.12065 -0.2794)
			(stroke
				(width 0.1)
				(type default)
			)
			(layer "F.Fab")
		)
		(fp_line
			(start 0.12065 -0.2794)
			(end 0.12065 -0.3048)
			(stroke
				(width 0.1)
				(type default)
			)
			(layer "F.Fab")
		)
		(fp_line
			(start 0.12065 -0.3048)
			(end 0.67945 -0.3048)
			(stroke
				(width 0.1)
				(type default)
			)
			(layer "F.Fab")
		)
		(fp_line
			(start 0.67945 -0.3048)
			(end 0.67945 0.3048)
			(stroke
				(width 0.1)
				(type default)
			)
			(layer "F.Fab")
		)
		(fp_line
			(start -0.67945 -0.305054)
			(end -0.12065 -0.305054)
			(stroke
				(width 0.1)
				(type default)
			)
			(layer "F.Fab")
		)
		(fp_line
			(start -0.12065 -0.305054)
			(end -0.12065 -0.2794)
			(stroke
				(width 0.1)
				(type default)
			)
			(layer "F.Fab")
		)
		(pad "1" smd circle
			(at -0.40005 0 270)
			(size 0 0)
			(layers "F.Cu" "F.Mask" "F.Paste")
			(net "SH_P1V25_PEX2_FB_P")
		)
		(pad "2" smd circle
			(at 0.40005 0 270)
			(size 0 0)
			(layers "F.Cu" "F.Mask" "F.Paste")
			(net "SH_P1V25_PEX2_FB_N")
		)
	)
	(footprint ""
		(layer "F.Cu")
		(at 9.195054 -59.577986 90)
		(property "Reference" "PC506"
			(at 0 0 90)
			(layer "F.SilkS")
			(hide yes)
			(effects
				(font
					(size 1.27 1.27)
				)
			)
		)
		(property "Value" ""
			(at 0 0 90)
			(layer "F.Fab")
			(effects
				(font
					(size 1.27 1.27)
				)
			)
		)
		(duplicate_pad_numbers_are_jumpers no)
		(fp_line
			(start 0.7874 -0.4064)
			(end 0.7874 0.4064)
			(stroke
				(width 0.1524)
				(type default)
			)
			(layer "F.SilkS")
		)
		(fp_line
			(start -0.7874 -0.4064)
			(end 0.7874 -0.4064)
			(stroke
				(width 0.1524)
				(type default)
			)
			(layer "F.SilkS")
		)
		(fp_line
			(start 0.7874 0.4064)
			(end -0.7874 0.4064)
			(stroke
				(width 0.1524)
				(type default)
			)
			(layer "F.SilkS")
		)
		(fp_line
			(start -0.7874 0.4064)
			(end -0.7874 -0.4064)
			(stroke
				(width 0.1524)
				(type default)
			)
			(layer "F.SilkS")
		)
		(fp_line
			(start -0.12065 -0.305054)
			(end -0.12065 -0.2794)
			(stroke
				(width 0.1)
				(type default)
			)
			(layer "F.Fab")
		)
		(fp_line
			(start -0.67945 -0.305054)
			(end -0.12065 -0.305054)
			(stroke
				(width 0.1)
				(type default)
			)
			(layer "F.Fab")
		)
		(fp_line
			(start 0.67945 -0.3048)
			(end 0.67945 0.3048)
			(stroke
				(width 0.1)
				(type default)
			)
			(layer "F.Fab")
		)
		(fp_line
			(start 0.12065 -0.3048)
			(end 0.67945 -0.3048)
			(stroke
				(width 0.1)
				(type default)
			)
			(layer "F.Fab")
		)
		(fp_line
			(start 0.12065 -0.2794)
			(end 0.12065 -0.3048)
			(stroke
				(width 0.1)
				(type default)
			)
			(layer "F.Fab")
		)
		(fp_line
			(start -0.12065 -0.2794)
			(end 0.12065 -0.2794)
			(stroke
				(width 0.1)
				(type default)
			)
			(layer "F.Fab")
		)
		(fp_line
			(start 0.120396 0.2794)
			(end -0.12065 0.2794)
			(stroke
				(width 0.1)
				(type default)
			)
			(layer "F.Fab")
		)
		(fp_line
			(start -0.12065 0.2794)
			(end -0.12065 0.3048)
			(stroke
				(width 0.1)
				(type default)
			)
			(layer "F.Fab")
		)
		(fp_line
			(start 0.67945 0.3048)
			(end 0.120396 0.3048)
			(stroke
				(width 0.1)
				(type default)
			)
			(layer "F.Fab")
		)
		(fp_line
			(start 0.120396 0.3048)
			(end 0.120396 0.2794)
			(stroke
				(width 0.1)
				(type default)
			)
			(layer "F.Fab")
		)
		(fp_line
			(start -0.12065 0.3048)
			(end -0.67945 0.3048)
			(stroke
				(width 0.1)
				(type default)
			)
			(layer "F.Fab")
		)
		(fp_line
			(start -0.67945 0.3048)
			(end -0.67945 -0.305054)
			(stroke
				(width 0.1)
				(type default)
			)
			(layer "F.Fab")
		)
		(pad "1" smd circle
			(at -0.40005 0 90)
			(size 0 0)
			(layers "F.Cu" "F.Mask" "F.Paste")
			(net "P3V3_SSD0_SS")
		)
		(pad "2" smd circle
			(at 0.40005 0 90)
			(size 0 0)
			(layers "F.Cu" "F.Mask" "F.Paste")
			(net "GND")
		)
	)
	(footprint ""
		(layer "F.Cu")
		(at 222.5548 -22.961346 90)
		(property "Reference" "R1676"
			(at 0 0 90)
			(layer "F.SilkS")
			(hide yes)
			(effects
				(font
					(size 1.27 1.27)
				)
			)
		)
		(property "Value" ""
			(at 0 0 90)
			(layer "F.Fab")
			(effects
				(font
					(size 1.27 1.27)
				)
			)
		)
		(duplicate_pad_numbers_are_jumpers no)
		(fp_line
			(start 0.7874 -0.4064)
			(end 0.7874 0.4064)
			(stroke
				(width 0.1524)
				(type default)
			)
			(layer "F.SilkS")
		)
		(fp_line
			(start -0.7874 -0.4064)
			(end 0.7874 -0.4064)
			(stroke
				(width 0.1524)
				(type default)
			)
			(layer "F.SilkS")
		)
		(fp_line
			(start 0.7874 0.4064)
			(end -0.7874 0.4064)
			(stroke
				(width 0.1524)
				(type default)
			)
			(layer "F.SilkS")
		)
		(fp_line
			(start -0.7874 0.4064)
			(end -0.7874 -0.4064)
			(stroke
				(width 0.1524)
				(type default)
			)
			(layer "F.SilkS")
		)
		(fp_line
			(start -0.12065 -0.305054)
			(end -0.12065 -0.2794)
			(stroke
				(width 0.1)
				(type default)
			)
			(layer "F.Fab")
		)
		(fp_line
			(start -0.67945 -0.305054)
			(end -0.12065 -0.305054)
			(stroke
				(width 0.1)
				(type default)
			)
			(layer "F.Fab")
		)
		(fp_line
			(start 0.67945 -0.3048)
			(end 0.67945 0.3048)
			(stroke
				(width 0.1)
				(type default)
			)
			(layer "F.Fab")
		)
		(fp_line
			(start 0.12065 -0.3048)
			(end 0.67945 -0.3048)
			(stroke
				(width 0.1)
				(type default)
			)
			(layer "F.Fab")
		)
		(fp_line
			(start 0.12065 -0.2794)
			(end 0.12065 -0.3048)
			(stroke
				(width 0.1)
				(type default)
			)
			(layer "F.Fab")
		)
		(fp_line
			(start -0.12065 -0.2794)
			(end 0.12065 -0.2794)
			(stroke
				(width 0.1)
				(type default)
			)
			(layer "F.Fab")
		)
		(fp_line
			(start 0.120396 0.2794)
			(end -0.12065 0.2794)
			(stroke
				(width 0.1)
				(type default)
			)
			(layer "F.Fab")
		)
		(fp_line
			(start -0.12065 0.2794)
			(end -0.12065 0.3048)
			(stroke
				(width 0.1)
				(type default)
			)
			(layer "F.Fab")
		)
		(fp_line
			(start 0.67945 0.3048)
			(end 0.120396 0.3048)
			(stroke
				(width 0.1)
				(type default)
			)
			(layer "F.Fab")
		)
		(fp_line
			(start 0.120396 0.3048)
			(end 0.120396 0.2794)
			(stroke
				(width 0.1)
				(type default)
			)
			(layer "F.Fab")
		)
		(fp_line
			(start -0.12065 0.3048)
			(end -0.67945 0.3048)
			(stroke
				(width 0.1)
				(type default)
			)
			(layer "F.Fab")
		)
		(fp_line
			(start -0.67945 0.3048)
			(end -0.67945 -0.305054)
			(stroke
				(width 0.1)
				(type default)
			)
			(layer "F.Fab")
		)
		(pad "1" smd circle
			(at -0.40005 0 90)
			(size 0 0)
			(layers "F.Cu" "F.Mask" "F.Paste")
			(net "SMB_SSD7_ISO_EN")
		)
		(pad "2" smd circle
			(at 0.40005 0 90)
			(size 0 0)
			(layers "F.Cu" "F.Mask" "F.Paste")
			(net "P3V3_AUX")
		)
	)
	(footprint ""
		(layer "F.Cu")
		(at 378.852684 -87.6808)
		(property "Reference" "R1767"
			(at 0 0 0)
			(layer "F.SilkS")
			(hide yes)
			(effects
				(font
					(size 1.27 1.27)
				)
			)
		)
		(property "Value" ""
			(at 0 0 0)
			(layer "F.Fab")
			(effects
				(font
					(size 1.27 1.27)
				)
			)
		)
		(duplicate_pad_numbers_are_jumpers no)
		(fp_line
			(start -0.7874 -0.4064)
			(end 0.7874 -0.4064)
			(stroke
				(width 0.1524)
				(type default)
			)
			(layer "F.SilkS")
		)
		(fp_line
			(start -0.7874 0.4064)
			(end -0.7874 -0.4064)
			(stroke
				(width 0.1524)
				(type default)
			)
			(layer "F.SilkS")
		)
		(fp_line
			(start 0.7874 -0.4064)
			(end 0.7874 0.4064)
			(stroke
				(width 0.1524)
				(type default)
			)
			(layer "F.SilkS")
		)
		(fp_line
			(start 0.7874 0.4064)
			(end -0.7874 0.4064)
			(stroke
				(width 0.1524)
				(type default)
			)
			(layer "F.SilkS")
		)
		(fp_line
			(start -0.67945 -0.305054)
			(end -0.12065 -0.305054)
			(stroke
				(width 0.1)
				(type default)
			)
			(layer "F.Fab")
		)
		(fp_line
			(start -0.67945 0.3048)
			(end -0.67945 -0.305054)
			(stroke
				(width 0.1)
				(type default)
			)
			(layer "F.Fab")
		)
		(fp_line
			(start -0.12065 -0.305054)
			(end -0.12065 -0.2794)
			(stroke
				(width 0.1)
				(type default)
			)
			(layer "F.Fab")
		)
		(fp_line
			(start -0.12065 -0.2794)
			(end 0.12065 -0.2794)
			(stroke
				(width 0.1)
				(type default)
			)
			(layer "F.Fab")
		)
		(fp_line
			(start -0.12065 0.2794)
			(end -0.12065 0.3048)
			(stroke
				(width 0.1)
				(type default)
			)
			(layer "F.Fab")
		)
		(fp_line
			(start -0.12065 0.3048)
			(end -0.67945 0.3048)
			(stroke
				(width 0.1)
				(type default)
			)
			(layer "F.Fab")
		)
		(fp_line
			(start 0.120396 0.2794)
			(end -0.12065 0.2794)
			(stroke
				(width 0.1)
				(type default)
			)
			(layer "F.Fab")
		)
		(fp_line
			(start 0.120396 0.3048)
			(end 0.120396 0.2794)
			(stroke
				(width 0.1)
				(type default)
			)
			(layer "F.Fab")
		)
		(fp_line
			(start 0.12065 -0.3048)
			(end 0.67945 -0.3048)
			(stroke
				(width 0.1)
				(type default)
			)
			(layer "F.Fab")
		)
		(fp_line
			(start 0.12065 -0.2794)
			(end 0.12065 -0.3048)
			(stroke
				(width 0.1)
				(type default)
			)
			(layer "F.Fab")
		)
		(fp_line
			(start 0.67945 -0.3048)
			(end 0.67945 0.3048)
			(stroke
				(width 0.1)
				(type default)
			)
			(layer "F.Fab")
		)
		(fp_line
			(start 0.67945 0.3048)
			(end 0.120396 0.3048)
			(stroke
				(width 0.1)
				(type default)
			)
			(layer "F.Fab")
		)
		(pad "1" smd circle
			(at -0.40005 0)
			(size 0 0)
			(layers "F.Cu" "F.Mask" "F.Paste")
			(net "SMB_BIC_I2C6_MUX_NIC_ADC_R_SCL")
		)
		(pad "2" smd circle
			(at 0.40005 0)
			(size 0 0)
			(layers "F.Cu" "F.Mask" "F.Paste")
			(net "SMB_BIC_I2C6_MUX_NIC_ADC_SCL")
		)
	)
	(footprint ""
		(layer "F.Cu")
		(at 341.63 -205.232 -90)
		(property "Reference" "R4137"
			(at 0 0 270)
			(layer "F.SilkS")
			(hide yes)
			(effects
				(font
					(size 1.27 1.27)
				)
			)
		)
		(property "Value" ""
			(at 0 0 270)
			(layer "F.Fab")
			(effects
				(font
					(size 1.27 1.27)
				)
			)
		)
		(duplicate_pad_numbers_are_jumpers no)
		(fp_line
			(start -0.7874 0.4064)
			(end -0.7874 -0.4064)
			(stroke
				(width 0.1524)
				(type default)
			)
			(layer "F.SilkS")
		)
		(fp_line
			(start 0.7874 0.4064)
			(end -0.7874 0.4064)
			(stroke
				(width 0.1524)
				(type default)
			)
			(layer "F.SilkS")
		)
		(fp_line
			(start -0.7874 -0.4064)
			(end 0.7874 -0.4064)
			(stroke
				(width 0.1524)
				(type default)
			)
			(layer "F.SilkS")
		)
		(fp_line
			(start 0.7874 -0.4064)
			(end 0.7874 0.4064)
			(stroke
				(width 0.1524)
				(type default)
			)
			(layer "F.SilkS")
		)
		(fp_line
			(start -0.67945 0.3048)
			(end -0.67945 -0.305054)
			(stroke
				(width 0.1)
				(type default)
			)
			(layer "F.Fab")
		)
		(fp_line
			(start -0.12065 0.3048)
			(end -0.67945 0.3048)
			(stroke
				(width 0.1)
				(type default)
			)
			(layer "F.Fab")
		)
		(fp_line
			(start 0.120396 0.3048)
			(end 0.120396 0.2794)
			(stroke
				(width 0.1)
				(type default)
			)
			(layer "F.Fab")
		)
		(fp_line
			(start 0.67945 0.3048)
			(end 0.120396 0.3048)
			(stroke
				(width 0.1)
				(type default)
			)
			(layer "F.Fab")
		)
		(fp_line
			(start -0.12065 0.2794)
			(end -0.12065 0.3048)
			(stroke
				(width 0.1)
				(type default)
			)
			(layer "F.Fab")
		)
		(fp_line
			(start 0.120396 0.2794)
			(end -0.12065 0.2794)
			(stroke
				(width 0.1)
				(type default)
			)
			(layer "F.Fab")
		)
		(fp_line
			(start -0.12065 -0.2794)
			(end 0.12065 -0.2794)
			(stroke
				(width 0.1)
				(type default)
			)
			(layer "F.Fab")
		)
		(fp_line
			(start 0.12065 -0.2794)
			(end 0.12065 -0.3048)
			(stroke
				(width 0.1)
				(type default)
			)
			(layer "F.Fab")
		)
		(fp_line
			(start 0.12065 -0.3048)
			(end 0.67945 -0.3048)
			(stroke
				(width 0.1)
				(type default)
			)
			(layer "F.Fab")
		)
		(fp_line
			(start 0.67945 -0.3048)
			(end 0.67945 0.3048)
			(stroke
				(width 0.1)
				(type default)
			)
			(layer "F.Fab")
		)
		(fp_line
			(start -0.67945 -0.305054)
			(end -0.12065 -0.305054)
			(stroke
				(width 0.1)
				(type default)
			)
			(layer "F.Fab")
		)
		(fp_line
			(start -0.12065 -0.305054)
			(end -0.12065 -0.2794)
			(stroke
				(width 0.1)
				(type default)
			)
			(layer "F.Fab")
		)
		(pad "1" smd circle
			(at -0.40005 0 270)
			(size 0 0)
			(layers "F.Cu" "F.Mask" "F.Paste")
			(net "RST_SSD13_PERST_N")
		)
		(pad "2" smd circle
			(at 0.40005 0 270)
			(size 0 0)
			(layers "F.Cu" "F.Mask" "F.Paste")
			(net "RST_SSD13_PERST_R_N")
		)
	)
	(footprint ""
		(layer "F.Cu")
		(at 243.564918 -314.424314)
		(property "Reference" "PC246"
			(at 0 0 0)
			(layer "F.SilkS")
			(hide yes)
			(effects
				(font
					(size 1.27 1.27)
				)
			)
		)
		(property "Value" ""
			(at 0 0 0)
			(layer "F.Fab")
			(effects
				(font
					(size 1.27 1.27)
				)
			)
		)
		(duplicate_pad_numbers_are_jumpers no)
		(fp_line
			(start -1.524 -0.762)
			(end 1.524 -0.762)
			(stroke
				(width 0.1524)
				(type default)
			)
			(layer "F.SilkS")
		)
		(fp_line
			(start -1.524 0.762)
			(end -1.524 -0.762)
			(stroke
				(width 0.1524)
				(type default)
			)
			(layer "F.SilkS")
		)
		(fp_line
			(start 1.524 -0.762)
			(end 1.524 0.762)
			(stroke
				(width 0.1524)
				(type default)
			)
			(layer "F.SilkS")
		)
		(fp_line
			(start 1.524 0.762)
			(end -1.524 0.762)
			(stroke
				(width 0.1524)
				(type default)
			)
			(layer "F.SilkS")
		)
		(fp_line
			(start -1.1049 -0.724916)
			(end -1.1049 0.724916)
			(stroke
				(width 0.1)
				(type default)
			)
			(layer "F.Fab")
		)
		(fp_line
			(start -1.1049 0.724916)
			(end 1.1049 0.724916)
			(stroke
				(width 0.1)
				(type default)
			)
			(layer "F.Fab")
		)
		(fp_line
			(start 1.1049 -0.724916)
			(end -1.1049 -0.724916)
			(stroke
				(width 0.1)
				(type default)
			)
			(layer "F.Fab")
		)
		(fp_line
			(start 1.1049 0.724916)
			(end 1.1049 -0.724916)
			(stroke
				(width 0.1)
				(type default)
			)
			(layer "F.Fab")
		)
		(pad "1" smd rect
			(at -0.889 0 180)
			(size 1.016 1.27)
			(layers "F.Cu" "F.Mask" "F.Paste")
			(net "SW_P12V_P1V25_PEX2_FLT")
		)
		(pad "2" smd rect
			(at 0.889 0 180)
			(size 1.016 1.27)
			(layers "F.Cu" "F.Mask" "F.Paste")
			(net "GND")
		)
	)
	(footprint ""
		(layer "F.Cu")
		(at 362.654596 -135.993632 -90)
		(property "Reference" "PC334"
			(at 0 0 270)
			(layer "F.SilkS")
			(hide yes)
			(effects
				(font
					(size 1.27 1.27)
				)
			)
		)
		(property "Value" ""
			(at 0 0 270)
			(layer "F.Fab")
			(effects
				(font
					(size 1.27 1.27)
				)
			)
		)
		(duplicate_pad_numbers_are_jumpers no)
		(fp_line
			(start -0.7874 0.4064)
			(end -0.7874 -0.4064)
			(stroke
				(width 0.1524)
				(type default)
			)
			(layer "F.SilkS")
		)
		(fp_line
			(start 0.7874 0.4064)
			(end -0.7874 0.4064)
			(stroke
				(width 0.1524)
				(type default)
			)
			(layer "F.SilkS")
		)
		(fp_line
			(start -0.7874 -0.4064)
			(end 0.7874 -0.4064)
			(stroke
				(width 0.1524)
				(type default)
			)
			(layer "F.SilkS")
		)
		(fp_line
			(start 0.7874 -0.4064)
			(end 0.7874 0.4064)
			(stroke
				(width 0.1524)
				(type default)
			)
			(layer "F.SilkS")
		)
		(fp_line
			(start -0.67945 0.3048)
			(end -0.67945 -0.305054)
			(stroke
				(width 0.1)
				(type default)
			)
			(layer "F.Fab")
		)
		(fp_line
			(start -0.12065 0.3048)
			(end -0.67945 0.3048)
			(stroke
				(width 0.1)
				(type default)
			)
			(layer "F.Fab")
		)
		(fp_line
			(start 0.120396 0.3048)
			(end 0.120396 0.2794)
			(stroke
				(width 0.1)
				(type default)
			)
			(layer "F.Fab")
		)
		(fp_line
			(start 0.67945 0.3048)
			(end 0.120396 0.3048)
			(stroke
				(width 0.1)
				(type default)
			)
			(layer "F.Fab")
		)
		(fp_line
			(start -0.12065 0.2794)
			(end -0.12065 0.3048)
			(stroke
				(width 0.1)
				(type default)
			)
			(layer "F.Fab")
		)
		(fp_line
			(start 0.120396 0.2794)
			(end -0.12065 0.2794)
			(stroke
				(width 0.1)
				(type default)
			)
			(layer "F.Fab")
		)
		(fp_line
			(start -0.12065 -0.2794)
			(end 0.12065 -0.2794)
			(stroke
				(width 0.1)
				(type default)
			)
			(layer "F.Fab")
		)
		(fp_line
			(start 0.12065 -0.2794)
			(end 0.12065 -0.3048)
			(stroke
				(width 0.1)
				(type default)
			)
			(layer "F.Fab")
		)
		(fp_line
			(start 0.12065 -0.3048)
			(end 0.67945 -0.3048)
			(stroke
				(width 0.1)
				(type default)
			)
			(layer "F.Fab")
		)
		(fp_line
			(start 0.67945 -0.3048)
			(end 0.67945 0.3048)
			(stroke
				(width 0.1)
				(type default)
			)
			(layer "F.Fab")
		)
		(fp_line
			(start -0.67945 -0.305054)
			(end -0.12065 -0.305054)
			(stroke
				(width 0.1)
				(type default)
			)
			(layer "F.Fab")
		)
		(fp_line
			(start -0.12065 -0.305054)
			(end -0.12065 -0.2794)
			(stroke
				(width 0.1)
				(type default)
			)
			(layer "F.Fab")
		)
		(pad "1" smd circle
			(at -0.40005 0 270)
			(size 0 0)
			(layers "F.Cu" "F.Mask" "F.Paste")
			(net "P12V_NIC6_R")
		)
		(pad "2" smd circle
			(at 0.40005 0 270)
			(size 0 0)
			(layers "F.Cu" "F.Mask" "F.Paste")
			(net "GND")
		)
	)
	(footprint ""
		(layer "F.Cu")
		(at 358.993186 -151.737822 180)
		(property "Reference" "PR7044"
			(at 0 0 180)
			(layer "F.SilkS")
			(hide yes)
			(effects
				(font
					(size 1.27 1.27)
				)
			)
		)
		(property "Value" ""
			(at 0 0 180)
			(layer "F.Fab")
			(effects
				(font
					(size 1.27 1.27)
				)
			)
		)
		(duplicate_pad_numbers_are_jumpers no)
		(fp_line
			(start 0.7874 0.4064)
			(end -0.7874 0.4064)
			(stroke
				(width 0.1524)
				(type default)
			)
			(layer "F.SilkS")
		)
		(fp_line
			(start 0.7874 -0.4064)
			(end 0.7874 0.4064)
			(stroke
				(width 0.1524)
				(type default)
			)
			(layer "F.SilkS")
		)
		(fp_line
			(start -0.7874 0.4064)
			(end -0.7874 -0.4064)
			(stroke
				(width 0.1524)
				(type default)
			)
			(layer "F.SilkS")
		)
		(fp_line
			(start -0.7874 -0.4064)
			(end 0.7874 -0.4064)
			(stroke
				(width 0.1524)
				(type default)
			)
			(layer "F.SilkS")
		)
		(fp_line
			(start 0.67945 0.3048)
			(end 0.120396 0.3048)
			(stroke
				(width 0.1)
				(type default)
			)
			(layer "F.Fab")
		)
		(fp_line
			(start 0.67945 -0.3048)
			(end 0.67945 0.3048)
			(stroke
				(width 0.1)
				(type default)
			)
			(layer "F.Fab")
		)
		(fp_line
			(start 0.12065 -0.2794)
			(end 0.12065 -0.3048)
			(stroke
				(width 0.1)
				(type default)
			)
			(layer "F.Fab")
		)
		(fp_line
			(start 0.12065 -0.3048)
			(end 0.67945 -0.3048)
			(stroke
				(width 0.1)
				(type default)
			)
			(layer "F.Fab")
		)
		(fp_line
			(start 0.120396 0.3048)
			(end 0.120396 0.2794)
			(stroke
				(width 0.1)
				(type default)
			)
			(layer "F.Fab")
		)
		(fp_line
			(start 0.120396 0.2794)
			(end -0.12065 0.2794)
			(stroke
				(width 0.1)
				(type default)
			)
			(layer "F.Fab")
		)
		(fp_line
			(start -0.12065 0.3048)
			(end -0.67945 0.3048)
			(stroke
				(width 0.1)
				(type default)
			)
			(layer "F.Fab")
		)
		(fp_line
			(start -0.12065 0.2794)
			(end -0.12065 0.3048)
			(stroke
				(width 0.1)
				(type default)
			)
			(layer "F.Fab")
		)
		(fp_line
			(start -0.12065 -0.2794)
			(end 0.12065 -0.2794)
			(stroke
				(width 0.1)
				(type default)
			)
			(layer "F.Fab")
		)
		(fp_line
			(start -0.12065 -0.305054)
			(end -0.12065 -0.2794)
			(stroke
				(width 0.1)
				(type default)
			)
			(layer "F.Fab")
		)
		(fp_line
			(start -0.67945 0.3048)
			(end -0.67945 -0.305054)
			(stroke
				(width 0.1)
				(type default)
			)
			(layer "F.Fab")
		)
		(fp_line
			(start -0.67945 -0.305054)
			(end -0.12065 -0.305054)
			(stroke
				(width 0.1)
				(type default)
			)
			(layer "F.Fab")
		)
		(pad "1" smd circle
			(at -0.40005 0 180)
			(size 0 0)
			(layers "F.Cu" "F.Mask" "F.Paste")
			(net "P12V_NIC6_R")
		)
		(pad "2" smd circle
			(at 0.40005 0 180)
			(size 0 0)
			(layers "F.Cu" "F.Mask" "F.Paste")
			(net "P12V_NIC6_CO_AVIN_PD")
		)
	)
	(footprint ""
		(layer "F.Cu")
		(at 319.140332 -141.404848 -90)
		(property "Reference" "R298"
			(at 0 0 270)
			(layer "F.SilkS")
			(hide yes)
			(effects
				(font
					(size 1.27 1.27)
				)
			)
		)
		(property "Value" ""
			(at 0 0 270)
			(layer "F.Fab")
			(effects
				(font
					(size 1.27 1.27)
				)
			)
		)
		(duplicate_pad_numbers_are_jumpers no)
		(fp_line
			(start -0.7874 0.4064)
			(end -0.7874 -0.4064)
			(stroke
				(width 0.1524)
				(type default)
			)
			(layer "F.SilkS")
		)
		(fp_line
			(start 0.7874 0.4064)
			(end -0.7874 0.4064)
			(stroke
				(width 0.1524)
				(type default)
			)
			(layer "F.SilkS")
		)
		(fp_line
			(start -0.7874 -0.4064)
			(end 0.7874 -0.4064)
			(stroke
				(width 0.1524)
				(type default)
			)
			(layer "F.SilkS")
		)
		(fp_line
			(start 0.7874 -0.4064)
			(end 0.7874 0.4064)
			(stroke
				(width 0.1524)
				(type default)
			)
			(layer "F.SilkS")
		)
		(fp_line
			(start -0.67945 0.3048)
			(end -0.67945 -0.305054)
			(stroke
				(width 0.1)
				(type default)
			)
			(layer "F.Fab")
		)
		(fp_line
			(start -0.12065 0.3048)
			(end -0.67945 0.3048)
			(stroke
				(width 0.1)
				(type default)
			)
			(layer "F.Fab")
		)
		(fp_line
			(start 0.120396 0.3048)
			(end 0.120396 0.2794)
			(stroke
				(width 0.1)
				(type default)
			)
			(layer "F.Fab")
		)
		(fp_line
			(start 0.67945 0.3048)
			(end 0.120396 0.3048)
			(stroke
				(width 0.1)
				(type default)
			)
			(layer "F.Fab")
		)
		(fp_line
			(start -0.12065 0.2794)
			(end -0.12065 0.3048)
			(stroke
				(width 0.1)
				(type default)
			)
			(layer "F.Fab")
		)
		(fp_line
			(start 0.120396 0.2794)
			(end -0.12065 0.2794)
			(stroke
				(width 0.1)
				(type default)
			)
			(layer "F.Fab")
		)
		(fp_line
			(start -0.12065 -0.2794)
			(end 0.12065 -0.2794)
			(stroke
				(width 0.1)
				(type default)
			)
			(layer "F.Fab")
		)
		(fp_line
			(start 0.12065 -0.2794)
			(end 0.12065 -0.3048)
			(stroke
				(width 0.1)
				(type default)
			)
			(layer "F.Fab")
		)
		(fp_line
			(start 0.12065 -0.3048)
			(end 0.67945 -0.3048)
			(stroke
				(width 0.1)
				(type default)
			)
			(layer "F.Fab")
		)
		(fp_line
			(start 0.67945 -0.3048)
			(end 0.67945 0.3048)
			(stroke
				(width 0.1)
				(type default)
			)
			(layer "F.Fab")
		)
		(fp_line
			(start -0.67945 -0.305054)
			(end -0.12065 -0.305054)
			(stroke
				(width 0.1)
				(type default)
			)
			(layer "F.Fab")
		)
		(fp_line
			(start -0.12065 -0.305054)
			(end -0.12065 -0.2794)
			(stroke
				(width 0.1)
				(type default)
			)
			(layer "F.Fab")
		)
		(pad "1" smd circle
			(at -0.40005 0 270)
			(size 0 0)
			(layers "F.Cu" "F.Mask" "F.Paste")
			(net "PRSNT_NIC5_R_N")
		)
		(pad "2" smd circle
			(at 0.40005 0 270)
			(size 0 0)
			(layers "F.Cu" "F.Mask" "F.Paste")
			(net "PRSNT_NIC5_N")
		)
	)
	(footprint ""
		(layer "F.Cu")
		(at 306.227734 -35.876738)
		(property "Reference" "R6095"
			(at 0 0 0)
			(layer "F.SilkS")
			(hide yes)
			(effects
				(font
					(size 1.27 1.27)
				)
			)
		)
		(property "Value" ""
			(at 0 0 0)
			(layer "F.Fab")
			(effects
				(font
					(size 1.27 1.27)
				)
			)
		)
		(duplicate_pad_numbers_are_jumpers no)
		(fp_line
			(start -0.7874 -0.4064)
			(end 0.7874 -0.4064)
			(stroke
				(width 0.1524)
				(type default)
			)
			(layer "F.SilkS")
		)
		(fp_line
			(start -0.7874 0.4064)
			(end -0.7874 -0.4064)
			(stroke
				(width 0.1524)
				(type default)
			)
			(layer "F.SilkS")
		)
		(fp_line
			(start 0.7874 -0.4064)
			(end 0.7874 0.4064)
			(stroke
				(width 0.1524)
				(type default)
			)
			(layer "F.SilkS")
		)
		(fp_line
			(start 0.7874 0.4064)
			(end -0.7874 0.4064)
			(stroke
				(width 0.1524)
				(type default)
			)
			(layer "F.SilkS")
		)
		(fp_line
			(start -0.67945 -0.305054)
			(end -0.12065 -0.305054)
			(stroke
				(width 0.1)
				(type default)
			)
			(layer "F.Fab")
		)
		(fp_line
			(start -0.67945 0.3048)
			(end -0.67945 -0.305054)
			(stroke
				(width 0.1)
				(type default)
			)
			(layer "F.Fab")
		)
		(fp_line
			(start -0.12065 -0.305054)
			(end -0.12065 -0.2794)
			(stroke
				(width 0.1)
				(type default)
			)
			(layer "F.Fab")
		)
		(fp_line
			(start -0.12065 -0.2794)
			(end 0.12065 -0.2794)
			(stroke
				(width 0.1)
				(type default)
			)
			(layer "F.Fab")
		)
		(fp_line
			(start -0.12065 0.2794)
			(end -0.12065 0.3048)
			(stroke
				(width 0.1)
				(type default)
			)
			(layer "F.Fab")
		)
		(fp_line
			(start -0.12065 0.3048)
			(end -0.67945 0.3048)
			(stroke
				(width 0.1)
				(type default)
			)
			(layer "F.Fab")
		)
		(fp_line
			(start 0.120396 0.2794)
			(end -0.12065 0.2794)
			(stroke
				(width 0.1)
				(type default)
			)
			(layer "F.Fab")
		)
		(fp_line
			(start 0.120396 0.3048)
			(end 0.120396 0.2794)
			(stroke
				(width 0.1)
				(type default)
			)
			(layer "F.Fab")
		)
		(fp_line
			(start 0.12065 -0.3048)
			(end 0.67945 -0.3048)
			(stroke
				(width 0.1)
				(type default)
			)
			(layer "F.Fab")
		)
		(fp_line
			(start 0.12065 -0.2794)
			(end 0.12065 -0.3048)
			(stroke
				(width 0.1)
				(type default)
			)
			(layer "F.Fab")
		)
		(fp_line
			(start 0.67945 -0.3048)
			(end 0.67945 0.3048)
			(stroke
				(width 0.1)
				(type default)
			)
			(layer "F.Fab")
		)
		(fp_line
			(start 0.67945 0.3048)
			(end 0.120396 0.3048)
			(stroke
				(width 0.1)
				(type default)
			)
			(layer "F.Fab")
		)
		(pad "1" smd circle
			(at -0.40005 0)
			(size 0 0)
			(layers "F.Cu" "F.Mask" "F.Paste")
			(net "PWRGD_P3V3_SSD11_D")
		)
		(pad "2" smd circle
			(at 0.40005 0)
			(size 0 0)
			(layers "F.Cu" "F.Mask" "F.Paste")
			(net "PWRGD_P3V3_SSD11_R")
		)
	)
	(footprint ""
		(layer "F.Cu")
		(at 19.408394 -142.455392 180)
		(property "Reference" "R682"
			(at 0 0 180)
			(layer "F.SilkS")
			(hide yes)
			(effects
				(font
					(size 1.27 1.27)
				)
			)
		)
		(property "Value" ""
			(at 0 0 180)
			(layer "F.Fab")
			(effects
				(font
					(size 1.27 1.27)
				)
			)
		)
		(duplicate_pad_numbers_are_jumpers no)
		(fp_line
			(start 3.937508 1.8796)
			(end 3.937508 -1.8796)
			(stroke
				(width 0.1524)
				(type default)
			)
			(layer "F.SilkS")
		)
		(fp_line
			(start 3.937508 -1.8796)
			(end -3.937508 -1.8796)
			(stroke
				(width 0.1524)
				(type default)
			)
			(layer "F.SilkS")
		)
		(fp_line
			(start -3.937508 1.8796)
			(end 3.937508 1.8796)
			(stroke
				(width 0.1524)
				(type default)
			)
			(layer "F.SilkS")
		)
		(fp_line
			(start -3.937508 -1.8796)
			(end -3.937508 1.8796)
			(stroke
				(width 0.1524)
				(type default)
			)
			(layer "F.SilkS")
		)
		(fp_line
			(start 3.275076 1.674876)
			(end 3.275076 -1.674876)
			(stroke
				(width 0.1)
				(type default)
			)
			(layer "F.Fab")
		)
		(fp_line
			(start 3.275076 -1.674876)
			(end -3.275076 -1.674876)
			(stroke
				(width 0.1)
				(type default)
			)
			(layer "F.Fab")
		)
		(fp_line
			(start -3.275076 1.674876)
			(end 3.275076 1.674876)
			(stroke
				(width 0.1)
				(type default)
			)
			(layer "F.Fab")
		)
		(fp_line
			(start -3.275076 -1.674876)
			(end -3.275076 1.674876)
			(stroke
				(width 0.1)
				(type default)
			)
			(layer "F.Fab")
		)
		(pad "1" smd rect
			(at -2.350008 0 180)
			(size 2.921 3.5052)
			(layers "F.Cu" "F.Mask" "F.Paste")
			(net "P12V_NIC0")
		)
		(pad "2" smd rect
			(at 2.350008 0 180)
			(size 2.921 3.5052)
			(layers "F.Cu" "F.Mask" "F.Paste")
			(net "P12V_NIC0_R")
		)
	)
	(footprint ""
		(layer "F.Cu")
		(at 193.939668 -406.358598 90)
		(property "Reference" "U340"
			(at -4.146296 0.955548 0)
			(unlocked yes)
			(layer "F.SilkS")
			(effects
				(font
					(size 0.7874 0.5842)
					(thickness 0.1524)
				)
				(justify left)
			)
		)
		(property "Value" ""
			(at 0 0 90)
			(layer "F.Fab")
			(effects
				(font
					(size 1.27 1.27)
				)
			)
		)
		(duplicate_pad_numbers_are_jumpers no)
		(fp_line
			(start 2.0574 -1.651)
			(end 2.0574 1.651)
			(stroke
				(width 0.1524)
				(type default)
			)
			(layer "F.SilkS")
		)
		(fp_line
			(start 0.381 -1.651)
			(end 2.0574 -1.651)
			(stroke
				(width 0.1524)
				(type default)
			)
			(layer "F.SilkS")
		)
		(fp_line
			(start -0.381 -1.651)
			(end 0 -1.016)
			(stroke
				(width 0.1524)
				(type default)
			)
			(layer "F.SilkS")
		)
		(fp_line
			(start -2.0574 -1.651)
			(end -0.381 -1.651)
			(stroke
				(width 0.1524)
				(type default)
			)
			(layer "F.SilkS")
		)
		(fp_line
			(start 0 -1.016)
			(end 0.381 -1.651)
			(stroke
				(width 0.1524)
				(type default)
			)
			(layer "F.SilkS")
		)
		(fp_line
			(start 2.0574 1.651)
			(end -2.0574 1.651)
			(stroke
				(width 0.1524)
				(type default)
			)
			(layer "F.SilkS")
		)
		(fp_line
			(start -2.0574 1.651)
			(end -2.0574 -1.651)
			(stroke
				(width 0.1524)
				(type default)
			)
			(layer "F.SilkS")
		)
		(fp_poly
			(pts
				(xy -2.793492 -1.531112) (xy -2.351532 -1.973072) (xy -2.19202 -1.349502)
			)
			(stroke
				(width 0)
				(type default)
			)
			(fill yes)
			(layer "F.SilkS")
		)
		(fp_line
			(start 0.899922 -1.549908)
			(end 0.899922 -1.199896)
			(stroke
				(width 0.1)
				(type default)
			)
			(layer "F.Fab")
		)
		(fp_line
			(start -0.899922 -1.549908)
			(end 0.899922 -1.549908)
			(stroke
				(width 0.1)
				(type default)
			)
			(layer "F.Fab")
		)
		(fp_line
			(start 1.599946 -1.199896)
			(end 1.599946 1.199896)
			(stroke
				(width 0.1)
				(type default)
			)
			(layer "F.Fab")
		)
		(fp_line
			(start 0.899922 -1.199896)
			(end 1.599946 -1.199896)
			(stroke
				(width 0.1)
				(type default)
			)
			(layer "F.Fab")
		)
		(fp_line
			(start -0.899922 -1.199896)
			(end -0.899922 -1.549908)
			(stroke
				(width 0.1)
				(type default)
			)
			(layer "F.Fab")
		)
		(fp_line
			(start -1.599946 -1.199896)
			(end -0.899922 -1.199896)
			(stroke
				(width 0.1)
				(type default)
			)
			(layer "F.Fab")
		)
		(fp_line
			(start 1.599946 1.199896)
			(end 0.899922 1.199896)
			(stroke
				(width 0.1)
				(type default)
			)
			(layer "F.Fab")
		)
		(fp_line
			(start 0.899922 1.199896)
			(end 0.899922 1.549908)
			(stroke
				(width 0.1)
				(type default)
			)
			(layer "F.Fab")
		)
		(fp_line
			(start -0.899922 1.199896)
			(end -1.599946 1.199896)
			(stroke
				(width 0.1)
				(type default)
			)
			(layer "F.Fab")
		)
		(fp_line
			(start -1.599946 1.199896)
			(end -1.599946 -1.199896)
			(stroke
				(width 0.1)
				(type default)
			)
			(layer "F.Fab")
		)
		(fp_line
			(start 0.899922 1.549908)
			(end -0.899922 1.549908)
			(stroke
				(width 0.1)
				(type default)
			)
			(layer "F.Fab")
		)
		(fp_line
			(start -0.899922 1.549908)
			(end -0.899922 1.199896)
			(stroke
				(width 0.1)
				(type default)
			)
			(layer "F.Fab")
		)
		(fp_poly
			(pts
				(xy -2.71272 -0.719328) (xy -2.71272 -1.344168) (xy -2.159 -1.016)
			)
			(stroke
				(width 0)
				(type default)
			)
			(fill yes)
			(layer "F.Fab")
		)
		(pad "1" smd rect
			(at -1.225042 -0.94996)
			(size 0.5588 1.3462)
			(layers "F.Cu" "F.Mask" "F.Paste")
			(net "FM_HSC_FAULT_N")
		)
		(pad "2" smd rect
			(at -1.225042 0)
			(size 0.5588 1.3462)
			(layers "F.Cu" "F.Mask" "F.Paste")
			(net "HSC_ALERT1_R_N")
		)
		(pad "3" smd rect
			(at -1.225042 0.94996)
			(size 0.5588 1.3462)
			(layers "F.Cu" "F.Mask" "F.Paste")
			(net "GND")
		)
		(pad "4" smd rect
			(at 1.225042 0.94996)
			(size 0.5588 1.3462)
			(layers "F.Cu" "F.Mask" "F.Paste")
			(net "SMB_ALERT_HSC_N")
		)
		(pad "5" smd rect
			(at 1.225042 -0.94996)
			(size 0.5588 1.3462)
			(layers "F.Cu" "F.Mask" "F.Paste")
			(net "P3V3_AUX")
		)
	)
	(footprint ""
		(layer "F.Cu")
		(at 376.706384 -250.070874 -90)
		(property "Reference" "R1403"
			(at 0 0 270)
			(layer "F.SilkS")
			(hide yes)
			(effects
				(font
					(size 1.27 1.27)
				)
			)
		)
		(property "Value" ""
			(at 0 0 270)
			(layer "F.Fab")
			(effects
				(font
					(size 1.27 1.27)
				)
			)
		)
		(duplicate_pad_numbers_are_jumpers no)
		(fp_line
			(start -0.7874 0.4064)
			(end -0.7874 -0.4064)
			(stroke
				(width 0.1524)
				(type default)
			)
			(layer "F.SilkS")
		)
		(fp_line
			(start 0.7874 0.4064)
			(end -0.7874 0.4064)
			(stroke
				(width 0.1524)
				(type default)
			)
			(layer "F.SilkS")
		)
		(fp_line
			(start -0.7874 -0.4064)
			(end 0.7874 -0.4064)
			(stroke
				(width 0.1524)
				(type default)
			)
			(layer "F.SilkS")
		)
		(fp_line
			(start 0.7874 -0.4064)
			(end 0.7874 0.4064)
			(stroke
				(width 0.1524)
				(type default)
			)
			(layer "F.SilkS")
		)
		(fp_line
			(start -0.67945 0.3048)
			(end -0.67945 -0.305054)
			(stroke
				(width 0.1)
				(type default)
			)
			(layer "F.Fab")
		)
		(fp_line
			(start -0.12065 0.3048)
			(end -0.67945 0.3048)
			(stroke
				(width 0.1)
				(type default)
			)
			(layer "F.Fab")
		)
		(fp_line
			(start 0.120396 0.3048)
			(end 0.120396 0.2794)
			(stroke
				(width 0.1)
				(type default)
			)
			(layer "F.Fab")
		)
		(fp_line
			(start 0.67945 0.3048)
			(end 0.120396 0.3048)
			(stroke
				(width 0.1)
				(type default)
			)
			(layer "F.Fab")
		)
		(fp_line
			(start -0.12065 0.2794)
			(end -0.12065 0.3048)
			(stroke
				(width 0.1)
				(type default)
			)
			(layer "F.Fab")
		)
		(fp_line
			(start 0.120396 0.2794)
			(end -0.12065 0.2794)
			(stroke
				(width 0.1)
				(type default)
			)
			(layer "F.Fab")
		)
		(fp_line
			(start -0.12065 -0.2794)
			(end 0.12065 -0.2794)
			(stroke
				(width 0.1)
				(type default)
			)
			(layer "F.Fab")
		)
		(fp_line
			(start 0.12065 -0.2794)
			(end 0.12065 -0.3048)
			(stroke
				(width 0.1)
				(type default)
			)
			(layer "F.Fab")
		)
		(fp_line
			(start 0.12065 -0.3048)
			(end 0.67945 -0.3048)
			(stroke
				(width 0.1)
				(type default)
			)
			(layer "F.Fab")
		)
		(fp_line
			(start 0.67945 -0.3048)
			(end 0.67945 0.3048)
			(stroke
				(width 0.1)
				(type default)
			)
			(layer "F.Fab")
		)
		(fp_line
			(start -0.67945 -0.305054)
			(end -0.12065 -0.305054)
			(stroke
				(width 0.1)
				(type default)
			)
			(layer "F.Fab")
		)
		(fp_line
			(start -0.12065 -0.305054)
			(end -0.12065 -0.2794)
			(stroke
				(width 0.1)
				(type default)
			)
			(layer "F.Fab")
		)
		(pad "1" smd circle
			(at -0.40005 0 270)
			(size 0 0)
			(layers "F.Cu" "F.Mask" "F.Paste")
			(net "PEX3_DBG_MODE3")
		)
		(pad "2" smd circle
			(at 0.40005 0 270)
			(size 0 0)
			(layers "F.Cu" "F.Mask" "F.Paste")
			(net "P1V8_PEX")
		)
	)
	(footprint ""
		(layer "F.Cu")
		(at 52.610512 -18.61439 90)
		(property "Reference" "U127"
			(at -1.44399 2.407158 90)
			(unlocked yes)
			(layer "F.SilkS")
			(effects
				(font
					(size 0.7874 0.5842)
					(thickness 0.1524)
				)
				(justify left)
			)
		)
		(property "Value" ""
			(at 0 0 90)
			(layer "F.Fab")
			(effects
				(font
					(size 1.27 1.27)
				)
			)
		)
		(duplicate_pad_numbers_are_jumpers no)
		(fp_line
			(start 1.463548 -1.549908)
			(end 1.463548 1.549908)
			(stroke
				(width 0.1524)
				(type default)
			)
			(layer "F.SilkS")
		)
		(fp_line
			(start 0.762 -1.549908)
			(end 1.463548 -1.549908)
			(stroke
				(width 0.1524)
				(type default)
			)
			(layer "F.SilkS")
		)
		(fp_line
			(start -0.787908 -1.549908)
			(end 0 -0.762)
			(stroke
				(width 0.1524)
				(type default)
			)
			(layer "F.SilkS")
		)
		(fp_line
			(start -1.463548 -1.549908)
			(end -0.787908 -1.549908)
			(stroke
				(width 0.1524)
				(type default)
			)
			(layer "F.SilkS")
		)
		(fp_line
			(start 0 -0.762)
			(end 0.762 -1.549908)
			(stroke
				(width 0.1524)
				(type default)
			)
			(layer "F.SilkS")
		)
		(fp_line
			(start 1.463548 1.549908)
			(end -1.463548 1.549908)
			(stroke
				(width 0.1524)
				(type default)
			)
			(layer "F.SilkS")
		)
		(fp_line
			(start -1.463548 1.549908)
			(end -1.463548 -1.549908)
			(stroke
				(width 0.1524)
				(type default)
			)
			(layer "F.SilkS")
		)
		(fp_poly
			(pts
				(xy -3.4798 -1.359916) (xy -2.86004 -1.050036) (xy -3.4798 -0.740156)
			)
			(stroke
				(width 0)
				(type default)
			)
			(fill yes)
			(layer "F.SilkS")
		)
		(fp_line
			(start 1.549908 -1.549908)
			(end 1.549908 1.549908)
			(stroke
				(width 0.1)
				(type default)
			)
			(layer "F.Fab")
		)
		(fp_line
			(start -1.549908 -1.549908)
			(end 1.549908 -1.549908)
			(stroke
				(width 0.1)
				(type default)
			)
			(layer "F.Fab")
		)
		(fp_line
			(start 1.549908 1.549908)
			(end -1.549908 1.549908)
			(stroke
				(width 0.1)
				(type default)
			)
			(layer "F.Fab")
		)
		(fp_line
			(start -1.549908 1.549908)
			(end -1.549908 -1.549908)
			(stroke
				(width 0.1)
				(type default)
			)
			(layer "F.Fab")
		)
		(fp_poly
			(pts
				(xy -3.4798 -1.359916) (xy -2.86004 -1.050036) (xy -3.4798 -0.740156)
			)
			(stroke
				(width 0)
				(type default)
			)
			(fill yes)
			(layer "F.Fab")
		)
		(pad "1" smd rect
			(at -2.175002 -1.050036 180)
			(size 0.6096 1.1684)
			(layers "F.Cu" "F.Mask" "F.Paste")
			(net "P3V3_SSD1")
		)
		(pad "2" smd rect
			(at -2.175002 -0.32512 180)
			(size 0.4318 1.1684)
			(layers "F.Cu" "F.Mask" "F.Paste")
			(net "SMB_ISO_SSD1_SCL")
		)
		(pad "3" smd rect
			(at -2.175002 0.32512 180)
			(size 0.4318 1.1684)
			(layers "F.Cu" "F.Mask" "F.Paste")
			(net "SMB_ISO_SSD1_SDA")
		)
		(pad "4" smd rect
			(at -2.175002 1.050036 180)
			(size 0.6096 1.1684)
			(layers "F.Cu" "F.Mask" "F.Paste")
			(net "GND")
		)
		(pad "5" smd rect
			(at 2.175002 1.050036 180)
			(size 0.6096 1.1684)
			(layers "F.Cu" "F.Mask" "F.Paste")
			(net "SMB_SSD1_ISO_EN")
		)
		(pad "6" smd rect
			(at 2.175002 0.32512 180)
			(size 0.4318 1.1684)
			(layers "F.Cu" "F.Mask" "F.Paste")
			(net "SMB_BIC_I2C9_MUX0_SSD1_R_SDA")
		)
		(pad "7" smd rect
			(at 2.175002 -0.32512 180)
			(size 0.4318 1.1684)
			(layers "F.Cu" "F.Mask" "F.Paste")
			(net "SMB_BIC_I2C9_MUX0_SSD1_R_SCL")
		)
		(pad "8" smd rect
			(at 2.175002 -1.050036 180)
			(size 0.6096 1.1684)
			(layers "F.Cu" "F.Mask" "F.Paste")
			(net "P3V3_AUX")
		)
	)
	(footprint ""
		(layer "F.Cu")
		(at 457.935838 -316.300358)
		(property "Reference" "PC266"
			(at 0 0 0)
			(layer "F.SilkS")
			(hide yes)
			(effects
				(font
					(size 1.27 1.27)
				)
			)
		)
		(property "Value" ""
			(at 0 0 0)
			(layer "F.Fab")
			(effects
				(font
					(size 1.27 1.27)
				)
			)
		)
		(duplicate_pad_numbers_are_jumpers no)
		(fp_line
			(start -1.524 -0.762)
			(end 1.524 -0.762)
			(stroke
				(width 0.1524)
				(type default)
			)
			(layer "F.SilkS")
		)
		(fp_line
			(start -1.524 0.762)
			(end -1.524 -0.762)
			(stroke
				(width 0.1524)
				(type default)
			)
			(layer "F.SilkS")
		)
		(fp_line
			(start 1.524 -0.762)
			(end 1.524 0.762)
			(stroke
				(width 0.1524)
				(type default)
			)
			(layer "F.SilkS")
		)
		(fp_line
			(start 1.524 0.762)
			(end -1.524 0.762)
			(stroke
				(width 0.1524)
				(type default)
			)
			(layer "F.SilkS")
		)
		(fp_line
			(start -1.1049 -0.724916)
			(end -1.1049 0.724916)
			(stroke
				(width 0.1)
				(type default)
			)
			(layer "F.Fab")
		)
		(fp_line
			(start -1.1049 0.724916)
			(end 1.1049 0.724916)
			(stroke
				(width 0.1)
				(type default)
			)
			(layer "F.Fab")
		)
		(fp_line
			(start 1.1049 -0.724916)
			(end -1.1049 -0.724916)
			(stroke
				(width 0.1)
				(type default)
			)
			(layer "F.Fab")
		)
		(fp_line
			(start 1.1049 0.724916)
			(end 1.1049 -0.724916)
			(stroke
				(width 0.1)
				(type default)
			)
			(layer "F.Fab")
		)
		(pad "1" smd rect
			(at -0.889 0 180)
			(size 1.016 1.27)
			(layers "F.Cu" "F.Mask" "F.Paste")
			(net "SW_P12V_P1V25_PEX3_FLT")
		)
		(pad "2" smd rect
			(at 0.889 0 180)
			(size 1.016 1.27)
			(layers "F.Cu" "F.Mask" "F.Paste")
			(net "GND")
		)
	)
	(footprint ""
		(layer "F.Cu")
		(at 98.12528 -42.849038 180)
		(property "Reference" "R546"
			(at 0 0 180)
			(layer "F.SilkS")
			(hide yes)
			(effects
				(font
					(size 1.27 1.27)
				)
			)
		)
		(property "Value" ""
			(at 0 0 180)
			(layer "F.Fab")
			(effects
				(font
					(size 1.27 1.27)
				)
			)
		)
		(duplicate_pad_numbers_are_jumpers no)
		(fp_line
			(start 0.7874 0.4064)
			(end -0.7874 0.4064)
			(stroke
				(width 0.1524)
				(type default)
			)
			(layer "F.SilkS")
		)
		(fp_line
			(start 0.7874 -0.4064)
			(end 0.7874 0.4064)
			(stroke
				(width 0.1524)
				(type default)
			)
			(layer "F.SilkS")
		)
		(fp_line
			(start -0.7874 0.4064)
			(end -0.7874 -0.4064)
			(stroke
				(width 0.1524)
				(type default)
			)
			(layer "F.SilkS")
		)
		(fp_line
			(start -0.7874 -0.4064)
			(end 0.7874 -0.4064)
			(stroke
				(width 0.1524)
				(type default)
			)
			(layer "F.SilkS")
		)
		(fp_line
			(start 0.67945 0.3048)
			(end 0.120396 0.3048)
			(stroke
				(width 0.1)
				(type default)
			)
			(layer "F.Fab")
		)
		(fp_line
			(start 0.67945 -0.3048)
			(end 0.67945 0.3048)
			(stroke
				(width 0.1)
				(type default)
			)
			(layer "F.Fab")
		)
		(fp_line
			(start 0.12065 -0.2794)
			(end 0.12065 -0.3048)
			(stroke
				(width 0.1)
				(type default)
			)
			(layer "F.Fab")
		)
		(fp_line
			(start 0.12065 -0.3048)
			(end 0.67945 -0.3048)
			(stroke
				(width 0.1)
				(type default)
			)
			(layer "F.Fab")
		)
		(fp_line
			(start 0.120396 0.3048)
			(end 0.120396 0.2794)
			(stroke
				(width 0.1)
				(type default)
			)
			(layer "F.Fab")
		)
		(fp_line
			(start 0.120396 0.2794)
			(end -0.12065 0.2794)
			(stroke
				(width 0.1)
				(type default)
			)
			(layer "F.Fab")
		)
		(fp_line
			(start -0.12065 0.3048)
			(end -0.67945 0.3048)
			(stroke
				(width 0.1)
				(type default)
			)
			(layer "F.Fab")
		)
		(fp_line
			(start -0.12065 0.2794)
			(end -0.12065 0.3048)
			(stroke
				(width 0.1)
				(type default)
			)
			(layer "F.Fab")
		)
		(fp_line
			(start -0.12065 -0.2794)
			(end 0.12065 -0.2794)
			(stroke
				(width 0.1)
				(type default)
			)
			(layer "F.Fab")
		)
		(fp_line
			(start -0.12065 -0.305054)
			(end -0.12065 -0.2794)
			(stroke
				(width 0.1)
				(type default)
			)
			(layer "F.Fab")
		)
		(fp_line
			(start -0.67945 0.3048)
			(end -0.67945 -0.305054)
			(stroke
				(width 0.1)
				(type default)
			)
			(layer "F.Fab")
		)
		(fp_line
			(start -0.67945 -0.305054)
			(end -0.12065 -0.305054)
			(stroke
				(width 0.1)
				(type default)
			)
			(layer "F.Fab")
		)
		(pad "1" smd circle
			(at -0.40005 0 180)
			(size 0 0)
			(layers "F.Cu" "F.Mask" "F.Paste")
			(net "P12V_SSD3_R")
		)
		(pad "2" smd circle
			(at 0.40005 0 180)
			(size 0 0)
			(layers "F.Cu" "F.Mask" "F.Paste")
			(net "P12V_SSD3_VIN_P")
		)
	)
	(footprint ""
		(layer "F.Cu")
		(at 19.02714 -174.247048 -90)
		(property "Reference" "R502"
			(at 0 0 270)
			(layer "F.SilkS")
			(hide yes)
			(effects
				(font
					(size 1.27 1.27)
				)
			)
		)
		(property "Value" ""
			(at 0 0 270)
			(layer "F.Fab")
			(effects
				(font
					(size 1.27 1.27)
				)
			)
		)
		(duplicate_pad_numbers_are_jumpers no)
		(fp_line
			(start -0.7874 0.4064)
			(end -0.7874 -0.4064)
			(stroke
				(width 0.1524)
				(type default)
			)
			(layer "F.SilkS")
		)
		(fp_line
			(start 0.7874 0.4064)
			(end -0.7874 0.4064)
			(stroke
				(width 0.1524)
				(type default)
			)
			(layer "F.SilkS")
		)
		(fp_line
			(start -0.7874 -0.4064)
			(end 0.7874 -0.4064)
			(stroke
				(width 0.1524)
				(type default)
			)
			(layer "F.SilkS")
		)
		(fp_line
			(start 0.7874 -0.4064)
			(end 0.7874 0.4064)
			(stroke
				(width 0.1524)
				(type default)
			)
			(layer "F.SilkS")
		)
		(fp_line
			(start -0.67945 0.3048)
			(end -0.67945 -0.305054)
			(stroke
				(width 0.1)
				(type default)
			)
			(layer "F.Fab")
		)
		(fp_line
			(start -0.12065 0.3048)
			(end -0.67945 0.3048)
			(stroke
				(width 0.1)
				(type default)
			)
			(layer "F.Fab")
		)
		(fp_line
			(start 0.120396 0.3048)
			(end 0.120396 0.2794)
			(stroke
				(width 0.1)
				(type default)
			)
			(layer "F.Fab")
		)
		(fp_line
			(start 0.67945 0.3048)
			(end 0.120396 0.3048)
			(stroke
				(width 0.1)
				(type default)
			)
			(layer "F.Fab")
		)
		(fp_line
			(start -0.12065 0.2794)
			(end -0.12065 0.3048)
			(stroke
				(width 0.1)
				(type default)
			)
			(layer "F.Fab")
		)
		(fp_line
			(start 0.120396 0.2794)
			(end -0.12065 0.2794)
			(stroke
				(width 0.1)
				(type default)
			)
			(layer "F.Fab")
		)
		(fp_line
			(start -0.12065 -0.2794)
			(end 0.12065 -0.2794)
			(stroke
				(width 0.1)
				(type default)
			)
			(layer "F.Fab")
		)
		(fp_line
			(start 0.12065 -0.2794)
			(end 0.12065 -0.3048)
			(stroke
				(width 0.1)
				(type default)
			)
			(layer "F.Fab")
		)
		(fp_line
			(start 0.12065 -0.3048)
			(end 0.67945 -0.3048)
			(stroke
				(width 0.1)
				(type default)
			)
			(layer "F.Fab")
		)
		(fp_line
			(start 0.67945 -0.3048)
			(end 0.67945 0.3048)
			(stroke
				(width 0.1)
				(type default)
			)
			(layer "F.Fab")
		)
		(fp_line
			(start -0.67945 -0.305054)
			(end -0.12065 -0.305054)
			(stroke
				(width 0.1)
				(type default)
			)
			(layer "F.Fab")
		)
		(fp_line
			(start -0.12065 -0.305054)
			(end -0.12065 -0.2794)
			(stroke
				(width 0.1)
				(type default)
			)
			(layer "F.Fab")
		)
		(pad "1" smd circle
			(at -0.40005 0 270)
			(size 0 0)
			(layers "F.Cu" "F.Mask" "F.Paste")
			(net "PWRGD_P5V_AUX")
		)
		(pad "2" smd circle
			(at 0.40005 0 270)
			(size 0 0)
			(layers "F.Cu" "F.Mask" "F.Paste")
			(net "GND")
		)
	)
	(footprint ""
		(layer "F.Cu")
		(at 294.70985 -165.670484 -90)
		(property "Reference" "R2468"
			(at 0 0 270)
			(layer "F.SilkS")
			(hide yes)
			(effects
				(font
					(size 1.27 1.27)
				)
			)
		)
		(property "Value" ""
			(at 0 0 270)
			(layer "F.Fab")
			(effects
				(font
					(size 1.27 1.27)
				)
			)
		)
		(duplicate_pad_numbers_are_jumpers no)
		(fp_line
			(start -0.7874 0.4064)
			(end -0.7874 -0.4064)
			(stroke
				(width 0.1524)
				(type default)
			)
			(layer "F.SilkS")
		)
		(fp_line
			(start 0.7874 0.4064)
			(end -0.7874 0.4064)
			(stroke
				(width 0.1524)
				(type default)
			)
			(layer "F.SilkS")
		)
		(fp_line
			(start -0.7874 -0.4064)
			(end 0.7874 -0.4064)
			(stroke
				(width 0.1524)
				(type default)
			)
			(layer "F.SilkS")
		)
		(fp_line
			(start 0.7874 -0.4064)
			(end 0.7874 0.4064)
			(stroke
				(width 0.1524)
				(type default)
			)
			(layer "F.SilkS")
		)
		(fp_line
			(start -0.67945 0.3048)
			(end -0.67945 -0.305054)
			(stroke
				(width 0.1)
				(type default)
			)
			(layer "F.Fab")
		)
		(fp_line
			(start -0.12065 0.3048)
			(end -0.67945 0.3048)
			(stroke
				(width 0.1)
				(type default)
			)
			(layer "F.Fab")
		)
		(fp_line
			(start 0.120396 0.3048)
			(end 0.120396 0.2794)
			(stroke
				(width 0.1)
				(type default)
			)
			(layer "F.Fab")
		)
		(fp_line
			(start 0.67945 0.3048)
			(end 0.120396 0.3048)
			(stroke
				(width 0.1)
				(type default)
			)
			(layer "F.Fab")
		)
		(fp_line
			(start -0.12065 0.2794)
			(end -0.12065 0.3048)
			(stroke
				(width 0.1)
				(type default)
			)
			(layer "F.Fab")
		)
		(fp_line
			(start 0.120396 0.2794)
			(end -0.12065 0.2794)
			(stroke
				(width 0.1)
				(type default)
			)
			(layer "F.Fab")
		)
		(fp_line
			(start -0.12065 -0.2794)
			(end 0.12065 -0.2794)
			(stroke
				(width 0.1)
				(type default)
			)
			(layer "F.Fab")
		)
		(fp_line
			(start 0.12065 -0.2794)
			(end 0.12065 -0.3048)
			(stroke
				(width 0.1)
				(type default)
			)
			(layer "F.Fab")
		)
		(fp_line
			(start 0.12065 -0.3048)
			(end 0.67945 -0.3048)
			(stroke
				(width 0.1)
				(type default)
			)
			(layer "F.Fab")
		)
		(fp_line
			(start 0.67945 -0.3048)
			(end 0.67945 0.3048)
			(stroke
				(width 0.1)
				(type default)
			)
			(layer "F.Fab")
		)
		(fp_line
			(start -0.67945 -0.305054)
			(end -0.12065 -0.305054)
			(stroke
				(width 0.1)
				(type default)
			)
			(layer "F.Fab")
		)
		(fp_line
			(start -0.12065 -0.305054)
			(end -0.12065 -0.2794)
			(stroke
				(width 0.1)
				(type default)
			)
			(layer "F.Fab")
		)
		(pad "1" smd circle
			(at -0.40005 0 270)
			(size 0 0)
			(layers "F.Cu" "F.Mask" "F.Paste")
			(net "NIC4_PWRBRK_R_N")
		)
		(pad "2" smd circle
			(at 0.40005 0 270)
			(size 0 0)
			(layers "F.Cu" "F.Mask" "F.Paste")
			(net "NIC4_PWRBRK_N")
		)
	)
	(footprint ""
		(layer "F.Cu")
		(at 324.991222 -235.075222 90)
		(property "Reference" "R4388"
			(at 0 0 90)
			(layer "F.SilkS")
			(hide yes)
			(effects
				(font
					(size 1.27 1.27)
				)
			)
		)
		(property "Value" ""
			(at 0 0 90)
			(layer "F.Fab")
			(effects
				(font
					(size 1.27 1.27)
				)
			)
		)
		(duplicate_pad_numbers_are_jumpers no)
		(fp_line
			(start 0.7874 -0.4064)
			(end 0.7874 0.4064)
			(stroke
				(width 0.1524)
				(type default)
			)
			(layer "F.SilkS")
		)
		(fp_line
			(start -0.7874 -0.4064)
			(end 0.7874 -0.4064)
			(stroke
				(width 0.1524)
				(type default)
			)
			(layer "F.SilkS")
		)
		(fp_line
			(start 0.7874 0.4064)
			(end -0.7874 0.4064)
			(stroke
				(width 0.1524)
				(type default)
			)
			(layer "F.SilkS")
		)
		(fp_line
			(start -0.7874 0.4064)
			(end -0.7874 -0.4064)
			(stroke
				(width 0.1524)
				(type default)
			)
			(layer "F.SilkS")
		)
		(fp_line
			(start -0.12065 -0.305054)
			(end -0.12065 -0.2794)
			(stroke
				(width 0.1)
				(type default)
			)
			(layer "F.Fab")
		)
		(fp_line
			(start -0.67945 -0.305054)
			(end -0.12065 -0.305054)
			(stroke
				(width 0.1)
				(type default)
			)
			(layer "F.Fab")
		)
		(fp_line
			(start 0.67945 -0.3048)
			(end 0.67945 0.3048)
			(stroke
				(width 0.1)
				(type default)
			)
			(layer "F.Fab")
		)
		(fp_line
			(start 0.12065 -0.3048)
			(end 0.67945 -0.3048)
			(stroke
				(width 0.1)
				(type default)
			)
			(layer "F.Fab")
		)
		(fp_line
			(start 0.12065 -0.2794)
			(end 0.12065 -0.3048)
			(stroke
				(width 0.1)
				(type default)
			)
			(layer "F.Fab")
		)
		(fp_line
			(start -0.12065 -0.2794)
			(end 0.12065 -0.2794)
			(stroke
				(width 0.1)
				(type default)
			)
			(layer "F.Fab")
		)
		(fp_line
			(start 0.120396 0.2794)
			(end -0.12065 0.2794)
			(stroke
				(width 0.1)
				(type default)
			)
			(layer "F.Fab")
		)
		(fp_line
			(start -0.12065 0.2794)
			(end -0.12065 0.3048)
			(stroke
				(width 0.1)
				(type default)
			)
			(layer "F.Fab")
		)
		(fp_line
			(start 0.67945 0.3048)
			(end 0.120396 0.3048)
			(stroke
				(width 0.1)
				(type default)
			)
			(layer "F.Fab")
		)
		(fp_line
			(start 0.120396 0.3048)
			(end 0.120396 0.2794)
			(stroke
				(width 0.1)
				(type default)
			)
			(layer "F.Fab")
		)
		(fp_line
			(start -0.12065 0.3048)
			(end -0.67945 0.3048)
			(stroke
				(width 0.1)
				(type default)
			)
			(layer "F.Fab")
		)
		(fp_line
			(start -0.67945 0.3048)
			(end -0.67945 -0.305054)
			(stroke
				(width 0.1)
				(type default)
			)
			(layer "F.Fab")
		)
		(pad "1" smd circle
			(at -0.40005 0 90)
			(size 0 0)
			(layers "F.Cu" "F.Mask" "F.Paste")
			(net "RST_PEX_SYS_BUF_R_N")
		)
		(pad "2" smd circle
			(at 0.40005 0 90)
			(size 0 0)
			(layers "F.Cu" "F.Mask" "F.Paste")
			(net "RST_PEX1_SYS_N")
		)
	)
	(footprint ""
		(layer "F.Cu")
		(at 338.64169 -293.5351 90)
		(property "Reference" "PL12"
			(at -4.920234 28.63723 90)
			(unlocked yes)
			(layer "F.SilkS")
			(effects
				(font
					(size 0.7874 0.5842)
					(thickness 0.1524)
				)
				(justify left)
			)
		)
		(property "Value" ""
			(at 0 0 90)
			(layer "F.Fab")
			(effects
				(font
					(size 1.27 1.27)
				)
			)
		)
		(duplicate_pad_numbers_are_jumpers no)
		(fp_line
			(start 4.800092 -3.199892)
			(end 4.800092 -1.6764)
			(stroke
				(width 0.1524)
				(type default)
			)
			(layer "F.SilkS")
		)
		(fp_line
			(start -4.800092 -3.199892)
			(end 4.800092 -3.199892)
			(stroke
				(width 0.1524)
				(type default)
			)
			(layer "F.SilkS")
		)
		(fp_line
			(start -4.800092 -1.6764)
			(end -4.800092 -3.199892)
			(stroke
				(width 0.1524)
				(type default)
			)
			(layer "F.SilkS")
		)
		(fp_line
			(start 4.800092 1.6764)
			(end 4.800092 3.199892)
			(stroke
				(width 0.1524)
				(type default)
			)
			(layer "F.SilkS")
		)
		(fp_line
			(start 4.800092 3.199892)
			(end -4.800092 3.199892)
			(stroke
				(width 0.1524)
				(type default)
			)
			(layer "F.SilkS")
		)
		(fp_line
			(start -4.800092 3.199892)
			(end -4.800092 1.6764)
			(stroke
				(width 0.1524)
				(type default)
			)
			(layer "F.SilkS")
		)
		(fp_line
			(start 4.800092 -3.199892)
			(end 4.800092 3.199892)
			(stroke
				(width 0.1)
				(type default)
			)
			(layer "F.Fab")
		)
		(fp_line
			(start -4.800092 -3.199892)
			(end 4.800092 -3.199892)
			(stroke
				(width 0.1)
				(type default)
			)
			(layer "F.Fab")
		)
		(fp_line
			(start 4.800092 3.199892)
			(end -4.800092 3.199892)
			(stroke
				(width 0.1)
				(type default)
			)
			(layer "F.Fab")
		)
		(fp_line
			(start -4.800092 3.199892)
			(end -4.800092 -3.199892)
			(stroke
				(width 0.1)
				(type default)
			)
			(layer "F.Fab")
		)
		(pad "1" smd rect
			(at -3.074924 0 180)
			(size 3.0988 3.3528)
			(layers "F.Cu" "F.Mask" "F.Paste")
			(net "SW_P0V8_PEX2_PH1")
		)
		(pad "2" smd rect
			(at 3.074924 0 180)
			(size 3.0988 3.3528)
			(layers "F.Cu" "F.Mask" "F.Paste")
			(net "P0V8_PEX2")
		)
	)
	(footprint ""
		(layer "F.Cu")
		(at 253.147322 -21.37156)
		(property "Reference" "C3929"
			(at 0 0 0)
			(layer "F.SilkS")
			(hide yes)
			(effects
				(font
					(size 1.27 1.27)
				)
			)
		)
		(property "Value" ""
			(at 0 0 0)
			(layer "F.Fab")
			(effects
				(font
					(size 1.27 1.27)
				)
			)
		)
		(duplicate_pad_numbers_are_jumpers no)
		(fp_line
			(start -0.7874 -0.4064)
			(end 0.7874 -0.4064)
			(stroke
				(width 0.1524)
				(type default)
			)
			(layer "F.SilkS")
		)
		(fp_line
			(start -0.7874 0.4064)
			(end -0.7874 -0.4064)
			(stroke
				(width 0.1524)
				(type default)
			)
			(layer "F.SilkS")
		)
		(fp_line
			(start 0.7874 -0.4064)
			(end 0.7874 0.4064)
			(stroke
				(width 0.1524)
				(type default)
			)
			(layer "F.SilkS")
		)
		(fp_line
			(start 0.7874 0.4064)
			(end -0.7874 0.4064)
			(stroke
				(width 0.1524)
				(type default)
			)
			(layer "F.SilkS")
		)
		(fp_line
			(start -0.67945 -0.305054)
			(end -0.12065 -0.305054)
			(stroke
				(width 0.1)
				(type default)
			)
			(layer "F.Fab")
		)
		(fp_line
			(start -0.67945 0.3048)
			(end -0.67945 -0.305054)
			(stroke
				(width 0.1)
				(type default)
			)
			(layer "F.Fab")
		)
		(fp_line
			(start -0.12065 -0.305054)
			(end -0.12065 -0.2794)
			(stroke
				(width 0.1)
				(type default)
			)
			(layer "F.Fab")
		)
		(fp_line
			(start -0.12065 -0.2794)
			(end 0.12065 -0.2794)
			(stroke
				(width 0.1)
				(type default)
			)
			(layer "F.Fab")
		)
		(fp_line
			(start -0.12065 0.2794)
			(end -0.12065 0.3048)
			(stroke
				(width 0.1)
				(type default)
			)
			(layer "F.Fab")
		)
		(fp_line
			(start -0.12065 0.3048)
			(end -0.67945 0.3048)
			(stroke
				(width 0.1)
				(type default)
			)
			(layer "F.Fab")
		)
		(fp_line
			(start 0.120396 0.2794)
			(end -0.12065 0.2794)
			(stroke
				(width 0.1)
				(type default)
			)
			(layer "F.Fab")
		)
		(fp_line
			(start 0.120396 0.3048)
			(end 0.120396 0.2794)
			(stroke
				(width 0.1)
				(type default)
			)
			(layer "F.Fab")
		)
		(fp_line
			(start 0.12065 -0.3048)
			(end 0.67945 -0.3048)
			(stroke
				(width 0.1)
				(type default)
			)
			(layer "F.Fab")
		)
		(fp_line
			(start 0.12065 -0.2794)
			(end 0.12065 -0.3048)
			(stroke
				(width 0.1)
				(type default)
			)
			(layer "F.Fab")
		)
		(fp_line
			(start 0.67945 -0.3048)
			(end 0.67945 0.3048)
			(stroke
				(width 0.1)
				(type default)
			)
			(layer "F.Fab")
		)
		(fp_line
			(start 0.67945 0.3048)
			(end 0.120396 0.3048)
			(stroke
				(width 0.1)
				(type default)
			)
			(layer "F.Fab")
		)
		(pad "1" smd circle
			(at -0.40005 0)
			(size 0 0)
			(layers "F.Cu" "F.Mask" "F.Paste")
			(net "P12V_SSD8")
		)
		(pad "2" smd circle
			(at 0.40005 0)
			(size 0 0)
			(layers "F.Cu" "F.Mask" "F.Paste")
			(net "GND")
		)
	)
	(footprint ""
		(layer "F.Cu")
		(at 90.028268 -300.64202 -90)
		(property "Reference" "R3882"
			(at 0 0 270)
			(layer "F.SilkS")
			(hide yes)
			(effects
				(font
					(size 1.27 1.27)
				)
			)
		)
		(property "Value" ""
			(at 0 0 270)
			(layer "F.Fab")
			(effects
				(font
					(size 1.27 1.27)
				)
			)
		)
		(duplicate_pad_numbers_are_jumpers no)
		(fp_line
			(start -0.7874 0.4064)
			(end -0.7874 -0.4064)
			(stroke
				(width 0.1524)
				(type default)
			)
			(layer "F.SilkS")
		)
		(fp_line
			(start 0.7874 0.4064)
			(end -0.7874 0.4064)
			(stroke
				(width 0.1524)
				(type default)
			)
			(layer "F.SilkS")
		)
		(fp_line
			(start -0.7874 -0.4064)
			(end 0.7874 -0.4064)
			(stroke
				(width 0.1524)
				(type default)
			)
			(layer "F.SilkS")
		)
		(fp_line
			(start 0.7874 -0.4064)
			(end 0.7874 0.4064)
			(stroke
				(width 0.1524)
				(type default)
			)
			(layer "F.SilkS")
		)
		(fp_line
			(start -0.67945 0.3048)
			(end -0.67945 -0.305054)
			(stroke
				(width 0.1)
				(type default)
			)
			(layer "F.Fab")
		)
		(fp_line
			(start -0.12065 0.3048)
			(end -0.67945 0.3048)
			(stroke
				(width 0.1)
				(type default)
			)
			(layer "F.Fab")
		)
		(fp_line
			(start 0.120396 0.3048)
			(end 0.120396 0.2794)
			(stroke
				(width 0.1)
				(type default)
			)
			(layer "F.Fab")
		)
		(fp_line
			(start 0.67945 0.3048)
			(end 0.120396 0.3048)
			(stroke
				(width 0.1)
				(type default)
			)
			(layer "F.Fab")
		)
		(fp_line
			(start -0.12065 0.2794)
			(end -0.12065 0.3048)
			(stroke
				(width 0.1)
				(type default)
			)
			(layer "F.Fab")
		)
		(fp_line
			(start 0.120396 0.2794)
			(end -0.12065 0.2794)
			(stroke
				(width 0.1)
				(type default)
			)
			(layer "F.Fab")
		)
		(fp_line
			(start -0.12065 -0.2794)
			(end 0.12065 -0.2794)
			(stroke
				(width 0.1)
				(type default)
			)
			(layer "F.Fab")
		)
		(fp_line
			(start 0.12065 -0.2794)
			(end 0.12065 -0.3048)
			(stroke
				(width 0.1)
				(type default)
			)
			(layer "F.Fab")
		)
		(fp_line
			(start 0.12065 -0.3048)
			(end 0.67945 -0.3048)
			(stroke
				(width 0.1)
				(type default)
			)
			(layer "F.Fab")
		)
		(fp_line
			(start 0.67945 -0.3048)
			(end 0.67945 0.3048)
			(stroke
				(width 0.1)
				(type default)
			)
			(layer "F.Fab")
		)
		(fp_line
			(start -0.67945 -0.305054)
			(end -0.12065 -0.305054)
			(stroke
				(width 0.1)
				(type default)
			)
			(layer "F.Fab")
		)
		(fp_line
			(start -0.12065 -0.305054)
			(end -0.12065 -0.2794)
			(stroke
				(width 0.1)
				(type default)
			)
			(layer "F.Fab")
		)
		(pad "1" smd circle
			(at -0.40005 0 270)
			(size 0 0)
			(layers "F.Cu" "F.Mask" "F.Paste")
			(net "I2C0_PEX0_SDA")
		)
		(pad "2" smd circle
			(at 0.40005 0 270)
			(size 0 0)
			(layers "F.Cu" "F.Mask" "F.Paste")
			(net "I2C_PEX0_HOST_SDA")
		)
	)
	(footprint ""
		(layer "F.Cu")
		(at 191.055752 -343.952322 90)
		(property "Reference" "C2539"
			(at 0 0 90)
			(layer "F.SilkS")
			(hide yes)
			(effects
				(font
					(size 1.27 1.27)
				)
			)
		)
		(property "Value" ""
			(at 0 0 90)
			(layer "F.Fab")
			(effects
				(font
					(size 1.27 1.27)
				)
			)
		)
		(duplicate_pad_numbers_are_jumpers no)
		(fp_line
			(start 0.299974 -0.150114)
			(end 0.299974 0.150114)
			(stroke
				(width 0.1)
				(type default)
			)
			(layer "F.Fab")
		)
		(fp_line
			(start -0.299974 -0.150114)
			(end 0.299974 -0.150114)
			(stroke
				(width 0.1)
				(type default)
			)
			(layer "F.Fab")
		)
		(fp_line
			(start 0.299974 0.150114)
			(end -0.299974 0.150114)
			(stroke
				(width 0.1)
				(type default)
			)
			(layer "F.Fab")
		)
		(fp_line
			(start -0.299974 0.150114)
			(end -0.299974 -0.150114)
			(stroke
				(width 0.1)
				(type default)
			)
			(layer "F.Fab")
		)
		(pad "1" smd rect
			(at -0.2667 0 90)
			(size 0.3048 0.381)
			(layers "F.Cu" "F.Mask" "F.Paste")
			(net "P5E_PEX1_STN4_TX_DN<66>")
		)
		(pad "2" smd rect
			(at 0.2667 0 90)
			(size 0.3048 0.381)
			(layers "F.Cu" "F.Mask" "F.Paste")
			(net "P5E_PEX1_STN4_TX_C_DN<66>")
		)
	)
	(footprint ""
		(layer "F.Cu")
		(at 213.838536 -44.341542 90)
		(property "Reference" "C320"
			(at 0 0 90)
			(layer "F.SilkS")
			(hide yes)
			(effects
				(font
					(size 1.27 1.27)
				)
			)
		)
		(property "Value" ""
			(at 0 0 90)
			(layer "F.Fab")
			(effects
				(font
					(size 1.27 1.27)
				)
			)
		)
		(duplicate_pad_numbers_are_jumpers no)
		(fp_line
			(start 0.7874 -0.4064)
			(end 0.7874 0.4064)
			(stroke
				(width 0.1524)
				(type default)
			)
			(layer "F.SilkS")
		)
		(fp_line
			(start -0.7874 -0.4064)
			(end 0.7874 -0.4064)
			(stroke
				(width 0.1524)
				(type default)
			)
			(layer "F.SilkS")
		)
		(fp_line
			(start 0.7874 0.4064)
			(end -0.7874 0.4064)
			(stroke
				(width 0.1524)
				(type default)
			)
			(layer "F.SilkS")
		)
		(fp_line
			(start -0.7874 0.4064)
			(end -0.7874 -0.4064)
			(stroke
				(width 0.1524)
				(type default)
			)
			(layer "F.SilkS")
		)
		(fp_line
			(start -0.12065 -0.305054)
			(end -0.12065 -0.2794)
			(stroke
				(width 0.1)
				(type default)
			)
			(layer "F.Fab")
		)
		(fp_line
			(start -0.67945 -0.305054)
			(end -0.12065 -0.305054)
			(stroke
				(width 0.1)
				(type default)
			)
			(layer "F.Fab")
		)
		(fp_line
			(start 0.67945 -0.3048)
			(end 0.67945 0.3048)
			(stroke
				(width 0.1)
				(type default)
			)
			(layer "F.Fab")
		)
		(fp_line
			(start 0.12065 -0.3048)
			(end 0.67945 -0.3048)
			(stroke
				(width 0.1)
				(type default)
			)
			(layer "F.Fab")
		)
		(fp_line
			(start 0.12065 -0.2794)
			(end 0.12065 -0.3048)
			(stroke
				(width 0.1)
				(type default)
			)
			(layer "F.Fab")
		)
		(fp_line
			(start -0.12065 -0.2794)
			(end 0.12065 -0.2794)
			(stroke
				(width 0.1)
				(type default)
			)
			(layer "F.Fab")
		)
		(fp_line
			(start 0.120396 0.2794)
			(end -0.12065 0.2794)
			(stroke
				(width 0.1)
				(type default)
			)
			(layer "F.Fab")
		)
		(fp_line
			(start -0.12065 0.2794)
			(end -0.12065 0.3048)
			(stroke
				(width 0.1)
				(type default)
			)
			(layer "F.Fab")
		)
		(fp_line
			(start 0.67945 0.3048)
			(end 0.120396 0.3048)
			(stroke
				(width 0.1)
				(type default)
			)
			(layer "F.Fab")
		)
		(fp_line
			(start 0.120396 0.3048)
			(end 0.120396 0.2794)
			(stroke
				(width 0.1)
				(type default)
			)
			(layer "F.Fab")
		)
		(fp_line
			(start -0.12065 0.3048)
			(end -0.67945 0.3048)
			(stroke
				(width 0.1)
				(type default)
			)
			(layer "F.Fab")
		)
		(fp_line
			(start -0.67945 0.3048)
			(end -0.67945 -0.305054)
			(stroke
				(width 0.1)
				(type default)
			)
			(layer "F.Fab")
		)
		(pad "1" smd circle
			(at -0.40005 0 90)
			(size 0 0)
			(layers "F.Cu" "F.Mask" "F.Paste")
			(net "P12V_SSD7_VIN_P")
		)
		(pad "2" smd circle
			(at 0.40005 0 90)
			(size 0 0)
			(layers "F.Cu" "F.Mask" "F.Paste")
			(net "P12V_SSD7_VIN_N")
		)
	)
	(footprint ""
		(layer "F.Cu")
		(at 224.54743 -190.17869 90)
		(property "Reference" "C2629"
			(at 0 0 90)
			(layer "F.SilkS")
			(hide yes)
			(effects
				(font
					(size 1.27 1.27)
				)
			)
		)
		(property "Value" ""
			(at 0 0 90)
			(layer "F.Fab")
			(effects
				(font
					(size 1.27 1.27)
				)
			)
		)
		(duplicate_pad_numbers_are_jumpers no)
		(fp_line
			(start 0.7874 -0.4064)
			(end 0.7874 0.4064)
			(stroke
				(width 0.1524)
				(type default)
			)
			(layer "F.SilkS")
		)
		(fp_line
			(start -0.7874 -0.4064)
			(end 0.7874 -0.4064)
			(stroke
				(width 0.1524)
				(type default)
			)
			(layer "F.SilkS")
		)
		(fp_line
			(start 0.7874 0.4064)
			(end -0.7874 0.4064)
			(stroke
				(width 0.1524)
				(type default)
			)
			(layer "F.SilkS")
		)
		(fp_line
			(start -0.7874 0.4064)
			(end -0.7874 -0.4064)
			(stroke
				(width 0.1524)
				(type default)
			)
			(layer "F.SilkS")
		)
		(fp_line
			(start -0.12065 -0.305054)
			(end -0.12065 -0.2794)
			(stroke
				(width 0.1)
				(type default)
			)
			(layer "F.Fab")
		)
		(fp_line
			(start -0.67945 -0.305054)
			(end -0.12065 -0.305054)
			(stroke
				(width 0.1)
				(type default)
			)
			(layer "F.Fab")
		)
		(fp_line
			(start 0.67945 -0.3048)
			(end 0.67945 0.3048)
			(stroke
				(width 0.1)
				(type default)
			)
			(layer "F.Fab")
		)
		(fp_line
			(start 0.12065 -0.3048)
			(end 0.67945 -0.3048)
			(stroke
				(width 0.1)
				(type default)
			)
			(layer "F.Fab")
		)
		(fp_line
			(start 0.12065 -0.2794)
			(end 0.12065 -0.3048)
			(stroke
				(width 0.1)
				(type default)
			)
			(layer "F.Fab")
		)
		(fp_line
			(start -0.12065 -0.2794)
			(end 0.12065 -0.2794)
			(stroke
				(width 0.1)
				(type default)
			)
			(layer "F.Fab")
		)
		(fp_line
			(start 0.120396 0.2794)
			(end -0.12065 0.2794)
			(stroke
				(width 0.1)
				(type default)
			)
			(layer "F.Fab")
		)
		(fp_line
			(start -0.12065 0.2794)
			(end -0.12065 0.3048)
			(stroke
				(width 0.1)
				(type default)
			)
			(layer "F.Fab")
		)
		(fp_line
			(start 0.67945 0.3048)
			(end 0.120396 0.3048)
			(stroke
				(width 0.1)
				(type default)
			)
			(layer "F.Fab")
		)
		(fp_line
			(start 0.120396 0.3048)
			(end 0.120396 0.2794)
			(stroke
				(width 0.1)
				(type default)
			)
			(layer "F.Fab")
		)
		(fp_line
			(start -0.12065 0.3048)
			(end -0.67945 0.3048)
			(stroke
				(width 0.1)
				(type default)
			)
			(layer "F.Fab")
		)
		(fp_line
			(start -0.67945 0.3048)
			(end -0.67945 -0.305054)
			(stroke
				(width 0.1)
				(type default)
			)
			(layer "F.Fab")
		)
		(pad "1" smd circle
			(at -0.40005 0 90)
			(size 0 0)
			(layers "F.Cu" "F.Mask" "F.Paste")
			(net "GND")
		)
		(pad "2" smd circle
			(at 0.40005 0 90)
			(size 0 0)
			(layers "F.Cu" "F.Mask" "F.Paste")
			(net "P3V3_AUX")
		)
	)
	(footprint ""
		(layer "F.Cu")
		(at 216.401396 -106.36504)
		(property "Reference" "R723"
			(at 0 0 0)
			(layer "F.SilkS")
			(hide yes)
			(effects
				(font
					(size 1.27 1.27)
				)
			)
		)
		(property "Value" ""
			(at 0 0 0)
			(layer "F.Fab")
			(effects
				(font
					(size 1.27 1.27)
				)
			)
		)
		(duplicate_pad_numbers_are_jumpers no)
		(fp_line
			(start -0.7874 -0.4064)
			(end 0.7874 -0.4064)
			(stroke
				(width 0.1524)
				(type default)
			)
			(layer "F.SilkS")
		)
		(fp_line
			(start -0.7874 0.4064)
			(end -0.7874 -0.4064)
			(stroke
				(width 0.1524)
				(type default)
			)
			(layer "F.SilkS")
		)
		(fp_line
			(start 0.7874 -0.4064)
			(end 0.7874 0.4064)
			(stroke
				(width 0.1524)
				(type default)
			)
			(layer "F.SilkS")
		)
		(fp_line
			(start 0.7874 0.4064)
			(end -0.7874 0.4064)
			(stroke
				(width 0.1524)
				(type default)
			)
			(layer "F.SilkS")
		)
		(fp_line
			(start -0.67945 -0.305054)
			(end -0.12065 -0.305054)
			(stroke
				(width 0.1)
				(type default)
			)
			(layer "F.Fab")
		)
		(fp_line
			(start -0.67945 0.3048)
			(end -0.67945 -0.305054)
			(stroke
				(width 0.1)
				(type default)
			)
			(layer "F.Fab")
		)
		(fp_line
			(start -0.12065 -0.305054)
			(end -0.12065 -0.2794)
			(stroke
				(width 0.1)
				(type default)
			)
			(layer "F.Fab")
		)
		(fp_line
			(start -0.12065 -0.2794)
			(end 0.12065 -0.2794)
			(stroke
				(width 0.1)
				(type default)
			)
			(layer "F.Fab")
		)
		(fp_line
			(start -0.12065 0.2794)
			(end -0.12065 0.3048)
			(stroke
				(width 0.1)
				(type default)
			)
			(layer "F.Fab")
		)
		(fp_line
			(start -0.12065 0.3048)
			(end -0.67945 0.3048)
			(stroke
				(width 0.1)
				(type default)
			)
			(layer "F.Fab")
		)
		(fp_line
			(start 0.120396 0.2794)
			(end -0.12065 0.2794)
			(stroke
				(width 0.1)
				(type default)
			)
			(layer "F.Fab")
		)
		(fp_line
			(start 0.120396 0.3048)
			(end 0.120396 0.2794)
			(stroke
				(width 0.1)
				(type default)
			)
			(layer "F.Fab")
		)
		(fp_line
			(start 0.12065 -0.3048)
			(end 0.67945 -0.3048)
			(stroke
				(width 0.1)
				(type default)
			)
			(layer "F.Fab")
		)
		(fp_line
			(start 0.12065 -0.2794)
			(end 0.12065 -0.3048)
			(stroke
				(width 0.1)
				(type default)
			)
			(layer "F.Fab")
		)
		(fp_line
			(start 0.67945 -0.3048)
			(end 0.67945 0.3048)
			(stroke
				(width 0.1)
				(type default)
			)
			(layer "F.Fab")
		)
		(fp_line
			(start 0.67945 0.3048)
			(end 0.120396 0.3048)
			(stroke
				(width 0.1)
				(type default)
			)
			(layer "F.Fab")
		)
		(pad "1" smd circle
			(at -0.40005 0)
			(size 0 0)
			(layers "F.Cu" "F.Mask" "F.Paste")
			(net "P12V_NIC3")
		)
		(pad "2" smd circle
			(at 0.40005 0)
			(size 0 0)
			(layers "F.Cu" "F.Mask" "F.Paste")
			(net "P12V_NIC3_VIN_N")
		)
	)
	(footprint ""
		(layer "F.Cu")
		(at 270.807942 -157.3784 180)
		(property "Reference" "R216"
			(at 0 0 180)
			(layer "F.SilkS")
			(hide yes)
			(effects
				(font
					(size 1.27 1.27)
				)
			)
		)
		(property "Value" ""
			(at 0 0 180)
			(layer "F.Fab")
			(effects
				(font
					(size 1.27 1.27)
				)
			)
		)
		(duplicate_pad_numbers_are_jumpers no)
		(fp_line
			(start 0.7874 0.4064)
			(end -0.7874 0.4064)
			(stroke
				(width 0.1524)
				(type default)
			)
			(layer "F.SilkS")
		)
		(fp_line
			(start 0.7874 -0.4064)
			(end 0.7874 0.4064)
			(stroke
				(width 0.1524)
				(type default)
			)
			(layer "F.SilkS")
		)
		(fp_line
			(start -0.7874 0.4064)
			(end -0.7874 -0.4064)
			(stroke
				(width 0.1524)
				(type default)
			)
			(layer "F.SilkS")
		)
		(fp_line
			(start -0.7874 -0.4064)
			(end 0.7874 -0.4064)
			(stroke
				(width 0.1524)
				(type default)
			)
			(layer "F.SilkS")
		)
		(fp_line
			(start 0.67945 0.3048)
			(end 0.120396 0.3048)
			(stroke
				(width 0.1)
				(type default)
			)
			(layer "F.Fab")
		)
		(fp_line
			(start 0.67945 -0.3048)
			(end 0.67945 0.3048)
			(stroke
				(width 0.1)
				(type default)
			)
			(layer "F.Fab")
		)
		(fp_line
			(start 0.12065 -0.2794)
			(end 0.12065 -0.3048)
			(stroke
				(width 0.1)
				(type default)
			)
			(layer "F.Fab")
		)
		(fp_line
			(start 0.12065 -0.3048)
			(end 0.67945 -0.3048)
			(stroke
				(width 0.1)
				(type default)
			)
			(layer "F.Fab")
		)
		(fp_line
			(start 0.120396 0.3048)
			(end 0.120396 0.2794)
			(stroke
				(width 0.1)
				(type default)
			)
			(layer "F.Fab")
		)
		(fp_line
			(start 0.120396 0.2794)
			(end -0.12065 0.2794)
			(stroke
				(width 0.1)
				(type default)
			)
			(layer "F.Fab")
		)
		(fp_line
			(start -0.12065 0.3048)
			(end -0.67945 0.3048)
			(stroke
				(width 0.1)
				(type default)
			)
			(layer "F.Fab")
		)
		(fp_line
			(start -0.12065 0.2794)
			(end -0.12065 0.3048)
			(stroke
				(width 0.1)
				(type default)
			)
			(layer "F.Fab")
		)
		(fp_line
			(start -0.12065 -0.2794)
			(end 0.12065 -0.2794)
			(stroke
				(width 0.1)
				(type default)
			)
			(layer "F.Fab")
		)
		(fp_line
			(start -0.12065 -0.305054)
			(end -0.12065 -0.2794)
			(stroke
				(width 0.1)
				(type default)
			)
			(layer "F.Fab")
		)
		(fp_line
			(start -0.67945 0.3048)
			(end -0.67945 -0.305054)
			(stroke
				(width 0.1)
				(type default)
			)
			(layer "F.Fab")
		)
		(fp_line
			(start -0.67945 -0.305054)
			(end -0.12065 -0.305054)
			(stroke
				(width 0.1)
				(type default)
			)
			(layer "F.Fab")
		)
		(pad "1" smd circle
			(at -0.40005 0 180)
			(size 0 0)
			(layers "F.Cu" "F.Mask" "F.Paste")
			(net "NIC4_DATA_IN")
		)
		(pad "2" smd circle
			(at 0.40005 0 180)
			(size 0 0)
			(layers "F.Cu" "F.Mask" "F.Paste")
			(net "P3V3_NIC4")
		)
	)
	(footprint ""
		(layer "F.Cu")
		(at 373.761 -192.659 90)
		(property "Reference" "C3598"
			(at 0 0 90)
			(layer "F.SilkS")
			(hide yes)
			(effects
				(font
					(size 1.27 1.27)
				)
			)
		)
		(property "Value" ""
			(at 0 0 90)
			(layer "F.Fab")
			(effects
				(font
					(size 1.27 1.27)
				)
			)
		)
		(duplicate_pad_numbers_are_jumpers no)
		(fp_line
			(start 0.7874 -0.4064)
			(end 0.7874 0.4064)
			(stroke
				(width 0.1524)
				(type default)
			)
			(layer "F.SilkS")
		)
		(fp_line
			(start -0.7874 -0.4064)
			(end 0.7874 -0.4064)
			(stroke
				(width 0.1524)
				(type default)
			)
			(layer "F.SilkS")
		)
		(fp_line
			(start 0.7874 0.4064)
			(end -0.7874 0.4064)
			(stroke
				(width 0.1524)
				(type default)
			)
			(layer "F.SilkS")
		)
		(fp_line
			(start -0.7874 0.4064)
			(end -0.7874 -0.4064)
			(stroke
				(width 0.1524)
				(type default)
			)
			(layer "F.SilkS")
		)
		(fp_line
			(start -0.12065 -0.305054)
			(end -0.12065 -0.2794)
			(stroke
				(width 0.1)
				(type default)
			)
			(layer "F.Fab")
		)
		(fp_line
			(start -0.67945 -0.305054)
			(end -0.12065 -0.305054)
			(stroke
				(width 0.1)
				(type default)
			)
			(layer "F.Fab")
		)
		(fp_line
			(start 0.67945 -0.3048)
			(end 0.67945 0.3048)
			(stroke
				(width 0.1)
				(type default)
			)
			(layer "F.Fab")
		)
		(fp_line
			(start 0.12065 -0.3048)
			(end 0.67945 -0.3048)
			(stroke
				(width 0.1)
				(type default)
			)
			(layer "F.Fab")
		)
		(fp_line
			(start 0.12065 -0.2794)
			(end 0.12065 -0.3048)
			(stroke
				(width 0.1)
				(type default)
			)
			(layer "F.Fab")
		)
		(fp_line
			(start -0.12065 -0.2794)
			(end 0.12065 -0.2794)
			(stroke
				(width 0.1)
				(type default)
			)
			(layer "F.Fab")
		)
		(fp_line
			(start 0.120396 0.2794)
			(end -0.12065 0.2794)
			(stroke
				(width 0.1)
				(type default)
			)
			(layer "F.Fab")
		)
		(fp_line
			(start -0.12065 0.2794)
			(end -0.12065 0.3048)
			(stroke
				(width 0.1)
				(type default)
			)
			(layer "F.Fab")
		)
		(fp_line
			(start 0.67945 0.3048)
			(end 0.120396 0.3048)
			(stroke
				(width 0.1)
				(type default)
			)
			(layer "F.Fab")
		)
		(fp_line
			(start 0.120396 0.3048)
			(end 0.120396 0.2794)
			(stroke
				(width 0.1)
				(type default)
			)
			(layer "F.Fab")
		)
		(fp_line
			(start -0.12065 0.3048)
			(end -0.67945 0.3048)
			(stroke
				(width 0.1)
				(type default)
			)
			(layer "F.Fab")
		)
		(fp_line
			(start -0.67945 0.3048)
			(end -0.67945 -0.305054)
			(stroke
				(width 0.1)
				(type default)
			)
			(layer "F.Fab")
		)
		(pad "1" smd circle
			(at -0.40005 0 90)
			(size 0 0)
			(layers "F.Cu" "F.Mask" "F.Paste")
			(net "P3V3_AUX")
		)
		(pad "2" smd circle
			(at 0.40005 0 90)
			(size 0 0)
			(layers "F.Cu" "F.Mask" "F.Paste")
			(net "GND")
		)
	)
	(footprint ""
		(layer "F.Cu")
		(at 252.646434 -58.323734)
		(property "Reference" "PC401"
			(at 0 0 0)
			(layer "F.SilkS")
			(hide yes)
			(effects
				(font
					(size 1.27 1.27)
				)
			)
		)
		(property "Value" ""
			(at 0 0 0)
			(layer "F.Fab")
			(effects
				(font
					(size 1.27 1.27)
				)
			)
		)
		(duplicate_pad_numbers_are_jumpers no)
		(fp_line
			(start -1.524 -0.762)
			(end 1.524 -0.762)
			(stroke
				(width 0.1524)
				(type default)
			)
			(layer "F.SilkS")
		)
		(fp_line
			(start -1.524 0.762)
			(end -1.524 -0.762)
			(stroke
				(width 0.1524)
				(type default)
			)
			(layer "F.SilkS")
		)
		(fp_line
			(start 1.524 -0.762)
			(end 1.524 0.762)
			(stroke
				(width 0.1524)
				(type default)
			)
			(layer "F.SilkS")
		)
		(fp_line
			(start 1.524 0.762)
			(end -1.524 0.762)
			(stroke
				(width 0.1524)
				(type default)
			)
			(layer "F.SilkS")
		)
		(fp_line
			(start -1.1049 -0.724916)
			(end -1.1049 0.724916)
			(stroke
				(width 0.1)
				(type default)
			)
			(layer "F.Fab")
		)
		(fp_line
			(start -1.1049 0.724916)
			(end 1.1049 0.724916)
			(stroke
				(width 0.1)
				(type default)
			)
			(layer "F.Fab")
		)
		(fp_line
			(start 1.1049 -0.724916)
			(end -1.1049 -0.724916)
			(stroke
				(width 0.1)
				(type default)
			)
			(layer "F.Fab")
		)
		(fp_line
			(start 1.1049 0.724916)
			(end 1.1049 -0.724916)
			(stroke
				(width 0.1)
				(type default)
			)
			(layer "F.Fab")
		)
		(pad "1" smd rect
			(at -0.889 0 180)
			(size 1.016 1.27)
			(layers "F.Cu" "F.Mask" "F.Paste")
			(net "GND")
		)
		(pad "2" smd rect
			(at 0.889 0 180)
			(size 1.016 1.27)
			(layers "F.Cu" "F.Mask" "F.Paste")
			(net "P12V_AUX")
		)
	)
	(footprint ""
		(layer "F.Cu")
		(at 87.175848 -450.754496 180)
		(property "Reference" "X20"
			(at -0.1778 -1.92913 180)
			(unlocked yes)
			(layer "F.SilkS")
			(effects
				(font
					(size 0.7874 0.5842)
					(thickness 0.1524)
				)
				(justify left)
			)
		)
		(property "Value" ""
			(at 0 0 180)
			(layer "F.Fab")
			(effects
				(font
					(size 1.27 1.27)
				)
			)
		)
		(property "Device Type" "TP_TDR_4P_FTS_MPKT4_H025P0200_IO_TP15_TP_TDR_4P_DIP"
			(at 1.30175 1.27 270)
			(unlocked yes)
			(layer "F.Fab")
			(hide yes)
			(effects
				(font
					(size 0.635 0.4064)
					(thickness 0.1524)
				)
			)
		)
		(property "User Part Number" "TP15"
			(at 1.30175 1.27 270)
			(unlocked yes)
			(layer "Cmts.User")
			(hide yes)
			(effects
				(font
					(size 0.635 0.4064)
					(thickness 0.1524)
				)
			)
		)
		(duplicate_pad_numbers_are_jumpers no)
		(fp_line
			(start 2.54 3.81)
			(end 2.54 3.6703)
			(stroke
				(width 0.1524)
				(type default)
			)
			(layer "F.SilkS")
		)
		(fp_line
			(start 2.54 1.4097)
			(end 2.54 1.1303)
			(stroke
				(width 0.1524)
				(type default)
			)
			(layer "F.SilkS")
		)
		(fp_line
			(start 2.54 -1.1303)
			(end 2.54 -1.27)
			(stroke
				(width 0.1524)
				(type default)
			)
			(layer "F.SilkS")
		)
		(fp_line
			(start 2.54 -1.27)
			(end 0 -1.27)
			(stroke
				(width 0.1524)
				(type default)
			)
			(layer "F.SilkS")
		)
		(fp_line
			(start 0 3.81)
			(end 2.54 3.81)
			(stroke
				(width 0.1524)
				(type default)
			)
			(layer "F.SilkS")
		)
		(fp_line
			(start 0 3.175)
			(end 0 3.81)
			(stroke
				(width 0.1524)
				(type default)
			)
			(layer "F.SilkS")
		)
		(fp_line
			(start 0 0.635)
			(end 0 1.905)
			(stroke
				(width 0.1524)
				(type default)
			)
			(layer "F.SilkS")
		)
		(fp_line
			(start 0 -1.27)
			(end 0 -0.635)
			(stroke
				(width 0.1524)
				(type default)
			)
			(layer "F.SilkS")
		)
		(fp_poly
			(pts
				(xy -0.761746 0) (xy -2.285746 -0.762) (xy -2.285746 0.762)
			)
			(stroke
				(width 0)
				(type default)
			)
			(fill yes)
			(layer "F.SilkS")
		)
		(fp_line
			(start 2.54 3.81)
			(end 2.54 -1.27)
			(stroke
				(width 0.1)
				(type default)
			)
			(layer "F.Fab")
		)
		(fp_line
			(start 2.54 -1.27)
			(end 0 -1.27)
			(stroke
				(width 0.1)
				(type default)
			)
			(layer "F.Fab")
		)
		(fp_line
			(start 0 3.81)
			(end 2.54 3.81)
			(stroke
				(width 0.1)
				(type default)
			)
			(layer "F.Fab")
		)
		(fp_line
			(start 0 -1.27)
			(end 0 3.81)
			(stroke
				(width 0.1)
				(type default)
			)
			(layer "F.Fab")
		)
		(fp_poly
			(pts
				(xy -0.761746 0) (xy -2.285746 -0.762) (xy -2.285746 0.762)
			)
			(stroke
				(width 0)
				(type default)
			)
			(fill yes)
			(layer "F.Fab")
		)
		(pad "1" thru_hole circle
			(at 0 0 180)
			(size 1.0033 1.0033)
			(drill 0.249936)
			(layers "*.Cu" "*.Mask")
			(remove_unused_layers no)
			(net "TDR_DIFF_85_IN3_DIP")
			(clearance 0.10795)
			(thermal_gap 0.10795)
			(padstack
				(mode front_inner_back)
				(layer "Inner"
					(shape circle)
					(size 0.8001 0.8001)
					(clearance 0.1524)
				)
				(layer "B.Cu"
					(shape circle)
					(size 1.0033 1.0033)
					(clearance 0.10795)
				)
			)
		)
		(pad "2" thru_hole circle
			(at 2.54 0 180)
			(size 1.9939 1.9939)
			(drill 0.249936)
			(layers "*.Cu" "*.Mask")
			(remove_unused_layers no)
			(net "COUPON_GND1")
			(clearance 0.10795)
			(thermal_gap 0.10795)
			(padstack
				(mode front_inner_back)
				(layer "Inner"
					(shape circle)
					(size 0.8001 0.8001)
					(clearance 0.1524)
				)
				(layer "B.Cu"
					(shape circle)
					(size 1.9939 1.9939)
					(clearance 0.10795)
				)
			)
		)
		(pad "3" thru_hole circle
			(at 2.54 2.54 180)
			(size 1.9939 1.9939)
			(drill 0.249936)
			(layers "*.Cu" "*.Mask")
			(remove_unused_layers no)
			(net "COUPON_GND1")
			(clearance 0.10795)
			(thermal_gap 0.10795)
			(padstack
				(mode front_inner_back)
				(layer "Inner"
					(shape circle)
					(size 0.8001 0.8001)
					(clearance 0.1524)
				)
				(layer "B.Cu"
					(shape circle)
					(size 1.9939 1.9939)
					(clearance 0.10795)
				)
			)
		)
		(pad "4" thru_hole circle
			(at 0 2.54 180)
			(size 1.0033 1.0033)
			(drill 0.249936)
			(layers "*.Cu" "*.Mask")
			(remove_unused_layers no)
			(net "TDR_DIFF_85_IN3_DIN")
			(clearance 0.10795)
			(thermal_gap 0.10795)
			(padstack
				(mode front_inner_back)
				(layer "Inner"
					(shape circle)
					(size 0.8001 0.8001)
					(clearance 0.1524)
				)
				(layer "B.Cu"
					(shape circle)
					(size 1.0033 1.0033)
					(clearance 0.10795)
				)
			)
		)
	)
	(footprint ""
		(layer "F.Cu")
		(at 38.7604 -96.1644)
		(property "Reference" "R42"
			(at 0 0 0)
			(layer "F.SilkS")
			(hide yes)
			(effects
				(font
					(size 1.27 1.27)
				)
			)
		)
		(property "Value" ""
			(at 0 0 0)
			(layer "F.Fab")
			(effects
				(font
					(size 1.27 1.27)
				)
			)
		)
		(duplicate_pad_numbers_are_jumpers no)
		(fp_line
			(start -0.7874 -0.4064)
			(end 0.7874 -0.4064)
			(stroke
				(width 0.1524)
				(type default)
			)
			(layer "F.SilkS")
		)
		(fp_line
			(start -0.7874 0.4064)
			(end -0.7874 -0.4064)
			(stroke
				(width 0.1524)
				(type default)
			)
			(layer "F.SilkS")
		)
		(fp_line
			(start 0.7874 -0.4064)
			(end 0.7874 0.4064)
			(stroke
				(width 0.1524)
				(type default)
			)
			(layer "F.SilkS")
		)
		(fp_line
			(start 0.7874 0.4064)
			(end -0.7874 0.4064)
			(stroke
				(width 0.1524)
				(type default)
			)
			(layer "F.SilkS")
		)
		(fp_line
			(start -0.67945 -0.305054)
			(end -0.12065 -0.305054)
			(stroke
				(width 0.1)
				(type default)
			)
			(layer "F.Fab")
		)
		(fp_line
			(start -0.67945 0.3048)
			(end -0.67945 -0.305054)
			(stroke
				(width 0.1)
				(type default)
			)
			(layer "F.Fab")
		)
		(fp_line
			(start -0.12065 -0.305054)
			(end -0.12065 -0.2794)
			(stroke
				(width 0.1)
				(type default)
			)
			(layer "F.Fab")
		)
		(fp_line
			(start -0.12065 -0.2794)
			(end 0.12065 -0.2794)
			(stroke
				(width 0.1)
				(type default)
			)
			(layer "F.Fab")
		)
		(fp_line
			(start -0.12065 0.2794)
			(end -0.12065 0.3048)
			(stroke
				(width 0.1)
				(type default)
			)
			(layer "F.Fab")
		)
		(fp_line
			(start -0.12065 0.3048)
			(end -0.67945 0.3048)
			(stroke
				(width 0.1)
				(type default)
			)
			(layer "F.Fab")
		)
		(fp_line
			(start 0.120396 0.2794)
			(end -0.12065 0.2794)
			(stroke
				(width 0.1)
				(type default)
			)
			(layer "F.Fab")
		)
		(fp_line
			(start 0.120396 0.3048)
			(end 0.120396 0.2794)
			(stroke
				(width 0.1)
				(type default)
			)
			(layer "F.Fab")
		)
		(fp_line
			(start 0.12065 -0.3048)
			(end 0.67945 -0.3048)
			(stroke
				(width 0.1)
				(type default)
			)
			(layer "F.Fab")
		)
		(fp_line
			(start 0.12065 -0.2794)
			(end 0.12065 -0.3048)
			(stroke
				(width 0.1)
				(type default)
			)
			(layer "F.Fab")
		)
		(fp_line
			(start 0.67945 -0.3048)
			(end 0.67945 0.3048)
			(stroke
				(width 0.1)
				(type default)
			)
			(layer "F.Fab")
		)
		(fp_line
			(start 0.67945 0.3048)
			(end 0.120396 0.3048)
			(stroke
				(width 0.1)
				(type default)
			)
			(layer "F.Fab")
		)
		(pad "1" smd circle
			(at -0.40005 0)
			(size 0 0)
			(layers "F.Cu" "F.Mask" "F.Paste")
			(net "PRSNT_NIC0_N")
		)
		(pad "2" smd circle
			(at 0.40005 0)
			(size 0 0)
			(layers "F.Cu" "F.Mask" "F.Paste")
			(net "PRSNTB3_NIC0_N")
		)
	)
	(footprint ""
		(layer "F.Cu")
		(at 378.453396 -297.791632)
		(property "Reference" "L136"
			(at 0 0 0)
			(layer "F.SilkS")
			(hide yes)
			(effects
				(font
					(size 1.27 1.27)
				)
			)
		)
		(property "Value" ""
			(at 0 0 0)
			(layer "F.Fab")
			(effects
				(font
					(size 1.27 1.27)
				)
			)
		)
		(duplicate_pad_numbers_are_jumpers no)
		(fp_line
			(start -1.63576 -0.8128)
			(end -1.63576 0.8128)
			(stroke
				(width 0.1524)
				(type default)
			)
			(layer "F.SilkS")
		)
		(fp_line
			(start -1.63576 -0.8128)
			(end 1.63576 -0.8128)
			(stroke
				(width 0.1524)
				(type default)
			)
			(layer "F.SilkS")
		)
		(fp_line
			(start 1.63576 -0.8128)
			(end 1.63576 0.8128)
			(stroke
				(width 0.1524)
				(type default)
			)
			(layer "F.SilkS")
		)
		(fp_line
			(start 1.63576 0.8128)
			(end -1.63576 0.8128)
			(stroke
				(width 0.1524)
				(type default)
			)
			(layer "F.SilkS")
		)
		(fp_line
			(start -1.56083 -0.738632)
			(end -1.56083 0.7366)
			(stroke
				(width 0.1)
				(type default)
			)
			(layer "F.Fab")
		)
		(fp_line
			(start -1.56083 0.7366)
			(end -1.524 0.7366)
			(stroke
				(width 0.1)
				(type default)
			)
			(layer "F.Fab")
		)
		(fp_line
			(start -1.524 0.7366)
			(end 1.524 0.7366)
			(stroke
				(width 0.1)
				(type default)
			)
			(layer "F.Fab")
		)
		(fp_line
			(start 1.524 0.7366)
			(end 1.560576 0.7366)
			(stroke
				(width 0.1)
				(type default)
			)
			(layer "F.Fab")
		)
		(fp_line
			(start 1.560576 -0.738632)
			(end -1.56083 -0.738632)
			(stroke
				(width 0.1)
				(type default)
			)
			(layer "F.Fab")
		)
		(fp_line
			(start 1.560576 0.7366)
			(end 1.560576 -0.738632)
			(stroke
				(width 0.1)
				(type default)
			)
			(layer "F.Fab")
		)
		(pad "1" smd rect
			(at -0.94996 0 180)
			(size 1.1176 1.3716)
			(layers "F.Cu" "F.Mask" "F.Paste")
			(net "P1V8_PLL0_PEX3")
		)
		(pad "2" smd rect
			(at 0.94996 0 180)
			(size 1.1176 1.3716)
			(layers "F.Cu" "F.Mask" "F.Paste")
			(net "PCEPLL0_VDDA18_PEX3")
		)
	)
	(footprint ""
		(layer "F.Cu")
		(at 140.074142 -173.865286 180)
		(property "Reference" "R1098"
			(at 0 0 180)
			(layer "F.SilkS")
			(hide yes)
			(effects
				(font
					(size 1.27 1.27)
				)
			)
		)
		(property "Value" ""
			(at 0 0 180)
			(layer "F.Fab")
			(effects
				(font
					(size 1.27 1.27)
				)
			)
		)
		(duplicate_pad_numbers_are_jumpers no)
		(fp_line
			(start -0.7874 -0.4064)
			(end 0.7874 -0.4064)
			(stroke
				(width 0.1524)
				(type default)
			)
			(layer "F.SilkS")
		)
		(fp_line
			(start 0.67945 0.3048)
			(end 0.120396 0.3048)
			(stroke
				(width 0.1)
				(type default)
			)
			(layer "F.Fab")
		)
		(fp_line
			(start 0.67945 -0.3048)
			(end 0.67945 0.3048)
			(stroke
				(width 0.1)
				(type default)
			)
			(layer "F.Fab")
		)
		(fp_line
			(start 0.12065 -0.2794)
			(end 0.12065 -0.3048)
			(stroke
				(width 0.1)
				(type default)
			)
			(layer "F.Fab")
		)
		(fp_line
			(start 0.12065 -0.3048)
			(end 0.67945 -0.3048)
			(stroke
				(width 0.1)
				(type default)
			)
			(layer "F.Fab")
		)
		(fp_line
			(start 0.120396 0.3048)
			(end 0.120396 0.2794)
			(stroke
				(width 0.1)
				(type default)
			)
			(layer "F.Fab")
		)
		(fp_line
			(start 0.120396 0.2794)
			(end -0.12065 0.2794)
			(stroke
				(width 0.1)
				(type default)
			)
			(layer "F.Fab")
		)
		(fp_line
			(start -0.12065 0.3048)
			(end -0.67945 0.3048)
			(stroke
				(width 0.1)
				(type default)
			)
			(layer "F.Fab")
		)
		(fp_line
			(start -0.12065 0.2794)
			(end -0.12065 0.3048)
			(stroke
				(width 0.1)
				(type default)
			)
			(layer "F.Fab")
		)
		(fp_line
			(start -0.12065 -0.2794)
			(end 0.12065 -0.2794)
			(stroke
				(width 0.1)
				(type default)
			)
			(layer "F.Fab")
		)
		(fp_line
			(start -0.12065 -0.305054)
			(end -0.12065 -0.2794)
			(stroke
				(width 0.1)
				(type default)
			)
			(layer "F.Fab")
		)
		(fp_line
			(start -0.67945 0.3048)
			(end -0.67945 -0.305054)
			(stroke
				(width 0.1)
				(type default)
			)
			(layer "F.Fab")
		)
		(fp_line
			(start -0.67945 -0.305054)
			(end -0.12065 -0.305054)
			(stroke
				(width 0.1)
				(type default)
			)
			(layer "F.Fab")
		)
		(pad "1" smd circle
			(at -0.40005 0 180)
			(size 0 0)
			(layers "F.Cu" "F.Mask" "F.Paste")
			(net "CLK_100M_DB2000QL_NIC2_R_DP")
		)
		(pad "2" smd circle
			(at 0.40005 0 180)
			(size 0 0)
			(layers "F.Cu" "F.Mask" "F.Paste")
			(net "CLK_100M_DB2000QL_NIC2_DP")
		)
	)
	(footprint ""
		(layer "F.Cu")
		(at 36.534344 -252.356874 -90)
		(property "Reference" "R1199"
			(at 0 0 270)
			(layer "F.SilkS")
			(hide yes)
			(effects
				(font
					(size 1.27 1.27)
				)
			)
		)
		(property "Value" ""
			(at 0 0 270)
			(layer "F.Fab")
			(effects
				(font
					(size 1.27 1.27)
				)
			)
		)
		(duplicate_pad_numbers_are_jumpers no)
		(fp_line
			(start -0.7874 0.4064)
			(end -0.7874 -0.4064)
			(stroke
				(width 0.1524)
				(type default)
			)
			(layer "F.SilkS")
		)
		(fp_line
			(start 0.7874 0.4064)
			(end -0.7874 0.4064)
			(stroke
				(width 0.1524)
				(type default)
			)
			(layer "F.SilkS")
		)
		(fp_line
			(start -0.7874 -0.4064)
			(end 0.7874 -0.4064)
			(stroke
				(width 0.1524)
				(type default)
			)
			(layer "F.SilkS")
		)
		(fp_line
			(start 0.7874 -0.4064)
			(end 0.7874 0.4064)
			(stroke
				(width 0.1524)
				(type default)
			)
			(layer "F.SilkS")
		)
		(fp_line
			(start -0.67945 0.3048)
			(end -0.67945 -0.305054)
			(stroke
				(width 0.1)
				(type default)
			)
			(layer "F.Fab")
		)
		(fp_line
			(start -0.12065 0.3048)
			(end -0.67945 0.3048)
			(stroke
				(width 0.1)
				(type default)
			)
			(layer "F.Fab")
		)
		(fp_line
			(start 0.120396 0.3048)
			(end 0.120396 0.2794)
			(stroke
				(width 0.1)
				(type default)
			)
			(layer "F.Fab")
		)
		(fp_line
			(start 0.67945 0.3048)
			(end 0.120396 0.3048)
			(stroke
				(width 0.1)
				(type default)
			)
			(layer "F.Fab")
		)
		(fp_line
			(start -0.12065 0.2794)
			(end -0.12065 0.3048)
			(stroke
				(width 0.1)
				(type default)
			)
			(layer "F.Fab")
		)
		(fp_line
			(start 0.120396 0.2794)
			(end -0.12065 0.2794)
			(stroke
				(width 0.1)
				(type default)
			)
			(layer "F.Fab")
		)
		(fp_line
			(start -0.12065 -0.2794)
			(end 0.12065 -0.2794)
			(stroke
				(width 0.1)
				(type default)
			)
			(layer "F.Fab")
		)
		(fp_line
			(start 0.12065 -0.2794)
			(end 0.12065 -0.3048)
			(stroke
				(width 0.1)
				(type default)
			)
			(layer "F.Fab")
		)
		(fp_line
			(start 0.12065 -0.3048)
			(end 0.67945 -0.3048)
			(stroke
				(width 0.1)
				(type default)
			)
			(layer "F.Fab")
		)
		(fp_line
			(start 0.67945 -0.3048)
			(end 0.67945 0.3048)
			(stroke
				(width 0.1)
				(type default)
			)
			(layer "F.Fab")
		)
		(fp_line
			(start -0.67945 -0.305054)
			(end -0.12065 -0.305054)
			(stroke
				(width 0.1)
				(type default)
			)
			(layer "F.Fab")
		)
		(fp_line
			(start -0.12065 -0.305054)
			(end -0.12065 -0.2794)
			(stroke
				(width 0.1)
				(type default)
			)
			(layer "F.Fab")
		)
		(pad "1" smd circle
			(at -0.40005 0 270)
			(size 0 0)
			(layers "F.Cu" "F.Mask" "F.Paste")
			(net "GND")
		)
		(pad "2" smd circle
			(at 0.40005 0 270)
			(size 0 0)
			(layers "F.Cu" "F.Mask" "F.Paste")
			(net "PEX0_MODE_SEL6")
		)
	)
	(footprint ""
		(layer "F.Cu")
		(at 3.198876 -30.549342 90)
		(property "Reference" "U126"
			(at -1.116076 -2.063496 90)
			(unlocked yes)
			(layer "F.SilkS")
			(effects
				(font
					(size 0.7874 0.5842)
					(thickness 0.1524)
				)
				(justify left)
			)
		)
		(property "Value" ""
			(at 0 0 90)
			(layer "F.Fab")
			(effects
				(font
					(size 1.27 1.27)
				)
			)
		)
		(duplicate_pad_numbers_are_jumpers no)
		(fp_line
			(start 1.463548 -1.549908)
			(end 1.463548 1.549908)
			(stroke
				(width 0.1524)
				(type default)
			)
			(layer "F.SilkS")
		)
		(fp_line
			(start 0.762 -1.549908)
			(end 1.463548 -1.549908)
			(stroke
				(width 0.1524)
				(type default)
			)
			(layer "F.SilkS")
		)
		(fp_line
			(start -0.787908 -1.549908)
			(end 0 -0.762)
			(stroke
				(width 0.1524)
				(type default)
			)
			(layer "F.SilkS")
		)
		(fp_line
			(start -1.463548 -1.549908)
			(end -0.787908 -1.549908)
			(stroke
				(width 0.1524)
				(type default)
			)
			(layer "F.SilkS")
		)
		(fp_line
			(start 0 -0.762)
			(end 0.762 -1.549908)
			(stroke
				(width 0.1524)
				(type default)
			)
			(layer "F.SilkS")
		)
		(fp_line
			(start 1.463548 1.549908)
			(end -1.463548 1.549908)
			(stroke
				(width 0.1524)
				(type default)
			)
			(layer "F.SilkS")
		)
		(fp_line
			(start -1.463548 1.549908)
			(end -1.463548 -1.549908)
			(stroke
				(width 0.1524)
				(type default)
			)
			(layer "F.SilkS")
		)
		(fp_poly
			(pts
				(xy -3.03022 -2.050288) (xy -2.811272 -1.392936) (xy -3.468624 -1.612138)
			)
			(stroke
				(width 0)
				(type default)
			)
			(fill yes)
			(layer "F.SilkS")
		)
		(fp_line
			(start 1.549908 -1.549908)
			(end 1.549908 1.549908)
			(stroke
				(width 0.1)
				(type default)
			)
			(layer "F.Fab")
		)
		(fp_line
			(start -1.549908 -1.549908)
			(end 1.549908 -1.549908)
			(stroke
				(width 0.1)
				(type default)
			)
			(layer "F.Fab")
		)
		(fp_line
			(start 1.549908 1.549908)
			(end -1.549908 1.549908)
			(stroke
				(width 0.1)
				(type default)
			)
			(layer "F.Fab")
		)
		(fp_line
			(start -1.549908 1.549908)
			(end -1.549908 -1.549908)
			(stroke
				(width 0.1)
				(type default)
			)
			(layer "F.Fab")
		)
		(fp_poly
			(pts
				(xy -3.4798 -1.359916) (xy -2.86004 -1.050036) (xy -3.4798 -0.740156)
			)
			(stroke
				(width 0)
				(type default)
			)
			(fill yes)
			(layer "F.Fab")
		)
		(pad "1" smd rect
			(at -2.175002 -1.050036 180)
			(size 0.6096 1.1684)
			(layers "F.Cu" "F.Mask" "F.Paste")
			(net "P3V3_SSD0")
		)
		(pad "2" smd rect
			(at -2.175002 -0.32512 180)
			(size 0.4318 1.1684)
			(layers "F.Cu" "F.Mask" "F.Paste")
			(net "SMB_ISO_SSD0_SCL")
		)
		(pad "3" smd rect
			(at -2.175002 0.32512 180)
			(size 0.4318 1.1684)
			(layers "F.Cu" "F.Mask" "F.Paste")
			(net "SMB_ISO_SSD0_SDA")
		)
		(pad "4" smd rect
			(at -2.175002 1.050036 180)
			(size 0.6096 1.1684)
			(layers "F.Cu" "F.Mask" "F.Paste")
			(net "GND")
		)
		(pad "5" smd rect
			(at 2.175002 1.050036 180)
			(size 0.6096 1.1684)
			(layers "F.Cu" "F.Mask" "F.Paste")
			(net "SMB_SSD0_ISO_EN")
		)
		(pad "6" smd rect
			(at 2.175002 0.32512 180)
			(size 0.4318 1.1684)
			(layers "F.Cu" "F.Mask" "F.Paste")
			(net "SMB_BIC_I2C9_MUX0_SSD0_R_SDA")
		)
		(pad "7" smd rect
			(at 2.175002 -0.32512 180)
			(size 0.4318 1.1684)
			(layers "F.Cu" "F.Mask" "F.Paste")
			(net "SMB_BIC_I2C9_MUX0_SSD0_R_SCL")
		)
		(pad "8" smd rect
			(at 2.175002 -1.050036 180)
			(size 0.6096 1.1684)
			(layers "F.Cu" "F.Mask" "F.Paste")
			(net "P3V3_AUX")
		)
	)
	(footprint ""
		(layer "F.Cu")
		(at 136.445244 -96.957642)
		(property "Reference" "R1568"
			(at 0 0 0)
			(layer "F.SilkS")
			(hide yes)
			(effects
				(font
					(size 1.27 1.27)
				)
			)
		)
		(property "Value" ""
			(at 0 0 0)
			(layer "F.Fab")
			(effects
				(font
					(size 1.27 1.27)
				)
			)
		)
		(duplicate_pad_numbers_are_jumpers no)
		(fp_line
			(start -0.7874 -0.4064)
			(end 0.7874 -0.4064)
			(stroke
				(width 0.1524)
				(type default)
			)
			(layer "F.SilkS")
		)
		(fp_line
			(start -0.7874 0.4064)
			(end -0.7874 -0.4064)
			(stroke
				(width 0.1524)
				(type default)
			)
			(layer "F.SilkS")
		)
		(fp_line
			(start 0.7874 -0.4064)
			(end 0.7874 0.4064)
			(stroke
				(width 0.1524)
				(type default)
			)
			(layer "F.SilkS")
		)
		(fp_line
			(start 0.7874 0.4064)
			(end -0.7874 0.4064)
			(stroke
				(width 0.1524)
				(type default)
			)
			(layer "F.SilkS")
		)
		(fp_line
			(start -0.67945 -0.305054)
			(end -0.12065 -0.305054)
			(stroke
				(width 0.1)
				(type default)
			)
			(layer "F.Fab")
		)
		(fp_line
			(start -0.67945 0.3048)
			(end -0.67945 -0.305054)
			(stroke
				(width 0.1)
				(type default)
			)
			(layer "F.Fab")
		)
		(fp_line
			(start -0.12065 -0.305054)
			(end -0.12065 -0.2794)
			(stroke
				(width 0.1)
				(type default)
			)
			(layer "F.Fab")
		)
		(fp_line
			(start -0.12065 -0.2794)
			(end 0.12065 -0.2794)
			(stroke
				(width 0.1)
				(type default)
			)
			(layer "F.Fab")
		)
		(fp_line
			(start -0.12065 0.2794)
			(end -0.12065 0.3048)
			(stroke
				(width 0.1)
				(type default)
			)
			(layer "F.Fab")
		)
		(fp_line
			(start -0.12065 0.3048)
			(end -0.67945 0.3048)
			(stroke
				(width 0.1)
				(type default)
			)
			(layer "F.Fab")
		)
		(fp_line
			(start 0.120396 0.2794)
			(end -0.12065 0.2794)
			(stroke
				(width 0.1)
				(type default)
			)
			(layer "F.Fab")
		)
		(fp_line
			(start 0.120396 0.3048)
			(end 0.120396 0.2794)
			(stroke
				(width 0.1)
				(type default)
			)
			(layer "F.Fab")
		)
		(fp_line
			(start 0.12065 -0.3048)
			(end 0.67945 -0.3048)
			(stroke
				(width 0.1)
				(type default)
			)
			(layer "F.Fab")
		)
		(fp_line
			(start 0.12065 -0.2794)
			(end 0.12065 -0.3048)
			(stroke
				(width 0.1)
				(type default)
			)
			(layer "F.Fab")
		)
		(fp_line
			(start 0.67945 -0.3048)
			(end 0.67945 0.3048)
			(stroke
				(width 0.1)
				(type default)
			)
			(layer "F.Fab")
		)
		(fp_line
			(start 0.67945 0.3048)
			(end 0.120396 0.3048)
			(stroke
				(width 0.1)
				(type default)
			)
			(layer "F.Fab")
		)
		(pad "1" smd circle
			(at -0.40005 0)
			(size 0 0)
			(layers "F.Cu" "F.Mask" "F.Paste")
			(net "BIC_I2C9_SSD_MUX0_A2")
		)
		(pad "2" smd circle
			(at 0.40005 0)
			(size 0 0)
			(layers "F.Cu" "F.Mask" "F.Paste")
			(net "GND")
		)
	)
	(footprint ""
		(layer "F.Cu")
		(at 455.339196 -319.515998 180)
		(property "Reference" "PC264"
			(at 0 0 180)
			(layer "F.SilkS")
			(hide yes)
			(effects
				(font
					(size 1.27 1.27)
				)
			)
		)
		(property "Value" ""
			(at 0 0 180)
			(layer "F.Fab")
			(effects
				(font
					(size 1.27 1.27)
				)
			)
		)
		(duplicate_pad_numbers_are_jumpers no)
		(fp_line
			(start 0.7874 0.4064)
			(end -0.7874 0.4064)
			(stroke
				(width 0.1524)
				(type default)
			)
			(layer "F.SilkS")
		)
		(fp_line
			(start 0.7874 -0.4064)
			(end 0.7874 0.4064)
			(stroke
				(width 0.1524)
				(type default)
			)
			(layer "F.SilkS")
		)
		(fp_line
			(start -0.7874 0.4064)
			(end -0.7874 -0.4064)
			(stroke
				(width 0.1524)
				(type default)
			)
			(layer "F.SilkS")
		)
		(fp_line
			(start -0.7874 -0.4064)
			(end 0.7874 -0.4064)
			(stroke
				(width 0.1524)
				(type default)
			)
			(layer "F.SilkS")
		)
		(fp_line
			(start 0.67945 0.3048)
			(end 0.120396 0.3048)
			(stroke
				(width 0.1)
				(type default)
			)
			(layer "F.Fab")
		)
		(fp_line
			(start 0.67945 -0.3048)
			(end 0.67945 0.3048)
			(stroke
				(width 0.1)
				(type default)
			)
			(layer "F.Fab")
		)
		(fp_line
			(start 0.12065 -0.2794)
			(end 0.12065 -0.3048)
			(stroke
				(width 0.1)
				(type default)
			)
			(layer "F.Fab")
		)
		(fp_line
			(start 0.12065 -0.3048)
			(end 0.67945 -0.3048)
			(stroke
				(width 0.1)
				(type default)
			)
			(layer "F.Fab")
		)
		(fp_line
			(start 0.120396 0.3048)
			(end 0.120396 0.2794)
			(stroke
				(width 0.1)
				(type default)
			)
			(layer "F.Fab")
		)
		(fp_line
			(start 0.120396 0.2794)
			(end -0.12065 0.2794)
			(stroke
				(width 0.1)
				(type default)
			)
			(layer "F.Fab")
		)
		(fp_line
			(start -0.12065 0.3048)
			(end -0.67945 0.3048)
			(stroke
				(width 0.1)
				(type default)
			)
			(layer "F.Fab")
		)
		(fp_line
			(start -0.12065 0.2794)
			(end -0.12065 0.3048)
			(stroke
				(width 0.1)
				(type default)
			)
			(layer "F.Fab")
		)
		(fp_line
			(start -0.12065 -0.2794)
			(end 0.12065 -0.2794)
			(stroke
				(width 0.1)
				(type default)
			)
			(layer "F.Fab")
		)
		(fp_line
			(start -0.12065 -0.305054)
			(end -0.12065 -0.2794)
			(stroke
				(width 0.1)
				(type default)
			)
			(layer "F.Fab")
		)
		(fp_line
			(start -0.67945 0.3048)
			(end -0.67945 -0.305054)
			(stroke
				(width 0.1)
				(type default)
			)
			(layer "F.Fab")
		)
		(fp_line
			(start -0.67945 -0.305054)
			(end -0.12065 -0.305054)
			(stroke
				(width 0.1)
				(type default)
			)
			(layer "F.Fab")
		)
		(pad "1" smd circle
			(at -0.40005 0 180)
			(size 0 0)
			(layers "F.Cu" "F.Mask" "F.Paste")
			(net "P12V_AUX")
		)
		(pad "2" smd circle
			(at 0.40005 0 180)
			(size 0 0)
			(layers "F.Cu" "F.Mask" "F.Paste")
			(net "GND")
		)
	)
	(footprint ""
		(layer "F.Cu")
		(at 98.965258 -223.21774 90)
		(property "Reference" "PJ17"
			(at 0 0 90)
			(layer "F.SilkS")
			(hide yes)
			(effects
				(font
					(size 1.27 1.27)
				)
			)
		)
		(property "Value" ""
			(at 0 0 90)
			(layer "F.Fab")
			(effects
				(font
					(size 1.27 1.27)
				)
			)
		)
		(duplicate_pad_numbers_are_jumpers no)
		(pad "1" smd circle
			(at -0.7493 0 180)
			(size 0 0)
			(layers "F.Cu" "F.Mask" "F.Paste")
			(net "SH_P1V8_PEX_FB")
		)
		(pad "2" smd rect
			(at 0.7493 0)
			(size 0.7112 0.8128)
			(layers "F.Cu" "F.Mask" "F.Paste")
			(net "P1V8_PEX_R")
		)
		(zone
			(layer "F.Cu")
			(hatch none 0.5)
			(connect_pads
				(clearance 0)
			)
			(min_thickness 0.25)
			(keepout
				(tracks allowed)
				(vias not_allowed)
				(pads allowed)
				(copperpour not_allowed)
				(footprints allowed)
			)
			(placement
				(enabled no)
				(sheetname "")
			)
			(fill
				(thermal_gap 0.5)
				(thermal_bridge_width 0.5)
				(island_removal_mode 0)
			)
			(polygon
				(pts
					(xy 98.558858 -224.42424) (xy 98.558858 -222.03664) (xy 99.376484 -222.03664) (xy 99.376484 -224.42424)
				)
			)
		)
	)
	(footprint ""
		(layer "F.Cu")
		(at 438.31764 -304.036476 90)
		(property "Reference" "R1451"
			(at 0 0 90)
			(layer "F.SilkS")
			(hide yes)
			(effects
				(font
					(size 1.27 1.27)
				)
			)
		)
		(property "Value" ""
			(at 0 0 90)
			(layer "F.Fab")
			(effects
				(font
					(size 1.27 1.27)
				)
			)
		)
		(duplicate_pad_numbers_are_jumpers no)
		(fp_line
			(start 0.7874 -0.4064)
			(end 0.7874 0.4064)
			(stroke
				(width 0.1524)
				(type default)
			)
			(layer "F.SilkS")
		)
		(fp_line
			(start -0.7874 -0.4064)
			(end 0.7874 -0.4064)
			(stroke
				(width 0.1524)
				(type default)
			)
			(layer "F.SilkS")
		)
		(fp_line
			(start 0.7874 0.4064)
			(end -0.7874 0.4064)
			(stroke
				(width 0.1524)
				(type default)
			)
			(layer "F.SilkS")
		)
		(fp_line
			(start -0.7874 0.4064)
			(end -0.7874 -0.4064)
			(stroke
				(width 0.1524)
				(type default)
			)
			(layer "F.SilkS")
		)
		(fp_line
			(start -0.12065 -0.305054)
			(end -0.12065 -0.2794)
			(stroke
				(width 0.1)
				(type default)
			)
			(layer "F.Fab")
		)
		(fp_line
			(start -0.67945 -0.305054)
			(end -0.12065 -0.305054)
			(stroke
				(width 0.1)
				(type default)
			)
			(layer "F.Fab")
		)
		(fp_line
			(start 0.67945 -0.3048)
			(end 0.67945 0.3048)
			(stroke
				(width 0.1)
				(type default)
			)
			(layer "F.Fab")
		)
		(fp_line
			(start 0.12065 -0.3048)
			(end 0.67945 -0.3048)
			(stroke
				(width 0.1)
				(type default)
			)
			(layer "F.Fab")
		)
		(fp_line
			(start 0.12065 -0.2794)
			(end 0.12065 -0.3048)
			(stroke
				(width 0.1)
				(type default)
			)
			(layer "F.Fab")
		)
		(fp_line
			(start -0.12065 -0.2794)
			(end 0.12065 -0.2794)
			(stroke
				(width 0.1)
				(type default)
			)
			(layer "F.Fab")
		)
		(fp_line
			(start 0.120396 0.2794)
			(end -0.12065 0.2794)
			(stroke
				(width 0.1)
				(type default)
			)
			(layer "F.Fab")
		)
		(fp_line
			(start -0.12065 0.2794)
			(end -0.12065 0.3048)
			(stroke
				(width 0.1)
				(type default)
			)
			(layer "F.Fab")
		)
		(fp_line
			(start 0.67945 0.3048)
			(end 0.120396 0.3048)
			(stroke
				(width 0.1)
				(type default)
			)
			(layer "F.Fab")
		)
		(fp_line
			(start 0.120396 0.3048)
			(end 0.120396 0.2794)
			(stroke
				(width 0.1)
				(type default)
			)
			(layer "F.Fab")
		)
		(fp_line
			(start -0.12065 0.3048)
			(end -0.67945 0.3048)
			(stroke
				(width 0.1)
				(type default)
			)
			(layer "F.Fab")
		)
		(fp_line
			(start -0.67945 0.3048)
			(end -0.67945 -0.305054)
			(stroke
				(width 0.1)
				(type default)
			)
			(layer "F.Fab")
		)
		(pad "1" smd circle
			(at -0.40005 0 90)
			(size 0 0)
			(layers "F.Cu" "F.Mask" "F.Paste")
			(net "GND")
		)
		(pad "2" smd circle
			(at 0.40005 0 90)
			(size 0 0)
			(layers "F.Cu" "F.Mask" "F.Paste")
			(net "PEX3_SPARE3")
		)
	)
	(footprint ""
		(layer "F.Cu")
		(at 11.1379 -264.508234)
		(property "Reference" "L84"
			(at 0 0 0)
			(layer "F.SilkS")
			(hide yes)
			(effects
				(font
					(size 1.27 1.27)
				)
			)
		)
		(property "Value" ""
			(at 0 0 0)
			(layer "F.Fab")
			(effects
				(font
					(size 1.27 1.27)
				)
			)
		)
		(duplicate_pad_numbers_are_jumpers no)
		(fp_line
			(start -2.248154 -4.9911)
			(end -2.248154 -1.786382)
			(stroke
				(width 0.1524)
				(type default)
			)
			(layer "F.SilkS")
		)
		(fp_line
			(start -2.248154 1.859026)
			(end -2.248154 4.9911)
			(stroke
				(width 0.1524)
				(type default)
			)
			(layer "F.SilkS")
		)
		(fp_line
			(start -2.248154 4.9911)
			(end 2.248154 4.9911)
			(stroke
				(width 0.1524)
				(type default)
			)
			(layer "F.SilkS")
		)
		(fp_line
			(start 2.248154 -4.9911)
			(end -2.248154 -4.9911)
			(stroke
				(width 0.1524)
				(type default)
			)
			(layer "F.SilkS")
		)
		(fp_line
			(start 2.248154 -1.775206)
			(end 2.248154 -4.9911)
			(stroke
				(width 0.1524)
				(type default)
			)
			(layer "F.SilkS")
		)
		(fp_line
			(start 2.248154 4.9911)
			(end 2.248154 1.79324)
			(stroke
				(width 0.1524)
				(type default)
			)
			(layer "F.SilkS")
		)
		(fp_line
			(start -1.700022 -0.899922)
			(end -1.700022 0.899922)
			(stroke
				(width 0.1)
				(type default)
			)
			(layer "F.Fab")
		)
		(fp_line
			(start -1.700022 0.899922)
			(end 1.700022 0.899922)
			(stroke
				(width 0.1)
				(type default)
			)
			(layer "F.Fab")
		)
		(fp_line
			(start 1.700022 -0.899922)
			(end -1.700022 -0.899922)
			(stroke
				(width 0.1)
				(type default)
			)
			(layer "F.Fab")
		)
		(fp_line
			(start 1.700022 0.899922)
			(end 1.700022 -0.899922)
			(stroke
				(width 0.1)
				(type default)
			)
			(layer "F.Fab")
		)
		(pad "1" smd rect
			(at -1.575054 0)
			(size 1.1684 9.8044)
			(layers "F.Cu" "F.Mask" "F.Paste")
			(net "P1V25_PEX0")
		)
		(pad "2" smd rect
			(at 1.575054 0)
			(size 1.1684 9.8044)
			(layers "F.Cu" "F.Mask" "F.Paste")
			(net "P1V25_SERDES_VDDPLL_PEX0")
		)
	)
	(footprint ""
		(layer "F.Cu")
		(at 213.730332 -224.398586 180)
		(property "Reference" "R4881"
			(at 0 0 180)
			(layer "F.SilkS")
			(hide yes)
			(effects
				(font
					(size 1.27 1.27)
				)
			)
		)
		(property "Value" ""
			(at 0 0 180)
			(layer "F.Fab")
			(effects
				(font
					(size 1.27 1.27)
				)
			)
		)
		(duplicate_pad_numbers_are_jumpers no)
		(fp_line
			(start 0.7874 0.4064)
			(end -0.7874 0.4064)
			(stroke
				(width 0.1524)
				(type default)
			)
			(layer "F.SilkS")
		)
		(fp_line
			(start 0.7874 -0.4064)
			(end 0.7874 0.4064)
			(stroke
				(width 0.1524)
				(type default)
			)
			(layer "F.SilkS")
		)
		(fp_line
			(start -0.7874 0.4064)
			(end -0.7874 -0.4064)
			(stroke
				(width 0.1524)
				(type default)
			)
			(layer "F.SilkS")
		)
		(fp_line
			(start -0.7874 -0.4064)
			(end 0.7874 -0.4064)
			(stroke
				(width 0.1524)
				(type default)
			)
			(layer "F.SilkS")
		)
		(fp_line
			(start 0.67945 0.3048)
			(end 0.120396 0.3048)
			(stroke
				(width 0.1)
				(type default)
			)
			(layer "F.Fab")
		)
		(fp_line
			(start 0.67945 -0.3048)
			(end 0.67945 0.3048)
			(stroke
				(width 0.1)
				(type default)
			)
			(layer "F.Fab")
		)
		(fp_line
			(start 0.12065 -0.2794)
			(end 0.12065 -0.3048)
			(stroke
				(width 0.1)
				(type default)
			)
			(layer "F.Fab")
		)
		(fp_line
			(start 0.12065 -0.3048)
			(end 0.67945 -0.3048)
			(stroke
				(width 0.1)
				(type default)
			)
			(layer "F.Fab")
		)
		(fp_line
			(start 0.120396 0.3048)
			(end 0.120396 0.2794)
			(stroke
				(width 0.1)
				(type default)
			)
			(layer "F.Fab")
		)
		(fp_line
			(start 0.120396 0.2794)
			(end -0.12065 0.2794)
			(stroke
				(width 0.1)
				(type default)
			)
			(layer "F.Fab")
		)
		(fp_line
			(start -0.12065 0.3048)
			(end -0.67945 0.3048)
			(stroke
				(width 0.1)
				(type default)
			)
			(layer "F.Fab")
		)
		(fp_line
			(start -0.12065 0.2794)
			(end -0.12065 0.3048)
			(stroke
				(width 0.1)
				(type default)
			)
			(layer "F.Fab")
		)
		(fp_line
			(start -0.12065 -0.2794)
			(end 0.12065 -0.2794)
			(stroke
				(width 0.1)
				(type default)
			)
			(layer "F.Fab")
		)
		(fp_line
			(start -0.12065 -0.305054)
			(end -0.12065 -0.2794)
			(stroke
				(width 0.1)
				(type default)
			)
			(layer "F.Fab")
		)
		(fp_line
			(start -0.67945 0.3048)
			(end -0.67945 -0.305054)
			(stroke
				(width 0.1)
				(type default)
			)
			(layer "F.Fab")
		)
		(fp_line
			(start -0.67945 -0.305054)
			(end -0.12065 -0.305054)
			(stroke
				(width 0.1)
				(type default)
			)
			(layer "F.Fab")
		)
		(pad "1" smd circle
			(at -0.40005 0 180)
			(size 0 0)
			(layers "F.Cu" "F.Mask" "F.Paste")
			(net "SMB_MB_I3C_ISO_SCL")
		)
		(pad "2" smd circle
			(at 0.40005 0 180)
			(size 0 0)
			(layers "F.Cu" "F.Mask" "F.Paste")
			(net "P3V3_AUX")
		)
	)
	(footprint ""
		(layer "F.Cu")
		(at 352.319844 -158.417768)
		(property "Reference" "R4809"
			(at 0 0 0)
			(layer "F.SilkS")
			(hide yes)
			(effects
				(font
					(size 1.27 1.27)
				)
			)
		)
		(property "Value" ""
			(at 0 0 0)
			(layer "F.Fab")
			(effects
				(font
					(size 1.27 1.27)
				)
			)
		)
		(duplicate_pad_numbers_are_jumpers no)
		(fp_line
			(start -0.7874 -0.4064)
			(end 0.7874 -0.4064)
			(stroke
				(width 0.1524)
				(type default)
			)
			(layer "F.SilkS")
		)
		(fp_line
			(start -0.7874 0.4064)
			(end -0.7874 -0.4064)
			(stroke
				(width 0.1524)
				(type default)
			)
			(layer "F.SilkS")
		)
		(fp_line
			(start 0.7874 -0.4064)
			(end 0.7874 0.4064)
			(stroke
				(width 0.1524)
				(type default)
			)
			(layer "F.SilkS")
		)
		(fp_line
			(start 0.7874 0.4064)
			(end -0.7874 0.4064)
			(stroke
				(width 0.1524)
				(type default)
			)
			(layer "F.SilkS")
		)
		(fp_line
			(start -0.67945 -0.305054)
			(end -0.12065 -0.305054)
			(stroke
				(width 0.1)
				(type default)
			)
			(layer "F.Fab")
		)
		(fp_line
			(start -0.67945 0.3048)
			(end -0.67945 -0.305054)
			(stroke
				(width 0.1)
				(type default)
			)
			(layer "F.Fab")
		)
		(fp_line
			(start -0.12065 -0.305054)
			(end -0.12065 -0.2794)
			(stroke
				(width 0.1)
				(type default)
			)
			(layer "F.Fab")
		)
		(fp_line
			(start -0.12065 -0.2794)
			(end 0.12065 -0.2794)
			(stroke
				(width 0.1)
				(type default)
			)
			(layer "F.Fab")
		)
		(fp_line
			(start -0.12065 0.2794)
			(end -0.12065 0.3048)
			(stroke
				(width 0.1)
				(type default)
			)
			(layer "F.Fab")
		)
		(fp_line
			(start -0.12065 0.3048)
			(end -0.67945 0.3048)
			(stroke
				(width 0.1)
				(type default)
			)
			(layer "F.Fab")
		)
		(fp_line
			(start 0.120396 0.2794)
			(end -0.12065 0.2794)
			(stroke
				(width 0.1)
				(type default)
			)
			(layer "F.Fab")
		)
		(fp_line
			(start 0.120396 0.3048)
			(end 0.120396 0.2794)
			(stroke
				(width 0.1)
				(type default)
			)
			(layer "F.Fab")
		)
		(fp_line
			(start 0.12065 -0.3048)
			(end 0.67945 -0.3048)
			(stroke
				(width 0.1)
				(type default)
			)
			(layer "F.Fab")
		)
		(fp_line
			(start 0.12065 -0.2794)
			(end 0.12065 -0.3048)
			(stroke
				(width 0.1)
				(type default)
			)
			(layer "F.Fab")
		)
		(fp_line
			(start 0.67945 -0.3048)
			(end 0.67945 0.3048)
			(stroke
				(width 0.1)
				(type default)
			)
			(layer "F.Fab")
		)
		(fp_line
			(start 0.67945 0.3048)
			(end 0.120396 0.3048)
			(stroke
				(width 0.1)
				(type default)
			)
			(layer "F.Fab")
		)
		(pad "1" smd circle
			(at -0.40005 0)
			(size 0 0)
			(layers "F.Cu" "F.Mask" "F.Paste")
			(net "PCA9555_0_PEX3_A0")
		)
		(pad "2" smd circle
			(at 0.40005 0)
			(size 0 0)
			(layers "F.Cu" "F.Mask" "F.Paste")
			(net "P3V3_AUX")
		)
	)
	(footprint ""
		(layer "F.Cu")
		(at 428.319438 -134.394702 180)
		(property "Reference" "C652"
			(at 0 0 180)
			(layer "F.SilkS")
			(hide yes)
			(effects
				(font
					(size 1.27 1.27)
				)
			)
		)
		(property "Value" ""
			(at 0 0 180)
			(layer "F.Fab")
			(effects
				(font
					(size 1.27 1.27)
				)
			)
		)
		(duplicate_pad_numbers_are_jumpers no)
		(fp_line
			(start 0.299974 0.150114)
			(end -0.299974 0.150114)
			(stroke
				(width 0.1)
				(type default)
			)
			(layer "F.Fab")
		)
		(fp_line
			(start 0.299974 -0.150114)
			(end 0.299974 0.150114)
			(stroke
				(width 0.1)
				(type default)
			)
			(layer "F.Fab")
		)
		(fp_line
			(start -0.299974 0.150114)
			(end -0.299974 -0.150114)
			(stroke
				(width 0.1)
				(type default)
			)
			(layer "F.Fab")
		)
		(fp_line
			(start -0.299974 -0.150114)
			(end 0.299974 -0.150114)
			(stroke
				(width 0.1)
				(type default)
			)
			(layer "F.Fab")
		)
		(pad "1" smd rect
			(at -0.2667 0 180)
			(size 0.3048 0.381)
			(layers "F.Cu" "F.Mask" "F.Paste")
			(net "P5E_PEX3_STN0_TX_DP<6>")
		)
		(pad "2" smd rect
			(at 0.2667 0 180)
			(size 0.3048 0.381)
			(layers "F.Cu" "F.Mask" "F.Paste")
			(net "P5E_PEX3_STN0_TX_C_DP<6>")
		)
	)
	(footprint ""
		(layer "F.Cu")
		(at 331.405992 -113.114582 -90)
		(property "Reference" "PD95"
			(at 4.199382 -2.198878 90)
			(unlocked yes)
			(layer "F.SilkS")
			(effects
				(font
					(size 0.7874 0.5842)
					(thickness 0.1524)
				)
				(justify left)
			)
		)
		(property "Value" ""
			(at 0 0 270)
			(layer "F.Fab")
			(effects
				(font
					(size 1.27 1.27)
				)
			)
		)
		(duplicate_pad_numbers_are_jumpers no)
		(fp_line
			(start -3.400044 1.459992)
			(end -3.400044 -1.459992)
			(stroke
				(width 0.1524)
				(type default)
			)
			(layer "F.SilkS")
		)
		(fp_line
			(start 4.107942 1.459992)
			(end -3.400044 1.459992)
			(stroke
				(width 0.1524)
				(type default)
			)
			(layer "F.SilkS")
		)
		(fp_line
			(start -3.400044 -1.459992)
			(end 4.107942 -1.459992)
			(stroke
				(width 0.1524)
				(type default)
			)
			(layer "F.SilkS")
		)
		(fp_line
			(start 4.107942 -1.459992)
			(end 4.107942 1.459992)
			(stroke
				(width 0.1524)
				(type default)
			)
			(layer "F.SilkS")
		)
		(fp_rect
			(start 4.107942 1.459992)
			(end 3.308096 -1.459992)
			(stroke
				(width 0)
				(type default)
			)
			(fill yes)
			(layer "F.SilkS")
		)
		(fp_line
			(start -2.29997 1.459992)
			(end -2.29997 -1.459992)
			(stroke
				(width 0.1)
				(type default)
			)
			(layer "F.Fab")
		)
		(fp_line
			(start 2.29997 1.459992)
			(end -2.29997 1.459992)
			(stroke
				(width 0.1)
				(type default)
			)
			(layer "F.Fab")
		)
		(fp_line
			(start -2.29997 -1.459992)
			(end 2.29997 -1.459992)
			(stroke
				(width 0.1)
				(type default)
			)
			(layer "F.Fab")
		)
		(fp_line
			(start 2.29997 -1.459992)
			(end 2.29997 1.459992)
			(stroke
				(width 0.1)
				(type default)
			)
			(layer "F.Fab")
		)
		(fp_text user "-"
			(at 5.4102 0.29845 90)
			(unlocked yes)
			(layer "F.SilkS")
			(effects
				(font
					(size 1.905 1.4224)
					(thickness 0.1524)
				)
				(justify left)
			)
		)
		(fp_text user "+"
			(at -4.7752 -0.12065 270)
			(unlocked yes)
			(layer "F.SilkS")
			(effects
				(font
					(size 1.905 1.4224)
					(thickness 0.1524)
				)
				(justify left)
			)
		)
		(fp_text user "-"
			(at 5.4102 0.29845 90)
			(unlocked yes)
			(layer "F.Fab")
			(effects
				(font
					(size 1.905 1.4224)
					(thickness 0.1524)
				)
				(justify left)
			)
		)
		(fp_text user "+"
			(at -4.7752 -0.12065 270)
			(unlocked yes)
			(layer "F.Fab")
			(effects
				(font
					(size 1.905 1.4224)
					(thickness 0.1524)
				)
				(justify left)
			)
		)
		(pad "A" smd rect
			(at -1.999996 0)
			(size 1.7018 2.5146)
			(layers "F.Cu" "F.Mask" "F.Paste")
			(net "GND")
		)
		(pad "C" smd rect
			(at 1.999996 0)
			(size 1.7018 2.5146)
			(layers "F.Cu" "F.Mask" "F.Paste")
			(net "P12V_NIC5_R")
		)
	)
	(footprint ""
		(layer "F.Cu")
		(at 376.34926 -300.197012 -90)
		(property "Reference" "C3540"
			(at 0 0 270)
			(layer "F.SilkS")
			(hide yes)
			(effects
				(font
					(size 1.27 1.27)
				)
			)
		)
		(property "Value" ""
			(at 0 0 270)
			(layer "F.Fab")
			(effects
				(font
					(size 1.27 1.27)
				)
			)
		)
		(duplicate_pad_numbers_are_jumpers no)
		(fp_line
			(start -0.299974 0.150114)
			(end -0.299974 -0.150114)
			(stroke
				(width 0.1)
				(type default)
			)
			(layer "F.Fab")
		)
		(fp_line
			(start 0.299974 0.150114)
			(end -0.299974 0.150114)
			(stroke
				(width 0.1)
				(type default)
			)
			(layer "F.Fab")
		)
		(fp_line
			(start -0.299974 -0.150114)
			(end 0.299974 -0.150114)
			(stroke
				(width 0.1)
				(type default)
			)
			(layer "F.Fab")
		)
		(fp_line
			(start 0.299974 -0.150114)
			(end 0.299974 0.150114)
			(stroke
				(width 0.1)
				(type default)
			)
			(layer "F.Fab")
		)
		(pad "1" smd rect
			(at -0.2667 0 270)
			(size 0.3048 0.381)
			(layers "F.Cu" "F.Mask" "F.Paste")
			(net "P1V8_PLL0_PEX3")
		)
		(pad "2" smd rect
			(at 0.2667 0 270)
			(size 0.3048 0.381)
			(layers "F.Cu" "F.Mask" "F.Paste")
			(net "GND")
		)
	)
	(footprint ""
		(layer "F.Cu")
		(at 266.956032 -115.590574 90)
		(property "Reference" "U29"
			(at 2.568956 -0.256032 0)
			(unlocked yes)
			(layer "F.SilkS")
			(effects
				(font
					(size 0.7874 0.5842)
					(thickness 0.1524)
				)
			)
		)
		(property "Value" ""
			(at 0 0 90)
			(layer "F.Fab")
			(effects
				(font
					(size 1.27 1.27)
				)
			)
		)
		(duplicate_pad_numbers_are_jumpers no)
		(fp_line
			(start -1.949958 -1.610106)
			(end 1.949958 -1.610106)
			(stroke
				(width 0.1524)
				(type default)
			)
			(layer "F.SilkS")
		)
		(fp_line
			(start 1.949958 -1.560068)
			(end 1.949958 1.610106)
			(stroke
				(width 0.1524)
				(type default)
			)
			(layer "F.SilkS")
		)
		(fp_line
			(start 1.949958 1.610106)
			(end -1.949958 1.610106)
			(stroke
				(width 0.1524)
				(type default)
			)
			(layer "F.SilkS")
		)
		(fp_line
			(start -1.949958 1.610106)
			(end -1.949958 -1.610106)
			(stroke
				(width 0.1524)
				(type default)
			)
			(layer "F.SilkS")
		)
		(fp_line
			(start 0.750062 -1.560068)
			(end 0.750062 1.560068)
			(stroke
				(width 0.1)
				(type default)
			)
			(layer "F.Fab")
		)
		(fp_line
			(start -0.750062 -1.560068)
			(end 0.750062 -1.560068)
			(stroke
				(width 0.1)
				(type default)
			)
			(layer "F.Fab")
		)
		(fp_line
			(start 0.750062 1.560068)
			(end -0.750062 1.560068)
			(stroke
				(width 0.1)
				(type default)
			)
			(layer "F.Fab")
		)
		(fp_line
			(start -0.750062 1.560068)
			(end -0.750062 -1.560068)
			(stroke
				(width 0.1)
				(type default)
			)
			(layer "F.Fab")
		)
		(pad "D" smd rect
			(at 1.100074 0)
			(size 1.016 1.4224)
			(layers "F.Cu" "F.Mask" "F.Paste")
			(net "HP_NIC4_EN")
		)
		(pad "G" smd rect
			(at -1.100074 -0.94996)
			(size 1.016 1.4224)
			(layers "F.Cu" "F.Mask" "F.Paste")
			(net "PRSNT_NIC4_R_N")
		)
		(pad "S" smd rect
			(at -1.100074 0.94996)
			(size 1.016 1.4224)
			(layers "F.Cu" "F.Mask" "F.Paste")
			(net "GND")
		)
	)
	(footprint ""
		(layer "F.Cu")
		(at 363.474 -196.723 180)
		(property "Reference" "R4675"
			(at 0 0 180)
			(layer "F.SilkS")
			(hide yes)
			(effects
				(font
					(size 1.27 1.27)
				)
			)
		)
		(property "Value" ""
			(at 0 0 180)
			(layer "F.Fab")
			(effects
				(font
					(size 1.27 1.27)
				)
			)
		)
		(duplicate_pad_numbers_are_jumpers no)
		(fp_line
			(start 0.7874 0.4064)
			(end -0.7874 0.4064)
			(stroke
				(width 0.1524)
				(type default)
			)
			(layer "F.SilkS")
		)
		(fp_line
			(start 0.7874 -0.4064)
			(end 0.7874 0.4064)
			(stroke
				(width 0.1524)
				(type default)
			)
			(layer "F.SilkS")
		)
		(fp_line
			(start -0.7874 0.4064)
			(end -0.7874 -0.4064)
			(stroke
				(width 0.1524)
				(type default)
			)
			(layer "F.SilkS")
		)
		(fp_line
			(start -0.7874 -0.4064)
			(end 0.7874 -0.4064)
			(stroke
				(width 0.1524)
				(type default)
			)
			(layer "F.SilkS")
		)
		(fp_line
			(start 0.67945 0.3048)
			(end 0.120396 0.3048)
			(stroke
				(width 0.1)
				(type default)
			)
			(layer "F.Fab")
		)
		(fp_line
			(start 0.67945 -0.3048)
			(end 0.67945 0.3048)
			(stroke
				(width 0.1)
				(type default)
			)
			(layer "F.Fab")
		)
		(fp_line
			(start 0.12065 -0.2794)
			(end 0.12065 -0.3048)
			(stroke
				(width 0.1)
				(type default)
			)
			(layer "F.Fab")
		)
		(fp_line
			(start 0.12065 -0.3048)
			(end 0.67945 -0.3048)
			(stroke
				(width 0.1)
				(type default)
			)
			(layer "F.Fab")
		)
		(fp_line
			(start 0.120396 0.3048)
			(end 0.120396 0.2794)
			(stroke
				(width 0.1)
				(type default)
			)
			(layer "F.Fab")
		)
		(fp_line
			(start 0.120396 0.2794)
			(end -0.12065 0.2794)
			(stroke
				(width 0.1)
				(type default)
			)
			(layer "F.Fab")
		)
		(fp_line
			(start -0.12065 0.3048)
			(end -0.67945 0.3048)
			(stroke
				(width 0.1)
				(type default)
			)
			(layer "F.Fab")
		)
		(fp_line
			(start -0.12065 0.2794)
			(end -0.12065 0.3048)
			(stroke
				(width 0.1)
				(type default)
			)
			(layer "F.Fab")
		)
		(fp_line
			(start -0.12065 -0.2794)
			(end 0.12065 -0.2794)
			(stroke
				(width 0.1)
				(type default)
			)
			(layer "F.Fab")
		)
		(fp_line
			(start -0.12065 -0.305054)
			(end -0.12065 -0.2794)
			(stroke
				(width 0.1)
				(type default)
			)
			(layer "F.Fab")
		)
		(fp_line
			(start -0.67945 0.3048)
			(end -0.67945 -0.305054)
			(stroke
				(width 0.1)
				(type default)
			)
			(layer "F.Fab")
		)
		(fp_line
			(start -0.67945 -0.305054)
			(end -0.12065 -0.305054)
			(stroke
				(width 0.1)
				(type default)
			)
			(layer "F.Fab")
		)
		(pad "1" smd circle
			(at -0.40005 0 180)
			(size 0 0)
			(layers "F.Cu" "F.Mask" "F.Paste")
			(net "SSD5_PEX_PWR_EN_R")
		)
		(pad "2" smd circle
			(at 0.40005 0 180)
			(size 0 0)
			(layers "F.Cu" "F.Mask" "F.Paste")
			(net "GND")
		)
	)
	(footprint ""
		(layer "F.Cu")
		(at 319.70599 -386.958332 180)
		(property "Reference" "C4116"
			(at 0 0 180)
			(layer "F.SilkS")
			(hide yes)
			(effects
				(font
					(size 1.27 1.27)
				)
			)
		)
		(property "Value" ""
			(at 0 0 180)
			(layer "F.Fab")
			(effects
				(font
					(size 1.27 1.27)
				)
			)
		)
		(duplicate_pad_numbers_are_jumpers no)
		(fp_line
			(start 0.7874 0.4064)
			(end -0.7874 0.4064)
			(stroke
				(width 0.1524)
				(type default)
			)
			(layer "F.SilkS")
		)
		(fp_line
			(start 0.7874 -0.4064)
			(end 0.7874 0.4064)
			(stroke
				(width 0.1524)
				(type default)
			)
			(layer "F.SilkS")
		)
		(fp_line
			(start -0.7874 0.4064)
			(end -0.7874 -0.4064)
			(stroke
				(width 0.1524)
				(type default)
			)
			(layer "F.SilkS")
		)
		(fp_line
			(start -0.7874 -0.4064)
			(end 0.7874 -0.4064)
			(stroke
				(width 0.1524)
				(type default)
			)
			(layer "F.SilkS")
		)
		(fp_line
			(start 0.67945 0.3048)
			(end 0.120396 0.3048)
			(stroke
				(width 0.1)
				(type default)
			)
			(layer "F.Fab")
		)
		(fp_line
			(start 0.67945 -0.3048)
			(end 0.67945 0.3048)
			(stroke
				(width 0.1)
				(type default)
			)
			(layer "F.Fab")
		)
		(fp_line
			(start 0.12065 -0.2794)
			(end 0.12065 -0.3048)
			(stroke
				(width 0.1)
				(type default)
			)
			(layer "F.Fab")
		)
		(fp_line
			(start 0.12065 -0.3048)
			(end 0.67945 -0.3048)
			(stroke
				(width 0.1)
				(type default)
			)
			(layer "F.Fab")
		)
		(fp_line
			(start 0.120396 0.3048)
			(end 0.120396 0.2794)
			(stroke
				(width 0.1)
				(type default)
			)
			(layer "F.Fab")
		)
		(fp_line
			(start 0.120396 0.2794)
			(end -0.12065 0.2794)
			(stroke
				(width 0.1)
				(type default)
			)
			(layer "F.Fab")
		)
		(fp_line
			(start -0.12065 0.3048)
			(end -0.67945 0.3048)
			(stroke
				(width 0.1)
				(type default)
			)
			(layer "F.Fab")
		)
		(fp_line
			(start -0.12065 0.2794)
			(end -0.12065 0.3048)
			(stroke
				(width 0.1)
				(type default)
			)
			(layer "F.Fab")
		)
		(fp_line
			(start -0.12065 -0.2794)
			(end 0.12065 -0.2794)
			(stroke
				(width 0.1)
				(type default)
			)
			(layer "F.Fab")
		)
		(fp_line
			(start -0.12065 -0.305054)
			(end -0.12065 -0.2794)
			(stroke
				(width 0.1)
				(type default)
			)
			(layer "F.Fab")
		)
		(fp_line
			(start -0.67945 0.3048)
			(end -0.67945 -0.305054)
			(stroke
				(width 0.1)
				(type default)
			)
			(layer "F.Fab")
		)
		(fp_line
			(start -0.67945 -0.305054)
			(end -0.12065 -0.305054)
			(stroke
				(width 0.1)
				(type default)
			)
			(layer "F.Fab")
		)
		(pad "1" smd circle
			(at -0.40005 0 180)
			(size 0 0)
			(layers "F.Cu" "F.Mask" "F.Paste")
			(net "GND")
		)
		(pad "2" smd circle
			(at 0.40005 0 180)
			(size 0 0)
			(layers "F.Cu" "F.Mask" "F.Paste")
			(net "GPU_FPGA_OVERT_N")
		)
	)
	(footprint ""
		(layer "F.Cu")
		(at 1.729994 -255.046734 -90)
		(property "Reference" "R6469"
			(at 0 0 270)
			(layer "F.SilkS")
			(hide yes)
			(effects
				(font
					(size 1.27 1.27)
				)
			)
		)
		(property "Value" ""
			(at 0 0 270)
			(layer "F.Fab")
			(effects
				(font
					(size 1.27 1.27)
				)
			)
		)
		(duplicate_pad_numbers_are_jumpers no)
		(fp_line
			(start -0.7874 0.4064)
			(end -0.7874 -0.4064)
			(stroke
				(width 0.1524)
				(type default)
			)
			(layer "F.SilkS")
		)
		(fp_line
			(start 0.7874 0.4064)
			(end -0.7874 0.4064)
			(stroke
				(width 0.1524)
				(type default)
			)
			(layer "F.SilkS")
		)
		(fp_line
			(start -0.7874 -0.4064)
			(end 0.7874 -0.4064)
			(stroke
				(width 0.1524)
				(type default)
			)
			(layer "F.SilkS")
		)
		(fp_line
			(start 0.7874 -0.4064)
			(end 0.7874 0.4064)
			(stroke
				(width 0.1524)
				(type default)
			)
			(layer "F.SilkS")
		)
		(fp_line
			(start -0.67945 0.3048)
			(end -0.67945 -0.305054)
			(stroke
				(width 0.1)
				(type default)
			)
			(layer "F.Fab")
		)
		(fp_line
			(start -0.12065 0.3048)
			(end -0.67945 0.3048)
			(stroke
				(width 0.1)
				(type default)
			)
			(layer "F.Fab")
		)
		(fp_line
			(start 0.120396 0.3048)
			(end 0.120396 0.2794)
			(stroke
				(width 0.1)
				(type default)
			)
			(layer "F.Fab")
		)
		(fp_line
			(start 0.67945 0.3048)
			(end 0.120396 0.3048)
			(stroke
				(width 0.1)
				(type default)
			)
			(layer "F.Fab")
		)
		(fp_line
			(start -0.12065 0.2794)
			(end -0.12065 0.3048)
			(stroke
				(width 0.1)
				(type default)
			)
			(layer "F.Fab")
		)
		(fp_line
			(start 0.120396 0.2794)
			(end -0.12065 0.2794)
			(stroke
				(width 0.1)
				(type default)
			)
			(layer "F.Fab")
		)
		(fp_line
			(start -0.12065 -0.2794)
			(end 0.12065 -0.2794)
			(stroke
				(width 0.1)
				(type default)
			)
			(layer "F.Fab")
		)
		(fp_line
			(start 0.12065 -0.2794)
			(end 0.12065 -0.3048)
			(stroke
				(width 0.1)
				(type default)
			)
			(layer "F.Fab")
		)
		(fp_line
			(start 0.12065 -0.3048)
			(end 0.67945 -0.3048)
			(stroke
				(width 0.1)
				(type default)
			)
			(layer "F.Fab")
		)
		(fp_line
			(start 0.67945 -0.3048)
			(end 0.67945 0.3048)
			(stroke
				(width 0.1)
				(type default)
			)
			(layer "F.Fab")
		)
		(fp_line
			(start -0.67945 -0.305054)
			(end -0.12065 -0.305054)
			(stroke
				(width 0.1)
				(type default)
			)
			(layer "F.Fab")
		)
		(fp_line
			(start -0.12065 -0.305054)
			(end -0.12065 -0.2794)
			(stroke
				(width 0.1)
				(type default)
			)
			(layer "F.Fab")
		)
		(pad "1" smd circle
			(at -0.40005 0 270)
			(size 0 0)
			(layers "F.Cu" "F.Mask" "F.Paste")
			(net "P1V25_SERDES_VDDPLL_PEX0")
		)
		(pad "2" smd circle
			(at 0.40005 0 270)
			(size 0 0)
			(layers "F.Cu" "F.Mask" "F.Paste")
			(net "P1V25_SERDES_VDDPLL_PEX0_C6")
		)
	)
	(footprint ""
		(layer "F.Cu")
		(at 446.814448 -66.32194 90)
		(property "Reference" "R6021"
			(at 0 0 90)
			(layer "F.SilkS")
			(hide yes)
			(effects
				(font
					(size 1.27 1.27)
				)
			)
		)
		(property "Value" ""
			(at 0 0 90)
			(layer "F.Fab")
			(effects
				(font
					(size 1.27 1.27)
				)
			)
		)
		(duplicate_pad_numbers_are_jumpers no)
		(fp_line
			(start 0.7874 -0.4064)
			(end 0.7874 0.4064)
			(stroke
				(width 0.1524)
				(type default)
			)
			(layer "F.SilkS")
		)
		(fp_line
			(start -0.7874 -0.4064)
			(end 0.7874 -0.4064)
			(stroke
				(width 0.1524)
				(type default)
			)
			(layer "F.SilkS")
		)
		(fp_line
			(start 0.7874 0.4064)
			(end -0.7874 0.4064)
			(stroke
				(width 0.1524)
				(type default)
			)
			(layer "F.SilkS")
		)
		(fp_line
			(start -0.7874 0.4064)
			(end -0.7874 -0.4064)
			(stroke
				(width 0.1524)
				(type default)
			)
			(layer "F.SilkS")
		)
		(fp_line
			(start -0.12065 -0.305054)
			(end -0.12065 -0.2794)
			(stroke
				(width 0.1)
				(type default)
			)
			(layer "F.Fab")
		)
		(fp_line
			(start -0.67945 -0.305054)
			(end -0.12065 -0.305054)
			(stroke
				(width 0.1)
				(type default)
			)
			(layer "F.Fab")
		)
		(fp_line
			(start 0.67945 -0.3048)
			(end 0.67945 0.3048)
			(stroke
				(width 0.1)
				(type default)
			)
			(layer "F.Fab")
		)
		(fp_line
			(start 0.12065 -0.3048)
			(end 0.67945 -0.3048)
			(stroke
				(width 0.1)
				(type default)
			)
			(layer "F.Fab")
		)
		(fp_line
			(start 0.12065 -0.2794)
			(end 0.12065 -0.3048)
			(stroke
				(width 0.1)
				(type default)
			)
			(layer "F.Fab")
		)
		(fp_line
			(start -0.12065 -0.2794)
			(end 0.12065 -0.2794)
			(stroke
				(width 0.1)
				(type default)
			)
			(layer "F.Fab")
		)
		(fp_line
			(start 0.120396 0.2794)
			(end -0.12065 0.2794)
			(stroke
				(width 0.1)
				(type default)
			)
			(layer "F.Fab")
		)
		(fp_line
			(start -0.12065 0.2794)
			(end -0.12065 0.3048)
			(stroke
				(width 0.1)
				(type default)
			)
			(layer "F.Fab")
		)
		(fp_line
			(start 0.67945 0.3048)
			(end 0.120396 0.3048)
			(stroke
				(width 0.1)
				(type default)
			)
			(layer "F.Fab")
		)
		(fp_line
			(start 0.120396 0.3048)
			(end 0.120396 0.2794)
			(stroke
				(width 0.1)
				(type default)
			)
			(layer "F.Fab")
		)
		(fp_line
			(start -0.12065 0.3048)
			(end -0.67945 0.3048)
			(stroke
				(width 0.1)
				(type default)
			)
			(layer "F.Fab")
		)
		(fp_line
			(start -0.67945 0.3048)
			(end -0.67945 -0.305054)
			(stroke
				(width 0.1)
				(type default)
			)
			(layer "F.Fab")
		)
		(pad "1" smd circle
			(at -0.40005 0 90)
			(size 0 0)
			(layers "F.Cu" "F.Mask" "F.Paste")
			(net "SSD15_PWR_EN_R")
		)
		(pad "2" smd circle
			(at 0.40005 0 90)
			(size 0 0)
			(layers "F.Cu" "F.Mask" "F.Paste")
			(net "P12V_SSD15_CO_EN")
		)
	)
	(footprint ""
		(layer "F.Cu")
		(at 352.1837 -61.487812 180)
		(property "Reference" "R6014"
			(at 0 0 180)
			(layer "F.SilkS")
			(hide yes)
			(effects
				(font
					(size 1.27 1.27)
				)
			)
		)
		(property "Value" ""
			(at 0 0 180)
			(layer "F.Fab")
			(effects
				(font
					(size 1.27 1.27)
				)
			)
		)
		(duplicate_pad_numbers_are_jumpers no)
		(fp_line
			(start 0.7874 0.4064)
			(end -0.7874 0.4064)
			(stroke
				(width 0.1524)
				(type default)
			)
			(layer "F.SilkS")
		)
		(fp_line
			(start 0.7874 -0.4064)
			(end 0.7874 0.4064)
			(stroke
				(width 0.1524)
				(type default)
			)
			(layer "F.SilkS")
		)
		(fp_line
			(start -0.7874 0.4064)
			(end -0.7874 -0.4064)
			(stroke
				(width 0.1524)
				(type default)
			)
			(layer "F.SilkS")
		)
		(fp_line
			(start -0.7874 -0.4064)
			(end 0.7874 -0.4064)
			(stroke
				(width 0.1524)
				(type default)
			)
			(layer "F.SilkS")
		)
		(fp_line
			(start 0.67945 0.3048)
			(end 0.120396 0.3048)
			(stroke
				(width 0.1)
				(type default)
			)
			(layer "F.Fab")
		)
		(fp_line
			(start 0.67945 -0.3048)
			(end 0.67945 0.3048)
			(stroke
				(width 0.1)
				(type default)
			)
			(layer "F.Fab")
		)
		(fp_line
			(start 0.12065 -0.2794)
			(end 0.12065 -0.3048)
			(stroke
				(width 0.1)
				(type default)
			)
			(layer "F.Fab")
		)
		(fp_line
			(start 0.12065 -0.3048)
			(end 0.67945 -0.3048)
			(stroke
				(width 0.1)
				(type default)
			)
			(layer "F.Fab")
		)
		(fp_line
			(start 0.120396 0.3048)
			(end 0.120396 0.2794)
			(stroke
				(width 0.1)
				(type default)
			)
			(layer "F.Fab")
		)
		(fp_line
			(start 0.120396 0.2794)
			(end -0.12065 0.2794)
			(stroke
				(width 0.1)
				(type default)
			)
			(layer "F.Fab")
		)
		(fp_line
			(start -0.12065 0.3048)
			(end -0.67945 0.3048)
			(stroke
				(width 0.1)
				(type default)
			)
			(layer "F.Fab")
		)
		(fp_line
			(start -0.12065 0.2794)
			(end -0.12065 0.3048)
			(stroke
				(width 0.1)
				(type default)
			)
			(layer "F.Fab")
		)
		(fp_line
			(start -0.12065 -0.2794)
			(end 0.12065 -0.2794)
			(stroke
				(width 0.1)
				(type default)
			)
			(layer "F.Fab")
		)
		(fp_line
			(start -0.12065 -0.305054)
			(end -0.12065 -0.2794)
			(stroke
				(width 0.1)
				(type default)
			)
			(layer "F.Fab")
		)
		(fp_line
			(start -0.67945 0.3048)
			(end -0.67945 -0.305054)
			(stroke
				(width 0.1)
				(type default)
			)
			(layer "F.Fab")
		)
		(fp_line
			(start -0.67945 -0.305054)
			(end -0.12065 -0.305054)
			(stroke
				(width 0.1)
				(type default)
			)
			(layer "F.Fab")
		)
		(pad "1" smd circle
			(at -0.40005 0 180)
			(size 0 0)
			(layers "F.Cu" "F.Mask" "F.Paste")
			(net "PWRGD_P12V_SSD12_D")
		)
		(pad "2" smd circle
			(at 0.40005 0 180)
			(size 0 0)
			(layers "F.Cu" "F.Mask" "F.Paste")
			(net "PWRGD_P12V_SSD12_R")
		)
	)
	(footprint ""
		(layer "F.Cu")
		(at 157.301438 -55.78475 -90)
		(property "Reference" "PD27"
			(at 1.881378 2.156968 90)
			(unlocked yes)
			(layer "F.SilkS")
			(effects
				(font
					(size 0.7874 0.5842)
					(thickness 0.1524)
				)
				(justify left)
			)
		)
		(property "Value" ""
			(at 0 0 270)
			(layer "F.Fab")
			(effects
				(font
					(size 1.27 1.27)
				)
			)
		)
		(duplicate_pad_numbers_are_jumpers no)
		(fp_line
			(start -3.400044 1.459992)
			(end -3.400044 -1.459992)
			(stroke
				(width 0.1524)
				(type default)
			)
			(layer "F.SilkS")
		)
		(fp_line
			(start 4.107942 1.459992)
			(end -3.400044 1.459992)
			(stroke
				(width 0.1524)
				(type default)
			)
			(layer "F.SilkS")
		)
		(fp_line
			(start -3.400044 -1.459992)
			(end 4.107942 -1.459992)
			(stroke
				(width 0.1524)
				(type default)
			)
			(layer "F.SilkS")
		)
		(fp_line
			(start 4.107942 -1.459992)
			(end 4.107942 1.459992)
			(stroke
				(width 0.1524)
				(type default)
			)
			(layer "F.SilkS")
		)
		(fp_poly
			(pts
				(xy 4.107942 -1.459992) (xy 4.107942 1.459992) (xy 3.308096 1.459992) (xy 3.308096 -1.459992)
			)
			(stroke
				(width 0)
				(type default)
			)
			(fill yes)
			(layer "F.SilkS")
		)
		(fp_line
			(start -2.29997 1.459992)
			(end -2.29997 -1.459992)
			(stroke
				(width 0.1)
				(type default)
			)
			(layer "F.Fab")
		)
		(fp_line
			(start 2.29997 1.459992)
			(end -2.29997 1.459992)
			(stroke
				(width 0.1)
				(type default)
			)
			(layer "F.Fab")
		)
		(fp_line
			(start -2.29997 -1.459992)
			(end 2.29997 -1.459992)
			(stroke
				(width 0.1)
				(type default)
			)
			(layer "F.Fab")
		)
		(fp_line
			(start 2.29997 -1.459992)
			(end 2.29997 1.459992)
			(stroke
				(width 0.1)
				(type default)
			)
			(layer "F.Fab")
		)
		(fp_text user "-"
			(at 5.4102 0.29845 90)
			(unlocked yes)
			(layer "F.SilkS")
			(effects
				(font
					(size 1.905 1.4224)
					(thickness 0.1524)
				)
				(justify left)
			)
		)
		(fp_text user "+"
			(at -4.7752 -0.12065 270)
			(unlocked yes)
			(layer "F.SilkS")
			(effects
				(font
					(size 1.905 1.4224)
					(thickness 0.1524)
				)
				(justify left)
			)
		)
		(fp_text user "-"
			(at 5.4102 0.29845 90)
			(unlocked yes)
			(layer "F.Fab")
			(effects
				(font
					(size 1.905 1.4224)
					(thickness 0.1524)
				)
				(justify left)
			)
		)
		(fp_text user "+"
			(at -4.7752 -0.12065 270)
			(unlocked yes)
			(layer "F.Fab")
			(effects
				(font
					(size 1.905 1.4224)
					(thickness 0.1524)
				)
				(justify left)
			)
		)
		(pad "A" smd rect
			(at -1.999996 0)
			(size 1.7018 2.5146)
			(layers "F.Cu" "F.Mask" "F.Paste")
			(net "GND")
		)
		(pad "C" smd rect
			(at 1.999996 0)
			(size 1.7018 2.5146)
			(layers "F.Cu" "F.Mask" "F.Paste")
			(net "P12V_SSD5_R")
		)
	)
	(footprint ""
		(layer "F.Cu")
		(at 400.567906 -53.051456)
		(property "Reference" "R4469"
			(at 0 0 0)
			(layer "F.SilkS")
			(hide yes)
			(effects
				(font
					(size 1.27 1.27)
				)
			)
		)
		(property "Value" ""
			(at 0 0 0)
			(layer "F.Fab")
			(effects
				(font
					(size 1.27 1.27)
				)
			)
		)
		(duplicate_pad_numbers_are_jumpers no)
		(fp_line
			(start -0.7874 -0.4064)
			(end 0.7874 -0.4064)
			(stroke
				(width 0.1524)
				(type default)
			)
			(layer "F.SilkS")
		)
		(fp_line
			(start -0.7874 0.4064)
			(end -0.7874 -0.4064)
			(stroke
				(width 0.1524)
				(type default)
			)
			(layer "F.SilkS")
		)
		(fp_line
			(start 0.7874 -0.4064)
			(end 0.7874 0.4064)
			(stroke
				(width 0.1524)
				(type default)
			)
			(layer "F.SilkS")
		)
		(fp_line
			(start 0.7874 0.4064)
			(end -0.7874 0.4064)
			(stroke
				(width 0.1524)
				(type default)
			)
			(layer "F.SilkS")
		)
		(fp_line
			(start -0.67945 -0.305054)
			(end -0.12065 -0.305054)
			(stroke
				(width 0.1)
				(type default)
			)
			(layer "F.Fab")
		)
		(fp_line
			(start -0.67945 0.3048)
			(end -0.67945 -0.305054)
			(stroke
				(width 0.1)
				(type default)
			)
			(layer "F.Fab")
		)
		(fp_line
			(start -0.12065 -0.305054)
			(end -0.12065 -0.2794)
			(stroke
				(width 0.1)
				(type default)
			)
			(layer "F.Fab")
		)
		(fp_line
			(start -0.12065 -0.2794)
			(end 0.12065 -0.2794)
			(stroke
				(width 0.1)
				(type default)
			)
			(layer "F.Fab")
		)
		(fp_line
			(start -0.12065 0.2794)
			(end -0.12065 0.3048)
			(stroke
				(width 0.1)
				(type default)
			)
			(layer "F.Fab")
		)
		(fp_line
			(start -0.12065 0.3048)
			(end -0.67945 0.3048)
			(stroke
				(width 0.1)
				(type default)
			)
			(layer "F.Fab")
		)
		(fp_line
			(start 0.120396 0.2794)
			(end -0.12065 0.2794)
			(stroke
				(width 0.1)
				(type default)
			)
			(layer "F.Fab")
		)
		(fp_line
			(start 0.120396 0.3048)
			(end 0.120396 0.2794)
			(stroke
				(width 0.1)
				(type default)
			)
			(layer "F.Fab")
		)
		(fp_line
			(start 0.12065 -0.3048)
			(end 0.67945 -0.3048)
			(stroke
				(width 0.1)
				(type default)
			)
			(layer "F.Fab")
		)
		(fp_line
			(start 0.12065 -0.2794)
			(end 0.12065 -0.3048)
			(stroke
				(width 0.1)
				(type default)
			)
			(layer "F.Fab")
		)
		(fp_line
			(start 0.67945 -0.3048)
			(end 0.67945 0.3048)
			(stroke
				(width 0.1)
				(type default)
			)
			(layer "F.Fab")
		)
		(fp_line
			(start 0.67945 0.3048)
			(end 0.120396 0.3048)
			(stroke
				(width 0.1)
				(type default)
			)
			(layer "F.Fab")
		)
		(pad "1" smd circle
			(at -0.40005 0)
			(size 0 0)
			(layers "F.Cu" "F.Mask" "F.Paste")
			(net "PWRGD_P12V_SSD13")
		)
		(pad "2" smd circle
			(at 0.40005 0)
			(size 0 0)
			(layers "F.Cu" "F.Mask" "F.Paste")
			(net "PWRGD_P12V_SSD13_R")
		)
	)
	(footprint ""
		(layer "F.Cu")
		(at 7.613396 -134.042404)
		(property "Reference" "R4444"
			(at 0 0 0)
			(layer "F.SilkS")
			(hide yes)
			(effects
				(font
					(size 1.27 1.27)
				)
			)
		)
		(property "Value" ""
			(at 0 0 0)
			(layer "F.Fab")
			(effects
				(font
					(size 1.27 1.27)
				)
			)
		)
		(duplicate_pad_numbers_are_jumpers no)
		(fp_line
			(start -0.7874 -0.4064)
			(end 0.7874 -0.4064)
			(stroke
				(width 0.1524)
				(type default)
			)
			(layer "F.SilkS")
		)
		(fp_line
			(start -0.7874 0.4064)
			(end -0.7874 -0.4064)
			(stroke
				(width 0.1524)
				(type default)
			)
			(layer "F.SilkS")
		)
		(fp_line
			(start 0.7874 -0.4064)
			(end 0.7874 0.4064)
			(stroke
				(width 0.1524)
				(type default)
			)
			(layer "F.SilkS")
		)
		(fp_line
			(start 0.7874 0.4064)
			(end -0.7874 0.4064)
			(stroke
				(width 0.1524)
				(type default)
			)
			(layer "F.SilkS")
		)
		(fp_line
			(start -0.67945 -0.305054)
			(end -0.12065 -0.305054)
			(stroke
				(width 0.1)
				(type default)
			)
			(layer "F.Fab")
		)
		(fp_line
			(start -0.67945 0.3048)
			(end -0.67945 -0.305054)
			(stroke
				(width 0.1)
				(type default)
			)
			(layer "F.Fab")
		)
		(fp_line
			(start -0.12065 -0.305054)
			(end -0.12065 -0.2794)
			(stroke
				(width 0.1)
				(type default)
			)
			(layer "F.Fab")
		)
		(fp_line
			(start -0.12065 -0.2794)
			(end 0.12065 -0.2794)
			(stroke
				(width 0.1)
				(type default)
			)
			(layer "F.Fab")
		)
		(fp_line
			(start -0.12065 0.2794)
			(end -0.12065 0.3048)
			(stroke
				(width 0.1)
				(type default)
			)
			(layer "F.Fab")
		)
		(fp_line
			(start -0.12065 0.3048)
			(end -0.67945 0.3048)
			(stroke
				(width 0.1)
				(type default)
			)
			(layer "F.Fab")
		)
		(fp_line
			(start 0.120396 0.2794)
			(end -0.12065 0.2794)
			(stroke
				(width 0.1)
				(type default)
			)
			(layer "F.Fab")
		)
		(fp_line
			(start 0.120396 0.3048)
			(end 0.120396 0.2794)
			(stroke
				(width 0.1)
				(type default)
			)
			(layer "F.Fab")
		)
		(fp_line
			(start 0.12065 -0.3048)
			(end 0.67945 -0.3048)
			(stroke
				(width 0.1)
				(type default)
			)
			(layer "F.Fab")
		)
		(fp_line
			(start 0.12065 -0.2794)
			(end 0.12065 -0.3048)
			(stroke
				(width 0.1)
				(type default)
			)
			(layer "F.Fab")
		)
		(fp_line
			(start 0.67945 -0.3048)
			(end 0.67945 0.3048)
			(stroke
				(width 0.1)
				(type default)
			)
			(layer "F.Fab")
		)
		(fp_line
			(start 0.67945 0.3048)
			(end 0.120396 0.3048)
			(stroke
				(width 0.1)
				(type default)
			)
			(layer "F.Fab")
		)
		(pad "1" smd circle
			(at -0.40005 0)
			(size 0 0)
			(layers "F.Cu" "F.Mask" "F.Paste")
			(net "HP_NIC0_EN")
		)
		(pad "2" smd circle
			(at 0.40005 0)
			(size 0 0)
			(layers "F.Cu" "F.Mask" "F.Paste")
			(net "P12V_NIC0_EN_R")
		)
	)
	(footprint ""
		(layer "F.Cu")
		(at 107.70616 -137.43686 -90)
		(property "Reference" "PC37"
			(at 0 0 270)
			(layer "F.SilkS")
			(hide yes)
			(effects
				(font
					(size 1.27 1.27)
				)
			)
		)
		(property "Value" ""
			(at 0 0 270)
			(layer "F.Fab")
			(effects
				(font
					(size 1.27 1.27)
				)
			)
		)
		(duplicate_pad_numbers_are_jumpers no)
		(fp_line
			(start -1.988058 2.750058)
			(end 2.750058 2.750058)
			(stroke
				(width 0.1524)
				(type default)
			)
			(layer "F.SilkS")
		)
		(fp_line
			(start 2.750058 2.750058)
			(end 2.750058 0.9398)
			(stroke
				(width 0.1524)
				(type default)
			)
			(layer "F.SilkS")
		)
		(fp_line
			(start -2.750058 1.988058)
			(end -1.988058 2.750058)
			(stroke
				(width 0.1524)
				(type default)
			)
			(layer "F.SilkS")
		)
		(fp_line
			(start -2.750058 0.9398)
			(end -2.750058 1.988058)
			(stroke
				(width 0.1524)
				(type default)
			)
			(layer "F.SilkS")
		)
		(fp_line
			(start 2.750058 -0.9398)
			(end 2.750058 -2.750058)
			(stroke
				(width 0.1524)
				(type default)
			)
			(layer "F.SilkS")
		)
		(fp_line
			(start -2.750058 -1.988058)
			(end -2.750058 -0.9398)
			(stroke
				(width 0.1524)
				(type default)
			)
			(layer "F.SilkS")
		)
		(fp_line
			(start -1.988058 -2.750058)
			(end -2.750058 -1.988058)
			(stroke
				(width 0.1524)
				(type default)
			)
			(layer "F.SilkS")
		)
		(fp_line
			(start 2.750058 -2.750058)
			(end -1.988058 -2.750058)
			(stroke
				(width 0.1524)
				(type default)
			)
			(layer "F.SilkS")
		)
		(fp_line
			(start -2.750058 2.750058)
			(end 2.750058 2.750058)
			(stroke
				(width 0.1)
				(type default)
			)
			(layer "F.Fab")
		)
		(fp_line
			(start 2.750058 2.750058)
			(end 2.750058 -2.750058)
			(stroke
				(width 0.1)
				(type default)
			)
			(layer "F.Fab")
		)
		(fp_line
			(start -2.750058 -2.750058)
			(end -2.750058 2.750058)
			(stroke
				(width 0.1)
				(type default)
			)
			(layer "F.Fab")
		)
		(fp_line
			(start 2.750058 -2.750058)
			(end -2.750058 -2.750058)
			(stroke
				(width 0.1)
				(type default)
			)
			(layer "F.Fab")
		)
		(pad "1" smd rect
			(at -2.199894 0)
			(size 1.6002 3.0226)
			(layers "F.Cu" "F.Mask" "F.Paste")
			(net "P3V3_AUX")
		)
		(pad "2" smd rect
			(at 2.199894 0)
			(size 1.6002 3.0226)
			(layers "F.Cu" "F.Mask" "F.Paste")
			(net "GND")
		)
	)
	(footprint ""
		(layer "F.Cu")
		(at 147.966938 -52.543456 180)
		(property "Reference" "PC514"
			(at 0 0 180)
			(layer "F.SilkS")
			(hide yes)
			(effects
				(font
					(size 1.27 1.27)
				)
			)
		)
		(property "Value" ""
			(at 0 0 180)
			(layer "F.Fab")
			(effects
				(font
					(size 1.27 1.27)
				)
			)
		)
		(duplicate_pad_numbers_are_jumpers no)
		(fp_line
			(start 0.7874 0.4064)
			(end -0.7874 0.4064)
			(stroke
				(width 0.1524)
				(type default)
			)
			(layer "F.SilkS")
		)
		(fp_line
			(start 0.7874 -0.4064)
			(end 0.7874 0.4064)
			(stroke
				(width 0.1524)
				(type default)
			)
			(layer "F.SilkS")
		)
		(fp_line
			(start -0.7874 0.4064)
			(end -0.7874 -0.4064)
			(stroke
				(width 0.1524)
				(type default)
			)
			(layer "F.SilkS")
		)
		(fp_line
			(start -0.7874 -0.4064)
			(end 0.7874 -0.4064)
			(stroke
				(width 0.1524)
				(type default)
			)
			(layer "F.SilkS")
		)
		(fp_line
			(start 0.67945 0.3048)
			(end 0.120396 0.3048)
			(stroke
				(width 0.1)
				(type default)
			)
			(layer "F.Fab")
		)
		(fp_line
			(start 0.67945 -0.3048)
			(end 0.67945 0.3048)
			(stroke
				(width 0.1)
				(type default)
			)
			(layer "F.Fab")
		)
		(fp_line
			(start 0.12065 -0.2794)
			(end 0.12065 -0.3048)
			(stroke
				(width 0.1)
				(type default)
			)
			(layer "F.Fab")
		)
		(fp_line
			(start 0.12065 -0.3048)
			(end 0.67945 -0.3048)
			(stroke
				(width 0.1)
				(type default)
			)
			(layer "F.Fab")
		)
		(fp_line
			(start 0.120396 0.3048)
			(end 0.120396 0.2794)
			(stroke
				(width 0.1)
				(type default)
			)
			(layer "F.Fab")
		)
		(fp_line
			(start 0.120396 0.2794)
			(end -0.12065 0.2794)
			(stroke
				(width 0.1)
				(type default)
			)
			(layer "F.Fab")
		)
		(fp_line
			(start -0.12065 0.3048)
			(end -0.67945 0.3048)
			(stroke
				(width 0.1)
				(type default)
			)
			(layer "F.Fab")
		)
		(fp_line
			(start -0.12065 0.2794)
			(end -0.12065 0.3048)
			(stroke
				(width 0.1)
				(type default)
			)
			(layer "F.Fab")
		)
		(fp_line
			(start -0.12065 -0.2794)
			(end 0.12065 -0.2794)
			(stroke
				(width 0.1)
				(type default)
			)
			(layer "F.Fab")
		)
		(fp_line
			(start -0.12065 -0.305054)
			(end -0.12065 -0.2794)
			(stroke
				(width 0.1)
				(type default)
			)
			(layer "F.Fab")
		)
		(fp_line
			(start -0.67945 0.3048)
			(end -0.67945 -0.305054)
			(stroke
				(width 0.1)
				(type default)
			)
			(layer "F.Fab")
		)
		(fp_line
			(start -0.67945 -0.305054)
			(end -0.12065 -0.305054)
			(stroke
				(width 0.1)
				(type default)
			)
			(layer "F.Fab")
		)
		(pad "1" smd circle
			(at -0.40005 0 180)
			(size 0 0)
			(layers "F.Cu" "F.Mask" "F.Paste")
			(net "P3V3_SSD5")
		)
		(pad "2" smd circle
			(at 0.40005 0 180)
			(size 0 0)
			(layers "F.Cu" "F.Mask" "F.Paste")
			(net "GND")
		)
	)
	(footprint ""
		(layer "F.Cu")
		(at 260.038596 -311.156604 -90)
		(property "Reference" "R1330"
			(at 0 0 270)
			(layer "F.SilkS")
			(hide yes)
			(effects
				(font
					(size 1.27 1.27)
				)
			)
		)
		(property "Value" ""
			(at 0 0 270)
			(layer "F.Fab")
			(effects
				(font
					(size 1.27 1.27)
				)
			)
		)
		(duplicate_pad_numbers_are_jumpers no)
		(fp_line
			(start -0.7874 0.4064)
			(end -0.7874 -0.4064)
			(stroke
				(width 0.1524)
				(type default)
			)
			(layer "F.SilkS")
		)
		(fp_line
			(start 0.7874 0.4064)
			(end -0.7874 0.4064)
			(stroke
				(width 0.1524)
				(type default)
			)
			(layer "F.SilkS")
		)
		(fp_line
			(start -0.7874 -0.4064)
			(end 0.7874 -0.4064)
			(stroke
				(width 0.1524)
				(type default)
			)
			(layer "F.SilkS")
		)
		(fp_line
			(start 0.7874 -0.4064)
			(end 0.7874 0.4064)
			(stroke
				(width 0.1524)
				(type default)
			)
			(layer "F.SilkS")
		)
		(fp_line
			(start -0.67945 0.3048)
			(end -0.67945 -0.305054)
			(stroke
				(width 0.1)
				(type default)
			)
			(layer "F.Fab")
		)
		(fp_line
			(start -0.12065 0.3048)
			(end -0.67945 0.3048)
			(stroke
				(width 0.1)
				(type default)
			)
			(layer "F.Fab")
		)
		(fp_line
			(start 0.120396 0.3048)
			(end 0.120396 0.2794)
			(stroke
				(width 0.1)
				(type default)
			)
			(layer "F.Fab")
		)
		(fp_line
			(start 0.67945 0.3048)
			(end 0.120396 0.3048)
			(stroke
				(width 0.1)
				(type default)
			)
			(layer "F.Fab")
		)
		(fp_line
			(start -0.12065 0.2794)
			(end -0.12065 0.3048)
			(stroke
				(width 0.1)
				(type default)
			)
			(layer "F.Fab")
		)
		(fp_line
			(start 0.120396 0.2794)
			(end -0.12065 0.2794)
			(stroke
				(width 0.1)
				(type default)
			)
			(layer "F.Fab")
		)
		(fp_line
			(start -0.12065 -0.2794)
			(end 0.12065 -0.2794)
			(stroke
				(width 0.1)
				(type default)
			)
			(layer "F.Fab")
		)
		(fp_line
			(start 0.12065 -0.2794)
			(end 0.12065 -0.3048)
			(stroke
				(width 0.1)
				(type default)
			)
			(layer "F.Fab")
		)
		(fp_line
			(start 0.12065 -0.3048)
			(end 0.67945 -0.3048)
			(stroke
				(width 0.1)
				(type default)
			)
			(layer "F.Fab")
		)
		(fp_line
			(start 0.67945 -0.3048)
			(end 0.67945 0.3048)
			(stroke
				(width 0.1)
				(type default)
			)
			(layer "F.Fab")
		)
		(fp_line
			(start -0.67945 -0.305054)
			(end -0.12065 -0.305054)
			(stroke
				(width 0.1)
				(type default)
			)
			(layer "F.Fab")
		)
		(fp_line
			(start -0.12065 -0.305054)
			(end -0.12065 -0.2794)
			(stroke
				(width 0.1)
				(type default)
			)
			(layer "F.Fab")
		)
		(pad "1" smd circle
			(at -0.40005 0 270)
			(size 0 0)
			(layers "F.Cu" "F.Mask" "F.Paste")
			(net "PEX2_DBG_SEL1")
		)
		(pad "2" smd circle
			(at 0.40005 0 270)
			(size 0 0)
			(layers "F.Cu" "F.Mask" "F.Paste")
			(net "P1V8_PEX")
		)
	)
	(footprint ""
		(layer "F.Cu")
		(at 131.367276 -196.391784 -90)
		(property "Reference" "U441"
			(at -1.053338 2.649474 0)
			(unlocked yes)
			(layer "F.SilkS")
			(effects
				(font
					(size 0.7874 0.5842)
					(thickness 0.1524)
				)
			)
		)
		(property "Value" ""
			(at 0 0 270)
			(layer "F.Fab")
			(effects
				(font
					(size 1.27 1.27)
				)
			)
		)
		(duplicate_pad_numbers_are_jumpers no)
		(fp_line
			(start -1.7272 1.1176)
			(end -1.7272 -1.1176)
			(stroke
				(width 0.1524)
				(type default)
			)
			(layer "F.SilkS")
		)
		(fp_line
			(start 1.7272 1.1176)
			(end -1.7272 1.1176)
			(stroke
				(width 0.1524)
				(type default)
			)
			(layer "F.SilkS")
		)
		(fp_line
			(start 0 -0.7366)
			(end -0.254 -1.1176)
			(stroke
				(width 0.1524)
				(type default)
			)
			(layer "F.SilkS")
		)
		(fp_line
			(start -0.254 -1.1176)
			(end -1.7272 -1.1176)
			(stroke
				(width 0.1524)
				(type default)
			)
			(layer "F.SilkS")
		)
		(fp_line
			(start 0.254 -1.1176)
			(end 0 -0.7366)
			(stroke
				(width 0.1524)
				(type default)
			)
			(layer "F.SilkS")
		)
		(fp_line
			(start 1.7272 -1.1176)
			(end 1.7272 1.1176)
			(stroke
				(width 0.1524)
				(type default)
			)
			(layer "F.SilkS")
		)
		(fp_line
			(start 1.7272 -1.1176)
			(end 0.254 -1.1176)
			(stroke
				(width 0.1524)
				(type default)
			)
			(layer "F.SilkS")
		)
		(fp_poly
			(pts
				(xy -1.9558 -0.649986) (xy -2.7178 -0.268986) (xy -2.7178 -1.030986)
			)
			(stroke
				(width 0)
				(type default)
			)
			(fill yes)
			(layer "F.SilkS")
		)
		(fp_line
			(start -1.5748 1.1176)
			(end 1.5748 1.1176)
			(stroke
				(width 0.1)
				(type default)
			)
			(layer "F.Fab")
		)
		(fp_line
			(start 1.5748 1.1176)
			(end 1.5748 -1.1176)
			(stroke
				(width 0.1)
				(type default)
			)
			(layer "F.Fab")
		)
		(fp_line
			(start -1.5748 -1.1176)
			(end -1.5748 1.1176)
			(stroke
				(width 0.1)
				(type default)
			)
			(layer "F.Fab")
		)
		(fp_line
			(start 1.5748 -1.1176)
			(end -1.5748 -1.1176)
			(stroke
				(width 0.1)
				(type default)
			)
			(layer "F.Fab")
		)
		(fp_poly
			(pts
				(xy -1.9558 -0.649986) (xy -2.7178 -0.268986) (xy -2.7178 -1.030986)
			)
			(stroke
				(width 0)
				(type default)
			)
			(fill yes)
			(layer "F.Fab")
		)
		(pad "1" smd rect
			(at -0.999998 -0.649986 180)
			(size 0.3556 1.1176)
			(layers "F.Cu" "F.Mask" "F.Paste")
			(net "NIC6_CLK_EN_R_N")
		)
		(pad "2" smd rect
			(at -0.999998 0 180)
			(size 0.3556 1.1176)
			(layers "F.Cu" "F.Mask" "F.Paste")
			(net "GND")
		)
		(pad "3" smd rect
			(at -0.999998 0.649986 180)
			(size 0.3556 1.1176)
			(layers "F.Cu" "F.Mask" "F.Paste")
			(net "NIC7_CLK_EN_R_N")
		)
		(pad "4" smd rect
			(at 0.999998 0.649986 180)
			(size 0.3556 1.1176)
			(layers "F.Cu" "F.Mask" "F.Paste")
			(net "NIC7_CLK_EN_BUF_N")
		)
		(pad "5" smd rect
			(at 0.999998 0 180)
			(size 0.3556 1.1176)
			(layers "F.Cu" "F.Mask" "F.Paste")
			(net "P3V3_AUX")
		)
		(pad "6" smd rect
			(at 0.999998 -0.649986 180)
			(size 0.3556 1.1176)
			(layers "F.Cu" "F.Mask" "F.Paste")
			(net "NIC6_CLK_EN_BUF_N")
		)
	)
	(footprint ""
		(layer "F.Cu")
		(at 78.134464 -87.599012)
		(property "Reference" "U15"
			(at -1.8034 -1.819148 0)
			(unlocked yes)
			(layer "F.SilkS")
			(effects
				(font
					(size 0.7874 0.5842)
					(thickness 0.1524)
				)
				(justify left)
			)
		)
		(property "Value" ""
			(at 0 0 0)
			(layer "F.Fab")
			(effects
				(font
					(size 1.27 1.27)
				)
			)
		)
		(duplicate_pad_numbers_are_jumpers no)
		(fp_line
			(start -1.684274 -1.074928)
			(end -0.381 -1.074928)
			(stroke
				(width 0.1524)
				(type default)
			)
			(layer "F.SilkS")
		)
		(fp_line
			(start -1.684274 1.074928)
			(end -1.684274 -1.074928)
			(stroke
				(width 0.1524)
				(type default)
			)
			(layer "F.SilkS")
		)
		(fp_line
			(start -0.381 -1.074928)
			(end 0 -0.625094)
			(stroke
				(width 0.1524)
				(type default)
			)
			(layer "F.SilkS")
		)
		(fp_line
			(start 0 -0.625094)
			(end 0.381 -1.074928)
			(stroke
				(width 0.1524)
				(type default)
			)
			(layer "F.SilkS")
		)
		(fp_line
			(start 0.381 -1.074928)
			(end 1.684274 -1.074928)
			(stroke
				(width 0.1524)
				(type default)
			)
			(layer "F.SilkS")
		)
		(fp_line
			(start 1.684274 -1.074928)
			(end 1.684274 1.074928)
			(stroke
				(width 0.1524)
				(type default)
			)
			(layer "F.SilkS")
		)
		(fp_line
			(start 1.684274 1.074928)
			(end -1.684274 1.074928)
			(stroke
				(width 0.1524)
				(type default)
			)
			(layer "F.SilkS")
		)
		(fp_poly
			(pts
				(xy -2.637282 -0.903986) (xy -2.637282 -0.395986) (xy -1.875282 -0.649986)
			)
			(stroke
				(width 0)
				(type default)
			)
			(fill yes)
			(layer "F.SilkS")
		)
		(fp_line
			(start -0.700024 -1.074928)
			(end -0.700024 1.074928)
			(stroke
				(width 0.1)
				(type default)
			)
			(layer "F.Fab")
		)
		(fp_line
			(start -0.700024 1.074928)
			(end 0.700024 1.074928)
			(stroke
				(width 0.1)
				(type default)
			)
			(layer "F.Fab")
		)
		(fp_line
			(start 0.700024 -1.074928)
			(end -0.700024 -1.074928)
			(stroke
				(width 0.1)
				(type default)
			)
			(layer "F.Fab")
		)
		(fp_line
			(start 0.700024 1.074928)
			(end 0.700024 -1.074928)
			(stroke
				(width 0.1)
				(type default)
			)
			(layer "F.Fab")
		)
		(fp_poly
			(pts
				(xy -2.637282 -0.903986) (xy -2.637282 -0.395986) (xy -1.875282 -0.649986)
			)
			(stroke
				(width 0)
				(type default)
			)
			(fill yes)
			(layer "F.Fab")
		)
		(pad "1" smd rect
			(at -1.100074 -0.649986 270)
			(size 0.4064 0.9144)
			(layers "F.Cu" "F.Mask" "F.Paste")
			(net "Net_8455")
		)
		(pad "2" smd rect
			(at -1.100074 0 270)
			(size 0.4064 0.9144)
			(layers "F.Cu" "F.Mask" "F.Paste")
			(net "RST_HP_NIC1_N")
		)
		(pad "3" smd rect
			(at -1.100074 0.649986 270)
			(size 0.4064 0.9144)
			(layers "F.Cu" "F.Mask" "F.Paste")
			(net "GND")
		)
		(pad "4" smd rect
			(at 1.100074 0.649986 270)
			(size 0.4064 0.9144)
			(layers "F.Cu" "F.Mask" "F.Paste")
			(net "RST_HP_NIC1_BUF_N")
		)
		(pad "5" smd rect
			(at 1.100074 -0.649986 270)
			(size 0.4064 0.9144)
			(layers "F.Cu" "F.Mask" "F.Paste")
			(net "P3V3_AUX")
		)
	)
	(footprint ""
		(layer "F.Cu")
		(at 117.940328 -32.848042 90)
		(property "Reference" "PC925"
			(at 0 0 90)
			(layer "F.SilkS")
			(hide yes)
			(effects
				(font
					(size 1.27 1.27)
				)
			)
		)
		(property "Value" ""
			(at 0 0 90)
			(layer "F.Fab")
			(effects
				(font
					(size 1.27 1.27)
				)
			)
		)
		(duplicate_pad_numbers_are_jumpers no)
		(fp_line
			(start 0.7874 -0.4064)
			(end 0.7874 0.4064)
			(stroke
				(width 0.1524)
				(type default)
			)
			(layer "F.SilkS")
		)
		(fp_line
			(start -0.7874 -0.4064)
			(end 0.7874 -0.4064)
			(stroke
				(width 0.1524)
				(type default)
			)
			(layer "F.SilkS")
		)
		(fp_line
			(start 0.7874 0.4064)
			(end -0.7874 0.4064)
			(stroke
				(width 0.1524)
				(type default)
			)
			(layer "F.SilkS")
		)
		(fp_line
			(start -0.7874 0.4064)
			(end -0.7874 -0.4064)
			(stroke
				(width 0.1524)
				(type default)
			)
			(layer "F.SilkS")
		)
		(fp_line
			(start -0.12065 -0.305054)
			(end -0.12065 -0.2794)
			(stroke
				(width 0.1)
				(type default)
			)
			(layer "F.Fab")
		)
		(fp_line
			(start -0.67945 -0.305054)
			(end -0.12065 -0.305054)
			(stroke
				(width 0.1)
				(type default)
			)
			(layer "F.Fab")
		)
		(fp_line
			(start 0.67945 -0.3048)
			(end 0.67945 0.3048)
			(stroke
				(width 0.1)
				(type default)
			)
			(layer "F.Fab")
		)
		(fp_line
			(start 0.12065 -0.3048)
			(end 0.67945 -0.3048)
			(stroke
				(width 0.1)
				(type default)
			)
			(layer "F.Fab")
		)
		(fp_line
			(start 0.12065 -0.2794)
			(end 0.12065 -0.3048)
			(stroke
				(width 0.1)
				(type default)
			)
			(layer "F.Fab")
		)
		(fp_line
			(start -0.12065 -0.2794)
			(end 0.12065 -0.2794)
			(stroke
				(width 0.1)
				(type default)
			)
			(layer "F.Fab")
		)
		(fp_line
			(start 0.120396 0.2794)
			(end -0.12065 0.2794)
			(stroke
				(width 0.1)
				(type default)
			)
			(layer "F.Fab")
		)
		(fp_line
			(start -0.12065 0.2794)
			(end -0.12065 0.3048)
			(stroke
				(width 0.1)
				(type default)
			)
			(layer "F.Fab")
		)
		(fp_line
			(start 0.67945 0.3048)
			(end 0.120396 0.3048)
			(stroke
				(width 0.1)
				(type default)
			)
			(layer "F.Fab")
		)
		(fp_line
			(start 0.120396 0.3048)
			(end 0.120396 0.2794)
			(stroke
				(width 0.1)
				(type default)
			)
			(layer "F.Fab")
		)
		(fp_line
			(start -0.12065 0.3048)
			(end -0.67945 0.3048)
			(stroke
				(width 0.1)
				(type default)
			)
			(layer "F.Fab")
		)
		(fp_line
			(start -0.67945 0.3048)
			(end -0.67945 -0.305054)
			(stroke
				(width 0.1)
				(type default)
			)
			(layer "F.Fab")
		)
		(pad "1" smd circle
			(at -0.40005 0 90)
			(size 0 0)
			(layers "F.Cu" "F.Mask" "F.Paste")
			(net "P3V3_SSD4_CO_DV_DT")
		)
		(pad "2" smd circle
			(at 0.40005 0 90)
			(size 0 0)
			(layers "F.Cu" "F.Mask" "F.Paste")
			(net "GND")
		)
	)
	(footprint ""
		(layer "F.Cu")
		(at 336.467704 -55.083456)
		(property "Reference" "PC432"
			(at 0 0 0)
			(layer "F.SilkS")
			(hide yes)
			(effects
				(font
					(size 1.27 1.27)
				)
			)
		)
		(property "Value" ""
			(at 0 0 0)
			(layer "F.Fab")
			(effects
				(font
					(size 1.27 1.27)
				)
			)
		)
		(duplicate_pad_numbers_are_jumpers no)
		(fp_line
			(start -0.7874 -0.4064)
			(end 0.7874 -0.4064)
			(stroke
				(width 0.1524)
				(type default)
			)
			(layer "F.SilkS")
		)
		(fp_line
			(start -0.7874 0.4064)
			(end -0.7874 -0.4064)
			(stroke
				(width 0.1524)
				(type default)
			)
			(layer "F.SilkS")
		)
		(fp_line
			(start 0.7874 -0.4064)
			(end 0.7874 0.4064)
			(stroke
				(width 0.1524)
				(type default)
			)
			(layer "F.SilkS")
		)
		(fp_line
			(start 0.7874 0.4064)
			(end -0.7874 0.4064)
			(stroke
				(width 0.1524)
				(type default)
			)
			(layer "F.SilkS")
		)
		(fp_line
			(start -0.67945 -0.305054)
			(end -0.12065 -0.305054)
			(stroke
				(width 0.1)
				(type default)
			)
			(layer "F.Fab")
		)
		(fp_line
			(start -0.67945 0.3048)
			(end -0.67945 -0.305054)
			(stroke
				(width 0.1)
				(type default)
			)
			(layer "F.Fab")
		)
		(fp_line
			(start -0.12065 -0.305054)
			(end -0.12065 -0.2794)
			(stroke
				(width 0.1)
				(type default)
			)
			(layer "F.Fab")
		)
		(fp_line
			(start -0.12065 -0.2794)
			(end 0.12065 -0.2794)
			(stroke
				(width 0.1)
				(type default)
			)
			(layer "F.Fab")
		)
		(fp_line
			(start -0.12065 0.2794)
			(end -0.12065 0.3048)
			(stroke
				(width 0.1)
				(type default)
			)
			(layer "F.Fab")
		)
		(fp_line
			(start -0.12065 0.3048)
			(end -0.67945 0.3048)
			(stroke
				(width 0.1)
				(type default)
			)
			(layer "F.Fab")
		)
		(fp_line
			(start 0.120396 0.2794)
			(end -0.12065 0.2794)
			(stroke
				(width 0.1)
				(type default)
			)
			(layer "F.Fab")
		)
		(fp_line
			(start 0.120396 0.3048)
			(end 0.120396 0.2794)
			(stroke
				(width 0.1)
				(type default)
			)
			(layer "F.Fab")
		)
		(fp_line
			(start 0.12065 -0.3048)
			(end 0.67945 -0.3048)
			(stroke
				(width 0.1)
				(type default)
			)
			(layer "F.Fab")
		)
		(fp_line
			(start 0.12065 -0.2794)
			(end 0.12065 -0.3048)
			(stroke
				(width 0.1)
				(type default)
			)
			(layer "F.Fab")
		)
		(fp_line
			(start 0.67945 -0.3048)
			(end 0.67945 0.3048)
			(stroke
				(width 0.1)
				(type default)
			)
			(layer "F.Fab")
		)
		(fp_line
			(start 0.67945 0.3048)
			(end 0.120396 0.3048)
			(stroke
				(width 0.1)
				(type default)
			)
			(layer "F.Fab")
		)
		(pad "1" smd circle
			(at -0.40005 0)
			(size 0 0)
			(layers "F.Cu" "F.Mask" "F.Paste")
			(net "P5V_AUX")
		)
		(pad "2" smd circle
			(at 0.40005 0)
			(size 0 0)
			(layers "F.Cu" "F.Mask" "F.Paste")
			(net "GND")
		)
	)
	(footprint ""
		(layer "F.Cu")
		(at 331.175614 -121.509028)
		(property "Reference" "PR246"
			(at 0 0 0)
			(layer "F.SilkS")
			(hide yes)
			(effects
				(font
					(size 1.27 1.27)
				)
			)
		)
		(property "Value" ""
			(at 0 0 0)
			(layer "F.Fab")
			(effects
				(font
					(size 1.27 1.27)
				)
			)
		)
		(duplicate_pad_numbers_are_jumpers no)
		(fp_line
			(start -0.7874 -0.4064)
			(end 0.7874 -0.4064)
			(stroke
				(width 0.1524)
				(type default)
			)
			(layer "F.SilkS")
		)
		(fp_line
			(start -0.7874 0.4064)
			(end -0.7874 -0.4064)
			(stroke
				(width 0.1524)
				(type default)
			)
			(layer "F.SilkS")
		)
		(fp_line
			(start 0.7874 -0.4064)
			(end 0.7874 0.4064)
			(stroke
				(width 0.1524)
				(type default)
			)
			(layer "F.SilkS")
		)
		(fp_line
			(start 0.7874 0.4064)
			(end -0.7874 0.4064)
			(stroke
				(width 0.1524)
				(type default)
			)
			(layer "F.SilkS")
		)
		(fp_line
			(start -0.67945 -0.305054)
			(end -0.12065 -0.305054)
			(stroke
				(width 0.1)
				(type default)
			)
			(layer "F.Fab")
		)
		(fp_line
			(start -0.67945 0.3048)
			(end -0.67945 -0.305054)
			(stroke
				(width 0.1)
				(type default)
			)
			(layer "F.Fab")
		)
		(fp_line
			(start -0.12065 -0.305054)
			(end -0.12065 -0.2794)
			(stroke
				(width 0.1)
				(type default)
			)
			(layer "F.Fab")
		)
		(fp_line
			(start -0.12065 -0.2794)
			(end 0.12065 -0.2794)
			(stroke
				(width 0.1)
				(type default)
			)
			(layer "F.Fab")
		)
		(fp_line
			(start -0.12065 0.2794)
			(end -0.12065 0.3048)
			(stroke
				(width 0.1)
				(type default)
			)
			(layer "F.Fab")
		)
		(fp_line
			(start -0.12065 0.3048)
			(end -0.67945 0.3048)
			(stroke
				(width 0.1)
				(type default)
			)
			(layer "F.Fab")
		)
		(fp_line
			(start 0.120396 0.2794)
			(end -0.12065 0.2794)
			(stroke
				(width 0.1)
				(type default)
			)
			(layer "F.Fab")
		)
		(fp_line
			(start 0.120396 0.3048)
			(end 0.120396 0.2794)
			(stroke
				(width 0.1)
				(type default)
			)
			(layer "F.Fab")
		)
		(fp_line
			(start 0.12065 -0.3048)
			(end 0.67945 -0.3048)
			(stroke
				(width 0.1)
				(type default)
			)
			(layer "F.Fab")
		)
		(fp_line
			(start 0.12065 -0.2794)
			(end 0.12065 -0.3048)
			(stroke
				(width 0.1)
				(type default)
			)
			(layer "F.Fab")
		)
		(fp_line
			(start 0.67945 -0.3048)
			(end 0.67945 0.3048)
			(stroke
				(width 0.1)
				(type default)
			)
			(layer "F.Fab")
		)
		(fp_line
			(start 0.67945 0.3048)
			(end 0.120396 0.3048)
			(stroke
				(width 0.1)
				(type default)
			)
			(layer "F.Fab")
		)
		(pad "1" smd circle
			(at -0.40005 0)
			(size 0 0)
			(layers "F.Cu" "F.Mask" "F.Paste")
			(net "P3V3_NIC5_OCP")
		)
		(pad "2" smd circle
			(at 0.40005 0)
			(size 0 0)
			(layers "F.Cu" "F.Mask" "F.Paste")
			(net "GND")
		)
	)
	(footprint ""
		(layer "F.Cu")
		(at 250.922536 -44.341542 90)
		(property "Reference" "R602"
			(at 0 0 90)
			(layer "F.SilkS")
			(hide yes)
			(effects
				(font
					(size 1.27 1.27)
				)
			)
		)
		(property "Value" ""
			(at 0 0 90)
			(layer "F.Fab")
			(effects
				(font
					(size 1.27 1.27)
				)
			)
		)
		(duplicate_pad_numbers_are_jumpers no)
		(fp_line
			(start 0.7874 -0.4064)
			(end 0.7874 0.4064)
			(stroke
				(width 0.1524)
				(type default)
			)
			(layer "F.SilkS")
		)
		(fp_line
			(start -0.7874 -0.4064)
			(end 0.7874 -0.4064)
			(stroke
				(width 0.1524)
				(type default)
			)
			(layer "F.SilkS")
		)
		(fp_line
			(start 0.7874 0.4064)
			(end -0.7874 0.4064)
			(stroke
				(width 0.1524)
				(type default)
			)
			(layer "F.SilkS")
		)
		(fp_line
			(start -0.7874 0.4064)
			(end -0.7874 -0.4064)
			(stroke
				(width 0.1524)
				(type default)
			)
			(layer "F.SilkS")
		)
		(fp_line
			(start -0.12065 -0.305054)
			(end -0.12065 -0.2794)
			(stroke
				(width 0.1)
				(type default)
			)
			(layer "F.Fab")
		)
		(fp_line
			(start -0.67945 -0.305054)
			(end -0.12065 -0.305054)
			(stroke
				(width 0.1)
				(type default)
			)
			(layer "F.Fab")
		)
		(fp_line
			(start 0.67945 -0.3048)
			(end 0.67945 0.3048)
			(stroke
				(width 0.1)
				(type default)
			)
			(layer "F.Fab")
		)
		(fp_line
			(start 0.12065 -0.3048)
			(end 0.67945 -0.3048)
			(stroke
				(width 0.1)
				(type default)
			)
			(layer "F.Fab")
		)
		(fp_line
			(start 0.12065 -0.2794)
			(end 0.12065 -0.3048)
			(stroke
				(width 0.1)
				(type default)
			)
			(layer "F.Fab")
		)
		(fp_line
			(start -0.12065 -0.2794)
			(end 0.12065 -0.2794)
			(stroke
				(width 0.1)
				(type default)
			)
			(layer "F.Fab")
		)
		(fp_line
			(start 0.120396 0.2794)
			(end -0.12065 0.2794)
			(stroke
				(width 0.1)
				(type default)
			)
			(layer "F.Fab")
		)
		(fp_line
			(start -0.12065 0.2794)
			(end -0.12065 0.3048)
			(stroke
				(width 0.1)
				(type default)
			)
			(layer "F.Fab")
		)
		(fp_line
			(start 0.67945 0.3048)
			(end 0.120396 0.3048)
			(stroke
				(width 0.1)
				(type default)
			)
			(layer "F.Fab")
		)
		(fp_line
			(start 0.120396 0.3048)
			(end 0.120396 0.2794)
			(stroke
				(width 0.1)
				(type default)
			)
			(layer "F.Fab")
		)
		(fp_line
			(start -0.12065 0.3048)
			(end -0.67945 0.3048)
			(stroke
				(width 0.1)
				(type default)
			)
			(layer "F.Fab")
		)
		(fp_line
			(start -0.67945 0.3048)
			(end -0.67945 -0.305054)
			(stroke
				(width 0.1)
				(type default)
			)
			(layer "F.Fab")
		)
		(pad "1" smd circle
			(at -0.40005 0 90)
			(size 0 0)
			(layers "F.Cu" "F.Mask" "F.Paste")
			(net "P12V_SSD8")
		)
		(pad "2" smd circle
			(at 0.40005 0 90)
			(size 0 0)
			(layers "F.Cu" "F.Mask" "F.Paste")
			(net "P12V_SSD8_VIN_N")
		)
	)
	(footprint ""
		(layer "F.Cu")
		(at 58.995056 -102.798372 180)
		(property "Reference" "R70"
			(at 0 0 180)
			(layer "F.SilkS")
			(hide yes)
			(effects
				(font
					(size 1.27 1.27)
				)
			)
		)
		(property "Value" ""
			(at 0 0 180)
			(layer "F.Fab")
			(effects
				(font
					(size 1.27 1.27)
				)
			)
		)
		(duplicate_pad_numbers_are_jumpers no)
		(fp_line
			(start 0.7874 0.4064)
			(end -0.7874 0.4064)
			(stroke
				(width 0.1524)
				(type default)
			)
			(layer "F.SilkS")
		)
		(fp_line
			(start 0.7874 -0.4064)
			(end 0.7874 0.4064)
			(stroke
				(width 0.1524)
				(type default)
			)
			(layer "F.SilkS")
		)
		(fp_line
			(start -0.7874 0.4064)
			(end -0.7874 -0.4064)
			(stroke
				(width 0.1524)
				(type default)
			)
			(layer "F.SilkS")
		)
		(fp_line
			(start -0.7874 -0.4064)
			(end 0.7874 -0.4064)
			(stroke
				(width 0.1524)
				(type default)
			)
			(layer "F.SilkS")
		)
		(fp_line
			(start 0.67945 0.3048)
			(end 0.120396 0.3048)
			(stroke
				(width 0.1)
				(type default)
			)
			(layer "F.Fab")
		)
		(fp_line
			(start 0.67945 -0.3048)
			(end 0.67945 0.3048)
			(stroke
				(width 0.1)
				(type default)
			)
			(layer "F.Fab")
		)
		(fp_line
			(start 0.12065 -0.2794)
			(end 0.12065 -0.3048)
			(stroke
				(width 0.1)
				(type default)
			)
			(layer "F.Fab")
		)
		(fp_line
			(start 0.12065 -0.3048)
			(end 0.67945 -0.3048)
			(stroke
				(width 0.1)
				(type default)
			)
			(layer "F.Fab")
		)
		(fp_line
			(start 0.120396 0.3048)
			(end 0.120396 0.2794)
			(stroke
				(width 0.1)
				(type default)
			)
			(layer "F.Fab")
		)
		(fp_line
			(start 0.120396 0.2794)
			(end -0.12065 0.2794)
			(stroke
				(width 0.1)
				(type default)
			)
			(layer "F.Fab")
		)
		(fp_line
			(start -0.12065 0.3048)
			(end -0.67945 0.3048)
			(stroke
				(width 0.1)
				(type default)
			)
			(layer "F.Fab")
		)
		(fp_line
			(start -0.12065 0.2794)
			(end -0.12065 0.3048)
			(stroke
				(width 0.1)
				(type default)
			)
			(layer "F.Fab")
		)
		(fp_line
			(start -0.12065 -0.2794)
			(end 0.12065 -0.2794)
			(stroke
				(width 0.1)
				(type default)
			)
			(layer "F.Fab")
		)
		(fp_line
			(start -0.12065 -0.305054)
			(end -0.12065 -0.2794)
			(stroke
				(width 0.1)
				(type default)
			)
			(layer "F.Fab")
		)
		(fp_line
			(start -0.67945 0.3048)
			(end -0.67945 -0.305054)
			(stroke
				(width 0.1)
				(type default)
			)
			(layer "F.Fab")
		)
		(fp_line
			(start -0.67945 -0.305054)
			(end -0.12065 -0.305054)
			(stroke
				(width 0.1)
				(type default)
			)
			(layer "F.Fab")
		)
		(pad "1" smd circle
			(at -0.40005 0 180)
			(size 0 0)
			(layers "F.Cu" "F.Mask" "F.Paste")
			(net "NCSI_NIC1_TXD1")
		)
		(pad "2" smd circle
			(at 0.40005 0 180)
			(size 0 0)
			(layers "F.Cu" "F.Mask" "F.Paste")
			(net "GND")
		)
	)
	(footprint ""
		(layer "F.Cu")
		(at 352.920554 -90.645234 180)
		(property "Reference" "R1608"
			(at 0 0 180)
			(layer "F.SilkS")
			(hide yes)
			(effects
				(font
					(size 1.27 1.27)
				)
			)
		)
		(property "Value" ""
			(at 0 0 180)
			(layer "F.Fab")
			(effects
				(font
					(size 1.27 1.27)
				)
			)
		)
		(duplicate_pad_numbers_are_jumpers no)
		(fp_line
			(start 0.7874 0.4064)
			(end -0.7874 0.4064)
			(stroke
				(width 0.1524)
				(type default)
			)
			(layer "F.SilkS")
		)
		(fp_line
			(start 0.7874 -0.4064)
			(end 0.7874 0.4064)
			(stroke
				(width 0.1524)
				(type default)
			)
			(layer "F.SilkS")
		)
		(fp_line
			(start -0.7874 0.4064)
			(end -0.7874 -0.4064)
			(stroke
				(width 0.1524)
				(type default)
			)
			(layer "F.SilkS")
		)
		(fp_line
			(start -0.7874 -0.4064)
			(end 0.7874 -0.4064)
			(stroke
				(width 0.1524)
				(type default)
			)
			(layer "F.SilkS")
		)
		(fp_line
			(start 0.67945 0.3048)
			(end 0.120396 0.3048)
			(stroke
				(width 0.1)
				(type default)
			)
			(layer "F.Fab")
		)
		(fp_line
			(start 0.67945 -0.3048)
			(end 0.67945 0.3048)
			(stroke
				(width 0.1)
				(type default)
			)
			(layer "F.Fab")
		)
		(fp_line
			(start 0.12065 -0.2794)
			(end 0.12065 -0.3048)
			(stroke
				(width 0.1)
				(type default)
			)
			(layer "F.Fab")
		)
		(fp_line
			(start 0.12065 -0.3048)
			(end 0.67945 -0.3048)
			(stroke
				(width 0.1)
				(type default)
			)
			(layer "F.Fab")
		)
		(fp_line
			(start 0.120396 0.3048)
			(end 0.120396 0.2794)
			(stroke
				(width 0.1)
				(type default)
			)
			(layer "F.Fab")
		)
		(fp_line
			(start 0.120396 0.2794)
			(end -0.12065 0.2794)
			(stroke
				(width 0.1)
				(type default)
			)
			(layer "F.Fab")
		)
		(fp_line
			(start -0.12065 0.3048)
			(end -0.67945 0.3048)
			(stroke
				(width 0.1)
				(type default)
			)
			(layer "F.Fab")
		)
		(fp_line
			(start -0.12065 0.2794)
			(end -0.12065 0.3048)
			(stroke
				(width 0.1)
				(type default)
			)
			(layer "F.Fab")
		)
		(fp_line
			(start -0.12065 -0.2794)
			(end 0.12065 -0.2794)
			(stroke
				(width 0.1)
				(type default)
			)
			(layer "F.Fab")
		)
		(fp_line
			(start -0.12065 -0.305054)
			(end -0.12065 -0.2794)
			(stroke
				(width 0.1)
				(type default)
			)
			(layer "F.Fab")
		)
		(fp_line
			(start -0.67945 0.3048)
			(end -0.67945 -0.305054)
			(stroke
				(width 0.1)
				(type default)
			)
			(layer "F.Fab")
		)
		(fp_line
			(start -0.67945 -0.305054)
			(end -0.12065 -0.305054)
			(stroke
				(width 0.1)
				(type default)
			)
			(layer "F.Fab")
		)
		(pad "1" smd circle
			(at -0.40005 0 180)
			(size 0 0)
			(layers "F.Cu" "F.Mask" "F.Paste")
			(net "BIC_I2C9_SSD_MUX1_A1")
		)
		(pad "2" smd circle
			(at 0.40005 0 180)
			(size 0 0)
			(layers "F.Cu" "F.Mask" "F.Paste")
			(net "GND")
		)
	)
	(footprint ""
		(layer "F.Cu")
		(at 63.525908 -165.670484 -90)
		(property "Reference" "R3305"
			(at 0 0 270)
			(layer "F.SilkS")
			(hide yes)
			(effects
				(font
					(size 1.27 1.27)
				)
			)
		)
		(property "Value" ""
			(at 0 0 270)
			(layer "F.Fab")
			(effects
				(font
					(size 1.27 1.27)
				)
			)
		)
		(duplicate_pad_numbers_are_jumpers no)
		(fp_line
			(start -0.7874 0.4064)
			(end -0.7874 -0.4064)
			(stroke
				(width 0.1524)
				(type default)
			)
			(layer "F.SilkS")
		)
		(fp_line
			(start 0.7874 0.4064)
			(end -0.7874 0.4064)
			(stroke
				(width 0.1524)
				(type default)
			)
			(layer "F.SilkS")
		)
		(fp_line
			(start -0.7874 -0.4064)
			(end 0.7874 -0.4064)
			(stroke
				(width 0.1524)
				(type default)
			)
			(layer "F.SilkS")
		)
		(fp_line
			(start 0.7874 -0.4064)
			(end 0.7874 0.4064)
			(stroke
				(width 0.1524)
				(type default)
			)
			(layer "F.SilkS")
		)
		(fp_line
			(start -0.67945 0.3048)
			(end -0.67945 -0.305054)
			(stroke
				(width 0.1)
				(type default)
			)
			(layer "F.Fab")
		)
		(fp_line
			(start -0.12065 0.3048)
			(end -0.67945 0.3048)
			(stroke
				(width 0.1)
				(type default)
			)
			(layer "F.Fab")
		)
		(fp_line
			(start 0.120396 0.3048)
			(end 0.120396 0.2794)
			(stroke
				(width 0.1)
				(type default)
			)
			(layer "F.Fab")
		)
		(fp_line
			(start 0.67945 0.3048)
			(end 0.120396 0.3048)
			(stroke
				(width 0.1)
				(type default)
			)
			(layer "F.Fab")
		)
		(fp_line
			(start -0.12065 0.2794)
			(end -0.12065 0.3048)
			(stroke
				(width 0.1)
				(type default)
			)
			(layer "F.Fab")
		)
		(fp_line
			(start 0.120396 0.2794)
			(end -0.12065 0.2794)
			(stroke
				(width 0.1)
				(type default)
			)
			(layer "F.Fab")
		)
		(fp_line
			(start -0.12065 -0.2794)
			(end 0.12065 -0.2794)
			(stroke
				(width 0.1)
				(type default)
			)
			(layer "F.Fab")
		)
		(fp_line
			(start 0.12065 -0.2794)
			(end 0.12065 -0.3048)
			(stroke
				(width 0.1)
				(type default)
			)
			(layer "F.Fab")
		)
		(fp_line
			(start 0.12065 -0.3048)
			(end 0.67945 -0.3048)
			(stroke
				(width 0.1)
				(type default)
			)
			(layer "F.Fab")
		)
		(fp_line
			(start 0.67945 -0.3048)
			(end 0.67945 0.3048)
			(stroke
				(width 0.1)
				(type default)
			)
			(layer "F.Fab")
		)
		(fp_line
			(start -0.67945 -0.305054)
			(end -0.12065 -0.305054)
			(stroke
				(width 0.1)
				(type default)
			)
			(layer "F.Fab")
		)
		(fp_line
			(start -0.12065 -0.305054)
			(end -0.12065 -0.2794)
			(stroke
				(width 0.1)
				(type default)
			)
			(layer "F.Fab")
		)
		(pad "1" smd circle
			(at -0.40005 0 270)
			(size 0 0)
			(layers "F.Cu" "F.Mask" "F.Paste")
			(net "FM_SYS_THROTTLE_R")
		)
		(pad "2" smd circle
			(at 0.40005 0 270)
			(size 0 0)
			(layers "F.Cu" "F.Mask" "F.Paste")
			(net "FM_SYS_THROTTLE_NIC1")
		)
	)
	(footprint ""
		(layer "F.Cu")
		(at 112.751108 -350.098614 90)
		(property "Reference" "C357"
			(at 0 0 90)
			(layer "F.SilkS")
			(hide yes)
			(effects
				(font
					(size 1.27 1.27)
				)
			)
		)
		(property "Value" ""
			(at 0 0 90)
			(layer "F.Fab")
			(effects
				(font
					(size 1.27 1.27)
				)
			)
		)
		(duplicate_pad_numbers_are_jumpers no)
		(fp_line
			(start 0.299974 -0.150114)
			(end 0.299974 0.150114)
			(stroke
				(width 0.1)
				(type default)
			)
			(layer "F.Fab")
		)
		(fp_line
			(start -0.299974 -0.150114)
			(end 0.299974 -0.150114)
			(stroke
				(width 0.1)
				(type default)
			)
			(layer "F.Fab")
		)
		(fp_line
			(start 0.299974 0.150114)
			(end -0.299974 0.150114)
			(stroke
				(width 0.1)
				(type default)
			)
			(layer "F.Fab")
		)
		(fp_line
			(start -0.299974 0.150114)
			(end -0.299974 -0.150114)
			(stroke
				(width 0.1)
				(type default)
			)
			(layer "F.Fab")
		)
		(pad "1" smd rect
			(at -0.2667 0 90)
			(size 0.3048 0.381)
			(layers "F.Cu" "F.Mask" "F.Paste")
			(net "P5E_PEX1_STN6_TX_DN<103>")
		)
		(pad "2" smd rect
			(at 0.2667 0 90)
			(size 0.3048 0.381)
			(layers "F.Cu" "F.Mask" "F.Paste")
			(net "P5E_PEX1_STN6_TX_C_DN<103>")
		)
	)
	(footprint ""
		(layer "F.Cu")
		(at 335.752948 -80.607662 90)
		(property "Reference" "R1171"
			(at 0 0 90)
			(layer "F.SilkS")
			(hide yes)
			(effects
				(font
					(size 1.27 1.27)
				)
			)
		)
		(property "Value" ""
			(at 0 0 90)
			(layer "F.Fab")
			(effects
				(font
					(size 1.27 1.27)
				)
			)
		)
		(duplicate_pad_numbers_are_jumpers no)
		(fp_line
			(start 0.7874 0.4064)
			(end -0.7874 0.4064)
			(stroke
				(width 0.1524)
				(type default)
			)
			(layer "F.SilkS")
		)
		(fp_line
			(start -0.12065 -0.305054)
			(end -0.12065 -0.2794)
			(stroke
				(width 0.1)
				(type default)
			)
			(layer "F.Fab")
		)
		(fp_line
			(start -0.67945 -0.305054)
			(end -0.12065 -0.305054)
			(stroke
				(width 0.1)
				(type default)
			)
			(layer "F.Fab")
		)
		(fp_line
			(start 0.67945 -0.3048)
			(end 0.67945 0.3048)
			(stroke
				(width 0.1)
				(type default)
			)
			(layer "F.Fab")
		)
		(fp_line
			(start 0.12065 -0.3048)
			(end 0.67945 -0.3048)
			(stroke
				(width 0.1)
				(type default)
			)
			(layer "F.Fab")
		)
		(fp_line
			(start 0.12065 -0.2794)
			(end 0.12065 -0.3048)
			(stroke
				(width 0.1)
				(type default)
			)
			(layer "F.Fab")
		)
		(fp_line
			(start -0.12065 -0.2794)
			(end 0.12065 -0.2794)
			(stroke
				(width 0.1)
				(type default)
			)
			(layer "F.Fab")
		)
		(fp_line
			(start 0.120396 0.2794)
			(end -0.12065 0.2794)
			(stroke
				(width 0.1)
				(type default)
			)
			(layer "F.Fab")
		)
		(fp_line
			(start -0.12065 0.2794)
			(end -0.12065 0.3048)
			(stroke
				(width 0.1)
				(type default)
			)
			(layer "F.Fab")
		)
		(fp_line
			(start 0.67945 0.3048)
			(end 0.120396 0.3048)
			(stroke
				(width 0.1)
				(type default)
			)
			(layer "F.Fab")
		)
		(fp_line
			(start 0.120396 0.3048)
			(end 0.120396 0.2794)
			(stroke
				(width 0.1)
				(type default)
			)
			(layer "F.Fab")
		)
		(fp_line
			(start -0.12065 0.3048)
			(end -0.67945 0.3048)
			(stroke
				(width 0.1)
				(type default)
			)
			(layer "F.Fab")
		)
		(fp_line
			(start -0.67945 0.3048)
			(end -0.67945 -0.305054)
			(stroke
				(width 0.1)
				(type default)
			)
			(layer "F.Fab")
		)
		(pad "1" smd circle
			(at -0.40005 0 90)
			(size 0 0)
			(layers "F.Cu" "F.Mask" "F.Paste")
			(net "CLK_100M_DB800ZL_SSD8_R_DN")
		)
		(pad "2" smd circle
			(at 0.40005 0 90)
			(size 0 0)
			(layers "F.Cu" "F.Mask" "F.Paste")
			(net "CLK_100M_DB800ZL_SSD8_DN")
		)
	)
	(footprint ""
		(layer "F.Cu")
		(at 74.697082 -343.952322 90)
		(property "Reference" "C140"
			(at 0 0 90)
			(layer "F.SilkS")
			(hide yes)
			(effects
				(font
					(size 1.27 1.27)
				)
			)
		)
		(property "Value" ""
			(at 0 0 90)
			(layer "F.Fab")
			(effects
				(font
					(size 1.27 1.27)
				)
			)
		)
		(duplicate_pad_numbers_are_jumpers no)
		(fp_line
			(start 0.299974 -0.150114)
			(end 0.299974 0.150114)
			(stroke
				(width 0.1)
				(type default)
			)
			(layer "F.Fab")
		)
		(fp_line
			(start -0.299974 -0.150114)
			(end 0.299974 -0.150114)
			(stroke
				(width 0.1)
				(type default)
			)
			(layer "F.Fab")
		)
		(fp_line
			(start 0.299974 0.150114)
			(end -0.299974 0.150114)
			(stroke
				(width 0.1)
				(type default)
			)
			(layer "F.Fab")
		)
		(fp_line
			(start -0.299974 0.150114)
			(end -0.299974 -0.150114)
			(stroke
				(width 0.1)
				(type default)
			)
			(layer "F.Fab")
		)
		(pad "1" smd rect
			(at -0.2667 0 90)
			(size 0.3048 0.381)
			(layers "F.Cu" "F.Mask" "F.Paste")
			(net "P5E_PEX0_STN6_TX_DN<106>")
		)
		(pad "2" smd rect
			(at 0.2667 0 90)
			(size 0.3048 0.381)
			(layers "F.Cu" "F.Mask" "F.Paste")
			(net "P5E_PEX0_STN6_TX_C_DN<106>")
		)
	)
	(footprint ""
		(layer "F.Cu")
		(at 258.538218 -378.393706 -90)
		(property "Reference" "PR6603"
			(at 0 0 270)
			(layer "F.SilkS")
			(hide yes)
			(effects
				(font
					(size 1.27 1.27)
				)
			)
		)
		(property "Value" ""
			(at 0 0 270)
			(layer "F.Fab")
			(effects
				(font
					(size 1.27 1.27)
				)
			)
		)
		(duplicate_pad_numbers_are_jumpers no)
		(fp_line
			(start -3.9878 3.5814)
			(end -3.9878 -3.5814)
			(stroke
				(width 0.1524)
				(type default)
			)
			(layer "F.SilkS")
		)
		(fp_line
			(start 3.9878 3.5814)
			(end -3.9878 3.5814)
			(stroke
				(width 0.1524)
				(type default)
			)
			(layer "F.SilkS")
		)
		(fp_line
			(start -3.9878 -3.5814)
			(end 3.9878 -3.5814)
			(stroke
				(width 0.1524)
				(type default)
			)
			(layer "F.SilkS")
		)
		(fp_line
			(start 3.9878 -3.5814)
			(end 3.9878 3.5814)
			(stroke
				(width 0.1524)
				(type default)
			)
			(layer "F.SilkS")
		)
		(fp_line
			(start -3.5306 3.353054)
			(end -3.5306 -3.353054)
			(stroke
				(width 0.1)
				(type default)
			)
			(layer "F.Fab")
		)
		(fp_line
			(start 3.5306 3.353054)
			(end -3.5306 3.353054)
			(stroke
				(width 0.1)
				(type default)
			)
			(layer "F.Fab")
		)
		(fp_line
			(start -3.5306 -3.353054)
			(end 3.5306 -3.353054)
			(stroke
				(width 0.1)
				(type default)
			)
			(layer "F.Fab")
		)
		(fp_line
			(start 3.5306 -3.353054)
			(end 3.5306 3.353054)
			(stroke
				(width 0.1)
				(type default)
			)
			(layer "F.Fab")
		)
		(pad "1A" smd rect
			(at -2.249932 0 90)
			(size 3.2004 6.858)
			(layers "F.Cu" "F.Mask" "F.Paste")
			(net "P12V_STBY")
		)
		(pad "1B" smd rect
			(at -0.776732 0 270)
			(size 0.254 0.508)
			(layers "F.Cu" "F.Mask" "F.Paste")
			(net "P12V_HSC_SENSE2_R2_P")
		)
		(pad "2A" smd rect
			(at 2.249932 0 90)
			(size 3.2004 6.858)
			(layers "F.Cu" "F.Mask" "F.Paste")
			(net "P12V_STBY_R2")
		)
		(pad "2B" smd rect
			(at 0.776732 0 270)
			(size 0.254 0.508)
			(layers "F.Cu" "F.Mask" "F.Paste")
			(net "P12V_HSC_SENSE2_R2_N")
		)
	)
	(footprint ""
		(layer "F.Cu")
		(at 393.669266 -83.785202 180)
		(property "Reference" "R1772"
			(at 0 0 180)
			(layer "F.SilkS")
			(hide yes)
			(effects
				(font
					(size 1.27 1.27)
				)
			)
		)
		(property "Value" ""
			(at 0 0 180)
			(layer "F.Fab")
			(effects
				(font
					(size 1.27 1.27)
				)
			)
		)
		(duplicate_pad_numbers_are_jumpers no)
		(fp_line
			(start 0.7874 0.4064)
			(end -0.7874 0.4064)
			(stroke
				(width 0.1524)
				(type default)
			)
			(layer "F.SilkS")
		)
		(fp_line
			(start 0.7874 -0.4064)
			(end 0.7874 0.4064)
			(stroke
				(width 0.1524)
				(type default)
			)
			(layer "F.SilkS")
		)
		(fp_line
			(start -0.7874 0.4064)
			(end -0.7874 -0.4064)
			(stroke
				(width 0.1524)
				(type default)
			)
			(layer "F.SilkS")
		)
		(fp_line
			(start -0.7874 -0.4064)
			(end 0.7874 -0.4064)
			(stroke
				(width 0.1524)
				(type default)
			)
			(layer "F.SilkS")
		)
		(fp_line
			(start 0.67945 0.3048)
			(end 0.120396 0.3048)
			(stroke
				(width 0.1)
				(type default)
			)
			(layer "F.Fab")
		)
		(fp_line
			(start 0.67945 -0.3048)
			(end 0.67945 0.3048)
			(stroke
				(width 0.1)
				(type default)
			)
			(layer "F.Fab")
		)
		(fp_line
			(start 0.12065 -0.2794)
			(end 0.12065 -0.3048)
			(stroke
				(width 0.1)
				(type default)
			)
			(layer "F.Fab")
		)
		(fp_line
			(start 0.12065 -0.3048)
			(end 0.67945 -0.3048)
			(stroke
				(width 0.1)
				(type default)
			)
			(layer "F.Fab")
		)
		(fp_line
			(start 0.120396 0.3048)
			(end 0.120396 0.2794)
			(stroke
				(width 0.1)
				(type default)
			)
			(layer "F.Fab")
		)
		(fp_line
			(start 0.120396 0.2794)
			(end -0.12065 0.2794)
			(stroke
				(width 0.1)
				(type default)
			)
			(layer "F.Fab")
		)
		(fp_line
			(start -0.12065 0.3048)
			(end -0.67945 0.3048)
			(stroke
				(width 0.1)
				(type default)
			)
			(layer "F.Fab")
		)
		(fp_line
			(start -0.12065 0.2794)
			(end -0.12065 0.3048)
			(stroke
				(width 0.1)
				(type default)
			)
			(layer "F.Fab")
		)
		(fp_line
			(start -0.12065 -0.2794)
			(end 0.12065 -0.2794)
			(stroke
				(width 0.1)
				(type default)
			)
			(layer "F.Fab")
		)
		(fp_line
			(start -0.12065 -0.305054)
			(end -0.12065 -0.2794)
			(stroke
				(width 0.1)
				(type default)
			)
			(layer "F.Fab")
		)
		(fp_line
			(start -0.67945 0.3048)
			(end -0.67945 -0.305054)
			(stroke
				(width 0.1)
				(type default)
			)
			(layer "F.Fab")
		)
		(fp_line
			(start -0.67945 -0.305054)
			(end -0.12065 -0.305054)
			(stroke
				(width 0.1)
				(type default)
			)
			(layer "F.Fab")
		)
		(pad "1" smd circle
			(at -0.40005 0 180)
			(size 0 0)
			(layers "F.Cu" "F.Mask" "F.Paste")
			(net "SMB_BIC_I2C6_MUX_CLK_R_SCL")
		)
		(pad "2" smd circle
			(at 0.40005 0 180)
			(size 0 0)
			(layers "F.Cu" "F.Mask" "F.Paste")
			(net "SMB_BIC_I2C6_MUX_CLK_SCL")
		)
	)
	(footprint ""
		(layer "F.Cu")
		(at 184.837832 -350.098614 90)
		(property "Reference" "C381"
			(at 0 0 90)
			(layer "F.SilkS")
			(hide yes)
			(effects
				(font
					(size 1.27 1.27)
				)
			)
		)
		(property "Value" ""
			(at 0 0 90)
			(layer "F.Fab")
			(effects
				(font
					(size 1.27 1.27)
				)
			)
		)
		(duplicate_pad_numbers_are_jumpers no)
		(fp_line
			(start 0.299974 -0.150114)
			(end 0.299974 0.150114)
			(stroke
				(width 0.1)
				(type default)
			)
			(layer "F.Fab")
		)
		(fp_line
			(start -0.299974 -0.150114)
			(end 0.299974 -0.150114)
			(stroke
				(width 0.1)
				(type default)
			)
			(layer "F.Fab")
		)
		(fp_line
			(start 0.299974 0.150114)
			(end -0.299974 0.150114)
			(stroke
				(width 0.1)
				(type default)
			)
			(layer "F.Fab")
		)
		(fp_line
			(start -0.299974 0.150114)
			(end -0.299974 -0.150114)
			(stroke
				(width 0.1)
				(type default)
			)
			(layer "F.Fab")
		)
		(pad "1" smd rect
			(at -0.2667 0 90)
			(size 0.3048 0.381)
			(layers "F.Cu" "F.Mask" "F.Paste")
			(net "P5E_PEX1_STN7_TX_DN<123>")
		)
		(pad "2" smd rect
			(at 0.2667 0 90)
			(size 0.3048 0.381)
			(layers "F.Cu" "F.Mask" "F.Paste")
			(net "P5E_PEX1_STN7_TX_C_DN<123>")
		)
	)
	(footprint ""
		(layer "F.Cu")
		(at 23.330408 -350.098614 90)
		(property "Reference" "C2155"
			(at 0 0 90)
			(layer "F.SilkS")
			(hide yes)
			(effects
				(font
					(size 1.27 1.27)
				)
			)
		)
		(property "Value" ""
			(at 0 0 90)
			(layer "F.Fab")
			(effects
				(font
					(size 1.27 1.27)
				)
			)
		)
		(duplicate_pad_numbers_are_jumpers no)
		(fp_line
			(start 0.299974 -0.150114)
			(end 0.299974 0.150114)
			(stroke
				(width 0.1)
				(type default)
			)
			(layer "F.Fab")
		)
		(fp_line
			(start -0.299974 -0.150114)
			(end 0.299974 -0.150114)
			(stroke
				(width 0.1)
				(type default)
			)
			(layer "F.Fab")
		)
		(fp_line
			(start 0.299974 0.150114)
			(end -0.299974 0.150114)
			(stroke
				(width 0.1)
				(type default)
			)
			(layer "F.Fab")
		)
		(fp_line
			(start -0.299974 0.150114)
			(end -0.299974 -0.150114)
			(stroke
				(width 0.1)
				(type default)
			)
			(layer "F.Fab")
		)
		(pad "1" smd rect
			(at -0.2667 0 90)
			(size 0.3048 0.381)
			(layers "F.Cu" "F.Mask" "F.Paste")
			(net "P5E_PEX0_STN4_TX_DN<78>")
		)
		(pad "2" smd rect
			(at 0.2667 0 90)
			(size 0.3048 0.381)
			(layers "F.Cu" "F.Mask" "F.Paste")
			(net "P5E_PEX0_STN4_TX_C_DN<78>")
		)
	)
	(footprint ""
		(layer "F.Cu")
		(at 9.62914 -315.26607 180)
		(property "Reference" "PC1007"
			(at 0 0 180)
			(layer "F.SilkS")
			(hide yes)
			(effects
				(font
					(size 1.27 1.27)
				)
			)
		)
		(property "Value" ""
			(at 0 0 180)
			(layer "F.Fab")
			(effects
				(font
					(size 1.27 1.27)
				)
			)
		)
		(duplicate_pad_numbers_are_jumpers no)
		(fp_line
			(start 1.524 0.762)
			(end -1.524 0.762)
			(stroke
				(width 0.1524)
				(type default)
			)
			(layer "F.SilkS")
		)
		(fp_line
			(start 1.524 -0.762)
			(end 1.524 0.762)
			(stroke
				(width 0.1524)
				(type default)
			)
			(layer "F.SilkS")
		)
		(fp_line
			(start -1.524 0.762)
			(end -1.524 -0.762)
			(stroke
				(width 0.1524)
				(type default)
			)
			(layer "F.SilkS")
		)
		(fp_line
			(start -1.524 -0.762)
			(end 1.524 -0.762)
			(stroke
				(width 0.1524)
				(type default)
			)
			(layer "F.SilkS")
		)
		(fp_line
			(start 1.1049 0.724916)
			(end 1.1049 -0.724916)
			(stroke
				(width 0.1)
				(type default)
			)
			(layer "F.Fab")
		)
		(fp_line
			(start 1.1049 -0.724916)
			(end -1.1049 -0.724916)
			(stroke
				(width 0.1)
				(type default)
			)
			(layer "F.Fab")
		)
		(fp_line
			(start -1.1049 0.724916)
			(end 1.1049 0.724916)
			(stroke
				(width 0.1)
				(type default)
			)
			(layer "F.Fab")
		)
		(fp_line
			(start -1.1049 -0.724916)
			(end -1.1049 0.724916)
			(stroke
				(width 0.1)
				(type default)
			)
			(layer "F.Fab")
		)
		(pad "1" smd rect
			(at -0.889 0)
			(size 1.016 1.27)
			(layers "F.Cu" "F.Mask" "F.Paste")
			(net "SW_P12V_P1V25_PEX0_FLT")
		)
		(pad "2" smd rect
			(at 0.889 0)
			(size 1.016 1.27)
			(layers "F.Cu" "F.Mask" "F.Paste")
			(net "GND")
		)
	)
	(footprint ""
		(layer "F.Cu")
		(at 174.80915 -26.03373)
		(property "Reference" "R4064"
			(at 0 0 0)
			(layer "F.SilkS")
			(hide yes)
			(effects
				(font
					(size 1.27 1.27)
				)
			)
		)
		(property "Value" ""
			(at 0 0 0)
			(layer "F.Fab")
			(effects
				(font
					(size 1.27 1.27)
				)
			)
		)
		(duplicate_pad_numbers_are_jumpers no)
		(fp_line
			(start -0.7874 -0.4064)
			(end 0.7874 -0.4064)
			(stroke
				(width 0.1524)
				(type default)
			)
			(layer "F.SilkS")
		)
		(fp_line
			(start -0.7874 0.4064)
			(end -0.7874 -0.4064)
			(stroke
				(width 0.1524)
				(type default)
			)
			(layer "F.SilkS")
		)
		(fp_line
			(start 0.7874 -0.4064)
			(end 0.7874 0.4064)
			(stroke
				(width 0.1524)
				(type default)
			)
			(layer "F.SilkS")
		)
		(fp_line
			(start 0.7874 0.4064)
			(end -0.7874 0.4064)
			(stroke
				(width 0.1524)
				(type default)
			)
			(layer "F.SilkS")
		)
		(fp_line
			(start -0.67945 -0.305054)
			(end -0.12065 -0.305054)
			(stroke
				(width 0.1)
				(type default)
			)
			(layer "F.Fab")
		)
		(fp_line
			(start -0.67945 0.3048)
			(end -0.67945 -0.305054)
			(stroke
				(width 0.1)
				(type default)
			)
			(layer "F.Fab")
		)
		(fp_line
			(start -0.12065 -0.305054)
			(end -0.12065 -0.2794)
			(stroke
				(width 0.1)
				(type default)
			)
			(layer "F.Fab")
		)
		(fp_line
			(start -0.12065 -0.2794)
			(end 0.12065 -0.2794)
			(stroke
				(width 0.1)
				(type default)
			)
			(layer "F.Fab")
		)
		(fp_line
			(start -0.12065 0.2794)
			(end -0.12065 0.3048)
			(stroke
				(width 0.1)
				(type default)
			)
			(layer "F.Fab")
		)
		(fp_line
			(start -0.12065 0.3048)
			(end -0.67945 0.3048)
			(stroke
				(width 0.1)
				(type default)
			)
			(layer "F.Fab")
		)
		(fp_line
			(start 0.120396 0.2794)
			(end -0.12065 0.2794)
			(stroke
				(width 0.1)
				(type default)
			)
			(layer "F.Fab")
		)
		(fp_line
			(start 0.120396 0.3048)
			(end 0.120396 0.2794)
			(stroke
				(width 0.1)
				(type default)
			)
			(layer "F.Fab")
		)
		(fp_line
			(start 0.12065 -0.3048)
			(end 0.67945 -0.3048)
			(stroke
				(width 0.1)
				(type default)
			)
			(layer "F.Fab")
		)
		(fp_line
			(start 0.12065 -0.2794)
			(end 0.12065 -0.3048)
			(stroke
				(width 0.1)
				(type default)
			)
			(layer "F.Fab")
		)
		(fp_line
			(start 0.67945 -0.3048)
			(end 0.67945 0.3048)
			(stroke
				(width 0.1)
				(type default)
			)
			(layer "F.Fab")
		)
		(fp_line
			(start 0.67945 0.3048)
			(end 0.120396 0.3048)
			(stroke
				(width 0.1)
				(type default)
			)
			(layer "F.Fab")
		)
		(pad "1" smd circle
			(at -0.40005 0)
			(size 0 0)
			(layers "F.Cu" "F.Mask" "F.Paste")
			(net "P3V3_AUX")
		)
		(pad "2" smd circle
			(at 0.40005 0)
			(size 0 0)
			(layers "F.Cu" "F.Mask" "F.Paste")
			(net "PRSNT_SSD6_R_N")
		)
	)
	(footprint ""
		(layer "F.Cu")
		(at 234.460288 -97.258378 90)
		(property "Reference" "R5439"
			(at 0 0 90)
			(layer "F.SilkS")
			(hide yes)
			(effects
				(font
					(size 1.27 1.27)
				)
			)
		)
		(property "Value" ""
			(at 0 0 90)
			(layer "F.Fab")
			(effects
				(font
					(size 1.27 1.27)
				)
			)
		)
		(duplicate_pad_numbers_are_jumpers no)
		(fp_line
			(start 0.7874 -0.4064)
			(end 0.7874 0.4064)
			(stroke
				(width 0.1524)
				(type default)
			)
			(layer "F.SilkS")
		)
		(fp_line
			(start -0.7874 -0.4064)
			(end 0.7874 -0.4064)
			(stroke
				(width 0.1524)
				(type default)
			)
			(layer "F.SilkS")
		)
		(fp_line
			(start 0.7874 0.4064)
			(end -0.7874 0.4064)
			(stroke
				(width 0.1524)
				(type default)
			)
			(layer "F.SilkS")
		)
		(fp_line
			(start -0.7874 0.4064)
			(end -0.7874 -0.4064)
			(stroke
				(width 0.1524)
				(type default)
			)
			(layer "F.SilkS")
		)
		(fp_line
			(start -0.12065 -0.305054)
			(end -0.12065 -0.2794)
			(stroke
				(width 0.1)
				(type default)
			)
			(layer "F.Fab")
		)
		(fp_line
			(start -0.67945 -0.305054)
			(end -0.12065 -0.305054)
			(stroke
				(width 0.1)
				(type default)
			)
			(layer "F.Fab")
		)
		(fp_line
			(start 0.67945 -0.3048)
			(end 0.67945 0.3048)
			(stroke
				(width 0.1)
				(type default)
			)
			(layer "F.Fab")
		)
		(fp_line
			(start 0.12065 -0.3048)
			(end 0.67945 -0.3048)
			(stroke
				(width 0.1)
				(type default)
			)
			(layer "F.Fab")
		)
		(fp_line
			(start 0.12065 -0.2794)
			(end 0.12065 -0.3048)
			(stroke
				(width 0.1)
				(type default)
			)
			(layer "F.Fab")
		)
		(fp_line
			(start -0.12065 -0.2794)
			(end 0.12065 -0.2794)
			(stroke
				(width 0.1)
				(type default)
			)
			(layer "F.Fab")
		)
		(fp_line
			(start 0.120396 0.2794)
			(end -0.12065 0.2794)
			(stroke
				(width 0.1)
				(type default)
			)
			(layer "F.Fab")
		)
		(fp_line
			(start -0.12065 0.2794)
			(end -0.12065 0.3048)
			(stroke
				(width 0.1)
				(type default)
			)
			(layer "F.Fab")
		)
		(fp_line
			(start 0.67945 0.3048)
			(end 0.120396 0.3048)
			(stroke
				(width 0.1)
				(type default)
			)
			(layer "F.Fab")
		)
		(fp_line
			(start 0.120396 0.3048)
			(end 0.120396 0.2794)
			(stroke
				(width 0.1)
				(type default)
			)
			(layer "F.Fab")
		)
		(fp_line
			(start -0.12065 0.3048)
			(end -0.67945 0.3048)
			(stroke
				(width 0.1)
				(type default)
			)
			(layer "F.Fab")
		)
		(fp_line
			(start -0.67945 0.3048)
			(end -0.67945 -0.305054)
			(stroke
				(width 0.1)
				(type default)
			)
			(layer "F.Fab")
		)
		(pad "1" smd circle
			(at -0.40005 0 90)
			(size 0 0)
			(layers "F.Cu" "F.Mask" "F.Paste")
			(net "RST_PEX_USB_HUB_R_N")
		)
		(pad "2" smd circle
			(at 0.40005 0 90)
			(size 0 0)
			(layers "F.Cu" "F.Mask" "F.Paste")
			(net "GND")
		)
	)
	(footprint ""
		(layer "F.Cu")
		(at 293.49319 -213.523068 -90)
		(property "Reference" "R3397"
			(at 0 0 270)
			(layer "F.SilkS")
			(hide yes)
			(effects
				(font
					(size 1.27 1.27)
				)
			)
		)
		(property "Value" ""
			(at 0 0 270)
			(layer "F.Fab")
			(effects
				(font
					(size 1.27 1.27)
				)
			)
		)
		(duplicate_pad_numbers_are_jumpers no)
		(fp_line
			(start -0.7874 0.4064)
			(end -0.7874 -0.4064)
			(stroke
				(width 0.1524)
				(type default)
			)
			(layer "F.SilkS")
		)
		(fp_line
			(start 0.7874 0.4064)
			(end -0.7874 0.4064)
			(stroke
				(width 0.1524)
				(type default)
			)
			(layer "F.SilkS")
		)
		(fp_line
			(start -0.7874 -0.4064)
			(end 0.7874 -0.4064)
			(stroke
				(width 0.1524)
				(type default)
			)
			(layer "F.SilkS")
		)
		(fp_line
			(start 0.7874 -0.4064)
			(end 0.7874 0.4064)
			(stroke
				(width 0.1524)
				(type default)
			)
			(layer "F.SilkS")
		)
		(fp_line
			(start -0.67945 0.3048)
			(end -0.67945 -0.305054)
			(stroke
				(width 0.1)
				(type default)
			)
			(layer "F.Fab")
		)
		(fp_line
			(start -0.12065 0.3048)
			(end -0.67945 0.3048)
			(stroke
				(width 0.1)
				(type default)
			)
			(layer "F.Fab")
		)
		(fp_line
			(start 0.120396 0.3048)
			(end 0.120396 0.2794)
			(stroke
				(width 0.1)
				(type default)
			)
			(layer "F.Fab")
		)
		(fp_line
			(start 0.67945 0.3048)
			(end 0.120396 0.3048)
			(stroke
				(width 0.1)
				(type default)
			)
			(layer "F.Fab")
		)
		(fp_line
			(start -0.12065 0.2794)
			(end -0.12065 0.3048)
			(stroke
				(width 0.1)
				(type default)
			)
			(layer "F.Fab")
		)
		(fp_line
			(start 0.120396 0.2794)
			(end -0.12065 0.2794)
			(stroke
				(width 0.1)
				(type default)
			)
			(layer "F.Fab")
		)
		(fp_line
			(start -0.12065 -0.2794)
			(end 0.12065 -0.2794)
			(stroke
				(width 0.1)
				(type default)
			)
			(layer "F.Fab")
		)
		(fp_line
			(start 0.12065 -0.2794)
			(end 0.12065 -0.3048)
			(stroke
				(width 0.1)
				(type default)
			)
			(layer "F.Fab")
		)
		(fp_line
			(start 0.12065 -0.3048)
			(end 0.67945 -0.3048)
			(stroke
				(width 0.1)
				(type default)
			)
			(layer "F.Fab")
		)
		(fp_line
			(start 0.67945 -0.3048)
			(end 0.67945 0.3048)
			(stroke
				(width 0.1)
				(type default)
			)
			(layer "F.Fab")
		)
		(fp_line
			(start -0.67945 -0.305054)
			(end -0.12065 -0.305054)
			(stroke
				(width 0.1)
				(type default)
			)
			(layer "F.Fab")
		)
		(fp_line
			(start -0.12065 -0.305054)
			(end -0.12065 -0.2794)
			(stroke
				(width 0.1)
				(type default)
			)
			(layer "F.Fab")
		)
		(pad "1" smd circle
			(at -0.40005 0 270)
			(size 0 0)
			(layers "F.Cu" "F.Mask" "F.Paste")
			(net "SPI_BIC1_MISO_LS23_R1")
		)
		(pad "2" smd circle
			(at 0.40005 0 270)
			(size 0 0)
			(layers "F.Cu" "F.Mask" "F.Paste")
			(net "SPI_BIC1_MISO_LS23_R")
		)
	)
	(footprint ""
		(layer "F.Cu")
		(at 152.738328 -130.408934)
		(property "Reference" "C250"
			(at 0 0 0)
			(layer "F.SilkS")
			(hide yes)
			(effects
				(font
					(size 1.27 1.27)
				)
			)
		)
		(property "Value" ""
			(at 0 0 0)
			(layer "F.Fab")
			(effects
				(font
					(size 1.27 1.27)
				)
			)
		)
		(duplicate_pad_numbers_are_jumpers no)
		(fp_line
			(start -0.299974 -0.150114)
			(end 0.299974 -0.150114)
			(stroke
				(width 0.1)
				(type default)
			)
			(layer "F.Fab")
		)
		(fp_line
			(start -0.299974 0.150114)
			(end -0.299974 -0.150114)
			(stroke
				(width 0.1)
				(type default)
			)
			(layer "F.Fab")
		)
		(fp_line
			(start 0.299974 -0.150114)
			(end 0.299974 0.150114)
			(stroke
				(width 0.1)
				(type default)
			)
			(layer "F.Fab")
		)
		(fp_line
			(start 0.299974 0.150114)
			(end -0.299974 0.150114)
			(stroke
				(width 0.1)
				(type default)
			)
			(layer "F.Fab")
		)
		(pad "1" smd rect
			(at -0.2667 0)
			(size 0.3048 0.381)
			(layers "F.Cu" "F.Mask" "F.Paste")
			(net "P5E_PEX1_STN1_TX_DP<28>")
		)
		(pad "2" smd rect
			(at 0.2667 0)
			(size 0.3048 0.381)
			(layers "F.Cu" "F.Mask" "F.Paste")
			(net "P5E_PEX1_STN1_TX_C_DP<28>")
		)
	)
	(footprint ""
		(layer "F.Cu")
		(at 56.034686 -370.421662 180)
		(property "Reference" "C3986"
			(at 0 0 180)
			(layer "F.SilkS")
			(hide yes)
			(effects
				(font
					(size 1.27 1.27)
				)
			)
		)
		(property "Value" ""
			(at 0 0 180)
			(layer "F.Fab")
			(effects
				(font
					(size 1.27 1.27)
				)
			)
		)
		(duplicate_pad_numbers_are_jumpers no)
		(fp_line
			(start 0.299974 0.150114)
			(end -0.299974 0.150114)
			(stroke
				(width 0.1)
				(type default)
			)
			(layer "F.Fab")
		)
		(fp_line
			(start 0.299974 -0.150114)
			(end 0.299974 0.150114)
			(stroke
				(width 0.1)
				(type default)
			)
			(layer "F.Fab")
		)
		(fp_line
			(start -0.299974 0.150114)
			(end -0.299974 -0.150114)
			(stroke
				(width 0.1)
				(type default)
			)
			(layer "F.Fab")
		)
		(fp_line
			(start -0.299974 -0.150114)
			(end 0.299974 -0.150114)
			(stroke
				(width 0.1)
				(type default)
			)
			(layer "F.Fab")
		)
		(pad "1" smd rect
			(at -0.2667 0 180)
			(size 0.3048 0.381)
			(layers "F.Cu" "F.Mask" "F.Paste")
			(net "P4E_PEX0_STN3_TX_DP<48>")
		)
		(pad "2" smd rect
			(at 0.2667 0 180)
			(size 0.3048 0.381)
			(layers "F.Cu" "F.Mask" "F.Paste")
			(net "P4E_PEX0_STN3_TX_C_DP<48>")
		)
	)
	(footprint ""
		(layer "F.Cu")
		(at 362.291376 -280.44902 -90)
		(property "Reference" "PR161"
			(at 0 0 270)
			(layer "F.SilkS")
			(hide yes)
			(effects
				(font
					(size 1.27 1.27)
				)
			)
		)
		(property "Value" ""
			(at 0 0 270)
			(layer "F.Fab")
			(effects
				(font
					(size 1.27 1.27)
				)
			)
		)
		(duplicate_pad_numbers_are_jumpers no)
		(fp_line
			(start -0.7874 0.4064)
			(end -0.7874 -0.4064)
			(stroke
				(width 0.1524)
				(type default)
			)
			(layer "F.SilkS")
		)
		(fp_line
			(start 0.7874 0.4064)
			(end -0.7874 0.4064)
			(stroke
				(width 0.1524)
				(type default)
			)
			(layer "F.SilkS")
		)
		(fp_line
			(start -0.7874 -0.4064)
			(end 0.7874 -0.4064)
			(stroke
				(width 0.1524)
				(type default)
			)
			(layer "F.SilkS")
		)
		(fp_line
			(start 0.7874 -0.4064)
			(end 0.7874 0.4064)
			(stroke
				(width 0.1524)
				(type default)
			)
			(layer "F.SilkS")
		)
		(fp_line
			(start -0.67945 0.3048)
			(end -0.67945 -0.305054)
			(stroke
				(width 0.1)
				(type default)
			)
			(layer "F.Fab")
		)
		(fp_line
			(start -0.12065 0.3048)
			(end -0.67945 0.3048)
			(stroke
				(width 0.1)
				(type default)
			)
			(layer "F.Fab")
		)
		(fp_line
			(start 0.120396 0.3048)
			(end 0.120396 0.2794)
			(stroke
				(width 0.1)
				(type default)
			)
			(layer "F.Fab")
		)
		(fp_line
			(start 0.67945 0.3048)
			(end 0.120396 0.3048)
			(stroke
				(width 0.1)
				(type default)
			)
			(layer "F.Fab")
		)
		(fp_line
			(start -0.12065 0.2794)
			(end -0.12065 0.3048)
			(stroke
				(width 0.1)
				(type default)
			)
			(layer "F.Fab")
		)
		(fp_line
			(start 0.120396 0.2794)
			(end -0.12065 0.2794)
			(stroke
				(width 0.1)
				(type default)
			)
			(layer "F.Fab")
		)
		(fp_line
			(start -0.12065 -0.2794)
			(end 0.12065 -0.2794)
			(stroke
				(width 0.1)
				(type default)
			)
			(layer "F.Fab")
		)
		(fp_line
			(start 0.12065 -0.2794)
			(end 0.12065 -0.3048)
			(stroke
				(width 0.1)
				(type default)
			)
			(layer "F.Fab")
		)
		(fp_line
			(start 0.12065 -0.3048)
			(end 0.67945 -0.3048)
			(stroke
				(width 0.1)
				(type default)
			)
			(layer "F.Fab")
		)
		(fp_line
			(start 0.67945 -0.3048)
			(end 0.67945 0.3048)
			(stroke
				(width 0.1)
				(type default)
			)
			(layer "F.Fab")
		)
		(fp_line
			(start -0.67945 -0.305054)
			(end -0.12065 -0.305054)
			(stroke
				(width 0.1)
				(type default)
			)
			(layer "F.Fab")
		)
		(fp_line
			(start -0.12065 -0.305054)
			(end -0.12065 -0.2794)
			(stroke
				(width 0.1)
				(type default)
			)
			(layer "F.Fab")
		)
		(pad "1" smd circle
			(at -0.40005 0 270)
			(size 0 0)
			(layers "F.Cu" "F.Mask" "F.Paste")
			(net "SW_P0V8_PEX3_BOOT2")
		)
		(pad "2" smd circle
			(at 0.40005 0 270)
			(size 0 0)
			(layers "F.Cu" "F.Mask" "F.Paste")
			(net "SW_P0V8_PEX3_BOOT2_R")
		)
	)
	(footprint ""
		(layer "F.Cu")
		(at 336.515456 -279.101804)
		(property "Reference" "PC138"
			(at 0 0 0)
			(layer "F.SilkS")
			(hide yes)
			(effects
				(font
					(size 1.27 1.27)
				)
			)
		)
		(property "Value" ""
			(at 0 0 0)
			(layer "F.Fab")
			(effects
				(font
					(size 1.27 1.27)
				)
			)
		)
		(duplicate_pad_numbers_are_jumpers no)
		(fp_line
			(start -0.7874 -0.4064)
			(end 0.7874 -0.4064)
			(stroke
				(width 0.1524)
				(type default)
			)
			(layer "F.SilkS")
		)
		(fp_line
			(start -0.7874 0.4064)
			(end -0.7874 -0.4064)
			(stroke
				(width 0.1524)
				(type default)
			)
			(layer "F.SilkS")
		)
		(fp_line
			(start 0.7874 -0.4064)
			(end 0.7874 0.4064)
			(stroke
				(width 0.1524)
				(type default)
			)
			(layer "F.SilkS")
		)
		(fp_line
			(start 0.7874 0.4064)
			(end -0.7874 0.4064)
			(stroke
				(width 0.1524)
				(type default)
			)
			(layer "F.SilkS")
		)
		(fp_line
			(start -0.67945 -0.305054)
			(end -0.12065 -0.305054)
			(stroke
				(width 0.1)
				(type default)
			)
			(layer "F.Fab")
		)
		(fp_line
			(start -0.67945 0.3048)
			(end -0.67945 -0.305054)
			(stroke
				(width 0.1)
				(type default)
			)
			(layer "F.Fab")
		)
		(fp_line
			(start -0.12065 -0.305054)
			(end -0.12065 -0.2794)
			(stroke
				(width 0.1)
				(type default)
			)
			(layer "F.Fab")
		)
		(fp_line
			(start -0.12065 -0.2794)
			(end 0.12065 -0.2794)
			(stroke
				(width 0.1)
				(type default)
			)
			(layer "F.Fab")
		)
		(fp_line
			(start -0.12065 0.2794)
			(end -0.12065 0.3048)
			(stroke
				(width 0.1)
				(type default)
			)
			(layer "F.Fab")
		)
		(fp_line
			(start -0.12065 0.3048)
			(end -0.67945 0.3048)
			(stroke
				(width 0.1)
				(type default)
			)
			(layer "F.Fab")
		)
		(fp_line
			(start 0.120396 0.2794)
			(end -0.12065 0.2794)
			(stroke
				(width 0.1)
				(type default)
			)
			(layer "F.Fab")
		)
		(fp_line
			(start 0.120396 0.3048)
			(end 0.120396 0.2794)
			(stroke
				(width 0.1)
				(type default)
			)
			(layer "F.Fab")
		)
		(fp_line
			(start 0.12065 -0.3048)
			(end 0.67945 -0.3048)
			(stroke
				(width 0.1)
				(type default)
			)
			(layer "F.Fab")
		)
		(fp_line
			(start 0.12065 -0.2794)
			(end 0.12065 -0.3048)
			(stroke
				(width 0.1)
				(type default)
			)
			(layer "F.Fab")
		)
		(fp_line
			(start 0.67945 -0.3048)
			(end 0.67945 0.3048)
			(stroke
				(width 0.1)
				(type default)
			)
			(layer "F.Fab")
		)
		(fp_line
			(start 0.67945 0.3048)
			(end 0.120396 0.3048)
			(stroke
				(width 0.1)
				(type default)
			)
			(layer "F.Fab")
		)
		(pad "1" smd circle
			(at -0.40005 0)
			(size 0 0)
			(layers "F.Cu" "F.Mask" "F.Paste")
			(net "SW_P12V_P0V8_PEX2_FLT")
		)
		(pad "2" smd circle
			(at 0.40005 0)
			(size 0 0)
			(layers "F.Cu" "F.Mask" "F.Paste")
			(net "GND")
		)
	)
	(footprint ""
		(layer "F.Cu")
		(at 446.787524 -25.342342 -90)
		(property "Reference" "R455"
			(at 0 0 270)
			(layer "F.SilkS")
			(hide yes)
			(effects
				(font
					(size 1.27 1.27)
				)
			)
		)
		(property "Value" ""
			(at 0 0 270)
			(layer "F.Fab")
			(effects
				(font
					(size 1.27 1.27)
				)
			)
		)
		(duplicate_pad_numbers_are_jumpers no)
		(fp_line
			(start -0.7874 0.4064)
			(end -0.7874 -0.4064)
			(stroke
				(width 0.1524)
				(type default)
			)
			(layer "F.SilkS")
		)
		(fp_line
			(start 0.7874 0.4064)
			(end -0.7874 0.4064)
			(stroke
				(width 0.1524)
				(type default)
			)
			(layer "F.SilkS")
		)
		(fp_line
			(start -0.7874 -0.4064)
			(end 0.7874 -0.4064)
			(stroke
				(width 0.1524)
				(type default)
			)
			(layer "F.SilkS")
		)
		(fp_line
			(start 0.7874 -0.4064)
			(end 0.7874 0.4064)
			(stroke
				(width 0.1524)
				(type default)
			)
			(layer "F.SilkS")
		)
		(fp_line
			(start -0.67945 0.3048)
			(end -0.67945 -0.305054)
			(stroke
				(width 0.1)
				(type default)
			)
			(layer "F.Fab")
		)
		(fp_line
			(start -0.12065 0.3048)
			(end -0.67945 0.3048)
			(stroke
				(width 0.1)
				(type default)
			)
			(layer "F.Fab")
		)
		(fp_line
			(start 0.120396 0.3048)
			(end 0.120396 0.2794)
			(stroke
				(width 0.1)
				(type default)
			)
			(layer "F.Fab")
		)
		(fp_line
			(start 0.67945 0.3048)
			(end 0.120396 0.3048)
			(stroke
				(width 0.1)
				(type default)
			)
			(layer "F.Fab")
		)
		(fp_line
			(start -0.12065 0.2794)
			(end -0.12065 0.3048)
			(stroke
				(width 0.1)
				(type default)
			)
			(layer "F.Fab")
		)
		(fp_line
			(start 0.120396 0.2794)
			(end -0.12065 0.2794)
			(stroke
				(width 0.1)
				(type default)
			)
			(layer "F.Fab")
		)
		(fp_line
			(start -0.12065 -0.2794)
			(end 0.12065 -0.2794)
			(stroke
				(width 0.1)
				(type default)
			)
			(layer "F.Fab")
		)
		(fp_line
			(start 0.12065 -0.2794)
			(end 0.12065 -0.3048)
			(stroke
				(width 0.1)
				(type default)
			)
			(layer "F.Fab")
		)
		(fp_line
			(start 0.12065 -0.3048)
			(end 0.67945 -0.3048)
			(stroke
				(width 0.1)
				(type default)
			)
			(layer "F.Fab")
		)
		(fp_line
			(start 0.67945 -0.3048)
			(end 0.67945 0.3048)
			(stroke
				(width 0.1)
				(type default)
			)
			(layer "F.Fab")
		)
		(fp_line
			(start -0.67945 -0.305054)
			(end -0.12065 -0.305054)
			(stroke
				(width 0.1)
				(type default)
			)
			(layer "F.Fab")
		)
		(fp_line
			(start -0.12065 -0.305054)
			(end -0.12065 -0.2794)
			(stroke
				(width 0.1)
				(type default)
			)
			(layer "F.Fab")
		)
		(pad "1" smd circle
			(at -0.40005 0 270)
			(size 0 0)
			(layers "F.Cu" "F.Mask" "F.Paste")
			(net "GND")
		)
		(pad "2" smd circle
			(at 0.40005 0 270)
			(size 0 0)
			(layers "F.Cu" "F.Mask" "F.Paste")
			(net "DUALPORT_N_SSD15")
		)
	)
	(footprint ""
		(layer "F.Cu")
		(at 421.705532 -356.244906 90)
		(property "Reference" "C812"
			(at 0 0 90)
			(layer "F.SilkS")
			(hide yes)
			(effects
				(font
					(size 1.27 1.27)
				)
			)
		)
		(property "Value" ""
			(at 0 0 90)
			(layer "F.Fab")
			(effects
				(font
					(size 1.27 1.27)
				)
			)
		)
		(duplicate_pad_numbers_are_jumpers no)
		(fp_line
			(start 0.299974 -0.150114)
			(end 0.299974 0.150114)
			(stroke
				(width 0.1)
				(type default)
			)
			(layer "F.Fab")
		)
		(fp_line
			(start -0.299974 -0.150114)
			(end 0.299974 -0.150114)
			(stroke
				(width 0.1)
				(type default)
			)
			(layer "F.Fab")
		)
		(fp_line
			(start 0.299974 0.150114)
			(end -0.299974 0.150114)
			(stroke
				(width 0.1)
				(type default)
			)
			(layer "F.Fab")
		)
		(fp_line
			(start -0.299974 0.150114)
			(end -0.299974 -0.150114)
			(stroke
				(width 0.1)
				(type default)
			)
			(layer "F.Fab")
		)
		(pad "1" smd rect
			(at -0.2667 0 90)
			(size 0.3048 0.381)
			(layers "F.Cu" "F.Mask" "F.Paste")
			(net "P5E_PEX3_STN7_TX_DP<118>")
		)
		(pad "2" smd rect
			(at 0.2667 0 90)
			(size 0.3048 0.381)
			(layers "F.Cu" "F.Mask" "F.Paste")
			(net "P5E_PEX3_STN7_TX_C_DP<118>")
		)
	)
	(footprint ""
		(layer "F.Cu")
		(at 154.699716 -154.327352 180)
		(property "Reference" "R128"
			(at 0 0 180)
			(layer "F.SilkS")
			(hide yes)
			(effects
				(font
					(size 1.27 1.27)
				)
			)
		)
		(property "Value" ""
			(at 0 0 180)
			(layer "F.Fab")
			(effects
				(font
					(size 1.27 1.27)
				)
			)
		)
		(duplicate_pad_numbers_are_jumpers no)
		(fp_line
			(start 0.7874 0.4064)
			(end -0.7874 0.4064)
			(stroke
				(width 0.1524)
				(type default)
			)
			(layer "F.SilkS")
		)
		(fp_line
			(start 0.7874 -0.4064)
			(end 0.7874 0.4064)
			(stroke
				(width 0.1524)
				(type default)
			)
			(layer "F.SilkS")
		)
		(fp_line
			(start -0.7874 0.4064)
			(end -0.7874 -0.4064)
			(stroke
				(width 0.1524)
				(type default)
			)
			(layer "F.SilkS")
		)
		(fp_line
			(start -0.7874 -0.4064)
			(end 0.7874 -0.4064)
			(stroke
				(width 0.1524)
				(type default)
			)
			(layer "F.SilkS")
		)
		(fp_line
			(start 0.67945 0.3048)
			(end 0.120396 0.3048)
			(stroke
				(width 0.1)
				(type default)
			)
			(layer "F.Fab")
		)
		(fp_line
			(start 0.67945 -0.3048)
			(end 0.67945 0.3048)
			(stroke
				(width 0.1)
				(type default)
			)
			(layer "F.Fab")
		)
		(fp_line
			(start 0.12065 -0.2794)
			(end 0.12065 -0.3048)
			(stroke
				(width 0.1)
				(type default)
			)
			(layer "F.Fab")
		)
		(fp_line
			(start 0.12065 -0.3048)
			(end 0.67945 -0.3048)
			(stroke
				(width 0.1)
				(type default)
			)
			(layer "F.Fab")
		)
		(fp_line
			(start 0.120396 0.3048)
			(end 0.120396 0.2794)
			(stroke
				(width 0.1)
				(type default)
			)
			(layer "F.Fab")
		)
		(fp_line
			(start 0.120396 0.2794)
			(end -0.12065 0.2794)
			(stroke
				(width 0.1)
				(type default)
			)
			(layer "F.Fab")
		)
		(fp_line
			(start -0.12065 0.3048)
			(end -0.67945 0.3048)
			(stroke
				(width 0.1)
				(type default)
			)
			(layer "F.Fab")
		)
		(fp_line
			(start -0.12065 0.2794)
			(end -0.12065 0.3048)
			(stroke
				(width 0.1)
				(type default)
			)
			(layer "F.Fab")
		)
		(fp_line
			(start -0.12065 -0.2794)
			(end 0.12065 -0.2794)
			(stroke
				(width 0.1)
				(type default)
			)
			(layer "F.Fab")
		)
		(fp_line
			(start -0.12065 -0.305054)
			(end -0.12065 -0.2794)
			(stroke
				(width 0.1)
				(type default)
			)
			(layer "F.Fab")
		)
		(fp_line
			(start -0.67945 0.3048)
			(end -0.67945 -0.305054)
			(stroke
				(width 0.1)
				(type default)
			)
			(layer "F.Fab")
		)
		(fp_line
			(start -0.67945 -0.305054)
			(end -0.12065 -0.305054)
			(stroke
				(width 0.1)
				(type default)
			)
			(layer "F.Fab")
		)
		(pad "1" smd circle
			(at -0.40005 0 180)
			(size 0 0)
			(layers "F.Cu" "F.Mask" "F.Paste")
			(net "NIC2_SLOT_ID0")
		)
		(pad "2" smd circle
			(at 0.40005 0 180)
			(size 0 0)
			(layers "F.Cu" "F.Mask" "F.Paste")
			(net "GND")
		)
	)
	(footprint ""
		(layer "F.Cu")
		(at 381.340106 -256.634234 180)
		(property "Reference" "C3572"
			(at 0 0 180)
			(layer "F.SilkS")
			(hide yes)
			(effects
				(font
					(size 1.27 1.27)
				)
			)
		)
		(property "Value" ""
			(at 0 0 180)
			(layer "F.Fab")
			(effects
				(font
					(size 1.27 1.27)
				)
			)
		)
		(duplicate_pad_numbers_are_jumpers no)
		(fp_line
			(start 1.2954 0.5842)
			(end -1.2954 0.5842)
			(stroke
				(width 0.1524)
				(type default)
			)
			(layer "F.SilkS")
		)
		(fp_line
			(start 1.2954 -0.5842)
			(end 1.2954 0.5842)
			(stroke
				(width 0.1524)
				(type default)
			)
			(layer "F.SilkS")
		)
		(fp_line
			(start -1.2954 0.5842)
			(end -1.2954 -0.5842)
			(stroke
				(width 0.1524)
				(type default)
			)
			(layer "F.SilkS")
		)
		(fp_line
			(start -1.2954 -0.5842)
			(end 1.2954 -0.5842)
			(stroke
				(width 0.1524)
				(type default)
			)
			(layer "F.SilkS")
		)
		(fp_line
			(start 1.1938 0.4064)
			(end 0.8636 0.4064)
			(stroke
				(width 0.1)
				(type default)
			)
			(layer "F.Fab")
		)
		(fp_line
			(start 1.1938 -0.4064)
			(end 1.1938 0.4064)
			(stroke
				(width 0.1)
				(type default)
			)
			(layer "F.Fab")
		)
		(fp_line
			(start 0.8636 0.4572)
			(end -0.8636 0.4572)
			(stroke
				(width 0.1)
				(type default)
			)
			(layer "F.Fab")
		)
		(fp_line
			(start 0.8636 0.4064)
			(end 0.8636 0.4572)
			(stroke
				(width 0.1)
				(type default)
			)
			(layer "F.Fab")
		)
		(fp_line
			(start 0.8636 -0.4064)
			(end 1.1938 -0.4064)
			(stroke
				(width 0.1)
				(type default)
			)
			(layer "F.Fab")
		)
		(fp_line
			(start 0.8636 -0.4572)
			(end 0.8636 -0.4064)
			(stroke
				(width 0.1)
				(type default)
			)
			(layer "F.Fab")
		)
		(fp_line
			(start -0.8636 0.4572)
			(end -0.8636 0.4064)
			(stroke
				(width 0.1)
				(type default)
			)
			(layer "F.Fab")
		)
		(fp_line
			(start -0.8636 0.4064)
			(end -1.1938 0.4064)
			(stroke
				(width 0.1)
				(type default)
			)
			(layer "F.Fab")
		)
		(fp_line
			(start -0.8636 -0.4064)
			(end -0.8636 -0.4572)
			(stroke
				(width 0.1)
				(type default)
			)
			(layer "F.Fab")
		)
		(fp_line
			(start -0.8636 -0.4572)
			(end 0.8636 -0.4572)
			(stroke
				(width 0.1)
				(type default)
			)
			(layer "F.Fab")
		)
		(fp_line
			(start -1.1938 0.4064)
			(end -1.1938 -0.4064)
			(stroke
				(width 0.1)
				(type default)
			)
			(layer "F.Fab")
		)
		(fp_line
			(start -1.1938 -0.4064)
			(end -0.8636 -0.4064)
			(stroke
				(width 0.1)
				(type default)
			)
			(layer "F.Fab")
		)
		(pad "1" smd rect
			(at -0.7366 0 90)
			(size 0.7112 0.8128)
			(layers "F.Cu" "F.Mask" "F.Paste")
			(net "PCEPLL5_VDDA18_PEX3_R")
		)
		(pad "2" smd rect
			(at 0.7366 0 90)
			(size 0.7112 0.8128)
			(layers "F.Cu" "F.Mask" "F.Paste")
			(net "GND")
		)
	)
	(footprint ""
		(layer "F.Cu")
		(at 41.069768 -350.098614 90)
		(property "Reference" "C2172"
			(at 0 0 90)
			(layer "F.SilkS")
			(hide yes)
			(effects
				(font
					(size 1.27 1.27)
				)
			)
		)
		(property "Value" ""
			(at 0 0 90)
			(layer "F.Fab")
			(effects
				(font
					(size 1.27 1.27)
				)
			)
		)
		(duplicate_pad_numbers_are_jumpers no)
		(fp_line
			(start 0.299974 -0.150114)
			(end 0.299974 0.150114)
			(stroke
				(width 0.1)
				(type default)
			)
			(layer "F.Fab")
		)
		(fp_line
			(start -0.299974 -0.150114)
			(end 0.299974 -0.150114)
			(stroke
				(width 0.1)
				(type default)
			)
			(layer "F.Fab")
		)
		(fp_line
			(start 0.299974 0.150114)
			(end -0.299974 0.150114)
			(stroke
				(width 0.1)
				(type default)
			)
			(layer "F.Fab")
		)
		(fp_line
			(start -0.299974 0.150114)
			(end -0.299974 -0.150114)
			(stroke
				(width 0.1)
				(type default)
			)
			(layer "F.Fab")
		)
		(pad "1" smd rect
			(at -0.2667 0 90)
			(size 0.3048 0.381)
			(layers "F.Cu" "F.Mask" "F.Paste")
			(net "P5E_PEX0_STN4_TX_DP<69>")
		)
		(pad "2" smd rect
			(at 0.2667 0 90)
			(size 0.3048 0.381)
			(layers "F.Cu" "F.Mask" "F.Paste")
			(net "P5E_PEX0_STN4_TX_C_DP<69>")
		)
	)
	(footprint ""
		(layer "F.Cu")
		(at 30.526736 -53.697124 -90)
		(property "Reference" "PC520"
			(at 0 0 270)
			(layer "F.SilkS")
			(hide yes)
			(effects
				(font
					(size 1.27 1.27)
				)
			)
		)
		(property "Value" ""
			(at 0 0 270)
			(layer "F.Fab")
			(effects
				(font
					(size 1.27 1.27)
				)
			)
		)
		(duplicate_pad_numbers_are_jumpers no)
		(fp_line
			(start -0.7874 0.4064)
			(end -0.7874 -0.4064)
			(stroke
				(width 0.1524)
				(type default)
			)
			(layer "F.SilkS")
		)
		(fp_line
			(start 0.7874 0.4064)
			(end -0.7874 0.4064)
			(stroke
				(width 0.1524)
				(type default)
			)
			(layer "F.SilkS")
		)
		(fp_line
			(start -0.7874 -0.4064)
			(end 0.7874 -0.4064)
			(stroke
				(width 0.1524)
				(type default)
			)
			(layer "F.SilkS")
		)
		(fp_line
			(start 0.7874 -0.4064)
			(end 0.7874 0.4064)
			(stroke
				(width 0.1524)
				(type default)
			)
			(layer "F.SilkS")
		)
		(fp_line
			(start -0.67945 0.3048)
			(end -0.67945 -0.305054)
			(stroke
				(width 0.1)
				(type default)
			)
			(layer "F.Fab")
		)
		(fp_line
			(start -0.12065 0.3048)
			(end -0.67945 0.3048)
			(stroke
				(width 0.1)
				(type default)
			)
			(layer "F.Fab")
		)
		(fp_line
			(start 0.120396 0.3048)
			(end 0.120396 0.2794)
			(stroke
				(width 0.1)
				(type default)
			)
			(layer "F.Fab")
		)
		(fp_line
			(start 0.67945 0.3048)
			(end 0.120396 0.3048)
			(stroke
				(width 0.1)
				(type default)
			)
			(layer "F.Fab")
		)
		(fp_line
			(start -0.12065 0.2794)
			(end -0.12065 0.3048)
			(stroke
				(width 0.1)
				(type default)
			)
			(layer "F.Fab")
		)
		(fp_line
			(start 0.120396 0.2794)
			(end -0.12065 0.2794)
			(stroke
				(width 0.1)
				(type default)
			)
			(layer "F.Fab")
		)
		(fp_line
			(start -0.12065 -0.2794)
			(end 0.12065 -0.2794)
			(stroke
				(width 0.1)
				(type default)
			)
			(layer "F.Fab")
		)
		(fp_line
			(start 0.12065 -0.2794)
			(end 0.12065 -0.3048)
			(stroke
				(width 0.1)
				(type default)
			)
			(layer "F.Fab")
		)
		(fp_line
			(start 0.12065 -0.3048)
			(end 0.67945 -0.3048)
			(stroke
				(width 0.1)
				(type default)
			)
			(layer "F.Fab")
		)
		(fp_line
			(start 0.67945 -0.3048)
			(end 0.67945 0.3048)
			(stroke
				(width 0.1)
				(type default)
			)
			(layer "F.Fab")
		)
		(fp_line
			(start -0.67945 -0.305054)
			(end -0.12065 -0.305054)
			(stroke
				(width 0.1)
				(type default)
			)
			(layer "F.Fab")
		)
		(fp_line
			(start -0.12065 -0.305054)
			(end -0.12065 -0.2794)
			(stroke
				(width 0.1)
				(type default)
			)
			(layer "F.Fab")
		)
		(pad "1" smd circle
			(at -0.40005 0 270)
			(size 0 0)
			(layers "F.Cu" "F.Mask" "F.Paste")
			(net "P3V3_AUX")
		)
		(pad "2" smd circle
			(at 0.40005 0 270)
			(size 0 0)
			(layers "F.Cu" "F.Mask" "F.Paste")
			(net "GND")
		)
	)
	(footprint ""
		(layer "F.Cu")
		(at 217.235786 -226.811586 180)
		(property "Reference" "R1481"
			(at 0 0 180)
			(layer "F.SilkS")
			(hide yes)
			(effects
				(font
					(size 1.27 1.27)
				)
			)
		)
		(property "Value" ""
			(at 0 0 180)
			(layer "F.Fab")
			(effects
				(font
					(size 1.27 1.27)
				)
			)
		)
		(duplicate_pad_numbers_are_jumpers no)
		(fp_line
			(start 0.7874 0.4064)
			(end -0.7874 0.4064)
			(stroke
				(width 0.1524)
				(type default)
			)
			(layer "F.SilkS")
		)
		(fp_line
			(start 0.7874 -0.4064)
			(end 0.7874 0.4064)
			(stroke
				(width 0.1524)
				(type default)
			)
			(layer "F.SilkS")
		)
		(fp_line
			(start -0.7874 0.4064)
			(end -0.7874 -0.4064)
			(stroke
				(width 0.1524)
				(type default)
			)
			(layer "F.SilkS")
		)
		(fp_line
			(start -0.7874 -0.4064)
			(end 0.7874 -0.4064)
			(stroke
				(width 0.1524)
				(type default)
			)
			(layer "F.SilkS")
		)
		(fp_line
			(start 0.67945 0.3048)
			(end 0.120396 0.3048)
			(stroke
				(width 0.1)
				(type default)
			)
			(layer "F.Fab")
		)
		(fp_line
			(start 0.67945 -0.3048)
			(end 0.67945 0.3048)
			(stroke
				(width 0.1)
				(type default)
			)
			(layer "F.Fab")
		)
		(fp_line
			(start 0.12065 -0.2794)
			(end 0.12065 -0.3048)
			(stroke
				(width 0.1)
				(type default)
			)
			(layer "F.Fab")
		)
		(fp_line
			(start 0.12065 -0.3048)
			(end 0.67945 -0.3048)
			(stroke
				(width 0.1)
				(type default)
			)
			(layer "F.Fab")
		)
		(fp_line
			(start 0.120396 0.3048)
			(end 0.120396 0.2794)
			(stroke
				(width 0.1)
				(type default)
			)
			(layer "F.Fab")
		)
		(fp_line
			(start 0.120396 0.2794)
			(end -0.12065 0.2794)
			(stroke
				(width 0.1)
				(type default)
			)
			(layer "F.Fab")
		)
		(fp_line
			(start -0.12065 0.3048)
			(end -0.67945 0.3048)
			(stroke
				(width 0.1)
				(type default)
			)
			(layer "F.Fab")
		)
		(fp_line
			(start -0.12065 0.2794)
			(end -0.12065 0.3048)
			(stroke
				(width 0.1)
				(type default)
			)
			(layer "F.Fab")
		)
		(fp_line
			(start -0.12065 -0.2794)
			(end 0.12065 -0.2794)
			(stroke
				(width 0.1)
				(type default)
			)
			(layer "F.Fab")
		)
		(fp_line
			(start -0.12065 -0.305054)
			(end -0.12065 -0.2794)
			(stroke
				(width 0.1)
				(type default)
			)
			(layer "F.Fab")
		)
		(fp_line
			(start -0.67945 0.3048)
			(end -0.67945 -0.305054)
			(stroke
				(width 0.1)
				(type default)
			)
			(layer "F.Fab")
		)
		(fp_line
			(start -0.67945 -0.305054)
			(end -0.12065 -0.305054)
			(stroke
				(width 0.1)
				(type default)
			)
			(layer "F.Fab")
		)
		(pad "1" smd circle
			(at -0.40005 0 180)
			(size 0 0)
			(layers "F.Cu" "F.Mask" "F.Paste")
			(net "SMB_NIC2_SCL")
		)
		(pad "2" smd circle
			(at 0.40005 0 180)
			(size 0 0)
			(layers "F.Cu" "F.Mask" "F.Paste")
			(net "SMB_NIC2_R_SCL")
		)
	)
	(footprint ""
		(layer "F.Cu")
		(at 126.210314 -124.963428 180)
		(property "Reference" "R4478"
			(at 0 0 180)
			(layer "F.SilkS")
			(hide yes)
			(effects
				(font
					(size 1.27 1.27)
				)
			)
		)
		(property "Value" ""
			(at 0 0 180)
			(layer "F.Fab")
			(effects
				(font
					(size 1.27 1.27)
				)
			)
		)
		(duplicate_pad_numbers_are_jumpers no)
		(fp_line
			(start 0.7874 0.4064)
			(end -0.7874 0.4064)
			(stroke
				(width 0.1524)
				(type default)
			)
			(layer "F.SilkS")
		)
		(fp_line
			(start 0.7874 -0.4064)
			(end 0.7874 0.4064)
			(stroke
				(width 0.1524)
				(type default)
			)
			(layer "F.SilkS")
		)
		(fp_line
			(start -0.7874 0.4064)
			(end -0.7874 -0.4064)
			(stroke
				(width 0.1524)
				(type default)
			)
			(layer "F.SilkS")
		)
		(fp_line
			(start -0.7874 -0.4064)
			(end 0.7874 -0.4064)
			(stroke
				(width 0.1524)
				(type default)
			)
			(layer "F.SilkS")
		)
		(fp_line
			(start 0.67945 0.3048)
			(end 0.120396 0.3048)
			(stroke
				(width 0.1)
				(type default)
			)
			(layer "F.Fab")
		)
		(fp_line
			(start 0.67945 -0.3048)
			(end 0.67945 0.3048)
			(stroke
				(width 0.1)
				(type default)
			)
			(layer "F.Fab")
		)
		(fp_line
			(start 0.12065 -0.2794)
			(end 0.12065 -0.3048)
			(stroke
				(width 0.1)
				(type default)
			)
			(layer "F.Fab")
		)
		(fp_line
			(start 0.12065 -0.3048)
			(end 0.67945 -0.3048)
			(stroke
				(width 0.1)
				(type default)
			)
			(layer "F.Fab")
		)
		(fp_line
			(start 0.120396 0.3048)
			(end 0.120396 0.2794)
			(stroke
				(width 0.1)
				(type default)
			)
			(layer "F.Fab")
		)
		(fp_line
			(start 0.120396 0.2794)
			(end -0.12065 0.2794)
			(stroke
				(width 0.1)
				(type default)
			)
			(layer "F.Fab")
		)
		(fp_line
			(start -0.12065 0.3048)
			(end -0.67945 0.3048)
			(stroke
				(width 0.1)
				(type default)
			)
			(layer "F.Fab")
		)
		(fp_line
			(start -0.12065 0.2794)
			(end -0.12065 0.3048)
			(stroke
				(width 0.1)
				(type default)
			)
			(layer "F.Fab")
		)
		(fp_line
			(start -0.12065 -0.2794)
			(end 0.12065 -0.2794)
			(stroke
				(width 0.1)
				(type default)
			)
			(layer "F.Fab")
		)
		(fp_line
			(start -0.12065 -0.305054)
			(end -0.12065 -0.2794)
			(stroke
				(width 0.1)
				(type default)
			)
			(layer "F.Fab")
		)
		(fp_line
			(start -0.67945 0.3048)
			(end -0.67945 -0.305054)
			(stroke
				(width 0.1)
				(type default)
			)
			(layer "F.Fab")
		)
		(fp_line
			(start -0.67945 -0.305054)
			(end -0.12065 -0.305054)
			(stroke
				(width 0.1)
				(type default)
			)
			(layer "F.Fab")
		)
		(pad "1" smd circle
			(at -0.40005 0 180)
			(size 0 0)
			(layers "F.Cu" "F.Mask" "F.Paste")
			(net "PWRGD_P3V3_NIC2")
		)
		(pad "2" smd circle
			(at 0.40005 0 180)
			(size 0 0)
			(layers "F.Cu" "F.Mask" "F.Paste")
			(net "PWRGD_P3V3_NIC2_R")
		)
	)
	(footprint ""
		(layer "F.Cu")
		(at 225.31705 -305.375564)
		(property "Reference" "PC230"
			(at 0 0 0)
			(layer "F.SilkS")
			(hide yes)
			(effects
				(font
					(size 1.27 1.27)
				)
			)
		)
		(property "Value" ""
			(at 0 0 0)
			(layer "F.Fab")
			(effects
				(font
					(size 1.27 1.27)
				)
			)
		)
		(duplicate_pad_numbers_are_jumpers no)
		(fp_line
			(start -0.7874 -0.4064)
			(end 0.7874 -0.4064)
			(stroke
				(width 0.1524)
				(type default)
			)
			(layer "F.SilkS")
		)
		(fp_line
			(start -0.7874 0.4064)
			(end -0.7874 -0.4064)
			(stroke
				(width 0.1524)
				(type default)
			)
			(layer "F.SilkS")
		)
		(fp_line
			(start 0.7874 -0.4064)
			(end 0.7874 0.4064)
			(stroke
				(width 0.1524)
				(type default)
			)
			(layer "F.SilkS")
		)
		(fp_line
			(start 0.7874 0.4064)
			(end -0.7874 0.4064)
			(stroke
				(width 0.1524)
				(type default)
			)
			(layer "F.SilkS")
		)
		(fp_line
			(start -0.67945 -0.305054)
			(end -0.12065 -0.305054)
			(stroke
				(width 0.1)
				(type default)
			)
			(layer "F.Fab")
		)
		(fp_line
			(start -0.67945 0.3048)
			(end -0.67945 -0.305054)
			(stroke
				(width 0.1)
				(type default)
			)
			(layer "F.Fab")
		)
		(fp_line
			(start -0.12065 -0.305054)
			(end -0.12065 -0.2794)
			(stroke
				(width 0.1)
				(type default)
			)
			(layer "F.Fab")
		)
		(fp_line
			(start -0.12065 -0.2794)
			(end 0.12065 -0.2794)
			(stroke
				(width 0.1)
				(type default)
			)
			(layer "F.Fab")
		)
		(fp_line
			(start -0.12065 0.2794)
			(end -0.12065 0.3048)
			(stroke
				(width 0.1)
				(type default)
			)
			(layer "F.Fab")
		)
		(fp_line
			(start -0.12065 0.3048)
			(end -0.67945 0.3048)
			(stroke
				(width 0.1)
				(type default)
			)
			(layer "F.Fab")
		)
		(fp_line
			(start 0.120396 0.2794)
			(end -0.12065 0.2794)
			(stroke
				(width 0.1)
				(type default)
			)
			(layer "F.Fab")
		)
		(fp_line
			(start 0.120396 0.3048)
			(end 0.120396 0.2794)
			(stroke
				(width 0.1)
				(type default)
			)
			(layer "F.Fab")
		)
		(fp_line
			(start 0.12065 -0.3048)
			(end 0.67945 -0.3048)
			(stroke
				(width 0.1)
				(type default)
			)
			(layer "F.Fab")
		)
		(fp_line
			(start 0.12065 -0.2794)
			(end 0.12065 -0.3048)
			(stroke
				(width 0.1)
				(type default)
			)
			(layer "F.Fab")
		)
		(fp_line
			(start 0.67945 -0.3048)
			(end 0.67945 0.3048)
			(stroke
				(width 0.1)
				(type default)
			)
			(layer "F.Fab")
		)
		(fp_line
			(start 0.67945 0.3048)
			(end 0.120396 0.3048)
			(stroke
				(width 0.1)
				(type default)
			)
			(layer "F.Fab")
		)
		(pad "1" smd circle
			(at -0.40005 0)
			(size 0 0)
			(layers "F.Cu" "F.Mask" "F.Paste")
			(net "SW_P12V_P1V25_PEX1_FLT")
		)
		(pad "2" smd circle
			(at 0.40005 0)
			(size 0 0)
			(layers "F.Cu" "F.Mask" "F.Paste")
			(net "GND")
		)
	)
	(footprint ""
		(layer "F.Cu")
		(at 350.380554 -90.645234)
		(property "Reference" "R1598"
			(at 0 0 0)
			(layer "F.SilkS")
			(hide yes)
			(effects
				(font
					(size 1.27 1.27)
				)
			)
		)
		(property "Value" ""
			(at 0 0 0)
			(layer "F.Fab")
			(effects
				(font
					(size 1.27 1.27)
				)
			)
		)
		(duplicate_pad_numbers_are_jumpers no)
		(fp_line
			(start -0.7874 -0.4064)
			(end 0.7874 -0.4064)
			(stroke
				(width 0.1524)
				(type default)
			)
			(layer "F.SilkS")
		)
		(fp_line
			(start -0.7874 0.4064)
			(end -0.7874 -0.4064)
			(stroke
				(width 0.1524)
				(type default)
			)
			(layer "F.SilkS")
		)
		(fp_line
			(start 0.7874 -0.4064)
			(end 0.7874 0.4064)
			(stroke
				(width 0.1524)
				(type default)
			)
			(layer "F.SilkS")
		)
		(fp_line
			(start 0.7874 0.4064)
			(end -0.7874 0.4064)
			(stroke
				(width 0.1524)
				(type default)
			)
			(layer "F.SilkS")
		)
		(fp_line
			(start -0.67945 -0.305054)
			(end -0.12065 -0.305054)
			(stroke
				(width 0.1)
				(type default)
			)
			(layer "F.Fab")
		)
		(fp_line
			(start -0.67945 0.3048)
			(end -0.67945 -0.305054)
			(stroke
				(width 0.1)
				(type default)
			)
			(layer "F.Fab")
		)
		(fp_line
			(start -0.12065 -0.305054)
			(end -0.12065 -0.2794)
			(stroke
				(width 0.1)
				(type default)
			)
			(layer "F.Fab")
		)
		(fp_line
			(start -0.12065 -0.2794)
			(end 0.12065 -0.2794)
			(stroke
				(width 0.1)
				(type default)
			)
			(layer "F.Fab")
		)
		(fp_line
			(start -0.12065 0.2794)
			(end -0.12065 0.3048)
			(stroke
				(width 0.1)
				(type default)
			)
			(layer "F.Fab")
		)
		(fp_line
			(start -0.12065 0.3048)
			(end -0.67945 0.3048)
			(stroke
				(width 0.1)
				(type default)
			)
			(layer "F.Fab")
		)
		(fp_line
			(start 0.120396 0.2794)
			(end -0.12065 0.2794)
			(stroke
				(width 0.1)
				(type default)
			)
			(layer "F.Fab")
		)
		(fp_line
			(start 0.120396 0.3048)
			(end 0.120396 0.2794)
			(stroke
				(width 0.1)
				(type default)
			)
			(layer "F.Fab")
		)
		(fp_line
			(start 0.12065 -0.3048)
			(end 0.67945 -0.3048)
			(stroke
				(width 0.1)
				(type default)
			)
			(layer "F.Fab")
		)
		(fp_line
			(start 0.12065 -0.2794)
			(end 0.12065 -0.3048)
			(stroke
				(width 0.1)
				(type default)
			)
			(layer "F.Fab")
		)
		(fp_line
			(start 0.67945 -0.3048)
			(end 0.67945 0.3048)
			(stroke
				(width 0.1)
				(type default)
			)
			(layer "F.Fab")
		)
		(fp_line
			(start 0.67945 0.3048)
			(end 0.120396 0.3048)
			(stroke
				(width 0.1)
				(type default)
			)
			(layer "F.Fab")
		)
		(pad "1" smd circle
			(at -0.40005 0)
			(size 0 0)
			(layers "F.Cu" "F.Mask" "F.Paste")
			(net "P3V3_AUX")
		)
		(pad "2" smd circle
			(at 0.40005 0)
			(size 0 0)
			(layers "F.Cu" "F.Mask" "F.Paste")
			(net "BIC_I2C9_SSD_MUX1_A1")
		)
	)
	(footprint ""
		(layer "F.Cu")
		(at 336.586068 -272.15846 -90)
		(property "Reference" "PL11"
			(at 1.04013 -2.958338 90)
			(unlocked yes)
			(layer "F.SilkS")
			(effects
				(font
					(size 0.7874 0.5842)
					(thickness 0.1524)
				)
				(justify left)
			)
		)
		(property "Value" ""
			(at 0 0 270)
			(layer "F.Fab")
			(effects
				(font
					(size 1.27 1.27)
				)
			)
		)
		(duplicate_pad_numbers_are_jumpers no)
		(fp_line
			(start -2.249932 2.249932)
			(end -2.249932 1.3843)
			(stroke
				(width 0.1524)
				(type default)
			)
			(layer "F.SilkS")
		)
		(fp_line
			(start 2.249932 2.249932)
			(end -2.249932 2.249932)
			(stroke
				(width 0.1524)
				(type default)
			)
			(layer "F.SilkS")
		)
		(fp_line
			(start 2.249932 1.3843)
			(end 2.249932 2.249932)
			(stroke
				(width 0.1524)
				(type default)
			)
			(layer "F.SilkS")
		)
		(fp_line
			(start -2.249932 -1.3843)
			(end -2.249932 -2.249932)
			(stroke
				(width 0.1524)
				(type default)
			)
			(layer "F.SilkS")
		)
		(fp_line
			(start -2.249932 -2.249932)
			(end 2.249932 -2.249932)
			(stroke
				(width 0.1524)
				(type default)
			)
			(layer "F.SilkS")
		)
		(fp_line
			(start 2.249932 -2.249932)
			(end 2.249932 -1.3843)
			(stroke
				(width 0.1524)
				(type default)
			)
			(layer "F.SilkS")
		)
		(fp_line
			(start -2.249932 2.249932)
			(end -2.249932 -2.249932)
			(stroke
				(width 0.1)
				(type default)
			)
			(layer "F.Fab")
		)
		(fp_line
			(start 2.249932 2.249932)
			(end -2.249932 2.249932)
			(stroke
				(width 0.1)
				(type default)
			)
			(layer "F.Fab")
		)
		(fp_line
			(start -2.249932 -2.249932)
			(end 2.249932 -2.249932)
			(stroke
				(width 0.1)
				(type default)
			)
			(layer "F.Fab")
		)
		(fp_line
			(start 2.249932 -2.249932)
			(end 2.249932 2.249932)
			(stroke
				(width 0.1)
				(type default)
			)
			(layer "F.Fab")
		)
		(pad "1" smd rect
			(at -1.82499 0 270)
			(size 1.0668 2.5146)
			(layers "F.Cu" "F.Mask" "F.Paste")
			(net "SW_P12V_P0V8_PEX2_FLT")
		)
		(pad "2" smd rect
			(at 1.82499 0 270)
			(size 1.0668 2.5146)
			(layers "F.Cu" "F.Mask" "F.Paste")
			(net "P12V_AUX")
		)
	)
	(footprint ""
		(layer "F.Cu")
		(at 488.88269 -553.245274 180)
		(property "Reference" "JPEX1_FW1"
			(at -4.0259 -1.402334 0)
			(unlocked yes)
			(layer "B.SilkS")
			(effects
				(font
					(size 0.7874 0.5842)
					(thickness 0.1524)
				)
				(justify mirror)
			)
		)
		(property "Value" ""
			(at 0 0 180)
			(layer "F.Fab")
			(effects
				(font
					(size 1.27 1.27)
				)
			)
		)
		(duplicate_pad_numbers_are_jumpers no)
		(pad "1" thru_hole circle
			(at 0 0 180)
			(size 0.4572 0.4572)
			(drill 0.2032)
			(layers "*.Cu" "*.Mask")
			(remove_unused_layers no)
			(net "Net_9089")
			(clearance 0.127)
			(thermal_gap 0.127)
			(padstack
				(mode front_inner_back)
				(layer "Inner"
					(shape circle)
					(size 0.4572 0.4572)
					(clearance 0.127)
				)
				(layer "B.Cu"
					(shape circle)
					(size 0.508 0.508)
					(clearance 0.1016)
				)
			)
		)
	)
	(footprint ""
		(layer "F.Cu")
		(at 225.446844 -38.49116 180)
		(property "Reference" "R6088"
			(at 0 0 180)
			(layer "F.SilkS")
			(hide yes)
			(effects
				(font
					(size 1.27 1.27)
				)
			)
		)
		(property "Value" ""
			(at 0 0 180)
			(layer "F.Fab")
			(effects
				(font
					(size 1.27 1.27)
				)
			)
		)
		(duplicate_pad_numbers_are_jumpers no)
		(fp_line
			(start 0.7874 0.4064)
			(end -0.7874 0.4064)
			(stroke
				(width 0.1524)
				(type default)
			)
			(layer "F.SilkS")
		)
		(fp_line
			(start 0.7874 -0.4064)
			(end 0.7874 0.4064)
			(stroke
				(width 0.1524)
				(type default)
			)
			(layer "F.SilkS")
		)
		(fp_line
			(start -0.7874 0.4064)
			(end -0.7874 -0.4064)
			(stroke
				(width 0.1524)
				(type default)
			)
			(layer "F.SilkS")
		)
		(fp_line
			(start -0.7874 -0.4064)
			(end 0.7874 -0.4064)
			(stroke
				(width 0.1524)
				(type default)
			)
			(layer "F.SilkS")
		)
		(fp_line
			(start 0.67945 0.3048)
			(end 0.120396 0.3048)
			(stroke
				(width 0.1)
				(type default)
			)
			(layer "F.Fab")
		)
		(fp_line
			(start 0.67945 -0.3048)
			(end 0.67945 0.3048)
			(stroke
				(width 0.1)
				(type default)
			)
			(layer "F.Fab")
		)
		(fp_line
			(start 0.12065 -0.2794)
			(end 0.12065 -0.3048)
			(stroke
				(width 0.1)
				(type default)
			)
			(layer "F.Fab")
		)
		(fp_line
			(start 0.12065 -0.3048)
			(end 0.67945 -0.3048)
			(stroke
				(width 0.1)
				(type default)
			)
			(layer "F.Fab")
		)
		(fp_line
			(start 0.120396 0.3048)
			(end 0.120396 0.2794)
			(stroke
				(width 0.1)
				(type default)
			)
			(layer "F.Fab")
		)
		(fp_line
			(start 0.120396 0.2794)
			(end -0.12065 0.2794)
			(stroke
				(width 0.1)
				(type default)
			)
			(layer "F.Fab")
		)
		(fp_line
			(start -0.12065 0.3048)
			(end -0.67945 0.3048)
			(stroke
				(width 0.1)
				(type default)
			)
			(layer "F.Fab")
		)
		(fp_line
			(start -0.12065 0.2794)
			(end -0.12065 0.3048)
			(stroke
				(width 0.1)
				(type default)
			)
			(layer "F.Fab")
		)
		(fp_line
			(start -0.12065 -0.2794)
			(end 0.12065 -0.2794)
			(stroke
				(width 0.1)
				(type default)
			)
			(layer "F.Fab")
		)
		(fp_line
			(start -0.12065 -0.305054)
			(end -0.12065 -0.2794)
			(stroke
				(width 0.1)
				(type default)
			)
			(layer "F.Fab")
		)
		(fp_line
			(start -0.67945 0.3048)
			(end -0.67945 -0.305054)
			(stroke
				(width 0.1)
				(type default)
			)
			(layer "F.Fab")
		)
		(fp_line
			(start -0.67945 -0.305054)
			(end -0.12065 -0.305054)
			(stroke
				(width 0.1)
				(type default)
			)
			(layer "F.Fab")
		)
		(pad "1" smd circle
			(at -0.40005 0 180)
			(size 0 0)
			(layers "F.Cu" "F.Mask" "F.Paste")
			(net "P3V3_SSD8_PG_G1")
		)
		(pad "2" smd circle
			(at 0.40005 0 180)
			(size 0 0)
			(layers "F.Cu" "F.Mask" "F.Paste")
			(net "GND")
		)
	)
	(footprint ""
		(layer "F.Cu")
		(at 198.564246 -365.615728 180)
		(property "Reference" "PC9"
			(at 0 0 180)
			(layer "F.SilkS")
			(hide yes)
			(effects
				(font
					(size 1.27 1.27)
				)
			)
		)
		(property "Value" ""
			(at 0 0 180)
			(layer "F.Fab")
			(effects
				(font
					(size 1.27 1.27)
				)
			)
		)
		(duplicate_pad_numbers_are_jumpers no)
		(fp_line
			(start 0.7874 0.4064)
			(end -0.7874 0.4064)
			(stroke
				(width 0.1524)
				(type default)
			)
			(layer "F.SilkS")
		)
		(fp_line
			(start 0.7874 -0.4064)
			(end 0.7874 0.4064)
			(stroke
				(width 0.1524)
				(type default)
			)
			(layer "F.SilkS")
		)
		(fp_line
			(start -0.7874 0.4064)
			(end -0.7874 -0.4064)
			(stroke
				(width 0.1524)
				(type default)
			)
			(layer "F.SilkS")
		)
		(fp_line
			(start -0.7874 -0.4064)
			(end 0.7874 -0.4064)
			(stroke
				(width 0.1524)
				(type default)
			)
			(layer "F.SilkS")
		)
		(fp_line
			(start 0.67945 0.3048)
			(end 0.120396 0.3048)
			(stroke
				(width 0.1)
				(type default)
			)
			(layer "F.Fab")
		)
		(fp_line
			(start 0.67945 -0.3048)
			(end 0.67945 0.3048)
			(stroke
				(width 0.1)
				(type default)
			)
			(layer "F.Fab")
		)
		(fp_line
			(start 0.12065 -0.2794)
			(end 0.12065 -0.3048)
			(stroke
				(width 0.1)
				(type default)
			)
			(layer "F.Fab")
		)
		(fp_line
			(start 0.12065 -0.3048)
			(end 0.67945 -0.3048)
			(stroke
				(width 0.1)
				(type default)
			)
			(layer "F.Fab")
		)
		(fp_line
			(start 0.120396 0.3048)
			(end 0.120396 0.2794)
			(stroke
				(width 0.1)
				(type default)
			)
			(layer "F.Fab")
		)
		(fp_line
			(start 0.120396 0.2794)
			(end -0.12065 0.2794)
			(stroke
				(width 0.1)
				(type default)
			)
			(layer "F.Fab")
		)
		(fp_line
			(start -0.12065 0.3048)
			(end -0.67945 0.3048)
			(stroke
				(width 0.1)
				(type default)
			)
			(layer "F.Fab")
		)
		(fp_line
			(start -0.12065 0.2794)
			(end -0.12065 0.3048)
			(stroke
				(width 0.1)
				(type default)
			)
			(layer "F.Fab")
		)
		(fp_line
			(start -0.12065 -0.2794)
			(end 0.12065 -0.2794)
			(stroke
				(width 0.1)
				(type default)
			)
			(layer "F.Fab")
		)
		(fp_line
			(start -0.12065 -0.305054)
			(end -0.12065 -0.2794)
			(stroke
				(width 0.1)
				(type default)
			)
			(layer "F.Fab")
		)
		(fp_line
			(start -0.67945 0.3048)
			(end -0.67945 -0.305054)
			(stroke
				(width 0.1)
				(type default)
			)
			(layer "F.Fab")
		)
		(fp_line
			(start -0.67945 -0.305054)
			(end -0.12065 -0.305054)
			(stroke
				(width 0.1)
				(type default)
			)
			(layer "F.Fab")
		)
		(pad "1" smd circle
			(at -0.40005 0 180)
			(size 0 0)
			(layers "F.Cu" "F.Mask" "F.Paste")
			(net "HSC_VDD18")
		)
		(pad "2" smd circle
			(at 0.40005 0 180)
			(size 0 0)
			(layers "F.Cu" "F.Mask" "F.Paste")
			(net "AGND_HSC")
		)
	)
	(footprint ""
		(layer "F.Cu")
		(at 149.080728 -383.460498 180)
		(property "Reference" "R1848"
			(at 0 0 180)
			(layer "F.SilkS")
			(hide yes)
			(effects
				(font
					(size 1.27 1.27)
				)
			)
		)
		(property "Value" ""
			(at 0 0 180)
			(layer "F.Fab")
			(effects
				(font
					(size 1.27 1.27)
				)
			)
		)
		(duplicate_pad_numbers_are_jumpers no)
		(fp_line
			(start 0.7874 0.4064)
			(end -0.7874 0.4064)
			(stroke
				(width 0.1524)
				(type default)
			)
			(layer "F.SilkS")
		)
		(fp_line
			(start 0.7874 -0.4064)
			(end 0.7874 0.4064)
			(stroke
				(width 0.1524)
				(type default)
			)
			(layer "F.SilkS")
		)
		(fp_line
			(start -0.7874 0.4064)
			(end -0.7874 -0.4064)
			(stroke
				(width 0.1524)
				(type default)
			)
			(layer "F.SilkS")
		)
		(fp_line
			(start -0.7874 -0.4064)
			(end 0.7874 -0.4064)
			(stroke
				(width 0.1524)
				(type default)
			)
			(layer "F.SilkS")
		)
		(fp_line
			(start 0.67945 0.3048)
			(end 0.120396 0.3048)
			(stroke
				(width 0.1)
				(type default)
			)
			(layer "F.Fab")
		)
		(fp_line
			(start 0.67945 -0.3048)
			(end 0.67945 0.3048)
			(stroke
				(width 0.1)
				(type default)
			)
			(layer "F.Fab")
		)
		(fp_line
			(start 0.12065 -0.2794)
			(end 0.12065 -0.3048)
			(stroke
				(width 0.1)
				(type default)
			)
			(layer "F.Fab")
		)
		(fp_line
			(start 0.12065 -0.3048)
			(end 0.67945 -0.3048)
			(stroke
				(width 0.1)
				(type default)
			)
			(layer "F.Fab")
		)
		(fp_line
			(start 0.120396 0.3048)
			(end 0.120396 0.2794)
			(stroke
				(width 0.1)
				(type default)
			)
			(layer "F.Fab")
		)
		(fp_line
			(start 0.120396 0.2794)
			(end -0.12065 0.2794)
			(stroke
				(width 0.1)
				(type default)
			)
			(layer "F.Fab")
		)
		(fp_line
			(start -0.12065 0.3048)
			(end -0.67945 0.3048)
			(stroke
				(width 0.1)
				(type default)
			)
			(layer "F.Fab")
		)
		(fp_line
			(start -0.12065 0.2794)
			(end -0.12065 0.3048)
			(stroke
				(width 0.1)
				(type default)
			)
			(layer "F.Fab")
		)
		(fp_line
			(start -0.12065 -0.2794)
			(end 0.12065 -0.2794)
			(stroke
				(width 0.1)
				(type default)
			)
			(layer "F.Fab")
		)
		(fp_line
			(start -0.12065 -0.305054)
			(end -0.12065 -0.2794)
			(stroke
				(width 0.1)
				(type default)
			)
			(layer "F.Fab")
		)
		(fp_line
			(start -0.67945 0.3048)
			(end -0.67945 -0.305054)
			(stroke
				(width 0.1)
				(type default)
			)
			(layer "F.Fab")
		)
		(fp_line
			(start -0.67945 -0.305054)
			(end -0.12065 -0.305054)
			(stroke
				(width 0.1)
				(type default)
			)
			(layer "F.Fab")
		)
		(pad "1" smd circle
			(at -0.40005 0 180)
			(size 0 0)
			(layers "F.Cu" "F.Mask" "F.Paste")
			(net "RST_GPU_FPGA_EROT_R_N")
		)
		(pad "2" smd circle
			(at 0.40005 0 180)
			(size 0 0)
			(layers "F.Cu" "F.Mask" "F.Paste")
			(net "RST_GPU_FPGA_EROT_N")
		)
	)
	(footprint ""
		(layer "F.Cu")
		(at 115.356386 -82.46999 180)
		(property "Reference" "R1142"
			(at 0 0 180)
			(layer "F.SilkS")
			(hide yes)
			(effects
				(font
					(size 1.27 1.27)
				)
			)
		)
		(property "Value" ""
			(at 0 0 180)
			(layer "F.Fab")
			(effects
				(font
					(size 1.27 1.27)
				)
			)
		)
		(duplicate_pad_numbers_are_jumpers no)
		(fp_line
			(start -0.7874 -0.4064)
			(end 0.7874 -0.4064)
			(stroke
				(width 0.1524)
				(type default)
			)
			(layer "F.SilkS")
		)
		(fp_line
			(start 0.67945 0.3048)
			(end 0.120396 0.3048)
			(stroke
				(width 0.1)
				(type default)
			)
			(layer "F.Fab")
		)
		(fp_line
			(start 0.67945 -0.3048)
			(end 0.67945 0.3048)
			(stroke
				(width 0.1)
				(type default)
			)
			(layer "F.Fab")
		)
		(fp_line
			(start 0.12065 -0.2794)
			(end 0.12065 -0.3048)
			(stroke
				(width 0.1)
				(type default)
			)
			(layer "F.Fab")
		)
		(fp_line
			(start 0.12065 -0.3048)
			(end 0.67945 -0.3048)
			(stroke
				(width 0.1)
				(type default)
			)
			(layer "F.Fab")
		)
		(fp_line
			(start 0.120396 0.3048)
			(end 0.120396 0.2794)
			(stroke
				(width 0.1)
				(type default)
			)
			(layer "F.Fab")
		)
		(fp_line
			(start 0.120396 0.2794)
			(end -0.12065 0.2794)
			(stroke
				(width 0.1)
				(type default)
			)
			(layer "F.Fab")
		)
		(fp_line
			(start -0.12065 0.3048)
			(end -0.67945 0.3048)
			(stroke
				(width 0.1)
				(type default)
			)
			(layer "F.Fab")
		)
		(fp_line
			(start -0.12065 0.2794)
			(end -0.12065 0.3048)
			(stroke
				(width 0.1)
				(type default)
			)
			(layer "F.Fab")
		)
		(fp_line
			(start -0.12065 -0.2794)
			(end 0.12065 -0.2794)
			(stroke
				(width 0.1)
				(type default)
			)
			(layer "F.Fab")
		)
		(fp_line
			(start -0.12065 -0.305054)
			(end -0.12065 -0.2794)
			(stroke
				(width 0.1)
				(type default)
			)
			(layer "F.Fab")
		)
		(fp_line
			(start -0.67945 0.3048)
			(end -0.67945 -0.305054)
			(stroke
				(width 0.1)
				(type default)
			)
			(layer "F.Fab")
		)
		(fp_line
			(start -0.67945 -0.305054)
			(end -0.12065 -0.305054)
			(stroke
				(width 0.1)
				(type default)
			)
			(layer "F.Fab")
		)
		(pad "1" smd circle
			(at -0.40005 0 180)
			(size 0 0)
			(layers "F.Cu" "F.Mask" "F.Paste")
			(net "CLK_100M_DB800ZL_SSD3_R_DP")
		)
		(pad "2" smd circle
			(at 0.40005 0 180)
			(size 0 0)
			(layers "F.Cu" "F.Mask" "F.Paste")
			(net "CLK_100M_DB800ZL_SSD3_DP")
		)
	)
	(footprint ""
		(layer "F.Cu")
		(at 254.471678 -152.71115 90)
		(property "Reference" "R725"
			(at 0 0 90)
			(layer "F.SilkS")
			(hide yes)
			(effects
				(font
					(size 1.27 1.27)
				)
			)
		)
		(property "Value" ""
			(at 0 0 90)
			(layer "F.Fab")
			(effects
				(font
					(size 1.27 1.27)
				)
			)
		)
		(duplicate_pad_numbers_are_jumpers no)
		(fp_line
			(start 0.7874 -0.4064)
			(end 0.7874 0.4064)
			(stroke
				(width 0.1524)
				(type default)
			)
			(layer "F.SilkS")
		)
		(fp_line
			(start -0.7874 -0.4064)
			(end 0.7874 -0.4064)
			(stroke
				(width 0.1524)
				(type default)
			)
			(layer "F.SilkS")
		)
		(fp_line
			(start 0.7874 0.4064)
			(end -0.7874 0.4064)
			(stroke
				(width 0.1524)
				(type default)
			)
			(layer "F.SilkS")
		)
		(fp_line
			(start -0.7874 0.4064)
			(end -0.7874 -0.4064)
			(stroke
				(width 0.1524)
				(type default)
			)
			(layer "F.SilkS")
		)
		(fp_line
			(start -0.12065 -0.305054)
			(end -0.12065 -0.2794)
			(stroke
				(width 0.1)
				(type default)
			)
			(layer "F.Fab")
		)
		(fp_line
			(start -0.67945 -0.305054)
			(end -0.12065 -0.305054)
			(stroke
				(width 0.1)
				(type default)
			)
			(layer "F.Fab")
		)
		(fp_line
			(start 0.67945 -0.3048)
			(end 0.67945 0.3048)
			(stroke
				(width 0.1)
				(type default)
			)
			(layer "F.Fab")
		)
		(fp_line
			(start 0.12065 -0.3048)
			(end 0.67945 -0.3048)
			(stroke
				(width 0.1)
				(type default)
			)
			(layer "F.Fab")
		)
		(fp_line
			(start 0.12065 -0.2794)
			(end 0.12065 -0.3048)
			(stroke
				(width 0.1)
				(type default)
			)
			(layer "F.Fab")
		)
		(fp_line
			(start -0.12065 -0.2794)
			(end 0.12065 -0.2794)
			(stroke
				(width 0.1)
				(type default)
			)
			(layer "F.Fab")
		)
		(fp_line
			(start 0.120396 0.2794)
			(end -0.12065 0.2794)
			(stroke
				(width 0.1)
				(type default)
			)
			(layer "F.Fab")
		)
		(fp_line
			(start -0.12065 0.2794)
			(end -0.12065 0.3048)
			(stroke
				(width 0.1)
				(type default)
			)
			(layer "F.Fab")
		)
		(fp_line
			(start 0.67945 0.3048)
			(end 0.120396 0.3048)
			(stroke
				(width 0.1)
				(type default)
			)
			(layer "F.Fab")
		)
		(fp_line
			(start 0.120396 0.3048)
			(end 0.120396 0.2794)
			(stroke
				(width 0.1)
				(type default)
			)
			(layer "F.Fab")
		)
		(fp_line
			(start -0.12065 0.3048)
			(end -0.67945 0.3048)
			(stroke
				(width 0.1)
				(type default)
			)
			(layer "F.Fab")
		)
		(fp_line
			(start -0.67945 0.3048)
			(end -0.67945 -0.305054)
			(stroke
				(width 0.1)
				(type default)
			)
			(layer "F.Fab")
		)
		(pad "1" smd circle
			(at -0.40005 0 90)
			(size 0 0)
			(layers "F.Cu" "F.Mask" "F.Paste")
			(net "NIC4_ADC_A1")
		)
		(pad "2" smd circle
			(at 0.40005 0 90)
			(size 0 0)
			(layers "F.Cu" "F.Mask" "F.Paste")
			(net "P3V3_AUX")
		)
	)
	(footprint ""
		(layer "F.Cu")
		(at 423.145966 -46.4439 180)
		(property "Reference" "U77"
			(at 0.540766 -2.45237 0)
			(unlocked yes)
			(layer "F.SilkS")
			(effects
				(font
					(size 0.7874 0.5842)
					(thickness 0.1524)
				)
			)
		)
		(property "Value" ""
			(at 0 0 180)
			(layer "F.Fab")
			(effects
				(font
					(size 1.27 1.27)
				)
			)
		)
		(duplicate_pad_numbers_are_jumpers no)
		(fp_line
			(start 1.500124 1.500124)
			(end 1.004062 1.500124)
			(stroke
				(width 0.1524)
				(type default)
			)
			(layer "F.SilkS")
		)
		(fp_line
			(start 1.500124 1.004062)
			(end 1.500124 1.500124)
			(stroke
				(width 0.1524)
				(type default)
			)
			(layer "F.SilkS")
		)
		(fp_line
			(start 1.500124 -1.500124)
			(end 1.500124 -1.004062)
			(stroke
				(width 0.1524)
				(type default)
			)
			(layer "F.SilkS")
		)
		(fp_line
			(start 1.004062 -1.500124)
			(end 1.500124 -1.500124)
			(stroke
				(width 0.1524)
				(type default)
			)
			(layer "F.SilkS")
		)
		(fp_line
			(start -1.004062 1.500124)
			(end -1.500124 1.500124)
			(stroke
				(width 0.1524)
				(type default)
			)
			(layer "F.SilkS")
		)
		(fp_line
			(start -1.500124 1.500124)
			(end -1.500124 1.004062)
			(stroke
				(width 0.1524)
				(type default)
			)
			(layer "F.SilkS")
		)
		(fp_line
			(start -1.500124 -1.004062)
			(end -1.500124 -1.500124)
			(stroke
				(width 0.1524)
				(type default)
			)
			(layer "F.SilkS")
		)
		(fp_line
			(start -1.500124 -1.500124)
			(end -1.004062 -1.500124)
			(stroke
				(width 0.1524)
				(type default)
			)
			(layer "F.SilkS")
		)
		(fp_poly
			(pts
				(xy -1.725168 -2.612136) (xy -2.44348 -1.89357) (xy -1.366012 -1.534414)
			)
			(stroke
				(width 0)
				(type default)
			)
			(fill yes)
			(layer "F.SilkS")
		)
		(fp_line
			(start 1.500124 1.500124)
			(end -1.500124 1.500124)
			(stroke
				(width 0.1)
				(type default)
			)
			(layer "F.Fab")
		)
		(fp_line
			(start 1.500124 -1.500124)
			(end 1.500124 1.500124)
			(stroke
				(width 0.1)
				(type default)
			)
			(layer "F.Fab")
		)
		(fp_line
			(start -1.500124 1.500124)
			(end -1.500124 -1.500124)
			(stroke
				(width 0.1)
				(type default)
			)
			(layer "F.Fab")
		)
		(fp_line
			(start -1.500124 -1.500124)
			(end 1.500124 -1.500124)
			(stroke
				(width 0.1)
				(type default)
			)
			(layer "F.Fab")
		)
		(fp_poly
			(pts
				(xy -2.847848 -1.258062) (xy -2.847848 -0.242062) (xy -1.831848 -0.750062)
			)
			(stroke
				(width 0)
				(type default)
			)
			(fill yes)
			(layer "F.Fab")
		)
		(pad "1" smd rect
			(at -1.400048 -0.750062 90)
			(size 0.2286 0.6096)
			(layers "F.Cu" "F.Mask" "F.Paste")
			(net "SSD14_ADC_A1")
		)
		(pad "2" smd rect
			(at -1.400048 -0.249936 90)
			(size 0.2286 0.6096)
			(layers "F.Cu" "F.Mask" "F.Paste")
			(net "SSD14_ADC_A0")
		)
		(pad "3" smd rect
			(at -1.400048 0.249936 90)
			(size 0.2286 0.6096)
			(layers "F.Cu" "F.Mask" "F.Paste")
			(net "SSD14_ADC_ALERT_N")
		)
		(pad "4" smd rect
			(at -1.400048 0.750062 90)
			(size 0.2286 0.6096)
			(layers "F.Cu" "F.Mask" "F.Paste")
			(net "SMB_SSD14_ADC_SDA")
		)
		(pad "5" smd rect
			(at -0.750062 1.400048 180)
			(size 0.2286 0.6096)
			(layers "F.Cu" "F.Mask" "F.Paste")
			(net "SMB_SSD14_ADC_SCL")
		)
		(pad "6" smd rect
			(at -0.249936 1.400048 180)
			(size 0.2286 0.6096)
			(layers "F.Cu" "F.Mask" "F.Paste")
			(net "Net_8678")
		)
		(pad "7" smd rect
			(at 0.249936 1.400048 180)
			(size 0.2286 0.6096)
			(layers "F.Cu" "F.Mask" "F.Paste")
			(net "Net_8677")
		)
		(pad "8" smd rect
			(at 0.750062 1.400048 180)
			(size 0.2286 0.6096)
			(layers "F.Cu" "F.Mask" "F.Paste")
			(net "Net_8676")
		)
		(pad "9" smd rect
			(at 1.400048 0.750062 90)
			(size 0.2286 0.6096)
			(layers "F.Cu" "F.Mask" "F.Paste")
			(net "P3V3_AUX")
		)
		(pad "10" smd rect
			(at 1.400048 0.249936 90)
			(size 0.2286 0.6096)
			(layers "F.Cu" "F.Mask" "F.Paste")
			(net "GND")
		)
		(pad "11" smd rect
			(at 1.400048 -0.249936 90)
			(size 0.2286 0.6096)
			(layers "F.Cu" "F.Mask" "F.Paste")
			(net "P12V_SSD14_R")
		)
		(pad "12" smd rect
			(at 1.400048 -0.750062 90)
			(size 0.2286 0.6096)
			(layers "F.Cu" "F.Mask" "F.Paste")
			(net "P12V_SSD14_VIN_N")
		)
		(pad "13" smd rect
			(at 0.750062 -1.400048 180)
			(size 0.2286 0.6096)
			(layers "F.Cu" "F.Mask" "F.Paste")
			(net "P12V_SSD14_VIN_P")
		)
		(pad "14" smd rect
			(at 0.249936 -1.400048 180)
			(size 0.2286 0.6096)
			(layers "F.Cu" "F.Mask" "F.Paste")
			(net "Net_8675")
		)
		(pad "15" smd rect
			(at -0.249936 -1.400048 180)
			(size 0.2286 0.6096)
			(layers "F.Cu" "F.Mask" "F.Paste")
			(net "Net_8674")
		)
		(pad "16" smd rect
			(at -0.750062 -1.400048 180)
			(size 0.2286 0.6096)
			(layers "F.Cu" "F.Mask" "F.Paste")
			(net "Net_8673")
		)
		(pad "TH" smd rect
			(at 0 0 180)
			(size 1.7018 1.7018)
			(layers "F.Cu" "F.Mask" "F.Paste")
			(net "GND")
		)
		(zone
			(layer "F.Cu")
			(hatch none 0.5)
			(connect_pads
				(clearance 0)
			)
			(min_thickness 0.25)
			(keepout
				(tracks not_allowed)
				(vias allowed)
				(pads allowed)
				(copperpour not_allowed)
				(footprints allowed)
			)
			(placement
				(enabled no)
				(sheetname "")
			)
			(fill
				(thermal_gap 0.5)
				(thermal_bridge_width 0.5)
				(island_removal_mode 0)
			)
			(polygon
				(pts
					(xy 424.190414 -46.4185) (xy 424.190414 -45.399452) (xy 422.101518 -45.399452) (xy 422.101518 -47.488348)
					(xy 424.190414 -47.488348) (xy 424.190414 -46.4439) (xy 424.047666 -46.4439) (xy 424.047666 -47.3456)
					(xy 422.244266 -47.3456) (xy 422.244266 -45.5422) (xy 424.047666 -45.5422) (xy 424.047666 -46.4185)
				)
			)
		)
	)
	(footprint ""
		(layer "F.Cu")
		(at 294.029892 -171.661328 180)
		(property "Reference" "C919"
			(at 0 0 180)
			(layer "F.SilkS")
			(hide yes)
			(effects
				(font
					(size 1.27 1.27)
				)
			)
		)
		(property "Value" ""
			(at 0 0 180)
			(layer "F.Fab")
			(effects
				(font
					(size 1.27 1.27)
				)
			)
		)
		(duplicate_pad_numbers_are_jumpers no)
		(fp_line
			(start 0.7874 0.4064)
			(end -0.7874 0.4064)
			(stroke
				(width 0.1524)
				(type default)
			)
			(layer "F.SilkS")
		)
		(fp_line
			(start 0.7874 -0.4064)
			(end 0.7874 0.4064)
			(stroke
				(width 0.1524)
				(type default)
			)
			(layer "F.SilkS")
		)
		(fp_line
			(start -0.7874 0.4064)
			(end -0.7874 -0.4064)
			(stroke
				(width 0.1524)
				(type default)
			)
			(layer "F.SilkS")
		)
		(fp_line
			(start -0.7874 -0.4064)
			(end 0.7874 -0.4064)
			(stroke
				(width 0.1524)
				(type default)
			)
			(layer "F.SilkS")
		)
		(fp_line
			(start 0.67945 0.3048)
			(end 0.120396 0.3048)
			(stroke
				(width 0.1)
				(type default)
			)
			(layer "F.Fab")
		)
		(fp_line
			(start 0.67945 -0.3048)
			(end 0.67945 0.3048)
			(stroke
				(width 0.1)
				(type default)
			)
			(layer "F.Fab")
		)
		(fp_line
			(start 0.12065 -0.2794)
			(end 0.12065 -0.3048)
			(stroke
				(width 0.1)
				(type default)
			)
			(layer "F.Fab")
		)
		(fp_line
			(start 0.12065 -0.3048)
			(end 0.67945 -0.3048)
			(stroke
				(width 0.1)
				(type default)
			)
			(layer "F.Fab")
		)
		(fp_line
			(start 0.120396 0.3048)
			(end 0.120396 0.2794)
			(stroke
				(width 0.1)
				(type default)
			)
			(layer "F.Fab")
		)
		(fp_line
			(start 0.120396 0.2794)
			(end -0.12065 0.2794)
			(stroke
				(width 0.1)
				(type default)
			)
			(layer "F.Fab")
		)
		(fp_line
			(start -0.12065 0.3048)
			(end -0.67945 0.3048)
			(stroke
				(width 0.1)
				(type default)
			)
			(layer "F.Fab")
		)
		(fp_line
			(start -0.12065 0.2794)
			(end -0.12065 0.3048)
			(stroke
				(width 0.1)
				(type default)
			)
			(layer "F.Fab")
		)
		(fp_line
			(start -0.12065 -0.2794)
			(end 0.12065 -0.2794)
			(stroke
				(width 0.1)
				(type default)
			)
			(layer "F.Fab")
		)
		(fp_line
			(start -0.12065 -0.305054)
			(end -0.12065 -0.2794)
			(stroke
				(width 0.1)
				(type default)
			)
			(layer "F.Fab")
		)
		(fp_line
			(start -0.67945 0.3048)
			(end -0.67945 -0.305054)
			(stroke
				(width 0.1)
				(type default)
			)
			(layer "F.Fab")
		)
		(fp_line
			(start -0.67945 -0.305054)
			(end -0.12065 -0.305054)
			(stroke
				(width 0.1)
				(type default)
			)
			(layer "F.Fab")
		)
		(pad "1" smd circle
			(at -0.40005 0 180)
			(size 0 0)
			(layers "F.Cu" "F.Mask" "F.Paste")
			(net "P3V3_NIC4")
		)
		(pad "2" smd circle
			(at 0.40005 0 180)
			(size 0 0)
			(layers "F.Cu" "F.Mask" "F.Paste")
			(net "GND")
		)
	)
	(footprint ""
		(layer "F.Cu")
		(at 247.16232 -254.141224 -90)
		(property "Reference" "C4352"
			(at 0 0 270)
			(layer "F.SilkS")
			(hide yes)
			(effects
				(font
					(size 1.27 1.27)
				)
			)
		)
		(property "Value" ""
			(at 0 0 270)
			(layer "F.Fab")
			(effects
				(font
					(size 1.27 1.27)
				)
			)
		)
		(duplicate_pad_numbers_are_jumpers no)
		(fp_line
			(start -1.2954 0.5842)
			(end -1.2954 -0.5842)
			(stroke
				(width 0.1524)
				(type default)
			)
			(layer "F.SilkS")
		)
		(fp_line
			(start 1.2954 0.5842)
			(end -1.2954 0.5842)
			(stroke
				(width 0.1524)
				(type default)
			)
			(layer "F.SilkS")
		)
		(fp_line
			(start -1.2954 -0.5842)
			(end 1.2954 -0.5842)
			(stroke
				(width 0.1524)
				(type default)
			)
			(layer "F.SilkS")
		)
		(fp_line
			(start 1.2954 -0.5842)
			(end 1.2954 0.5842)
			(stroke
				(width 0.1524)
				(type default)
			)
			(layer "F.SilkS")
		)
		(fp_line
			(start -0.8636 0.4572)
			(end -0.8636 0.4064)
			(stroke
				(width 0.1)
				(type default)
			)
			(layer "F.Fab")
		)
		(fp_line
			(start 0.8636 0.4572)
			(end -0.8636 0.4572)
			(stroke
				(width 0.1)
				(type default)
			)
			(layer "F.Fab")
		)
		(fp_line
			(start -1.1938 0.4064)
			(end -1.1938 -0.4064)
			(stroke
				(width 0.1)
				(type default)
			)
			(layer "F.Fab")
		)
		(fp_line
			(start -0.8636 0.4064)
			(end -1.1938 0.4064)
			(stroke
				(width 0.1)
				(type default)
			)
			(layer "F.Fab")
		)
		(fp_line
			(start 0.8636 0.4064)
			(end 0.8636 0.4572)
			(stroke
				(width 0.1)
				(type default)
			)
			(layer "F.Fab")
		)
		(fp_line
			(start 1.1938 0.4064)
			(end 0.8636 0.4064)
			(stroke
				(width 0.1)
				(type default)
			)
			(layer "F.Fab")
		)
		(fp_line
			(start -1.1938 -0.4064)
			(end -0.8636 -0.4064)
			(stroke
				(width 0.1)
				(type default)
			)
			(layer "F.Fab")
		)
		(fp_line
			(start -0.8636 -0.4064)
			(end -0.8636 -0.4572)
			(stroke
				(width 0.1)
				(type default)
			)
			(layer "F.Fab")
		)
		(fp_line
			(start 0.8636 -0.4064)
			(end 1.1938 -0.4064)
			(stroke
				(width 0.1)
				(type default)
			)
			(layer "F.Fab")
		)
		(fp_line
			(start 1.1938 -0.4064)
			(end 1.1938 0.4064)
			(stroke
				(width 0.1)
				(type default)
			)
			(layer "F.Fab")
		)
		(fp_line
			(start -0.8636 -0.4572)
			(end 0.8636 -0.4572)
			(stroke
				(width 0.1)
				(type default)
			)
			(layer "F.Fab")
		)
		(fp_line
			(start 0.8636 -0.4572)
			(end 0.8636 -0.4064)
			(stroke
				(width 0.1)
				(type default)
			)
			(layer "F.Fab")
		)
		(pad "1" smd rect
			(at -0.7366 0 180)
			(size 0.7112 0.8128)
			(layers "F.Cu" "F.Mask" "F.Paste")
			(net "P1V25_SERDES_VDDPLL_PEX2_C6")
		)
		(pad "2" smd rect
			(at 0.7366 0 180)
			(size 0.7112 0.8128)
			(layers "F.Cu" "F.Mask" "F.Paste")
			(net "GND")
		)
	)
	(footprint ""
		(layer "F.Cu")
		(at 350.380554 -91.788234)
		(property "Reference" "R1597"
			(at 0 0 0)
			(layer "F.SilkS")
			(hide yes)
			(effects
				(font
					(size 1.27 1.27)
				)
			)
		)
		(property "Value" ""
			(at 0 0 0)
			(layer "F.Fab")
			(effects
				(font
					(size 1.27 1.27)
				)
			)
		)
		(duplicate_pad_numbers_are_jumpers no)
		(fp_line
			(start -0.7874 -0.4064)
			(end 0.7874 -0.4064)
			(stroke
				(width 0.1524)
				(type default)
			)
			(layer "F.SilkS")
		)
		(fp_line
			(start -0.7874 0.4064)
			(end -0.7874 -0.4064)
			(stroke
				(width 0.1524)
				(type default)
			)
			(layer "F.SilkS")
		)
		(fp_line
			(start 0.7874 -0.4064)
			(end 0.7874 0.4064)
			(stroke
				(width 0.1524)
				(type default)
			)
			(layer "F.SilkS")
		)
		(fp_line
			(start 0.7874 0.4064)
			(end -0.7874 0.4064)
			(stroke
				(width 0.1524)
				(type default)
			)
			(layer "F.SilkS")
		)
		(fp_line
			(start -0.67945 -0.305054)
			(end -0.12065 -0.305054)
			(stroke
				(width 0.1)
				(type default)
			)
			(layer "F.Fab")
		)
		(fp_line
			(start -0.67945 0.3048)
			(end -0.67945 -0.305054)
			(stroke
				(width 0.1)
				(type default)
			)
			(layer "F.Fab")
		)
		(fp_line
			(start -0.12065 -0.305054)
			(end -0.12065 -0.2794)
			(stroke
				(width 0.1)
				(type default)
			)
			(layer "F.Fab")
		)
		(fp_line
			(start -0.12065 -0.2794)
			(end 0.12065 -0.2794)
			(stroke
				(width 0.1)
				(type default)
			)
			(layer "F.Fab")
		)
		(fp_line
			(start -0.12065 0.2794)
			(end -0.12065 0.3048)
			(stroke
				(width 0.1)
				(type default)
			)
			(layer "F.Fab")
		)
		(fp_line
			(start -0.12065 0.3048)
			(end -0.67945 0.3048)
			(stroke
				(width 0.1)
				(type default)
			)
			(layer "F.Fab")
		)
		(fp_line
			(start 0.120396 0.2794)
			(end -0.12065 0.2794)
			(stroke
				(width 0.1)
				(type default)
			)
			(layer "F.Fab")
		)
		(fp_line
			(start 0.120396 0.3048)
			(end 0.120396 0.2794)
			(stroke
				(width 0.1)
				(type default)
			)
			(layer "F.Fab")
		)
		(fp_line
			(start 0.12065 -0.3048)
			(end 0.67945 -0.3048)
			(stroke
				(width 0.1)
				(type default)
			)
			(layer "F.Fab")
		)
		(fp_line
			(start 0.12065 -0.2794)
			(end 0.12065 -0.3048)
			(stroke
				(width 0.1)
				(type default)
			)
			(layer "F.Fab")
		)
		(fp_line
			(start 0.67945 -0.3048)
			(end 0.67945 0.3048)
			(stroke
				(width 0.1)
				(type default)
			)
			(layer "F.Fab")
		)
		(fp_line
			(start 0.67945 0.3048)
			(end 0.120396 0.3048)
			(stroke
				(width 0.1)
				(type default)
			)
			(layer "F.Fab")
		)
		(pad "1" smd circle
			(at -0.40005 0)
			(size 0 0)
			(layers "F.Cu" "F.Mask" "F.Paste")
			(net "P3V3_AUX")
		)
		(pad "2" smd circle
			(at 0.40005 0)
			(size 0 0)
			(layers "F.Cu" "F.Mask" "F.Paste")
			(net "BIC_I2C9_SSD_MUX1_A0")
		)
	)
	(footprint ""
		(layer "F.Cu")
		(at 277.198582 -343.952322 90)
		(property "Reference" "C605"
			(at 0 0 90)
			(layer "F.SilkS")
			(hide yes)
			(effects
				(font
					(size 1.27 1.27)
				)
			)
		)
		(property "Value" ""
			(at 0 0 90)
			(layer "F.Fab")
			(effects
				(font
					(size 1.27 1.27)
				)
			)
		)
		(duplicate_pad_numbers_are_jumpers no)
		(fp_line
			(start 0.299974 -0.150114)
			(end 0.299974 0.150114)
			(stroke
				(width 0.1)
				(type default)
			)
			(layer "F.Fab")
		)
		(fp_line
			(start -0.299974 -0.150114)
			(end 0.299974 -0.150114)
			(stroke
				(width 0.1)
				(type default)
			)
			(layer "F.Fab")
		)
		(fp_line
			(start 0.299974 0.150114)
			(end -0.299974 0.150114)
			(stroke
				(width 0.1)
				(type default)
			)
			(layer "F.Fab")
		)
		(fp_line
			(start -0.299974 0.150114)
			(end -0.299974 -0.150114)
			(stroke
				(width 0.1)
				(type default)
			)
			(layer "F.Fab")
		)
		(pad "1" smd rect
			(at -0.2667 0 90)
			(size 0.3048 0.381)
			(layers "F.Cu" "F.Mask" "F.Paste")
			(net "P5E_PEX2_STN7_TX_DP<116>")
		)
		(pad "2" smd rect
			(at 0.2667 0 90)
			(size 0.3048 0.381)
			(layers "F.Cu" "F.Mask" "F.Paste")
			(net "P5E_PEX2_STN7_TX_C_DP<116>")
		)
	)
	(footprint ""
		(layer "F.Cu")
		(at 257.521964 -369.900962 90)
		(property "Reference" "PQ6604"
			(at -8.228584 -2.05994 0)
			(unlocked yes)
			(layer "F.SilkS")
			(effects
				(font
					(size 0.7874 0.5842)
					(thickness 0.1524)
				)
				(justify left)
			)
		)
		(property "Value" ""
			(at 0 0 90)
			(layer "F.Fab")
			(effects
				(font
					(size 1.27 1.27)
				)
			)
		)
		(duplicate_pad_numbers_are_jumpers no)
		(fp_line
			(start 2.350008 -2.649982)
			(end 2.350008 -2.4892)
			(stroke
				(width 0.1524)
				(type default)
			)
			(layer "F.SilkS")
		)
		(fp_line
			(start -2.350008 -2.649982)
			(end 2.350008 -2.649982)
			(stroke
				(width 0.1524)
				(type default)
			)
			(layer "F.SilkS")
		)
		(fp_line
			(start -2.350008 -2.4384)
			(end -2.350008 -2.649982)
			(stroke
				(width 0.1524)
				(type default)
			)
			(layer "F.SilkS")
		)
		(fp_line
			(start 2.350008 2.4892)
			(end 2.350008 2.649982)
			(stroke
				(width 0.1524)
				(type default)
			)
			(layer "F.SilkS")
		)
		(fp_line
			(start 2.350008 2.649982)
			(end -2.350008 2.649982)
			(stroke
				(width 0.1524)
				(type default)
			)
			(layer "F.SilkS")
		)
		(fp_line
			(start -2.350008 2.649982)
			(end -2.350008 2.413)
			(stroke
				(width 0.1524)
				(type default)
			)
			(layer "F.SilkS")
		)
		(fp_poly
			(pts
				(xy -3.717544 -1.905) (xy -4.758944 -2.3241) (xy -4.758944 -1.524)
			)
			(stroke
				(width 0)
				(type default)
			)
			(fill yes)
			(layer "F.SilkS")
		)
		(fp_line
			(start 2.350008 -2.649982)
			(end 2.350008 2.649982)
			(stroke
				(width 0.1)
				(type default)
			)
			(layer "F.Fab")
		)
		(fp_line
			(start -2.350008 -2.649982)
			(end 2.350008 -2.649982)
			(stroke
				(width 0.1)
				(type default)
			)
			(layer "F.Fab")
		)
		(fp_line
			(start 2.350008 2.649982)
			(end -2.350008 2.649982)
			(stroke
				(width 0.1)
				(type default)
			)
			(layer "F.Fab")
		)
		(fp_line
			(start -2.350008 2.649982)
			(end -2.350008 -2.649982)
			(stroke
				(width 0.1)
				(type default)
			)
			(layer "F.Fab")
		)
		(fp_poly
			(pts
				(xy -3.717544 -1.905) (xy -4.758944 -2.3241) (xy -4.758944 -1.524)
			)
			(stroke
				(width 0)
				(type default)
			)
			(fill yes)
			(layer "F.Fab")
		)
		(pad "1" smd rect
			(at -2.999994 -1.905)
			(size 0.7112 1.1684)
			(layers "F.Cu" "F.Mask" "F.Paste")
			(net "P12V_AUX")
		)
		(pad "2" smd rect
			(at -2.999994 -0.635)
			(size 0.7112 1.1684)
			(layers "F.Cu" "F.Mask" "F.Paste")
			(net "P12V_AUX")
		)
		(pad "3" smd rect
			(at -2.999994 0.635)
			(size 0.7112 1.1684)
			(layers "F.Cu" "F.Mask" "F.Paste")
			(net "P12V_AUX")
		)
		(pad "4" smd rect
			(at -2.999994 1.905)
			(size 0.7112 1.1684)
			(layers "F.Cu" "F.Mask" "F.Paste")
			(net "HS_GATE2_R_3")
		)
		(pad "5" smd circle
			(at 0.925068 0)
			(size 0 0)
			(layers "F.Cu" "F.Mask" "F.Paste")
			(net "P12V_STBY_R2")
		)
		(zone
			(layer "F.Cu")
			(hatch none 0.5)
			(connect_pads
				(clearance 0)
			)
			(min_thickness 0.25)
			(keepout
				(tracks not_allowed)
				(vias allowed)
				(pads allowed)
				(copperpour not_allowed)
				(footprints allowed)
			)
			(placement
				(enabled no)
				(sheetname "")
			)
			(fill
				(thermal_gap 0.5)
				(thermal_bridge_width 0.5)
				(island_removal_mode 0)
			)
			(polygon
				(pts
					(xy 255.362964 -368.453162) (xy 259.680964 -368.453162) (xy 260.163564 -368.453162) (xy 260.163564 -367.551462)
					(xy 254.880364 -367.551462) (xy 254.880364 -368.453162)
				)
			)
		)
	)
	(footprint ""
		(layer "F.Cu")
		(at 188.079888 -127.700024 180)
		(property "Reference" "J23"
			(at 5.351018 -34.634424 90)
			(unlocked yes)
			(layer "F.SilkS")
			(effects
				(font
					(size 0.7874 0.5842)
					(thickness 0.1524)
				)
				(justify left)
			)
		)
		(property "Value" ""
			(at 0 0 180)
			(layer "F.Fab")
			(effects
				(font
					(size 1.27 1.27)
				)
			)
		)
		(duplicate_pad_numbers_are_jumpers no)
		(fp_line
			(start 4.507484 -21.5265)
			(end 4.507484 -34.720022)
			(stroke
				(width 0.1524)
				(type default)
			)
			(layer "F.SilkS")
		)
		(fp_line
			(start 4.507484 -34.720022)
			(end 2.6162 -34.720022)
			(stroke
				(width 0.1524)
				(type default)
			)
			(layer "F.SilkS")
		)
		(fp_line
			(start 2.6035 34.720022)
			(end 4.507484 34.720022)
			(stroke
				(width 0.1524)
				(type default)
			)
			(layer "F.SilkS")
		)
		(fp_line
			(start -0.57658 -34.720022)
			(end -4.507484 -34.720022)
			(stroke
				(width 0.1524)
				(type default)
			)
			(layer "F.SilkS")
		)
		(fp_line
			(start -4.507484 34.720022)
			(end -0.5588 34.720022)
			(stroke
				(width 0.1524)
				(type default)
			)
			(layer "F.SilkS")
		)
		(fp_poly
			(pts
				(xy 5.735574 -17.957038) (xy 5.735574 -18.973038) (xy 4.719574 -18.465038)
			)
			(stroke
				(width 0)
				(type default)
			)
			(fill yes)
			(layer "F.SilkS")
		)
		(fp_line
			(start 4.507484 34.720022)
			(end 4.507484 -34.720022)
			(stroke
				(width 0.1)
				(type default)
			)
			(layer "F.Fab")
		)
		(fp_line
			(start 4.507484 -34.720022)
			(end -4.507484 -34.720022)
			(stroke
				(width 0.1)
				(type default)
			)
			(layer "F.Fab")
		)
		(fp_line
			(start -4.507484 34.720022)
			(end 4.507484 34.720022)
			(stroke
				(width 0.1)
				(type default)
			)
			(layer "F.Fab")
		)
		(fp_line
			(start -4.507484 -34.720022)
			(end -4.507484 34.720022)
			(stroke
				(width 0.1)
				(type default)
			)
			(layer "F.Fab")
		)
		(fp_poly
			(pts
				(xy 5.735574 -17.957038) (xy 5.735574 -18.973038) (xy 4.719574 -18.465038)
			)
			(stroke
				(width 0)
				(type default)
			)
			(fill yes)
			(layer "F.Fab")
		)
		(pad "" np_thru_hole circle
			(at -0.727456 -32.485076 180)
			(size 1.1176 1.1176)
			(drill 1.1176)
			(layers "*.Cu" "*.Mask")
			(clearance 0.381)
			(thermal_gap 0.381)
		)
		(pad "" np_thru_hole circle
			(at 1.022604 32.485076 180)
			(size 1.1176 1.1176)
			(drill 1.1176)
			(layers "*.Cu" "*.Mask")
			(clearance 0.381)
			(thermal_gap 0.381)
		)
		(pad "A1" smd rect
			(at 3.322574 -18.465038 90)
			(size 0.3556 1.2192)
			(layers "F.Cu" "F.Mask" "F.Paste")
			(net "GND")
		)
		(pad "A2" smd rect
			(at 3.322574 -17.86509 90)
			(size 0.3556 1.2192)
			(layers "F.Cu" "F.Mask" "F.Paste")
			(net "GND")
		)
		(pad "A3" smd rect
			(at 3.322574 -17.264888 90)
			(size 0.3556 1.2192)
			(layers "F.Cu" "F.Mask" "F.Paste")
			(net "GND")
		)
		(pad "A4" smd rect
			(at 3.322574 -16.66494 90)
			(size 0.3556 1.2192)
			(layers "F.Cu" "F.Mask" "F.Paste")
			(net "GND")
		)
		(pad "A5" smd rect
			(at 3.322574 -16.064992 90)
			(size 0.3556 1.2192)
			(layers "F.Cu" "F.Mask" "F.Paste")
			(net "GND")
		)
		(pad "A6" smd rect
			(at 3.322574 -15.465044 90)
			(size 0.3556 1.2192)
			(layers "F.Cu" "F.Mask" "F.Paste")
			(net "GND")
		)
		(pad "A7" smd rect
			(at 3.322574 -14.865096 90)
			(size 0.3556 1.2192)
			(layers "F.Cu" "F.Mask" "F.Paste")
			(net "SMB_NIC3_R_SCL")
		)
		(pad "A8" smd rect
			(at 3.322574 -14.264894 90)
			(size 0.3556 1.2192)
			(layers "F.Cu" "F.Mask" "F.Paste")
			(net "SMB_NIC3_R_SDA")
		)
		(pad "A9" smd rect
			(at 3.322574 -13.664946 90)
			(size 0.3556 1.2192)
			(layers "F.Cu" "F.Mask" "F.Paste")
			(net "RST_SMB_NIC3_MUX_ISO_R_N")
		)
		(pad "A10" smd rect
			(at 3.322574 -13.064998 90)
			(size 0.3556 1.2192)
			(layers "F.Cu" "F.Mask" "F.Paste")
			(net "GND")
		)
		(pad "A11" smd rect
			(at 3.322574 -12.46505 90)
			(size 0.3556 1.2192)
			(layers "F.Cu" "F.Mask" "F.Paste")
			(net "RST_NIC3_PERST1_R_N")
		)
		(pad "A12" smd rect
			(at 3.322574 -11.865102 90)
			(size 0.3556 1.2192)
			(layers "F.Cu" "F.Mask" "F.Paste")
			(net "PRSNTB2_NIC3_N")
		)
		(pad "A13" smd rect
			(at 3.322574 -11.2649 90)
			(size 0.3556 1.2192)
			(layers "F.Cu" "F.Mask" "F.Paste")
			(net "GND")
		)
		(pad "A14" smd rect
			(at 3.322574 -10.664952 90)
			(size 0.3556 1.2192)
			(layers "F.Cu" "F.Mask" "F.Paste")
			(net "Net_2614")
		)
		(pad "A15" smd rect
			(at 3.322574 -10.065004 90)
			(size 0.3556 1.2192)
			(layers "F.Cu" "F.Mask" "F.Paste")
			(net "Net_2617")
		)
		(pad "A16" smd rect
			(at 3.322574 -9.465056 90)
			(size 0.3556 1.2192)
			(layers "F.Cu" "F.Mask" "F.Paste")
			(net "GND")
		)
		(pad "A17" smd rect
			(at 3.322574 -8.865108 90)
			(size 0.3556 1.2192)
			(layers "F.Cu" "F.Mask" "F.Paste")
			(net "P5E_PEX1_STN0_RX_DN<0>")
		)
		(pad "A18" smd rect
			(at 3.322574 -8.264906 90)
			(size 0.3556 1.2192)
			(layers "F.Cu" "F.Mask" "F.Paste")
			(net "P5E_PEX1_STN0_RX_DP<0>")
		)
		(pad "A19" smd rect
			(at 3.322574 -7.664958 90)
			(size 0.3556 1.2192)
			(layers "F.Cu" "F.Mask" "F.Paste")
			(net "GND")
		)
		(pad "A20" smd rect
			(at 3.322574 -7.06501 90)
			(size 0.3556 1.2192)
			(layers "F.Cu" "F.Mask" "F.Paste")
			(net "P5E_PEX1_STN0_RX_DN<1>")
		)
		(pad "A21" smd rect
			(at 3.322574 -6.465062 90)
			(size 0.3556 1.2192)
			(layers "F.Cu" "F.Mask" "F.Paste")
			(net "P5E_PEX1_STN0_RX_DP<1>")
		)
		(pad "A22" smd rect
			(at 3.322574 -5.865114 90)
			(size 0.3556 1.2192)
			(layers "F.Cu" "F.Mask" "F.Paste")
			(net "GND")
		)
		(pad "A23" smd rect
			(at 3.322574 -5.264912 90)
			(size 0.3556 1.2192)
			(layers "F.Cu" "F.Mask" "F.Paste")
			(net "P5E_PEX1_STN0_RX_DN<2>")
		)
		(pad "A24" smd rect
			(at 3.322574 -4.664964 90)
			(size 0.3556 1.2192)
			(layers "F.Cu" "F.Mask" "F.Paste")
			(net "P5E_PEX1_STN0_RX_DP<2>")
		)
		(pad "A25" smd rect
			(at 3.322574 -4.065016 90)
			(size 0.3556 1.2192)
			(layers "F.Cu" "F.Mask" "F.Paste")
			(net "GND")
		)
		(pad "A26" smd rect
			(at 3.322574 -3.465068 90)
			(size 0.3556 1.2192)
			(layers "F.Cu" "F.Mask" "F.Paste")
			(net "P5E_PEX1_STN0_RX_DN<3>")
		)
		(pad "A27" smd rect
			(at 3.322574 -2.86512 90)
			(size 0.3556 1.2192)
			(layers "F.Cu" "F.Mask" "F.Paste")
			(net "P5E_PEX1_STN0_RX_DP<3>")
		)
		(pad "A28" smd rect
			(at 3.322574 -2.264918 90)
			(size 0.3556 1.2192)
			(layers "F.Cu" "F.Mask" "F.Paste")
			(net "GND")
		)
		(pad "A29" smd rect
			(at 3.322574 1.74498 90)
			(size 0.3556 1.2192)
			(layers "F.Cu" "F.Mask" "F.Paste")
			(net "GND")
		)
		(pad "A30" smd rect
			(at 3.322574 2.344928 90)
			(size 0.3556 1.2192)
			(layers "F.Cu" "F.Mask" "F.Paste")
			(net "P5E_PEX1_STN0_RX_DN<4>")
		)
		(pad "A31" smd rect
			(at 3.322574 2.944876 90)
			(size 0.3556 1.2192)
			(layers "F.Cu" "F.Mask" "F.Paste")
			(net "P5E_PEX1_STN0_RX_DP<4>")
		)
		(pad "A32" smd rect
			(at 3.322574 3.545078 90)
			(size 0.3556 1.2192)
			(layers "F.Cu" "F.Mask" "F.Paste")
			(net "GND")
		)
		(pad "A33" smd rect
			(at 3.322574 4.145026 90)
			(size 0.3556 1.2192)
			(layers "F.Cu" "F.Mask" "F.Paste")
			(net "P5E_PEX1_STN0_RX_DN<5>")
		)
		(pad "A34" smd rect
			(at 3.322574 4.744974 90)
			(size 0.3556 1.2192)
			(layers "F.Cu" "F.Mask" "F.Paste")
			(net "P5E_PEX1_STN0_RX_DP<5>")
		)
		(pad "A35" smd rect
			(at 3.322574 5.344922 90)
			(size 0.3556 1.2192)
			(layers "F.Cu" "F.Mask" "F.Paste")
			(net "GND")
		)
		(pad "A36" smd rect
			(at 3.322574 5.945124 90)
			(size 0.3556 1.2192)
			(layers "F.Cu" "F.Mask" "F.Paste")
			(net "P5E_PEX1_STN0_RX_DN<6>")
		)
		(pad "A37" smd rect
			(at 3.322574 6.545072 90)
			(size 0.3556 1.2192)
			(layers "F.Cu" "F.Mask" "F.Paste")
			(net "P5E_PEX1_STN0_RX_DP<6>")
		)
		(pad "A38" smd rect
			(at 3.322574 7.14502 90)
			(size 0.3556 1.2192)
			(layers "F.Cu" "F.Mask" "F.Paste")
			(net "GND")
		)
		(pad "A39" smd rect
			(at 3.322574 7.744968 90)
			(size 0.3556 1.2192)
			(layers "F.Cu" "F.Mask" "F.Paste")
			(net "P5E_PEX1_STN0_RX_DN<7>")
		)
		(pad "A40" smd rect
			(at 3.322574 8.344916 90)
			(size 0.3556 1.2192)
			(layers "F.Cu" "F.Mask" "F.Paste")
			(net "P5E_PEX1_STN0_RX_DP<7>")
		)
		(pad "A41" smd rect
			(at 3.322574 8.945118 90)
			(size 0.3556 1.2192)
			(layers "F.Cu" "F.Mask" "F.Paste")
			(net "GND")
		)
		(pad "A42" smd rect
			(at 3.322574 9.545066 90)
			(size 0.3556 1.2192)
			(layers "F.Cu" "F.Mask" "F.Paste")
			(net "PRSNTB1_NIC3_N")
		)
		(pad "A43" smd rect
			(at 3.322574 14.454886 90)
			(size 0.3556 1.2192)
			(layers "F.Cu" "F.Mask" "F.Paste")
			(net "GND")
		)
		(pad "A44" smd rect
			(at 3.322574 15.055088 90)
			(size 0.3556 1.2192)
			(layers "F.Cu" "F.Mask" "F.Paste")
			(net "P5E_PEX1_STN0_RX_DN<8>")
		)
		(pad "A45" smd rect
			(at 3.322574 15.655036 90)
			(size 0.3556 1.2192)
			(layers "F.Cu" "F.Mask" "F.Paste")
			(net "P5E_PEX1_STN0_RX_DP<8>")
		)
		(pad "A46" smd rect
			(at 3.322574 16.254984 90)
			(size 0.3556 1.2192)
			(layers "F.Cu" "F.Mask" "F.Paste")
			(net "GND")
		)
		(pad "A47" smd rect
			(at 3.322574 16.854932 90)
			(size 0.3556 1.2192)
			(layers "F.Cu" "F.Mask" "F.Paste")
			(net "P5E_PEX1_STN0_RX_DN<9>")
		)
		(pad "A48" smd rect
			(at 3.322574 17.45488 90)
			(size 0.3556 1.2192)
			(layers "F.Cu" "F.Mask" "F.Paste")
			(net "P5E_PEX1_STN0_RX_DP<9>")
		)
		(pad "A49" smd rect
			(at 3.322574 18.055082 90)
			(size 0.3556 1.2192)
			(layers "F.Cu" "F.Mask" "F.Paste")
			(net "GND")
		)
		(pad "A50" smd rect
			(at 3.322574 18.65503 90)
			(size 0.3556 1.2192)
			(layers "F.Cu" "F.Mask" "F.Paste")
			(net "P5E_PEX1_STN0_RX_DN<10>")
		)
		(pad "A51" smd rect
			(at 3.322574 19.254978 90)
			(size 0.3556 1.2192)
			(layers "F.Cu" "F.Mask" "F.Paste")
			(net "P5E_PEX1_STN0_RX_DP<10>")
		)
		(pad "A52" smd rect
			(at 3.322574 19.854926 90)
			(size 0.3556 1.2192)
			(layers "F.Cu" "F.Mask" "F.Paste")
			(net "GND")
		)
		(pad "A53" smd rect
			(at 3.322574 20.455128 90)
			(size 0.3556 1.2192)
			(layers "F.Cu" "F.Mask" "F.Paste")
			(net "P5E_PEX1_STN0_RX_DN<11>")
		)
		(pad "A54" smd rect
			(at 3.322574 21.055076 90)
			(size 0.3556 1.2192)
			(layers "F.Cu" "F.Mask" "F.Paste")
			(net "P5E_PEX1_STN0_RX_DP<11>")
		)
		(pad "A55" smd rect
			(at 3.322574 21.655024 90)
			(size 0.3556 1.2192)
			(layers "F.Cu" "F.Mask" "F.Paste")
			(net "GND")
		)
		(pad "A56" smd rect
			(at 3.322574 22.254972 90)
			(size 0.3556 1.2192)
			(layers "F.Cu" "F.Mask" "F.Paste")
			(net "P5E_PEX1_STN0_RX_DN<12>")
		)
		(pad "A57" smd rect
			(at 3.322574 22.85492 90)
			(size 0.3556 1.2192)
			(layers "F.Cu" "F.Mask" "F.Paste")
			(net "P5E_PEX1_STN0_RX_DP<12>")
		)
		(pad "A58" smd rect
			(at 3.322574 23.455122 90)
			(size 0.3556 1.2192)
			(layers "F.Cu" "F.Mask" "F.Paste")
			(net "GND")
		)
		(pad "A59" smd rect
			(at 3.322574 24.05507 90)
			(size 0.3556 1.2192)
			(layers "F.Cu" "F.Mask" "F.Paste")
			(net "P5E_PEX1_STN0_RX_DN<13>")
		)
		(pad "A60" smd rect
			(at 3.322574 24.655018 90)
			(size 0.3556 1.2192)
			(layers "F.Cu" "F.Mask" "F.Paste")
			(net "P5E_PEX1_STN0_RX_DP<13>")
		)
		(pad "A61" smd rect
			(at 3.322574 25.254966 90)
			(size 0.3556 1.2192)
			(layers "F.Cu" "F.Mask" "F.Paste")
			(net "GND")
		)
		(pad "A62" smd rect
			(at 3.322574 25.854914 90)
			(size 0.3556 1.2192)
			(layers "F.Cu" "F.Mask" "F.Paste")
			(net "P5E_PEX1_STN0_RX_DN<14>")
		)
		(pad "A63" smd rect
			(at 3.322574 26.455116 90)
			(size 0.3556 1.2192)
			(layers "F.Cu" "F.Mask" "F.Paste")
			(net "P5E_PEX1_STN0_RX_DP<14>")
		)
		(pad "A64" smd rect
			(at 3.322574 27.055064 90)
			(size 0.3556 1.2192)
			(layers "F.Cu" "F.Mask" "F.Paste")
			(net "GND")
		)
		(pad "A65" smd rect
			(at 3.322574 27.655012 90)
			(size 0.3556 1.2192)
			(layers "F.Cu" "F.Mask" "F.Paste")
			(net "P5E_PEX1_STN0_RX_DN<15>")
		)
		(pad "A66" smd rect
			(at 3.322574 28.25496 90)
			(size 0.3556 1.2192)
			(layers "F.Cu" "F.Mask" "F.Paste")
			(net "P5E_PEX1_STN0_RX_DP<15>")
		)
		(pad "A67" smd rect
			(at 3.322574 28.854908 90)
			(size 0.3556 1.2192)
			(layers "F.Cu" "F.Mask" "F.Paste")
			(net "GND")
		)
		(pad "A68" smd rect
			(at 3.322574 29.45511 90)
			(size 0.3556 1.2192)
			(layers "F.Cu" "F.Mask" "F.Paste")
			(net "Net_2622")
		)
		(pad "A69" smd rect
			(at 3.322574 30.055058 90)
			(size 0.3556 1.2192)
			(layers "F.Cu" "F.Mask" "F.Paste")
			(net "Net_2623")
		)
		(pad "A70" smd rect
			(at 3.322574 30.655006 90)
			(size 0.3556 1.2192)
			(layers "F.Cu" "F.Mask" "F.Paste")
			(net "NIC3_PWRBRK_R_N")
		)
		(pad "B1" smd rect
			(at -1.27762 -18.465038 90)
			(size 0.3556 1.2192)
			(layers "F.Cu" "F.Mask" "F.Paste")
			(net "P12V_NIC3")
		)
		(pad "B2" smd rect
			(at -1.27762 -17.86509 90)
			(size 0.3556 1.2192)
			(layers "F.Cu" "F.Mask" "F.Paste")
			(net "P12V_NIC3")
		)
		(pad "B3" smd rect
			(at -1.27762 -17.264888 90)
			(size 0.3556 1.2192)
			(layers "F.Cu" "F.Mask" "F.Paste")
			(net "P12V_NIC3")
		)
		(pad "B4" smd rect
			(at -1.27762 -16.66494 90)
			(size 0.3556 1.2192)
			(layers "F.Cu" "F.Mask" "F.Paste")
			(net "P12V_NIC3")
		)
		(pad "B5" smd rect
			(at -1.27762 -16.064992 90)
			(size 0.3556 1.2192)
			(layers "F.Cu" "F.Mask" "F.Paste")
			(net "P12V_NIC3")
		)
		(pad "B6" smd rect
			(at -1.27762 -15.465044 90)
			(size 0.3556 1.2192)
			(layers "F.Cu" "F.Mask" "F.Paste")
			(net "P12V_NIC3")
		)
		(pad "B7" smd rect
			(at -1.27762 -14.865096 90)
			(size 0.3556 1.2192)
			(layers "F.Cu" "F.Mask" "F.Paste")
			(net "NIC3_BIF0_N")
		)
		(pad "B8" smd rect
			(at -1.27762 -14.264894 90)
			(size 0.3556 1.2192)
			(layers "F.Cu" "F.Mask" "F.Paste")
			(net "NIC3_BIF1_N")
		)
		(pad "B9" smd rect
			(at -1.27762 -13.664946 90)
			(size 0.3556 1.2192)
			(layers "F.Cu" "F.Mask" "F.Paste")
			(net "NIC3_BIF2_N")
		)
		(pad "B10" smd rect
			(at -1.27762 -13.064998 90)
			(size 0.3556 1.2192)
			(layers "F.Cu" "F.Mask" "F.Paste")
			(net "RST_NIC3_PERST0_R_N")
		)
		(pad "B11" smd rect
			(at -1.27762 -12.46505 90)
			(size 0.3556 1.2192)
			(layers "F.Cu" "F.Mask" "F.Paste")
			(net "P3V3_NIC3")
		)
		(pad "B12" smd rect
			(at -1.27762 -11.865102 90)
			(size 0.3556 1.2192)
			(layers "F.Cu" "F.Mask" "F.Paste")
			(net "NIC3_AUX_PWR_EN_R")
		)
		(pad "B13" smd rect
			(at -1.27762 -11.2649 90)
			(size 0.3556 1.2192)
			(layers "F.Cu" "F.Mask" "F.Paste")
			(net "GND")
		)
		(pad "B14" smd rect
			(at -1.27762 -10.664952 90)
			(size 0.3556 1.2192)
			(layers "F.Cu" "F.Mask" "F.Paste")
			(net "CLK_100M_DB2000QL_NIC3_R_DN")
		)
		(pad "B15" smd rect
			(at -1.27762 -10.065004 90)
			(size 0.3556 1.2192)
			(layers "F.Cu" "F.Mask" "F.Paste")
			(net "CLK_100M_DB2000QL_NIC3_R_DP")
		)
		(pad "B16" smd rect
			(at -1.27762 -9.465056 90)
			(size 0.3556 1.2192)
			(layers "F.Cu" "F.Mask" "F.Paste")
			(net "GND")
		)
		(pad "B17" smd rect
			(at -1.27762 -8.865108 90)
			(size 0.3556 1.2192)
			(layers "F.Cu" "F.Mask" "F.Paste")
			(net "P5E_PEX1_STN0_TX_C_DN<0>")
		)
		(pad "B18" smd rect
			(at -1.27762 -8.264906 90)
			(size 0.3556 1.2192)
			(layers "F.Cu" "F.Mask" "F.Paste")
			(net "P5E_PEX1_STN0_TX_C_DP<0>")
		)
		(pad "B19" smd rect
			(at -1.27762 -7.664958 90)
			(size 0.3556 1.2192)
			(layers "F.Cu" "F.Mask" "F.Paste")
			(net "GND")
		)
		(pad "B20" smd rect
			(at -1.27762 -7.06501 90)
			(size 0.3556 1.2192)
			(layers "F.Cu" "F.Mask" "F.Paste")
			(net "P5E_PEX1_STN0_TX_C_DN<1>")
		)
		(pad "B21" smd rect
			(at -1.27762 -6.465062 90)
			(size 0.3556 1.2192)
			(layers "F.Cu" "F.Mask" "F.Paste")
			(net "P5E_PEX1_STN0_TX_C_DP<1>")
		)
		(pad "B22" smd rect
			(at -1.27762 -5.865114 90)
			(size 0.3556 1.2192)
			(layers "F.Cu" "F.Mask" "F.Paste")
			(net "GND")
		)
		(pad "B23" smd rect
			(at -1.27762 -5.264912 90)
			(size 0.3556 1.2192)
			(layers "F.Cu" "F.Mask" "F.Paste")
			(net "P5E_PEX1_STN0_TX_C_DN<2>")
		)
		(pad "B24" smd rect
			(at -1.27762 -4.664964 90)
			(size 0.3556 1.2192)
			(layers "F.Cu" "F.Mask" "F.Paste")
			(net "P5E_PEX1_STN0_TX_C_DP<2>")
		)
		(pad "B25" smd rect
			(at -1.27762 -4.065016 90)
			(size 0.3556 1.2192)
			(layers "F.Cu" "F.Mask" "F.Paste")
			(net "GND")
		)
		(pad "B26" smd rect
			(at -1.27762 -3.465068 90)
			(size 0.3556 1.2192)
			(layers "F.Cu" "F.Mask" "F.Paste")
			(net "P5E_PEX1_STN0_TX_C_DN<3>")
		)
		(pad "B27" smd rect
			(at -1.27762 -2.86512 90)
			(size 0.3556 1.2192)
			(layers "F.Cu" "F.Mask" "F.Paste")
			(net "P5E_PEX1_STN0_TX_C_DP<3>")
		)
		(pad "B28" smd rect
			(at -1.27762 -2.264918 90)
			(size 0.3556 1.2192)
			(layers "F.Cu" "F.Mask" "F.Paste")
			(net "GND")
		)
		(pad "B29" smd rect
			(at -1.27762 1.74498 90)
			(size 0.3556 1.2192)
			(layers "F.Cu" "F.Mask" "F.Paste")
			(net "GND")
		)
		(pad "B30" smd rect
			(at -1.27762 2.344928 90)
			(size 0.3556 1.2192)
			(layers "F.Cu" "F.Mask" "F.Paste")
			(net "P5E_PEX1_STN0_TX_C_DN<4>")
		)
		(pad "B31" smd rect
			(at -1.27762 2.944876 90)
			(size 0.3556 1.2192)
			(layers "F.Cu" "F.Mask" "F.Paste")
			(net "P5E_PEX1_STN0_TX_C_DP<4>")
		)
		(pad "B32" smd rect
			(at -1.27762 3.545078 90)
			(size 0.3556 1.2192)
			(layers "F.Cu" "F.Mask" "F.Paste")
			(net "GND")
		)
		(pad "B33" smd rect
			(at -1.27762 4.145026 90)
			(size 0.3556 1.2192)
			(layers "F.Cu" "F.Mask" "F.Paste")
			(net "P5E_PEX1_STN0_TX_C_DN<5>")
		)
		(pad "B34" smd rect
			(at -1.27762 4.744974 90)
			(size 0.3556 1.2192)
			(layers "F.Cu" "F.Mask" "F.Paste")
			(net "P5E_PEX1_STN0_TX_C_DP<5>")
		)
		(pad "B35" smd rect
			(at -1.27762 5.344922 90)
			(size 0.3556 1.2192)
			(layers "F.Cu" "F.Mask" "F.Paste")
			(net "GND")
		)
		(pad "B36" smd rect
			(at -1.27762 5.945124 90)
			(size 0.3556 1.2192)
			(layers "F.Cu" "F.Mask" "F.Paste")
			(net "P5E_PEX1_STN0_TX_C_DN<6>")
		)
		(pad "B37" smd rect
			(at -1.27762 6.545072 90)
			(size 0.3556 1.2192)
			(layers "F.Cu" "F.Mask" "F.Paste")
			(net "P5E_PEX1_STN0_TX_C_DP<6>")
		)
		(pad "B38" smd rect
			(at -1.27762 7.14502 90)
			(size 0.3556 1.2192)
			(layers "F.Cu" "F.Mask" "F.Paste")
			(net "GND")
		)
		(pad "B39" smd rect
			(at -1.27762 7.744968 90)
			(size 0.3556 1.2192)
			(layers "F.Cu" "F.Mask" "F.Paste")
			(net "P5E_PEX1_STN0_TX_C_DN<7>")
		)
		(pad "B40" smd rect
			(at -1.27762 8.344916 90)
			(size 0.3556 1.2192)
			(layers "F.Cu" "F.Mask" "F.Paste")
			(net "P5E_PEX1_STN0_TX_C_DP<7>")
		)
		(pad "B41" smd rect
			(at -1.27762 8.945118 90)
			(size 0.3556 1.2192)
			(layers "F.Cu" "F.Mask" "F.Paste")
			(net "GND")
		)
		(pad "B42" smd rect
			(at -1.27762 9.545066 90)
			(size 0.3556 1.2192)
			(layers "F.Cu" "F.Mask" "F.Paste")
			(net "PRSNTB0_NIC3_N")
		)
		(pad "B43" smd rect
			(at -1.27762 14.454886 90)
			(size 0.3556 1.2192)
			(layers "F.Cu" "F.Mask" "F.Paste")
			(net "GND")
		)
		(pad "B44" smd rect
			(at -1.27762 15.055088 90)
			(size 0.3556 1.2192)
			(layers "F.Cu" "F.Mask" "F.Paste")
			(net "P5E_PEX1_STN0_TX_C_DN<8>")
		)
		(pad "B45" smd rect
			(at -1.27762 15.655036 90)
			(size 0.3556 1.2192)
			(layers "F.Cu" "F.Mask" "F.Paste")
			(net "P5E_PEX1_STN0_TX_C_DP<8>")
		)
		(pad "B46" smd rect
			(at -1.27762 16.254984 90)
			(size 0.3556 1.2192)
			(layers "F.Cu" "F.Mask" "F.Paste")
			(net "GND")
		)
		(pad "B47" smd rect
			(at -1.27762 16.854932 90)
			(size 0.3556 1.2192)
			(layers "F.Cu" "F.Mask" "F.Paste")
			(net "P5E_PEX1_STN0_TX_C_DN<9>")
		)
		(pad "B48" smd rect
			(at -1.27762 17.45488 90)
			(size 0.3556 1.2192)
			(layers "F.Cu" "F.Mask" "F.Paste")
			(net "P5E_PEX1_STN0_TX_C_DP<9>")
		)
		(pad "B49" smd rect
			(at -1.27762 18.055082 90)
			(size 0.3556 1.2192)
			(layers "F.Cu" "F.Mask" "F.Paste")
			(net "GND")
		)
		(pad "B50" smd rect
			(at -1.27762 18.65503 90)
			(size 0.3556 1.2192)
			(layers "F.Cu" "F.Mask" "F.Paste")
			(net "P5E_PEX1_STN0_TX_C_DN<10>")
		)
		(pad "B51" smd rect
			(at -1.27762 19.254978 90)
			(size 0.3556 1.2192)
			(layers "F.Cu" "F.Mask" "F.Paste")
			(net "P5E_PEX1_STN0_TX_C_DP<10>")
		)
		(pad "B52" smd rect
			(at -1.27762 19.854926 90)
			(size 0.3556 1.2192)
			(layers "F.Cu" "F.Mask" "F.Paste")
			(net "GND")
		)
		(pad "B53" smd rect
			(at -1.27762 20.455128 90)
			(size 0.3556 1.2192)
			(layers "F.Cu" "F.Mask" "F.Paste")
			(net "P5E_PEX1_STN0_TX_C_DN<11>")
		)
		(pad "B54" smd rect
			(at -1.27762 21.055076 90)
			(size 0.3556 1.2192)
			(layers "F.Cu" "F.Mask" "F.Paste")
			(net "P5E_PEX1_STN0_TX_C_DP<11>")
		)
		(pad "B55" smd rect
			(at -1.27762 21.655024 90)
			(size 0.3556 1.2192)
			(layers "F.Cu" "F.Mask" "F.Paste")
			(net "GND")
		)
		(pad "B56" smd rect
			(at -1.27762 22.254972 90)
			(size 0.3556 1.2192)
			(layers "F.Cu" "F.Mask" "F.Paste")
			(net "P5E_PEX1_STN0_TX_C_DP<12>")
		)
		(pad "B57" smd rect
			(at -1.27762 22.85492 90)
			(size 0.3556 1.2192)
			(layers "F.Cu" "F.Mask" "F.Paste")
			(net "P5E_PEX1_STN0_TX_C_DN<12>")
		)
		(pad "B58" smd rect
			(at -1.27762 23.455122 90)
			(size 0.3556 1.2192)
			(layers "F.Cu" "F.Mask" "F.Paste")
			(net "GND")
		)
		(pad "B59" smd rect
			(at -1.27762 24.05507 90)
			(size 0.3556 1.2192)
			(layers "F.Cu" "F.Mask" "F.Paste")
			(net "P5E_PEX1_STN0_TX_C_DN<13>")
		)
		(pad "B60" smd rect
			(at -1.27762 24.655018 90)
			(size 0.3556 1.2192)
			(layers "F.Cu" "F.Mask" "F.Paste")
			(net "P5E_PEX1_STN0_TX_C_DP<13>")
		)
		(pad "B61" smd rect
			(at -1.27762 25.254966 90)
			(size 0.3556 1.2192)
			(layers "F.Cu" "F.Mask" "F.Paste")
			(net "GND")
		)
		(pad "B62" smd rect
			(at -1.27762 25.854914 90)
			(size 0.3556 1.2192)
			(layers "F.Cu" "F.Mask" "F.Paste")
			(net "P5E_PEX1_STN0_TX_C_DP<14>")
		)
		(pad "B63" smd rect
			(at -1.27762 26.455116 90)
			(size 0.3556 1.2192)
			(layers "F.Cu" "F.Mask" "F.Paste")
			(net "P5E_PEX1_STN0_TX_C_DN<14>")
		)
		(pad "B64" smd rect
			(at -1.27762 27.055064 90)
			(size 0.3556 1.2192)
			(layers "F.Cu" "F.Mask" "F.Paste")
			(net "GND")
		)
		(pad "B65" smd rect
			(at -1.27762 27.655012 90)
			(size 0.3556 1.2192)
			(layers "F.Cu" "F.Mask" "F.Paste")
			(net "P5E_PEX1_STN0_TX_C_DN<15>")
		)
		(pad "B66" smd rect
			(at -1.27762 28.25496 90)
			(size 0.3556 1.2192)
			(layers "F.Cu" "F.Mask" "F.Paste")
			(net "P5E_PEX1_STN0_TX_C_DP<15>")
		)
		(pad "B67" smd rect
			(at -1.27762 28.854908 90)
			(size 0.3556 1.2192)
			(layers "F.Cu" "F.Mask" "F.Paste")
			(net "GND")
		)
		(pad "B68" smd rect
			(at -1.27762 29.45511 90)
			(size 0.3556 1.2192)
			(layers "F.Cu" "F.Mask" "F.Paste")
			(net "Net_2620")
		)
		(pad "B69" smd rect
			(at -1.27762 30.055058 90)
			(size 0.3556 1.2192)
			(layers "F.Cu" "F.Mask" "F.Paste")
			(net "Net_2621")
		)
		(pad "B70" smd rect
			(at -1.27762 30.655006 90)
			(size 0.3556 1.2192)
			(layers "F.Cu" "F.Mask" "F.Paste")
			(net "PRSNTB3_NIC3_N")
		)
		(pad "G1" thru_hole oval
			(at 1.022604 -34.034984 90)
			(size 1.6256 3.4798)
			(drill oval 1.1176 2.4638)
			(layers "*.Cu" "*.Mask")
			(remove_unused_layers no)
			(net "GND")
			(clearance 0.127)
			(thermal_gap 0.127)
		)
		(pad "G2" thru_hole oval
			(at 1.022604 -20.625054 90)
			(size 1.6256 3.4798)
			(drill oval 1.1176 2.4638)
			(layers "*.Cu" "*.Mask")
			(remove_unused_layers no)
			(net "GND")
			(clearance 0.127)
			(thermal_gap 0.127)
		)
		(pad "G3" thru_hole oval
			(at 1.022604 -0.255016 90)
			(size 1.6256 3.4798)
			(drill oval 1.1176 2.4638)
			(layers "*.Cu" "*.Mask")
			(remove_unused_layers no)
			(net "GND")
			(clearance 0.127)
			(thermal_gap 0.127)
		)
		(pad "G4" thru_hole oval
			(at 1.022604 12.005056 90)
			(size 1.6256 3.4798)
			(drill oval 1.1176 2.4638)
			(layers "*.Cu" "*.Mask")
			(remove_unused_layers no)
			(net "GND")
			(clearance 0.127)
			(thermal_gap 0.127)
		)
		(pad "G5" thru_hole oval
			(at 1.022604 34.034984 90)
			(size 1.5748 3.4798)
			(drill oval 1.1176 2.4638)
			(layers "*.Cu" "*.Mask")
			(remove_unused_layers no)
			(net "GND")
			(clearance 0.1524)
			(thermal_gap 0.1524)
		)
		(pad "G6" thru_hole circle
			(at -3.16738 -20.625054 180)
			(size 1.6256 1.6256)
			(drill 1.1176)
			(layers "*.Cu" "*.Mask")
			(remove_unused_layers no)
			(net "GND")
			(clearance 0)
		)
		(pad "G7" thru_hole circle
			(at -3.16738 12.005056 180)
			(size 1.6256 1.6256)
			(drill 1.1176)
			(layers "*.Cu" "*.Mask")
			(remove_unused_layers no)
			(net "GND")
			(clearance 0)
		)
		(pad "G8" thru_hole circle
			(at 4.20243 -20.625054 180)
			(size 1.6256 1.6256)
			(drill 1.1176)
			(layers "*.Cu" "*.Mask")
			(remove_unused_layers no)
			(net "GND")
			(clearance 0)
		)
		(pad "G9" thru_hole circle
			(at 4.20243 12.005056 180)
			(size 1.6256 1.6256)
			(drill 1.1176)
			(layers "*.Cu" "*.Mask")
			(remove_unused_layers no)
			(net "GND")
			(clearance 0)
		)
		(pad "OA1" smd rect
			(at 3.322574 -30.660086 90)
			(size 0.3556 1.2192)
			(layers "F.Cu" "F.Mask" "F.Paste")
			(net "RST_NIC3_PERST2_R_N")
		)
		(pad "OA2" smd rect
			(at 3.322574 -30.059884 90)
			(size 0.3556 1.2192)
			(layers "F.Cu" "F.Mask" "F.Paste")
			(net "RST_NIC3_PERST3_R_N")
		)
		(pad "OA3" smd rect
			(at 3.322574 -29.459936 90)
			(size 0.3556 1.2192)
			(layers "F.Cu" "F.Mask" "F.Paste")
			(net "Net_2624")
		)
		(pad "OA4" smd rect
			(at 3.322574 -28.859988 90)
			(size 0.3556 1.2192)
			(layers "F.Cu" "F.Mask" "F.Paste")
			(net "NIC3_RBT_ARB_IN")
		)
		(pad "OA5" smd rect
			(at 3.322574 -28.26004 90)
			(size 0.3556 1.2192)
			(layers "F.Cu" "F.Mask" "F.Paste")
			(net "NIC3_RBT_ARB_OUT")
		)
		(pad "OA6" smd rect
			(at 3.322574 -27.660092 90)
			(size 0.3556 1.2192)
			(layers "F.Cu" "F.Mask" "F.Paste")
			(net "NIC3_SLOT_ID1")
		)
		(pad "OA7" smd rect
			(at 3.322574 -27.05989 90)
			(size 0.3556 1.2192)
			(layers "F.Cu" "F.Mask" "F.Paste")
			(net "NCSI_NIC3_TX_EN")
		)
		(pad "OA8" smd rect
			(at 3.322574 -26.459942 90)
			(size 0.3556 1.2192)
			(layers "F.Cu" "F.Mask" "F.Paste")
			(net "NCSI_NIC3_TXD1")
		)
		(pad "OA9" smd rect
			(at 3.322574 -25.859994 90)
			(size 0.3556 1.2192)
			(layers "F.Cu" "F.Mask" "F.Paste")
			(net "NCSI_NIC3_TXD0")
		)
		(pad "OA10" smd rect
			(at 3.322574 -25.260046 90)
			(size 0.3556 1.2192)
			(layers "F.Cu" "F.Mask" "F.Paste")
			(net "GND")
		)
		(pad "OA11" smd rect
			(at 3.322574 -24.660098 90)
			(size 0.3556 1.2192)
			(layers "F.Cu" "F.Mask" "F.Paste")
			(net "Net_2616")
		)
		(pad "OA12" smd rect
			(at 3.322574 -24.059896 90)
			(size 0.3556 1.2192)
			(layers "F.Cu" "F.Mask" "F.Paste")
			(net "Net_2619")
		)
		(pad "OA13" smd rect
			(at 3.322574 -23.459948 90)
			(size 0.3556 1.2192)
			(layers "F.Cu" "F.Mask" "F.Paste")
			(net "GND")
		)
		(pad "OA14" smd rect
			(at 3.322574 -22.86 90)
			(size 0.3556 1.2192)
			(layers "F.Cu" "F.Mask" "F.Paste")
			(net "CLK_50M_NIC3_RBT_REF")
		)
		(pad "OB1" smd rect
			(at -1.27762 -30.660086 90)
			(size 0.3556 1.2192)
			(layers "F.Cu" "F.Mask" "F.Paste")
			(net "PWRGD_NIC3_PWR_GOOD")
		)
		(pad "OB2" smd rect
			(at -1.27762 -30.059884 90)
			(size 0.3556 1.2192)
			(layers "F.Cu" "F.Mask" "F.Paste")
			(net "NIC3_MAIN_PWR_EN_R")
		)
		(pad "OB3" smd rect
			(at -1.27762 -29.459936 90)
			(size 0.3556 1.2192)
			(layers "F.Cu" "F.Mask" "F.Paste")
			(net "NIC3_LD_N")
		)
		(pad "OB4" smd rect
			(at -1.27762 -28.859988 90)
			(size 0.3556 1.2192)
			(layers "F.Cu" "F.Mask" "F.Paste")
			(net "NIC3_DATA_IN")
		)
		(pad "OB5" smd rect
			(at -1.27762 -28.26004 90)
			(size 0.3556 1.2192)
			(layers "F.Cu" "F.Mask" "F.Paste")
			(net "NIC3_DATA_OUT")
		)
		(pad "OB6" smd rect
			(at -1.27762 -27.660092 90)
			(size 0.3556 1.2192)
			(layers "F.Cu" "F.Mask" "F.Paste")
			(net "NIC3_CLK")
		)
		(pad "OB7" smd rect
			(at -1.27762 -27.05989 90)
			(size 0.3556 1.2192)
			(layers "F.Cu" "F.Mask" "F.Paste")
			(net "NIC3_SLOT_ID0")
		)
		(pad "OB8" smd rect
			(at -1.27762 -26.459942 90)
			(size 0.3556 1.2192)
			(layers "F.Cu" "F.Mask" "F.Paste")
			(net "NCSI_NIC3_RXD1")
		)
		(pad "OB9" smd rect
			(at -1.27762 -25.859994 90)
			(size 0.3556 1.2192)
			(layers "F.Cu" "F.Mask" "F.Paste")
			(net "NCSI_NIC3_RXD0")
		)
		(pad "OB10" smd rect
			(at -1.27762 -25.260046 90)
			(size 0.3556 1.2192)
			(layers "F.Cu" "F.Mask" "F.Paste")
			(net "GND")
		)
		(pad "OB11" smd rect
			(at -1.27762 -24.660098 90)
			(size 0.3556 1.2192)
			(layers "F.Cu" "F.Mask" "F.Paste")
			(net "Net_2615")
		)
		(pad "OB12" smd rect
			(at -1.27762 -24.059896 90)
			(size 0.3556 1.2192)
			(layers "F.Cu" "F.Mask" "F.Paste")
			(net "Net_2618")
		)
		(pad "OB13" smd rect
			(at -1.27762 -23.459948 90)
			(size 0.3556 1.2192)
			(layers "F.Cu" "F.Mask" "F.Paste")
			(net "GND")
		)
		(pad "OB14" smd rect
			(at -1.27762 -22.86 90)
			(size 0.3556 1.2192)
			(layers "F.Cu" "F.Mask" "F.Paste")
			(net "NCSI_NIC3_CRS_DV")
		)
		(zone
			(layers "F.Cu" "B.Cu" "In1.Cu" "In2.Cu" "In3.Cu" "In4.Cu" "In5.Cu" "In6.Cu"
				"In7.Cu" "In8.Cu" "In9.Cu" "In10.Cu" "In11.Cu" "In12.Cu" "In13.Cu" "In14.Cu"
				"In15.Cu" "In16.Cu"
			)
			(hatch none 0.5)
			(connect_pads
				(clearance 0)
			)
			(min_thickness 0.25)
			(keepout
				(tracks not_allowed)
				(vias allowed)
				(pads allowed)
				(copperpour not_allowed)
				(footprints allowed)
			)
			(placement
				(enabled no)
				(sheetname "")
			)
			(fill
				(thermal_gap 0.5)
				(thermal_bridge_width 0.5)
				(island_removal_mode 0)
			)
			(polygon
				(pts
					(arc
						(start 188.124338 -160.1851)
						(mid 185.99023 -160.1851)
						(end 188.124338 -160.1851)
					)
				)
			)
		)
		(zone
			(layers "F.Cu" "B.Cu" "In1.Cu" "In2.Cu" "In3.Cu" "In4.Cu" "In5.Cu" "In6.Cu"
				"In7.Cu" "In8.Cu" "In9.Cu" "In10.Cu" "In11.Cu" "In12.Cu" "In13.Cu" "In14.Cu"
				"In15.Cu" "In16.Cu"
			)
			(hatch none 0.5)
			(connect_pads
				(clearance 0)
			)
			(min_thickness 0.25)
			(keepout
				(tracks not_allowed)
				(vias allowed)
				(pads allowed)
				(copperpour not_allowed)
				(footprints allowed)
			)
			(placement
				(enabled no)
				(sheetname "")
			)
			(fill
				(thermal_gap 0.5)
				(thermal_bridge_width 0.5)
				(island_removal_mode 0)
			)
			(polygon
				(pts
					(arc
						(start 189.874144 -95.214948)
						(mid 187.740544 -95.214948)
						(end 189.874144 -95.214948)
					)
				)
			)
		)
	)
	(footprint ""
		(layer "F.Cu")
		(at 187.946792 -356.22103 90)
		(property "Reference" "C377"
			(at 0 0 90)
			(layer "F.SilkS")
			(hide yes)
			(effects
				(font
					(size 1.27 1.27)
				)
			)
		)
		(property "Value" ""
			(at 0 0 90)
			(layer "F.Fab")
			(effects
				(font
					(size 1.27 1.27)
				)
			)
		)
		(duplicate_pad_numbers_are_jumpers no)
		(fp_line
			(start 0.299974 -0.150114)
			(end 0.299974 0.150114)
			(stroke
				(width 0.1)
				(type default)
			)
			(layer "F.Fab")
		)
		(fp_line
			(start -0.299974 -0.150114)
			(end 0.299974 -0.150114)
			(stroke
				(width 0.1)
				(type default)
			)
			(layer "F.Fab")
		)
		(fp_line
			(start 0.299974 0.150114)
			(end -0.299974 0.150114)
			(stroke
				(width 0.1)
				(type default)
			)
			(layer "F.Fab")
		)
		(fp_line
			(start -0.299974 0.150114)
			(end -0.299974 -0.150114)
			(stroke
				(width 0.1)
				(type default)
			)
			(layer "F.Fab")
		)
		(pad "1" smd rect
			(at -0.2667 0 90)
			(size 0.3048 0.381)
			(layers "F.Cu" "F.Mask" "F.Paste")
			(net "P5E_PEX1_STN7_TX_DN<125>")
		)
		(pad "2" smd rect
			(at 0.2667 0 90)
			(size 0.3048 0.381)
			(layers "F.Cu" "F.Mask" "F.Paste")
			(net "P5E_PEX1_STN7_TX_C_DN<125>")
		)
	)
	(footprint ""
		(layer "F.Cu")
		(at 8.179054 -59.577986 -90)
		(property "Reference" "R886"
			(at 0 0 270)
			(layer "F.SilkS")
			(hide yes)
			(effects
				(font
					(size 1.27 1.27)
				)
			)
		)
		(property "Value" ""
			(at 0 0 270)
			(layer "F.Fab")
			(effects
				(font
					(size 1.27 1.27)
				)
			)
		)
		(duplicate_pad_numbers_are_jumpers no)
		(fp_line
			(start -0.7874 0.4064)
			(end -0.7874 -0.4064)
			(stroke
				(width 0.1524)
				(type default)
			)
			(layer "F.SilkS")
		)
		(fp_line
			(start 0.7874 0.4064)
			(end -0.7874 0.4064)
			(stroke
				(width 0.1524)
				(type default)
			)
			(layer "F.SilkS")
		)
		(fp_line
			(start -0.7874 -0.4064)
			(end 0.7874 -0.4064)
			(stroke
				(width 0.1524)
				(type default)
			)
			(layer "F.SilkS")
		)
		(fp_line
			(start 0.7874 -0.4064)
			(end 0.7874 0.4064)
			(stroke
				(width 0.1524)
				(type default)
			)
			(layer "F.SilkS")
		)
		(fp_line
			(start -0.67945 0.3048)
			(end -0.67945 -0.305054)
			(stroke
				(width 0.1)
				(type default)
			)
			(layer "F.Fab")
		)
		(fp_line
			(start -0.12065 0.3048)
			(end -0.67945 0.3048)
			(stroke
				(width 0.1)
				(type default)
			)
			(layer "F.Fab")
		)
		(fp_line
			(start 0.120396 0.3048)
			(end 0.120396 0.2794)
			(stroke
				(width 0.1)
				(type default)
			)
			(layer "F.Fab")
		)
		(fp_line
			(start 0.67945 0.3048)
			(end 0.120396 0.3048)
			(stroke
				(width 0.1)
				(type default)
			)
			(layer "F.Fab")
		)
		(fp_line
			(start -0.12065 0.2794)
			(end -0.12065 0.3048)
			(stroke
				(width 0.1)
				(type default)
			)
			(layer "F.Fab")
		)
		(fp_line
			(start 0.120396 0.2794)
			(end -0.12065 0.2794)
			(stroke
				(width 0.1)
				(type default)
			)
			(layer "F.Fab")
		)
		(fp_line
			(start -0.12065 -0.2794)
			(end 0.12065 -0.2794)
			(stroke
				(width 0.1)
				(type default)
			)
			(layer "F.Fab")
		)
		(fp_line
			(start 0.12065 -0.2794)
			(end 0.12065 -0.3048)
			(stroke
				(width 0.1)
				(type default)
			)
			(layer "F.Fab")
		)
		(fp_line
			(start 0.12065 -0.3048)
			(end 0.67945 -0.3048)
			(stroke
				(width 0.1)
				(type default)
			)
			(layer "F.Fab")
		)
		(fp_line
			(start 0.67945 -0.3048)
			(end 0.67945 0.3048)
			(stroke
				(width 0.1)
				(type default)
			)
			(layer "F.Fab")
		)
		(fp_line
			(start -0.67945 -0.305054)
			(end -0.12065 -0.305054)
			(stroke
				(width 0.1)
				(type default)
			)
			(layer "F.Fab")
		)
		(fp_line
			(start -0.12065 -0.305054)
			(end -0.12065 -0.2794)
			(stroke
				(width 0.1)
				(type default)
			)
			(layer "F.Fab")
		)
		(pad "1" smd circle
			(at -0.40005 0 270)
			(size 0 0)
			(layers "F.Cu" "F.Mask" "F.Paste")
			(net "P3V3_SSD0")
		)
		(pad "2" smd circle
			(at 0.40005 0 270)
			(size 0 0)
			(layers "F.Cu" "F.Mask" "F.Paste")
			(net "PWRGD_P3V3_SSD0")
		)
	)
	(footprint ""
		(layer "F.Cu")
		(at 444.713868 -232.524554)
		(property "Reference" "R6605"
			(at 0 0 0)
			(layer "F.SilkS")
			(hide yes)
			(effects
				(font
					(size 1.27 1.27)
				)
			)
		)
		(property "Value" ""
			(at 0 0 0)
			(layer "F.Fab")
			(effects
				(font
					(size 1.27 1.27)
				)
			)
		)
		(duplicate_pad_numbers_are_jumpers no)
		(fp_line
			(start -0.7874 -0.4064)
			(end 0.7874 -0.4064)
			(stroke
				(width 0.1524)
				(type default)
			)
			(layer "F.SilkS")
		)
		(fp_line
			(start -0.7874 0.4064)
			(end -0.7874 -0.4064)
			(stroke
				(width 0.1524)
				(type default)
			)
			(layer "F.SilkS")
		)
		(fp_line
			(start 0.7874 -0.4064)
			(end 0.7874 0.4064)
			(stroke
				(width 0.1524)
				(type default)
			)
			(layer "F.SilkS")
		)
		(fp_line
			(start 0.7874 0.4064)
			(end -0.7874 0.4064)
			(stroke
				(width 0.1524)
				(type default)
			)
			(layer "F.SilkS")
		)
		(fp_line
			(start -0.67945 -0.305054)
			(end -0.12065 -0.305054)
			(stroke
				(width 0.1)
				(type default)
			)
			(layer "F.Fab")
		)
		(fp_line
			(start -0.67945 0.3048)
			(end -0.67945 -0.305054)
			(stroke
				(width 0.1)
				(type default)
			)
			(layer "F.Fab")
		)
		(fp_line
			(start -0.12065 -0.305054)
			(end -0.12065 -0.2794)
			(stroke
				(width 0.1)
				(type default)
			)
			(layer "F.Fab")
		)
		(fp_line
			(start -0.12065 -0.2794)
			(end 0.12065 -0.2794)
			(stroke
				(width 0.1)
				(type default)
			)
			(layer "F.Fab")
		)
		(fp_line
			(start -0.12065 0.2794)
			(end -0.12065 0.3048)
			(stroke
				(width 0.1)
				(type default)
			)
			(layer "F.Fab")
		)
		(fp_line
			(start -0.12065 0.3048)
			(end -0.67945 0.3048)
			(stroke
				(width 0.1)
				(type default)
			)
			(layer "F.Fab")
		)
		(fp_line
			(start 0.120396 0.2794)
			(end -0.12065 0.2794)
			(stroke
				(width 0.1)
				(type default)
			)
			(layer "F.Fab")
		)
		(fp_line
			(start 0.120396 0.3048)
			(end 0.120396 0.2794)
			(stroke
				(width 0.1)
				(type default)
			)
			(layer "F.Fab")
		)
		(fp_line
			(start 0.12065 -0.3048)
			(end 0.67945 -0.3048)
			(stroke
				(width 0.1)
				(type default)
			)
			(layer "F.Fab")
		)
		(fp_line
			(start 0.12065 -0.2794)
			(end 0.12065 -0.3048)
			(stroke
				(width 0.1)
				(type default)
			)
			(layer "F.Fab")
		)
		(fp_line
			(start 0.67945 -0.3048)
			(end 0.67945 0.3048)
			(stroke
				(width 0.1)
				(type default)
			)
			(layer "F.Fab")
		)
		(fp_line
			(start 0.67945 0.3048)
			(end 0.120396 0.3048)
			(stroke
				(width 0.1)
				(type default)
			)
			(layer "F.Fab")
		)
		(pad "1" smd circle
			(at -0.40005 0)
			(size 0 0)
			(layers "F.Cu" "F.Mask" "F.Paste")
			(net "UART_PEX3_SDB_BUF_R_TX")
		)
		(pad "2" smd circle
			(at 0.40005 0)
			(size 0 0)
			(layers "F.Cu" "F.Mask" "F.Paste")
			(net "UART_PEX3_SDB_CP2108_TX")
		)
	)
	(footprint ""
		(layer "F.Cu")
		(at 251.457968 -72.766682 90)
		(property "Reference" "PC860"
			(at 0 0 90)
			(layer "F.SilkS")
			(hide yes)
			(effects
				(font
					(size 1.27 1.27)
				)
			)
		)
		(property "Value" ""
			(at 0 0 90)
			(layer "F.Fab")
			(effects
				(font
					(size 1.27 1.27)
				)
			)
		)
		(duplicate_pad_numbers_are_jumpers no)
		(fp_line
			(start 0.7874 -0.4064)
			(end 0.7874 0.4064)
			(stroke
				(width 0.1524)
				(type default)
			)
			(layer "F.SilkS")
		)
		(fp_line
			(start -0.7874 -0.4064)
			(end 0.7874 -0.4064)
			(stroke
				(width 0.1524)
				(type default)
			)
			(layer "F.SilkS")
		)
		(fp_line
			(start 0.7874 0.4064)
			(end -0.7874 0.4064)
			(stroke
				(width 0.1524)
				(type default)
			)
			(layer "F.SilkS")
		)
		(fp_line
			(start -0.7874 0.4064)
			(end -0.7874 -0.4064)
			(stroke
				(width 0.1524)
				(type default)
			)
			(layer "F.SilkS")
		)
		(fp_line
			(start -0.12065 -0.305054)
			(end -0.12065 -0.2794)
			(stroke
				(width 0.1)
				(type default)
			)
			(layer "F.Fab")
		)
		(fp_line
			(start -0.67945 -0.305054)
			(end -0.12065 -0.305054)
			(stroke
				(width 0.1)
				(type default)
			)
			(layer "F.Fab")
		)
		(fp_line
			(start 0.67945 -0.3048)
			(end 0.67945 0.3048)
			(stroke
				(width 0.1)
				(type default)
			)
			(layer "F.Fab")
		)
		(fp_line
			(start 0.12065 -0.3048)
			(end 0.67945 -0.3048)
			(stroke
				(width 0.1)
				(type default)
			)
			(layer "F.Fab")
		)
		(fp_line
			(start 0.12065 -0.2794)
			(end 0.12065 -0.3048)
			(stroke
				(width 0.1)
				(type default)
			)
			(layer "F.Fab")
		)
		(fp_line
			(start -0.12065 -0.2794)
			(end 0.12065 -0.2794)
			(stroke
				(width 0.1)
				(type default)
			)
			(layer "F.Fab")
		)
		(fp_line
			(start 0.120396 0.2794)
			(end -0.12065 0.2794)
			(stroke
				(width 0.1)
				(type default)
			)
			(layer "F.Fab")
		)
		(fp_line
			(start -0.12065 0.2794)
			(end -0.12065 0.3048)
			(stroke
				(width 0.1)
				(type default)
			)
			(layer "F.Fab")
		)
		(fp_line
			(start 0.67945 0.3048)
			(end 0.120396 0.3048)
			(stroke
				(width 0.1)
				(type default)
			)
			(layer "F.Fab")
		)
		(fp_line
			(start 0.120396 0.3048)
			(end 0.120396 0.2794)
			(stroke
				(width 0.1)
				(type default)
			)
			(layer "F.Fab")
		)
		(fp_line
			(start -0.12065 0.3048)
			(end -0.67945 0.3048)
			(stroke
				(width 0.1)
				(type default)
			)
			(layer "F.Fab")
		)
		(fp_line
			(start -0.67945 0.3048)
			(end -0.67945 -0.305054)
			(stroke
				(width 0.1)
				(type default)
			)
			(layer "F.Fab")
		)
		(pad "1" smd circle
			(at -0.40005 0 90)
			(size 0 0)
			(layers "F.Cu" "F.Mask" "F.Paste")
			(net "P12V_SSD8_CO_MODE")
		)
		(pad "2" smd circle
			(at 0.40005 0 90)
			(size 0 0)
			(layers "F.Cu" "F.Mask" "F.Paste")
			(net "GND")
		)
	)
	(footprint ""
		(layer "F.Cu")
		(at 334.130396 -118.76024 180)
		(property "Reference" "R6035"
			(at 0 0 180)
			(layer "F.SilkS")
			(hide yes)
			(effects
				(font
					(size 1.27 1.27)
				)
			)
		)
		(property "Value" ""
			(at 0 0 180)
			(layer "F.Fab")
			(effects
				(font
					(size 1.27 1.27)
				)
			)
		)
		(duplicate_pad_numbers_are_jumpers no)
		(fp_line
			(start 0.7874 0.4064)
			(end -0.7874 0.4064)
			(stroke
				(width 0.1524)
				(type default)
			)
			(layer "F.SilkS")
		)
		(fp_line
			(start 0.7874 -0.4064)
			(end 0.7874 0.4064)
			(stroke
				(width 0.1524)
				(type default)
			)
			(layer "F.SilkS")
		)
		(fp_line
			(start -0.7874 0.4064)
			(end -0.7874 -0.4064)
			(stroke
				(width 0.1524)
				(type default)
			)
			(layer "F.SilkS")
		)
		(fp_line
			(start -0.7874 -0.4064)
			(end 0.7874 -0.4064)
			(stroke
				(width 0.1524)
				(type default)
			)
			(layer "F.SilkS")
		)
		(fp_line
			(start 0.67945 0.3048)
			(end 0.120396 0.3048)
			(stroke
				(width 0.1)
				(type default)
			)
			(layer "F.Fab")
		)
		(fp_line
			(start 0.67945 -0.3048)
			(end 0.67945 0.3048)
			(stroke
				(width 0.1)
				(type default)
			)
			(layer "F.Fab")
		)
		(fp_line
			(start 0.12065 -0.2794)
			(end 0.12065 -0.3048)
			(stroke
				(width 0.1)
				(type default)
			)
			(layer "F.Fab")
		)
		(fp_line
			(start 0.12065 -0.3048)
			(end 0.67945 -0.3048)
			(stroke
				(width 0.1)
				(type default)
			)
			(layer "F.Fab")
		)
		(fp_line
			(start 0.120396 0.3048)
			(end 0.120396 0.2794)
			(stroke
				(width 0.1)
				(type default)
			)
			(layer "F.Fab")
		)
		(fp_line
			(start 0.120396 0.2794)
			(end -0.12065 0.2794)
			(stroke
				(width 0.1)
				(type default)
			)
			(layer "F.Fab")
		)
		(fp_line
			(start -0.12065 0.3048)
			(end -0.67945 0.3048)
			(stroke
				(width 0.1)
				(type default)
			)
			(layer "F.Fab")
		)
		(fp_line
			(start -0.12065 0.2794)
			(end -0.12065 0.3048)
			(stroke
				(width 0.1)
				(type default)
			)
			(layer "F.Fab")
		)
		(fp_line
			(start -0.12065 -0.2794)
			(end 0.12065 -0.2794)
			(stroke
				(width 0.1)
				(type default)
			)
			(layer "F.Fab")
		)
		(fp_line
			(start -0.12065 -0.305054)
			(end -0.12065 -0.2794)
			(stroke
				(width 0.1)
				(type default)
			)
			(layer "F.Fab")
		)
		(fp_line
			(start -0.67945 0.3048)
			(end -0.67945 -0.305054)
			(stroke
				(width 0.1)
				(type default)
			)
			(layer "F.Fab")
		)
		(fp_line
			(start -0.67945 -0.305054)
			(end -0.12065 -0.305054)
			(stroke
				(width 0.1)
				(type default)
			)
			(layer "F.Fab")
		)
		(pad "1" smd circle
			(at -0.40005 0 180)
			(size 0 0)
			(layers "F.Cu" "F.Mask" "F.Paste")
			(net "PWRGD_P3V3_NIC5_D")
		)
		(pad "2" smd circle
			(at 0.40005 0 180)
			(size 0 0)
			(layers "F.Cu" "F.Mask" "F.Paste")
			(net "PWRGD_P3V3_NIC5_R")
		)
	)
	(footprint ""
		(layer "F.Cu")
		(at 370.185696 -25.1587 -90)
		(property "Reference" "R5752"
			(at 0 0 270)
			(layer "F.SilkS")
			(hide yes)
			(effects
				(font
					(size 1.27 1.27)
				)
			)
		)
		(property "Value" ""
			(at 0 0 270)
			(layer "F.Fab")
			(effects
				(font
					(size 1.27 1.27)
				)
			)
		)
		(duplicate_pad_numbers_are_jumpers no)
		(fp_line
			(start -0.7874 0.4064)
			(end -0.7874 -0.4064)
			(stroke
				(width 0.1524)
				(type default)
			)
			(layer "F.SilkS")
		)
		(fp_line
			(start 0.7874 0.4064)
			(end -0.7874 0.4064)
			(stroke
				(width 0.1524)
				(type default)
			)
			(layer "F.SilkS")
		)
		(fp_line
			(start -0.7874 -0.4064)
			(end 0.7874 -0.4064)
			(stroke
				(width 0.1524)
				(type default)
			)
			(layer "F.SilkS")
		)
		(fp_line
			(start 0.7874 -0.4064)
			(end 0.7874 0.4064)
			(stroke
				(width 0.1524)
				(type default)
			)
			(layer "F.SilkS")
		)
		(fp_line
			(start -0.67945 0.3048)
			(end -0.67945 -0.305054)
			(stroke
				(width 0.1)
				(type default)
			)
			(layer "F.Fab")
		)
		(fp_line
			(start -0.12065 0.3048)
			(end -0.67945 0.3048)
			(stroke
				(width 0.1)
				(type default)
			)
			(layer "F.Fab")
		)
		(fp_line
			(start 0.120396 0.3048)
			(end 0.120396 0.2794)
			(stroke
				(width 0.1)
				(type default)
			)
			(layer "F.Fab")
		)
		(fp_line
			(start 0.67945 0.3048)
			(end 0.120396 0.3048)
			(stroke
				(width 0.1)
				(type default)
			)
			(layer "F.Fab")
		)
		(fp_line
			(start -0.12065 0.2794)
			(end -0.12065 0.3048)
			(stroke
				(width 0.1)
				(type default)
			)
			(layer "F.Fab")
		)
		(fp_line
			(start 0.120396 0.2794)
			(end -0.12065 0.2794)
			(stroke
				(width 0.1)
				(type default)
			)
			(layer "F.Fab")
		)
		(fp_line
			(start -0.12065 -0.2794)
			(end 0.12065 -0.2794)
			(stroke
				(width 0.1)
				(type default)
			)
			(layer "F.Fab")
		)
		(fp_line
			(start 0.12065 -0.2794)
			(end 0.12065 -0.3048)
			(stroke
				(width 0.1)
				(type default)
			)
			(layer "F.Fab")
		)
		(fp_line
			(start 0.12065 -0.3048)
			(end 0.67945 -0.3048)
			(stroke
				(width 0.1)
				(type default)
			)
			(layer "F.Fab")
		)
		(fp_line
			(start 0.67945 -0.3048)
			(end 0.67945 0.3048)
			(stroke
				(width 0.1)
				(type default)
			)
			(layer "F.Fab")
		)
		(fp_line
			(start -0.67945 -0.305054)
			(end -0.12065 -0.305054)
			(stroke
				(width 0.1)
				(type default)
			)
			(layer "F.Fab")
		)
		(fp_line
			(start -0.12065 -0.305054)
			(end -0.12065 -0.2794)
			(stroke
				(width 0.1)
				(type default)
			)
			(layer "F.Fab")
		)
		(pad "1" smd circle
			(at -0.40005 0 270)
			(size 0 0)
			(layers "F.Cu" "F.Mask" "F.Paste")
			(net "SSD12_LED_ISO_N")
		)
		(pad "2" smd circle
			(at 0.40005 0 270)
			(size 0 0)
			(layers "F.Cu" "F.Mask" "F.Paste")
			(net "SSD12_LED_ISO_R_N")
		)
	)
	(footprint ""
		(layer "F.Cu")
		(at 212.471 -228.981 180)
		(property "Reference" "R6215"
			(at 0 0 180)
			(layer "F.SilkS")
			(hide yes)
			(effects
				(font
					(size 1.27 1.27)
				)
			)
		)
		(property "Value" ""
			(at 0 0 180)
			(layer "F.Fab")
			(effects
				(font
					(size 1.27 1.27)
				)
			)
		)
		(duplicate_pad_numbers_are_jumpers no)
		(fp_line
			(start 0.7874 0.4064)
			(end -0.7874 0.4064)
			(stroke
				(width 0.1524)
				(type default)
			)
			(layer "F.SilkS")
		)
		(fp_line
			(start 0.7874 -0.4064)
			(end 0.7874 0.4064)
			(stroke
				(width 0.1524)
				(type default)
			)
			(layer "F.SilkS")
		)
		(fp_line
			(start -0.7874 0.4064)
			(end -0.7874 -0.4064)
			(stroke
				(width 0.1524)
				(type default)
			)
			(layer "F.SilkS")
		)
		(fp_line
			(start -0.7874 -0.4064)
			(end 0.7874 -0.4064)
			(stroke
				(width 0.1524)
				(type default)
			)
			(layer "F.SilkS")
		)
		(fp_line
			(start 0.67945 0.3048)
			(end 0.120396 0.3048)
			(stroke
				(width 0.1)
				(type default)
			)
			(layer "F.Fab")
		)
		(fp_line
			(start 0.67945 -0.3048)
			(end 0.67945 0.3048)
			(stroke
				(width 0.1)
				(type default)
			)
			(layer "F.Fab")
		)
		(fp_line
			(start 0.12065 -0.2794)
			(end 0.12065 -0.3048)
			(stroke
				(width 0.1)
				(type default)
			)
			(layer "F.Fab")
		)
		(fp_line
			(start 0.12065 -0.3048)
			(end 0.67945 -0.3048)
			(stroke
				(width 0.1)
				(type default)
			)
			(layer "F.Fab")
		)
		(fp_line
			(start 0.120396 0.3048)
			(end 0.120396 0.2794)
			(stroke
				(width 0.1)
				(type default)
			)
			(layer "F.Fab")
		)
		(fp_line
			(start 0.120396 0.2794)
			(end -0.12065 0.2794)
			(stroke
				(width 0.1)
				(type default)
			)
			(layer "F.Fab")
		)
		(fp_line
			(start -0.12065 0.3048)
			(end -0.67945 0.3048)
			(stroke
				(width 0.1)
				(type default)
			)
			(layer "F.Fab")
		)
		(fp_line
			(start -0.12065 0.2794)
			(end -0.12065 0.3048)
			(stroke
				(width 0.1)
				(type default)
			)
			(layer "F.Fab")
		)
		(fp_line
			(start -0.12065 -0.2794)
			(end 0.12065 -0.2794)
			(stroke
				(width 0.1)
				(type default)
			)
			(layer "F.Fab")
		)
		(fp_line
			(start -0.12065 -0.305054)
			(end -0.12065 -0.2794)
			(stroke
				(width 0.1)
				(type default)
			)
			(layer "F.Fab")
		)
		(fp_line
			(start -0.67945 0.3048)
			(end -0.67945 -0.305054)
			(stroke
				(width 0.1)
				(type default)
			)
			(layer "F.Fab")
		)
		(fp_line
			(start -0.67945 -0.305054)
			(end -0.12065 -0.305054)
			(stroke
				(width 0.1)
				(type default)
			)
			(layer "F.Fab")
		)
		(pad "1" smd circle
			(at -0.40005 0 180)
			(size 0 0)
			(layers "F.Cu" "F.Mask" "F.Paste")
			(net "PRSNT_DBV2_SLIMSAS_R")
		)
		(pad "2" smd circle
			(at 0.40005 0 180)
			(size 0 0)
			(layers "F.Cu" "F.Mask" "F.Paste")
			(net "PRSNT_DBV2_SLIMSAS")
		)
	)
	(footprint ""
		(layer "F.Cu")
		(at 262.57377 -27.006296 -90)
		(property "Reference" "PC946"
			(at 0 0 270)
			(layer "F.SilkS")
			(hide yes)
			(effects
				(font
					(size 1.27 1.27)
				)
			)
		)
		(property "Value" ""
			(at 0 0 270)
			(layer "F.Fab")
			(effects
				(font
					(size 1.27 1.27)
				)
			)
		)
		(duplicate_pad_numbers_are_jumpers no)
		(fp_line
			(start -0.7874 0.4064)
			(end -0.7874 -0.4064)
			(stroke
				(width 0.1524)
				(type default)
			)
			(layer "F.SilkS")
		)
		(fp_line
			(start 0.7874 0.4064)
			(end -0.7874 0.4064)
			(stroke
				(width 0.1524)
				(type default)
			)
			(layer "F.SilkS")
		)
		(fp_line
			(start -0.7874 -0.4064)
			(end 0.7874 -0.4064)
			(stroke
				(width 0.1524)
				(type default)
			)
			(layer "F.SilkS")
		)
		(fp_line
			(start 0.7874 -0.4064)
			(end 0.7874 0.4064)
			(stroke
				(width 0.1524)
				(type default)
			)
			(layer "F.SilkS")
		)
		(fp_line
			(start -0.67945 0.3048)
			(end -0.67945 -0.305054)
			(stroke
				(width 0.1)
				(type default)
			)
			(layer "F.Fab")
		)
		(fp_line
			(start -0.12065 0.3048)
			(end -0.67945 0.3048)
			(stroke
				(width 0.1)
				(type default)
			)
			(layer "F.Fab")
		)
		(fp_line
			(start 0.120396 0.3048)
			(end 0.120396 0.2794)
			(stroke
				(width 0.1)
				(type default)
			)
			(layer "F.Fab")
		)
		(fp_line
			(start 0.67945 0.3048)
			(end 0.120396 0.3048)
			(stroke
				(width 0.1)
				(type default)
			)
			(layer "F.Fab")
		)
		(fp_line
			(start -0.12065 0.2794)
			(end -0.12065 0.3048)
			(stroke
				(width 0.1)
				(type default)
			)
			(layer "F.Fab")
		)
		(fp_line
			(start 0.120396 0.2794)
			(end -0.12065 0.2794)
			(stroke
				(width 0.1)
				(type default)
			)
			(layer "F.Fab")
		)
		(fp_line
			(start -0.12065 -0.2794)
			(end 0.12065 -0.2794)
			(stroke
				(width 0.1)
				(type default)
			)
			(layer "F.Fab")
		)
		(fp_line
			(start 0.12065 -0.2794)
			(end 0.12065 -0.3048)
			(stroke
				(width 0.1)
				(type default)
			)
			(layer "F.Fab")
		)
		(fp_line
			(start 0.12065 -0.3048)
			(end 0.67945 -0.3048)
			(stroke
				(width 0.1)
				(type default)
			)
			(layer "F.Fab")
		)
		(fp_line
			(start 0.67945 -0.3048)
			(end 0.67945 0.3048)
			(stroke
				(width 0.1)
				(type default)
			)
			(layer "F.Fab")
		)
		(fp_line
			(start -0.67945 -0.305054)
			(end -0.12065 -0.305054)
			(stroke
				(width 0.1)
				(type default)
			)
			(layer "F.Fab")
		)
		(fp_line
			(start -0.12065 -0.305054)
			(end -0.12065 -0.2794)
			(stroke
				(width 0.1)
				(type default)
			)
			(layer "F.Fab")
		)
		(pad "1" smd circle
			(at -0.40005 0 270)
			(size 0 0)
			(layers "F.Cu" "F.Mask" "F.Paste")
			(net "P3V3_SSD9_CO_MODE")
		)
		(pad "2" smd circle
			(at 0.40005 0 270)
			(size 0 0)
			(layers "F.Cu" "F.Mask" "F.Paste")
			(net "GND")
		)
	)
	(footprint ""
		(layer "F.Cu")
		(at 289.634422 -343.952322 90)
		(property "Reference" "C594"
			(at 0 0 90)
			(layer "F.SilkS")
			(hide yes)
			(effects
				(font
					(size 1.27 1.27)
				)
			)
		)
		(property "Value" ""
			(at 0 0 90)
			(layer "F.Fab")
			(effects
				(font
					(size 1.27 1.27)
				)
			)
		)
		(duplicate_pad_numbers_are_jumpers no)
		(fp_line
			(start 0.299974 -0.150114)
			(end 0.299974 0.150114)
			(stroke
				(width 0.1)
				(type default)
			)
			(layer "F.Fab")
		)
		(fp_line
			(start -0.299974 -0.150114)
			(end 0.299974 -0.150114)
			(stroke
				(width 0.1)
				(type default)
			)
			(layer "F.Fab")
		)
		(fp_line
			(start 0.299974 0.150114)
			(end -0.299974 0.150114)
			(stroke
				(width 0.1)
				(type default)
			)
			(layer "F.Fab")
		)
		(fp_line
			(start -0.299974 0.150114)
			(end -0.299974 -0.150114)
			(stroke
				(width 0.1)
				(type default)
			)
			(layer "F.Fab")
		)
		(pad "1" smd rect
			(at -0.2667 0 90)
			(size 0.3048 0.381)
			(layers "F.Cu" "F.Mask" "F.Paste")
			(net "P5E_PEX2_STN7_TX_DN<122>")
		)
		(pad "2" smd rect
			(at 0.2667 0 90)
			(size 0.3048 0.381)
			(layers "F.Cu" "F.Mask" "F.Paste")
			(net "P5E_PEX2_STN7_TX_C_DN<122>")
		)
	)
	(footprint ""
		(layer "F.Cu")
		(at 152.738328 -109.20984)
		(property "Reference" "C265"
			(at 0 0 0)
			(layer "F.SilkS")
			(hide yes)
			(effects
				(font
					(size 1.27 1.27)
				)
			)
		)
		(property "Value" ""
			(at 0 0 0)
			(layer "F.Fab")
			(effects
				(font
					(size 1.27 1.27)
				)
			)
		)
		(duplicate_pad_numbers_are_jumpers no)
		(fp_line
			(start -0.299974 -0.150114)
			(end 0.299974 -0.150114)
			(stroke
				(width 0.1)
				(type default)
			)
			(layer "F.Fab")
		)
		(fp_line
			(start -0.299974 0.150114)
			(end -0.299974 -0.150114)
			(stroke
				(width 0.1)
				(type default)
			)
			(layer "F.Fab")
		)
		(fp_line
			(start 0.299974 -0.150114)
			(end 0.299974 0.150114)
			(stroke
				(width 0.1)
				(type default)
			)
			(layer "F.Fab")
		)
		(fp_line
			(start 0.299974 0.150114)
			(end -0.299974 0.150114)
			(stroke
				(width 0.1)
				(type default)
			)
			(layer "F.Fab")
		)
		(pad "1" smd rect
			(at -0.2667 0)
			(size 0.3048 0.381)
			(layers "F.Cu" "F.Mask" "F.Paste")
			(net "P5E_PEX1_STN1_TX_DP<21>")
		)
		(pad "2" smd rect
			(at 0.2667 0)
			(size 0.3048 0.381)
			(layers "F.Cu" "F.Mask" "F.Paste")
			(net "P5E_PEX1_STN1_TX_C_DP<21>")
		)
	)
	(footprint ""
		(layer "F.Cu")
		(at 287.439862 -343.952322 90)
		(property "Reference" "C2358"
			(at 0 0 90)
			(layer "F.SilkS")
			(hide yes)
			(effects
				(font
					(size 1.27 1.27)
				)
			)
		)
		(property "Value" ""
			(at 0 0 90)
			(layer "F.Fab")
			(effects
				(font
					(size 1.27 1.27)
				)
			)
		)
		(duplicate_pad_numbers_are_jumpers no)
		(fp_line
			(start 0.299974 -0.150114)
			(end 0.299974 0.150114)
			(stroke
				(width 0.1)
				(type default)
			)
			(layer "F.Fab")
		)
		(fp_line
			(start -0.299974 -0.150114)
			(end 0.299974 -0.150114)
			(stroke
				(width 0.1)
				(type default)
			)
			(layer "F.Fab")
		)
		(fp_line
			(start 0.299974 0.150114)
			(end -0.299974 0.150114)
			(stroke
				(width 0.1)
				(type default)
			)
			(layer "F.Fab")
		)
		(fp_line
			(start -0.299974 0.150114)
			(end -0.299974 -0.150114)
			(stroke
				(width 0.1)
				(type default)
			)
			(layer "F.Fab")
		)
		(pad "1" smd rect
			(at -0.2667 0 90)
			(size 0.3048 0.381)
			(layers "F.Cu" "F.Mask" "F.Paste")
			(net "P5E_PEX2_STN4_TX_DN<71>")
		)
		(pad "2" smd rect
			(at 0.2667 0 90)
			(size 0.3048 0.381)
			(layers "F.Cu" "F.Mask" "F.Paste")
			(net "P5E_PEX2_STN4_TX_C_DN<71>")
		)
	)
	(footprint ""
		(layer "F.Cu")
		(at 346.075 -234.061 -90)
		(property "Reference" "R3554"
			(at 0 0 270)
			(layer "F.SilkS")
			(hide yes)
			(effects
				(font
					(size 1.27 1.27)
				)
			)
		)
		(property "Value" ""
			(at 0 0 270)
			(layer "F.Fab")
			(effects
				(font
					(size 1.27 1.27)
				)
			)
		)
		(duplicate_pad_numbers_are_jumpers no)
		(fp_line
			(start -0.7874 0.4064)
			(end -0.7874 -0.4064)
			(stroke
				(width 0.1524)
				(type default)
			)
			(layer "F.SilkS")
		)
		(fp_line
			(start 0.7874 0.4064)
			(end -0.7874 0.4064)
			(stroke
				(width 0.1524)
				(type default)
			)
			(layer "F.SilkS")
		)
		(fp_line
			(start -0.7874 -0.4064)
			(end 0.7874 -0.4064)
			(stroke
				(width 0.1524)
				(type default)
			)
			(layer "F.SilkS")
		)
		(fp_line
			(start 0.7874 -0.4064)
			(end 0.7874 0.4064)
			(stroke
				(width 0.1524)
				(type default)
			)
			(layer "F.SilkS")
		)
		(fp_line
			(start -0.67945 0.3048)
			(end -0.67945 -0.305054)
			(stroke
				(width 0.1)
				(type default)
			)
			(layer "F.Fab")
		)
		(fp_line
			(start -0.12065 0.3048)
			(end -0.67945 0.3048)
			(stroke
				(width 0.1)
				(type default)
			)
			(layer "F.Fab")
		)
		(fp_line
			(start 0.120396 0.3048)
			(end 0.120396 0.2794)
			(stroke
				(width 0.1)
				(type default)
			)
			(layer "F.Fab")
		)
		(fp_line
			(start 0.67945 0.3048)
			(end 0.120396 0.3048)
			(stroke
				(width 0.1)
				(type default)
			)
			(layer "F.Fab")
		)
		(fp_line
			(start -0.12065 0.2794)
			(end -0.12065 0.3048)
			(stroke
				(width 0.1)
				(type default)
			)
			(layer "F.Fab")
		)
		(fp_line
			(start 0.120396 0.2794)
			(end -0.12065 0.2794)
			(stroke
				(width 0.1)
				(type default)
			)
			(layer "F.Fab")
		)
		(fp_line
			(start -0.12065 -0.2794)
			(end 0.12065 -0.2794)
			(stroke
				(width 0.1)
				(type default)
			)
			(layer "F.Fab")
		)
		(fp_line
			(start 0.12065 -0.2794)
			(end 0.12065 -0.3048)
			(stroke
				(width 0.1)
				(type default)
			)
			(layer "F.Fab")
		)
		(fp_line
			(start 0.12065 -0.3048)
			(end 0.67945 -0.3048)
			(stroke
				(width 0.1)
				(type default)
			)
			(layer "F.Fab")
		)
		(fp_line
			(start 0.67945 -0.3048)
			(end 0.67945 0.3048)
			(stroke
				(width 0.1)
				(type default)
			)
			(layer "F.Fab")
		)
		(fp_line
			(start -0.67945 -0.305054)
			(end -0.12065 -0.305054)
			(stroke
				(width 0.1)
				(type default)
			)
			(layer "F.Fab")
		)
		(fp_line
			(start -0.12065 -0.305054)
			(end -0.12065 -0.2794)
			(stroke
				(width 0.1)
				(type default)
			)
			(layer "F.Fab")
		)
		(pad "1" smd circle
			(at -0.40005 0 270)
			(size 0 0)
			(layers "F.Cu" "F.Mask" "F.Paste")
			(net "RST_SSD4_PERST_R_N")
		)
		(pad "2" smd circle
			(at 0.40005 0 270)
			(size 0 0)
			(layers "F.Cu" "F.Mask" "F.Paste")
			(net "RST_SSD4_PERST_N")
		)
	)
	(footprint ""
		(layer "F.Cu")
		(at 102.383336 -49.94148)
		(property "Reference" "R5895"
			(at 0 0 0)
			(layer "F.SilkS")
			(hide yes)
			(effects
				(font
					(size 1.27 1.27)
				)
			)
		)
		(property "Value" ""
			(at 0 0 0)
			(layer "F.Fab")
			(effects
				(font
					(size 1.27 1.27)
				)
			)
		)
		(duplicate_pad_numbers_are_jumpers no)
		(fp_line
			(start -0.7874 -0.4064)
			(end 0.7874 -0.4064)
			(stroke
				(width 0.1524)
				(type default)
			)
			(layer "F.SilkS")
		)
		(fp_line
			(start -0.7874 0.4064)
			(end -0.7874 -0.4064)
			(stroke
				(width 0.1524)
				(type default)
			)
			(layer "F.SilkS")
		)
		(fp_line
			(start 0.7874 -0.4064)
			(end 0.7874 0.4064)
			(stroke
				(width 0.1524)
				(type default)
			)
			(layer "F.SilkS")
		)
		(fp_line
			(start 0.7874 0.4064)
			(end -0.7874 0.4064)
			(stroke
				(width 0.1524)
				(type default)
			)
			(layer "F.SilkS")
		)
		(fp_line
			(start -0.67945 -0.305054)
			(end -0.12065 -0.305054)
			(stroke
				(width 0.1)
				(type default)
			)
			(layer "F.Fab")
		)
		(fp_line
			(start -0.67945 0.3048)
			(end -0.67945 -0.305054)
			(stroke
				(width 0.1)
				(type default)
			)
			(layer "F.Fab")
		)
		(fp_line
			(start -0.12065 -0.305054)
			(end -0.12065 -0.2794)
			(stroke
				(width 0.1)
				(type default)
			)
			(layer "F.Fab")
		)
		(fp_line
			(start -0.12065 -0.2794)
			(end 0.12065 -0.2794)
			(stroke
				(width 0.1)
				(type default)
			)
			(layer "F.Fab")
		)
		(fp_line
			(start -0.12065 0.2794)
			(end -0.12065 0.3048)
			(stroke
				(width 0.1)
				(type default)
			)
			(layer "F.Fab")
		)
		(fp_line
			(start -0.12065 0.3048)
			(end -0.67945 0.3048)
			(stroke
				(width 0.1)
				(type default)
			)
			(layer "F.Fab")
		)
		(fp_line
			(start 0.120396 0.2794)
			(end -0.12065 0.2794)
			(stroke
				(width 0.1)
				(type default)
			)
			(layer "F.Fab")
		)
		(fp_line
			(start 0.120396 0.3048)
			(end 0.120396 0.2794)
			(stroke
				(width 0.1)
				(type default)
			)
			(layer "F.Fab")
		)
		(fp_line
			(start 0.12065 -0.3048)
			(end 0.67945 -0.3048)
			(stroke
				(width 0.1)
				(type default)
			)
			(layer "F.Fab")
		)
		(fp_line
			(start 0.12065 -0.2794)
			(end 0.12065 -0.3048)
			(stroke
				(width 0.1)
				(type default)
			)
			(layer "F.Fab")
		)
		(fp_line
			(start 0.67945 -0.3048)
			(end 0.67945 0.3048)
			(stroke
				(width 0.1)
				(type default)
			)
			(layer "F.Fab")
		)
		(fp_line
			(start 0.67945 0.3048)
			(end 0.120396 0.3048)
			(stroke
				(width 0.1)
				(type default)
			)
			(layer "F.Fab")
		)
		(pad "1" smd circle
			(at -0.40005 0)
			(size 0 0)
			(layers "F.Cu" "F.Mask" "F.Paste")
			(net "SSD3_ADC_A0")
		)
		(pad "2" smd circle
			(at 0.40005 0)
			(size 0 0)
			(layers "F.Cu" "F.Mask" "F.Paste")
			(net "SMB_SSD3_ADC_SCL")
		)
	)
	(footprint ""
		(layer "F.Cu")
		(at 161.896298 -47.20082 90)
		(property "Reference" "C313"
			(at 0 0 90)
			(layer "F.SilkS")
			(hide yes)
			(effects
				(font
					(size 1.27 1.27)
				)
			)
		)
		(property "Value" ""
			(at 0 0 90)
			(layer "F.Fab")
			(effects
				(font
					(size 1.27 1.27)
				)
			)
		)
		(duplicate_pad_numbers_are_jumpers no)
		(fp_line
			(start 0.7874 -0.4064)
			(end 0.7874 0.4064)
			(stroke
				(width 0.1524)
				(type default)
			)
			(layer "F.SilkS")
		)
		(fp_line
			(start -0.7874 -0.4064)
			(end 0.7874 -0.4064)
			(stroke
				(width 0.1524)
				(type default)
			)
			(layer "F.SilkS")
		)
		(fp_line
			(start 0.7874 0.4064)
			(end -0.7874 0.4064)
			(stroke
				(width 0.1524)
				(type default)
			)
			(layer "F.SilkS")
		)
		(fp_line
			(start -0.7874 0.4064)
			(end -0.7874 -0.4064)
			(stroke
				(width 0.1524)
				(type default)
			)
			(layer "F.SilkS")
		)
		(fp_line
			(start -0.12065 -0.305054)
			(end -0.12065 -0.2794)
			(stroke
				(width 0.1)
				(type default)
			)
			(layer "F.Fab")
		)
		(fp_line
			(start -0.67945 -0.305054)
			(end -0.12065 -0.305054)
			(stroke
				(width 0.1)
				(type default)
			)
			(layer "F.Fab")
		)
		(fp_line
			(start 0.67945 -0.3048)
			(end 0.67945 0.3048)
			(stroke
				(width 0.1)
				(type default)
			)
			(layer "F.Fab")
		)
		(fp_line
			(start 0.12065 -0.3048)
			(end 0.67945 -0.3048)
			(stroke
				(width 0.1)
				(type default)
			)
			(layer "F.Fab")
		)
		(fp_line
			(start 0.12065 -0.2794)
			(end 0.12065 -0.3048)
			(stroke
				(width 0.1)
				(type default)
			)
			(layer "F.Fab")
		)
		(fp_line
			(start -0.12065 -0.2794)
			(end 0.12065 -0.2794)
			(stroke
				(width 0.1)
				(type default)
			)
			(layer "F.Fab")
		)
		(fp_line
			(start 0.120396 0.2794)
			(end -0.12065 0.2794)
			(stroke
				(width 0.1)
				(type default)
			)
			(layer "F.Fab")
		)
		(fp_line
			(start -0.12065 0.2794)
			(end -0.12065 0.3048)
			(stroke
				(width 0.1)
				(type default)
			)
			(layer "F.Fab")
		)
		(fp_line
			(start 0.67945 0.3048)
			(end 0.120396 0.3048)
			(stroke
				(width 0.1)
				(type default)
			)
			(layer "F.Fab")
		)
		(fp_line
			(start 0.120396 0.3048)
			(end 0.120396 0.2794)
			(stroke
				(width 0.1)
				(type default)
			)
			(layer "F.Fab")
		)
		(fp_line
			(start -0.12065 0.3048)
			(end -0.67945 0.3048)
			(stroke
				(width 0.1)
				(type default)
			)
			(layer "F.Fab")
		)
		(fp_line
			(start -0.67945 0.3048)
			(end -0.67945 -0.305054)
			(stroke
				(width 0.1)
				(type default)
			)
			(layer "F.Fab")
		)
		(pad "1" smd circle
			(at -0.40005 0 90)
			(size 0 0)
			(layers "F.Cu" "F.Mask" "F.Paste")
			(net "P12V_SSD5_R")
		)
		(pad "2" smd circle
			(at 0.40005 0 90)
			(size 0 0)
			(layers "F.Cu" "F.Mask" "F.Paste")
			(net "GND")
		)
	)
	(footprint ""
		(layer "F.Cu")
		(at 359.85831 -255.210564 180)
		(property "Reference" "C835"
			(at 0 0 180)
			(layer "F.SilkS")
			(hide yes)
			(effects
				(font
					(size 1.27 1.27)
				)
			)
		)
		(property "Value" ""
			(at 0 0 180)
			(layer "F.Fab")
			(effects
				(font
					(size 1.27 1.27)
				)
			)
		)
		(duplicate_pad_numbers_are_jumpers no)
		(fp_line
			(start 0.7874 0.4064)
			(end -0.7874 0.4064)
			(stroke
				(width 0.1524)
				(type default)
			)
			(layer "F.SilkS")
		)
		(fp_line
			(start 0.7874 -0.4064)
			(end 0.7874 0.4064)
			(stroke
				(width 0.1524)
				(type default)
			)
			(layer "F.SilkS")
		)
		(fp_line
			(start -0.7874 0.4064)
			(end -0.7874 -0.4064)
			(stroke
				(width 0.1524)
				(type default)
			)
			(layer "F.SilkS")
		)
		(fp_line
			(start -0.7874 -0.4064)
			(end 0.7874 -0.4064)
			(stroke
				(width 0.1524)
				(type default)
			)
			(layer "F.SilkS")
		)
		(fp_line
			(start 0.67945 0.3048)
			(end 0.120396 0.3048)
			(stroke
				(width 0.1)
				(type default)
			)
			(layer "F.Fab")
		)
		(fp_line
			(start 0.67945 -0.3048)
			(end 0.67945 0.3048)
			(stroke
				(width 0.1)
				(type default)
			)
			(layer "F.Fab")
		)
		(fp_line
			(start 0.12065 -0.2794)
			(end 0.12065 -0.3048)
			(stroke
				(width 0.1)
				(type default)
			)
			(layer "F.Fab")
		)
		(fp_line
			(start 0.12065 -0.3048)
			(end 0.67945 -0.3048)
			(stroke
				(width 0.1)
				(type default)
			)
			(layer "F.Fab")
		)
		(fp_line
			(start 0.120396 0.3048)
			(end 0.120396 0.2794)
			(stroke
				(width 0.1)
				(type default)
			)
			(layer "F.Fab")
		)
		(fp_line
			(start 0.120396 0.2794)
			(end -0.12065 0.2794)
			(stroke
				(width 0.1)
				(type default)
			)
			(layer "F.Fab")
		)
		(fp_line
			(start -0.12065 0.3048)
			(end -0.67945 0.3048)
			(stroke
				(width 0.1)
				(type default)
			)
			(layer "F.Fab")
		)
		(fp_line
			(start -0.12065 0.2794)
			(end -0.12065 0.3048)
			(stroke
				(width 0.1)
				(type default)
			)
			(layer "F.Fab")
		)
		(fp_line
			(start -0.12065 -0.2794)
			(end 0.12065 -0.2794)
			(stroke
				(width 0.1)
				(type default)
			)
			(layer "F.Fab")
		)
		(fp_line
			(start -0.12065 -0.305054)
			(end -0.12065 -0.2794)
			(stroke
				(width 0.1)
				(type default)
			)
			(layer "F.Fab")
		)
		(fp_line
			(start -0.67945 0.3048)
			(end -0.67945 -0.305054)
			(stroke
				(width 0.1)
				(type default)
			)
			(layer "F.Fab")
		)
		(fp_line
			(start -0.67945 -0.305054)
			(end -0.12065 -0.305054)
			(stroke
				(width 0.1)
				(type default)
			)
			(layer "F.Fab")
		)
		(pad "1" smd circle
			(at -0.40005 0 180)
			(size 0 0)
			(layers "F.Cu" "F.Mask" "F.Paste")
			(net "GND")
		)
		(pad "2" smd circle
			(at 0.40005 0 180)
			(size 0 0)
			(layers "F.Cu" "F.Mask" "F.Paste")
			(net "FM_P0V8_PEX2_EN_R")
		)
	)
	(footprint ""
		(layer "F.Cu")
		(at 446.099438 -258.331208 -90)
		(property "Reference" "R6559"
			(at 0 0 270)
			(layer "F.SilkS")
			(hide yes)
			(effects
				(font
					(size 1.27 1.27)
				)
			)
		)
		(property "Value" ""
			(at 0 0 270)
			(layer "F.Fab")
			(effects
				(font
					(size 1.27 1.27)
				)
			)
		)
		(duplicate_pad_numbers_are_jumpers no)
		(fp_line
			(start -0.7874 0.4064)
			(end -0.7874 -0.4064)
			(stroke
				(width 0.1524)
				(type default)
			)
			(layer "F.SilkS")
		)
		(fp_line
			(start 0.7874 0.4064)
			(end -0.7874 0.4064)
			(stroke
				(width 0.1524)
				(type default)
			)
			(layer "F.SilkS")
		)
		(fp_line
			(start -0.7874 -0.4064)
			(end 0.7874 -0.4064)
			(stroke
				(width 0.1524)
				(type default)
			)
			(layer "F.SilkS")
		)
		(fp_line
			(start 0.7874 -0.4064)
			(end 0.7874 0.4064)
			(stroke
				(width 0.1524)
				(type default)
			)
			(layer "F.SilkS")
		)
		(fp_line
			(start -0.67945 0.3048)
			(end -0.67945 -0.305054)
			(stroke
				(width 0.1)
				(type default)
			)
			(layer "F.Fab")
		)
		(fp_line
			(start -0.12065 0.3048)
			(end -0.67945 0.3048)
			(stroke
				(width 0.1)
				(type default)
			)
			(layer "F.Fab")
		)
		(fp_line
			(start 0.120396 0.3048)
			(end 0.120396 0.2794)
			(stroke
				(width 0.1)
				(type default)
			)
			(layer "F.Fab")
		)
		(fp_line
			(start 0.67945 0.3048)
			(end 0.120396 0.3048)
			(stroke
				(width 0.1)
				(type default)
			)
			(layer "F.Fab")
		)
		(fp_line
			(start -0.12065 0.2794)
			(end -0.12065 0.3048)
			(stroke
				(width 0.1)
				(type default)
			)
			(layer "F.Fab")
		)
		(fp_line
			(start 0.120396 0.2794)
			(end -0.12065 0.2794)
			(stroke
				(width 0.1)
				(type default)
			)
			(layer "F.Fab")
		)
		(fp_line
			(start -0.12065 -0.2794)
			(end 0.12065 -0.2794)
			(stroke
				(width 0.1)
				(type default)
			)
			(layer "F.Fab")
		)
		(fp_line
			(start 0.12065 -0.2794)
			(end 0.12065 -0.3048)
			(stroke
				(width 0.1)
				(type default)
			)
			(layer "F.Fab")
		)
		(fp_line
			(start 0.12065 -0.3048)
			(end 0.67945 -0.3048)
			(stroke
				(width 0.1)
				(type default)
			)
			(layer "F.Fab")
		)
		(fp_line
			(start 0.67945 -0.3048)
			(end 0.67945 0.3048)
			(stroke
				(width 0.1)
				(type default)
			)
			(layer "F.Fab")
		)
		(fp_line
			(start -0.67945 -0.305054)
			(end -0.12065 -0.305054)
			(stroke
				(width 0.1)
				(type default)
			)
			(layer "F.Fab")
		)
		(fp_line
			(start -0.12065 -0.305054)
			(end -0.12065 -0.2794)
			(stroke
				(width 0.1)
				(type default)
			)
			(layer "F.Fab")
		)
		(pad "1" smd circle
			(at -0.40005 0 270)
			(size 0 0)
			(layers "F.Cu" "F.Mask" "F.Paste")
			(net "P1V25_SERDES_VDDPLL_PEX3")
		)
		(pad "2" smd circle
			(at 0.40005 0 270)
			(size 0 0)
			(layers "F.Cu" "F.Mask" "F.Paste")
			(net "P1V25_SERDES_VDDPLL_PEX3_C6")
		)
	)
	(footprint ""
		(layer "F.Cu")
		(at 38.96487 -26.785062 180)
		(property "Reference" "J31"
			(at 3.8608 -10.884662 90)
			(unlocked yes)
			(layer "F.SilkS")
			(effects
				(font
					(size 0.7874 0.5842)
					(thickness 0.1524)
				)
			)
		)
		(property "Value" ""
			(at 0 0 180)
			(layer "F.Fab")
			(effects
				(font
					(size 1.27 1.27)
				)
			)
		)
		(duplicate_pad_numbers_are_jumpers no)
		(fp_line
			(start 3.150108 12.115038)
			(end 1.529334 12.115038)
			(stroke
				(width 0.1524)
				(type default)
			)
			(layer "F.SilkS")
		)
		(fp_line
			(start 3.074924 12.014962)
			(end 1.632204 12.014962)
			(stroke
				(width 0.1524)
				(type default)
			)
			(layer "F.SilkS")
		)
		(fp_line
			(start 1.632204 -12.014962)
			(end 3.074924 -12.014962)
			(stroke
				(width 0.1524)
				(type default)
			)
			(layer "F.SilkS")
		)
		(fp_line
			(start 1.529334 -12.115038)
			(end 3.150108 -12.115038)
			(stroke
				(width 0.1524)
				(type default)
			)
			(layer "F.SilkS")
		)
		(fp_line
			(start -1.529334 12.115038)
			(end -3.150108 12.115038)
			(stroke
				(width 0.1524)
				(type default)
			)
			(layer "F.SilkS")
		)
		(fp_line
			(start -1.632204 12.014962)
			(end -3.074924 12.014962)
			(stroke
				(width 0.1524)
				(type default)
			)
			(layer "F.SilkS")
		)
		(fp_line
			(start -3.074924 -12.014962)
			(end -1.632204 -12.014962)
			(stroke
				(width 0.1524)
				(type default)
			)
			(layer "F.SilkS")
		)
		(fp_line
			(start -3.150108 -12.115038)
			(end -1.529334 -12.115038)
			(stroke
				(width 0.1524)
				(type default)
			)
			(layer "F.SilkS")
		)
		(fp_poly
			(pts
				(xy 3.291078 -8.609584) (xy 3.71348 -9.877298) (xy 4.558538 -9.03224)
			)
			(stroke
				(width 0)
				(type default)
			)
			(fill yes)
			(layer "F.SilkS")
		)
		(fp_line
			(start 3.074924 12.014962)
			(end -3.074924 12.014962)
			(stroke
				(width 0.1)
				(type default)
			)
			(layer "F.Fab")
		)
		(fp_line
			(start 3.074924 -12.014962)
			(end 3.074924 12.014962)
			(stroke
				(width 0.1)
				(type default)
			)
			(layer "F.Fab")
		)
		(fp_line
			(start -3.074924 12.014962)
			(end -3.074924 -12.014962)
			(stroke
				(width 0.1)
				(type default)
			)
			(layer "F.Fab")
		)
		(fp_line
			(start -3.074924 -12.014962)
			(end 3.074924 -12.014962)
			(stroke
				(width 0.1)
				(type default)
			)
			(layer "F.Fab")
		)
		(fp_poly
			(pts
				(xy 3.348736 -7.994904) (xy 4.543806 -8.592566) (xy 4.543806 -7.397496)
			)
			(stroke
				(width 0)
				(type default)
			)
			(fill yes)
			(layer "F.Fab")
		)
		(pad "" np_thru_hole circle
			(at -1.75006 -9.815068 90)
			(size 1.1176 1.1176)
			(drill 1.1176)
			(layers "*.Cu" "*.Mask")
			(clearance 0.381)
			(thermal_gap 0.381)
		)
		(pad "" np_thru_hole circle
			(at 0 9.815068 90)
			(size 1.1176 1.1176)
			(drill 1.1176)
			(layers "*.Cu" "*.Mask")
			(clearance 0.381)
			(thermal_gap 0.381)
		)
		(pad "A1" smd rect
			(at 2.29997 -7.994904 90)
			(size 0.381 1.27)
			(layers "F.Cu" "F.Mask" "F.Paste")
			(net "GND")
		)
		(pad "A2" smd rect
			(at 2.29997 -7.394956 90)
			(size 0.381 1.27)
			(layers "F.Cu" "F.Mask" "F.Paste")
			(net "GND")
		)
		(pad "A3" smd rect
			(at 2.29997 -6.795008 90)
			(size 0.381 1.27)
			(layers "F.Cu" "F.Mask" "F.Paste")
			(net "GND")
		)
		(pad "A4" smd rect
			(at 2.29997 -6.19506 90)
			(size 0.381 1.27)
			(layers "F.Cu" "F.Mask" "F.Paste")
			(net "GND")
		)
		(pad "A5" smd rect
			(at 2.29997 -5.595112 90)
			(size 0.381 1.27)
			(layers "F.Cu" "F.Mask" "F.Paste")
			(net "GND")
		)
		(pad "A6" smd rect
			(at 2.29997 -4.99491 90)
			(size 0.381 1.27)
			(layers "F.Cu" "F.Mask" "F.Paste")
			(net "GND")
		)
		(pad "A7" smd rect
			(at 2.29997 -4.394962 90)
			(size 0.381 1.27)
			(layers "F.Cu" "F.Mask" "F.Paste")
			(net "SMB_ISO_SSD1_R_SCL")
		)
		(pad "A8" smd rect
			(at 2.29997 -3.795014 90)
			(size 0.381 1.27)
			(layers "F.Cu" "F.Mask" "F.Paste")
			(net "SMB_ISO_SSD1_R_SDA")
		)
		(pad "A9" smd rect
			(at 2.29997 -3.195066 90)
			(size 0.381 1.27)
			(layers "F.Cu" "F.Mask" "F.Paste")
			(net "RST_SMB_SSD1_ISO_R_N")
		)
		(pad "A10" smd rect
			(at 2.29997 -2.595118 90)
			(size 0.381 1.27)
			(layers "F.Cu" "F.Mask" "F.Paste")
			(net "SSD1_LED_ISO_R_N")
		)
		(pad "A11" smd rect
			(at 2.29997 -1.994916 90)
			(size 0.381 1.27)
			(layers "F.Cu" "F.Mask" "F.Paste")
			(net "PU_CLKREQ1")
		)
		(pad "A12" smd rect
			(at 2.29997 -1.394968 90)
			(size 0.381 1.27)
			(layers "F.Cu" "F.Mask" "F.Paste")
			(net "PRSNT_SSD1_N")
		)
		(pad "A13" smd rect
			(at 2.29997 -0.79502 90)
			(size 0.381 1.27)
			(layers "F.Cu" "F.Mask" "F.Paste")
			(net "GND")
		)
		(pad "A14" smd rect
			(at 2.29997 -0.195072 90)
			(size 0.381 1.27)
			(layers "F.Cu" "F.Mask" "F.Paste")
			(net "Net_8579")
		)
		(pad "A15" smd rect
			(at 2.29997 0.404876 90)
			(size 0.381 1.27)
			(layers "F.Cu" "F.Mask" "F.Paste")
			(net "Net_8578")
		)
		(pad "A16" smd rect
			(at 2.29997 1.005078 90)
			(size 0.381 1.27)
			(layers "F.Cu" "F.Mask" "F.Paste")
			(net "GND")
		)
		(pad "A17" smd rect
			(at 2.29997 1.605026 90)
			(size 0.381 1.27)
			(layers "F.Cu" "F.Mask" "F.Paste")
			(net "P5E_PEX0_STN2_RX_DN<40>")
		)
		(pad "A18" smd rect
			(at 2.29997 2.204974 90)
			(size 0.381 1.27)
			(layers "F.Cu" "F.Mask" "F.Paste")
			(net "P5E_PEX0_STN2_RX_DP<40>")
		)
		(pad "A19" smd rect
			(at 2.29997 2.804922 90)
			(size 0.381 1.27)
			(layers "F.Cu" "F.Mask" "F.Paste")
			(net "GND")
		)
		(pad "A20" smd rect
			(at 2.29997 3.405124 90)
			(size 0.381 1.27)
			(layers "F.Cu" "F.Mask" "F.Paste")
			(net "P5E_PEX0_STN2_RX_DN<41>")
		)
		(pad "A21" smd rect
			(at 2.29997 4.005072 90)
			(size 0.381 1.27)
			(layers "F.Cu" "F.Mask" "F.Paste")
			(net "P5E_PEX0_STN2_RX_DP<41>")
		)
		(pad "A22" smd rect
			(at 2.29997 4.60502 90)
			(size 0.381 1.27)
			(layers "F.Cu" "F.Mask" "F.Paste")
			(net "GND")
		)
		(pad "A23" smd rect
			(at 2.29997 5.204968 90)
			(size 0.381 1.27)
			(layers "F.Cu" "F.Mask" "F.Paste")
			(net "P5E_PEX0_STN2_RX_DN<42>")
		)
		(pad "A24" smd rect
			(at 2.29997 5.804916 90)
			(size 0.381 1.27)
			(layers "F.Cu" "F.Mask" "F.Paste")
			(net "P5E_PEX0_STN2_RX_DP<42>")
		)
		(pad "A25" smd rect
			(at 2.29997 6.405118 90)
			(size 0.381 1.27)
			(layers "F.Cu" "F.Mask" "F.Paste")
			(net "GND")
		)
		(pad "A26" smd rect
			(at 2.29997 7.005066 90)
			(size 0.381 1.27)
			(layers "F.Cu" "F.Mask" "F.Paste")
			(net "P5E_PEX0_STN2_RX_DN<43>")
		)
		(pad "A27" smd rect
			(at 2.29997 7.605014 90)
			(size 0.381 1.27)
			(layers "F.Cu" "F.Mask" "F.Paste")
			(net "P5E_PEX0_STN2_RX_DP<43>")
		)
		(pad "A28" smd rect
			(at 2.29997 8.204962 90)
			(size 0.381 1.27)
			(layers "F.Cu" "F.Mask" "F.Paste")
			(net "GND")
		)
		(pad "B1" smd rect
			(at -2.29997 -7.994904 90)
			(size 0.381 1.27)
			(layers "F.Cu" "F.Mask" "F.Paste")
			(net "P12V_SSD1")
		)
		(pad "B2" smd rect
			(at -2.29997 -7.394956 90)
			(size 0.381 1.27)
			(layers "F.Cu" "F.Mask" "F.Paste")
			(net "P12V_SSD1")
		)
		(pad "B3" smd rect
			(at -2.29997 -6.795008 90)
			(size 0.381 1.27)
			(layers "F.Cu" "F.Mask" "F.Paste")
			(net "P12V_SSD1")
		)
		(pad "B4" smd rect
			(at -2.29997 -6.19506 90)
			(size 0.381 1.27)
			(layers "F.Cu" "F.Mask" "F.Paste")
			(net "P12V_SSD1")
		)
		(pad "B5" smd rect
			(at -2.29997 -5.595112 90)
			(size 0.381 1.27)
			(layers "F.Cu" "F.Mask" "F.Paste")
			(net "P12V_SSD1")
		)
		(pad "B6" smd rect
			(at -2.29997 -4.99491 90)
			(size 0.381 1.27)
			(layers "F.Cu" "F.Mask" "F.Paste")
			(net "P12V_SSD1")
		)
		(pad "B7" smd rect
			(at -2.29997 -4.394962 90)
			(size 0.381 1.27)
			(layers "F.Cu" "F.Mask" "F.Paste")
			(net "Net_8580")
		)
		(pad "B8" smd rect
			(at -2.29997 -3.795014 90)
			(size 0.381 1.27)
			(layers "F.Cu" "F.Mask" "F.Paste")
			(net "Net_8577")
		)
		(pad "B9" smd rect
			(at -2.29997 -3.195066 90)
			(size 0.381 1.27)
			(layers "F.Cu" "F.Mask" "F.Paste")
			(net "DUALPORT_N_SSD1")
		)
		(pad "B10" smd rect
			(at -2.29997 -2.595118 90)
			(size 0.381 1.27)
			(layers "F.Cu" "F.Mask" "F.Paste")
			(net "RST_SSD1_PERST_R_N")
		)
		(pad "B11" smd rect
			(at -2.29997 -1.994916 90)
			(size 0.381 1.27)
			(layers "F.Cu" "F.Mask" "F.Paste")
			(net "P3V3_SSD1")
		)
		(pad "B12" smd rect
			(at -2.29997 -1.394968 90)
			(size 0.381 1.27)
			(layers "F.Cu" "F.Mask" "F.Paste")
			(net "SSD1_PWRDIS_R")
		)
		(pad "B13" smd rect
			(at -2.29997 -0.79502 90)
			(size 0.381 1.27)
			(layers "F.Cu" "F.Mask" "F.Paste")
			(net "GND")
		)
		(pad "B14" smd rect
			(at -2.29997 -0.195072 90)
			(size 0.381 1.27)
			(layers "F.Cu" "F.Mask" "F.Paste")
			(net "CLK_100M_DB800ZL_SSD1_R_DN")
		)
		(pad "B15" smd rect
			(at -2.29997 0.404876 90)
			(size 0.381 1.27)
			(layers "F.Cu" "F.Mask" "F.Paste")
			(net "CLK_100M_DB800ZL_SSD1_R_DP")
		)
		(pad "B16" smd rect
			(at -2.29997 1.005078 90)
			(size 0.381 1.27)
			(layers "F.Cu" "F.Mask" "F.Paste")
			(net "GND")
		)
		(pad "B17" smd rect
			(at -2.29997 1.605026 90)
			(size 0.381 1.27)
			(layers "F.Cu" "F.Mask" "F.Paste")
			(net "P5E_PEX0_STN2_TX_C_DN<40>")
		)
		(pad "B18" smd rect
			(at -2.29997 2.204974 90)
			(size 0.381 1.27)
			(layers "F.Cu" "F.Mask" "F.Paste")
			(net "P5E_PEX0_STN2_TX_C_DP<40>")
		)
		(pad "B19" smd rect
			(at -2.29997 2.804922 90)
			(size 0.381 1.27)
			(layers "F.Cu" "F.Mask" "F.Paste")
			(net "GND")
		)
		(pad "B20" smd rect
			(at -2.29997 3.405124 90)
			(size 0.381 1.27)
			(layers "F.Cu" "F.Mask" "F.Paste")
			(net "P5E_PEX0_STN2_TX_C_DN<41>")
		)
		(pad "B21" smd rect
			(at -2.29997 4.005072 90)
			(size 0.381 1.27)
			(layers "F.Cu" "F.Mask" "F.Paste")
			(net "P5E_PEX0_STN2_TX_C_DP<41>")
		)
		(pad "B22" smd rect
			(at -2.29997 4.60502 90)
			(size 0.381 1.27)
			(layers "F.Cu" "F.Mask" "F.Paste")
			(net "GND")
		)
		(pad "B23" smd rect
			(at -2.29997 5.204968 90)
			(size 0.381 1.27)
			(layers "F.Cu" "F.Mask" "F.Paste")
			(net "P5E_PEX0_STN2_TX_C_DN<42>")
		)
		(pad "B24" smd rect
			(at -2.29997 5.804916 90)
			(size 0.381 1.27)
			(layers "F.Cu" "F.Mask" "F.Paste")
			(net "P5E_PEX0_STN2_TX_C_DP<42>")
		)
		(pad "B25" smd rect
			(at -2.29997 6.405118 90)
			(size 0.381 1.27)
			(layers "F.Cu" "F.Mask" "F.Paste")
			(net "GND")
		)
		(pad "B26" smd rect
			(at -2.29997 7.005066 90)
			(size 0.381 1.27)
			(layers "F.Cu" "F.Mask" "F.Paste")
			(net "P5E_PEX0_STN2_TX_C_DN<43>")
		)
		(pad "B27" smd rect
			(at -2.29997 7.605014 90)
			(size 0.381 1.27)
			(layers "F.Cu" "F.Mask" "F.Paste")
			(net "P5E_PEX0_STN2_TX_C_DP<43>")
		)
		(pad "B28" smd rect
			(at -2.29997 8.204962 90)
			(size 0.381 1.27)
			(layers "F.Cu" "F.Mask" "F.Paste")
			(net "GND")
		)
		(pad "G1" thru_hole oval
			(at 0 -11.364976 90)
			(size 1.6256 3.4798)
			(drill oval 1.1176 2.4638)
			(layers "*.Cu" "*.Mask")
			(remove_unused_layers no)
			(net "GND")
			(clearance 0.127)
			(thermal_gap 0.127)
		)
		(pad "G2" thru_hole oval
			(at 0 11.364976 90)
			(size 1.6256 3.4798)
			(drill oval 1.1176 2.4638)
			(layers "*.Cu" "*.Mask")
			(remove_unused_layers no)
			(net "GND")
			(clearance 0.127)
			(thermal_gap 0.127)
		)
		(zone
			(layer "F.Cu")
			(hatch none 0.5)
			(connect_pads
				(clearance 0)
			)
			(min_thickness 0.25)
			(keepout
				(tracks not_allowed)
				(vias allowed)
				(pads allowed)
				(copperpour not_allowed)
				(footprints allowed)
			)
			(placement
				(enabled no)
				(sheetname "")
			)
			(fill
				(thermal_gap 0.5)
				(thermal_bridge_width 0.5)
				(island_removal_mode 0)
			)
			(polygon
				(pts
					(xy 40.344852 -38.850062) (xy 37.594794 -38.850062) (xy 37.594794 -35.900106) (xy 40.344852 -35.900106)
				)
			)
		)
		(zone
			(layer "F.Cu")
			(hatch none 0.5)
			(connect_pads
				(clearance 0)
			)
			(min_thickness 0.25)
			(keepout
				(tracks not_allowed)
				(vias allowed)
				(pads allowed)
				(copperpour not_allowed)
				(footprints allowed)
			)
			(placement
				(enabled no)
				(sheetname "")
			)
			(fill
				(thermal_gap 0.5)
				(thermal_bridge_width 0.5)
				(island_removal_mode 0)
			)
			(polygon
				(pts
					(xy 41.414954 -17.670018) (xy 37.584888 -17.670018) (xy 37.584888 -14.720062) (xy 41.414954 -14.720062)
				)
			)
		)
		(zone
			(layers "F.Cu" "B.Cu" "In1.Cu" "In2.Cu" "In3.Cu" "In4.Cu" "In5.Cu" "In6.Cu"
				"In7.Cu" "In8.Cu" "In9.Cu" "In10.Cu" "In11.Cu" "In12.Cu" "In13.Cu" "In14.Cu"
				"In15.Cu" "In16.Cu"
			)
			(hatch none 0.5)
			(connect_pads
				(clearance 0)
			)
			(min_thickness 0.25)
			(keepout
				(tracks not_allowed)
				(vias allowed)
				(pads allowed)
				(copperpour not_allowed)
				(footprints allowed)
			)
			(placement
				(enabled no)
				(sheetname "")
			)
			(fill
				(thermal_gap 0.5)
				(thermal_bridge_width 0.5)
				(island_removal_mode 0)
			)
			(polygon
				(pts
					(arc
						(start 39.93007 -36.60013)
						(mid 37.99967 -36.60013)
						(end 39.93007 -36.60013)
					)
				)
			)
		)
		(zone
			(layers "F.Cu" "B.Cu" "In1.Cu" "In2.Cu" "In3.Cu" "In4.Cu" "In5.Cu" "In6.Cu"
				"In7.Cu" "In8.Cu" "In9.Cu" "In10.Cu" "In11.Cu" "In12.Cu" "In13.Cu" "In14.Cu"
				"In15.Cu" "In16.Cu"
			)
			(hatch none 0.5)
			(connect_pads
				(clearance 0)
			)
			(min_thickness 0.25)
			(keepout
				(tracks not_allowed)
				(vias allowed)
				(pads allowed)
				(copperpour not_allowed)
				(footprints allowed)
			)
			(placement
				(enabled no)
				(sheetname "")
			)
			(fill
				(thermal_gap 0.5)
				(thermal_bridge_width 0.5)
				(island_removal_mode 0)
			)
			(polygon
				(pts
					(arc
						(start 41.68013 -16.969994)
						(mid 39.74973 -16.969994)
						(end 41.68013 -16.969994)
					)
				)
			)
		)
	)
	(footprint ""
		(layer "F.Cu")
		(at 238.123476 -44.451524)
		(property "Reference" "PD68"
			(at 1.500124 2.136394 0)
			(unlocked yes)
			(layer "F.SilkS")
			(effects
				(font
					(size 0.7874 0.5842)
					(thickness 0.1524)
				)
				(justify left)
			)
		)
		(property "Value" ""
			(at 0 0 0)
			(layer "F.Fab")
			(effects
				(font
					(size 1.27 1.27)
				)
			)
		)
		(duplicate_pad_numbers_are_jumpers no)
		(fp_line
			(start -3.400044 -1.459992)
			(end 4.107942 -1.459992)
			(stroke
				(width 0.1524)
				(type default)
			)
			(layer "F.SilkS")
		)
		(fp_line
			(start -3.400044 1.459992)
			(end -3.400044 -1.459992)
			(stroke
				(width 0.1524)
				(type default)
			)
			(layer "F.SilkS")
		)
		(fp_line
			(start 4.107942 -1.459992)
			(end 4.107942 1.459992)
			(stroke
				(width 0.1524)
				(type default)
			)
			(layer "F.SilkS")
		)
		(fp_line
			(start 4.107942 1.459992)
			(end -3.400044 1.459992)
			(stroke
				(width 0.1524)
				(type default)
			)
			(layer "F.SilkS")
		)
		(fp_poly
			(pts
				(xy 4.107942 -1.459992) (xy 4.107942 1.459992) (xy 3.308096 1.459992) (xy 3.308096 -1.459992)
			)
			(stroke
				(width 0)
				(type default)
			)
			(fill yes)
			(layer "F.SilkS")
		)
		(fp_line
			(start -2.29997 -1.459992)
			(end 2.29997 -1.459992)
			(stroke
				(width 0.1)
				(type default)
			)
			(layer "F.Fab")
		)
		(fp_line
			(start -2.29997 1.459992)
			(end -2.29997 -1.459992)
			(stroke
				(width 0.1)
				(type default)
			)
			(layer "F.Fab")
		)
		(fp_line
			(start 2.29997 -1.459992)
			(end 2.29997 1.459992)
			(stroke
				(width 0.1)
				(type default)
			)
			(layer "F.Fab")
		)
		(fp_line
			(start 2.29997 1.459992)
			(end -2.29997 1.459992)
			(stroke
				(width 0.1)
				(type default)
			)
			(layer "F.Fab")
		)
		(fp_text user "+"
			(at -4.7752 -0.12065 0)
			(unlocked yes)
			(layer "F.SilkS")
			(effects
				(font
					(size 1.905 1.4224)
					(thickness 0.1524)
				)
				(justify left)
			)
		)
		(fp_text user "-"
			(at 5.4102 0.29845 180)
			(unlocked yes)
			(layer "F.SilkS")
			(effects
				(font
					(size 1.905 1.4224)
					(thickness 0.1524)
				)
				(justify left)
			)
		)
		(fp_text user "+"
			(at -4.7752 -0.12065 0)
			(unlocked yes)
			(layer "F.Fab")
			(effects
				(font
					(size 1.905 1.4224)
					(thickness 0.1524)
				)
				(justify left)
			)
		)
		(fp_text user "-"
			(at 5.4102 0.29845 180)
			(unlocked yes)
			(layer "F.Fab")
			(effects
				(font
					(size 1.905 1.4224)
					(thickness 0.1524)
				)
				(justify left)
			)
		)
		(pad "A" smd rect
			(at -1.999996 0 90)
			(size 1.7018 2.5146)
			(layers "F.Cu" "F.Mask" "F.Paste")
			(net "GND")
		)
		(pad "C" smd rect
			(at 1.999996 0 90)
			(size 1.7018 2.5146)
			(layers "F.Cu" "F.Mask" "F.Paste")
			(net "P3V3_SSD8")
		)
	)
	(footprint ""
		(layer "F.Cu")
		(at 297.55719 -213.523068 -90)
		(property "Reference" "R3395"
			(at 0 0 270)
			(layer "F.SilkS")
			(hide yes)
			(effects
				(font
					(size 1.27 1.27)
				)
			)
		)
		(property "Value" ""
			(at 0 0 270)
			(layer "F.Fab")
			(effects
				(font
					(size 1.27 1.27)
				)
			)
		)
		(duplicate_pad_numbers_are_jumpers no)
		(fp_line
			(start -0.7874 0.4064)
			(end -0.7874 -0.4064)
			(stroke
				(width 0.1524)
				(type default)
			)
			(layer "F.SilkS")
		)
		(fp_line
			(start 0.7874 0.4064)
			(end -0.7874 0.4064)
			(stroke
				(width 0.1524)
				(type default)
			)
			(layer "F.SilkS")
		)
		(fp_line
			(start -0.7874 -0.4064)
			(end 0.7874 -0.4064)
			(stroke
				(width 0.1524)
				(type default)
			)
			(layer "F.SilkS")
		)
		(fp_line
			(start 0.7874 -0.4064)
			(end 0.7874 0.4064)
			(stroke
				(width 0.1524)
				(type default)
			)
			(layer "F.SilkS")
		)
		(fp_line
			(start -0.67945 0.3048)
			(end -0.67945 -0.305054)
			(stroke
				(width 0.1)
				(type default)
			)
			(layer "F.Fab")
		)
		(fp_line
			(start -0.12065 0.3048)
			(end -0.67945 0.3048)
			(stroke
				(width 0.1)
				(type default)
			)
			(layer "F.Fab")
		)
		(fp_line
			(start 0.120396 0.3048)
			(end 0.120396 0.2794)
			(stroke
				(width 0.1)
				(type default)
			)
			(layer "F.Fab")
		)
		(fp_line
			(start 0.67945 0.3048)
			(end 0.120396 0.3048)
			(stroke
				(width 0.1)
				(type default)
			)
			(layer "F.Fab")
		)
		(fp_line
			(start -0.12065 0.2794)
			(end -0.12065 0.3048)
			(stroke
				(width 0.1)
				(type default)
			)
			(layer "F.Fab")
		)
		(fp_line
			(start 0.120396 0.2794)
			(end -0.12065 0.2794)
			(stroke
				(width 0.1)
				(type default)
			)
			(layer "F.Fab")
		)
		(fp_line
			(start -0.12065 -0.2794)
			(end 0.12065 -0.2794)
			(stroke
				(width 0.1)
				(type default)
			)
			(layer "F.Fab")
		)
		(fp_line
			(start 0.12065 -0.2794)
			(end 0.12065 -0.3048)
			(stroke
				(width 0.1)
				(type default)
			)
			(layer "F.Fab")
		)
		(fp_line
			(start 0.12065 -0.3048)
			(end 0.67945 -0.3048)
			(stroke
				(width 0.1)
				(type default)
			)
			(layer "F.Fab")
		)
		(fp_line
			(start 0.67945 -0.3048)
			(end 0.67945 0.3048)
			(stroke
				(width 0.1)
				(type default)
			)
			(layer "F.Fab")
		)
		(fp_line
			(start -0.67945 -0.305054)
			(end -0.12065 -0.305054)
			(stroke
				(width 0.1)
				(type default)
			)
			(layer "F.Fab")
		)
		(fp_line
			(start -0.12065 -0.305054)
			(end -0.12065 -0.2794)
			(stroke
				(width 0.1)
				(type default)
			)
			(layer "F.Fab")
		)
		(pad "1" smd circle
			(at -0.40005 0 270)
			(size 0 0)
			(layers "F.Cu" "F.Mask" "F.Paste")
			(net "SPI_BIC1_CLK_LS23_R1")
		)
		(pad "2" smd circle
			(at 0.40005 0 270)
			(size 0 0)
			(layers "F.Cu" "F.Mask" "F.Paste")
			(net "SPI_BIC1_CLK_LS23_R")
		)
	)
	(footprint ""
		(layer "F.Cu")
		(at 19.307048 -350.098614 90)
		(property "Reference" "C191"
			(at 0 0 90)
			(layer "F.SilkS")
			(hide yes)
			(effects
				(font
					(size 1.27 1.27)
				)
			)
		)
		(property "Value" ""
			(at 0 0 90)
			(layer "F.Fab")
			(effects
				(font
					(size 1.27 1.27)
				)
			)
		)
		(duplicate_pad_numbers_are_jumpers no)
		(fp_line
			(start 0.299974 -0.150114)
			(end 0.299974 0.150114)
			(stroke
				(width 0.1)
				(type default)
			)
			(layer "F.Fab")
		)
		(fp_line
			(start -0.299974 -0.150114)
			(end 0.299974 -0.150114)
			(stroke
				(width 0.1)
				(type default)
			)
			(layer "F.Fab")
		)
		(fp_line
			(start 0.299974 0.150114)
			(end -0.299974 0.150114)
			(stroke
				(width 0.1)
				(type default)
			)
			(layer "F.Fab")
		)
		(fp_line
			(start -0.299974 0.150114)
			(end -0.299974 -0.150114)
			(stroke
				(width 0.1)
				(type default)
			)
			(layer "F.Fab")
		)
		(pad "1" smd rect
			(at -0.2667 0 90)
			(size 0.3048 0.381)
			(layers "F.Cu" "F.Mask" "F.Paste")
			(net "P5E_PEX0_STN7_TX_DP<112>")
		)
		(pad "2" smd rect
			(at 0.2667 0 90)
			(size 0.3048 0.381)
			(layers "F.Cu" "F.Mask" "F.Paste")
			(net "P5E_PEX0_STN7_TX_C_DP<112>")
		)
	)
	(footprint ""
		(layer "F.Cu")
		(at 320.851276 -227.295964 180)
		(property "Reference" "R2987"
			(at 0 0 180)
			(layer "F.SilkS")
			(hide yes)
			(effects
				(font
					(size 1.27 1.27)
				)
			)
		)
		(property "Value" ""
			(at 0 0 180)
			(layer "F.Fab")
			(effects
				(font
					(size 1.27 1.27)
				)
			)
		)
		(duplicate_pad_numbers_are_jumpers no)
		(fp_line
			(start 0.7874 0.4064)
			(end -0.7874 0.4064)
			(stroke
				(width 0.1524)
				(type default)
			)
			(layer "F.SilkS")
		)
		(fp_line
			(start 0.7874 -0.4064)
			(end 0.7874 0.4064)
			(stroke
				(width 0.1524)
				(type default)
			)
			(layer "F.SilkS")
		)
		(fp_line
			(start -0.7874 0.4064)
			(end -0.7874 -0.4064)
			(stroke
				(width 0.1524)
				(type default)
			)
			(layer "F.SilkS")
		)
		(fp_line
			(start -0.7874 -0.4064)
			(end 0.7874 -0.4064)
			(stroke
				(width 0.1524)
				(type default)
			)
			(layer "F.SilkS")
		)
		(fp_line
			(start 0.67945 0.3048)
			(end 0.120396 0.3048)
			(stroke
				(width 0.1)
				(type default)
			)
			(layer "F.Fab")
		)
		(fp_line
			(start 0.67945 -0.3048)
			(end 0.67945 0.3048)
			(stroke
				(width 0.1)
				(type default)
			)
			(layer "F.Fab")
		)
		(fp_line
			(start 0.12065 -0.2794)
			(end 0.12065 -0.3048)
			(stroke
				(width 0.1)
				(type default)
			)
			(layer "F.Fab")
		)
		(fp_line
			(start 0.12065 -0.3048)
			(end 0.67945 -0.3048)
			(stroke
				(width 0.1)
				(type default)
			)
			(layer "F.Fab")
		)
		(fp_line
			(start 0.120396 0.3048)
			(end 0.120396 0.2794)
			(stroke
				(width 0.1)
				(type default)
			)
			(layer "F.Fab")
		)
		(fp_line
			(start 0.120396 0.2794)
			(end -0.12065 0.2794)
			(stroke
				(width 0.1)
				(type default)
			)
			(layer "F.Fab")
		)
		(fp_line
			(start -0.12065 0.3048)
			(end -0.67945 0.3048)
			(stroke
				(width 0.1)
				(type default)
			)
			(layer "F.Fab")
		)
		(fp_line
			(start -0.12065 0.2794)
			(end -0.12065 0.3048)
			(stroke
				(width 0.1)
				(type default)
			)
			(layer "F.Fab")
		)
		(fp_line
			(start -0.12065 -0.2794)
			(end 0.12065 -0.2794)
			(stroke
				(width 0.1)
				(type default)
			)
			(layer "F.Fab")
		)
		(fp_line
			(start -0.12065 -0.305054)
			(end -0.12065 -0.2794)
			(stroke
				(width 0.1)
				(type default)
			)
			(layer "F.Fab")
		)
		(fp_line
			(start -0.67945 0.3048)
			(end -0.67945 -0.305054)
			(stroke
				(width 0.1)
				(type default)
			)
			(layer "F.Fab")
		)
		(fp_line
			(start -0.67945 -0.305054)
			(end -0.12065 -0.305054)
			(stroke
				(width 0.1)
				(type default)
			)
			(layer "F.Fab")
		)
		(pad "1" smd circle
			(at -0.40005 0 180)
			(size 0 0)
			(layers "F.Cu" "F.Mask" "F.Paste")
			(net "P3V3_AUX")
		)
		(pad "2" smd circle
			(at 0.40005 0 180)
			(size 0 0)
			(layers "F.Cu" "F.Mask" "F.Paste")
			(net "FPGA_DEBUG_LED_R_N")
		)
	)
	(footprint ""
		(layer "F.Cu")
		(at 375.230136 -284.404308 -90)
		(property "Reference" "C3573"
			(at 0 0 270)
			(layer "F.SilkS")
			(hide yes)
			(effects
				(font
					(size 1.27 1.27)
				)
			)
		)
		(property "Value" ""
			(at 0 0 270)
			(layer "F.Fab")
			(effects
				(font
					(size 1.27 1.27)
				)
			)
		)
		(duplicate_pad_numbers_are_jumpers no)
		(fp_line
			(start -1.2954 0.5842)
			(end -1.2954 -0.5842)
			(stroke
				(width 0.1524)
				(type default)
			)
			(layer "F.SilkS")
		)
		(fp_line
			(start 1.2954 0.5842)
			(end -1.2954 0.5842)
			(stroke
				(width 0.1524)
				(type default)
			)
			(layer "F.SilkS")
		)
		(fp_line
			(start -1.2954 -0.5842)
			(end 1.2954 -0.5842)
			(stroke
				(width 0.1524)
				(type default)
			)
			(layer "F.SilkS")
		)
		(fp_line
			(start 1.2954 -0.5842)
			(end 1.2954 0.5842)
			(stroke
				(width 0.1524)
				(type default)
			)
			(layer "F.SilkS")
		)
		(fp_line
			(start -0.8636 0.4572)
			(end -0.8636 0.4064)
			(stroke
				(width 0.1)
				(type default)
			)
			(layer "F.Fab")
		)
		(fp_line
			(start 0.8636 0.4572)
			(end -0.8636 0.4572)
			(stroke
				(width 0.1)
				(type default)
			)
			(layer "F.Fab")
		)
		(fp_line
			(start -1.1938 0.4064)
			(end -1.1938 -0.4064)
			(stroke
				(width 0.1)
				(type default)
			)
			(layer "F.Fab")
		)
		(fp_line
			(start -0.8636 0.4064)
			(end -1.1938 0.4064)
			(stroke
				(width 0.1)
				(type default)
			)
			(layer "F.Fab")
		)
		(fp_line
			(start 0.8636 0.4064)
			(end 0.8636 0.4572)
			(stroke
				(width 0.1)
				(type default)
			)
			(layer "F.Fab")
		)
		(fp_line
			(start 1.1938 0.4064)
			(end 0.8636 0.4064)
			(stroke
				(width 0.1)
				(type default)
			)
			(layer "F.Fab")
		)
		(fp_line
			(start -1.1938 -0.4064)
			(end -0.8636 -0.4064)
			(stroke
				(width 0.1)
				(type default)
			)
			(layer "F.Fab")
		)
		(fp_line
			(start -0.8636 -0.4064)
			(end -0.8636 -0.4572)
			(stroke
				(width 0.1)
				(type default)
			)
			(layer "F.Fab")
		)
		(fp_line
			(start 0.8636 -0.4064)
			(end 1.1938 -0.4064)
			(stroke
				(width 0.1)
				(type default)
			)
			(layer "F.Fab")
		)
		(fp_line
			(start 1.1938 -0.4064)
			(end 1.1938 0.4064)
			(stroke
				(width 0.1)
				(type default)
			)
			(layer "F.Fab")
		)
		(fp_line
			(start -0.8636 -0.4572)
			(end 0.8636 -0.4572)
			(stroke
				(width 0.1)
				(type default)
			)
			(layer "F.Fab")
		)
		(fp_line
			(start 0.8636 -0.4572)
			(end 0.8636 -0.4064)
			(stroke
				(width 0.1)
				(type default)
			)
			(layer "F.Fab")
		)
		(pad "1" smd rect
			(at -0.7366 0 180)
			(size 0.7112 0.8128)
			(layers "F.Cu" "F.Mask" "F.Paste")
			(net "P1V8_PLL0_PEX3")
		)
		(pad "2" smd rect
			(at 0.7366 0 180)
			(size 0.7112 0.8128)
			(layers "F.Cu" "F.Mask" "F.Paste")
			(net "GND")
		)
	)
	(footprint ""
		(layer "F.Cu")
		(at 341.63 -201.168 90)
		(property "Reference" "R4143"
			(at 0 0 90)
			(layer "F.SilkS")
			(hide yes)
			(effects
				(font
					(size 1.27 1.27)
				)
			)
		)
		(property "Value" ""
			(at 0 0 90)
			(layer "F.Fab")
			(effects
				(font
					(size 1.27 1.27)
				)
			)
		)
		(duplicate_pad_numbers_are_jumpers no)
		(fp_line
			(start 0.7874 -0.4064)
			(end 0.7874 0.4064)
			(stroke
				(width 0.1524)
				(type default)
			)
			(layer "F.SilkS")
		)
		(fp_line
			(start -0.7874 -0.4064)
			(end 0.7874 -0.4064)
			(stroke
				(width 0.1524)
				(type default)
			)
			(layer "F.SilkS")
		)
		(fp_line
			(start 0.7874 0.4064)
			(end -0.7874 0.4064)
			(stroke
				(width 0.1524)
				(type default)
			)
			(layer "F.SilkS")
		)
		(fp_line
			(start -0.7874 0.4064)
			(end -0.7874 -0.4064)
			(stroke
				(width 0.1524)
				(type default)
			)
			(layer "F.SilkS")
		)
		(fp_line
			(start -0.12065 -0.305054)
			(end -0.12065 -0.2794)
			(stroke
				(width 0.1)
				(type default)
			)
			(layer "F.Fab")
		)
		(fp_line
			(start -0.67945 -0.305054)
			(end -0.12065 -0.305054)
			(stroke
				(width 0.1)
				(type default)
			)
			(layer "F.Fab")
		)
		(fp_line
			(start 0.67945 -0.3048)
			(end 0.67945 0.3048)
			(stroke
				(width 0.1)
				(type default)
			)
			(layer "F.Fab")
		)
		(fp_line
			(start 0.12065 -0.3048)
			(end 0.67945 -0.3048)
			(stroke
				(width 0.1)
				(type default)
			)
			(layer "F.Fab")
		)
		(fp_line
			(start 0.12065 -0.2794)
			(end 0.12065 -0.3048)
			(stroke
				(width 0.1)
				(type default)
			)
			(layer "F.Fab")
		)
		(fp_line
			(start -0.12065 -0.2794)
			(end 0.12065 -0.2794)
			(stroke
				(width 0.1)
				(type default)
			)
			(layer "F.Fab")
		)
		(fp_line
			(start 0.120396 0.2794)
			(end -0.12065 0.2794)
			(stroke
				(width 0.1)
				(type default)
			)
			(layer "F.Fab")
		)
		(fp_line
			(start -0.12065 0.2794)
			(end -0.12065 0.3048)
			(stroke
				(width 0.1)
				(type default)
			)
			(layer "F.Fab")
		)
		(fp_line
			(start 0.67945 0.3048)
			(end 0.120396 0.3048)
			(stroke
				(width 0.1)
				(type default)
			)
			(layer "F.Fab")
		)
		(fp_line
			(start 0.120396 0.3048)
			(end 0.120396 0.2794)
			(stroke
				(width 0.1)
				(type default)
			)
			(layer "F.Fab")
		)
		(fp_line
			(start -0.12065 0.3048)
			(end -0.67945 0.3048)
			(stroke
				(width 0.1)
				(type default)
			)
			(layer "F.Fab")
		)
		(fp_line
			(start -0.67945 0.3048)
			(end -0.67945 -0.305054)
			(stroke
				(width 0.1)
				(type default)
			)
			(layer "F.Fab")
		)
		(pad "1" smd circle
			(at -0.40005 0 90)
			(size 0 0)
			(layers "F.Cu" "F.Mask" "F.Paste")
			(net "SSD15_PWR_EN_R")
		)
		(pad "2" smd circle
			(at 0.40005 0 90)
			(size 0 0)
			(layers "F.Cu" "F.Mask" "F.Paste")
			(net "SSD15_PWR_EN")
		)
	)
	(footprint ""
		(layer "F.Cu")
		(at 210.439 -207.391 180)
		(property "Reference" "R1511"
			(at 0 0 180)
			(layer "F.SilkS")
			(hide yes)
			(effects
				(font
					(size 1.27 1.27)
				)
			)
		)
		(property "Value" ""
			(at 0 0 180)
			(layer "F.Fab")
			(effects
				(font
					(size 1.27 1.27)
				)
			)
		)
		(duplicate_pad_numbers_are_jumpers no)
		(fp_line
			(start 0.7874 0.4064)
			(end -0.7874 0.4064)
			(stroke
				(width 0.1524)
				(type default)
			)
			(layer "F.SilkS")
		)
		(fp_line
			(start 0.7874 -0.4064)
			(end 0.7874 0.4064)
			(stroke
				(width 0.1524)
				(type default)
			)
			(layer "F.SilkS")
		)
		(fp_line
			(start -0.7874 0.4064)
			(end -0.7874 -0.4064)
			(stroke
				(width 0.1524)
				(type default)
			)
			(layer "F.SilkS")
		)
		(fp_line
			(start -0.7874 -0.4064)
			(end 0.7874 -0.4064)
			(stroke
				(width 0.1524)
				(type default)
			)
			(layer "F.SilkS")
		)
		(fp_line
			(start 0.67945 0.3048)
			(end 0.120396 0.3048)
			(stroke
				(width 0.1)
				(type default)
			)
			(layer "F.Fab")
		)
		(fp_line
			(start 0.67945 -0.3048)
			(end 0.67945 0.3048)
			(stroke
				(width 0.1)
				(type default)
			)
			(layer "F.Fab")
		)
		(fp_line
			(start 0.12065 -0.2794)
			(end 0.12065 -0.3048)
			(stroke
				(width 0.1)
				(type default)
			)
			(layer "F.Fab")
		)
		(fp_line
			(start 0.12065 -0.3048)
			(end 0.67945 -0.3048)
			(stroke
				(width 0.1)
				(type default)
			)
			(layer "F.Fab")
		)
		(fp_line
			(start 0.120396 0.3048)
			(end 0.120396 0.2794)
			(stroke
				(width 0.1)
				(type default)
			)
			(layer "F.Fab")
		)
		(fp_line
			(start 0.120396 0.2794)
			(end -0.12065 0.2794)
			(stroke
				(width 0.1)
				(type default)
			)
			(layer "F.Fab")
		)
		(fp_line
			(start -0.12065 0.3048)
			(end -0.67945 0.3048)
			(stroke
				(width 0.1)
				(type default)
			)
			(layer "F.Fab")
		)
		(fp_line
			(start -0.12065 0.2794)
			(end -0.12065 0.3048)
			(stroke
				(width 0.1)
				(type default)
			)
			(layer "F.Fab")
		)
		(fp_line
			(start -0.12065 -0.2794)
			(end 0.12065 -0.2794)
			(stroke
				(width 0.1)
				(type default)
			)
			(layer "F.Fab")
		)
		(fp_line
			(start -0.12065 -0.305054)
			(end -0.12065 -0.2794)
			(stroke
				(width 0.1)
				(type default)
			)
			(layer "F.Fab")
		)
		(fp_line
			(start -0.67945 0.3048)
			(end -0.67945 -0.305054)
			(stroke
				(width 0.1)
				(type default)
			)
			(layer "F.Fab")
		)
		(fp_line
			(start -0.67945 -0.305054)
			(end -0.12065 -0.305054)
			(stroke
				(width 0.1)
				(type default)
			)
			(layer "F.Fab")
		)
		(pad "1" smd circle
			(at -0.40005 0 180)
			(size 0 0)
			(layers "F.Cu" "F.Mask" "F.Paste")
			(net "SMB_NIC4_R_SDA")
		)
		(pad "2" smd circle
			(at 0.40005 0 180)
			(size 0 0)
			(layers "F.Cu" "F.Mask" "F.Paste")
			(net "P1V2_AUX")
		)
	)
	(footprint ""
		(layer "F.Cu")
		(at 151.50719 -380.379732 180)
		(property "Reference" "C4098"
			(at 0 0 180)
			(layer "F.SilkS")
			(hide yes)
			(effects
				(font
					(size 1.27 1.27)
				)
			)
		)
		(property "Value" ""
			(at 0 0 180)
			(layer "F.Fab")
			(effects
				(font
					(size 1.27 1.27)
				)
			)
		)
		(duplicate_pad_numbers_are_jumpers no)
		(fp_line
			(start 0.7874 0.4064)
			(end -0.7874 0.4064)
			(stroke
				(width 0.1524)
				(type default)
			)
			(layer "F.SilkS")
		)
		(fp_line
			(start 0.7874 -0.4064)
			(end 0.7874 0.4064)
			(stroke
				(width 0.1524)
				(type default)
			)
			(layer "F.SilkS")
		)
		(fp_line
			(start -0.7874 0.4064)
			(end -0.7874 -0.4064)
			(stroke
				(width 0.1524)
				(type default)
			)
			(layer "F.SilkS")
		)
		(fp_line
			(start -0.7874 -0.4064)
			(end 0.7874 -0.4064)
			(stroke
				(width 0.1524)
				(type default)
			)
			(layer "F.SilkS")
		)
		(fp_line
			(start 0.67945 0.3048)
			(end 0.120396 0.3048)
			(stroke
				(width 0.1)
				(type default)
			)
			(layer "F.Fab")
		)
		(fp_line
			(start 0.67945 -0.3048)
			(end 0.67945 0.3048)
			(stroke
				(width 0.1)
				(type default)
			)
			(layer "F.Fab")
		)
		(fp_line
			(start 0.12065 -0.2794)
			(end 0.12065 -0.3048)
			(stroke
				(width 0.1)
				(type default)
			)
			(layer "F.Fab")
		)
		(fp_line
			(start 0.12065 -0.3048)
			(end 0.67945 -0.3048)
			(stroke
				(width 0.1)
				(type default)
			)
			(layer "F.Fab")
		)
		(fp_line
			(start 0.120396 0.3048)
			(end 0.120396 0.2794)
			(stroke
				(width 0.1)
				(type default)
			)
			(layer "F.Fab")
		)
		(fp_line
			(start 0.120396 0.2794)
			(end -0.12065 0.2794)
			(stroke
				(width 0.1)
				(type default)
			)
			(layer "F.Fab")
		)
		(fp_line
			(start -0.12065 0.3048)
			(end -0.67945 0.3048)
			(stroke
				(width 0.1)
				(type default)
			)
			(layer "F.Fab")
		)
		(fp_line
			(start -0.12065 0.2794)
			(end -0.12065 0.3048)
			(stroke
				(width 0.1)
				(type default)
			)
			(layer "F.Fab")
		)
		(fp_line
			(start -0.12065 -0.2794)
			(end 0.12065 -0.2794)
			(stroke
				(width 0.1)
				(type default)
			)
			(layer "F.Fab")
		)
		(fp_line
			(start -0.12065 -0.305054)
			(end -0.12065 -0.2794)
			(stroke
				(width 0.1)
				(type default)
			)
			(layer "F.Fab")
		)
		(fp_line
			(start -0.67945 0.3048)
			(end -0.67945 -0.305054)
			(stroke
				(width 0.1)
				(type default)
			)
			(layer "F.Fab")
		)
		(fp_line
			(start -0.67945 -0.305054)
			(end -0.12065 -0.305054)
			(stroke
				(width 0.1)
				(type default)
			)
			(layer "F.Fab")
		)
		(pad "1" smd circle
			(at -0.40005 0 180)
			(size 0 0)
			(layers "F.Cu" "F.Mask" "F.Paste")
			(net "GND")
		)
		(pad "2" smd circle
			(at 0.40005 0 180)
			(size 0 0)
			(layers "F.Cu" "F.Mask" "F.Paste")
			(net "GPU_3V3IO_RSVD0_FFU")
		)
	)
	(footprint ""
		(layer "F.Cu")
		(at 114.802158 -162.122866 180)
		(property "Reference" "PR61"
			(at 0 0 180)
			(layer "F.SilkS")
			(hide yes)
			(effects
				(font
					(size 1.27 1.27)
				)
			)
		)
		(property "Value" ""
			(at 0 0 180)
			(layer "F.Fab")
			(effects
				(font
					(size 1.27 1.27)
				)
			)
		)
		(duplicate_pad_numbers_are_jumpers no)
		(fp_line
			(start 0.7874 0.4064)
			(end -0.7874 0.4064)
			(stroke
				(width 0.1524)
				(type default)
			)
			(layer "F.SilkS")
		)
		(fp_line
			(start 0.7874 -0.4064)
			(end 0.7874 0.4064)
			(stroke
				(width 0.1524)
				(type default)
			)
			(layer "F.SilkS")
		)
		(fp_line
			(start -0.7874 0.4064)
			(end -0.7874 -0.4064)
			(stroke
				(width 0.1524)
				(type default)
			)
			(layer "F.SilkS")
		)
		(fp_line
			(start -0.7874 -0.4064)
			(end 0.7874 -0.4064)
			(stroke
				(width 0.1524)
				(type default)
			)
			(layer "F.SilkS")
		)
		(fp_line
			(start 0.67945 0.3048)
			(end 0.120396 0.3048)
			(stroke
				(width 0.1)
				(type default)
			)
			(layer "F.Fab")
		)
		(fp_line
			(start 0.67945 -0.3048)
			(end 0.67945 0.3048)
			(stroke
				(width 0.1)
				(type default)
			)
			(layer "F.Fab")
		)
		(fp_line
			(start 0.12065 -0.2794)
			(end 0.12065 -0.3048)
			(stroke
				(width 0.1)
				(type default)
			)
			(layer "F.Fab")
		)
		(fp_line
			(start 0.12065 -0.3048)
			(end 0.67945 -0.3048)
			(stroke
				(width 0.1)
				(type default)
			)
			(layer "F.Fab")
		)
		(fp_line
			(start 0.120396 0.3048)
			(end 0.120396 0.2794)
			(stroke
				(width 0.1)
				(type default)
			)
			(layer "F.Fab")
		)
		(fp_line
			(start 0.120396 0.2794)
			(end -0.12065 0.2794)
			(stroke
				(width 0.1)
				(type default)
			)
			(layer "F.Fab")
		)
		(fp_line
			(start -0.12065 0.3048)
			(end -0.67945 0.3048)
			(stroke
				(width 0.1)
				(type default)
			)
			(layer "F.Fab")
		)
		(fp_line
			(start -0.12065 0.2794)
			(end -0.12065 0.3048)
			(stroke
				(width 0.1)
				(type default)
			)
			(layer "F.Fab")
		)
		(fp_line
			(start -0.12065 -0.2794)
			(end 0.12065 -0.2794)
			(stroke
				(width 0.1)
				(type default)
			)
			(layer "F.Fab")
		)
		(fp_line
			(start -0.12065 -0.305054)
			(end -0.12065 -0.2794)
			(stroke
				(width 0.1)
				(type default)
			)
			(layer "F.Fab")
		)
		(fp_line
			(start -0.67945 0.3048)
			(end -0.67945 -0.305054)
			(stroke
				(width 0.1)
				(type default)
			)
			(layer "F.Fab")
		)
		(fp_line
			(start -0.67945 -0.305054)
			(end -0.12065 -0.305054)
			(stroke
				(width 0.1)
				(type default)
			)
			(layer "F.Fab")
		)
		(pad "1" smd circle
			(at -0.40005 0 180)
			(size 0 0)
			(layers "F.Cu" "F.Mask" "F.Paste")
			(net "SH_P3V3_AUX_FB")
		)
		(pad "2" smd circle
			(at 0.40005 0 180)
			(size 0 0)
			(layers "F.Cu" "F.Mask" "F.Paste")
			(net "P3V3_AUX_FB")
		)
	)
	(footprint ""
		(layer "F.Cu")
		(at 109.347 -38.49116 180)
		(property "Reference" "R6064"
			(at 0 0 180)
			(layer "F.SilkS")
			(hide yes)
			(effects
				(font
					(size 1.27 1.27)
				)
			)
		)
		(property "Value" ""
			(at 0 0 180)
			(layer "F.Fab")
			(effects
				(font
					(size 1.27 1.27)
				)
			)
		)
		(duplicate_pad_numbers_are_jumpers no)
		(fp_line
			(start 0.7874 0.4064)
			(end -0.7874 0.4064)
			(stroke
				(width 0.1524)
				(type default)
			)
			(layer "F.SilkS")
		)
		(fp_line
			(start 0.7874 -0.4064)
			(end 0.7874 0.4064)
			(stroke
				(width 0.1524)
				(type default)
			)
			(layer "F.SilkS")
		)
		(fp_line
			(start -0.7874 0.4064)
			(end -0.7874 -0.4064)
			(stroke
				(width 0.1524)
				(type default)
			)
			(layer "F.SilkS")
		)
		(fp_line
			(start -0.7874 -0.4064)
			(end 0.7874 -0.4064)
			(stroke
				(width 0.1524)
				(type default)
			)
			(layer "F.SilkS")
		)
		(fp_line
			(start 0.67945 0.3048)
			(end 0.120396 0.3048)
			(stroke
				(width 0.1)
				(type default)
			)
			(layer "F.Fab")
		)
		(fp_line
			(start 0.67945 -0.3048)
			(end 0.67945 0.3048)
			(stroke
				(width 0.1)
				(type default)
			)
			(layer "F.Fab")
		)
		(fp_line
			(start 0.12065 -0.2794)
			(end 0.12065 -0.3048)
			(stroke
				(width 0.1)
				(type default)
			)
			(layer "F.Fab")
		)
		(fp_line
			(start 0.12065 -0.3048)
			(end 0.67945 -0.3048)
			(stroke
				(width 0.1)
				(type default)
			)
			(layer "F.Fab")
		)
		(fp_line
			(start 0.120396 0.3048)
			(end 0.120396 0.2794)
			(stroke
				(width 0.1)
				(type default)
			)
			(layer "F.Fab")
		)
		(fp_line
			(start 0.120396 0.2794)
			(end -0.12065 0.2794)
			(stroke
				(width 0.1)
				(type default)
			)
			(layer "F.Fab")
		)
		(fp_line
			(start -0.12065 0.3048)
			(end -0.67945 0.3048)
			(stroke
				(width 0.1)
				(type default)
			)
			(layer "F.Fab")
		)
		(fp_line
			(start -0.12065 0.2794)
			(end -0.12065 0.3048)
			(stroke
				(width 0.1)
				(type default)
			)
			(layer "F.Fab")
		)
		(fp_line
			(start -0.12065 -0.2794)
			(end 0.12065 -0.2794)
			(stroke
				(width 0.1)
				(type default)
			)
			(layer "F.Fab")
		)
		(fp_line
			(start -0.12065 -0.305054)
			(end -0.12065 -0.2794)
			(stroke
				(width 0.1)
				(type default)
			)
			(layer "F.Fab")
		)
		(fp_line
			(start -0.67945 0.3048)
			(end -0.67945 -0.305054)
			(stroke
				(width 0.1)
				(type default)
			)
			(layer "F.Fab")
		)
		(fp_line
			(start -0.67945 -0.305054)
			(end -0.12065 -0.305054)
			(stroke
				(width 0.1)
				(type default)
			)
			(layer "F.Fab")
		)
		(pad "1" smd circle
			(at -0.40005 0 180)
			(size 0 0)
			(layers "F.Cu" "F.Mask" "F.Paste")
			(net "P3V3_SSD4_PG_G1")
		)
		(pad "2" smd circle
			(at 0.40005 0 180)
			(size 0 0)
			(layers "F.Cu" "F.Mask" "F.Paste")
			(net "GND")
		)
	)
	(footprint ""
		(layer "F.Cu")
		(at 134.822692 -44.341542 90)
		(property "Reference" "R558"
			(at 0 0 90)
			(layer "F.SilkS")
			(hide yes)
			(effects
				(font
					(size 1.27 1.27)
				)
			)
		)
		(property "Value" ""
			(at 0 0 90)
			(layer "F.Fab")
			(effects
				(font
					(size 1.27 1.27)
				)
			)
		)
		(duplicate_pad_numbers_are_jumpers no)
		(fp_line
			(start 0.7874 -0.4064)
			(end 0.7874 0.4064)
			(stroke
				(width 0.1524)
				(type default)
			)
			(layer "F.SilkS")
		)
		(fp_line
			(start -0.7874 -0.4064)
			(end 0.7874 -0.4064)
			(stroke
				(width 0.1524)
				(type default)
			)
			(layer "F.SilkS")
		)
		(fp_line
			(start 0.7874 0.4064)
			(end -0.7874 0.4064)
			(stroke
				(width 0.1524)
				(type default)
			)
			(layer "F.SilkS")
		)
		(fp_line
			(start -0.7874 0.4064)
			(end -0.7874 -0.4064)
			(stroke
				(width 0.1524)
				(type default)
			)
			(layer "F.SilkS")
		)
		(fp_line
			(start -0.12065 -0.305054)
			(end -0.12065 -0.2794)
			(stroke
				(width 0.1)
				(type default)
			)
			(layer "F.Fab")
		)
		(fp_line
			(start -0.67945 -0.305054)
			(end -0.12065 -0.305054)
			(stroke
				(width 0.1)
				(type default)
			)
			(layer "F.Fab")
		)
		(fp_line
			(start 0.67945 -0.3048)
			(end 0.67945 0.3048)
			(stroke
				(width 0.1)
				(type default)
			)
			(layer "F.Fab")
		)
		(fp_line
			(start 0.12065 -0.3048)
			(end 0.67945 -0.3048)
			(stroke
				(width 0.1)
				(type default)
			)
			(layer "F.Fab")
		)
		(fp_line
			(start 0.12065 -0.2794)
			(end 0.12065 -0.3048)
			(stroke
				(width 0.1)
				(type default)
			)
			(layer "F.Fab")
		)
		(fp_line
			(start -0.12065 -0.2794)
			(end 0.12065 -0.2794)
			(stroke
				(width 0.1)
				(type default)
			)
			(layer "F.Fab")
		)
		(fp_line
			(start 0.120396 0.2794)
			(end -0.12065 0.2794)
			(stroke
				(width 0.1)
				(type default)
			)
			(layer "F.Fab")
		)
		(fp_line
			(start -0.12065 0.2794)
			(end -0.12065 0.3048)
			(stroke
				(width 0.1)
				(type default)
			)
			(layer "F.Fab")
		)
		(fp_line
			(start 0.67945 0.3048)
			(end 0.120396 0.3048)
			(stroke
				(width 0.1)
				(type default)
			)
			(layer "F.Fab")
		)
		(fp_line
			(start 0.120396 0.3048)
			(end 0.120396 0.2794)
			(stroke
				(width 0.1)
				(type default)
			)
			(layer "F.Fab")
		)
		(fp_line
			(start -0.12065 0.3048)
			(end -0.67945 0.3048)
			(stroke
				(width 0.1)
				(type default)
			)
			(layer "F.Fab")
		)
		(fp_line
			(start -0.67945 0.3048)
			(end -0.67945 -0.305054)
			(stroke
				(width 0.1)
				(type default)
			)
			(layer "F.Fab")
		)
		(pad "1" smd circle
			(at -0.40005 0 90)
			(size 0 0)
			(layers "F.Cu" "F.Mask" "F.Paste")
			(net "P12V_SSD4")
		)
		(pad "2" smd circle
			(at 0.40005 0 90)
			(size 0 0)
			(layers "F.Cu" "F.Mask" "F.Paste")
			(net "P12V_SSD4_VIN_N")
		)
	)
	(footprint ""
		(layer "F.Cu")
		(at 420.787576 -25.342342 -90)
		(property "Reference" "R452"
			(at 0 0 270)
			(layer "F.SilkS")
			(hide yes)
			(effects
				(font
					(size 1.27 1.27)
				)
			)
		)
		(property "Value" ""
			(at 0 0 270)
			(layer "F.Fab")
			(effects
				(font
					(size 1.27 1.27)
				)
			)
		)
		(duplicate_pad_numbers_are_jumpers no)
		(fp_line
			(start -0.7874 0.4064)
			(end -0.7874 -0.4064)
			(stroke
				(width 0.1524)
				(type default)
			)
			(layer "F.SilkS")
		)
		(fp_line
			(start 0.7874 0.4064)
			(end -0.7874 0.4064)
			(stroke
				(width 0.1524)
				(type default)
			)
			(layer "F.SilkS")
		)
		(fp_line
			(start -0.7874 -0.4064)
			(end 0.7874 -0.4064)
			(stroke
				(width 0.1524)
				(type default)
			)
			(layer "F.SilkS")
		)
		(fp_line
			(start 0.7874 -0.4064)
			(end 0.7874 0.4064)
			(stroke
				(width 0.1524)
				(type default)
			)
			(layer "F.SilkS")
		)
		(fp_line
			(start -0.67945 0.3048)
			(end -0.67945 -0.305054)
			(stroke
				(width 0.1)
				(type default)
			)
			(layer "F.Fab")
		)
		(fp_line
			(start -0.12065 0.3048)
			(end -0.67945 0.3048)
			(stroke
				(width 0.1)
				(type default)
			)
			(layer "F.Fab")
		)
		(fp_line
			(start 0.120396 0.3048)
			(end 0.120396 0.2794)
			(stroke
				(width 0.1)
				(type default)
			)
			(layer "F.Fab")
		)
		(fp_line
			(start 0.67945 0.3048)
			(end 0.120396 0.3048)
			(stroke
				(width 0.1)
				(type default)
			)
			(layer "F.Fab")
		)
		(fp_line
			(start -0.12065 0.2794)
			(end -0.12065 0.3048)
			(stroke
				(width 0.1)
				(type default)
			)
			(layer "F.Fab")
		)
		(fp_line
			(start 0.120396 0.2794)
			(end -0.12065 0.2794)
			(stroke
				(width 0.1)
				(type default)
			)
			(layer "F.Fab")
		)
		(fp_line
			(start -0.12065 -0.2794)
			(end 0.12065 -0.2794)
			(stroke
				(width 0.1)
				(type default)
			)
			(layer "F.Fab")
		)
		(fp_line
			(start 0.12065 -0.2794)
			(end 0.12065 -0.3048)
			(stroke
				(width 0.1)
				(type default)
			)
			(layer "F.Fab")
		)
		(fp_line
			(start 0.12065 -0.3048)
			(end 0.67945 -0.3048)
			(stroke
				(width 0.1)
				(type default)
			)
			(layer "F.Fab")
		)
		(fp_line
			(start 0.67945 -0.3048)
			(end 0.67945 0.3048)
			(stroke
				(width 0.1)
				(type default)
			)
			(layer "F.Fab")
		)
		(fp_line
			(start -0.67945 -0.305054)
			(end -0.12065 -0.305054)
			(stroke
				(width 0.1)
				(type default)
			)
			(layer "F.Fab")
		)
		(fp_line
			(start -0.12065 -0.305054)
			(end -0.12065 -0.2794)
			(stroke
				(width 0.1)
				(type default)
			)
			(layer "F.Fab")
		)
		(pad "1" smd circle
			(at -0.40005 0 270)
			(size 0 0)
			(layers "F.Cu" "F.Mask" "F.Paste")
			(net "GND")
		)
		(pad "2" smd circle
			(at 0.40005 0 270)
			(size 0 0)
			(layers "F.Cu" "F.Mask" "F.Paste")
			(net "DUALPORT_N_SSD14")
		)
	)
	(footprint ""
		(layer "F.Cu")
		(at 11.113516 -42.419016)
		(property "Reference" "U363"
			(at 0.113284 2.339086 0)
			(unlocked yes)
			(layer "F.SilkS")
			(effects
				(font
					(size 0.7874 0.5842)
					(thickness 0.1524)
				)
			)
		)
		(property "Value" ""
			(at 0 0 0)
			(layer "F.Fab")
			(effects
				(font
					(size 1.27 1.27)
				)
			)
		)
		(duplicate_pad_numbers_are_jumpers no)
		(fp_line
			(start -1.949958 -1.610106)
			(end 1.949958 -1.610106)
			(stroke
				(width 0.1524)
				(type default)
			)
			(layer "F.SilkS")
		)
		(fp_line
			(start -1.949958 1.610106)
			(end -1.949958 -1.610106)
			(stroke
				(width 0.1524)
				(type default)
			)
			(layer "F.SilkS")
		)
		(fp_line
			(start 1.949958 -1.560068)
			(end 1.949958 1.610106)
			(stroke
				(width 0.1524)
				(type default)
			)
			(layer "F.SilkS")
		)
		(fp_line
			(start 1.949958 1.610106)
			(end -1.949958 1.610106)
			(stroke
				(width 0.1524)
				(type default)
			)
			(layer "F.SilkS")
		)
		(fp_line
			(start -0.750062 -1.560068)
			(end 0.750062 -1.560068)
			(stroke
				(width 0.1)
				(type default)
			)
			(layer "F.Fab")
		)
		(fp_line
			(start -0.750062 1.560068)
			(end -0.750062 -1.560068)
			(stroke
				(width 0.1)
				(type default)
			)
			(layer "F.Fab")
		)
		(fp_line
			(start 0.750062 -1.560068)
			(end 0.750062 1.560068)
			(stroke
				(width 0.1)
				(type default)
			)
			(layer "F.Fab")
		)
		(fp_line
			(start 0.750062 1.560068)
			(end -0.750062 1.560068)
			(stroke
				(width 0.1)
				(type default)
			)
			(layer "F.Fab")
		)
		(pad "D" smd rect
			(at 1.100074 0 270)
			(size 1.016 1.4224)
			(layers "F.Cu" "F.Mask" "F.Paste")
			(net "SSD0_AUX_P3V3_EN")
		)
		(pad "G" smd rect
			(at -1.100074 -0.94996 270)
			(size 1.016 1.4224)
			(layers "F.Cu" "F.Mask" "F.Paste")
			(net "PRSNT_SSD0_R1_N")
		)
		(pad "S" smd rect
			(at -1.100074 0.94996 270)
			(size 1.016 1.4224)
			(layers "F.Cu" "F.Mask" "F.Paste")
			(net "GND")
		)
	)
	(footprint ""
		(layer "F.Cu")
		(at 247.10771 -154.510994)
		(property "Reference" "PC803"
			(at 0 0 0)
			(layer "F.SilkS")
			(hide yes)
			(effects
				(font
					(size 1.27 1.27)
				)
			)
		)
		(property "Value" ""
			(at 0 0 0)
			(layer "F.Fab")
			(effects
				(font
					(size 1.27 1.27)
				)
			)
		)
		(duplicate_pad_numbers_are_jumpers no)
		(fp_line
			(start -0.7874 -0.4064)
			(end 0.7874 -0.4064)
			(stroke
				(width 0.1524)
				(type default)
			)
			(layer "F.SilkS")
		)
		(fp_line
			(start -0.7874 0.4064)
			(end -0.7874 -0.4064)
			(stroke
				(width 0.1524)
				(type default)
			)
			(layer "F.SilkS")
		)
		(fp_line
			(start 0.7874 -0.4064)
			(end 0.7874 0.4064)
			(stroke
				(width 0.1524)
				(type default)
			)
			(layer "F.SilkS")
		)
		(fp_line
			(start 0.7874 0.4064)
			(end -0.7874 0.4064)
			(stroke
				(width 0.1524)
				(type default)
			)
			(layer "F.SilkS")
		)
		(fp_line
			(start -0.67945 -0.305054)
			(end -0.12065 -0.305054)
			(stroke
				(width 0.1)
				(type default)
			)
			(layer "F.Fab")
		)
		(fp_line
			(start -0.67945 0.3048)
			(end -0.67945 -0.305054)
			(stroke
				(width 0.1)
				(type default)
			)
			(layer "F.Fab")
		)
		(fp_line
			(start -0.12065 -0.305054)
			(end -0.12065 -0.2794)
			(stroke
				(width 0.1)
				(type default)
			)
			(layer "F.Fab")
		)
		(fp_line
			(start -0.12065 -0.2794)
			(end 0.12065 -0.2794)
			(stroke
				(width 0.1)
				(type default)
			)
			(layer "F.Fab")
		)
		(fp_line
			(start -0.12065 0.2794)
			(end -0.12065 0.3048)
			(stroke
				(width 0.1)
				(type default)
			)
			(layer "F.Fab")
		)
		(fp_line
			(start -0.12065 0.3048)
			(end -0.67945 0.3048)
			(stroke
				(width 0.1)
				(type default)
			)
			(layer "F.Fab")
		)
		(fp_line
			(start 0.120396 0.2794)
			(end -0.12065 0.2794)
			(stroke
				(width 0.1)
				(type default)
			)
			(layer "F.Fab")
		)
		(fp_line
			(start 0.120396 0.3048)
			(end 0.120396 0.2794)
			(stroke
				(width 0.1)
				(type default)
			)
			(layer "F.Fab")
		)
		(fp_line
			(start 0.12065 -0.3048)
			(end 0.67945 -0.3048)
			(stroke
				(width 0.1)
				(type default)
			)
			(layer "F.Fab")
		)
		(fp_line
			(start 0.12065 -0.2794)
			(end 0.12065 -0.3048)
			(stroke
				(width 0.1)
				(type default)
			)
			(layer "F.Fab")
		)
		(fp_line
			(start 0.67945 -0.3048)
			(end 0.67945 0.3048)
			(stroke
				(width 0.1)
				(type default)
			)
			(layer "F.Fab")
		)
		(fp_line
			(start 0.67945 0.3048)
			(end 0.120396 0.3048)
			(stroke
				(width 0.1)
				(type default)
			)
			(layer "F.Fab")
		)
		(pad "1" smd circle
			(at -0.40005 0)
			(size 0 0)
			(layers "F.Cu" "F.Mask" "F.Paste")
			(net "P12V_NIC4_R")
		)
		(pad "2" smd circle
			(at 0.40005 0)
			(size 0 0)
			(layers "F.Cu" "F.Mask" "F.Paste")
			(net "GND")
		)
	)
	(footprint ""
		(layer "F.Cu")
		(at 319.79997 -407.960068 180)
		(property "Reference" "J61"
			(at -1.724406 -11.62685 0)
			(unlocked yes)
			(layer "F.SilkS")
			(effects
				(font
					(size 0.7874 0.5842)
					(thickness 0.1524)
				)
			)
		)
		(property "Value" ""
			(at 0 0 180)
			(layer "F.Fab")
			(effects
				(font
					(size 1.27 1.27)
				)
			)
		)
		(duplicate_pad_numbers_are_jumpers no)
		(fp_line
			(start 3.525012 21.310092)
			(end 3.525012 -10.489946)
			(stroke
				(width 0.1524)
				(type default)
			)
			(layer "F.SilkS")
		)
		(fp_line
			(start 3.525012 -10.489946)
			(end -3.525012 -10.489946)
			(stroke
				(width 0.1524)
				(type default)
			)
			(layer "F.SilkS")
		)
		(fp_line
			(start -3.525012 21.310092)
			(end 3.525012 21.310092)
			(stroke
				(width 0.1524)
				(type default)
			)
			(layer "F.SilkS")
		)
		(fp_line
			(start -3.525012 10.6299)
			(end 3.525012 10.6299)
			(stroke
				(width 0.1524)
				(type default)
			)
			(layer "F.SilkS")
		)
		(fp_line
			(start -3.525012 -10.489946)
			(end -3.525012 21.310092)
			(stroke
				(width 0.1524)
				(type default)
			)
			(layer "F.SilkS")
		)
		(fp_line
			(start 3.525012 21.310092)
			(end 3.525012 -10.489946)
			(stroke
				(width 0.1)
				(type default)
			)
			(layer "F.Fab")
		)
		(fp_line
			(start 3.525012 -10.489946)
			(end -3.525012 -10.489946)
			(stroke
				(width 0.1)
				(type default)
			)
			(layer "F.Fab")
		)
		(fp_line
			(start -3.525012 21.310092)
			(end 3.525012 21.310092)
			(stroke
				(width 0.1)
				(type default)
			)
			(layer "F.Fab")
		)
		(fp_line
			(start -3.525012 -10.489946)
			(end -3.525012 21.310092)
			(stroke
				(width 0.1)
				(type default)
			)
			(layer "F.Fab")
		)
		(pad "" np_thru_hole circle
			(at 0 -6.620002 180)
			(size 3.175 3.175)
			(drill 3.175)
			(layers "*.Cu" "*.Mask")
			(clearance 0.381)
			(thermal_gap 0.381)
		)
		(pad "" np_thru_hole circle
			(at 0 0 180)
			(size 0 0)
			(drill 3.175)
			(layers "*.Cu" "*.Mask")
			(clearance 0)
		)
		(pad "" np_thru_hole circle
			(at 0 5.130038 180)
			(size 3.175 3.175)
			(drill 3.175)
			(layers "*.Cu" "*.Mask")
			(clearance 0.381)
			(thermal_gap 0.381)
		)
		(zone
			(layers "F.Cu" "B.Cu" "In1.Cu" "In2.Cu" "In3.Cu" "In4.Cu" "In5.Cu" "In6.Cu"
				"In7.Cu" "In8.Cu" "In9.Cu" "In10.Cu" "In11.Cu" "In12.Cu" "In13.Cu" "In14.Cu"
				"In15.Cu" "In16.Cu"
			)
			(hatch none 0.5)
			(connect_pads
				(clearance 0)
			)
			(min_thickness 0.25)
			(keepout
				(tracks not_allowed)
				(vias allowed)
				(pads allowed)
				(copperpour not_allowed)
				(footprints allowed)
			)
			(placement
				(enabled no)
				(sheetname "")
			)
			(fill
				(thermal_gap 0.5)
				(thermal_bridge_width 0.5)
				(island_removal_mode 0)
			)
			(polygon
				(pts
					(arc
						(start 321.89547 -413.090106)
						(mid 317.70447 -413.090106)
						(end 321.89547 -413.090106)
					)
				)
			)
		)
		(zone
			(layers "F.Cu" "B.Cu" "In1.Cu" "In2.Cu" "In3.Cu" "In4.Cu" "In5.Cu" "In6.Cu"
				"In7.Cu" "In8.Cu" "In9.Cu" "In10.Cu" "In11.Cu" "In12.Cu" "In13.Cu" "In14.Cu"
				"In15.Cu" "In16.Cu"
			)
			(hatch none 0.5)
			(connect_pads
				(clearance 0)
			)
			(min_thickness 0.25)
			(keepout
				(tracks not_allowed)
				(vias allowed)
				(pads allowed)
				(copperpour not_allowed)
				(footprints allowed)
			)
			(placement
				(enabled no)
				(sheetname "")
			)
			(fill
				(thermal_gap 0.5)
				(thermal_bridge_width 0.5)
				(island_removal_mode 0)
			)
			(polygon
				(pts
					(arc
						(start 321.89547 -401.340066)
						(mid 317.70447 -401.340066)
						(end 321.89547 -401.340066)
					)
				)
			)
		)
		(zone
			(layers "F.Cu" "B.Cu" "In1.Cu" "In2.Cu" "In3.Cu" "In4.Cu" "In5.Cu" "In6.Cu"
				"In7.Cu" "In8.Cu" "In9.Cu" "In10.Cu" "In11.Cu" "In12.Cu" "In13.Cu" "In14.Cu"
				"In15.Cu" "In16.Cu"
			)
			(hatch none 0.5)
			(connect_pads
				(clearance 0)
			)
			(min_thickness 0.25)
			(keepout
				(tracks not_allowed)
				(vias allowed)
				(pads allowed)
				(copperpour not_allowed)
				(footprints allowed)
			)
			(placement
				(enabled no)
				(sheetname "")
			)
			(fill
				(thermal_gap 0.5)
				(thermal_bridge_width 0.5)
				(island_removal_mode 0)
			)
			(polygon
				(pts
					(arc
						(start 323.41947 -407.960068)
						(mid 316.18047 -407.960068)
						(end 323.41947 -407.960068)
					)
				)
			)
		)
	)
	(footprint ""
		(layer "F.Cu")
		(at 86.803992 -289.230816 90)
		(property "Reference" "R3947"
			(at 0 0 90)
			(layer "F.SilkS")
			(hide yes)
			(effects
				(font
					(size 1.27 1.27)
				)
			)
		)
		(property "Value" ""
			(at 0 0 90)
			(layer "F.Fab")
			(effects
				(font
					(size 1.27 1.27)
				)
			)
		)
		(duplicate_pad_numbers_are_jumpers no)
		(fp_line
			(start 0.7874 -0.4064)
			(end 0.7874 0.4064)
			(stroke
				(width 0.1524)
				(type default)
			)
			(layer "F.SilkS")
		)
		(fp_line
			(start -0.7874 -0.4064)
			(end 0.7874 -0.4064)
			(stroke
				(width 0.1524)
				(type default)
			)
			(layer "F.SilkS")
		)
		(fp_line
			(start 0.7874 0.4064)
			(end -0.7874 0.4064)
			(stroke
				(width 0.1524)
				(type default)
			)
			(layer "F.SilkS")
		)
		(fp_line
			(start -0.7874 0.4064)
			(end -0.7874 -0.4064)
			(stroke
				(width 0.1524)
				(type default)
			)
			(layer "F.SilkS")
		)
		(fp_line
			(start -0.12065 -0.305054)
			(end -0.12065 -0.2794)
			(stroke
				(width 0.1)
				(type default)
			)
			(layer "F.Fab")
		)
		(fp_line
			(start -0.67945 -0.305054)
			(end -0.12065 -0.305054)
			(stroke
				(width 0.1)
				(type default)
			)
			(layer "F.Fab")
		)
		(fp_line
			(start 0.67945 -0.3048)
			(end 0.67945 0.3048)
			(stroke
				(width 0.1)
				(type default)
			)
			(layer "F.Fab")
		)
		(fp_line
			(start 0.12065 -0.3048)
			(end 0.67945 -0.3048)
			(stroke
				(width 0.1)
				(type default)
			)
			(layer "F.Fab")
		)
		(fp_line
			(start 0.12065 -0.2794)
			(end 0.12065 -0.3048)
			(stroke
				(width 0.1)
				(type default)
			)
			(layer "F.Fab")
		)
		(fp_line
			(start -0.12065 -0.2794)
			(end 0.12065 -0.2794)
			(stroke
				(width 0.1)
				(type default)
			)
			(layer "F.Fab")
		)
		(fp_line
			(start 0.120396 0.2794)
			(end -0.12065 0.2794)
			(stroke
				(width 0.1)
				(type default)
			)
			(layer "F.Fab")
		)
		(fp_line
			(start -0.12065 0.2794)
			(end -0.12065 0.3048)
			(stroke
				(width 0.1)
				(type default)
			)
			(layer "F.Fab")
		)
		(fp_line
			(start 0.67945 0.3048)
			(end 0.120396 0.3048)
			(stroke
				(width 0.1)
				(type default)
			)
			(layer "F.Fab")
		)
		(fp_line
			(start 0.120396 0.3048)
			(end 0.120396 0.2794)
			(stroke
				(width 0.1)
				(type default)
			)
			(layer "F.Fab")
		)
		(fp_line
			(start -0.12065 0.3048)
			(end -0.67945 0.3048)
			(stroke
				(width 0.1)
				(type default)
			)
			(layer "F.Fab")
		)
		(fp_line
			(start -0.67945 0.3048)
			(end -0.67945 -0.305054)
			(stroke
				(width 0.1)
				(type default)
			)
			(layer "F.Fab")
		)
		(pad "1" smd circle
			(at -0.40005 0 90)
			(size 0 0)
			(layers "F.Cu" "F.Mask" "F.Paste")
			(net "PWRGD_P1V8_PEX_R")
		)
		(pad "2" smd circle
			(at 0.40005 0 90)
			(size 0 0)
			(layers "F.Cu" "F.Mask" "F.Paste")
			(net "PWRGD_P1V8_PEX0_R")
		)
	)
	(footprint ""
		(layer "F.Cu")
		(at 189.98565 -27.092148 -90)
		(property "Reference" "R5743"
			(at 0 0 270)
			(layer "F.SilkS")
			(hide yes)
			(effects
				(font
					(size 1.27 1.27)
				)
			)
		)
		(property "Value" ""
			(at 0 0 270)
			(layer "F.Fab")
			(effects
				(font
					(size 1.27 1.27)
				)
			)
		)
		(duplicate_pad_numbers_are_jumpers no)
		(fp_line
			(start -0.7874 0.4064)
			(end -0.7874 -0.4064)
			(stroke
				(width 0.1524)
				(type default)
			)
			(layer "F.SilkS")
		)
		(fp_line
			(start 0.7874 0.4064)
			(end -0.7874 0.4064)
			(stroke
				(width 0.1524)
				(type default)
			)
			(layer "F.SilkS")
		)
		(fp_line
			(start -0.7874 -0.4064)
			(end 0.7874 -0.4064)
			(stroke
				(width 0.1524)
				(type default)
			)
			(layer "F.SilkS")
		)
		(fp_line
			(start 0.7874 -0.4064)
			(end 0.7874 0.4064)
			(stroke
				(width 0.1524)
				(type default)
			)
			(layer "F.SilkS")
		)
		(fp_line
			(start -0.67945 0.3048)
			(end -0.67945 -0.305054)
			(stroke
				(width 0.1)
				(type default)
			)
			(layer "F.Fab")
		)
		(fp_line
			(start -0.12065 0.3048)
			(end -0.67945 0.3048)
			(stroke
				(width 0.1)
				(type default)
			)
			(layer "F.Fab")
		)
		(fp_line
			(start 0.120396 0.3048)
			(end 0.120396 0.2794)
			(stroke
				(width 0.1)
				(type default)
			)
			(layer "F.Fab")
		)
		(fp_line
			(start 0.67945 0.3048)
			(end 0.120396 0.3048)
			(stroke
				(width 0.1)
				(type default)
			)
			(layer "F.Fab")
		)
		(fp_line
			(start -0.12065 0.2794)
			(end -0.12065 0.3048)
			(stroke
				(width 0.1)
				(type default)
			)
			(layer "F.Fab")
		)
		(fp_line
			(start 0.120396 0.2794)
			(end -0.12065 0.2794)
			(stroke
				(width 0.1)
				(type default)
			)
			(layer "F.Fab")
		)
		(fp_line
			(start -0.12065 -0.2794)
			(end 0.12065 -0.2794)
			(stroke
				(width 0.1)
				(type default)
			)
			(layer "F.Fab")
		)
		(fp_line
			(start 0.12065 -0.2794)
			(end 0.12065 -0.3048)
			(stroke
				(width 0.1)
				(type default)
			)
			(layer "F.Fab")
		)
		(fp_line
			(start 0.12065 -0.3048)
			(end 0.67945 -0.3048)
			(stroke
				(width 0.1)
				(type default)
			)
			(layer "F.Fab")
		)
		(fp_line
			(start 0.67945 -0.3048)
			(end 0.67945 0.3048)
			(stroke
				(width 0.1)
				(type default)
			)
			(layer "F.Fab")
		)
		(fp_line
			(start -0.67945 -0.305054)
			(end -0.12065 -0.305054)
			(stroke
				(width 0.1)
				(type default)
			)
			(layer "F.Fab")
		)
		(fp_line
			(start -0.12065 -0.305054)
			(end -0.12065 -0.2794)
			(stroke
				(width 0.1)
				(type default)
			)
			(layer "F.Fab")
		)
		(pad "1" smd circle
			(at -0.40005 0 270)
			(size 0 0)
			(layers "F.Cu" "F.Mask" "F.Paste")
			(net "P3V3_SSD6")
		)
		(pad "2" smd circle
			(at 0.40005 0 270)
			(size 0 0)
			(layers "F.Cu" "F.Mask" "F.Paste")
			(net "SSD6_LED_ISO_N")
		)
	)
	(footprint ""
		(layer "F.Cu")
		(at 268.506448 -86.235286 180)
		(property "Reference" "R1069"
			(at 0 0 180)
			(layer "F.SilkS")
			(hide yes)
			(effects
				(font
					(size 1.27 1.27)
				)
			)
		)
		(property "Value" ""
			(at 0 0 180)
			(layer "F.Fab")
			(effects
				(font
					(size 1.27 1.27)
				)
			)
		)
		(duplicate_pad_numbers_are_jumpers no)
		(fp_line
			(start 0.7874 0.4064)
			(end -0.7874 0.4064)
			(stroke
				(width 0.1524)
				(type default)
			)
			(layer "F.SilkS")
		)
		(fp_line
			(start 0.7874 -0.4064)
			(end 0.7874 0.4064)
			(stroke
				(width 0.1524)
				(type default)
			)
			(layer "F.SilkS")
		)
		(fp_line
			(start -0.7874 0.4064)
			(end -0.7874 -0.4064)
			(stroke
				(width 0.1524)
				(type default)
			)
			(layer "F.SilkS")
		)
		(fp_line
			(start -0.7874 -0.4064)
			(end 0.7874 -0.4064)
			(stroke
				(width 0.1524)
				(type default)
			)
			(layer "F.SilkS")
		)
		(fp_line
			(start 0.67945 0.3048)
			(end 0.120396 0.3048)
			(stroke
				(width 0.1)
				(type default)
			)
			(layer "F.Fab")
		)
		(fp_line
			(start 0.67945 -0.3048)
			(end 0.67945 0.3048)
			(stroke
				(width 0.1)
				(type default)
			)
			(layer "F.Fab")
		)
		(fp_line
			(start 0.12065 -0.2794)
			(end 0.12065 -0.3048)
			(stroke
				(width 0.1)
				(type default)
			)
			(layer "F.Fab")
		)
		(fp_line
			(start 0.12065 -0.3048)
			(end 0.67945 -0.3048)
			(stroke
				(width 0.1)
				(type default)
			)
			(layer "F.Fab")
		)
		(fp_line
			(start 0.120396 0.3048)
			(end 0.120396 0.2794)
			(stroke
				(width 0.1)
				(type default)
			)
			(layer "F.Fab")
		)
		(fp_line
			(start 0.120396 0.2794)
			(end -0.12065 0.2794)
			(stroke
				(width 0.1)
				(type default)
			)
			(layer "F.Fab")
		)
		(fp_line
			(start -0.12065 0.3048)
			(end -0.67945 0.3048)
			(stroke
				(width 0.1)
				(type default)
			)
			(layer "F.Fab")
		)
		(fp_line
			(start -0.12065 0.2794)
			(end -0.12065 0.3048)
			(stroke
				(width 0.1)
				(type default)
			)
			(layer "F.Fab")
		)
		(fp_line
			(start -0.12065 -0.2794)
			(end 0.12065 -0.2794)
			(stroke
				(width 0.1)
				(type default)
			)
			(layer "F.Fab")
		)
		(fp_line
			(start -0.12065 -0.305054)
			(end -0.12065 -0.2794)
			(stroke
				(width 0.1)
				(type default)
			)
			(layer "F.Fab")
		)
		(fp_line
			(start -0.67945 0.3048)
			(end -0.67945 -0.305054)
			(stroke
				(width 0.1)
				(type default)
			)
			(layer "F.Fab")
		)
		(fp_line
			(start -0.67945 -0.305054)
			(end -0.12065 -0.305054)
			(stroke
				(width 0.1)
				(type default)
			)
			(layer "F.Fab")
		)
		(pad "1" smd circle
			(at -0.40005 0 180)
			(size 0 0)
			(layers "F.Cu" "F.Mask" "F.Paste")
			(net "GND")
		)
		(pad "2" smd circle
			(at 0.40005 0 180)
			(size 0 0)
			(layers "F.Cu" "F.Mask" "F.Paste")
			(net "CLK_BUFFER_DB2000QL_OE0_N")
		)
	)
	(footprint ""
		(layer "F.Cu")
		(at 137.27684 -124.008134 90)
		(property "Reference" "PD56"
			(at -3.390392 2.350516 90)
			(unlocked yes)
			(layer "F.SilkS")
			(effects
				(font
					(size 0.7874 0.5842)
					(thickness 0.1524)
				)
				(justify left)
			)
		)
		(property "Value" ""
			(at 0 0 90)
			(layer "F.Fab")
			(effects
				(font
					(size 1.27 1.27)
				)
			)
		)
		(duplicate_pad_numbers_are_jumpers no)
		(fp_line
			(start 4.107942 -1.459992)
			(end 4.107942 1.459992)
			(stroke
				(width 0.1524)
				(type default)
			)
			(layer "F.SilkS")
		)
		(fp_line
			(start -3.400044 -1.459992)
			(end 4.107942 -1.459992)
			(stroke
				(width 0.1524)
				(type default)
			)
			(layer "F.SilkS")
		)
		(fp_line
			(start 4.107942 1.459992)
			(end -3.400044 1.459992)
			(stroke
				(width 0.1524)
				(type default)
			)
			(layer "F.SilkS")
		)
		(fp_line
			(start -3.400044 1.459992)
			(end -3.400044 -1.459992)
			(stroke
				(width 0.1524)
				(type default)
			)
			(layer "F.SilkS")
		)
		(fp_poly
			(pts
				(xy 4.107942 -1.459992) (xy 4.107942 1.459992) (xy 3.308096 1.459992) (xy 3.308096 -1.459992)
			)
			(stroke
				(width 0)
				(type default)
			)
			(fill yes)
			(layer "F.SilkS")
		)
		(fp_line
			(start 2.29997 -1.459992)
			(end 2.29997 1.459992)
			(stroke
				(width 0.1)
				(type default)
			)
			(layer "F.Fab")
		)
		(fp_line
			(start -2.29997 -1.459992)
			(end 2.29997 -1.459992)
			(stroke
				(width 0.1)
				(type default)
			)
			(layer "F.Fab")
		)
		(fp_line
			(start 2.29997 1.459992)
			(end -2.29997 1.459992)
			(stroke
				(width 0.1)
				(type default)
			)
			(layer "F.Fab")
		)
		(fp_line
			(start -2.29997 1.459992)
			(end -2.29997 -1.459992)
			(stroke
				(width 0.1)
				(type default)
			)
			(layer "F.Fab")
		)
		(fp_text user "+"
			(at -4.7752 -0.12065 90)
			(unlocked yes)
			(layer "F.SilkS")
			(effects
				(font
					(size 1.905 1.4224)
					(thickness 0.1524)
				)
				(justify left)
			)
		)
		(fp_text user "-"
			(at 5.4102 0.29845 270)
			(unlocked yes)
			(layer "F.SilkS")
			(effects
				(font
					(size 1.905 1.4224)
					(thickness 0.1524)
				)
				(justify left)
			)
		)
		(fp_text user "+"
			(at -4.7752 -0.12065 90)
			(unlocked yes)
			(layer "F.Fab")
			(effects
				(font
					(size 1.905 1.4224)
					(thickness 0.1524)
				)
				(justify left)
			)
		)
		(fp_text user "-"
			(at 5.4102 0.29845 270)
			(unlocked yes)
			(layer "F.Fab")
			(effects
				(font
					(size 1.905 1.4224)
					(thickness 0.1524)
				)
				(justify left)
			)
		)
		(pad "A" smd rect
			(at -1.999996 0 180)
			(size 1.7018 2.5146)
			(layers "F.Cu" "F.Mask" "F.Paste")
			(net "GND")
		)
		(pad "C" smd rect
			(at 1.999996 0 180)
			(size 1.7018 2.5146)
			(layers "F.Cu" "F.Mask" "F.Paste")
			(net "P3V3_NIC2")
		)
	)
	(footprint ""
		(layer "F.Cu")
		(at 336.042 -159.766 180)
		(property "Reference" "R4800"
			(at 0 0 180)
			(layer "F.SilkS")
			(hide yes)
			(effects
				(font
					(size 1.27 1.27)
				)
			)
		)
		(property "Value" ""
			(at 0 0 180)
			(layer "F.Fab")
			(effects
				(font
					(size 1.27 1.27)
				)
			)
		)
		(duplicate_pad_numbers_are_jumpers no)
		(fp_line
			(start 0.7874 0.4064)
			(end -0.7874 0.4064)
			(stroke
				(width 0.1524)
				(type default)
			)
			(layer "F.SilkS")
		)
		(fp_line
			(start 0.7874 -0.4064)
			(end 0.7874 0.4064)
			(stroke
				(width 0.1524)
				(type default)
			)
			(layer "F.SilkS")
		)
		(fp_line
			(start -0.7874 0.4064)
			(end -0.7874 -0.4064)
			(stroke
				(width 0.1524)
				(type default)
			)
			(layer "F.SilkS")
		)
		(fp_line
			(start -0.7874 -0.4064)
			(end 0.7874 -0.4064)
			(stroke
				(width 0.1524)
				(type default)
			)
			(layer "F.SilkS")
		)
		(fp_line
			(start 0.67945 0.3048)
			(end 0.120396 0.3048)
			(stroke
				(width 0.1)
				(type default)
			)
			(layer "F.Fab")
		)
		(fp_line
			(start 0.67945 -0.3048)
			(end 0.67945 0.3048)
			(stroke
				(width 0.1)
				(type default)
			)
			(layer "F.Fab")
		)
		(fp_line
			(start 0.12065 -0.2794)
			(end 0.12065 -0.3048)
			(stroke
				(width 0.1)
				(type default)
			)
			(layer "F.Fab")
		)
		(fp_line
			(start 0.12065 -0.3048)
			(end 0.67945 -0.3048)
			(stroke
				(width 0.1)
				(type default)
			)
			(layer "F.Fab")
		)
		(fp_line
			(start 0.120396 0.3048)
			(end 0.120396 0.2794)
			(stroke
				(width 0.1)
				(type default)
			)
			(layer "F.Fab")
		)
		(fp_line
			(start 0.120396 0.2794)
			(end -0.12065 0.2794)
			(stroke
				(width 0.1)
				(type default)
			)
			(layer "F.Fab")
		)
		(fp_line
			(start -0.12065 0.3048)
			(end -0.67945 0.3048)
			(stroke
				(width 0.1)
				(type default)
			)
			(layer "F.Fab")
		)
		(fp_line
			(start -0.12065 0.2794)
			(end -0.12065 0.3048)
			(stroke
				(width 0.1)
				(type default)
			)
			(layer "F.Fab")
		)
		(fp_line
			(start -0.12065 -0.2794)
			(end 0.12065 -0.2794)
			(stroke
				(width 0.1)
				(type default)
			)
			(layer "F.Fab")
		)
		(fp_line
			(start -0.12065 -0.305054)
			(end -0.12065 -0.2794)
			(stroke
				(width 0.1)
				(type default)
			)
			(layer "F.Fab")
		)
		(fp_line
			(start -0.67945 0.3048)
			(end -0.67945 -0.305054)
			(stroke
				(width 0.1)
				(type default)
			)
			(layer "F.Fab")
		)
		(fp_line
			(start -0.67945 -0.305054)
			(end -0.12065 -0.305054)
			(stroke
				(width 0.1)
				(type default)
			)
			(layer "F.Fab")
		)
		(pad "1" smd circle
			(at -0.40005 0 180)
			(size 0 0)
			(layers "F.Cu" "F.Mask" "F.Paste")
			(net "SSD12_PEX_PWR_EN_R")
		)
		(pad "2" smd circle
			(at 0.40005 0 180)
			(size 0 0)
			(layers "F.Cu" "F.Mask" "F.Paste")
			(net "GND")
		)
	)
	(footprint ""
		(layer "F.Cu")
		(at 414.676082 -200.381108 -90)
		(property "Reference" "R6433"
			(at 0 0 270)
			(layer "F.SilkS")
			(hide yes)
			(effects
				(font
					(size 1.27 1.27)
				)
			)
		)
		(property "Value" ""
			(at 0 0 270)
			(layer "F.Fab")
			(effects
				(font
					(size 1.27 1.27)
				)
			)
		)
		(duplicate_pad_numbers_are_jumpers no)
		(fp_line
			(start -0.7874 0.4064)
			(end -0.7874 -0.4064)
			(stroke
				(width 0.1524)
				(type default)
			)
			(layer "F.SilkS")
		)
		(fp_line
			(start 0.7874 0.4064)
			(end -0.7874 0.4064)
			(stroke
				(width 0.1524)
				(type default)
			)
			(layer "F.SilkS")
		)
		(fp_line
			(start -0.7874 -0.4064)
			(end 0.7874 -0.4064)
			(stroke
				(width 0.1524)
				(type default)
			)
			(layer "F.SilkS")
		)
		(fp_line
			(start 0.7874 -0.4064)
			(end 0.7874 0.4064)
			(stroke
				(width 0.1524)
				(type default)
			)
			(layer "F.SilkS")
		)
		(fp_line
			(start -0.67945 0.3048)
			(end -0.67945 -0.305054)
			(stroke
				(width 0.1)
				(type default)
			)
			(layer "F.Fab")
		)
		(fp_line
			(start -0.12065 0.3048)
			(end -0.67945 0.3048)
			(stroke
				(width 0.1)
				(type default)
			)
			(layer "F.Fab")
		)
		(fp_line
			(start 0.120396 0.3048)
			(end 0.120396 0.2794)
			(stroke
				(width 0.1)
				(type default)
			)
			(layer "F.Fab")
		)
		(fp_line
			(start 0.67945 0.3048)
			(end 0.120396 0.3048)
			(stroke
				(width 0.1)
				(type default)
			)
			(layer "F.Fab")
		)
		(fp_line
			(start -0.12065 0.2794)
			(end -0.12065 0.3048)
			(stroke
				(width 0.1)
				(type default)
			)
			(layer "F.Fab")
		)
		(fp_line
			(start 0.120396 0.2794)
			(end -0.12065 0.2794)
			(stroke
				(width 0.1)
				(type default)
			)
			(layer "F.Fab")
		)
		(fp_line
			(start -0.12065 -0.2794)
			(end 0.12065 -0.2794)
			(stroke
				(width 0.1)
				(type default)
			)
			(layer "F.Fab")
		)
		(fp_line
			(start 0.12065 -0.2794)
			(end 0.12065 -0.3048)
			(stroke
				(width 0.1)
				(type default)
			)
			(layer "F.Fab")
		)
		(fp_line
			(start 0.12065 -0.3048)
			(end 0.67945 -0.3048)
			(stroke
				(width 0.1)
				(type default)
			)
			(layer "F.Fab")
		)
		(fp_line
			(start 0.67945 -0.3048)
			(end 0.67945 0.3048)
			(stroke
				(width 0.1)
				(type default)
			)
			(layer "F.Fab")
		)
		(fp_line
			(start -0.67945 -0.305054)
			(end -0.12065 -0.305054)
			(stroke
				(width 0.1)
				(type default)
			)
			(layer "F.Fab")
		)
		(fp_line
			(start -0.12065 -0.305054)
			(end -0.12065 -0.2794)
			(stroke
				(width 0.1)
				(type default)
			)
			(layer "F.Fab")
		)
		(pad "1" smd circle
			(at -0.40005 0 270)
			(size 0 0)
			(layers "F.Cu" "F.Mask" "F.Paste")
			(net "FPGA_PEX1_MODE_SEL2_D_N")
		)
		(pad "2" smd circle
			(at 0.40005 0 270)
			(size 0 0)
			(layers "F.Cu" "F.Mask" "F.Paste")
			(net "P3V3_AUX")
		)
	)
	(footprint ""
		(layer "F.Cu")
		(at 454.542398 -235.223558 90)
		(property "Reference" "R6612"
			(at 0 0 90)
			(layer "F.SilkS")
			(hide yes)
			(effects
				(font
					(size 1.27 1.27)
				)
			)
		)
		(property "Value" ""
			(at 0 0 90)
			(layer "F.Fab")
			(effects
				(font
					(size 1.27 1.27)
				)
			)
		)
		(duplicate_pad_numbers_are_jumpers no)
		(fp_line
			(start 0.7874 -0.4064)
			(end 0.7874 0.4064)
			(stroke
				(width 0.1524)
				(type default)
			)
			(layer "F.SilkS")
		)
		(fp_line
			(start -0.7874 -0.4064)
			(end 0.7874 -0.4064)
			(stroke
				(width 0.1524)
				(type default)
			)
			(layer "F.SilkS")
		)
		(fp_line
			(start 0.7874 0.4064)
			(end -0.7874 0.4064)
			(stroke
				(width 0.1524)
				(type default)
			)
			(layer "F.SilkS")
		)
		(fp_line
			(start -0.7874 0.4064)
			(end -0.7874 -0.4064)
			(stroke
				(width 0.1524)
				(type default)
			)
			(layer "F.SilkS")
		)
		(fp_line
			(start -0.12065 -0.305054)
			(end -0.12065 -0.2794)
			(stroke
				(width 0.1)
				(type default)
			)
			(layer "F.Fab")
		)
		(fp_line
			(start -0.67945 -0.305054)
			(end -0.12065 -0.305054)
			(stroke
				(width 0.1)
				(type default)
			)
			(layer "F.Fab")
		)
		(fp_line
			(start 0.67945 -0.3048)
			(end 0.67945 0.3048)
			(stroke
				(width 0.1)
				(type default)
			)
			(layer "F.Fab")
		)
		(fp_line
			(start 0.12065 -0.3048)
			(end 0.67945 -0.3048)
			(stroke
				(width 0.1)
				(type default)
			)
			(layer "F.Fab")
		)
		(fp_line
			(start 0.12065 -0.2794)
			(end 0.12065 -0.3048)
			(stroke
				(width 0.1)
				(type default)
			)
			(layer "F.Fab")
		)
		(fp_line
			(start -0.12065 -0.2794)
			(end 0.12065 -0.2794)
			(stroke
				(width 0.1)
				(type default)
			)
			(layer "F.Fab")
		)
		(fp_line
			(start 0.120396 0.2794)
			(end -0.12065 0.2794)
			(stroke
				(width 0.1)
				(type default)
			)
			(layer "F.Fab")
		)
		(fp_line
			(start -0.12065 0.2794)
			(end -0.12065 0.3048)
			(stroke
				(width 0.1)
				(type default)
			)
			(layer "F.Fab")
		)
		(fp_line
			(start 0.67945 0.3048)
			(end 0.120396 0.3048)
			(stroke
				(width 0.1)
				(type default)
			)
			(layer "F.Fab")
		)
		(fp_line
			(start 0.120396 0.3048)
			(end 0.120396 0.2794)
			(stroke
				(width 0.1)
				(type default)
			)
			(layer "F.Fab")
		)
		(fp_line
			(start -0.12065 0.3048)
			(end -0.67945 0.3048)
			(stroke
				(width 0.1)
				(type default)
			)
			(layer "F.Fab")
		)
		(fp_line
			(start -0.67945 0.3048)
			(end -0.67945 -0.305054)
			(stroke
				(width 0.1)
				(type default)
			)
			(layer "F.Fab")
		)
		(pad "1" smd circle
			(at -0.40005 0 90)
			(size 0 0)
			(layers "F.Cu" "F.Mask" "F.Paste")
			(net "UART_PEX0_SDB_CP2108_RX")
		)
		(pad "2" smd circle
			(at 0.40005 0 90)
			(size 0 0)
			(layers "F.Cu" "F.Mask" "F.Paste")
			(net "UART_PEX0_SDB_R_RX")
		)
	)
	(footprint ""
		(layer "F.Cu")
		(at 11.912854 -45.111924 180)
		(property "Reference" "R5540"
			(at 0 0 180)
			(layer "F.SilkS")
			(hide yes)
			(effects
				(font
					(size 1.27 1.27)
				)
			)
		)
		(property "Value" ""
			(at 0 0 180)
			(layer "F.Fab")
			(effects
				(font
					(size 1.27 1.27)
				)
			)
		)
		(duplicate_pad_numbers_are_jumpers no)
		(fp_line
			(start 0.7874 0.4064)
			(end -0.7874 0.4064)
			(stroke
				(width 0.1524)
				(type default)
			)
			(layer "F.SilkS")
		)
		(fp_line
			(start 0.7874 -0.4064)
			(end 0.7874 0.4064)
			(stroke
				(width 0.1524)
				(type default)
			)
			(layer "F.SilkS")
		)
		(fp_line
			(start -0.7874 0.4064)
			(end -0.7874 -0.4064)
			(stroke
				(width 0.1524)
				(type default)
			)
			(layer "F.SilkS")
		)
		(fp_line
			(start -0.7874 -0.4064)
			(end 0.7874 -0.4064)
			(stroke
				(width 0.1524)
				(type default)
			)
			(layer "F.SilkS")
		)
		(fp_line
			(start 0.67945 0.3048)
			(end 0.120396 0.3048)
			(stroke
				(width 0.1)
				(type default)
			)
			(layer "F.Fab")
		)
		(fp_line
			(start 0.67945 -0.3048)
			(end 0.67945 0.3048)
			(stroke
				(width 0.1)
				(type default)
			)
			(layer "F.Fab")
		)
		(fp_line
			(start 0.12065 -0.2794)
			(end 0.12065 -0.3048)
			(stroke
				(width 0.1)
				(type default)
			)
			(layer "F.Fab")
		)
		(fp_line
			(start 0.12065 -0.3048)
			(end 0.67945 -0.3048)
			(stroke
				(width 0.1)
				(type default)
			)
			(layer "F.Fab")
		)
		(fp_line
			(start 0.120396 0.3048)
			(end 0.120396 0.2794)
			(stroke
				(width 0.1)
				(type default)
			)
			(layer "F.Fab")
		)
		(fp_line
			(start 0.120396 0.2794)
			(end -0.12065 0.2794)
			(stroke
				(width 0.1)
				(type default)
			)
			(layer "F.Fab")
		)
		(fp_line
			(start -0.12065 0.3048)
			(end -0.67945 0.3048)
			(stroke
				(width 0.1)
				(type default)
			)
			(layer "F.Fab")
		)
		(fp_line
			(start -0.12065 0.2794)
			(end -0.12065 0.3048)
			(stroke
				(width 0.1)
				(type default)
			)
			(layer "F.Fab")
		)
		(fp_line
			(start -0.12065 -0.2794)
			(end 0.12065 -0.2794)
			(stroke
				(width 0.1)
				(type default)
			)
			(layer "F.Fab")
		)
		(fp_line
			(start -0.12065 -0.305054)
			(end -0.12065 -0.2794)
			(stroke
				(width 0.1)
				(type default)
			)
			(layer "F.Fab")
		)
		(fp_line
			(start -0.67945 0.3048)
			(end -0.67945 -0.305054)
			(stroke
				(width 0.1)
				(type default)
			)
			(layer "F.Fab")
		)
		(fp_line
			(start -0.67945 -0.305054)
			(end -0.12065 -0.305054)
			(stroke
				(width 0.1)
				(type default)
			)
			(layer "F.Fab")
		)
		(pad "1" smd circle
			(at -0.40005 0 180)
			(size 0 0)
			(layers "F.Cu" "F.Mask" "F.Paste")
			(net "P3V3_AUX")
		)
		(pad "2" smd circle
			(at 0.40005 0 180)
			(size 0 0)
			(layers "F.Cu" "F.Mask" "F.Paste")
			(net "SSD0_AUX_P3V3_EN")
		)
	)
	(footprint ""
		(layer "F.Cu")
		(at 163.985702 -25.1587 -90)
		(property "Reference" "R5742"
			(at 0 0 270)
			(layer "F.SilkS")
			(hide yes)
			(effects
				(font
					(size 1.27 1.27)
				)
			)
		)
		(property "Value" ""
			(at 0 0 270)
			(layer "F.Fab")
			(effects
				(font
					(size 1.27 1.27)
				)
			)
		)
		(duplicate_pad_numbers_are_jumpers no)
		(fp_line
			(start -0.7874 0.4064)
			(end -0.7874 -0.4064)
			(stroke
				(width 0.1524)
				(type default)
			)
			(layer "F.SilkS")
		)
		(fp_line
			(start 0.7874 0.4064)
			(end -0.7874 0.4064)
			(stroke
				(width 0.1524)
				(type default)
			)
			(layer "F.SilkS")
		)
		(fp_line
			(start -0.7874 -0.4064)
			(end 0.7874 -0.4064)
			(stroke
				(width 0.1524)
				(type default)
			)
			(layer "F.SilkS")
		)
		(fp_line
			(start 0.7874 -0.4064)
			(end 0.7874 0.4064)
			(stroke
				(width 0.1524)
				(type default)
			)
			(layer "F.SilkS")
		)
		(fp_line
			(start -0.67945 0.3048)
			(end -0.67945 -0.305054)
			(stroke
				(width 0.1)
				(type default)
			)
			(layer "F.Fab")
		)
		(fp_line
			(start -0.12065 0.3048)
			(end -0.67945 0.3048)
			(stroke
				(width 0.1)
				(type default)
			)
			(layer "F.Fab")
		)
		(fp_line
			(start 0.120396 0.3048)
			(end 0.120396 0.2794)
			(stroke
				(width 0.1)
				(type default)
			)
			(layer "F.Fab")
		)
		(fp_line
			(start 0.67945 0.3048)
			(end 0.120396 0.3048)
			(stroke
				(width 0.1)
				(type default)
			)
			(layer "F.Fab")
		)
		(fp_line
			(start -0.12065 0.2794)
			(end -0.12065 0.3048)
			(stroke
				(width 0.1)
				(type default)
			)
			(layer "F.Fab")
		)
		(fp_line
			(start 0.120396 0.2794)
			(end -0.12065 0.2794)
			(stroke
				(width 0.1)
				(type default)
			)
			(layer "F.Fab")
		)
		(fp_line
			(start -0.12065 -0.2794)
			(end 0.12065 -0.2794)
			(stroke
				(width 0.1)
				(type default)
			)
			(layer "F.Fab")
		)
		(fp_line
			(start 0.12065 -0.2794)
			(end 0.12065 -0.3048)
			(stroke
				(width 0.1)
				(type default)
			)
			(layer "F.Fab")
		)
		(fp_line
			(start 0.12065 -0.3048)
			(end 0.67945 -0.3048)
			(stroke
				(width 0.1)
				(type default)
			)
			(layer "F.Fab")
		)
		(fp_line
			(start 0.67945 -0.3048)
			(end 0.67945 0.3048)
			(stroke
				(width 0.1)
				(type default)
			)
			(layer "F.Fab")
		)
		(fp_line
			(start -0.67945 -0.305054)
			(end -0.12065 -0.305054)
			(stroke
				(width 0.1)
				(type default)
			)
			(layer "F.Fab")
		)
		(fp_line
			(start -0.12065 -0.305054)
			(end -0.12065 -0.2794)
			(stroke
				(width 0.1)
				(type default)
			)
			(layer "F.Fab")
		)
		(pad "1" smd circle
			(at -0.40005 0 270)
			(size 0 0)
			(layers "F.Cu" "F.Mask" "F.Paste")
			(net "SSD5_LED_ISO_N")
		)
		(pad "2" smd circle
			(at 0.40005 0 270)
			(size 0 0)
			(layers "F.Cu" "F.Mask" "F.Paste")
			(net "SSD5_LED_ISO_R_N")
		)
	)
	(footprint ""
		(layer "F.Cu")
		(at 37.960808 -356.244906 90)
		(property "Reference" "C2170"
			(at 0 0 90)
			(layer "F.SilkS")
			(hide yes)
			(effects
				(font
					(size 1.27 1.27)
				)
			)
		)
		(property "Value" ""
			(at 0 0 90)
			(layer "F.Fab")
			(effects
				(font
					(size 1.27 1.27)
				)
			)
		)
		(duplicate_pad_numbers_are_jumpers no)
		(fp_line
			(start 0.299974 -0.150114)
			(end 0.299974 0.150114)
			(stroke
				(width 0.1)
				(type default)
			)
			(layer "F.Fab")
		)
		(fp_line
			(start -0.299974 -0.150114)
			(end 0.299974 -0.150114)
			(stroke
				(width 0.1)
				(type default)
			)
			(layer "F.Fab")
		)
		(fp_line
			(start 0.299974 0.150114)
			(end -0.299974 0.150114)
			(stroke
				(width 0.1)
				(type default)
			)
			(layer "F.Fab")
		)
		(fp_line
			(start -0.299974 0.150114)
			(end -0.299974 -0.150114)
			(stroke
				(width 0.1)
				(type default)
			)
			(layer "F.Fab")
		)
		(pad "1" smd rect
			(at -0.2667 0 90)
			(size 0.3048 0.381)
			(layers "F.Cu" "F.Mask" "F.Paste")
			(net "P5E_PEX0_STN4_TX_DP<70>")
		)
		(pad "2" smd rect
			(at 0.2667 0 90)
			(size 0.3048 0.381)
			(layers "F.Cu" "F.Mask" "F.Paste")
			(net "P5E_PEX0_STN4_TX_C_DP<70>")
		)
	)
	(footprint ""
		(layer "F.Cu")
		(at 97.471484 -25.342342 -90)
		(property "Reference" "R418"
			(at 0 0 270)
			(layer "F.SilkS")
			(hide yes)
			(effects
				(font
					(size 1.27 1.27)
				)
			)
		)
		(property "Value" ""
			(at 0 0 270)
			(layer "F.Fab")
			(effects
				(font
					(size 1.27 1.27)
				)
			)
		)
		(duplicate_pad_numbers_are_jumpers no)
		(fp_line
			(start -0.7874 0.4064)
			(end -0.7874 -0.4064)
			(stroke
				(width 0.1524)
				(type default)
			)
			(layer "F.SilkS")
		)
		(fp_line
			(start 0.7874 0.4064)
			(end -0.7874 0.4064)
			(stroke
				(width 0.1524)
				(type default)
			)
			(layer "F.SilkS")
		)
		(fp_line
			(start -0.7874 -0.4064)
			(end 0.7874 -0.4064)
			(stroke
				(width 0.1524)
				(type default)
			)
			(layer "F.SilkS")
		)
		(fp_line
			(start 0.7874 -0.4064)
			(end 0.7874 0.4064)
			(stroke
				(width 0.1524)
				(type default)
			)
			(layer "F.SilkS")
		)
		(fp_line
			(start -0.67945 0.3048)
			(end -0.67945 -0.305054)
			(stroke
				(width 0.1)
				(type default)
			)
			(layer "F.Fab")
		)
		(fp_line
			(start -0.12065 0.3048)
			(end -0.67945 0.3048)
			(stroke
				(width 0.1)
				(type default)
			)
			(layer "F.Fab")
		)
		(fp_line
			(start 0.120396 0.3048)
			(end 0.120396 0.2794)
			(stroke
				(width 0.1)
				(type default)
			)
			(layer "F.Fab")
		)
		(fp_line
			(start 0.67945 0.3048)
			(end 0.120396 0.3048)
			(stroke
				(width 0.1)
				(type default)
			)
			(layer "F.Fab")
		)
		(fp_line
			(start -0.12065 0.2794)
			(end -0.12065 0.3048)
			(stroke
				(width 0.1)
				(type default)
			)
			(layer "F.Fab")
		)
		(fp_line
			(start 0.120396 0.2794)
			(end -0.12065 0.2794)
			(stroke
				(width 0.1)
				(type default)
			)
			(layer "F.Fab")
		)
		(fp_line
			(start -0.12065 -0.2794)
			(end 0.12065 -0.2794)
			(stroke
				(width 0.1)
				(type default)
			)
			(layer "F.Fab")
		)
		(fp_line
			(start 0.12065 -0.2794)
			(end 0.12065 -0.3048)
			(stroke
				(width 0.1)
				(type default)
			)
			(layer "F.Fab")
		)
		(fp_line
			(start 0.12065 -0.3048)
			(end 0.67945 -0.3048)
			(stroke
				(width 0.1)
				(type default)
			)
			(layer "F.Fab")
		)
		(fp_line
			(start 0.67945 -0.3048)
			(end 0.67945 0.3048)
			(stroke
				(width 0.1)
				(type default)
			)
			(layer "F.Fab")
		)
		(fp_line
			(start -0.67945 -0.305054)
			(end -0.12065 -0.305054)
			(stroke
				(width 0.1)
				(type default)
			)
			(layer "F.Fab")
		)
		(fp_line
			(start -0.12065 -0.305054)
			(end -0.12065 -0.2794)
			(stroke
				(width 0.1)
				(type default)
			)
			(layer "F.Fab")
		)
		(pad "1" smd circle
			(at -0.40005 0 270)
			(size 0 0)
			(layers "F.Cu" "F.Mask" "F.Paste")
			(net "P3V3_SSD3")
		)
		(pad "2" smd circle
			(at 0.40005 0 270)
			(size 0 0)
			(layers "F.Cu" "F.Mask" "F.Paste")
			(net "DUALPORT_N_SSD3")
		)
	)
	(footprint ""
		(layer "F.Cu")
		(at 371.956584 -20.467574 180)
		(property "Reference" "R1717"
			(at 0 0 180)
			(layer "F.SilkS")
			(hide yes)
			(effects
				(font
					(size 1.27 1.27)
				)
			)
		)
		(property "Value" ""
			(at 0 0 180)
			(layer "F.Fab")
			(effects
				(font
					(size 1.27 1.27)
				)
			)
		)
		(duplicate_pad_numbers_are_jumpers no)
		(fp_line
			(start 0.7874 0.4064)
			(end -0.7874 0.4064)
			(stroke
				(width 0.1524)
				(type default)
			)
			(layer "F.SilkS")
		)
		(fp_line
			(start 0.7874 -0.4064)
			(end 0.7874 0.4064)
			(stroke
				(width 0.1524)
				(type default)
			)
			(layer "F.SilkS")
		)
		(fp_line
			(start -0.7874 0.4064)
			(end -0.7874 -0.4064)
			(stroke
				(width 0.1524)
				(type default)
			)
			(layer "F.SilkS")
		)
		(fp_line
			(start -0.7874 -0.4064)
			(end 0.7874 -0.4064)
			(stroke
				(width 0.1524)
				(type default)
			)
			(layer "F.SilkS")
		)
		(fp_line
			(start 0.67945 0.3048)
			(end 0.120396 0.3048)
			(stroke
				(width 0.1)
				(type default)
			)
			(layer "F.Fab")
		)
		(fp_line
			(start 0.67945 -0.3048)
			(end 0.67945 0.3048)
			(stroke
				(width 0.1)
				(type default)
			)
			(layer "F.Fab")
		)
		(fp_line
			(start 0.12065 -0.2794)
			(end 0.12065 -0.3048)
			(stroke
				(width 0.1)
				(type default)
			)
			(layer "F.Fab")
		)
		(fp_line
			(start 0.12065 -0.3048)
			(end 0.67945 -0.3048)
			(stroke
				(width 0.1)
				(type default)
			)
			(layer "F.Fab")
		)
		(fp_line
			(start 0.120396 0.3048)
			(end 0.120396 0.2794)
			(stroke
				(width 0.1)
				(type default)
			)
			(layer "F.Fab")
		)
		(fp_line
			(start 0.120396 0.2794)
			(end -0.12065 0.2794)
			(stroke
				(width 0.1)
				(type default)
			)
			(layer "F.Fab")
		)
		(fp_line
			(start -0.12065 0.3048)
			(end -0.67945 0.3048)
			(stroke
				(width 0.1)
				(type default)
			)
			(layer "F.Fab")
		)
		(fp_line
			(start -0.12065 0.2794)
			(end -0.12065 0.3048)
			(stroke
				(width 0.1)
				(type default)
			)
			(layer "F.Fab")
		)
		(fp_line
			(start -0.12065 -0.2794)
			(end 0.12065 -0.2794)
			(stroke
				(width 0.1)
				(type default)
			)
			(layer "F.Fab")
		)
		(fp_line
			(start -0.12065 -0.305054)
			(end -0.12065 -0.2794)
			(stroke
				(width 0.1)
				(type default)
			)
			(layer "F.Fab")
		)
		(fp_line
			(start -0.67945 0.3048)
			(end -0.67945 -0.305054)
			(stroke
				(width 0.1)
				(type default)
			)
			(layer "F.Fab")
		)
		(fp_line
			(start -0.67945 -0.305054)
			(end -0.12065 -0.305054)
			(stroke
				(width 0.1)
				(type default)
			)
			(layer "F.Fab")
		)
		(pad "1" smd circle
			(at -0.40005 0 180)
			(size 0 0)
			(layers "F.Cu" "F.Mask" "F.Paste")
			(net "P3V3_SSD12")
		)
		(pad "2" smd circle
			(at 0.40005 0 180)
			(size 0 0)
			(layers "F.Cu" "F.Mask" "F.Paste")
			(net "SMB_ISO_SSD12_SDA")
		)
	)
	(footprint ""
		(layer "F.Cu")
		(at 144.975326 -64.102234 180)
		(property "Reference" "PR7068"
			(at 0 0 180)
			(layer "F.SilkS")
			(hide yes)
			(effects
				(font
					(size 1.27 1.27)
				)
			)
		)
		(property "Value" ""
			(at 0 0 180)
			(layer "F.Fab")
			(effects
				(font
					(size 1.27 1.27)
				)
			)
		)
		(duplicate_pad_numbers_are_jumpers no)
		(fp_line
			(start 0.7874 0.4064)
			(end -0.7874 0.4064)
			(stroke
				(width 0.1524)
				(type default)
			)
			(layer "F.SilkS")
		)
		(fp_line
			(start 0.7874 -0.4064)
			(end 0.7874 0.4064)
			(stroke
				(width 0.1524)
				(type default)
			)
			(layer "F.SilkS")
		)
		(fp_line
			(start -0.7874 0.4064)
			(end -0.7874 -0.4064)
			(stroke
				(width 0.1524)
				(type default)
			)
			(layer "F.SilkS")
		)
		(fp_line
			(start -0.7874 -0.4064)
			(end 0.7874 -0.4064)
			(stroke
				(width 0.1524)
				(type default)
			)
			(layer "F.SilkS")
		)
		(fp_line
			(start 0.67945 0.3048)
			(end 0.120396 0.3048)
			(stroke
				(width 0.1)
				(type default)
			)
			(layer "F.Fab")
		)
		(fp_line
			(start 0.67945 -0.3048)
			(end 0.67945 0.3048)
			(stroke
				(width 0.1)
				(type default)
			)
			(layer "F.Fab")
		)
		(fp_line
			(start 0.12065 -0.2794)
			(end 0.12065 -0.3048)
			(stroke
				(width 0.1)
				(type default)
			)
			(layer "F.Fab")
		)
		(fp_line
			(start 0.12065 -0.3048)
			(end 0.67945 -0.3048)
			(stroke
				(width 0.1)
				(type default)
			)
			(layer "F.Fab")
		)
		(fp_line
			(start 0.120396 0.3048)
			(end 0.120396 0.2794)
			(stroke
				(width 0.1)
				(type default)
			)
			(layer "F.Fab")
		)
		(fp_line
			(start 0.120396 0.2794)
			(end -0.12065 0.2794)
			(stroke
				(width 0.1)
				(type default)
			)
			(layer "F.Fab")
		)
		(fp_line
			(start -0.12065 0.3048)
			(end -0.67945 0.3048)
			(stroke
				(width 0.1)
				(type default)
			)
			(layer "F.Fab")
		)
		(fp_line
			(start -0.12065 0.2794)
			(end -0.12065 0.3048)
			(stroke
				(width 0.1)
				(type default)
			)
			(layer "F.Fab")
		)
		(fp_line
			(start -0.12065 -0.2794)
			(end 0.12065 -0.2794)
			(stroke
				(width 0.1)
				(type default)
			)
			(layer "F.Fab")
		)
		(fp_line
			(start -0.12065 -0.305054)
			(end -0.12065 -0.2794)
			(stroke
				(width 0.1)
				(type default)
			)
			(layer "F.Fab")
		)
		(fp_line
			(start -0.67945 0.3048)
			(end -0.67945 -0.305054)
			(stroke
				(width 0.1)
				(type default)
			)
			(layer "F.Fab")
		)
		(fp_line
			(start -0.67945 -0.305054)
			(end -0.12065 -0.305054)
			(stroke
				(width 0.1)
				(type default)
			)
			(layer "F.Fab")
		)
		(pad "1" smd circle
			(at -0.40005 0 180)
			(size 0 0)
			(layers "F.Cu" "F.Mask" "F.Paste")
			(net "P12V_SSD5_PG_G1")
		)
		(pad "2" smd circle
			(at 0.40005 0 180)
			(size 0 0)
			(layers "F.Cu" "F.Mask" "F.Paste")
			(net "GND")
		)
	)
	(footprint ""
		(layer "F.Cu")
		(at 254.671322 -395.293596 180)
		(property "Reference" "PD1"
			(at 3.719576 4.10464 0)
			(unlocked yes)
			(layer "F.SilkS")
			(effects
				(font
					(size 0.7874 0.5842)
					(thickness 0.1524)
				)
			)
		)
		(property "Value" ""
			(at 0 0 180)
			(layer "F.Fab")
			(effects
				(font
					(size 1.27 1.27)
				)
			)
		)
		(duplicate_pad_numbers_are_jumpers no)
		(fp_line
			(start 5.4102 3.109976)
			(end 5.4102 -3.109976)
			(stroke
				(width 0.1524)
				(type default)
			)
			(layer "F.SilkS")
		)
		(fp_line
			(start 5.4102 -3.109976)
			(end 4.783074 -3.109976)
			(stroke
				(width 0.1524)
				(type default)
			)
			(layer "F.SilkS")
		)
		(fp_line
			(start 5.313426 -3.109976)
			(end 5.313426 3.109976)
			(stroke
				(width 0.1524)
				(type default)
			)
			(layer "F.SilkS")
		)
		(fp_line
			(start 5.262626 -3.109976)
			(end 5.262626 3.109976)
			(stroke
				(width 0.1524)
				(type default)
			)
			(layer "F.SilkS")
		)
		(fp_line
			(start 5.211826 -3.109976)
			(end 5.211826 3.109976)
			(stroke
				(width 0.1524)
				(type default)
			)
			(layer "F.SilkS")
		)
		(fp_line
			(start 5.110226 -3.109976)
			(end 5.110226 3.109976)
			(stroke
				(width 0.1524)
				(type default)
			)
			(layer "F.SilkS")
		)
		(fp_line
			(start 5.008626 -3.109976)
			(end 5.008626 3.109976)
			(stroke
				(width 0.1524)
				(type default)
			)
			(layer "F.SilkS")
		)
		(fp_line
			(start 4.932426 -3.109976)
			(end 4.932426 3.109976)
			(stroke
				(width 0.1524)
				(type default)
			)
			(layer "F.SilkS")
		)
		(fp_line
			(start 4.805426 -3.109976)
			(end 4.805426 3.109976)
			(stroke
				(width 0.1524)
				(type default)
			)
			(layer "F.SilkS")
		)
		(fp_line
			(start 4.794504 3.109976)
			(end 3.554984 3.109976)
			(stroke
				(width 0.1524)
				(type default)
			)
			(layer "F.SilkS")
		)
		(fp_line
			(start 4.769104 3.109976)
			(end -4.664456 3.109976)
			(stroke
				(width 0.1524)
				(type default)
			)
			(layer "F.SilkS")
		)
		(fp_line
			(start 4.743704 3.109976)
			(end 5.4102 3.109976)
			(stroke
				(width 0.1524)
				(type default)
			)
			(layer "F.SilkS")
		)
		(fp_line
			(start 4.743704 3.109976)
			(end 4.6101 3.109976)
			(stroke
				(width 0.1524)
				(type default)
			)
			(layer "F.SilkS")
		)
		(fp_line
			(start 4.715002 3.035554)
			(end 4.7117 2.984754)
			(stroke
				(width 0.1524)
				(type default)
			)
			(layer "F.SilkS")
		)
		(fp_line
			(start 4.70535 -3.109976)
			(end 4.70535 3.109976)
			(stroke
				(width 0.1524)
				(type default)
			)
			(layer "F.SilkS")
		)
		(fp_line
			(start 4.70535 -3.109976)
			(end 4.70535 3.109976)
			(stroke
				(width 0.1524)
				(type default)
			)
			(layer "F.SilkS")
		)
		(fp_line
			(start 4.70535 -3.109976)
			(end 4.70535 3.109976)
			(stroke
				(width 0.1524)
				(type default)
			)
			(layer "F.SilkS")
		)
		(fp_line
			(start 4.695444 -3.109976)
			(end 4.695444 3.109976)
			(stroke
				(width 0.1524)
				(type default)
			)
			(layer "F.SilkS")
		)
		(fp_line
			(start 4.6101 -3.109976)
			(end 4.283202 -3.109976)
			(stroke
				(width 0.1524)
				(type default)
			)
			(layer "F.SilkS")
		)
		(fp_line
			(start 4.511802 -3.109976)
			(end 4.207002 -3.109976)
			(stroke
				(width 0.1524)
				(type default)
			)
			(layer "F.SilkS")
		)
		(fp_line
			(start 4.183126 -3.109976)
			(end 4.794504 -3.109976)
			(stroke
				(width 0.1524)
				(type default)
			)
			(layer "F.SilkS")
		)
		(fp_line
			(start 4.156202 3.109976)
			(end 4.183126 3.109976)
			(stroke
				(width 0.1524)
				(type default)
			)
			(layer "F.SilkS")
		)
		(fp_line
			(start 0.762 1.27)
			(end 0.762 -1.27)
			(stroke
				(width 0.1524)
				(type default)
			)
			(layer "F.SilkS")
		)
		(fp_line
			(start 0.762 0)
			(end 1.2192 0)
			(stroke
				(width 0.1524)
				(type default)
			)
			(layer "F.SilkS")
		)
		(fp_line
			(start 0.762 0)
			(end -0.508 1.016)
			(stroke
				(width 0.1524)
				(type default)
			)
			(layer "F.SilkS")
		)
		(fp_line
			(start -0.508 1.016)
			(end -0.508 -1.016)
			(stroke
				(width 0.1524)
				(type default)
			)
			(layer "F.SilkS")
		)
		(fp_line
			(start -0.508 -1.016)
			(end 0.762 0)
			(stroke
				(width 0.1524)
				(type default)
			)
			(layer "F.SilkS")
		)
		(fp_line
			(start -1.0668 0)
			(end -0.6096 0)
			(stroke
				(width 0.1524)
				(type default)
			)
			(layer "F.SilkS")
		)
		(fp_line
			(start -4.664456 3.109976)
			(end -4.664456 -3.109976)
			(stroke
				(width 0.1524)
				(type default)
			)
			(layer "F.SilkS")
		)
		(fp_line
			(start -4.664456 -3.109976)
			(end 4.743704 -3.109976)
			(stroke
				(width 0.1524)
				(type default)
			)
			(layer "F.SilkS")
		)
		(fp_line
			(start 4.065016 3.109976)
			(end -4.065016 3.109976)
			(stroke
				(width 0.1)
				(type default)
			)
			(layer "F.Fab")
		)
		(fp_line
			(start 4.065016 -3.109976)
			(end 4.065016 3.109976)
			(stroke
				(width 0.1)
				(type default)
			)
			(layer "F.Fab")
		)
		(fp_line
			(start -4.065016 3.109976)
			(end -4.065016 -3.109976)
			(stroke
				(width 0.1)
				(type default)
			)
			(layer "F.Fab")
		)
		(fp_line
			(start -4.065016 -3.109976)
			(end 4.065016 -3.109976)
			(stroke
				(width 0.1)
				(type default)
			)
			(layer "F.Fab")
		)
		(fp_text user "-"
			(at 6.084316 -3.33248 0)
			(unlocked yes)
			(layer "F.SilkS")
			(effects
				(font
					(size 1.905 1.4224)
					(thickness 0.1524)
				)
				(justify left)
			)
		)
		(fp_text user "+"
			(at -1.90246 -3.616706 0)
			(unlocked yes)
			(layer "F.SilkS")
			(effects
				(font
					(size 1.905 1.4224)
					(thickness 0.1524)
				)
				(justify left)
			)
		)
		(fp_text user "-"
			(at 6.643624 0.40005 0)
			(unlocked yes)
			(layer "F.Fab")
			(effects
				(font
					(size 1.905 1.4224)
					(thickness 0.1524)
				)
				(justify left)
			)
		)
		(fp_text user "+"
			(at -4.5974 0.24765 0)
			(unlocked yes)
			(layer "F.Fab")
			(effects
				(font
					(size 1.905 1.4224)
					(thickness 0.1524)
				)
				(justify left)
			)
		)
		(pad "A" smd rect
			(at -3.299968 0)
			(size 2.413 3.302)
			(layers "F.Cu" "F.Mask" "F.Paste")
			(net "GND")
		)
		(pad "C" smd rect
			(at 3.299968 0)
			(size 2.413 3.302)
			(layers "F.Cu" "F.Mask" "F.Paste")
			(net "P12V_STBY_FUSE")
		)
	)
	(footprint ""
		(layer "F.Cu")
		(at 213.70671 -225.42246 180)
		(property "Reference" "R1488"
			(at 0 0 180)
			(layer "F.SilkS")
			(hide yes)
			(effects
				(font
					(size 1.27 1.27)
				)
			)
		)
		(property "Value" ""
			(at 0 0 180)
			(layer "F.Fab")
			(effects
				(font
					(size 1.27 1.27)
				)
			)
		)
		(duplicate_pad_numbers_are_jumpers no)
		(fp_line
			(start 0.7874 0.4064)
			(end -0.7874 0.4064)
			(stroke
				(width 0.1524)
				(type default)
			)
			(layer "F.SilkS")
		)
		(fp_line
			(start 0.7874 -0.4064)
			(end 0.7874 0.4064)
			(stroke
				(width 0.1524)
				(type default)
			)
			(layer "F.SilkS")
		)
		(fp_line
			(start -0.7874 0.4064)
			(end -0.7874 -0.4064)
			(stroke
				(width 0.1524)
				(type default)
			)
			(layer "F.SilkS")
		)
		(fp_line
			(start -0.7874 -0.4064)
			(end 0.7874 -0.4064)
			(stroke
				(width 0.1524)
				(type default)
			)
			(layer "F.SilkS")
		)
		(fp_line
			(start 0.67945 0.3048)
			(end 0.120396 0.3048)
			(stroke
				(width 0.1)
				(type default)
			)
			(layer "F.Fab")
		)
		(fp_line
			(start 0.67945 -0.3048)
			(end 0.67945 0.3048)
			(stroke
				(width 0.1)
				(type default)
			)
			(layer "F.Fab")
		)
		(fp_line
			(start 0.12065 -0.2794)
			(end 0.12065 -0.3048)
			(stroke
				(width 0.1)
				(type default)
			)
			(layer "F.Fab")
		)
		(fp_line
			(start 0.12065 -0.3048)
			(end 0.67945 -0.3048)
			(stroke
				(width 0.1)
				(type default)
			)
			(layer "F.Fab")
		)
		(fp_line
			(start 0.120396 0.3048)
			(end 0.120396 0.2794)
			(stroke
				(width 0.1)
				(type default)
			)
			(layer "F.Fab")
		)
		(fp_line
			(start 0.120396 0.2794)
			(end -0.12065 0.2794)
			(stroke
				(width 0.1)
				(type default)
			)
			(layer "F.Fab")
		)
		(fp_line
			(start -0.12065 0.3048)
			(end -0.67945 0.3048)
			(stroke
				(width 0.1)
				(type default)
			)
			(layer "F.Fab")
		)
		(fp_line
			(start -0.12065 0.2794)
			(end -0.12065 0.3048)
			(stroke
				(width 0.1)
				(type default)
			)
			(layer "F.Fab")
		)
		(fp_line
			(start -0.12065 -0.2794)
			(end 0.12065 -0.2794)
			(stroke
				(width 0.1)
				(type default)
			)
			(layer "F.Fab")
		)
		(fp_line
			(start -0.12065 -0.305054)
			(end -0.12065 -0.2794)
			(stroke
				(width 0.1)
				(type default)
			)
			(layer "F.Fab")
		)
		(fp_line
			(start -0.67945 0.3048)
			(end -0.67945 -0.305054)
			(stroke
				(width 0.1)
				(type default)
			)
			(layer "F.Fab")
		)
		(fp_line
			(start -0.67945 -0.305054)
			(end -0.12065 -0.305054)
			(stroke
				(width 0.1)
				(type default)
			)
			(layer "F.Fab")
		)
		(pad "1" smd circle
			(at -0.40005 0 180)
			(size 0 0)
			(layers "F.Cu" "F.Mask" "F.Paste")
			(net "SMB_NIC3_SDA")
		)
		(pad "2" smd circle
			(at 0.40005 0 180)
			(size 0 0)
			(layers "F.Cu" "F.Mask" "F.Paste")
			(net "SMB_NIC3_R_SDA")
		)
	)
	(footprint ""
		(layer "F.Cu")
		(at 9.446768 -154.256994)
		(property "Reference" "PC610"
			(at 0 0 0)
			(layer "F.SilkS")
			(hide yes)
			(effects
				(font
					(size 1.27 1.27)
				)
			)
		)
		(property "Value" ""
			(at 0 0 0)
			(layer "F.Fab")
			(effects
				(font
					(size 1.27 1.27)
				)
			)
		)
		(duplicate_pad_numbers_are_jumpers no)
		(fp_line
			(start -1.2954 -0.5842)
			(end 1.2954 -0.5842)
			(stroke
				(width 0.1524)
				(type default)
			)
			(layer "F.SilkS")
		)
		(fp_line
			(start -1.2954 0.5842)
			(end -1.2954 -0.5842)
			(stroke
				(width 0.1524)
				(type default)
			)
			(layer "F.SilkS")
		)
		(fp_line
			(start 1.2954 -0.5842)
			(end 1.2954 0.5842)
			(stroke
				(width 0.1524)
				(type default)
			)
			(layer "F.SilkS")
		)
		(fp_line
			(start 1.2954 0.5842)
			(end -1.2954 0.5842)
			(stroke
				(width 0.1524)
				(type default)
			)
			(layer "F.SilkS")
		)
		(fp_line
			(start -1.1938 -0.4064)
			(end -0.8636 -0.4064)
			(stroke
				(width 0.1)
				(type default)
			)
			(layer "F.Fab")
		)
		(fp_line
			(start -1.1938 0.4064)
			(end -1.1938 -0.4064)
			(stroke
				(width 0.1)
				(type default)
			)
			(layer "F.Fab")
		)
		(fp_line
			(start -0.8636 -0.4572)
			(end 0.8636 -0.4572)
			(stroke
				(width 0.1)
				(type default)
			)
			(layer "F.Fab")
		)
		(fp_line
			(start -0.8636 -0.4064)
			(end -0.8636 -0.4572)
			(stroke
				(width 0.1)
				(type default)
			)
			(layer "F.Fab")
		)
		(fp_line
			(start -0.8636 0.4064)
			(end -1.1938 0.4064)
			(stroke
				(width 0.1)
				(type default)
			)
			(layer "F.Fab")
		)
		(fp_line
			(start -0.8636 0.4572)
			(end -0.8636 0.4064)
			(stroke
				(width 0.1)
				(type default)
			)
			(layer "F.Fab")
		)
		(fp_line
			(start 0.8636 -0.4572)
			(end 0.8636 -0.4064)
			(stroke
				(width 0.1)
				(type default)
			)
			(layer "F.Fab")
		)
		(fp_line
			(start 0.8636 -0.4064)
			(end 1.1938 -0.4064)
			(stroke
				(width 0.1)
				(type default)
			)
			(layer "F.Fab")
		)
		(fp_line
			(start 0.8636 0.4064)
			(end 0.8636 0.4572)
			(stroke
				(width 0.1)
				(type default)
			)
			(layer "F.Fab")
		)
		(fp_line
			(start 0.8636 0.4572)
			(end -0.8636 0.4572)
			(stroke
				(width 0.1)
				(type default)
			)
			(layer "F.Fab")
		)
		(fp_line
			(start 1.1938 -0.4064)
			(end 1.1938 0.4064)
			(stroke
				(width 0.1)
				(type default)
			)
			(layer "F.Fab")
		)
		(fp_line
			(start 1.1938 0.4064)
			(end 0.8636 0.4064)
			(stroke
				(width 0.1)
				(type default)
			)
			(layer "F.Fab")
		)
		(pad "1" smd rect
			(at -0.7366 0 270)
			(size 0.7112 0.8128)
			(layers "F.Cu" "F.Mask" "F.Paste")
			(net "GND")
		)
		(pad "2" smd rect
			(at 0.7366 0 270)
			(size 0.7112 0.8128)
			(layers "F.Cu" "F.Mask" "F.Paste")
			(net "P12V_NIC0_CO_AVIN_PD")
		)
	)
	(footprint ""
		(layer "F.Cu")
		(at 3.50012 -311.410096)
		(property "Reference" "H133"
			(at -1.870202 -4.598924 0)
			(unlocked yes)
			(layer "F.SilkS")
			(effects
				(font
					(size 0.7874 0.5842)
					(thickness 0.1524)
				)
				(justify left)
			)
		)
		(property "Value" ""
			(at 0 0 0)
			(layer "F.Fab")
			(effects
				(font
					(size 1.27 1.27)
				)
			)
		)
		(duplicate_pad_numbers_are_jumpers no)
		(pad "1" thru_hole circle
			(at 0 0)
			(size 6.5024 6.5024)
			(drill 3.2004)
			(layers "*.Cu" "*.Mask")
			(remove_unused_layers no)
			(net "GND")
			(clearance -1.397)
		)
	)
	(footprint ""
		(layer "F.Cu")
		(at 133.93039 -184.656984 -90)
		(property "Reference" "R1113"
			(at 0 0 270)
			(layer "F.SilkS")
			(hide yes)
			(effects
				(font
					(size 1.27 1.27)
				)
			)
		)
		(property "Value" ""
			(at 0 0 270)
			(layer "F.Fab")
			(effects
				(font
					(size 1.27 1.27)
				)
			)
		)
		(duplicate_pad_numbers_are_jumpers no)
		(fp_line
			(start 0.7874 0.4064)
			(end -0.7874 0.4064)
			(stroke
				(width 0.1524)
				(type default)
			)
			(layer "F.SilkS")
		)
		(fp_line
			(start -0.67945 0.3048)
			(end -0.67945 -0.305054)
			(stroke
				(width 0.1)
				(type default)
			)
			(layer "F.Fab")
		)
		(fp_line
			(start -0.12065 0.3048)
			(end -0.67945 0.3048)
			(stroke
				(width 0.1)
				(type default)
			)
			(layer "F.Fab")
		)
		(fp_line
			(start 0.120396 0.3048)
			(end 0.120396 0.2794)
			(stroke
				(width 0.1)
				(type default)
			)
			(layer "F.Fab")
		)
		(fp_line
			(start 0.67945 0.3048)
			(end 0.120396 0.3048)
			(stroke
				(width 0.1)
				(type default)
			)
			(layer "F.Fab")
		)
		(fp_line
			(start -0.12065 0.2794)
			(end -0.12065 0.3048)
			(stroke
				(width 0.1)
				(type default)
			)
			(layer "F.Fab")
		)
		(fp_line
			(start 0.120396 0.2794)
			(end -0.12065 0.2794)
			(stroke
				(width 0.1)
				(type default)
			)
			(layer "F.Fab")
		)
		(fp_line
			(start -0.12065 -0.2794)
			(end 0.12065 -0.2794)
			(stroke
				(width 0.1)
				(type default)
			)
			(layer "F.Fab")
		)
		(fp_line
			(start 0.12065 -0.2794)
			(end 0.12065 -0.3048)
			(stroke
				(width 0.1)
				(type default)
			)
			(layer "F.Fab")
		)
		(fp_line
			(start 0.12065 -0.3048)
			(end 0.67945 -0.3048)
			(stroke
				(width 0.1)
				(type default)
			)
			(layer "F.Fab")
		)
		(fp_line
			(start 0.67945 -0.3048)
			(end 0.67945 0.3048)
			(stroke
				(width 0.1)
				(type default)
			)
			(layer "F.Fab")
		)
		(fp_line
			(start -0.67945 -0.305054)
			(end -0.12065 -0.305054)
			(stroke
				(width 0.1)
				(type default)
			)
			(layer "F.Fab")
		)
		(fp_line
			(start -0.12065 -0.305054)
			(end -0.12065 -0.2794)
			(stroke
				(width 0.1)
				(type default)
			)
			(layer "F.Fab")
		)
		(pad "1" smd circle
			(at -0.40005 0 270)
			(size 0 0)
			(layers "F.Cu" "F.Mask" "F.Paste")
			(net "CLK_100M_DB2000QL_GPU_REF0_R_DN")
		)
		(pad "2" smd circle
			(at 0.40005 0 270)
			(size 0 0)
			(layers "F.Cu" "F.Mask" "F.Paste")
			(net "CLK_100M_DB2000QL_GPU_REF0_DN")
		)
	)
	(footprint ""
		(layer "F.Cu")
		(at 250.147074 -55.63489 90)
		(property "Reference" "PC861"
			(at 0 0 90)
			(layer "F.SilkS")
			(hide yes)
			(effects
				(font
					(size 1.27 1.27)
				)
			)
		)
		(property "Value" ""
			(at 0 0 90)
			(layer "F.Fab")
			(effects
				(font
					(size 1.27 1.27)
				)
			)
		)
		(duplicate_pad_numbers_are_jumpers no)
		(fp_line
			(start 1.524 -0.762)
			(end 1.524 0.762)
			(stroke
				(width 0.1524)
				(type default)
			)
			(layer "F.SilkS")
		)
		(fp_line
			(start -1.524 -0.762)
			(end 1.524 -0.762)
			(stroke
				(width 0.1524)
				(type default)
			)
			(layer "F.SilkS")
		)
		(fp_line
			(start 1.524 0.762)
			(end -1.524 0.762)
			(stroke
				(width 0.1524)
				(type default)
			)
			(layer "F.SilkS")
		)
		(fp_line
			(start -1.524 0.762)
			(end -1.524 -0.762)
			(stroke
				(width 0.1524)
				(type default)
			)
			(layer "F.SilkS")
		)
		(fp_line
			(start 1.1049 -0.724916)
			(end -1.1049 -0.724916)
			(stroke
				(width 0.1)
				(type default)
			)
			(layer "F.Fab")
		)
		(fp_line
			(start -1.1049 -0.724916)
			(end -1.1049 0.724916)
			(stroke
				(width 0.1)
				(type default)
			)
			(layer "F.Fab")
		)
		(fp_line
			(start 1.1049 0.724916)
			(end 1.1049 -0.724916)
			(stroke
				(width 0.1)
				(type default)
			)
			(layer "F.Fab")
		)
		(fp_line
			(start -1.1049 0.724916)
			(end 1.1049 0.724916)
			(stroke
				(width 0.1)
				(type default)
			)
			(layer "F.Fab")
		)
		(pad "1" smd rect
			(at -0.889 0 270)
			(size 1.016 1.27)
			(layers "F.Cu" "F.Mask" "F.Paste")
			(net "P12V_SSD8_R")
		)
		(pad "2" smd rect
			(at 0.889 0 270)
			(size 1.016 1.27)
			(layers "F.Cu" "F.Mask" "F.Paste")
			(net "GND")
		)
	)
	(footprint ""
		(layer "F.Cu")
		(at 154.699716 -152.295352 180)
		(property "Reference" "R119"
			(at 0 0 180)
			(layer "F.SilkS")
			(hide yes)
			(effects
				(font
					(size 1.27 1.27)
				)
			)
		)
		(property "Value" ""
			(at 0 0 180)
			(layer "F.Fab")
			(effects
				(font
					(size 1.27 1.27)
				)
			)
		)
		(duplicate_pad_numbers_are_jumpers no)
		(fp_line
			(start 0.7874 0.4064)
			(end -0.7874 0.4064)
			(stroke
				(width 0.1524)
				(type default)
			)
			(layer "F.SilkS")
		)
		(fp_line
			(start 0.7874 -0.4064)
			(end 0.7874 0.4064)
			(stroke
				(width 0.1524)
				(type default)
			)
			(layer "F.SilkS")
		)
		(fp_line
			(start -0.7874 0.4064)
			(end -0.7874 -0.4064)
			(stroke
				(width 0.1524)
				(type default)
			)
			(layer "F.SilkS")
		)
		(fp_line
			(start -0.7874 -0.4064)
			(end 0.7874 -0.4064)
			(stroke
				(width 0.1524)
				(type default)
			)
			(layer "F.SilkS")
		)
		(fp_line
			(start 0.67945 0.3048)
			(end 0.120396 0.3048)
			(stroke
				(width 0.1)
				(type default)
			)
			(layer "F.Fab")
		)
		(fp_line
			(start 0.67945 -0.3048)
			(end 0.67945 0.3048)
			(stroke
				(width 0.1)
				(type default)
			)
			(layer "F.Fab")
		)
		(fp_line
			(start 0.12065 -0.2794)
			(end 0.12065 -0.3048)
			(stroke
				(width 0.1)
				(type default)
			)
			(layer "F.Fab")
		)
		(fp_line
			(start 0.12065 -0.3048)
			(end 0.67945 -0.3048)
			(stroke
				(width 0.1)
				(type default)
			)
			(layer "F.Fab")
		)
		(fp_line
			(start 0.120396 0.3048)
			(end 0.120396 0.2794)
			(stroke
				(width 0.1)
				(type default)
			)
			(layer "F.Fab")
		)
		(fp_line
			(start 0.120396 0.2794)
			(end -0.12065 0.2794)
			(stroke
				(width 0.1)
				(type default)
			)
			(layer "F.Fab")
		)
		(fp_line
			(start -0.12065 0.3048)
			(end -0.67945 0.3048)
			(stroke
				(width 0.1)
				(type default)
			)
			(layer "F.Fab")
		)
		(fp_line
			(start -0.12065 0.2794)
			(end -0.12065 0.3048)
			(stroke
				(width 0.1)
				(type default)
			)
			(layer "F.Fab")
		)
		(fp_line
			(start -0.12065 -0.2794)
			(end 0.12065 -0.2794)
			(stroke
				(width 0.1)
				(type default)
			)
			(layer "F.Fab")
		)
		(fp_line
			(start -0.12065 -0.305054)
			(end -0.12065 -0.2794)
			(stroke
				(width 0.1)
				(type default)
			)
			(layer "F.Fab")
		)
		(fp_line
			(start -0.67945 0.3048)
			(end -0.67945 -0.305054)
			(stroke
				(width 0.1)
				(type default)
			)
			(layer "F.Fab")
		)
		(fp_line
			(start -0.67945 -0.305054)
			(end -0.12065 -0.305054)
			(stroke
				(width 0.1)
				(type default)
			)
			(layer "F.Fab")
		)
		(pad "1" smd circle
			(at -0.40005 0 180)
			(size 0 0)
			(layers "F.Cu" "F.Mask" "F.Paste")
			(net "NCSI_NIC2_RXD1")
		)
		(pad "2" smd circle
			(at 0.40005 0 180)
			(size 0 0)
			(layers "F.Cu" "F.Mask" "F.Paste")
			(net "GND")
		)
	)
	(footprint ""
		(layer "F.Cu")
		(at 194.164712 -343.952322 90)
		(property "Reference" "C373"
			(at 0 0 90)
			(layer "F.SilkS")
			(hide yes)
			(effects
				(font
					(size 1.27 1.27)
				)
			)
		)
		(property "Value" ""
			(at 0 0 90)
			(layer "F.Fab")
			(effects
				(font
					(size 1.27 1.27)
				)
			)
		)
		(duplicate_pad_numbers_are_jumpers no)
		(fp_line
			(start 0.299974 -0.150114)
			(end 0.299974 0.150114)
			(stroke
				(width 0.1)
				(type default)
			)
			(layer "F.Fab")
		)
		(fp_line
			(start -0.299974 -0.150114)
			(end 0.299974 -0.150114)
			(stroke
				(width 0.1)
				(type default)
			)
			(layer "F.Fab")
		)
		(fp_line
			(start 0.299974 0.150114)
			(end -0.299974 0.150114)
			(stroke
				(width 0.1)
				(type default)
			)
			(layer "F.Fab")
		)
		(fp_line
			(start -0.299974 0.150114)
			(end -0.299974 -0.150114)
			(stroke
				(width 0.1)
				(type default)
			)
			(layer "F.Fab")
		)
		(pad "1" smd rect
			(at -0.2667 0 90)
			(size 0.3048 0.381)
			(layers "F.Cu" "F.Mask" "F.Paste")
			(net "P5E_PEX1_STN7_TX_DN<127>")
		)
		(pad "2" smd rect
			(at 0.2667 0 90)
			(size 0.3048 0.381)
			(layers "F.Cu" "F.Mask" "F.Paste")
			(net "P5E_PEX1_STN7_TX_C_DN<127>")
		)
	)
	(footprint ""
		(layer "F.Cu")
		(at 217.235786 -213.222586 180)
		(property "Reference" "R5773"
			(at 0 0 180)
			(layer "F.SilkS")
			(hide yes)
			(effects
				(font
					(size 1.27 1.27)
				)
			)
		)
		(property "Value" ""
			(at 0 0 180)
			(layer "F.Fab")
			(effects
				(font
					(size 1.27 1.27)
				)
			)
		)
		(duplicate_pad_numbers_are_jumpers no)
		(fp_line
			(start 0.7874 0.4064)
			(end -0.7874 0.4064)
			(stroke
				(width 0.1524)
				(type default)
			)
			(layer "F.SilkS")
		)
		(fp_line
			(start 0.7874 -0.4064)
			(end 0.7874 0.4064)
			(stroke
				(width 0.1524)
				(type default)
			)
			(layer "F.SilkS")
		)
		(fp_line
			(start -0.7874 0.4064)
			(end -0.7874 -0.4064)
			(stroke
				(width 0.1524)
				(type default)
			)
			(layer "F.SilkS")
		)
		(fp_line
			(start -0.7874 -0.4064)
			(end 0.7874 -0.4064)
			(stroke
				(width 0.1524)
				(type default)
			)
			(layer "F.SilkS")
		)
		(fp_line
			(start 0.67945 0.3048)
			(end 0.120396 0.3048)
			(stroke
				(width 0.1)
				(type default)
			)
			(layer "F.Fab")
		)
		(fp_line
			(start 0.67945 -0.3048)
			(end 0.67945 0.3048)
			(stroke
				(width 0.1)
				(type default)
			)
			(layer "F.Fab")
		)
		(fp_line
			(start 0.12065 -0.2794)
			(end 0.12065 -0.3048)
			(stroke
				(width 0.1)
				(type default)
			)
			(layer "F.Fab")
		)
		(fp_line
			(start 0.12065 -0.3048)
			(end 0.67945 -0.3048)
			(stroke
				(width 0.1)
				(type default)
			)
			(layer "F.Fab")
		)
		(fp_line
			(start 0.120396 0.3048)
			(end 0.120396 0.2794)
			(stroke
				(width 0.1)
				(type default)
			)
			(layer "F.Fab")
		)
		(fp_line
			(start 0.120396 0.2794)
			(end -0.12065 0.2794)
			(stroke
				(width 0.1)
				(type default)
			)
			(layer "F.Fab")
		)
		(fp_line
			(start -0.12065 0.3048)
			(end -0.67945 0.3048)
			(stroke
				(width 0.1)
				(type default)
			)
			(layer "F.Fab")
		)
		(fp_line
			(start -0.12065 0.2794)
			(end -0.12065 0.3048)
			(stroke
				(width 0.1)
				(type default)
			)
			(layer "F.Fab")
		)
		(fp_line
			(start -0.12065 -0.2794)
			(end 0.12065 -0.2794)
			(stroke
				(width 0.1)
				(type default)
			)
			(layer "F.Fab")
		)
		(fp_line
			(start -0.12065 -0.305054)
			(end -0.12065 -0.2794)
			(stroke
				(width 0.1)
				(type default)
			)
			(layer "F.Fab")
		)
		(fp_line
			(start -0.67945 0.3048)
			(end -0.67945 -0.305054)
			(stroke
				(width 0.1)
				(type default)
			)
			(layer "F.Fab")
		)
		(fp_line
			(start -0.67945 -0.305054)
			(end -0.12065 -0.305054)
			(stroke
				(width 0.1)
				(type default)
			)
			(layer "F.Fab")
		)
		(pad "1" smd circle
			(at -0.40005 0 180)
			(size 0 0)
			(layers "F.Cu" "F.Mask" "F.Paste")
			(net "SMB_ALERT_PMBUS_R_N")
		)
		(pad "2" smd circle
			(at 0.40005 0 180)
			(size 0 0)
			(layers "F.Cu" "F.Mask" "F.Paste")
			(net "P0V8_PEX2_SMBALERT")
		)
	)
	(footprint ""
		(layer "F.Cu")
		(at 145.988278 -257.64871 -90)
		(property "Reference" "C3227"
			(at 0 0 270)
			(layer "F.SilkS")
			(hide yes)
			(effects
				(font
					(size 1.27 1.27)
				)
			)
		)
		(property "Value" ""
			(at 0 0 270)
			(layer "F.Fab")
			(effects
				(font
					(size 1.27 1.27)
				)
			)
		)
		(duplicate_pad_numbers_are_jumpers no)
		(fp_line
			(start -1.2954 0.5842)
			(end -1.2954 -0.5842)
			(stroke
				(width 0.1524)
				(type default)
			)
			(layer "F.SilkS")
		)
		(fp_line
			(start 1.2954 0.5842)
			(end -1.2954 0.5842)
			(stroke
				(width 0.1524)
				(type default)
			)
			(layer "F.SilkS")
		)
		(fp_line
			(start -1.2954 -0.5842)
			(end 1.2954 -0.5842)
			(stroke
				(width 0.1524)
				(type default)
			)
			(layer "F.SilkS")
		)
		(fp_line
			(start 1.2954 -0.5842)
			(end 1.2954 0.5842)
			(stroke
				(width 0.1524)
				(type default)
			)
			(layer "F.SilkS")
		)
		(fp_line
			(start -0.8636 0.4572)
			(end -0.8636 0.4064)
			(stroke
				(width 0.1)
				(type default)
			)
			(layer "F.Fab")
		)
		(fp_line
			(start 0.8636 0.4572)
			(end -0.8636 0.4572)
			(stroke
				(width 0.1)
				(type default)
			)
			(layer "F.Fab")
		)
		(fp_line
			(start -1.1938 0.4064)
			(end -1.1938 -0.4064)
			(stroke
				(width 0.1)
				(type default)
			)
			(layer "F.Fab")
		)
		(fp_line
			(start -0.8636 0.4064)
			(end -1.1938 0.4064)
			(stroke
				(width 0.1)
				(type default)
			)
			(layer "F.Fab")
		)
		(fp_line
			(start 0.8636 0.4064)
			(end 0.8636 0.4572)
			(stroke
				(width 0.1)
				(type default)
			)
			(layer "F.Fab")
		)
		(fp_line
			(start 1.1938 0.4064)
			(end 0.8636 0.4064)
			(stroke
				(width 0.1)
				(type default)
			)
			(layer "F.Fab")
		)
		(fp_line
			(start -1.1938 -0.4064)
			(end -0.8636 -0.4064)
			(stroke
				(width 0.1)
				(type default)
			)
			(layer "F.Fab")
		)
		(fp_line
			(start -0.8636 -0.4064)
			(end -0.8636 -0.4572)
			(stroke
				(width 0.1)
				(type default)
			)
			(layer "F.Fab")
		)
		(fp_line
			(start 0.8636 -0.4064)
			(end 1.1938 -0.4064)
			(stroke
				(width 0.1)
				(type default)
			)
			(layer "F.Fab")
		)
		(fp_line
			(start 1.1938 -0.4064)
			(end 1.1938 0.4064)
			(stroke
				(width 0.1)
				(type default)
			)
			(layer "F.Fab")
		)
		(fp_line
			(start -0.8636 -0.4572)
			(end 0.8636 -0.4572)
			(stroke
				(width 0.1)
				(type default)
			)
			(layer "F.Fab")
		)
		(fp_line
			(start 0.8636 -0.4572)
			(end 0.8636 -0.4064)
			(stroke
				(width 0.1)
				(type default)
			)
			(layer "F.Fab")
		)
		(pad "1" smd rect
			(at -0.7366 0 180)
			(size 0.7112 0.8128)
			(layers "F.Cu" "F.Mask" "F.Paste")
			(net "P1V8_PLL0_PEX1")
		)
		(pad "2" smd rect
			(at 0.7366 0 180)
			(size 0.7112 0.8128)
			(layers "F.Cu" "F.Mask" "F.Paste")
			(net "GND")
		)
	)
	(footprint ""
		(layer "F.Cu")
		(at 198.76135 -145.311114 180)
		(property "Reference" "C224"
			(at 0 0 180)
			(layer "F.SilkS")
			(hide yes)
			(effects
				(font
					(size 1.27 1.27)
				)
			)
		)
		(property "Value" ""
			(at 0 0 180)
			(layer "F.Fab")
			(effects
				(font
					(size 1.27 1.27)
				)
			)
		)
		(duplicate_pad_numbers_are_jumpers no)
		(fp_line
			(start 0.299974 0.150114)
			(end -0.299974 0.150114)
			(stroke
				(width 0.1)
				(type default)
			)
			(layer "F.Fab")
		)
		(fp_line
			(start 0.299974 -0.150114)
			(end 0.299974 0.150114)
			(stroke
				(width 0.1)
				(type default)
			)
			(layer "F.Fab")
		)
		(fp_line
			(start -0.299974 0.150114)
			(end -0.299974 -0.150114)
			(stroke
				(width 0.1)
				(type default)
			)
			(layer "F.Fab")
		)
		(fp_line
			(start -0.299974 -0.150114)
			(end 0.299974 -0.150114)
			(stroke
				(width 0.1)
				(type default)
			)
			(layer "F.Fab")
		)
		(pad "1" smd rect
			(at -0.2667 0 180)
			(size 0.3048 0.381)
			(layers "F.Cu" "F.Mask" "F.Paste")
			(net "P5E_PEX1_STN0_TX_DP<9>")
		)
		(pad "2" smd rect
			(at 0.2667 0 180)
			(size 0.3048 0.381)
			(layers "F.Cu" "F.Mask" "F.Paste")
			(net "P5E_PEX1_STN0_TX_C_DP<9>")
		)
	)
	(footprint ""
		(layer "F.Cu")
		(at 446.959482 -61.612526)
		(property "Reference" "PD40"
			(at -3.7084 -2.733548 0)
			(unlocked yes)
			(layer "F.SilkS")
			(effects
				(font
					(size 0.7874 0.5842)
					(thickness 0.1524)
				)
				(justify left)
			)
		)
		(property "Value" ""
			(at 0 0 0)
			(layer "F.Fab")
			(effects
				(font
					(size 1.27 1.27)
				)
			)
		)
		(duplicate_pad_numbers_are_jumpers no)
		(fp_line
			(start -3.656584 -1.970024)
			(end -3.656584 1.970024)
			(stroke
				(width 0.1524)
				(type default)
			)
			(layer "F.SilkS")
		)
		(fp_line
			(start -3.656584 1.970024)
			(end 4.240784 1.970024)
			(stroke
				(width 0.1524)
				(type default)
			)
			(layer "F.SilkS")
		)
		(fp_line
			(start 4.240784 -1.970024)
			(end -3.656584 -1.970024)
			(stroke
				(width 0.1524)
				(type default)
			)
			(layer "F.SilkS")
		)
		(fp_line
			(start 4.240784 1.970024)
			(end 4.240784 -1.970024)
			(stroke
				(width 0.1524)
				(type default)
			)
			(layer "F.SilkS")
		)
		(fp_poly
			(pts
				(xy 3.580384 1.970024) (xy 3.580384 -1.970024) (xy 4.240784 -1.970024) (xy 4.240784 1.970024)
			)
			(stroke
				(width 0)
				(type default)
			)
			(fill yes)
			(layer "F.SilkS")
		)
		(fp_line
			(start -2.3749 -1.970024)
			(end -2.3749 1.970024)
			(stroke
				(width 0.1)
				(type default)
			)
			(layer "F.Fab")
		)
		(fp_line
			(start -2.3749 1.970024)
			(end 2.3749 1.970024)
			(stroke
				(width 0.1)
				(type default)
			)
			(layer "F.Fab")
		)
		(fp_line
			(start 2.3749 -1.970024)
			(end -2.3749 -1.970024)
			(stroke
				(width 0.1)
				(type default)
			)
			(layer "F.Fab")
		)
		(fp_line
			(start 2.3749 1.970024)
			(end 2.3749 -1.970024)
			(stroke
				(width 0.1)
				(type default)
			)
			(layer "F.Fab")
		)
		(fp_text user "+"
			(at -4.9784 -0.23495 0)
			(unlocked yes)
			(layer "F.Fab")
			(effects
				(font
					(size 1.905 1.4224)
					(thickness 0.1524)
				)
				(justify left)
			)
		)
		(fp_text user "-"
			(at 4.1656 -0.23495 0)
			(unlocked yes)
			(layer "F.Fab")
			(effects
				(font
					(size 1.905 1.4224)
					(thickness 0.1524)
				)
				(justify left)
			)
		)
		(pad "A" smd rect
			(at -2.450084 0)
			(size 2.159 2.2606)
			(layers "F.Cu" "F.Mask" "F.Paste")
			(net "GND")
		)
		(pad "C" smd rect
			(at 2.450084 0)
			(size 2.159 2.2606)
			(layers "F.Cu" "F.Mask" "F.Paste")
			(net "P12V_AUX")
		)
	)
	(footprint ""
		(layer "F.Cu")
		(at 362.336334 -240.68913 180)
		(property "Reference" "R6405"
			(at 0 0 180)
			(layer "F.SilkS")
			(hide yes)
			(effects
				(font
					(size 1.27 1.27)
				)
			)
		)
		(property "Value" ""
			(at 0 0 180)
			(layer "F.Fab")
			(effects
				(font
					(size 1.27 1.27)
				)
			)
		)
		(duplicate_pad_numbers_are_jumpers no)
		(fp_line
			(start 0.7874 0.4064)
			(end -0.7874 0.4064)
			(stroke
				(width 0.1524)
				(type default)
			)
			(layer "F.SilkS")
		)
		(fp_line
			(start 0.7874 -0.4064)
			(end 0.7874 0.4064)
			(stroke
				(width 0.1524)
				(type default)
			)
			(layer "F.SilkS")
		)
		(fp_line
			(start -0.7874 0.4064)
			(end -0.7874 -0.4064)
			(stroke
				(width 0.1524)
				(type default)
			)
			(layer "F.SilkS")
		)
		(fp_line
			(start -0.7874 -0.4064)
			(end 0.7874 -0.4064)
			(stroke
				(width 0.1524)
				(type default)
			)
			(layer "F.SilkS")
		)
		(fp_line
			(start 0.67945 0.3048)
			(end 0.120396 0.3048)
			(stroke
				(width 0.1)
				(type default)
			)
			(layer "F.Fab")
		)
		(fp_line
			(start 0.67945 -0.3048)
			(end 0.67945 0.3048)
			(stroke
				(width 0.1)
				(type default)
			)
			(layer "F.Fab")
		)
		(fp_line
			(start 0.12065 -0.2794)
			(end 0.12065 -0.3048)
			(stroke
				(width 0.1)
				(type default)
			)
			(layer "F.Fab")
		)
		(fp_line
			(start 0.12065 -0.3048)
			(end 0.67945 -0.3048)
			(stroke
				(width 0.1)
				(type default)
			)
			(layer "F.Fab")
		)
		(fp_line
			(start 0.120396 0.3048)
			(end 0.120396 0.2794)
			(stroke
				(width 0.1)
				(type default)
			)
			(layer "F.Fab")
		)
		(fp_line
			(start 0.120396 0.2794)
			(end -0.12065 0.2794)
			(stroke
				(width 0.1)
				(type default)
			)
			(layer "F.Fab")
		)
		(fp_line
			(start -0.12065 0.3048)
			(end -0.67945 0.3048)
			(stroke
				(width 0.1)
				(type default)
			)
			(layer "F.Fab")
		)
		(fp_line
			(start -0.12065 0.2794)
			(end -0.12065 0.3048)
			(stroke
				(width 0.1)
				(type default)
			)
			(layer "F.Fab")
		)
		(fp_line
			(start -0.12065 -0.2794)
			(end 0.12065 -0.2794)
			(stroke
				(width 0.1)
				(type default)
			)
			(layer "F.Fab")
		)
		(fp_line
			(start -0.12065 -0.305054)
			(end -0.12065 -0.2794)
			(stroke
				(width 0.1)
				(type default)
			)
			(layer "F.Fab")
		)
		(fp_line
			(start -0.67945 0.3048)
			(end -0.67945 -0.305054)
			(stroke
				(width 0.1)
				(type default)
			)
			(layer "F.Fab")
		)
		(fp_line
			(start -0.67945 -0.305054)
			(end -0.12065 -0.305054)
			(stroke
				(width 0.1)
				(type default)
			)
			(layer "F.Fab")
		)
		(pad "1" smd circle
			(at -0.40005 0 180)
			(size 0 0)
			(layers "F.Cu" "F.Mask" "F.Paste")
			(net "PWRGD_P3V3_AUX_BUF")
		)
		(pad "2" smd circle
			(at 0.40005 0 180)
			(size 0 0)
			(layers "F.Cu" "F.Mask" "F.Paste")
			(net "PWRGD_P3V3_AUX_BUF_R")
		)
	)
	(footprint ""
		(layer "F.Cu")
		(at 387.580632 -136.729724)
		(property "Reference" "C667"
			(at 0 0 0)
			(layer "F.SilkS")
			(hide yes)
			(effects
				(font
					(size 1.27 1.27)
				)
			)
		)
		(property "Value" ""
			(at 0 0 0)
			(layer "F.Fab")
			(effects
				(font
					(size 1.27 1.27)
				)
			)
		)
		(duplicate_pad_numbers_are_jumpers no)
		(fp_line
			(start -0.299974 -0.150114)
			(end 0.299974 -0.150114)
			(stroke
				(width 0.1)
				(type default)
			)
			(layer "F.Fab")
		)
		(fp_line
			(start -0.299974 0.150114)
			(end -0.299974 -0.150114)
			(stroke
				(width 0.1)
				(type default)
			)
			(layer "F.Fab")
		)
		(fp_line
			(start 0.299974 -0.150114)
			(end 0.299974 0.150114)
			(stroke
				(width 0.1)
				(type default)
			)
			(layer "F.Fab")
		)
		(fp_line
			(start 0.299974 0.150114)
			(end -0.299974 0.150114)
			(stroke
				(width 0.1)
				(type default)
			)
			(layer "F.Fab")
		)
		(pad "1" smd rect
			(at -0.2667 0)
			(size 0.3048 0.381)
			(layers "F.Cu" "F.Mask" "F.Paste")
			(net "P5E_PEX3_STN1_TX_DP<31>")
		)
		(pad "2" smd rect
			(at 0.2667 0)
			(size 0.3048 0.381)
			(layers "F.Cu" "F.Mask" "F.Paste")
			(net "P5E_PEX3_STN1_TX_C_DP<31>")
		)
	)
	(footprint ""
		(layer "F.Cu")
		(at 224.851976 -374.106186 180)
		(property "Reference" "PR27"
			(at 0 0 180)
			(layer "F.SilkS")
			(hide yes)
			(effects
				(font
					(size 1.27 1.27)
				)
			)
		)
		(property "Value" ""
			(at 0 0 180)
			(layer "F.Fab")
			(effects
				(font
					(size 1.27 1.27)
				)
			)
		)
		(duplicate_pad_numbers_are_jumpers no)
		(fp_line
			(start 0.7874 0.4064)
			(end -0.7874 0.4064)
			(stroke
				(width 0.1524)
				(type default)
			)
			(layer "F.SilkS")
		)
		(fp_line
			(start 0.7874 -0.4064)
			(end 0.7874 0.4064)
			(stroke
				(width 0.1524)
				(type default)
			)
			(layer "F.SilkS")
		)
		(fp_line
			(start -0.7874 0.4064)
			(end -0.7874 -0.4064)
			(stroke
				(width 0.1524)
				(type default)
			)
			(layer "F.SilkS")
		)
		(fp_line
			(start -0.7874 -0.4064)
			(end 0.7874 -0.4064)
			(stroke
				(width 0.1524)
				(type default)
			)
			(layer "F.SilkS")
		)
		(fp_line
			(start 0.67945 0.3048)
			(end 0.120396 0.3048)
			(stroke
				(width 0.1)
				(type default)
			)
			(layer "F.Fab")
		)
		(fp_line
			(start 0.67945 -0.3048)
			(end 0.67945 0.3048)
			(stroke
				(width 0.1)
				(type default)
			)
			(layer "F.Fab")
		)
		(fp_line
			(start 0.12065 -0.2794)
			(end 0.12065 -0.3048)
			(stroke
				(width 0.1)
				(type default)
			)
			(layer "F.Fab")
		)
		(fp_line
			(start 0.12065 -0.3048)
			(end 0.67945 -0.3048)
			(stroke
				(width 0.1)
				(type default)
			)
			(layer "F.Fab")
		)
		(fp_line
			(start 0.120396 0.3048)
			(end 0.120396 0.2794)
			(stroke
				(width 0.1)
				(type default)
			)
			(layer "F.Fab")
		)
		(fp_line
			(start 0.120396 0.2794)
			(end -0.12065 0.2794)
			(stroke
				(width 0.1)
				(type default)
			)
			(layer "F.Fab")
		)
		(fp_line
			(start -0.12065 0.3048)
			(end -0.67945 0.3048)
			(stroke
				(width 0.1)
				(type default)
			)
			(layer "F.Fab")
		)
		(fp_line
			(start -0.12065 0.2794)
			(end -0.12065 0.3048)
			(stroke
				(width 0.1)
				(type default)
			)
			(layer "F.Fab")
		)
		(fp_line
			(start -0.12065 -0.2794)
			(end 0.12065 -0.2794)
			(stroke
				(width 0.1)
				(type default)
			)
			(layer "F.Fab")
		)
		(fp_line
			(start -0.12065 -0.305054)
			(end -0.12065 -0.2794)
			(stroke
				(width 0.1)
				(type default)
			)
			(layer "F.Fab")
		)
		(fp_line
			(start -0.67945 0.3048)
			(end -0.67945 -0.305054)
			(stroke
				(width 0.1)
				(type default)
			)
			(layer "F.Fab")
		)
		(fp_line
			(start -0.67945 -0.305054)
			(end -0.12065 -0.305054)
			(stroke
				(width 0.1)
				(type default)
			)
			(layer "F.Fab")
		)
		(pad "1" smd circle
			(at -0.40005 0 180)
			(size 0 0)
			(layers "F.Cu" "F.Mask" "F.Paste")
			(net "AGND_HSC")
		)
		(pad "2" smd circle
			(at 0.40005 0 180)
			(size 0 0)
			(layers "F.Cu" "F.Mask" "F.Paste")
			(net "HSC_MODE_1")
		)
	)
	(footprint ""
		(layer "F.Cu")
		(at 133.29158 -152.71115 90)
		(property "Reference" "R702"
			(at 0 0 90)
			(layer "F.SilkS")
			(hide yes)
			(effects
				(font
					(size 1.27 1.27)
				)
			)
		)
		(property "Value" ""
			(at 0 0 90)
			(layer "F.Fab")
			(effects
				(font
					(size 1.27 1.27)
				)
			)
		)
		(duplicate_pad_numbers_are_jumpers no)
		(fp_line
			(start 0.7874 -0.4064)
			(end 0.7874 0.4064)
			(stroke
				(width 0.1524)
				(type default)
			)
			(layer "F.SilkS")
		)
		(fp_line
			(start -0.7874 -0.4064)
			(end 0.7874 -0.4064)
			(stroke
				(width 0.1524)
				(type default)
			)
			(layer "F.SilkS")
		)
		(fp_line
			(start 0.7874 0.4064)
			(end -0.7874 0.4064)
			(stroke
				(width 0.1524)
				(type default)
			)
			(layer "F.SilkS")
		)
		(fp_line
			(start -0.7874 0.4064)
			(end -0.7874 -0.4064)
			(stroke
				(width 0.1524)
				(type default)
			)
			(layer "F.SilkS")
		)
		(fp_line
			(start -0.12065 -0.305054)
			(end -0.12065 -0.2794)
			(stroke
				(width 0.1)
				(type default)
			)
			(layer "F.Fab")
		)
		(fp_line
			(start -0.67945 -0.305054)
			(end -0.12065 -0.305054)
			(stroke
				(width 0.1)
				(type default)
			)
			(layer "F.Fab")
		)
		(fp_line
			(start 0.67945 -0.3048)
			(end 0.67945 0.3048)
			(stroke
				(width 0.1)
				(type default)
			)
			(layer "F.Fab")
		)
		(fp_line
			(start 0.12065 -0.3048)
			(end 0.67945 -0.3048)
			(stroke
				(width 0.1)
				(type default)
			)
			(layer "F.Fab")
		)
		(fp_line
			(start 0.12065 -0.2794)
			(end 0.12065 -0.3048)
			(stroke
				(width 0.1)
				(type default)
			)
			(layer "F.Fab")
		)
		(fp_line
			(start -0.12065 -0.2794)
			(end 0.12065 -0.2794)
			(stroke
				(width 0.1)
				(type default)
			)
			(layer "F.Fab")
		)
		(fp_line
			(start 0.120396 0.2794)
			(end -0.12065 0.2794)
			(stroke
				(width 0.1)
				(type default)
			)
			(layer "F.Fab")
		)
		(fp_line
			(start -0.12065 0.2794)
			(end -0.12065 0.3048)
			(stroke
				(width 0.1)
				(type default)
			)
			(layer "F.Fab")
		)
		(fp_line
			(start 0.67945 0.3048)
			(end 0.120396 0.3048)
			(stroke
				(width 0.1)
				(type default)
			)
			(layer "F.Fab")
		)
		(fp_line
			(start 0.120396 0.3048)
			(end 0.120396 0.2794)
			(stroke
				(width 0.1)
				(type default)
			)
			(layer "F.Fab")
		)
		(fp_line
			(start -0.12065 0.3048)
			(end -0.67945 0.3048)
			(stroke
				(width 0.1)
				(type default)
			)
			(layer "F.Fab")
		)
		(fp_line
			(start -0.67945 0.3048)
			(end -0.67945 -0.305054)
			(stroke
				(width 0.1)
				(type default)
			)
			(layer "F.Fab")
		)
		(pad "1" smd circle
			(at -0.40005 0 90)
			(size 0 0)
			(layers "F.Cu" "F.Mask" "F.Paste")
			(net "P3V3_AUX")
		)
		(pad "2" smd circle
			(at 0.40005 0 90)
			(size 0 0)
			(layers "F.Cu" "F.Mask" "F.Paste")
			(net "NIC_ADC_ALERT_N")
		)
	)
	(footprint ""
		(layer "F.Cu")
		(at 413.264858 -26.785062 180)
		(property "Reference" "J44"
			(at 4.660392 -11.134344 90)
			(unlocked yes)
			(layer "F.SilkS")
			(effects
				(font
					(size 0.7874 0.5842)
					(thickness 0.1524)
				)
			)
		)
		(property "Value" ""
			(at 0 0 180)
			(layer "F.Fab")
			(effects
				(font
					(size 1.27 1.27)
				)
			)
		)
		(duplicate_pad_numbers_are_jumpers no)
		(fp_line
			(start 3.150108 12.115038)
			(end 1.529334 12.115038)
			(stroke
				(width 0.1524)
				(type default)
			)
			(layer "F.SilkS")
		)
		(fp_line
			(start 3.074924 12.014962)
			(end 1.632204 12.014962)
			(stroke
				(width 0.1524)
				(type default)
			)
			(layer "F.SilkS")
		)
		(fp_line
			(start 1.632204 -12.014962)
			(end 3.074924 -12.014962)
			(stroke
				(width 0.1524)
				(type default)
			)
			(layer "F.SilkS")
		)
		(fp_line
			(start 1.529334 -12.115038)
			(end 3.150108 -12.115038)
			(stroke
				(width 0.1524)
				(type default)
			)
			(layer "F.SilkS")
		)
		(fp_line
			(start -1.529334 12.115038)
			(end -3.150108 12.115038)
			(stroke
				(width 0.1524)
				(type default)
			)
			(layer "F.SilkS")
		)
		(fp_line
			(start -1.632204 12.014962)
			(end -3.074924 12.014962)
			(stroke
				(width 0.1524)
				(type default)
			)
			(layer "F.SilkS")
		)
		(fp_line
			(start -3.074924 -12.014962)
			(end -1.632204 -12.014962)
			(stroke
				(width 0.1524)
				(type default)
			)
			(layer "F.SilkS")
		)
		(fp_line
			(start -3.150108 -12.115038)
			(end -1.529334 -12.115038)
			(stroke
				(width 0.1524)
				(type default)
			)
			(layer "F.SilkS")
		)
		(fp_poly
			(pts
				(xy 3.620008 -8.68426) (xy 4.042664 -9.95172) (xy 4.887468 -9.106662)
			)
			(stroke
				(width 0)
				(type default)
			)
			(fill yes)
			(layer "F.SilkS")
		)
		(fp_line
			(start 3.074924 12.014962)
			(end -3.074924 12.014962)
			(stroke
				(width 0.1)
				(type default)
			)
			(layer "F.Fab")
		)
		(fp_line
			(start 3.074924 -12.014962)
			(end 3.074924 12.014962)
			(stroke
				(width 0.1)
				(type default)
			)
			(layer "F.Fab")
		)
		(fp_line
			(start -3.074924 12.014962)
			(end -3.074924 -12.014962)
			(stroke
				(width 0.1)
				(type default)
			)
			(layer "F.Fab")
		)
		(fp_line
			(start -3.074924 -12.014962)
			(end 3.074924 -12.014962)
			(stroke
				(width 0.1)
				(type default)
			)
			(layer "F.Fab")
		)
		(fp_poly
			(pts
				(xy 3.348736 -7.994904) (xy 4.543806 -8.592566) (xy 4.543806 -7.397496)
			)
			(stroke
				(width 0)
				(type default)
			)
			(fill yes)
			(layer "F.Fab")
		)
		(pad "" np_thru_hole circle
			(at -1.75006 -9.815068 90)
			(size 1.1176 1.1176)
			(drill 1.1176)
			(layers "*.Cu" "*.Mask")
			(clearance 0.381)
			(thermal_gap 0.381)
		)
		(pad "" np_thru_hole circle
			(at 0 9.815068 90)
			(size 1.1176 1.1176)
			(drill 1.1176)
			(layers "*.Cu" "*.Mask")
			(clearance 0.381)
			(thermal_gap 0.381)
		)
		(pad "A1" smd rect
			(at 2.29997 -7.994904 90)
			(size 0.381 1.27)
			(layers "F.Cu" "F.Mask" "F.Paste")
			(net "GND")
		)
		(pad "A2" smd rect
			(at 2.29997 -7.394956 90)
			(size 0.381 1.27)
			(layers "F.Cu" "F.Mask" "F.Paste")
			(net "GND")
		)
		(pad "A3" smd rect
			(at 2.29997 -6.795008 90)
			(size 0.381 1.27)
			(layers "F.Cu" "F.Mask" "F.Paste")
			(net "GND")
		)
		(pad "A4" smd rect
			(at 2.29997 -6.19506 90)
			(size 0.381 1.27)
			(layers "F.Cu" "F.Mask" "F.Paste")
			(net "GND")
		)
		(pad "A5" smd rect
			(at 2.29997 -5.595112 90)
			(size 0.381 1.27)
			(layers "F.Cu" "F.Mask" "F.Paste")
			(net "GND")
		)
		(pad "A6" smd rect
			(at 2.29997 -4.99491 90)
			(size 0.381 1.27)
			(layers "F.Cu" "F.Mask" "F.Paste")
			(net "GND")
		)
		(pad "A7" smd rect
			(at 2.29997 -4.394962 90)
			(size 0.381 1.27)
			(layers "F.Cu" "F.Mask" "F.Paste")
			(net "SMB_ISO_SSD14_R_SCL")
		)
		(pad "A8" smd rect
			(at 2.29997 -3.795014 90)
			(size 0.381 1.27)
			(layers "F.Cu" "F.Mask" "F.Paste")
			(net "SMB_ISO_SSD14_R_SDA")
		)
		(pad "A9" smd rect
			(at 2.29997 -3.195066 90)
			(size 0.381 1.27)
			(layers "F.Cu" "F.Mask" "F.Paste")
			(net "RST_SMB_SSD14_ISO_R_N")
		)
		(pad "A10" smd rect
			(at 2.29997 -2.595118 90)
			(size 0.381 1.27)
			(layers "F.Cu" "F.Mask" "F.Paste")
			(net "SSD14_LED_ISO_R_N")
		)
		(pad "A11" smd rect
			(at 2.29997 -1.994916 90)
			(size 0.381 1.27)
			(layers "F.Cu" "F.Mask" "F.Paste")
			(net "PU_CLKREQ14")
		)
		(pad "A12" smd rect
			(at 2.29997 -1.394968 90)
			(size 0.381 1.27)
			(layers "F.Cu" "F.Mask" "F.Paste")
			(net "PRSNT_SSD14_N")
		)
		(pad "A13" smd rect
			(at 2.29997 -0.79502 90)
			(size 0.381 1.27)
			(layers "F.Cu" "F.Mask" "F.Paste")
			(net "GND")
		)
		(pad "A14" smd rect
			(at 2.29997 -0.195072 90)
			(size 0.381 1.27)
			(layers "F.Cu" "F.Mask" "F.Paste")
			(net "Net_8465")
		)
		(pad "A15" smd rect
			(at 2.29997 0.404876 90)
			(size 0.381 1.27)
			(layers "F.Cu" "F.Mask" "F.Paste")
			(net "Net_8464")
		)
		(pad "A16" smd rect
			(at 2.29997 1.005078 90)
			(size 0.381 1.27)
			(layers "F.Cu" "F.Mask" "F.Paste")
			(net "GND")
		)
		(pad "A17" smd rect
			(at 2.29997 1.605026 90)
			(size 0.381 1.27)
			(layers "F.Cu" "F.Mask" "F.Paste")
			(net "P5E_PEX3_STN2_RX_DN<36>")
		)
		(pad "A18" smd rect
			(at 2.29997 2.204974 90)
			(size 0.381 1.27)
			(layers "F.Cu" "F.Mask" "F.Paste")
			(net "P5E_PEX3_STN2_RX_DP<36>")
		)
		(pad "A19" smd rect
			(at 2.29997 2.804922 90)
			(size 0.381 1.27)
			(layers "F.Cu" "F.Mask" "F.Paste")
			(net "GND")
		)
		(pad "A20" smd rect
			(at 2.29997 3.405124 90)
			(size 0.381 1.27)
			(layers "F.Cu" "F.Mask" "F.Paste")
			(net "P5E_PEX3_STN2_RX_DN<37>")
		)
		(pad "A21" smd rect
			(at 2.29997 4.005072 90)
			(size 0.381 1.27)
			(layers "F.Cu" "F.Mask" "F.Paste")
			(net "P5E_PEX3_STN2_RX_DP<37>")
		)
		(pad "A22" smd rect
			(at 2.29997 4.60502 90)
			(size 0.381 1.27)
			(layers "F.Cu" "F.Mask" "F.Paste")
			(net "GND")
		)
		(pad "A23" smd rect
			(at 2.29997 5.204968 90)
			(size 0.381 1.27)
			(layers "F.Cu" "F.Mask" "F.Paste")
			(net "P5E_PEX3_STN2_RX_DN<38>")
		)
		(pad "A24" smd rect
			(at 2.29997 5.804916 90)
			(size 0.381 1.27)
			(layers "F.Cu" "F.Mask" "F.Paste")
			(net "P5E_PEX3_STN2_RX_DP<38>")
		)
		(pad "A25" smd rect
			(at 2.29997 6.405118 90)
			(size 0.381 1.27)
			(layers "F.Cu" "F.Mask" "F.Paste")
			(net "GND")
		)
		(pad "A26" smd rect
			(at 2.29997 7.005066 90)
			(size 0.381 1.27)
			(layers "F.Cu" "F.Mask" "F.Paste")
			(net "P5E_PEX3_STN2_RX_DN<39>")
		)
		(pad "A27" smd rect
			(at 2.29997 7.605014 90)
			(size 0.381 1.27)
			(layers "F.Cu" "F.Mask" "F.Paste")
			(net "P5E_PEX3_STN2_RX_DP<39>")
		)
		(pad "A28" smd rect
			(at 2.29997 8.204962 90)
			(size 0.381 1.27)
			(layers "F.Cu" "F.Mask" "F.Paste")
			(net "GND")
		)
		(pad "B1" smd rect
			(at -2.29997 -7.994904 90)
			(size 0.381 1.27)
			(layers "F.Cu" "F.Mask" "F.Paste")
			(net "P12V_SSD14")
		)
		(pad "B2" smd rect
			(at -2.29997 -7.394956 90)
			(size 0.381 1.27)
			(layers "F.Cu" "F.Mask" "F.Paste")
			(net "P12V_SSD14")
		)
		(pad "B3" smd rect
			(at -2.29997 -6.795008 90)
			(size 0.381 1.27)
			(layers "F.Cu" "F.Mask" "F.Paste")
			(net "P12V_SSD14")
		)
		(pad "B4" smd rect
			(at -2.29997 -6.19506 90)
			(size 0.381 1.27)
			(layers "F.Cu" "F.Mask" "F.Paste")
			(net "P12V_SSD14")
		)
		(pad "B5" smd rect
			(at -2.29997 -5.595112 90)
			(size 0.381 1.27)
			(layers "F.Cu" "F.Mask" "F.Paste")
			(net "P12V_SSD14")
		)
		(pad "B6" smd rect
			(at -2.29997 -4.99491 90)
			(size 0.381 1.27)
			(layers "F.Cu" "F.Mask" "F.Paste")
			(net "P12V_SSD14")
		)
		(pad "B7" smd rect
			(at -2.29997 -4.394962 90)
			(size 0.381 1.27)
			(layers "F.Cu" "F.Mask" "F.Paste")
			(net "Net_8466")
		)
		(pad "B8" smd rect
			(at -2.29997 -3.795014 90)
			(size 0.381 1.27)
			(layers "F.Cu" "F.Mask" "F.Paste")
			(net "Net_8463")
		)
		(pad "B9" smd rect
			(at -2.29997 -3.195066 90)
			(size 0.381 1.27)
			(layers "F.Cu" "F.Mask" "F.Paste")
			(net "DUALPORT_N_SSD14")
		)
		(pad "B10" smd rect
			(at -2.29997 -2.595118 90)
			(size 0.381 1.27)
			(layers "F.Cu" "F.Mask" "F.Paste")
			(net "RST_SSD14_PERST_R_N")
		)
		(pad "B11" smd rect
			(at -2.29997 -1.994916 90)
			(size 0.381 1.27)
			(layers "F.Cu" "F.Mask" "F.Paste")
			(net "P3V3_SSD14")
		)
		(pad "B12" smd rect
			(at -2.29997 -1.394968 90)
			(size 0.381 1.27)
			(layers "F.Cu" "F.Mask" "F.Paste")
			(net "SSD14_PWRDIS_R")
		)
		(pad "B13" smd rect
			(at -2.29997 -0.79502 90)
			(size 0.381 1.27)
			(layers "F.Cu" "F.Mask" "F.Paste")
			(net "GND")
		)
		(pad "B14" smd rect
			(at -2.29997 -0.195072 90)
			(size 0.381 1.27)
			(layers "F.Cu" "F.Mask" "F.Paste")
			(net "CLK_100M_DB800ZL_SSD14_R_DN")
		)
		(pad "B15" smd rect
			(at -2.29997 0.404876 90)
			(size 0.381 1.27)
			(layers "F.Cu" "F.Mask" "F.Paste")
			(net "CLK_100M_DB800ZL_SSD14_R_DP")
		)
		(pad "B16" smd rect
			(at -2.29997 1.005078 90)
			(size 0.381 1.27)
			(layers "F.Cu" "F.Mask" "F.Paste")
			(net "GND")
		)
		(pad "B17" smd rect
			(at -2.29997 1.605026 90)
			(size 0.381 1.27)
			(layers "F.Cu" "F.Mask" "F.Paste")
			(net "P5E_PEX3_STN2_TX_C_DN<36>")
		)
		(pad "B18" smd rect
			(at -2.29997 2.204974 90)
			(size 0.381 1.27)
			(layers "F.Cu" "F.Mask" "F.Paste")
			(net "P5E_PEX3_STN2_TX_C_DP<36>")
		)
		(pad "B19" smd rect
			(at -2.29997 2.804922 90)
			(size 0.381 1.27)
			(layers "F.Cu" "F.Mask" "F.Paste")
			(net "GND")
		)
		(pad "B20" smd rect
			(at -2.29997 3.405124 90)
			(size 0.381 1.27)
			(layers "F.Cu" "F.Mask" "F.Paste")
			(net "P5E_PEX3_STN2_TX_C_DN<37>")
		)
		(pad "B21" smd rect
			(at -2.29997 4.005072 90)
			(size 0.381 1.27)
			(layers "F.Cu" "F.Mask" "F.Paste")
			(net "P5E_PEX3_STN2_TX_C_DP<37>")
		)
		(pad "B22" smd rect
			(at -2.29997 4.60502 90)
			(size 0.381 1.27)
			(layers "F.Cu" "F.Mask" "F.Paste")
			(net "GND")
		)
		(pad "B23" smd rect
			(at -2.29997 5.204968 90)
			(size 0.381 1.27)
			(layers "F.Cu" "F.Mask" "F.Paste")
			(net "P5E_PEX3_STN2_TX_C_DN<38>")
		)
		(pad "B24" smd rect
			(at -2.29997 5.804916 90)
			(size 0.381 1.27)
			(layers "F.Cu" "F.Mask" "F.Paste")
			(net "P5E_PEX3_STN2_TX_C_DP<38>")
		)
		(pad "B25" smd rect
			(at -2.29997 6.405118 90)
			(size 0.381 1.27)
			(layers "F.Cu" "F.Mask" "F.Paste")
			(net "GND")
		)
		(pad "B26" smd rect
			(at -2.29997 7.005066 90)
			(size 0.381 1.27)
			(layers "F.Cu" "F.Mask" "F.Paste")
			(net "P5E_PEX3_STN2_TX_C_DN<39>")
		)
		(pad "B27" smd rect
			(at -2.29997 7.605014 90)
			(size 0.381 1.27)
			(layers "F.Cu" "F.Mask" "F.Paste")
			(net "P5E_PEX3_STN2_TX_C_DP<39>")
		)
		(pad "B28" smd rect
			(at -2.29997 8.204962 90)
			(size 0.381 1.27)
			(layers "F.Cu" "F.Mask" "F.Paste")
			(net "GND")
		)
		(pad "G1" thru_hole oval
			(at 0 -11.364976 90)
			(size 1.6256 3.4798)
			(drill oval 1.1176 2.4638)
			(layers "*.Cu" "*.Mask")
			(remove_unused_layers no)
			(net "GND")
			(clearance 0.127)
			(thermal_gap 0.127)
		)
		(pad "G2" thru_hole oval
			(at 0 11.364976 90)
			(size 1.6256 3.4798)
			(drill oval 1.1176 2.4638)
			(layers "*.Cu" "*.Mask")
			(remove_unused_layers no)
			(net "GND")
			(clearance 0.127)
			(thermal_gap 0.127)
		)
		(zone
			(layer "F.Cu")
			(hatch none 0.5)
			(connect_pads
				(clearance 0)
			)
			(min_thickness 0.25)
			(keepout
				(tracks not_allowed)
				(vias allowed)
				(pads allowed)
				(copperpour not_allowed)
				(footprints allowed)
			)
			(placement
				(enabled no)
				(sheetname "")
			)
			(fill
				(thermal_gap 0.5)
				(thermal_bridge_width 0.5)
				(island_removal_mode 0)
			)
			(polygon
				(pts
					(xy 414.64484 -38.850062) (xy 411.894782 -38.850062) (xy 411.894782 -35.900106) (xy 414.64484 -35.900106)
				)
			)
		)
		(zone
			(layer "F.Cu")
			(hatch none 0.5)
			(connect_pads
				(clearance 0)
			)
			(min_thickness 0.25)
			(keepout
				(tracks not_allowed)
				(vias allowed)
				(pads allowed)
				(copperpour not_allowed)
				(footprints allowed)
			)
			(placement
				(enabled no)
				(sheetname "")
			)
			(fill
				(thermal_gap 0.5)
				(thermal_bridge_width 0.5)
				(island_removal_mode 0)
			)
			(polygon
				(pts
					(xy 415.714942 -17.670018) (xy 411.884876 -17.670018) (xy 411.884876 -14.720062) (xy 415.714942 -14.720062)
				)
			)
		)
		(zone
			(layers "F.Cu" "B.Cu" "In1.Cu" "In2.Cu" "In3.Cu" "In4.Cu" "In5.Cu" "In6.Cu"
				"In7.Cu" "In8.Cu" "In9.Cu" "In10.Cu" "In11.Cu" "In12.Cu" "In13.Cu" "In14.Cu"
				"In15.Cu" "In16.Cu"
			)
			(hatch none 0.5)
			(connect_pads
				(clearance 0)
			)
			(min_thickness 0.25)
			(keepout
				(tracks not_allowed)
				(vias allowed)
				(pads allowed)
				(copperpour not_allowed)
				(footprints allowed)
			)
			(placement
				(enabled no)
				(sheetname "")
			)
			(fill
				(thermal_gap 0.5)
				(thermal_bridge_width 0.5)
				(island_removal_mode 0)
			)
			(polygon
				(pts
					(arc
						(start 414.230058 -36.60013)
						(mid 412.299658 -36.60013)
						(end 414.230058 -36.60013)
					)
				)
			)
		)
		(zone
			(layers "F.Cu" "B.Cu" "In1.Cu" "In2.Cu" "In3.Cu" "In4.Cu" "In5.Cu" "In6.Cu"
				"In7.Cu" "In8.Cu" "In9.Cu" "In10.Cu" "In11.Cu" "In12.Cu" "In13.Cu" "In14.Cu"
				"In15.Cu" "In16.Cu"
			)
			(hatch none 0.5)
			(connect_pads
				(clearance 0)
			)
			(min_thickness 0.25)
			(keepout
				(tracks not_allowed)
				(vias allowed)
				(pads allowed)
				(copperpour not_allowed)
				(footprints allowed)
			)
			(placement
				(enabled no)
				(sheetname "")
			)
			(fill
				(thermal_gap 0.5)
				(thermal_bridge_width 0.5)
				(island_removal_mode 0)
			)
			(polygon
				(pts
					(arc
						(start 415.980118 -16.969994)
						(mid 414.049718 -16.969994)
						(end 415.980118 -16.969994)
					)
				)
			)
		)
	)
	(footprint ""
		(layer "F.Cu")
		(at 3.71983 -255.046734 -90)
		(property "Reference" "R6471"
			(at 0 0 270)
			(layer "F.SilkS")
			(hide yes)
			(effects
				(font
					(size 1.27 1.27)
				)
			)
		)
		(property "Value" ""
			(at 0 0 270)
			(layer "F.Fab")
			(effects
				(font
					(size 1.27 1.27)
				)
			)
		)
		(duplicate_pad_numbers_are_jumpers no)
		(fp_line
			(start -0.7874 0.4064)
			(end -0.7874 -0.4064)
			(stroke
				(width 0.1524)
				(type default)
			)
			(layer "F.SilkS")
		)
		(fp_line
			(start 0.7874 0.4064)
			(end -0.7874 0.4064)
			(stroke
				(width 0.1524)
				(type default)
			)
			(layer "F.SilkS")
		)
		(fp_line
			(start -0.7874 -0.4064)
			(end 0.7874 -0.4064)
			(stroke
				(width 0.1524)
				(type default)
			)
			(layer "F.SilkS")
		)
		(fp_line
			(start 0.7874 -0.4064)
			(end 0.7874 0.4064)
			(stroke
				(width 0.1524)
				(type default)
			)
			(layer "F.SilkS")
		)
		(fp_line
			(start -0.67945 0.3048)
			(end -0.67945 -0.305054)
			(stroke
				(width 0.1)
				(type default)
			)
			(layer "F.Fab")
		)
		(fp_line
			(start -0.12065 0.3048)
			(end -0.67945 0.3048)
			(stroke
				(width 0.1)
				(type default)
			)
			(layer "F.Fab")
		)
		(fp_line
			(start 0.120396 0.3048)
			(end 0.120396 0.2794)
			(stroke
				(width 0.1)
				(type default)
			)
			(layer "F.Fab")
		)
		(fp_line
			(start 0.67945 0.3048)
			(end 0.120396 0.3048)
			(stroke
				(width 0.1)
				(type default)
			)
			(layer "F.Fab")
		)
		(fp_line
			(start -0.12065 0.2794)
			(end -0.12065 0.3048)
			(stroke
				(width 0.1)
				(type default)
			)
			(layer "F.Fab")
		)
		(fp_line
			(start 0.120396 0.2794)
			(end -0.12065 0.2794)
			(stroke
				(width 0.1)
				(type default)
			)
			(layer "F.Fab")
		)
		(fp_line
			(start -0.12065 -0.2794)
			(end 0.12065 -0.2794)
			(stroke
				(width 0.1)
				(type default)
			)
			(layer "F.Fab")
		)
		(fp_line
			(start 0.12065 -0.2794)
			(end 0.12065 -0.3048)
			(stroke
				(width 0.1)
				(type default)
			)
			(layer "F.Fab")
		)
		(fp_line
			(start 0.12065 -0.3048)
			(end 0.67945 -0.3048)
			(stroke
				(width 0.1)
				(type default)
			)
			(layer "F.Fab")
		)
		(fp_line
			(start 0.67945 -0.3048)
			(end 0.67945 0.3048)
			(stroke
				(width 0.1)
				(type default)
			)
			(layer "F.Fab")
		)
		(fp_line
			(start -0.67945 -0.305054)
			(end -0.12065 -0.305054)
			(stroke
				(width 0.1)
				(type default)
			)
			(layer "F.Fab")
		)
		(fp_line
			(start -0.12065 -0.305054)
			(end -0.12065 -0.2794)
			(stroke
				(width 0.1)
				(type default)
			)
			(layer "F.Fab")
		)
		(pad "1" smd circle
			(at -0.40005 0 270)
			(size 0 0)
			(layers "F.Cu" "F.Mask" "F.Paste")
			(net "P1V25_SERDES_VDDPLL_PEX0")
		)
		(pad "2" smd circle
			(at 0.40005 0 270)
			(size 0 0)
			(layers "F.Cu" "F.Mask" "F.Paste")
			(net "P1V25_SERDES_VDDPLL_PEX0_C8")
		)
	)
	(footprint ""
		(layer "F.Cu")
		(at 251.938536 -44.341542 90)
		(property "Reference" "C323"
			(at 0 0 90)
			(layer "F.SilkS")
			(hide yes)
			(effects
				(font
					(size 1.27 1.27)
				)
			)
		)
		(property "Value" ""
			(at 0 0 90)
			(layer "F.Fab")
			(effects
				(font
					(size 1.27 1.27)
				)
			)
		)
		(duplicate_pad_numbers_are_jumpers no)
		(fp_line
			(start 0.7874 -0.4064)
			(end 0.7874 0.4064)
			(stroke
				(width 0.1524)
				(type default)
			)
			(layer "F.SilkS")
		)
		(fp_line
			(start -0.7874 -0.4064)
			(end 0.7874 -0.4064)
			(stroke
				(width 0.1524)
				(type default)
			)
			(layer "F.SilkS")
		)
		(fp_line
			(start 0.7874 0.4064)
			(end -0.7874 0.4064)
			(stroke
				(width 0.1524)
				(type default)
			)
			(layer "F.SilkS")
		)
		(fp_line
			(start -0.7874 0.4064)
			(end -0.7874 -0.4064)
			(stroke
				(width 0.1524)
				(type default)
			)
			(layer "F.SilkS")
		)
		(fp_line
			(start -0.12065 -0.305054)
			(end -0.12065 -0.2794)
			(stroke
				(width 0.1)
				(type default)
			)
			(layer "F.Fab")
		)
		(fp_line
			(start -0.67945 -0.305054)
			(end -0.12065 -0.305054)
			(stroke
				(width 0.1)
				(type default)
			)
			(layer "F.Fab")
		)
		(fp_line
			(start 0.67945 -0.3048)
			(end 0.67945 0.3048)
			(stroke
				(width 0.1)
				(type default)
			)
			(layer "F.Fab")
		)
		(fp_line
			(start 0.12065 -0.3048)
			(end 0.67945 -0.3048)
			(stroke
				(width 0.1)
				(type default)
			)
			(layer "F.Fab")
		)
		(fp_line
			(start 0.12065 -0.2794)
			(end 0.12065 -0.3048)
			(stroke
				(width 0.1)
				(type default)
			)
			(layer "F.Fab")
		)
		(fp_line
			(start -0.12065 -0.2794)
			(end 0.12065 -0.2794)
			(stroke
				(width 0.1)
				(type default)
			)
			(layer "F.Fab")
		)
		(fp_line
			(start 0.120396 0.2794)
			(end -0.12065 0.2794)
			(stroke
				(width 0.1)
				(type default)
			)
			(layer "F.Fab")
		)
		(fp_line
			(start -0.12065 0.2794)
			(end -0.12065 0.3048)
			(stroke
				(width 0.1)
				(type default)
			)
			(layer "F.Fab")
		)
		(fp_line
			(start 0.67945 0.3048)
			(end 0.120396 0.3048)
			(stroke
				(width 0.1)
				(type default)
			)
			(layer "F.Fab")
		)
		(fp_line
			(start 0.120396 0.3048)
			(end 0.120396 0.2794)
			(stroke
				(width 0.1)
				(type default)
			)
			(layer "F.Fab")
		)
		(fp_line
			(start -0.12065 0.3048)
			(end -0.67945 0.3048)
			(stroke
				(width 0.1)
				(type default)
			)
			(layer "F.Fab")
		)
		(fp_line
			(start -0.67945 0.3048)
			(end -0.67945 -0.305054)
			(stroke
				(width 0.1)
				(type default)
			)
			(layer "F.Fab")
		)
		(pad "1" smd circle
			(at -0.40005 0 90)
			(size 0 0)
			(layers "F.Cu" "F.Mask" "F.Paste")
			(net "P12V_SSD8_VIN_P")
		)
		(pad "2" smd circle
			(at 0.40005 0 90)
			(size 0 0)
			(layers "F.Cu" "F.Mask" "F.Paste")
			(net "P12V_SSD8_VIN_N")
		)
	)
	(footprint ""
		(layer "F.Cu")
		(at 95.1992 -196.4944 90)
		(property "Reference" "C4443"
			(at 0 0 90)
			(layer "F.SilkS")
			(hide yes)
			(effects
				(font
					(size 1.27 1.27)
				)
			)
		)
		(property "Value" ""
			(at 0 0 90)
			(layer "F.Fab")
			(effects
				(font
					(size 1.27 1.27)
				)
			)
		)
		(duplicate_pad_numbers_are_jumpers no)
		(fp_line
			(start 1.2954 -0.5842)
			(end 1.2954 0.5842)
			(stroke
				(width 0.1524)
				(type default)
			)
			(layer "F.SilkS")
		)
		(fp_line
			(start -1.2954 -0.5842)
			(end 1.2954 -0.5842)
			(stroke
				(width 0.1524)
				(type default)
			)
			(layer "F.SilkS")
		)
		(fp_line
			(start 1.2954 0.5842)
			(end -1.2954 0.5842)
			(stroke
				(width 0.1524)
				(type default)
			)
			(layer "F.SilkS")
		)
		(fp_line
			(start -1.2954 0.5842)
			(end -1.2954 -0.5842)
			(stroke
				(width 0.1524)
				(type default)
			)
			(layer "F.SilkS")
		)
		(fp_line
			(start 0.8636 -0.4572)
			(end 0.8636 -0.4064)
			(stroke
				(width 0.1)
				(type default)
			)
			(layer "F.Fab")
		)
		(fp_line
			(start -0.8636 -0.4572)
			(end 0.8636 -0.4572)
			(stroke
				(width 0.1)
				(type default)
			)
			(layer "F.Fab")
		)
		(fp_line
			(start 1.1938 -0.4064)
			(end 1.1938 0.4064)
			(stroke
				(width 0.1)
				(type default)
			)
			(layer "F.Fab")
		)
		(fp_line
			(start 0.8636 -0.4064)
			(end 1.1938 -0.4064)
			(stroke
				(width 0.1)
				(type default)
			)
			(layer "F.Fab")
		)
		(fp_line
			(start -0.8636 -0.4064)
			(end -0.8636 -0.4572)
			(stroke
				(width 0.1)
				(type default)
			)
			(layer "F.Fab")
		)
		(fp_line
			(start -1.1938 -0.4064)
			(end -0.8636 -0.4064)
			(stroke
				(width 0.1)
				(type default)
			)
			(layer "F.Fab")
		)
		(fp_line
			(start 1.1938 0.4064)
			(end 0.8636 0.4064)
			(stroke
				(width 0.1)
				(type default)
			)
			(layer "F.Fab")
		)
		(fp_line
			(start 0.8636 0.4064)
			(end 0.8636 0.4572)
			(stroke
				(width 0.1)
				(type default)
			)
			(layer "F.Fab")
		)
		(fp_line
			(start -0.8636 0.4064)
			(end -1.1938 0.4064)
			(stroke
				(width 0.1)
				(type default)
			)
			(layer "F.Fab")
		)
		(fp_line
			(start -1.1938 0.4064)
			(end -1.1938 -0.4064)
			(stroke
				(width 0.1)
				(type default)
			)
			(layer "F.Fab")
		)
		(fp_line
			(start 0.8636 0.4572)
			(end -0.8636 0.4572)
			(stroke
				(width 0.1)
				(type default)
			)
			(layer "F.Fab")
		)
		(fp_line
			(start -0.8636 0.4572)
			(end -0.8636 0.4064)
			(stroke
				(width 0.1)
				(type default)
			)
			(layer "F.Fab")
		)
		(pad "1" smd rect
			(at -0.7366 0)
			(size 0.7112 0.8128)
			(layers "F.Cu" "F.Mask" "F.Paste")
			(net "P3V3_AUX")
		)
		(pad "2" smd rect
			(at 0.7366 0)
			(size 0.7112 0.8128)
			(layers "F.Cu" "F.Mask" "F.Paste")
			(net "GND")
		)
	)
	(footprint ""
		(layer "F.Cu")
		(at 147.68957 -63.56223)
		(property "Reference" "Q201"
			(at -0.044196 -2.749042 0)
			(unlocked yes)
			(layer "F.SilkS")
			(effects
				(font
					(size 0.7874 0.5842)
					(thickness 0.1524)
				)
			)
		)
		(property "Value" ""
			(at 0 0 0)
			(layer "F.Fab")
			(effects
				(font
					(size 1.27 1.27)
				)
			)
		)
		(duplicate_pad_numbers_are_jumpers no)
		(fp_line
			(start -1.376172 -1.199896)
			(end -0.508 -1.199896)
			(stroke
				(width 0.1524)
				(type default)
			)
			(layer "F.SilkS")
		)
		(fp_line
			(start -1.376172 1.199896)
			(end -1.376172 -1.199896)
			(stroke
				(width 0.1524)
				(type default)
			)
			(layer "F.SilkS")
		)
		(fp_line
			(start -0.508 -1.199896)
			(end 0 -0.762)
			(stroke
				(width 0.1524)
				(type default)
			)
			(layer "F.SilkS")
		)
		(fp_line
			(start 0 -0.762)
			(end 0.508 -1.199896)
			(stroke
				(width 0.1524)
				(type default)
			)
			(layer "F.SilkS")
		)
		(fp_line
			(start 0.508 -1.199896)
			(end 1.376172 -1.199896)
			(stroke
				(width 0.1524)
				(type default)
			)
			(layer "F.SilkS")
		)
		(fp_line
			(start 1.376172 -1.199896)
			(end 1.376172 1.199896)
			(stroke
				(width 0.1524)
				(type default)
			)
			(layer "F.SilkS")
		)
		(fp_line
			(start 1.376172 1.199896)
			(end -1.376172 1.199896)
			(stroke
				(width 0.1524)
				(type default)
			)
			(layer "F.SilkS")
		)
		(fp_poly
			(pts
				(xy -1.524508 -0.903224) (xy -1.793748 -1.711452) (xy -2.332736 -1.172718)
			)
			(stroke
				(width 0)
				(type default)
			)
			(fill yes)
			(layer "F.SilkS")
		)
		(fp_line
			(start -0.674878 -1.100074)
			(end 0.674878 -1.100074)
			(stroke
				(width 0.1)
				(type default)
			)
			(layer "F.Fab")
		)
		(fp_line
			(start -0.674878 1.100074)
			(end -0.674878 -1.100074)
			(stroke
				(width 0.1)
				(type default)
			)
			(layer "F.Fab")
		)
		(fp_line
			(start 0.674878 -1.100074)
			(end 0.674878 1.100074)
			(stroke
				(width 0.1)
				(type default)
			)
			(layer "F.Fab")
		)
		(fp_line
			(start 0.674878 1.100074)
			(end -0.674878 1.100074)
			(stroke
				(width 0.1)
				(type default)
			)
			(layer "F.Fab")
		)
		(fp_poly
			(pts
				(xy -1.4605 -0.7493) (xy -2.2225 -1.1303) (xy -2.2225 -0.3683)
			)
			(stroke
				(width 0)
				(type default)
			)
			(fill yes)
			(layer "F.Fab")
		)
		(pad "1" smd rect
			(at -0.899922 -0.750062 270)
			(size 0.6096 0.6096)
			(layers "F.Cu" "F.Mask" "F.Paste")
			(net "GND")
		)
		(pad "2" smd rect
			(at -0.899922 0 270)
			(size 0.4064 0.6096)
			(layers "F.Cu" "F.Mask" "F.Paste")
			(net "P12V_SSD5_PG_G1")
		)
		(pad "3" smd rect
			(at -0.899922 0.750062 270)
			(size 0.6096 0.6096)
			(layers "F.Cu" "F.Mask" "F.Paste")
			(net "PWRGD_P12V_SSD5_D")
		)
		(pad "4" smd rect
			(at 0.899922 0.750062 270)
			(size 0.6096 0.6096)
			(layers "F.Cu" "F.Mask" "F.Paste")
			(net "GND")
		)
		(pad "5" smd rect
			(at 0.899922 0 270)
			(size 0.4064 0.6096)
			(layers "F.Cu" "F.Mask" "F.Paste")
			(net "P12V_SSD5_PG_G2")
		)
		(pad "6" smd rect
			(at 0.899922 -0.750062 270)
			(size 0.6096 0.6096)
			(layers "F.Cu" "F.Mask" "F.Paste")
			(net "P12V_SSD5_PG_G2")
		)
	)
	(footprint ""
		(layer "F.Cu")
		(at 247.74271 -162.003994 -90)
		(property "Reference" "C843"
			(at 0 0 270)
			(layer "F.SilkS")
			(hide yes)
			(effects
				(font
					(size 1.27 1.27)
				)
			)
		)
		(property "Value" ""
			(at 0 0 270)
			(layer "F.Fab")
			(effects
				(font
					(size 1.27 1.27)
				)
			)
		)
		(duplicate_pad_numbers_are_jumpers no)
		(fp_line
			(start -0.7874 0.4064)
			(end -0.7874 -0.4064)
			(stroke
				(width 0.1524)
				(type default)
			)
			(layer "F.SilkS")
		)
		(fp_line
			(start 0.7874 0.4064)
			(end -0.7874 0.4064)
			(stroke
				(width 0.1524)
				(type default)
			)
			(layer "F.SilkS")
		)
		(fp_line
			(start -0.7874 -0.4064)
			(end 0.7874 -0.4064)
			(stroke
				(width 0.1524)
				(type default)
			)
			(layer "F.SilkS")
		)
		(fp_line
			(start 0.7874 -0.4064)
			(end 0.7874 0.4064)
			(stroke
				(width 0.1524)
				(type default)
			)
			(layer "F.SilkS")
		)
		(fp_line
			(start -0.67945 0.3048)
			(end -0.67945 -0.305054)
			(stroke
				(width 0.1)
				(type default)
			)
			(layer "F.Fab")
		)
		(fp_line
			(start -0.12065 0.3048)
			(end -0.67945 0.3048)
			(stroke
				(width 0.1)
				(type default)
			)
			(layer "F.Fab")
		)
		(fp_line
			(start 0.120396 0.3048)
			(end 0.120396 0.2794)
			(stroke
				(width 0.1)
				(type default)
			)
			(layer "F.Fab")
		)
		(fp_line
			(start 0.67945 0.3048)
			(end 0.120396 0.3048)
			(stroke
				(width 0.1)
				(type default)
			)
			(layer "F.Fab")
		)
		(fp_line
			(start -0.12065 0.2794)
			(end -0.12065 0.3048)
			(stroke
				(width 0.1)
				(type default)
			)
			(layer "F.Fab")
		)
		(fp_line
			(start 0.120396 0.2794)
			(end -0.12065 0.2794)
			(stroke
				(width 0.1)
				(type default)
			)
			(layer "F.Fab")
		)
		(fp_line
			(start -0.12065 -0.2794)
			(end 0.12065 -0.2794)
			(stroke
				(width 0.1)
				(type default)
			)
			(layer "F.Fab")
		)
		(fp_line
			(start 0.12065 -0.2794)
			(end 0.12065 -0.3048)
			(stroke
				(width 0.1)
				(type default)
			)
			(layer "F.Fab")
		)
		(fp_line
			(start 0.12065 -0.3048)
			(end 0.67945 -0.3048)
			(stroke
				(width 0.1)
				(type default)
			)
			(layer "F.Fab")
		)
		(fp_line
			(start 0.67945 -0.3048)
			(end 0.67945 0.3048)
			(stroke
				(width 0.1)
				(type default)
			)
			(layer "F.Fab")
		)
		(fp_line
			(start -0.67945 -0.305054)
			(end -0.12065 -0.305054)
			(stroke
				(width 0.1)
				(type default)
			)
			(layer "F.Fab")
		)
		(fp_line
			(start -0.12065 -0.305054)
			(end -0.12065 -0.2794)
			(stroke
				(width 0.1)
				(type default)
			)
			(layer "F.Fab")
		)
		(pad "1" smd circle
			(at -0.40005 0 270)
			(size 0 0)
			(layers "F.Cu" "F.Mask" "F.Paste")
			(net "GND")
		)
		(pad "2" smd circle
			(at 0.40005 0 270)
			(size 0 0)
			(layers "F.Cu" "F.Mask" "F.Paste")
			(net "P12V_NIC4_CO_EN")
		)
	)
	(footprint ""
		(layer "F.Cu")
		(at 354.419154 -59.574684 90)
		(property "Reference" "PC576"
			(at 0 0 90)
			(layer "F.SilkS")
			(hide yes)
			(effects
				(font
					(size 1.27 1.27)
				)
			)
		)
		(property "Value" ""
			(at 0 0 90)
			(layer "F.Fab")
			(effects
				(font
					(size 1.27 1.27)
				)
			)
		)
		(duplicate_pad_numbers_are_jumpers no)
		(fp_line
			(start 0.7874 -0.4064)
			(end 0.7874 0.4064)
			(stroke
				(width 0.1524)
				(type default)
			)
			(layer "F.SilkS")
		)
		(fp_line
			(start -0.7874 -0.4064)
			(end 0.7874 -0.4064)
			(stroke
				(width 0.1524)
				(type default)
			)
			(layer "F.SilkS")
		)
		(fp_line
			(start 0.7874 0.4064)
			(end -0.7874 0.4064)
			(stroke
				(width 0.1524)
				(type default)
			)
			(layer "F.SilkS")
		)
		(fp_line
			(start -0.7874 0.4064)
			(end -0.7874 -0.4064)
			(stroke
				(width 0.1524)
				(type default)
			)
			(layer "F.SilkS")
		)
		(fp_line
			(start -0.12065 -0.305054)
			(end -0.12065 -0.2794)
			(stroke
				(width 0.1)
				(type default)
			)
			(layer "F.Fab")
		)
		(fp_line
			(start -0.67945 -0.305054)
			(end -0.12065 -0.305054)
			(stroke
				(width 0.1)
				(type default)
			)
			(layer "F.Fab")
		)
		(fp_line
			(start 0.67945 -0.3048)
			(end 0.67945 0.3048)
			(stroke
				(width 0.1)
				(type default)
			)
			(layer "F.Fab")
		)
		(fp_line
			(start 0.12065 -0.3048)
			(end 0.67945 -0.3048)
			(stroke
				(width 0.1)
				(type default)
			)
			(layer "F.Fab")
		)
		(fp_line
			(start 0.12065 -0.2794)
			(end 0.12065 -0.3048)
			(stroke
				(width 0.1)
				(type default)
			)
			(layer "F.Fab")
		)
		(fp_line
			(start -0.12065 -0.2794)
			(end 0.12065 -0.2794)
			(stroke
				(width 0.1)
				(type default)
			)
			(layer "F.Fab")
		)
		(fp_line
			(start 0.120396 0.2794)
			(end -0.12065 0.2794)
			(stroke
				(width 0.1)
				(type default)
			)
			(layer "F.Fab")
		)
		(fp_line
			(start -0.12065 0.2794)
			(end -0.12065 0.3048)
			(stroke
				(width 0.1)
				(type default)
			)
			(layer "F.Fab")
		)
		(fp_line
			(start 0.67945 0.3048)
			(end 0.120396 0.3048)
			(stroke
				(width 0.1)
				(type default)
			)
			(layer "F.Fab")
		)
		(fp_line
			(start 0.120396 0.3048)
			(end 0.120396 0.2794)
			(stroke
				(width 0.1)
				(type default)
			)
			(layer "F.Fab")
		)
		(fp_line
			(start -0.12065 0.3048)
			(end -0.67945 0.3048)
			(stroke
				(width 0.1)
				(type default)
			)
			(layer "F.Fab")
		)
		(fp_line
			(start -0.67945 0.3048)
			(end -0.67945 -0.305054)
			(stroke
				(width 0.1)
				(type default)
			)
			(layer "F.Fab")
		)
		(pad "1" smd circle
			(at -0.40005 0 90)
			(size 0 0)
			(layers "F.Cu" "F.Mask" "F.Paste")
			(net "P5V_AUX")
		)
		(pad "2" smd circle
			(at 0.40005 0 90)
			(size 0 0)
			(layers "F.Cu" "F.Mask" "F.Paste")
			(net "GND")
		)
	)
	(footprint ""
		(layer "F.Cu")
		(at 350.647 -150.368 90)
		(property "Reference" "C3603"
			(at 0 0 90)
			(layer "F.SilkS")
			(hide yes)
			(effects
				(font
					(size 1.27 1.27)
				)
			)
		)
		(property "Value" ""
			(at 0 0 90)
			(layer "F.Fab")
			(effects
				(font
					(size 1.27 1.27)
				)
			)
		)
		(duplicate_pad_numbers_are_jumpers no)
		(fp_line
			(start 0.7874 -0.4064)
			(end 0.7874 0.4064)
			(stroke
				(width 0.1524)
				(type default)
			)
			(layer "F.SilkS")
		)
		(fp_line
			(start -0.7874 -0.4064)
			(end 0.7874 -0.4064)
			(stroke
				(width 0.1524)
				(type default)
			)
			(layer "F.SilkS")
		)
		(fp_line
			(start 0.7874 0.4064)
			(end -0.7874 0.4064)
			(stroke
				(width 0.1524)
				(type default)
			)
			(layer "F.SilkS")
		)
		(fp_line
			(start -0.7874 0.4064)
			(end -0.7874 -0.4064)
			(stroke
				(width 0.1524)
				(type default)
			)
			(layer "F.SilkS")
		)
		(fp_line
			(start -0.12065 -0.305054)
			(end -0.12065 -0.2794)
			(stroke
				(width 0.1)
				(type default)
			)
			(layer "F.Fab")
		)
		(fp_line
			(start -0.67945 -0.305054)
			(end -0.12065 -0.305054)
			(stroke
				(width 0.1)
				(type default)
			)
			(layer "F.Fab")
		)
		(fp_line
			(start 0.67945 -0.3048)
			(end 0.67945 0.3048)
			(stroke
				(width 0.1)
				(type default)
			)
			(layer "F.Fab")
		)
		(fp_line
			(start 0.12065 -0.3048)
			(end 0.67945 -0.3048)
			(stroke
				(width 0.1)
				(type default)
			)
			(layer "F.Fab")
		)
		(fp_line
			(start 0.12065 -0.2794)
			(end 0.12065 -0.3048)
			(stroke
				(width 0.1)
				(type default)
			)
			(layer "F.Fab")
		)
		(fp_line
			(start -0.12065 -0.2794)
			(end 0.12065 -0.2794)
			(stroke
				(width 0.1)
				(type default)
			)
			(layer "F.Fab")
		)
		(fp_line
			(start 0.120396 0.2794)
			(end -0.12065 0.2794)
			(stroke
				(width 0.1)
				(type default)
			)
			(layer "F.Fab")
		)
		(fp_line
			(start -0.12065 0.2794)
			(end -0.12065 0.3048)
			(stroke
				(width 0.1)
				(type default)
			)
			(layer "F.Fab")
		)
		(fp_line
			(start 0.67945 0.3048)
			(end 0.120396 0.3048)
			(stroke
				(width 0.1)
				(type default)
			)
			(layer "F.Fab")
		)
		(fp_line
			(start 0.120396 0.3048)
			(end 0.120396 0.2794)
			(stroke
				(width 0.1)
				(type default)
			)
			(layer "F.Fab")
		)
		(fp_line
			(start -0.12065 0.3048)
			(end -0.67945 0.3048)
			(stroke
				(width 0.1)
				(type default)
			)
			(layer "F.Fab")
		)
		(fp_line
			(start -0.67945 0.3048)
			(end -0.67945 -0.305054)
			(stroke
				(width 0.1)
				(type default)
			)
			(layer "F.Fab")
		)
		(pad "1" smd circle
			(at -0.40005 0 90)
			(size 0 0)
			(layers "F.Cu" "F.Mask" "F.Paste")
			(net "P3V3_AUX")
		)
		(pad "2" smd circle
			(at 0.40005 0 90)
			(size 0 0)
			(layers "F.Cu" "F.Mask" "F.Paste")
			(net "GND")
		)
	)
	(footprint ""
		(layer "F.Cu")
		(at 419.546786 -38.49116 180)
		(property "Reference" "R6125"
			(at 0 0 180)
			(layer "F.SilkS")
			(hide yes)
			(effects
				(font
					(size 1.27 1.27)
				)
			)
		)
		(property "Value" ""
			(at 0 0 180)
			(layer "F.Fab")
			(effects
				(font
					(size 1.27 1.27)
				)
			)
		)
		(duplicate_pad_numbers_are_jumpers no)
		(fp_line
			(start 0.7874 0.4064)
			(end -0.7874 0.4064)
			(stroke
				(width 0.1524)
				(type default)
			)
			(layer "F.SilkS")
		)
		(fp_line
			(start 0.7874 -0.4064)
			(end 0.7874 0.4064)
			(stroke
				(width 0.1524)
				(type default)
			)
			(layer "F.SilkS")
		)
		(fp_line
			(start -0.7874 0.4064)
			(end -0.7874 -0.4064)
			(stroke
				(width 0.1524)
				(type default)
			)
			(layer "F.SilkS")
		)
		(fp_line
			(start -0.7874 -0.4064)
			(end 0.7874 -0.4064)
			(stroke
				(width 0.1524)
				(type default)
			)
			(layer "F.SilkS")
		)
		(fp_line
			(start 0.67945 0.3048)
			(end 0.120396 0.3048)
			(stroke
				(width 0.1)
				(type default)
			)
			(layer "F.Fab")
		)
		(fp_line
			(start 0.67945 -0.3048)
			(end 0.67945 0.3048)
			(stroke
				(width 0.1)
				(type default)
			)
			(layer "F.Fab")
		)
		(fp_line
			(start 0.12065 -0.2794)
			(end 0.12065 -0.3048)
			(stroke
				(width 0.1)
				(type default)
			)
			(layer "F.Fab")
		)
		(fp_line
			(start 0.12065 -0.3048)
			(end 0.67945 -0.3048)
			(stroke
				(width 0.1)
				(type default)
			)
			(layer "F.Fab")
		)
		(fp_line
			(start 0.120396 0.3048)
			(end 0.120396 0.2794)
			(stroke
				(width 0.1)
				(type default)
			)
			(layer "F.Fab")
		)
		(fp_line
			(start 0.120396 0.2794)
			(end -0.12065 0.2794)
			(stroke
				(width 0.1)
				(type default)
			)
			(layer "F.Fab")
		)
		(fp_line
			(start -0.12065 0.3048)
			(end -0.67945 0.3048)
			(stroke
				(width 0.1)
				(type default)
			)
			(layer "F.Fab")
		)
		(fp_line
			(start -0.12065 0.2794)
			(end -0.12065 0.3048)
			(stroke
				(width 0.1)
				(type default)
			)
			(layer "F.Fab")
		)
		(fp_line
			(start -0.12065 -0.2794)
			(end 0.12065 -0.2794)
			(stroke
				(width 0.1)
				(type default)
			)
			(layer "F.Fab")
		)
		(fp_line
			(start -0.12065 -0.305054)
			(end -0.12065 -0.2794)
			(stroke
				(width 0.1)
				(type default)
			)
			(layer "F.Fab")
		)
		(fp_line
			(start -0.67945 0.3048)
			(end -0.67945 -0.305054)
			(stroke
				(width 0.1)
				(type default)
			)
			(layer "F.Fab")
		)
		(fp_line
			(start -0.67945 -0.305054)
			(end -0.12065 -0.305054)
			(stroke
				(width 0.1)
				(type default)
			)
			(layer "F.Fab")
		)
		(pad "1" smd circle
			(at -0.40005 0 180)
			(size 0 0)
			(layers "F.Cu" "F.Mask" "F.Paste")
			(net "P3V3_SSD15_PG_G1")
		)
		(pad "2" smd circle
			(at 0.40005 0 180)
			(size 0 0)
			(layers "F.Cu" "F.Mask" "F.Paste")
			(net "GND")
		)
	)
	(footprint ""
		(layer "F.Cu")
		(at 182.572406 -175.668686)
		(property "Reference" "R6664"
			(at 0 0 0)
			(layer "F.SilkS")
			(hide yes)
			(effects
				(font
					(size 1.27 1.27)
				)
			)
		)
		(property "Value" ""
			(at 0 0 0)
			(layer "F.Fab")
			(effects
				(font
					(size 1.27 1.27)
				)
			)
		)
		(duplicate_pad_numbers_are_jumpers no)
		(fp_line
			(start -0.7874 -0.4064)
			(end 0.7874 -0.4064)
			(stroke
				(width 0.1524)
				(type default)
			)
			(layer "F.SilkS")
		)
		(fp_line
			(start -0.7874 0.4064)
			(end -0.7874 -0.4064)
			(stroke
				(width 0.1524)
				(type default)
			)
			(layer "F.SilkS")
		)
		(fp_line
			(start 0.7874 -0.4064)
			(end 0.7874 0.4064)
			(stroke
				(width 0.1524)
				(type default)
			)
			(layer "F.SilkS")
		)
		(fp_line
			(start 0.7874 0.4064)
			(end -0.7874 0.4064)
			(stroke
				(width 0.1524)
				(type default)
			)
			(layer "F.SilkS")
		)
		(fp_line
			(start -0.67945 -0.305054)
			(end -0.12065 -0.305054)
			(stroke
				(width 0.1)
				(type default)
			)
			(layer "F.Fab")
		)
		(fp_line
			(start -0.67945 0.3048)
			(end -0.67945 -0.305054)
			(stroke
				(width 0.1)
				(type default)
			)
			(layer "F.Fab")
		)
		(fp_line
			(start -0.12065 -0.305054)
			(end -0.12065 -0.2794)
			(stroke
				(width 0.1)
				(type default)
			)
			(layer "F.Fab")
		)
		(fp_line
			(start -0.12065 -0.2794)
			(end 0.12065 -0.2794)
			(stroke
				(width 0.1)
				(type default)
			)
			(layer "F.Fab")
		)
		(fp_line
			(start -0.12065 0.2794)
			(end -0.12065 0.3048)
			(stroke
				(width 0.1)
				(type default)
			)
			(layer "F.Fab")
		)
		(fp_line
			(start -0.12065 0.3048)
			(end -0.67945 0.3048)
			(stroke
				(width 0.1)
				(type default)
			)
			(layer "F.Fab")
		)
		(fp_line
			(start 0.120396 0.2794)
			(end -0.12065 0.2794)
			(stroke
				(width 0.1)
				(type default)
			)
			(layer "F.Fab")
		)
		(fp_line
			(start 0.120396 0.3048)
			(end 0.120396 0.2794)
			(stroke
				(width 0.1)
				(type default)
			)
			(layer "F.Fab")
		)
		(fp_line
			(start 0.12065 -0.3048)
			(end 0.67945 -0.3048)
			(stroke
				(width 0.1)
				(type default)
			)
			(layer "F.Fab")
		)
		(fp_line
			(start 0.12065 -0.2794)
			(end 0.12065 -0.3048)
			(stroke
				(width 0.1)
				(type default)
			)
			(layer "F.Fab")
		)
		(fp_line
			(start 0.67945 -0.3048)
			(end 0.67945 0.3048)
			(stroke
				(width 0.1)
				(type default)
			)
			(layer "F.Fab")
		)
		(fp_line
			(start 0.67945 0.3048)
			(end 0.120396 0.3048)
			(stroke
				(width 0.1)
				(type default)
			)
			(layer "F.Fab")
		)
		(pad "1" smd circle
			(at -0.40005 0)
			(size 0 0)
			(layers "F.Cu" "F.Mask" "F.Paste")
			(net "NIC3_CLK_EN_BUF_N")
		)
		(pad "2" smd circle
			(at 0.40005 0)
			(size 0 0)
			(layers "F.Cu" "F.Mask" "F.Paste")
			(net "NIC3_CLK_EN_BUF_R_N")
		)
	)
	(footprint ""
		(layer "F.Cu")
		(at 140.748004 -213.712552 180)
		(property "Reference" "C2595"
			(at 0 0 180)
			(layer "F.SilkS")
			(hide yes)
			(effects
				(font
					(size 1.27 1.27)
				)
			)
		)
		(property "Value" ""
			(at 0 0 180)
			(layer "F.Fab")
			(effects
				(font
					(size 1.27 1.27)
				)
			)
		)
		(duplicate_pad_numbers_are_jumpers no)
		(fp_line
			(start 0.7874 0.4064)
			(end -0.7874 0.4064)
			(stroke
				(width 0.1524)
				(type default)
			)
			(layer "F.SilkS")
		)
		(fp_line
			(start 0.7874 -0.4064)
			(end 0.7874 0.4064)
			(stroke
				(width 0.1524)
				(type default)
			)
			(layer "F.SilkS")
		)
		(fp_line
			(start -0.7874 0.4064)
			(end -0.7874 -0.4064)
			(stroke
				(width 0.1524)
				(type default)
			)
			(layer "F.SilkS")
		)
		(fp_line
			(start -0.7874 -0.4064)
			(end 0.7874 -0.4064)
			(stroke
				(width 0.1524)
				(type default)
			)
			(layer "F.SilkS")
		)
		(fp_line
			(start 0.67945 0.3048)
			(end 0.120396 0.3048)
			(stroke
				(width 0.1)
				(type default)
			)
			(layer "F.Fab")
		)
		(fp_line
			(start 0.67945 -0.3048)
			(end 0.67945 0.3048)
			(stroke
				(width 0.1)
				(type default)
			)
			(layer "F.Fab")
		)
		(fp_line
			(start 0.12065 -0.2794)
			(end 0.12065 -0.3048)
			(stroke
				(width 0.1)
				(type default)
			)
			(layer "F.Fab")
		)
		(fp_line
			(start 0.12065 -0.3048)
			(end 0.67945 -0.3048)
			(stroke
				(width 0.1)
				(type default)
			)
			(layer "F.Fab")
		)
		(fp_line
			(start 0.120396 0.3048)
			(end 0.120396 0.2794)
			(stroke
				(width 0.1)
				(type default)
			)
			(layer "F.Fab")
		)
		(fp_line
			(start 0.120396 0.2794)
			(end -0.12065 0.2794)
			(stroke
				(width 0.1)
				(type default)
			)
			(layer "F.Fab")
		)
		(fp_line
			(start -0.12065 0.3048)
			(end -0.67945 0.3048)
			(stroke
				(width 0.1)
				(type default)
			)
			(layer "F.Fab")
		)
		(fp_line
			(start -0.12065 0.2794)
			(end -0.12065 0.3048)
			(stroke
				(width 0.1)
				(type default)
			)
			(layer "F.Fab")
		)
		(fp_line
			(start -0.12065 -0.2794)
			(end 0.12065 -0.2794)
			(stroke
				(width 0.1)
				(type default)
			)
			(layer "F.Fab")
		)
		(fp_line
			(start -0.12065 -0.305054)
			(end -0.12065 -0.2794)
			(stroke
				(width 0.1)
				(type default)
			)
			(layer "F.Fab")
		)
		(fp_line
			(start -0.67945 0.3048)
			(end -0.67945 -0.305054)
			(stroke
				(width 0.1)
				(type default)
			)
			(layer "F.Fab")
		)
		(fp_line
			(start -0.67945 -0.305054)
			(end -0.12065 -0.305054)
			(stroke
				(width 0.1)
				(type default)
			)
			(layer "F.Fab")
		)
		(pad "1" smd circle
			(at -0.40005 0 180)
			(size 0 0)
			(layers "F.Cu" "F.Mask" "F.Paste")
			(net "P1V8_CLI_VCORE")
		)
		(pad "2" smd circle
			(at 0.40005 0 180)
			(size 0 0)
			(layers "F.Cu" "F.Mask" "F.Paste")
			(net "GND")
		)
	)
	(footprint ""
		(layer "F.Cu")
		(at 355.727 -171.45)
		(property "Reference" "R4766"
			(at 0 0 0)
			(layer "F.SilkS")
			(hide yes)
			(effects
				(font
					(size 1.27 1.27)
				)
			)
		)
		(property "Value" ""
			(at 0 0 0)
			(layer "F.Fab")
			(effects
				(font
					(size 1.27 1.27)
				)
			)
		)
		(duplicate_pad_numbers_are_jumpers no)
		(fp_line
			(start -0.7874 -0.4064)
			(end 0.7874 -0.4064)
			(stroke
				(width 0.1524)
				(type default)
			)
			(layer "F.SilkS")
		)
		(fp_line
			(start -0.7874 0.4064)
			(end -0.7874 -0.4064)
			(stroke
				(width 0.1524)
				(type default)
			)
			(layer "F.SilkS")
		)
		(fp_line
			(start 0.7874 -0.4064)
			(end 0.7874 0.4064)
			(stroke
				(width 0.1524)
				(type default)
			)
			(layer "F.SilkS")
		)
		(fp_line
			(start 0.7874 0.4064)
			(end -0.7874 0.4064)
			(stroke
				(width 0.1524)
				(type default)
			)
			(layer "F.SilkS")
		)
		(fp_line
			(start -0.67945 -0.305054)
			(end -0.12065 -0.305054)
			(stroke
				(width 0.1)
				(type default)
			)
			(layer "F.Fab")
		)
		(fp_line
			(start -0.67945 0.3048)
			(end -0.67945 -0.305054)
			(stroke
				(width 0.1)
				(type default)
			)
			(layer "F.Fab")
		)
		(fp_line
			(start -0.12065 -0.305054)
			(end -0.12065 -0.2794)
			(stroke
				(width 0.1)
				(type default)
			)
			(layer "F.Fab")
		)
		(fp_line
			(start -0.12065 -0.2794)
			(end 0.12065 -0.2794)
			(stroke
				(width 0.1)
				(type default)
			)
			(layer "F.Fab")
		)
		(fp_line
			(start -0.12065 0.2794)
			(end -0.12065 0.3048)
			(stroke
				(width 0.1)
				(type default)
			)
			(layer "F.Fab")
		)
		(fp_line
			(start -0.12065 0.3048)
			(end -0.67945 0.3048)
			(stroke
				(width 0.1)
				(type default)
			)
			(layer "F.Fab")
		)
		(fp_line
			(start 0.120396 0.2794)
			(end -0.12065 0.2794)
			(stroke
				(width 0.1)
				(type default)
			)
			(layer "F.Fab")
		)
		(fp_line
			(start 0.120396 0.3048)
			(end 0.120396 0.2794)
			(stroke
				(width 0.1)
				(type default)
			)
			(layer "F.Fab")
		)
		(fp_line
			(start 0.12065 -0.3048)
			(end 0.67945 -0.3048)
			(stroke
				(width 0.1)
				(type default)
			)
			(layer "F.Fab")
		)
		(fp_line
			(start 0.12065 -0.2794)
			(end 0.12065 -0.3048)
			(stroke
				(width 0.1)
				(type default)
			)
			(layer "F.Fab")
		)
		(fp_line
			(start 0.67945 -0.3048)
			(end 0.67945 0.3048)
			(stroke
				(width 0.1)
				(type default)
			)
			(layer "F.Fab")
		)
		(fp_line
			(start 0.67945 0.3048)
			(end 0.120396 0.3048)
			(stroke
				(width 0.1)
				(type default)
			)
			(layer "F.Fab")
		)
		(pad "1" smd circle
			(at -0.40005 0)
			(size 0 0)
			(layers "F.Cu" "F.Mask" "F.Paste")
			(net "PCA9555_1_PEX2_A0")
		)
		(pad "2" smd circle
			(at 0.40005 0)
			(size 0 0)
			(layers "F.Cu" "F.Mask" "F.Paste")
			(net "P3V3_AUX")
		)
	)
	(footprint ""
		(layer "F.Cu")
		(at 93.9546 -124.159264 180)
		(property "Reference" "PC460"
			(at 0 0 180)
			(layer "F.SilkS")
			(hide yes)
			(effects
				(font
					(size 1.27 1.27)
				)
			)
		)
		(property "Value" ""
			(at 0 0 180)
			(layer "F.Fab")
			(effects
				(font
					(size 1.27 1.27)
				)
			)
		)
		(duplicate_pad_numbers_are_jumpers no)
		(fp_line
			(start 0.7874 0.4064)
			(end -0.7874 0.4064)
			(stroke
				(width 0.1524)
				(type default)
			)
			(layer "F.SilkS")
		)
		(fp_line
			(start 0.7874 -0.4064)
			(end 0.7874 0.4064)
			(stroke
				(width 0.1524)
				(type default)
			)
			(layer "F.SilkS")
		)
		(fp_line
			(start -0.7874 0.4064)
			(end -0.7874 -0.4064)
			(stroke
				(width 0.1524)
				(type default)
			)
			(layer "F.SilkS")
		)
		(fp_line
			(start -0.7874 -0.4064)
			(end 0.7874 -0.4064)
			(stroke
				(width 0.1524)
				(type default)
			)
			(layer "F.SilkS")
		)
		(fp_line
			(start 0.67945 0.3048)
			(end 0.120396 0.3048)
			(stroke
				(width 0.1)
				(type default)
			)
			(layer "F.Fab")
		)
		(fp_line
			(start 0.67945 -0.3048)
			(end 0.67945 0.3048)
			(stroke
				(width 0.1)
				(type default)
			)
			(layer "F.Fab")
		)
		(fp_line
			(start 0.12065 -0.2794)
			(end 0.12065 -0.3048)
			(stroke
				(width 0.1)
				(type default)
			)
			(layer "F.Fab")
		)
		(fp_line
			(start 0.12065 -0.3048)
			(end 0.67945 -0.3048)
			(stroke
				(width 0.1)
				(type default)
			)
			(layer "F.Fab")
		)
		(fp_line
			(start 0.120396 0.3048)
			(end 0.120396 0.2794)
			(stroke
				(width 0.1)
				(type default)
			)
			(layer "F.Fab")
		)
		(fp_line
			(start 0.120396 0.2794)
			(end -0.12065 0.2794)
			(stroke
				(width 0.1)
				(type default)
			)
			(layer "F.Fab")
		)
		(fp_line
			(start -0.12065 0.3048)
			(end -0.67945 0.3048)
			(stroke
				(width 0.1)
				(type default)
			)
			(layer "F.Fab")
		)
		(fp_line
			(start -0.12065 0.2794)
			(end -0.12065 0.3048)
			(stroke
				(width 0.1)
				(type default)
			)
			(layer "F.Fab")
		)
		(fp_line
			(start -0.12065 -0.2794)
			(end 0.12065 -0.2794)
			(stroke
				(width 0.1)
				(type default)
			)
			(layer "F.Fab")
		)
		(fp_line
			(start -0.12065 -0.305054)
			(end -0.12065 -0.2794)
			(stroke
				(width 0.1)
				(type default)
			)
			(layer "F.Fab")
		)
		(fp_line
			(start -0.67945 0.3048)
			(end -0.67945 -0.305054)
			(stroke
				(width 0.1)
				(type default)
			)
			(layer "F.Fab")
		)
		(fp_line
			(start -0.67945 -0.305054)
			(end -0.12065 -0.305054)
			(stroke
				(width 0.1)
				(type default)
			)
			(layer "F.Fab")
		)
		(pad "1" smd circle
			(at -0.40005 0 180)
			(size 0 0)
			(layers "F.Cu" "F.Mask" "F.Paste")
			(net "P3V3_AUX")
		)
		(pad "2" smd circle
			(at 0.40005 0 180)
			(size 0 0)
			(layers "F.Cu" "F.Mask" "F.Paste")
			(net "GND")
		)
	)
	(footprint ""
		(layer "F.Cu")
		(at 400.745198 -175.182276)
		(property "Reference" "R357"
			(at 0 0 0)
			(layer "F.SilkS")
			(hide yes)
			(effects
				(font
					(size 1.27 1.27)
				)
			)
		)
		(property "Value" ""
			(at 0 0 0)
			(layer "F.Fab")
			(effects
				(font
					(size 1.27 1.27)
				)
			)
		)
		(duplicate_pad_numbers_are_jumpers no)
		(fp_line
			(start -0.7874 -0.4064)
			(end 0.7874 -0.4064)
			(stroke
				(width 0.1524)
				(type default)
			)
			(layer "F.SilkS")
		)
		(fp_line
			(start -0.7874 0.4064)
			(end -0.7874 -0.4064)
			(stroke
				(width 0.1524)
				(type default)
			)
			(layer "F.SilkS")
		)
		(fp_line
			(start 0.7874 -0.4064)
			(end 0.7874 0.4064)
			(stroke
				(width 0.1524)
				(type default)
			)
			(layer "F.SilkS")
		)
		(fp_line
			(start 0.7874 0.4064)
			(end -0.7874 0.4064)
			(stroke
				(width 0.1524)
				(type default)
			)
			(layer "F.SilkS")
		)
		(fp_line
			(start -0.67945 -0.305054)
			(end -0.12065 -0.305054)
			(stroke
				(width 0.1)
				(type default)
			)
			(layer "F.Fab")
		)
		(fp_line
			(start -0.67945 0.3048)
			(end -0.67945 -0.305054)
			(stroke
				(width 0.1)
				(type default)
			)
			(layer "F.Fab")
		)
		(fp_line
			(start -0.12065 -0.305054)
			(end -0.12065 -0.2794)
			(stroke
				(width 0.1)
				(type default)
			)
			(layer "F.Fab")
		)
		(fp_line
			(start -0.12065 -0.2794)
			(end 0.12065 -0.2794)
			(stroke
				(width 0.1)
				(type default)
			)
			(layer "F.Fab")
		)
		(fp_line
			(start -0.12065 0.2794)
			(end -0.12065 0.3048)
			(stroke
				(width 0.1)
				(type default)
			)
			(layer "F.Fab")
		)
		(fp_line
			(start -0.12065 0.3048)
			(end -0.67945 0.3048)
			(stroke
				(width 0.1)
				(type default)
			)
			(layer "F.Fab")
		)
		(fp_line
			(start 0.120396 0.2794)
			(end -0.12065 0.2794)
			(stroke
				(width 0.1)
				(type default)
			)
			(layer "F.Fab")
		)
		(fp_line
			(start 0.120396 0.3048)
			(end 0.120396 0.2794)
			(stroke
				(width 0.1)
				(type default)
			)
			(layer "F.Fab")
		)
		(fp_line
			(start 0.12065 -0.3048)
			(end 0.67945 -0.3048)
			(stroke
				(width 0.1)
				(type default)
			)
			(layer "F.Fab")
		)
		(fp_line
			(start 0.12065 -0.2794)
			(end 0.12065 -0.3048)
			(stroke
				(width 0.1)
				(type default)
			)
			(layer "F.Fab")
		)
		(fp_line
			(start 0.67945 -0.3048)
			(end 0.67945 0.3048)
			(stroke
				(width 0.1)
				(type default)
			)
			(layer "F.Fab")
		)
		(fp_line
			(start 0.67945 0.3048)
			(end 0.120396 0.3048)
			(stroke
				(width 0.1)
				(type default)
			)
			(layer "F.Fab")
		)
		(pad "1" smd circle
			(at -0.40005 0)
			(size 0 0)
			(layers "F.Cu" "F.Mask" "F.Paste")
			(net "HP_NIC6_PWRGD_R")
		)
		(pad "2" smd circle
			(at 0.40005 0)
			(size 0 0)
			(layers "F.Cu" "F.Mask" "F.Paste")
			(net "HP_NIC6_PWRGD")
		)
	)
	(footprint ""
		(layer "F.Cu")
		(at 109.54639 -282.421584 -90)
		(property "Reference" "PC65"
			(at 0 0 270)
			(layer "F.SilkS")
			(hide yes)
			(effects
				(font
					(size 1.27 1.27)
				)
			)
		)
		(property "Value" ""
			(at 0 0 270)
			(layer "F.Fab")
			(effects
				(font
					(size 1.27 1.27)
				)
			)
		)
		(duplicate_pad_numbers_are_jumpers no)
		(fp_line
			(start -0.7874 0.4064)
			(end -0.7874 -0.4064)
			(stroke
				(width 0.1524)
				(type default)
			)
			(layer "F.SilkS")
		)
		(fp_line
			(start 0.7874 0.4064)
			(end -0.7874 0.4064)
			(stroke
				(width 0.1524)
				(type default)
			)
			(layer "F.SilkS")
		)
		(fp_line
			(start -0.7874 -0.4064)
			(end 0.7874 -0.4064)
			(stroke
				(width 0.1524)
				(type default)
			)
			(layer "F.SilkS")
		)
		(fp_line
			(start 0.7874 -0.4064)
			(end 0.7874 0.4064)
			(stroke
				(width 0.1524)
				(type default)
			)
			(layer "F.SilkS")
		)
		(fp_line
			(start -0.67945 0.3048)
			(end -0.67945 -0.305054)
			(stroke
				(width 0.1)
				(type default)
			)
			(layer "F.Fab")
		)
		(fp_line
			(start -0.12065 0.3048)
			(end -0.67945 0.3048)
			(stroke
				(width 0.1)
				(type default)
			)
			(layer "F.Fab")
		)
		(fp_line
			(start 0.120396 0.3048)
			(end 0.120396 0.2794)
			(stroke
				(width 0.1)
				(type default)
			)
			(layer "F.Fab")
		)
		(fp_line
			(start 0.67945 0.3048)
			(end 0.120396 0.3048)
			(stroke
				(width 0.1)
				(type default)
			)
			(layer "F.Fab")
		)
		(fp_line
			(start -0.12065 0.2794)
			(end -0.12065 0.3048)
			(stroke
				(width 0.1)
				(type default)
			)
			(layer "F.Fab")
		)
		(fp_line
			(start 0.120396 0.2794)
			(end -0.12065 0.2794)
			(stroke
				(width 0.1)
				(type default)
			)
			(layer "F.Fab")
		)
		(fp_line
			(start -0.12065 -0.2794)
			(end 0.12065 -0.2794)
			(stroke
				(width 0.1)
				(type default)
			)
			(layer "F.Fab")
		)
		(fp_line
			(start 0.12065 -0.2794)
			(end 0.12065 -0.3048)
			(stroke
				(width 0.1)
				(type default)
			)
			(layer "F.Fab")
		)
		(fp_line
			(start 0.12065 -0.3048)
			(end 0.67945 -0.3048)
			(stroke
				(width 0.1)
				(type default)
			)
			(layer "F.Fab")
		)
		(fp_line
			(start 0.67945 -0.3048)
			(end 0.67945 0.3048)
			(stroke
				(width 0.1)
				(type default)
			)
			(layer "F.Fab")
		)
		(fp_line
			(start -0.67945 -0.305054)
			(end -0.12065 -0.305054)
			(stroke
				(width 0.1)
				(type default)
			)
			(layer "F.Fab")
		)
		(fp_line
			(start -0.12065 -0.305054)
			(end -0.12065 -0.2794)
			(stroke
				(width 0.1)
				(type default)
			)
			(layer "F.Fab")
		)
		(pad "1" smd circle
			(at -0.40005 0 270)
			(size 0 0)
			(layers "F.Cu" "F.Mask" "F.Paste")
			(net "P0V8_PEX0_VCC1")
		)
		(pad "2" smd circle
			(at 0.40005 0 270)
			(size 0 0)
			(layers "F.Cu" "F.Mask" "F.Paste")
			(net "GND")
		)
	)
	(footprint ""
		(layer "F.Cu")
		(at 55.883556 -61.487812 180)
		(property "Reference" "R5848"
			(at 0 0 180)
			(layer "F.SilkS")
			(hide yes)
			(effects
				(font
					(size 1.27 1.27)
				)
			)
		)
		(property "Value" ""
			(at 0 0 180)
			(layer "F.Fab")
			(effects
				(font
					(size 1.27 1.27)
				)
			)
		)
		(duplicate_pad_numbers_are_jumpers no)
		(fp_line
			(start 0.7874 0.4064)
			(end -0.7874 0.4064)
			(stroke
				(width 0.1524)
				(type default)
			)
			(layer "F.SilkS")
		)
		(fp_line
			(start 0.7874 -0.4064)
			(end 0.7874 0.4064)
			(stroke
				(width 0.1524)
				(type default)
			)
			(layer "F.SilkS")
		)
		(fp_line
			(start -0.7874 0.4064)
			(end -0.7874 -0.4064)
			(stroke
				(width 0.1524)
				(type default)
			)
			(layer "F.SilkS")
		)
		(fp_line
			(start -0.7874 -0.4064)
			(end 0.7874 -0.4064)
			(stroke
				(width 0.1524)
				(type default)
			)
			(layer "F.SilkS")
		)
		(fp_line
			(start 0.67945 0.3048)
			(end 0.120396 0.3048)
			(stroke
				(width 0.1)
				(type default)
			)
			(layer "F.Fab")
		)
		(fp_line
			(start 0.67945 -0.3048)
			(end 0.67945 0.3048)
			(stroke
				(width 0.1)
				(type default)
			)
			(layer "F.Fab")
		)
		(fp_line
			(start 0.12065 -0.2794)
			(end 0.12065 -0.3048)
			(stroke
				(width 0.1)
				(type default)
			)
			(layer "F.Fab")
		)
		(fp_line
			(start 0.12065 -0.3048)
			(end 0.67945 -0.3048)
			(stroke
				(width 0.1)
				(type default)
			)
			(layer "F.Fab")
		)
		(fp_line
			(start 0.120396 0.3048)
			(end 0.120396 0.2794)
			(stroke
				(width 0.1)
				(type default)
			)
			(layer "F.Fab")
		)
		(fp_line
			(start 0.120396 0.2794)
			(end -0.12065 0.2794)
			(stroke
				(width 0.1)
				(type default)
			)
			(layer "F.Fab")
		)
		(fp_line
			(start -0.12065 0.3048)
			(end -0.67945 0.3048)
			(stroke
				(width 0.1)
				(type default)
			)
			(layer "F.Fab")
		)
		(fp_line
			(start -0.12065 0.2794)
			(end -0.12065 0.3048)
			(stroke
				(width 0.1)
				(type default)
			)
			(layer "F.Fab")
		)
		(fp_line
			(start -0.12065 -0.2794)
			(end 0.12065 -0.2794)
			(stroke
				(width 0.1)
				(type default)
			)
			(layer "F.Fab")
		)
		(fp_line
			(start -0.12065 -0.305054)
			(end -0.12065 -0.2794)
			(stroke
				(width 0.1)
				(type default)
			)
			(layer "F.Fab")
		)
		(fp_line
			(start -0.67945 0.3048)
			(end -0.67945 -0.305054)
			(stroke
				(width 0.1)
				(type default)
			)
			(layer "F.Fab")
		)
		(fp_line
			(start -0.67945 -0.305054)
			(end -0.12065 -0.305054)
			(stroke
				(width 0.1)
				(type default)
			)
			(layer "F.Fab")
		)
		(pad "1" smd circle
			(at -0.40005 0 180)
			(size 0 0)
			(layers "F.Cu" "F.Mask" "F.Paste")
			(net "PWRGD_P12V_SSD2_D")
		)
		(pad "2" smd circle
			(at 0.40005 0 180)
			(size 0 0)
			(layers "F.Cu" "F.Mask" "F.Paste")
			(net "PWRGD_P12V_SSD2_R")
		)
	)
	(footprint ""
		(layer "F.Cu")
		(at 356.934008 -156.288994 -90)
		(property "Reference" "PR7053"
			(at 0 0 270)
			(layer "F.SilkS")
			(hide yes)
			(effects
				(font
					(size 1.27 1.27)
				)
			)
		)
		(property "Value" ""
			(at 0 0 270)
			(layer "F.Fab")
			(effects
				(font
					(size 1.27 1.27)
				)
			)
		)
		(duplicate_pad_numbers_are_jumpers no)
		(fp_line
			(start -0.7874 0.4064)
			(end -0.7874 -0.4064)
			(stroke
				(width 0.1524)
				(type default)
			)
			(layer "F.SilkS")
		)
		(fp_line
			(start 0.7874 0.4064)
			(end -0.7874 0.4064)
			(stroke
				(width 0.1524)
				(type default)
			)
			(layer "F.SilkS")
		)
		(fp_line
			(start -0.7874 -0.4064)
			(end 0.7874 -0.4064)
			(stroke
				(width 0.1524)
				(type default)
			)
			(layer "F.SilkS")
		)
		(fp_line
			(start 0.7874 -0.4064)
			(end 0.7874 0.4064)
			(stroke
				(width 0.1524)
				(type default)
			)
			(layer "F.SilkS")
		)
		(fp_line
			(start -0.67945 0.3048)
			(end -0.67945 -0.305054)
			(stroke
				(width 0.1)
				(type default)
			)
			(layer "F.Fab")
		)
		(fp_line
			(start -0.12065 0.3048)
			(end -0.67945 0.3048)
			(stroke
				(width 0.1)
				(type default)
			)
			(layer "F.Fab")
		)
		(fp_line
			(start 0.120396 0.3048)
			(end 0.120396 0.2794)
			(stroke
				(width 0.1)
				(type default)
			)
			(layer "F.Fab")
		)
		(fp_line
			(start 0.67945 0.3048)
			(end 0.120396 0.3048)
			(stroke
				(width 0.1)
				(type default)
			)
			(layer "F.Fab")
		)
		(fp_line
			(start -0.12065 0.2794)
			(end -0.12065 0.3048)
			(stroke
				(width 0.1)
				(type default)
			)
			(layer "F.Fab")
		)
		(fp_line
			(start 0.120396 0.2794)
			(end -0.12065 0.2794)
			(stroke
				(width 0.1)
				(type default)
			)
			(layer "F.Fab")
		)
		(fp_line
			(start -0.12065 -0.2794)
			(end 0.12065 -0.2794)
			(stroke
				(width 0.1)
				(type default)
			)
			(layer "F.Fab")
		)
		(fp_line
			(start 0.12065 -0.2794)
			(end 0.12065 -0.3048)
			(stroke
				(width 0.1)
				(type default)
			)
			(layer "F.Fab")
		)
		(fp_line
			(start 0.12065 -0.3048)
			(end 0.67945 -0.3048)
			(stroke
				(width 0.1)
				(type default)
			)
			(layer "F.Fab")
		)
		(fp_line
			(start 0.67945 -0.3048)
			(end 0.67945 0.3048)
			(stroke
				(width 0.1)
				(type default)
			)
			(layer "F.Fab")
		)
		(fp_line
			(start -0.67945 -0.305054)
			(end -0.12065 -0.305054)
			(stroke
				(width 0.1)
				(type default)
			)
			(layer "F.Fab")
		)
		(fp_line
			(start -0.12065 -0.305054)
			(end -0.12065 -0.2794)
			(stroke
				(width 0.1)
				(type default)
			)
			(layer "F.Fab")
		)
		(pad "1" smd circle
			(at -0.40005 0 270)
			(size 0 0)
			(layers "F.Cu" "F.Mask" "F.Paste")
			(net "P12V_NIC6_CO_OV_FB")
		)
		(pad "2" smd circle
			(at 0.40005 0 270)
			(size 0 0)
			(layers "F.Cu" "F.Mask" "F.Paste")
			(net "GND")
		)
	)
	(footprint ""
		(layer "F.Cu")
		(at 91.958668 -111.227108 90)
		(property "Reference" "PC604"
			(at 0 0 90)
			(layer "F.SilkS")
			(hide yes)
			(effects
				(font
					(size 1.27 1.27)
				)
			)
		)
		(property "Value" ""
			(at 0 0 90)
			(layer "F.Fab")
			(effects
				(font
					(size 1.27 1.27)
				)
			)
		)
		(duplicate_pad_numbers_are_jumpers no)
		(fp_line
			(start 1.524 -0.762)
			(end 1.524 0.762)
			(stroke
				(width 0.1524)
				(type default)
			)
			(layer "F.SilkS")
		)
		(fp_line
			(start -1.524 -0.762)
			(end 1.524 -0.762)
			(stroke
				(width 0.1524)
				(type default)
			)
			(layer "F.SilkS")
		)
		(fp_line
			(start 1.524 0.762)
			(end -1.524 0.762)
			(stroke
				(width 0.1524)
				(type default)
			)
			(layer "F.SilkS")
		)
		(fp_line
			(start -1.524 0.762)
			(end -1.524 -0.762)
			(stroke
				(width 0.1524)
				(type default)
			)
			(layer "F.SilkS")
		)
		(fp_line
			(start 1.1049 -0.724916)
			(end -1.1049 -0.724916)
			(stroke
				(width 0.1)
				(type default)
			)
			(layer "F.Fab")
		)
		(fp_line
			(start -1.1049 -0.724916)
			(end -1.1049 0.724916)
			(stroke
				(width 0.1)
				(type default)
			)
			(layer "F.Fab")
		)
		(fp_line
			(start 1.1049 0.724916)
			(end 1.1049 -0.724916)
			(stroke
				(width 0.1)
				(type default)
			)
			(layer "F.Fab")
		)
		(fp_line
			(start -1.1049 0.724916)
			(end 1.1049 0.724916)
			(stroke
				(width 0.1)
				(type default)
			)
			(layer "F.Fab")
		)
		(pad "1" smd rect
			(at -0.889 0 270)
			(size 1.016 1.27)
			(layers "F.Cu" "F.Mask" "F.Paste")
			(net "P12V_NIC1_R")
		)
		(pad "2" smd rect
			(at 0.889 0 270)
			(size 1.016 1.27)
			(layers "F.Cu" "F.Mask" "F.Paste")
			(net "GND")
		)
	)
	(footprint ""
		(layer "F.Cu")
		(at 124.272548 -350.098614 90)
		(property "Reference" "C368"
			(at 0 0 90)
			(layer "F.SilkS")
			(hide yes)
			(effects
				(font
					(size 1.27 1.27)
				)
			)
		)
		(property "Value" ""
			(at 0 0 90)
			(layer "F.Fab")
			(effects
				(font
					(size 1.27 1.27)
				)
			)
		)
		(duplicate_pad_numbers_are_jumpers no)
		(fp_line
			(start 0.299974 -0.150114)
			(end 0.299974 0.150114)
			(stroke
				(width 0.1)
				(type default)
			)
			(layer "F.Fab")
		)
		(fp_line
			(start -0.299974 -0.150114)
			(end 0.299974 -0.150114)
			(stroke
				(width 0.1)
				(type default)
			)
			(layer "F.Fab")
		)
		(fp_line
			(start 0.299974 0.150114)
			(end -0.299974 0.150114)
			(stroke
				(width 0.1)
				(type default)
			)
			(layer "F.Fab")
		)
		(fp_line
			(start -0.299974 0.150114)
			(end -0.299974 -0.150114)
			(stroke
				(width 0.1)
				(type default)
			)
			(layer "F.Fab")
		)
		(pad "1" smd rect
			(at -0.2667 0 90)
			(size 0.3048 0.381)
			(layers "F.Cu" "F.Mask" "F.Paste")
			(net "P5E_PEX1_STN6_TX_DP<97>")
		)
		(pad "2" smd rect
			(at 0.2667 0 90)
			(size 0.3048 0.381)
			(layers "F.Cu" "F.Mask" "F.Paste")
			(net "P5E_PEX1_STN6_TX_C_DP<97>")
		)
	)
	(footprint ""
		(layer "F.Cu")
		(at 446.972944 -22.867366 90)
		(property "Reference" "C3977"
			(at 0 0 90)
			(layer "F.SilkS")
			(hide yes)
			(effects
				(font
					(size 1.27 1.27)
				)
			)
		)
		(property "Value" ""
			(at 0 0 90)
			(layer "F.Fab")
			(effects
				(font
					(size 1.27 1.27)
				)
			)
		)
		(duplicate_pad_numbers_are_jumpers no)
		(fp_line
			(start 0.7874 -0.4064)
			(end 0.7874 0.4064)
			(stroke
				(width 0.1524)
				(type default)
			)
			(layer "F.SilkS")
		)
		(fp_line
			(start -0.7874 -0.4064)
			(end 0.7874 -0.4064)
			(stroke
				(width 0.1524)
				(type default)
			)
			(layer "F.SilkS")
		)
		(fp_line
			(start 0.7874 0.4064)
			(end -0.7874 0.4064)
			(stroke
				(width 0.1524)
				(type default)
			)
			(layer "F.SilkS")
		)
		(fp_line
			(start -0.7874 0.4064)
			(end -0.7874 -0.4064)
			(stroke
				(width 0.1524)
				(type default)
			)
			(layer "F.SilkS")
		)
		(fp_line
			(start -0.12065 -0.305054)
			(end -0.12065 -0.2794)
			(stroke
				(width 0.1)
				(type default)
			)
			(layer "F.Fab")
		)
		(fp_line
			(start -0.67945 -0.305054)
			(end -0.12065 -0.305054)
			(stroke
				(width 0.1)
				(type default)
			)
			(layer "F.Fab")
		)
		(fp_line
			(start 0.67945 -0.3048)
			(end 0.67945 0.3048)
			(stroke
				(width 0.1)
				(type default)
			)
			(layer "F.Fab")
		)
		(fp_line
			(start 0.12065 -0.3048)
			(end 0.67945 -0.3048)
			(stroke
				(width 0.1)
				(type default)
			)
			(layer "F.Fab")
		)
		(fp_line
			(start 0.12065 -0.2794)
			(end 0.12065 -0.3048)
			(stroke
				(width 0.1)
				(type default)
			)
			(layer "F.Fab")
		)
		(fp_line
			(start -0.12065 -0.2794)
			(end 0.12065 -0.2794)
			(stroke
				(width 0.1)
				(type default)
			)
			(layer "F.Fab")
		)
		(fp_line
			(start 0.120396 0.2794)
			(end -0.12065 0.2794)
			(stroke
				(width 0.1)
				(type default)
			)
			(layer "F.Fab")
		)
		(fp_line
			(start -0.12065 0.2794)
			(end -0.12065 0.3048)
			(stroke
				(width 0.1)
				(type default)
			)
			(layer "F.Fab")
		)
		(fp_line
			(start 0.67945 0.3048)
			(end 0.120396 0.3048)
			(stroke
				(width 0.1)
				(type default)
			)
			(layer "F.Fab")
		)
		(fp_line
			(start 0.120396 0.3048)
			(end 0.120396 0.2794)
			(stroke
				(width 0.1)
				(type default)
			)
			(layer "F.Fab")
		)
		(fp_line
			(start -0.12065 0.3048)
			(end -0.67945 0.3048)
			(stroke
				(width 0.1)
				(type default)
			)
			(layer "F.Fab")
		)
		(fp_line
			(start -0.67945 0.3048)
			(end -0.67945 -0.305054)
			(stroke
				(width 0.1)
				(type default)
			)
			(layer "F.Fab")
		)
		(pad "1" smd circle
			(at -0.40005 0 90)
			(size 0 0)
			(layers "F.Cu" "F.Mask" "F.Paste")
			(net "P12V_SSD15")
		)
		(pad "2" smd circle
			(at 0.40005 0 90)
			(size 0 0)
			(layers "F.Cu" "F.Mask" "F.Paste")
			(net "GND")
		)
	)
	(footprint ""
		(layer "F.Cu")
		(at 249.20575 -86.098888 180)
		(property "Reference" "R1051"
			(at 0 0 180)
			(layer "F.SilkS")
			(hide yes)
			(effects
				(font
					(size 1.27 1.27)
				)
			)
		)
		(property "Value" ""
			(at 0 0 180)
			(layer "F.Fab")
			(effects
				(font
					(size 1.27 1.27)
				)
			)
		)
		(duplicate_pad_numbers_are_jumpers no)
		(fp_line
			(start 0.7874 0.4064)
			(end -0.7874 0.4064)
			(stroke
				(width 0.1524)
				(type default)
			)
			(layer "F.SilkS")
		)
		(fp_line
			(start 0.7874 -0.4064)
			(end 0.7874 0.4064)
			(stroke
				(width 0.1524)
				(type default)
			)
			(layer "F.SilkS")
		)
		(fp_line
			(start -0.7874 0.4064)
			(end -0.7874 -0.4064)
			(stroke
				(width 0.1524)
				(type default)
			)
			(layer "F.SilkS")
		)
		(fp_line
			(start -0.7874 -0.4064)
			(end 0.7874 -0.4064)
			(stroke
				(width 0.1524)
				(type default)
			)
			(layer "F.SilkS")
		)
		(fp_line
			(start 0.67945 0.3048)
			(end 0.120396 0.3048)
			(stroke
				(width 0.1)
				(type default)
			)
			(layer "F.Fab")
		)
		(fp_line
			(start 0.67945 -0.3048)
			(end 0.67945 0.3048)
			(stroke
				(width 0.1)
				(type default)
			)
			(layer "F.Fab")
		)
		(fp_line
			(start 0.12065 -0.2794)
			(end 0.12065 -0.3048)
			(stroke
				(width 0.1)
				(type default)
			)
			(layer "F.Fab")
		)
		(fp_line
			(start 0.12065 -0.3048)
			(end 0.67945 -0.3048)
			(stroke
				(width 0.1)
				(type default)
			)
			(layer "F.Fab")
		)
		(fp_line
			(start 0.120396 0.3048)
			(end 0.120396 0.2794)
			(stroke
				(width 0.1)
				(type default)
			)
			(layer "F.Fab")
		)
		(fp_line
			(start 0.120396 0.2794)
			(end -0.12065 0.2794)
			(stroke
				(width 0.1)
				(type default)
			)
			(layer "F.Fab")
		)
		(fp_line
			(start -0.12065 0.3048)
			(end -0.67945 0.3048)
			(stroke
				(width 0.1)
				(type default)
			)
			(layer "F.Fab")
		)
		(fp_line
			(start -0.12065 0.2794)
			(end -0.12065 0.3048)
			(stroke
				(width 0.1)
				(type default)
			)
			(layer "F.Fab")
		)
		(fp_line
			(start -0.12065 -0.2794)
			(end 0.12065 -0.2794)
			(stroke
				(width 0.1)
				(type default)
			)
			(layer "F.Fab")
		)
		(fp_line
			(start -0.12065 -0.305054)
			(end -0.12065 -0.2794)
			(stroke
				(width 0.1)
				(type default)
			)
			(layer "F.Fab")
		)
		(fp_line
			(start -0.67945 0.3048)
			(end -0.67945 -0.305054)
			(stroke
				(width 0.1)
				(type default)
			)
			(layer "F.Fab")
		)
		(fp_line
			(start -0.67945 -0.305054)
			(end -0.12065 -0.305054)
			(stroke
				(width 0.1)
				(type default)
			)
			(layer "F.Fab")
		)
		(pad "1" smd circle
			(at -0.40005 0 180)
			(size 0 0)
			(layers "F.Cu" "F.Mask" "F.Paste")
			(net "CLK_CK440_SMB_ADDR1")
		)
		(pad "2" smd circle
			(at 0.40005 0 180)
			(size 0 0)
			(layers "F.Cu" "F.Mask" "F.Paste")
			(net "P3V3")
		)
	)
	(footprint ""
		(layer "F.Cu")
		(at 140.442442 -252.356874 -90)
		(property "Reference" "R1298"
			(at 0 0 270)
			(layer "F.SilkS")
			(hide yes)
			(effects
				(font
					(size 1.27 1.27)
				)
			)
		)
		(property "Value" ""
			(at 0 0 270)
			(layer "F.Fab")
			(effects
				(font
					(size 1.27 1.27)
				)
			)
		)
		(duplicate_pad_numbers_are_jumpers no)
		(fp_line
			(start -0.7874 0.4064)
			(end -0.7874 -0.4064)
			(stroke
				(width 0.1524)
				(type default)
			)
			(layer "F.SilkS")
		)
		(fp_line
			(start 0.7874 0.4064)
			(end -0.7874 0.4064)
			(stroke
				(width 0.1524)
				(type default)
			)
			(layer "F.SilkS")
		)
		(fp_line
			(start -0.7874 -0.4064)
			(end 0.7874 -0.4064)
			(stroke
				(width 0.1524)
				(type default)
			)
			(layer "F.SilkS")
		)
		(fp_line
			(start 0.7874 -0.4064)
			(end 0.7874 0.4064)
			(stroke
				(width 0.1524)
				(type default)
			)
			(layer "F.SilkS")
		)
		(fp_line
			(start -0.67945 0.3048)
			(end -0.67945 -0.305054)
			(stroke
				(width 0.1)
				(type default)
			)
			(layer "F.Fab")
		)
		(fp_line
			(start -0.12065 0.3048)
			(end -0.67945 0.3048)
			(stroke
				(width 0.1)
				(type default)
			)
			(layer "F.Fab")
		)
		(fp_line
			(start 0.120396 0.3048)
			(end 0.120396 0.2794)
			(stroke
				(width 0.1)
				(type default)
			)
			(layer "F.Fab")
		)
		(fp_line
			(start 0.67945 0.3048)
			(end 0.120396 0.3048)
			(stroke
				(width 0.1)
				(type default)
			)
			(layer "F.Fab")
		)
		(fp_line
			(start -0.12065 0.2794)
			(end -0.12065 0.3048)
			(stroke
				(width 0.1)
				(type default)
			)
			(layer "F.Fab")
		)
		(fp_line
			(start 0.120396 0.2794)
			(end -0.12065 0.2794)
			(stroke
				(width 0.1)
				(type default)
			)
			(layer "F.Fab")
		)
		(fp_line
			(start -0.12065 -0.2794)
			(end 0.12065 -0.2794)
			(stroke
				(width 0.1)
				(type default)
			)
			(layer "F.Fab")
		)
		(fp_line
			(start 0.12065 -0.2794)
			(end 0.12065 -0.3048)
			(stroke
				(width 0.1)
				(type default)
			)
			(layer "F.Fab")
		)
		(fp_line
			(start 0.12065 -0.3048)
			(end 0.67945 -0.3048)
			(stroke
				(width 0.1)
				(type default)
			)
			(layer "F.Fab")
		)
		(fp_line
			(start 0.67945 -0.3048)
			(end 0.67945 0.3048)
			(stroke
				(width 0.1)
				(type default)
			)
			(layer "F.Fab")
		)
		(fp_line
			(start -0.67945 -0.305054)
			(end -0.12065 -0.305054)
			(stroke
				(width 0.1)
				(type default)
			)
			(layer "F.Fab")
		)
		(fp_line
			(start -0.12065 -0.305054)
			(end -0.12065 -0.2794)
			(stroke
				(width 0.1)
				(type default)
			)
			(layer "F.Fab")
		)
		(pad "1" smd circle
			(at -0.40005 0 270)
			(size 0 0)
			(layers "F.Cu" "F.Mask" "F.Paste")
			(net "GND")
		)
		(pad "2" smd circle
			(at 0.40005 0 270)
			(size 0 0)
			(layers "F.Cu" "F.Mask" "F.Paste")
			(net "PEX1_MODE_SEL9")
		)
	)
	(footprint ""
		(layer "F.Cu")
		(at 315.04763 -40.037258 90)
		(property "Reference" "U377"
			(at 0.297942 2.40284 90)
			(unlocked yes)
			(layer "F.SilkS")
			(effects
				(font
					(size 0.7874 0.5842)
					(thickness 0.1524)
				)
			)
		)
		(property "Value" ""
			(at 0 0 90)
			(layer "F.Fab")
			(effects
				(font
					(size 1.27 1.27)
				)
			)
		)
		(duplicate_pad_numbers_are_jumpers no)
		(fp_line
			(start -1.949958 -1.610106)
			(end 1.949958 -1.610106)
			(stroke
				(width 0.1524)
				(type default)
			)
			(layer "F.SilkS")
		)
		(fp_line
			(start 1.949958 -1.560068)
			(end 1.949958 1.610106)
			(stroke
				(width 0.1524)
				(type default)
			)
			(layer "F.SilkS")
		)
		(fp_line
			(start 1.949958 1.610106)
			(end -1.949958 1.610106)
			(stroke
				(width 0.1524)
				(type default)
			)
			(layer "F.SilkS")
		)
		(fp_line
			(start -1.949958 1.610106)
			(end -1.949958 -1.610106)
			(stroke
				(width 0.1524)
				(type default)
			)
			(layer "F.SilkS")
		)
		(fp_line
			(start 0.750062 -1.560068)
			(end 0.750062 1.560068)
			(stroke
				(width 0.1)
				(type default)
			)
			(layer "F.Fab")
		)
		(fp_line
			(start -0.750062 -1.560068)
			(end 0.750062 -1.560068)
			(stroke
				(width 0.1)
				(type default)
			)
			(layer "F.Fab")
		)
		(fp_line
			(start 0.750062 1.560068)
			(end -0.750062 1.560068)
			(stroke
				(width 0.1)
				(type default)
			)
			(layer "F.Fab")
		)
		(fp_line
			(start -0.750062 1.560068)
			(end -0.750062 -1.560068)
			(stroke
				(width 0.1)
				(type default)
			)
			(layer "F.Fab")
		)
		(pad "D" smd rect
			(at 1.100074 0)
			(size 1.016 1.4224)
			(layers "F.Cu" "F.Mask" "F.Paste")
			(net "SSD11_AUX_P3V3_EN")
		)
		(pad "G" smd rect
			(at -1.100074 -0.94996)
			(size 1.016 1.4224)
			(layers "F.Cu" "F.Mask" "F.Paste")
			(net "PRSNT_SSD11_R1_N")
		)
		(pad "S" smd rect
			(at -1.100074 0.94996)
			(size 1.016 1.4224)
			(layers "F.Cu" "F.Mask" "F.Paste")
			(net "GND")
		)
	)
	(footprint ""
		(layer "F.Cu")
		(at 196.550788 -414.45815 -90)
		(property "Reference" "C4477"
			(at 0 0 270)
			(layer "F.SilkS")
			(hide yes)
			(effects
				(font
					(size 1.27 1.27)
				)
			)
		)
		(property "Value" ""
			(at 0 0 270)
			(layer "F.Fab")
			(effects
				(font
					(size 1.27 1.27)
				)
			)
		)
		(duplicate_pad_numbers_are_jumpers no)
		(fp_line
			(start -0.7874 0.4064)
			(end -0.7874 -0.4064)
			(stroke
				(width 0.1524)
				(type default)
			)
			(layer "F.SilkS")
		)
		(fp_line
			(start 0.7874 0.4064)
			(end -0.7874 0.4064)
			(stroke
				(width 0.1524)
				(type default)
			)
			(layer "F.SilkS")
		)
		(fp_line
			(start -0.7874 -0.4064)
			(end 0.7874 -0.4064)
			(stroke
				(width 0.1524)
				(type default)
			)
			(layer "F.SilkS")
		)
		(fp_line
			(start 0.7874 -0.4064)
			(end 0.7874 0.4064)
			(stroke
				(width 0.1524)
				(type default)
			)
			(layer "F.SilkS")
		)
		(fp_line
			(start -0.67945 0.3048)
			(end -0.67945 -0.305054)
			(stroke
				(width 0.1)
				(type default)
			)
			(layer "F.Fab")
		)
		(fp_line
			(start -0.12065 0.3048)
			(end -0.67945 0.3048)
			(stroke
				(width 0.1)
				(type default)
			)
			(layer "F.Fab")
		)
		(fp_line
			(start 0.120396 0.3048)
			(end 0.120396 0.2794)
			(stroke
				(width 0.1)
				(type default)
			)
			(layer "F.Fab")
		)
		(fp_line
			(start 0.67945 0.3048)
			(end 0.120396 0.3048)
			(stroke
				(width 0.1)
				(type default)
			)
			(layer "F.Fab")
		)
		(fp_line
			(start -0.12065 0.2794)
			(end -0.12065 0.3048)
			(stroke
				(width 0.1)
				(type default)
			)
			(layer "F.Fab")
		)
		(fp_line
			(start 0.120396 0.2794)
			(end -0.12065 0.2794)
			(stroke
				(width 0.1)
				(type default)
			)
			(layer "F.Fab")
		)
		(fp_line
			(start -0.12065 -0.2794)
			(end 0.12065 -0.2794)
			(stroke
				(width 0.1)
				(type default)
			)
			(layer "F.Fab")
		)
		(fp_line
			(start 0.12065 -0.2794)
			(end 0.12065 -0.3048)
			(stroke
				(width 0.1)
				(type default)
			)
			(layer "F.Fab")
		)
		(fp_line
			(start 0.12065 -0.3048)
			(end 0.67945 -0.3048)
			(stroke
				(width 0.1)
				(type default)
			)
			(layer "F.Fab")
		)
		(fp_line
			(start 0.67945 -0.3048)
			(end 0.67945 0.3048)
			(stroke
				(width 0.1)
				(type default)
			)
			(layer "F.Fab")
		)
		(fp_line
			(start -0.67945 -0.305054)
			(end -0.12065 -0.305054)
			(stroke
				(width 0.1)
				(type default)
			)
			(layer "F.Fab")
		)
		(fp_line
			(start -0.12065 -0.305054)
			(end -0.12065 -0.2794)
			(stroke
				(width 0.1)
				(type default)
			)
			(layer "F.Fab")
		)
		(pad "1" smd circle
			(at -0.40005 0 270)
			(size 0 0)
			(layers "F.Cu" "F.Mask" "F.Paste")
			(net "UV_P2V5_COMP")
		)
		(pad "2" smd circle
			(at 0.40005 0 270)
			(size 0 0)
			(layers "F.Cu" "F.Mask" "F.Paste")
			(net "GND")
		)
	)
	(footprint ""
		(layer "F.Cu")
		(at 235.871512 -234.728004 -90)
		(property "Reference" "R6189"
			(at 0 0 270)
			(layer "F.SilkS")
			(hide yes)
			(effects
				(font
					(size 1.27 1.27)
				)
			)
		)
		(property "Value" ""
			(at 0 0 270)
			(layer "F.Fab")
			(effects
				(font
					(size 1.27 1.27)
				)
			)
		)
		(duplicate_pad_numbers_are_jumpers no)
		(fp_line
			(start -0.7874 0.4064)
			(end -0.7874 -0.4064)
			(stroke
				(width 0.1524)
				(type default)
			)
			(layer "F.SilkS")
		)
		(fp_line
			(start 0.7874 0.4064)
			(end -0.7874 0.4064)
			(stroke
				(width 0.1524)
				(type default)
			)
			(layer "F.SilkS")
		)
		(fp_line
			(start -0.7874 -0.4064)
			(end 0.7874 -0.4064)
			(stroke
				(width 0.1524)
				(type default)
			)
			(layer "F.SilkS")
		)
		(fp_line
			(start 0.7874 -0.4064)
			(end 0.7874 0.4064)
			(stroke
				(width 0.1524)
				(type default)
			)
			(layer "F.SilkS")
		)
		(fp_line
			(start -0.67945 0.3048)
			(end -0.67945 -0.305054)
			(stroke
				(width 0.1)
				(type default)
			)
			(layer "F.Fab")
		)
		(fp_line
			(start -0.12065 0.3048)
			(end -0.67945 0.3048)
			(stroke
				(width 0.1)
				(type default)
			)
			(layer "F.Fab")
		)
		(fp_line
			(start 0.120396 0.3048)
			(end 0.120396 0.2794)
			(stroke
				(width 0.1)
				(type default)
			)
			(layer "F.Fab")
		)
		(fp_line
			(start 0.67945 0.3048)
			(end 0.120396 0.3048)
			(stroke
				(width 0.1)
				(type default)
			)
			(layer "F.Fab")
		)
		(fp_line
			(start -0.12065 0.2794)
			(end -0.12065 0.3048)
			(stroke
				(width 0.1)
				(type default)
			)
			(layer "F.Fab")
		)
		(fp_line
			(start 0.120396 0.2794)
			(end -0.12065 0.2794)
			(stroke
				(width 0.1)
				(type default)
			)
			(layer "F.Fab")
		)
		(fp_line
			(start -0.12065 -0.2794)
			(end 0.12065 -0.2794)
			(stroke
				(width 0.1)
				(type default)
			)
			(layer "F.Fab")
		)
		(fp_line
			(start 0.12065 -0.2794)
			(end 0.12065 -0.3048)
			(stroke
				(width 0.1)
				(type default)
			)
			(layer "F.Fab")
		)
		(fp_line
			(start 0.12065 -0.3048)
			(end 0.67945 -0.3048)
			(stroke
				(width 0.1)
				(type default)
			)
			(layer "F.Fab")
		)
		(fp_line
			(start 0.67945 -0.3048)
			(end 0.67945 0.3048)
			(stroke
				(width 0.1)
				(type default)
			)
			(layer "F.Fab")
		)
		(fp_line
			(start -0.67945 -0.305054)
			(end -0.12065 -0.305054)
			(stroke
				(width 0.1)
				(type default)
			)
			(layer "F.Fab")
		)
		(fp_line
			(start -0.12065 -0.305054)
			(end -0.12065 -0.2794)
			(stroke
				(width 0.1)
				(type default)
			)
			(layer "F.Fab")
		)
		(pad "1" smd circle
			(at -0.40005 0 270)
			(size 0 0)
			(layers "F.Cu" "F.Mask" "F.Paste")
			(net "GND")
		)
		(pad "2" smd circle
			(at 0.40005 0 270)
			(size 0 0)
			(layers "F.Cu" "F.Mask" "F.Paste")
			(net "SSD7_PWRDIS_BIC_R")
		)
	)
	(footprint ""
		(layer "F.Cu")
		(at 380.711456 -283.643832 -90)
		(property "Reference" "R4595"
			(at 0 0 270)
			(layer "F.SilkS")
			(hide yes)
			(effects
				(font
					(size 1.27 1.27)
				)
			)
		)
		(property "Value" ""
			(at 0 0 270)
			(layer "F.Fab")
			(effects
				(font
					(size 1.27 1.27)
				)
			)
		)
		(duplicate_pad_numbers_are_jumpers no)
		(fp_line
			(start -0.7874 0.4064)
			(end -0.7874 -0.4064)
			(stroke
				(width 0.1524)
				(type default)
			)
			(layer "F.SilkS")
		)
		(fp_line
			(start 0.7874 0.4064)
			(end -0.7874 0.4064)
			(stroke
				(width 0.1524)
				(type default)
			)
			(layer "F.SilkS")
		)
		(fp_line
			(start -0.7874 -0.4064)
			(end 0.7874 -0.4064)
			(stroke
				(width 0.1524)
				(type default)
			)
			(layer "F.SilkS")
		)
		(fp_line
			(start 0.7874 -0.4064)
			(end 0.7874 0.4064)
			(stroke
				(width 0.1524)
				(type default)
			)
			(layer "F.SilkS")
		)
		(fp_line
			(start -0.67945 0.3048)
			(end -0.67945 -0.305054)
			(stroke
				(width 0.1)
				(type default)
			)
			(layer "F.Fab")
		)
		(fp_line
			(start -0.12065 0.3048)
			(end -0.67945 0.3048)
			(stroke
				(width 0.1)
				(type default)
			)
			(layer "F.Fab")
		)
		(fp_line
			(start 0.120396 0.3048)
			(end 0.120396 0.2794)
			(stroke
				(width 0.1)
				(type default)
			)
			(layer "F.Fab")
		)
		(fp_line
			(start 0.67945 0.3048)
			(end 0.120396 0.3048)
			(stroke
				(width 0.1)
				(type default)
			)
			(layer "F.Fab")
		)
		(fp_line
			(start -0.12065 0.2794)
			(end -0.12065 0.3048)
			(stroke
				(width 0.1)
				(type default)
			)
			(layer "F.Fab")
		)
		(fp_line
			(start 0.120396 0.2794)
			(end -0.12065 0.2794)
			(stroke
				(width 0.1)
				(type default)
			)
			(layer "F.Fab")
		)
		(fp_line
			(start -0.12065 -0.2794)
			(end 0.12065 -0.2794)
			(stroke
				(width 0.1)
				(type default)
			)
			(layer "F.Fab")
		)
		(fp_line
			(start 0.12065 -0.2794)
			(end 0.12065 -0.3048)
			(stroke
				(width 0.1)
				(type default)
			)
			(layer "F.Fab")
		)
		(fp_line
			(start 0.12065 -0.3048)
			(end 0.67945 -0.3048)
			(stroke
				(width 0.1)
				(type default)
			)
			(layer "F.Fab")
		)
		(fp_line
			(start 0.67945 -0.3048)
			(end 0.67945 0.3048)
			(stroke
				(width 0.1)
				(type default)
			)
			(layer "F.Fab")
		)
		(fp_line
			(start -0.67945 -0.305054)
			(end -0.12065 -0.305054)
			(stroke
				(width 0.1)
				(type default)
			)
			(layer "F.Fab")
		)
		(fp_line
			(start -0.12065 -0.305054)
			(end -0.12065 -0.2794)
			(stroke
				(width 0.1)
				(type default)
			)
			(layer "F.Fab")
		)
		(pad "1" smd circle
			(at -0.40005 0 270)
			(size 0 0)
			(layers "F.Cu" "F.Mask" "F.Paste")
			(net "PCEPLL7_VDDA18_PEX3")
		)
		(pad "2" smd circle
			(at 0.40005 0 270)
			(size 0 0)
			(layers "F.Cu" "F.Mask" "F.Paste")
			(net "PCEPLL7_VDDA18_PEX3_R")
		)
	)
	(footprint ""
		(layer "F.Cu")
		(at 219.202 -203.2)
		(property "Reference" "R1515"
			(at 0 0 0)
			(layer "F.SilkS")
			(hide yes)
			(effects
				(font
					(size 1.27 1.27)
				)
			)
		)
		(property "Value" ""
			(at 0 0 0)
			(layer "F.Fab")
			(effects
				(font
					(size 1.27 1.27)
				)
			)
		)
		(duplicate_pad_numbers_are_jumpers no)
		(fp_line
			(start -0.7874 -0.4064)
			(end 0.7874 -0.4064)
			(stroke
				(width 0.1524)
				(type default)
			)
			(layer "F.SilkS")
		)
		(fp_line
			(start -0.7874 0.4064)
			(end -0.7874 -0.4064)
			(stroke
				(width 0.1524)
				(type default)
			)
			(layer "F.SilkS")
		)
		(fp_line
			(start 0.7874 -0.4064)
			(end 0.7874 0.4064)
			(stroke
				(width 0.1524)
				(type default)
			)
			(layer "F.SilkS")
		)
		(fp_line
			(start 0.7874 0.4064)
			(end -0.7874 0.4064)
			(stroke
				(width 0.1524)
				(type default)
			)
			(layer "F.SilkS")
		)
		(fp_line
			(start -0.67945 -0.305054)
			(end -0.12065 -0.305054)
			(stroke
				(width 0.1)
				(type default)
			)
			(layer "F.Fab")
		)
		(fp_line
			(start -0.67945 0.3048)
			(end -0.67945 -0.305054)
			(stroke
				(width 0.1)
				(type default)
			)
			(layer "F.Fab")
		)
		(fp_line
			(start -0.12065 -0.305054)
			(end -0.12065 -0.2794)
			(stroke
				(width 0.1)
				(type default)
			)
			(layer "F.Fab")
		)
		(fp_line
			(start -0.12065 -0.2794)
			(end 0.12065 -0.2794)
			(stroke
				(width 0.1)
				(type default)
			)
			(layer "F.Fab")
		)
		(fp_line
			(start -0.12065 0.2794)
			(end -0.12065 0.3048)
			(stroke
				(width 0.1)
				(type default)
			)
			(layer "F.Fab")
		)
		(fp_line
			(start -0.12065 0.3048)
			(end -0.67945 0.3048)
			(stroke
				(width 0.1)
				(type default)
			)
			(layer "F.Fab")
		)
		(fp_line
			(start 0.120396 0.2794)
			(end -0.12065 0.2794)
			(stroke
				(width 0.1)
				(type default)
			)
			(layer "F.Fab")
		)
		(fp_line
			(start 0.120396 0.3048)
			(end 0.120396 0.2794)
			(stroke
				(width 0.1)
				(type default)
			)
			(layer "F.Fab")
		)
		(fp_line
			(start 0.12065 -0.3048)
			(end 0.67945 -0.3048)
			(stroke
				(width 0.1)
				(type default)
			)
			(layer "F.Fab")
		)
		(fp_line
			(start 0.12065 -0.2794)
			(end 0.12065 -0.3048)
			(stroke
				(width 0.1)
				(type default)
			)
			(layer "F.Fab")
		)
		(fp_line
			(start 0.67945 -0.3048)
			(end 0.67945 0.3048)
			(stroke
				(width 0.1)
				(type default)
			)
			(layer "F.Fab")
		)
		(fp_line
			(start 0.67945 0.3048)
			(end 0.120396 0.3048)
			(stroke
				(width 0.1)
				(type default)
			)
			(layer "F.Fab")
		)
		(pad "1" smd circle
			(at -0.40005 0)
			(size 0 0)
			(layers "F.Cu" "F.Mask" "F.Paste")
			(net "SMB_NIC5_LS_R_SDA")
		)
		(pad "2" smd circle
			(at 0.40005 0)
			(size 0 0)
			(layers "F.Cu" "F.Mask" "F.Paste")
			(net "P3V3_NIC5")
		)
	)
	(footprint ""
		(layer "F.Cu")
		(at 363.998002 -122.780552)
		(property "Reference" "PC462"
			(at 0 0 0)
			(layer "F.SilkS")
			(hide yes)
			(effects
				(font
					(size 1.27 1.27)
				)
			)
		)
		(property "Value" ""
			(at 0 0 0)
			(layer "F.Fab")
			(effects
				(font
					(size 1.27 1.27)
				)
			)
		)
		(duplicate_pad_numbers_are_jumpers no)
		(fp_line
			(start -0.7874 -0.4064)
			(end 0.7874 -0.4064)
			(stroke
				(width 0.1524)
				(type default)
			)
			(layer "F.SilkS")
		)
		(fp_line
			(start -0.7874 0.4064)
			(end -0.7874 -0.4064)
			(stroke
				(width 0.1524)
				(type default)
			)
			(layer "F.SilkS")
		)
		(fp_line
			(start 0.7874 -0.4064)
			(end 0.7874 0.4064)
			(stroke
				(width 0.1524)
				(type default)
			)
			(layer "F.SilkS")
		)
		(fp_line
			(start 0.7874 0.4064)
			(end -0.7874 0.4064)
			(stroke
				(width 0.1524)
				(type default)
			)
			(layer "F.SilkS")
		)
		(fp_line
			(start -0.67945 -0.305054)
			(end -0.12065 -0.305054)
			(stroke
				(width 0.1)
				(type default)
			)
			(layer "F.Fab")
		)
		(fp_line
			(start -0.67945 0.3048)
			(end -0.67945 -0.305054)
			(stroke
				(width 0.1)
				(type default)
			)
			(layer "F.Fab")
		)
		(fp_line
			(start -0.12065 -0.305054)
			(end -0.12065 -0.2794)
			(stroke
				(width 0.1)
				(type default)
			)
			(layer "F.Fab")
		)
		(fp_line
			(start -0.12065 -0.2794)
			(end 0.12065 -0.2794)
			(stroke
				(width 0.1)
				(type default)
			)
			(layer "F.Fab")
		)
		(fp_line
			(start -0.12065 0.2794)
			(end -0.12065 0.3048)
			(stroke
				(width 0.1)
				(type default)
			)
			(layer "F.Fab")
		)
		(fp_line
			(start -0.12065 0.3048)
			(end -0.67945 0.3048)
			(stroke
				(width 0.1)
				(type default)
			)
			(layer "F.Fab")
		)
		(fp_line
			(start 0.120396 0.2794)
			(end -0.12065 0.2794)
			(stroke
				(width 0.1)
				(type default)
			)
			(layer "F.Fab")
		)
		(fp_line
			(start 0.120396 0.3048)
			(end 0.120396 0.2794)
			(stroke
				(width 0.1)
				(type default)
			)
			(layer "F.Fab")
		)
		(fp_line
			(start 0.12065 -0.3048)
			(end 0.67945 -0.3048)
			(stroke
				(width 0.1)
				(type default)
			)
			(layer "F.Fab")
		)
		(fp_line
			(start 0.12065 -0.2794)
			(end 0.12065 -0.3048)
			(stroke
				(width 0.1)
				(type default)
			)
			(layer "F.Fab")
		)
		(fp_line
			(start 0.67945 -0.3048)
			(end 0.67945 0.3048)
			(stroke
				(width 0.1)
				(type default)
			)
			(layer "F.Fab")
		)
		(fp_line
			(start 0.67945 0.3048)
			(end 0.120396 0.3048)
			(stroke
				(width 0.1)
				(type default)
			)
			(layer "F.Fab")
		)
		(pad "1" smd circle
			(at -0.40005 0)
			(size 0 0)
			(layers "F.Cu" "F.Mask" "F.Paste")
			(net "P3V3_AUX")
		)
		(pad "2" smd circle
			(at 0.40005 0)
			(size 0 0)
			(layers "F.Cu" "F.Mask" "F.Paste")
			(net "GND")
		)
	)
	(footprint ""
		(layer "F.Cu")
		(at 26.243788 -49.95291 180)
		(property "Reference" "R511"
			(at 0 0 180)
			(layer "F.SilkS")
			(hide yes)
			(effects
				(font
					(size 1.27 1.27)
				)
			)
		)
		(property "Value" ""
			(at 0 0 180)
			(layer "F.Fab")
			(effects
				(font
					(size 1.27 1.27)
				)
			)
		)
		(duplicate_pad_numbers_are_jumpers no)
		(fp_line
			(start 0.7874 0.4064)
			(end -0.7874 0.4064)
			(stroke
				(width 0.1524)
				(type default)
			)
			(layer "F.SilkS")
		)
		(fp_line
			(start 0.7874 -0.4064)
			(end 0.7874 0.4064)
			(stroke
				(width 0.1524)
				(type default)
			)
			(layer "F.SilkS")
		)
		(fp_line
			(start -0.7874 0.4064)
			(end -0.7874 -0.4064)
			(stroke
				(width 0.1524)
				(type default)
			)
			(layer "F.SilkS")
		)
		(fp_line
			(start -0.7874 -0.4064)
			(end 0.7874 -0.4064)
			(stroke
				(width 0.1524)
				(type default)
			)
			(layer "F.SilkS")
		)
		(fp_line
			(start 0.67945 0.3048)
			(end 0.120396 0.3048)
			(stroke
				(width 0.1)
				(type default)
			)
			(layer "F.Fab")
		)
		(fp_line
			(start 0.67945 -0.3048)
			(end 0.67945 0.3048)
			(stroke
				(width 0.1)
				(type default)
			)
			(layer "F.Fab")
		)
		(fp_line
			(start 0.12065 -0.2794)
			(end 0.12065 -0.3048)
			(stroke
				(width 0.1)
				(type default)
			)
			(layer "F.Fab")
		)
		(fp_line
			(start 0.12065 -0.3048)
			(end 0.67945 -0.3048)
			(stroke
				(width 0.1)
				(type default)
			)
			(layer "F.Fab")
		)
		(fp_line
			(start 0.120396 0.3048)
			(end 0.120396 0.2794)
			(stroke
				(width 0.1)
				(type default)
			)
			(layer "F.Fab")
		)
		(fp_line
			(start 0.120396 0.2794)
			(end -0.12065 0.2794)
			(stroke
				(width 0.1)
				(type default)
			)
			(layer "F.Fab")
		)
		(fp_line
			(start -0.12065 0.3048)
			(end -0.67945 0.3048)
			(stroke
				(width 0.1)
				(type default)
			)
			(layer "F.Fab")
		)
		(fp_line
			(start -0.12065 0.2794)
			(end -0.12065 0.3048)
			(stroke
				(width 0.1)
				(type default)
			)
			(layer "F.Fab")
		)
		(fp_line
			(start -0.12065 -0.2794)
			(end 0.12065 -0.2794)
			(stroke
				(width 0.1)
				(type default)
			)
			(layer "F.Fab")
		)
		(fp_line
			(start -0.12065 -0.305054)
			(end -0.12065 -0.2794)
			(stroke
				(width 0.1)
				(type default)
			)
			(layer "F.Fab")
		)
		(fp_line
			(start -0.67945 0.3048)
			(end -0.67945 -0.305054)
			(stroke
				(width 0.1)
				(type default)
			)
			(layer "F.Fab")
		)
		(fp_line
			(start -0.67945 -0.305054)
			(end -0.12065 -0.305054)
			(stroke
				(width 0.1)
				(type default)
			)
			(layer "F.Fab")
		)
		(pad "1" smd circle
			(at -0.40005 0 180)
			(size 0 0)
			(layers "F.Cu" "F.Mask" "F.Paste")
			(net "SMB_BIC_I2C6_MUX_SSD_0_7_ADC_R_SCL")
		)
		(pad "2" smd circle
			(at 0.40005 0 180)
			(size 0 0)
			(layers "F.Cu" "F.Mask" "F.Paste")
			(net "SMB_SSD0_ADC_SCL")
		)
	)
	(footprint ""
		(layer "F.Cu")
		(at 435.055772 -343.952322 90)
		(property "Reference" "C803"
			(at 0 0 90)
			(layer "F.SilkS")
			(hide yes)
			(effects
				(font
					(size 1.27 1.27)
				)
			)
		)
		(property "Value" ""
			(at 0 0 90)
			(layer "F.Fab")
			(effects
				(font
					(size 1.27 1.27)
				)
			)
		)
		(duplicate_pad_numbers_are_jumpers no)
		(fp_line
			(start 0.299974 -0.150114)
			(end 0.299974 0.150114)
			(stroke
				(width 0.1)
				(type default)
			)
			(layer "F.Fab")
		)
		(fp_line
			(start -0.299974 -0.150114)
			(end 0.299974 -0.150114)
			(stroke
				(width 0.1)
				(type default)
			)
			(layer "F.Fab")
		)
		(fp_line
			(start 0.299974 0.150114)
			(end -0.299974 0.150114)
			(stroke
				(width 0.1)
				(type default)
			)
			(layer "F.Fab")
		)
		(fp_line
			(start -0.299974 0.150114)
			(end -0.299974 -0.150114)
			(stroke
				(width 0.1)
				(type default)
			)
			(layer "F.Fab")
		)
		(pad "1" smd rect
			(at -0.2667 0 90)
			(size 0.3048 0.381)
			(layers "F.Cu" "F.Mask" "F.Paste")
			(net "P5E_PEX3_STN7_TX_DN<123>")
		)
		(pad "2" smd rect
			(at 0.2667 0 90)
			(size 0.3048 0.381)
			(layers "F.Cu" "F.Mask" "F.Paste")
			(net "P5E_PEX3_STN7_TX_C_DN<123>")
		)
	)
	(footprint ""
		(layer "F.Cu")
		(at 16.785336 -277.280624 180)
		(property "Reference" "R776"
			(at 0 0 180)
			(layer "F.SilkS")
			(hide yes)
			(effects
				(font
					(size 1.27 1.27)
				)
			)
		)
		(property "Value" ""
			(at 0 0 180)
			(layer "F.Fab")
			(effects
				(font
					(size 1.27 1.27)
				)
			)
		)
		(duplicate_pad_numbers_are_jumpers no)
		(fp_line
			(start 0.7874 0.4064)
			(end -0.7874 0.4064)
			(stroke
				(width 0.1524)
				(type default)
			)
			(layer "F.SilkS")
		)
		(fp_line
			(start 0.7874 -0.4064)
			(end 0.7874 0.4064)
			(stroke
				(width 0.1524)
				(type default)
			)
			(layer "F.SilkS")
		)
		(fp_line
			(start -0.7874 0.4064)
			(end -0.7874 -0.4064)
			(stroke
				(width 0.1524)
				(type default)
			)
			(layer "F.SilkS")
		)
		(fp_line
			(start -0.7874 -0.4064)
			(end 0.7874 -0.4064)
			(stroke
				(width 0.1524)
				(type default)
			)
			(layer "F.SilkS")
		)
		(fp_line
			(start 0.67945 0.3048)
			(end 0.120396 0.3048)
			(stroke
				(width 0.1)
				(type default)
			)
			(layer "F.Fab")
		)
		(fp_line
			(start 0.67945 -0.3048)
			(end 0.67945 0.3048)
			(stroke
				(width 0.1)
				(type default)
			)
			(layer "F.Fab")
		)
		(fp_line
			(start 0.12065 -0.2794)
			(end 0.12065 -0.3048)
			(stroke
				(width 0.1)
				(type default)
			)
			(layer "F.Fab")
		)
		(fp_line
			(start 0.12065 -0.3048)
			(end 0.67945 -0.3048)
			(stroke
				(width 0.1)
				(type default)
			)
			(layer "F.Fab")
		)
		(fp_line
			(start 0.120396 0.3048)
			(end 0.120396 0.2794)
			(stroke
				(width 0.1)
				(type default)
			)
			(layer "F.Fab")
		)
		(fp_line
			(start 0.120396 0.2794)
			(end -0.12065 0.2794)
			(stroke
				(width 0.1)
				(type default)
			)
			(layer "F.Fab")
		)
		(fp_line
			(start -0.12065 0.3048)
			(end -0.67945 0.3048)
			(stroke
				(width 0.1)
				(type default)
			)
			(layer "F.Fab")
		)
		(fp_line
			(start -0.12065 0.2794)
			(end -0.12065 0.3048)
			(stroke
				(width 0.1)
				(type default)
			)
			(layer "F.Fab")
		)
		(fp_line
			(start -0.12065 -0.2794)
			(end 0.12065 -0.2794)
			(stroke
				(width 0.1)
				(type default)
			)
			(layer "F.Fab")
		)
		(fp_line
			(start -0.12065 -0.305054)
			(end -0.12065 -0.2794)
			(stroke
				(width 0.1)
				(type default)
			)
			(layer "F.Fab")
		)
		(fp_line
			(start -0.67945 0.3048)
			(end -0.67945 -0.305054)
			(stroke
				(width 0.1)
				(type default)
			)
			(layer "F.Fab")
		)
		(fp_line
			(start -0.67945 -0.305054)
			(end -0.12065 -0.305054)
			(stroke
				(width 0.1)
				(type default)
			)
			(layer "F.Fab")
		)
		(pad "1" smd circle
			(at -0.40005 0 180)
			(size 0 0)
			(layers "F.Cu" "F.Mask" "F.Paste")
			(net "SMB_BIC_I2C6_MUX_PEX_ADC_R_SDA")
		)
		(pad "2" smd circle
			(at 0.40005 0 180)
			(size 0 0)
			(layers "F.Cu" "F.Mask" "F.Paste")
			(net "SMB_PEX0_P1V25_ADC_SDA")
		)
	)
	(footprint ""
		(layer "F.Cu")
		(at 214.884 -228.6 -90)
		(property "Reference" "R6305"
			(at 0 0 270)
			(layer "F.SilkS")
			(hide yes)
			(effects
				(font
					(size 1.27 1.27)
				)
			)
		)
		(property "Value" ""
			(at 0 0 270)
			(layer "F.Fab")
			(effects
				(font
					(size 1.27 1.27)
				)
			)
		)
		(duplicate_pad_numbers_are_jumpers no)
		(fp_line
			(start -0.7874 0.4064)
			(end -0.7874 -0.4064)
			(stroke
				(width 0.1524)
				(type default)
			)
			(layer "F.SilkS")
		)
		(fp_line
			(start 0.7874 0.4064)
			(end -0.7874 0.4064)
			(stroke
				(width 0.1524)
				(type default)
			)
			(layer "F.SilkS")
		)
		(fp_line
			(start -0.7874 -0.4064)
			(end 0.7874 -0.4064)
			(stroke
				(width 0.1524)
				(type default)
			)
			(layer "F.SilkS")
		)
		(fp_line
			(start 0.7874 -0.4064)
			(end 0.7874 0.4064)
			(stroke
				(width 0.1524)
				(type default)
			)
			(layer "F.SilkS")
		)
		(fp_line
			(start -0.67945 0.3048)
			(end -0.67945 -0.305054)
			(stroke
				(width 0.1)
				(type default)
			)
			(layer "F.Fab")
		)
		(fp_line
			(start -0.12065 0.3048)
			(end -0.67945 0.3048)
			(stroke
				(width 0.1)
				(type default)
			)
			(layer "F.Fab")
		)
		(fp_line
			(start 0.120396 0.3048)
			(end 0.120396 0.2794)
			(stroke
				(width 0.1)
				(type default)
			)
			(layer "F.Fab")
		)
		(fp_line
			(start 0.67945 0.3048)
			(end 0.120396 0.3048)
			(stroke
				(width 0.1)
				(type default)
			)
			(layer "F.Fab")
		)
		(fp_line
			(start -0.12065 0.2794)
			(end -0.12065 0.3048)
			(stroke
				(width 0.1)
				(type default)
			)
			(layer "F.Fab")
		)
		(fp_line
			(start 0.120396 0.2794)
			(end -0.12065 0.2794)
			(stroke
				(width 0.1)
				(type default)
			)
			(layer "F.Fab")
		)
		(fp_line
			(start -0.12065 -0.2794)
			(end 0.12065 -0.2794)
			(stroke
				(width 0.1)
				(type default)
			)
			(layer "F.Fab")
		)
		(fp_line
			(start 0.12065 -0.2794)
			(end 0.12065 -0.3048)
			(stroke
				(width 0.1)
				(type default)
			)
			(layer "F.Fab")
		)
		(fp_line
			(start 0.12065 -0.3048)
			(end 0.67945 -0.3048)
			(stroke
				(width 0.1)
				(type default)
			)
			(layer "F.Fab")
		)
		(fp_line
			(start 0.67945 -0.3048)
			(end 0.67945 0.3048)
			(stroke
				(width 0.1)
				(type default)
			)
			(layer "F.Fab")
		)
		(fp_line
			(start -0.67945 -0.305054)
			(end -0.12065 -0.305054)
			(stroke
				(width 0.1)
				(type default)
			)
			(layer "F.Fab")
		)
		(fp_line
			(start -0.12065 -0.305054)
			(end -0.12065 -0.2794)
			(stroke
				(width 0.1)
				(type default)
			)
			(layer "F.Fab")
		)
		(pad "1" smd circle
			(at -0.40005 0 270)
			(size 0 0)
			(layers "F.Cu" "F.Mask" "F.Paste")
			(net "PRSNT_DBV2_SLIMSAS_R")
		)
		(pad "2" smd circle
			(at 0.40005 0 270)
			(size 0 0)
			(layers "F.Cu" "F.Mask" "F.Paste")
			(net "GND")
		)
	)
	(footprint ""
		(layer "F.Cu")
		(at 226.546664 -204.44206 90)
		(property "Reference" "R5279"
			(at 0 0 90)
			(layer "F.SilkS")
			(hide yes)
			(effects
				(font
					(size 1.27 1.27)
				)
			)
		)
		(property "Value" ""
			(at 0 0 90)
			(layer "F.Fab")
			(effects
				(font
					(size 1.27 1.27)
				)
			)
		)
		(duplicate_pad_numbers_are_jumpers no)
		(fp_line
			(start 0.7874 -0.4064)
			(end 0.7874 0.4064)
			(stroke
				(width 0.1524)
				(type default)
			)
			(layer "F.SilkS")
		)
		(fp_line
			(start -0.7874 -0.4064)
			(end 0.7874 -0.4064)
			(stroke
				(width 0.1524)
				(type default)
			)
			(layer "F.SilkS")
		)
		(fp_line
			(start 0.7874 0.4064)
			(end -0.7874 0.4064)
			(stroke
				(width 0.1524)
				(type default)
			)
			(layer "F.SilkS")
		)
		(fp_line
			(start -0.7874 0.4064)
			(end -0.7874 -0.4064)
			(stroke
				(width 0.1524)
				(type default)
			)
			(layer "F.SilkS")
		)
		(fp_line
			(start -0.12065 -0.305054)
			(end -0.12065 -0.2794)
			(stroke
				(width 0.1)
				(type default)
			)
			(layer "F.Fab")
		)
		(fp_line
			(start -0.67945 -0.305054)
			(end -0.12065 -0.305054)
			(stroke
				(width 0.1)
				(type default)
			)
			(layer "F.Fab")
		)
		(fp_line
			(start 0.67945 -0.3048)
			(end 0.67945 0.3048)
			(stroke
				(width 0.1)
				(type default)
			)
			(layer "F.Fab")
		)
		(fp_line
			(start 0.12065 -0.3048)
			(end 0.67945 -0.3048)
			(stroke
				(width 0.1)
				(type default)
			)
			(layer "F.Fab")
		)
		(fp_line
			(start 0.12065 -0.2794)
			(end 0.12065 -0.3048)
			(stroke
				(width 0.1)
				(type default)
			)
			(layer "F.Fab")
		)
		(fp_line
			(start -0.12065 -0.2794)
			(end 0.12065 -0.2794)
			(stroke
				(width 0.1)
				(type default)
			)
			(layer "F.Fab")
		)
		(fp_line
			(start 0.120396 0.2794)
			(end -0.12065 0.2794)
			(stroke
				(width 0.1)
				(type default)
			)
			(layer "F.Fab")
		)
		(fp_line
			(start -0.12065 0.2794)
			(end -0.12065 0.3048)
			(stroke
				(width 0.1)
				(type default)
			)
			(layer "F.Fab")
		)
		(fp_line
			(start 0.67945 0.3048)
			(end 0.120396 0.3048)
			(stroke
				(width 0.1)
				(type default)
			)
			(layer "F.Fab")
		)
		(fp_line
			(start 0.120396 0.3048)
			(end 0.120396 0.2794)
			(stroke
				(width 0.1)
				(type default)
			)
			(layer "F.Fab")
		)
		(fp_line
			(start -0.12065 0.3048)
			(end -0.67945 0.3048)
			(stroke
				(width 0.1)
				(type default)
			)
			(layer "F.Fab")
		)
		(fp_line
			(start -0.67945 0.3048)
			(end -0.67945 -0.305054)
			(stroke
				(width 0.1)
				(type default)
			)
			(layer "F.Fab")
		)
		(pad "1" smd circle
			(at -0.40005 0 90)
			(size 0 0)
			(layers "F.Cu" "F.Mask" "F.Paste")
			(net "JTAG_BIC_TDI_R")
		)
		(pad "2" smd circle
			(at 0.40005 0 90)
			(size 0 0)
			(layers "F.Cu" "F.Mask" "F.Paste")
			(net "JTAG_BIC_TDI")
		)
	)
	(footprint ""
		(layer "F.Cu")
		(at 196.639434 -158.219648)
		(property "Reference" "R161"
			(at 0 0 0)
			(layer "F.SilkS")
			(hide yes)
			(effects
				(font
					(size 1.27 1.27)
				)
			)
		)
		(property "Value" ""
			(at 0 0 0)
			(layer "F.Fab")
			(effects
				(font
					(size 1.27 1.27)
				)
			)
		)
		(duplicate_pad_numbers_are_jumpers no)
		(fp_line
			(start -0.7874 -0.4064)
			(end 0.7874 -0.4064)
			(stroke
				(width 0.1524)
				(type default)
			)
			(layer "F.SilkS")
		)
		(fp_line
			(start -0.7874 0.4064)
			(end -0.7874 -0.4064)
			(stroke
				(width 0.1524)
				(type default)
			)
			(layer "F.SilkS")
		)
		(fp_line
			(start 0.7874 -0.4064)
			(end 0.7874 0.4064)
			(stroke
				(width 0.1524)
				(type default)
			)
			(layer "F.SilkS")
		)
		(fp_line
			(start 0.7874 0.4064)
			(end -0.7874 0.4064)
			(stroke
				(width 0.1524)
				(type default)
			)
			(layer "F.SilkS")
		)
		(fp_line
			(start -0.67945 -0.305054)
			(end -0.12065 -0.305054)
			(stroke
				(width 0.1)
				(type default)
			)
			(layer "F.Fab")
		)
		(fp_line
			(start -0.67945 0.3048)
			(end -0.67945 -0.305054)
			(stroke
				(width 0.1)
				(type default)
			)
			(layer "F.Fab")
		)
		(fp_line
			(start -0.12065 -0.305054)
			(end -0.12065 -0.2794)
			(stroke
				(width 0.1)
				(type default)
			)
			(layer "F.Fab")
		)
		(fp_line
			(start -0.12065 -0.2794)
			(end 0.12065 -0.2794)
			(stroke
				(width 0.1)
				(type default)
			)
			(layer "F.Fab")
		)
		(fp_line
			(start -0.12065 0.2794)
			(end -0.12065 0.3048)
			(stroke
				(width 0.1)
				(type default)
			)
			(layer "F.Fab")
		)
		(fp_line
			(start -0.12065 0.3048)
			(end -0.67945 0.3048)
			(stroke
				(width 0.1)
				(type default)
			)
			(layer "F.Fab")
		)
		(fp_line
			(start 0.120396 0.2794)
			(end -0.12065 0.2794)
			(stroke
				(width 0.1)
				(type default)
			)
			(layer "F.Fab")
		)
		(fp_line
			(start 0.120396 0.3048)
			(end 0.120396 0.2794)
			(stroke
				(width 0.1)
				(type default)
			)
			(layer "F.Fab")
		)
		(fp_line
			(start 0.12065 -0.3048)
			(end 0.67945 -0.3048)
			(stroke
				(width 0.1)
				(type default)
			)
			(layer "F.Fab")
		)
		(fp_line
			(start 0.12065 -0.2794)
			(end 0.12065 -0.3048)
			(stroke
				(width 0.1)
				(type default)
			)
			(layer "F.Fab")
		)
		(fp_line
			(start 0.67945 -0.3048)
			(end 0.67945 0.3048)
			(stroke
				(width 0.1)
				(type default)
			)
			(layer "F.Fab")
		)
		(fp_line
			(start 0.67945 0.3048)
			(end 0.120396 0.3048)
			(stroke
				(width 0.1)
				(type default)
			)
			(layer "F.Fab")
		)
		(pad "1" smd circle
			(at -0.40005 0)
			(size 0 0)
			(layers "F.Cu" "F.Mask" "F.Paste")
			(net "PRSNTB3_NIC3_N")
		)
		(pad "2" smd circle
			(at 0.40005 0)
			(size 0 0)
			(layers "F.Cu" "F.Mask" "F.Paste")
			(net "P3V3_AUX")
		)
	)
	(footprint ""
		(layer "F.Cu")
		(at 319.609724 -350.098614 90)
		(property "Reference" "C544"
			(at 0 0 90)
			(layer "F.SilkS")
			(hide yes)
			(effects
				(font
					(size 1.27 1.27)
				)
			)
		)
		(property "Value" ""
			(at 0 0 90)
			(layer "F.Fab")
			(effects
				(font
					(size 1.27 1.27)
				)
			)
		)
		(duplicate_pad_numbers_are_jumpers no)
		(fp_line
			(start 0.299974 -0.150114)
			(end 0.299974 0.150114)
			(stroke
				(width 0.1)
				(type default)
			)
			(layer "F.Fab")
		)
		(fp_line
			(start -0.299974 -0.150114)
			(end 0.299974 -0.150114)
			(stroke
				(width 0.1)
				(type default)
			)
			(layer "F.Fab")
		)
		(fp_line
			(start 0.299974 0.150114)
			(end -0.299974 0.150114)
			(stroke
				(width 0.1)
				(type default)
			)
			(layer "F.Fab")
		)
		(fp_line
			(start -0.299974 0.150114)
			(end -0.299974 -0.150114)
			(stroke
				(width 0.1)
				(type default)
			)
			(layer "F.Fab")
		)
		(pad "1" smd rect
			(at -0.2667 0 90)
			(size 0.3048 0.381)
			(layers "F.Cu" "F.Mask" "F.Paste")
			(net "P5E_PEX2_STN5_TX_DN<83>")
		)
		(pad "2" smd rect
			(at 0.2667 0 90)
			(size 0.3048 0.381)
			(layers "F.Cu" "F.Mask" "F.Paste")
			(net "P5E_PEX2_STN5_TX_C_DN<83>")
		)
	)
	(footprint ""
		(layer "F.Cu")
		(at 352.39452 -303.649634 90)
		(property "Reference" "PC183"
			(at 0 0 90)
			(layer "F.SilkS")
			(hide yes)
			(effects
				(font
					(size 1.27 1.27)
				)
			)
		)
		(property "Value" ""
			(at 0 0 90)
			(layer "F.Fab")
			(effects
				(font
					(size 1.27 1.27)
				)
			)
		)
		(duplicate_pad_numbers_are_jumpers no)
		(fp_line
			(start 1.524 -0.762)
			(end 1.524 0.762)
			(stroke
				(width 0.1524)
				(type default)
			)
			(layer "F.SilkS")
		)
		(fp_line
			(start -1.524 -0.762)
			(end 1.524 -0.762)
			(stroke
				(width 0.1524)
				(type default)
			)
			(layer "F.SilkS")
		)
		(fp_line
			(start 1.524 0.762)
			(end -1.524 0.762)
			(stroke
				(width 0.1524)
				(type default)
			)
			(layer "F.SilkS")
		)
		(fp_line
			(start -1.524 0.762)
			(end -1.524 -0.762)
			(stroke
				(width 0.1524)
				(type default)
			)
			(layer "F.SilkS")
		)
		(fp_line
			(start 1.1049 -0.724916)
			(end -1.1049 -0.724916)
			(stroke
				(width 0.1)
				(type default)
			)
			(layer "F.Fab")
		)
		(fp_line
			(start -1.1049 -0.724916)
			(end -1.1049 0.724916)
			(stroke
				(width 0.1)
				(type default)
			)
			(layer "F.Fab")
		)
		(fp_line
			(start 1.1049 0.724916)
			(end 1.1049 -0.724916)
			(stroke
				(width 0.1)
				(type default)
			)
			(layer "F.Fab")
		)
		(fp_line
			(start -1.1049 0.724916)
			(end 1.1049 0.724916)
			(stroke
				(width 0.1)
				(type default)
			)
			(layer "F.Fab")
		)
		(pad "1" smd rect
			(at -0.889 0 270)
			(size 1.016 1.27)
			(layers "F.Cu" "F.Mask" "F.Paste")
			(net "P0V8_PEX3")
		)
		(pad "2" smd rect
			(at 0.889 0 270)
			(size 1.016 1.27)
			(layers "F.Cu" "F.Mask" "F.Paste")
			(net "GND")
		)
	)
	(footprint ""
		(layer "F.Cu")
		(at 267.569442 -256.888234 -90)
		(property "Reference" "R4583"
			(at 0 0 270)
			(layer "F.SilkS")
			(hide yes)
			(effects
				(font
					(size 1.27 1.27)
				)
			)
		)
		(property "Value" ""
			(at 0 0 270)
			(layer "F.Fab")
			(effects
				(font
					(size 1.27 1.27)
				)
			)
		)
		(duplicate_pad_numbers_are_jumpers no)
		(fp_line
			(start -0.7874 0.4064)
			(end -0.7874 -0.4064)
			(stroke
				(width 0.1524)
				(type default)
			)
			(layer "F.SilkS")
		)
		(fp_line
			(start 0.7874 0.4064)
			(end -0.7874 0.4064)
			(stroke
				(width 0.1524)
				(type default)
			)
			(layer "F.SilkS")
		)
		(fp_line
			(start -0.7874 -0.4064)
			(end 0.7874 -0.4064)
			(stroke
				(width 0.1524)
				(type default)
			)
			(layer "F.SilkS")
		)
		(fp_line
			(start 0.7874 -0.4064)
			(end 0.7874 0.4064)
			(stroke
				(width 0.1524)
				(type default)
			)
			(layer "F.SilkS")
		)
		(fp_line
			(start -0.67945 0.3048)
			(end -0.67945 -0.305054)
			(stroke
				(width 0.1)
				(type default)
			)
			(layer "F.Fab")
		)
		(fp_line
			(start -0.12065 0.3048)
			(end -0.67945 0.3048)
			(stroke
				(width 0.1)
				(type default)
			)
			(layer "F.Fab")
		)
		(fp_line
			(start 0.120396 0.3048)
			(end 0.120396 0.2794)
			(stroke
				(width 0.1)
				(type default)
			)
			(layer "F.Fab")
		)
		(fp_line
			(start 0.67945 0.3048)
			(end 0.120396 0.3048)
			(stroke
				(width 0.1)
				(type default)
			)
			(layer "F.Fab")
		)
		(fp_line
			(start -0.12065 0.2794)
			(end -0.12065 0.3048)
			(stroke
				(width 0.1)
				(type default)
			)
			(layer "F.Fab")
		)
		(fp_line
			(start 0.120396 0.2794)
			(end -0.12065 0.2794)
			(stroke
				(width 0.1)
				(type default)
			)
			(layer "F.Fab")
		)
		(fp_line
			(start -0.12065 -0.2794)
			(end 0.12065 -0.2794)
			(stroke
				(width 0.1)
				(type default)
			)
			(layer "F.Fab")
		)
		(fp_line
			(start 0.12065 -0.2794)
			(end 0.12065 -0.3048)
			(stroke
				(width 0.1)
				(type default)
			)
			(layer "F.Fab")
		)
		(fp_line
			(start 0.12065 -0.3048)
			(end 0.67945 -0.3048)
			(stroke
				(width 0.1)
				(type default)
			)
			(layer "F.Fab")
		)
		(fp_line
			(start 0.67945 -0.3048)
			(end 0.67945 0.3048)
			(stroke
				(width 0.1)
				(type default)
			)
			(layer "F.Fab")
		)
		(fp_line
			(start -0.67945 -0.305054)
			(end -0.12065 -0.305054)
			(stroke
				(width 0.1)
				(type default)
			)
			(layer "F.Fab")
		)
		(fp_line
			(start -0.12065 -0.305054)
			(end -0.12065 -0.2794)
			(stroke
				(width 0.1)
				(type default)
			)
			(layer "F.Fab")
		)
		(pad "1" smd circle
			(at -0.40005 0 270)
			(size 0 0)
			(layers "F.Cu" "F.Mask" "F.Paste")
			(net "PCEPLL5_VDDA18_PEX2")
		)
		(pad "2" smd circle
			(at 0.40005 0 270)
			(size 0 0)
			(layers "F.Cu" "F.Mask" "F.Paste")
			(net "PCEPLL5_VDDA18_PEX2_R")
		)
	)
	(footprint ""
		(layer "F.Cu")
		(at 376.936 -187.833)
		(property "Reference" "R4652"
			(at 0 0 0)
			(layer "F.SilkS")
			(hide yes)
			(effects
				(font
					(size 1.27 1.27)
				)
			)
		)
		(property "Value" ""
			(at 0 0 0)
			(layer "F.Fab")
			(effects
				(font
					(size 1.27 1.27)
				)
			)
		)
		(duplicate_pad_numbers_are_jumpers no)
		(fp_line
			(start -0.7874 -0.4064)
			(end 0.7874 -0.4064)
			(stroke
				(width 0.1524)
				(type default)
			)
			(layer "F.SilkS")
		)
		(fp_line
			(start -0.7874 0.4064)
			(end -0.7874 -0.4064)
			(stroke
				(width 0.1524)
				(type default)
			)
			(layer "F.SilkS")
		)
		(fp_line
			(start 0.7874 -0.4064)
			(end 0.7874 0.4064)
			(stroke
				(width 0.1524)
				(type default)
			)
			(layer "F.SilkS")
		)
		(fp_line
			(start 0.7874 0.4064)
			(end -0.7874 0.4064)
			(stroke
				(width 0.1524)
				(type default)
			)
			(layer "F.SilkS")
		)
		(fp_line
			(start -0.67945 -0.305054)
			(end -0.12065 -0.305054)
			(stroke
				(width 0.1)
				(type default)
			)
			(layer "F.Fab")
		)
		(fp_line
			(start -0.67945 0.3048)
			(end -0.67945 -0.305054)
			(stroke
				(width 0.1)
				(type default)
			)
			(layer "F.Fab")
		)
		(fp_line
			(start -0.12065 -0.305054)
			(end -0.12065 -0.2794)
			(stroke
				(width 0.1)
				(type default)
			)
			(layer "F.Fab")
		)
		(fp_line
			(start -0.12065 -0.2794)
			(end 0.12065 -0.2794)
			(stroke
				(width 0.1)
				(type default)
			)
			(layer "F.Fab")
		)
		(fp_line
			(start -0.12065 0.2794)
			(end -0.12065 0.3048)
			(stroke
				(width 0.1)
				(type default)
			)
			(layer "F.Fab")
		)
		(fp_line
			(start -0.12065 0.3048)
			(end -0.67945 0.3048)
			(stroke
				(width 0.1)
				(type default)
			)
			(layer "F.Fab")
		)
		(fp_line
			(start 0.120396 0.2794)
			(end -0.12065 0.2794)
			(stroke
				(width 0.1)
				(type default)
			)
			(layer "F.Fab")
		)
		(fp_line
			(start 0.120396 0.3048)
			(end 0.120396 0.2794)
			(stroke
				(width 0.1)
				(type default)
			)
			(layer "F.Fab")
		)
		(fp_line
			(start 0.12065 -0.3048)
			(end 0.67945 -0.3048)
			(stroke
				(width 0.1)
				(type default)
			)
			(layer "F.Fab")
		)
		(fp_line
			(start 0.12065 -0.2794)
			(end 0.12065 -0.3048)
			(stroke
				(width 0.1)
				(type default)
			)
			(layer "F.Fab")
		)
		(fp_line
			(start 0.67945 -0.3048)
			(end 0.67945 0.3048)
			(stroke
				(width 0.1)
				(type default)
			)
			(layer "F.Fab")
		)
		(fp_line
			(start 0.67945 0.3048)
			(end 0.120396 0.3048)
			(stroke
				(width 0.1)
				(type default)
			)
			(layer "F.Fab")
		)
		(pad "1" smd circle
			(at -0.40005 0)
			(size 0 0)
			(layers "F.Cu" "F.Mask" "F.Paste")
			(net "RST_PEX_NIC1_PERST_N")
		)
		(pad "2" smd circle
			(at 0.40005 0)
			(size 0 0)
			(layers "F.Cu" "F.Mask" "F.Paste")
			(net "RST_PEX_NIC1_PERST_R_N")
		)
	)
	(footprint ""
		(layer "F.Cu")
		(at 433.00904 -26.03373)
		(property "Reference" "R4082"
			(at 0 0 0)
			(layer "F.SilkS")
			(hide yes)
			(effects
				(font
					(size 1.27 1.27)
				)
			)
		)
		(property "Value" ""
			(at 0 0 0)
			(layer "F.Fab")
			(effects
				(font
					(size 1.27 1.27)
				)
			)
		)
		(duplicate_pad_numbers_are_jumpers no)
		(fp_line
			(start -0.7874 -0.4064)
			(end 0.7874 -0.4064)
			(stroke
				(width 0.1524)
				(type default)
			)
			(layer "F.SilkS")
		)
		(fp_line
			(start -0.7874 0.4064)
			(end -0.7874 -0.4064)
			(stroke
				(width 0.1524)
				(type default)
			)
			(layer "F.SilkS")
		)
		(fp_line
			(start 0.7874 -0.4064)
			(end 0.7874 0.4064)
			(stroke
				(width 0.1524)
				(type default)
			)
			(layer "F.SilkS")
		)
		(fp_line
			(start 0.7874 0.4064)
			(end -0.7874 0.4064)
			(stroke
				(width 0.1524)
				(type default)
			)
			(layer "F.SilkS")
		)
		(fp_line
			(start -0.67945 -0.305054)
			(end -0.12065 -0.305054)
			(stroke
				(width 0.1)
				(type default)
			)
			(layer "F.Fab")
		)
		(fp_line
			(start -0.67945 0.3048)
			(end -0.67945 -0.305054)
			(stroke
				(width 0.1)
				(type default)
			)
			(layer "F.Fab")
		)
		(fp_line
			(start -0.12065 -0.305054)
			(end -0.12065 -0.2794)
			(stroke
				(width 0.1)
				(type default)
			)
			(layer "F.Fab")
		)
		(fp_line
			(start -0.12065 -0.2794)
			(end 0.12065 -0.2794)
			(stroke
				(width 0.1)
				(type default)
			)
			(layer "F.Fab")
		)
		(fp_line
			(start -0.12065 0.2794)
			(end -0.12065 0.3048)
			(stroke
				(width 0.1)
				(type default)
			)
			(layer "F.Fab")
		)
		(fp_line
			(start -0.12065 0.3048)
			(end -0.67945 0.3048)
			(stroke
				(width 0.1)
				(type default)
			)
			(layer "F.Fab")
		)
		(fp_line
			(start 0.120396 0.2794)
			(end -0.12065 0.2794)
			(stroke
				(width 0.1)
				(type default)
			)
			(layer "F.Fab")
		)
		(fp_line
			(start 0.120396 0.3048)
			(end 0.120396 0.2794)
			(stroke
				(width 0.1)
				(type default)
			)
			(layer "F.Fab")
		)
		(fp_line
			(start 0.12065 -0.3048)
			(end 0.67945 -0.3048)
			(stroke
				(width 0.1)
				(type default)
			)
			(layer "F.Fab")
		)
		(fp_line
			(start 0.12065 -0.2794)
			(end 0.12065 -0.3048)
			(stroke
				(width 0.1)
				(type default)
			)
			(layer "F.Fab")
		)
		(fp_line
			(start 0.67945 -0.3048)
			(end 0.67945 0.3048)
			(stroke
				(width 0.1)
				(type default)
			)
			(layer "F.Fab")
		)
		(fp_line
			(start 0.67945 0.3048)
			(end 0.120396 0.3048)
			(stroke
				(width 0.1)
				(type default)
			)
			(layer "F.Fab")
		)
		(pad "1" smd circle
			(at -0.40005 0)
			(size 0 0)
			(layers "F.Cu" "F.Mask" "F.Paste")
			(net "P3V3_AUX")
		)
		(pad "2" smd circle
			(at 0.40005 0)
			(size 0 0)
			(layers "F.Cu" "F.Mask" "F.Paste")
			(net "PRSNT_SSD15_R_N")
		)
	)
	(footprint ""
		(layer "F.Cu")
		(at 28.406344 -250.070874 -90)
		(property "Reference" "R1126"
			(at 0 0 270)
			(layer "F.SilkS")
			(hide yes)
			(effects
				(font
					(size 1.27 1.27)
				)
			)
		)
		(property "Value" ""
			(at 0 0 270)
			(layer "F.Fab")
			(effects
				(font
					(size 1.27 1.27)
				)
			)
		)
		(duplicate_pad_numbers_are_jumpers no)
		(fp_line
			(start -0.7874 0.4064)
			(end -0.7874 -0.4064)
			(stroke
				(width 0.1524)
				(type default)
			)
			(layer "F.SilkS")
		)
		(fp_line
			(start 0.7874 0.4064)
			(end -0.7874 0.4064)
			(stroke
				(width 0.1524)
				(type default)
			)
			(layer "F.SilkS")
		)
		(fp_line
			(start -0.7874 -0.4064)
			(end 0.7874 -0.4064)
			(stroke
				(width 0.1524)
				(type default)
			)
			(layer "F.SilkS")
		)
		(fp_line
			(start 0.7874 -0.4064)
			(end 0.7874 0.4064)
			(stroke
				(width 0.1524)
				(type default)
			)
			(layer "F.SilkS")
		)
		(fp_line
			(start -0.67945 0.3048)
			(end -0.67945 -0.305054)
			(stroke
				(width 0.1)
				(type default)
			)
			(layer "F.Fab")
		)
		(fp_line
			(start -0.12065 0.3048)
			(end -0.67945 0.3048)
			(stroke
				(width 0.1)
				(type default)
			)
			(layer "F.Fab")
		)
		(fp_line
			(start 0.120396 0.3048)
			(end 0.120396 0.2794)
			(stroke
				(width 0.1)
				(type default)
			)
			(layer "F.Fab")
		)
		(fp_line
			(start 0.67945 0.3048)
			(end 0.120396 0.3048)
			(stroke
				(width 0.1)
				(type default)
			)
			(layer "F.Fab")
		)
		(fp_line
			(start -0.12065 0.2794)
			(end -0.12065 0.3048)
			(stroke
				(width 0.1)
				(type default)
			)
			(layer "F.Fab")
		)
		(fp_line
			(start 0.120396 0.2794)
			(end -0.12065 0.2794)
			(stroke
				(width 0.1)
				(type default)
			)
			(layer "F.Fab")
		)
		(fp_line
			(start -0.12065 -0.2794)
			(end 0.12065 -0.2794)
			(stroke
				(width 0.1)
				(type default)
			)
			(layer "F.Fab")
		)
		(fp_line
			(start 0.12065 -0.2794)
			(end 0.12065 -0.3048)
			(stroke
				(width 0.1)
				(type default)
			)
			(layer "F.Fab")
		)
		(fp_line
			(start 0.12065 -0.3048)
			(end 0.67945 -0.3048)
			(stroke
				(width 0.1)
				(type default)
			)
			(layer "F.Fab")
		)
		(fp_line
			(start 0.67945 -0.3048)
			(end 0.67945 0.3048)
			(stroke
				(width 0.1)
				(type default)
			)
			(layer "F.Fab")
		)
		(fp_line
			(start -0.67945 -0.305054)
			(end -0.12065 -0.305054)
			(stroke
				(width 0.1)
				(type default)
			)
			(layer "F.Fab")
		)
		(fp_line
			(start -0.12065 -0.305054)
			(end -0.12065 -0.2794)
			(stroke
				(width 0.1)
				(type default)
			)
			(layer "F.Fab")
		)
		(pad "1" smd circle
			(at -0.40005 0 270)
			(size 0 0)
			(layers "F.Cu" "F.Mask" "F.Paste")
			(net "PEX0_DBG_MODE3")
		)
		(pad "2" smd circle
			(at 0.40005 0 270)
			(size 0 0)
			(layers "F.Cu" "F.Mask" "F.Paste")
			(net "P1V8_PEX")
		)
	)
	(footprint ""
		(layer "F.Cu")
		(at 121.163588 -343.952322 90)
		(property "Reference" "C364"
			(at 0 0 90)
			(layer "F.SilkS")
			(hide yes)
			(effects
				(font
					(size 1.27 1.27)
				)
			)
		)
		(property "Value" ""
			(at 0 0 90)
			(layer "F.Fab")
			(effects
				(font
					(size 1.27 1.27)
				)
			)
		)
		(duplicate_pad_numbers_are_jumpers no)
		(fp_line
			(start 0.299974 -0.150114)
			(end 0.299974 0.150114)
			(stroke
				(width 0.1)
				(type default)
			)
			(layer "F.Fab")
		)
		(fp_line
			(start -0.299974 -0.150114)
			(end 0.299974 -0.150114)
			(stroke
				(width 0.1)
				(type default)
			)
			(layer "F.Fab")
		)
		(fp_line
			(start 0.299974 0.150114)
			(end -0.299974 0.150114)
			(stroke
				(width 0.1)
				(type default)
			)
			(layer "F.Fab")
		)
		(fp_line
			(start -0.299974 0.150114)
			(end -0.299974 -0.150114)
			(stroke
				(width 0.1)
				(type default)
			)
			(layer "F.Fab")
		)
		(pad "1" smd rect
			(at -0.2667 0 90)
			(size 0.3048 0.381)
			(layers "F.Cu" "F.Mask" "F.Paste")
			(net "P5E_PEX1_STN6_TX_DP<99>")
		)
		(pad "2" smd rect
			(at 0.2667 0 90)
			(size 0.3048 0.381)
			(layers "F.Cu" "F.Mask" "F.Paste")
			(net "P5E_PEX1_STN6_TX_C_DP<99>")
		)
	)
	(footprint ""
		(layer "F.Cu")
		(at 141.441932 -261.026402 180)
		(property "Reference" "C3244"
			(at 0 0 180)
			(layer "F.SilkS")
			(hide yes)
			(effects
				(font
					(size 1.27 1.27)
				)
			)
		)
		(property "Value" ""
			(at 0 0 180)
			(layer "F.Fab")
			(effects
				(font
					(size 1.27 1.27)
				)
			)
		)
		(duplicate_pad_numbers_are_jumpers no)
		(fp_line
			(start 1.2954 0.5842)
			(end -1.2954 0.5842)
			(stroke
				(width 0.1524)
				(type default)
			)
			(layer "F.SilkS")
		)
		(fp_line
			(start 1.2954 -0.5842)
			(end 1.2954 0.5842)
			(stroke
				(width 0.1524)
				(type default)
			)
			(layer "F.SilkS")
		)
		(fp_line
			(start -1.2954 0.5842)
			(end -1.2954 -0.5842)
			(stroke
				(width 0.1524)
				(type default)
			)
			(layer "F.SilkS")
		)
		(fp_line
			(start -1.2954 -0.5842)
			(end 1.2954 -0.5842)
			(stroke
				(width 0.1524)
				(type default)
			)
			(layer "F.SilkS")
		)
		(fp_line
			(start 1.1938 0.4064)
			(end 0.8636 0.4064)
			(stroke
				(width 0.1)
				(type default)
			)
			(layer "F.Fab")
		)
		(fp_line
			(start 1.1938 -0.4064)
			(end 1.1938 0.4064)
			(stroke
				(width 0.1)
				(type default)
			)
			(layer "F.Fab")
		)
		(fp_line
			(start 0.8636 0.4572)
			(end -0.8636 0.4572)
			(stroke
				(width 0.1)
				(type default)
			)
			(layer "F.Fab")
		)
		(fp_line
			(start 0.8636 0.4064)
			(end 0.8636 0.4572)
			(stroke
				(width 0.1)
				(type default)
			)
			(layer "F.Fab")
		)
		(fp_line
			(start 0.8636 -0.4064)
			(end 1.1938 -0.4064)
			(stroke
				(width 0.1)
				(type default)
			)
			(layer "F.Fab")
		)
		(fp_line
			(start 0.8636 -0.4572)
			(end 0.8636 -0.4064)
			(stroke
				(width 0.1)
				(type default)
			)
			(layer "F.Fab")
		)
		(fp_line
			(start -0.8636 0.4572)
			(end -0.8636 0.4064)
			(stroke
				(width 0.1)
				(type default)
			)
			(layer "F.Fab")
		)
		(fp_line
			(start -0.8636 0.4064)
			(end -1.1938 0.4064)
			(stroke
				(width 0.1)
				(type default)
			)
			(layer "F.Fab")
		)
		(fp_line
			(start -0.8636 -0.4064)
			(end -0.8636 -0.4572)
			(stroke
				(width 0.1)
				(type default)
			)
			(layer "F.Fab")
		)
		(fp_line
			(start -0.8636 -0.4572)
			(end 0.8636 -0.4572)
			(stroke
				(width 0.1)
				(type default)
			)
			(layer "F.Fab")
		)
		(fp_line
			(start -1.1938 0.4064)
			(end -1.1938 -0.4064)
			(stroke
				(width 0.1)
				(type default)
			)
			(layer "F.Fab")
		)
		(fp_line
			(start -1.1938 -0.4064)
			(end -0.8636 -0.4064)
			(stroke
				(width 0.1)
				(type default)
			)
			(layer "F.Fab")
		)
		(pad "1" smd rect
			(at -0.7366 0 90)
			(size 0.7112 0.8128)
			(layers "F.Cu" "F.Mask" "F.Paste")
			(net "P1V8_VDDA_PEX1")
		)
		(pad "2" smd rect
			(at 0.7366 0 90)
			(size 0.7112 0.8128)
			(layers "F.Cu" "F.Mask" "F.Paste")
			(net "GND")
		)
	)
	(footprint ""
		(layer "F.Cu")
		(at 17.839944 -70.52437 90)
		(property "Reference" "PC643"
			(at 0 0 90)
			(layer "F.SilkS")
			(hide yes)
			(effects
				(font
					(size 1.27 1.27)
				)
			)
		)
		(property "Value" ""
			(at 0 0 90)
			(layer "F.Fab")
			(effects
				(font
					(size 1.27 1.27)
				)
			)
		)
		(duplicate_pad_numbers_are_jumpers no)
		(fp_line
			(start 1.524 -0.762)
			(end 1.524 0.762)
			(stroke
				(width 0.1524)
				(type default)
			)
			(layer "F.SilkS")
		)
		(fp_line
			(start -1.524 -0.762)
			(end 1.524 -0.762)
			(stroke
				(width 0.1524)
				(type default)
			)
			(layer "F.SilkS")
		)
		(fp_line
			(start 1.524 0.762)
			(end -1.524 0.762)
			(stroke
				(width 0.1524)
				(type default)
			)
			(layer "F.SilkS")
		)
		(fp_line
			(start -1.524 0.762)
			(end -1.524 -0.762)
			(stroke
				(width 0.1524)
				(type default)
			)
			(layer "F.SilkS")
		)
		(fp_line
			(start 1.1049 -0.724916)
			(end -1.1049 -0.724916)
			(stroke
				(width 0.1)
				(type default)
			)
			(layer "F.Fab")
		)
		(fp_line
			(start -1.1049 -0.724916)
			(end -1.1049 0.724916)
			(stroke
				(width 0.1)
				(type default)
			)
			(layer "F.Fab")
		)
		(fp_line
			(start 1.1049 0.724916)
			(end 1.1049 -0.724916)
			(stroke
				(width 0.1)
				(type default)
			)
			(layer "F.Fab")
		)
		(fp_line
			(start -1.1049 0.724916)
			(end 1.1049 0.724916)
			(stroke
				(width 0.1)
				(type default)
			)
			(layer "F.Fab")
		)
		(pad "1" smd rect
			(at -0.889 0 270)
			(size 1.016 1.27)
			(layers "F.Cu" "F.Mask" "F.Paste")
			(net "P12V_SSD0_R")
		)
		(pad "2" smd rect
			(at 0.889 0 270)
			(size 1.016 1.27)
			(layers "F.Cu" "F.Mask" "F.Paste")
			(net "GND")
		)
	)
	(footprint ""
		(layer "F.Cu")
		(at 371.428518 -260.807708 90)
		(property "Reference" "R5802"
			(at 0 0 90)
			(layer "F.SilkS")
			(hide yes)
			(effects
				(font
					(size 1.27 1.27)
				)
			)
		)
		(property "Value" ""
			(at 0 0 90)
			(layer "F.Fab")
			(effects
				(font
					(size 1.27 1.27)
				)
			)
		)
		(duplicate_pad_numbers_are_jumpers no)
		(fp_line
			(start 0.7874 -0.4064)
			(end 0.7874 0.4064)
			(stroke
				(width 0.1524)
				(type default)
			)
			(layer "F.SilkS")
		)
		(fp_line
			(start -0.7874 -0.4064)
			(end 0.7874 -0.4064)
			(stroke
				(width 0.1524)
				(type default)
			)
			(layer "F.SilkS")
		)
		(fp_line
			(start 0.7874 0.4064)
			(end -0.7874 0.4064)
			(stroke
				(width 0.1524)
				(type default)
			)
			(layer "F.SilkS")
		)
		(fp_line
			(start -0.7874 0.4064)
			(end -0.7874 -0.4064)
			(stroke
				(width 0.1524)
				(type default)
			)
			(layer "F.SilkS")
		)
		(fp_line
			(start -0.12065 -0.305054)
			(end -0.12065 -0.2794)
			(stroke
				(width 0.1)
				(type default)
			)
			(layer "F.Fab")
		)
		(fp_line
			(start -0.67945 -0.305054)
			(end -0.12065 -0.305054)
			(stroke
				(width 0.1)
				(type default)
			)
			(layer "F.Fab")
		)
		(fp_line
			(start 0.67945 -0.3048)
			(end 0.67945 0.3048)
			(stroke
				(width 0.1)
				(type default)
			)
			(layer "F.Fab")
		)
		(fp_line
			(start 0.12065 -0.3048)
			(end 0.67945 -0.3048)
			(stroke
				(width 0.1)
				(type default)
			)
			(layer "F.Fab")
		)
		(fp_line
			(start 0.12065 -0.2794)
			(end 0.12065 -0.3048)
			(stroke
				(width 0.1)
				(type default)
			)
			(layer "F.Fab")
		)
		(fp_line
			(start -0.12065 -0.2794)
			(end 0.12065 -0.2794)
			(stroke
				(width 0.1)
				(type default)
			)
			(layer "F.Fab")
		)
		(fp_line
			(start 0.120396 0.2794)
			(end -0.12065 0.2794)
			(stroke
				(width 0.1)
				(type default)
			)
			(layer "F.Fab")
		)
		(fp_line
			(start -0.12065 0.2794)
			(end -0.12065 0.3048)
			(stroke
				(width 0.1)
				(type default)
			)
			(layer "F.Fab")
		)
		(fp_line
			(start 0.67945 0.3048)
			(end 0.120396 0.3048)
			(stroke
				(width 0.1)
				(type default)
			)
			(layer "F.Fab")
		)
		(fp_line
			(start 0.120396 0.3048)
			(end 0.120396 0.2794)
			(stroke
				(width 0.1)
				(type default)
			)
			(layer "F.Fab")
		)
		(fp_line
			(start -0.12065 0.3048)
			(end -0.67945 0.3048)
			(stroke
				(width 0.1)
				(type default)
			)
			(layer "F.Fab")
		)
		(fp_line
			(start -0.67945 0.3048)
			(end -0.67945 -0.305054)
			(stroke
				(width 0.1)
				(type default)
			)
			(layer "F.Fab")
		)
		(pad "1" smd circle
			(at -0.40005 0 90)
			(size 0 0)
			(layers "F.Cu" "F.Mask" "F.Paste")
			(net "PEX3_SYS_ERR_N_G")
		)
		(pad "2" smd circle
			(at 0.40005 0 90)
			(size 0 0)
			(layers "F.Cu" "F.Mask" "F.Paste")
			(net "PEX3_SYS_ERR_FPGA")
		)
	)
	(footprint ""
		(layer "F.Cu")
		(at 145.749772 -270.89989)
		(property "Reference" "H89"
			(at -9.468358 5.423154 0)
			(unlocked yes)
			(layer "F.SilkS")
			(effects
				(font
					(size 0.7874 0.5842)
					(thickness 0.1524)
				)
				(justify left)
			)
		)
		(property "Value" ""
			(at 0 0 0)
			(layer "F.Fab")
			(effects
				(font
					(size 1.27 1.27)
				)
			)
		)
		(duplicate_pad_numbers_are_jumpers no)
		(fp_arc
			(start -5.917438 -5.383022)
			(mid -0.133593 -7.998818)
			(end 5.734558 -5.578094)
			(stroke
				(width 0.1524)
				(type default)
			)
			(layer "F.SilkS")
		)
		(fp_arc
			(start 7.987284 -0.45212)
			(mid 7.996831 -0.22615)
			(end 7.999984 0)
			(stroke
				(width 0.1524)
				(type default)
			)
			(layer "F.SilkS")
		)
		(fp_arc
			(start 7.999984 0)
			(mid -0.877926 7.950904)
			(end -7.806436 -1.745996)
			(stroke
				(width 0.1524)
				(type default)
			)
			(layer "F.SilkS")
		)
		(fp_arc
			(start -6.001004 -5.290312)
			(mid -4.324075 -6.730651)
			(end -2.316988 -7.657084)
			(stroke
				(width 0.1524)
				(type default)
			)
			(layer "B.SilkS")
		)
		(fp_arc
			(start 1.529588 -7.85241)
			(mid 4.016762 -6.91843)
			(end 6.060948 -5.221478)
			(stroke
				(width 0.1524)
				(type default)
			)
			(layer "B.SilkS")
		)
		(fp_arc
			(start 7.813802 -1.71577)
			(mid 7.953308 -0.862922)
			(end 7.999984 0)
			(stroke
				(width 0.1524)
				(type default)
			)
			(layer "B.SilkS")
		)
		(fp_arc
			(start 7.999984 0)
			(mid 0.524857 7.982789)
			(end -7.93115 1.047496)
			(stroke
				(width 0.1524)
				(type default)
			)
			(layer "B.SilkS")
		)
		(fp_circle
			(center 0 0)
			(end 7.999984 0)
			(stroke
				(width 0.1)
				(type default)
			)
			(fill no)
			(layer "B.Fab")
		)
		(fp_circle
			(center 0 0)
			(end 7.999984 0)
			(stroke
				(width 0.1)
				(type default)
			)
			(fill no)
			(layer "F.Fab")
		)
		(pad "" np_thru_hole circle
			(at 0 0)
			(size 4.5212 4.5212)
			(drill 4.5212)
			(layers "*.Cu" "*.Mask")
			(clearance 0.381)
			(thermal_gap 0.381)
		)
		(pad "2" thru_hole circle
			(at 3.6322 0)
			(size 0.762 0.762)
			(drill 0.5588)
			(layers "*.Cu" "*.Mask")
			(remove_unused_layers no)
			(net "GND")
			(clearance 0.1524)
			(thermal_gap 0.1524)
		)
		(pad "3" thru_hole circle
			(at 2.568448 -2.568448)
			(size 0.762 0.762)
			(drill 0.5588)
			(layers "*.Cu" "*.Mask")
			(remove_unused_layers no)
			(net "GND")
			(clearance 0.1524)
			(thermal_gap 0.1524)
		)
		(pad "4" thru_hole circle
			(at 0 -3.6322)
			(size 0.762 0.762)
			(drill 0.5588)
			(layers "*.Cu" "*.Mask")
			(remove_unused_layers no)
			(net "GND")
			(clearance 0.1524)
			(thermal_gap 0.1524)
		)
		(pad "5" thru_hole circle
			(at -2.568448 -2.568448)
			(size 0.762 0.762)
			(drill 0.5588)
			(layers "*.Cu" "*.Mask")
			(remove_unused_layers no)
			(net "GND")
			(clearance 0.1524)
			(thermal_gap 0.1524)
		)
		(pad "6" thru_hole circle
			(at -3.6322 0)
			(size 0.762 0.762)
			(drill 0.5588)
			(layers "*.Cu" "*.Mask")
			(remove_unused_layers no)
			(net "GND")
			(clearance 0.1524)
			(thermal_gap 0.1524)
		)
		(pad "7" thru_hole circle
			(at -2.568448 2.568448)
			(size 0.762 0.762)
			(drill 0.5588)
			(layers "*.Cu" "*.Mask")
			(remove_unused_layers no)
			(net "GND")
			(clearance 0.1524)
			(thermal_gap 0.1524)
		)
		(pad "8" thru_hole circle
			(at 0 3.6322)
			(size 0.762 0.762)
			(drill 0.5588)
			(layers "*.Cu" "*.Mask")
			(remove_unused_layers no)
			(net "GND")
			(clearance 0.1524)
			(thermal_gap 0.1524)
		)
		(pad "9" thru_hole circle
			(at 2.568448 2.568448)
			(size 0.762 0.762)
			(drill 0.5588)
			(layers "*.Cu" "*.Mask")
			(remove_unused_layers no)
			(net "GND")
			(clearance 0.1524)
			(thermal_gap 0.1524)
		)
		(zone
			(layer "F.Cu")
			(hatch none 0.5)
			(connect_pads
				(clearance 0)
			)
			(min_thickness 0.25)
			(keepout
				(tracks not_allowed)
				(vias allowed)
				(pads allowed)
				(copperpour not_allowed)
				(footprints allowed)
			)
			(placement
				(enabled no)
				(sheetname "")
			)
			(fill
				(thermal_gap 0.5)
				(thermal_bridge_width 0.5)
				(island_removal_mode 0)
			)
			(polygon
				(pts
					(arc
						(start 145.749772 -262.899906)
						(mid 137.749788 -270.89989)
						(end 145.749772 -278.899874)
					)
					(arc
						(start 145.749772 -275.64969)
						(mid 140.999972 -270.89989)
						(end 145.749772 -266.15009)
					)
				)
			)
		)
		(zone
			(layer "F.Cu")
			(hatch none 0.5)
			(connect_pads
				(clearance 0)
			)
			(min_thickness 0.25)
			(keepout
				(tracks not_allowed)
				(vias allowed)
				(pads allowed)
				(copperpour not_allowed)
				(footprints allowed)
			)
			(placement
				(enabled no)
				(sheetname "")
			)
			(fill
				(thermal_gap 0.5)
				(thermal_bridge_width 0.5)
				(island_removal_mode 0)
			)
			(polygon
				(pts
					(arc
						(start 145.749772 -262.899906)
						(mid 153.749756 -270.89989)
						(end 145.749772 -278.899874)
					)
					(arc
						(start 145.749772 -275.64969)
						(mid 150.499572 -270.89989)
						(end 145.749772 -266.15009)
					)
				)
			)
		)
		(zone
			(layers "F.Cu" "B.Cu" "In1.Cu" "In2.Cu" "In3.Cu" "In4.Cu" "In5.Cu" "In6.Cu"
				"In7.Cu" "In8.Cu" "In9.Cu" "In10.Cu" "In11.Cu" "In12.Cu" "In13.Cu" "In14.Cu"
				"In15.Cu" "In16.Cu"
			)
			(hatch none 0.5)
			(connect_pads
				(clearance 0)
			)
			(min_thickness 0.25)
			(keepout
				(tracks not_allowed)
				(vias allowed)
				(pads allowed)
				(copperpour not_allowed)
				(footprints allowed)
			)
			(placement
				(enabled no)
				(sheetname "")
			)
			(fill
				(thermal_gap 0.5)
				(thermal_bridge_width 0.5)
				(island_removal_mode 0)
			)
			(polygon
				(pts
					(arc
						(start 148.515832 -270.89989)
						(mid 142.983712 -270.89989)
						(end 148.515832 -270.89989)
					)
				)
			)
		)
		(zone
			(layer "B.Cu")
			(hatch none 0.5)
			(connect_pads
				(clearance 0)
			)
			(min_thickness 0.25)
			(keepout
				(tracks not_allowed)
				(vias allowed)
				(pads allowed)
				(copperpour not_allowed)
				(footprints allowed)
			)
			(placement
				(enabled no)
				(sheetname "")
			)
			(fill
				(thermal_gap 0.5)
				(thermal_bridge_width 0.5)
				(island_removal_mode 0)
			)
			(polygon
				(pts
					(arc
						(start 145.749772 -265.89609)
						(mid 140.745972 -270.89989)
						(end 145.749772 -275.90369)
					)
					(arc
						(start 145.749772 -275.42109)
						(mid 141.228572 -270.89989)
						(end 145.749772 -266.37869)
					)
				)
			)
		)
		(zone
			(layer "B.Cu")
			(hatch none 0.5)
			(connect_pads
				(clearance 0)
			)
			(min_thickness 0.25)
			(keepout
				(tracks not_allowed)
				(vias allowed)
				(pads allowed)
				(copperpour not_allowed)
				(footprints allowed)
			)
			(placement
				(enabled no)
				(sheetname "")
			)
			(fill
				(thermal_gap 0.5)
				(thermal_bridge_width 0.5)
				(island_removal_mode 0)
			)
			(polygon
				(pts
					(arc
						(start 145.749772 -265.89609)
						(mid 150.753572 -270.89989)
						(end 145.749772 -275.90369)
					)
					(arc
						(start 145.749772 -275.42109)
						(mid 150.270972 -270.89989)
						(end 145.749772 -266.37869)
					)
				)
			)
		)
	)
	(footprint ""
		(layer "F.Cu")
		(at 403.455124 -53.468524 90)
		(property "Reference" "PC569"
			(at 0 0 90)
			(layer "F.SilkS")
			(hide yes)
			(effects
				(font
					(size 1.27 1.27)
				)
			)
		)
		(property "Value" ""
			(at 0 0 90)
			(layer "F.Fab")
			(effects
				(font
					(size 1.27 1.27)
				)
			)
		)
		(duplicate_pad_numbers_are_jumpers no)
		(fp_line
			(start 1.524 -0.762)
			(end 1.524 0.762)
			(stroke
				(width 0.1524)
				(type default)
			)
			(layer "F.SilkS")
		)
		(fp_line
			(start -1.524 -0.762)
			(end 1.524 -0.762)
			(stroke
				(width 0.1524)
				(type default)
			)
			(layer "F.SilkS")
		)
		(fp_line
			(start 1.524 0.762)
			(end -1.524 0.762)
			(stroke
				(width 0.1524)
				(type default)
			)
			(layer "F.SilkS")
		)
		(fp_line
			(start -1.524 0.762)
			(end -1.524 -0.762)
			(stroke
				(width 0.1524)
				(type default)
			)
			(layer "F.SilkS")
		)
		(fp_line
			(start 1.1049 -0.724916)
			(end -1.1049 -0.724916)
			(stroke
				(width 0.1)
				(type default)
			)
			(layer "F.Fab")
		)
		(fp_line
			(start -1.1049 -0.724916)
			(end -1.1049 0.724916)
			(stroke
				(width 0.1)
				(type default)
			)
			(layer "F.Fab")
		)
		(fp_line
			(start 1.1049 0.724916)
			(end 1.1049 -0.724916)
			(stroke
				(width 0.1)
				(type default)
			)
			(layer "F.Fab")
		)
		(fp_line
			(start -1.1049 0.724916)
			(end 1.1049 0.724916)
			(stroke
				(width 0.1)
				(type default)
			)
			(layer "F.Fab")
		)
		(pad "1" smd rect
			(at -0.889 0 270)
			(size 1.016 1.27)
			(layers "F.Cu" "F.Mask" "F.Paste")
			(net "GND")
		)
		(pad "2" smd rect
			(at 0.889 0 270)
			(size 1.016 1.27)
			(layers "F.Cu" "F.Mask" "F.Paste")
			(net "P3V3_AUX")
		)
	)
	(footprint ""
		(layer "F.Cu")
		(at 293.657782 -356.244906 90)
		(property "Reference" "C2366"
			(at 0 0 90)
			(layer "F.SilkS")
			(hide yes)
			(effects
				(font
					(size 1.27 1.27)
				)
			)
		)
		(property "Value" ""
			(at 0 0 90)
			(layer "F.Fab")
			(effects
				(font
					(size 1.27 1.27)
				)
			)
		)
		(duplicate_pad_numbers_are_jumpers no)
		(fp_line
			(start 0.299974 -0.150114)
			(end 0.299974 0.150114)
			(stroke
				(width 0.1)
				(type default)
			)
			(layer "F.Fab")
		)
		(fp_line
			(start -0.299974 -0.150114)
			(end 0.299974 -0.150114)
			(stroke
				(width 0.1)
				(type default)
			)
			(layer "F.Fab")
		)
		(fp_line
			(start 0.299974 0.150114)
			(end -0.299974 0.150114)
			(stroke
				(width 0.1)
				(type default)
			)
			(layer "F.Fab")
		)
		(fp_line
			(start -0.299974 0.150114)
			(end -0.299974 -0.150114)
			(stroke
				(width 0.1)
				(type default)
			)
			(layer "F.Fab")
		)
		(pad "1" smd rect
			(at -0.2667 0 90)
			(size 0.3048 0.381)
			(layers "F.Cu" "F.Mask" "F.Paste")
			(net "P5E_PEX2_STN4_TX_DN<67>")
		)
		(pad "2" smd rect
			(at 0.2667 0 90)
			(size 0.3048 0.381)
			(layers "F.Cu" "F.Mask" "F.Paste")
			(net "P5E_PEX2_STN4_TX_C_DN<67>")
		)
	)
	(footprint ""
		(layer "F.Cu")
		(at 70.673722 -350.098614 90)
		(property "Reference" "C137"
			(at 0 0 90)
			(layer "F.SilkS")
			(hide yes)
			(effects
				(font
					(size 1.27 1.27)
				)
			)
		)
		(property "Value" ""
			(at 0 0 90)
			(layer "F.Fab")
			(effects
				(font
					(size 1.27 1.27)
				)
			)
		)
		(duplicate_pad_numbers_are_jumpers no)
		(fp_line
			(start 0.299974 -0.150114)
			(end 0.299974 0.150114)
			(stroke
				(width 0.1)
				(type default)
			)
			(layer "F.Fab")
		)
		(fp_line
			(start -0.299974 -0.150114)
			(end 0.299974 -0.150114)
			(stroke
				(width 0.1)
				(type default)
			)
			(layer "F.Fab")
		)
		(fp_line
			(start 0.299974 0.150114)
			(end -0.299974 0.150114)
			(stroke
				(width 0.1)
				(type default)
			)
			(layer "F.Fab")
		)
		(fp_line
			(start -0.299974 0.150114)
			(end -0.299974 -0.150114)
			(stroke
				(width 0.1)
				(type default)
			)
			(layer "F.Fab")
		)
		(pad "1" smd rect
			(at -0.2667 0 90)
			(size 0.3048 0.381)
			(layers "F.Cu" "F.Mask" "F.Paste")
			(net "P5E_PEX0_STN6_TX_DP<107>")
		)
		(pad "2" smd rect
			(at 0.2667 0 90)
			(size 0.3048 0.381)
			(layers "F.Cu" "F.Mask" "F.Paste")
			(net "P5E_PEX0_STN6_TX_C_DP<107>")
		)
	)
	(footprint ""
		(layer "F.Cu")
		(at 149.387814 -294.819832)
		(property "Reference" "C3201"
			(at 0 0 0)
			(layer "F.SilkS")
			(hide yes)
			(effects
				(font
					(size 1.27 1.27)
				)
			)
		)
		(property "Value" ""
			(at 0 0 0)
			(layer "F.Fab")
			(effects
				(font
					(size 1.27 1.27)
				)
			)
		)
		(duplicate_pad_numbers_are_jumpers no)
		(fp_line
			(start -1.2954 -0.5842)
			(end 1.2954 -0.5842)
			(stroke
				(width 0.1524)
				(type default)
			)
			(layer "F.SilkS")
		)
		(fp_line
			(start -1.2954 0.5842)
			(end -1.2954 -0.5842)
			(stroke
				(width 0.1524)
				(type default)
			)
			(layer "F.SilkS")
		)
		(fp_line
			(start 1.2954 -0.5842)
			(end 1.2954 0.5842)
			(stroke
				(width 0.1524)
				(type default)
			)
			(layer "F.SilkS")
		)
		(fp_line
			(start 1.2954 0.5842)
			(end -1.2954 0.5842)
			(stroke
				(width 0.1524)
				(type default)
			)
			(layer "F.SilkS")
		)
		(fp_line
			(start -1.1938 -0.4064)
			(end -0.8636 -0.4064)
			(stroke
				(width 0.1)
				(type default)
			)
			(layer "F.Fab")
		)
		(fp_line
			(start -1.1938 0.4064)
			(end -1.1938 -0.4064)
			(stroke
				(width 0.1)
				(type default)
			)
			(layer "F.Fab")
		)
		(fp_line
			(start -0.8636 -0.4572)
			(end 0.8636 -0.4572)
			(stroke
				(width 0.1)
				(type default)
			)
			(layer "F.Fab")
		)
		(fp_line
			(start -0.8636 -0.4064)
			(end -0.8636 -0.4572)
			(stroke
				(width 0.1)
				(type default)
			)
			(layer "F.Fab")
		)
		(fp_line
			(start -0.8636 0.4064)
			(end -1.1938 0.4064)
			(stroke
				(width 0.1)
				(type default)
			)
			(layer "F.Fab")
		)
		(fp_line
			(start -0.8636 0.4572)
			(end -0.8636 0.4064)
			(stroke
				(width 0.1)
				(type default)
			)
			(layer "F.Fab")
		)
		(fp_line
			(start 0.8636 -0.4572)
			(end 0.8636 -0.4064)
			(stroke
				(width 0.1)
				(type default)
			)
			(layer "F.Fab")
		)
		(fp_line
			(start 0.8636 -0.4064)
			(end 1.1938 -0.4064)
			(stroke
				(width 0.1)
				(type default)
			)
			(layer "F.Fab")
		)
		(fp_line
			(start 0.8636 0.4064)
			(end 0.8636 0.4572)
			(stroke
				(width 0.1)
				(type default)
			)
			(layer "F.Fab")
		)
		(fp_line
			(start 0.8636 0.4572)
			(end -0.8636 0.4572)
			(stroke
				(width 0.1)
				(type default)
			)
			(layer "F.Fab")
		)
		(fp_line
			(start 1.1938 -0.4064)
			(end 1.1938 0.4064)
			(stroke
				(width 0.1)
				(type default)
			)
			(layer "F.Fab")
		)
		(fp_line
			(start 1.1938 0.4064)
			(end 0.8636 0.4064)
			(stroke
				(width 0.1)
				(type default)
			)
			(layer "F.Fab")
		)
		(pad "1" smd rect
			(at -0.7366 0 270)
			(size 0.7112 0.8128)
			(layers "F.Cu" "F.Mask" "F.Paste")
			(net "PCEPLL2_VDDA18_PEX1")
		)
		(pad "2" smd rect
			(at 0.7366 0 270)
			(size 0.7112 0.8128)
			(layers "F.Cu" "F.Mask" "F.Paste")
			(net "GND")
		)
	)
	(footprint ""
		(layer "F.Cu")
		(at 308.58333 -49.94148)
		(property "Reference" "R621"
			(at 0 0 0)
			(layer "F.SilkS")
			(hide yes)
			(effects
				(font
					(size 1.27 1.27)
				)
			)
		)
		(property "Value" ""
			(at 0 0 0)
			(layer "F.Fab")
			(effects
				(font
					(size 1.27 1.27)
				)
			)
		)
		(duplicate_pad_numbers_are_jumpers no)
		(fp_line
			(start -0.7874 -0.4064)
			(end 0.7874 -0.4064)
			(stroke
				(width 0.1524)
				(type default)
			)
			(layer "F.SilkS")
		)
		(fp_line
			(start -0.7874 0.4064)
			(end -0.7874 -0.4064)
			(stroke
				(width 0.1524)
				(type default)
			)
			(layer "F.SilkS")
		)
		(fp_line
			(start 0.7874 -0.4064)
			(end 0.7874 0.4064)
			(stroke
				(width 0.1524)
				(type default)
			)
			(layer "F.SilkS")
		)
		(fp_line
			(start 0.7874 0.4064)
			(end -0.7874 0.4064)
			(stroke
				(width 0.1524)
				(type default)
			)
			(layer "F.SilkS")
		)
		(fp_line
			(start -0.67945 -0.305054)
			(end -0.12065 -0.305054)
			(stroke
				(width 0.1)
				(type default)
			)
			(layer "F.Fab")
		)
		(fp_line
			(start -0.67945 0.3048)
			(end -0.67945 -0.305054)
			(stroke
				(width 0.1)
				(type default)
			)
			(layer "F.Fab")
		)
		(fp_line
			(start -0.12065 -0.305054)
			(end -0.12065 -0.2794)
			(stroke
				(width 0.1)
				(type default)
			)
			(layer "F.Fab")
		)
		(fp_line
			(start -0.12065 -0.2794)
			(end 0.12065 -0.2794)
			(stroke
				(width 0.1)
				(type default)
			)
			(layer "F.Fab")
		)
		(fp_line
			(start -0.12065 0.2794)
			(end -0.12065 0.3048)
			(stroke
				(width 0.1)
				(type default)
			)
			(layer "F.Fab")
		)
		(fp_line
			(start -0.12065 0.3048)
			(end -0.67945 0.3048)
			(stroke
				(width 0.1)
				(type default)
			)
			(layer "F.Fab")
		)
		(fp_line
			(start 0.120396 0.2794)
			(end -0.12065 0.2794)
			(stroke
				(width 0.1)
				(type default)
			)
			(layer "F.Fab")
		)
		(fp_line
			(start 0.120396 0.3048)
			(end 0.120396 0.2794)
			(stroke
				(width 0.1)
				(type default)
			)
			(layer "F.Fab")
		)
		(fp_line
			(start 0.12065 -0.3048)
			(end 0.67945 -0.3048)
			(stroke
				(width 0.1)
				(type default)
			)
			(layer "F.Fab")
		)
		(fp_line
			(start 0.12065 -0.2794)
			(end 0.12065 -0.3048)
			(stroke
				(width 0.1)
				(type default)
			)
			(layer "F.Fab")
		)
		(fp_line
			(start 0.67945 -0.3048)
			(end 0.67945 0.3048)
			(stroke
				(width 0.1)
				(type default)
			)
			(layer "F.Fab")
		)
		(fp_line
			(start 0.67945 0.3048)
			(end 0.120396 0.3048)
			(stroke
				(width 0.1)
				(type default)
			)
			(layer "F.Fab")
		)
		(pad "1" smd circle
			(at -0.40005 0)
			(size 0 0)
			(layers "F.Cu" "F.Mask" "F.Paste")
			(net "SMB_BIC_I2C6_MUX_SSD_8_15_ADC_R_SCL")
		)
		(pad "2" smd circle
			(at 0.40005 0)
			(size 0 0)
			(layers "F.Cu" "F.Mask" "F.Paste")
			(net "SMB_SSD10_ADC_SCL")
		)
	)
	(footprint ""
		(layer "F.Cu")
		(at 112.734344 -180.644546)
		(property "Reference" "PC23"
			(at 0 0 0)
			(layer "F.SilkS")
			(hide yes)
			(effects
				(font
					(size 1.27 1.27)
				)
			)
		)
		(property "Value" ""
			(at 0 0 0)
			(layer "F.Fab")
			(effects
				(font
					(size 1.27 1.27)
				)
			)
		)
		(duplicate_pad_numbers_are_jumpers no)
		(fp_line
			(start -0.7874 -0.4064)
			(end 0.7874 -0.4064)
			(stroke
				(width 0.1524)
				(type default)
			)
			(layer "F.SilkS")
		)
		(fp_line
			(start -0.7874 0.4064)
			(end -0.7874 -0.4064)
			(stroke
				(width 0.1524)
				(type default)
			)
			(layer "F.SilkS")
		)
		(fp_line
			(start 0.7874 -0.4064)
			(end 0.7874 0.4064)
			(stroke
				(width 0.1524)
				(type default)
			)
			(layer "F.SilkS")
		)
		(fp_line
			(start 0.7874 0.4064)
			(end -0.7874 0.4064)
			(stroke
				(width 0.1524)
				(type default)
			)
			(layer "F.SilkS")
		)
		(fp_line
			(start -0.67945 -0.305054)
			(end -0.12065 -0.305054)
			(stroke
				(width 0.1)
				(type default)
			)
			(layer "F.Fab")
		)
		(fp_line
			(start -0.67945 0.3048)
			(end -0.67945 -0.305054)
			(stroke
				(width 0.1)
				(type default)
			)
			(layer "F.Fab")
		)
		(fp_line
			(start -0.12065 -0.305054)
			(end -0.12065 -0.2794)
			(stroke
				(width 0.1)
				(type default)
			)
			(layer "F.Fab")
		)
		(fp_line
			(start -0.12065 -0.2794)
			(end 0.12065 -0.2794)
			(stroke
				(width 0.1)
				(type default)
			)
			(layer "F.Fab")
		)
		(fp_line
			(start -0.12065 0.2794)
			(end -0.12065 0.3048)
			(stroke
				(width 0.1)
				(type default)
			)
			(layer "F.Fab")
		)
		(fp_line
			(start -0.12065 0.3048)
			(end -0.67945 0.3048)
			(stroke
				(width 0.1)
				(type default)
			)
			(layer "F.Fab")
		)
		(fp_line
			(start 0.120396 0.2794)
			(end -0.12065 0.2794)
			(stroke
				(width 0.1)
				(type default)
			)
			(layer "F.Fab")
		)
		(fp_line
			(start 0.120396 0.3048)
			(end 0.120396 0.2794)
			(stroke
				(width 0.1)
				(type default)
			)
			(layer "F.Fab")
		)
		(fp_line
			(start 0.12065 -0.3048)
			(end 0.67945 -0.3048)
			(stroke
				(width 0.1)
				(type default)
			)
			(layer "F.Fab")
		)
		(fp_line
			(start 0.12065 -0.2794)
			(end 0.12065 -0.3048)
			(stroke
				(width 0.1)
				(type default)
			)
			(layer "F.Fab")
		)
		(fp_line
			(start 0.67945 -0.3048)
			(end 0.67945 0.3048)
			(stroke
				(width 0.1)
				(type default)
			)
			(layer "F.Fab")
		)
		(fp_line
			(start 0.67945 0.3048)
			(end 0.120396 0.3048)
			(stroke
				(width 0.1)
				(type default)
			)
			(layer "F.Fab")
		)
		(pad "1" smd circle
			(at -0.40005 0)
			(size 0 0)
			(layers "F.Cu" "F.Mask" "F.Paste")
			(net "P12V_AUX")
		)
		(pad "2" smd circle
			(at 0.40005 0)
			(size 0 0)
			(layers "F.Cu" "F.Mask" "F.Paste")
			(net "GND")
		)
	)
	(footprint ""
		(layer "F.Cu")
		(at 199.647302 -224.356676)
		(property "Reference" "J59"
			(at -1.4224 -4.562348 0)
			(unlocked yes)
			(layer "F.SilkS")
			(effects
				(font
					(size 0.7874 0.5842)
					(thickness 0.1524)
				)
				(justify left)
			)
		)
		(property "Value" ""
			(at 0 0 0)
			(layer "F.Fab")
			(effects
				(font
					(size 1.27 1.27)
				)
			)
		)
		(duplicate_pad_numbers_are_jumpers no)
		(fp_line
			(start -1.27 -3.81)
			(end 1.27 -3.81)
			(stroke
				(width 0.1524)
				(type default)
			)
			(layer "F.SilkS")
		)
		(fp_line
			(start -1.27 -0.7747)
			(end -1.27 -3.81)
			(stroke
				(width 0.1524)
				(type default)
			)
			(layer "F.SilkS")
		)
		(fp_line
			(start -1.27 3.81)
			(end -1.27 0.7747)
			(stroke
				(width 0.1524)
				(type default)
			)
			(layer "F.SilkS")
		)
		(fp_line
			(start 1.27 -3.81)
			(end 1.27 -3.3147)
			(stroke
				(width 0.1524)
				(type default)
			)
			(layer "F.SilkS")
		)
		(fp_line
			(start 1.27 -1.7653)
			(end 1.27 1.7653)
			(stroke
				(width 0.1524)
				(type default)
			)
			(layer "F.SilkS")
		)
		(fp_line
			(start 1.27 3.3147)
			(end 1.27 3.81)
			(stroke
				(width 0.1524)
				(type default)
			)
			(layer "F.SilkS")
		)
		(fp_line
			(start 1.27 3.81)
			(end -1.27 3.81)
			(stroke
				(width 0.1524)
				(type default)
			)
			(layer "F.SilkS")
		)
		(fp_poly
			(pts
				(xy 4.3942 -3.048) (xy 4.3942 -2.032) (xy 3.3782 -2.54)
			)
			(stroke
				(width 0)
				(type default)
			)
			(fill yes)
			(layer "F.SilkS")
		)
		(fp_line
			(start -1.27 -3.81)
			(end -1.27 3.81)
			(stroke
				(width 0.1)
				(type default)
			)
			(layer "F.Fab")
		)
		(fp_line
			(start -1.27 3.81)
			(end 1.27 3.81)
			(stroke
				(width 0.1)
				(type default)
			)
			(layer "F.Fab")
		)
		(fp_line
			(start 1.27 -3.81)
			(end -1.27 -3.81)
			(stroke
				(width 0.1)
				(type default)
			)
			(layer "F.Fab")
		)
		(fp_line
			(start 1.27 3.81)
			(end 1.27 -3.81)
			(stroke
				(width 0.1)
				(type default)
			)
			(layer "F.Fab")
		)
		(fp_poly
			(pts
				(xy 4.3942 -3.048) (xy 4.3942 -2.032) (xy 3.3782 -2.54)
			)
			(stroke
				(width 0)
				(type default)
			)
			(fill yes)
			(layer "F.Fab")
		)
		(fp_text user "3"
			(at 3.921252 2.54 90)
			(unlocked yes)
			(layer "F.SilkS")
			(effects
				(font
					(size 0.7874 0.5842)
					(thickness 0.1524)
				)
			)
		)
		(fp_text user "3"
			(at 3.921252 2.54 90)
			(unlocked yes)
			(layer "F.Fab")
			(effects
				(font
					(size 0.7874 0.5842)
					(thickness 0.1524)
				)
			)
		)
		(pad "1" smd rect
			(at 1.459992 -2.54 90)
			(size 1.27 3.429)
			(layers "F.Cu" "F.Mask" "F.Paste")
			(net "PD_BIC_UART_SEL")
		)
		(pad "2" smd rect
			(at -1.459992 0 90)
			(size 1.27 3.429)
			(layers "F.Cu" "F.Mask" "F.Paste")
			(net "BIC_UART_HW_SEL1")
		)
		(pad "3" smd rect
			(at 1.459992 2.54 90)
			(size 1.27 3.429)
			(layers "F.Cu" "F.Mask" "F.Paste")
			(net "PU_BIC_UART_SEL")
		)
	)
	(footprint ""
		(layer "F.Cu")
		(at 218.599512 -231.416606 90)
		(property "Reference" "R4550"
			(at 0 0 90)
			(layer "F.SilkS")
			(hide yes)
			(effects
				(font
					(size 1.27 1.27)
				)
			)
		)
		(property "Value" ""
			(at 0 0 90)
			(layer "F.Fab")
			(effects
				(font
					(size 1.27 1.27)
				)
			)
		)
		(duplicate_pad_numbers_are_jumpers no)
		(fp_line
			(start 0.7874 -0.4064)
			(end 0.7874 0.4064)
			(stroke
				(width 0.1524)
				(type default)
			)
			(layer "F.SilkS")
		)
		(fp_line
			(start -0.7874 -0.4064)
			(end 0.7874 -0.4064)
			(stroke
				(width 0.1524)
				(type default)
			)
			(layer "F.SilkS")
		)
		(fp_line
			(start 0.7874 0.4064)
			(end -0.7874 0.4064)
			(stroke
				(width 0.1524)
				(type default)
			)
			(layer "F.SilkS")
		)
		(fp_line
			(start -0.7874 0.4064)
			(end -0.7874 -0.4064)
			(stroke
				(width 0.1524)
				(type default)
			)
			(layer "F.SilkS")
		)
		(fp_line
			(start -0.12065 -0.305054)
			(end -0.12065 -0.2794)
			(stroke
				(width 0.1)
				(type default)
			)
			(layer "F.Fab")
		)
		(fp_line
			(start -0.67945 -0.305054)
			(end -0.12065 -0.305054)
			(stroke
				(width 0.1)
				(type default)
			)
			(layer "F.Fab")
		)
		(fp_line
			(start 0.67945 -0.3048)
			(end 0.67945 0.3048)
			(stroke
				(width 0.1)
				(type default)
			)
			(layer "F.Fab")
		)
		(fp_line
			(start 0.12065 -0.3048)
			(end 0.67945 -0.3048)
			(stroke
				(width 0.1)
				(type default)
			)
			(layer "F.Fab")
		)
		(fp_line
			(start 0.12065 -0.2794)
			(end 0.12065 -0.3048)
			(stroke
				(width 0.1)
				(type default)
			)
			(layer "F.Fab")
		)
		(fp_line
			(start -0.12065 -0.2794)
			(end 0.12065 -0.2794)
			(stroke
				(width 0.1)
				(type default)
			)
			(layer "F.Fab")
		)
		(fp_line
			(start 0.120396 0.2794)
			(end -0.12065 0.2794)
			(stroke
				(width 0.1)
				(type default)
			)
			(layer "F.Fab")
		)
		(fp_line
			(start -0.12065 0.2794)
			(end -0.12065 0.3048)
			(stroke
				(width 0.1)
				(type default)
			)
			(layer "F.Fab")
		)
		(fp_line
			(start 0.67945 0.3048)
			(end 0.120396 0.3048)
			(stroke
				(width 0.1)
				(type default)
			)
			(layer "F.Fab")
		)
		(fp_line
			(start 0.120396 0.3048)
			(end 0.120396 0.2794)
			(stroke
				(width 0.1)
				(type default)
			)
			(layer "F.Fab")
		)
		(fp_line
			(start -0.12065 0.3048)
			(end -0.67945 0.3048)
			(stroke
				(width 0.1)
				(type default)
			)
			(layer "F.Fab")
		)
		(fp_line
			(start -0.67945 0.3048)
			(end -0.67945 -0.305054)
			(stroke
				(width 0.1)
				(type default)
			)
			(layer "F.Fab")
		)
		(pad "1" smd circle
			(at -0.40005 0 90)
			(size 0 0)
			(layers "F.Cu" "F.Mask" "F.Paste")
			(net "BOARD_ID0")
		)
		(pad "2" smd circle
			(at 0.40005 0 90)
			(size 0 0)
			(layers "F.Cu" "F.Mask" "F.Paste")
			(net "P3V3_AUX")
		)
	)
	(footprint ""
		(layer "F.Cu")
		(at 358.013 -212.344 180)
		(property "Reference" "R4095"
			(at 0 0 180)
			(layer "F.SilkS")
			(hide yes)
			(effects
				(font
					(size 1.27 1.27)
				)
			)
		)
		(property "Value" ""
			(at 0 0 180)
			(layer "F.Fab")
			(effects
				(font
					(size 1.27 1.27)
				)
			)
		)
		(duplicate_pad_numbers_are_jumpers no)
		(fp_line
			(start 0.7874 0.4064)
			(end -0.7874 0.4064)
			(stroke
				(width 0.1524)
				(type default)
			)
			(layer "F.SilkS")
		)
		(fp_line
			(start 0.7874 -0.4064)
			(end 0.7874 0.4064)
			(stroke
				(width 0.1524)
				(type default)
			)
			(layer "F.SilkS")
		)
		(fp_line
			(start -0.7874 0.4064)
			(end -0.7874 -0.4064)
			(stroke
				(width 0.1524)
				(type default)
			)
			(layer "F.SilkS")
		)
		(fp_line
			(start -0.7874 -0.4064)
			(end 0.7874 -0.4064)
			(stroke
				(width 0.1524)
				(type default)
			)
			(layer "F.SilkS")
		)
		(fp_line
			(start 0.67945 0.3048)
			(end 0.120396 0.3048)
			(stroke
				(width 0.1)
				(type default)
			)
			(layer "F.Fab")
		)
		(fp_line
			(start 0.67945 -0.3048)
			(end 0.67945 0.3048)
			(stroke
				(width 0.1)
				(type default)
			)
			(layer "F.Fab")
		)
		(fp_line
			(start 0.12065 -0.2794)
			(end 0.12065 -0.3048)
			(stroke
				(width 0.1)
				(type default)
			)
			(layer "F.Fab")
		)
		(fp_line
			(start 0.12065 -0.3048)
			(end 0.67945 -0.3048)
			(stroke
				(width 0.1)
				(type default)
			)
			(layer "F.Fab")
		)
		(fp_line
			(start 0.120396 0.3048)
			(end 0.120396 0.2794)
			(stroke
				(width 0.1)
				(type default)
			)
			(layer "F.Fab")
		)
		(fp_line
			(start 0.120396 0.2794)
			(end -0.12065 0.2794)
			(stroke
				(width 0.1)
				(type default)
			)
			(layer "F.Fab")
		)
		(fp_line
			(start -0.12065 0.3048)
			(end -0.67945 0.3048)
			(stroke
				(width 0.1)
				(type default)
			)
			(layer "F.Fab")
		)
		(fp_line
			(start -0.12065 0.2794)
			(end -0.12065 0.3048)
			(stroke
				(width 0.1)
				(type default)
			)
			(layer "F.Fab")
		)
		(fp_line
			(start -0.12065 -0.2794)
			(end 0.12065 -0.2794)
			(stroke
				(width 0.1)
				(type default)
			)
			(layer "F.Fab")
		)
		(fp_line
			(start -0.12065 -0.305054)
			(end -0.12065 -0.2794)
			(stroke
				(width 0.1)
				(type default)
			)
			(layer "F.Fab")
		)
		(fp_line
			(start -0.67945 0.3048)
			(end -0.67945 -0.305054)
			(stroke
				(width 0.1)
				(type default)
			)
			(layer "F.Fab")
		)
		(fp_line
			(start -0.67945 -0.305054)
			(end -0.12065 -0.305054)
			(stroke
				(width 0.1)
				(type default)
			)
			(layer "F.Fab")
		)
		(pad "1" smd circle
			(at -0.40005 0 180)
			(size 0 0)
			(layers "F.Cu" "F.Mask" "F.Paste")
			(net "PRSNT_NIC3_FPGA_R_N")
		)
		(pad "2" smd circle
			(at 0.40005 0 180)
			(size 0 0)
			(layers "F.Cu" "F.Mask" "F.Paste")
			(net "PRSNT_NIC3_FPGA_N")
		)
	)
	(footprint ""
		(layer "F.Cu")
		(at 251.7267 -55.418228 90)
		(property "Reference" "PC404"
			(at 0 0 90)
			(layer "F.SilkS")
			(hide yes)
			(effects
				(font
					(size 1.27 1.27)
				)
			)
		)
		(property "Value" ""
			(at 0 0 90)
			(layer "F.Fab")
			(effects
				(font
					(size 1.27 1.27)
				)
			)
		)
		(duplicate_pad_numbers_are_jumpers no)
		(fp_line
			(start 0.7874 -0.4064)
			(end 0.7874 0.4064)
			(stroke
				(width 0.1524)
				(type default)
			)
			(layer "F.SilkS")
		)
		(fp_line
			(start -0.7874 -0.4064)
			(end 0.7874 -0.4064)
			(stroke
				(width 0.1524)
				(type default)
			)
			(layer "F.SilkS")
		)
		(fp_line
			(start 0.7874 0.4064)
			(end -0.7874 0.4064)
			(stroke
				(width 0.1524)
				(type default)
			)
			(layer "F.SilkS")
		)
		(fp_line
			(start -0.7874 0.4064)
			(end -0.7874 -0.4064)
			(stroke
				(width 0.1524)
				(type default)
			)
			(layer "F.SilkS")
		)
		(fp_line
			(start -0.12065 -0.305054)
			(end -0.12065 -0.2794)
			(stroke
				(width 0.1)
				(type default)
			)
			(layer "F.Fab")
		)
		(fp_line
			(start -0.67945 -0.305054)
			(end -0.12065 -0.305054)
			(stroke
				(width 0.1)
				(type default)
			)
			(layer "F.Fab")
		)
		(fp_line
			(start 0.67945 -0.3048)
			(end 0.67945 0.3048)
			(stroke
				(width 0.1)
				(type default)
			)
			(layer "F.Fab")
		)
		(fp_line
			(start 0.12065 -0.3048)
			(end 0.67945 -0.3048)
			(stroke
				(width 0.1)
				(type default)
			)
			(layer "F.Fab")
		)
		(fp_line
			(start 0.12065 -0.2794)
			(end 0.12065 -0.3048)
			(stroke
				(width 0.1)
				(type default)
			)
			(layer "F.Fab")
		)
		(fp_line
			(start -0.12065 -0.2794)
			(end 0.12065 -0.2794)
			(stroke
				(width 0.1)
				(type default)
			)
			(layer "F.Fab")
		)
		(fp_line
			(start 0.120396 0.2794)
			(end -0.12065 0.2794)
			(stroke
				(width 0.1)
				(type default)
			)
			(layer "F.Fab")
		)
		(fp_line
			(start -0.12065 0.2794)
			(end -0.12065 0.3048)
			(stroke
				(width 0.1)
				(type default)
			)
			(layer "F.Fab")
		)
		(fp_line
			(start 0.67945 0.3048)
			(end 0.120396 0.3048)
			(stroke
				(width 0.1)
				(type default)
			)
			(layer "F.Fab")
		)
		(fp_line
			(start 0.120396 0.3048)
			(end 0.120396 0.2794)
			(stroke
				(width 0.1)
				(type default)
			)
			(layer "F.Fab")
		)
		(fp_line
			(start -0.12065 0.3048)
			(end -0.67945 0.3048)
			(stroke
				(width 0.1)
				(type default)
			)
			(layer "F.Fab")
		)
		(fp_line
			(start -0.67945 0.3048)
			(end -0.67945 -0.305054)
			(stroke
				(width 0.1)
				(type default)
			)
			(layer "F.Fab")
		)
		(pad "1" smd circle
			(at -0.40005 0 90)
			(size 0 0)
			(layers "F.Cu" "F.Mask" "F.Paste")
			(net "P12V_SSD8_R")
		)
		(pad "2" smd circle
			(at 0.40005 0 90)
			(size 0 0)
			(layers "F.Cu" "F.Mask" "F.Paste")
			(net "GND")
		)
	)
	(footprint ""
		(layer "F.Cu")
		(at 282.473908 -26.31186 -90)
		(property "Reference" "U413"
			(at -0.20574 -2.312162 90)
			(unlocked yes)
			(layer "F.SilkS")
			(effects
				(font
					(size 0.7874 0.5842)
					(thickness 0.1524)
				)
			)
		)
		(property "Value" ""
			(at 0 0 270)
			(layer "F.Fab")
			(effects
				(font
					(size 1.27 1.27)
				)
			)
		)
		(duplicate_pad_numbers_are_jumpers no)
		(fp_line
			(start -1.949958 1.610106)
			(end -1.949958 -1.610106)
			(stroke
				(width 0.1524)
				(type default)
			)
			(layer "F.SilkS")
		)
		(fp_line
			(start 1.949958 1.610106)
			(end -1.949958 1.610106)
			(stroke
				(width 0.1524)
				(type default)
			)
			(layer "F.SilkS")
		)
		(fp_line
			(start 1.949958 -1.560068)
			(end 1.949958 1.610106)
			(stroke
				(width 0.1524)
				(type default)
			)
			(layer "F.SilkS")
		)
		(fp_line
			(start -1.949958 -1.610106)
			(end 1.949958 -1.610106)
			(stroke
				(width 0.1524)
				(type default)
			)
			(layer "F.SilkS")
		)
		(fp_line
			(start -0.750062 1.560068)
			(end -0.750062 -1.560068)
			(stroke
				(width 0.1)
				(type default)
			)
			(layer "F.Fab")
		)
		(fp_line
			(start 0.750062 1.560068)
			(end -0.750062 1.560068)
			(stroke
				(width 0.1)
				(type default)
			)
			(layer "F.Fab")
		)
		(fp_line
			(start -0.750062 -1.560068)
			(end 0.750062 -1.560068)
			(stroke
				(width 0.1)
				(type default)
			)
			(layer "F.Fab")
		)
		(fp_line
			(start 0.750062 -1.560068)
			(end 0.750062 1.560068)
			(stroke
				(width 0.1)
				(type default)
			)
			(layer "F.Fab")
		)
		(pad "D" smd rect
			(at 1.100074 0 180)
			(size 1.016 1.4224)
			(layers "F.Cu" "F.Mask" "F.Paste")
			(net "SSD9_LED_ISO_N")
		)
		(pad "G" smd rect
			(at -1.100074 -0.94996 180)
			(size 1.016 1.4224)
			(layers "F.Cu" "F.Mask" "F.Paste")
			(net "SSD9_LED_R")
		)
		(pad "S" smd rect
			(at -1.100074 0.94996 180)
			(size 1.016 1.4224)
			(layers "F.Cu" "F.Mask" "F.Paste")
			(net "GND")
		)
	)
	(footprint ""
		(layer "F.Cu")
		(at 149.20341 -59.571636 90)
		(property "Reference" "PR262"
			(at 0 0 90)
			(layer "F.SilkS")
			(hide yes)
			(effects
				(font
					(size 1.27 1.27)
				)
			)
		)
		(property "Value" ""
			(at 0 0 90)
			(layer "F.Fab")
			(effects
				(font
					(size 1.27 1.27)
				)
			)
		)
		(duplicate_pad_numbers_are_jumpers no)
		(fp_line
			(start 0.7874 -0.4064)
			(end 0.7874 0.4064)
			(stroke
				(width 0.1524)
				(type default)
			)
			(layer "F.SilkS")
		)
		(fp_line
			(start -0.7874 -0.4064)
			(end 0.7874 -0.4064)
			(stroke
				(width 0.1524)
				(type default)
			)
			(layer "F.SilkS")
		)
		(fp_line
			(start 0.7874 0.4064)
			(end -0.7874 0.4064)
			(stroke
				(width 0.1524)
				(type default)
			)
			(layer "F.SilkS")
		)
		(fp_line
			(start -0.7874 0.4064)
			(end -0.7874 -0.4064)
			(stroke
				(width 0.1524)
				(type default)
			)
			(layer "F.SilkS")
		)
		(fp_line
			(start -0.12065 -0.305054)
			(end -0.12065 -0.2794)
			(stroke
				(width 0.1)
				(type default)
			)
			(layer "F.Fab")
		)
		(fp_line
			(start -0.67945 -0.305054)
			(end -0.12065 -0.305054)
			(stroke
				(width 0.1)
				(type default)
			)
			(layer "F.Fab")
		)
		(fp_line
			(start 0.67945 -0.3048)
			(end 0.67945 0.3048)
			(stroke
				(width 0.1)
				(type default)
			)
			(layer "F.Fab")
		)
		(fp_line
			(start 0.12065 -0.3048)
			(end 0.67945 -0.3048)
			(stroke
				(width 0.1)
				(type default)
			)
			(layer "F.Fab")
		)
		(fp_line
			(start 0.12065 -0.2794)
			(end 0.12065 -0.3048)
			(stroke
				(width 0.1)
				(type default)
			)
			(layer "F.Fab")
		)
		(fp_line
			(start -0.12065 -0.2794)
			(end 0.12065 -0.2794)
			(stroke
				(width 0.1)
				(type default)
			)
			(layer "F.Fab")
		)
		(fp_line
			(start 0.120396 0.2794)
			(end -0.12065 0.2794)
			(stroke
				(width 0.1)
				(type default)
			)
			(layer "F.Fab")
		)
		(fp_line
			(start -0.12065 0.2794)
			(end -0.12065 0.3048)
			(stroke
				(width 0.1)
				(type default)
			)
			(layer "F.Fab")
		)
		(fp_line
			(start 0.67945 0.3048)
			(end 0.120396 0.3048)
			(stroke
				(width 0.1)
				(type default)
			)
			(layer "F.Fab")
		)
		(fp_line
			(start 0.120396 0.3048)
			(end 0.120396 0.2794)
			(stroke
				(width 0.1)
				(type default)
			)
			(layer "F.Fab")
		)
		(fp_line
			(start -0.12065 0.3048)
			(end -0.67945 0.3048)
			(stroke
				(width 0.1)
				(type default)
			)
			(layer "F.Fab")
		)
		(fp_line
			(start -0.67945 0.3048)
			(end -0.67945 -0.305054)
			(stroke
				(width 0.1)
				(type default)
			)
			(layer "F.Fab")
		)
		(pad "1" smd circle
			(at -0.40005 0 90)
			(size 0 0)
			(layers "F.Cu" "F.Mask" "F.Paste")
			(net "P3V3_SSD5_OCP")
		)
		(pad "2" smd circle
			(at 0.40005 0 90)
			(size 0 0)
			(layers "F.Cu" "F.Mask" "F.Paste")
			(net "GND")
		)
	)
	(footprint ""
		(layer "F.Cu")
		(at 364.226602 -121.408952 180)
		(property "Reference" "PC475"
			(at 0 0 180)
			(layer "F.SilkS")
			(hide yes)
			(effects
				(font
					(size 1.27 1.27)
				)
			)
		)
		(property "Value" ""
			(at 0 0 180)
			(layer "F.Fab")
			(effects
				(font
					(size 1.27 1.27)
				)
			)
		)
		(duplicate_pad_numbers_are_jumpers no)
		(fp_line
			(start 1.524 0.762)
			(end -1.524 0.762)
			(stroke
				(width 0.1524)
				(type default)
			)
			(layer "F.SilkS")
		)
		(fp_line
			(start 1.524 -0.762)
			(end 1.524 0.762)
			(stroke
				(width 0.1524)
				(type default)
			)
			(layer "F.SilkS")
		)
		(fp_line
			(start -1.524 0.762)
			(end -1.524 -0.762)
			(stroke
				(width 0.1524)
				(type default)
			)
			(layer "F.SilkS")
		)
		(fp_line
			(start -1.524 -0.762)
			(end 1.524 -0.762)
			(stroke
				(width 0.1524)
				(type default)
			)
			(layer "F.SilkS")
		)
		(fp_line
			(start 1.1049 0.724916)
			(end 1.1049 -0.724916)
			(stroke
				(width 0.1)
				(type default)
			)
			(layer "F.Fab")
		)
		(fp_line
			(start 1.1049 -0.724916)
			(end -1.1049 -0.724916)
			(stroke
				(width 0.1)
				(type default)
			)
			(layer "F.Fab")
		)
		(fp_line
			(start -1.1049 0.724916)
			(end 1.1049 0.724916)
			(stroke
				(width 0.1)
				(type default)
			)
			(layer "F.Fab")
		)
		(fp_line
			(start -1.1049 -0.724916)
			(end -1.1049 0.724916)
			(stroke
				(width 0.1)
				(type default)
			)
			(layer "F.Fab")
		)
		(pad "1" smd rect
			(at -0.889 0)
			(size 1.016 1.27)
			(layers "F.Cu" "F.Mask" "F.Paste")
			(net "GND")
		)
		(pad "2" smd rect
			(at 0.889 0)
			(size 1.016 1.27)
			(layers "F.Cu" "F.Mask" "F.Paste")
			(net "P3V3_AUX")
		)
	)
	(footprint ""
		(layer "F.Cu")
		(at 376.312684 -89.9668)
		(property "Reference" "R1750"
			(at 0 0 0)
			(layer "F.SilkS")
			(hide yes)
			(effects
				(font
					(size 1.27 1.27)
				)
			)
		)
		(property "Value" ""
			(at 0 0 0)
			(layer "F.Fab")
			(effects
				(font
					(size 1.27 1.27)
				)
			)
		)
		(duplicate_pad_numbers_are_jumpers no)
		(fp_line
			(start -0.7874 -0.4064)
			(end 0.7874 -0.4064)
			(stroke
				(width 0.1524)
				(type default)
			)
			(layer "F.SilkS")
		)
		(fp_line
			(start -0.7874 0.4064)
			(end -0.7874 -0.4064)
			(stroke
				(width 0.1524)
				(type default)
			)
			(layer "F.SilkS")
		)
		(fp_line
			(start 0.7874 -0.4064)
			(end 0.7874 0.4064)
			(stroke
				(width 0.1524)
				(type default)
			)
			(layer "F.SilkS")
		)
		(fp_line
			(start 0.7874 0.4064)
			(end -0.7874 0.4064)
			(stroke
				(width 0.1524)
				(type default)
			)
			(layer "F.SilkS")
		)
		(fp_line
			(start -0.67945 -0.305054)
			(end -0.12065 -0.305054)
			(stroke
				(width 0.1)
				(type default)
			)
			(layer "F.Fab")
		)
		(fp_line
			(start -0.67945 0.3048)
			(end -0.67945 -0.305054)
			(stroke
				(width 0.1)
				(type default)
			)
			(layer "F.Fab")
		)
		(fp_line
			(start -0.12065 -0.305054)
			(end -0.12065 -0.2794)
			(stroke
				(width 0.1)
				(type default)
			)
			(layer "F.Fab")
		)
		(fp_line
			(start -0.12065 -0.2794)
			(end 0.12065 -0.2794)
			(stroke
				(width 0.1)
				(type default)
			)
			(layer "F.Fab")
		)
		(fp_line
			(start -0.12065 0.2794)
			(end -0.12065 0.3048)
			(stroke
				(width 0.1)
				(type default)
			)
			(layer "F.Fab")
		)
		(fp_line
			(start -0.12065 0.3048)
			(end -0.67945 0.3048)
			(stroke
				(width 0.1)
				(type default)
			)
			(layer "F.Fab")
		)
		(fp_line
			(start 0.120396 0.2794)
			(end -0.12065 0.2794)
			(stroke
				(width 0.1)
				(type default)
			)
			(layer "F.Fab")
		)
		(fp_line
			(start 0.120396 0.3048)
			(end 0.120396 0.2794)
			(stroke
				(width 0.1)
				(type default)
			)
			(layer "F.Fab")
		)
		(fp_line
			(start 0.12065 -0.3048)
			(end 0.67945 -0.3048)
			(stroke
				(width 0.1)
				(type default)
			)
			(layer "F.Fab")
		)
		(fp_line
			(start 0.12065 -0.2794)
			(end 0.12065 -0.3048)
			(stroke
				(width 0.1)
				(type default)
			)
			(layer "F.Fab")
		)
		(fp_line
			(start 0.67945 -0.3048)
			(end 0.67945 0.3048)
			(stroke
				(width 0.1)
				(type default)
			)
			(layer "F.Fab")
		)
		(fp_line
			(start 0.67945 0.3048)
			(end 0.120396 0.3048)
			(stroke
				(width 0.1)
				(type default)
			)
			(layer "F.Fab")
		)
		(pad "1" smd circle
			(at -0.40005 0)
			(size 0 0)
			(layers "F.Cu" "F.Mask" "F.Paste")
			(net "P3V3_AUX")
		)
		(pad "2" smd circle
			(at 0.40005 0)
			(size 0 0)
			(layers "F.Cu" "F.Mask" "F.Paste")
			(net "BIC_I2C6_MUX_A1")
		)
	)
	(footprint ""
		(layer "F.Cu")
		(at 51.064414 -29.079952 180)
		(property "Reference" "R6199"
			(at 0 0 180)
			(layer "F.SilkS")
			(hide yes)
			(effects
				(font
					(size 1.27 1.27)
				)
			)
		)
		(property "Value" ""
			(at 0 0 180)
			(layer "F.Fab")
			(effects
				(font
					(size 1.27 1.27)
				)
			)
		)
		(duplicate_pad_numbers_are_jumpers no)
		(fp_line
			(start 0.7874 0.4064)
			(end -0.7874 0.4064)
			(stroke
				(width 0.1524)
				(type default)
			)
			(layer "F.SilkS")
		)
		(fp_line
			(start 0.7874 -0.4064)
			(end 0.7874 0.4064)
			(stroke
				(width 0.1524)
				(type default)
			)
			(layer "F.SilkS")
		)
		(fp_line
			(start -0.7874 0.4064)
			(end -0.7874 -0.4064)
			(stroke
				(width 0.1524)
				(type default)
			)
			(layer "F.SilkS")
		)
		(fp_line
			(start -0.7874 -0.4064)
			(end 0.7874 -0.4064)
			(stroke
				(width 0.1524)
				(type default)
			)
			(layer "F.SilkS")
		)
		(fp_line
			(start 0.67945 0.3048)
			(end 0.120396 0.3048)
			(stroke
				(width 0.1)
				(type default)
			)
			(layer "F.Fab")
		)
		(fp_line
			(start 0.67945 -0.3048)
			(end 0.67945 0.3048)
			(stroke
				(width 0.1)
				(type default)
			)
			(layer "F.Fab")
		)
		(fp_line
			(start 0.12065 -0.2794)
			(end 0.12065 -0.3048)
			(stroke
				(width 0.1)
				(type default)
			)
			(layer "F.Fab")
		)
		(fp_line
			(start 0.12065 -0.3048)
			(end 0.67945 -0.3048)
			(stroke
				(width 0.1)
				(type default)
			)
			(layer "F.Fab")
		)
		(fp_line
			(start 0.120396 0.3048)
			(end 0.120396 0.2794)
			(stroke
				(width 0.1)
				(type default)
			)
			(layer "F.Fab")
		)
		(fp_line
			(start 0.120396 0.2794)
			(end -0.12065 0.2794)
			(stroke
				(width 0.1)
				(type default)
			)
			(layer "F.Fab")
		)
		(fp_line
			(start -0.12065 0.3048)
			(end -0.67945 0.3048)
			(stroke
				(width 0.1)
				(type default)
			)
			(layer "F.Fab")
		)
		(fp_line
			(start -0.12065 0.2794)
			(end -0.12065 0.3048)
			(stroke
				(width 0.1)
				(type default)
			)
			(layer "F.Fab")
		)
		(fp_line
			(start -0.12065 -0.2794)
			(end 0.12065 -0.2794)
			(stroke
				(width 0.1)
				(type default)
			)
			(layer "F.Fab")
		)
		(fp_line
			(start -0.12065 -0.305054)
			(end -0.12065 -0.2794)
			(stroke
				(width 0.1)
				(type default)
			)
			(layer "F.Fab")
		)
		(fp_line
			(start -0.67945 0.3048)
			(end -0.67945 -0.305054)
			(stroke
				(width 0.1)
				(type default)
			)
			(layer "F.Fab")
		)
		(fp_line
			(start -0.67945 -0.305054)
			(end -0.12065 -0.305054)
			(stroke
				(width 0.1)
				(type default)
			)
			(layer "F.Fab")
		)
		(pad "1" smd circle
			(at -0.40005 0 180)
			(size 0 0)
			(layers "F.Cu" "F.Mask" "F.Paste")
			(net "GND")
		)
		(pad "2" smd circle
			(at 0.40005 0 180)
			(size 0 0)
			(layers "F.Cu" "F.Mask" "F.Paste")
			(net "SSD1_PWRDIS_R")
		)
	)
	(footprint ""
		(layer "F.Cu")
		(at 401.073112 -232.818432)
		(property "Reference" "J65"
			(at -7.126986 0.264668 0)
			(unlocked yes)
			(layer "F.SilkS")
			(effects
				(font
					(size 0.7874 0.5842)
					(thickness 0.1524)
				)
				(justify left)
			)
		)
		(property "Value" ""
			(at 0 0 0)
			(layer "F.Fab")
			(effects
				(font
					(size 1.27 1.27)
				)
			)
		)
		(duplicate_pad_numbers_are_jumpers no)
		(fp_line
			(start -1.27 -3.81)
			(end 1.27 -3.81)
			(stroke
				(width 0.1524)
				(type default)
			)
			(layer "F.SilkS")
		)
		(fp_line
			(start -1.27 -0.7747)
			(end -1.27 -3.81)
			(stroke
				(width 0.1524)
				(type default)
			)
			(layer "F.SilkS")
		)
		(fp_line
			(start -1.27 3.81)
			(end -1.27 0.7747)
			(stroke
				(width 0.1524)
				(type default)
			)
			(layer "F.SilkS")
		)
		(fp_line
			(start 1.27 -3.81)
			(end 1.27 -3.3147)
			(stroke
				(width 0.1524)
				(type default)
			)
			(layer "F.SilkS")
		)
		(fp_line
			(start 1.27 -1.7653)
			(end 1.27 1.7653)
			(stroke
				(width 0.1524)
				(type default)
			)
			(layer "F.SilkS")
		)
		(fp_line
			(start 1.27 3.3147)
			(end 1.27 3.81)
			(stroke
				(width 0.1524)
				(type default)
			)
			(layer "F.SilkS")
		)
		(fp_line
			(start 1.27 3.81)
			(end -1.27 3.81)
			(stroke
				(width 0.1524)
				(type default)
			)
			(layer "F.SilkS")
		)
		(fp_poly
			(pts
				(xy 4.3942 -3.048) (xy 4.3942 -2.032) (xy 3.3782 -2.54)
			)
			(stroke
				(width 0)
				(type default)
			)
			(fill yes)
			(layer "F.SilkS")
		)
		(fp_line
			(start -1.27 -3.81)
			(end -1.27 3.81)
			(stroke
				(width 0.1)
				(type default)
			)
			(layer "F.Fab")
		)
		(fp_line
			(start -1.27 3.81)
			(end 1.27 3.81)
			(stroke
				(width 0.1)
				(type default)
			)
			(layer "F.Fab")
		)
		(fp_line
			(start 1.27 -3.81)
			(end -1.27 -3.81)
			(stroke
				(width 0.1)
				(type default)
			)
			(layer "F.Fab")
		)
		(fp_line
			(start 1.27 3.81)
			(end 1.27 -3.81)
			(stroke
				(width 0.1)
				(type default)
			)
			(layer "F.Fab")
		)
		(fp_poly
			(pts
				(xy 4.3942 -3.048) (xy 4.3942 -2.032) (xy 3.3782 -2.54)
			)
			(stroke
				(width 0)
				(type default)
			)
			(fill yes)
			(layer "F.Fab")
		)
		(fp_text user "3"
			(at 3.921252 2.54 90)
			(unlocked yes)
			(layer "F.SilkS")
			(effects
				(font
					(size 0.7874 0.5842)
					(thickness 0.1524)
				)
			)
		)
		(fp_text user "3"
			(at 3.921252 2.54 90)
			(unlocked yes)
			(layer "F.Fab")
			(effects
				(font
					(size 0.7874 0.5842)
					(thickness 0.1524)
				)
			)
		)
		(pad "1" smd rect
			(at 1.459992 -2.54 90)
			(size 1.27 3.429)
			(layers "F.Cu" "F.Mask" "F.Paste")
			(net "GND")
		)
		(pad "2" smd rect
			(at -1.459992 0 90)
			(size 1.27 3.429)
			(layers "F.Cu" "F.Mask" "F.Paste")
			(net "UART_PEX3_SDB_BUF_R1_TX")
		)
		(pad "3" smd rect
			(at 1.459992 2.54 90)
			(size 1.27 3.429)
			(layers "F.Cu" "F.Mask" "F.Paste")
			(net "UART_PEX3_SDB_R1_RX")
		)
	)
	(footprint ""
		(layer "F.Cu")
		(at 87.77732 -309.791354 135)
		(property "Reference" "R1243"
			(at 0 0 135)
			(layer "F.SilkS")
			(hide yes)
			(effects
				(font
					(size 1.27 1.27)
				)
			)
		)
		(property "Value" ""
			(at 0 0 135)
			(layer "F.Fab")
			(effects
				(font
					(size 1.27 1.27)
				)
			)
		)
		(duplicate_pad_numbers_are_jumpers no)
		(fp_line
			(start 0.787389 -0.406267)
			(end 0.787389 0.406267)
			(stroke
				(width 0.1524)
				(type default)
			)
			(layer "F.SilkS")
		)
		(fp_line
			(start 0.787389 0.406267)
			(end -0.787389 0.406267)
			(stroke
				(width 0.1524)
				(type default)
			)
			(layer "F.SilkS")
		)
		(fp_line
			(start -0.787389 -0.406267)
			(end 0.787389 -0.406267)
			(stroke
				(width 0.1524)
				(type default)
			)
			(layer "F.SilkS")
		)
		(fp_line
			(start -0.787389 0.406267)
			(end -0.787389 -0.406267)
			(stroke
				(width 0.1524)
				(type default)
			)
			(layer "F.SilkS")
		)
		(fp_line
			(start 0.679446 -0.30479)
			(end 0.679446 0.30479)
			(stroke
				(width 0.1)
				(type default)
			)
			(layer "F.Fab")
		)
		(fp_line
			(start 0.120515 -0.30479)
			(end 0.679446 -0.30479)
			(stroke
				(width 0.1)
				(type default)
			)
			(layer "F.Fab")
		)
		(fp_line
			(start 0.120695 -0.279466)
			(end 0.120515 -0.30479)
			(stroke
				(width 0.1)
				(type default)
			)
			(layer "F.Fab")
		)
		(fp_line
			(start 0.679446 0.30479)
			(end 0.120515 0.30479)
			(stroke
				(width 0.1)
				(type default)
			)
			(layer "F.Fab")
		)
		(fp_line
			(start -0.120695 -0.304969)
			(end -0.120695 -0.279466)
			(stroke
				(width 0.1)
				(type default)
			)
			(layer "F.Fab")
		)
		(fp_line
			(start -0.120695 -0.279466)
			(end 0.120695 -0.279466)
			(stroke
				(width 0.1)
				(type default)
			)
			(layer "F.Fab")
		)
		(fp_line
			(start 0.120335 0.279466)
			(end -0.120695 0.279466)
			(stroke
				(width 0.1)
				(type default)
			)
			(layer "F.Fab")
		)
		(fp_line
			(start 0.120515 0.30479)
			(end 0.120335 0.279466)
			(stroke
				(width 0.1)
				(type default)
			)
			(layer "F.Fab")
		)
		(fp_line
			(start -0.679446 -0.305149)
			(end -0.120695 -0.304969)
			(stroke
				(width 0.1)
				(type default)
			)
			(layer "F.Fab")
		)
		(fp_line
			(start -0.120695 0.279466)
			(end -0.120515 0.30479)
			(stroke
				(width 0.1)
				(type default)
			)
			(layer "F.Fab")
		)
		(fp_line
			(start -0.120515 0.30479)
			(end -0.679446 0.30479)
			(stroke
				(width 0.1)
				(type default)
			)
			(layer "F.Fab")
		)
		(fp_line
			(start -0.679446 0.30479)
			(end -0.679446 -0.305149)
			(stroke
				(width 0.1)
				(type default)
			)
			(layer "F.Fab")
		)
		(pad "1" smd circle
			(at -0.40005 0 135)
			(size 0 0)
			(layers "F.Cu" "F.Mask" "F.Paste")
			(net "PEX0_SPARE7")
		)
		(pad "2" smd circle
			(at 0.40005 0 135)
			(size 0 0)
			(layers "F.Cu" "F.Mask" "F.Paste")
			(net "P1V8_PEX")
		)
	)
	(footprint ""
		(layer "F.Cu")
		(at 327.53173 -222.956882)
		(property "Reference" "R4172"
			(at 0 0 0)
			(layer "F.SilkS")
			(hide yes)
			(effects
				(font
					(size 1.27 1.27)
				)
			)
		)
		(property "Value" ""
			(at 0 0 0)
			(layer "F.Fab")
			(effects
				(font
					(size 1.27 1.27)
				)
			)
		)
		(duplicate_pad_numbers_are_jumpers no)
		(fp_line
			(start -0.7874 -0.4064)
			(end 0.7874 -0.4064)
			(stroke
				(width 0.1524)
				(type default)
			)
			(layer "F.SilkS")
		)
		(fp_line
			(start -0.7874 0.4064)
			(end -0.7874 -0.4064)
			(stroke
				(width 0.1524)
				(type default)
			)
			(layer "F.SilkS")
		)
		(fp_line
			(start 0.7874 -0.4064)
			(end 0.7874 0.4064)
			(stroke
				(width 0.1524)
				(type default)
			)
			(layer "F.SilkS")
		)
		(fp_line
			(start 0.7874 0.4064)
			(end -0.7874 0.4064)
			(stroke
				(width 0.1524)
				(type default)
			)
			(layer "F.SilkS")
		)
		(fp_line
			(start -0.67945 -0.305054)
			(end -0.12065 -0.305054)
			(stroke
				(width 0.1)
				(type default)
			)
			(layer "F.Fab")
		)
		(fp_line
			(start -0.67945 0.3048)
			(end -0.67945 -0.305054)
			(stroke
				(width 0.1)
				(type default)
			)
			(layer "F.Fab")
		)
		(fp_line
			(start -0.12065 -0.305054)
			(end -0.12065 -0.2794)
			(stroke
				(width 0.1)
				(type default)
			)
			(layer "F.Fab")
		)
		(fp_line
			(start -0.12065 -0.2794)
			(end 0.12065 -0.2794)
			(stroke
				(width 0.1)
				(type default)
			)
			(layer "F.Fab")
		)
		(fp_line
			(start -0.12065 0.2794)
			(end -0.12065 0.3048)
			(stroke
				(width 0.1)
				(type default)
			)
			(layer "F.Fab")
		)
		(fp_line
			(start -0.12065 0.3048)
			(end -0.67945 0.3048)
			(stroke
				(width 0.1)
				(type default)
			)
			(layer "F.Fab")
		)
		(fp_line
			(start 0.120396 0.2794)
			(end -0.12065 0.2794)
			(stroke
				(width 0.1)
				(type default)
			)
			(layer "F.Fab")
		)
		(fp_line
			(start 0.120396 0.3048)
			(end 0.120396 0.2794)
			(stroke
				(width 0.1)
				(type default)
			)
			(layer "F.Fab")
		)
		(fp_line
			(start 0.12065 -0.3048)
			(end 0.67945 -0.3048)
			(stroke
				(width 0.1)
				(type default)
			)
			(layer "F.Fab")
		)
		(fp_line
			(start 0.12065 -0.2794)
			(end 0.12065 -0.3048)
			(stroke
				(width 0.1)
				(type default)
			)
			(layer "F.Fab")
		)
		(fp_line
			(start 0.67945 -0.3048)
			(end 0.67945 0.3048)
			(stroke
				(width 0.1)
				(type default)
			)
			(layer "F.Fab")
		)
		(fp_line
			(start 0.67945 0.3048)
			(end 0.120396 0.3048)
			(stroke
				(width 0.1)
				(type default)
			)
			(layer "F.Fab")
		)
		(pad "1" smd circle
			(at -0.40005 0)
			(size 0 0)
			(layers "F.Cu" "F.Mask" "F.Paste")
			(net "RST_PEX1_PERST_R_N")
		)
		(pad "2" smd circle
			(at 0.40005 0)
			(size 0 0)
			(layers "F.Cu" "F.Mask" "F.Paste")
			(net "RST_PEX1_PERST_N")
		)
	)
	(footprint ""
		(layer "F.Cu")
		(at 312.857388 -112.504474 90)
		(property "Reference" "C921"
			(at 0 0 90)
			(layer "F.SilkS")
			(hide yes)
			(effects
				(font
					(size 1.27 1.27)
				)
			)
		)
		(property "Value" ""
			(at 0 0 90)
			(layer "F.Fab")
			(effects
				(font
					(size 1.27 1.27)
				)
			)
		)
		(duplicate_pad_numbers_are_jumpers no)
		(fp_line
			(start 1.524 -0.762)
			(end 1.524 0.762)
			(stroke
				(width 0.1524)
				(type default)
			)
			(layer "F.SilkS")
		)
		(fp_line
			(start -1.524 -0.762)
			(end 1.524 -0.762)
			(stroke
				(width 0.1524)
				(type default)
			)
			(layer "F.SilkS")
		)
		(fp_line
			(start 1.524 0.762)
			(end -1.524 0.762)
			(stroke
				(width 0.1524)
				(type default)
			)
			(layer "F.SilkS")
		)
		(fp_line
			(start -1.524 0.762)
			(end -1.524 -0.762)
			(stroke
				(width 0.1524)
				(type default)
			)
			(layer "F.SilkS")
		)
		(fp_line
			(start 1.1049 -0.724916)
			(end -1.1049 -0.724916)
			(stroke
				(width 0.1)
				(type default)
			)
			(layer "F.Fab")
		)
		(fp_line
			(start -1.1049 -0.724916)
			(end -1.1049 0.724916)
			(stroke
				(width 0.1)
				(type default)
			)
			(layer "F.Fab")
		)
		(fp_line
			(start 1.1049 0.724916)
			(end 1.1049 -0.724916)
			(stroke
				(width 0.1)
				(type default)
			)
			(layer "F.Fab")
		)
		(fp_line
			(start -1.1049 0.724916)
			(end 1.1049 0.724916)
			(stroke
				(width 0.1)
				(type default)
			)
			(layer "F.Fab")
		)
		(pad "1" smd rect
			(at -0.889 0 270)
			(size 1.016 1.27)
			(layers "F.Cu" "F.Mask" "F.Paste")
			(net "P12V_NIC5")
		)
		(pad "2" smd rect
			(at 0.889 0 270)
			(size 1.016 1.27)
			(layers "F.Cu" "F.Mask" "F.Paste")
			(net "GND")
		)
	)
	(footprint ""
		(layer "F.Cu")
		(at 195.432172 -32.848042 90)
		(property "Reference" "PC937"
			(at 0 0 90)
			(layer "F.SilkS")
			(hide yes)
			(effects
				(font
					(size 1.27 1.27)
				)
			)
		)
		(property "Value" ""
			(at 0 0 90)
			(layer "F.Fab")
			(effects
				(font
					(size 1.27 1.27)
				)
			)
		)
		(duplicate_pad_numbers_are_jumpers no)
		(fp_line
			(start 0.7874 -0.4064)
			(end 0.7874 0.4064)
			(stroke
				(width 0.1524)
				(type default)
			)
			(layer "F.SilkS")
		)
		(fp_line
			(start -0.7874 -0.4064)
			(end 0.7874 -0.4064)
			(stroke
				(width 0.1524)
				(type default)
			)
			(layer "F.SilkS")
		)
		(fp_line
			(start 0.7874 0.4064)
			(end -0.7874 0.4064)
			(stroke
				(width 0.1524)
				(type default)
			)
			(layer "F.SilkS")
		)
		(fp_line
			(start -0.7874 0.4064)
			(end -0.7874 -0.4064)
			(stroke
				(width 0.1524)
				(type default)
			)
			(layer "F.SilkS")
		)
		(fp_line
			(start -0.12065 -0.305054)
			(end -0.12065 -0.2794)
			(stroke
				(width 0.1)
				(type default)
			)
			(layer "F.Fab")
		)
		(fp_line
			(start -0.67945 -0.305054)
			(end -0.12065 -0.305054)
			(stroke
				(width 0.1)
				(type default)
			)
			(layer "F.Fab")
		)
		(fp_line
			(start 0.67945 -0.3048)
			(end 0.67945 0.3048)
			(stroke
				(width 0.1)
				(type default)
			)
			(layer "F.Fab")
		)
		(fp_line
			(start 0.12065 -0.3048)
			(end 0.67945 -0.3048)
			(stroke
				(width 0.1)
				(type default)
			)
			(layer "F.Fab")
		)
		(fp_line
			(start 0.12065 -0.2794)
			(end 0.12065 -0.3048)
			(stroke
				(width 0.1)
				(type default)
			)
			(layer "F.Fab")
		)
		(fp_line
			(start -0.12065 -0.2794)
			(end 0.12065 -0.2794)
			(stroke
				(width 0.1)
				(type default)
			)
			(layer "F.Fab")
		)
		(fp_line
			(start 0.120396 0.2794)
			(end -0.12065 0.2794)
			(stroke
				(width 0.1)
				(type default)
			)
			(layer "F.Fab")
		)
		(fp_line
			(start -0.12065 0.2794)
			(end -0.12065 0.3048)
			(stroke
				(width 0.1)
				(type default)
			)
			(layer "F.Fab")
		)
		(fp_line
			(start 0.67945 0.3048)
			(end 0.120396 0.3048)
			(stroke
				(width 0.1)
				(type default)
			)
			(layer "F.Fab")
		)
		(fp_line
			(start 0.120396 0.3048)
			(end 0.120396 0.2794)
			(stroke
				(width 0.1)
				(type default)
			)
			(layer "F.Fab")
		)
		(fp_line
			(start -0.12065 0.3048)
			(end -0.67945 0.3048)
			(stroke
				(width 0.1)
				(type default)
			)
			(layer "F.Fab")
		)
		(fp_line
			(start -0.67945 0.3048)
			(end -0.67945 -0.305054)
			(stroke
				(width 0.1)
				(type default)
			)
			(layer "F.Fab")
		)
		(pad "1" smd circle
			(at -0.40005 0 90)
			(size 0 0)
			(layers "F.Cu" "F.Mask" "F.Paste")
			(net "P3V3_SSD7_CO_DV_DT")
		)
		(pad "2" smd circle
			(at 0.40005 0 90)
			(size 0 0)
			(layers "F.Cu" "F.Mask" "F.Paste")
			(net "GND")
		)
	)
	(footprint ""
		(layer "F.Cu")
		(at 446.734438 -30.03169 180)
		(property "Reference" "C727"
			(at 0 0 180)
			(layer "F.SilkS")
			(hide yes)
			(effects
				(font
					(size 1.27 1.27)
				)
			)
		)
		(property "Value" ""
			(at 0 0 180)
			(layer "F.Fab")
			(effects
				(font
					(size 1.27 1.27)
				)
			)
		)
		(duplicate_pad_numbers_are_jumpers no)
		(fp_line
			(start 0.299974 0.150114)
			(end -0.299974 0.150114)
			(stroke
				(width 0.1)
				(type default)
			)
			(layer "F.Fab")
		)
		(fp_line
			(start 0.299974 -0.150114)
			(end 0.299974 0.150114)
			(stroke
				(width 0.1)
				(type default)
			)
			(layer "F.Fab")
		)
		(fp_line
			(start -0.299974 0.150114)
			(end -0.299974 -0.150114)
			(stroke
				(width 0.1)
				(type default)
			)
			(layer "F.Fab")
		)
		(fp_line
			(start -0.299974 -0.150114)
			(end 0.299974 -0.150114)
			(stroke
				(width 0.1)
				(type default)
			)
			(layer "F.Fab")
		)
		(pad "1" smd rect
			(at -0.2667 0 180)
			(size 0.3048 0.381)
			(layers "F.Cu" "F.Mask" "F.Paste")
			(net "P5E_PEX3_STN2_TX_DN<33>")
		)
		(pad "2" smd rect
			(at 0.2667 0 180)
			(size 0.3048 0.381)
			(layers "F.Cu" "F.Mask" "F.Paste")
			(net "P5E_PEX3_STN2_TX_C_DN<33>")
		)
	)
	(footprint ""
		(layer "F.Cu")
		(at 378.2949 -356.244906 90)
		(property "Reference" "C769"
			(at 0 0 90)
			(layer "F.SilkS")
			(hide yes)
			(effects
				(font
					(size 1.27 1.27)
				)
			)
		)
		(property "Value" ""
			(at 0 0 90)
			(layer "F.Fab")
			(effects
				(font
					(size 1.27 1.27)
				)
			)
		)
		(duplicate_pad_numbers_are_jumpers no)
		(fp_line
			(start 0.299974 -0.150114)
			(end 0.299974 0.150114)
			(stroke
				(width 0.1)
				(type default)
			)
			(layer "F.Fab")
		)
		(fp_line
			(start -0.299974 -0.150114)
			(end 0.299974 -0.150114)
			(stroke
				(width 0.1)
				(type default)
			)
			(layer "F.Fab")
		)
		(fp_line
			(start 0.299974 0.150114)
			(end -0.299974 0.150114)
			(stroke
				(width 0.1)
				(type default)
			)
			(layer "F.Fab")
		)
		(fp_line
			(start -0.299974 0.150114)
			(end -0.299974 -0.150114)
			(stroke
				(width 0.1)
				(type default)
			)
			(layer "F.Fab")
		)
		(pad "1" smd rect
			(at -0.2667 0 90)
			(size 0.3048 0.381)
			(layers "F.Cu" "F.Mask" "F.Paste")
			(net "P5E_PEX3_STN6_TX_DN<108>")
		)
		(pad "2" smd rect
			(at 0.2667 0 90)
			(size 0.3048 0.381)
			(layers "F.Cu" "F.Mask" "F.Paste")
			(net "P5E_PEX3_STN6_TX_C_DN<108>")
		)
	)
	(footprint ""
		(layer "F.Cu")
		(at 186.996832 -410.070554 180)
		(property "Reference" "Q125"
			(at 2.00406 -1.206754 90)
			(unlocked yes)
			(layer "F.SilkS")
			(effects
				(font
					(size 0.7874 0.5842)
					(thickness 0.1524)
				)
				(justify left)
			)
		)
		(property "Value" ""
			(at 0 0 180)
			(layer "F.Fab")
			(effects
				(font
					(size 1.27 1.27)
				)
			)
		)
		(duplicate_pad_numbers_are_jumpers no)
		(fp_line
			(start 1.335278 1.100074)
			(end 1.335278 -1.100074)
			(stroke
				(width 0.1524)
				(type default)
			)
			(layer "F.SilkS")
		)
		(fp_line
			(start 1.335278 -1.100074)
			(end -1.335278 -1.100074)
			(stroke
				(width 0.1524)
				(type default)
			)
			(layer "F.SilkS")
		)
		(fp_line
			(start -1.335278 1.100074)
			(end 1.335278 1.100074)
			(stroke
				(width 0.1524)
				(type default)
			)
			(layer "F.SilkS")
		)
		(fp_line
			(start -1.335278 -1.100074)
			(end -1.335278 1.100074)
			(stroke
				(width 0.1524)
				(type default)
			)
			(layer "F.SilkS")
		)
		(fp_line
			(start 0.674878 1.100074)
			(end 0.674878 -1.100074)
			(stroke
				(width 0.1)
				(type default)
			)
			(layer "F.Fab")
		)
		(fp_line
			(start 0.674878 -1.100074)
			(end -0.674878 -1.100074)
			(stroke
				(width 0.1)
				(type default)
			)
			(layer "F.Fab")
		)
		(fp_line
			(start -0.674878 1.100074)
			(end 0.674878 1.100074)
			(stroke
				(width 0.1)
				(type default)
			)
			(layer "F.Fab")
		)
		(fp_line
			(start -0.674878 -1.100074)
			(end -0.674878 1.100074)
			(stroke
				(width 0.1)
				(type default)
			)
			(layer "F.Fab")
		)
		(pad "D" smd rect
			(at 0.8001 0 90)
			(size 0.6096 0.8128)
			(layers "F.Cu" "F.Mask" "F.Paste")
			(net "HSC_UV_N")
		)
		(pad "G" smd rect
			(at -0.8001 -0.649986 90)
			(size 0.6096 0.8128)
			(layers "F.Cu" "F.Mask" "F.Paste")
			(net "A_P12V_AUX_FPH_GATE")
		)
		(pad "S" smd rect
			(at -0.8001 0.649986 90)
			(size 0.6096 0.8128)
			(layers "F.Cu" "F.Mask" "F.Paste")
			(net "GND")
		)
	)
	(footprint ""
		(layer "F.Cu")
		(at 294.76319 -195.362068 90)
		(property "Reference" "R3392"
			(at 0 0 90)
			(layer "F.SilkS")
			(hide yes)
			(effects
				(font
					(size 1.27 1.27)
				)
			)
		)
		(property "Value" ""
			(at 0 0 90)
			(layer "F.Fab")
			(effects
				(font
					(size 1.27 1.27)
				)
			)
		)
		(duplicate_pad_numbers_are_jumpers no)
		(fp_line
			(start 0.7874 -0.4064)
			(end 0.7874 0.4064)
			(stroke
				(width 0.1524)
				(type default)
			)
			(layer "F.SilkS")
		)
		(fp_line
			(start -0.7874 -0.4064)
			(end 0.7874 -0.4064)
			(stroke
				(width 0.1524)
				(type default)
			)
			(layer "F.SilkS")
		)
		(fp_line
			(start 0.7874 0.4064)
			(end -0.7874 0.4064)
			(stroke
				(width 0.1524)
				(type default)
			)
			(layer "F.SilkS")
		)
		(fp_line
			(start -0.7874 0.4064)
			(end -0.7874 -0.4064)
			(stroke
				(width 0.1524)
				(type default)
			)
			(layer "F.SilkS")
		)
		(fp_line
			(start -0.12065 -0.305054)
			(end -0.12065 -0.2794)
			(stroke
				(width 0.1)
				(type default)
			)
			(layer "F.Fab")
		)
		(fp_line
			(start -0.67945 -0.305054)
			(end -0.12065 -0.305054)
			(stroke
				(width 0.1)
				(type default)
			)
			(layer "F.Fab")
		)
		(fp_line
			(start 0.67945 -0.3048)
			(end 0.67945 0.3048)
			(stroke
				(width 0.1)
				(type default)
			)
			(layer "F.Fab")
		)
		(fp_line
			(start 0.12065 -0.3048)
			(end 0.67945 -0.3048)
			(stroke
				(width 0.1)
				(type default)
			)
			(layer "F.Fab")
		)
		(fp_line
			(start 0.12065 -0.2794)
			(end 0.12065 -0.3048)
			(stroke
				(width 0.1)
				(type default)
			)
			(layer "F.Fab")
		)
		(fp_line
			(start -0.12065 -0.2794)
			(end 0.12065 -0.2794)
			(stroke
				(width 0.1)
				(type default)
			)
			(layer "F.Fab")
		)
		(fp_line
			(start 0.120396 0.2794)
			(end -0.12065 0.2794)
			(stroke
				(width 0.1)
				(type default)
			)
			(layer "F.Fab")
		)
		(fp_line
			(start -0.12065 0.2794)
			(end -0.12065 0.3048)
			(stroke
				(width 0.1)
				(type default)
			)
			(layer "F.Fab")
		)
		(fp_line
			(start 0.67945 0.3048)
			(end 0.120396 0.3048)
			(stroke
				(width 0.1)
				(type default)
			)
			(layer "F.Fab")
		)
		(fp_line
			(start 0.120396 0.3048)
			(end 0.120396 0.2794)
			(stroke
				(width 0.1)
				(type default)
			)
			(layer "F.Fab")
		)
		(fp_line
			(start -0.12065 0.3048)
			(end -0.67945 0.3048)
			(stroke
				(width 0.1)
				(type default)
			)
			(layer "F.Fab")
		)
		(fp_line
			(start -0.67945 0.3048)
			(end -0.67945 -0.305054)
			(stroke
				(width 0.1)
				(type default)
			)
			(layer "F.Fab")
		)
		(pad "1" smd circle
			(at -0.40005 0 90)
			(size 0 0)
			(layers "F.Cu" "F.Mask" "F.Paste")
			(net "SPI_BIC1_MOSI_R2")
		)
		(pad "2" smd circle
			(at 0.40005 0 90)
			(size 0 0)
			(layers "F.Cu" "F.Mask" "F.Paste")
			(net "SPI_BIC1_MOSI_R4")
		)
	)
	(footprint ""
		(layer "F.Cu")
		(at 130.38074 -118.378986 90)
		(property "Reference" "PC796"
			(at 0 0 90)
			(layer "F.SilkS")
			(hide yes)
			(effects
				(font
					(size 1.27 1.27)
				)
			)
		)
		(property "Value" ""
			(at 0 0 90)
			(layer "F.Fab")
			(effects
				(font
					(size 1.27 1.27)
				)
			)
		)
		(duplicate_pad_numbers_are_jumpers no)
		(fp_line
			(start 0.7874 -0.4064)
			(end 0.7874 0.4064)
			(stroke
				(width 0.1524)
				(type default)
			)
			(layer "F.SilkS")
		)
		(fp_line
			(start -0.7874 -0.4064)
			(end 0.7874 -0.4064)
			(stroke
				(width 0.1524)
				(type default)
			)
			(layer "F.SilkS")
		)
		(fp_line
			(start 0.7874 0.4064)
			(end -0.7874 0.4064)
			(stroke
				(width 0.1524)
				(type default)
			)
			(layer "F.SilkS")
		)
		(fp_line
			(start -0.7874 0.4064)
			(end -0.7874 -0.4064)
			(stroke
				(width 0.1524)
				(type default)
			)
			(layer "F.SilkS")
		)
		(fp_line
			(start -0.12065 -0.305054)
			(end -0.12065 -0.2794)
			(stroke
				(width 0.1)
				(type default)
			)
			(layer "F.Fab")
		)
		(fp_line
			(start -0.67945 -0.305054)
			(end -0.12065 -0.305054)
			(stroke
				(width 0.1)
				(type default)
			)
			(layer "F.Fab")
		)
		(fp_line
			(start 0.67945 -0.3048)
			(end 0.67945 0.3048)
			(stroke
				(width 0.1)
				(type default)
			)
			(layer "F.Fab")
		)
		(fp_line
			(start 0.12065 -0.3048)
			(end 0.67945 -0.3048)
			(stroke
				(width 0.1)
				(type default)
			)
			(layer "F.Fab")
		)
		(fp_line
			(start 0.12065 -0.2794)
			(end 0.12065 -0.3048)
			(stroke
				(width 0.1)
				(type default)
			)
			(layer "F.Fab")
		)
		(fp_line
			(start -0.12065 -0.2794)
			(end 0.12065 -0.2794)
			(stroke
				(width 0.1)
				(type default)
			)
			(layer "F.Fab")
		)
		(fp_line
			(start 0.120396 0.2794)
			(end -0.12065 0.2794)
			(stroke
				(width 0.1)
				(type default)
			)
			(layer "F.Fab")
		)
		(fp_line
			(start -0.12065 0.2794)
			(end -0.12065 0.3048)
			(stroke
				(width 0.1)
				(type default)
			)
			(layer "F.Fab")
		)
		(fp_line
			(start 0.67945 0.3048)
			(end 0.120396 0.3048)
			(stroke
				(width 0.1)
				(type default)
			)
			(layer "F.Fab")
		)
		(fp_line
			(start 0.120396 0.3048)
			(end 0.120396 0.2794)
			(stroke
				(width 0.1)
				(type default)
			)
			(layer "F.Fab")
		)
		(fp_line
			(start -0.12065 0.3048)
			(end -0.67945 0.3048)
			(stroke
				(width 0.1)
				(type default)
			)
			(layer "F.Fab")
		)
		(fp_line
			(start -0.67945 0.3048)
			(end -0.67945 -0.305054)
			(stroke
				(width 0.1)
				(type default)
			)
			(layer "F.Fab")
		)
		(pad "1" smd circle
			(at -0.40005 0 90)
			(size 0 0)
			(layers "F.Cu" "F.Mask" "F.Paste")
			(net "P3V3_NIC2_CO_DV_DT")
		)
		(pad "2" smd circle
			(at 0.40005 0 90)
			(size 0 0)
			(layers "F.Cu" "F.Mask" "F.Paste")
			(net "GND")
		)
	)
	(footprint ""
		(layer "F.Cu")
		(at 256.717546 -207.1116 -90)
		(property "Reference" "R5643"
			(at 0 0 270)
			(layer "F.SilkS")
			(hide yes)
			(effects
				(font
					(size 1.27 1.27)
				)
			)
		)
		(property "Value" ""
			(at 0 0 270)
			(layer "F.Fab")
			(effects
				(font
					(size 1.27 1.27)
				)
			)
		)
		(duplicate_pad_numbers_are_jumpers no)
		(fp_line
			(start -0.7874 0.4064)
			(end -0.7874 -0.4064)
			(stroke
				(width 0.1524)
				(type default)
			)
			(layer "F.SilkS")
		)
		(fp_line
			(start 0.7874 0.4064)
			(end -0.7874 0.4064)
			(stroke
				(width 0.1524)
				(type default)
			)
			(layer "F.SilkS")
		)
		(fp_line
			(start -0.7874 -0.4064)
			(end 0.7874 -0.4064)
			(stroke
				(width 0.1524)
				(type default)
			)
			(layer "F.SilkS")
		)
		(fp_line
			(start 0.7874 -0.4064)
			(end 0.7874 0.4064)
			(stroke
				(width 0.1524)
				(type default)
			)
			(layer "F.SilkS")
		)
		(fp_line
			(start -0.67945 0.3048)
			(end -0.67945 -0.305054)
			(stroke
				(width 0.1)
				(type default)
			)
			(layer "F.Fab")
		)
		(fp_line
			(start -0.12065 0.3048)
			(end -0.67945 0.3048)
			(stroke
				(width 0.1)
				(type default)
			)
			(layer "F.Fab")
		)
		(fp_line
			(start 0.120396 0.3048)
			(end 0.120396 0.2794)
			(stroke
				(width 0.1)
				(type default)
			)
			(layer "F.Fab")
		)
		(fp_line
			(start 0.67945 0.3048)
			(end 0.120396 0.3048)
			(stroke
				(width 0.1)
				(type default)
			)
			(layer "F.Fab")
		)
		(fp_line
			(start -0.12065 0.2794)
			(end -0.12065 0.3048)
			(stroke
				(width 0.1)
				(type default)
			)
			(layer "F.Fab")
		)
		(fp_line
			(start 0.120396 0.2794)
			(end -0.12065 0.2794)
			(stroke
				(width 0.1)
				(type default)
			)
			(layer "F.Fab")
		)
		(fp_line
			(start -0.12065 -0.2794)
			(end 0.12065 -0.2794)
			(stroke
				(width 0.1)
				(type default)
			)
			(layer "F.Fab")
		)
		(fp_line
			(start 0.12065 -0.2794)
			(end 0.12065 -0.3048)
			(stroke
				(width 0.1)
				(type default)
			)
			(layer "F.Fab")
		)
		(fp_line
			(start 0.12065 -0.3048)
			(end 0.67945 -0.3048)
			(stroke
				(width 0.1)
				(type default)
			)
			(layer "F.Fab")
		)
		(fp_line
			(start 0.67945 -0.3048)
			(end 0.67945 0.3048)
			(stroke
				(width 0.1)
				(type default)
			)
			(layer "F.Fab")
		)
		(fp_line
			(start -0.67945 -0.305054)
			(end -0.12065 -0.305054)
			(stroke
				(width 0.1)
				(type default)
			)
			(layer "F.Fab")
		)
		(fp_line
			(start -0.12065 -0.305054)
			(end -0.12065 -0.2794)
			(stroke
				(width 0.1)
				(type default)
			)
			(layer "F.Fab")
		)
		(pad "1" smd circle
			(at -0.40005 0 270)
			(size 0 0)
			(layers "F.Cu" "F.Mask" "F.Paste")
			(net "JTAG_BIC_TDI_R")
		)
		(pad "2" smd circle
			(at 0.40005 0 270)
			(size 0 0)
			(layers "F.Cu" "F.Mask" "F.Paste")
			(net "JTAG_BIC_TDI_R1")
		)
	)
	(footprint ""
		(layer "F.Cu")
		(at 262.281924 -299.391832 180)
		(property "Reference" "C3379"
			(at 0 0 180)
			(layer "F.SilkS")
			(hide yes)
			(effects
				(font
					(size 1.27 1.27)
				)
			)
		)
		(property "Value" ""
			(at 0 0 180)
			(layer "F.Fab")
			(effects
				(font
					(size 1.27 1.27)
				)
			)
		)
		(duplicate_pad_numbers_are_jumpers no)
		(fp_line
			(start 1.2954 0.5842)
			(end -1.2954 0.5842)
			(stroke
				(width 0.1524)
				(type default)
			)
			(layer "F.SilkS")
		)
		(fp_line
			(start 1.2954 -0.5842)
			(end 1.2954 0.5842)
			(stroke
				(width 0.1524)
				(type default)
			)
			(layer "F.SilkS")
		)
		(fp_line
			(start -1.2954 0.5842)
			(end -1.2954 -0.5842)
			(stroke
				(width 0.1524)
				(type default)
			)
			(layer "F.SilkS")
		)
		(fp_line
			(start -1.2954 -0.5842)
			(end 1.2954 -0.5842)
			(stroke
				(width 0.1524)
				(type default)
			)
			(layer "F.SilkS")
		)
		(fp_line
			(start 1.1938 0.4064)
			(end 0.8636 0.4064)
			(stroke
				(width 0.1)
				(type default)
			)
			(layer "F.Fab")
		)
		(fp_line
			(start 1.1938 -0.4064)
			(end 1.1938 0.4064)
			(stroke
				(width 0.1)
				(type default)
			)
			(layer "F.Fab")
		)
		(fp_line
			(start 0.8636 0.4572)
			(end -0.8636 0.4572)
			(stroke
				(width 0.1)
				(type default)
			)
			(layer "F.Fab")
		)
		(fp_line
			(start 0.8636 0.4064)
			(end 0.8636 0.4572)
			(stroke
				(width 0.1)
				(type default)
			)
			(layer "F.Fab")
		)
		(fp_line
			(start 0.8636 -0.4064)
			(end 1.1938 -0.4064)
			(stroke
				(width 0.1)
				(type default)
			)
			(layer "F.Fab")
		)
		(fp_line
			(start 0.8636 -0.4572)
			(end 0.8636 -0.4064)
			(stroke
				(width 0.1)
				(type default)
			)
			(layer "F.Fab")
		)
		(fp_line
			(start -0.8636 0.4572)
			(end -0.8636 0.4064)
			(stroke
				(width 0.1)
				(type default)
			)
			(layer "F.Fab")
		)
		(fp_line
			(start -0.8636 0.4064)
			(end -1.1938 0.4064)
			(stroke
				(width 0.1)
				(type default)
			)
			(layer "F.Fab")
		)
		(fp_line
			(start -0.8636 -0.4064)
			(end -0.8636 -0.4572)
			(stroke
				(width 0.1)
				(type default)
			)
			(layer "F.Fab")
		)
		(fp_line
			(start -0.8636 -0.4572)
			(end 0.8636 -0.4572)
			(stroke
				(width 0.1)
				(type default)
			)
			(layer "F.Fab")
		)
		(fp_line
			(start -1.1938 0.4064)
			(end -1.1938 -0.4064)
			(stroke
				(width 0.1)
				(type default)
			)
			(layer "F.Fab")
		)
		(fp_line
			(start -1.1938 -0.4064)
			(end -0.8636 -0.4064)
			(stroke
				(width 0.1)
				(type default)
			)
			(layer "F.Fab")
		)
		(pad "1" smd rect
			(at -0.7366 0 90)
			(size 0.7112 0.8128)
			(layers "F.Cu" "F.Mask" "F.Paste")
			(net "PCEPLL1_VDDA18_PEX2_R")
		)
		(pad "2" smd rect
			(at 0.7366 0 90)
			(size 0.7112 0.8128)
			(layers "F.Cu" "F.Mask" "F.Paste")
			(net "GND")
		)
	)
	(footprint ""
		(layer "F.Cu")
		(at 323.573648 -298.885102 -90)
		(property "Reference" "R4017"
			(at 0 0 270)
			(layer "F.SilkS")
			(hide yes)
			(effects
				(font
					(size 1.27 1.27)
				)
			)
		)
		(property "Value" ""
			(at 0 0 270)
			(layer "F.Fab")
			(effects
				(font
					(size 1.27 1.27)
				)
			)
		)
		(duplicate_pad_numbers_are_jumpers no)
		(fp_line
			(start -0.7874 0.4064)
			(end -0.7874 -0.4064)
			(stroke
				(width 0.1524)
				(type default)
			)
			(layer "F.SilkS")
		)
		(fp_line
			(start 0.7874 0.4064)
			(end -0.7874 0.4064)
			(stroke
				(width 0.1524)
				(type default)
			)
			(layer "F.SilkS")
		)
		(fp_line
			(start -0.7874 -0.4064)
			(end 0.7874 -0.4064)
			(stroke
				(width 0.1524)
				(type default)
			)
			(layer "F.SilkS")
		)
		(fp_line
			(start 0.7874 -0.4064)
			(end 0.7874 0.4064)
			(stroke
				(width 0.1524)
				(type default)
			)
			(layer "F.SilkS")
		)
		(fp_line
			(start -0.67945 0.3048)
			(end -0.67945 -0.305054)
			(stroke
				(width 0.1)
				(type default)
			)
			(layer "F.Fab")
		)
		(fp_line
			(start -0.12065 0.3048)
			(end -0.67945 0.3048)
			(stroke
				(width 0.1)
				(type default)
			)
			(layer "F.Fab")
		)
		(fp_line
			(start 0.120396 0.3048)
			(end 0.120396 0.2794)
			(stroke
				(width 0.1)
				(type default)
			)
			(layer "F.Fab")
		)
		(fp_line
			(start 0.67945 0.3048)
			(end 0.120396 0.3048)
			(stroke
				(width 0.1)
				(type default)
			)
			(layer "F.Fab")
		)
		(fp_line
			(start -0.12065 0.2794)
			(end -0.12065 0.3048)
			(stroke
				(width 0.1)
				(type default)
			)
			(layer "F.Fab")
		)
		(fp_line
			(start 0.120396 0.2794)
			(end -0.12065 0.2794)
			(stroke
				(width 0.1)
				(type default)
			)
			(layer "F.Fab")
		)
		(fp_line
			(start -0.12065 -0.2794)
			(end 0.12065 -0.2794)
			(stroke
				(width 0.1)
				(type default)
			)
			(layer "F.Fab")
		)
		(fp_line
			(start 0.12065 -0.2794)
			(end 0.12065 -0.3048)
			(stroke
				(width 0.1)
				(type default)
			)
			(layer "F.Fab")
		)
		(fp_line
			(start 0.12065 -0.3048)
			(end 0.67945 -0.3048)
			(stroke
				(width 0.1)
				(type default)
			)
			(layer "F.Fab")
		)
		(fp_line
			(start 0.67945 -0.3048)
			(end 0.67945 0.3048)
			(stroke
				(width 0.1)
				(type default)
			)
			(layer "F.Fab")
		)
		(fp_line
			(start -0.67945 -0.305054)
			(end -0.12065 -0.305054)
			(stroke
				(width 0.1)
				(type default)
			)
			(layer "F.Fab")
		)
		(fp_line
			(start -0.12065 -0.305054)
			(end -0.12065 -0.2794)
			(stroke
				(width 0.1)
				(type default)
			)
			(layer "F.Fab")
		)
		(pad "1" smd circle
			(at -0.40005 0 270)
			(size 0 0)
			(layers "F.Cu" "F.Mask" "F.Paste")
			(net "P1V8_PEX")
		)
		(pad "2" smd circle
			(at 0.40005 0 270)
			(size 0 0)
			(layers "F.Cu" "F.Mask" "F.Paste")
			(net "I2C_PEX2_HOST_R_SCL")
		)
	)
	(footprint ""
		(layer "F.Cu")
		(at 83.034124 -8.078724)
		(property "Reference" "R5811"
			(at 0 0 0)
			(layer "F.SilkS")
			(hide yes)
			(effects
				(font
					(size 1.27 1.27)
				)
			)
		)
		(property "Value" ""
			(at 0 0 0)
			(layer "F.Fab")
			(effects
				(font
					(size 1.27 1.27)
				)
			)
		)
		(duplicate_pad_numbers_are_jumpers no)
		(fp_line
			(start -0.7874 -0.4064)
			(end 0.7874 -0.4064)
			(stroke
				(width 0.1524)
				(type default)
			)
			(layer "F.SilkS")
		)
		(fp_line
			(start -0.7874 0.4064)
			(end -0.7874 -0.4064)
			(stroke
				(width 0.1524)
				(type default)
			)
			(layer "F.SilkS")
		)
		(fp_line
			(start 0.7874 -0.4064)
			(end 0.7874 0.4064)
			(stroke
				(width 0.1524)
				(type default)
			)
			(layer "F.SilkS")
		)
		(fp_line
			(start 0.7874 0.4064)
			(end -0.7874 0.4064)
			(stroke
				(width 0.1524)
				(type default)
			)
			(layer "F.SilkS")
		)
		(fp_line
			(start -0.67945 -0.305054)
			(end -0.12065 -0.305054)
			(stroke
				(width 0.1)
				(type default)
			)
			(layer "F.Fab")
		)
		(fp_line
			(start -0.67945 0.3048)
			(end -0.67945 -0.305054)
			(stroke
				(width 0.1)
				(type default)
			)
			(layer "F.Fab")
		)
		(fp_line
			(start -0.12065 -0.305054)
			(end -0.12065 -0.2794)
			(stroke
				(width 0.1)
				(type default)
			)
			(layer "F.Fab")
		)
		(fp_line
			(start -0.12065 -0.2794)
			(end 0.12065 -0.2794)
			(stroke
				(width 0.1)
				(type default)
			)
			(layer "F.Fab")
		)
		(fp_line
			(start -0.12065 0.2794)
			(end -0.12065 0.3048)
			(stroke
				(width 0.1)
				(type default)
			)
			(layer "F.Fab")
		)
		(fp_line
			(start -0.12065 0.3048)
			(end -0.67945 0.3048)
			(stroke
				(width 0.1)
				(type default)
			)
			(layer "F.Fab")
		)
		(fp_line
			(start 0.120396 0.2794)
			(end -0.12065 0.2794)
			(stroke
				(width 0.1)
				(type default)
			)
			(layer "F.Fab")
		)
		(fp_line
			(start 0.120396 0.3048)
			(end 0.120396 0.2794)
			(stroke
				(width 0.1)
				(type default)
			)
			(layer "F.Fab")
		)
		(fp_line
			(start 0.12065 -0.3048)
			(end 0.67945 -0.3048)
			(stroke
				(width 0.1)
				(type default)
			)
			(layer "F.Fab")
		)
		(fp_line
			(start 0.12065 -0.2794)
			(end 0.12065 -0.3048)
			(stroke
				(width 0.1)
				(type default)
			)
			(layer "F.Fab")
		)
		(fp_line
			(start 0.67945 -0.3048)
			(end 0.67945 0.3048)
			(stroke
				(width 0.1)
				(type default)
			)
			(layer "F.Fab")
		)
		(fp_line
			(start 0.67945 0.3048)
			(end 0.120396 0.3048)
			(stroke
				(width 0.1)
				(type default)
			)
			(layer "F.Fab")
		)
		(pad "1" smd circle
			(at -0.40005 0)
			(size 0 0)
			(layers "F.Cu" "F.Mask" "F.Paste")
			(net "LM75_2_A0")
		)
		(pad "2" smd circle
			(at 0.40005 0)
			(size 0 0)
			(layers "F.Cu" "F.Mask" "F.Paste")
			(net "GND")
		)
	)
	(footprint ""
		(layer "F.Cu")
		(at 365.506 -202.819 180)
		(property "Reference" "R4699"
			(at 0 0 180)
			(layer "F.SilkS")
			(hide yes)
			(effects
				(font
					(size 1.27 1.27)
				)
			)
		)
		(property "Value" ""
			(at 0 0 180)
			(layer "F.Fab")
			(effects
				(font
					(size 1.27 1.27)
				)
			)
		)
		(duplicate_pad_numbers_are_jumpers no)
		(fp_line
			(start 0.7874 0.4064)
			(end -0.7874 0.4064)
			(stroke
				(width 0.1524)
				(type default)
			)
			(layer "F.SilkS")
		)
		(fp_line
			(start 0.7874 -0.4064)
			(end 0.7874 0.4064)
			(stroke
				(width 0.1524)
				(type default)
			)
			(layer "F.SilkS")
		)
		(fp_line
			(start -0.7874 0.4064)
			(end -0.7874 -0.4064)
			(stroke
				(width 0.1524)
				(type default)
			)
			(layer "F.SilkS")
		)
		(fp_line
			(start -0.7874 -0.4064)
			(end 0.7874 -0.4064)
			(stroke
				(width 0.1524)
				(type default)
			)
			(layer "F.SilkS")
		)
		(fp_line
			(start 0.67945 0.3048)
			(end 0.120396 0.3048)
			(stroke
				(width 0.1)
				(type default)
			)
			(layer "F.Fab")
		)
		(fp_line
			(start 0.67945 -0.3048)
			(end 0.67945 0.3048)
			(stroke
				(width 0.1)
				(type default)
			)
			(layer "F.Fab")
		)
		(fp_line
			(start 0.12065 -0.2794)
			(end 0.12065 -0.3048)
			(stroke
				(width 0.1)
				(type default)
			)
			(layer "F.Fab")
		)
		(fp_line
			(start 0.12065 -0.3048)
			(end 0.67945 -0.3048)
			(stroke
				(width 0.1)
				(type default)
			)
			(layer "F.Fab")
		)
		(fp_line
			(start 0.120396 0.3048)
			(end 0.120396 0.2794)
			(stroke
				(width 0.1)
				(type default)
			)
			(layer "F.Fab")
		)
		(fp_line
			(start 0.120396 0.2794)
			(end -0.12065 0.2794)
			(stroke
				(width 0.1)
				(type default)
			)
			(layer "F.Fab")
		)
		(fp_line
			(start -0.12065 0.3048)
			(end -0.67945 0.3048)
			(stroke
				(width 0.1)
				(type default)
			)
			(layer "F.Fab")
		)
		(fp_line
			(start -0.12065 0.2794)
			(end -0.12065 0.3048)
			(stroke
				(width 0.1)
				(type default)
			)
			(layer "F.Fab")
		)
		(fp_line
			(start -0.12065 -0.2794)
			(end 0.12065 -0.2794)
			(stroke
				(width 0.1)
				(type default)
			)
			(layer "F.Fab")
		)
		(fp_line
			(start -0.12065 -0.305054)
			(end -0.12065 -0.2794)
			(stroke
				(width 0.1)
				(type default)
			)
			(layer "F.Fab")
		)
		(fp_line
			(start -0.67945 0.3048)
			(end -0.67945 -0.305054)
			(stroke
				(width 0.1)
				(type default)
			)
			(layer "F.Fab")
		)
		(fp_line
			(start -0.67945 -0.305054)
			(end -0.12065 -0.305054)
			(stroke
				(width 0.1)
				(type default)
			)
			(layer "F.Fab")
		)
		(pad "1" smd circle
			(at -0.40005 0 180)
			(size 0 0)
			(layers "F.Cu" "F.Mask" "F.Paste")
			(net "GND")
		)
		(pad "2" smd circle
			(at 0.40005 0 180)
			(size 0 0)
			(layers "F.Cu" "F.Mask" "F.Paste")
			(net "PCA9555_0_PEX1_A1")
		)
	)
	(footprint ""
		(layer "F.Cu")
		(at 28.633928 -343.952322 90)
		(property "Reference" "C183"
			(at 0 0 90)
			(layer "F.SilkS")
			(hide yes)
			(effects
				(font
					(size 1.27 1.27)
				)
			)
		)
		(property "Value" ""
			(at 0 0 90)
			(layer "F.Fab")
			(effects
				(font
					(size 1.27 1.27)
				)
			)
		)
		(duplicate_pad_numbers_are_jumpers no)
		(fp_line
			(start 0.299974 -0.150114)
			(end 0.299974 0.150114)
			(stroke
				(width 0.1)
				(type default)
			)
			(layer "F.Fab")
		)
		(fp_line
			(start -0.299974 -0.150114)
			(end 0.299974 -0.150114)
			(stroke
				(width 0.1)
				(type default)
			)
			(layer "F.Fab")
		)
		(fp_line
			(start 0.299974 0.150114)
			(end -0.299974 0.150114)
			(stroke
				(width 0.1)
				(type default)
			)
			(layer "F.Fab")
		)
		(fp_line
			(start -0.299974 0.150114)
			(end -0.299974 -0.150114)
			(stroke
				(width 0.1)
				(type default)
			)
			(layer "F.Fab")
		)
		(pad "1" smd rect
			(at -0.2667 0 90)
			(size 0.3048 0.381)
			(layers "F.Cu" "F.Mask" "F.Paste")
			(net "P5E_PEX0_STN7_TX_DP<116>")
		)
		(pad "2" smd rect
			(at 0.2667 0 90)
			(size 0.3048 0.381)
			(layers "F.Cu" "F.Mask" "F.Paste")
			(net "P5E_PEX0_STN7_TX_C_DP<116>")
		)
	)
	(footprint ""
		(layer "F.Cu")
		(at 263.654286 -252.356874 -90)
		(property "Reference" "R1360"
			(at 0 0 270)
			(layer "F.SilkS")
			(hide yes)
			(effects
				(font
					(size 1.27 1.27)
				)
			)
		)
		(property "Value" ""
			(at 0 0 270)
			(layer "F.Fab")
			(effects
				(font
					(size 1.27 1.27)
				)
			)
		)
		(duplicate_pad_numbers_are_jumpers no)
		(fp_line
			(start -0.7874 0.4064)
			(end -0.7874 -0.4064)
			(stroke
				(width 0.1524)
				(type default)
			)
			(layer "F.SilkS")
		)
		(fp_line
			(start 0.7874 0.4064)
			(end -0.7874 0.4064)
			(stroke
				(width 0.1524)
				(type default)
			)
			(layer "F.SilkS")
		)
		(fp_line
			(start -0.7874 -0.4064)
			(end 0.7874 -0.4064)
			(stroke
				(width 0.1524)
				(type default)
			)
			(layer "F.SilkS")
		)
		(fp_line
			(start 0.7874 -0.4064)
			(end 0.7874 0.4064)
			(stroke
				(width 0.1524)
				(type default)
			)
			(layer "F.SilkS")
		)
		(fp_line
			(start -0.67945 0.3048)
			(end -0.67945 -0.305054)
			(stroke
				(width 0.1)
				(type default)
			)
			(layer "F.Fab")
		)
		(fp_line
			(start -0.12065 0.3048)
			(end -0.67945 0.3048)
			(stroke
				(width 0.1)
				(type default)
			)
			(layer "F.Fab")
		)
		(fp_line
			(start 0.120396 0.3048)
			(end 0.120396 0.2794)
			(stroke
				(width 0.1)
				(type default)
			)
			(layer "F.Fab")
		)
		(fp_line
			(start 0.67945 0.3048)
			(end 0.120396 0.3048)
			(stroke
				(width 0.1)
				(type default)
			)
			(layer "F.Fab")
		)
		(fp_line
			(start -0.12065 0.2794)
			(end -0.12065 0.3048)
			(stroke
				(width 0.1)
				(type default)
			)
			(layer "F.Fab")
		)
		(fp_line
			(start 0.120396 0.2794)
			(end -0.12065 0.2794)
			(stroke
				(width 0.1)
				(type default)
			)
			(layer "F.Fab")
		)
		(fp_line
			(start -0.12065 -0.2794)
			(end 0.12065 -0.2794)
			(stroke
				(width 0.1)
				(type default)
			)
			(layer "F.Fab")
		)
		(fp_line
			(start 0.12065 -0.2794)
			(end 0.12065 -0.3048)
			(stroke
				(width 0.1)
				(type default)
			)
			(layer "F.Fab")
		)
		(fp_line
			(start 0.12065 -0.3048)
			(end 0.67945 -0.3048)
			(stroke
				(width 0.1)
				(type default)
			)
			(layer "F.Fab")
		)
		(fp_line
			(start 0.67945 -0.3048)
			(end 0.67945 0.3048)
			(stroke
				(width 0.1)
				(type default)
			)
			(layer "F.Fab")
		)
		(fp_line
			(start -0.67945 -0.305054)
			(end -0.12065 -0.305054)
			(stroke
				(width 0.1)
				(type default)
			)
			(layer "F.Fab")
		)
		(fp_line
			(start -0.12065 -0.305054)
			(end -0.12065 -0.2794)
			(stroke
				(width 0.1)
				(type default)
			)
			(layer "F.Fab")
		)
		(pad "1" smd circle
			(at -0.40005 0 270)
			(size 0 0)
			(layers "F.Cu" "F.Mask" "F.Paste")
			(net "GND")
		)
		(pad "2" smd circle
			(at 0.40005 0 270)
			(size 0 0)
			(layers "F.Cu" "F.Mask" "F.Paste")
			(net "PEX2_MODE_SEL4")
		)
	)
	(footprint ""
		(layer "F.Cu")
		(at 417.1315 -224.027746 180)
		(property "Reference" "R6616"
			(at 0 0 180)
			(layer "F.SilkS")
			(hide yes)
			(effects
				(font
					(size 1.27 1.27)
				)
			)
		)
		(property "Value" ""
			(at 0 0 180)
			(layer "F.Fab")
			(effects
				(font
					(size 1.27 1.27)
				)
			)
		)
		(duplicate_pad_numbers_are_jumpers no)
		(fp_line
			(start 0.7874 0.4064)
			(end -0.7874 0.4064)
			(stroke
				(width 0.1524)
				(type default)
			)
			(layer "F.SilkS")
		)
		(fp_line
			(start 0.7874 -0.4064)
			(end 0.7874 0.4064)
			(stroke
				(width 0.1524)
				(type default)
			)
			(layer "F.SilkS")
		)
		(fp_line
			(start -0.7874 0.4064)
			(end -0.7874 -0.4064)
			(stroke
				(width 0.1524)
				(type default)
			)
			(layer "F.SilkS")
		)
		(fp_line
			(start -0.7874 -0.4064)
			(end 0.7874 -0.4064)
			(stroke
				(width 0.1524)
				(type default)
			)
			(layer "F.SilkS")
		)
		(fp_line
			(start 0.67945 0.3048)
			(end 0.120396 0.3048)
			(stroke
				(width 0.1)
				(type default)
			)
			(layer "F.Fab")
		)
		(fp_line
			(start 0.67945 -0.3048)
			(end 0.67945 0.3048)
			(stroke
				(width 0.1)
				(type default)
			)
			(layer "F.Fab")
		)
		(fp_line
			(start 0.12065 -0.2794)
			(end 0.12065 -0.3048)
			(stroke
				(width 0.1)
				(type default)
			)
			(layer "F.Fab")
		)
		(fp_line
			(start 0.12065 -0.3048)
			(end 0.67945 -0.3048)
			(stroke
				(width 0.1)
				(type default)
			)
			(layer "F.Fab")
		)
		(fp_line
			(start 0.120396 0.3048)
			(end 0.120396 0.2794)
			(stroke
				(width 0.1)
				(type default)
			)
			(layer "F.Fab")
		)
		(fp_line
			(start 0.120396 0.2794)
			(end -0.12065 0.2794)
			(stroke
				(width 0.1)
				(type default)
			)
			(layer "F.Fab")
		)
		(fp_line
			(start -0.12065 0.3048)
			(end -0.67945 0.3048)
			(stroke
				(width 0.1)
				(type default)
			)
			(layer "F.Fab")
		)
		(fp_line
			(start -0.12065 0.2794)
			(end -0.12065 0.3048)
			(stroke
				(width 0.1)
				(type default)
			)
			(layer "F.Fab")
		)
		(fp_line
			(start -0.12065 -0.2794)
			(end 0.12065 -0.2794)
			(stroke
				(width 0.1)
				(type default)
			)
			(layer "F.Fab")
		)
		(fp_line
			(start -0.12065 -0.305054)
			(end -0.12065 -0.2794)
			(stroke
				(width 0.1)
				(type default)
			)
			(layer "F.Fab")
		)
		(fp_line
			(start -0.67945 0.3048)
			(end -0.67945 -0.305054)
			(stroke
				(width 0.1)
				(type default)
			)
			(layer "F.Fab")
		)
		(fp_line
			(start -0.67945 -0.305054)
			(end -0.12065 -0.305054)
			(stroke
				(width 0.1)
				(type default)
			)
			(layer "F.Fab")
		)
		(pad "1" smd circle
			(at -0.40005 0 180)
			(size 0 0)
			(layers "F.Cu" "F.Mask" "F.Paste")
			(net "UART_PEX0_SDB_BUF_R_TX")
		)
		(pad "2" smd circle
			(at 0.40005 0 180)
			(size 0 0)
			(layers "F.Cu" "F.Mask" "F.Paste")
			(net "UART_PEX0_SDB_BUF_R1_TX")
		)
	)
	(footprint ""
		(layer "F.Cu")
		(at 138.985244 -98.100642)
		(property "Reference" "R1614"
			(at 0 0 0)
			(layer "F.SilkS")
			(hide yes)
			(effects
				(font
					(size 1.27 1.27)
				)
			)
		)
		(property "Value" ""
			(at 0 0 0)
			(layer "F.Fab")
			(effects
				(font
					(size 1.27 1.27)
				)
			)
		)
		(duplicate_pad_numbers_are_jumpers no)
		(fp_line
			(start -0.7874 -0.4064)
			(end 0.7874 -0.4064)
			(stroke
				(width 0.1524)
				(type default)
			)
			(layer "F.SilkS")
		)
		(fp_line
			(start -0.7874 0.4064)
			(end -0.7874 -0.4064)
			(stroke
				(width 0.1524)
				(type default)
			)
			(layer "F.SilkS")
		)
		(fp_line
			(start 0.7874 -0.4064)
			(end 0.7874 0.4064)
			(stroke
				(width 0.1524)
				(type default)
			)
			(layer "F.SilkS")
		)
		(fp_line
			(start 0.7874 0.4064)
			(end -0.7874 0.4064)
			(stroke
				(width 0.1524)
				(type default)
			)
			(layer "F.SilkS")
		)
		(fp_line
			(start -0.67945 -0.305054)
			(end -0.12065 -0.305054)
			(stroke
				(width 0.1)
				(type default)
			)
			(layer "F.Fab")
		)
		(fp_line
			(start -0.67945 0.3048)
			(end -0.67945 -0.305054)
			(stroke
				(width 0.1)
				(type default)
			)
			(layer "F.Fab")
		)
		(fp_line
			(start -0.12065 -0.305054)
			(end -0.12065 -0.2794)
			(stroke
				(width 0.1)
				(type default)
			)
			(layer "F.Fab")
		)
		(fp_line
			(start -0.12065 -0.2794)
			(end 0.12065 -0.2794)
			(stroke
				(width 0.1)
				(type default)
			)
			(layer "F.Fab")
		)
		(fp_line
			(start -0.12065 0.2794)
			(end -0.12065 0.3048)
			(stroke
				(width 0.1)
				(type default)
			)
			(layer "F.Fab")
		)
		(fp_line
			(start -0.12065 0.3048)
			(end -0.67945 0.3048)
			(stroke
				(width 0.1)
				(type default)
			)
			(layer "F.Fab")
		)
		(fp_line
			(start 0.120396 0.2794)
			(end -0.12065 0.2794)
			(stroke
				(width 0.1)
				(type default)
			)
			(layer "F.Fab")
		)
		(fp_line
			(start 0.120396 0.3048)
			(end 0.120396 0.2794)
			(stroke
				(width 0.1)
				(type default)
			)
			(layer "F.Fab")
		)
		(fp_line
			(start 0.12065 -0.3048)
			(end 0.67945 -0.3048)
			(stroke
				(width 0.1)
				(type default)
			)
			(layer "F.Fab")
		)
		(fp_line
			(start 0.12065 -0.2794)
			(end 0.12065 -0.3048)
			(stroke
				(width 0.1)
				(type default)
			)
			(layer "F.Fab")
		)
		(fp_line
			(start 0.67945 -0.3048)
			(end 0.67945 0.3048)
			(stroke
				(width 0.1)
				(type default)
			)
			(layer "F.Fab")
		)
		(fp_line
			(start 0.67945 0.3048)
			(end 0.120396 0.3048)
			(stroke
				(width 0.1)
				(type default)
			)
			(layer "F.Fab")
		)
		(pad "1" smd circle
			(at -0.40005 0)
			(size 0 0)
			(layers "F.Cu" "F.Mask" "F.Paste")
			(net "SMB_BIC_I2C9_SSD_MUX_R_SCL")
		)
		(pad "2" smd circle
			(at 0.40005 0)
			(size 0 0)
			(layers "F.Cu" "F.Mask" "F.Paste")
			(net "SMB_BIC_I2C9_SSD_MUX1_SCL")
		)
	)
	(footprint ""
		(layer "F.Cu")
		(at 355.913436 -134.042404)
		(property "Reference" "R4453"
			(at 0 0 0)
			(layer "F.SilkS")
			(hide yes)
			(effects
				(font
					(size 1.27 1.27)
				)
			)
		)
		(property "Value" ""
			(at 0 0 0)
			(layer "F.Fab")
			(effects
				(font
					(size 1.27 1.27)
				)
			)
		)
		(duplicate_pad_numbers_are_jumpers no)
		(fp_line
			(start -0.7874 -0.4064)
			(end 0.7874 -0.4064)
			(stroke
				(width 0.1524)
				(type default)
			)
			(layer "F.SilkS")
		)
		(fp_line
			(start -0.7874 0.4064)
			(end -0.7874 -0.4064)
			(stroke
				(width 0.1524)
				(type default)
			)
			(layer "F.SilkS")
		)
		(fp_line
			(start 0.7874 -0.4064)
			(end 0.7874 0.4064)
			(stroke
				(width 0.1524)
				(type default)
			)
			(layer "F.SilkS")
		)
		(fp_line
			(start 0.7874 0.4064)
			(end -0.7874 0.4064)
			(stroke
				(width 0.1524)
				(type default)
			)
			(layer "F.SilkS")
		)
		(fp_line
			(start -0.67945 -0.305054)
			(end -0.12065 -0.305054)
			(stroke
				(width 0.1)
				(type default)
			)
			(layer "F.Fab")
		)
		(fp_line
			(start -0.67945 0.3048)
			(end -0.67945 -0.305054)
			(stroke
				(width 0.1)
				(type default)
			)
			(layer "F.Fab")
		)
		(fp_line
			(start -0.12065 -0.305054)
			(end -0.12065 -0.2794)
			(stroke
				(width 0.1)
				(type default)
			)
			(layer "F.Fab")
		)
		(fp_line
			(start -0.12065 -0.2794)
			(end 0.12065 -0.2794)
			(stroke
				(width 0.1)
				(type default)
			)
			(layer "F.Fab")
		)
		(fp_line
			(start -0.12065 0.2794)
			(end -0.12065 0.3048)
			(stroke
				(width 0.1)
				(type default)
			)
			(layer "F.Fab")
		)
		(fp_line
			(start -0.12065 0.3048)
			(end -0.67945 0.3048)
			(stroke
				(width 0.1)
				(type default)
			)
			(layer "F.Fab")
		)
		(fp_line
			(start 0.120396 0.2794)
			(end -0.12065 0.2794)
			(stroke
				(width 0.1)
				(type default)
			)
			(layer "F.Fab")
		)
		(fp_line
			(start 0.120396 0.3048)
			(end 0.120396 0.2794)
			(stroke
				(width 0.1)
				(type default)
			)
			(layer "F.Fab")
		)
		(fp_line
			(start 0.12065 -0.3048)
			(end 0.67945 -0.3048)
			(stroke
				(width 0.1)
				(type default)
			)
			(layer "F.Fab")
		)
		(fp_line
			(start 0.12065 -0.2794)
			(end 0.12065 -0.3048)
			(stroke
				(width 0.1)
				(type default)
			)
			(layer "F.Fab")
		)
		(fp_line
			(start 0.67945 -0.3048)
			(end 0.67945 0.3048)
			(stroke
				(width 0.1)
				(type default)
			)
			(layer "F.Fab")
		)
		(fp_line
			(start 0.67945 0.3048)
			(end 0.120396 0.3048)
			(stroke
				(width 0.1)
				(type default)
			)
			(layer "F.Fab")
		)
		(pad "1" smd circle
			(at -0.40005 0)
			(size 0 0)
			(layers "F.Cu" "F.Mask" "F.Paste")
			(net "HP_NIC6_EN")
		)
		(pad "2" smd circle
			(at 0.40005 0)
			(size 0 0)
			(layers "F.Cu" "F.Mask" "F.Paste")
			(net "P12V_NIC6_EN_R")
		)
	)
	(footprint ""
		(layer "F.Cu")
		(at 47.289974 -72.766682 90)
		(property "Reference" "PR6906"
			(at 0 0 90)
			(layer "F.SilkS")
			(hide yes)
			(effects
				(font
					(size 1.27 1.27)
				)
			)
		)
		(property "Value" ""
			(at 0 0 90)
			(layer "F.Fab")
			(effects
				(font
					(size 1.27 1.27)
				)
			)
		)
		(duplicate_pad_numbers_are_jumpers no)
		(fp_line
			(start 0.7874 -0.4064)
			(end 0.7874 0.4064)
			(stroke
				(width 0.1524)
				(type default)
			)
			(layer "F.SilkS")
		)
		(fp_line
			(start -0.7874 -0.4064)
			(end 0.7874 -0.4064)
			(stroke
				(width 0.1524)
				(type default)
			)
			(layer "F.SilkS")
		)
		(fp_line
			(start 0.7874 0.4064)
			(end -0.7874 0.4064)
			(stroke
				(width 0.1524)
				(type default)
			)
			(layer "F.SilkS")
		)
		(fp_line
			(start -0.7874 0.4064)
			(end -0.7874 -0.4064)
			(stroke
				(width 0.1524)
				(type default)
			)
			(layer "F.SilkS")
		)
		(fp_line
			(start -0.12065 -0.305054)
			(end -0.12065 -0.2794)
			(stroke
				(width 0.1)
				(type default)
			)
			(layer "F.Fab")
		)
		(fp_line
			(start -0.67945 -0.305054)
			(end -0.12065 -0.305054)
			(stroke
				(width 0.1)
				(type default)
			)
			(layer "F.Fab")
		)
		(fp_line
			(start 0.67945 -0.3048)
			(end 0.67945 0.3048)
			(stroke
				(width 0.1)
				(type default)
			)
			(layer "F.Fab")
		)
		(fp_line
			(start 0.12065 -0.3048)
			(end 0.67945 -0.3048)
			(stroke
				(width 0.1)
				(type default)
			)
			(layer "F.Fab")
		)
		(fp_line
			(start 0.12065 -0.2794)
			(end 0.12065 -0.3048)
			(stroke
				(width 0.1)
				(type default)
			)
			(layer "F.Fab")
		)
		(fp_line
			(start -0.12065 -0.2794)
			(end 0.12065 -0.2794)
			(stroke
				(width 0.1)
				(type default)
			)
			(layer "F.Fab")
		)
		(fp_line
			(start 0.120396 0.2794)
			(end -0.12065 0.2794)
			(stroke
				(width 0.1)
				(type default)
			)
			(layer "F.Fab")
		)
		(fp_line
			(start -0.12065 0.2794)
			(end -0.12065 0.3048)
			(stroke
				(width 0.1)
				(type default)
			)
			(layer "F.Fab")
		)
		(fp_line
			(start 0.67945 0.3048)
			(end 0.120396 0.3048)
			(stroke
				(width 0.1)
				(type default)
			)
			(layer "F.Fab")
		)
		(fp_line
			(start 0.120396 0.3048)
			(end 0.120396 0.2794)
			(stroke
				(width 0.1)
				(type default)
			)
			(layer "F.Fab")
		)
		(fp_line
			(start -0.12065 0.3048)
			(end -0.67945 0.3048)
			(stroke
				(width 0.1)
				(type default)
			)
			(layer "F.Fab")
		)
		(fp_line
			(start -0.67945 0.3048)
			(end -0.67945 -0.305054)
			(stroke
				(width 0.1)
				(type default)
			)
			(layer "F.Fab")
		)
		(pad "1" smd circle
			(at -0.40005 0 90)
			(size 0 0)
			(layers "F.Cu" "F.Mask" "F.Paste")
			(net "P12V_SSD1_CO_ILIMIT")
		)
		(pad "2" smd circle
			(at 0.40005 0 90)
			(size 0 0)
			(layers "F.Cu" "F.Mask" "F.Paste")
			(net "GND")
		)
	)
	(footprint ""
		(layer "F.Cu")
		(at 306.085494 -27.092148 -90)
		(property "Reference" "R5755"
			(at 0 0 270)
			(layer "F.SilkS")
			(hide yes)
			(effects
				(font
					(size 1.27 1.27)
				)
			)
		)
		(property "Value" ""
			(at 0 0 270)
			(layer "F.Fab")
			(effects
				(font
					(size 1.27 1.27)
				)
			)
		)
		(duplicate_pad_numbers_are_jumpers no)
		(fp_line
			(start -0.7874 0.4064)
			(end -0.7874 -0.4064)
			(stroke
				(width 0.1524)
				(type default)
			)
			(layer "F.SilkS")
		)
		(fp_line
			(start 0.7874 0.4064)
			(end -0.7874 0.4064)
			(stroke
				(width 0.1524)
				(type default)
			)
			(layer "F.SilkS")
		)
		(fp_line
			(start -0.7874 -0.4064)
			(end 0.7874 -0.4064)
			(stroke
				(width 0.1524)
				(type default)
			)
			(layer "F.SilkS")
		)
		(fp_line
			(start 0.7874 -0.4064)
			(end 0.7874 0.4064)
			(stroke
				(width 0.1524)
				(type default)
			)
			(layer "F.SilkS")
		)
		(fp_line
			(start -0.67945 0.3048)
			(end -0.67945 -0.305054)
			(stroke
				(width 0.1)
				(type default)
			)
			(layer "F.Fab")
		)
		(fp_line
			(start -0.12065 0.3048)
			(end -0.67945 0.3048)
			(stroke
				(width 0.1)
				(type default)
			)
			(layer "F.Fab")
		)
		(fp_line
			(start 0.120396 0.3048)
			(end 0.120396 0.2794)
			(stroke
				(width 0.1)
				(type default)
			)
			(layer "F.Fab")
		)
		(fp_line
			(start 0.67945 0.3048)
			(end 0.120396 0.3048)
			(stroke
				(width 0.1)
				(type default)
			)
			(layer "F.Fab")
		)
		(fp_line
			(start -0.12065 0.2794)
			(end -0.12065 0.3048)
			(stroke
				(width 0.1)
				(type default)
			)
			(layer "F.Fab")
		)
		(fp_line
			(start 0.120396 0.2794)
			(end -0.12065 0.2794)
			(stroke
				(width 0.1)
				(type default)
			)
			(layer "F.Fab")
		)
		(fp_line
			(start -0.12065 -0.2794)
			(end 0.12065 -0.2794)
			(stroke
				(width 0.1)
				(type default)
			)
			(layer "F.Fab")
		)
		(fp_line
			(start 0.12065 -0.2794)
			(end 0.12065 -0.3048)
			(stroke
				(width 0.1)
				(type default)
			)
			(layer "F.Fab")
		)
		(fp_line
			(start 0.12065 -0.3048)
			(end 0.67945 -0.3048)
			(stroke
				(width 0.1)
				(type default)
			)
			(layer "F.Fab")
		)
		(fp_line
			(start 0.67945 -0.3048)
			(end 0.67945 0.3048)
			(stroke
				(width 0.1)
				(type default)
			)
			(layer "F.Fab")
		)
		(fp_line
			(start -0.67945 -0.305054)
			(end -0.12065 -0.305054)
			(stroke
				(width 0.1)
				(type default)
			)
			(layer "F.Fab")
		)
		(fp_line
			(start -0.12065 -0.305054)
			(end -0.12065 -0.2794)
			(stroke
				(width 0.1)
				(type default)
			)
			(layer "F.Fab")
		)
		(pad "1" smd circle
			(at -0.40005 0 270)
			(size 0 0)
			(layers "F.Cu" "F.Mask" "F.Paste")
			(net "P3V3_SSD10")
		)
		(pad "2" smd circle
			(at 0.40005 0 270)
			(size 0 0)
			(layers "F.Cu" "F.Mask" "F.Paste")
			(net "SSD10_LED_ISO_N")
		)
	)
	(footprint ""
		(layer "F.Cu")
		(at 144.882616 -29.875734)
		(property "Reference" "PU124"
			(at -3.135884 -2.121662 90)
			(unlocked yes)
			(layer "F.SilkS")
			(effects
				(font
					(size 0.7874 0.5842)
					(thickness 0.1524)
				)
			)
		)
		(property "Value" ""
			(at 0 0 0)
			(layer "F.Fab")
			(effects
				(font
					(size 1.27 1.27)
				)
			)
		)
		(duplicate_pad_numbers_are_jumpers no)
		(fp_line
			(start -1.239774 -1.495298)
			(end 1.239774 -1.495298)
			(stroke
				(width 0.1524)
				(type default)
			)
			(layer "F.SilkS")
		)
		(fp_line
			(start -1.239774 1.495298)
			(end -1.239774 -1.495298)
			(stroke
				(width 0.1524)
				(type default)
			)
			(layer "F.SilkS")
		)
		(fp_line
			(start 1.239774 -1.495298)
			(end 1.239774 1.495298)
			(stroke
				(width 0.1524)
				(type default)
			)
			(layer "F.SilkS")
		)
		(fp_line
			(start 1.239774 1.495298)
			(end -1.239774 1.495298)
			(stroke
				(width 0.1524)
				(type default)
			)
			(layer "F.SilkS")
		)
		(fp_poly
			(pts
				(xy -2.222246 -1.384554) (xy -2.940812 -0.665988) (xy -1.86309 -0.306832)
			)
			(stroke
				(width 0)
				(type default)
			)
			(fill yes)
			(layer "F.SilkS")
		)
		(fp_line
			(start -0.8001 -1.050036)
			(end 0.8001 -1.050036)
			(stroke
				(width 0.1)
				(type default)
			)
			(layer "F.Fab")
		)
		(fp_line
			(start -0.8001 1.050036)
			(end -0.8001 -1.050036)
			(stroke
				(width 0.1)
				(type default)
			)
			(layer "F.Fab")
		)
		(fp_line
			(start 0.8001 -1.050036)
			(end 0.8001 1.050036)
			(stroke
				(width 0.1)
				(type default)
			)
			(layer "F.Fab")
		)
		(fp_line
			(start 0.8001 1.050036)
			(end -0.8001 1.050036)
			(stroke
				(width 0.1)
				(type default)
			)
			(layer "F.Fab")
		)
		(fp_poly
			(pts
				(xy -2.458974 -0.508) (xy -2.458974 0.508) (xy -1.442974 0)
			)
			(stroke
				(width 0)
				(type default)
			)
			(fill yes)
			(layer "F.Fab")
		)
		(pad "1_2" smd circle
			(at -0.374904 0 90)
			(size 0 0)
			(layers "F.Cu" "F.Mask" "F.Paste")
			(net "P3V3_AUX")
		)
		(pad "3" smd rect
			(at -0.499872 0.999998)
			(size 0.254 0.7112)
			(layers "F.Cu" "F.Mask" "F.Paste")
			(net "GND")
		)
		(pad "4" smd rect
			(at 0 0.999998)
			(size 0.254 0.7112)
			(layers "F.Cu" "F.Mask" "F.Paste")
			(net "P3V3_SSD5_CO_ILIMIT")
		)
		(pad "5" smd rect
			(at 0.499872 0.999998)
			(size 0.254 0.7112)
			(layers "F.Cu" "F.Mask" "F.Paste")
			(net "P3V3_SSD5_CO_MODE")
		)
		(pad "6_7" smd circle
			(at 0.374904 0 270)
			(size 0 0)
			(layers "F.Cu" "F.Mask" "F.Paste")
			(net "P3V3_SSD5")
		)
		(pad "8" smd rect
			(at 0.499872 -0.999998)
			(size 0.254 0.7112)
			(layers "F.Cu" "F.Mask" "F.Paste")
			(net "P3V3_SSD5_CO_GATE")
		)
		(pad "9" smd rect
			(at 0 -0.999998)
			(size 0.254 0.7112)
			(layers "F.Cu" "F.Mask" "F.Paste")
			(net "P3V3_SSD5_CO_EN")
		)
		(pad "10" smd rect
			(at -0.499872 -0.999998)
			(size 0.254 0.7112)
			(layers "F.Cu" "F.Mask" "F.Paste")
			(net "P3V3_SSD5_CO_DV_DT")
		)
	)
	(footprint ""
		(layer "F.Cu")
		(at 380.875794 -36.915598 -90)
		(property "Reference" "R5574"
			(at 0 0 270)
			(layer "F.SilkS")
			(hide yes)
			(effects
				(font
					(size 1.27 1.27)
				)
			)
		)
		(property "Value" ""
			(at 0 0 270)
			(layer "F.Fab")
			(effects
				(font
					(size 1.27 1.27)
				)
			)
		)
		(duplicate_pad_numbers_are_jumpers no)
		(fp_line
			(start -0.7874 0.4064)
			(end -0.7874 -0.4064)
			(stroke
				(width 0.1524)
				(type default)
			)
			(layer "F.SilkS")
		)
		(fp_line
			(start 0.7874 0.4064)
			(end -0.7874 0.4064)
			(stroke
				(width 0.1524)
				(type default)
			)
			(layer "F.SilkS")
		)
		(fp_line
			(start -0.7874 -0.4064)
			(end 0.7874 -0.4064)
			(stroke
				(width 0.1524)
				(type default)
			)
			(layer "F.SilkS")
		)
		(fp_line
			(start 0.7874 -0.4064)
			(end 0.7874 0.4064)
			(stroke
				(width 0.1524)
				(type default)
			)
			(layer "F.SilkS")
		)
		(fp_line
			(start -0.67945 0.3048)
			(end -0.67945 -0.305054)
			(stroke
				(width 0.1)
				(type default)
			)
			(layer "F.Fab")
		)
		(fp_line
			(start -0.12065 0.3048)
			(end -0.67945 0.3048)
			(stroke
				(width 0.1)
				(type default)
			)
			(layer "F.Fab")
		)
		(fp_line
			(start 0.120396 0.3048)
			(end 0.120396 0.2794)
			(stroke
				(width 0.1)
				(type default)
			)
			(layer "F.Fab")
		)
		(fp_line
			(start 0.67945 0.3048)
			(end 0.120396 0.3048)
			(stroke
				(width 0.1)
				(type default)
			)
			(layer "F.Fab")
		)
		(fp_line
			(start -0.12065 0.2794)
			(end -0.12065 0.3048)
			(stroke
				(width 0.1)
				(type default)
			)
			(layer "F.Fab")
		)
		(fp_line
			(start 0.120396 0.2794)
			(end -0.12065 0.2794)
			(stroke
				(width 0.1)
				(type default)
			)
			(layer "F.Fab")
		)
		(fp_line
			(start -0.12065 -0.2794)
			(end 0.12065 -0.2794)
			(stroke
				(width 0.1)
				(type default)
			)
			(layer "F.Fab")
		)
		(fp_line
			(start 0.12065 -0.2794)
			(end 0.12065 -0.3048)
			(stroke
				(width 0.1)
				(type default)
			)
			(layer "F.Fab")
		)
		(fp_line
			(start 0.12065 -0.3048)
			(end 0.67945 -0.3048)
			(stroke
				(width 0.1)
				(type default)
			)
			(layer "F.Fab")
		)
		(fp_line
			(start 0.67945 -0.3048)
			(end 0.67945 0.3048)
			(stroke
				(width 0.1)
				(type default)
			)
			(layer "F.Fab")
		)
		(fp_line
			(start -0.67945 -0.305054)
			(end -0.12065 -0.305054)
			(stroke
				(width 0.1)
				(type default)
			)
			(layer "F.Fab")
		)
		(fp_line
			(start -0.12065 -0.305054)
			(end -0.12065 -0.2794)
			(stroke
				(width 0.1)
				(type default)
			)
			(layer "F.Fab")
		)
		(pad "1" smd circle
			(at -0.40005 0 270)
			(size 0 0)
			(layers "F.Cu" "F.Mask" "F.Paste")
			(net "PRSNT_SSD13_R1_N")
		)
		(pad "2" smd circle
			(at 0.40005 0 270)
			(size 0 0)
			(layers "F.Cu" "F.Mask" "F.Paste")
			(net "PRSNT_SSD13_R_N")
		)
	)
	(footprint ""
		(layer "F.Cu")
		(at 136.614662 -66.32194 90)
		(property "Reference" "R5970"
			(at 0 0 90)
			(layer "F.SilkS")
			(hide yes)
			(effects
				(font
					(size 1.27 1.27)
				)
			)
		)
		(property "Value" ""
			(at 0 0 90)
			(layer "F.Fab")
			(effects
				(font
					(size 1.27 1.27)
				)
			)
		)
		(duplicate_pad_numbers_are_jumpers no)
		(fp_line
			(start 0.7874 -0.4064)
			(end 0.7874 0.4064)
			(stroke
				(width 0.1524)
				(type default)
			)
			(layer "F.SilkS")
		)
		(fp_line
			(start -0.7874 -0.4064)
			(end 0.7874 -0.4064)
			(stroke
				(width 0.1524)
				(type default)
			)
			(layer "F.SilkS")
		)
		(fp_line
			(start 0.7874 0.4064)
			(end -0.7874 0.4064)
			(stroke
				(width 0.1524)
				(type default)
			)
			(layer "F.SilkS")
		)
		(fp_line
			(start -0.7874 0.4064)
			(end -0.7874 -0.4064)
			(stroke
				(width 0.1524)
				(type default)
			)
			(layer "F.SilkS")
		)
		(fp_line
			(start -0.12065 -0.305054)
			(end -0.12065 -0.2794)
			(stroke
				(width 0.1)
				(type default)
			)
			(layer "F.Fab")
		)
		(fp_line
			(start -0.67945 -0.305054)
			(end -0.12065 -0.305054)
			(stroke
				(width 0.1)
				(type default)
			)
			(layer "F.Fab")
		)
		(fp_line
			(start 0.67945 -0.3048)
			(end 0.67945 0.3048)
			(stroke
				(width 0.1)
				(type default)
			)
			(layer "F.Fab")
		)
		(fp_line
			(start 0.12065 -0.3048)
			(end 0.67945 -0.3048)
			(stroke
				(width 0.1)
				(type default)
			)
			(layer "F.Fab")
		)
		(fp_line
			(start 0.12065 -0.2794)
			(end 0.12065 -0.3048)
			(stroke
				(width 0.1)
				(type default)
			)
			(layer "F.Fab")
		)
		(fp_line
			(start -0.12065 -0.2794)
			(end 0.12065 -0.2794)
			(stroke
				(width 0.1)
				(type default)
			)
			(layer "F.Fab")
		)
		(fp_line
			(start 0.120396 0.2794)
			(end -0.12065 0.2794)
			(stroke
				(width 0.1)
				(type default)
			)
			(layer "F.Fab")
		)
		(fp_line
			(start -0.12065 0.2794)
			(end -0.12065 0.3048)
			(stroke
				(width 0.1)
				(type default)
			)
			(layer "F.Fab")
		)
		(fp_line
			(start 0.67945 0.3048)
			(end 0.120396 0.3048)
			(stroke
				(width 0.1)
				(type default)
			)
			(layer "F.Fab")
		)
		(fp_line
			(start 0.120396 0.3048)
			(end 0.120396 0.2794)
			(stroke
				(width 0.1)
				(type default)
			)
			(layer "F.Fab")
		)
		(fp_line
			(start -0.12065 0.3048)
			(end -0.67945 0.3048)
			(stroke
				(width 0.1)
				(type default)
			)
			(layer "F.Fab")
		)
		(fp_line
			(start -0.67945 0.3048)
			(end -0.67945 -0.305054)
			(stroke
				(width 0.1)
				(type default)
			)
			(layer "F.Fab")
		)
		(pad "1" smd circle
			(at -0.40005 0 90)
			(size 0 0)
			(layers "F.Cu" "F.Mask" "F.Paste")
			(net "SSD4_PWR_EN_R")
		)
		(pad "2" smd circle
			(at 0.40005 0 90)
			(size 0 0)
			(layers "F.Cu" "F.Mask" "F.Paste")
			(net "P12V_SSD4_CO_EN")
		)
	)
	(footprint ""
		(layer "F.Cu")
		(at 101.774244 -10.534142 -90)
		(property "Reference" "R1652"
			(at 0 0 270)
			(layer "F.SilkS")
			(hide yes)
			(effects
				(font
					(size 1.27 1.27)
				)
			)
		)
		(property "Value" ""
			(at 0 0 270)
			(layer "F.Fab")
			(effects
				(font
					(size 1.27 1.27)
				)
			)
		)
		(duplicate_pad_numbers_are_jumpers no)
		(fp_line
			(start -0.7874 0.4064)
			(end -0.7874 -0.4064)
			(stroke
				(width 0.1524)
				(type default)
			)
			(layer "F.SilkS")
		)
		(fp_line
			(start 0.7874 0.4064)
			(end -0.7874 0.4064)
			(stroke
				(width 0.1524)
				(type default)
			)
			(layer "F.SilkS")
		)
		(fp_line
			(start -0.7874 -0.4064)
			(end 0.7874 -0.4064)
			(stroke
				(width 0.1524)
				(type default)
			)
			(layer "F.SilkS")
		)
		(fp_line
			(start 0.7874 -0.4064)
			(end 0.7874 0.4064)
			(stroke
				(width 0.1524)
				(type default)
			)
			(layer "F.SilkS")
		)
		(fp_line
			(start -0.67945 0.3048)
			(end -0.67945 -0.305054)
			(stroke
				(width 0.1)
				(type default)
			)
			(layer "F.Fab")
		)
		(fp_line
			(start -0.12065 0.3048)
			(end -0.67945 0.3048)
			(stroke
				(width 0.1)
				(type default)
			)
			(layer "F.Fab")
		)
		(fp_line
			(start 0.120396 0.3048)
			(end 0.120396 0.2794)
			(stroke
				(width 0.1)
				(type default)
			)
			(layer "F.Fab")
		)
		(fp_line
			(start 0.67945 0.3048)
			(end 0.120396 0.3048)
			(stroke
				(width 0.1)
				(type default)
			)
			(layer "F.Fab")
		)
		(fp_line
			(start -0.12065 0.2794)
			(end -0.12065 0.3048)
			(stroke
				(width 0.1)
				(type default)
			)
			(layer "F.Fab")
		)
		(fp_line
			(start 0.120396 0.2794)
			(end -0.12065 0.2794)
			(stroke
				(width 0.1)
				(type default)
			)
			(layer "F.Fab")
		)
		(fp_line
			(start -0.12065 -0.2794)
			(end 0.12065 -0.2794)
			(stroke
				(width 0.1)
				(type default)
			)
			(layer "F.Fab")
		)
		(fp_line
			(start 0.12065 -0.2794)
			(end 0.12065 -0.3048)
			(stroke
				(width 0.1)
				(type default)
			)
			(layer "F.Fab")
		)
		(fp_line
			(start 0.12065 -0.3048)
			(end 0.67945 -0.3048)
			(stroke
				(width 0.1)
				(type default)
			)
			(layer "F.Fab")
		)
		(fp_line
			(start 0.67945 -0.3048)
			(end 0.67945 0.3048)
			(stroke
				(width 0.1)
				(type default)
			)
			(layer "F.Fab")
		)
		(fp_line
			(start -0.67945 -0.305054)
			(end -0.12065 -0.305054)
			(stroke
				(width 0.1)
				(type default)
			)
			(layer "F.Fab")
		)
		(fp_line
			(start -0.12065 -0.305054)
			(end -0.12065 -0.2794)
			(stroke
				(width 0.1)
				(type default)
			)
			(layer "F.Fab")
		)
		(pad "1" smd circle
			(at -0.40005 0 270)
			(size 0 0)
			(layers "F.Cu" "F.Mask" "F.Paste")
			(net "SMB_ISO_SSD3_R_SCL")
		)
		(pad "2" smd circle
			(at 0.40005 0 270)
			(size 0 0)
			(layers "F.Cu" "F.Mask" "F.Paste")
			(net "SMB_ISO_SSD3_SCL")
		)
	)
	(footprint ""
		(layer "F.Cu")
		(at 48.820578 -70.307454 90)
		(property "Reference" "PC649"
			(at 0 0 90)
			(layer "F.SilkS")
			(hide yes)
			(effects
				(font
					(size 1.27 1.27)
				)
			)
		)
		(property "Value" ""
			(at 0 0 90)
			(layer "F.Fab")
			(effects
				(font
					(size 1.27 1.27)
				)
			)
		)
		(duplicate_pad_numbers_are_jumpers no)
		(fp_line
			(start 0.7874 -0.4064)
			(end 0.7874 0.4064)
			(stroke
				(width 0.1524)
				(type default)
			)
			(layer "F.SilkS")
		)
		(fp_line
			(start -0.7874 -0.4064)
			(end 0.7874 -0.4064)
			(stroke
				(width 0.1524)
				(type default)
			)
			(layer "F.SilkS")
		)
		(fp_line
			(start 0.7874 0.4064)
			(end -0.7874 0.4064)
			(stroke
				(width 0.1524)
				(type default)
			)
			(layer "F.SilkS")
		)
		(fp_line
			(start -0.7874 0.4064)
			(end -0.7874 -0.4064)
			(stroke
				(width 0.1524)
				(type default)
			)
			(layer "F.SilkS")
		)
		(fp_line
			(start -0.12065 -0.305054)
			(end -0.12065 -0.2794)
			(stroke
				(width 0.1)
				(type default)
			)
			(layer "F.Fab")
		)
		(fp_line
			(start -0.67945 -0.305054)
			(end -0.12065 -0.305054)
			(stroke
				(width 0.1)
				(type default)
			)
			(layer "F.Fab")
		)
		(fp_line
			(start 0.67945 -0.3048)
			(end 0.67945 0.3048)
			(stroke
				(width 0.1)
				(type default)
			)
			(layer "F.Fab")
		)
		(fp_line
			(start 0.12065 -0.3048)
			(end 0.67945 -0.3048)
			(stroke
				(width 0.1)
				(type default)
			)
			(layer "F.Fab")
		)
		(fp_line
			(start 0.12065 -0.2794)
			(end 0.12065 -0.3048)
			(stroke
				(width 0.1)
				(type default)
			)
			(layer "F.Fab")
		)
		(fp_line
			(start -0.12065 -0.2794)
			(end 0.12065 -0.2794)
			(stroke
				(width 0.1)
				(type default)
			)
			(layer "F.Fab")
		)
		(fp_line
			(start 0.120396 0.2794)
			(end -0.12065 0.2794)
			(stroke
				(width 0.1)
				(type default)
			)
			(layer "F.Fab")
		)
		(fp_line
			(start -0.12065 0.2794)
			(end -0.12065 0.3048)
			(stroke
				(width 0.1)
				(type default)
			)
			(layer "F.Fab")
		)
		(fp_line
			(start 0.67945 0.3048)
			(end 0.120396 0.3048)
			(stroke
				(width 0.1)
				(type default)
			)
			(layer "F.Fab")
		)
		(fp_line
			(start 0.120396 0.3048)
			(end 0.120396 0.2794)
			(stroke
				(width 0.1)
				(type default)
			)
			(layer "F.Fab")
		)
		(fp_line
			(start -0.12065 0.3048)
			(end -0.67945 0.3048)
			(stroke
				(width 0.1)
				(type default)
			)
			(layer "F.Fab")
		)
		(fp_line
			(start -0.67945 0.3048)
			(end -0.67945 -0.305054)
			(stroke
				(width 0.1)
				(type default)
			)
			(layer "F.Fab")
		)
		(pad "1" smd circle
			(at -0.40005 0 90)
			(size 0 0)
			(layers "F.Cu" "F.Mask" "F.Paste")
			(net "P12V_AUX")
		)
		(pad "2" smd circle
			(at 0.40005 0 90)
			(size 0 0)
			(layers "F.Cu" "F.Mask" "F.Paste")
			(net "GND")
		)
	)
	(footprint ""
		(layer "F.Cu")
		(at 235.127038 -369.779804 90)
		(property "Reference" "PC14"
			(at 0 0 90)
			(layer "F.SilkS")
			(hide yes)
			(effects
				(font
					(size 1.27 1.27)
				)
			)
		)
		(property "Value" ""
			(at 0 0 90)
			(layer "F.Fab")
			(effects
				(font
					(size 1.27 1.27)
				)
			)
		)
		(duplicate_pad_numbers_are_jumpers no)
		(fp_line
			(start 0.7874 -0.4064)
			(end 0.7874 0.4064)
			(stroke
				(width 0.1524)
				(type default)
			)
			(layer "F.SilkS")
		)
		(fp_line
			(start -0.7874 -0.4064)
			(end 0.7874 -0.4064)
			(stroke
				(width 0.1524)
				(type default)
			)
			(layer "F.SilkS")
		)
		(fp_line
			(start 0.7874 0.4064)
			(end -0.7874 0.4064)
			(stroke
				(width 0.1524)
				(type default)
			)
			(layer "F.SilkS")
		)
		(fp_line
			(start -0.7874 0.4064)
			(end -0.7874 -0.4064)
			(stroke
				(width 0.1524)
				(type default)
			)
			(layer "F.SilkS")
		)
		(fp_line
			(start -0.12065 -0.305054)
			(end -0.12065 -0.2794)
			(stroke
				(width 0.1)
				(type default)
			)
			(layer "F.Fab")
		)
		(fp_line
			(start -0.67945 -0.305054)
			(end -0.12065 -0.305054)
			(stroke
				(width 0.1)
				(type default)
			)
			(layer "F.Fab")
		)
		(fp_line
			(start 0.67945 -0.3048)
			(end 0.67945 0.3048)
			(stroke
				(width 0.1)
				(type default)
			)
			(layer "F.Fab")
		)
		(fp_line
			(start 0.12065 -0.3048)
			(end 0.67945 -0.3048)
			(stroke
				(width 0.1)
				(type default)
			)
			(layer "F.Fab")
		)
		(fp_line
			(start 0.12065 -0.2794)
			(end 0.12065 -0.3048)
			(stroke
				(width 0.1)
				(type default)
			)
			(layer "F.Fab")
		)
		(fp_line
			(start -0.12065 -0.2794)
			(end 0.12065 -0.2794)
			(stroke
				(width 0.1)
				(type default)
			)
			(layer "F.Fab")
		)
		(fp_line
			(start 0.120396 0.2794)
			(end -0.12065 0.2794)
			(stroke
				(width 0.1)
				(type default)
			)
			(layer "F.Fab")
		)
		(fp_line
			(start -0.12065 0.2794)
			(end -0.12065 0.3048)
			(stroke
				(width 0.1)
				(type default)
			)
			(layer "F.Fab")
		)
		(fp_line
			(start 0.67945 0.3048)
			(end 0.120396 0.3048)
			(stroke
				(width 0.1)
				(type default)
			)
			(layer "F.Fab")
		)
		(fp_line
			(start 0.120396 0.3048)
			(end 0.120396 0.2794)
			(stroke
				(width 0.1)
				(type default)
			)
			(layer "F.Fab")
		)
		(fp_line
			(start -0.12065 0.3048)
			(end -0.67945 0.3048)
			(stroke
				(width 0.1)
				(type default)
			)
			(layer "F.Fab")
		)
		(fp_line
			(start -0.67945 0.3048)
			(end -0.67945 -0.305054)
			(stroke
				(width 0.1)
				(type default)
			)
			(layer "F.Fab")
		)
		(pad "1" smd circle
			(at -0.40005 0 90)
			(size 0 0)
			(layers "F.Cu" "F.Mask" "F.Paste")
			(net "HSC_ON")
		)
		(pad "2" smd circle
			(at 0.40005 0 90)
			(size 0 0)
			(layers "F.Cu" "F.Mask" "F.Paste")
			(net "AGND_HSC")
		)
	)
	(footprint ""
		(layer "F.Cu")
		(at 284.224984 -14.735302 180)
		(property "Reference" "C2730"
			(at 0 0 180)
			(layer "F.SilkS")
			(hide yes)
			(effects
				(font
					(size 1.27 1.27)
				)
			)
		)
		(property "Value" ""
			(at 0 0 180)
			(layer "F.Fab")
			(effects
				(font
					(size 1.27 1.27)
				)
			)
		)
		(duplicate_pad_numbers_are_jumpers no)
		(fp_line
			(start 0.7874 0.4064)
			(end -0.7874 0.4064)
			(stroke
				(width 0.1524)
				(type default)
			)
			(layer "F.SilkS")
		)
		(fp_line
			(start 0.7874 -0.4064)
			(end 0.7874 0.4064)
			(stroke
				(width 0.1524)
				(type default)
			)
			(layer "F.SilkS")
		)
		(fp_line
			(start -0.7874 0.4064)
			(end -0.7874 -0.4064)
			(stroke
				(width 0.1524)
				(type default)
			)
			(layer "F.SilkS")
		)
		(fp_line
			(start -0.7874 -0.4064)
			(end 0.7874 -0.4064)
			(stroke
				(width 0.1524)
				(type default)
			)
			(layer "F.SilkS")
		)
		(fp_line
			(start 0.67945 0.3048)
			(end 0.120396 0.3048)
			(stroke
				(width 0.1)
				(type default)
			)
			(layer "F.Fab")
		)
		(fp_line
			(start 0.67945 -0.3048)
			(end 0.67945 0.3048)
			(stroke
				(width 0.1)
				(type default)
			)
			(layer "F.Fab")
		)
		(fp_line
			(start 0.12065 -0.2794)
			(end 0.12065 -0.3048)
			(stroke
				(width 0.1)
				(type default)
			)
			(layer "F.Fab")
		)
		(fp_line
			(start 0.12065 -0.3048)
			(end 0.67945 -0.3048)
			(stroke
				(width 0.1)
				(type default)
			)
			(layer "F.Fab")
		)
		(fp_line
			(start 0.120396 0.3048)
			(end 0.120396 0.2794)
			(stroke
				(width 0.1)
				(type default)
			)
			(layer "F.Fab")
		)
		(fp_line
			(start 0.120396 0.2794)
			(end -0.12065 0.2794)
			(stroke
				(width 0.1)
				(type default)
			)
			(layer "F.Fab")
		)
		(fp_line
			(start -0.12065 0.3048)
			(end -0.67945 0.3048)
			(stroke
				(width 0.1)
				(type default)
			)
			(layer "F.Fab")
		)
		(fp_line
			(start -0.12065 0.2794)
			(end -0.12065 0.3048)
			(stroke
				(width 0.1)
				(type default)
			)
			(layer "F.Fab")
		)
		(fp_line
			(start -0.12065 -0.2794)
			(end 0.12065 -0.2794)
			(stroke
				(width 0.1)
				(type default)
			)
			(layer "F.Fab")
		)
		(fp_line
			(start -0.12065 -0.305054)
			(end -0.12065 -0.2794)
			(stroke
				(width 0.1)
				(type default)
			)
			(layer "F.Fab")
		)
		(fp_line
			(start -0.67945 0.3048)
			(end -0.67945 -0.305054)
			(stroke
				(width 0.1)
				(type default)
			)
			(layer "F.Fab")
		)
		(fp_line
			(start -0.67945 -0.305054)
			(end -0.12065 -0.305054)
			(stroke
				(width 0.1)
				(type default)
			)
			(layer "F.Fab")
		)
		(pad "1" smd circle
			(at -0.40005 0 180)
			(size 0 0)
			(layers "F.Cu" "F.Mask" "F.Paste")
			(net "GND")
		)
		(pad "2" smd circle
			(at 0.40005 0 180)
			(size 0 0)
			(layers "F.Cu" "F.Mask" "F.Paste")
			(net "P3V3_SSD9")
		)
	)
	(footprint ""
		(layer "F.Cu")
		(at 142.368016 -52.035456 180)
		(property "Reference" "R862"
			(at 0 0 180)
			(layer "F.SilkS")
			(hide yes)
			(effects
				(font
					(size 1.27 1.27)
				)
			)
		)
		(property "Value" ""
			(at 0 0 180)
			(layer "F.Fab")
			(effects
				(font
					(size 1.27 1.27)
				)
			)
		)
		(duplicate_pad_numbers_are_jumpers no)
		(fp_line
			(start 0.7874 0.4064)
			(end -0.7874 0.4064)
			(stroke
				(width 0.1524)
				(type default)
			)
			(layer "F.SilkS")
		)
		(fp_line
			(start 0.7874 -0.4064)
			(end 0.7874 0.4064)
			(stroke
				(width 0.1524)
				(type default)
			)
			(layer "F.SilkS")
		)
		(fp_line
			(start -0.7874 0.4064)
			(end -0.7874 -0.4064)
			(stroke
				(width 0.1524)
				(type default)
			)
			(layer "F.SilkS")
		)
		(fp_line
			(start -0.7874 -0.4064)
			(end 0.7874 -0.4064)
			(stroke
				(width 0.1524)
				(type default)
			)
			(layer "F.SilkS")
		)
		(fp_line
			(start 0.67945 0.3048)
			(end 0.120396 0.3048)
			(stroke
				(width 0.1)
				(type default)
			)
			(layer "F.Fab")
		)
		(fp_line
			(start 0.67945 -0.3048)
			(end 0.67945 0.3048)
			(stroke
				(width 0.1)
				(type default)
			)
			(layer "F.Fab")
		)
		(fp_line
			(start 0.12065 -0.2794)
			(end 0.12065 -0.3048)
			(stroke
				(width 0.1)
				(type default)
			)
			(layer "F.Fab")
		)
		(fp_line
			(start 0.12065 -0.3048)
			(end 0.67945 -0.3048)
			(stroke
				(width 0.1)
				(type default)
			)
			(layer "F.Fab")
		)
		(fp_line
			(start 0.120396 0.3048)
			(end 0.120396 0.2794)
			(stroke
				(width 0.1)
				(type default)
			)
			(layer "F.Fab")
		)
		(fp_line
			(start 0.120396 0.2794)
			(end -0.12065 0.2794)
			(stroke
				(width 0.1)
				(type default)
			)
			(layer "F.Fab")
		)
		(fp_line
			(start -0.12065 0.3048)
			(end -0.67945 0.3048)
			(stroke
				(width 0.1)
				(type default)
			)
			(layer "F.Fab")
		)
		(fp_line
			(start -0.12065 0.2794)
			(end -0.12065 0.3048)
			(stroke
				(width 0.1)
				(type default)
			)
			(layer "F.Fab")
		)
		(fp_line
			(start -0.12065 -0.2794)
			(end 0.12065 -0.2794)
			(stroke
				(width 0.1)
				(type default)
			)
			(layer "F.Fab")
		)
		(fp_line
			(start -0.12065 -0.305054)
			(end -0.12065 -0.2794)
			(stroke
				(width 0.1)
				(type default)
			)
			(layer "F.Fab")
		)
		(fp_line
			(start -0.67945 0.3048)
			(end -0.67945 -0.305054)
			(stroke
				(width 0.1)
				(type default)
			)
			(layer "F.Fab")
		)
		(fp_line
			(start -0.67945 -0.305054)
			(end -0.12065 -0.305054)
			(stroke
				(width 0.1)
				(type default)
			)
			(layer "F.Fab")
		)
		(pad "1" smd circle
			(at -0.40005 0 180)
			(size 0 0)
			(layers "F.Cu" "F.Mask" "F.Paste")
			(net "P3V3_AUX")
		)
		(pad "2" smd circle
			(at 0.40005 0 180)
			(size 0 0)
			(layers "F.Cu" "F.Mask" "F.Paste")
			(net "PWRGD_P12V_SSD4")
		)
	)
	(footprint ""
		(layer "F.Cu")
		(at 96.620076 -15.649956 180)
		(property "Reference" "H118"
			(at -3.792474 -2.39141 0)
			(unlocked yes)
			(layer "B.SilkS")
			(effects
				(font
					(size 0.7874 0.5842)
					(thickness 0.1524)
				)
				(justify left mirror)
			)
		)
		(property "Value" ""
			(at 0 0 180)
			(layer "F.Fab")
			(effects
				(font
					(size 1.27 1.27)
				)
			)
		)
		(duplicate_pad_numbers_are_jumpers no)
		(pad "1" thru_hole rect
			(at 0 0 180)
			(size 4.2164 5.0038)
			(drill 2.0066
				(offset 0.099822 0)
			)
			(layers "*.Cu" "*.Mask")
			(remove_unused_layers no)
			(net "Net_8545")
			(clearance -0.8509)
			(padstack
				(mode front_inner_back)
				(layer "Inner"
					(shape circle)
					(size 4.0132 4.0132)
					(clearance -0.7493)
				)
				(layer "B.Cu"
					(shape circle)
					(size 4.0132 4.0132)
					(clearance -0.7493)
				)
			)
		)
	)
	(footprint ""
		(layer "F.Cu")
		(at 259.326126 -37.929566 90)
		(property "Reference" "R5570"
			(at 0 0 90)
			(layer "F.SilkS")
			(hide yes)
			(effects
				(font
					(size 1.27 1.27)
				)
			)
		)
		(property "Value" ""
			(at 0 0 90)
			(layer "F.Fab")
			(effects
				(font
					(size 1.27 1.27)
				)
			)
		)
		(duplicate_pad_numbers_are_jumpers no)
		(fp_line
			(start 0.7874 -0.4064)
			(end 0.7874 0.4064)
			(stroke
				(width 0.1524)
				(type default)
			)
			(layer "F.SilkS")
		)
		(fp_line
			(start -0.7874 -0.4064)
			(end 0.7874 -0.4064)
			(stroke
				(width 0.1524)
				(type default)
			)
			(layer "F.SilkS")
		)
		(fp_line
			(start 0.7874 0.4064)
			(end -0.7874 0.4064)
			(stroke
				(width 0.1524)
				(type default)
			)
			(layer "F.SilkS")
		)
		(fp_line
			(start -0.7874 0.4064)
			(end -0.7874 -0.4064)
			(stroke
				(width 0.1524)
				(type default)
			)
			(layer "F.SilkS")
		)
		(fp_line
			(start -0.12065 -0.305054)
			(end -0.12065 -0.2794)
			(stroke
				(width 0.1)
				(type default)
			)
			(layer "F.Fab")
		)
		(fp_line
			(start -0.67945 -0.305054)
			(end -0.12065 -0.305054)
			(stroke
				(width 0.1)
				(type default)
			)
			(layer "F.Fab")
		)
		(fp_line
			(start 0.67945 -0.3048)
			(end 0.67945 0.3048)
			(stroke
				(width 0.1)
				(type default)
			)
			(layer "F.Fab")
		)
		(fp_line
			(start 0.12065 -0.3048)
			(end 0.67945 -0.3048)
			(stroke
				(width 0.1)
				(type default)
			)
			(layer "F.Fab")
		)
		(fp_line
			(start 0.12065 -0.2794)
			(end 0.12065 -0.3048)
			(stroke
				(width 0.1)
				(type default)
			)
			(layer "F.Fab")
		)
		(fp_line
			(start -0.12065 -0.2794)
			(end 0.12065 -0.2794)
			(stroke
				(width 0.1)
				(type default)
			)
			(layer "F.Fab")
		)
		(fp_line
			(start 0.120396 0.2794)
			(end -0.12065 0.2794)
			(stroke
				(width 0.1)
				(type default)
			)
			(layer "F.Fab")
		)
		(fp_line
			(start -0.12065 0.2794)
			(end -0.12065 0.3048)
			(stroke
				(width 0.1)
				(type default)
			)
			(layer "F.Fab")
		)
		(fp_line
			(start 0.67945 0.3048)
			(end 0.120396 0.3048)
			(stroke
				(width 0.1)
				(type default)
			)
			(layer "F.Fab")
		)
		(fp_line
			(start 0.120396 0.3048)
			(end 0.120396 0.2794)
			(stroke
				(width 0.1)
				(type default)
			)
			(layer "F.Fab")
		)
		(fp_line
			(start -0.12065 0.3048)
			(end -0.67945 0.3048)
			(stroke
				(width 0.1)
				(type default)
			)
			(layer "F.Fab")
		)
		(fp_line
			(start -0.67945 0.3048)
			(end -0.67945 -0.305054)
			(stroke
				(width 0.1)
				(type default)
			)
			(layer "F.Fab")
		)
		(pad "1" smd circle
			(at -0.40005 0 90)
			(size 0 0)
			(layers "F.Cu" "F.Mask" "F.Paste")
			(net "SSD9_AUX_P3V3_EN_R")
		)
		(pad "2" smd circle
			(at 0.40005 0 90)
			(size 0 0)
			(layers "F.Cu" "F.Mask" "F.Paste")
			(net "SSD9_AUX_P3V3_EN")
		)
	)
	(footprint ""
		(layer "F.Cu")
		(at 262.353298 -297.791632)
		(property "Reference" "L120"
			(at 0 0 0)
			(layer "F.SilkS")
			(hide yes)
			(effects
				(font
					(size 1.27 1.27)
				)
			)
		)
		(property "Value" ""
			(at 0 0 0)
			(layer "F.Fab")
			(effects
				(font
					(size 1.27 1.27)
				)
			)
		)
		(duplicate_pad_numbers_are_jumpers no)
		(fp_line
			(start -1.63576 -0.8128)
			(end -1.63576 0.8128)
			(stroke
				(width 0.1524)
				(type default)
			)
			(layer "F.SilkS")
		)
		(fp_line
			(start -1.63576 -0.8128)
			(end 1.63576 -0.8128)
			(stroke
				(width 0.1524)
				(type default)
			)
			(layer "F.SilkS")
		)
		(fp_line
			(start 1.63576 -0.8128)
			(end 1.63576 0.8128)
			(stroke
				(width 0.1524)
				(type default)
			)
			(layer "F.SilkS")
		)
		(fp_line
			(start 1.63576 0.8128)
			(end -1.63576 0.8128)
			(stroke
				(width 0.1524)
				(type default)
			)
			(layer "F.SilkS")
		)
		(fp_line
			(start -1.56083 -0.738632)
			(end -1.56083 0.7366)
			(stroke
				(width 0.1)
				(type default)
			)
			(layer "F.Fab")
		)
		(fp_line
			(start -1.56083 0.7366)
			(end -1.524 0.7366)
			(stroke
				(width 0.1)
				(type default)
			)
			(layer "F.Fab")
		)
		(fp_line
			(start -1.524 0.7366)
			(end 1.524 0.7366)
			(stroke
				(width 0.1)
				(type default)
			)
			(layer "F.Fab")
		)
		(fp_line
			(start 1.524 0.7366)
			(end 1.560576 0.7366)
			(stroke
				(width 0.1)
				(type default)
			)
			(layer "F.Fab")
		)
		(fp_line
			(start 1.560576 -0.738632)
			(end -1.56083 -0.738632)
			(stroke
				(width 0.1)
				(type default)
			)
			(layer "F.Fab")
		)
		(fp_line
			(start 1.560576 0.7366)
			(end 1.560576 -0.738632)
			(stroke
				(width 0.1)
				(type default)
			)
			(layer "F.Fab")
		)
		(pad "1" smd rect
			(at -0.94996 0 180)
			(size 1.1176 1.3716)
			(layers "F.Cu" "F.Mask" "F.Paste")
			(net "P1V8_PLL0_PEX2")
		)
		(pad "2" smd rect
			(at 0.94996 0 180)
			(size 1.1176 1.3716)
			(layers "F.Cu" "F.Mask" "F.Paste")
			(net "PCEPLL0_VDDA18_PEX2")
		)
	)
	(footprint ""
		(layer "F.Cu")
		(at 358.41051 -124.963428 180)
		(property "Reference" "R4479"
			(at 0 0 180)
			(layer "F.SilkS")
			(hide yes)
			(effects
				(font
					(size 1.27 1.27)
				)
			)
		)
		(property "Value" ""
			(at 0 0 180)
			(layer "F.Fab")
			(effects
				(font
					(size 1.27 1.27)
				)
			)
		)
		(duplicate_pad_numbers_are_jumpers no)
		(fp_line
			(start 0.7874 0.4064)
			(end -0.7874 0.4064)
			(stroke
				(width 0.1524)
				(type default)
			)
			(layer "F.SilkS")
		)
		(fp_line
			(start 0.7874 -0.4064)
			(end 0.7874 0.4064)
			(stroke
				(width 0.1524)
				(type default)
			)
			(layer "F.SilkS")
		)
		(fp_line
			(start -0.7874 0.4064)
			(end -0.7874 -0.4064)
			(stroke
				(width 0.1524)
				(type default)
			)
			(layer "F.SilkS")
		)
		(fp_line
			(start -0.7874 -0.4064)
			(end 0.7874 -0.4064)
			(stroke
				(width 0.1524)
				(type default)
			)
			(layer "F.SilkS")
		)
		(fp_line
			(start 0.67945 0.3048)
			(end 0.120396 0.3048)
			(stroke
				(width 0.1)
				(type default)
			)
			(layer "F.Fab")
		)
		(fp_line
			(start 0.67945 -0.3048)
			(end 0.67945 0.3048)
			(stroke
				(width 0.1)
				(type default)
			)
			(layer "F.Fab")
		)
		(fp_line
			(start 0.12065 -0.2794)
			(end 0.12065 -0.3048)
			(stroke
				(width 0.1)
				(type default)
			)
			(layer "F.Fab")
		)
		(fp_line
			(start 0.12065 -0.3048)
			(end 0.67945 -0.3048)
			(stroke
				(width 0.1)
				(type default)
			)
			(layer "F.Fab")
		)
		(fp_line
			(start 0.120396 0.3048)
			(end 0.120396 0.2794)
			(stroke
				(width 0.1)
				(type default)
			)
			(layer "F.Fab")
		)
		(fp_line
			(start 0.120396 0.2794)
			(end -0.12065 0.2794)
			(stroke
				(width 0.1)
				(type default)
			)
			(layer "F.Fab")
		)
		(fp_line
			(start -0.12065 0.3048)
			(end -0.67945 0.3048)
			(stroke
				(width 0.1)
				(type default)
			)
			(layer "F.Fab")
		)
		(fp_line
			(start -0.12065 0.2794)
			(end -0.12065 0.3048)
			(stroke
				(width 0.1)
				(type default)
			)
			(layer "F.Fab")
		)
		(fp_line
			(start -0.12065 -0.2794)
			(end 0.12065 -0.2794)
			(stroke
				(width 0.1)
				(type default)
			)
			(layer "F.Fab")
		)
		(fp_line
			(start -0.12065 -0.305054)
			(end -0.12065 -0.2794)
			(stroke
				(width 0.1)
				(type default)
			)
			(layer "F.Fab")
		)
		(fp_line
			(start -0.67945 0.3048)
			(end -0.67945 -0.305054)
			(stroke
				(width 0.1)
				(type default)
			)
			(layer "F.Fab")
		)
		(fp_line
			(start -0.67945 -0.305054)
			(end -0.12065 -0.305054)
			(stroke
				(width 0.1)
				(type default)
			)
			(layer "F.Fab")
		)
		(pad "1" smd circle
			(at -0.40005 0 180)
			(size 0 0)
			(layers "F.Cu" "F.Mask" "F.Paste")
			(net "PWRGD_P3V3_NIC6")
		)
		(pad "2" smd circle
			(at 0.40005 0 180)
			(size 0 0)
			(layers "F.Cu" "F.Mask" "F.Paste")
			(net "PWRGD_P3V3_NIC6_R")
		)
	)
	(footprint ""
		(layer "F.Cu")
		(at 395.735556 -249.0216)
		(property "Reference" "J67"
			(at -1.4224 -4.562348 0)
			(unlocked yes)
			(layer "F.SilkS")
			(effects
				(font
					(size 0.7874 0.5842)
					(thickness 0.1524)
				)
				(justify left)
			)
		)
		(property "Value" ""
			(at 0 0 0)
			(layer "F.Fab")
			(effects
				(font
					(size 1.27 1.27)
				)
			)
		)
		(duplicate_pad_numbers_are_jumpers no)
		(fp_line
			(start -1.27 -3.81)
			(end 1.27 -3.81)
			(stroke
				(width 0.1524)
				(type default)
			)
			(layer "F.SilkS")
		)
		(fp_line
			(start -1.27 -0.7747)
			(end -1.27 -3.81)
			(stroke
				(width 0.1524)
				(type default)
			)
			(layer "F.SilkS")
		)
		(fp_line
			(start -1.27 3.81)
			(end -1.27 0.7747)
			(stroke
				(width 0.1524)
				(type default)
			)
			(layer "F.SilkS")
		)
		(fp_line
			(start 1.27 -3.81)
			(end 1.27 -3.3147)
			(stroke
				(width 0.1524)
				(type default)
			)
			(layer "F.SilkS")
		)
		(fp_line
			(start 1.27 -1.7653)
			(end 1.27 1.7653)
			(stroke
				(width 0.1524)
				(type default)
			)
			(layer "F.SilkS")
		)
		(fp_line
			(start 1.27 3.3147)
			(end 1.27 3.81)
			(stroke
				(width 0.1524)
				(type default)
			)
			(layer "F.SilkS")
		)
		(fp_line
			(start 1.27 3.81)
			(end -1.27 3.81)
			(stroke
				(width 0.1524)
				(type default)
			)
			(layer "F.SilkS")
		)
		(fp_poly
			(pts
				(xy 4.3942 -3.048) (xy 4.3942 -2.032) (xy 3.3782 -2.54)
			)
			(stroke
				(width 0)
				(type default)
			)
			(fill yes)
			(layer "F.SilkS")
		)
		(fp_line
			(start -1.27 -3.81)
			(end -1.27 3.81)
			(stroke
				(width 0.1)
				(type default)
			)
			(layer "F.Fab")
		)
		(fp_line
			(start -1.27 3.81)
			(end 1.27 3.81)
			(stroke
				(width 0.1)
				(type default)
			)
			(layer "F.Fab")
		)
		(fp_line
			(start 1.27 -3.81)
			(end -1.27 -3.81)
			(stroke
				(width 0.1)
				(type default)
			)
			(layer "F.Fab")
		)
		(fp_line
			(start 1.27 3.81)
			(end 1.27 -3.81)
			(stroke
				(width 0.1)
				(type default)
			)
			(layer "F.Fab")
		)
		(fp_poly
			(pts
				(xy 4.3942 -3.048) (xy 4.3942 -2.032) (xy 3.3782 -2.54)
			)
			(stroke
				(width 0)
				(type default)
			)
			(fill yes)
			(layer "F.Fab")
		)
		(fp_text user "3"
			(at 3.921252 2.54 90)
			(unlocked yes)
			(layer "F.SilkS")
			(effects
				(font
					(size 0.7874 0.5842)
					(thickness 0.1524)
				)
			)
		)
		(fp_text user "3"
			(at 3.921252 2.54 90)
			(unlocked yes)
			(layer "F.Fab")
			(effects
				(font
					(size 0.7874 0.5842)
					(thickness 0.1524)
				)
			)
		)
		(pad "1" smd rect
			(at 1.459992 -2.54 90)
			(size 1.27 3.429)
			(layers "F.Cu" "F.Mask" "F.Paste")
			(net "GND")
		)
		(pad "2" smd rect
			(at -1.459992 0 90)
			(size 1.27 3.429)
			(layers "F.Cu" "F.Mask" "F.Paste")
			(net "UART_PEX1_SDB_BUF_R1_TX")
		)
		(pad "3" smd rect
			(at 1.459992 2.54 90)
			(size 1.27 3.429)
			(layers "F.Cu" "F.Mask" "F.Paste")
			(net "UART_PEX1_SDB_R1_RX")
		)
	)
	(footprint ""
		(layer "F.Cu")
		(at 294.973248 -84.238592)
		(property "Reference" "U7"
			(at -0.536448 -3.237738 0)
			(unlocked yes)
			(layer "F.SilkS")
			(effects
				(font
					(size 0.7874 0.5842)
					(thickness 0.1524)
				)
				(justify left)
			)
		)
		(property "Value" ""
			(at 0 0 0)
			(layer "F.Fab")
			(effects
				(font
					(size 1.27 1.27)
				)
			)
		)
		(duplicate_pad_numbers_are_jumpers no)
		(fp_line
			(start -1.4224 -2.5146)
			(end -1.4224 2.5146)
			(stroke
				(width 0.1524)
				(type default)
			)
			(layer "F.SilkS")
		)
		(fp_line
			(start -1.4224 2.5146)
			(end 1.4224 2.5146)
			(stroke
				(width 0.1524)
				(type default)
			)
			(layer "F.SilkS")
		)
		(fp_line
			(start -0.4572 -2.5146)
			(end -1.4224 -2.5146)
			(stroke
				(width 0.1524)
				(type default)
			)
			(layer "F.SilkS")
		)
		(fp_line
			(start 0 -2.0574)
			(end -0.4572 -2.5146)
			(stroke
				(width 0.1524)
				(type default)
			)
			(layer "F.SilkS")
		)
		(fp_line
			(start 0.4572 -2.5146)
			(end 0 -2.0574)
			(stroke
				(width 0.1524)
				(type default)
			)
			(layer "F.SilkS")
		)
		(fp_line
			(start 1.4224 -2.5146)
			(end 0.4572 -2.5146)
			(stroke
				(width 0.1524)
				(type default)
			)
			(layer "F.SilkS")
		)
		(fp_line
			(start 1.4224 2.5146)
			(end 1.4224 -2.5146)
			(stroke
				(width 0.1524)
				(type default)
			)
			(layer "F.SilkS")
		)
		(fp_poly
			(pts
				(xy -4.30911 -1.833372) (xy -5.07111 -1.452372) (xy -5.07111 -2.214372)
			)
			(stroke
				(width 0)
				(type default)
			)
			(fill yes)
			(layer "F.SilkS")
		)
		(fp_line
			(start -2.648712 -2.114804)
			(end -2.648712 2.112264)
			(stroke
				(width 0.1)
				(type default)
			)
			(layer "F.Fab")
		)
		(fp_line
			(start -2.648712 2.112264)
			(end -2.0066 2.112264)
			(stroke
				(width 0.1)
				(type default)
			)
			(layer "F.Fab")
		)
		(fp_line
			(start -2.0066 -2.5146)
			(end -2.0066 -2.114804)
			(stroke
				(width 0.1)
				(type default)
			)
			(layer "F.Fab")
		)
		(fp_line
			(start -2.0066 -2.114804)
			(end -2.648712 -2.114804)
			(stroke
				(width 0.1)
				(type default)
			)
			(layer "F.Fab")
		)
		(fp_line
			(start -2.0066 2.112264)
			(end -2.0066 2.5146)
			(stroke
				(width 0.1)
				(type default)
			)
			(layer "F.Fab")
		)
		(fp_line
			(start -2.0066 2.5146)
			(end 2.0066 2.5146)
			(stroke
				(width 0.1)
				(type default)
			)
			(layer "F.Fab")
		)
		(fp_line
			(start 2.0066 -2.5146)
			(end -2.0066 -2.5146)
			(stroke
				(width 0.1)
				(type default)
			)
			(layer "F.Fab")
		)
		(fp_line
			(start 2.0066 -2.112264)
			(end 2.0066 -2.5146)
			(stroke
				(width 0.1)
				(type default)
			)
			(layer "F.Fab")
		)
		(fp_line
			(start 2.0066 2.112264)
			(end 2.642616 2.112264)
			(stroke
				(width 0.1)
				(type default)
			)
			(layer "F.Fab")
		)
		(fp_line
			(start 2.0066 2.5146)
			(end 2.0066 2.112264)
			(stroke
				(width 0.1)
				(type default)
			)
			(layer "F.Fab")
		)
		(fp_line
			(start 2.642616 -2.112264)
			(end 2.0066 -2.112264)
			(stroke
				(width 0.1)
				(type default)
			)
			(layer "F.Fab")
		)
		(fp_line
			(start 2.642616 2.112264)
			(end 2.642616 -2.112264)
			(stroke
				(width 0.1)
				(type default)
			)
			(layer "F.Fab")
		)
		(fp_poly
			(pts
				(xy -3.6322 -1.869186) (xy -4.3942 -1.488186) (xy -4.3942 -2.250186)
			)
			(stroke
				(width 0)
				(type default)
			)
			(fill yes)
			(layer "F.Fab")
		)
		(pad "1" smd rect
			(at -2.6416 -1.905 270)
			(size 0.5588 1.7272)
			(layers "F.Cu" "F.Mask" "F.Paste")
			(net "BB_FRU_A0")
		)
		(pad "2" smd rect
			(at -2.6416 -0.635 270)
			(size 0.5588 1.7272)
			(layers "F.Cu" "F.Mask" "F.Paste")
			(net "BB_FRU_A1")
		)
		(pad "3" smd rect
			(at -2.6416 0.635 270)
			(size 0.5588 1.7272)
			(layers "F.Cu" "F.Mask" "F.Paste")
			(net "BB_FRU_A2")
		)
		(pad "4" smd rect
			(at -2.6416 1.905 270)
			(size 0.5588 1.7272)
			(layers "F.Cu" "F.Mask" "F.Paste")
			(net "GND")
		)
		(pad "5" smd rect
			(at 2.6416 1.905 270)
			(size 0.5588 1.7272)
			(layers "F.Cu" "F.Mask" "F.Paste")
			(net "SMB_BMC_FRU_SDA")
		)
		(pad "6" smd rect
			(at 2.6416 0.635 270)
			(size 0.5588 1.7272)
			(layers "F.Cu" "F.Mask" "F.Paste")
			(net "SMB_BMC_FRU_SCL")
		)
		(pad "7" smd rect
			(at 2.6416 -0.635 270)
			(size 0.5588 1.7272)
			(layers "F.Cu" "F.Mask" "F.Paste")
			(net "GND")
		)
		(pad "8" smd rect
			(at 2.6416 -1.905 270)
			(size 0.5588 1.7272)
			(layers "F.Cu" "F.Mask" "F.Paste")
			(net "P3V3_AUX")
		)
	)
	(footprint ""
		(layer "F.Cu")
		(at 362.697014 -387.160008 180)
		(property "Reference" "R6711"
			(at 0 0 180)
			(layer "F.SilkS")
			(hide yes)
			(effects
				(font
					(size 1.27 1.27)
				)
			)
		)
		(property "Value" ""
			(at 0 0 180)
			(layer "F.Fab")
			(effects
				(font
					(size 1.27 1.27)
				)
			)
		)
		(duplicate_pad_numbers_are_jumpers no)
		(fp_line
			(start 0.7874 0.4064)
			(end -0.7874 0.4064)
			(stroke
				(width 0.1524)
				(type default)
			)
			(layer "F.SilkS")
		)
		(fp_line
			(start 0.7874 -0.4064)
			(end 0.7874 0.4064)
			(stroke
				(width 0.1524)
				(type default)
			)
			(layer "F.SilkS")
		)
		(fp_line
			(start -0.7874 0.4064)
			(end -0.7874 -0.4064)
			(stroke
				(width 0.1524)
				(type default)
			)
			(layer "F.SilkS")
		)
		(fp_line
			(start -0.7874 -0.4064)
			(end 0.7874 -0.4064)
			(stroke
				(width 0.1524)
				(type default)
			)
			(layer "F.SilkS")
		)
		(fp_line
			(start 0.67945 0.3048)
			(end 0.120396 0.3048)
			(stroke
				(width 0.1)
				(type default)
			)
			(layer "F.Fab")
		)
		(fp_line
			(start 0.67945 -0.3048)
			(end 0.67945 0.3048)
			(stroke
				(width 0.1)
				(type default)
			)
			(layer "F.Fab")
		)
		(fp_line
			(start 0.12065 -0.2794)
			(end 0.12065 -0.3048)
			(stroke
				(width 0.1)
				(type default)
			)
			(layer "F.Fab")
		)
		(fp_line
			(start 0.12065 -0.3048)
			(end 0.67945 -0.3048)
			(stroke
				(width 0.1)
				(type default)
			)
			(layer "F.Fab")
		)
		(fp_line
			(start 0.120396 0.3048)
			(end 0.120396 0.2794)
			(stroke
				(width 0.1)
				(type default)
			)
			(layer "F.Fab")
		)
		(fp_line
			(start 0.120396 0.2794)
			(end -0.12065 0.2794)
			(stroke
				(width 0.1)
				(type default)
			)
			(layer "F.Fab")
		)
		(fp_line
			(start -0.12065 0.3048)
			(end -0.67945 0.3048)
			(stroke
				(width 0.1)
				(type default)
			)
			(layer "F.Fab")
		)
		(fp_line
			(start -0.12065 0.2794)
			(end -0.12065 0.3048)
			(stroke
				(width 0.1)
				(type default)
			)
			(layer "F.Fab")
		)
		(fp_line
			(start -0.12065 -0.2794)
			(end 0.12065 -0.2794)
			(stroke
				(width 0.1)
				(type default)
			)
			(layer "F.Fab")
		)
		(fp_line
			(start -0.12065 -0.305054)
			(end -0.12065 -0.2794)
			(stroke
				(width 0.1)
				(type default)
			)
			(layer "F.Fab")
		)
		(fp_line
			(start -0.67945 0.3048)
			(end -0.67945 -0.305054)
			(stroke
				(width 0.1)
				(type default)
			)
			(layer "F.Fab")
		)
		(fp_line
			(start -0.67945 -0.305054)
			(end -0.12065 -0.305054)
			(stroke
				(width 0.1)
				(type default)
			)
			(layer "F.Fab")
		)
		(pad "1" smd circle
			(at -0.40005 0 180)
			(size 0 0)
			(layers "F.Cu" "F.Mask" "F.Paste")
			(net "MB_3V3IO_RSVD4")
		)
		(pad "2" smd circle
			(at 0.40005 0 180)
			(size 0 0)
			(layers "F.Cu" "F.Mask" "F.Paste")
			(net "GND")
		)
	)
	(footprint ""
		(layer "F.Cu")
		(at 340.561422 -198.54545 180)
		(property "Reference" "R4233"
			(at 0 0 180)
			(layer "F.SilkS")
			(hide yes)
			(effects
				(font
					(size 1.27 1.27)
				)
			)
		)
		(property "Value" ""
			(at 0 0 180)
			(layer "F.Fab")
			(effects
				(font
					(size 1.27 1.27)
				)
			)
		)
		(duplicate_pad_numbers_are_jumpers no)
		(fp_line
			(start 0.7874 0.4064)
			(end -0.7874 0.4064)
			(stroke
				(width 0.1524)
				(type default)
			)
			(layer "F.SilkS")
		)
		(fp_line
			(start 0.7874 -0.4064)
			(end 0.7874 0.4064)
			(stroke
				(width 0.1524)
				(type default)
			)
			(layer "F.SilkS")
		)
		(fp_line
			(start -0.7874 0.4064)
			(end -0.7874 -0.4064)
			(stroke
				(width 0.1524)
				(type default)
			)
			(layer "F.SilkS")
		)
		(fp_line
			(start -0.7874 -0.4064)
			(end 0.7874 -0.4064)
			(stroke
				(width 0.1524)
				(type default)
			)
			(layer "F.SilkS")
		)
		(fp_line
			(start 0.67945 0.3048)
			(end 0.120396 0.3048)
			(stroke
				(width 0.1)
				(type default)
			)
			(layer "F.Fab")
		)
		(fp_line
			(start 0.67945 -0.3048)
			(end 0.67945 0.3048)
			(stroke
				(width 0.1)
				(type default)
			)
			(layer "F.Fab")
		)
		(fp_line
			(start 0.12065 -0.2794)
			(end 0.12065 -0.3048)
			(stroke
				(width 0.1)
				(type default)
			)
			(layer "F.Fab")
		)
		(fp_line
			(start 0.12065 -0.3048)
			(end 0.67945 -0.3048)
			(stroke
				(width 0.1)
				(type default)
			)
			(layer "F.Fab")
		)
		(fp_line
			(start 0.120396 0.3048)
			(end 0.120396 0.2794)
			(stroke
				(width 0.1)
				(type default)
			)
			(layer "F.Fab")
		)
		(fp_line
			(start 0.120396 0.2794)
			(end -0.12065 0.2794)
			(stroke
				(width 0.1)
				(type default)
			)
			(layer "F.Fab")
		)
		(fp_line
			(start -0.12065 0.3048)
			(end -0.67945 0.3048)
			(stroke
				(width 0.1)
				(type default)
			)
			(layer "F.Fab")
		)
		(fp_line
			(start -0.12065 0.2794)
			(end -0.12065 0.3048)
			(stroke
				(width 0.1)
				(type default)
			)
			(layer "F.Fab")
		)
		(fp_line
			(start -0.12065 -0.2794)
			(end 0.12065 -0.2794)
			(stroke
				(width 0.1)
				(type default)
			)
			(layer "F.Fab")
		)
		(fp_line
			(start -0.12065 -0.305054)
			(end -0.12065 -0.2794)
			(stroke
				(width 0.1)
				(type default)
			)
			(layer "F.Fab")
		)
		(fp_line
			(start -0.67945 0.3048)
			(end -0.67945 -0.305054)
			(stroke
				(width 0.1)
				(type default)
			)
			(layer "F.Fab")
		)
		(fp_line
			(start -0.67945 -0.305054)
			(end -0.12065 -0.305054)
			(stroke
				(width 0.1)
				(type default)
			)
			(layer "F.Fab")
		)
		(pad "1" smd circle
			(at -0.40005 0 180)
			(size 0 0)
			(layers "F.Cu" "F.Mask" "F.Paste")
			(net "SMB_FIO_R1_SDA")
		)
		(pad "2" smd circle
			(at 0.40005 0 180)
			(size 0 0)
			(layers "F.Cu" "F.Mask" "F.Paste")
			(net "SMB_IO_DEBUG_CARD_R_SDA")
		)
	)
	(footprint ""
		(layer "F.Cu")
		(at 240.35258 -222.064072)
		(property "Reference" "C3613"
			(at 0 0 0)
			(layer "F.SilkS")
			(hide yes)
			(effects
				(font
					(size 1.27 1.27)
				)
			)
		)
		(property "Value" ""
			(at 0 0 0)
			(layer "F.Fab")
			(effects
				(font
					(size 1.27 1.27)
				)
			)
		)
		(duplicate_pad_numbers_are_jumpers no)
		(fp_line
			(start -0.69215 -0.2921)
			(end 0.69215 -0.2921)
			(stroke
				(width 0.1524)
				(type default)
			)
			(layer "F.SilkS")
		)
		(fp_line
			(start -0.69215 0.2921)
			(end -0.69215 -0.2921)
			(stroke
				(width 0.1524)
				(type default)
			)
			(layer "F.SilkS")
		)
		(fp_line
			(start 0.69215 -0.2921)
			(end 0.69215 0.2921)
			(stroke
				(width 0.1524)
				(type default)
			)
			(layer "F.SilkS")
		)
		(fp_line
			(start 0.69215 0.2921)
			(end -0.69215 0.2921)
			(stroke
				(width 0.1524)
				(type default)
			)
			(layer "F.SilkS")
		)
		(fp_line
			(start -0.51435 -0.2794)
			(end 0.51435 -0.2794)
			(stroke
				(width 0.1)
				(type default)
			)
			(layer "F.Fab")
		)
		(fp_line
			(start -0.51435 0.2794)
			(end -0.51435 -0.2794)
			(stroke
				(width 0.1)
				(type default)
			)
			(layer "F.Fab")
		)
		(fp_line
			(start 0.51435 -0.2794)
			(end 0.51435 0.2794)
			(stroke
				(width 0.1)
				(type default)
			)
			(layer "F.Fab")
		)
		(fp_line
			(start 0.51435 0.2794)
			(end -0.51435 0.2794)
			(stroke
				(width 0.1)
				(type default)
			)
			(layer "F.Fab")
		)
		(pad "1" smd circle
			(at -0.40005 0)
			(size 0 0)
			(layers "F.Cu" "F.Mask" "F.Paste")
			(net "P1V2_BIC_ADCVREFREXT1")
		)
		(pad "2" smd circle
			(at 0.40005 0)
			(size 0 0)
			(layers "F.Cu" "F.Mask" "F.Paste")
			(net "GND")
		)
		(zone
			(layer "F.Cu")
			(hatch none 0.5)
			(connect_pads
				(clearance 0)
			)
			(min_thickness 0.25)
			(keepout
				(tracks not_allowed)
				(vias allowed)
				(pads allowed)
				(copperpour not_allowed)
				(footprints allowed)
			)
			(placement
				(enabled no)
				(sheetname "")
			)
			(fill
				(thermal_gap 0.5)
				(thermal_bridge_width 0.5)
				(island_removal_mode 0)
			)
			(polygon
				(pts
					(xy 240.16208 -221.976442) (xy 240.25352 -221.918276) (xy 240.45291 -221.918276) (xy 240.54308 -221.976442)
					(xy 240.54308 -222.151702) (xy 240.45291 -222.210122) (xy 240.25352 -222.210122) (xy 240.16208 -222.151956)
				)
			)
		)
	)
	(footprint ""
		(layer "F.Cu")
		(at 243.434108 -137.01776 180)
		(property "Reference" "PU23"
			(at 2.611374 -2.796286 0)
			(unlocked yes)
			(layer "F.SilkS")
			(effects
				(font
					(size 0.7874 0.5842)
					(thickness 0.1524)
				)
				(justify left)
			)
		)
		(property "Value" ""
			(at 0 0 180)
			(layer "F.Fab")
			(effects
				(font
					(size 1.27 1.27)
				)
			)
		)
		(duplicate_pad_numbers_are_jumpers no)
		(fp_line
			(start 1.943608 1.549908)
			(end -1.943608 1.549908)
			(stroke
				(width 0.1524)
				(type default)
			)
			(layer "F.SilkS")
		)
		(fp_line
			(start 1.943608 -1.549908)
			(end 1.943608 1.549908)
			(stroke
				(width 0.1524)
				(type default)
			)
			(layer "F.SilkS")
		)
		(fp_line
			(start -1.943608 1.549908)
			(end -1.943608 -1.549908)
			(stroke
				(width 0.1524)
				(type default)
			)
			(layer "F.SilkS")
		)
		(fp_line
			(start -1.943608 -1.549908)
			(end 1.943608 -1.549908)
			(stroke
				(width 0.1524)
				(type default)
			)
			(layer "F.SilkS")
		)
		(fp_poly
			(pts
				(xy -2.019808 -1.549908) (xy -1.257808 -1.549908) (xy -1.257808 -1.880108) (xy -2.019808 -1.880108)
			)
			(stroke
				(width 0)
				(type default)
			)
			(fill yes)
			(layer "F.SilkS")
		)
		(fp_line
			(start 1.549908 1.549908)
			(end -1.549908 1.549908)
			(stroke
				(width 0.1)
				(type default)
			)
			(layer "F.Fab")
		)
		(fp_line
			(start 1.549908 -1.549908)
			(end 1.549908 1.549908)
			(stroke
				(width 0.1)
				(type default)
			)
			(layer "F.Fab")
		)
		(fp_line
			(start -1.549908 1.549908)
			(end -1.549908 -1.549908)
			(stroke
				(width 0.1)
				(type default)
			)
			(layer "F.Fab")
		)
		(fp_line
			(start -1.549908 -1.549908)
			(end 1.549908 -1.549908)
			(stroke
				(width 0.1)
				(type default)
			)
			(layer "F.Fab")
		)
		(fp_poly
			(pts
				(xy -2.019808 -1.549908) (xy -1.257808 -1.549908) (xy -1.257808 -1.880108) (xy -2.019808 -1.880108)
			)
			(stroke
				(width 0)
				(type default)
			)
			(fill yes)
			(layer "F.Fab")
		)
		(pad "1" smd rect
			(at -1.500124 -1.249934 90)
			(size 0.2794 0.6096)
			(layers "F.Cu" "F.Mask" "F.Paste")
			(net "P12V_NIC4_R")
		)
		(pad "2" smd rect
			(at -1.500124 -0.750062 90)
			(size 0.2794 0.6096)
			(layers "F.Cu" "F.Mask" "F.Paste")
			(net "P12V_NIC4_R")
		)
		(pad "3" smd rect
			(at -1.500124 -0.249936 90)
			(size 0.2794 0.6096)
			(layers "F.Cu" "F.Mask" "F.Paste")
			(net "P12V_NIC4_R")
		)
		(pad "4" smd rect
			(at -1.500124 0.249936 90)
			(size 0.2794 0.6096)
			(layers "F.Cu" "F.Mask" "F.Paste")
			(net "P12V_NIC4_R")
		)
		(pad "5" smd rect
			(at -1.500124 0.750062 90)
			(size 0.2794 0.6096)
			(layers "F.Cu" "F.Mask" "F.Paste")
			(net "P12V_NIC4_R")
		)
		(pad "6" smd rect
			(at -1.500124 1.249934 90)
			(size 0.2794 0.6096)
			(layers "F.Cu" "F.Mask" "F.Paste")
			(net "GND")
		)
		(pad "7" smd rect
			(at 1.500124 1.249934 90)
			(size 0.2794 0.6096)
			(layers "F.Cu" "F.Mask" "F.Paste")
			(net "P12V_NIC4_SS")
		)
		(pad "8" smd rect
			(at 1.500124 0.750062 90)
			(size 0.2794 0.6096)
			(layers "F.Cu" "F.Mask" "F.Paste")
			(net "PWRGD_P12V_NIC4")
		)
		(pad "9" smd rect
			(at 1.500124 0.249936 90)
			(size 0.2794 0.6096)
			(layers "F.Cu" "F.Mask" "F.Paste")
			(net "P12V_NIC4_OCP")
		)
		(pad "10" smd rect
			(at 1.500124 -0.249936 90)
			(size 0.2794 0.6096)
			(layers "F.Cu" "F.Mask" "F.Paste")
			(net "P5V_AUX")
		)
		(pad "11" smd rect
			(at 1.500124 -0.750062 90)
			(size 0.2794 0.6096)
			(layers "F.Cu" "F.Mask" "F.Paste")
			(net "P12V_NIC4_EN_R")
		)
		(pad "12" smd rect
			(at 1.500124 -1.249934 90)
			(size 0.2794 0.6096)
			(layers "F.Cu" "F.Mask" "F.Paste")
			(net "P12V_AUX")
		)
		(pad "13" smd rect
			(at 0 0 180)
			(size 1.9812 2.7178)
			(layers "F.Cu" "F.Mask" "F.Paste")
			(net "P12V_AUX")
		)
		(zone
			(layer "F.Cu")
			(hatch none 0.5)
			(connect_pads
				(clearance 0)
			)
			(min_thickness 0.25)
			(keepout
				(tracks not_allowed)
				(vias allowed)
				(pads allowed)
				(copperpour not_allowed)
				(footprints allowed)
			)
			(placement
				(enabled no)
				(sheetname "")
			)
			(fill
				(thermal_gap 0.5)
				(thermal_bridge_width 0.5)
				(island_removal_mode 0)
			)
			(polygon
				(pts
					(xy 242.291108 -135.46836) (xy 242.291108 -135.59536) (xy 242.291108 -138.56716) (xy 242.291108 -138.567668)
					(xy 244.577108 -138.567668) (xy 244.577108 -138.56716) (xy 244.577108 -138.44016) (xy 244.577108 -137.01776)
					(xy 244.475508 -137.01776) (xy 244.475508 -138.44016) (xy 242.392708 -138.44016) (xy 242.392708 -135.59536)
					(xy 244.475508 -135.59536) (xy 244.475508 -136.99236) (xy 244.577108 -136.99236) (xy 244.577108 -135.59536)
					(xy 244.577108 -135.46836) (xy 244.577108 -135.467852) (xy 242.291108 -135.467852)
				)
			)
		)
	)
	(footprint ""
		(layer "F.Cu")
		(at 362.3691 -293.5351 90)
		(property "Reference" "PL16"
			(at -5.014468 8.645398 90)
			(unlocked yes)
			(layer "F.SilkS")
			(effects
				(font
					(size 0.7874 0.5842)
					(thickness 0.1524)
				)
				(justify left)
			)
		)
		(property "Value" ""
			(at 0 0 90)
			(layer "F.Fab")
			(effects
				(font
					(size 1.27 1.27)
				)
			)
		)
		(duplicate_pad_numbers_are_jumpers no)
		(fp_line
			(start 4.800092 -3.199892)
			(end 4.800092 -1.6764)
			(stroke
				(width 0.1524)
				(type default)
			)
			(layer "F.SilkS")
		)
		(fp_line
			(start -4.800092 -3.199892)
			(end 4.800092 -3.199892)
			(stroke
				(width 0.1524)
				(type default)
			)
			(layer "F.SilkS")
		)
		(fp_line
			(start -4.800092 -1.6764)
			(end -4.800092 -3.199892)
			(stroke
				(width 0.1524)
				(type default)
			)
			(layer "F.SilkS")
		)
		(fp_line
			(start 4.800092 1.6764)
			(end 4.800092 3.199892)
			(stroke
				(width 0.1524)
				(type default)
			)
			(layer "F.SilkS")
		)
		(fp_line
			(start 4.800092 3.199892)
			(end -4.800092 3.199892)
			(stroke
				(width 0.1524)
				(type default)
			)
			(layer "F.SilkS")
		)
		(fp_line
			(start -4.800092 3.199892)
			(end -4.800092 1.6764)
			(stroke
				(width 0.1524)
				(type default)
			)
			(layer "F.SilkS")
		)
		(fp_line
			(start 4.800092 -3.199892)
			(end 4.800092 3.199892)
			(stroke
				(width 0.1)
				(type default)
			)
			(layer "F.Fab")
		)
		(fp_line
			(start -4.800092 -3.199892)
			(end 4.800092 -3.199892)
			(stroke
				(width 0.1)
				(type default)
			)
			(layer "F.Fab")
		)
		(fp_line
			(start 4.800092 3.199892)
			(end -4.800092 3.199892)
			(stroke
				(width 0.1)
				(type default)
			)
			(layer "F.Fab")
		)
		(fp_line
			(start -4.800092 3.199892)
			(end -4.800092 -3.199892)
			(stroke
				(width 0.1)
				(type default)
			)
			(layer "F.Fab")
		)
		(pad "1" smd rect
			(at -3.074924 0 180)
			(size 3.0988 3.3528)
			(layers "F.Cu" "F.Mask" "F.Paste")
			(net "SW_P0V8_PEX3_PH2")
		)
		(pad "2" smd rect
			(at 3.074924 0 180)
			(size 3.0988 3.3528)
			(layers "F.Cu" "F.Mask" "F.Paste")
			(net "P0V8_PEX3")
		)
	)
	(footprint ""
		(layer "F.Cu")
		(at 276.979126 -402.33219 90)
		(property "Reference" "R1807"
			(at 0 0 90)
			(layer "F.SilkS")
			(hide yes)
			(effects
				(font
					(size 1.27 1.27)
				)
			)
		)
		(property "Value" ""
			(at 0 0 90)
			(layer "F.Fab")
			(effects
				(font
					(size 1.27 1.27)
				)
			)
		)
		(duplicate_pad_numbers_are_jumpers no)
		(fp_line
			(start 0.7874 -0.4064)
			(end 0.7874 0.4064)
			(stroke
				(width 0.1524)
				(type default)
			)
			(layer "F.SilkS")
		)
		(fp_line
			(start -0.7874 -0.4064)
			(end 0.7874 -0.4064)
			(stroke
				(width 0.1524)
				(type default)
			)
			(layer "F.SilkS")
		)
		(fp_line
			(start 0.7874 0.4064)
			(end -0.7874 0.4064)
			(stroke
				(width 0.1524)
				(type default)
			)
			(layer "F.SilkS")
		)
		(fp_line
			(start -0.7874 0.4064)
			(end -0.7874 -0.4064)
			(stroke
				(width 0.1524)
				(type default)
			)
			(layer "F.SilkS")
		)
		(fp_line
			(start -0.12065 -0.305054)
			(end -0.12065 -0.2794)
			(stroke
				(width 0.1)
				(type default)
			)
			(layer "F.Fab")
		)
		(fp_line
			(start -0.67945 -0.305054)
			(end -0.12065 -0.305054)
			(stroke
				(width 0.1)
				(type default)
			)
			(layer "F.Fab")
		)
		(fp_line
			(start 0.67945 -0.3048)
			(end 0.67945 0.3048)
			(stroke
				(width 0.1)
				(type default)
			)
			(layer "F.Fab")
		)
		(fp_line
			(start 0.12065 -0.3048)
			(end 0.67945 -0.3048)
			(stroke
				(width 0.1)
				(type default)
			)
			(layer "F.Fab")
		)
		(fp_line
			(start 0.12065 -0.2794)
			(end 0.12065 -0.3048)
			(stroke
				(width 0.1)
				(type default)
			)
			(layer "F.Fab")
		)
		(fp_line
			(start -0.12065 -0.2794)
			(end 0.12065 -0.2794)
			(stroke
				(width 0.1)
				(type default)
			)
			(layer "F.Fab")
		)
		(fp_line
			(start 0.120396 0.2794)
			(end -0.12065 0.2794)
			(stroke
				(width 0.1)
				(type default)
			)
			(layer "F.Fab")
		)
		(fp_line
			(start -0.12065 0.2794)
			(end -0.12065 0.3048)
			(stroke
				(width 0.1)
				(type default)
			)
			(layer "F.Fab")
		)
		(fp_line
			(start 0.67945 0.3048)
			(end 0.120396 0.3048)
			(stroke
				(width 0.1)
				(type default)
			)
			(layer "F.Fab")
		)
		(fp_line
			(start 0.120396 0.3048)
			(end 0.120396 0.2794)
			(stroke
				(width 0.1)
				(type default)
			)
			(layer "F.Fab")
		)
		(fp_line
			(start -0.12065 0.3048)
			(end -0.67945 0.3048)
			(stroke
				(width 0.1)
				(type default)
			)
			(layer "F.Fab")
		)
		(fp_line
			(start -0.67945 0.3048)
			(end -0.67945 -0.305054)
			(stroke
				(width 0.1)
				(type default)
			)
			(layer "F.Fab")
		)
		(pad "1" smd circle
			(at -0.40005 0 90)
			(size 0 0)
			(layers "F.Cu" "F.Mask" "F.Paste")
			(net "MB_BMC_MON_ISO")
		)
		(pad "2" smd circle
			(at 0.40005 0 90)
			(size 0 0)
			(layers "F.Cu" "F.Mask" "F.Paste")
			(net "MB_BMC_MON_ISO_R")
		)
	)
	(footprint ""
		(layer "F.Cu")
		(at 239.813338 -139.376404)
		(property "Reference" "R854"
			(at 0 0 0)
			(layer "F.SilkS")
			(hide yes)
			(effects
				(font
					(size 1.27 1.27)
				)
			)
		)
		(property "Value" ""
			(at 0 0 0)
			(layer "F.Fab")
			(effects
				(font
					(size 1.27 1.27)
				)
			)
		)
		(duplicate_pad_numbers_are_jumpers no)
		(fp_line
			(start -0.7874 -0.4064)
			(end 0.7874 -0.4064)
			(stroke
				(width 0.1524)
				(type default)
			)
			(layer "F.SilkS")
		)
		(fp_line
			(start -0.7874 0.4064)
			(end -0.7874 -0.4064)
			(stroke
				(width 0.1524)
				(type default)
			)
			(layer "F.SilkS")
		)
		(fp_line
			(start 0.7874 -0.4064)
			(end 0.7874 0.4064)
			(stroke
				(width 0.1524)
				(type default)
			)
			(layer "F.SilkS")
		)
		(fp_line
			(start 0.7874 0.4064)
			(end -0.7874 0.4064)
			(stroke
				(width 0.1524)
				(type default)
			)
			(layer "F.SilkS")
		)
		(fp_line
			(start -0.67945 -0.305054)
			(end -0.12065 -0.305054)
			(stroke
				(width 0.1)
				(type default)
			)
			(layer "F.Fab")
		)
		(fp_line
			(start -0.67945 0.3048)
			(end -0.67945 -0.305054)
			(stroke
				(width 0.1)
				(type default)
			)
			(layer "F.Fab")
		)
		(fp_line
			(start -0.12065 -0.305054)
			(end -0.12065 -0.2794)
			(stroke
				(width 0.1)
				(type default)
			)
			(layer "F.Fab")
		)
		(fp_line
			(start -0.12065 -0.2794)
			(end 0.12065 -0.2794)
			(stroke
				(width 0.1)
				(type default)
			)
			(layer "F.Fab")
		)
		(fp_line
			(start -0.12065 0.2794)
			(end -0.12065 0.3048)
			(stroke
				(width 0.1)
				(type default)
			)
			(layer "F.Fab")
		)
		(fp_line
			(start -0.12065 0.3048)
			(end -0.67945 0.3048)
			(stroke
				(width 0.1)
				(type default)
			)
			(layer "F.Fab")
		)
		(fp_line
			(start 0.120396 0.2794)
			(end -0.12065 0.2794)
			(stroke
				(width 0.1)
				(type default)
			)
			(layer "F.Fab")
		)
		(fp_line
			(start 0.120396 0.3048)
			(end 0.120396 0.2794)
			(stroke
				(width 0.1)
				(type default)
			)
			(layer "F.Fab")
		)
		(fp_line
			(start 0.12065 -0.3048)
			(end 0.67945 -0.3048)
			(stroke
				(width 0.1)
				(type default)
			)
			(layer "F.Fab")
		)
		(fp_line
			(start 0.12065 -0.2794)
			(end 0.12065 -0.3048)
			(stroke
				(width 0.1)
				(type default)
			)
			(layer "F.Fab")
		)
		(fp_line
			(start 0.67945 -0.3048)
			(end 0.67945 0.3048)
			(stroke
				(width 0.1)
				(type default)
			)
			(layer "F.Fab")
		)
		(fp_line
			(start 0.67945 0.3048)
			(end 0.120396 0.3048)
			(stroke
				(width 0.1)
				(type default)
			)
			(layer "F.Fab")
		)
		(pad "1" smd circle
			(at -0.40005 0)
			(size 0 0)
			(layers "F.Cu" "F.Mask" "F.Paste")
			(net "P3V3_AUX")
		)
		(pad "2" smd circle
			(at 0.40005 0)
			(size 0 0)
			(layers "F.Cu" "F.Mask" "F.Paste")
			(net "PWRGD_P12V_NIC4")
		)
	)
	(footprint ""
		(layer "F.Cu")
		(at 350.647 -162.179 90)
		(property "Reference" "C3604"
			(at 0 0 90)
			(layer "F.SilkS")
			(hide yes)
			(effects
				(font
					(size 1.27 1.27)
				)
			)
		)
		(property "Value" ""
			(at 0 0 90)
			(layer "F.Fab")
			(effects
				(font
					(size 1.27 1.27)
				)
			)
		)
		(duplicate_pad_numbers_are_jumpers no)
		(fp_line
			(start 0.7874 -0.4064)
			(end 0.7874 0.4064)
			(stroke
				(width 0.1524)
				(type default)
			)
			(layer "F.SilkS")
		)
		(fp_line
			(start -0.7874 -0.4064)
			(end 0.7874 -0.4064)
			(stroke
				(width 0.1524)
				(type default)
			)
			(layer "F.SilkS")
		)
		(fp_line
			(start 0.7874 0.4064)
			(end -0.7874 0.4064)
			(stroke
				(width 0.1524)
				(type default)
			)
			(layer "F.SilkS")
		)
		(fp_line
			(start -0.7874 0.4064)
			(end -0.7874 -0.4064)
			(stroke
				(width 0.1524)
				(type default)
			)
			(layer "F.SilkS")
		)
		(fp_line
			(start -0.12065 -0.305054)
			(end -0.12065 -0.2794)
			(stroke
				(width 0.1)
				(type default)
			)
			(layer "F.Fab")
		)
		(fp_line
			(start -0.67945 -0.305054)
			(end -0.12065 -0.305054)
			(stroke
				(width 0.1)
				(type default)
			)
			(layer "F.Fab")
		)
		(fp_line
			(start 0.67945 -0.3048)
			(end 0.67945 0.3048)
			(stroke
				(width 0.1)
				(type default)
			)
			(layer "F.Fab")
		)
		(fp_line
			(start 0.12065 -0.3048)
			(end 0.67945 -0.3048)
			(stroke
				(width 0.1)
				(type default)
			)
			(layer "F.Fab")
		)
		(fp_line
			(start 0.12065 -0.2794)
			(end 0.12065 -0.3048)
			(stroke
				(width 0.1)
				(type default)
			)
			(layer "F.Fab")
		)
		(fp_line
			(start -0.12065 -0.2794)
			(end 0.12065 -0.2794)
			(stroke
				(width 0.1)
				(type default)
			)
			(layer "F.Fab")
		)
		(fp_line
			(start 0.120396 0.2794)
			(end -0.12065 0.2794)
			(stroke
				(width 0.1)
				(type default)
			)
			(layer "F.Fab")
		)
		(fp_line
			(start -0.12065 0.2794)
			(end -0.12065 0.3048)
			(stroke
				(width 0.1)
				(type default)
			)
			(layer "F.Fab")
		)
		(fp_line
			(start 0.67945 0.3048)
			(end 0.120396 0.3048)
			(stroke
				(width 0.1)
				(type default)
			)
			(layer "F.Fab")
		)
		(fp_line
			(start 0.120396 0.3048)
			(end 0.120396 0.2794)
			(stroke
				(width 0.1)
				(type default)
			)
			(layer "F.Fab")
		)
		(fp_line
			(start -0.12065 0.3048)
			(end -0.67945 0.3048)
			(stroke
				(width 0.1)
				(type default)
			)
			(layer "F.Fab")
		)
		(fp_line
			(start -0.67945 0.3048)
			(end -0.67945 -0.305054)
			(stroke
				(width 0.1)
				(type default)
			)
			(layer "F.Fab")
		)
		(pad "1" smd circle
			(at -0.40005 0 90)
			(size 0 0)
			(layers "F.Cu" "F.Mask" "F.Paste")
			(net "P3V3_AUX")
		)
		(pad "2" smd circle
			(at 0.40005 0 90)
			(size 0 0)
			(layers "F.Cu" "F.Mask" "F.Paste")
			(net "GND")
		)
	)
	(footprint ""
		(layer "F.Cu")
		(at 297.009566 -441.70346)
		(property "Reference" "X72"
			(at -0.1778 -1.92913 0)
			(unlocked yes)
			(layer "F.SilkS")
			(effects
				(font
					(size 0.7874 0.5842)
					(thickness 0.1524)
				)
				(justify left)
			)
		)
		(property "Value" ""
			(at 0 0 0)
			(layer "F.Fab")
			(effects
				(font
					(size 1.27 1.27)
				)
			)
		)
		(property "Device Type" "TP_TDR_4P_FTS_MPKT4_H025P0200_IO_TP15_TP_TDR_4P_DIP"
			(at 1.30175 1.27 90)
			(unlocked yes)
			(layer "F.Fab")
			(hide yes)
			(effects
				(font
					(size 0.635 0.4064)
					(thickness 0.1524)
				)
			)
		)
		(property "User Part Number" "TP15"
			(at 1.30175 1.27 90)
			(unlocked yes)
			(layer "Cmts.User")
			(hide yes)
			(effects
				(font
					(size 0.635 0.4064)
					(thickness 0.1524)
				)
			)
		)
		(duplicate_pad_numbers_are_jumpers no)
		(fp_line
			(start 0 -1.27)
			(end 0 -0.635)
			(stroke
				(width 0.1524)
				(type default)
			)
			(layer "F.SilkS")
		)
		(fp_line
			(start 0 0.635)
			(end 0 1.905)
			(stroke
				(width 0.1524)
				(type default)
			)
			(layer "F.SilkS")
		)
		(fp_line
			(start 0 3.175)
			(end 0 3.81)
			(stroke
				(width 0.1524)
				(type default)
			)
			(layer "F.SilkS")
		)
		(fp_line
			(start 0 3.81)
			(end 2.54 3.81)
			(stroke
				(width 0.1524)
				(type default)
			)
			(layer "F.SilkS")
		)
		(fp_line
			(start 2.54 -1.27)
			(end 0 -1.27)
			(stroke
				(width 0.1524)
				(type default)
			)
			(layer "F.SilkS")
		)
		(fp_line
			(start 2.54 -1.1303)
			(end 2.54 -1.27)
			(stroke
				(width 0.1524)
				(type default)
			)
			(layer "F.SilkS")
		)
		(fp_line
			(start 2.54 1.4097)
			(end 2.54 1.1303)
			(stroke
				(width 0.1524)
				(type default)
			)
			(layer "F.SilkS")
		)
		(fp_line
			(start 2.54 3.81)
			(end 2.54 3.6703)
			(stroke
				(width 0.1524)
				(type default)
			)
			(layer "F.SilkS")
		)
		(fp_poly
			(pts
				(xy -0.761746 0) (xy -2.285746 -0.762) (xy -2.285746 0.762)
			)
			(stroke
				(width 0)
				(type default)
			)
			(fill yes)
			(layer "F.SilkS")
		)
		(fp_line
			(start 0 -1.27)
			(end 0 3.81)
			(stroke
				(width 0.1)
				(type default)
			)
			(layer "F.Fab")
		)
		(fp_line
			(start 0 3.81)
			(end 2.54 3.81)
			(stroke
				(width 0.1)
				(type default)
			)
			(layer "F.Fab")
		)
		(fp_line
			(start 2.54 -1.27)
			(end 0 -1.27)
			(stroke
				(width 0.1)
				(type default)
			)
			(layer "F.Fab")
		)
		(fp_line
			(start 2.54 3.81)
			(end 2.54 -1.27)
			(stroke
				(width 0.1)
				(type default)
			)
			(layer "F.Fab")
		)
		(fp_poly
			(pts
				(xy -0.761746 0) (xy -2.285746 -0.762) (xy -2.285746 0.762)
			)
			(stroke
				(width 0)
				(type default)
			)
			(fill yes)
			(layer "F.Fab")
		)
		(pad "1" thru_hole circle
			(at 0 0)
			(size 1.0033 1.0033)
			(drill 0.249936)
			(layers "*.Cu" "*.Mask")
			(remove_unused_layers no)
			(net "TDR_DIFF_100_IN3_DIP")
			(clearance 0.10795)
			(thermal_gap 0.10795)
			(padstack
				(mode front_inner_back)
				(layer "Inner"
					(shape circle)
					(size 0.8001 0.8001)
					(clearance 0.1524)
				)
				(layer "B.Cu"
					(shape circle)
					(size 1.0033 1.0033)
					(clearance 0.10795)
				)
			)
		)
		(pad "2" thru_hole circle
			(at 2.54 0)
			(size 1.9939 1.9939)
			(drill 0.249936)
			(layers "*.Cu" "*.Mask")
			(remove_unused_layers no)
			(net "COUPON_GND1")
			(clearance 0.10795)
			(thermal_gap 0.10795)
			(padstack
				(mode front_inner_back)
				(layer "Inner"
					(shape circle)
					(size 0.8001 0.8001)
					(clearance 0.1524)
				)
				(layer "B.Cu"
					(shape circle)
					(size 1.9939 1.9939)
					(clearance 0.10795)
				)
			)
		)
		(pad "3" thru_hole circle
			(at 2.54 2.54)
			(size 1.9939 1.9939)
			(drill 0.249936)
			(layers "*.Cu" "*.Mask")
			(remove_unused_layers no)
			(net "COUPON_GND1")
			(clearance 0.10795)
			(thermal_gap 0.10795)
			(padstack
				(mode front_inner_back)
				(layer "Inner"
					(shape circle)
					(size 0.8001 0.8001)
					(clearance 0.1524)
				)
				(layer "B.Cu"
					(shape circle)
					(size 1.9939 1.9939)
					(clearance 0.10795)
				)
			)
		)
		(pad "4" thru_hole circle
			(at 0 2.54)
			(size 1.0033 1.0033)
			(drill 0.249936)
			(layers "*.Cu" "*.Mask")
			(remove_unused_layers no)
			(net "TDR_DIFF_100_IN3_DIN")
			(clearance 0.10795)
			(thermal_gap 0.10795)
			(padstack
				(mode front_inner_back)
				(layer "Inner"
					(shape circle)
					(size 0.8001 0.8001)
					(clearance 0.1524)
				)
				(layer "B.Cu"
					(shape circle)
					(size 1.0033 1.0033)
					(clearance 0.10795)
				)
			)
		)
	)
	(footprint ""
		(layer "F.Cu")
		(at 115.356386 -83.38439 180)
		(property "Reference" "R1143"
			(at 0 0 180)
			(layer "F.SilkS")
			(hide yes)
			(effects
				(font
					(size 1.27 1.27)
				)
			)
		)
		(property "Value" ""
			(at 0 0 180)
			(layer "F.Fab")
			(effects
				(font
					(size 1.27 1.27)
				)
			)
		)
		(duplicate_pad_numbers_are_jumpers no)
		(fp_line
			(start 0.7874 0.4064)
			(end -0.7874 0.4064)
			(stroke
				(width 0.1524)
				(type default)
			)
			(layer "F.SilkS")
		)
		(fp_line
			(start 0.67945 0.3048)
			(end 0.120396 0.3048)
			(stroke
				(width 0.1)
				(type default)
			)
			(layer "F.Fab")
		)
		(fp_line
			(start 0.67945 -0.3048)
			(end 0.67945 0.3048)
			(stroke
				(width 0.1)
				(type default)
			)
			(layer "F.Fab")
		)
		(fp_line
			(start 0.12065 -0.2794)
			(end 0.12065 -0.3048)
			(stroke
				(width 0.1)
				(type default)
			)
			(layer "F.Fab")
		)
		(fp_line
			(start 0.12065 -0.3048)
			(end 0.67945 -0.3048)
			(stroke
				(width 0.1)
				(type default)
			)
			(layer "F.Fab")
		)
		(fp_line
			(start 0.120396 0.3048)
			(end 0.120396 0.2794)
			(stroke
				(width 0.1)
				(type default)
			)
			(layer "F.Fab")
		)
		(fp_line
			(start 0.120396 0.2794)
			(end -0.12065 0.2794)
			(stroke
				(width 0.1)
				(type default)
			)
			(layer "F.Fab")
		)
		(fp_line
			(start -0.12065 0.3048)
			(end -0.67945 0.3048)
			(stroke
				(width 0.1)
				(type default)
			)
			(layer "F.Fab")
		)
		(fp_line
			(start -0.12065 0.2794)
			(end -0.12065 0.3048)
			(stroke
				(width 0.1)
				(type default)
			)
			(layer "F.Fab")
		)
		(fp_line
			(start -0.12065 -0.2794)
			(end 0.12065 -0.2794)
			(stroke
				(width 0.1)
				(type default)
			)
			(layer "F.Fab")
		)
		(fp_line
			(start -0.12065 -0.305054)
			(end -0.12065 -0.2794)
			(stroke
				(width 0.1)
				(type default)
			)
			(layer "F.Fab")
		)
		(fp_line
			(start -0.67945 0.3048)
			(end -0.67945 -0.305054)
			(stroke
				(width 0.1)
				(type default)
			)
			(layer "F.Fab")
		)
		(fp_line
			(start -0.67945 -0.305054)
			(end -0.12065 -0.305054)
			(stroke
				(width 0.1)
				(type default)
			)
			(layer "F.Fab")
		)
		(pad "1" smd circle
			(at -0.40005 0 180)
			(size 0 0)
			(layers "F.Cu" "F.Mask" "F.Paste")
			(net "CLK_100M_DB800ZL_SSD3_R_DN")
		)
		(pad "2" smd circle
			(at 0.40005 0 180)
			(size 0 0)
			(layers "F.Cu" "F.Mask" "F.Paste")
			(net "CLK_100M_DB800ZL_SSD3_DN")
		)
	)
	(footprint ""
		(layer "F.Cu")
		(at 194.125088 -14.735302 180)
		(property "Reference" "C2724"
			(at 0 0 180)
			(layer "F.SilkS")
			(hide yes)
			(effects
				(font
					(size 1.27 1.27)
				)
			)
		)
		(property "Value" ""
			(at 0 0 180)
			(layer "F.Fab")
			(effects
				(font
					(size 1.27 1.27)
				)
			)
		)
		(duplicate_pad_numbers_are_jumpers no)
		(fp_line
			(start 0.7874 0.4064)
			(end -0.7874 0.4064)
			(stroke
				(width 0.1524)
				(type default)
			)
			(layer "F.SilkS")
		)
		(fp_line
			(start 0.7874 -0.4064)
			(end 0.7874 0.4064)
			(stroke
				(width 0.1524)
				(type default)
			)
			(layer "F.SilkS")
		)
		(fp_line
			(start -0.7874 0.4064)
			(end -0.7874 -0.4064)
			(stroke
				(width 0.1524)
				(type default)
			)
			(layer "F.SilkS")
		)
		(fp_line
			(start -0.7874 -0.4064)
			(end 0.7874 -0.4064)
			(stroke
				(width 0.1524)
				(type default)
			)
			(layer "F.SilkS")
		)
		(fp_line
			(start 0.67945 0.3048)
			(end 0.120396 0.3048)
			(stroke
				(width 0.1)
				(type default)
			)
			(layer "F.Fab")
		)
		(fp_line
			(start 0.67945 -0.3048)
			(end 0.67945 0.3048)
			(stroke
				(width 0.1)
				(type default)
			)
			(layer "F.Fab")
		)
		(fp_line
			(start 0.12065 -0.2794)
			(end 0.12065 -0.3048)
			(stroke
				(width 0.1)
				(type default)
			)
			(layer "F.Fab")
		)
		(fp_line
			(start 0.12065 -0.3048)
			(end 0.67945 -0.3048)
			(stroke
				(width 0.1)
				(type default)
			)
			(layer "F.Fab")
		)
		(fp_line
			(start 0.120396 0.3048)
			(end 0.120396 0.2794)
			(stroke
				(width 0.1)
				(type default)
			)
			(layer "F.Fab")
		)
		(fp_line
			(start 0.120396 0.2794)
			(end -0.12065 0.2794)
			(stroke
				(width 0.1)
				(type default)
			)
			(layer "F.Fab")
		)
		(fp_line
			(start -0.12065 0.3048)
			(end -0.67945 0.3048)
			(stroke
				(width 0.1)
				(type default)
			)
			(layer "F.Fab")
		)
		(fp_line
			(start -0.12065 0.2794)
			(end -0.12065 0.3048)
			(stroke
				(width 0.1)
				(type default)
			)
			(layer "F.Fab")
		)
		(fp_line
			(start -0.12065 -0.2794)
			(end 0.12065 -0.2794)
			(stroke
				(width 0.1)
				(type default)
			)
			(layer "F.Fab")
		)
		(fp_line
			(start -0.12065 -0.305054)
			(end -0.12065 -0.2794)
			(stroke
				(width 0.1)
				(type default)
			)
			(layer "F.Fab")
		)
		(fp_line
			(start -0.67945 0.3048)
			(end -0.67945 -0.305054)
			(stroke
				(width 0.1)
				(type default)
			)
			(layer "F.Fab")
		)
		(fp_line
			(start -0.67945 -0.305054)
			(end -0.12065 -0.305054)
			(stroke
				(width 0.1)
				(type default)
			)
			(layer "F.Fab")
		)
		(pad "1" smd circle
			(at -0.40005 0 180)
			(size 0 0)
			(layers "F.Cu" "F.Mask" "F.Paste")
			(net "GND")
		)
		(pad "2" smd circle
			(at 0.40005 0 180)
			(size 0 0)
			(layers "F.Cu" "F.Mask" "F.Paste")
			(net "P3V3_SSD6")
		)
	)
	(footprint ""
		(layer "F.Cu")
		(at 284.6451 -175.182276)
		(property "Reference" "R255"
			(at 0 0 0)
			(layer "F.SilkS")
			(hide yes)
			(effects
				(font
					(size 1.27 1.27)
				)
			)
		)
		(property "Value" ""
			(at 0 0 0)
			(layer "F.Fab")
			(effects
				(font
					(size 1.27 1.27)
				)
			)
		)
		(duplicate_pad_numbers_are_jumpers no)
		(fp_line
			(start -0.7874 -0.4064)
			(end 0.7874 -0.4064)
			(stroke
				(width 0.1524)
				(type default)
			)
			(layer "F.SilkS")
		)
		(fp_line
			(start -0.7874 0.4064)
			(end -0.7874 -0.4064)
			(stroke
				(width 0.1524)
				(type default)
			)
			(layer "F.SilkS")
		)
		(fp_line
			(start 0.7874 -0.4064)
			(end 0.7874 0.4064)
			(stroke
				(width 0.1524)
				(type default)
			)
			(layer "F.SilkS")
		)
		(fp_line
			(start 0.7874 0.4064)
			(end -0.7874 0.4064)
			(stroke
				(width 0.1524)
				(type default)
			)
			(layer "F.SilkS")
		)
		(fp_line
			(start -0.67945 -0.305054)
			(end -0.12065 -0.305054)
			(stroke
				(width 0.1)
				(type default)
			)
			(layer "F.Fab")
		)
		(fp_line
			(start -0.67945 0.3048)
			(end -0.67945 -0.305054)
			(stroke
				(width 0.1)
				(type default)
			)
			(layer "F.Fab")
		)
		(fp_line
			(start -0.12065 -0.305054)
			(end -0.12065 -0.2794)
			(stroke
				(width 0.1)
				(type default)
			)
			(layer "F.Fab")
		)
		(fp_line
			(start -0.12065 -0.2794)
			(end 0.12065 -0.2794)
			(stroke
				(width 0.1)
				(type default)
			)
			(layer "F.Fab")
		)
		(fp_line
			(start -0.12065 0.2794)
			(end -0.12065 0.3048)
			(stroke
				(width 0.1)
				(type default)
			)
			(layer "F.Fab")
		)
		(fp_line
			(start -0.12065 0.3048)
			(end -0.67945 0.3048)
			(stroke
				(width 0.1)
				(type default)
			)
			(layer "F.Fab")
		)
		(fp_line
			(start 0.120396 0.2794)
			(end -0.12065 0.2794)
			(stroke
				(width 0.1)
				(type default)
			)
			(layer "F.Fab")
		)
		(fp_line
			(start 0.120396 0.3048)
			(end 0.120396 0.2794)
			(stroke
				(width 0.1)
				(type default)
			)
			(layer "F.Fab")
		)
		(fp_line
			(start 0.12065 -0.3048)
			(end 0.67945 -0.3048)
			(stroke
				(width 0.1)
				(type default)
			)
			(layer "F.Fab")
		)
		(fp_line
			(start 0.12065 -0.2794)
			(end 0.12065 -0.3048)
			(stroke
				(width 0.1)
				(type default)
			)
			(layer "F.Fab")
		)
		(fp_line
			(start 0.67945 -0.3048)
			(end 0.67945 0.3048)
			(stroke
				(width 0.1)
				(type default)
			)
			(layer "F.Fab")
		)
		(fp_line
			(start 0.67945 0.3048)
			(end 0.120396 0.3048)
			(stroke
				(width 0.1)
				(type default)
			)
			(layer "F.Fab")
		)
		(pad "1" smd circle
			(at -0.40005 0)
			(size 0 0)
			(layers "F.Cu" "F.Mask" "F.Paste")
			(net "HP_NIC4_PWRGD_R")
		)
		(pad "2" smd circle
			(at 0.40005 0)
			(size 0 0)
			(layers "F.Cu" "F.Mask" "F.Paste")
			(net "HP_NIC4_PWRGD")
		)
	)
	(footprint ""
		(layer "F.Cu")
		(at 341.372444 -350.098614 90)
		(property "Reference" "C578"
			(at 0 0 90)
			(layer "F.SilkS")
			(hide yes)
			(effects
				(font
					(size 1.27 1.27)
				)
			)
		)
		(property "Value" ""
			(at 0 0 90)
			(layer "F.Fab")
			(effects
				(font
					(size 1.27 1.27)
				)
			)
		)
		(duplicate_pad_numbers_are_jumpers no)
		(fp_line
			(start 0.299974 -0.150114)
			(end 0.299974 0.150114)
			(stroke
				(width 0.1)
				(type default)
			)
			(layer "F.Fab")
		)
		(fp_line
			(start -0.299974 -0.150114)
			(end 0.299974 -0.150114)
			(stroke
				(width 0.1)
				(type default)
			)
			(layer "F.Fab")
		)
		(fp_line
			(start 0.299974 0.150114)
			(end -0.299974 0.150114)
			(stroke
				(width 0.1)
				(type default)
			)
			(layer "F.Fab")
		)
		(fp_line
			(start -0.299974 0.150114)
			(end -0.299974 -0.150114)
			(stroke
				(width 0.1)
				(type default)
			)
			(layer "F.Fab")
		)
		(pad "1" smd rect
			(at -0.2667 0 90)
			(size 0.3048 0.381)
			(layers "F.Cu" "F.Mask" "F.Paste")
			(net "P5E_PEX2_STN6_TX_DN<98>")
		)
		(pad "2" smd rect
			(at 0.2667 0 90)
			(size 0.3048 0.381)
			(layers "F.Cu" "F.Mask" "F.Paste")
			(net "P5E_PEX2_STN6_TX_C_DN<98>")
		)
	)
	(footprint ""
		(layer "F.Cu")
		(at 282.681934 -38.041072 180)
		(property "Reference" "R6096"
			(at 0 0 180)
			(layer "F.SilkS")
			(hide yes)
			(effects
				(font
					(size 1.27 1.27)
				)
			)
		)
		(property "Value" ""
			(at 0 0 180)
			(layer "F.Fab")
			(effects
				(font
					(size 1.27 1.27)
				)
			)
		)
		(duplicate_pad_numbers_are_jumpers no)
		(fp_line
			(start 0.7874 0.4064)
			(end -0.7874 0.4064)
			(stroke
				(width 0.1524)
				(type default)
			)
			(layer "F.SilkS")
		)
		(fp_line
			(start 0.7874 -0.4064)
			(end 0.7874 0.4064)
			(stroke
				(width 0.1524)
				(type default)
			)
			(layer "F.SilkS")
		)
		(fp_line
			(start -0.7874 0.4064)
			(end -0.7874 -0.4064)
			(stroke
				(width 0.1524)
				(type default)
			)
			(layer "F.SilkS")
		)
		(fp_line
			(start -0.7874 -0.4064)
			(end 0.7874 -0.4064)
			(stroke
				(width 0.1524)
				(type default)
			)
			(layer "F.SilkS")
		)
		(fp_line
			(start 0.67945 0.3048)
			(end 0.120396 0.3048)
			(stroke
				(width 0.1)
				(type default)
			)
			(layer "F.Fab")
		)
		(fp_line
			(start 0.67945 -0.3048)
			(end 0.67945 0.3048)
			(stroke
				(width 0.1)
				(type default)
			)
			(layer "F.Fab")
		)
		(fp_line
			(start 0.12065 -0.2794)
			(end 0.12065 -0.3048)
			(stroke
				(width 0.1)
				(type default)
			)
			(layer "F.Fab")
		)
		(fp_line
			(start 0.12065 -0.3048)
			(end 0.67945 -0.3048)
			(stroke
				(width 0.1)
				(type default)
			)
			(layer "F.Fab")
		)
		(fp_line
			(start 0.120396 0.3048)
			(end 0.120396 0.2794)
			(stroke
				(width 0.1)
				(type default)
			)
			(layer "F.Fab")
		)
		(fp_line
			(start 0.120396 0.2794)
			(end -0.12065 0.2794)
			(stroke
				(width 0.1)
				(type default)
			)
			(layer "F.Fab")
		)
		(fp_line
			(start -0.12065 0.3048)
			(end -0.67945 0.3048)
			(stroke
				(width 0.1)
				(type default)
			)
			(layer "F.Fab")
		)
		(fp_line
			(start -0.12065 0.2794)
			(end -0.12065 0.3048)
			(stroke
				(width 0.1)
				(type default)
			)
			(layer "F.Fab")
		)
		(fp_line
			(start -0.12065 -0.2794)
			(end 0.12065 -0.2794)
			(stroke
				(width 0.1)
				(type default)
			)
			(layer "F.Fab")
		)
		(fp_line
			(start -0.12065 -0.305054)
			(end -0.12065 -0.2794)
			(stroke
				(width 0.1)
				(type default)
			)
			(layer "F.Fab")
		)
		(fp_line
			(start -0.67945 0.3048)
			(end -0.67945 -0.305054)
			(stroke
				(width 0.1)
				(type default)
			)
			(layer "F.Fab")
		)
		(fp_line
			(start -0.67945 -0.305054)
			(end -0.12065 -0.305054)
			(stroke
				(width 0.1)
				(type default)
			)
			(layer "F.Fab")
		)
		(pad "1" smd circle
			(at -0.40005 0 180)
			(size 0 0)
			(layers "F.Cu" "F.Mask" "F.Paste")
			(net "P5V_AUX")
		)
		(pad "2" smd circle
			(at 0.40005 0 180)
			(size 0 0)
			(layers "F.Cu" "F.Mask" "F.Paste")
			(net "P3V3_SSD10_PG_G2")
		)
	)
	(footprint ""
		(layer "F.Cu")
		(at 248.094754 -278.551386)
		(property "Reference" "R790"
			(at 0 0 0)
			(layer "F.SilkS")
			(hide yes)
			(effects
				(font
					(size 1.27 1.27)
				)
			)
		)
		(property "Value" ""
			(at 0 0 0)
			(layer "F.Fab")
			(effects
				(font
					(size 1.27 1.27)
				)
			)
		)
		(duplicate_pad_numbers_are_jumpers no)
		(fp_line
			(start -0.7874 -0.4064)
			(end 0.7874 -0.4064)
			(stroke
				(width 0.1524)
				(type default)
			)
			(layer "F.SilkS")
		)
		(fp_line
			(start -0.7874 0.4064)
			(end -0.7874 -0.4064)
			(stroke
				(width 0.1524)
				(type default)
			)
			(layer "F.SilkS")
		)
		(fp_line
			(start 0.7874 -0.4064)
			(end 0.7874 0.4064)
			(stroke
				(width 0.1524)
				(type default)
			)
			(layer "F.SilkS")
		)
		(fp_line
			(start 0.7874 0.4064)
			(end -0.7874 0.4064)
			(stroke
				(width 0.1524)
				(type default)
			)
			(layer "F.SilkS")
		)
		(fp_line
			(start -0.67945 -0.305054)
			(end -0.12065 -0.305054)
			(stroke
				(width 0.1)
				(type default)
			)
			(layer "F.Fab")
		)
		(fp_line
			(start -0.67945 0.3048)
			(end -0.67945 -0.305054)
			(stroke
				(width 0.1)
				(type default)
			)
			(layer "F.Fab")
		)
		(fp_line
			(start -0.12065 -0.305054)
			(end -0.12065 -0.2794)
			(stroke
				(width 0.1)
				(type default)
			)
			(layer "F.Fab")
		)
		(fp_line
			(start -0.12065 -0.2794)
			(end 0.12065 -0.2794)
			(stroke
				(width 0.1)
				(type default)
			)
			(layer "F.Fab")
		)
		(fp_line
			(start -0.12065 0.2794)
			(end -0.12065 0.3048)
			(stroke
				(width 0.1)
				(type default)
			)
			(layer "F.Fab")
		)
		(fp_line
			(start -0.12065 0.3048)
			(end -0.67945 0.3048)
			(stroke
				(width 0.1)
				(type default)
			)
			(layer "F.Fab")
		)
		(fp_line
			(start 0.120396 0.2794)
			(end -0.12065 0.2794)
			(stroke
				(width 0.1)
				(type default)
			)
			(layer "F.Fab")
		)
		(fp_line
			(start 0.120396 0.3048)
			(end 0.120396 0.2794)
			(stroke
				(width 0.1)
				(type default)
			)
			(layer "F.Fab")
		)
		(fp_line
			(start 0.12065 -0.3048)
			(end 0.67945 -0.3048)
			(stroke
				(width 0.1)
				(type default)
			)
			(layer "F.Fab")
		)
		(fp_line
			(start 0.12065 -0.2794)
			(end 0.12065 -0.3048)
			(stroke
				(width 0.1)
				(type default)
			)
			(layer "F.Fab")
		)
		(fp_line
			(start 0.67945 -0.3048)
			(end 0.67945 0.3048)
			(stroke
				(width 0.1)
				(type default)
			)
			(layer "F.Fab")
		)
		(fp_line
			(start 0.67945 0.3048)
			(end 0.120396 0.3048)
			(stroke
				(width 0.1)
				(type default)
			)
			(layer "F.Fab")
		)
		(pad "1" smd circle
			(at -0.40005 0)
			(size 0 0)
			(layers "F.Cu" "F.Mask" "F.Paste")
			(net "P3V3_AUX")
		)
		(pad "2" smd circle
			(at 0.40005 0)
			(size 0 0)
			(layers "F.Cu" "F.Mask" "F.Paste")
			(net "PEX_ADC_ALERT_N")
		)
	)
	(footprint ""
		(layer "F.Cu")
		(at 356.410514 -63.652146 180)
		(property "Reference" "R6016"
			(at 0 0 180)
			(layer "F.SilkS")
			(hide yes)
			(effects
				(font
					(size 1.27 1.27)
				)
			)
		)
		(property "Value" ""
			(at 0 0 180)
			(layer "F.Fab")
			(effects
				(font
					(size 1.27 1.27)
				)
			)
		)
		(duplicate_pad_numbers_are_jumpers no)
		(fp_line
			(start 0.7874 0.4064)
			(end -0.7874 0.4064)
			(stroke
				(width 0.1524)
				(type default)
			)
			(layer "F.SilkS")
		)
		(fp_line
			(start 0.7874 -0.4064)
			(end 0.7874 0.4064)
			(stroke
				(width 0.1524)
				(type default)
			)
			(layer "F.SilkS")
		)
		(fp_line
			(start -0.7874 0.4064)
			(end -0.7874 -0.4064)
			(stroke
				(width 0.1524)
				(type default)
			)
			(layer "F.SilkS")
		)
		(fp_line
			(start -0.7874 -0.4064)
			(end 0.7874 -0.4064)
			(stroke
				(width 0.1524)
				(type default)
			)
			(layer "F.SilkS")
		)
		(fp_line
			(start 0.67945 0.3048)
			(end 0.120396 0.3048)
			(stroke
				(width 0.1)
				(type default)
			)
			(layer "F.Fab")
		)
		(fp_line
			(start 0.67945 -0.3048)
			(end 0.67945 0.3048)
			(stroke
				(width 0.1)
				(type default)
			)
			(layer "F.Fab")
		)
		(fp_line
			(start 0.12065 -0.2794)
			(end 0.12065 -0.3048)
			(stroke
				(width 0.1)
				(type default)
			)
			(layer "F.Fab")
		)
		(fp_line
			(start 0.12065 -0.3048)
			(end 0.67945 -0.3048)
			(stroke
				(width 0.1)
				(type default)
			)
			(layer "F.Fab")
		)
		(fp_line
			(start 0.120396 0.3048)
			(end 0.120396 0.2794)
			(stroke
				(width 0.1)
				(type default)
			)
			(layer "F.Fab")
		)
		(fp_line
			(start 0.120396 0.2794)
			(end -0.12065 0.2794)
			(stroke
				(width 0.1)
				(type default)
			)
			(layer "F.Fab")
		)
		(fp_line
			(start -0.12065 0.3048)
			(end -0.67945 0.3048)
			(stroke
				(width 0.1)
				(type default)
			)
			(layer "F.Fab")
		)
		(fp_line
			(start -0.12065 0.2794)
			(end -0.12065 0.3048)
			(stroke
				(width 0.1)
				(type default)
			)
			(layer "F.Fab")
		)
		(fp_line
			(start -0.12065 -0.2794)
			(end 0.12065 -0.2794)
			(stroke
				(width 0.1)
				(type default)
			)
			(layer "F.Fab")
		)
		(fp_line
			(start -0.12065 -0.305054)
			(end -0.12065 -0.2794)
			(stroke
				(width 0.1)
				(type default)
			)
			(layer "F.Fab")
		)
		(fp_line
			(start -0.67945 0.3048)
			(end -0.67945 -0.305054)
			(stroke
				(width 0.1)
				(type default)
			)
			(layer "F.Fab")
		)
		(fp_line
			(start -0.67945 -0.305054)
			(end -0.12065 -0.305054)
			(stroke
				(width 0.1)
				(type default)
			)
			(layer "F.Fab")
		)
		(pad "1" smd circle
			(at -0.40005 0 180)
			(size 0 0)
			(layers "F.Cu" "F.Mask" "F.Paste")
			(net "P5V_AUX")
		)
		(pad "2" smd circle
			(at 0.40005 0 180)
			(size 0 0)
			(layers "F.Cu" "F.Mask" "F.Paste")
			(net "P12V_SSD12_PG_G2")
		)
	)
	(footprint ""
		(layer "F.Cu")
		(at 328.146918 -55.63489 90)
		(property "Reference" "PC441"
			(at 0 0 90)
			(layer "F.SilkS")
			(hide yes)
			(effects
				(font
					(size 1.27 1.27)
				)
			)
		)
		(property "Value" ""
			(at 0 0 90)
			(layer "F.Fab")
			(effects
				(font
					(size 1.27 1.27)
				)
			)
		)
		(duplicate_pad_numbers_are_jumpers no)
		(fp_line
			(start 1.524 -0.762)
			(end 1.524 0.762)
			(stroke
				(width 0.1524)
				(type default)
			)
			(layer "F.SilkS")
		)
		(fp_line
			(start -1.524 -0.762)
			(end 1.524 -0.762)
			(stroke
				(width 0.1524)
				(type default)
			)
			(layer "F.SilkS")
		)
		(fp_line
			(start 1.524 0.762)
			(end -1.524 0.762)
			(stroke
				(width 0.1524)
				(type default)
			)
			(layer "F.SilkS")
		)
		(fp_line
			(start -1.524 0.762)
			(end -1.524 -0.762)
			(stroke
				(width 0.1524)
				(type default)
			)
			(layer "F.SilkS")
		)
		(fp_line
			(start 1.1049 -0.724916)
			(end -1.1049 -0.724916)
			(stroke
				(width 0.1)
				(type default)
			)
			(layer "F.Fab")
		)
		(fp_line
			(start -1.1049 -0.724916)
			(end -1.1049 0.724916)
			(stroke
				(width 0.1)
				(type default)
			)
			(layer "F.Fab")
		)
		(fp_line
			(start 1.1049 0.724916)
			(end 1.1049 -0.724916)
			(stroke
				(width 0.1)
				(type default)
			)
			(layer "F.Fab")
		)
		(fp_line
			(start -1.1049 0.724916)
			(end 1.1049 0.724916)
			(stroke
				(width 0.1)
				(type default)
			)
			(layer "F.Fab")
		)
		(pad "1" smd rect
			(at -0.889 0 270)
			(size 1.016 1.27)
			(layers "F.Cu" "F.Mask" "F.Paste")
			(net "P12V_SSD11_R")
		)
		(pad "2" smd rect
			(at 0.889 0 270)
			(size 1.016 1.27)
			(layers "F.Cu" "F.Mask" "F.Paste")
			(net "GND")
		)
	)
	(footprint ""
		(layer "F.Cu")
		(at 290.775644 -36.915598 -90)
		(property "Reference" "R5577"
			(at 0 0 270)
			(layer "F.SilkS")
			(hide yes)
			(effects
				(font
					(size 1.27 1.27)
				)
			)
		)
		(property "Value" ""
			(at 0 0 270)
			(layer "F.Fab")
			(effects
				(font
					(size 1.27 1.27)
				)
			)
		)
		(duplicate_pad_numbers_are_jumpers no)
		(fp_line
			(start -0.7874 0.4064)
			(end -0.7874 -0.4064)
			(stroke
				(width 0.1524)
				(type default)
			)
			(layer "F.SilkS")
		)
		(fp_line
			(start 0.7874 0.4064)
			(end -0.7874 0.4064)
			(stroke
				(width 0.1524)
				(type default)
			)
			(layer "F.SilkS")
		)
		(fp_line
			(start -0.7874 -0.4064)
			(end 0.7874 -0.4064)
			(stroke
				(width 0.1524)
				(type default)
			)
			(layer "F.SilkS")
		)
		(fp_line
			(start 0.7874 -0.4064)
			(end 0.7874 0.4064)
			(stroke
				(width 0.1524)
				(type default)
			)
			(layer "F.SilkS")
		)
		(fp_line
			(start -0.67945 0.3048)
			(end -0.67945 -0.305054)
			(stroke
				(width 0.1)
				(type default)
			)
			(layer "F.Fab")
		)
		(fp_line
			(start -0.12065 0.3048)
			(end -0.67945 0.3048)
			(stroke
				(width 0.1)
				(type default)
			)
			(layer "F.Fab")
		)
		(fp_line
			(start 0.120396 0.3048)
			(end 0.120396 0.2794)
			(stroke
				(width 0.1)
				(type default)
			)
			(layer "F.Fab")
		)
		(fp_line
			(start 0.67945 0.3048)
			(end 0.120396 0.3048)
			(stroke
				(width 0.1)
				(type default)
			)
			(layer "F.Fab")
		)
		(fp_line
			(start -0.12065 0.2794)
			(end -0.12065 0.3048)
			(stroke
				(width 0.1)
				(type default)
			)
			(layer "F.Fab")
		)
		(fp_line
			(start 0.120396 0.2794)
			(end -0.12065 0.2794)
			(stroke
				(width 0.1)
				(type default)
			)
			(layer "F.Fab")
		)
		(fp_line
			(start -0.12065 -0.2794)
			(end 0.12065 -0.2794)
			(stroke
				(width 0.1)
				(type default)
			)
			(layer "F.Fab")
		)
		(fp_line
			(start 0.12065 -0.2794)
			(end 0.12065 -0.3048)
			(stroke
				(width 0.1)
				(type default)
			)
			(layer "F.Fab")
		)
		(fp_line
			(start 0.12065 -0.3048)
			(end 0.67945 -0.3048)
			(stroke
				(width 0.1)
				(type default)
			)
			(layer "F.Fab")
		)
		(fp_line
			(start 0.67945 -0.3048)
			(end 0.67945 0.3048)
			(stroke
				(width 0.1)
				(type default)
			)
			(layer "F.Fab")
		)
		(fp_line
			(start -0.67945 -0.305054)
			(end -0.12065 -0.305054)
			(stroke
				(width 0.1)
				(type default)
			)
			(layer "F.Fab")
		)
		(fp_line
			(start -0.12065 -0.305054)
			(end -0.12065 -0.2794)
			(stroke
				(width 0.1)
				(type default)
			)
			(layer "F.Fab")
		)
		(pad "1" smd circle
			(at -0.40005 0 270)
			(size 0 0)
			(layers "F.Cu" "F.Mask" "F.Paste")
			(net "PRSNT_SSD10_R1_N")
		)
		(pad "2" smd circle
			(at 0.40005 0 270)
			(size 0 0)
			(layers "F.Cu" "F.Mask" "F.Paste")
			(net "PRSNT_SSD10_R_N")
		)
	)
	(footprint ""
		(layer "F.Cu")
		(at 332.085442 -27.092148 -90)
		(property "Reference" "R5757"
			(at 0 0 270)
			(layer "F.SilkS")
			(hide yes)
			(effects
				(font
					(size 1.27 1.27)
				)
			)
		)
		(property "Value" ""
			(at 0 0 270)
			(layer "F.Fab")
			(effects
				(font
					(size 1.27 1.27)
				)
			)
		)
		(duplicate_pad_numbers_are_jumpers no)
		(fp_line
			(start -0.7874 0.4064)
			(end -0.7874 -0.4064)
			(stroke
				(width 0.1524)
				(type default)
			)
			(layer "F.SilkS")
		)
		(fp_line
			(start 0.7874 0.4064)
			(end -0.7874 0.4064)
			(stroke
				(width 0.1524)
				(type default)
			)
			(layer "F.SilkS")
		)
		(fp_line
			(start -0.7874 -0.4064)
			(end 0.7874 -0.4064)
			(stroke
				(width 0.1524)
				(type default)
			)
			(layer "F.SilkS")
		)
		(fp_line
			(start 0.7874 -0.4064)
			(end 0.7874 0.4064)
			(stroke
				(width 0.1524)
				(type default)
			)
			(layer "F.SilkS")
		)
		(fp_line
			(start -0.67945 0.3048)
			(end -0.67945 -0.305054)
			(stroke
				(width 0.1)
				(type default)
			)
			(layer "F.Fab")
		)
		(fp_line
			(start -0.12065 0.3048)
			(end -0.67945 0.3048)
			(stroke
				(width 0.1)
				(type default)
			)
			(layer "F.Fab")
		)
		(fp_line
			(start 0.120396 0.3048)
			(end 0.120396 0.2794)
			(stroke
				(width 0.1)
				(type default)
			)
			(layer "F.Fab")
		)
		(fp_line
			(start 0.67945 0.3048)
			(end 0.120396 0.3048)
			(stroke
				(width 0.1)
				(type default)
			)
			(layer "F.Fab")
		)
		(fp_line
			(start -0.12065 0.2794)
			(end -0.12065 0.3048)
			(stroke
				(width 0.1)
				(type default)
			)
			(layer "F.Fab")
		)
		(fp_line
			(start 0.120396 0.2794)
			(end -0.12065 0.2794)
			(stroke
				(width 0.1)
				(type default)
			)
			(layer "F.Fab")
		)
		(fp_line
			(start -0.12065 -0.2794)
			(end 0.12065 -0.2794)
			(stroke
				(width 0.1)
				(type default)
			)
			(layer "F.Fab")
		)
		(fp_line
			(start 0.12065 -0.2794)
			(end 0.12065 -0.3048)
			(stroke
				(width 0.1)
				(type default)
			)
			(layer "F.Fab")
		)
		(fp_line
			(start 0.12065 -0.3048)
			(end 0.67945 -0.3048)
			(stroke
				(width 0.1)
				(type default)
			)
			(layer "F.Fab")
		)
		(fp_line
			(start 0.67945 -0.3048)
			(end 0.67945 0.3048)
			(stroke
				(width 0.1)
				(type default)
			)
			(layer "F.Fab")
		)
		(fp_line
			(start -0.67945 -0.305054)
			(end -0.12065 -0.305054)
			(stroke
				(width 0.1)
				(type default)
			)
			(layer "F.Fab")
		)
		(fp_line
			(start -0.12065 -0.305054)
			(end -0.12065 -0.2794)
			(stroke
				(width 0.1)
				(type default)
			)
			(layer "F.Fab")
		)
		(pad "1" smd circle
			(at -0.40005 0 270)
			(size 0 0)
			(layers "F.Cu" "F.Mask" "F.Paste")
			(net "P3V3_SSD11")
		)
		(pad "2" smd circle
			(at 0.40005 0 270)
			(size 0 0)
			(layers "F.Cu" "F.Mask" "F.Paste")
			(net "SSD11_LED_ISO_N")
		)
	)
	(footprint ""
		(layer "F.Cu")
		(at 447.275712 -120.493028)
		(property "Reference" "R4481"
			(at 0 0 0)
			(layer "F.SilkS")
			(hide yes)
			(effects
				(font
					(size 1.27 1.27)
				)
			)
		)
		(property "Value" ""
			(at 0 0 0)
			(layer "F.Fab")
			(effects
				(font
					(size 1.27 1.27)
				)
			)
		)
		(duplicate_pad_numbers_are_jumpers no)
		(fp_line
			(start -0.7874 -0.4064)
			(end 0.7874 -0.4064)
			(stroke
				(width 0.1524)
				(type default)
			)
			(layer "F.SilkS")
		)
		(fp_line
			(start -0.7874 0.4064)
			(end -0.7874 -0.4064)
			(stroke
				(width 0.1524)
				(type default)
			)
			(layer "F.SilkS")
		)
		(fp_line
			(start 0.7874 -0.4064)
			(end 0.7874 0.4064)
			(stroke
				(width 0.1524)
				(type default)
			)
			(layer "F.SilkS")
		)
		(fp_line
			(start 0.7874 0.4064)
			(end -0.7874 0.4064)
			(stroke
				(width 0.1524)
				(type default)
			)
			(layer "F.SilkS")
		)
		(fp_line
			(start -0.67945 -0.305054)
			(end -0.12065 -0.305054)
			(stroke
				(width 0.1)
				(type default)
			)
			(layer "F.Fab")
		)
		(fp_line
			(start -0.67945 0.3048)
			(end -0.67945 -0.305054)
			(stroke
				(width 0.1)
				(type default)
			)
			(layer "F.Fab")
		)
		(fp_line
			(start -0.12065 -0.305054)
			(end -0.12065 -0.2794)
			(stroke
				(width 0.1)
				(type default)
			)
			(layer "F.Fab")
		)
		(fp_line
			(start -0.12065 -0.2794)
			(end 0.12065 -0.2794)
			(stroke
				(width 0.1)
				(type default)
			)
			(layer "F.Fab")
		)
		(fp_line
			(start -0.12065 0.2794)
			(end -0.12065 0.3048)
			(stroke
				(width 0.1)
				(type default)
			)
			(layer "F.Fab")
		)
		(fp_line
			(start -0.12065 0.3048)
			(end -0.67945 0.3048)
			(stroke
				(width 0.1)
				(type default)
			)
			(layer "F.Fab")
		)
		(fp_line
			(start 0.120396 0.2794)
			(end -0.12065 0.2794)
			(stroke
				(width 0.1)
				(type default)
			)
			(layer "F.Fab")
		)
		(fp_line
			(start 0.120396 0.3048)
			(end 0.120396 0.2794)
			(stroke
				(width 0.1)
				(type default)
			)
			(layer "F.Fab")
		)
		(fp_line
			(start 0.12065 -0.3048)
			(end 0.67945 -0.3048)
			(stroke
				(width 0.1)
				(type default)
			)
			(layer "F.Fab")
		)
		(fp_line
			(start 0.12065 -0.2794)
			(end 0.12065 -0.3048)
			(stroke
				(width 0.1)
				(type default)
			)
			(layer "F.Fab")
		)
		(fp_line
			(start 0.67945 -0.3048)
			(end 0.67945 0.3048)
			(stroke
				(width 0.1)
				(type default)
			)
			(layer "F.Fab")
		)
		(fp_line
			(start 0.67945 0.3048)
			(end 0.120396 0.3048)
			(stroke
				(width 0.1)
				(type default)
			)
			(layer "F.Fab")
		)
		(pad "1" smd circle
			(at -0.40005 0)
			(size 0 0)
			(layers "F.Cu" "F.Mask" "F.Paste")
			(net "PWRGD_P3V3_NIC7")
		)
		(pad "2" smd circle
			(at 0.40005 0)
			(size 0 0)
			(layers "F.Cu" "F.Mask" "F.Paste")
			(net "PWRGD_P3V3_NIC7_R")
		)
	)
	(footprint ""
		(layer "F.Cu")
		(at 242.310412 -126.995428 180)
		(property "Reference" "PC459"
			(at 0 0 180)
			(layer "F.SilkS")
			(hide yes)
			(effects
				(font
					(size 1.27 1.27)
				)
			)
		)
		(property "Value" ""
			(at 0 0 180)
			(layer "F.Fab")
			(effects
				(font
					(size 1.27 1.27)
				)
			)
		)
		(duplicate_pad_numbers_are_jumpers no)
		(fp_line
			(start 0.7874 0.4064)
			(end -0.7874 0.4064)
			(stroke
				(width 0.1524)
				(type default)
			)
			(layer "F.SilkS")
		)
		(fp_line
			(start 0.7874 -0.4064)
			(end 0.7874 0.4064)
			(stroke
				(width 0.1524)
				(type default)
			)
			(layer "F.SilkS")
		)
		(fp_line
			(start -0.7874 0.4064)
			(end -0.7874 -0.4064)
			(stroke
				(width 0.1524)
				(type default)
			)
			(layer "F.SilkS")
		)
		(fp_line
			(start -0.7874 -0.4064)
			(end 0.7874 -0.4064)
			(stroke
				(width 0.1524)
				(type default)
			)
			(layer "F.SilkS")
		)
		(fp_line
			(start 0.67945 0.3048)
			(end 0.120396 0.3048)
			(stroke
				(width 0.1)
				(type default)
			)
			(layer "F.Fab")
		)
		(fp_line
			(start 0.67945 -0.3048)
			(end 0.67945 0.3048)
			(stroke
				(width 0.1)
				(type default)
			)
			(layer "F.Fab")
		)
		(fp_line
			(start 0.12065 -0.2794)
			(end 0.12065 -0.3048)
			(stroke
				(width 0.1)
				(type default)
			)
			(layer "F.Fab")
		)
		(fp_line
			(start 0.12065 -0.3048)
			(end 0.67945 -0.3048)
			(stroke
				(width 0.1)
				(type default)
			)
			(layer "F.Fab")
		)
		(fp_line
			(start 0.120396 0.3048)
			(end 0.120396 0.2794)
			(stroke
				(width 0.1)
				(type default)
			)
			(layer "F.Fab")
		)
		(fp_line
			(start 0.120396 0.2794)
			(end -0.12065 0.2794)
			(stroke
				(width 0.1)
				(type default)
			)
			(layer "F.Fab")
		)
		(fp_line
			(start -0.12065 0.3048)
			(end -0.67945 0.3048)
			(stroke
				(width 0.1)
				(type default)
			)
			(layer "F.Fab")
		)
		(fp_line
			(start -0.12065 0.2794)
			(end -0.12065 0.3048)
			(stroke
				(width 0.1)
				(type default)
			)
			(layer "F.Fab")
		)
		(fp_line
			(start -0.12065 -0.2794)
			(end 0.12065 -0.2794)
			(stroke
				(width 0.1)
				(type default)
			)
			(layer "F.Fab")
		)
		(fp_line
			(start -0.12065 -0.305054)
			(end -0.12065 -0.2794)
			(stroke
				(width 0.1)
				(type default)
			)
			(layer "F.Fab")
		)
		(fp_line
			(start -0.67945 0.3048)
			(end -0.67945 -0.305054)
			(stroke
				(width 0.1)
				(type default)
			)
			(layer "F.Fab")
		)
		(fp_line
			(start -0.67945 -0.305054)
			(end -0.12065 -0.305054)
			(stroke
				(width 0.1)
				(type default)
			)
			(layer "F.Fab")
		)
		(pad "1" smd circle
			(at -0.40005 0 180)
			(size 0 0)
			(layers "F.Cu" "F.Mask" "F.Paste")
			(net "P3V3_NIC4_SS")
		)
		(pad "2" smd circle
			(at 0.40005 0 180)
			(size 0 0)
			(layers "F.Cu" "F.Mask" "F.Paste")
			(net "GND")
		)
	)
	(footprint ""
		(layer "F.Cu")
		(at 403.175216 -63.086234)
		(property "Reference" "R6028"
			(at 0 0 0)
			(layer "F.SilkS")
			(hide yes)
			(effects
				(font
					(size 1.27 1.27)
				)
			)
		)
		(property "Value" ""
			(at 0 0 0)
			(layer "F.Fab")
			(effects
				(font
					(size 1.27 1.27)
				)
			)
		)
		(duplicate_pad_numbers_are_jumpers no)
		(fp_line
			(start -0.7874 -0.4064)
			(end 0.7874 -0.4064)
			(stroke
				(width 0.1524)
				(type default)
			)
			(layer "F.SilkS")
		)
		(fp_line
			(start -0.7874 0.4064)
			(end -0.7874 -0.4064)
			(stroke
				(width 0.1524)
				(type default)
			)
			(layer "F.SilkS")
		)
		(fp_line
			(start 0.7874 -0.4064)
			(end 0.7874 0.4064)
			(stroke
				(width 0.1524)
				(type default)
			)
			(layer "F.SilkS")
		)
		(fp_line
			(start 0.7874 0.4064)
			(end -0.7874 0.4064)
			(stroke
				(width 0.1524)
				(type default)
			)
			(layer "F.SilkS")
		)
		(fp_line
			(start -0.67945 -0.305054)
			(end -0.12065 -0.305054)
			(stroke
				(width 0.1)
				(type default)
			)
			(layer "F.Fab")
		)
		(fp_line
			(start -0.67945 0.3048)
			(end -0.67945 -0.305054)
			(stroke
				(width 0.1)
				(type default)
			)
			(layer "F.Fab")
		)
		(fp_line
			(start -0.12065 -0.305054)
			(end -0.12065 -0.2794)
			(stroke
				(width 0.1)
				(type default)
			)
			(layer "F.Fab")
		)
		(fp_line
			(start -0.12065 -0.2794)
			(end 0.12065 -0.2794)
			(stroke
				(width 0.1)
				(type default)
			)
			(layer "F.Fab")
		)
		(fp_line
			(start -0.12065 0.2794)
			(end -0.12065 0.3048)
			(stroke
				(width 0.1)
				(type default)
			)
			(layer "F.Fab")
		)
		(fp_line
			(start -0.12065 0.3048)
			(end -0.67945 0.3048)
			(stroke
				(width 0.1)
				(type default)
			)
			(layer "F.Fab")
		)
		(fp_line
			(start 0.120396 0.2794)
			(end -0.12065 0.2794)
			(stroke
				(width 0.1)
				(type default)
			)
			(layer "F.Fab")
		)
		(fp_line
			(start 0.120396 0.3048)
			(end 0.120396 0.2794)
			(stroke
				(width 0.1)
				(type default)
			)
			(layer "F.Fab")
		)
		(fp_line
			(start 0.12065 -0.3048)
			(end 0.67945 -0.3048)
			(stroke
				(width 0.1)
				(type default)
			)
			(layer "F.Fab")
		)
		(fp_line
			(start 0.12065 -0.2794)
			(end 0.12065 -0.3048)
			(stroke
				(width 0.1)
				(type default)
			)
			(layer "F.Fab")
		)
		(fp_line
			(start 0.67945 -0.3048)
			(end 0.67945 0.3048)
			(stroke
				(width 0.1)
				(type default)
			)
			(layer "F.Fab")
		)
		(fp_line
			(start 0.67945 0.3048)
			(end 0.120396 0.3048)
			(stroke
				(width 0.1)
				(type default)
			)
			(layer "F.Fab")
		)
		(pad "1" smd circle
			(at -0.40005 0)
			(size 0 0)
			(layers "F.Cu" "F.Mask" "F.Paste")
			(net "P12V_SSD14_R")
		)
		(pad "2" smd circle
			(at 0.40005 0)
			(size 0 0)
			(layers "F.Cu" "F.Mask" "F.Paste")
			(net "P12V_SSD14_PG_G1")
		)
	)
	(footprint ""
		(layer "F.Cu")
		(at 359.156 -175.006 180)
		(property "Reference" "R4677"
			(at 0 0 180)
			(layer "F.SilkS")
			(hide yes)
			(effects
				(font
					(size 1.27 1.27)
				)
			)
		)
		(property "Value" ""
			(at 0 0 180)
			(layer "F.Fab")
			(effects
				(font
					(size 1.27 1.27)
				)
			)
		)
		(duplicate_pad_numbers_are_jumpers no)
		(fp_line
			(start 0.7874 0.4064)
			(end -0.7874 0.4064)
			(stroke
				(width 0.1524)
				(type default)
			)
			(layer "F.SilkS")
		)
		(fp_line
			(start 0.7874 -0.4064)
			(end 0.7874 0.4064)
			(stroke
				(width 0.1524)
				(type default)
			)
			(layer "F.SilkS")
		)
		(fp_line
			(start -0.7874 0.4064)
			(end -0.7874 -0.4064)
			(stroke
				(width 0.1524)
				(type default)
			)
			(layer "F.SilkS")
		)
		(fp_line
			(start -0.7874 -0.4064)
			(end 0.7874 -0.4064)
			(stroke
				(width 0.1524)
				(type default)
			)
			(layer "F.SilkS")
		)
		(fp_line
			(start 0.67945 0.3048)
			(end 0.120396 0.3048)
			(stroke
				(width 0.1)
				(type default)
			)
			(layer "F.Fab")
		)
		(fp_line
			(start 0.67945 -0.3048)
			(end 0.67945 0.3048)
			(stroke
				(width 0.1)
				(type default)
			)
			(layer "F.Fab")
		)
		(fp_line
			(start 0.12065 -0.2794)
			(end 0.12065 -0.3048)
			(stroke
				(width 0.1)
				(type default)
			)
			(layer "F.Fab")
		)
		(fp_line
			(start 0.12065 -0.3048)
			(end 0.67945 -0.3048)
			(stroke
				(width 0.1)
				(type default)
			)
			(layer "F.Fab")
		)
		(fp_line
			(start 0.120396 0.3048)
			(end 0.120396 0.2794)
			(stroke
				(width 0.1)
				(type default)
			)
			(layer "F.Fab")
		)
		(fp_line
			(start 0.120396 0.2794)
			(end -0.12065 0.2794)
			(stroke
				(width 0.1)
				(type default)
			)
			(layer "F.Fab")
		)
		(fp_line
			(start -0.12065 0.3048)
			(end -0.67945 0.3048)
			(stroke
				(width 0.1)
				(type default)
			)
			(layer "F.Fab")
		)
		(fp_line
			(start -0.12065 0.2794)
			(end -0.12065 0.3048)
			(stroke
				(width 0.1)
				(type default)
			)
			(layer "F.Fab")
		)
		(fp_line
			(start -0.12065 -0.2794)
			(end 0.12065 -0.2794)
			(stroke
				(width 0.1)
				(type default)
			)
			(layer "F.Fab")
		)
		(fp_line
			(start -0.12065 -0.305054)
			(end -0.12065 -0.2794)
			(stroke
				(width 0.1)
				(type default)
			)
			(layer "F.Fab")
		)
		(fp_line
			(start -0.67945 0.3048)
			(end -0.67945 -0.305054)
			(stroke
				(width 0.1)
				(type default)
			)
			(layer "F.Fab")
		)
		(fp_line
			(start -0.67945 -0.305054)
			(end -0.12065 -0.305054)
			(stroke
				(width 0.1)
				(type default)
			)
			(layer "F.Fab")
		)
		(pad "1" smd circle
			(at -0.40005 0 180)
			(size 0 0)
			(layers "F.Cu" "F.Mask" "F.Paste")
			(net "SSD7_PEX_PWR_EN_R")
		)
		(pad "2" smd circle
			(at 0.40005 0 180)
			(size 0 0)
			(layers "F.Cu" "F.Mask" "F.Paste")
			(net "GND")
		)
	)
	(footprint ""
		(layer "F.Cu")
		(at 108.238544 -393.753594 180)
		(property "Reference" "C3636"
			(at 0 0 180)
			(layer "F.SilkS")
			(hide yes)
			(effects
				(font
					(size 1.27 1.27)
				)
			)
		)
		(property "Value" ""
			(at 0 0 180)
			(layer "F.Fab")
			(effects
				(font
					(size 1.27 1.27)
				)
			)
		)
		(duplicate_pad_numbers_are_jumpers no)
		(fp_line
			(start 0.7874 0.4064)
			(end -0.7874 0.4064)
			(stroke
				(width 0.1524)
				(type default)
			)
			(layer "F.SilkS")
		)
		(fp_line
			(start 0.7874 -0.4064)
			(end 0.7874 0.4064)
			(stroke
				(width 0.1524)
				(type default)
			)
			(layer "F.SilkS")
		)
		(fp_line
			(start -0.7874 0.4064)
			(end -0.7874 -0.4064)
			(stroke
				(width 0.1524)
				(type default)
			)
			(layer "F.SilkS")
		)
		(fp_line
			(start -0.7874 -0.4064)
			(end 0.7874 -0.4064)
			(stroke
				(width 0.1524)
				(type default)
			)
			(layer "F.SilkS")
		)
		(fp_line
			(start 0.67945 0.3048)
			(end 0.120396 0.3048)
			(stroke
				(width 0.1)
				(type default)
			)
			(layer "F.Fab")
		)
		(fp_line
			(start 0.67945 -0.3048)
			(end 0.67945 0.3048)
			(stroke
				(width 0.1)
				(type default)
			)
			(layer "F.Fab")
		)
		(fp_line
			(start 0.12065 -0.2794)
			(end 0.12065 -0.3048)
			(stroke
				(width 0.1)
				(type default)
			)
			(layer "F.Fab")
		)
		(fp_line
			(start 0.12065 -0.3048)
			(end 0.67945 -0.3048)
			(stroke
				(width 0.1)
				(type default)
			)
			(layer "F.Fab")
		)
		(fp_line
			(start 0.120396 0.3048)
			(end 0.120396 0.2794)
			(stroke
				(width 0.1)
				(type default)
			)
			(layer "F.Fab")
		)
		(fp_line
			(start 0.120396 0.2794)
			(end -0.12065 0.2794)
			(stroke
				(width 0.1)
				(type default)
			)
			(layer "F.Fab")
		)
		(fp_line
			(start -0.12065 0.3048)
			(end -0.67945 0.3048)
			(stroke
				(width 0.1)
				(type default)
			)
			(layer "F.Fab")
		)
		(fp_line
			(start -0.12065 0.2794)
			(end -0.12065 0.3048)
			(stroke
				(width 0.1)
				(type default)
			)
			(layer "F.Fab")
		)
		(fp_line
			(start -0.12065 -0.2794)
			(end 0.12065 -0.2794)
			(stroke
				(width 0.1)
				(type default)
			)
			(layer "F.Fab")
		)
		(fp_line
			(start -0.12065 -0.305054)
			(end -0.12065 -0.2794)
			(stroke
				(width 0.1)
				(type default)
			)
			(layer "F.Fab")
		)
		(fp_line
			(start -0.67945 0.3048)
			(end -0.67945 -0.305054)
			(stroke
				(width 0.1)
				(type default)
			)
			(layer "F.Fab")
		)
		(fp_line
			(start -0.67945 -0.305054)
			(end -0.12065 -0.305054)
			(stroke
				(width 0.1)
				(type default)
			)
			(layer "F.Fab")
		)
		(pad "1" smd circle
			(at -0.40005 0 180)
			(size 0 0)
			(layers "F.Cu" "F.Mask" "F.Paste")
			(net "BIC_USB_HUB_XOUT_R")
		)
		(pad "2" smd circle
			(at 0.40005 0 180)
			(size 0 0)
			(layers "F.Cu" "F.Mask" "F.Paste")
			(net "GND")
		)
	)
	(footprint ""
		(layer "F.Cu")
		(at 132.142738 -279.486868 -90)
		(property "Reference" "PR114"
			(at 0 0 270)
			(layer "F.SilkS")
			(hide yes)
			(effects
				(font
					(size 1.27 1.27)
				)
			)
		)
		(property "Value" ""
			(at 0 0 270)
			(layer "F.Fab")
			(effects
				(font
					(size 1.27 1.27)
				)
			)
		)
		(duplicate_pad_numbers_are_jumpers no)
		(fp_line
			(start -0.7874 0.4064)
			(end -0.7874 -0.4064)
			(stroke
				(width 0.1524)
				(type default)
			)
			(layer "F.SilkS")
		)
		(fp_line
			(start 0.7874 0.4064)
			(end -0.7874 0.4064)
			(stroke
				(width 0.1524)
				(type default)
			)
			(layer "F.SilkS")
		)
		(fp_line
			(start -0.7874 -0.4064)
			(end 0.7874 -0.4064)
			(stroke
				(width 0.1524)
				(type default)
			)
			(layer "F.SilkS")
		)
		(fp_line
			(start 0.7874 -0.4064)
			(end 0.7874 0.4064)
			(stroke
				(width 0.1524)
				(type default)
			)
			(layer "F.SilkS")
		)
		(fp_line
			(start -0.67945 0.3048)
			(end -0.67945 -0.305054)
			(stroke
				(width 0.1)
				(type default)
			)
			(layer "F.Fab")
		)
		(fp_line
			(start -0.12065 0.3048)
			(end -0.67945 0.3048)
			(stroke
				(width 0.1)
				(type default)
			)
			(layer "F.Fab")
		)
		(fp_line
			(start 0.120396 0.3048)
			(end 0.120396 0.2794)
			(stroke
				(width 0.1)
				(type default)
			)
			(layer "F.Fab")
		)
		(fp_line
			(start 0.67945 0.3048)
			(end 0.120396 0.3048)
			(stroke
				(width 0.1)
				(type default)
			)
			(layer "F.Fab")
		)
		(fp_line
			(start -0.12065 0.2794)
			(end -0.12065 0.3048)
			(stroke
				(width 0.1)
				(type default)
			)
			(layer "F.Fab")
		)
		(fp_line
			(start 0.120396 0.2794)
			(end -0.12065 0.2794)
			(stroke
				(width 0.1)
				(type default)
			)
			(layer "F.Fab")
		)
		(fp_line
			(start -0.12065 -0.2794)
			(end 0.12065 -0.2794)
			(stroke
				(width 0.1)
				(type default)
			)
			(layer "F.Fab")
		)
		(fp_line
			(start 0.12065 -0.2794)
			(end 0.12065 -0.3048)
			(stroke
				(width 0.1)
				(type default)
			)
			(layer "F.Fab")
		)
		(fp_line
			(start 0.12065 -0.3048)
			(end 0.67945 -0.3048)
			(stroke
				(width 0.1)
				(type default)
			)
			(layer "F.Fab")
		)
		(fp_line
			(start 0.67945 -0.3048)
			(end 0.67945 0.3048)
			(stroke
				(width 0.1)
				(type default)
			)
			(layer "F.Fab")
		)
		(fp_line
			(start -0.67945 -0.305054)
			(end -0.12065 -0.305054)
			(stroke
				(width 0.1)
				(type default)
			)
			(layer "F.Fab")
		)
		(fp_line
			(start -0.12065 -0.305054)
			(end -0.12065 -0.2794)
			(stroke
				(width 0.1)
				(type default)
			)
			(layer "F.Fab")
		)
		(pad "1" smd circle
			(at -0.40005 0 270)
			(size 0 0)
			(layers "F.Cu" "F.Mask" "F.Paste")
			(net "P0V8_PEX1_LSET2")
		)
		(pad "2" smd circle
			(at 0.40005 0 270)
			(size 0 0)
			(layers "F.Cu" "F.Mask" "F.Paste")
			(net "GND")
		)
	)
	(footprint ""
		(layer "F.Cu")
		(at 198.76135 -155.196794 180)
		(property "Reference" "C213"
			(at 0 0 180)
			(layer "F.SilkS")
			(hide yes)
			(effects
				(font
					(size 1.27 1.27)
				)
			)
		)
		(property "Value" ""
			(at 0 0 180)
			(layer "F.Fab")
			(effects
				(font
					(size 1.27 1.27)
				)
			)
		)
		(duplicate_pad_numbers_are_jumpers no)
		(fp_line
			(start 0.299974 0.150114)
			(end -0.299974 0.150114)
			(stroke
				(width 0.1)
				(type default)
			)
			(layer "F.Fab")
		)
		(fp_line
			(start 0.299974 -0.150114)
			(end 0.299974 0.150114)
			(stroke
				(width 0.1)
				(type default)
			)
			(layer "F.Fab")
		)
		(fp_line
			(start -0.299974 0.150114)
			(end -0.299974 -0.150114)
			(stroke
				(width 0.1)
				(type default)
			)
			(layer "F.Fab")
		)
		(fp_line
			(start -0.299974 -0.150114)
			(end 0.299974 -0.150114)
			(stroke
				(width 0.1)
				(type default)
			)
			(layer "F.Fab")
		)
		(pad "1" smd rect
			(at -0.2667 0 180)
			(size 0.3048 0.381)
			(layers "F.Cu" "F.Mask" "F.Paste")
			(net "P5E_PEX1_STN0_TX_DN<15>")
		)
		(pad "2" smd rect
			(at 0.2667 0 180)
			(size 0.3048 0.381)
			(layers "F.Cu" "F.Mask" "F.Paste")
			(net "P5E_PEX1_STN0_TX_C_DN<15>")
		)
	)
	(footprint ""
		(layer "F.Cu")
		(at 360.794808 -157.304994 -90)
		(property "Reference" "PU105"
			(at 3.839464 1.638808 0)
			(unlocked yes)
			(layer "F.SilkS")
			(effects
				(font
					(size 0.7874 0.5842)
					(thickness 0.1524)
				)
				(justify left)
			)
		)
		(property "Value" ""
			(at 0 0 270)
			(layer "F.Fab")
			(effects
				(font
					(size 1.27 1.27)
				)
			)
		)
		(duplicate_pad_numbers_are_jumpers no)
		(fp_line
			(start -1.549908 2.549906)
			(end -0.753872 2.549906)
			(stroke
				(width 0.1524)
				(type default)
			)
			(layer "F.SilkS")
		)
		(fp_line
			(start -0.245872 2.549906)
			(end 0.245872 2.549906)
			(stroke
				(width 0.1524)
				(type default)
			)
			(layer "F.SilkS")
		)
		(fp_line
			(start 0.753872 2.549906)
			(end 1.549908 2.549906)
			(stroke
				(width 0.1524)
				(type default)
			)
			(layer "F.SilkS")
		)
		(fp_line
			(start 1.549908 2.549906)
			(end 1.549908 2.253996)
			(stroke
				(width 0.1524)
				(type default)
			)
			(layer "F.SilkS")
		)
		(fp_line
			(start -1.549908 2.253996)
			(end -1.549908 2.549906)
			(stroke
				(width 0.1524)
				(type default)
			)
			(layer "F.SilkS")
		)
		(fp_line
			(start 1.549908 -2.253996)
			(end 1.549908 -2.549906)
			(stroke
				(width 0.1524)
				(type default)
			)
			(layer "F.SilkS")
		)
		(fp_line
			(start -1.549908 -2.549906)
			(end -1.549908 -2.251964)
			(stroke
				(width 0.1524)
				(type default)
			)
			(layer "F.SilkS")
		)
		(fp_line
			(start -0.752094 -2.549906)
			(end -1.549908 -2.549906)
			(stroke
				(width 0.1524)
				(type default)
			)
			(layer "F.SilkS")
		)
		(fp_line
			(start 0.2413 -2.549906)
			(end -0.2413 -2.549906)
			(stroke
				(width 0.1524)
				(type default)
			)
			(layer "F.SilkS")
		)
		(fp_line
			(start 1.549908 -2.549906)
			(end 0.752094 -2.549906)
			(stroke
				(width 0.1524)
				(type default)
			)
			(layer "F.SilkS")
		)
		(fp_poly
			(pts
				(xy -2.312162 -2.109724) (xy -3.163824 -1.68402) (xy -3.163824 -2.535428)
			)
			(stroke
				(width 0)
				(type default)
			)
			(fill yes)
			(layer "F.SilkS")
		)
		(fp_line
			(start -1.549908 2.549906)
			(end 1.549908 2.549906)
			(stroke
				(width 0.1)
				(type default)
			)
			(layer "F.Fab")
		)
		(fp_line
			(start 1.549908 2.549906)
			(end 1.549908 -2.549906)
			(stroke
				(width 0.1)
				(type default)
			)
			(layer "F.Fab")
		)
		(fp_line
			(start -1.549908 -2.549906)
			(end -1.549908 2.549906)
			(stroke
				(width 0.1)
				(type default)
			)
			(layer "F.Fab")
		)
		(fp_line
			(start 1.549908 -2.549906)
			(end -1.549908 -2.549906)
			(stroke
				(width 0.1)
				(type default)
			)
			(layer "F.Fab")
		)
		(fp_poly
			(pts
				(xy -1.891538 -1.999996) (xy -2.7432 -1.574292) (xy -2.7432 -2.4257)
			)
			(stroke
				(width 0)
				(type default)
			)
			(fill yes)
			(layer "F.Fab")
		)
		(fp_text user "11"
			(at 1.215644 3.135884 270)
			(unlocked yes)
			(layer "F.SilkS")
			(effects
				(font
					(size 0.635 0.4064)
					(thickness 0.1524)
				)
			)
		)
		(fp_text user "10"
			(at -1.409446 3.12039 0)
			(unlocked yes)
			(layer "F.SilkS")
			(effects
				(font
					(size 0.635 0.4064)
					(thickness 0.1524)
				)
			)
		)
		(fp_text user "12"
			(at 2.176018 2.903728 0)
			(unlocked yes)
			(layer "F.SilkS")
			(effects
				(font
					(size 0.635 0.4064)
					(thickness 0.1524)
				)
			)
		)
		(fp_text user "9"
			(at -2.338832 2.5908 180)
			(unlocked yes)
			(layer "F.SilkS")
			(effects
				(font
					(size 0.635 0.4064)
					(thickness 0.1524)
				)
			)
		)
		(fp_text user "20"
			(at 1.820164 -3.10642 0)
			(unlocked yes)
			(layer "F.SilkS")
			(effects
				(font
					(size 0.635 0.4064)
					(thickness 0.1524)
				)
			)
		)
		(fp_text user "21_22"
			(at 0.307848 -3.987038 270)
			(unlocked yes)
			(layer "F.SilkS")
			(effects
				(font
					(size 0.635 0.4064)
					(thickness 0.1524)
				)
			)
		)
		(fp_text user "11"
			(at 1.1938 3.329432 270)
			(unlocked yes)
			(layer "F.Fab")
			(effects
				(font
					(size 0.635 0.4064)
					(thickness 0.1524)
				)
			)
		)
		(fp_text user "10"
			(at -1.4224 3.253232 270)
			(unlocked yes)
			(layer "F.Fab")
			(effects
				(font
					(size 0.635 0.4064)
					(thickness 0.1524)
				)
			)
		)
		(fp_text user "12"
			(at 2.207768 2.7178 180)
			(unlocked yes)
			(layer "F.Fab")
			(effects
				(font
					(size 0.635 0.4064)
					(thickness 0.1524)
				)
			)
		)
		(fp_text user "9"
			(at -2.338832 2.5908 180)
			(unlocked yes)
			(layer "F.Fab")
			(effects
				(font
					(size 0.635 0.4064)
					(thickness 0.1524)
				)
			)
		)
		(fp_text user "20"
			(at 2.055368 -2.7686 180)
			(unlocked yes)
			(layer "F.Fab")
			(effects
				(font
					(size 0.635 0.4064)
					(thickness 0.1524)
				)
			)
		)
		(fp_text user "21_22"
			(at -0.0762 -3.401568 270)
			(unlocked yes)
			(layer "F.Fab")
			(effects
				(font
					(size 0.635 0.4064)
					(thickness 0.1524)
				)
			)
		)
		(pad "1" smd circle
			(at -1.374902 -1.999996 180)
			(size 0 0)
			(layers "F.Cu" "F.Mask" "F.Paste")
			(net "P12V_NIC6_CO_EN")
		)
		(pad "2" smd rect
			(at -1.400048 -1.500124 180)
			(size 0.254 0.8128)
			(layers "F.Cu" "F.Mask" "F.Paste")
			(net "GND")
		)
		(pad "3" smd rect
			(at -1.400048 -0.999998 180)
			(size 0.254 0.8128)
			(layers "F.Cu" "F.Mask" "F.Paste")
			(net "GND")
		)
		(pad "4" smd rect
			(at -1.400048 -0.499872 180)
			(size 0.254 0.8128)
			(layers "F.Cu" "F.Mask" "F.Paste")
			(net "P12V_NIC6_CO_TIMER")
		)
		(pad "5" smd rect
			(at -1.400048 0 180)
			(size 0.254 0.8128)
			(layers "F.Cu" "F.Mask" "F.Paste")
			(net "P12V_NIC6_CO_ISET")
		)
		(pad "6" smd rect
			(at -1.400048 0.499872 180)
			(size 0.254 0.8128)
			(layers "F.Cu" "F.Mask" "F.Paste")
			(net "P12V_NIC6_CO_SS")
		)
		(pad "7" smd rect
			(at -1.400048 0.999998 180)
			(size 0.254 0.8128)
			(layers "F.Cu" "F.Mask" "F.Paste")
			(net "GND")
		)
		(pad "8" smd rect
			(at -1.400048 1.500124 180)
			(size 0.254 0.8128)
			(layers "F.Cu" "F.Mask" "F.Paste")
			(net "P12V_NIC6_CO_IMON_VR")
		)
		(pad "9" smd rect
			(at -1.400048 1.999996 180)
			(size 0.254 0.8128)
			(layers "F.Cu" "F.Mask" "F.Paste")
			(net "P12V_NIC6_CO_FLTB")
		)
		(pad "10" smd rect
			(at -0.499872 2.400046 270)
			(size 0.254 0.8128)
			(layers "F.Cu" "F.Mask" "F.Paste")
			(net "PWRGD_P12V_NIC6_CO")
		)
		(pad "11" smd rect
			(at 0.499872 2.400046 270)
			(size 0.254 0.8128)
			(layers "F.Cu" "F.Mask" "F.Paste")
			(net "P12V_NIC6_CO_OV_FB")
		)
		(pad "12" smd rect
			(at 1.400048 1.999996 180)
			(size 0.254 0.8128)
			(layers "F.Cu" "F.Mask" "F.Paste")
			(net "P12V_NIC6_CO_AVIN_PD")
		)
		(pad "13" smd rect
			(at 1.400048 1.500124 180)
			(size 0.254 0.8128)
			(layers "F.Cu" "F.Mask" "F.Paste")
			(net "P12V_NIC6_R")
		)
		(pad "14" smd rect
			(at 1.400048 0.999998 180)
			(size 0.254 0.8128)
			(layers "F.Cu" "F.Mask" "F.Paste")
			(net "P12V_NIC6_R")
		)
		(pad "15" smd rect
			(at 1.400048 0.499872 180)
			(size 0.254 0.8128)
			(layers "F.Cu" "F.Mask" "F.Paste")
			(net "P12V_NIC6_R")
		)
		(pad "16" smd rect
			(at 1.400048 0 180)
			(size 0.254 0.8128)
			(layers "F.Cu" "F.Mask" "F.Paste")
			(net "P12V_NIC6_R")
		)
		(pad "17" smd rect
			(at 1.400048 -0.499872 180)
			(size 0.254 0.8128)
			(layers "F.Cu" "F.Mask" "F.Paste")
			(net "P12V_NIC6_R")
		)
		(pad "18" smd rect
			(at 1.400048 -0.999998 180)
			(size 0.254 0.8128)
			(layers "F.Cu" "F.Mask" "F.Paste")
			(net "P12V_NIC6_R")
		)
		(pad "19" smd rect
			(at 1.400048 -1.500124 180)
			(size 0.254 0.8128)
			(layers "F.Cu" "F.Mask" "F.Paste")
			(net "P12V_NIC6_R")
		)
		(pad "20" smd rect
			(at 1.400048 -1.999996 180)
			(size 0.254 0.8128)
			(layers "F.Cu" "F.Mask" "F.Paste")
			(net "P12V_NIC6_R")
		)
		(pad "21_22" smd circle
			(at 0.499872 -2.337562 180)
			(size 0 0)
			(layers "F.Cu" "F.Mask" "F.Paste")
			(net "P12V_AUX")
		)
		(pad "23" smd rect
			(at 0 -1.100074 180)
			(size 0.254 1.27)
			(layers "F.Cu" "F.Mask" "F.Paste")
			(net "P12V_AUX")
		)
		(pad "24" smd rect
			(at 0 -0.199898 180)
			(size 0.254 1.27)
			(layers "F.Cu" "F.Mask" "F.Paste")
			(net "P12V_AUX")
		)
		(pad "25" smd rect
			(at 0 0.700024 180)
			(size 0.254 1.27)
			(layers "F.Cu" "F.Mask" "F.Paste")
			(net "P12V_AUX")
		)
		(pad "26" smd rect
			(at 0 1.599946 180)
			(size 0.254 1.27)
			(layers "F.Cu" "F.Mask" "F.Paste")
			(net "P12V_AUX")
		)
	)
	(footprint ""
		(layer "F.Cu")
		(at 227.008944 -98.36912 -90)
		(property "Reference" "C2859"
			(at 0 0 270)
			(layer "F.SilkS")
			(hide yes)
			(effects
				(font
					(size 1.27 1.27)
				)
			)
		)
		(property "Value" ""
			(at 0 0 270)
			(layer "F.Fab")
			(effects
				(font
					(size 1.27 1.27)
				)
			)
		)
		(duplicate_pad_numbers_are_jumpers no)
		(fp_line
			(start -0.7874 0.4064)
			(end -0.7874 -0.4064)
			(stroke
				(width 0.1524)
				(type default)
			)
			(layer "F.SilkS")
		)
		(fp_line
			(start 0.7874 0.4064)
			(end -0.7874 0.4064)
			(stroke
				(width 0.1524)
				(type default)
			)
			(layer "F.SilkS")
		)
		(fp_line
			(start -0.7874 -0.4064)
			(end 0.7874 -0.4064)
			(stroke
				(width 0.1524)
				(type default)
			)
			(layer "F.SilkS")
		)
		(fp_line
			(start 0.7874 -0.4064)
			(end 0.7874 0.4064)
			(stroke
				(width 0.1524)
				(type default)
			)
			(layer "F.SilkS")
		)
		(fp_line
			(start -0.67945 0.3048)
			(end -0.67945 -0.305054)
			(stroke
				(width 0.1)
				(type default)
			)
			(layer "F.Fab")
		)
		(fp_line
			(start -0.12065 0.3048)
			(end -0.67945 0.3048)
			(stroke
				(width 0.1)
				(type default)
			)
			(layer "F.Fab")
		)
		(fp_line
			(start 0.120396 0.3048)
			(end 0.120396 0.2794)
			(stroke
				(width 0.1)
				(type default)
			)
			(layer "F.Fab")
		)
		(fp_line
			(start 0.67945 0.3048)
			(end 0.120396 0.3048)
			(stroke
				(width 0.1)
				(type default)
			)
			(layer "F.Fab")
		)
		(fp_line
			(start -0.12065 0.2794)
			(end -0.12065 0.3048)
			(stroke
				(width 0.1)
				(type default)
			)
			(layer "F.Fab")
		)
		(fp_line
			(start 0.120396 0.2794)
			(end -0.12065 0.2794)
			(stroke
				(width 0.1)
				(type default)
			)
			(layer "F.Fab")
		)
		(fp_line
			(start -0.12065 -0.2794)
			(end 0.12065 -0.2794)
			(stroke
				(width 0.1)
				(type default)
			)
			(layer "F.Fab")
		)
		(fp_line
			(start 0.12065 -0.2794)
			(end 0.12065 -0.3048)
			(stroke
				(width 0.1)
				(type default)
			)
			(layer "F.Fab")
		)
		(fp_line
			(start 0.12065 -0.3048)
			(end 0.67945 -0.3048)
			(stroke
				(width 0.1)
				(type default)
			)
			(layer "F.Fab")
		)
		(fp_line
			(start 0.67945 -0.3048)
			(end 0.67945 0.3048)
			(stroke
				(width 0.1)
				(type default)
			)
			(layer "F.Fab")
		)
		(fp_line
			(start -0.67945 -0.305054)
			(end -0.12065 -0.305054)
			(stroke
				(width 0.1)
				(type default)
			)
			(layer "F.Fab")
		)
		(fp_line
			(start -0.12065 -0.305054)
			(end -0.12065 -0.2794)
			(stroke
				(width 0.1)
				(type default)
			)
			(layer "F.Fab")
		)
		(pad "1" smd circle
			(at -0.40005 0 270)
			(size 0 0)
			(layers "F.Cu" "F.Mask" "F.Paste")
			(net "P12V_NIC3_EN_R")
		)
		(pad "2" smd circle
			(at 0.40005 0 270)
			(size 0 0)
			(layers "F.Cu" "F.Mask" "F.Paste")
			(net "GND")
		)
	)
	(footprint ""
		(layer "F.Cu")
		(at 330.63434 -33.631886 180)
		(property "Reference" "C512"
			(at 0 0 180)
			(layer "F.SilkS")
			(hide yes)
			(effects
				(font
					(size 1.27 1.27)
				)
			)
		)
		(property "Value" ""
			(at 0 0 180)
			(layer "F.Fab")
			(effects
				(font
					(size 1.27 1.27)
				)
			)
		)
		(duplicate_pad_numbers_are_jumpers no)
		(fp_line
			(start 0.299974 0.150114)
			(end -0.299974 0.150114)
			(stroke
				(width 0.1)
				(type default)
			)
			(layer "F.Fab")
		)
		(fp_line
			(start 0.299974 -0.150114)
			(end 0.299974 0.150114)
			(stroke
				(width 0.1)
				(type default)
			)
			(layer "F.Fab")
		)
		(fp_line
			(start -0.299974 0.150114)
			(end -0.299974 -0.150114)
			(stroke
				(width 0.1)
				(type default)
			)
			(layer "F.Fab")
		)
		(fp_line
			(start -0.299974 -0.150114)
			(end 0.299974 -0.150114)
			(stroke
				(width 0.1)
				(type default)
			)
			(layer "F.Fab")
		)
		(pad "1" smd rect
			(at -0.2667 0 180)
			(size 0.3048 0.381)
			(layers "F.Cu" "F.Mask" "F.Paste")
			(net "P5E_PEX2_STN2_TX_DN<35>")
		)
		(pad "2" smd rect
			(at 0.2667 0 180)
			(size 0.3048 0.381)
			(layers "F.Cu" "F.Mask" "F.Paste")
			(net "P5E_PEX2_STN2_TX_C_DN<35>")
		)
	)
	(footprint ""
		(layer "F.Cu")
		(at 352.232214 -156.337)
		(property "Reference" "R4822"
			(at 0 0 0)
			(layer "F.SilkS")
			(hide yes)
			(effects
				(font
					(size 1.27 1.27)
				)
			)
		)
		(property "Value" ""
			(at 0 0 0)
			(layer "F.Fab")
			(effects
				(font
					(size 1.27 1.27)
				)
			)
		)
		(duplicate_pad_numbers_are_jumpers no)
		(fp_line
			(start -0.7874 -0.4064)
			(end 0.7874 -0.4064)
			(stroke
				(width 0.1524)
				(type default)
			)
			(layer "F.SilkS")
		)
		(fp_line
			(start -0.7874 0.4064)
			(end -0.7874 -0.4064)
			(stroke
				(width 0.1524)
				(type default)
			)
			(layer "F.SilkS")
		)
		(fp_line
			(start 0.7874 -0.4064)
			(end 0.7874 0.4064)
			(stroke
				(width 0.1524)
				(type default)
			)
			(layer "F.SilkS")
		)
		(fp_line
			(start 0.7874 0.4064)
			(end -0.7874 0.4064)
			(stroke
				(width 0.1524)
				(type default)
			)
			(layer "F.SilkS")
		)
		(fp_line
			(start -0.67945 -0.305054)
			(end -0.12065 -0.305054)
			(stroke
				(width 0.1)
				(type default)
			)
			(layer "F.Fab")
		)
		(fp_line
			(start -0.67945 0.3048)
			(end -0.67945 -0.305054)
			(stroke
				(width 0.1)
				(type default)
			)
			(layer "F.Fab")
		)
		(fp_line
			(start -0.12065 -0.305054)
			(end -0.12065 -0.2794)
			(stroke
				(width 0.1)
				(type default)
			)
			(layer "F.Fab")
		)
		(fp_line
			(start -0.12065 -0.2794)
			(end 0.12065 -0.2794)
			(stroke
				(width 0.1)
				(type default)
			)
			(layer "F.Fab")
		)
		(fp_line
			(start -0.12065 0.2794)
			(end -0.12065 0.3048)
			(stroke
				(width 0.1)
				(type default)
			)
			(layer "F.Fab")
		)
		(fp_line
			(start -0.12065 0.3048)
			(end -0.67945 0.3048)
			(stroke
				(width 0.1)
				(type default)
			)
			(layer "F.Fab")
		)
		(fp_line
			(start 0.120396 0.2794)
			(end -0.12065 0.2794)
			(stroke
				(width 0.1)
				(type default)
			)
			(layer "F.Fab")
		)
		(fp_line
			(start 0.120396 0.3048)
			(end 0.120396 0.2794)
			(stroke
				(width 0.1)
				(type default)
			)
			(layer "F.Fab")
		)
		(fp_line
			(start 0.12065 -0.3048)
			(end 0.67945 -0.3048)
			(stroke
				(width 0.1)
				(type default)
			)
			(layer "F.Fab")
		)
		(fp_line
			(start 0.12065 -0.2794)
			(end 0.12065 -0.3048)
			(stroke
				(width 0.1)
				(type default)
			)
			(layer "F.Fab")
		)
		(fp_line
			(start 0.67945 -0.3048)
			(end 0.67945 0.3048)
			(stroke
				(width 0.1)
				(type default)
			)
			(layer "F.Fab")
		)
		(fp_line
			(start 0.67945 0.3048)
			(end 0.120396 0.3048)
			(stroke
				(width 0.1)
				(type default)
			)
			(layer "F.Fab")
		)
		(pad "1" smd circle
			(at -0.40005 0)
			(size 0 0)
			(layers "F.Cu" "F.Mask" "F.Paste")
			(net "RST_PEX_NIC6_PERST_N")
		)
		(pad "2" smd circle
			(at 0.40005 0)
			(size 0 0)
			(layers "F.Cu" "F.Mask" "F.Paste")
			(net "RST_PEX_NIC6_PERST_R_N")
		)
	)
	(footprint ""
		(layer "F.Cu")
		(at 243.271802 -181.85892 -90)
		(property "Reference" "U325"
			(at 1.333246 -2.302002 90)
			(unlocked yes)
			(layer "F.SilkS")
			(effects
				(font
					(size 0.7874 0.5842)
					(thickness 0.1524)
				)
				(justify left)
			)
		)
		(property "Value" ""
			(at 0 0 270)
			(layer "F.Fab")
			(effects
				(font
					(size 1.27 1.27)
				)
			)
		)
		(duplicate_pad_numbers_are_jumpers no)
		(fp_line
			(start -2.0574 1.651)
			(end -2.0574 -1.651)
			(stroke
				(width 0.1524)
				(type default)
			)
			(layer "F.SilkS")
		)
		(fp_line
			(start 2.0574 1.651)
			(end -2.0574 1.651)
			(stroke
				(width 0.1524)
				(type default)
			)
			(layer "F.SilkS")
		)
		(fp_line
			(start 0 -1.016)
			(end 0.381 -1.651)
			(stroke
				(width 0.1524)
				(type default)
			)
			(layer "F.SilkS")
		)
		(fp_line
			(start -2.0574 -1.651)
			(end -0.381 -1.651)
			(stroke
				(width 0.1524)
				(type default)
			)
			(layer "F.SilkS")
		)
		(fp_line
			(start -0.381 -1.651)
			(end 0 -1.016)
			(stroke
				(width 0.1524)
				(type default)
			)
			(layer "F.SilkS")
		)
		(fp_line
			(start 0.381 -1.651)
			(end 2.0574 -1.651)
			(stroke
				(width 0.1524)
				(type default)
			)
			(layer "F.SilkS")
		)
		(fp_line
			(start 2.0574 -1.651)
			(end 2.0574 1.651)
			(stroke
				(width 0.1524)
				(type default)
			)
			(layer "F.SilkS")
		)
		(fp_poly
			(pts
				(xy -2.71272 -0.719328) (xy -2.71272 -1.344168) (xy -2.159 -1.016)
			)
			(stroke
				(width 0)
				(type default)
			)
			(fill yes)
			(layer "F.SilkS")
		)
		(fp_line
			(start -0.899922 1.549908)
			(end -0.899922 1.199896)
			(stroke
				(width 0.1)
				(type default)
			)
			(layer "F.Fab")
		)
		(fp_line
			(start 0.899922 1.549908)
			(end -0.899922 1.549908)
			(stroke
				(width 0.1)
				(type default)
			)
			(layer "F.Fab")
		)
		(fp_line
			(start -1.599946 1.199896)
			(end -1.599946 -1.199896)
			(stroke
				(width 0.1)
				(type default)
			)
			(layer "F.Fab")
		)
		(fp_line
			(start -0.899922 1.199896)
			(end -1.599946 1.199896)
			(stroke
				(width 0.1)
				(type default)
			)
			(layer "F.Fab")
		)
		(fp_line
			(start 0.899922 1.199896)
			(end 0.899922 1.549908)
			(stroke
				(width 0.1)
				(type default)
			)
			(layer "F.Fab")
		)
		(fp_line
			(start 1.599946 1.199896)
			(end 0.899922 1.199896)
			(stroke
				(width 0.1)
				(type default)
			)
			(layer "F.Fab")
		)
		(fp_line
			(start -1.599946 -1.199896)
			(end -0.899922 -1.199896)
			(stroke
				(width 0.1)
				(type default)
			)
			(layer "F.Fab")
		)
		(fp_line
			(start -0.899922 -1.199896)
			(end -0.899922 -1.549908)
			(stroke
				(width 0.1)
				(type default)
			)
			(layer "F.Fab")
		)
		(fp_line
			(start 0.899922 -1.199896)
			(end 1.599946 -1.199896)
			(stroke
				(width 0.1)
				(type default)
			)
			(layer "F.Fab")
		)
		(fp_line
			(start 1.599946 -1.199896)
			(end 1.599946 1.199896)
			(stroke
				(width 0.1)
				(type default)
			)
			(layer "F.Fab")
		)
		(fp_line
			(start -0.899922 -1.549908)
			(end 0.899922 -1.549908)
			(stroke
				(width 0.1)
				(type default)
			)
			(layer "F.Fab")
		)
		(fp_line
			(start 0.899922 -1.549908)
			(end 0.899922 -1.199896)
			(stroke
				(width 0.1)
				(type default)
			)
			(layer "F.Fab")
		)
		(fp_poly
			(pts
				(xy -2.71272 -0.719328) (xy -2.71272 -1.344168) (xy -2.159 -1.016)
			)
			(stroke
				(width 0)
				(type default)
			)
			(fill yes)
			(layer "F.Fab")
		)
		(pad "1" smd rect
			(at -1.225042 -0.94996 180)
			(size 0.5588 1.3462)
			(layers "F.Cu" "F.Mask" "F.Paste")
			(net "PWRGD_P1V2_AUX_RST")
		)
		(pad "2" smd rect
			(at -1.225042 0 180)
			(size 0.5588 1.3462)
			(layers "F.Cu" "F.Mask" "F.Paste")
			(net "BIC_RST_RSMRST_R_N")
		)
		(pad "3" smd rect
			(at -1.225042 0.94996 180)
			(size 0.5588 1.3462)
			(layers "F.Cu" "F.Mask" "F.Paste")
			(net "GND")
		)
		(pad "4" smd rect
			(at 1.225042 0.94996 180)
			(size 0.5588 1.3462)
			(layers "F.Cu" "F.Mask" "F.Paste")
			(net "BIC_RST_PWRGD_RSMRST_R")
		)
		(pad "5" smd rect
			(at 1.225042 -0.94996 180)
			(size 0.5588 1.3462)
			(layers "F.Cu" "F.Mask" "F.Paste")
			(net "P3V3_AUX")
		)
	)
	(footprint ""
		(layer "F.Cu")
		(at 429.302672 -89.1159)
		(property "Reference" "C963"
			(at 0 0 0)
			(layer "F.SilkS")
			(hide yes)
			(effects
				(font
					(size 1.27 1.27)
				)
			)
		)
		(property "Value" ""
			(at 0 0 0)
			(layer "F.Fab")
			(effects
				(font
					(size 1.27 1.27)
				)
			)
		)
		(duplicate_pad_numbers_are_jumpers no)
		(fp_line
			(start -0.7874 -0.4064)
			(end 0.7874 -0.4064)
			(stroke
				(width 0.1524)
				(type default)
			)
			(layer "F.SilkS")
		)
		(fp_line
			(start -0.7874 0.4064)
			(end -0.7874 -0.4064)
			(stroke
				(width 0.1524)
				(type default)
			)
			(layer "F.SilkS")
		)
		(fp_line
			(start 0.7874 -0.4064)
			(end 0.7874 0.4064)
			(stroke
				(width 0.1524)
				(type default)
			)
			(layer "F.SilkS")
		)
		(fp_line
			(start 0.7874 0.4064)
			(end -0.7874 0.4064)
			(stroke
				(width 0.1524)
				(type default)
			)
			(layer "F.SilkS")
		)
		(fp_line
			(start -0.67945 -0.305054)
			(end -0.12065 -0.305054)
			(stroke
				(width 0.1)
				(type default)
			)
			(layer "F.Fab")
		)
		(fp_line
			(start -0.67945 0.3048)
			(end -0.67945 -0.305054)
			(stroke
				(width 0.1)
				(type default)
			)
			(layer "F.Fab")
		)
		(fp_line
			(start -0.12065 -0.305054)
			(end -0.12065 -0.2794)
			(stroke
				(width 0.1)
				(type default)
			)
			(layer "F.Fab")
		)
		(fp_line
			(start -0.12065 -0.2794)
			(end 0.12065 -0.2794)
			(stroke
				(width 0.1)
				(type default)
			)
			(layer "F.Fab")
		)
		(fp_line
			(start -0.12065 0.2794)
			(end -0.12065 0.3048)
			(stroke
				(width 0.1)
				(type default)
			)
			(layer "F.Fab")
		)
		(fp_line
			(start -0.12065 0.3048)
			(end -0.67945 0.3048)
			(stroke
				(width 0.1)
				(type default)
			)
			(layer "F.Fab")
		)
		(fp_line
			(start 0.120396 0.2794)
			(end -0.12065 0.2794)
			(stroke
				(width 0.1)
				(type default)
			)
			(layer "F.Fab")
		)
		(fp_line
			(start 0.120396 0.3048)
			(end 0.120396 0.2794)
			(stroke
				(width 0.1)
				(type default)
			)
			(layer "F.Fab")
		)
		(fp_line
			(start 0.12065 -0.3048)
			(end 0.67945 -0.3048)
			(stroke
				(width 0.1)
				(type default)
			)
			(layer "F.Fab")
		)
		(fp_line
			(start 0.12065 -0.2794)
			(end 0.12065 -0.3048)
			(stroke
				(width 0.1)
				(type default)
			)
			(layer "F.Fab")
		)
		(fp_line
			(start 0.67945 -0.3048)
			(end 0.67945 0.3048)
			(stroke
				(width 0.1)
				(type default)
			)
			(layer "F.Fab")
		)
		(fp_line
			(start 0.67945 0.3048)
			(end 0.120396 0.3048)
			(stroke
				(width 0.1)
				(type default)
			)
			(layer "F.Fab")
		)
		(pad "1" smd circle
			(at -0.40005 0)
			(size 0 0)
			(layers "F.Cu" "F.Mask" "F.Paste")
			(net "P3V3_AUX")
		)
		(pad "2" smd circle
			(at 0.40005 0)
			(size 0 0)
			(layers "F.Cu" "F.Mask" "F.Paste")
			(net "GND")
		)
	)
	(footprint ""
		(layer "F.Cu")
		(at 220.34373 -48.93691 180)
		(property "Reference" "R589"
			(at 0 0 180)
			(layer "F.SilkS")
			(hide yes)
			(effects
				(font
					(size 1.27 1.27)
				)
			)
		)
		(property "Value" ""
			(at 0 0 180)
			(layer "F.Fab")
			(effects
				(font
					(size 1.27 1.27)
				)
			)
		)
		(duplicate_pad_numbers_are_jumpers no)
		(fp_line
			(start 0.7874 0.4064)
			(end -0.7874 0.4064)
			(stroke
				(width 0.1524)
				(type default)
			)
			(layer "F.SilkS")
		)
		(fp_line
			(start 0.7874 -0.4064)
			(end 0.7874 0.4064)
			(stroke
				(width 0.1524)
				(type default)
			)
			(layer "F.SilkS")
		)
		(fp_line
			(start -0.7874 0.4064)
			(end -0.7874 -0.4064)
			(stroke
				(width 0.1524)
				(type default)
			)
			(layer "F.SilkS")
		)
		(fp_line
			(start -0.7874 -0.4064)
			(end 0.7874 -0.4064)
			(stroke
				(width 0.1524)
				(type default)
			)
			(layer "F.SilkS")
		)
		(fp_line
			(start 0.67945 0.3048)
			(end 0.120396 0.3048)
			(stroke
				(width 0.1)
				(type default)
			)
			(layer "F.Fab")
		)
		(fp_line
			(start 0.67945 -0.3048)
			(end 0.67945 0.3048)
			(stroke
				(width 0.1)
				(type default)
			)
			(layer "F.Fab")
		)
		(fp_line
			(start 0.12065 -0.2794)
			(end 0.12065 -0.3048)
			(stroke
				(width 0.1)
				(type default)
			)
			(layer "F.Fab")
		)
		(fp_line
			(start 0.12065 -0.3048)
			(end 0.67945 -0.3048)
			(stroke
				(width 0.1)
				(type default)
			)
			(layer "F.Fab")
		)
		(fp_line
			(start 0.120396 0.3048)
			(end 0.120396 0.2794)
			(stroke
				(width 0.1)
				(type default)
			)
			(layer "F.Fab")
		)
		(fp_line
			(start 0.120396 0.2794)
			(end -0.12065 0.2794)
			(stroke
				(width 0.1)
				(type default)
			)
			(layer "F.Fab")
		)
		(fp_line
			(start -0.12065 0.3048)
			(end -0.67945 0.3048)
			(stroke
				(width 0.1)
				(type default)
			)
			(layer "F.Fab")
		)
		(fp_line
			(start -0.12065 0.2794)
			(end -0.12065 0.3048)
			(stroke
				(width 0.1)
				(type default)
			)
			(layer "F.Fab")
		)
		(fp_line
			(start -0.12065 -0.2794)
			(end 0.12065 -0.2794)
			(stroke
				(width 0.1)
				(type default)
			)
			(layer "F.Fab")
		)
		(fp_line
			(start -0.12065 -0.305054)
			(end -0.12065 -0.2794)
			(stroke
				(width 0.1)
				(type default)
			)
			(layer "F.Fab")
		)
		(fp_line
			(start -0.67945 0.3048)
			(end -0.67945 -0.305054)
			(stroke
				(width 0.1)
				(type default)
			)
			(layer "F.Fab")
		)
		(fp_line
			(start -0.67945 -0.305054)
			(end -0.12065 -0.305054)
			(stroke
				(width 0.1)
				(type default)
			)
			(layer "F.Fab")
		)
		(pad "1" smd circle
			(at -0.40005 0 180)
			(size 0 0)
			(layers "F.Cu" "F.Mask" "F.Paste")
			(net "SMB_BIC_I2C6_MUX_SSD_0_7_ADC_R_SDA")
		)
		(pad "2" smd circle
			(at 0.40005 0 180)
			(size 0 0)
			(layers "F.Cu" "F.Mask" "F.Paste")
			(net "SMB_SSD7_ADC_SDA")
		)
	)
	(footprint ""
		(layer "F.Cu")
		(at 3.228086 -43.637708 90)
		(property "Reference" "PC675"
			(at 0 0 90)
			(layer "F.SilkS")
			(hide yes)
			(effects
				(font
					(size 1.27 1.27)
				)
			)
		)
		(property "Value" ""
			(at 0 0 90)
			(layer "F.Fab")
			(effects
				(font
					(size 1.27 1.27)
				)
			)
		)
		(duplicate_pad_numbers_are_jumpers no)
		(fp_line
			(start 0.7874 -0.4064)
			(end 0.7874 0.4064)
			(stroke
				(width 0.1524)
				(type default)
			)
			(layer "F.SilkS")
		)
		(fp_line
			(start -0.7874 -0.4064)
			(end 0.7874 -0.4064)
			(stroke
				(width 0.1524)
				(type default)
			)
			(layer "F.SilkS")
		)
		(fp_line
			(start 0.7874 0.4064)
			(end -0.7874 0.4064)
			(stroke
				(width 0.1524)
				(type default)
			)
			(layer "F.SilkS")
		)
		(fp_line
			(start -0.7874 0.4064)
			(end -0.7874 -0.4064)
			(stroke
				(width 0.1524)
				(type default)
			)
			(layer "F.SilkS")
		)
		(fp_line
			(start -0.12065 -0.305054)
			(end -0.12065 -0.2794)
			(stroke
				(width 0.1)
				(type default)
			)
			(layer "F.Fab")
		)
		(fp_line
			(start -0.67945 -0.305054)
			(end -0.12065 -0.305054)
			(stroke
				(width 0.1)
				(type default)
			)
			(layer "F.Fab")
		)
		(fp_line
			(start 0.67945 -0.3048)
			(end 0.67945 0.3048)
			(stroke
				(width 0.1)
				(type default)
			)
			(layer "F.Fab")
		)
		(fp_line
			(start 0.12065 -0.3048)
			(end 0.67945 -0.3048)
			(stroke
				(width 0.1)
				(type default)
			)
			(layer "F.Fab")
		)
		(fp_line
			(start 0.12065 -0.2794)
			(end 0.12065 -0.3048)
			(stroke
				(width 0.1)
				(type default)
			)
			(layer "F.Fab")
		)
		(fp_line
			(start -0.12065 -0.2794)
			(end 0.12065 -0.2794)
			(stroke
				(width 0.1)
				(type default)
			)
			(layer "F.Fab")
		)
		(fp_line
			(start 0.120396 0.2794)
			(end -0.12065 0.2794)
			(stroke
				(width 0.1)
				(type default)
			)
			(layer "F.Fab")
		)
		(fp_line
			(start -0.12065 0.2794)
			(end -0.12065 0.3048)
			(stroke
				(width 0.1)
				(type default)
			)
			(layer "F.Fab")
		)
		(fp_line
			(start 0.67945 0.3048)
			(end 0.120396 0.3048)
			(stroke
				(width 0.1)
				(type default)
			)
			(layer "F.Fab")
		)
		(fp_line
			(start 0.120396 0.3048)
			(end 0.120396 0.2794)
			(stroke
				(width 0.1)
				(type default)
			)
			(layer "F.Fab")
		)
		(fp_line
			(start -0.12065 0.3048)
			(end -0.67945 0.3048)
			(stroke
				(width 0.1)
				(type default)
			)
			(layer "F.Fab")
		)
		(fp_line
			(start -0.67945 0.3048)
			(end -0.67945 -0.305054)
			(stroke
				(width 0.1)
				(type default)
			)
			(layer "F.Fab")
		)
		(pad "1" smd circle
			(at -0.40005 0 90)
			(size 0 0)
			(layers "F.Cu" "F.Mask" "F.Paste")
			(net "P3V3_SSD0_CO_DV_DT")
		)
		(pad "2" smd circle
			(at 0.40005 0 90)
			(size 0 0)
			(layers "F.Cu" "F.Mask" "F.Paste")
			(net "GND")
		)
	)
	(footprint ""
		(layer "F.Cu")
		(at 86.72957 -300.62043 90)
		(property "Reference" "R6386"
			(at 0 0 90)
			(layer "F.SilkS")
			(hide yes)
			(effects
				(font
					(size 1.27 1.27)
				)
			)
		)
		(property "Value" ""
			(at 0 0 90)
			(layer "F.Fab")
			(effects
				(font
					(size 1.27 1.27)
				)
			)
		)
		(duplicate_pad_numbers_are_jumpers no)
		(fp_line
			(start 0.7874 -0.4064)
			(end 0.7874 0.4064)
			(stroke
				(width 0.1524)
				(type default)
			)
			(layer "F.SilkS")
		)
		(fp_line
			(start -0.7874 -0.4064)
			(end 0.7874 -0.4064)
			(stroke
				(width 0.1524)
				(type default)
			)
			(layer "F.SilkS")
		)
		(fp_line
			(start 0.7874 0.4064)
			(end -0.7874 0.4064)
			(stroke
				(width 0.1524)
				(type default)
			)
			(layer "F.SilkS")
		)
		(fp_line
			(start -0.7874 0.4064)
			(end -0.7874 -0.4064)
			(stroke
				(width 0.1524)
				(type default)
			)
			(layer "F.SilkS")
		)
		(fp_line
			(start -0.12065 -0.305054)
			(end -0.12065 -0.2794)
			(stroke
				(width 0.1)
				(type default)
			)
			(layer "F.Fab")
		)
		(fp_line
			(start -0.67945 -0.305054)
			(end -0.12065 -0.305054)
			(stroke
				(width 0.1)
				(type default)
			)
			(layer "F.Fab")
		)
		(fp_line
			(start 0.67945 -0.3048)
			(end 0.67945 0.3048)
			(stroke
				(width 0.1)
				(type default)
			)
			(layer "F.Fab")
		)
		(fp_line
			(start 0.12065 -0.3048)
			(end 0.67945 -0.3048)
			(stroke
				(width 0.1)
				(type default)
			)
			(layer "F.Fab")
		)
		(fp_line
			(start 0.12065 -0.2794)
			(end 0.12065 -0.3048)
			(stroke
				(width 0.1)
				(type default)
			)
			(layer "F.Fab")
		)
		(fp_line
			(start -0.12065 -0.2794)
			(end 0.12065 -0.2794)
			(stroke
				(width 0.1)
				(type default)
			)
			(layer "F.Fab")
		)
		(fp_line
			(start 0.120396 0.2794)
			(end -0.12065 0.2794)
			(stroke
				(width 0.1)
				(type default)
			)
			(layer "F.Fab")
		)
		(fp_line
			(start -0.12065 0.2794)
			(end -0.12065 0.3048)
			(stroke
				(width 0.1)
				(type default)
			)
			(layer "F.Fab")
		)
		(fp_line
			(start 0.67945 0.3048)
			(end 0.120396 0.3048)
			(stroke
				(width 0.1)
				(type default)
			)
			(layer "F.Fab")
		)
		(fp_line
			(start 0.120396 0.3048)
			(end 0.120396 0.2794)
			(stroke
				(width 0.1)
				(type default)
			)
			(layer "F.Fab")
		)
		(fp_line
			(start -0.12065 0.3048)
			(end -0.67945 0.3048)
			(stroke
				(width 0.1)
				(type default)
			)
			(layer "F.Fab")
		)
		(fp_line
			(start -0.67945 0.3048)
			(end -0.67945 -0.305054)
			(stroke
				(width 0.1)
				(type default)
			)
			(layer "F.Fab")
		)
		(pad "1" smd circle
			(at -0.40005 0 90)
			(size 0 0)
			(layers "F.Cu" "F.Mask" "F.Paste")
			(net "RST_PEX0_S3_PERST_N")
		)
		(pad "2" smd circle
			(at 0.40005 0 90)
			(size 0 0)
			(layers "F.Cu" "F.Mask" "F.Paste")
			(net "RST_PEX0_S3_PERST_R_N")
		)
	)
	(footprint ""
		(layer "F.Cu")
		(at 236.706664 -206.51216 90)
		(property "Reference" "R3286"
			(at 0 0 90)
			(layer "F.SilkS")
			(hide yes)
			(effects
				(font
					(size 1.27 1.27)
				)
			)
		)
		(property "Value" ""
			(at 0 0 90)
			(layer "F.Fab")
			(effects
				(font
					(size 1.27 1.27)
				)
			)
		)
		(duplicate_pad_numbers_are_jumpers no)
		(fp_line
			(start 0.7874 -0.4064)
			(end 0.7874 0.4064)
			(stroke
				(width 0.1524)
				(type default)
			)
			(layer "F.SilkS")
		)
		(fp_line
			(start -0.7874 -0.4064)
			(end 0.7874 -0.4064)
			(stroke
				(width 0.1524)
				(type default)
			)
			(layer "F.SilkS")
		)
		(fp_line
			(start 0.7874 0.4064)
			(end -0.7874 0.4064)
			(stroke
				(width 0.1524)
				(type default)
			)
			(layer "F.SilkS")
		)
		(fp_line
			(start -0.7874 0.4064)
			(end -0.7874 -0.4064)
			(stroke
				(width 0.1524)
				(type default)
			)
			(layer "F.SilkS")
		)
		(fp_line
			(start -0.12065 -0.305054)
			(end -0.12065 -0.2794)
			(stroke
				(width 0.1)
				(type default)
			)
			(layer "F.Fab")
		)
		(fp_line
			(start -0.67945 -0.305054)
			(end -0.12065 -0.305054)
			(stroke
				(width 0.1)
				(type default)
			)
			(layer "F.Fab")
		)
		(fp_line
			(start 0.67945 -0.3048)
			(end 0.67945 0.3048)
			(stroke
				(width 0.1)
				(type default)
			)
			(layer "F.Fab")
		)
		(fp_line
			(start 0.12065 -0.3048)
			(end 0.67945 -0.3048)
			(stroke
				(width 0.1)
				(type default)
			)
			(layer "F.Fab")
		)
		(fp_line
			(start 0.12065 -0.2794)
			(end 0.12065 -0.3048)
			(stroke
				(width 0.1)
				(type default)
			)
			(layer "F.Fab")
		)
		(fp_line
			(start -0.12065 -0.2794)
			(end 0.12065 -0.2794)
			(stroke
				(width 0.1)
				(type default)
			)
			(layer "F.Fab")
		)
		(fp_line
			(start 0.120396 0.2794)
			(end -0.12065 0.2794)
			(stroke
				(width 0.1)
				(type default)
			)
			(layer "F.Fab")
		)
		(fp_line
			(start -0.12065 0.2794)
			(end -0.12065 0.3048)
			(stroke
				(width 0.1)
				(type default)
			)
			(layer "F.Fab")
		)
		(fp_line
			(start 0.67945 0.3048)
			(end 0.120396 0.3048)
			(stroke
				(width 0.1)
				(type default)
			)
			(layer "F.Fab")
		)
		(fp_line
			(start 0.120396 0.3048)
			(end 0.120396 0.2794)
			(stroke
				(width 0.1)
				(type default)
			)
			(layer "F.Fab")
		)
		(fp_line
			(start -0.12065 0.3048)
			(end -0.67945 0.3048)
			(stroke
				(width 0.1)
				(type default)
			)
			(layer "F.Fab")
		)
		(fp_line
			(start -0.67945 0.3048)
			(end -0.67945 -0.305054)
			(stroke
				(width 0.1)
				(type default)
			)
			(layer "F.Fab")
		)
		(pad "1" smd circle
			(at -0.40005 0 90)
			(size 0 0)
			(layers "F.Cu" "F.Mask" "F.Paste")
			(net "BIC_HEARTBEAT_N")
		)
		(pad "2" smd circle
			(at 0.40005 0 90)
			(size 0 0)
			(layers "F.Cu" "F.Mask" "F.Paste")
			(net "P3V3_AUX")
		)
	)
	(footprint ""
		(layer "F.Cu")
		(at 268.734286 -252.356874 -90)
		(property "Reference" "R1362"
			(at 0 0 270)
			(layer "F.SilkS")
			(hide yes)
			(effects
				(font
					(size 1.27 1.27)
				)
			)
		)
		(property "Value" ""
			(at 0 0 270)
			(layer "F.Fab")
			(effects
				(font
					(size 1.27 1.27)
				)
			)
		)
		(duplicate_pad_numbers_are_jumpers no)
		(fp_line
			(start -0.7874 0.4064)
			(end -0.7874 -0.4064)
			(stroke
				(width 0.1524)
				(type default)
			)
			(layer "F.SilkS")
		)
		(fp_line
			(start 0.7874 0.4064)
			(end -0.7874 0.4064)
			(stroke
				(width 0.1524)
				(type default)
			)
			(layer "F.SilkS")
		)
		(fp_line
			(start -0.7874 -0.4064)
			(end 0.7874 -0.4064)
			(stroke
				(width 0.1524)
				(type default)
			)
			(layer "F.SilkS")
		)
		(fp_line
			(start 0.7874 -0.4064)
			(end 0.7874 0.4064)
			(stroke
				(width 0.1524)
				(type default)
			)
			(layer "F.SilkS")
		)
		(fp_line
			(start -0.67945 0.3048)
			(end -0.67945 -0.305054)
			(stroke
				(width 0.1)
				(type default)
			)
			(layer "F.Fab")
		)
		(fp_line
			(start -0.12065 0.3048)
			(end -0.67945 0.3048)
			(stroke
				(width 0.1)
				(type default)
			)
			(layer "F.Fab")
		)
		(fp_line
			(start 0.120396 0.3048)
			(end 0.120396 0.2794)
			(stroke
				(width 0.1)
				(type default)
			)
			(layer "F.Fab")
		)
		(fp_line
			(start 0.67945 0.3048)
			(end 0.120396 0.3048)
			(stroke
				(width 0.1)
				(type default)
			)
			(layer "F.Fab")
		)
		(fp_line
			(start -0.12065 0.2794)
			(end -0.12065 0.3048)
			(stroke
				(width 0.1)
				(type default)
			)
			(layer "F.Fab")
		)
		(fp_line
			(start 0.120396 0.2794)
			(end -0.12065 0.2794)
			(stroke
				(width 0.1)
				(type default)
			)
			(layer "F.Fab")
		)
		(fp_line
			(start -0.12065 -0.2794)
			(end 0.12065 -0.2794)
			(stroke
				(width 0.1)
				(type default)
			)
			(layer "F.Fab")
		)
		(fp_line
			(start 0.12065 -0.2794)
			(end 0.12065 -0.3048)
			(stroke
				(width 0.1)
				(type default)
			)
			(layer "F.Fab")
		)
		(fp_line
			(start 0.12065 -0.3048)
			(end 0.67945 -0.3048)
			(stroke
				(width 0.1)
				(type default)
			)
			(layer "F.Fab")
		)
		(fp_line
			(start 0.67945 -0.3048)
			(end 0.67945 0.3048)
			(stroke
				(width 0.1)
				(type default)
			)
			(layer "F.Fab")
		)
		(fp_line
			(start -0.67945 -0.305054)
			(end -0.12065 -0.305054)
			(stroke
				(width 0.1)
				(type default)
			)
			(layer "F.Fab")
		)
		(fp_line
			(start -0.12065 -0.305054)
			(end -0.12065 -0.2794)
			(stroke
				(width 0.1)
				(type default)
			)
			(layer "F.Fab")
		)
		(pad "1" smd circle
			(at -0.40005 0 270)
			(size 0 0)
			(layers "F.Cu" "F.Mask" "F.Paste")
			(net "GND")
		)
		(pad "2" smd circle
			(at 0.40005 0 270)
			(size 0 0)
			(layers "F.Cu" "F.Mask" "F.Paste")
			(net "PEX2_MODE_SEL6")
		)
	)
	(footprint ""
		(layer "F.Cu")
		(at 39.280592 -111.003334)
		(property "Reference" "C52"
			(at 0 0 0)
			(layer "F.SilkS")
			(hide yes)
			(effects
				(font
					(size 1.27 1.27)
				)
			)
		)
		(property "Value" ""
			(at 0 0 0)
			(layer "F.Fab")
			(effects
				(font
					(size 1.27 1.27)
				)
			)
		)
		(duplicate_pad_numbers_are_jumpers no)
		(fp_line
			(start -0.299974 -0.150114)
			(end 0.299974 -0.150114)
			(stroke
				(width 0.1)
				(type default)
			)
			(layer "F.Fab")
		)
		(fp_line
			(start -0.299974 0.150114)
			(end -0.299974 -0.150114)
			(stroke
				(width 0.1)
				(type default)
			)
			(layer "F.Fab")
		)
		(fp_line
			(start 0.299974 -0.150114)
			(end 0.299974 0.150114)
			(stroke
				(width 0.1)
				(type default)
			)
			(layer "F.Fab")
		)
		(fp_line
			(start 0.299974 0.150114)
			(end -0.299974 0.150114)
			(stroke
				(width 0.1)
				(type default)
			)
			(layer "F.Fab")
		)
		(pad "1" smd rect
			(at -0.2667 0)
			(size 0.3048 0.381)
			(layers "F.Cu" "F.Mask" "F.Paste")
			(net "P5E_PEX0_STN1_TX_DN<22>")
		)
		(pad "2" smd rect
			(at 0.2667 0)
			(size 0.3048 0.381)
			(layers "F.Cu" "F.Mask" "F.Paste")
			(net "P5E_PEX0_STN1_TX_C_DN<22>")
		)
	)
	(footprint ""
		(layer "F.Cu")
		(at 204.591158 -78.579472)
		(property "Reference" "R4336"
			(at 0 0 0)
			(layer "F.SilkS")
			(hide yes)
			(effects
				(font
					(size 1.27 1.27)
				)
			)
		)
		(property "Value" ""
			(at 0 0 0)
			(layer "F.Fab")
			(effects
				(font
					(size 1.27 1.27)
				)
			)
		)
		(duplicate_pad_numbers_are_jumpers no)
		(fp_line
			(start -0.7874 -0.4064)
			(end 0.7874 -0.4064)
			(stroke
				(width 0.1524)
				(type default)
			)
			(layer "F.SilkS")
		)
		(fp_line
			(start -0.7874 0.4064)
			(end -0.7874 -0.4064)
			(stroke
				(width 0.1524)
				(type default)
			)
			(layer "F.SilkS")
		)
		(fp_line
			(start 0.7874 -0.4064)
			(end 0.7874 0.4064)
			(stroke
				(width 0.1524)
				(type default)
			)
			(layer "F.SilkS")
		)
		(fp_line
			(start 0.7874 0.4064)
			(end -0.7874 0.4064)
			(stroke
				(width 0.1524)
				(type default)
			)
			(layer "F.SilkS")
		)
		(fp_line
			(start -0.67945 -0.305054)
			(end -0.12065 -0.305054)
			(stroke
				(width 0.1)
				(type default)
			)
			(layer "F.Fab")
		)
		(fp_line
			(start -0.67945 0.3048)
			(end -0.67945 -0.305054)
			(stroke
				(width 0.1)
				(type default)
			)
			(layer "F.Fab")
		)
		(fp_line
			(start -0.12065 -0.305054)
			(end -0.12065 -0.2794)
			(stroke
				(width 0.1)
				(type default)
			)
			(layer "F.Fab")
		)
		(fp_line
			(start -0.12065 -0.2794)
			(end 0.12065 -0.2794)
			(stroke
				(width 0.1)
				(type default)
			)
			(layer "F.Fab")
		)
		(fp_line
			(start -0.12065 0.2794)
			(end -0.12065 0.3048)
			(stroke
				(width 0.1)
				(type default)
			)
			(layer "F.Fab")
		)
		(fp_line
			(start -0.12065 0.3048)
			(end -0.67945 0.3048)
			(stroke
				(width 0.1)
				(type default)
			)
			(layer "F.Fab")
		)
		(fp_line
			(start 0.120396 0.2794)
			(end -0.12065 0.2794)
			(stroke
				(width 0.1)
				(type default)
			)
			(layer "F.Fab")
		)
		(fp_line
			(start 0.120396 0.3048)
			(end 0.120396 0.2794)
			(stroke
				(width 0.1)
				(type default)
			)
			(layer "F.Fab")
		)
		(fp_line
			(start 0.12065 -0.3048)
			(end 0.67945 -0.3048)
			(stroke
				(width 0.1)
				(type default)
			)
			(layer "F.Fab")
		)
		(fp_line
			(start 0.12065 -0.2794)
			(end 0.12065 -0.3048)
			(stroke
				(width 0.1)
				(type default)
			)
			(layer "F.Fab")
		)
		(fp_line
			(start 0.67945 -0.3048)
			(end 0.67945 0.3048)
			(stroke
				(width 0.1)
				(type default)
			)
			(layer "F.Fab")
		)
		(fp_line
			(start 0.67945 0.3048)
			(end 0.120396 0.3048)
			(stroke
				(width 0.1)
				(type default)
			)
			(layer "F.Fab")
		)
		(pad "1" smd circle
			(at -0.40005 0)
			(size 0 0)
			(layers "F.Cu" "F.Mask" "F.Paste")
			(net "P3V3_AUX")
		)
		(pad "2" smd circle
			(at 0.40005 0)
			(size 0 0)
			(layers "F.Cu" "F.Mask" "F.Paste")
			(net "SSD6_LED_R")
		)
	)
	(footprint ""
		(layer "F.Cu")
		(at 245.96471 -162.003994 90)
		(property "Reference" "PC813"
			(at 0 0 90)
			(layer "F.SilkS")
			(hide yes)
			(effects
				(font
					(size 1.27 1.27)
				)
			)
		)
		(property "Value" ""
			(at 0 0 90)
			(layer "F.Fab")
			(effects
				(font
					(size 1.27 1.27)
				)
			)
		)
		(duplicate_pad_numbers_are_jumpers no)
		(fp_line
			(start 0.7874 -0.4064)
			(end 0.7874 0.4064)
			(stroke
				(width 0.1524)
				(type default)
			)
			(layer "F.SilkS")
		)
		(fp_line
			(start -0.7874 -0.4064)
			(end 0.7874 -0.4064)
			(stroke
				(width 0.1524)
				(type default)
			)
			(layer "F.SilkS")
		)
		(fp_line
			(start 0.7874 0.4064)
			(end -0.7874 0.4064)
			(stroke
				(width 0.1524)
				(type default)
			)
			(layer "F.SilkS")
		)
		(fp_line
			(start -0.7874 0.4064)
			(end -0.7874 -0.4064)
			(stroke
				(width 0.1524)
				(type default)
			)
			(layer "F.SilkS")
		)
		(fp_line
			(start -0.12065 -0.305054)
			(end -0.12065 -0.2794)
			(stroke
				(width 0.1)
				(type default)
			)
			(layer "F.Fab")
		)
		(fp_line
			(start -0.67945 -0.305054)
			(end -0.12065 -0.305054)
			(stroke
				(width 0.1)
				(type default)
			)
			(layer "F.Fab")
		)
		(fp_line
			(start 0.67945 -0.3048)
			(end 0.67945 0.3048)
			(stroke
				(width 0.1)
				(type default)
			)
			(layer "F.Fab")
		)
		(fp_line
			(start 0.12065 -0.3048)
			(end 0.67945 -0.3048)
			(stroke
				(width 0.1)
				(type default)
			)
			(layer "F.Fab")
		)
		(fp_line
			(start 0.12065 -0.2794)
			(end 0.12065 -0.3048)
			(stroke
				(width 0.1)
				(type default)
			)
			(layer "F.Fab")
		)
		(fp_line
			(start -0.12065 -0.2794)
			(end 0.12065 -0.2794)
			(stroke
				(width 0.1)
				(type default)
			)
			(layer "F.Fab")
		)
		(fp_line
			(start 0.120396 0.2794)
			(end -0.12065 0.2794)
			(stroke
				(width 0.1)
				(type default)
			)
			(layer "F.Fab")
		)
		(fp_line
			(start -0.12065 0.2794)
			(end -0.12065 0.3048)
			(stroke
				(width 0.1)
				(type default)
			)
			(layer "F.Fab")
		)
		(fp_line
			(start 0.67945 0.3048)
			(end 0.120396 0.3048)
			(stroke
				(width 0.1)
				(type default)
			)
			(layer "F.Fab")
		)
		(fp_line
			(start 0.120396 0.3048)
			(end 0.120396 0.2794)
			(stroke
				(width 0.1)
				(type default)
			)
			(layer "F.Fab")
		)
		(fp_line
			(start -0.12065 0.3048)
			(end -0.67945 0.3048)
			(stroke
				(width 0.1)
				(type default)
			)
			(layer "F.Fab")
		)
		(fp_line
			(start -0.67945 0.3048)
			(end -0.67945 -0.305054)
			(stroke
				(width 0.1)
				(type default)
			)
			(layer "F.Fab")
		)
		(pad "1" smd circle
			(at -0.40005 0 90)
			(size 0 0)
			(layers "F.Cu" "F.Mask" "F.Paste")
			(net "P12V_NIC4_CO_TIMER")
		)
		(pad "2" smd circle
			(at 0.40005 0 90)
			(size 0 0)
			(layers "F.Cu" "F.Mask" "F.Paste")
			(net "GND")
		)
	)
	(footprint ""
		(layer "F.Cu")
		(at 223.498664 -207.02016 90)
		(property "Reference" "R5285"
			(at 0 0 90)
			(layer "F.SilkS")
			(hide yes)
			(effects
				(font
					(size 1.27 1.27)
				)
			)
		)
		(property "Value" ""
			(at 0 0 90)
			(layer "F.Fab")
			(effects
				(font
					(size 1.27 1.27)
				)
			)
		)
		(duplicate_pad_numbers_are_jumpers no)
		(fp_line
			(start 0.7874 -0.4064)
			(end 0.7874 0.4064)
			(stroke
				(width 0.1524)
				(type default)
			)
			(layer "F.SilkS")
		)
		(fp_line
			(start -0.7874 -0.4064)
			(end 0.7874 -0.4064)
			(stroke
				(width 0.1524)
				(type default)
			)
			(layer "F.SilkS")
		)
		(fp_line
			(start 0.7874 0.4064)
			(end -0.7874 0.4064)
			(stroke
				(width 0.1524)
				(type default)
			)
			(layer "F.SilkS")
		)
		(fp_line
			(start -0.7874 0.4064)
			(end -0.7874 -0.4064)
			(stroke
				(width 0.1524)
				(type default)
			)
			(layer "F.SilkS")
		)
		(fp_line
			(start -0.12065 -0.305054)
			(end -0.12065 -0.2794)
			(stroke
				(width 0.1)
				(type default)
			)
			(layer "F.Fab")
		)
		(fp_line
			(start -0.67945 -0.305054)
			(end -0.12065 -0.305054)
			(stroke
				(width 0.1)
				(type default)
			)
			(layer "F.Fab")
		)
		(fp_line
			(start 0.67945 -0.3048)
			(end 0.67945 0.3048)
			(stroke
				(width 0.1)
				(type default)
			)
			(layer "F.Fab")
		)
		(fp_line
			(start 0.12065 -0.3048)
			(end 0.67945 -0.3048)
			(stroke
				(width 0.1)
				(type default)
			)
			(layer "F.Fab")
		)
		(fp_line
			(start 0.12065 -0.2794)
			(end 0.12065 -0.3048)
			(stroke
				(width 0.1)
				(type default)
			)
			(layer "F.Fab")
		)
		(fp_line
			(start -0.12065 -0.2794)
			(end 0.12065 -0.2794)
			(stroke
				(width 0.1)
				(type default)
			)
			(layer "F.Fab")
		)
		(fp_line
			(start 0.120396 0.2794)
			(end -0.12065 0.2794)
			(stroke
				(width 0.1)
				(type default)
			)
			(layer "F.Fab")
		)
		(fp_line
			(start -0.12065 0.2794)
			(end -0.12065 0.3048)
			(stroke
				(width 0.1)
				(type default)
			)
			(layer "F.Fab")
		)
		(fp_line
			(start 0.67945 0.3048)
			(end 0.120396 0.3048)
			(stroke
				(width 0.1)
				(type default)
			)
			(layer "F.Fab")
		)
		(fp_line
			(start 0.120396 0.3048)
			(end 0.120396 0.2794)
			(stroke
				(width 0.1)
				(type default)
			)
			(layer "F.Fab")
		)
		(fp_line
			(start -0.12065 0.3048)
			(end -0.67945 0.3048)
			(stroke
				(width 0.1)
				(type default)
			)
			(layer "F.Fab")
		)
		(fp_line
			(start -0.67945 0.3048)
			(end -0.67945 -0.305054)
			(stroke
				(width 0.1)
				(type default)
			)
			(layer "F.Fab")
		)
		(pad "1" smd circle
			(at -0.40005 0 90)
			(size 0 0)
			(layers "F.Cu" "F.Mask" "F.Paste")
			(net "RST_SMB_SSD_R_N")
		)
		(pad "2" smd circle
			(at 0.40005 0 90)
			(size 0 0)
			(layers "F.Cu" "F.Mask" "F.Paste")
			(net "RST_SMB_SSD_N")
		)
	)
	(footprint ""
		(layer "F.Cu")
		(at 27.838654 -311.156604 -90)
		(property "Reference" "R1093"
			(at 0 0 270)
			(layer "F.SilkS")
			(hide yes)
			(effects
				(font
					(size 1.27 1.27)
				)
			)
		)
		(property "Value" ""
			(at 0 0 270)
			(layer "F.Fab")
			(effects
				(font
					(size 1.27 1.27)
				)
			)
		)
		(duplicate_pad_numbers_are_jumpers no)
		(fp_line
			(start -0.7874 0.4064)
			(end -0.7874 -0.4064)
			(stroke
				(width 0.1524)
				(type default)
			)
			(layer "F.SilkS")
		)
		(fp_line
			(start 0.7874 0.4064)
			(end -0.7874 0.4064)
			(stroke
				(width 0.1524)
				(type default)
			)
			(layer "F.SilkS")
		)
		(fp_line
			(start -0.7874 -0.4064)
			(end 0.7874 -0.4064)
			(stroke
				(width 0.1524)
				(type default)
			)
			(layer "F.SilkS")
		)
		(fp_line
			(start 0.7874 -0.4064)
			(end 0.7874 0.4064)
			(stroke
				(width 0.1524)
				(type default)
			)
			(layer "F.SilkS")
		)
		(fp_line
			(start -0.67945 0.3048)
			(end -0.67945 -0.305054)
			(stroke
				(width 0.1)
				(type default)
			)
			(layer "F.Fab")
		)
		(fp_line
			(start -0.12065 0.3048)
			(end -0.67945 0.3048)
			(stroke
				(width 0.1)
				(type default)
			)
			(layer "F.Fab")
		)
		(fp_line
			(start 0.120396 0.3048)
			(end 0.120396 0.2794)
			(stroke
				(width 0.1)
				(type default)
			)
			(layer "F.Fab")
		)
		(fp_line
			(start 0.67945 0.3048)
			(end 0.120396 0.3048)
			(stroke
				(width 0.1)
				(type default)
			)
			(layer "F.Fab")
		)
		(fp_line
			(start -0.12065 0.2794)
			(end -0.12065 0.3048)
			(stroke
				(width 0.1)
				(type default)
			)
			(layer "F.Fab")
		)
		(fp_line
			(start 0.120396 0.2794)
			(end -0.12065 0.2794)
			(stroke
				(width 0.1)
				(type default)
			)
			(layer "F.Fab")
		)
		(fp_line
			(start -0.12065 -0.2794)
			(end 0.12065 -0.2794)
			(stroke
				(width 0.1)
				(type default)
			)
			(layer "F.Fab")
		)
		(fp_line
			(start 0.12065 -0.2794)
			(end 0.12065 -0.3048)
			(stroke
				(width 0.1)
				(type default)
			)
			(layer "F.Fab")
		)
		(fp_line
			(start 0.12065 -0.3048)
			(end 0.67945 -0.3048)
			(stroke
				(width 0.1)
				(type default)
			)
			(layer "F.Fab")
		)
		(fp_line
			(start 0.67945 -0.3048)
			(end 0.67945 0.3048)
			(stroke
				(width 0.1)
				(type default)
			)
			(layer "F.Fab")
		)
		(fp_line
			(start -0.67945 -0.305054)
			(end -0.12065 -0.305054)
			(stroke
				(width 0.1)
				(type default)
			)
			(layer "F.Fab")
		)
		(fp_line
			(start -0.12065 -0.305054)
			(end -0.12065 -0.2794)
			(stroke
				(width 0.1)
				(type default)
			)
			(layer "F.Fab")
		)
		(pad "1" smd circle
			(at -0.40005 0 270)
			(size 0 0)
			(layers "F.Cu" "F.Mask" "F.Paste")
			(net "PEX0_DBG_SEL1")
		)
		(pad "2" smd circle
			(at 0.40005 0 270)
			(size 0 0)
			(layers "F.Cu" "F.Mask" "F.Paste")
			(net "P1V8_PEX")
		)
	)
	(footprint ""
		(layer "F.Cu")
		(at 358.013 -211.328 180)
		(property "Reference" "R4096"
			(at 0 0 180)
			(layer "F.SilkS")
			(hide yes)
			(effects
				(font
					(size 1.27 1.27)
				)
			)
		)
		(property "Value" ""
			(at 0 0 180)
			(layer "F.Fab")
			(effects
				(font
					(size 1.27 1.27)
				)
			)
		)
		(duplicate_pad_numbers_are_jumpers no)
		(fp_line
			(start 0.7874 0.4064)
			(end -0.7874 0.4064)
			(stroke
				(width 0.1524)
				(type default)
			)
			(layer "F.SilkS")
		)
		(fp_line
			(start 0.7874 -0.4064)
			(end 0.7874 0.4064)
			(stroke
				(width 0.1524)
				(type default)
			)
			(layer "F.SilkS")
		)
		(fp_line
			(start -0.7874 0.4064)
			(end -0.7874 -0.4064)
			(stroke
				(width 0.1524)
				(type default)
			)
			(layer "F.SilkS")
		)
		(fp_line
			(start -0.7874 -0.4064)
			(end 0.7874 -0.4064)
			(stroke
				(width 0.1524)
				(type default)
			)
			(layer "F.SilkS")
		)
		(fp_line
			(start 0.67945 0.3048)
			(end 0.120396 0.3048)
			(stroke
				(width 0.1)
				(type default)
			)
			(layer "F.Fab")
		)
		(fp_line
			(start 0.67945 -0.3048)
			(end 0.67945 0.3048)
			(stroke
				(width 0.1)
				(type default)
			)
			(layer "F.Fab")
		)
		(fp_line
			(start 0.12065 -0.2794)
			(end 0.12065 -0.3048)
			(stroke
				(width 0.1)
				(type default)
			)
			(layer "F.Fab")
		)
		(fp_line
			(start 0.12065 -0.3048)
			(end 0.67945 -0.3048)
			(stroke
				(width 0.1)
				(type default)
			)
			(layer "F.Fab")
		)
		(fp_line
			(start 0.120396 0.3048)
			(end 0.120396 0.2794)
			(stroke
				(width 0.1)
				(type default)
			)
			(layer "F.Fab")
		)
		(fp_line
			(start 0.120396 0.2794)
			(end -0.12065 0.2794)
			(stroke
				(width 0.1)
				(type default)
			)
			(layer "F.Fab")
		)
		(fp_line
			(start -0.12065 0.3048)
			(end -0.67945 0.3048)
			(stroke
				(width 0.1)
				(type default)
			)
			(layer "F.Fab")
		)
		(fp_line
			(start -0.12065 0.2794)
			(end -0.12065 0.3048)
			(stroke
				(width 0.1)
				(type default)
			)
			(layer "F.Fab")
		)
		(fp_line
			(start -0.12065 -0.2794)
			(end 0.12065 -0.2794)
			(stroke
				(width 0.1)
				(type default)
			)
			(layer "F.Fab")
		)
		(fp_line
			(start -0.12065 -0.305054)
			(end -0.12065 -0.2794)
			(stroke
				(width 0.1)
				(type default)
			)
			(layer "F.Fab")
		)
		(fp_line
			(start -0.67945 0.3048)
			(end -0.67945 -0.305054)
			(stroke
				(width 0.1)
				(type default)
			)
			(layer "F.Fab")
		)
		(fp_line
			(start -0.67945 -0.305054)
			(end -0.12065 -0.305054)
			(stroke
				(width 0.1)
				(type default)
			)
			(layer "F.Fab")
		)
		(pad "1" smd circle
			(at -0.40005 0 180)
			(size 0 0)
			(layers "F.Cu" "F.Mask" "F.Paste")
			(net "PRSNT_NIC4_FPGA_R_N")
		)
		(pad "2" smd circle
			(at 0.40005 0 180)
			(size 0 0)
			(layers "F.Cu" "F.Mask" "F.Paste")
			(net "PRSNT_NIC4_FPGA_N")
		)
	)
	(footprint ""
		(layer "F.Cu")
		(at 82.661506 -147.99691 180)
		(property "Reference" "C10"
			(at 0 0 180)
			(layer "F.SilkS")
			(hide yes)
			(effects
				(font
					(size 1.27 1.27)
				)
			)
		)
		(property "Value" ""
			(at 0 0 180)
			(layer "F.Fab")
			(effects
				(font
					(size 1.27 1.27)
				)
			)
		)
		(duplicate_pad_numbers_are_jumpers no)
		(fp_line
			(start 0.299974 0.150114)
			(end -0.299974 0.150114)
			(stroke
				(width 0.1)
				(type default)
			)
			(layer "F.Fab")
		)
		(fp_line
			(start 0.299974 -0.150114)
			(end 0.299974 0.150114)
			(stroke
				(width 0.1)
				(type default)
			)
			(layer "F.Fab")
		)
		(fp_line
			(start -0.299974 0.150114)
			(end -0.299974 -0.150114)
			(stroke
				(width 0.1)
				(type default)
			)
			(layer "F.Fab")
		)
		(fp_line
			(start -0.299974 -0.150114)
			(end 0.299974 -0.150114)
			(stroke
				(width 0.1)
				(type default)
			)
			(layer "F.Fab")
		)
		(pad "1" smd rect
			(at -0.2667 0 180)
			(size 0.3048 0.381)
			(layers "F.Cu" "F.Mask" "F.Paste")
			(net "P5E_PEX0_STN0_TX_DN<11>")
		)
		(pad "2" smd rect
			(at 0.2667 0 180)
			(size 0.3048 0.381)
			(layers "F.Cu" "F.Mask" "F.Paste")
			(net "P5E_PEX0_STN0_TX_C_DN<11>")
		)
	)
	(footprint ""
		(layer "F.Cu")
		(at 365.980726 -258.758182 90)
		(property "Reference" "U379"
			(at -1.8034 -1.819148 90)
			(unlocked yes)
			(layer "F.SilkS")
			(effects
				(font
					(size 0.7874 0.5842)
					(thickness 0.1524)
				)
				(justify left)
			)
		)
		(property "Value" ""
			(at 0 0 90)
			(layer "F.Fab")
			(effects
				(font
					(size 1.27 1.27)
				)
			)
		)
		(duplicate_pad_numbers_are_jumpers no)
		(fp_line
			(start 1.684274 -1.074928)
			(end 1.684274 1.074928)
			(stroke
				(width 0.1524)
				(type default)
			)
			(layer "F.SilkS")
		)
		(fp_line
			(start 0.381 -1.074928)
			(end 1.684274 -1.074928)
			(stroke
				(width 0.1524)
				(type default)
			)
			(layer "F.SilkS")
		)
		(fp_line
			(start -0.381 -1.074928)
			(end 0 -0.625094)
			(stroke
				(width 0.1524)
				(type default)
			)
			(layer "F.SilkS")
		)
		(fp_line
			(start -1.684274 -1.074928)
			(end -0.381 -1.074928)
			(stroke
				(width 0.1524)
				(type default)
			)
			(layer "F.SilkS")
		)
		(fp_line
			(start 0 -0.625094)
			(end 0.381 -1.074928)
			(stroke
				(width 0.1524)
				(type default)
			)
			(layer "F.SilkS")
		)
		(fp_line
			(start 1.684274 1.074928)
			(end -1.684274 1.074928)
			(stroke
				(width 0.1524)
				(type default)
			)
			(layer "F.SilkS")
		)
		(fp_line
			(start -1.684274 1.074928)
			(end -1.684274 -1.074928)
			(stroke
				(width 0.1524)
				(type default)
			)
			(layer "F.SilkS")
		)
		(fp_poly
			(pts
				(xy -2.637282 -0.903986) (xy -2.637282 -0.395986) (xy -1.875282 -0.649986)
			)
			(stroke
				(width 0)
				(type default)
			)
			(fill yes)
			(layer "F.SilkS")
		)
		(fp_line
			(start 0.700024 -1.074928)
			(end -0.700024 -1.074928)
			(stroke
				(width 0.1)
				(type default)
			)
			(layer "F.Fab")
		)
		(fp_line
			(start -0.700024 -1.074928)
			(end -0.700024 1.074928)
			(stroke
				(width 0.1)
				(type default)
			)
			(layer "F.Fab")
		)
		(fp_line
			(start 0.700024 1.074928)
			(end 0.700024 -1.074928)
			(stroke
				(width 0.1)
				(type default)
			)
			(layer "F.Fab")
		)
		(fp_line
			(start -0.700024 1.074928)
			(end 0.700024 1.074928)
			(stroke
				(width 0.1)
				(type default)
			)
			(layer "F.Fab")
		)
		(fp_poly
			(pts
				(xy -2.637282 -0.903986) (xy -2.637282 -0.395986) (xy -1.875282 -0.649986)
			)
			(stroke
				(width 0)
				(type default)
			)
			(fill yes)
			(layer "F.Fab")
		)
		(pad "1" smd rect
			(at -1.100074 -0.649986)
			(size 0.4064 0.9144)
			(layers "F.Cu" "F.Mask" "F.Paste")
			(net "Net_9085")
		)
		(pad "2" smd rect
			(at -1.100074 0)
			(size 0.4064 0.9144)
			(layers "F.Cu" "F.Mask" "F.Paste")
			(net "PWR_EN_PEX_R1")
		)
		(pad "3" smd rect
			(at -1.100074 0.649986)
			(size 0.4064 0.9144)
			(layers "F.Cu" "F.Mask" "F.Paste")
			(net "GND")
		)
		(pad "4" smd rect
			(at 1.100074 0.649986)
			(size 0.4064 0.9144)
			(layers "F.Cu" "F.Mask" "F.Paste")
			(net "PWR_EN_PEX_BUF")
		)
		(pad "5" smd rect
			(at 1.100074 -0.649986)
			(size 0.4064 0.9144)
			(layers "F.Cu" "F.Mask" "F.Paste")
			(net "P3V3_AUX")
		)
	)
	(footprint ""
		(layer "F.Cu")
		(at 359.156 -186.182 180)
		(property "Reference" "R4614"
			(at 0 0 180)
			(layer "F.SilkS")
			(hide yes)
			(effects
				(font
					(size 1.27 1.27)
				)
			)
		)
		(property "Value" ""
			(at 0 0 180)
			(layer "F.Fab")
			(effects
				(font
					(size 1.27 1.27)
				)
			)
		)
		(duplicate_pad_numbers_are_jumpers no)
		(fp_line
			(start 0.7874 0.4064)
			(end -0.7874 0.4064)
			(stroke
				(width 0.1524)
				(type default)
			)
			(layer "F.SilkS")
		)
		(fp_line
			(start 0.7874 -0.4064)
			(end 0.7874 0.4064)
			(stroke
				(width 0.1524)
				(type default)
			)
			(layer "F.SilkS")
		)
		(fp_line
			(start -0.7874 0.4064)
			(end -0.7874 -0.4064)
			(stroke
				(width 0.1524)
				(type default)
			)
			(layer "F.SilkS")
		)
		(fp_line
			(start -0.7874 -0.4064)
			(end 0.7874 -0.4064)
			(stroke
				(width 0.1524)
				(type default)
			)
			(layer "F.SilkS")
		)
		(fp_line
			(start 0.67945 0.3048)
			(end 0.120396 0.3048)
			(stroke
				(width 0.1)
				(type default)
			)
			(layer "F.Fab")
		)
		(fp_line
			(start 0.67945 -0.3048)
			(end 0.67945 0.3048)
			(stroke
				(width 0.1)
				(type default)
			)
			(layer "F.Fab")
		)
		(fp_line
			(start 0.12065 -0.2794)
			(end 0.12065 -0.3048)
			(stroke
				(width 0.1)
				(type default)
			)
			(layer "F.Fab")
		)
		(fp_line
			(start 0.12065 -0.3048)
			(end 0.67945 -0.3048)
			(stroke
				(width 0.1)
				(type default)
			)
			(layer "F.Fab")
		)
		(fp_line
			(start 0.120396 0.3048)
			(end 0.120396 0.2794)
			(stroke
				(width 0.1)
				(type default)
			)
			(layer "F.Fab")
		)
		(fp_line
			(start 0.120396 0.2794)
			(end -0.12065 0.2794)
			(stroke
				(width 0.1)
				(type default)
			)
			(layer "F.Fab")
		)
		(fp_line
			(start -0.12065 0.3048)
			(end -0.67945 0.3048)
			(stroke
				(width 0.1)
				(type default)
			)
			(layer "F.Fab")
		)
		(fp_line
			(start -0.12065 0.2794)
			(end -0.12065 0.3048)
			(stroke
				(width 0.1)
				(type default)
			)
			(layer "F.Fab")
		)
		(fp_line
			(start -0.12065 -0.2794)
			(end 0.12065 -0.2794)
			(stroke
				(width 0.1)
				(type default)
			)
			(layer "F.Fab")
		)
		(fp_line
			(start -0.12065 -0.305054)
			(end -0.12065 -0.2794)
			(stroke
				(width 0.1)
				(type default)
			)
			(layer "F.Fab")
		)
		(fp_line
			(start -0.67945 0.3048)
			(end -0.67945 -0.305054)
			(stroke
				(width 0.1)
				(type default)
			)
			(layer "F.Fab")
		)
		(fp_line
			(start -0.67945 -0.305054)
			(end -0.12065 -0.305054)
			(stroke
				(width 0.1)
				(type default)
			)
			(layer "F.Fab")
		)
		(pad "1" smd circle
			(at -0.40005 0 180)
			(size 0 0)
			(layers "F.Cu" "F.Mask" "F.Paste")
			(net "SSD3_PEX_PWR_EN_R")
		)
		(pad "2" smd circle
			(at 0.40005 0 180)
			(size 0 0)
			(layers "F.Cu" "F.Mask" "F.Paste")
			(net "GND")
		)
	)
	(footprint ""
		(layer "F.Cu")
		(at 329.85456 -22.867366 90)
		(property "Reference" "C3951"
			(at 0 0 90)
			(layer "F.SilkS")
			(hide yes)
			(effects
				(font
					(size 1.27 1.27)
				)
			)
		)
		(property "Value" ""
			(at 0 0 90)
			(layer "F.Fab")
			(effects
				(font
					(size 1.27 1.27)
				)
			)
		)
		(duplicate_pad_numbers_are_jumpers no)
		(fp_line
			(start 0.7874 -0.4064)
			(end 0.7874 0.4064)
			(stroke
				(width 0.1524)
				(type default)
			)
			(layer "F.SilkS")
		)
		(fp_line
			(start -0.7874 -0.4064)
			(end 0.7874 -0.4064)
			(stroke
				(width 0.1524)
				(type default)
			)
			(layer "F.SilkS")
		)
		(fp_line
			(start 0.7874 0.4064)
			(end -0.7874 0.4064)
			(stroke
				(width 0.1524)
				(type default)
			)
			(layer "F.SilkS")
		)
		(fp_line
			(start -0.7874 0.4064)
			(end -0.7874 -0.4064)
			(stroke
				(width 0.1524)
				(type default)
			)
			(layer "F.SilkS")
		)
		(fp_line
			(start -0.12065 -0.305054)
			(end -0.12065 -0.2794)
			(stroke
				(width 0.1)
				(type default)
			)
			(layer "F.Fab")
		)
		(fp_line
			(start -0.67945 -0.305054)
			(end -0.12065 -0.305054)
			(stroke
				(width 0.1)
				(type default)
			)
			(layer "F.Fab")
		)
		(fp_line
			(start 0.67945 -0.3048)
			(end 0.67945 0.3048)
			(stroke
				(width 0.1)
				(type default)
			)
			(layer "F.Fab")
		)
		(fp_line
			(start 0.12065 -0.3048)
			(end 0.67945 -0.3048)
			(stroke
				(width 0.1)
				(type default)
			)
			(layer "F.Fab")
		)
		(fp_line
			(start 0.12065 -0.2794)
			(end 0.12065 -0.3048)
			(stroke
				(width 0.1)
				(type default)
			)
			(layer "F.Fab")
		)
		(fp_line
			(start -0.12065 -0.2794)
			(end 0.12065 -0.2794)
			(stroke
				(width 0.1)
				(type default)
			)
			(layer "F.Fab")
		)
		(fp_line
			(start 0.120396 0.2794)
			(end -0.12065 0.2794)
			(stroke
				(width 0.1)
				(type default)
			)
			(layer "F.Fab")
		)
		(fp_line
			(start -0.12065 0.2794)
			(end -0.12065 0.3048)
			(stroke
				(width 0.1)
				(type default)
			)
			(layer "F.Fab")
		)
		(fp_line
			(start 0.67945 0.3048)
			(end 0.120396 0.3048)
			(stroke
				(width 0.1)
				(type default)
			)
			(layer "F.Fab")
		)
		(fp_line
			(start 0.120396 0.3048)
			(end 0.120396 0.2794)
			(stroke
				(width 0.1)
				(type default)
			)
			(layer "F.Fab")
		)
		(fp_line
			(start -0.12065 0.3048)
			(end -0.67945 0.3048)
			(stroke
				(width 0.1)
				(type default)
			)
			(layer "F.Fab")
		)
		(fp_line
			(start -0.67945 0.3048)
			(end -0.67945 -0.305054)
			(stroke
				(width 0.1)
				(type default)
			)
			(layer "F.Fab")
		)
		(pad "1" smd circle
			(at -0.40005 0 90)
			(size 0 0)
			(layers "F.Cu" "F.Mask" "F.Paste")
			(net "P12V_SSD11")
		)
		(pad "2" smd circle
			(at 0.40005 0 90)
			(size 0 0)
			(layers "F.Cu" "F.Mask" "F.Paste")
			(net "GND")
		)
	)
	(footprint ""
		(layer "F.Cu")
		(at 2.51714 -72.165972)
		(property "Reference" "R5653"
			(at 0 0 0)
			(layer "F.SilkS")
			(hide yes)
			(effects
				(font
					(size 1.27 1.27)
				)
			)
		)
		(property "Value" ""
			(at 0 0 0)
			(layer "F.Fab")
			(effects
				(font
					(size 1.27 1.27)
				)
			)
		)
		(duplicate_pad_numbers_are_jumpers no)
		(fp_line
			(start -0.7874 -0.4064)
			(end 0.7874 -0.4064)
			(stroke
				(width 0.1524)
				(type default)
			)
			(layer "F.SilkS")
		)
		(fp_line
			(start -0.7874 0.4064)
			(end -0.7874 -0.4064)
			(stroke
				(width 0.1524)
				(type default)
			)
			(layer "F.SilkS")
		)
		(fp_line
			(start 0.7874 -0.4064)
			(end 0.7874 0.4064)
			(stroke
				(width 0.1524)
				(type default)
			)
			(layer "F.SilkS")
		)
		(fp_line
			(start 0.7874 0.4064)
			(end -0.7874 0.4064)
			(stroke
				(width 0.1524)
				(type default)
			)
			(layer "F.SilkS")
		)
		(fp_line
			(start -0.67945 -0.305054)
			(end -0.12065 -0.305054)
			(stroke
				(width 0.1)
				(type default)
			)
			(layer "F.Fab")
		)
		(fp_line
			(start -0.67945 0.3048)
			(end -0.67945 -0.305054)
			(stroke
				(width 0.1)
				(type default)
			)
			(layer "F.Fab")
		)
		(fp_line
			(start -0.12065 -0.305054)
			(end -0.12065 -0.2794)
			(stroke
				(width 0.1)
				(type default)
			)
			(layer "F.Fab")
		)
		(fp_line
			(start -0.12065 -0.2794)
			(end 0.12065 -0.2794)
			(stroke
				(width 0.1)
				(type default)
			)
			(layer "F.Fab")
		)
		(fp_line
			(start -0.12065 0.2794)
			(end -0.12065 0.3048)
			(stroke
				(width 0.1)
				(type default)
			)
			(layer "F.Fab")
		)
		(fp_line
			(start -0.12065 0.3048)
			(end -0.67945 0.3048)
			(stroke
				(width 0.1)
				(type default)
			)
			(layer "F.Fab")
		)
		(fp_line
			(start 0.120396 0.2794)
			(end -0.12065 0.2794)
			(stroke
				(width 0.1)
				(type default)
			)
			(layer "F.Fab")
		)
		(fp_line
			(start 0.120396 0.3048)
			(end 0.120396 0.2794)
			(stroke
				(width 0.1)
				(type default)
			)
			(layer "F.Fab")
		)
		(fp_line
			(start 0.12065 -0.3048)
			(end 0.67945 -0.3048)
			(stroke
				(width 0.1)
				(type default)
			)
			(layer "F.Fab")
		)
		(fp_line
			(start 0.12065 -0.2794)
			(end 0.12065 -0.3048)
			(stroke
				(width 0.1)
				(type default)
			)
			(layer "F.Fab")
		)
		(fp_line
			(start 0.67945 -0.3048)
			(end 0.67945 0.3048)
			(stroke
				(width 0.1)
				(type default)
			)
			(layer "F.Fab")
		)
		(fp_line
			(start 0.67945 0.3048)
			(end 0.120396 0.3048)
			(stroke
				(width 0.1)
				(type default)
			)
			(layer "F.Fab")
		)
		(pad "1" smd circle
			(at -0.40005 0)
			(size 0 0)
			(layers "F.Cu" "F.Mask" "F.Paste")
			(net "RST_SMB_SSD_R_N")
		)
		(pad "2" smd circle
			(at 0.40005 0)
			(size 0 0)
			(layers "F.Cu" "F.Mask" "F.Paste")
			(net "RST_SMB_SSD0_N")
		)
	)
	(footprint ""
		(layer "F.Cu")
		(at 385.850384 -250.070874 -90)
		(property "Reference" "R1415"
			(at 0 0 270)
			(layer "F.SilkS")
			(hide yes)
			(effects
				(font
					(size 1.27 1.27)
				)
			)
		)
		(property "Value" ""
			(at 0 0 270)
			(layer "F.Fab")
			(effects
				(font
					(size 1.27 1.27)
				)
			)
		)
		(duplicate_pad_numbers_are_jumpers no)
		(fp_line
			(start -0.7874 0.4064)
			(end -0.7874 -0.4064)
			(stroke
				(width 0.1524)
				(type default)
			)
			(layer "F.SilkS")
		)
		(fp_line
			(start 0.7874 0.4064)
			(end -0.7874 0.4064)
			(stroke
				(width 0.1524)
				(type default)
			)
			(layer "F.SilkS")
		)
		(fp_line
			(start -0.7874 -0.4064)
			(end 0.7874 -0.4064)
			(stroke
				(width 0.1524)
				(type default)
			)
			(layer "F.SilkS")
		)
		(fp_line
			(start 0.7874 -0.4064)
			(end 0.7874 0.4064)
			(stroke
				(width 0.1524)
				(type default)
			)
			(layer "F.SilkS")
		)
		(fp_line
			(start -0.67945 0.3048)
			(end -0.67945 -0.305054)
			(stroke
				(width 0.1)
				(type default)
			)
			(layer "F.Fab")
		)
		(fp_line
			(start -0.12065 0.3048)
			(end -0.67945 0.3048)
			(stroke
				(width 0.1)
				(type default)
			)
			(layer "F.Fab")
		)
		(fp_line
			(start 0.120396 0.3048)
			(end 0.120396 0.2794)
			(stroke
				(width 0.1)
				(type default)
			)
			(layer "F.Fab")
		)
		(fp_line
			(start 0.67945 0.3048)
			(end 0.120396 0.3048)
			(stroke
				(width 0.1)
				(type default)
			)
			(layer "F.Fab")
		)
		(fp_line
			(start -0.12065 0.2794)
			(end -0.12065 0.3048)
			(stroke
				(width 0.1)
				(type default)
			)
			(layer "F.Fab")
		)
		(fp_line
			(start 0.120396 0.2794)
			(end -0.12065 0.2794)
			(stroke
				(width 0.1)
				(type default)
			)
			(layer "F.Fab")
		)
		(fp_line
			(start -0.12065 -0.2794)
			(end 0.12065 -0.2794)
			(stroke
				(width 0.1)
				(type default)
			)
			(layer "F.Fab")
		)
		(fp_line
			(start 0.12065 -0.2794)
			(end 0.12065 -0.3048)
			(stroke
				(width 0.1)
				(type default)
			)
			(layer "F.Fab")
		)
		(fp_line
			(start 0.12065 -0.3048)
			(end 0.67945 -0.3048)
			(stroke
				(width 0.1)
				(type default)
			)
			(layer "F.Fab")
		)
		(fp_line
			(start 0.67945 -0.3048)
			(end 0.67945 0.3048)
			(stroke
				(width 0.1)
				(type default)
			)
			(layer "F.Fab")
		)
		(fp_line
			(start -0.67945 -0.305054)
			(end -0.12065 -0.305054)
			(stroke
				(width 0.1)
				(type default)
			)
			(layer "F.Fab")
		)
		(fp_line
			(start -0.12065 -0.305054)
			(end -0.12065 -0.2794)
			(stroke
				(width 0.1)
				(type default)
			)
			(layer "F.Fab")
		)
		(pad "1" smd circle
			(at -0.40005 0 270)
			(size 0 0)
			(layers "F.Cu" "F.Mask" "F.Paste")
			(net "PEX3_MODE_SEL10")
		)
		(pad "2" smd circle
			(at 0.40005 0 270)
			(size 0 0)
			(layers "F.Cu" "F.Mask" "F.Paste")
			(net "P1V8_PEX")
		)
	)
	(footprint ""
		(layer "F.Cu")
		(at 224.022158 -84.675472 180)
		(property "Reference" "R4353"
			(at 0 0 180)
			(layer "F.SilkS")
			(hide yes)
			(effects
				(font
					(size 1.27 1.27)
				)
			)
		)
		(property "Value" ""
			(at 0 0 180)
			(layer "F.Fab")
			(effects
				(font
					(size 1.27 1.27)
				)
			)
		)
		(duplicate_pad_numbers_are_jumpers no)
		(fp_line
			(start 0.7874 0.4064)
			(end -0.7874 0.4064)
			(stroke
				(width 0.1524)
				(type default)
			)
			(layer "F.SilkS")
		)
		(fp_line
			(start 0.7874 -0.4064)
			(end 0.7874 0.4064)
			(stroke
				(width 0.1524)
				(type default)
			)
			(layer "F.SilkS")
		)
		(fp_line
			(start -0.7874 0.4064)
			(end -0.7874 -0.4064)
			(stroke
				(width 0.1524)
				(type default)
			)
			(layer "F.SilkS")
		)
		(fp_line
			(start -0.7874 -0.4064)
			(end 0.7874 -0.4064)
			(stroke
				(width 0.1524)
				(type default)
			)
			(layer "F.SilkS")
		)
		(fp_line
			(start 0.67945 0.3048)
			(end 0.120396 0.3048)
			(stroke
				(width 0.1)
				(type default)
			)
			(layer "F.Fab")
		)
		(fp_line
			(start 0.67945 -0.3048)
			(end 0.67945 0.3048)
			(stroke
				(width 0.1)
				(type default)
			)
			(layer "F.Fab")
		)
		(fp_line
			(start 0.12065 -0.2794)
			(end 0.12065 -0.3048)
			(stroke
				(width 0.1)
				(type default)
			)
			(layer "F.Fab")
		)
		(fp_line
			(start 0.12065 -0.3048)
			(end 0.67945 -0.3048)
			(stroke
				(width 0.1)
				(type default)
			)
			(layer "F.Fab")
		)
		(fp_line
			(start 0.120396 0.3048)
			(end 0.120396 0.2794)
			(stroke
				(width 0.1)
				(type default)
			)
			(layer "F.Fab")
		)
		(fp_line
			(start 0.120396 0.2794)
			(end -0.12065 0.2794)
			(stroke
				(width 0.1)
				(type default)
			)
			(layer "F.Fab")
		)
		(fp_line
			(start -0.12065 0.3048)
			(end -0.67945 0.3048)
			(stroke
				(width 0.1)
				(type default)
			)
			(layer "F.Fab")
		)
		(fp_line
			(start -0.12065 0.2794)
			(end -0.12065 0.3048)
			(stroke
				(width 0.1)
				(type default)
			)
			(layer "F.Fab")
		)
		(fp_line
			(start -0.12065 -0.2794)
			(end 0.12065 -0.2794)
			(stroke
				(width 0.1)
				(type default)
			)
			(layer "F.Fab")
		)
		(fp_line
			(start -0.12065 -0.305054)
			(end -0.12065 -0.2794)
			(stroke
				(width 0.1)
				(type default)
			)
			(layer "F.Fab")
		)
		(fp_line
			(start -0.67945 0.3048)
			(end -0.67945 -0.305054)
			(stroke
				(width 0.1)
				(type default)
			)
			(layer "F.Fab")
		)
		(fp_line
			(start -0.67945 -0.305054)
			(end -0.12065 -0.305054)
			(stroke
				(width 0.1)
				(type default)
			)
			(layer "F.Fab")
		)
		(pad "1" smd circle
			(at -0.40005 0 180)
			(size 0 0)
			(layers "F.Cu" "F.Mask" "F.Paste")
			(net "P3V3_AUX")
		)
		(pad "2" smd circle
			(at 0.40005 0 180)
			(size 0 0)
			(layers "F.Cu" "F.Mask" "F.Paste")
			(net "SSD15_LED_R")
		)
	)
	(footprint ""
		(layer "F.Cu")
		(at 419.510972 -343.952322 90)
		(property "Reference" "C2448"
			(at 0 0 90)
			(layer "F.SilkS")
			(hide yes)
			(effects
				(font
					(size 1.27 1.27)
				)
			)
		)
		(property "Value" ""
			(at 0 0 90)
			(layer "F.Fab")
			(effects
				(font
					(size 1.27 1.27)
				)
			)
		)
		(duplicate_pad_numbers_are_jumpers no)
		(fp_line
			(start 0.299974 -0.150114)
			(end 0.299974 0.150114)
			(stroke
				(width 0.1)
				(type default)
			)
			(layer "F.Fab")
		)
		(fp_line
			(start -0.299974 -0.150114)
			(end 0.299974 -0.150114)
			(stroke
				(width 0.1)
				(type default)
			)
			(layer "F.Fab")
		)
		(fp_line
			(start 0.299974 0.150114)
			(end -0.299974 0.150114)
			(stroke
				(width 0.1)
				(type default)
			)
			(layer "F.Fab")
		)
		(fp_line
			(start -0.299974 0.150114)
			(end -0.299974 -0.150114)
			(stroke
				(width 0.1)
				(type default)
			)
			(layer "F.Fab")
		)
		(pad "1" smd rect
			(at -0.2667 0 90)
			(size 0.3048 0.381)
			(layers "F.Cu" "F.Mask" "F.Paste")
			(net "P5E_PEX3_STN4_TX_DN<75>")
		)
		(pad "2" smd rect
			(at 0.2667 0 90)
			(size 0.3048 0.381)
			(layers "F.Cu" "F.Mask" "F.Paste")
			(net "P5E_PEX3_STN4_TX_C_DN<75>")
		)
	)
	(footprint ""
		(layer "F.Cu")
		(at 142.343886 -47.92091)
		(property "Reference" "R548"
			(at 0 0 0)
			(layer "F.SilkS")
			(hide yes)
			(effects
				(font
					(size 1.27 1.27)
				)
			)
		)
		(property "Value" ""
			(at 0 0 0)
			(layer "F.Fab")
			(effects
				(font
					(size 1.27 1.27)
				)
			)
		)
		(duplicate_pad_numbers_are_jumpers no)
		(fp_line
			(start -0.7874 -0.4064)
			(end 0.7874 -0.4064)
			(stroke
				(width 0.1524)
				(type default)
			)
			(layer "F.SilkS")
		)
		(fp_line
			(start -0.7874 0.4064)
			(end -0.7874 -0.4064)
			(stroke
				(width 0.1524)
				(type default)
			)
			(layer "F.SilkS")
		)
		(fp_line
			(start 0.7874 -0.4064)
			(end 0.7874 0.4064)
			(stroke
				(width 0.1524)
				(type default)
			)
			(layer "F.SilkS")
		)
		(fp_line
			(start 0.7874 0.4064)
			(end -0.7874 0.4064)
			(stroke
				(width 0.1524)
				(type default)
			)
			(layer "F.SilkS")
		)
		(fp_line
			(start -0.67945 -0.305054)
			(end -0.12065 -0.305054)
			(stroke
				(width 0.1)
				(type default)
			)
			(layer "F.Fab")
		)
		(fp_line
			(start -0.67945 0.3048)
			(end -0.67945 -0.305054)
			(stroke
				(width 0.1)
				(type default)
			)
			(layer "F.Fab")
		)
		(fp_line
			(start -0.12065 -0.305054)
			(end -0.12065 -0.2794)
			(stroke
				(width 0.1)
				(type default)
			)
			(layer "F.Fab")
		)
		(fp_line
			(start -0.12065 -0.2794)
			(end 0.12065 -0.2794)
			(stroke
				(width 0.1)
				(type default)
			)
			(layer "F.Fab")
		)
		(fp_line
			(start -0.12065 0.2794)
			(end -0.12065 0.3048)
			(stroke
				(width 0.1)
				(type default)
			)
			(layer "F.Fab")
		)
		(fp_line
			(start -0.12065 0.3048)
			(end -0.67945 0.3048)
			(stroke
				(width 0.1)
				(type default)
			)
			(layer "F.Fab")
		)
		(fp_line
			(start 0.120396 0.2794)
			(end -0.12065 0.2794)
			(stroke
				(width 0.1)
				(type default)
			)
			(layer "F.Fab")
		)
		(fp_line
			(start 0.120396 0.3048)
			(end 0.120396 0.2794)
			(stroke
				(width 0.1)
				(type default)
			)
			(layer "F.Fab")
		)
		(fp_line
			(start 0.12065 -0.3048)
			(end 0.67945 -0.3048)
			(stroke
				(width 0.1)
				(type default)
			)
			(layer "F.Fab")
		)
		(fp_line
			(start 0.12065 -0.2794)
			(end 0.12065 -0.3048)
			(stroke
				(width 0.1)
				(type default)
			)
			(layer "F.Fab")
		)
		(fp_line
			(start 0.67945 -0.3048)
			(end 0.67945 0.3048)
			(stroke
				(width 0.1)
				(type default)
			)
			(layer "F.Fab")
		)
		(fp_line
			(start 0.67945 0.3048)
			(end 0.120396 0.3048)
			(stroke
				(width 0.1)
				(type default)
			)
			(layer "F.Fab")
		)
		(pad "1" smd circle
			(at -0.40005 0)
			(size 0 0)
			(layers "F.Cu" "F.Mask" "F.Paste")
			(net "P3V3_AUX")
		)
		(pad "2" smd circle
			(at 0.40005 0)
			(size 0 0)
			(layers "F.Cu" "F.Mask" "F.Paste")
			(net "SSD_0_7_ADC_ALERT_N")
		)
	)
	(footprint ""
		(layer "F.Cu")
		(at 260.249162 -300.197012 -90)
		(property "Reference" "C3364"
			(at 0 0 270)
			(layer "F.SilkS")
			(hide yes)
			(effects
				(font
					(size 1.27 1.27)
				)
			)
		)
		(property "Value" ""
			(at 0 0 270)
			(layer "F.Fab")
			(effects
				(font
					(size 1.27 1.27)
				)
			)
		)
		(duplicate_pad_numbers_are_jumpers no)
		(fp_line
			(start -0.299974 0.150114)
			(end -0.299974 -0.150114)
			(stroke
				(width 0.1)
				(type default)
			)
			(layer "F.Fab")
		)
		(fp_line
			(start 0.299974 0.150114)
			(end -0.299974 0.150114)
			(stroke
				(width 0.1)
				(type default)
			)
			(layer "F.Fab")
		)
		(fp_line
			(start -0.299974 -0.150114)
			(end 0.299974 -0.150114)
			(stroke
				(width 0.1)
				(type default)
			)
			(layer "F.Fab")
		)
		(fp_line
			(start 0.299974 -0.150114)
			(end 0.299974 0.150114)
			(stroke
				(width 0.1)
				(type default)
			)
			(layer "F.Fab")
		)
		(pad "1" smd rect
			(at -0.2667 0 270)
			(size 0.3048 0.381)
			(layers "F.Cu" "F.Mask" "F.Paste")
			(net "P1V8_PLL0_PEX2")
		)
		(pad "2" smd rect
			(at 0.2667 0 270)
			(size 0.3048 0.381)
			(layers "F.Cu" "F.Mask" "F.Paste")
			(net "GND")
		)
	)
	(footprint ""
		(layer "F.Cu")
		(at 337.349084 -356.244906 90)
		(property "Reference" "C575"
			(at 0 0 90)
			(layer "F.SilkS")
			(hide yes)
			(effects
				(font
					(size 1.27 1.27)
				)
			)
		)
		(property "Value" ""
			(at 0 0 90)
			(layer "F.Fab")
			(effects
				(font
					(size 1.27 1.27)
				)
			)
		)
		(duplicate_pad_numbers_are_jumpers no)
		(fp_line
			(start 0.299974 -0.150114)
			(end 0.299974 0.150114)
			(stroke
				(width 0.1)
				(type default)
			)
			(layer "F.Fab")
		)
		(fp_line
			(start -0.299974 -0.150114)
			(end 0.299974 -0.150114)
			(stroke
				(width 0.1)
				(type default)
			)
			(layer "F.Fab")
		)
		(fp_line
			(start 0.299974 0.150114)
			(end -0.299974 0.150114)
			(stroke
				(width 0.1)
				(type default)
			)
			(layer "F.Fab")
		)
		(fp_line
			(start -0.299974 0.150114)
			(end -0.299974 -0.150114)
			(stroke
				(width 0.1)
				(type default)
			)
			(layer "F.Fab")
		)
		(pad "1" smd rect
			(at -0.2667 0 90)
			(size 0.3048 0.381)
			(layers "F.Cu" "F.Mask" "F.Paste")
			(net "P5E_PEX2_STN6_TX_DP<99>")
		)
		(pad "2" smd rect
			(at 0.2667 0 90)
			(size 0.3048 0.381)
			(layers "F.Cu" "F.Mask" "F.Paste")
			(net "P5E_PEX2_STN6_TX_C_DP<99>")
		)
	)
	(footprint ""
		(layer "F.Cu")
		(at 33.287716 -285.218632)
		(property "Reference" "C3058"
			(at 0 0 0)
			(layer "F.SilkS")
			(hide yes)
			(effects
				(font
					(size 1.27 1.27)
				)
			)
		)
		(property "Value" ""
			(at 0 0 0)
			(layer "F.Fab")
			(effects
				(font
					(size 1.27 1.27)
				)
			)
		)
		(duplicate_pad_numbers_are_jumpers no)
		(fp_line
			(start -1.2954 -0.5842)
			(end 1.2954 -0.5842)
			(stroke
				(width 0.1524)
				(type default)
			)
			(layer "F.SilkS")
		)
		(fp_line
			(start -1.2954 0.5842)
			(end -1.2954 -0.5842)
			(stroke
				(width 0.1524)
				(type default)
			)
			(layer "F.SilkS")
		)
		(fp_line
			(start 1.2954 -0.5842)
			(end 1.2954 0.5842)
			(stroke
				(width 0.1524)
				(type default)
			)
			(layer "F.SilkS")
		)
		(fp_line
			(start 1.2954 0.5842)
			(end -1.2954 0.5842)
			(stroke
				(width 0.1524)
				(type default)
			)
			(layer "F.SilkS")
		)
		(fp_line
			(start -1.1938 -0.4064)
			(end -0.8636 -0.4064)
			(stroke
				(width 0.1)
				(type default)
			)
			(layer "F.Fab")
		)
		(fp_line
			(start -1.1938 0.4064)
			(end -1.1938 -0.4064)
			(stroke
				(width 0.1)
				(type default)
			)
			(layer "F.Fab")
		)
		(fp_line
			(start -0.8636 -0.4572)
			(end 0.8636 -0.4572)
			(stroke
				(width 0.1)
				(type default)
			)
			(layer "F.Fab")
		)
		(fp_line
			(start -0.8636 -0.4064)
			(end -0.8636 -0.4572)
			(stroke
				(width 0.1)
				(type default)
			)
			(layer "F.Fab")
		)
		(fp_line
			(start -0.8636 0.4064)
			(end -1.1938 0.4064)
			(stroke
				(width 0.1)
				(type default)
			)
			(layer "F.Fab")
		)
		(fp_line
			(start -0.8636 0.4572)
			(end -0.8636 0.4064)
			(stroke
				(width 0.1)
				(type default)
			)
			(layer "F.Fab")
		)
		(fp_line
			(start 0.8636 -0.4572)
			(end 0.8636 -0.4064)
			(stroke
				(width 0.1)
				(type default)
			)
			(layer "F.Fab")
		)
		(fp_line
			(start 0.8636 -0.4064)
			(end 1.1938 -0.4064)
			(stroke
				(width 0.1)
				(type default)
			)
			(layer "F.Fab")
		)
		(fp_line
			(start 0.8636 0.4064)
			(end 0.8636 0.4572)
			(stroke
				(width 0.1)
				(type default)
			)
			(layer "F.Fab")
		)
		(fp_line
			(start 0.8636 0.4572)
			(end -0.8636 0.4572)
			(stroke
				(width 0.1)
				(type default)
			)
			(layer "F.Fab")
		)
		(fp_line
			(start 1.1938 -0.4064)
			(end 1.1938 0.4064)
			(stroke
				(width 0.1)
				(type default)
			)
			(layer "F.Fab")
		)
		(fp_line
			(start 1.1938 0.4064)
			(end 0.8636 0.4064)
			(stroke
				(width 0.1)
				(type default)
			)
			(layer "F.Fab")
		)
		(pad "1" smd rect
			(at -0.7366 0 270)
			(size 0.7112 0.8128)
			(layers "F.Cu" "F.Mask" "F.Paste")
			(net "PCEPLL7_VDDA18_PEX0")
		)
		(pad "2" smd rect
			(at 0.7366 0 270)
			(size 0.7112 0.8128)
			(layers "F.Cu" "F.Mask" "F.Paste")
			(net "GND")
		)
	)
	(footprint ""
		(layer "F.Cu")
		(at 101.951536 -7.591552)
		(property "Reference" "U129"
			(at -1.265936 2.360422 0)
			(unlocked yes)
			(layer "F.SilkS")
			(effects
				(font
					(size 0.7874 0.5842)
					(thickness 0.1524)
				)
				(justify left)
			)
		)
		(property "Value" ""
			(at 0 0 0)
			(layer "F.Fab")
			(effects
				(font
					(size 1.27 1.27)
				)
			)
		)
		(duplicate_pad_numbers_are_jumpers no)
		(fp_line
			(start -1.463548 -1.549908)
			(end -0.787908 -1.549908)
			(stroke
				(width 0.1524)
				(type default)
			)
			(layer "F.SilkS")
		)
		(fp_line
			(start -1.463548 1.549908)
			(end -1.463548 -1.549908)
			(stroke
				(width 0.1524)
				(type default)
			)
			(layer "F.SilkS")
		)
		(fp_line
			(start -0.787908 -1.549908)
			(end 0 -0.762)
			(stroke
				(width 0.1524)
				(type default)
			)
			(layer "F.SilkS")
		)
		(fp_line
			(start 0 -0.762)
			(end 0.762 -1.549908)
			(stroke
				(width 0.1524)
				(type default)
			)
			(layer "F.SilkS")
		)
		(fp_line
			(start 0.762 -1.549908)
			(end 1.463548 -1.549908)
			(stroke
				(width 0.1524)
				(type default)
			)
			(layer "F.SilkS")
		)
		(fp_line
			(start 1.463548 -1.549908)
			(end 1.463548 1.549908)
			(stroke
				(width 0.1524)
				(type default)
			)
			(layer "F.SilkS")
		)
		(fp_line
			(start 1.463548 1.549908)
			(end -1.463548 1.549908)
			(stroke
				(width 0.1524)
				(type default)
			)
			(layer "F.SilkS")
		)
		(fp_poly
			(pts
				(xy -3.4798 -1.359916) (xy -2.86004 -1.050036) (xy -3.4798 -0.740156)
			)
			(stroke
				(width 0)
				(type default)
			)
			(fill yes)
			(layer "F.SilkS")
		)
		(fp_line
			(start -1.549908 -1.549908)
			(end 1.549908 -1.549908)
			(stroke
				(width 0.1)
				(type default)
			)
			(layer "F.Fab")
		)
		(fp_line
			(start -1.549908 1.549908)
			(end -1.549908 -1.549908)
			(stroke
				(width 0.1)
				(type default)
			)
			(layer "F.Fab")
		)
		(fp_line
			(start 1.549908 -1.549908)
			(end 1.549908 1.549908)
			(stroke
				(width 0.1)
				(type default)
			)
			(layer "F.Fab")
		)
		(fp_line
			(start 1.549908 1.549908)
			(end -1.549908 1.549908)
			(stroke
				(width 0.1)
				(type default)
			)
			(layer "F.Fab")
		)
		(fp_poly
			(pts
				(xy -3.4798 -1.359916) (xy -2.86004 -1.050036) (xy -3.4798 -0.740156)
			)
			(stroke
				(width 0)
				(type default)
			)
			(fill yes)
			(layer "F.Fab")
		)
		(pad "1" smd rect
			(at -2.175002 -1.050036 90)
			(size 0.6096 1.1684)
			(layers "F.Cu" "F.Mask" "F.Paste")
			(net "P3V3_SSD3")
		)
		(pad "2" smd rect
			(at -2.175002 -0.32512 90)
			(size 0.4318 1.1684)
			(layers "F.Cu" "F.Mask" "F.Paste")
			(net "SMB_ISO_SSD3_SCL")
		)
		(pad "3" smd rect
			(at -2.175002 0.32512 90)
			(size 0.4318 1.1684)
			(layers "F.Cu" "F.Mask" "F.Paste")
			(net "SMB_ISO_SSD3_SDA")
		)
		(pad "4" smd rect
			(at -2.175002 1.050036 90)
			(size 0.6096 1.1684)
			(layers "F.Cu" "F.Mask" "F.Paste")
			(net "GND")
		)
		(pad "5" smd rect
			(at 2.175002 1.050036 90)
			(size 0.6096 1.1684)
			(layers "F.Cu" "F.Mask" "F.Paste")
			(net "SMB_SSD3_ISO_EN")
		)
		(pad "6" smd rect
			(at 2.175002 0.32512 90)
			(size 0.4318 1.1684)
			(layers "F.Cu" "F.Mask" "F.Paste")
			(net "SMB_BIC_I2C9_MUX0_SSD3_R_SDA")
		)
		(pad "7" smd rect
			(at 2.175002 -0.32512 90)
			(size 0.4318 1.1684)
			(layers "F.Cu" "F.Mask" "F.Paste")
			(net "SMB_BIC_I2C9_MUX0_SSD3_R_SCL")
		)
		(pad "8" smd rect
			(at 2.175002 -1.050036 90)
			(size 0.6096 1.1684)
			(layers "F.Cu" "F.Mask" "F.Paste")
			(net "P3V3_AUX")
		)
	)
	(footprint ""
		(layer "F.Cu")
		(at 167.498522 -180.372766 180)
		(property "Reference" "R152"
			(at 0 0 180)
			(layer "F.SilkS")
			(hide yes)
			(effects
				(font
					(size 1.27 1.27)
				)
			)
		)
		(property "Value" ""
			(at 0 0 180)
			(layer "F.Fab")
			(effects
				(font
					(size 1.27 1.27)
				)
			)
		)
		(duplicate_pad_numbers_are_jumpers no)
		(fp_line
			(start 0.7874 0.4064)
			(end -0.7874 0.4064)
			(stroke
				(width 0.1524)
				(type default)
			)
			(layer "F.SilkS")
		)
		(fp_line
			(start 0.7874 -0.4064)
			(end 0.7874 0.4064)
			(stroke
				(width 0.1524)
				(type default)
			)
			(layer "F.SilkS")
		)
		(fp_line
			(start -0.7874 0.4064)
			(end -0.7874 -0.4064)
			(stroke
				(width 0.1524)
				(type default)
			)
			(layer "F.SilkS")
		)
		(fp_line
			(start -0.7874 -0.4064)
			(end 0.7874 -0.4064)
			(stroke
				(width 0.1524)
				(type default)
			)
			(layer "F.SilkS")
		)
		(fp_line
			(start 0.67945 0.3048)
			(end 0.120396 0.3048)
			(stroke
				(width 0.1)
				(type default)
			)
			(layer "F.Fab")
		)
		(fp_line
			(start 0.67945 -0.3048)
			(end 0.67945 0.3048)
			(stroke
				(width 0.1)
				(type default)
			)
			(layer "F.Fab")
		)
		(fp_line
			(start 0.12065 -0.2794)
			(end 0.12065 -0.3048)
			(stroke
				(width 0.1)
				(type default)
			)
			(layer "F.Fab")
		)
		(fp_line
			(start 0.12065 -0.3048)
			(end 0.67945 -0.3048)
			(stroke
				(width 0.1)
				(type default)
			)
			(layer "F.Fab")
		)
		(fp_line
			(start 0.120396 0.3048)
			(end 0.120396 0.2794)
			(stroke
				(width 0.1)
				(type default)
			)
			(layer "F.Fab")
		)
		(fp_line
			(start 0.120396 0.2794)
			(end -0.12065 0.2794)
			(stroke
				(width 0.1)
				(type default)
			)
			(layer "F.Fab")
		)
		(fp_line
			(start -0.12065 0.3048)
			(end -0.67945 0.3048)
			(stroke
				(width 0.1)
				(type default)
			)
			(layer "F.Fab")
		)
		(fp_line
			(start -0.12065 0.2794)
			(end -0.12065 0.3048)
			(stroke
				(width 0.1)
				(type default)
			)
			(layer "F.Fab")
		)
		(fp_line
			(start -0.12065 -0.2794)
			(end 0.12065 -0.2794)
			(stroke
				(width 0.1)
				(type default)
			)
			(layer "F.Fab")
		)
		(fp_line
			(start -0.12065 -0.305054)
			(end -0.12065 -0.2794)
			(stroke
				(width 0.1)
				(type default)
			)
			(layer "F.Fab")
		)
		(fp_line
			(start -0.67945 0.3048)
			(end -0.67945 -0.305054)
			(stroke
				(width 0.1)
				(type default)
			)
			(layer "F.Fab")
		)
		(fp_line
			(start -0.67945 -0.305054)
			(end -0.12065 -0.305054)
			(stroke
				(width 0.1)
				(type default)
			)
			(layer "F.Fab")
		)
		(pad "1" smd circle
			(at -0.40005 0 180)
			(size 0 0)
			(layers "F.Cu" "F.Mask" "F.Paste")
			(net "P3V3_AUX")
		)
		(pad "2" smd circle
			(at 0.40005 0 180)
			(size 0 0)
			(layers "F.Cu" "F.Mask" "F.Paste")
			(net "HP_NIC2_HSC_PWRGD_N")
		)
	)
	(footprint ""
		(layer "F.Cu")
		(at 453.841866 -254.5969 -90)
		(property "Reference" "C4395"
			(at 0 0 270)
			(layer "F.SilkS")
			(hide yes)
			(effects
				(font
					(size 1.27 1.27)
				)
			)
		)
		(property "Value" ""
			(at 0 0 270)
			(layer "F.Fab")
			(effects
				(font
					(size 1.27 1.27)
				)
			)
		)
		(duplicate_pad_numbers_are_jumpers no)
		(fp_line
			(start -1.2954 0.5842)
			(end -1.2954 -0.5842)
			(stroke
				(width 0.1524)
				(type default)
			)
			(layer "F.SilkS")
		)
		(fp_line
			(start 1.2954 0.5842)
			(end -1.2954 0.5842)
			(stroke
				(width 0.1524)
				(type default)
			)
			(layer "F.SilkS")
		)
		(fp_line
			(start -1.2954 -0.5842)
			(end 1.2954 -0.5842)
			(stroke
				(width 0.1524)
				(type default)
			)
			(layer "F.SilkS")
		)
		(fp_line
			(start 1.2954 -0.5842)
			(end 1.2954 0.5842)
			(stroke
				(width 0.1524)
				(type default)
			)
			(layer "F.SilkS")
		)
		(fp_line
			(start -0.8636 0.4572)
			(end -0.8636 0.4064)
			(stroke
				(width 0.1)
				(type default)
			)
			(layer "F.Fab")
		)
		(fp_line
			(start 0.8636 0.4572)
			(end -0.8636 0.4572)
			(stroke
				(width 0.1)
				(type default)
			)
			(layer "F.Fab")
		)
		(fp_line
			(start -1.1938 0.4064)
			(end -1.1938 -0.4064)
			(stroke
				(width 0.1)
				(type default)
			)
			(layer "F.Fab")
		)
		(fp_line
			(start -0.8636 0.4064)
			(end -1.1938 0.4064)
			(stroke
				(width 0.1)
				(type default)
			)
			(layer "F.Fab")
		)
		(fp_line
			(start 0.8636 0.4064)
			(end 0.8636 0.4572)
			(stroke
				(width 0.1)
				(type default)
			)
			(layer "F.Fab")
		)
		(fp_line
			(start 1.1938 0.4064)
			(end 0.8636 0.4064)
			(stroke
				(width 0.1)
				(type default)
			)
			(layer "F.Fab")
		)
		(fp_line
			(start -1.1938 -0.4064)
			(end -0.8636 -0.4064)
			(stroke
				(width 0.1)
				(type default)
			)
			(layer "F.Fab")
		)
		(fp_line
			(start -0.8636 -0.4064)
			(end -0.8636 -0.4572)
			(stroke
				(width 0.1)
				(type default)
			)
			(layer "F.Fab")
		)
		(fp_line
			(start 0.8636 -0.4064)
			(end 1.1938 -0.4064)
			(stroke
				(width 0.1)
				(type default)
			)
			(layer "F.Fab")
		)
		(fp_line
			(start 1.1938 -0.4064)
			(end 1.1938 0.4064)
			(stroke
				(width 0.1)
				(type default)
			)
			(layer "F.Fab")
		)
		(fp_line
			(start -0.8636 -0.4572)
			(end 0.8636 -0.4572)
			(stroke
				(width 0.1)
				(type default)
			)
			(layer "F.Fab")
		)
		(fp_line
			(start 0.8636 -0.4572)
			(end 0.8636 -0.4064)
			(stroke
				(width 0.1)
				(type default)
			)
			(layer "F.Fab")
		)
		(pad "1" smd rect
			(at -0.7366 0 180)
			(size 0.7112 0.8128)
			(layers "F.Cu" "F.Mask" "F.Paste")
			(net "P1V25_SERDES_VDDPLL_PEX3_C1")
		)
		(pad "2" smd rect
			(at 0.7366 0 180)
			(size 0.7112 0.8128)
			(layers "F.Cu" "F.Mask" "F.Paste")
			(net "GND")
		)
	)
	(footprint ""
		(layer "F.Cu")
		(at 319.70599 -392.063732 180)
		(property "Reference" "C4108"
			(at 0 0 180)
			(layer "F.SilkS")
			(hide yes)
			(effects
				(font
					(size 1.27 1.27)
				)
			)
		)
		(property "Value" ""
			(at 0 0 180)
			(layer "F.Fab")
			(effects
				(font
					(size 1.27 1.27)
				)
			)
		)
		(duplicate_pad_numbers_are_jumpers no)
		(fp_line
			(start 0.7874 0.4064)
			(end -0.7874 0.4064)
			(stroke
				(width 0.1524)
				(type default)
			)
			(layer "F.SilkS")
		)
		(fp_line
			(start 0.7874 -0.4064)
			(end 0.7874 0.4064)
			(stroke
				(width 0.1524)
				(type default)
			)
			(layer "F.SilkS")
		)
		(fp_line
			(start -0.7874 0.4064)
			(end -0.7874 -0.4064)
			(stroke
				(width 0.1524)
				(type default)
			)
			(layer "F.SilkS")
		)
		(fp_line
			(start -0.7874 -0.4064)
			(end 0.7874 -0.4064)
			(stroke
				(width 0.1524)
				(type default)
			)
			(layer "F.SilkS")
		)
		(fp_line
			(start 0.67945 0.3048)
			(end 0.120396 0.3048)
			(stroke
				(width 0.1)
				(type default)
			)
			(layer "F.Fab")
		)
		(fp_line
			(start 0.67945 -0.3048)
			(end 0.67945 0.3048)
			(stroke
				(width 0.1)
				(type default)
			)
			(layer "F.Fab")
		)
		(fp_line
			(start 0.12065 -0.2794)
			(end 0.12065 -0.3048)
			(stroke
				(width 0.1)
				(type default)
			)
			(layer "F.Fab")
		)
		(fp_line
			(start 0.12065 -0.3048)
			(end 0.67945 -0.3048)
			(stroke
				(width 0.1)
				(type default)
			)
			(layer "F.Fab")
		)
		(fp_line
			(start 0.120396 0.3048)
			(end 0.120396 0.2794)
			(stroke
				(width 0.1)
				(type default)
			)
			(layer "F.Fab")
		)
		(fp_line
			(start 0.120396 0.2794)
			(end -0.12065 0.2794)
			(stroke
				(width 0.1)
				(type default)
			)
			(layer "F.Fab")
		)
		(fp_line
			(start -0.12065 0.3048)
			(end -0.67945 0.3048)
			(stroke
				(width 0.1)
				(type default)
			)
			(layer "F.Fab")
		)
		(fp_line
			(start -0.12065 0.2794)
			(end -0.12065 0.3048)
			(stroke
				(width 0.1)
				(type default)
			)
			(layer "F.Fab")
		)
		(fp_line
			(start -0.12065 -0.2794)
			(end 0.12065 -0.2794)
			(stroke
				(width 0.1)
				(type default)
			)
			(layer "F.Fab")
		)
		(fp_line
			(start -0.12065 -0.305054)
			(end -0.12065 -0.2794)
			(stroke
				(width 0.1)
				(type default)
			)
			(layer "F.Fab")
		)
		(fp_line
			(start -0.67945 0.3048)
			(end -0.67945 -0.305054)
			(stroke
				(width 0.1)
				(type default)
			)
			(layer "F.Fab")
		)
		(fp_line
			(start -0.67945 -0.305054)
			(end -0.12065 -0.305054)
			(stroke
				(width 0.1)
				(type default)
			)
			(layer "F.Fab")
		)
		(pad "1" smd circle
			(at -0.40005 0 180)
			(size 0 0)
			(layers "F.Cu" "F.Mask" "F.Paste")
			(net "GND")
		)
		(pad "2" smd circle
			(at 0.40005 0 180)
			(size 0 0)
			(layers "F.Cu" "F.Mask" "F.Paste")
			(net "GPU_3V3IO_RSVD3_FFU")
		)
	)
	(footprint ""
		(layer "F.Cu")
		(at 316.066678 -52.543456 180)
		(property "Reference" "PC585"
			(at 0 0 180)
			(layer "F.SilkS")
			(hide yes)
			(effects
				(font
					(size 1.27 1.27)
				)
			)
		)
		(property "Value" ""
			(at 0 0 180)
			(layer "F.Fab")
			(effects
				(font
					(size 1.27 1.27)
				)
			)
		)
		(duplicate_pad_numbers_are_jumpers no)
		(fp_line
			(start 0.7874 0.4064)
			(end -0.7874 0.4064)
			(stroke
				(width 0.1524)
				(type default)
			)
			(layer "F.SilkS")
		)
		(fp_line
			(start 0.7874 -0.4064)
			(end 0.7874 0.4064)
			(stroke
				(width 0.1524)
				(type default)
			)
			(layer "F.SilkS")
		)
		(fp_line
			(start -0.7874 0.4064)
			(end -0.7874 -0.4064)
			(stroke
				(width 0.1524)
				(type default)
			)
			(layer "F.SilkS")
		)
		(fp_line
			(start -0.7874 -0.4064)
			(end 0.7874 -0.4064)
			(stroke
				(width 0.1524)
				(type default)
			)
			(layer "F.SilkS")
		)
		(fp_line
			(start 0.67945 0.3048)
			(end 0.120396 0.3048)
			(stroke
				(width 0.1)
				(type default)
			)
			(layer "F.Fab")
		)
		(fp_line
			(start 0.67945 -0.3048)
			(end 0.67945 0.3048)
			(stroke
				(width 0.1)
				(type default)
			)
			(layer "F.Fab")
		)
		(fp_line
			(start 0.12065 -0.2794)
			(end 0.12065 -0.3048)
			(stroke
				(width 0.1)
				(type default)
			)
			(layer "F.Fab")
		)
		(fp_line
			(start 0.12065 -0.3048)
			(end 0.67945 -0.3048)
			(stroke
				(width 0.1)
				(type default)
			)
			(layer "F.Fab")
		)
		(fp_line
			(start 0.120396 0.3048)
			(end 0.120396 0.2794)
			(stroke
				(width 0.1)
				(type default)
			)
			(layer "F.Fab")
		)
		(fp_line
			(start 0.120396 0.2794)
			(end -0.12065 0.2794)
			(stroke
				(width 0.1)
				(type default)
			)
			(layer "F.Fab")
		)
		(fp_line
			(start -0.12065 0.3048)
			(end -0.67945 0.3048)
			(stroke
				(width 0.1)
				(type default)
			)
			(layer "F.Fab")
		)
		(fp_line
			(start -0.12065 0.2794)
			(end -0.12065 0.3048)
			(stroke
				(width 0.1)
				(type default)
			)
			(layer "F.Fab")
		)
		(fp_line
			(start -0.12065 -0.2794)
			(end 0.12065 -0.2794)
			(stroke
				(width 0.1)
				(type default)
			)
			(layer "F.Fab")
		)
		(fp_line
			(start -0.12065 -0.305054)
			(end -0.12065 -0.2794)
			(stroke
				(width 0.1)
				(type default)
			)
			(layer "F.Fab")
		)
		(fp_line
			(start -0.67945 0.3048)
			(end -0.67945 -0.305054)
			(stroke
				(width 0.1)
				(type default)
			)
			(layer "F.Fab")
		)
		(fp_line
			(start -0.67945 -0.305054)
			(end -0.12065 -0.305054)
			(stroke
				(width 0.1)
				(type default)
			)
			(layer "F.Fab")
		)
		(pad "1" smd circle
			(at -0.40005 0 180)
			(size 0 0)
			(layers "F.Cu" "F.Mask" "F.Paste")
			(net "P3V3_SSD11")
		)
		(pad "2" smd circle
			(at 0.40005 0 180)
			(size 0 0)
			(layers "F.Cu" "F.Mask" "F.Paste")
			(net "GND")
		)
	)
	(footprint ""
		(layer "F.Cu")
		(at 363.474 -199.771)
		(property "Reference" "R4661"
			(at 0 0 0)
			(layer "F.SilkS")
			(hide yes)
			(effects
				(font
					(size 1.27 1.27)
				)
			)
		)
		(property "Value" ""
			(at 0 0 0)
			(layer "F.Fab")
			(effects
				(font
					(size 1.27 1.27)
				)
			)
		)
		(duplicate_pad_numbers_are_jumpers no)
		(fp_line
			(start -0.7874 -0.4064)
			(end 0.7874 -0.4064)
			(stroke
				(width 0.1524)
				(type default)
			)
			(layer "F.SilkS")
		)
		(fp_line
			(start -0.7874 0.4064)
			(end -0.7874 -0.4064)
			(stroke
				(width 0.1524)
				(type default)
			)
			(layer "F.SilkS")
		)
		(fp_line
			(start 0.7874 -0.4064)
			(end 0.7874 0.4064)
			(stroke
				(width 0.1524)
				(type default)
			)
			(layer "F.SilkS")
		)
		(fp_line
			(start 0.7874 0.4064)
			(end -0.7874 0.4064)
			(stroke
				(width 0.1524)
				(type default)
			)
			(layer "F.SilkS")
		)
		(fp_line
			(start -0.67945 -0.305054)
			(end -0.12065 -0.305054)
			(stroke
				(width 0.1)
				(type default)
			)
			(layer "F.Fab")
		)
		(fp_line
			(start -0.67945 0.3048)
			(end -0.67945 -0.305054)
			(stroke
				(width 0.1)
				(type default)
			)
			(layer "F.Fab")
		)
		(fp_line
			(start -0.12065 -0.305054)
			(end -0.12065 -0.2794)
			(stroke
				(width 0.1)
				(type default)
			)
			(layer "F.Fab")
		)
		(fp_line
			(start -0.12065 -0.2794)
			(end 0.12065 -0.2794)
			(stroke
				(width 0.1)
				(type default)
			)
			(layer "F.Fab")
		)
		(fp_line
			(start -0.12065 0.2794)
			(end -0.12065 0.3048)
			(stroke
				(width 0.1)
				(type default)
			)
			(layer "F.Fab")
		)
		(fp_line
			(start -0.12065 0.3048)
			(end -0.67945 0.3048)
			(stroke
				(width 0.1)
				(type default)
			)
			(layer "F.Fab")
		)
		(fp_line
			(start 0.120396 0.2794)
			(end -0.12065 0.2794)
			(stroke
				(width 0.1)
				(type default)
			)
			(layer "F.Fab")
		)
		(fp_line
			(start 0.120396 0.3048)
			(end 0.120396 0.2794)
			(stroke
				(width 0.1)
				(type default)
			)
			(layer "F.Fab")
		)
		(fp_line
			(start 0.12065 -0.3048)
			(end 0.67945 -0.3048)
			(stroke
				(width 0.1)
				(type default)
			)
			(layer "F.Fab")
		)
		(fp_line
			(start 0.12065 -0.2794)
			(end 0.12065 -0.3048)
			(stroke
				(width 0.1)
				(type default)
			)
			(layer "F.Fab")
		)
		(fp_line
			(start 0.67945 -0.3048)
			(end 0.67945 0.3048)
			(stroke
				(width 0.1)
				(type default)
			)
			(layer "F.Fab")
		)
		(fp_line
			(start 0.67945 0.3048)
			(end 0.120396 0.3048)
			(stroke
				(width 0.1)
				(type default)
			)
			(layer "F.Fab")
		)
		(pad "1" smd circle
			(at -0.40005 0)
			(size 0 0)
			(layers "F.Cu" "F.Mask" "F.Paste")
			(net "P3V3_AUX")
		)
		(pad "2" smd circle
			(at 0.40005 0)
			(size 0 0)
			(layers "F.Cu" "F.Mask" "F.Paste")
			(net "SSD4_PEX_PWR_EN_R")
		)
	)
	(footprint ""
		(layer "F.Cu")
		(at 39.280592 -102.888796)
		(property "Reference" "C59"
			(at 0 0 0)
			(layer "F.SilkS")
			(hide yes)
			(effects
				(font
					(size 1.27 1.27)
				)
			)
		)
		(property "Value" ""
			(at 0 0 0)
			(layer "F.Fab")
			(effects
				(font
					(size 1.27 1.27)
				)
			)
		)
		(duplicate_pad_numbers_are_jumpers no)
		(fp_line
			(start -0.299974 -0.150114)
			(end 0.299974 -0.150114)
			(stroke
				(width 0.1)
				(type default)
			)
			(layer "F.Fab")
		)
		(fp_line
			(start -0.299974 0.150114)
			(end -0.299974 -0.150114)
			(stroke
				(width 0.1)
				(type default)
			)
			(layer "F.Fab")
		)
		(fp_line
			(start 0.299974 -0.150114)
			(end 0.299974 0.150114)
			(stroke
				(width 0.1)
				(type default)
			)
			(layer "F.Fab")
		)
		(fp_line
			(start 0.299974 0.150114)
			(end -0.299974 0.150114)
			(stroke
				(width 0.1)
				(type default)
			)
			(layer "F.Fab")
		)
		(pad "1" smd rect
			(at -0.2667 0)
			(size 0.3048 0.381)
			(layers "F.Cu" "F.Mask" "F.Paste")
			(net "P5E_PEX0_STN1_TX_DP<18>")
		)
		(pad "2" smd rect
			(at 0.2667 0)
			(size 0.3048 0.381)
			(layers "F.Cu" "F.Mask" "F.Paste")
			(net "P5E_PEX0_STN1_TX_C_DP<18>")
		)
	)
	(footprint ""
		(layer "F.Cu")
		(at 358.013 -219.456 180)
		(property "Reference" "R4086"
			(at 0 0 180)
			(layer "F.SilkS")
			(hide yes)
			(effects
				(font
					(size 1.27 1.27)
				)
			)
		)
		(property "Value" ""
			(at 0 0 180)
			(layer "F.Fab")
			(effects
				(font
					(size 1.27 1.27)
				)
			)
		)
		(duplicate_pad_numbers_are_jumpers no)
		(fp_line
			(start 0.7874 0.4064)
			(end -0.7874 0.4064)
			(stroke
				(width 0.1524)
				(type default)
			)
			(layer "F.SilkS")
		)
		(fp_line
			(start 0.7874 -0.4064)
			(end 0.7874 0.4064)
			(stroke
				(width 0.1524)
				(type default)
			)
			(layer "F.SilkS")
		)
		(fp_line
			(start -0.7874 0.4064)
			(end -0.7874 -0.4064)
			(stroke
				(width 0.1524)
				(type default)
			)
			(layer "F.SilkS")
		)
		(fp_line
			(start -0.7874 -0.4064)
			(end 0.7874 -0.4064)
			(stroke
				(width 0.1524)
				(type default)
			)
			(layer "F.SilkS")
		)
		(fp_line
			(start 0.67945 0.3048)
			(end 0.120396 0.3048)
			(stroke
				(width 0.1)
				(type default)
			)
			(layer "F.Fab")
		)
		(fp_line
			(start 0.67945 -0.3048)
			(end 0.67945 0.3048)
			(stroke
				(width 0.1)
				(type default)
			)
			(layer "F.Fab")
		)
		(fp_line
			(start 0.12065 -0.2794)
			(end 0.12065 -0.3048)
			(stroke
				(width 0.1)
				(type default)
			)
			(layer "F.Fab")
		)
		(fp_line
			(start 0.12065 -0.3048)
			(end 0.67945 -0.3048)
			(stroke
				(width 0.1)
				(type default)
			)
			(layer "F.Fab")
		)
		(fp_line
			(start 0.120396 0.3048)
			(end 0.120396 0.2794)
			(stroke
				(width 0.1)
				(type default)
			)
			(layer "F.Fab")
		)
		(fp_line
			(start 0.120396 0.2794)
			(end -0.12065 0.2794)
			(stroke
				(width 0.1)
				(type default)
			)
			(layer "F.Fab")
		)
		(fp_line
			(start -0.12065 0.3048)
			(end -0.67945 0.3048)
			(stroke
				(width 0.1)
				(type default)
			)
			(layer "F.Fab")
		)
		(fp_line
			(start -0.12065 0.2794)
			(end -0.12065 0.3048)
			(stroke
				(width 0.1)
				(type default)
			)
			(layer "F.Fab")
		)
		(fp_line
			(start -0.12065 -0.2794)
			(end 0.12065 -0.2794)
			(stroke
				(width 0.1)
				(type default)
			)
			(layer "F.Fab")
		)
		(fp_line
			(start -0.12065 -0.305054)
			(end -0.12065 -0.2794)
			(stroke
				(width 0.1)
				(type default)
			)
			(layer "F.Fab")
		)
		(fp_line
			(start -0.67945 0.3048)
			(end -0.67945 -0.305054)
			(stroke
				(width 0.1)
				(type default)
			)
			(layer "F.Fab")
		)
		(fp_line
			(start -0.67945 -0.305054)
			(end -0.12065 -0.305054)
			(stroke
				(width 0.1)
				(type default)
			)
			(layer "F.Fab")
		)
		(pad "1" smd circle
			(at -0.40005 0 180)
			(size 0 0)
			(layers "F.Cu" "F.Mask" "F.Paste")
			(net "RST_NIC6_PERST_R_N")
		)
		(pad "2" smd circle
			(at 0.40005 0 180)
			(size 0 0)
			(layers "F.Cu" "F.Mask" "F.Paste")
			(net "RST_NIC6_PERST_N")
		)
	)
	(footprint ""
		(layer "F.Cu")
		(at 189.474856 -406.291796 90)
		(property "Reference" "U338"
			(at -1.481328 -3.258312 0)
			(unlocked yes)
			(layer "F.SilkS")
			(effects
				(font
					(size 0.7874 0.5842)
					(thickness 0.1524)
				)
			)
		)
		(property "Value" ""
			(at 0 0 90)
			(layer "F.Fab")
			(effects
				(font
					(size 1.27 1.27)
				)
			)
		)
		(duplicate_pad_numbers_are_jumpers no)
		(fp_line
			(start 2.046478 -1.450086)
			(end 0.484886 -1.450086)
			(stroke
				(width 0.1524)
				(type default)
			)
			(layer "F.SilkS")
		)
		(fp_line
			(start 0.484886 -1.450086)
			(end 0 -0.762)
			(stroke
				(width 0.1524)
				(type default)
			)
			(layer "F.SilkS")
		)
		(fp_line
			(start -0.484886 -1.450086)
			(end -2.046478 -1.450086)
			(stroke
				(width 0.1524)
				(type default)
			)
			(layer "F.SilkS")
		)
		(fp_line
			(start -2.046478 -1.450086)
			(end -2.046478 1.450086)
			(stroke
				(width 0.1524)
				(type default)
			)
			(layer "F.SilkS")
		)
		(fp_line
			(start 0 -0.762)
			(end -0.484886 -1.450086)
			(stroke
				(width 0.1524)
				(type default)
			)
			(layer "F.SilkS")
		)
		(fp_line
			(start 2.046478 1.450086)
			(end 2.046478 -1.450086)
			(stroke
				(width 0.1524)
				(type default)
			)
			(layer "F.SilkS")
		)
		(fp_line
			(start -2.046478 1.450086)
			(end 2.046478 1.450086)
			(stroke
				(width 0.1524)
				(type default)
			)
			(layer "F.SilkS")
		)
		(fp_poly
			(pts
				(xy -3.229356 -1.693164) (xy -2.511044 -2.411476) (xy -2.151888 -1.334008)
			)
			(stroke
				(width 0)
				(type default)
			)
			(fill yes)
			(layer "F.SilkS")
		)
		(fp_line
			(start 0.87503 -1.450086)
			(end -0.87503 -1.450086)
			(stroke
				(width 0.1)
				(type default)
			)
			(layer "F.Fab")
		)
		(fp_line
			(start -0.87503 -1.450086)
			(end -0.87503 1.450086)
			(stroke
				(width 0.1)
				(type default)
			)
			(layer "F.Fab")
		)
		(fp_line
			(start 0.87503 1.450086)
			(end 0.87503 -1.450086)
			(stroke
				(width 0.1)
				(type default)
			)
			(layer "F.Fab")
		)
		(fp_line
			(start -0.87503 1.450086)
			(end 0.87503 1.450086)
			(stroke
				(width 0.1)
				(type default)
			)
			(layer "F.Fab")
		)
		(fp_poly
			(pts
				(xy -3.2512 -0.44196) (xy -3.2512 -1.45796) (xy -2.2352 -0.94996)
			)
			(stroke
				(width 0)
				(type default)
			)
			(fill yes)
			(layer "F.Fab")
		)
		(pad "1" smd rect
			(at -1.309878 -0.94996 180)
			(size 0.635 1.2192)
			(layers "F.Cu" "F.Mask" "F.Paste")
			(net "FM_UV_ADR_TRIGGER_N")
		)
		(pad "2" smd rect
			(at -1.309878 0 180)
			(size 0.635 1.2192)
			(layers "F.Cu" "F.Mask" "F.Paste")
			(net "GND")
		)
		(pad "3" smd rect
			(at -1.309878 0.94996 180)
			(size 0.635 1.2192)
			(layers "F.Cu" "F.Mask" "F.Paste")
			(net "A_P12V_AUX_ADR_TRIGGER")
		)
		(pad "4" smd rect
			(at 1.309878 0.94996 180)
			(size 0.635 1.2192)
			(layers "F.Cu" "F.Mask" "F.Paste")
			(net "A_P12V_AUX_FP_TRIGGER")
		)
		(pad "5" smd rect
			(at 1.309878 0 180)
			(size 0.635 1.2192)
			(layers "F.Cu" "F.Mask" "F.Paste")
			(net "FM_UV_LT6700_VS")
		)
		(pad "6" smd rect
			(at 1.309878 -0.94996 180)
			(size 0.635 1.2192)
			(layers "F.Cu" "F.Mask" "F.Paste")
			(net "A_P12V_AUX_FPH_GATE")
		)
	)
	(footprint ""
		(layer "F.Cu")
		(at 339.773514 -241.336322 -90)
		(property "Reference" "C2745"
			(at 0 0 270)
			(layer "F.SilkS")
			(hide yes)
			(effects
				(font
					(size 1.27 1.27)
				)
			)
		)
		(property "Value" ""
			(at 0 0 270)
			(layer "F.Fab")
			(effects
				(font
					(size 1.27 1.27)
				)
			)
		)
		(duplicate_pad_numbers_are_jumpers no)
		(fp_line
			(start -0.7874 0.4064)
			(end -0.7874 -0.4064)
			(stroke
				(width 0.1524)
				(type default)
			)
			(layer "F.SilkS")
		)
		(fp_line
			(start 0.7874 0.4064)
			(end -0.7874 0.4064)
			(stroke
				(width 0.1524)
				(type default)
			)
			(layer "F.SilkS")
		)
		(fp_line
			(start -0.7874 -0.4064)
			(end 0.7874 -0.4064)
			(stroke
				(width 0.1524)
				(type default)
			)
			(layer "F.SilkS")
		)
		(fp_line
			(start 0.7874 -0.4064)
			(end 0.7874 0.4064)
			(stroke
				(width 0.1524)
				(type default)
			)
			(layer "F.SilkS")
		)
		(fp_line
			(start -0.67945 0.3048)
			(end -0.67945 -0.305054)
			(stroke
				(width 0.1)
				(type default)
			)
			(layer "F.Fab")
		)
		(fp_line
			(start -0.12065 0.3048)
			(end -0.67945 0.3048)
			(stroke
				(width 0.1)
				(type default)
			)
			(layer "F.Fab")
		)
		(fp_line
			(start 0.120396 0.3048)
			(end 0.120396 0.2794)
			(stroke
				(width 0.1)
				(type default)
			)
			(layer "F.Fab")
		)
		(fp_line
			(start 0.67945 0.3048)
			(end 0.120396 0.3048)
			(stroke
				(width 0.1)
				(type default)
			)
			(layer "F.Fab")
		)
		(fp_line
			(start -0.12065 0.2794)
			(end -0.12065 0.3048)
			(stroke
				(width 0.1)
				(type default)
			)
			(layer "F.Fab")
		)
		(fp_line
			(start 0.120396 0.2794)
			(end -0.12065 0.2794)
			(stroke
				(width 0.1)
				(type default)
			)
			(layer "F.Fab")
		)
		(fp_line
			(start -0.12065 -0.2794)
			(end 0.12065 -0.2794)
			(stroke
				(width 0.1)
				(type default)
			)
			(layer "F.Fab")
		)
		(fp_line
			(start 0.12065 -0.2794)
			(end 0.12065 -0.3048)
			(stroke
				(width 0.1)
				(type default)
			)
			(layer "F.Fab")
		)
		(fp_line
			(start 0.12065 -0.3048)
			(end 0.67945 -0.3048)
			(stroke
				(width 0.1)
				(type default)
			)
			(layer "F.Fab")
		)
		(fp_line
			(start 0.67945 -0.3048)
			(end 0.67945 0.3048)
			(stroke
				(width 0.1)
				(type default)
			)
			(layer "F.Fab")
		)
		(fp_line
			(start -0.67945 -0.305054)
			(end -0.12065 -0.305054)
			(stroke
				(width 0.1)
				(type default)
			)
			(layer "F.Fab")
		)
		(fp_line
			(start -0.12065 -0.305054)
			(end -0.12065 -0.2794)
			(stroke
				(width 0.1)
				(type default)
			)
			(layer "F.Fab")
		)
		(pad "1" smd circle
			(at -0.40005 0 270)
			(size 0 0)
			(layers "F.Cu" "F.Mask" "F.Paste")
			(net "P3V3_AUX")
		)
		(pad "2" smd circle
			(at 0.40005 0 270)
			(size 0 0)
			(layers "F.Cu" "F.Mask" "F.Paste")
			(net "GND")
		)
	)
	(footprint ""
		(layer "F.Cu")
		(at 98.503486 -243.237258)
		(property "Reference" "U96"
			(at -0.205486 -2.328672 0)
			(unlocked yes)
			(layer "F.SilkS")
			(effects
				(font
					(size 0.7874 0.5842)
					(thickness 0.1524)
				)
			)
		)
		(property "Value" ""
			(at 0 0 0)
			(layer "F.Fab")
			(effects
				(font
					(size 1.27 1.27)
				)
			)
		)
		(duplicate_pad_numbers_are_jumpers no)
		(fp_line
			(start -1.500124 -1.500124)
			(end -1.004062 -1.500124)
			(stroke
				(width 0.1524)
				(type default)
			)
			(layer "F.SilkS")
		)
		(fp_line
			(start -1.500124 -1.004062)
			(end -1.500124 -1.500124)
			(stroke
				(width 0.1524)
				(type default)
			)
			(layer "F.SilkS")
		)
		(fp_line
			(start -1.500124 1.500124)
			(end -1.500124 1.004062)
			(stroke
				(width 0.1524)
				(type default)
			)
			(layer "F.SilkS")
		)
		(fp_line
			(start -1.004062 1.500124)
			(end -1.500124 1.500124)
			(stroke
				(width 0.1524)
				(type default)
			)
			(layer "F.SilkS")
		)
		(fp_line
			(start 1.004062 -1.500124)
			(end 1.500124 -1.500124)
			(stroke
				(width 0.1524)
				(type default)
			)
			(layer "F.SilkS")
		)
		(fp_line
			(start 1.500124 -1.500124)
			(end 1.500124 -1.004062)
			(stroke
				(width 0.1524)
				(type default)
			)
			(layer "F.SilkS")
		)
		(fp_line
			(start 1.500124 1.004062)
			(end 1.500124 1.500124)
			(stroke
				(width 0.1524)
				(type default)
			)
			(layer "F.SilkS")
		)
		(fp_line
			(start 1.500124 1.500124)
			(end 1.004062 1.500124)
			(stroke
				(width 0.1524)
				(type default)
			)
			(layer "F.SilkS")
		)
		(fp_poly
			(pts
				(xy -2.518156 -1.494282) (xy -1.64084 -1.201928) (xy -1.933194 -2.079244)
			)
			(stroke
				(width 0)
				(type default)
			)
			(fill yes)
			(layer "F.SilkS")
		)
		(fp_line
			(start -1.500124 -1.500124)
			(end 1.500124 -1.500124)
			(stroke
				(width 0.1)
				(type default)
			)
			(layer "F.Fab")
		)
		(fp_line
			(start -1.500124 1.500124)
			(end -1.500124 -1.500124)
			(stroke
				(width 0.1)
				(type default)
			)
			(layer "F.Fab")
		)
		(fp_line
			(start 1.500124 -1.500124)
			(end 1.500124 1.500124)
			(stroke
				(width 0.1)
				(type default)
			)
			(layer "F.Fab")
		)
		(fp_line
			(start 1.500124 1.500124)
			(end -1.500124 1.500124)
			(stroke
				(width 0.1)
				(type default)
			)
			(layer "F.Fab")
		)
		(fp_poly
			(pts
				(xy -2.847848 -1.258062) (xy -2.847848 -0.242062) (xy -1.831848 -0.750062)
			)
			(stroke
				(width 0)
				(type default)
			)
			(fill yes)
			(layer "F.Fab")
		)
		(pad "1" smd rect
			(at -1.400048 -0.750062 270)
			(size 0.2286 0.6096)
			(layers "F.Cu" "F.Mask" "F.Paste")
			(net "PEX_P1V8_ADC_A1")
		)
		(pad "2" smd rect
			(at -1.400048 -0.249936 270)
			(size 0.2286 0.6096)
			(layers "F.Cu" "F.Mask" "F.Paste")
			(net "PEX_P1V8_ADC_A0")
		)
		(pad "3" smd rect
			(at -1.400048 0.249936 270)
			(size 0.2286 0.6096)
			(layers "F.Cu" "F.Mask" "F.Paste")
			(net "PEX_P1V8_ADC_ALERT_N")
		)
		(pad "4" smd rect
			(at -1.400048 0.750062 270)
			(size 0.2286 0.6096)
			(layers "F.Cu" "F.Mask" "F.Paste")
			(net "SMB_PEX_P1V8_ADC_SDA")
		)
		(pad "5" smd rect
			(at -0.750062 1.400048)
			(size 0.2286 0.6096)
			(layers "F.Cu" "F.Mask" "F.Paste")
			(net "SMB_PEX_P1V8_ADC_SCL")
		)
		(pad "6" smd rect
			(at -0.249936 1.400048)
			(size 0.2286 0.6096)
			(layers "F.Cu" "F.Mask" "F.Paste")
			(net "Net_8594")
		)
		(pad "7" smd rect
			(at 0.249936 1.400048)
			(size 0.2286 0.6096)
			(layers "F.Cu" "F.Mask" "F.Paste")
			(net "Net_8593")
		)
		(pad "8" smd rect
			(at 0.750062 1.400048)
			(size 0.2286 0.6096)
			(layers "F.Cu" "F.Mask" "F.Paste")
			(net "Net_8592")
		)
		(pad "9" smd rect
			(at 1.400048 0.750062 270)
			(size 0.2286 0.6096)
			(layers "F.Cu" "F.Mask" "F.Paste")
			(net "P3V3_AUX")
		)
		(pad "10" smd rect
			(at 1.400048 0.249936 270)
			(size 0.2286 0.6096)
			(layers "F.Cu" "F.Mask" "F.Paste")
			(net "GND")
		)
		(pad "11" smd rect
			(at 1.400048 -0.249936 270)
			(size 0.2286 0.6096)
			(layers "F.Cu" "F.Mask" "F.Paste")
			(net "P1V8_PEX_R")
		)
		(pad "12" smd rect
			(at 1.400048 -0.750062 270)
			(size 0.2286 0.6096)
			(layers "F.Cu" "F.Mask" "F.Paste")
			(net "P12V_PEX_P1V8_VIN_N")
		)
		(pad "13" smd rect
			(at 0.750062 -1.400048)
			(size 0.2286 0.6096)
			(layers "F.Cu" "F.Mask" "F.Paste")
			(net "P12V_PEX_P1V8_VIN_P")
		)
		(pad "14" smd rect
			(at 0.249936 -1.400048)
			(size 0.2286 0.6096)
			(layers "F.Cu" "F.Mask" "F.Paste")
			(net "Net_8591")
		)
		(pad "15" smd rect
			(at -0.249936 -1.400048)
			(size 0.2286 0.6096)
			(layers "F.Cu" "F.Mask" "F.Paste")
			(net "Net_8590")
		)
		(pad "16" smd rect
			(at -0.750062 -1.400048)
			(size 0.2286 0.6096)
			(layers "F.Cu" "F.Mask" "F.Paste")
			(net "Net_8589")
		)
		(pad "TH" smd rect
			(at 0 0)
			(size 1.7018 1.7018)
			(layers "F.Cu" "F.Mask" "F.Paste")
			(net "GND")
		)
		(zone
			(layer "F.Cu")
			(hatch none 0.5)
			(connect_pads
				(clearance 0)
			)
			(min_thickness 0.25)
			(keepout
				(tracks not_allowed)
				(vias allowed)
				(pads allowed)
				(copperpour not_allowed)
				(footprints allowed)
			)
			(placement
				(enabled no)
				(sheetname "")
			)
			(fill
				(thermal_gap 0.5)
				(thermal_bridge_width 0.5)
				(island_removal_mode 0)
			)
			(polygon
				(pts
					(xy 97.459038 -243.262658) (xy 97.459038 -244.281706) (xy 99.547934 -244.281706) (xy 99.547934 -242.19281)
					(xy 97.459038 -242.19281) (xy 97.459038 -243.237258) (xy 97.601786 -243.237258) (xy 97.601786 -242.335558)
					(xy 99.405186 -242.335558) (xy 99.405186 -244.138958) (xy 97.601786 -244.138958) (xy 97.601786 -243.262658)
				)
			)
		)
	)
	(footprint ""
		(layer "F.Cu")
		(at 117.117114 -260.671564 90)
		(property "Reference" "PC50"
			(at 0 0 90)
			(layer "F.SilkS")
			(hide yes)
			(effects
				(font
					(size 1.27 1.27)
				)
			)
		)
		(property "Value" ""
			(at 0 0 90)
			(layer "F.Fab")
			(effects
				(font
					(size 1.27 1.27)
				)
			)
		)
		(duplicate_pad_numbers_are_jumpers no)
		(fp_line
			(start 0.7874 -0.4064)
			(end 0.7874 0.4064)
			(stroke
				(width 0.1524)
				(type default)
			)
			(layer "F.SilkS")
		)
		(fp_line
			(start -0.7874 -0.4064)
			(end 0.7874 -0.4064)
			(stroke
				(width 0.1524)
				(type default)
			)
			(layer "F.SilkS")
		)
		(fp_line
			(start 0.7874 0.4064)
			(end -0.7874 0.4064)
			(stroke
				(width 0.1524)
				(type default)
			)
			(layer "F.SilkS")
		)
		(fp_line
			(start -0.7874 0.4064)
			(end -0.7874 -0.4064)
			(stroke
				(width 0.1524)
				(type default)
			)
			(layer "F.SilkS")
		)
		(fp_line
			(start -0.12065 -0.305054)
			(end -0.12065 -0.2794)
			(stroke
				(width 0.1)
				(type default)
			)
			(layer "F.Fab")
		)
		(fp_line
			(start -0.67945 -0.305054)
			(end -0.12065 -0.305054)
			(stroke
				(width 0.1)
				(type default)
			)
			(layer "F.Fab")
		)
		(fp_line
			(start 0.67945 -0.3048)
			(end 0.67945 0.3048)
			(stroke
				(width 0.1)
				(type default)
			)
			(layer "F.Fab")
		)
		(fp_line
			(start 0.12065 -0.3048)
			(end 0.67945 -0.3048)
			(stroke
				(width 0.1)
				(type default)
			)
			(layer "F.Fab")
		)
		(fp_line
			(start 0.12065 -0.2794)
			(end 0.12065 -0.3048)
			(stroke
				(width 0.1)
				(type default)
			)
			(layer "F.Fab")
		)
		(fp_line
			(start -0.12065 -0.2794)
			(end 0.12065 -0.2794)
			(stroke
				(width 0.1)
				(type default)
			)
			(layer "F.Fab")
		)
		(fp_line
			(start 0.120396 0.2794)
			(end -0.12065 0.2794)
			(stroke
				(width 0.1)
				(type default)
			)
			(layer "F.Fab")
		)
		(fp_line
			(start -0.12065 0.2794)
			(end -0.12065 0.3048)
			(stroke
				(width 0.1)
				(type default)
			)
			(layer "F.Fab")
		)
		(fp_line
			(start 0.67945 0.3048)
			(end 0.120396 0.3048)
			(stroke
				(width 0.1)
				(type default)
			)
			(layer "F.Fab")
		)
		(fp_line
			(start 0.120396 0.3048)
			(end 0.120396 0.2794)
			(stroke
				(width 0.1)
				(type default)
			)
			(layer "F.Fab")
		)
		(fp_line
			(start -0.12065 0.3048)
			(end -0.67945 0.3048)
			(stroke
				(width 0.1)
				(type default)
			)
			(layer "F.Fab")
		)
		(fp_line
			(start -0.67945 0.3048)
			(end -0.67945 -0.305054)
			(stroke
				(width 0.1)
				(type default)
			)
			(layer "F.Fab")
		)
		(pad "1" smd circle
			(at -0.40005 0 90)
			(size 0 0)
			(layers "F.Cu" "F.Mask" "F.Paste")
			(net "P0V8_PEX1_VSEN1")
		)
		(pad "2" smd circle
			(at 0.40005 0 90)
			(size 0 0)
			(layers "F.Cu" "F.Mask" "F.Paste")
			(net "SH_P0V8_PEX1_RGND1")
		)
	)
	(footprint ""
		(layer "F.Cu")
		(at 205.95209 -289.230816 90)
		(property "Reference" "R3938"
			(at 0 0 90)
			(layer "F.SilkS")
			(hide yes)
			(effects
				(font
					(size 1.27 1.27)
				)
			)
		)
		(property "Value" ""
			(at 0 0 90)
			(layer "F.Fab")
			(effects
				(font
					(size 1.27 1.27)
				)
			)
		)
		(duplicate_pad_numbers_are_jumpers no)
		(fp_line
			(start 0.7874 -0.4064)
			(end 0.7874 0.4064)
			(stroke
				(width 0.1524)
				(type default)
			)
			(layer "F.SilkS")
		)
		(fp_line
			(start -0.7874 -0.4064)
			(end 0.7874 -0.4064)
			(stroke
				(width 0.1524)
				(type default)
			)
			(layer "F.SilkS")
		)
		(fp_line
			(start 0.7874 0.4064)
			(end -0.7874 0.4064)
			(stroke
				(width 0.1524)
				(type default)
			)
			(layer "F.SilkS")
		)
		(fp_line
			(start -0.7874 0.4064)
			(end -0.7874 -0.4064)
			(stroke
				(width 0.1524)
				(type default)
			)
			(layer "F.SilkS")
		)
		(fp_line
			(start -0.12065 -0.305054)
			(end -0.12065 -0.2794)
			(stroke
				(width 0.1)
				(type default)
			)
			(layer "F.Fab")
		)
		(fp_line
			(start -0.67945 -0.305054)
			(end -0.12065 -0.305054)
			(stroke
				(width 0.1)
				(type default)
			)
			(layer "F.Fab")
		)
		(fp_line
			(start 0.67945 -0.3048)
			(end 0.67945 0.3048)
			(stroke
				(width 0.1)
				(type default)
			)
			(layer "F.Fab")
		)
		(fp_line
			(start 0.12065 -0.3048)
			(end 0.67945 -0.3048)
			(stroke
				(width 0.1)
				(type default)
			)
			(layer "F.Fab")
		)
		(fp_line
			(start 0.12065 -0.2794)
			(end 0.12065 -0.3048)
			(stroke
				(width 0.1)
				(type default)
			)
			(layer "F.Fab")
		)
		(fp_line
			(start -0.12065 -0.2794)
			(end 0.12065 -0.2794)
			(stroke
				(width 0.1)
				(type default)
			)
			(layer "F.Fab")
		)
		(fp_line
			(start 0.120396 0.2794)
			(end -0.12065 0.2794)
			(stroke
				(width 0.1)
				(type default)
			)
			(layer "F.Fab")
		)
		(fp_line
			(start -0.12065 0.2794)
			(end -0.12065 0.3048)
			(stroke
				(width 0.1)
				(type default)
			)
			(layer "F.Fab")
		)
		(fp_line
			(start 0.67945 0.3048)
			(end 0.120396 0.3048)
			(stroke
				(width 0.1)
				(type default)
			)
			(layer "F.Fab")
		)
		(fp_line
			(start 0.120396 0.3048)
			(end 0.120396 0.2794)
			(stroke
				(width 0.1)
				(type default)
			)
			(layer "F.Fab")
		)
		(fp_line
			(start -0.12065 0.3048)
			(end -0.67945 0.3048)
			(stroke
				(width 0.1)
				(type default)
			)
			(layer "F.Fab")
		)
		(fp_line
			(start -0.67945 0.3048)
			(end -0.67945 -0.305054)
			(stroke
				(width 0.1)
				(type default)
			)
			(layer "F.Fab")
		)
		(pad "1" smd circle
			(at -0.40005 0 90)
			(size 0 0)
			(layers "F.Cu" "F.Mask" "F.Paste")
			(net "SMB_PEX1_PCA9555_SDA")
		)
		(pad "2" smd circle
			(at 0.40005 0 90)
			(size 0 0)
			(layers "F.Cu" "F.Mask" "F.Paste")
			(net "SMB_PEX1_HOST_LS_SDA")
		)
	)
	(footprint ""
		(layer "F.Cu")
		(at 129.690114 -255.210564 180)
		(property "Reference" "R827"
			(at 0 0 180)
			(layer "F.SilkS")
			(hide yes)
			(effects
				(font
					(size 1.27 1.27)
				)
			)
		)
		(property "Value" ""
			(at 0 0 180)
			(layer "F.Fab")
			(effects
				(font
					(size 1.27 1.27)
				)
			)
		)
		(duplicate_pad_numbers_are_jumpers no)
		(fp_line
			(start 0.7874 0.4064)
			(end -0.7874 0.4064)
			(stroke
				(width 0.1524)
				(type default)
			)
			(layer "F.SilkS")
		)
		(fp_line
			(start 0.7874 -0.4064)
			(end 0.7874 0.4064)
			(stroke
				(width 0.1524)
				(type default)
			)
			(layer "F.SilkS")
		)
		(fp_line
			(start -0.7874 0.4064)
			(end -0.7874 -0.4064)
			(stroke
				(width 0.1524)
				(type default)
			)
			(layer "F.SilkS")
		)
		(fp_line
			(start -0.7874 -0.4064)
			(end 0.7874 -0.4064)
			(stroke
				(width 0.1524)
				(type default)
			)
			(layer "F.SilkS")
		)
		(fp_line
			(start 0.67945 0.3048)
			(end 0.120396 0.3048)
			(stroke
				(width 0.1)
				(type default)
			)
			(layer "F.Fab")
		)
		(fp_line
			(start 0.67945 -0.3048)
			(end 0.67945 0.3048)
			(stroke
				(width 0.1)
				(type default)
			)
			(layer "F.Fab")
		)
		(fp_line
			(start 0.12065 -0.2794)
			(end 0.12065 -0.3048)
			(stroke
				(width 0.1)
				(type default)
			)
			(layer "F.Fab")
		)
		(fp_line
			(start 0.12065 -0.3048)
			(end 0.67945 -0.3048)
			(stroke
				(width 0.1)
				(type default)
			)
			(layer "F.Fab")
		)
		(fp_line
			(start 0.120396 0.3048)
			(end 0.120396 0.2794)
			(stroke
				(width 0.1)
				(type default)
			)
			(layer "F.Fab")
		)
		(fp_line
			(start 0.120396 0.2794)
			(end -0.12065 0.2794)
			(stroke
				(width 0.1)
				(type default)
			)
			(layer "F.Fab")
		)
		(fp_line
			(start -0.12065 0.3048)
			(end -0.67945 0.3048)
			(stroke
				(width 0.1)
				(type default)
			)
			(layer "F.Fab")
		)
		(fp_line
			(start -0.12065 0.2794)
			(end -0.12065 0.3048)
			(stroke
				(width 0.1)
				(type default)
			)
			(layer "F.Fab")
		)
		(fp_line
			(start -0.12065 -0.2794)
			(end 0.12065 -0.2794)
			(stroke
				(width 0.1)
				(type default)
			)
			(layer "F.Fab")
		)
		(fp_line
			(start -0.12065 -0.305054)
			(end -0.12065 -0.2794)
			(stroke
				(width 0.1)
				(type default)
			)
			(layer "F.Fab")
		)
		(fp_line
			(start -0.67945 0.3048)
			(end -0.67945 -0.305054)
			(stroke
				(width 0.1)
				(type default)
			)
			(layer "F.Fab")
		)
		(fp_line
			(start -0.67945 -0.305054)
			(end -0.12065 -0.305054)
			(stroke
				(width 0.1)
				(type default)
			)
			(layer "F.Fab")
		)
		(pad "1" smd circle
			(at -0.40005 0 180)
			(size 0 0)
			(layers "F.Cu" "F.Mask" "F.Paste")
			(net "PWR_EN_PEX_R")
		)
		(pad "2" smd circle
			(at 0.40005 0 180)
			(size 0 0)
			(layers "F.Cu" "F.Mask" "F.Paste")
			(net "FM_P0V8_PEX0_EN_R")
		)
	)
	(footprint ""
		(layer "F.Cu")
		(at 10.420858 -317.105792 180)
		(property "Reference" "PC203"
			(at 0 0 180)
			(layer "F.SilkS")
			(hide yes)
			(effects
				(font
					(size 1.27 1.27)
				)
			)
		)
		(property "Value" ""
			(at 0 0 180)
			(layer "F.Fab")
			(effects
				(font
					(size 1.27 1.27)
				)
			)
		)
		(duplicate_pad_numbers_are_jumpers no)
		(fp_line
			(start 0.7874 0.4064)
			(end -0.7874 0.4064)
			(stroke
				(width 0.1524)
				(type default)
			)
			(layer "F.SilkS")
		)
		(fp_line
			(start 0.7874 -0.4064)
			(end 0.7874 0.4064)
			(stroke
				(width 0.1524)
				(type default)
			)
			(layer "F.SilkS")
		)
		(fp_line
			(start -0.7874 0.4064)
			(end -0.7874 -0.4064)
			(stroke
				(width 0.1524)
				(type default)
			)
			(layer "F.SilkS")
		)
		(fp_line
			(start -0.7874 -0.4064)
			(end 0.7874 -0.4064)
			(stroke
				(width 0.1524)
				(type default)
			)
			(layer "F.SilkS")
		)
		(fp_line
			(start 0.67945 0.3048)
			(end 0.120396 0.3048)
			(stroke
				(width 0.1)
				(type default)
			)
			(layer "F.Fab")
		)
		(fp_line
			(start 0.67945 -0.3048)
			(end 0.67945 0.3048)
			(stroke
				(width 0.1)
				(type default)
			)
			(layer "F.Fab")
		)
		(fp_line
			(start 0.12065 -0.2794)
			(end 0.12065 -0.3048)
			(stroke
				(width 0.1)
				(type default)
			)
			(layer "F.Fab")
		)
		(fp_line
			(start 0.12065 -0.3048)
			(end 0.67945 -0.3048)
			(stroke
				(width 0.1)
				(type default)
			)
			(layer "F.Fab")
		)
		(fp_line
			(start 0.120396 0.3048)
			(end 0.120396 0.2794)
			(stroke
				(width 0.1)
				(type default)
			)
			(layer "F.Fab")
		)
		(fp_line
			(start 0.120396 0.2794)
			(end -0.12065 0.2794)
			(stroke
				(width 0.1)
				(type default)
			)
			(layer "F.Fab")
		)
		(fp_line
			(start -0.12065 0.3048)
			(end -0.67945 0.3048)
			(stroke
				(width 0.1)
				(type default)
			)
			(layer "F.Fab")
		)
		(fp_line
			(start -0.12065 0.2794)
			(end -0.12065 0.3048)
			(stroke
				(width 0.1)
				(type default)
			)
			(layer "F.Fab")
		)
		(fp_line
			(start -0.12065 -0.2794)
			(end 0.12065 -0.2794)
			(stroke
				(width 0.1)
				(type default)
			)
			(layer "F.Fab")
		)
		(fp_line
			(start -0.12065 -0.305054)
			(end -0.12065 -0.2794)
			(stroke
				(width 0.1)
				(type default)
			)
			(layer "F.Fab")
		)
		(fp_line
			(start -0.67945 0.3048)
			(end -0.67945 -0.305054)
			(stroke
				(width 0.1)
				(type default)
			)
			(layer "F.Fab")
		)
		(fp_line
			(start -0.67945 -0.305054)
			(end -0.12065 -0.305054)
			(stroke
				(width 0.1)
				(type default)
			)
			(layer "F.Fab")
		)
		(pad "1" smd circle
			(at -0.40005 0 180)
			(size 0 0)
			(layers "F.Cu" "F.Mask" "F.Paste")
			(net "P12V_AUX")
		)
		(pad "2" smd circle
			(at 0.40005 0 180)
			(size 0 0)
			(layers "F.Cu" "F.Mask" "F.Paste")
			(net "GND")
		)
	)
	(footprint ""
		(layer "F.Cu")
		(at 124.210572 -63.652146 180)
		(property "Reference" "R5976"
			(at 0 0 180)
			(layer "F.SilkS")
			(hide yes)
			(effects
				(font
					(size 1.27 1.27)
				)
			)
		)
		(property "Value" ""
			(at 0 0 180)
			(layer "F.Fab")
			(effects
				(font
					(size 1.27 1.27)
				)
			)
		)
		(duplicate_pad_numbers_are_jumpers no)
		(fp_line
			(start 0.7874 0.4064)
			(end -0.7874 0.4064)
			(stroke
				(width 0.1524)
				(type default)
			)
			(layer "F.SilkS")
		)
		(fp_line
			(start 0.7874 -0.4064)
			(end 0.7874 0.4064)
			(stroke
				(width 0.1524)
				(type default)
			)
			(layer "F.SilkS")
		)
		(fp_line
			(start -0.7874 0.4064)
			(end -0.7874 -0.4064)
			(stroke
				(width 0.1524)
				(type default)
			)
			(layer "F.SilkS")
		)
		(fp_line
			(start -0.7874 -0.4064)
			(end 0.7874 -0.4064)
			(stroke
				(width 0.1524)
				(type default)
			)
			(layer "F.SilkS")
		)
		(fp_line
			(start 0.67945 0.3048)
			(end 0.120396 0.3048)
			(stroke
				(width 0.1)
				(type default)
			)
			(layer "F.Fab")
		)
		(fp_line
			(start 0.67945 -0.3048)
			(end 0.67945 0.3048)
			(stroke
				(width 0.1)
				(type default)
			)
			(layer "F.Fab")
		)
		(fp_line
			(start 0.12065 -0.2794)
			(end 0.12065 -0.3048)
			(stroke
				(width 0.1)
				(type default)
			)
			(layer "F.Fab")
		)
		(fp_line
			(start 0.12065 -0.3048)
			(end 0.67945 -0.3048)
			(stroke
				(width 0.1)
				(type default)
			)
			(layer "F.Fab")
		)
		(fp_line
			(start 0.120396 0.3048)
			(end 0.120396 0.2794)
			(stroke
				(width 0.1)
				(type default)
			)
			(layer "F.Fab")
		)
		(fp_line
			(start 0.120396 0.2794)
			(end -0.12065 0.2794)
			(stroke
				(width 0.1)
				(type default)
			)
			(layer "F.Fab")
		)
		(fp_line
			(start -0.12065 0.3048)
			(end -0.67945 0.3048)
			(stroke
				(width 0.1)
				(type default)
			)
			(layer "F.Fab")
		)
		(fp_line
			(start -0.12065 0.2794)
			(end -0.12065 0.3048)
			(stroke
				(width 0.1)
				(type default)
			)
			(layer "F.Fab")
		)
		(fp_line
			(start -0.12065 -0.2794)
			(end 0.12065 -0.2794)
			(stroke
				(width 0.1)
				(type default)
			)
			(layer "F.Fab")
		)
		(fp_line
			(start -0.12065 -0.305054)
			(end -0.12065 -0.2794)
			(stroke
				(width 0.1)
				(type default)
			)
			(layer "F.Fab")
		)
		(fp_line
			(start -0.67945 0.3048)
			(end -0.67945 -0.305054)
			(stroke
				(width 0.1)
				(type default)
			)
			(layer "F.Fab")
		)
		(fp_line
			(start -0.67945 -0.305054)
			(end -0.12065 -0.305054)
			(stroke
				(width 0.1)
				(type default)
			)
			(layer "F.Fab")
		)
		(pad "1" smd circle
			(at -0.40005 0 180)
			(size 0 0)
			(layers "F.Cu" "F.Mask" "F.Paste")
			(net "P5V_AUX")
		)
		(pad "2" smd circle
			(at 0.40005 0 180)
			(size 0 0)
			(layers "F.Cu" "F.Mask" "F.Paste")
			(net "P12V_SSD4_PG_G2")
		)
	)
	(footprint ""
		(layer "F.Cu")
		(at 226.727512 -231.416606 -90)
		(property "Reference" "R4540"
			(at 0 0 270)
			(layer "F.SilkS")
			(hide yes)
			(effects
				(font
					(size 1.27 1.27)
				)
			)
		)
		(property "Value" ""
			(at 0 0 270)
			(layer "F.Fab")
			(effects
				(font
					(size 1.27 1.27)
				)
			)
		)
		(duplicate_pad_numbers_are_jumpers no)
		(fp_line
			(start -0.7874 0.4064)
			(end -0.7874 -0.4064)
			(stroke
				(width 0.1524)
				(type default)
			)
			(layer "F.SilkS")
		)
		(fp_line
			(start 0.7874 0.4064)
			(end -0.7874 0.4064)
			(stroke
				(width 0.1524)
				(type default)
			)
			(layer "F.SilkS")
		)
		(fp_line
			(start -0.7874 -0.4064)
			(end 0.7874 -0.4064)
			(stroke
				(width 0.1524)
				(type default)
			)
			(layer "F.SilkS")
		)
		(fp_line
			(start 0.7874 -0.4064)
			(end 0.7874 0.4064)
			(stroke
				(width 0.1524)
				(type default)
			)
			(layer "F.SilkS")
		)
		(fp_line
			(start -0.67945 0.3048)
			(end -0.67945 -0.305054)
			(stroke
				(width 0.1)
				(type default)
			)
			(layer "F.Fab")
		)
		(fp_line
			(start -0.12065 0.3048)
			(end -0.67945 0.3048)
			(stroke
				(width 0.1)
				(type default)
			)
			(layer "F.Fab")
		)
		(fp_line
			(start 0.120396 0.3048)
			(end 0.120396 0.2794)
			(stroke
				(width 0.1)
				(type default)
			)
			(layer "F.Fab")
		)
		(fp_line
			(start 0.67945 0.3048)
			(end 0.120396 0.3048)
			(stroke
				(width 0.1)
				(type default)
			)
			(layer "F.Fab")
		)
		(fp_line
			(start -0.12065 0.2794)
			(end -0.12065 0.3048)
			(stroke
				(width 0.1)
				(type default)
			)
			(layer "F.Fab")
		)
		(fp_line
			(start 0.120396 0.2794)
			(end -0.12065 0.2794)
			(stroke
				(width 0.1)
				(type default)
			)
			(layer "F.Fab")
		)
		(fp_line
			(start -0.12065 -0.2794)
			(end 0.12065 -0.2794)
			(stroke
				(width 0.1)
				(type default)
			)
			(layer "F.Fab")
		)
		(fp_line
			(start 0.12065 -0.2794)
			(end 0.12065 -0.3048)
			(stroke
				(width 0.1)
				(type default)
			)
			(layer "F.Fab")
		)
		(fp_line
			(start 0.12065 -0.3048)
			(end 0.67945 -0.3048)
			(stroke
				(width 0.1)
				(type default)
			)
			(layer "F.Fab")
		)
		(fp_line
			(start 0.67945 -0.3048)
			(end 0.67945 0.3048)
			(stroke
				(width 0.1)
				(type default)
			)
			(layer "F.Fab")
		)
		(fp_line
			(start -0.67945 -0.305054)
			(end -0.12065 -0.305054)
			(stroke
				(width 0.1)
				(type default)
			)
			(layer "F.Fab")
		)
		(fp_line
			(start -0.12065 -0.305054)
			(end -0.12065 -0.2794)
			(stroke
				(width 0.1)
				(type default)
			)
			(layer "F.Fab")
		)
		(pad "1" smd circle
			(at -0.40005 0 270)
			(size 0 0)
			(layers "F.Cu" "F.Mask" "F.Paste")
			(net "NIC4_MAIN_PWR_BIC_EN_R")
		)
		(pad "2" smd circle
			(at 0.40005 0 270)
			(size 0 0)
			(layers "F.Cu" "F.Mask" "F.Paste")
			(net "NIC4_MAIN_PWR_BIC_EN")
		)
	)
	(footprint ""
		(layer "F.Cu")
		(at 103.80472 -10.545572 90)
		(property "Reference" "R1650"
			(at 0 0 90)
			(layer "F.SilkS")
			(hide yes)
			(effects
				(font
					(size 1.27 1.27)
				)
			)
		)
		(property "Value" ""
			(at 0 0 90)
			(layer "F.Fab")
			(effects
				(font
					(size 1.27 1.27)
				)
			)
		)
		(duplicate_pad_numbers_are_jumpers no)
		(fp_line
			(start 0.7874 -0.4064)
			(end 0.7874 0.4064)
			(stroke
				(width 0.1524)
				(type default)
			)
			(layer "F.SilkS")
		)
		(fp_line
			(start -0.7874 -0.4064)
			(end 0.7874 -0.4064)
			(stroke
				(width 0.1524)
				(type default)
			)
			(layer "F.SilkS")
		)
		(fp_line
			(start 0.7874 0.4064)
			(end -0.7874 0.4064)
			(stroke
				(width 0.1524)
				(type default)
			)
			(layer "F.SilkS")
		)
		(fp_line
			(start -0.7874 0.4064)
			(end -0.7874 -0.4064)
			(stroke
				(width 0.1524)
				(type default)
			)
			(layer "F.SilkS")
		)
		(fp_line
			(start -0.12065 -0.305054)
			(end -0.12065 -0.2794)
			(stroke
				(width 0.1)
				(type default)
			)
			(layer "F.Fab")
		)
		(fp_line
			(start -0.67945 -0.305054)
			(end -0.12065 -0.305054)
			(stroke
				(width 0.1)
				(type default)
			)
			(layer "F.Fab")
		)
		(fp_line
			(start 0.67945 -0.3048)
			(end 0.67945 0.3048)
			(stroke
				(width 0.1)
				(type default)
			)
			(layer "F.Fab")
		)
		(fp_line
			(start 0.12065 -0.3048)
			(end 0.67945 -0.3048)
			(stroke
				(width 0.1)
				(type default)
			)
			(layer "F.Fab")
		)
		(fp_line
			(start 0.12065 -0.2794)
			(end 0.12065 -0.3048)
			(stroke
				(width 0.1)
				(type default)
			)
			(layer "F.Fab")
		)
		(fp_line
			(start -0.12065 -0.2794)
			(end 0.12065 -0.2794)
			(stroke
				(width 0.1)
				(type default)
			)
			(layer "F.Fab")
		)
		(fp_line
			(start 0.120396 0.2794)
			(end -0.12065 0.2794)
			(stroke
				(width 0.1)
				(type default)
			)
			(layer "F.Fab")
		)
		(fp_line
			(start -0.12065 0.2794)
			(end -0.12065 0.3048)
			(stroke
				(width 0.1)
				(type default)
			)
			(layer "F.Fab")
		)
		(fp_line
			(start 0.67945 0.3048)
			(end 0.120396 0.3048)
			(stroke
				(width 0.1)
				(type default)
			)
			(layer "F.Fab")
		)
		(fp_line
			(start 0.120396 0.3048)
			(end 0.120396 0.2794)
			(stroke
				(width 0.1)
				(type default)
			)
			(layer "F.Fab")
		)
		(fp_line
			(start -0.12065 0.3048)
			(end -0.67945 0.3048)
			(stroke
				(width 0.1)
				(type default)
			)
			(layer "F.Fab")
		)
		(fp_line
			(start -0.67945 0.3048)
			(end -0.67945 -0.305054)
			(stroke
				(width 0.1)
				(type default)
			)
			(layer "F.Fab")
		)
		(pad "1" smd circle
			(at -0.40005 0 90)
			(size 0 0)
			(layers "F.Cu" "F.Mask" "F.Paste")
			(net "P3V3_SSD3")
		)
		(pad "2" smd circle
			(at 0.40005 0 90)
			(size 0 0)
			(layers "F.Cu" "F.Mask" "F.Paste")
			(net "SMB_ISO_SSD3_SDA")
		)
	)
	(footprint ""
		(layer "F.Cu")
		(at 149.387814 -301.220632)
		(property "Reference" "C3198"
			(at 0 0 0)
			(layer "F.SilkS")
			(hide yes)
			(effects
				(font
					(size 1.27 1.27)
				)
			)
		)
		(property "Value" ""
			(at 0 0 0)
			(layer "F.Fab")
			(effects
				(font
					(size 1.27 1.27)
				)
			)
		)
		(duplicate_pad_numbers_are_jumpers no)
		(fp_line
			(start -1.2954 -0.5842)
			(end 1.2954 -0.5842)
			(stroke
				(width 0.1524)
				(type default)
			)
			(layer "F.SilkS")
		)
		(fp_line
			(start -1.2954 0.5842)
			(end -1.2954 -0.5842)
			(stroke
				(width 0.1524)
				(type default)
			)
			(layer "F.SilkS")
		)
		(fp_line
			(start 1.2954 -0.5842)
			(end 1.2954 0.5842)
			(stroke
				(width 0.1524)
				(type default)
			)
			(layer "F.SilkS")
		)
		(fp_line
			(start 1.2954 0.5842)
			(end -1.2954 0.5842)
			(stroke
				(width 0.1524)
				(type default)
			)
			(layer "F.SilkS")
		)
		(fp_line
			(start -1.1938 -0.4064)
			(end -0.8636 -0.4064)
			(stroke
				(width 0.1)
				(type default)
			)
			(layer "F.Fab")
		)
		(fp_line
			(start -1.1938 0.4064)
			(end -1.1938 -0.4064)
			(stroke
				(width 0.1)
				(type default)
			)
			(layer "F.Fab")
		)
		(fp_line
			(start -0.8636 -0.4572)
			(end 0.8636 -0.4572)
			(stroke
				(width 0.1)
				(type default)
			)
			(layer "F.Fab")
		)
		(fp_line
			(start -0.8636 -0.4064)
			(end -0.8636 -0.4572)
			(stroke
				(width 0.1)
				(type default)
			)
			(layer "F.Fab")
		)
		(fp_line
			(start -0.8636 0.4064)
			(end -1.1938 0.4064)
			(stroke
				(width 0.1)
				(type default)
			)
			(layer "F.Fab")
		)
		(fp_line
			(start -0.8636 0.4572)
			(end -0.8636 0.4064)
			(stroke
				(width 0.1)
				(type default)
			)
			(layer "F.Fab")
		)
		(fp_line
			(start 0.8636 -0.4572)
			(end 0.8636 -0.4064)
			(stroke
				(width 0.1)
				(type default)
			)
			(layer "F.Fab")
		)
		(fp_line
			(start 0.8636 -0.4064)
			(end 1.1938 -0.4064)
			(stroke
				(width 0.1)
				(type default)
			)
			(layer "F.Fab")
		)
		(fp_line
			(start 0.8636 0.4064)
			(end 0.8636 0.4572)
			(stroke
				(width 0.1)
				(type default)
			)
			(layer "F.Fab")
		)
		(fp_line
			(start 0.8636 0.4572)
			(end -0.8636 0.4572)
			(stroke
				(width 0.1)
				(type default)
			)
			(layer "F.Fab")
		)
		(fp_line
			(start 1.1938 -0.4064)
			(end 1.1938 0.4064)
			(stroke
				(width 0.1)
				(type default)
			)
			(layer "F.Fab")
		)
		(fp_line
			(start 1.1938 0.4064)
			(end 0.8636 0.4064)
			(stroke
				(width 0.1)
				(type default)
			)
			(layer "F.Fab")
		)
		(pad "1" smd rect
			(at -0.7366 0 270)
			(size 0.7112 0.8128)
			(layers "F.Cu" "F.Mask" "F.Paste")
			(net "PCEPLL1_VDDA18_PEX1")
		)
		(pad "2" smd rect
			(at 0.7366 0 270)
			(size 0.7112 0.8128)
			(layers "F.Cu" "F.Mask" "F.Paste")
			(net "GND")
		)
	)
	(footprint ""
		(layer "F.Cu")
		(at 39.280592 -136.729724)
		(property "Reference" "C34"
			(at 0 0 0)
			(layer "F.SilkS")
			(hide yes)
			(effects
				(font
					(size 1.27 1.27)
				)
			)
		)
		(property "Value" ""
			(at 0 0 0)
			(layer "F.Fab")
			(effects
				(font
					(size 1.27 1.27)
				)
			)
		)
		(duplicate_pad_numbers_are_jumpers no)
		(fp_line
			(start -0.299974 -0.150114)
			(end 0.299974 -0.150114)
			(stroke
				(width 0.1)
				(type default)
			)
			(layer "F.Fab")
		)
		(fp_line
			(start -0.299974 0.150114)
			(end -0.299974 -0.150114)
			(stroke
				(width 0.1)
				(type default)
			)
			(layer "F.Fab")
		)
		(fp_line
			(start 0.299974 -0.150114)
			(end 0.299974 0.150114)
			(stroke
				(width 0.1)
				(type default)
			)
			(layer "F.Fab")
		)
		(fp_line
			(start 0.299974 0.150114)
			(end -0.299974 0.150114)
			(stroke
				(width 0.1)
				(type default)
			)
			(layer "F.Fab")
		)
		(pad "1" smd rect
			(at -0.2667 0)
			(size 0.3048 0.381)
			(layers "F.Cu" "F.Mask" "F.Paste")
			(net "P5E_PEX0_STN1_TX_DP<31>")
		)
		(pad "2" smd rect
			(at 0.2667 0)
			(size 0.3048 0.381)
			(layers "F.Cu" "F.Mask" "F.Paste")
			(net "P5E_PEX0_STN1_TX_C_DP<31>")
		)
	)
	(footprint ""
		(layer "F.Cu")
		(at 329.996038 -47.20082 90)
		(property "Reference" "C331"
			(at 0 0 90)
			(layer "F.SilkS")
			(hide yes)
			(effects
				(font
					(size 1.27 1.27)
				)
			)
		)
		(property "Value" ""
			(at 0 0 90)
			(layer "F.Fab")
			(effects
				(font
					(size 1.27 1.27)
				)
			)
		)
		(duplicate_pad_numbers_are_jumpers no)
		(fp_line
			(start 0.7874 -0.4064)
			(end 0.7874 0.4064)
			(stroke
				(width 0.1524)
				(type default)
			)
			(layer "F.SilkS")
		)
		(fp_line
			(start -0.7874 -0.4064)
			(end 0.7874 -0.4064)
			(stroke
				(width 0.1524)
				(type default)
			)
			(layer "F.SilkS")
		)
		(fp_line
			(start 0.7874 0.4064)
			(end -0.7874 0.4064)
			(stroke
				(width 0.1524)
				(type default)
			)
			(layer "F.SilkS")
		)
		(fp_line
			(start -0.7874 0.4064)
			(end -0.7874 -0.4064)
			(stroke
				(width 0.1524)
				(type default)
			)
			(layer "F.SilkS")
		)
		(fp_line
			(start -0.12065 -0.305054)
			(end -0.12065 -0.2794)
			(stroke
				(width 0.1)
				(type default)
			)
			(layer "F.Fab")
		)
		(fp_line
			(start -0.67945 -0.305054)
			(end -0.12065 -0.305054)
			(stroke
				(width 0.1)
				(type default)
			)
			(layer "F.Fab")
		)
		(fp_line
			(start 0.67945 -0.3048)
			(end 0.67945 0.3048)
			(stroke
				(width 0.1)
				(type default)
			)
			(layer "F.Fab")
		)
		(fp_line
			(start 0.12065 -0.3048)
			(end 0.67945 -0.3048)
			(stroke
				(width 0.1)
				(type default)
			)
			(layer "F.Fab")
		)
		(fp_line
			(start 0.12065 -0.2794)
			(end 0.12065 -0.3048)
			(stroke
				(width 0.1)
				(type default)
			)
			(layer "F.Fab")
		)
		(fp_line
			(start -0.12065 -0.2794)
			(end 0.12065 -0.2794)
			(stroke
				(width 0.1)
				(type default)
			)
			(layer "F.Fab")
		)
		(fp_line
			(start 0.120396 0.2794)
			(end -0.12065 0.2794)
			(stroke
				(width 0.1)
				(type default)
			)
			(layer "F.Fab")
		)
		(fp_line
			(start -0.12065 0.2794)
			(end -0.12065 0.3048)
			(stroke
				(width 0.1)
				(type default)
			)
			(layer "F.Fab")
		)
		(fp_line
			(start 0.67945 0.3048)
			(end 0.120396 0.3048)
			(stroke
				(width 0.1)
				(type default)
			)
			(layer "F.Fab")
		)
		(fp_line
			(start 0.120396 0.3048)
			(end 0.120396 0.2794)
			(stroke
				(width 0.1)
				(type default)
			)
			(layer "F.Fab")
		)
		(fp_line
			(start -0.12065 0.3048)
			(end -0.67945 0.3048)
			(stroke
				(width 0.1)
				(type default)
			)
			(layer "F.Fab")
		)
		(fp_line
			(start -0.67945 0.3048)
			(end -0.67945 -0.305054)
			(stroke
				(width 0.1)
				(type default)
			)
			(layer "F.Fab")
		)
		(pad "1" smd circle
			(at -0.40005 0 90)
			(size 0 0)
			(layers "F.Cu" "F.Mask" "F.Paste")
			(net "P12V_SSD11_R")
		)
		(pad "2" smd circle
			(at 0.40005 0 90)
			(size 0 0)
			(layers "F.Cu" "F.Mask" "F.Paste")
			(net "GND")
		)
	)
	(footprint ""
		(layer "F.Cu")
		(at 202.210416 -63.652146 180)
		(property "Reference" "R5987"
			(at 0 0 180)
			(layer "F.SilkS")
			(hide yes)
			(effects
				(font
					(size 1.27 1.27)
				)
			)
		)
		(property "Value" ""
			(at 0 0 180)
			(layer "F.Fab")
			(effects
				(font
					(size 1.27 1.27)
				)
			)
		)
		(duplicate_pad_numbers_are_jumpers no)
		(fp_line
			(start 0.7874 0.4064)
			(end -0.7874 0.4064)
			(stroke
				(width 0.1524)
				(type default)
			)
			(layer "F.SilkS")
		)
		(fp_line
			(start 0.7874 -0.4064)
			(end 0.7874 0.4064)
			(stroke
				(width 0.1524)
				(type default)
			)
			(layer "F.SilkS")
		)
		(fp_line
			(start -0.7874 0.4064)
			(end -0.7874 -0.4064)
			(stroke
				(width 0.1524)
				(type default)
			)
			(layer "F.SilkS")
		)
		(fp_line
			(start -0.7874 -0.4064)
			(end 0.7874 -0.4064)
			(stroke
				(width 0.1524)
				(type default)
			)
			(layer "F.SilkS")
		)
		(fp_line
			(start 0.67945 0.3048)
			(end 0.120396 0.3048)
			(stroke
				(width 0.1)
				(type default)
			)
			(layer "F.Fab")
		)
		(fp_line
			(start 0.67945 -0.3048)
			(end 0.67945 0.3048)
			(stroke
				(width 0.1)
				(type default)
			)
			(layer "F.Fab")
		)
		(fp_line
			(start 0.12065 -0.2794)
			(end 0.12065 -0.3048)
			(stroke
				(width 0.1)
				(type default)
			)
			(layer "F.Fab")
		)
		(fp_line
			(start 0.12065 -0.3048)
			(end 0.67945 -0.3048)
			(stroke
				(width 0.1)
				(type default)
			)
			(layer "F.Fab")
		)
		(fp_line
			(start 0.120396 0.3048)
			(end 0.120396 0.2794)
			(stroke
				(width 0.1)
				(type default)
			)
			(layer "F.Fab")
		)
		(fp_line
			(start 0.120396 0.2794)
			(end -0.12065 0.2794)
			(stroke
				(width 0.1)
				(type default)
			)
			(layer "F.Fab")
		)
		(fp_line
			(start -0.12065 0.3048)
			(end -0.67945 0.3048)
			(stroke
				(width 0.1)
				(type default)
			)
			(layer "F.Fab")
		)
		(fp_line
			(start -0.12065 0.2794)
			(end -0.12065 0.3048)
			(stroke
				(width 0.1)
				(type default)
			)
			(layer "F.Fab")
		)
		(fp_line
			(start -0.12065 -0.2794)
			(end 0.12065 -0.2794)
			(stroke
				(width 0.1)
				(type default)
			)
			(layer "F.Fab")
		)
		(fp_line
			(start -0.12065 -0.305054)
			(end -0.12065 -0.2794)
			(stroke
				(width 0.1)
				(type default)
			)
			(layer "F.Fab")
		)
		(fp_line
			(start -0.67945 0.3048)
			(end -0.67945 -0.305054)
			(stroke
				(width 0.1)
				(type default)
			)
			(layer "F.Fab")
		)
		(fp_line
			(start -0.67945 -0.305054)
			(end -0.12065 -0.305054)
			(stroke
				(width 0.1)
				(type default)
			)
			(layer "F.Fab")
		)
		(pad "1" smd circle
			(at -0.40005 0 180)
			(size 0 0)
			(layers "F.Cu" "F.Mask" "F.Paste")
			(net "P5V_AUX")
		)
		(pad "2" smd circle
			(at 0.40005 0 180)
			(size 0 0)
			(layers "F.Cu" "F.Mask" "F.Paste")
			(net "P12V_SSD7_PG_G2")
		)
	)
	(footprint ""
		(layer "F.Cu")
		(at 224.022158 -82.643472 180)
		(property "Reference" "R4351"
			(at 0 0 180)
			(layer "F.SilkS")
			(hide yes)
			(effects
				(font
					(size 1.27 1.27)
				)
			)
		)
		(property "Value" ""
			(at 0 0 180)
			(layer "F.Fab")
			(effects
				(font
					(size 1.27 1.27)
				)
			)
		)
		(duplicate_pad_numbers_are_jumpers no)
		(fp_line
			(start 0.7874 0.4064)
			(end -0.7874 0.4064)
			(stroke
				(width 0.1524)
				(type default)
			)
			(layer "F.SilkS")
		)
		(fp_line
			(start 0.7874 -0.4064)
			(end 0.7874 0.4064)
			(stroke
				(width 0.1524)
				(type default)
			)
			(layer "F.SilkS")
		)
		(fp_line
			(start -0.7874 0.4064)
			(end -0.7874 -0.4064)
			(stroke
				(width 0.1524)
				(type default)
			)
			(layer "F.SilkS")
		)
		(fp_line
			(start -0.7874 -0.4064)
			(end 0.7874 -0.4064)
			(stroke
				(width 0.1524)
				(type default)
			)
			(layer "F.SilkS")
		)
		(fp_line
			(start 0.67945 0.3048)
			(end 0.120396 0.3048)
			(stroke
				(width 0.1)
				(type default)
			)
			(layer "F.Fab")
		)
		(fp_line
			(start 0.67945 -0.3048)
			(end 0.67945 0.3048)
			(stroke
				(width 0.1)
				(type default)
			)
			(layer "F.Fab")
		)
		(fp_line
			(start 0.12065 -0.2794)
			(end 0.12065 -0.3048)
			(stroke
				(width 0.1)
				(type default)
			)
			(layer "F.Fab")
		)
		(fp_line
			(start 0.12065 -0.3048)
			(end 0.67945 -0.3048)
			(stroke
				(width 0.1)
				(type default)
			)
			(layer "F.Fab")
		)
		(fp_line
			(start 0.120396 0.3048)
			(end 0.120396 0.2794)
			(stroke
				(width 0.1)
				(type default)
			)
			(layer "F.Fab")
		)
		(fp_line
			(start 0.120396 0.2794)
			(end -0.12065 0.2794)
			(stroke
				(width 0.1)
				(type default)
			)
			(layer "F.Fab")
		)
		(fp_line
			(start -0.12065 0.3048)
			(end -0.67945 0.3048)
			(stroke
				(width 0.1)
				(type default)
			)
			(layer "F.Fab")
		)
		(fp_line
			(start -0.12065 0.2794)
			(end -0.12065 0.3048)
			(stroke
				(width 0.1)
				(type default)
			)
			(layer "F.Fab")
		)
		(fp_line
			(start -0.12065 -0.2794)
			(end 0.12065 -0.2794)
			(stroke
				(width 0.1)
				(type default)
			)
			(layer "F.Fab")
		)
		(fp_line
			(start -0.12065 -0.305054)
			(end -0.12065 -0.2794)
			(stroke
				(width 0.1)
				(type default)
			)
			(layer "F.Fab")
		)
		(fp_line
			(start -0.67945 0.3048)
			(end -0.67945 -0.305054)
			(stroke
				(width 0.1)
				(type default)
			)
			(layer "F.Fab")
		)
		(fp_line
			(start -0.67945 -0.305054)
			(end -0.12065 -0.305054)
			(stroke
				(width 0.1)
				(type default)
			)
			(layer "F.Fab")
		)
		(pad "1" smd circle
			(at -0.40005 0 180)
			(size 0 0)
			(layers "F.Cu" "F.Mask" "F.Paste")
			(net "P3V3_AUX")
		)
		(pad "2" smd circle
			(at 0.40005 0 180)
			(size 0 0)
			(layers "F.Cu" "F.Mask" "F.Paste")
			(net "SSD13_LED_R")
		)
	)
	(footprint ""
		(layer "F.Cu")
		(at 126.63043 -142.035276 180)
		(property "Reference" "PC623"
			(at 0 0 180)
			(layer "F.SilkS")
			(hide yes)
			(effects
				(font
					(size 1.27 1.27)
				)
			)
		)
		(property "Value" ""
			(at 0 0 180)
			(layer "F.Fab")
			(effects
				(font
					(size 1.27 1.27)
				)
			)
		)
		(duplicate_pad_numbers_are_jumpers no)
		(fp_line
			(start 1.524 0.762)
			(end -1.524 0.762)
			(stroke
				(width 0.1524)
				(type default)
			)
			(layer "F.SilkS")
		)
		(fp_line
			(start 1.524 -0.762)
			(end 1.524 0.762)
			(stroke
				(width 0.1524)
				(type default)
			)
			(layer "F.SilkS")
		)
		(fp_line
			(start -1.524 0.762)
			(end -1.524 -0.762)
			(stroke
				(width 0.1524)
				(type default)
			)
			(layer "F.SilkS")
		)
		(fp_line
			(start -1.524 -0.762)
			(end 1.524 -0.762)
			(stroke
				(width 0.1524)
				(type default)
			)
			(layer "F.SilkS")
		)
		(fp_line
			(start 1.1049 0.724916)
			(end 1.1049 -0.724916)
			(stroke
				(width 0.1)
				(type default)
			)
			(layer "F.Fab")
		)
		(fp_line
			(start 1.1049 -0.724916)
			(end -1.1049 -0.724916)
			(stroke
				(width 0.1)
				(type default)
			)
			(layer "F.Fab")
		)
		(fp_line
			(start -1.1049 0.724916)
			(end 1.1049 0.724916)
			(stroke
				(width 0.1)
				(type default)
			)
			(layer "F.Fab")
		)
		(fp_line
			(start -1.1049 -0.724916)
			(end -1.1049 0.724916)
			(stroke
				(width 0.1)
				(type default)
			)
			(layer "F.Fab")
		)
		(pad "1" smd rect
			(at -0.889 0)
			(size 1.016 1.27)
			(layers "F.Cu" "F.Mask" "F.Paste")
			(net "P12V_NIC2_R")
		)
		(pad "2" smd rect
			(at 0.889 0)
			(size 1.016 1.27)
			(layers "F.Cu" "F.Mask" "F.Paste")
			(net "GND")
		)
	)
	(footprint ""
		(layer "F.Cu")
		(at 411.047438 -86.424008)
		(property "Reference" "R6266"
			(at 0 0 0)
			(layer "F.SilkS")
			(hide yes)
			(effects
				(font
					(size 1.27 1.27)
				)
			)
		)
		(property "Value" ""
			(at 0 0 0)
			(layer "F.Fab")
			(effects
				(font
					(size 1.27 1.27)
				)
			)
		)
		(duplicate_pad_numbers_are_jumpers no)
		(fp_line
			(start -0.7874 -0.4064)
			(end 0.7874 -0.4064)
			(stroke
				(width 0.1524)
				(type default)
			)
			(layer "F.SilkS")
		)
		(fp_line
			(start -0.7874 0.4064)
			(end -0.7874 -0.4064)
			(stroke
				(width 0.1524)
				(type default)
			)
			(layer "F.SilkS")
		)
		(fp_line
			(start 0.7874 -0.4064)
			(end 0.7874 0.4064)
			(stroke
				(width 0.1524)
				(type default)
			)
			(layer "F.SilkS")
		)
		(fp_line
			(start 0.7874 0.4064)
			(end -0.7874 0.4064)
			(stroke
				(width 0.1524)
				(type default)
			)
			(layer "F.SilkS")
		)
		(fp_line
			(start -0.67945 -0.305054)
			(end -0.12065 -0.305054)
			(stroke
				(width 0.1)
				(type default)
			)
			(layer "F.Fab")
		)
		(fp_line
			(start -0.67945 0.3048)
			(end -0.67945 -0.305054)
			(stroke
				(width 0.1)
				(type default)
			)
			(layer "F.Fab")
		)
		(fp_line
			(start -0.12065 -0.305054)
			(end -0.12065 -0.2794)
			(stroke
				(width 0.1)
				(type default)
			)
			(layer "F.Fab")
		)
		(fp_line
			(start -0.12065 -0.2794)
			(end 0.12065 -0.2794)
			(stroke
				(width 0.1)
				(type default)
			)
			(layer "F.Fab")
		)
		(fp_line
			(start -0.12065 0.2794)
			(end -0.12065 0.3048)
			(stroke
				(width 0.1)
				(type default)
			)
			(layer "F.Fab")
		)
		(fp_line
			(start -0.12065 0.3048)
			(end -0.67945 0.3048)
			(stroke
				(width 0.1)
				(type default)
			)
			(layer "F.Fab")
		)
		(fp_line
			(start 0.120396 0.2794)
			(end -0.12065 0.2794)
			(stroke
				(width 0.1)
				(type default)
			)
			(layer "F.Fab")
		)
		(fp_line
			(start 0.120396 0.3048)
			(end 0.120396 0.2794)
			(stroke
				(width 0.1)
				(type default)
			)
			(layer "F.Fab")
		)
		(fp_line
			(start 0.12065 -0.3048)
			(end 0.67945 -0.3048)
			(stroke
				(width 0.1)
				(type default)
			)
			(layer "F.Fab")
		)
		(fp_line
			(start 0.12065 -0.2794)
			(end 0.12065 -0.3048)
			(stroke
				(width 0.1)
				(type default)
			)
			(layer "F.Fab")
		)
		(fp_line
			(start 0.67945 -0.3048)
			(end 0.67945 0.3048)
			(stroke
				(width 0.1)
				(type default)
			)
			(layer "F.Fab")
		)
		(fp_line
			(start 0.67945 0.3048)
			(end 0.120396 0.3048)
			(stroke
				(width 0.1)
				(type default)
			)
			(layer "F.Fab")
		)
		(pad "1" smd circle
			(at -0.40005 0)
			(size 0 0)
			(layers "F.Cu" "F.Mask" "F.Paste")
			(net "SMB_CLK_ISO_R_SCL_R1")
		)
		(pad "2" smd circle
			(at 0.40005 0)
			(size 0 0)
			(layers "F.Cu" "F.Mask" "F.Paste")
			(net "P3V3")
		)
	)
	(footprint ""
		(layer "F.Cu")
		(at 71.588122 -343.952322 90)
		(property "Reference" "C120"
			(at 0 0 90)
			(layer "F.SilkS")
			(hide yes)
			(effects
				(font
					(size 1.27 1.27)
				)
			)
		)
		(property "Value" ""
			(at 0 0 90)
			(layer "F.Fab")
			(effects
				(font
					(size 1.27 1.27)
				)
			)
		)
		(duplicate_pad_numbers_are_jumpers no)
		(fp_line
			(start 0.299974 -0.150114)
			(end 0.299974 0.150114)
			(stroke
				(width 0.1)
				(type default)
			)
			(layer "F.Fab")
		)
		(fp_line
			(start -0.299974 -0.150114)
			(end 0.299974 -0.150114)
			(stroke
				(width 0.1)
				(type default)
			)
			(layer "F.Fab")
		)
		(fp_line
			(start 0.299974 0.150114)
			(end -0.299974 0.150114)
			(stroke
				(width 0.1)
				(type default)
			)
			(layer "F.Fab")
		)
		(fp_line
			(start -0.299974 0.150114)
			(end -0.299974 -0.150114)
			(stroke
				(width 0.1)
				(type default)
			)
			(layer "F.Fab")
		)
		(pad "1" smd rect
			(at -0.2667 0 90)
			(size 0.3048 0.381)
			(layers "F.Cu" "F.Mask" "F.Paste")
			(net "P5E_PEX0_STN5_TX_DN<84>")
		)
		(pad "2" smd rect
			(at 0.2667 0 90)
			(size 0.3048 0.381)
			(layers "F.Cu" "F.Mask" "F.Paste")
			(net "P5E_PEX0_STN5_TX_C_DN<84>")
		)
	)
	(footprint ""
		(layer "F.Cu")
		(at 37.960808 -350.098614 90)
		(property "Reference" "C174"
			(at 0 0 90)
			(layer "F.SilkS")
			(hide yes)
			(effects
				(font
					(size 1.27 1.27)
				)
			)
		)
		(property "Value" ""
			(at 0 0 90)
			(layer "F.Fab")
			(effects
				(font
					(size 1.27 1.27)
				)
			)
		)
		(duplicate_pad_numbers_are_jumpers no)
		(fp_line
			(start 0.299974 -0.150114)
			(end 0.299974 0.150114)
			(stroke
				(width 0.1)
				(type default)
			)
			(layer "F.Fab")
		)
		(fp_line
			(start -0.299974 -0.150114)
			(end 0.299974 -0.150114)
			(stroke
				(width 0.1)
				(type default)
			)
			(layer "F.Fab")
		)
		(fp_line
			(start 0.299974 0.150114)
			(end -0.299974 0.150114)
			(stroke
				(width 0.1)
				(type default)
			)
			(layer "F.Fab")
		)
		(fp_line
			(start -0.299974 0.150114)
			(end -0.299974 -0.150114)
			(stroke
				(width 0.1)
				(type default)
			)
			(layer "F.Fab")
		)
		(pad "1" smd rect
			(at -0.2667 0 90)
			(size 0.3048 0.381)
			(layers "F.Cu" "F.Mask" "F.Paste")
			(net "P5E_PEX0_STN7_TX_DN<121>")
		)
		(pad "2" smd rect
			(at 0.2667 0 90)
			(size 0.3048 0.381)
			(layers "F.Cu" "F.Mask" "F.Paste")
			(net "P5E_PEX0_STN7_TX_C_DN<121>")
		)
	)
	(footprint ""
		(layer "F.Cu")
		(at 356.239318 -205.160118 90)
		(property "Reference" "R6419"
			(at 0 0 90)
			(layer "F.SilkS")
			(hide yes)
			(effects
				(font
					(size 1.27 1.27)
				)
			)
		)
		(property "Value" ""
			(at 0 0 90)
			(layer "F.Fab")
			(effects
				(font
					(size 1.27 1.27)
				)
			)
		)
		(duplicate_pad_numbers_are_jumpers no)
		(fp_line
			(start 0.7874 -0.4064)
			(end 0.7874 0.4064)
			(stroke
				(width 0.1524)
				(type default)
			)
			(layer "F.SilkS")
		)
		(fp_line
			(start -0.7874 -0.4064)
			(end 0.7874 -0.4064)
			(stroke
				(width 0.1524)
				(type default)
			)
			(layer "F.SilkS")
		)
		(fp_line
			(start 0.7874 0.4064)
			(end -0.7874 0.4064)
			(stroke
				(width 0.1524)
				(type default)
			)
			(layer "F.SilkS")
		)
		(fp_line
			(start -0.7874 0.4064)
			(end -0.7874 -0.4064)
			(stroke
				(width 0.1524)
				(type default)
			)
			(layer "F.SilkS")
		)
		(fp_line
			(start -0.12065 -0.305054)
			(end -0.12065 -0.2794)
			(stroke
				(width 0.1)
				(type default)
			)
			(layer "F.Fab")
		)
		(fp_line
			(start -0.67945 -0.305054)
			(end -0.12065 -0.305054)
			(stroke
				(width 0.1)
				(type default)
			)
			(layer "F.Fab")
		)
		(fp_line
			(start 0.67945 -0.3048)
			(end 0.67945 0.3048)
			(stroke
				(width 0.1)
				(type default)
			)
			(layer "F.Fab")
		)
		(fp_line
			(start 0.12065 -0.3048)
			(end 0.67945 -0.3048)
			(stroke
				(width 0.1)
				(type default)
			)
			(layer "F.Fab")
		)
		(fp_line
			(start 0.12065 -0.2794)
			(end 0.12065 -0.3048)
			(stroke
				(width 0.1)
				(type default)
			)
			(layer "F.Fab")
		)
		(fp_line
			(start -0.12065 -0.2794)
			(end 0.12065 -0.2794)
			(stroke
				(width 0.1)
				(type default)
			)
			(layer "F.Fab")
		)
		(fp_line
			(start 0.120396 0.2794)
			(end -0.12065 0.2794)
			(stroke
				(width 0.1)
				(type default)
			)
			(layer "F.Fab")
		)
		(fp_line
			(start -0.12065 0.2794)
			(end -0.12065 0.3048)
			(stroke
				(width 0.1)
				(type default)
			)
			(layer "F.Fab")
		)
		(fp_line
			(start 0.67945 0.3048)
			(end 0.120396 0.3048)
			(stroke
				(width 0.1)
				(type default)
			)
			(layer "F.Fab")
		)
		(fp_line
			(start 0.120396 0.3048)
			(end 0.120396 0.2794)
			(stroke
				(width 0.1)
				(type default)
			)
			(layer "F.Fab")
		)
		(fp_line
			(start -0.12065 0.3048)
			(end -0.67945 0.3048)
			(stroke
				(width 0.1)
				(type default)
			)
			(layer "F.Fab")
		)
		(fp_line
			(start -0.67945 0.3048)
			(end -0.67945 -0.305054)
			(stroke
				(width 0.1)
				(type default)
			)
			(layer "F.Fab")
		)
		(pad "1" smd circle
			(at -0.40005 0 90)
			(size 0 0)
			(layers "F.Cu" "F.Mask" "F.Paste")
			(net "FPGA_PEX1_MODE_SEL1_R")
		)
		(pad "2" smd circle
			(at 0.40005 0 90)
			(size 0 0)
			(layers "F.Cu" "F.Mask" "F.Paste")
			(net "FPGA_PEX1_MODE_SEL1")
		)
	)
	(footprint ""
		(layer "F.Cu")
		(at 381.254 -194.31)
		(property "Reference" "R4694"
			(at 0 0 0)
			(layer "F.SilkS")
			(hide yes)
			(effects
				(font
					(size 1.27 1.27)
				)
			)
		)
		(property "Value" ""
			(at 0 0 0)
			(layer "F.Fab")
			(effects
				(font
					(size 1.27 1.27)
				)
			)
		)
		(duplicate_pad_numbers_are_jumpers no)
		(fp_line
			(start -0.7874 -0.4064)
			(end 0.7874 -0.4064)
			(stroke
				(width 0.1524)
				(type default)
			)
			(layer "F.SilkS")
		)
		(fp_line
			(start -0.7874 0.4064)
			(end -0.7874 -0.4064)
			(stroke
				(width 0.1524)
				(type default)
			)
			(layer "F.SilkS")
		)
		(fp_line
			(start 0.7874 -0.4064)
			(end 0.7874 0.4064)
			(stroke
				(width 0.1524)
				(type default)
			)
			(layer "F.SilkS")
		)
		(fp_line
			(start 0.7874 0.4064)
			(end -0.7874 0.4064)
			(stroke
				(width 0.1524)
				(type default)
			)
			(layer "F.SilkS")
		)
		(fp_line
			(start -0.67945 -0.305054)
			(end -0.12065 -0.305054)
			(stroke
				(width 0.1)
				(type default)
			)
			(layer "F.Fab")
		)
		(fp_line
			(start -0.67945 0.3048)
			(end -0.67945 -0.305054)
			(stroke
				(width 0.1)
				(type default)
			)
			(layer "F.Fab")
		)
		(fp_line
			(start -0.12065 -0.305054)
			(end -0.12065 -0.2794)
			(stroke
				(width 0.1)
				(type default)
			)
			(layer "F.Fab")
		)
		(fp_line
			(start -0.12065 -0.2794)
			(end 0.12065 -0.2794)
			(stroke
				(width 0.1)
				(type default)
			)
			(layer "F.Fab")
		)
		(fp_line
			(start -0.12065 0.2794)
			(end -0.12065 0.3048)
			(stroke
				(width 0.1)
				(type default)
			)
			(layer "F.Fab")
		)
		(fp_line
			(start -0.12065 0.3048)
			(end -0.67945 0.3048)
			(stroke
				(width 0.1)
				(type default)
			)
			(layer "F.Fab")
		)
		(fp_line
			(start 0.120396 0.2794)
			(end -0.12065 0.2794)
			(stroke
				(width 0.1)
				(type default)
			)
			(layer "F.Fab")
		)
		(fp_line
			(start 0.120396 0.3048)
			(end 0.120396 0.2794)
			(stroke
				(width 0.1)
				(type default)
			)
			(layer "F.Fab")
		)
		(fp_line
			(start 0.12065 -0.3048)
			(end 0.67945 -0.3048)
			(stroke
				(width 0.1)
				(type default)
			)
			(layer "F.Fab")
		)
		(fp_line
			(start 0.12065 -0.2794)
			(end 0.12065 -0.3048)
			(stroke
				(width 0.1)
				(type default)
			)
			(layer "F.Fab")
		)
		(fp_line
			(start 0.67945 -0.3048)
			(end 0.67945 0.3048)
			(stroke
				(width 0.1)
				(type default)
			)
			(layer "F.Fab")
		)
		(fp_line
			(start 0.67945 0.3048)
			(end 0.120396 0.3048)
			(stroke
				(width 0.1)
				(type default)
			)
			(layer "F.Fab")
		)
		(pad "1" smd circle
			(at -0.40005 0)
			(size 0 0)
			(layers "F.Cu" "F.Mask" "F.Paste")
			(net "PRSNT_NIC2_FPGA_PCA9555_N")
		)
		(pad "2" smd circle
			(at 0.40005 0)
			(size 0 0)
			(layers "F.Cu" "F.Mask" "F.Paste")
			(net "PRSNT_NIC2_FPGA_R_N")
		)
	)
	(footprint ""
		(layer "F.Cu")
		(at 207.983074 -212.913214 90)
		(property "Reference" "R4892"
			(at 0 0 90)
			(layer "F.SilkS")
			(hide yes)
			(effects
				(font
					(size 1.27 1.27)
				)
			)
		)
		(property "Value" ""
			(at 0 0 90)
			(layer "F.Fab")
			(effects
				(font
					(size 1.27 1.27)
				)
			)
		)
		(duplicate_pad_numbers_are_jumpers no)
		(fp_line
			(start 0.7874 -0.4064)
			(end 0.7874 0.4064)
			(stroke
				(width 0.1524)
				(type default)
			)
			(layer "F.SilkS")
		)
		(fp_line
			(start -0.7874 -0.4064)
			(end 0.7874 -0.4064)
			(stroke
				(width 0.1524)
				(type default)
			)
			(layer "F.SilkS")
		)
		(fp_line
			(start 0.7874 0.4064)
			(end -0.7874 0.4064)
			(stroke
				(width 0.1524)
				(type default)
			)
			(layer "F.SilkS")
		)
		(fp_line
			(start -0.7874 0.4064)
			(end -0.7874 -0.4064)
			(stroke
				(width 0.1524)
				(type default)
			)
			(layer "F.SilkS")
		)
		(fp_line
			(start -0.12065 -0.305054)
			(end -0.12065 -0.2794)
			(stroke
				(width 0.1)
				(type default)
			)
			(layer "F.Fab")
		)
		(fp_line
			(start -0.67945 -0.305054)
			(end -0.12065 -0.305054)
			(stroke
				(width 0.1)
				(type default)
			)
			(layer "F.Fab")
		)
		(fp_line
			(start 0.67945 -0.3048)
			(end 0.67945 0.3048)
			(stroke
				(width 0.1)
				(type default)
			)
			(layer "F.Fab")
		)
		(fp_line
			(start 0.12065 -0.3048)
			(end 0.67945 -0.3048)
			(stroke
				(width 0.1)
				(type default)
			)
			(layer "F.Fab")
		)
		(fp_line
			(start 0.12065 -0.2794)
			(end 0.12065 -0.3048)
			(stroke
				(width 0.1)
				(type default)
			)
			(layer "F.Fab")
		)
		(fp_line
			(start -0.12065 -0.2794)
			(end 0.12065 -0.2794)
			(stroke
				(width 0.1)
				(type default)
			)
			(layer "F.Fab")
		)
		(fp_line
			(start 0.120396 0.2794)
			(end -0.12065 0.2794)
			(stroke
				(width 0.1)
				(type default)
			)
			(layer "F.Fab")
		)
		(fp_line
			(start -0.12065 0.2794)
			(end -0.12065 0.3048)
			(stroke
				(width 0.1)
				(type default)
			)
			(layer "F.Fab")
		)
		(fp_line
			(start 0.67945 0.3048)
			(end 0.120396 0.3048)
			(stroke
				(width 0.1)
				(type default)
			)
			(layer "F.Fab")
		)
		(fp_line
			(start 0.120396 0.3048)
			(end 0.120396 0.2794)
			(stroke
				(width 0.1)
				(type default)
			)
			(layer "F.Fab")
		)
		(fp_line
			(start -0.12065 0.3048)
			(end -0.67945 0.3048)
			(stroke
				(width 0.1)
				(type default)
			)
			(layer "F.Fab")
		)
		(fp_line
			(start -0.67945 0.3048)
			(end -0.67945 -0.305054)
			(stroke
				(width 0.1)
				(type default)
			)
			(layer "F.Fab")
		)
		(pad "1" smd circle
			(at -0.40005 0 90)
			(size 0 0)
			(layers "F.Cu" "F.Mask" "F.Paste")
			(net "UART_BIC_DEBUG_R_RX")
		)
		(pad "2" smd circle
			(at 0.40005 0 90)
			(size 0 0)
			(layers "F.Cu" "F.Mask" "F.Paste")
			(net "UART_BIC_DEBUG_RX")
		)
	)
	(footprint ""
		(layer "F.Cu")
		(at 49.656492 -17.419574 180)
		(property "Reference" "R1635"
			(at 0 0 180)
			(layer "F.SilkS")
			(hide yes)
			(effects
				(font
					(size 1.27 1.27)
				)
			)
		)
		(property "Value" ""
			(at 0 0 180)
			(layer "F.Fab")
			(effects
				(font
					(size 1.27 1.27)
				)
			)
		)
		(duplicate_pad_numbers_are_jumpers no)
		(fp_line
			(start 0.7874 0.4064)
			(end -0.7874 0.4064)
			(stroke
				(width 0.1524)
				(type default)
			)
			(layer "F.SilkS")
		)
		(fp_line
			(start 0.7874 -0.4064)
			(end 0.7874 0.4064)
			(stroke
				(width 0.1524)
				(type default)
			)
			(layer "F.SilkS")
		)
		(fp_line
			(start -0.7874 0.4064)
			(end -0.7874 -0.4064)
			(stroke
				(width 0.1524)
				(type default)
			)
			(layer "F.SilkS")
		)
		(fp_line
			(start -0.7874 -0.4064)
			(end 0.7874 -0.4064)
			(stroke
				(width 0.1524)
				(type default)
			)
			(layer "F.SilkS")
		)
		(fp_line
			(start 0.67945 0.3048)
			(end 0.120396 0.3048)
			(stroke
				(width 0.1)
				(type default)
			)
			(layer "F.Fab")
		)
		(fp_line
			(start 0.67945 -0.3048)
			(end 0.67945 0.3048)
			(stroke
				(width 0.1)
				(type default)
			)
			(layer "F.Fab")
		)
		(fp_line
			(start 0.12065 -0.2794)
			(end 0.12065 -0.3048)
			(stroke
				(width 0.1)
				(type default)
			)
			(layer "F.Fab")
		)
		(fp_line
			(start 0.12065 -0.3048)
			(end 0.67945 -0.3048)
			(stroke
				(width 0.1)
				(type default)
			)
			(layer "F.Fab")
		)
		(fp_line
			(start 0.120396 0.3048)
			(end 0.120396 0.2794)
			(stroke
				(width 0.1)
				(type default)
			)
			(layer "F.Fab")
		)
		(fp_line
			(start 0.120396 0.2794)
			(end -0.12065 0.2794)
			(stroke
				(width 0.1)
				(type default)
			)
			(layer "F.Fab")
		)
		(fp_line
			(start -0.12065 0.3048)
			(end -0.67945 0.3048)
			(stroke
				(width 0.1)
				(type default)
			)
			(layer "F.Fab")
		)
		(fp_line
			(start -0.12065 0.2794)
			(end -0.12065 0.3048)
			(stroke
				(width 0.1)
				(type default)
			)
			(layer "F.Fab")
		)
		(fp_line
			(start -0.12065 -0.2794)
			(end 0.12065 -0.2794)
			(stroke
				(width 0.1)
				(type default)
			)
			(layer "F.Fab")
		)
		(fp_line
			(start -0.12065 -0.305054)
			(end -0.12065 -0.2794)
			(stroke
				(width 0.1)
				(type default)
			)
			(layer "F.Fab")
		)
		(fp_line
			(start -0.67945 0.3048)
			(end -0.67945 -0.305054)
			(stroke
				(width 0.1)
				(type default)
			)
			(layer "F.Fab")
		)
		(fp_line
			(start -0.67945 -0.305054)
			(end -0.12065 -0.305054)
			(stroke
				(width 0.1)
				(type default)
			)
			(layer "F.Fab")
		)
		(pad "1" smd circle
			(at -0.40005 0 180)
			(size 0 0)
			(layers "F.Cu" "F.Mask" "F.Paste")
			(net "P3V3_SSD1")
		)
		(pad "2" smd circle
			(at 0.40005 0 180)
			(size 0 0)
			(layers "F.Cu" "F.Mask" "F.Paste")
			(net "SMB_ISO_SSD1_SCL")
		)
	)
	(footprint ""
		(layer "F.Cu")
		(at 215.69807 -235.765086 -90)
		(property "Reference" "R6318"
			(at 0 0 270)
			(layer "F.SilkS")
			(hide yes)
			(effects
				(font
					(size 1.27 1.27)
				)
			)
		)
		(property "Value" ""
			(at 0 0 270)
			(layer "F.Fab")
			(effects
				(font
					(size 1.27 1.27)
				)
			)
		)
		(duplicate_pad_numbers_are_jumpers no)
		(fp_line
			(start -0.7874 0.4064)
			(end -0.7874 -0.4064)
			(stroke
				(width 0.1524)
				(type default)
			)
			(layer "F.SilkS")
		)
		(fp_line
			(start 0.7874 0.4064)
			(end -0.7874 0.4064)
			(stroke
				(width 0.1524)
				(type default)
			)
			(layer "F.SilkS")
		)
		(fp_line
			(start -0.7874 -0.4064)
			(end 0.7874 -0.4064)
			(stroke
				(width 0.1524)
				(type default)
			)
			(layer "F.SilkS")
		)
		(fp_line
			(start 0.7874 -0.4064)
			(end 0.7874 0.4064)
			(stroke
				(width 0.1524)
				(type default)
			)
			(layer "F.SilkS")
		)
		(fp_line
			(start -0.67945 0.3048)
			(end -0.67945 -0.305054)
			(stroke
				(width 0.1)
				(type default)
			)
			(layer "F.Fab")
		)
		(fp_line
			(start -0.12065 0.3048)
			(end -0.67945 0.3048)
			(stroke
				(width 0.1)
				(type default)
			)
			(layer "F.Fab")
		)
		(fp_line
			(start 0.120396 0.3048)
			(end 0.120396 0.2794)
			(stroke
				(width 0.1)
				(type default)
			)
			(layer "F.Fab")
		)
		(fp_line
			(start 0.67945 0.3048)
			(end 0.120396 0.3048)
			(stroke
				(width 0.1)
				(type default)
			)
			(layer "F.Fab")
		)
		(fp_line
			(start -0.12065 0.2794)
			(end -0.12065 0.3048)
			(stroke
				(width 0.1)
				(type default)
			)
			(layer "F.Fab")
		)
		(fp_line
			(start 0.120396 0.2794)
			(end -0.12065 0.2794)
			(stroke
				(width 0.1)
				(type default)
			)
			(layer "F.Fab")
		)
		(fp_line
			(start -0.12065 -0.2794)
			(end 0.12065 -0.2794)
			(stroke
				(width 0.1)
				(type default)
			)
			(layer "F.Fab")
		)
		(fp_line
			(start 0.12065 -0.2794)
			(end 0.12065 -0.3048)
			(stroke
				(width 0.1)
				(type default)
			)
			(layer "F.Fab")
		)
		(fp_line
			(start 0.12065 -0.3048)
			(end 0.67945 -0.3048)
			(stroke
				(width 0.1)
				(type default)
			)
			(layer "F.Fab")
		)
		(fp_line
			(start 0.67945 -0.3048)
			(end 0.67945 0.3048)
			(stroke
				(width 0.1)
				(type default)
			)
			(layer "F.Fab")
		)
		(fp_line
			(start -0.67945 -0.305054)
			(end -0.12065 -0.305054)
			(stroke
				(width 0.1)
				(type default)
			)
			(layer "F.Fab")
		)
		(fp_line
			(start -0.12065 -0.305054)
			(end -0.12065 -0.2794)
			(stroke
				(width 0.1)
				(type default)
			)
			(layer "F.Fab")
		)
		(pad "1" smd circle
			(at -0.40005 0 270)
			(size 0 0)
			(layers "F.Cu" "F.Mask" "F.Paste")
			(net "SMB_PEX_LS_SDA")
		)
		(pad "2" smd circle
			(at 0.40005 0 270)
			(size 0 0)
			(layers "F.Cu" "F.Mask" "F.Paste")
			(net "SMB_PEX_MUX_SDA")
		)
	)
	(footprint ""
		(layer "F.Cu")
		(at 78.267814 -54.067456)
		(property "Reference" "PR217"
			(at 0 0 0)
			(layer "F.SilkS")
			(hide yes)
			(effects
				(font
					(size 1.27 1.27)
				)
			)
		)
		(property "Value" ""
			(at 0 0 0)
			(layer "F.Fab")
			(effects
				(font
					(size 1.27 1.27)
				)
			)
		)
		(duplicate_pad_numbers_are_jumpers no)
		(fp_line
			(start -0.7874 -0.4064)
			(end 0.7874 -0.4064)
			(stroke
				(width 0.1524)
				(type default)
			)
			(layer "F.SilkS")
		)
		(fp_line
			(start -0.7874 0.4064)
			(end -0.7874 -0.4064)
			(stroke
				(width 0.1524)
				(type default)
			)
			(layer "F.SilkS")
		)
		(fp_line
			(start 0.7874 -0.4064)
			(end 0.7874 0.4064)
			(stroke
				(width 0.1524)
				(type default)
			)
			(layer "F.SilkS")
		)
		(fp_line
			(start 0.7874 0.4064)
			(end -0.7874 0.4064)
			(stroke
				(width 0.1524)
				(type default)
			)
			(layer "F.SilkS")
		)
		(fp_line
			(start -0.67945 -0.305054)
			(end -0.12065 -0.305054)
			(stroke
				(width 0.1)
				(type default)
			)
			(layer "F.Fab")
		)
		(fp_line
			(start -0.67945 0.3048)
			(end -0.67945 -0.305054)
			(stroke
				(width 0.1)
				(type default)
			)
			(layer "F.Fab")
		)
		(fp_line
			(start -0.12065 -0.305054)
			(end -0.12065 -0.2794)
			(stroke
				(width 0.1)
				(type default)
			)
			(layer "F.Fab")
		)
		(fp_line
			(start -0.12065 -0.2794)
			(end 0.12065 -0.2794)
			(stroke
				(width 0.1)
				(type default)
			)
			(layer "F.Fab")
		)
		(fp_line
			(start -0.12065 0.2794)
			(end -0.12065 0.3048)
			(stroke
				(width 0.1)
				(type default)
			)
			(layer "F.Fab")
		)
		(fp_line
			(start -0.12065 0.3048)
			(end -0.67945 0.3048)
			(stroke
				(width 0.1)
				(type default)
			)
			(layer "F.Fab")
		)
		(fp_line
			(start 0.120396 0.2794)
			(end -0.12065 0.2794)
			(stroke
				(width 0.1)
				(type default)
			)
			(layer "F.Fab")
		)
		(fp_line
			(start 0.120396 0.3048)
			(end 0.120396 0.2794)
			(stroke
				(width 0.1)
				(type default)
			)
			(layer "F.Fab")
		)
		(fp_line
			(start 0.12065 -0.3048)
			(end 0.67945 -0.3048)
			(stroke
				(width 0.1)
				(type default)
			)
			(layer "F.Fab")
		)
		(fp_line
			(start 0.12065 -0.2794)
			(end 0.12065 -0.3048)
			(stroke
				(width 0.1)
				(type default)
			)
			(layer "F.Fab")
		)
		(fp_line
			(start 0.67945 -0.3048)
			(end 0.67945 0.3048)
			(stroke
				(width 0.1)
				(type default)
			)
			(layer "F.Fab")
		)
		(fp_line
			(start 0.67945 0.3048)
			(end 0.120396 0.3048)
			(stroke
				(width 0.1)
				(type default)
			)
			(layer "F.Fab")
		)
		(pad "1" smd circle
			(at -0.40005 0)
			(size 0 0)
			(layers "F.Cu" "F.Mask" "F.Paste")
			(net "P12V_SSD2_OCP")
		)
		(pad "2" smd circle
			(at 0.40005 0)
			(size 0 0)
			(layers "F.Cu" "F.Mask" "F.Paste")
			(net "GND")
		)
	)
	(footprint ""
		(layer "F.Cu")
		(at 155.064968 -26.785062 180)
		(property "Reference" "J35"
			(at 4.396994 -11.469878 90)
			(unlocked yes)
			(layer "F.SilkS")
			(effects
				(font
					(size 0.7874 0.5842)
					(thickness 0.1524)
				)
			)
		)
		(property "Value" ""
			(at 0 0 180)
			(layer "F.Fab")
			(effects
				(font
					(size 1.27 1.27)
				)
			)
		)
		(duplicate_pad_numbers_are_jumpers no)
		(fp_line
			(start 3.150108 12.115038)
			(end 1.529334 12.115038)
			(stroke
				(width 0.1524)
				(type default)
			)
			(layer "F.SilkS")
		)
		(fp_line
			(start 3.074924 12.014962)
			(end 1.632204 12.014962)
			(stroke
				(width 0.1524)
				(type default)
			)
			(layer "F.SilkS")
		)
		(fp_line
			(start 1.632204 -12.014962)
			(end 3.074924 -12.014962)
			(stroke
				(width 0.1524)
				(type default)
			)
			(layer "F.SilkS")
		)
		(fp_line
			(start 1.529334 -12.115038)
			(end 3.150108 -12.115038)
			(stroke
				(width 0.1524)
				(type default)
			)
			(layer "F.SilkS")
		)
		(fp_line
			(start -1.529334 12.115038)
			(end -3.150108 12.115038)
			(stroke
				(width 0.1524)
				(type default)
			)
			(layer "F.SilkS")
		)
		(fp_line
			(start -1.632204 12.014962)
			(end -3.074924 12.014962)
			(stroke
				(width 0.1524)
				(type default)
			)
			(layer "F.SilkS")
		)
		(fp_line
			(start -3.074924 -12.014962)
			(end -1.632204 -12.014962)
			(stroke
				(width 0.1524)
				(type default)
			)
			(layer "F.SilkS")
		)
		(fp_line
			(start -3.150108 -12.115038)
			(end -1.529334 -12.115038)
			(stroke
				(width 0.1524)
				(type default)
			)
			(layer "F.SilkS")
		)
		(fp_poly
			(pts
				(xy 3.34645 -8.762492) (xy 3.768852 -10.030206) (xy 4.61391 -9.185148)
			)
			(stroke
				(width 0)
				(type default)
			)
			(fill yes)
			(layer "F.SilkS")
		)
		(fp_line
			(start 3.074924 12.014962)
			(end -3.074924 12.014962)
			(stroke
				(width 0.1)
				(type default)
			)
			(layer "F.Fab")
		)
		(fp_line
			(start 3.074924 -12.014962)
			(end 3.074924 12.014962)
			(stroke
				(width 0.1)
				(type default)
			)
			(layer "F.Fab")
		)
		(fp_line
			(start -3.074924 12.014962)
			(end -3.074924 -12.014962)
			(stroke
				(width 0.1)
				(type default)
			)
			(layer "F.Fab")
		)
		(fp_line
			(start -3.074924 -12.014962)
			(end 3.074924 -12.014962)
			(stroke
				(width 0.1)
				(type default)
			)
			(layer "F.Fab")
		)
		(fp_poly
			(pts
				(xy 3.348736 -7.994904) (xy 4.543806 -8.592566) (xy 4.543806 -7.397496)
			)
			(stroke
				(width 0)
				(type default)
			)
			(fill yes)
			(layer "F.Fab")
		)
		(pad "" np_thru_hole circle
			(at -1.75006 -9.815068 90)
			(size 1.1176 1.1176)
			(drill 1.1176)
			(layers "*.Cu" "*.Mask")
			(clearance 0.381)
			(thermal_gap 0.381)
		)
		(pad "" np_thru_hole circle
			(at 0 9.815068 90)
			(size 1.1176 1.1176)
			(drill 1.1176)
			(layers "*.Cu" "*.Mask")
			(clearance 0.381)
			(thermal_gap 0.381)
		)
		(pad "A1" smd rect
			(at 2.29997 -7.994904 90)
			(size 0.381 1.27)
			(layers "F.Cu" "F.Mask" "F.Paste")
			(net "GND")
		)
		(pad "A2" smd rect
			(at 2.29997 -7.394956 90)
			(size 0.381 1.27)
			(layers "F.Cu" "F.Mask" "F.Paste")
			(net "GND")
		)
		(pad "A3" smd rect
			(at 2.29997 -6.795008 90)
			(size 0.381 1.27)
			(layers "F.Cu" "F.Mask" "F.Paste")
			(net "GND")
		)
		(pad "A4" smd rect
			(at 2.29997 -6.19506 90)
			(size 0.381 1.27)
			(layers "F.Cu" "F.Mask" "F.Paste")
			(net "GND")
		)
		(pad "A5" smd rect
			(at 2.29997 -5.595112 90)
			(size 0.381 1.27)
			(layers "F.Cu" "F.Mask" "F.Paste")
			(net "GND")
		)
		(pad "A6" smd rect
			(at 2.29997 -4.99491 90)
			(size 0.381 1.27)
			(layers "F.Cu" "F.Mask" "F.Paste")
			(net "GND")
		)
		(pad "A7" smd rect
			(at 2.29997 -4.394962 90)
			(size 0.381 1.27)
			(layers "F.Cu" "F.Mask" "F.Paste")
			(net "SMB_ISO_SSD5_R_SCL")
		)
		(pad "A8" smd rect
			(at 2.29997 -3.795014 90)
			(size 0.381 1.27)
			(layers "F.Cu" "F.Mask" "F.Paste")
			(net "SMB_ISO_SSD5_R_SDA")
		)
		(pad "A9" smd rect
			(at 2.29997 -3.195066 90)
			(size 0.381 1.27)
			(layers "F.Cu" "F.Mask" "F.Paste")
			(net "RST_SMB_SSD5_ISO_R_N")
		)
		(pad "A10" smd rect
			(at 2.29997 -2.595118 90)
			(size 0.381 1.27)
			(layers "F.Cu" "F.Mask" "F.Paste")
			(net "SSD5_LED_ISO_R_N")
		)
		(pad "A11" smd rect
			(at 2.29997 -1.994916 90)
			(size 0.381 1.27)
			(layers "F.Cu" "F.Mask" "F.Paste")
			(net "PU_CLKREQ5")
		)
		(pad "A12" smd rect
			(at 2.29997 -1.394968 90)
			(size 0.381 1.27)
			(layers "F.Cu" "F.Mask" "F.Paste")
			(net "PRSNT_SSD5_N")
		)
		(pad "A13" smd rect
			(at 2.29997 -0.79502 90)
			(size 0.381 1.27)
			(layers "F.Cu" "F.Mask" "F.Paste")
			(net "GND")
		)
		(pad "A14" smd rect
			(at 2.29997 -0.195072 90)
			(size 0.381 1.27)
			(layers "F.Cu" "F.Mask" "F.Paste")
			(net "Net_8519")
		)
		(pad "A15" smd rect
			(at 2.29997 0.404876 90)
			(size 0.381 1.27)
			(layers "F.Cu" "F.Mask" "F.Paste")
			(net "Net_8518")
		)
		(pad "A16" smd rect
			(at 2.29997 1.005078 90)
			(size 0.381 1.27)
			(layers "F.Cu" "F.Mask" "F.Paste")
			(net "GND")
		)
		(pad "A17" smd rect
			(at 2.29997 1.605026 90)
			(size 0.381 1.27)
			(layers "F.Cu" "F.Mask" "F.Paste")
			(net "P5E_PEX1_STN2_RX_DN<40>")
		)
		(pad "A18" smd rect
			(at 2.29997 2.204974 90)
			(size 0.381 1.27)
			(layers "F.Cu" "F.Mask" "F.Paste")
			(net "P5E_PEX1_STN2_RX_DP<40>")
		)
		(pad "A19" smd rect
			(at 2.29997 2.804922 90)
			(size 0.381 1.27)
			(layers "F.Cu" "F.Mask" "F.Paste")
			(net "GND")
		)
		(pad "A20" smd rect
			(at 2.29997 3.405124 90)
			(size 0.381 1.27)
			(layers "F.Cu" "F.Mask" "F.Paste")
			(net "P5E_PEX1_STN2_RX_DN<41>")
		)
		(pad "A21" smd rect
			(at 2.29997 4.005072 90)
			(size 0.381 1.27)
			(layers "F.Cu" "F.Mask" "F.Paste")
			(net "P5E_PEX1_STN2_RX_DP<41>")
		)
		(pad "A22" smd rect
			(at 2.29997 4.60502 90)
			(size 0.381 1.27)
			(layers "F.Cu" "F.Mask" "F.Paste")
			(net "GND")
		)
		(pad "A23" smd rect
			(at 2.29997 5.204968 90)
			(size 0.381 1.27)
			(layers "F.Cu" "F.Mask" "F.Paste")
			(net "P5E_PEX1_STN2_RX_DN<42>")
		)
		(pad "A24" smd rect
			(at 2.29997 5.804916 90)
			(size 0.381 1.27)
			(layers "F.Cu" "F.Mask" "F.Paste")
			(net "P5E_PEX1_STN2_RX_DP<42>")
		)
		(pad "A25" smd rect
			(at 2.29997 6.405118 90)
			(size 0.381 1.27)
			(layers "F.Cu" "F.Mask" "F.Paste")
			(net "GND")
		)
		(pad "A26" smd rect
			(at 2.29997 7.005066 90)
			(size 0.381 1.27)
			(layers "F.Cu" "F.Mask" "F.Paste")
			(net "P5E_PEX1_STN2_RX_DN<43>")
		)
		(pad "A27" smd rect
			(at 2.29997 7.605014 90)
			(size 0.381 1.27)
			(layers "F.Cu" "F.Mask" "F.Paste")
			(net "P5E_PEX1_STN2_RX_DP<43>")
		)
		(pad "A28" smd rect
			(at 2.29997 8.204962 90)
			(size 0.381 1.27)
			(layers "F.Cu" "F.Mask" "F.Paste")
			(net "GND")
		)
		(pad "B1" smd rect
			(at -2.29997 -7.994904 90)
			(size 0.381 1.27)
			(layers "F.Cu" "F.Mask" "F.Paste")
			(net "P12V_SSD5")
		)
		(pad "B2" smd rect
			(at -2.29997 -7.394956 90)
			(size 0.381 1.27)
			(layers "F.Cu" "F.Mask" "F.Paste")
			(net "P12V_SSD5")
		)
		(pad "B3" smd rect
			(at -2.29997 -6.795008 90)
			(size 0.381 1.27)
			(layers "F.Cu" "F.Mask" "F.Paste")
			(net "P12V_SSD5")
		)
		(pad "B4" smd rect
			(at -2.29997 -6.19506 90)
			(size 0.381 1.27)
			(layers "F.Cu" "F.Mask" "F.Paste")
			(net "P12V_SSD5")
		)
		(pad "B5" smd rect
			(at -2.29997 -5.595112 90)
			(size 0.381 1.27)
			(layers "F.Cu" "F.Mask" "F.Paste")
			(net "P12V_SSD5")
		)
		(pad "B6" smd rect
			(at -2.29997 -4.99491 90)
			(size 0.381 1.27)
			(layers "F.Cu" "F.Mask" "F.Paste")
			(net "P12V_SSD5")
		)
		(pad "B7" smd rect
			(at -2.29997 -4.394962 90)
			(size 0.381 1.27)
			(layers "F.Cu" "F.Mask" "F.Paste")
			(net "Net_8520")
		)
		(pad "B8" smd rect
			(at -2.29997 -3.795014 90)
			(size 0.381 1.27)
			(layers "F.Cu" "F.Mask" "F.Paste")
			(net "Net_8517")
		)
		(pad "B9" smd rect
			(at -2.29997 -3.195066 90)
			(size 0.381 1.27)
			(layers "F.Cu" "F.Mask" "F.Paste")
			(net "DUALPORT_N_SSD5")
		)
		(pad "B10" smd rect
			(at -2.29997 -2.595118 90)
			(size 0.381 1.27)
			(layers "F.Cu" "F.Mask" "F.Paste")
			(net "RST_SSD5_PERST_R_N")
		)
		(pad "B11" smd rect
			(at -2.29997 -1.994916 90)
			(size 0.381 1.27)
			(layers "F.Cu" "F.Mask" "F.Paste")
			(net "P3V3_SSD5")
		)
		(pad "B12" smd rect
			(at -2.29997 -1.394968 90)
			(size 0.381 1.27)
			(layers "F.Cu" "F.Mask" "F.Paste")
			(net "SSD5_PWRDIS_R")
		)
		(pad "B13" smd rect
			(at -2.29997 -0.79502 90)
			(size 0.381 1.27)
			(layers "F.Cu" "F.Mask" "F.Paste")
			(net "GND")
		)
		(pad "B14" smd rect
			(at -2.29997 -0.195072 90)
			(size 0.381 1.27)
			(layers "F.Cu" "F.Mask" "F.Paste")
			(net "CLK_100M_DB800ZL_SSD5_R_DN")
		)
		(pad "B15" smd rect
			(at -2.29997 0.404876 90)
			(size 0.381 1.27)
			(layers "F.Cu" "F.Mask" "F.Paste")
			(net "CLK_100M_DB800ZL_SSD5_R_DP")
		)
		(pad "B16" smd rect
			(at -2.29997 1.005078 90)
			(size 0.381 1.27)
			(layers "F.Cu" "F.Mask" "F.Paste")
			(net "GND")
		)
		(pad "B17" smd rect
			(at -2.29997 1.605026 90)
			(size 0.381 1.27)
			(layers "F.Cu" "F.Mask" "F.Paste")
			(net "P5E_PEX1_STN2_TX_C_DN<40>")
		)
		(pad "B18" smd rect
			(at -2.29997 2.204974 90)
			(size 0.381 1.27)
			(layers "F.Cu" "F.Mask" "F.Paste")
			(net "P5E_PEX1_STN2_TX_C_DP<40>")
		)
		(pad "B19" smd rect
			(at -2.29997 2.804922 90)
			(size 0.381 1.27)
			(layers "F.Cu" "F.Mask" "F.Paste")
			(net "GND")
		)
		(pad "B20" smd rect
			(at -2.29997 3.405124 90)
			(size 0.381 1.27)
			(layers "F.Cu" "F.Mask" "F.Paste")
			(net "P5E_PEX1_STN2_TX_C_DN<41>")
		)
		(pad "B21" smd rect
			(at -2.29997 4.005072 90)
			(size 0.381 1.27)
			(layers "F.Cu" "F.Mask" "F.Paste")
			(net "P5E_PEX1_STN2_TX_C_DP<41>")
		)
		(pad "B22" smd rect
			(at -2.29997 4.60502 90)
			(size 0.381 1.27)
			(layers "F.Cu" "F.Mask" "F.Paste")
			(net "GND")
		)
		(pad "B23" smd rect
			(at -2.29997 5.204968 90)
			(size 0.381 1.27)
			(layers "F.Cu" "F.Mask" "F.Paste")
			(net "P5E_PEX1_STN2_TX_C_DN<42>")
		)
		(pad "B24" smd rect
			(at -2.29997 5.804916 90)
			(size 0.381 1.27)
			(layers "F.Cu" "F.Mask" "F.Paste")
			(net "P5E_PEX1_STN2_TX_C_DP<42>")
		)
		(pad "B25" smd rect
			(at -2.29997 6.405118 90)
			(size 0.381 1.27)
			(layers "F.Cu" "F.Mask" "F.Paste")
			(net "GND")
		)
		(pad "B26" smd rect
			(at -2.29997 7.005066 90)
			(size 0.381 1.27)
			(layers "F.Cu" "F.Mask" "F.Paste")
			(net "P5E_PEX1_STN2_TX_C_DN<43>")
		)
		(pad "B27" smd rect
			(at -2.29997 7.605014 90)
			(size 0.381 1.27)
			(layers "F.Cu" "F.Mask" "F.Paste")
			(net "P5E_PEX1_STN2_TX_C_DP<43>")
		)
		(pad "B28" smd rect
			(at -2.29997 8.204962 90)
			(size 0.381 1.27)
			(layers "F.Cu" "F.Mask" "F.Paste")
			(net "GND")
		)
		(pad "G1" thru_hole oval
			(at 0 -11.364976 90)
			(size 1.6256 3.4798)
			(drill oval 1.1176 2.4638)
			(layers "*.Cu" "*.Mask")
			(remove_unused_layers no)
			(net "GND")
			(clearance 0.127)
			(thermal_gap 0.127)
		)
		(pad "G2" thru_hole oval
			(at 0 11.364976 90)
			(size 1.6256 3.4798)
			(drill oval 1.1176 2.4638)
			(layers "*.Cu" "*.Mask")
			(remove_unused_layers no)
			(net "GND")
			(clearance 0.127)
			(thermal_gap 0.127)
		)
		(zone
			(layer "F.Cu")
			(hatch none 0.5)
			(connect_pads
				(clearance 0)
			)
			(min_thickness 0.25)
			(keepout
				(tracks not_allowed)
				(vias allowed)
				(pads allowed)
				(copperpour not_allowed)
				(footprints allowed)
			)
			(placement
				(enabled no)
				(sheetname "")
			)
			(fill
				(thermal_gap 0.5)
				(thermal_bridge_width 0.5)
				(island_removal_mode 0)
			)
			(polygon
				(pts
					(xy 156.44495 -38.850062) (xy 153.694892 -38.850062) (xy 153.694892 -35.900106) (xy 156.44495 -35.900106)
				)
			)
		)
		(zone
			(layer "F.Cu")
			(hatch none 0.5)
			(connect_pads
				(clearance 0)
			)
			(min_thickness 0.25)
			(keepout
				(tracks not_allowed)
				(vias allowed)
				(pads allowed)
				(copperpour not_allowed)
				(footprints allowed)
			)
			(placement
				(enabled no)
				(sheetname "")
			)
			(fill
				(thermal_gap 0.5)
				(thermal_bridge_width 0.5)
				(island_removal_mode 0)
			)
			(polygon
				(pts
					(xy 157.515052 -17.670018) (xy 153.684986 -17.670018) (xy 153.684986 -14.720062) (xy 157.515052 -14.720062)
				)
			)
		)
		(zone
			(layers "F.Cu" "B.Cu" "In1.Cu" "In2.Cu" "In3.Cu" "In4.Cu" "In5.Cu" "In6.Cu"
				"In7.Cu" "In8.Cu" "In9.Cu" "In10.Cu" "In11.Cu" "In12.Cu" "In13.Cu" "In14.Cu"
				"In15.Cu" "In16.Cu"
			)
			(hatch none 0.5)
			(connect_pads
				(clearance 0)
			)
			(min_thickness 0.25)
			(keepout
				(tracks not_allowed)
				(vias allowed)
				(pads allowed)
				(copperpour not_allowed)
				(footprints allowed)
			)
			(placement
				(enabled no)
				(sheetname "")
			)
			(fill
				(thermal_gap 0.5)
				(thermal_bridge_width 0.5)
				(island_removal_mode 0)
			)
			(polygon
				(pts
					(arc
						(start 156.030168 -36.60013)
						(mid 154.099768 -36.60013)
						(end 156.030168 -36.60013)
					)
				)
			)
		)
		(zone
			(layers "F.Cu" "B.Cu" "In1.Cu" "In2.Cu" "In3.Cu" "In4.Cu" "In5.Cu" "In6.Cu"
				"In7.Cu" "In8.Cu" "In9.Cu" "In10.Cu" "In11.Cu" "In12.Cu" "In13.Cu" "In14.Cu"
				"In15.Cu" "In16.Cu"
			)
			(hatch none 0.5)
			(connect_pads
				(clearance 0)
			)
			(min_thickness 0.25)
			(keepout
				(tracks not_allowed)
				(vias allowed)
				(pads allowed)
				(copperpour not_allowed)
				(footprints allowed)
			)
			(placement
				(enabled no)
				(sheetname "")
			)
			(fill
				(thermal_gap 0.5)
				(thermal_bridge_width 0.5)
				(island_removal_mode 0)
			)
			(polygon
				(pts
					(arc
						(start 157.780228 -16.969994)
						(mid 155.849828 -16.969994)
						(end 157.780228 -16.969994)
					)
				)
			)
		)
	)
	(footprint ""
		(layer "F.Cu")
		(at 392.9253 -356.244906 90)
		(property "Reference" "C754"
			(at 0 0 90)
			(layer "F.SilkS")
			(hide yes)
			(effects
				(font
					(size 1.27 1.27)
				)
			)
		)
		(property "Value" ""
			(at 0 0 90)
			(layer "F.Fab")
			(effects
				(font
					(size 1.27 1.27)
				)
			)
		)
		(duplicate_pad_numbers_are_jumpers no)
		(fp_line
			(start 0.299974 -0.150114)
			(end 0.299974 0.150114)
			(stroke
				(width 0.1)
				(type default)
			)
			(layer "F.Fab")
		)
		(fp_line
			(start -0.299974 -0.150114)
			(end 0.299974 -0.150114)
			(stroke
				(width 0.1)
				(type default)
			)
			(layer "F.Fab")
		)
		(fp_line
			(start 0.299974 0.150114)
			(end -0.299974 0.150114)
			(stroke
				(width 0.1)
				(type default)
			)
			(layer "F.Fab")
		)
		(fp_line
			(start -0.299974 0.150114)
			(end -0.299974 -0.150114)
			(stroke
				(width 0.1)
				(type default)
			)
			(layer "F.Fab")
		)
		(pad "1" smd rect
			(at -0.2667 0 90)
			(size 0.3048 0.381)
			(layers "F.Cu" "F.Mask" "F.Paste")
			(net "P5E_PEX3_STN5_TX_DP<83>")
		)
		(pad "2" smd rect
			(at 0.2667 0 90)
			(size 0.3048 0.381)
			(layers "F.Cu" "F.Mask" "F.Paste")
			(net "P5E_PEX3_STN5_TX_C_DP<83>")
		)
	)
	(footprint ""
		(layer "F.Cu")
		(at 284.443678 -42.84091)
		(property "Reference" "R604"
			(at 0 0 0)
			(layer "F.SilkS")
			(hide yes)
			(effects
				(font
					(size 1.27 1.27)
				)
			)
		)
		(property "Value" ""
			(at 0 0 0)
			(layer "F.Fab")
			(effects
				(font
					(size 1.27 1.27)
				)
			)
		)
		(duplicate_pad_numbers_are_jumpers no)
		(fp_line
			(start -0.7874 -0.4064)
			(end 0.7874 -0.4064)
			(stroke
				(width 0.1524)
				(type default)
			)
			(layer "F.SilkS")
		)
		(fp_line
			(start -0.7874 0.4064)
			(end -0.7874 -0.4064)
			(stroke
				(width 0.1524)
				(type default)
			)
			(layer "F.SilkS")
		)
		(fp_line
			(start 0.7874 -0.4064)
			(end 0.7874 0.4064)
			(stroke
				(width 0.1524)
				(type default)
			)
			(layer "F.SilkS")
		)
		(fp_line
			(start 0.7874 0.4064)
			(end -0.7874 0.4064)
			(stroke
				(width 0.1524)
				(type default)
			)
			(layer "F.SilkS")
		)
		(fp_line
			(start -0.67945 -0.305054)
			(end -0.12065 -0.305054)
			(stroke
				(width 0.1)
				(type default)
			)
			(layer "F.Fab")
		)
		(fp_line
			(start -0.67945 0.3048)
			(end -0.67945 -0.305054)
			(stroke
				(width 0.1)
				(type default)
			)
			(layer "F.Fab")
		)
		(fp_line
			(start -0.12065 -0.305054)
			(end -0.12065 -0.2794)
			(stroke
				(width 0.1)
				(type default)
			)
			(layer "F.Fab")
		)
		(fp_line
			(start -0.12065 -0.2794)
			(end 0.12065 -0.2794)
			(stroke
				(width 0.1)
				(type default)
			)
			(layer "F.Fab")
		)
		(fp_line
			(start -0.12065 0.2794)
			(end -0.12065 0.3048)
			(stroke
				(width 0.1)
				(type default)
			)
			(layer "F.Fab")
		)
		(fp_line
			(start -0.12065 0.3048)
			(end -0.67945 0.3048)
			(stroke
				(width 0.1)
				(type default)
			)
			(layer "F.Fab")
		)
		(fp_line
			(start 0.120396 0.2794)
			(end -0.12065 0.2794)
			(stroke
				(width 0.1)
				(type default)
			)
			(layer "F.Fab")
		)
		(fp_line
			(start 0.120396 0.3048)
			(end 0.120396 0.2794)
			(stroke
				(width 0.1)
				(type default)
			)
			(layer "F.Fab")
		)
		(fp_line
			(start 0.12065 -0.3048)
			(end 0.67945 -0.3048)
			(stroke
				(width 0.1)
				(type default)
			)
			(layer "F.Fab")
		)
		(fp_line
			(start 0.12065 -0.2794)
			(end 0.12065 -0.3048)
			(stroke
				(width 0.1)
				(type default)
			)
			(layer "F.Fab")
		)
		(fp_line
			(start 0.67945 -0.3048)
			(end 0.67945 0.3048)
			(stroke
				(width 0.1)
				(type default)
			)
			(layer "F.Fab")
		)
		(fp_line
			(start 0.67945 0.3048)
			(end 0.120396 0.3048)
			(stroke
				(width 0.1)
				(type default)
			)
			(layer "F.Fab")
		)
		(pad "1" smd circle
			(at -0.40005 0)
			(size 0 0)
			(layers "F.Cu" "F.Mask" "F.Paste")
			(net "SSD9_ADC_A1")
		)
		(pad "2" smd circle
			(at 0.40005 0)
			(size 0 0)
			(layers "F.Cu" "F.Mask" "F.Paste")
			(net "P3V3_AUX")
		)
	)
	(footprint ""
		(layer "F.Cu")
		(at 205.749652 -320.900044)
		(property "Reference" "H84"
			(at -7.150608 -7.090664 0)
			(unlocked yes)
			(layer "F.SilkS")
			(effects
				(font
					(size 0.7874 0.5842)
					(thickness 0.1524)
				)
				(justify left)
			)
		)
		(property "Value" ""
			(at 0 0 0)
			(layer "F.Fab")
			(effects
				(font
					(size 1.27 1.27)
				)
			)
		)
		(duplicate_pad_numbers_are_jumpers no)
		(fp_arc
			(start -7.962138 -0.77724)
			(mid -2.032459 -7.737232)
			(end 6.552184 -4.58978)
			(stroke
				(width 0.1524)
				(type default)
			)
			(layer "F.SilkS")
		)
		(fp_arc
			(start 7.999984 0)
			(mid 3.047385 7.396948)
			(end -5.678424 5.635244)
			(stroke
				(width 0.1524)
				(type default)
			)
			(layer "F.SilkS")
		)
		(fp_arc
			(start -7.981442 0.544068)
			(mid -0.272184 -7.995347)
			(end 7.999984 0)
			(stroke
				(width 0.1524)
				(type default)
			)
			(layer "B.SilkS")
		)
		(fp_arc
			(start 7.999984 0)
			(mid 3.266595 7.302491)
			(end -5.332222 5.963666)
			(stroke
				(width 0.1524)
				(type default)
			)
			(layer "B.SilkS")
		)
		(fp_circle
			(center 0 0)
			(end 7.999984 0)
			(stroke
				(width 0.1)
				(type default)
			)
			(fill no)
			(layer "B.Fab")
		)
		(fp_circle
			(center 0 0)
			(end 7.999984 0)
			(stroke
				(width 0.1)
				(type default)
			)
			(fill no)
			(layer "F.Fab")
		)
		(pad "" np_thru_hole circle
			(at 0 0)
			(size 4.5212 4.5212)
			(drill 4.5212)
			(layers "*.Cu" "*.Mask")
			(clearance 0.381)
			(thermal_gap 0.381)
		)
		(pad "2" thru_hole circle
			(at 3.6322 0)
			(size 0.762 0.762)
			(drill 0.5588)
			(layers "*.Cu" "*.Mask")
			(remove_unused_layers no)
			(net "GND")
			(clearance 0.1524)
			(thermal_gap 0.1524)
		)
		(pad "3" thru_hole circle
			(at 2.568448 -2.568448)
			(size 0.762 0.762)
			(drill 0.5588)
			(layers "*.Cu" "*.Mask")
			(remove_unused_layers no)
			(net "GND")
			(clearance 0.1524)
			(thermal_gap 0.1524)
		)
		(pad "4" thru_hole circle
			(at 0 -3.6322)
			(size 0.762 0.762)
			(drill 0.5588)
			(layers "*.Cu" "*.Mask")
			(remove_unused_layers no)
			(net "GND")
			(clearance 0.1524)
			(thermal_gap 0.1524)
		)
		(pad "5" thru_hole circle
			(at -2.568448 -2.568448)
			(size 0.762 0.762)
			(drill 0.5588)
			(layers "*.Cu" "*.Mask")
			(remove_unused_layers no)
			(net "GND")
			(clearance 0.1524)
			(thermal_gap 0.1524)
		)
		(pad "6" thru_hole circle
			(at -3.6322 0)
			(size 0.762 0.762)
			(drill 0.5588)
			(layers "*.Cu" "*.Mask")
			(remove_unused_layers no)
			(net "GND")
			(clearance 0.1524)
			(thermal_gap 0.1524)
		)
		(pad "7" thru_hole circle
			(at -2.568448 2.568448)
			(size 0.762 0.762)
			(drill 0.5588)
			(layers "*.Cu" "*.Mask")
			(remove_unused_layers no)
			(net "GND")
			(clearance 0.1524)
			(thermal_gap 0.1524)
		)
		(pad "8" thru_hole circle
			(at 0 3.6322)
			(size 0.762 0.762)
			(drill 0.5588)
			(layers "*.Cu" "*.Mask")
			(remove_unused_layers no)
			(net "GND")
			(clearance 0.1524)
			(thermal_gap 0.1524)
		)
		(pad "9" thru_hole circle
			(at 2.568448 2.568448)
			(size 0.762 0.762)
			(drill 0.5588)
			(layers "*.Cu" "*.Mask")
			(remove_unused_layers no)
			(net "GND")
			(clearance 0.1524)
			(thermal_gap 0.1524)
		)
		(zone
			(layer "F.Cu")
			(hatch none 0.5)
			(connect_pads
				(clearance 0)
			)
			(min_thickness 0.25)
			(keepout
				(tracks not_allowed)
				(vias allowed)
				(pads allowed)
				(copperpour not_allowed)
				(footprints allowed)
			)
			(placement
				(enabled no)
				(sheetname "")
			)
			(fill
				(thermal_gap 0.5)
				(thermal_bridge_width 0.5)
				(island_removal_mode 0)
			)
			(polygon
				(pts
					(arc
						(start 205.749652 -312.90006)
						(mid 197.749668 -320.900044)
						(end 205.749652 -328.900028)
					)
					(arc
						(start 205.749652 -325.649844)
						(mid 200.999852 -320.900044)
						(end 205.749652 -316.150244)
					)
				)
			)
		)
		(zone
			(layer "F.Cu")
			(hatch none 0.5)
			(connect_pads
				(clearance 0)
			)
			(min_thickness 0.25)
			(keepout
				(tracks not_allowed)
				(vias allowed)
				(pads allowed)
				(copperpour not_allowed)
				(footprints allowed)
			)
			(placement
				(enabled no)
				(sheetname "")
			)
			(fill
				(thermal_gap 0.5)
				(thermal_bridge_width 0.5)
				(island_removal_mode 0)
			)
			(polygon
				(pts
					(arc
						(start 205.749652 -312.90006)
						(mid 213.749636 -320.900044)
						(end 205.749652 -328.900028)
					)
					(arc
						(start 205.749652 -325.649844)
						(mid 210.499452 -320.900044)
						(end 205.749652 -316.150244)
					)
				)
			)
		)
		(zone
			(layers "F.Cu" "B.Cu" "In1.Cu" "In2.Cu" "In3.Cu" "In4.Cu" "In5.Cu" "In6.Cu"
				"In7.Cu" "In8.Cu" "In9.Cu" "In10.Cu" "In11.Cu" "In12.Cu" "In13.Cu" "In14.Cu"
				"In15.Cu" "In16.Cu"
			)
			(hatch none 0.5)
			(connect_pads
				(clearance 0)
			)
			(min_thickness 0.25)
			(keepout
				(tracks not_allowed)
				(vias allowed)
				(pads allowed)
				(copperpour not_allowed)
				(footprints allowed)
			)
			(placement
				(enabled no)
				(sheetname "")
			)
			(fill
				(thermal_gap 0.5)
				(thermal_bridge_width 0.5)
				(island_removal_mode 0)
			)
			(polygon
				(pts
					(arc
						(start 208.515712 -320.900044)
						(mid 202.983592 -320.900044)
						(end 208.515712 -320.900044)
					)
				)
			)
		)
		(zone
			(layer "B.Cu")
			(hatch none 0.5)
			(connect_pads
				(clearance 0)
			)
			(min_thickness 0.25)
			(keepout
				(tracks not_allowed)
				(vias allowed)
				(pads allowed)
				(copperpour not_allowed)
				(footprints allowed)
			)
			(placement
				(enabled no)
				(sheetname "")
			)
			(fill
				(thermal_gap 0.5)
				(thermal_bridge_width 0.5)
				(island_removal_mode 0)
			)
			(polygon
				(pts
					(arc
						(start 205.749652 -315.896244)
						(mid 200.745852 -320.900044)
						(end 205.749652 -325.903844)
					)
					(arc
						(start 205.749652 -325.421244)
						(mid 201.228452 -320.900044)
						(end 205.749652 -316.378844)
					)
				)
			)
		)
		(zone
			(layer "B.Cu")
			(hatch none 0.5)
			(connect_pads
				(clearance 0)
			)
			(min_thickness 0.25)
			(keepout
				(tracks not_allowed)
				(vias allowed)
				(pads allowed)
				(copperpour not_allowed)
				(footprints allowed)
			)
			(placement
				(enabled no)
				(sheetname "")
			)
			(fill
				(thermal_gap 0.5)
				(thermal_bridge_width 0.5)
				(island_removal_mode 0)
			)
			(polygon
				(pts
					(arc
						(start 205.749652 -315.896244)
						(mid 210.753452 -320.900044)
						(end 205.749652 -325.903844)
					)
					(arc
						(start 205.749652 -325.421244)
						(mid 210.270852 -320.900044)
						(end 205.749652 -316.378844)
					)
				)
			)
		)
	)
	(footprint ""
		(layer "F.Cu")
		(at 214.310976 -371.337586)
		(property "Reference" "PR28"
			(at 0 0 0)
			(layer "F.SilkS")
			(hide yes)
			(effects
				(font
					(size 1.27 1.27)
				)
			)
		)
		(property "Value" ""
			(at 0 0 0)
			(layer "F.Fab")
			(effects
				(font
					(size 1.27 1.27)
				)
			)
		)
		(duplicate_pad_numbers_are_jumpers no)
		(fp_line
			(start -0.7874 -0.4064)
			(end 0.7874 -0.4064)
			(stroke
				(width 0.1524)
				(type default)
			)
			(layer "F.SilkS")
		)
		(fp_line
			(start -0.7874 0.4064)
			(end -0.7874 -0.4064)
			(stroke
				(width 0.1524)
				(type default)
			)
			(layer "F.SilkS")
		)
		(fp_line
			(start 0.7874 -0.4064)
			(end 0.7874 0.4064)
			(stroke
				(width 0.1524)
				(type default)
			)
			(layer "F.SilkS")
		)
		(fp_line
			(start 0.7874 0.4064)
			(end -0.7874 0.4064)
			(stroke
				(width 0.1524)
				(type default)
			)
			(layer "F.SilkS")
		)
		(fp_line
			(start -0.67945 -0.305054)
			(end -0.12065 -0.305054)
			(stroke
				(width 0.1)
				(type default)
			)
			(layer "F.Fab")
		)
		(fp_line
			(start -0.67945 0.3048)
			(end -0.67945 -0.305054)
			(stroke
				(width 0.1)
				(type default)
			)
			(layer "F.Fab")
		)
		(fp_line
			(start -0.12065 -0.305054)
			(end -0.12065 -0.2794)
			(stroke
				(width 0.1)
				(type default)
			)
			(layer "F.Fab")
		)
		(fp_line
			(start -0.12065 -0.2794)
			(end 0.12065 -0.2794)
			(stroke
				(width 0.1)
				(type default)
			)
			(layer "F.Fab")
		)
		(fp_line
			(start -0.12065 0.2794)
			(end -0.12065 0.3048)
			(stroke
				(width 0.1)
				(type default)
			)
			(layer "F.Fab")
		)
		(fp_line
			(start -0.12065 0.3048)
			(end -0.67945 0.3048)
			(stroke
				(width 0.1)
				(type default)
			)
			(layer "F.Fab")
		)
		(fp_line
			(start 0.120396 0.2794)
			(end -0.12065 0.2794)
			(stroke
				(width 0.1)
				(type default)
			)
			(layer "F.Fab")
		)
		(fp_line
			(start 0.120396 0.3048)
			(end 0.120396 0.2794)
			(stroke
				(width 0.1)
				(type default)
			)
			(layer "F.Fab")
		)
		(fp_line
			(start 0.12065 -0.3048)
			(end 0.67945 -0.3048)
			(stroke
				(width 0.1)
				(type default)
			)
			(layer "F.Fab")
		)
		(fp_line
			(start 0.12065 -0.2794)
			(end 0.12065 -0.3048)
			(stroke
				(width 0.1)
				(type default)
			)
			(layer "F.Fab")
		)
		(fp_line
			(start 0.67945 -0.3048)
			(end 0.67945 0.3048)
			(stroke
				(width 0.1)
				(type default)
			)
			(layer "F.Fab")
		)
		(fp_line
			(start 0.67945 0.3048)
			(end 0.120396 0.3048)
			(stroke
				(width 0.1)
				(type default)
			)
			(layer "F.Fab")
		)
		(pad "1" smd circle
			(at -0.40005 0)
			(size 0 0)
			(layers "F.Cu" "F.Mask" "F.Paste")
			(net "HSC_SCREF")
		)
		(pad "2" smd circle
			(at 0.40005 0)
			(size 0 0)
			(layers "F.Cu" "F.Mask" "F.Paste")
			(net "HSC_SCREF_1")
		)
	)
	(footprint ""
		(layer "F.Cu")
		(at 251.671582 -25.342342 -90)
		(property "Reference" "R433"
			(at 0 0 270)
			(layer "F.SilkS")
			(hide yes)
			(effects
				(font
					(size 1.27 1.27)
				)
			)
		)
		(property "Value" ""
			(at 0 0 270)
			(layer "F.Fab")
			(effects
				(font
					(size 1.27 1.27)
				)
			)
		)
		(duplicate_pad_numbers_are_jumpers no)
		(fp_line
			(start -0.7874 0.4064)
			(end -0.7874 -0.4064)
			(stroke
				(width 0.1524)
				(type default)
			)
			(layer "F.SilkS")
		)
		(fp_line
			(start 0.7874 0.4064)
			(end -0.7874 0.4064)
			(stroke
				(width 0.1524)
				(type default)
			)
			(layer "F.SilkS")
		)
		(fp_line
			(start -0.7874 -0.4064)
			(end 0.7874 -0.4064)
			(stroke
				(width 0.1524)
				(type default)
			)
			(layer "F.SilkS")
		)
		(fp_line
			(start 0.7874 -0.4064)
			(end 0.7874 0.4064)
			(stroke
				(width 0.1524)
				(type default)
			)
			(layer "F.SilkS")
		)
		(fp_line
			(start -0.67945 0.3048)
			(end -0.67945 -0.305054)
			(stroke
				(width 0.1)
				(type default)
			)
			(layer "F.Fab")
		)
		(fp_line
			(start -0.12065 0.3048)
			(end -0.67945 0.3048)
			(stroke
				(width 0.1)
				(type default)
			)
			(layer "F.Fab")
		)
		(fp_line
			(start 0.120396 0.3048)
			(end 0.120396 0.2794)
			(stroke
				(width 0.1)
				(type default)
			)
			(layer "F.Fab")
		)
		(fp_line
			(start 0.67945 0.3048)
			(end 0.120396 0.3048)
			(stroke
				(width 0.1)
				(type default)
			)
			(layer "F.Fab")
		)
		(fp_line
			(start -0.12065 0.2794)
			(end -0.12065 0.3048)
			(stroke
				(width 0.1)
				(type default)
			)
			(layer "F.Fab")
		)
		(fp_line
			(start 0.120396 0.2794)
			(end -0.12065 0.2794)
			(stroke
				(width 0.1)
				(type default)
			)
			(layer "F.Fab")
		)
		(fp_line
			(start -0.12065 -0.2794)
			(end 0.12065 -0.2794)
			(stroke
				(width 0.1)
				(type default)
			)
			(layer "F.Fab")
		)
		(fp_line
			(start 0.12065 -0.2794)
			(end 0.12065 -0.3048)
			(stroke
				(width 0.1)
				(type default)
			)
			(layer "F.Fab")
		)
		(fp_line
			(start 0.12065 -0.3048)
			(end 0.67945 -0.3048)
			(stroke
				(width 0.1)
				(type default)
			)
			(layer "F.Fab")
		)
		(fp_line
			(start 0.67945 -0.3048)
			(end 0.67945 0.3048)
			(stroke
				(width 0.1)
				(type default)
			)
			(layer "F.Fab")
		)
		(fp_line
			(start -0.67945 -0.305054)
			(end -0.12065 -0.305054)
			(stroke
				(width 0.1)
				(type default)
			)
			(layer "F.Fab")
		)
		(fp_line
			(start -0.12065 -0.305054)
			(end -0.12065 -0.2794)
			(stroke
				(width 0.1)
				(type default)
			)
			(layer "F.Fab")
		)
		(pad "1" smd circle
			(at -0.40005 0 270)
			(size 0 0)
			(layers "F.Cu" "F.Mask" "F.Paste")
			(net "P3V3_SSD8")
		)
		(pad "2" smd circle
			(at 0.40005 0 270)
			(size 0 0)
			(layers "F.Cu" "F.Mask" "F.Paste")
			(net "DUALPORT_N_SSD8")
		)
	)
	(footprint ""
		(layer "F.Cu")
		(at 80.657446 -112.504474 90)
		(property "Reference" "C861"
			(at 0 0 90)
			(layer "F.SilkS")
			(hide yes)
			(effects
				(font
					(size 1.27 1.27)
				)
			)
		)
		(property "Value" ""
			(at 0 0 90)
			(layer "F.Fab")
			(effects
				(font
					(size 1.27 1.27)
				)
			)
		)
		(duplicate_pad_numbers_are_jumpers no)
		(fp_line
			(start 1.524 -0.762)
			(end 1.524 0.762)
			(stroke
				(width 0.1524)
				(type default)
			)
			(layer "F.SilkS")
		)
		(fp_line
			(start -1.524 -0.762)
			(end 1.524 -0.762)
			(stroke
				(width 0.1524)
				(type default)
			)
			(layer "F.SilkS")
		)
		(fp_line
			(start 1.524 0.762)
			(end -1.524 0.762)
			(stroke
				(width 0.1524)
				(type default)
			)
			(layer "F.SilkS")
		)
		(fp_line
			(start -1.524 0.762)
			(end -1.524 -0.762)
			(stroke
				(width 0.1524)
				(type default)
			)
			(layer "F.SilkS")
		)
		(fp_line
			(start 1.1049 -0.724916)
			(end -1.1049 -0.724916)
			(stroke
				(width 0.1)
				(type default)
			)
			(layer "F.Fab")
		)
		(fp_line
			(start -1.1049 -0.724916)
			(end -1.1049 0.724916)
			(stroke
				(width 0.1)
				(type default)
			)
			(layer "F.Fab")
		)
		(fp_line
			(start 1.1049 0.724916)
			(end 1.1049 -0.724916)
			(stroke
				(width 0.1)
				(type default)
			)
			(layer "F.Fab")
		)
		(fp_line
			(start -1.1049 0.724916)
			(end 1.1049 0.724916)
			(stroke
				(width 0.1)
				(type default)
			)
			(layer "F.Fab")
		)
		(pad "1" smd rect
			(at -0.889 0 270)
			(size 1.016 1.27)
			(layers "F.Cu" "F.Mask" "F.Paste")
			(net "P12V_NIC1")
		)
		(pad "2" smd rect
			(at 0.889 0 270)
			(size 1.016 1.27)
			(layers "F.Cu" "F.Mask" "F.Paste")
			(net "GND")
		)
	)
	(footprint ""
		(layer "F.Cu")
		(at 6.297168 -274.861274 90)
		(property "Reference" "R770"
			(at 0 0 90)
			(layer "F.SilkS")
			(hide yes)
			(effects
				(font
					(size 1.27 1.27)
				)
			)
		)
		(property "Value" ""
			(at 0 0 90)
			(layer "F.Fab")
			(effects
				(font
					(size 1.27 1.27)
				)
			)
		)
		(duplicate_pad_numbers_are_jumpers no)
		(fp_line
			(start 3.937508 -1.8796)
			(end -3.937508 -1.8796)
			(stroke
				(width 0.1524)
				(type default)
			)
			(layer "F.SilkS")
		)
		(fp_line
			(start -3.937508 -1.8796)
			(end -3.937508 1.8796)
			(stroke
				(width 0.1524)
				(type default)
			)
			(layer "F.SilkS")
		)
		(fp_line
			(start 3.937508 1.8796)
			(end 3.937508 -1.8796)
			(stroke
				(width 0.1524)
				(type default)
			)
			(layer "F.SilkS")
		)
		(fp_line
			(start -3.937508 1.8796)
			(end 3.937508 1.8796)
			(stroke
				(width 0.1524)
				(type default)
			)
			(layer "F.SilkS")
		)
		(fp_line
			(start 3.275076 -1.674876)
			(end -3.275076 -1.674876)
			(stroke
				(width 0.1)
				(type default)
			)
			(layer "F.Fab")
		)
		(fp_line
			(start -3.275076 -1.674876)
			(end -3.275076 1.674876)
			(stroke
				(width 0.1)
				(type default)
			)
			(layer "F.Fab")
		)
		(fp_line
			(start 3.275076 1.674876)
			(end 3.275076 -1.674876)
			(stroke
				(width 0.1)
				(type default)
			)
			(layer "F.Fab")
		)
		(fp_line
			(start -3.275076 1.674876)
			(end 3.275076 1.674876)
			(stroke
				(width 0.1)
				(type default)
			)
			(layer "F.Fab")
		)
		(pad "1" smd rect
			(at -2.350008 0 90)
			(size 2.921 3.5052)
			(layers "F.Cu" "F.Mask" "F.Paste")
			(net "P1V25_PEX0")
		)
		(pad "2" smd rect
			(at 2.350008 0 90)
			(size 2.921 3.5052)
			(layers "F.Cu" "F.Mask" "F.Paste")
			(net "P1V25_PEX0_R")
		)
	)
	(footprint ""
		(layer "F.Cu")
		(at 284.443678 -43.85691)
		(property "Reference" "R608"
			(at 0 0 0)
			(layer "F.SilkS")
			(hide yes)
			(effects
				(font
					(size 1.27 1.27)
				)
			)
		)
		(property "Value" ""
			(at 0 0 0)
			(layer "F.Fab")
			(effects
				(font
					(size 1.27 1.27)
				)
			)
		)
		(duplicate_pad_numbers_are_jumpers no)
		(fp_line
			(start -0.7874 -0.4064)
			(end 0.7874 -0.4064)
			(stroke
				(width 0.1524)
				(type default)
			)
			(layer "F.SilkS")
		)
		(fp_line
			(start -0.7874 0.4064)
			(end -0.7874 -0.4064)
			(stroke
				(width 0.1524)
				(type default)
			)
			(layer "F.SilkS")
		)
		(fp_line
			(start 0.7874 -0.4064)
			(end 0.7874 0.4064)
			(stroke
				(width 0.1524)
				(type default)
			)
			(layer "F.SilkS")
		)
		(fp_line
			(start 0.7874 0.4064)
			(end -0.7874 0.4064)
			(stroke
				(width 0.1524)
				(type default)
			)
			(layer "F.SilkS")
		)
		(fp_line
			(start -0.67945 -0.305054)
			(end -0.12065 -0.305054)
			(stroke
				(width 0.1)
				(type default)
			)
			(layer "F.Fab")
		)
		(fp_line
			(start -0.67945 0.3048)
			(end -0.67945 -0.305054)
			(stroke
				(width 0.1)
				(type default)
			)
			(layer "F.Fab")
		)
		(fp_line
			(start -0.12065 -0.305054)
			(end -0.12065 -0.2794)
			(stroke
				(width 0.1)
				(type default)
			)
			(layer "F.Fab")
		)
		(fp_line
			(start -0.12065 -0.2794)
			(end 0.12065 -0.2794)
			(stroke
				(width 0.1)
				(type default)
			)
			(layer "F.Fab")
		)
		(fp_line
			(start -0.12065 0.2794)
			(end -0.12065 0.3048)
			(stroke
				(width 0.1)
				(type default)
			)
			(layer "F.Fab")
		)
		(fp_line
			(start -0.12065 0.3048)
			(end -0.67945 0.3048)
			(stroke
				(width 0.1)
				(type default)
			)
			(layer "F.Fab")
		)
		(fp_line
			(start 0.120396 0.2794)
			(end -0.12065 0.2794)
			(stroke
				(width 0.1)
				(type default)
			)
			(layer "F.Fab")
		)
		(fp_line
			(start 0.120396 0.3048)
			(end 0.120396 0.2794)
			(stroke
				(width 0.1)
				(type default)
			)
			(layer "F.Fab")
		)
		(fp_line
			(start 0.12065 -0.3048)
			(end 0.67945 -0.3048)
			(stroke
				(width 0.1)
				(type default)
			)
			(layer "F.Fab")
		)
		(fp_line
			(start 0.12065 -0.2794)
			(end 0.12065 -0.3048)
			(stroke
				(width 0.1)
				(type default)
			)
			(layer "F.Fab")
		)
		(fp_line
			(start 0.67945 -0.3048)
			(end 0.67945 0.3048)
			(stroke
				(width 0.1)
				(type default)
			)
			(layer "F.Fab")
		)
		(fp_line
			(start 0.67945 0.3048)
			(end 0.120396 0.3048)
			(stroke
				(width 0.1)
				(type default)
			)
			(layer "F.Fab")
		)
		(pad "1" smd circle
			(at -0.40005 0)
			(size 0 0)
			(layers "F.Cu" "F.Mask" "F.Paste")
			(net "SSD9_ADC_A1")
		)
		(pad "2" smd circle
			(at 0.40005 0)
			(size 0 0)
			(layers "F.Cu" "F.Mask" "F.Paste")
			(net "GND")
		)
	)
	(footprint ""
		(layer "F.Cu")
		(at 28.005532 -258.511548 -90)
		(property "Reference" "C3074"
			(at 0 0 270)
			(layer "F.SilkS")
			(hide yes)
			(effects
				(font
					(size 1.27 1.27)
				)
			)
		)
		(property "Value" ""
			(at 0 0 270)
			(layer "F.Fab")
			(effects
				(font
					(size 1.27 1.27)
				)
			)
		)
		(duplicate_pad_numbers_are_jumpers no)
		(fp_line
			(start -1.2954 0.5842)
			(end -1.2954 -0.5842)
			(stroke
				(width 0.1524)
				(type default)
			)
			(layer "F.SilkS")
		)
		(fp_line
			(start 1.2954 0.5842)
			(end -1.2954 0.5842)
			(stroke
				(width 0.1524)
				(type default)
			)
			(layer "F.SilkS")
		)
		(fp_line
			(start -1.2954 -0.5842)
			(end 1.2954 -0.5842)
			(stroke
				(width 0.1524)
				(type default)
			)
			(layer "F.SilkS")
		)
		(fp_line
			(start 1.2954 -0.5842)
			(end 1.2954 0.5842)
			(stroke
				(width 0.1524)
				(type default)
			)
			(layer "F.SilkS")
		)
		(fp_line
			(start -0.8636 0.4572)
			(end -0.8636 0.4064)
			(stroke
				(width 0.1)
				(type default)
			)
			(layer "F.Fab")
		)
		(fp_line
			(start 0.8636 0.4572)
			(end -0.8636 0.4572)
			(stroke
				(width 0.1)
				(type default)
			)
			(layer "F.Fab")
		)
		(fp_line
			(start -1.1938 0.4064)
			(end -1.1938 -0.4064)
			(stroke
				(width 0.1)
				(type default)
			)
			(layer "F.Fab")
		)
		(fp_line
			(start -0.8636 0.4064)
			(end -1.1938 0.4064)
			(stroke
				(width 0.1)
				(type default)
			)
			(layer "F.Fab")
		)
		(fp_line
			(start 0.8636 0.4064)
			(end 0.8636 0.4572)
			(stroke
				(width 0.1)
				(type default)
			)
			(layer "F.Fab")
		)
		(fp_line
			(start 1.1938 0.4064)
			(end 0.8636 0.4064)
			(stroke
				(width 0.1)
				(type default)
			)
			(layer "F.Fab")
		)
		(fp_line
			(start -1.1938 -0.4064)
			(end -0.8636 -0.4064)
			(stroke
				(width 0.1)
				(type default)
			)
			(layer "F.Fab")
		)
		(fp_line
			(start -0.8636 -0.4064)
			(end -0.8636 -0.4572)
			(stroke
				(width 0.1)
				(type default)
			)
			(layer "F.Fab")
		)
		(fp_line
			(start 0.8636 -0.4064)
			(end 1.1938 -0.4064)
			(stroke
				(width 0.1)
				(type default)
			)
			(layer "F.Fab")
		)
		(fp_line
			(start 1.1938 -0.4064)
			(end 1.1938 0.4064)
			(stroke
				(width 0.1)
				(type default)
			)
			(layer "F.Fab")
		)
		(fp_line
			(start -0.8636 -0.4572)
			(end 0.8636 -0.4572)
			(stroke
				(width 0.1)
				(type default)
			)
			(layer "F.Fab")
		)
		(fp_line
			(start 0.8636 -0.4572)
			(end 0.8636 -0.4064)
			(stroke
				(width 0.1)
				(type default)
			)
			(layer "F.Fab")
		)
		(pad "1" smd rect
			(at -0.7366 0 180)
			(size 0.7112 0.8128)
			(layers "F.Cu" "F.Mask" "F.Paste")
			(net "P1V8_VDDA_PEX0_R")
		)
		(pad "2" smd rect
			(at 0.7366 0 180)
			(size 0.7112 0.8128)
			(layers "F.Cu" "F.Mask" "F.Paste")
			(net "GND")
		)
	)
	(footprint ""
		(layer "F.Cu")
		(at 411.97784 -114.267742)
		(property "Reference" "R395"
			(at 0 0 0)
			(layer "F.SilkS")
			(hide yes)
			(effects
				(font
					(size 1.27 1.27)
				)
			)
		)
		(property "Value" ""
			(at 0 0 0)
			(layer "F.Fab")
			(effects
				(font
					(size 1.27 1.27)
				)
			)
		)
		(duplicate_pad_numbers_are_jumpers no)
		(fp_line
			(start -0.7874 -0.4064)
			(end 0.7874 -0.4064)
			(stroke
				(width 0.1524)
				(type default)
			)
			(layer "F.SilkS")
		)
		(fp_line
			(start -0.7874 0.4064)
			(end -0.7874 -0.4064)
			(stroke
				(width 0.1524)
				(type default)
			)
			(layer "F.SilkS")
		)
		(fp_line
			(start 0.7874 -0.4064)
			(end 0.7874 0.4064)
			(stroke
				(width 0.1524)
				(type default)
			)
			(layer "F.SilkS")
		)
		(fp_line
			(start 0.7874 0.4064)
			(end -0.7874 0.4064)
			(stroke
				(width 0.1524)
				(type default)
			)
			(layer "F.SilkS")
		)
		(fp_line
			(start -0.67945 -0.305054)
			(end -0.12065 -0.305054)
			(stroke
				(width 0.1)
				(type default)
			)
			(layer "F.Fab")
		)
		(fp_line
			(start -0.67945 0.3048)
			(end -0.67945 -0.305054)
			(stroke
				(width 0.1)
				(type default)
			)
			(layer "F.Fab")
		)
		(fp_line
			(start -0.12065 -0.305054)
			(end -0.12065 -0.2794)
			(stroke
				(width 0.1)
				(type default)
			)
			(layer "F.Fab")
		)
		(fp_line
			(start -0.12065 -0.2794)
			(end 0.12065 -0.2794)
			(stroke
				(width 0.1)
				(type default)
			)
			(layer "F.Fab")
		)
		(fp_line
			(start -0.12065 0.2794)
			(end -0.12065 0.3048)
			(stroke
				(width 0.1)
				(type default)
			)
			(layer "F.Fab")
		)
		(fp_line
			(start -0.12065 0.3048)
			(end -0.67945 0.3048)
			(stroke
				(width 0.1)
				(type default)
			)
			(layer "F.Fab")
		)
		(fp_line
			(start 0.120396 0.2794)
			(end -0.12065 0.2794)
			(stroke
				(width 0.1)
				(type default)
			)
			(layer "F.Fab")
		)
		(fp_line
			(start 0.120396 0.3048)
			(end 0.120396 0.2794)
			(stroke
				(width 0.1)
				(type default)
			)
			(layer "F.Fab")
		)
		(fp_line
			(start 0.12065 -0.3048)
			(end 0.67945 -0.3048)
			(stroke
				(width 0.1)
				(type default)
			)
			(layer "F.Fab")
		)
		(fp_line
			(start 0.12065 -0.2794)
			(end 0.12065 -0.3048)
			(stroke
				(width 0.1)
				(type default)
			)
			(layer "F.Fab")
		)
		(fp_line
			(start 0.67945 -0.3048)
			(end 0.67945 0.3048)
			(stroke
				(width 0.1)
				(type default)
			)
			(layer "F.Fab")
		)
		(fp_line
			(start 0.67945 0.3048)
			(end 0.120396 0.3048)
			(stroke
				(width 0.1)
				(type default)
			)
			(layer "F.Fab")
		)
		(pad "1" smd circle
			(at -0.40005 0)
			(size 0 0)
			(layers "F.Cu" "F.Mask" "F.Paste")
			(net "RST_SMB_NIC7_MUX_ISO_N")
		)
		(pad "2" smd circle
			(at 0.40005 0)
			(size 0 0)
			(layers "F.Cu" "F.Mask" "F.Paste")
			(net "GND")
		)
	)
	(footprint ""
		(layer "F.Cu")
		(at 221.990158 -78.579472)
		(property "Reference" "R5763"
			(at 0 0 0)
			(layer "F.SilkS")
			(hide yes)
			(effects
				(font
					(size 1.27 1.27)
				)
			)
		)
		(property "Value" ""
			(at 0 0 0)
			(layer "F.Fab")
			(effects
				(font
					(size 1.27 1.27)
				)
			)
		)
		(duplicate_pad_numbers_are_jumpers no)
		(fp_line
			(start -0.7874 -0.4064)
			(end 0.7874 -0.4064)
			(stroke
				(width 0.1524)
				(type default)
			)
			(layer "F.SilkS")
		)
		(fp_line
			(start -0.7874 0.4064)
			(end -0.7874 -0.4064)
			(stroke
				(width 0.1524)
				(type default)
			)
			(layer "F.SilkS")
		)
		(fp_line
			(start 0.7874 -0.4064)
			(end 0.7874 0.4064)
			(stroke
				(width 0.1524)
				(type default)
			)
			(layer "F.SilkS")
		)
		(fp_line
			(start 0.7874 0.4064)
			(end -0.7874 0.4064)
			(stroke
				(width 0.1524)
				(type default)
			)
			(layer "F.SilkS")
		)
		(fp_line
			(start -0.67945 -0.305054)
			(end -0.12065 -0.305054)
			(stroke
				(width 0.1)
				(type default)
			)
			(layer "F.Fab")
		)
		(fp_line
			(start -0.67945 0.3048)
			(end -0.67945 -0.305054)
			(stroke
				(width 0.1)
				(type default)
			)
			(layer "F.Fab")
		)
		(fp_line
			(start -0.12065 -0.305054)
			(end -0.12065 -0.2794)
			(stroke
				(width 0.1)
				(type default)
			)
			(layer "F.Fab")
		)
		(fp_line
			(start -0.12065 -0.2794)
			(end 0.12065 -0.2794)
			(stroke
				(width 0.1)
				(type default)
			)
			(layer "F.Fab")
		)
		(fp_line
			(start -0.12065 0.2794)
			(end -0.12065 0.3048)
			(stroke
				(width 0.1)
				(type default)
			)
			(layer "F.Fab")
		)
		(fp_line
			(start -0.12065 0.3048)
			(end -0.67945 0.3048)
			(stroke
				(width 0.1)
				(type default)
			)
			(layer "F.Fab")
		)
		(fp_line
			(start 0.120396 0.2794)
			(end -0.12065 0.2794)
			(stroke
				(width 0.1)
				(type default)
			)
			(layer "F.Fab")
		)
		(fp_line
			(start 0.120396 0.3048)
			(end 0.120396 0.2794)
			(stroke
				(width 0.1)
				(type default)
			)
			(layer "F.Fab")
		)
		(fp_line
			(start 0.12065 -0.3048)
			(end 0.67945 -0.3048)
			(stroke
				(width 0.1)
				(type default)
			)
			(layer "F.Fab")
		)
		(fp_line
			(start 0.12065 -0.2794)
			(end 0.12065 -0.3048)
			(stroke
				(width 0.1)
				(type default)
			)
			(layer "F.Fab")
		)
		(fp_line
			(start 0.67945 -0.3048)
			(end 0.67945 0.3048)
			(stroke
				(width 0.1)
				(type default)
			)
			(layer "F.Fab")
		)
		(fp_line
			(start 0.67945 0.3048)
			(end 0.120396 0.3048)
			(stroke
				(width 0.1)
				(type default)
			)
			(layer "F.Fab")
		)
		(pad "1" smd circle
			(at -0.40005 0)
			(size 0 0)
			(layers "F.Cu" "F.Mask" "F.Paste")
			(net "SSD9_LED")
		)
		(pad "2" smd circle
			(at 0.40005 0)
			(size 0 0)
			(layers "F.Cu" "F.Mask" "F.Paste")
			(net "SSD9_LED_R")
		)
	)
	(footprint ""
		(layer "F.Cu")
		(at 144.595342 -35.48253)
		(property "Reference" "U386"
			(at -2.506472 1.44653 90)
			(unlocked yes)
			(layer "F.SilkS")
			(effects
				(font
					(size 0.7874 0.5842)
					(thickness 0.1524)
				)
				(justify left)
			)
		)
		(property "Value" ""
			(at 0 0 0)
			(layer "F.Fab")
			(effects
				(font
					(size 1.27 1.27)
				)
			)
		)
		(duplicate_pad_numbers_are_jumpers no)
		(fp_line
			(start -1.3462 -1.1938)
			(end -1.3462 1.1684)
			(stroke
				(width 0.1524)
				(type default)
			)
			(layer "F.SilkS")
		)
		(fp_line
			(start -1.3462 1.1938)
			(end 1.3462 1.1938)
			(stroke
				(width 0.1524)
				(type default)
			)
			(layer "F.SilkS")
		)
		(fp_line
			(start 1.3462 -1.1938)
			(end -1.3462 -1.1938)
			(stroke
				(width 0.1524)
				(type default)
			)
			(layer "F.SilkS")
		)
		(fp_line
			(start 1.3462 1.1938)
			(end 1.3462 -1.1938)
			(stroke
				(width 0.1524)
				(type default)
			)
			(layer "F.SilkS")
		)
		(fp_poly
			(pts
				(xy -1.447038 -0.760476) (xy -2.052066 -0.457962) (xy -2.052066 -1.06299)
			)
			(stroke
				(width 0)
				(type default)
			)
			(fill yes)
			(layer "F.SilkS")
		)
		(fp_line
			(start -0.674878 -1.124966)
			(end -0.674878 1.124966)
			(stroke
				(width 0.1)
				(type default)
			)
			(layer "F.Fab")
		)
		(fp_line
			(start -0.674878 1.124966)
			(end 0.674878 1.124966)
			(stroke
				(width 0.1)
				(type default)
			)
			(layer "F.Fab")
		)
		(fp_line
			(start 0.674878 -1.124966)
			(end -0.674878 -1.124966)
			(stroke
				(width 0.1)
				(type default)
			)
			(layer "F.Fab")
		)
		(fp_line
			(start 0.674878 1.124966)
			(end 0.674878 -1.124966)
			(stroke
				(width 0.1)
				(type default)
			)
			(layer "F.Fab")
		)
		(fp_poly
			(pts
				(xy -1.447038 -0.760476) (xy -2.052066 -0.457962) (xy -2.052066 -1.06299)
			)
			(stroke
				(width 0)
				(type default)
			)
			(fill yes)
			(layer "F.Fab")
		)
		(pad "1" smd rect
			(at -0.899922 -0.750062)
			(size 0.6096 0.6096)
			(layers "F.Cu" "F.Mask" "F.Paste")
			(net "PWRGD_P3V3_SSD5_R")
		)
		(pad "2" smd rect
			(at -0.899922 0 90)
			(size 0.4064 0.6096)
			(layers "F.Cu" "F.Mask" "F.Paste")
			(net "RST_SMB_SSD5_N")
		)
		(pad "3" smd rect
			(at -0.899922 0.750062)
			(size 0.6096 0.6096)
			(layers "F.Cu" "F.Mask" "F.Paste")
			(net "GND")
		)
		(pad "4" smd rect
			(at 0.899922 0.750062)
			(size 0.6096 0.6096)
			(layers "F.Cu" "F.Mask" "F.Paste")
			(net "RST_SMB_SSD5_ISO_N")
		)
		(pad "5" smd rect
			(at 0.899922 -0.750062)
			(size 0.6096 0.6096)
			(layers "F.Cu" "F.Mask" "F.Paste")
			(net "P3V3_AUX")
		)
	)
	(footprint ""
		(layer "F.Cu")
		(at 62.963044 -207.3402 180)
		(property "Reference" "R6635"
			(at 0 0 180)
			(layer "F.SilkS")
			(hide yes)
			(effects
				(font
					(size 1.27 1.27)
				)
			)
		)
		(property "Value" ""
			(at 0 0 180)
			(layer "F.Fab")
			(effects
				(font
					(size 1.27 1.27)
				)
			)
		)
		(duplicate_pad_numbers_are_jumpers no)
		(fp_line
			(start 0.7874 0.4064)
			(end -0.7874 0.4064)
			(stroke
				(width 0.1524)
				(type default)
			)
			(layer "F.SilkS")
		)
		(fp_line
			(start 0.7874 -0.4064)
			(end 0.7874 0.4064)
			(stroke
				(width 0.1524)
				(type default)
			)
			(layer "F.SilkS")
		)
		(fp_line
			(start -0.7874 0.4064)
			(end -0.7874 -0.4064)
			(stroke
				(width 0.1524)
				(type default)
			)
			(layer "F.SilkS")
		)
		(fp_line
			(start -0.7874 -0.4064)
			(end 0.7874 -0.4064)
			(stroke
				(width 0.1524)
				(type default)
			)
			(layer "F.SilkS")
		)
		(fp_line
			(start 0.67945 0.3048)
			(end 0.120396 0.3048)
			(stroke
				(width 0.1)
				(type default)
			)
			(layer "F.Fab")
		)
		(fp_line
			(start 0.67945 -0.3048)
			(end 0.67945 0.3048)
			(stroke
				(width 0.1)
				(type default)
			)
			(layer "F.Fab")
		)
		(fp_line
			(start 0.12065 -0.2794)
			(end 0.12065 -0.3048)
			(stroke
				(width 0.1)
				(type default)
			)
			(layer "F.Fab")
		)
		(fp_line
			(start 0.12065 -0.3048)
			(end 0.67945 -0.3048)
			(stroke
				(width 0.1)
				(type default)
			)
			(layer "F.Fab")
		)
		(fp_line
			(start 0.120396 0.3048)
			(end 0.120396 0.2794)
			(stroke
				(width 0.1)
				(type default)
			)
			(layer "F.Fab")
		)
		(fp_line
			(start 0.120396 0.2794)
			(end -0.12065 0.2794)
			(stroke
				(width 0.1)
				(type default)
			)
			(layer "F.Fab")
		)
		(fp_line
			(start -0.12065 0.3048)
			(end -0.67945 0.3048)
			(stroke
				(width 0.1)
				(type default)
			)
			(layer "F.Fab")
		)
		(fp_line
			(start -0.12065 0.2794)
			(end -0.12065 0.3048)
			(stroke
				(width 0.1)
				(type default)
			)
			(layer "F.Fab")
		)
		(fp_line
			(start -0.12065 -0.2794)
			(end 0.12065 -0.2794)
			(stroke
				(width 0.1)
				(type default)
			)
			(layer "F.Fab")
		)
		(fp_line
			(start -0.12065 -0.305054)
			(end -0.12065 -0.2794)
			(stroke
				(width 0.1)
				(type default)
			)
			(layer "F.Fab")
		)
		(fp_line
			(start -0.67945 0.3048)
			(end -0.67945 -0.305054)
			(stroke
				(width 0.1)
				(type default)
			)
			(layer "F.Fab")
		)
		(fp_line
			(start -0.67945 -0.305054)
			(end -0.12065 -0.305054)
			(stroke
				(width 0.1)
				(type default)
			)
			(layer "F.Fab")
		)
		(pad "1" smd circle
			(at -0.40005 0 180)
			(size 0 0)
			(layers "F.Cu" "F.Mask" "F.Paste")
			(net "UART_PEX2_CLI_R_RX")
		)
		(pad "2" smd circle
			(at 0.40005 0 180)
			(size 0 0)
			(layers "F.Cu" "F.Mask" "F.Paste")
			(net "UART_PEX2_CLI_R1_RX")
		)
	)
	(footprint ""
		(layer "F.Cu")
		(at 472.499436 -548.056054 180)
		(property "Reference" "J41_OTH"
			(at -3.2385 -1.402334 0)
			(unlocked yes)
			(layer "B.SilkS")
			(effects
				(font
					(size 0.7874 0.5842)
					(thickness 0.1524)
				)
				(justify mirror)
			)
		)
		(property "Value" ""
			(at 0 0 180)
			(layer "F.Fab")
			(effects
				(font
					(size 1.27 1.27)
				)
			)
		)
		(duplicate_pad_numbers_are_jumpers no)
		(pad "1" thru_hole circle
			(at 0 0 180)
			(size 0.4572 0.4572)
			(drill 0.2032)
			(layers "*.Cu" "*.Mask")
			(remove_unused_layers no)
			(net "Net_9095")
			(clearance 0.127)
			(thermal_gap 0.127)
			(padstack
				(mode front_inner_back)
				(layer "Inner"
					(shape circle)
					(size 0.4572 0.4572)
					(clearance 0.127)
				)
				(layer "B.Cu"
					(shape circle)
					(size 0.508 0.508)
					(clearance 0.1016)
				)
			)
		)
	)
	(footprint ""
		(layer "F.Cu")
		(at 145.255234 -53.468524 90)
		(property "Reference" "PC521"
			(at 0 0 90)
			(layer "F.SilkS")
			(hide yes)
			(effects
				(font
					(size 1.27 1.27)
				)
			)
		)
		(property "Value" ""
			(at 0 0 90)
			(layer "F.Fab")
			(effects
				(font
					(size 1.27 1.27)
				)
			)
		)
		(duplicate_pad_numbers_are_jumpers no)
		(fp_line
			(start 1.524 -0.762)
			(end 1.524 0.762)
			(stroke
				(width 0.1524)
				(type default)
			)
			(layer "F.SilkS")
		)
		(fp_line
			(start -1.524 -0.762)
			(end 1.524 -0.762)
			(stroke
				(width 0.1524)
				(type default)
			)
			(layer "F.SilkS")
		)
		(fp_line
			(start 1.524 0.762)
			(end -1.524 0.762)
			(stroke
				(width 0.1524)
				(type default)
			)
			(layer "F.SilkS")
		)
		(fp_line
			(start -1.524 0.762)
			(end -1.524 -0.762)
			(stroke
				(width 0.1524)
				(type default)
			)
			(layer "F.SilkS")
		)
		(fp_line
			(start 1.1049 -0.724916)
			(end -1.1049 -0.724916)
			(stroke
				(width 0.1)
				(type default)
			)
			(layer "F.Fab")
		)
		(fp_line
			(start -1.1049 -0.724916)
			(end -1.1049 0.724916)
			(stroke
				(width 0.1)
				(type default)
			)
			(layer "F.Fab")
		)
		(fp_line
			(start 1.1049 0.724916)
			(end 1.1049 -0.724916)
			(stroke
				(width 0.1)
				(type default)
			)
			(layer "F.Fab")
		)
		(fp_line
			(start -1.1049 0.724916)
			(end 1.1049 0.724916)
			(stroke
				(width 0.1)
				(type default)
			)
			(layer "F.Fab")
		)
		(pad "1" smd rect
			(at -0.889 0 270)
			(size 1.016 1.27)
			(layers "F.Cu" "F.Mask" "F.Paste")
			(net "GND")
		)
		(pad "2" smd rect
			(at 0.889 0 270)
			(size 1.016 1.27)
			(layers "F.Cu" "F.Mask" "F.Paste")
			(net "P3V3_AUX")
		)
	)
	(footprint ""
		(layer "F.Cu")
		(at 353.695 -183.388)
		(property "Reference" "R4763"
			(at 0 0 0)
			(layer "F.SilkS")
			(hide yes)
			(effects
				(font
					(size 1.27 1.27)
				)
			)
		)
		(property "Value" ""
			(at 0 0 0)
			(layer "F.Fab")
			(effects
				(font
					(size 1.27 1.27)
				)
			)
		)
		(duplicate_pad_numbers_are_jumpers no)
		(fp_line
			(start -0.7874 -0.4064)
			(end 0.7874 -0.4064)
			(stroke
				(width 0.1524)
				(type default)
			)
			(layer "F.SilkS")
		)
		(fp_line
			(start -0.7874 0.4064)
			(end -0.7874 -0.4064)
			(stroke
				(width 0.1524)
				(type default)
			)
			(layer "F.SilkS")
		)
		(fp_line
			(start 0.7874 -0.4064)
			(end 0.7874 0.4064)
			(stroke
				(width 0.1524)
				(type default)
			)
			(layer "F.SilkS")
		)
		(fp_line
			(start 0.7874 0.4064)
			(end -0.7874 0.4064)
			(stroke
				(width 0.1524)
				(type default)
			)
			(layer "F.SilkS")
		)
		(fp_line
			(start -0.67945 -0.305054)
			(end -0.12065 -0.305054)
			(stroke
				(width 0.1)
				(type default)
			)
			(layer "F.Fab")
		)
		(fp_line
			(start -0.67945 0.3048)
			(end -0.67945 -0.305054)
			(stroke
				(width 0.1)
				(type default)
			)
			(layer "F.Fab")
		)
		(fp_line
			(start -0.12065 -0.305054)
			(end -0.12065 -0.2794)
			(stroke
				(width 0.1)
				(type default)
			)
			(layer "F.Fab")
		)
		(fp_line
			(start -0.12065 -0.2794)
			(end 0.12065 -0.2794)
			(stroke
				(width 0.1)
				(type default)
			)
			(layer "F.Fab")
		)
		(fp_line
			(start -0.12065 0.2794)
			(end -0.12065 0.3048)
			(stroke
				(width 0.1)
				(type default)
			)
			(layer "F.Fab")
		)
		(fp_line
			(start -0.12065 0.3048)
			(end -0.67945 0.3048)
			(stroke
				(width 0.1)
				(type default)
			)
			(layer "F.Fab")
		)
		(fp_line
			(start 0.120396 0.2794)
			(end -0.12065 0.2794)
			(stroke
				(width 0.1)
				(type default)
			)
			(layer "F.Fab")
		)
		(fp_line
			(start 0.120396 0.3048)
			(end 0.120396 0.2794)
			(stroke
				(width 0.1)
				(type default)
			)
			(layer "F.Fab")
		)
		(fp_line
			(start 0.12065 -0.3048)
			(end 0.67945 -0.3048)
			(stroke
				(width 0.1)
				(type default)
			)
			(layer "F.Fab")
		)
		(fp_line
			(start 0.12065 -0.2794)
			(end 0.12065 -0.3048)
			(stroke
				(width 0.1)
				(type default)
			)
			(layer "F.Fab")
		)
		(fp_line
			(start 0.67945 -0.3048)
			(end 0.67945 0.3048)
			(stroke
				(width 0.1)
				(type default)
			)
			(layer "F.Fab")
		)
		(fp_line
			(start 0.67945 0.3048)
			(end 0.120396 0.3048)
			(stroke
				(width 0.1)
				(type default)
			)
			(layer "F.Fab")
		)
		(pad "1" smd circle
			(at -0.40005 0)
			(size 0 0)
			(layers "F.Cu" "F.Mask" "F.Paste")
			(net "GND")
		)
		(pad "2" smd circle
			(at 0.40005 0)
			(size 0 0)
			(layers "F.Cu" "F.Mask" "F.Paste")
			(net "PCA9555_0_PEX2_A0")
		)
	)
	(footprint ""
		(layer "F.Cu")
		(at 32.657288 -350.098614 90)
		(property "Reference" "C180"
			(at 0 0 90)
			(layer "F.SilkS")
			(hide yes)
			(effects
				(font
					(size 1.27 1.27)
				)
			)
		)
		(property "Value" ""
			(at 0 0 90)
			(layer "F.Fab")
			(effects
				(font
					(size 1.27 1.27)
				)
			)
		)
		(duplicate_pad_numbers_are_jumpers no)
		(fp_line
			(start 0.299974 -0.150114)
			(end 0.299974 0.150114)
			(stroke
				(width 0.1)
				(type default)
			)
			(layer "F.Fab")
		)
		(fp_line
			(start -0.299974 -0.150114)
			(end 0.299974 -0.150114)
			(stroke
				(width 0.1)
				(type default)
			)
			(layer "F.Fab")
		)
		(fp_line
			(start 0.299974 0.150114)
			(end -0.299974 0.150114)
			(stroke
				(width 0.1)
				(type default)
			)
			(layer "F.Fab")
		)
		(fp_line
			(start -0.299974 0.150114)
			(end -0.299974 -0.150114)
			(stroke
				(width 0.1)
				(type default)
			)
			(layer "F.Fab")
		)
		(pad "1" smd rect
			(at -0.2667 0 90)
			(size 0.3048 0.381)
			(layers "F.Cu" "F.Mask" "F.Paste")
			(net "P5E_PEX0_STN7_TX_DN<118>")
		)
		(pad "2" smd rect
			(at 0.2667 0 90)
			(size 0.3048 0.381)
			(layers "F.Cu" "F.Mask" "F.Paste")
			(net "P5E_PEX0_STN7_TX_C_DN<118>")
		)
	)
	(footprint ""
		(layer "F.Cu")
		(at 219.825316 -123.774962)
		(property "Reference" "R5963"
			(at 0 0 0)
			(layer "F.SilkS")
			(hide yes)
			(effects
				(font
					(size 1.27 1.27)
				)
			)
		)
		(property "Value" ""
			(at 0 0 0)
			(layer "F.Fab")
			(effects
				(font
					(size 1.27 1.27)
				)
			)
		)
		(duplicate_pad_numbers_are_jumpers no)
		(fp_line
			(start -0.7874 -0.4064)
			(end 0.7874 -0.4064)
			(stroke
				(width 0.1524)
				(type default)
			)
			(layer "F.SilkS")
		)
		(fp_line
			(start -0.7874 0.4064)
			(end -0.7874 -0.4064)
			(stroke
				(width 0.1524)
				(type default)
			)
			(layer "F.SilkS")
		)
		(fp_line
			(start 0.7874 -0.4064)
			(end 0.7874 0.4064)
			(stroke
				(width 0.1524)
				(type default)
			)
			(layer "F.SilkS")
		)
		(fp_line
			(start 0.7874 0.4064)
			(end -0.7874 0.4064)
			(stroke
				(width 0.1524)
				(type default)
			)
			(layer "F.SilkS")
		)
		(fp_line
			(start -0.67945 -0.305054)
			(end -0.12065 -0.305054)
			(stroke
				(width 0.1)
				(type default)
			)
			(layer "F.Fab")
		)
		(fp_line
			(start -0.67945 0.3048)
			(end -0.67945 -0.305054)
			(stroke
				(width 0.1)
				(type default)
			)
			(layer "F.Fab")
		)
		(fp_line
			(start -0.12065 -0.305054)
			(end -0.12065 -0.2794)
			(stroke
				(width 0.1)
				(type default)
			)
			(layer "F.Fab")
		)
		(fp_line
			(start -0.12065 -0.2794)
			(end 0.12065 -0.2794)
			(stroke
				(width 0.1)
				(type default)
			)
			(layer "F.Fab")
		)
		(fp_line
			(start -0.12065 0.2794)
			(end -0.12065 0.3048)
			(stroke
				(width 0.1)
				(type default)
			)
			(layer "F.Fab")
		)
		(fp_line
			(start -0.12065 0.3048)
			(end -0.67945 0.3048)
			(stroke
				(width 0.1)
				(type default)
			)
			(layer "F.Fab")
		)
		(fp_line
			(start 0.120396 0.2794)
			(end -0.12065 0.2794)
			(stroke
				(width 0.1)
				(type default)
			)
			(layer "F.Fab")
		)
		(fp_line
			(start 0.120396 0.3048)
			(end 0.120396 0.2794)
			(stroke
				(width 0.1)
				(type default)
			)
			(layer "F.Fab")
		)
		(fp_line
			(start 0.12065 -0.3048)
			(end 0.67945 -0.3048)
			(stroke
				(width 0.1)
				(type default)
			)
			(layer "F.Fab")
		)
		(fp_line
			(start 0.12065 -0.2794)
			(end 0.12065 -0.3048)
			(stroke
				(width 0.1)
				(type default)
			)
			(layer "F.Fab")
		)
		(fp_line
			(start 0.67945 -0.3048)
			(end 0.67945 0.3048)
			(stroke
				(width 0.1)
				(type default)
			)
			(layer "F.Fab")
		)
		(fp_line
			(start 0.67945 0.3048)
			(end 0.120396 0.3048)
			(stroke
				(width 0.1)
				(type default)
			)
			(layer "F.Fab")
		)
		(pad "1" smd circle
			(at -0.40005 0)
			(size 0 0)
			(layers "F.Cu" "F.Mask" "F.Paste")
			(net "P3V3_NIC3")
		)
		(pad "2" smd circle
			(at 0.40005 0)
			(size 0 0)
			(layers "F.Cu" "F.Mask" "F.Paste")
			(net "P3V3_NIC3_PG_G1")
		)
	)
	(footprint ""
		(layer "F.Cu")
		(at 104.564942 -114.833654 -90)
		(property "Reference" "PC611"
			(at 0 0 270)
			(layer "F.SilkS")
			(hide yes)
			(effects
				(font
					(size 1.27 1.27)
				)
			)
		)
		(property "Value" ""
			(at 0 0 270)
			(layer "F.Fab")
			(effects
				(font
					(size 1.27 1.27)
				)
			)
		)
		(duplicate_pad_numbers_are_jumpers no)
		(fp_line
			(start -1.2954 0.5842)
			(end -1.2954 -0.5842)
			(stroke
				(width 0.1524)
				(type default)
			)
			(layer "F.SilkS")
		)
		(fp_line
			(start 1.2954 0.5842)
			(end -1.2954 0.5842)
			(stroke
				(width 0.1524)
				(type default)
			)
			(layer "F.SilkS")
		)
		(fp_line
			(start -1.2954 -0.5842)
			(end 1.2954 -0.5842)
			(stroke
				(width 0.1524)
				(type default)
			)
			(layer "F.SilkS")
		)
		(fp_line
			(start 1.2954 -0.5842)
			(end 1.2954 0.5842)
			(stroke
				(width 0.1524)
				(type default)
			)
			(layer "F.SilkS")
		)
		(fp_line
			(start -0.8636 0.4572)
			(end -0.8636 0.4064)
			(stroke
				(width 0.1)
				(type default)
			)
			(layer "F.Fab")
		)
		(fp_line
			(start 0.8636 0.4572)
			(end -0.8636 0.4572)
			(stroke
				(width 0.1)
				(type default)
			)
			(layer "F.Fab")
		)
		(fp_line
			(start -1.1938 0.4064)
			(end -1.1938 -0.4064)
			(stroke
				(width 0.1)
				(type default)
			)
			(layer "F.Fab")
		)
		(fp_line
			(start -0.8636 0.4064)
			(end -1.1938 0.4064)
			(stroke
				(width 0.1)
				(type default)
			)
			(layer "F.Fab")
		)
		(fp_line
			(start 0.8636 0.4064)
			(end 0.8636 0.4572)
			(stroke
				(width 0.1)
				(type default)
			)
			(layer "F.Fab")
		)
		(fp_line
			(start 1.1938 0.4064)
			(end 0.8636 0.4064)
			(stroke
				(width 0.1)
				(type default)
			)
			(layer "F.Fab")
		)
		(fp_line
			(start -1.1938 -0.4064)
			(end -0.8636 -0.4064)
			(stroke
				(width 0.1)
				(type default)
			)
			(layer "F.Fab")
		)
		(fp_line
			(start -0.8636 -0.4064)
			(end -0.8636 -0.4572)
			(stroke
				(width 0.1)
				(type default)
			)
			(layer "F.Fab")
		)
		(fp_line
			(start 0.8636 -0.4064)
			(end 1.1938 -0.4064)
			(stroke
				(width 0.1)
				(type default)
			)
			(layer "F.Fab")
		)
		(fp_line
			(start 1.1938 -0.4064)
			(end 1.1938 0.4064)
			(stroke
				(width 0.1)
				(type default)
			)
			(layer "F.Fab")
		)
		(fp_line
			(start -0.8636 -0.4572)
			(end 0.8636 -0.4572)
			(stroke
				(width 0.1)
				(type default)
			)
			(layer "F.Fab")
		)
		(fp_line
			(start 0.8636 -0.4572)
			(end 0.8636 -0.4064)
			(stroke
				(width 0.1)
				(type default)
			)
			(layer "F.Fab")
		)
		(pad "1" smd rect
			(at -0.7366 0 180)
			(size 0.7112 0.8128)
			(layers "F.Cu" "F.Mask" "F.Paste")
			(net "GND")
		)
		(pad "2" smd rect
			(at 0.7366 0 180)
			(size 0.7112 0.8128)
			(layers "F.Cu" "F.Mask" "F.Paste")
			(net "P12V_NIC1_CO_AVIN_PD")
		)
	)
	(footprint ""
		(layer "F.Cu")
		(at 241.075464 -218.80576)
		(property "Reference" "C3616"
			(at 0 0 0)
			(layer "F.SilkS")
			(hide yes)
			(effects
				(font
					(size 1.27 1.27)
				)
			)
		)
		(property "Value" ""
			(at 0 0 0)
			(layer "F.Fab")
			(effects
				(font
					(size 1.27 1.27)
				)
			)
		)
		(duplicate_pad_numbers_are_jumpers no)
		(fp_line
			(start -0.69215 -0.2921)
			(end 0.69215 -0.2921)
			(stroke
				(width 0.1524)
				(type default)
			)
			(layer "F.SilkS")
		)
		(fp_line
			(start -0.69215 0.2921)
			(end -0.69215 -0.2921)
			(stroke
				(width 0.1524)
				(type default)
			)
			(layer "F.SilkS")
		)
		(fp_line
			(start 0.69215 -0.2921)
			(end 0.69215 0.2921)
			(stroke
				(width 0.1524)
				(type default)
			)
			(layer "F.SilkS")
		)
		(fp_line
			(start 0.69215 0.2921)
			(end -0.69215 0.2921)
			(stroke
				(width 0.1524)
				(type default)
			)
			(layer "F.SilkS")
		)
		(fp_line
			(start -0.51435 -0.2794)
			(end 0.51435 -0.2794)
			(stroke
				(width 0.1)
				(type default)
			)
			(layer "F.Fab")
		)
		(fp_line
			(start -0.51435 0.2794)
			(end -0.51435 -0.2794)
			(stroke
				(width 0.1)
				(type default)
			)
			(layer "F.Fab")
		)
		(fp_line
			(start 0.51435 -0.2794)
			(end 0.51435 0.2794)
			(stroke
				(width 0.1)
				(type default)
			)
			(layer "F.Fab")
		)
		(fp_line
			(start 0.51435 0.2794)
			(end -0.51435 0.2794)
			(stroke
				(width 0.1)
				(type default)
			)
			(layer "F.Fab")
		)
		(pad "1" smd circle
			(at -0.40005 0)
			(size 0 0)
			(layers "F.Cu" "F.Mask" "F.Paste")
			(net "BIC_ADCVREFN0")
		)
		(pad "2" smd circle
			(at 0.40005 0)
			(size 0 0)
			(layers "F.Cu" "F.Mask" "F.Paste")
			(net "GND")
		)
		(zone
			(layer "F.Cu")
			(hatch none 0.5)
			(connect_pads
				(clearance 0)
			)
			(min_thickness 0.25)
			(keepout
				(tracks not_allowed)
				(vias allowed)
				(pads allowed)
				(copperpour not_allowed)
				(footprints allowed)
			)
			(placement
				(enabled no)
				(sheetname "")
			)
			(fill
				(thermal_gap 0.5)
				(thermal_bridge_width 0.5)
				(island_removal_mode 0)
			)
			(polygon
				(pts
					(xy 240.884964 -218.71813) (xy 240.976404 -218.659964) (xy 241.175794 -218.659964) (xy 241.265964 -218.71813)
					(xy 241.265964 -218.89339) (xy 241.175794 -218.95181) (xy 240.976404 -218.95181) (xy 240.884964 -218.893644)
				)
			)
		)
	)
	(footprint ""
		(layer "F.Cu")
		(at 279.774396 -414.88995 -90)
		(property "Reference" "R1809"
			(at 0 0 270)
			(layer "F.SilkS")
			(hide yes)
			(effects
				(font
					(size 1.27 1.27)
				)
			)
		)
		(property "Value" ""
			(at 0 0 270)
			(layer "F.Fab")
			(effects
				(font
					(size 1.27 1.27)
				)
			)
		)
		(duplicate_pad_numbers_are_jumpers no)
		(fp_line
			(start -0.7874 0.4064)
			(end -0.7874 -0.4064)
			(stroke
				(width 0.1524)
				(type default)
			)
			(layer "F.SilkS")
		)
		(fp_line
			(start 0.7874 0.4064)
			(end -0.7874 0.4064)
			(stroke
				(width 0.1524)
				(type default)
			)
			(layer "F.SilkS")
		)
		(fp_line
			(start -0.7874 -0.4064)
			(end 0.7874 -0.4064)
			(stroke
				(width 0.1524)
				(type default)
			)
			(layer "F.SilkS")
		)
		(fp_line
			(start 0.7874 -0.4064)
			(end 0.7874 0.4064)
			(stroke
				(width 0.1524)
				(type default)
			)
			(layer "F.SilkS")
		)
		(fp_line
			(start -0.67945 0.3048)
			(end -0.67945 -0.305054)
			(stroke
				(width 0.1)
				(type default)
			)
			(layer "F.Fab")
		)
		(fp_line
			(start -0.12065 0.3048)
			(end -0.67945 0.3048)
			(stroke
				(width 0.1)
				(type default)
			)
			(layer "F.Fab")
		)
		(fp_line
			(start 0.120396 0.3048)
			(end 0.120396 0.2794)
			(stroke
				(width 0.1)
				(type default)
			)
			(layer "F.Fab")
		)
		(fp_line
			(start 0.67945 0.3048)
			(end 0.120396 0.3048)
			(stroke
				(width 0.1)
				(type default)
			)
			(layer "F.Fab")
		)
		(fp_line
			(start -0.12065 0.2794)
			(end -0.12065 0.3048)
			(stroke
				(width 0.1)
				(type default)
			)
			(layer "F.Fab")
		)
		(fp_line
			(start 0.120396 0.2794)
			(end -0.12065 0.2794)
			(stroke
				(width 0.1)
				(type default)
			)
			(layer "F.Fab")
		)
		(fp_line
			(start -0.12065 -0.2794)
			(end 0.12065 -0.2794)
			(stroke
				(width 0.1)
				(type default)
			)
			(layer "F.Fab")
		)
		(fp_line
			(start 0.12065 -0.2794)
			(end 0.12065 -0.3048)
			(stroke
				(width 0.1)
				(type default)
			)
			(layer "F.Fab")
		)
		(fp_line
			(start 0.12065 -0.3048)
			(end 0.67945 -0.3048)
			(stroke
				(width 0.1)
				(type default)
			)
			(layer "F.Fab")
		)
		(fp_line
			(start 0.67945 -0.3048)
			(end 0.67945 0.3048)
			(stroke
				(width 0.1)
				(type default)
			)
			(layer "F.Fab")
		)
		(fp_line
			(start -0.67945 -0.305054)
			(end -0.12065 -0.305054)
			(stroke
				(width 0.1)
				(type default)
			)
			(layer "F.Fab")
		)
		(fp_line
			(start -0.12065 -0.305054)
			(end -0.12065 -0.2794)
			(stroke
				(width 0.1)
				(type default)
			)
			(layer "F.Fab")
		)
		(pad "1" smd circle
			(at -0.40005 0 270)
			(size 0 0)
			(layers "F.Cu" "F.Mask" "F.Paste")
			(net "P3V3_AUX")
		)
		(pad "2" smd circle
			(at 0.40005 0 270)
			(size 0 0)
			(layers "F.Cu" "F.Mask" "F.Paste")
			(net "MB_BIC_MON")
		)
	)
	(footprint ""
		(layer "F.Cu")
		(at 322.39712 -309.0418 135)
		(property "Reference" "R1385"
			(at 0 0 135)
			(layer "F.SilkS")
			(hide yes)
			(effects
				(font
					(size 1.27 1.27)
				)
			)
		)
		(property "Value" ""
			(at 0 0 135)
			(layer "F.Fab")
			(effects
				(font
					(size 1.27 1.27)
				)
			)
		)
		(duplicate_pad_numbers_are_jumpers no)
		(fp_line
			(start 0.787389 -0.406267)
			(end 0.787389 0.406267)
			(stroke
				(width 0.1524)
				(type default)
			)
			(layer "F.SilkS")
		)
		(fp_line
			(start 0.787389 0.406267)
			(end -0.787389 0.406267)
			(stroke
				(width 0.1524)
				(type default)
			)
			(layer "F.SilkS")
		)
		(fp_line
			(start -0.787389 -0.406267)
			(end 0.787389 -0.406267)
			(stroke
				(width 0.1524)
				(type default)
			)
			(layer "F.SilkS")
		)
		(fp_line
			(start -0.787389 0.406267)
			(end -0.787389 -0.406267)
			(stroke
				(width 0.1524)
				(type default)
			)
			(layer "F.SilkS")
		)
		(fp_line
			(start 0.679446 -0.30479)
			(end 0.679446 0.30479)
			(stroke
				(width 0.1)
				(type default)
			)
			(layer "F.Fab")
		)
		(fp_line
			(start 0.120515 -0.30479)
			(end 0.679446 -0.30479)
			(stroke
				(width 0.1)
				(type default)
			)
			(layer "F.Fab")
		)
		(fp_line
			(start 0.120695 -0.279466)
			(end 0.120515 -0.30479)
			(stroke
				(width 0.1)
				(type default)
			)
			(layer "F.Fab")
		)
		(fp_line
			(start 0.679446 0.30479)
			(end 0.120515 0.30479)
			(stroke
				(width 0.1)
				(type default)
			)
			(layer "F.Fab")
		)
		(fp_line
			(start -0.120695 -0.304969)
			(end -0.120695 -0.279466)
			(stroke
				(width 0.1)
				(type default)
			)
			(layer "F.Fab")
		)
		(fp_line
			(start -0.120695 -0.279466)
			(end 0.120695 -0.279466)
			(stroke
				(width 0.1)
				(type default)
			)
			(layer "F.Fab")
		)
		(fp_line
			(start 0.120335 0.279466)
			(end -0.120695 0.279466)
			(stroke
				(width 0.1)
				(type default)
			)
			(layer "F.Fab")
		)
		(fp_line
			(start 0.120515 0.30479)
			(end 0.120335 0.279466)
			(stroke
				(width 0.1)
				(type default)
			)
			(layer "F.Fab")
		)
		(fp_line
			(start -0.679446 -0.305149)
			(end -0.120695 -0.304969)
			(stroke
				(width 0.1)
				(type default)
			)
			(layer "F.Fab")
		)
		(fp_line
			(start -0.120695 0.279466)
			(end -0.120515 0.30479)
			(stroke
				(width 0.1)
				(type default)
			)
			(layer "F.Fab")
		)
		(fp_line
			(start -0.120515 0.30479)
			(end -0.679446 0.30479)
			(stroke
				(width 0.1)
				(type default)
			)
			(layer "F.Fab")
		)
		(fp_line
			(start -0.679446 0.30479)
			(end -0.679446 -0.305149)
			(stroke
				(width 0.1)
				(type default)
			)
			(layer "F.Fab")
		)
		(pad "1" smd circle
			(at -0.40005 0 135)
			(size 0 0)
			(layers "F.Cu" "F.Mask" "F.Paste")
			(net "GND")
		)
		(pad "2" smd circle
			(at 0.40005 0 135)
			(size 0 0)
			(layers "F.Cu" "F.Mask" "F.Paste")
			(net "PEX2_SPARE2")
		)
	)
	(footprint ""
		(layer "F.Cu")
		(at 35.3695 -260.088634 -90)
		(property "Reference" "R4561"
			(at 0 0 270)
			(layer "F.SilkS")
			(hide yes)
			(effects
				(font
					(size 1.27 1.27)
				)
			)
		)
		(property "Value" ""
			(at 0 0 270)
			(layer "F.Fab")
			(effects
				(font
					(size 1.27 1.27)
				)
			)
		)
		(duplicate_pad_numbers_are_jumpers no)
		(fp_line
			(start -0.7874 0.4064)
			(end -0.7874 -0.4064)
			(stroke
				(width 0.1524)
				(type default)
			)
			(layer "F.SilkS")
		)
		(fp_line
			(start 0.7874 0.4064)
			(end -0.7874 0.4064)
			(stroke
				(width 0.1524)
				(type default)
			)
			(layer "F.SilkS")
		)
		(fp_line
			(start -0.7874 -0.4064)
			(end 0.7874 -0.4064)
			(stroke
				(width 0.1524)
				(type default)
			)
			(layer "F.SilkS")
		)
		(fp_line
			(start 0.7874 -0.4064)
			(end 0.7874 0.4064)
			(stroke
				(width 0.1524)
				(type default)
			)
			(layer "F.SilkS")
		)
		(fp_line
			(start -0.67945 0.3048)
			(end -0.67945 -0.305054)
			(stroke
				(width 0.1)
				(type default)
			)
			(layer "F.Fab")
		)
		(fp_line
			(start -0.12065 0.3048)
			(end -0.67945 0.3048)
			(stroke
				(width 0.1)
				(type default)
			)
			(layer "F.Fab")
		)
		(fp_line
			(start 0.120396 0.3048)
			(end 0.120396 0.2794)
			(stroke
				(width 0.1)
				(type default)
			)
			(layer "F.Fab")
		)
		(fp_line
			(start 0.67945 0.3048)
			(end 0.120396 0.3048)
			(stroke
				(width 0.1)
				(type default)
			)
			(layer "F.Fab")
		)
		(fp_line
			(start -0.12065 0.2794)
			(end -0.12065 0.3048)
			(stroke
				(width 0.1)
				(type default)
			)
			(layer "F.Fab")
		)
		(fp_line
			(start 0.120396 0.2794)
			(end -0.12065 0.2794)
			(stroke
				(width 0.1)
				(type default)
			)
			(layer "F.Fab")
		)
		(fp_line
			(start -0.12065 -0.2794)
			(end 0.12065 -0.2794)
			(stroke
				(width 0.1)
				(type default)
			)
			(layer "F.Fab")
		)
		(fp_line
			(start 0.12065 -0.2794)
			(end 0.12065 -0.3048)
			(stroke
				(width 0.1)
				(type default)
			)
			(layer "F.Fab")
		)
		(fp_line
			(start 0.12065 -0.3048)
			(end 0.67945 -0.3048)
			(stroke
				(width 0.1)
				(type default)
			)
			(layer "F.Fab")
		)
		(fp_line
			(start 0.67945 -0.3048)
			(end 0.67945 0.3048)
			(stroke
				(width 0.1)
				(type default)
			)
			(layer "F.Fab")
		)
		(fp_line
			(start -0.67945 -0.305054)
			(end -0.12065 -0.305054)
			(stroke
				(width 0.1)
				(type default)
			)
			(layer "F.Fab")
		)
		(fp_line
			(start -0.12065 -0.305054)
			(end -0.12065 -0.2794)
			(stroke
				(width 0.1)
				(type default)
			)
			(layer "F.Fab")
		)
		(pad "1" smd circle
			(at -0.40005 0 270)
			(size 0 0)
			(layers "F.Cu" "F.Mask" "F.Paste")
			(net "PCEPLL3_VDDA18_PEX0")
		)
		(pad "2" smd circle
			(at 0.40005 0 270)
			(size 0 0)
			(layers "F.Cu" "F.Mask" "F.Paste")
			(net "PCEPLL3_VDDA18_PEX0_R")
		)
	)
	(footprint ""
		(layer "F.Cu")
		(at 449.862702 -100.406708 -90)
		(property "Reference" "PC331"
			(at 0 0 270)
			(layer "F.SilkS")
			(hide yes)
			(effects
				(font
					(size 1.27 1.27)
				)
			)
		)
		(property "Value" ""
			(at 0 0 270)
			(layer "F.Fab")
			(effects
				(font
					(size 1.27 1.27)
				)
			)
		)
		(duplicate_pad_numbers_are_jumpers no)
		(fp_line
			(start -1.524 0.762)
			(end -1.524 -0.762)
			(stroke
				(width 0.1524)
				(type default)
			)
			(layer "F.SilkS")
		)
		(fp_line
			(start 1.524 0.762)
			(end -1.524 0.762)
			(stroke
				(width 0.1524)
				(type default)
			)
			(layer "F.SilkS")
		)
		(fp_line
			(start -1.524 -0.762)
			(end 1.524 -0.762)
			(stroke
				(width 0.1524)
				(type default)
			)
			(layer "F.SilkS")
		)
		(fp_line
			(start 1.524 -0.762)
			(end 1.524 0.762)
			(stroke
				(width 0.1524)
				(type default)
			)
			(layer "F.SilkS")
		)
		(fp_line
			(start -1.1049 0.724916)
			(end 1.1049 0.724916)
			(stroke
				(width 0.1)
				(type default)
			)
			(layer "F.Fab")
		)
		(fp_line
			(start 1.1049 0.724916)
			(end 1.1049 -0.724916)
			(stroke
				(width 0.1)
				(type default)
			)
			(layer "F.Fab")
		)
		(fp_line
			(start -1.1049 -0.724916)
			(end -1.1049 0.724916)
			(stroke
				(width 0.1)
				(type default)
			)
			(layer "F.Fab")
		)
		(fp_line
			(start 1.1049 -0.724916)
			(end -1.1049 -0.724916)
			(stroke
				(width 0.1)
				(type default)
			)
			(layer "F.Fab")
		)
		(pad "1" smd rect
			(at -0.889 0 90)
			(size 1.016 1.27)
			(layers "F.Cu" "F.Mask" "F.Paste")
			(net "GND")
		)
		(pad "2" smd rect
			(at 0.889 0 90)
			(size 1.016 1.27)
			(layers "F.Cu" "F.Mask" "F.Paste")
			(net "P12V_AUX")
		)
	)
	(footprint ""
		(layer "F.Cu")
		(at 497.694712 -548.965882 180)
		(property "Reference" "SCREW_0"
			(at -3.2385 -1.402334 0)
			(unlocked yes)
			(layer "B.SilkS")
			(effects
				(font
					(size 0.7874 0.5842)
					(thickness 0.1524)
				)
				(justify mirror)
			)
		)
		(property "Value" ""
			(at 0 0 180)
			(layer "F.Fab")
			(effects
				(font
					(size 1.27 1.27)
				)
			)
		)
		(duplicate_pad_numbers_are_jumpers no)
		(pad "1" thru_hole circle
			(at 0 0 180)
			(size 0.4572 0.4572)
			(drill 0.2032)
			(layers "*.Cu" "*.Mask")
			(remove_unused_layers no)
			(net "Net_9164")
			(clearance 0.127)
			(thermal_gap 0.127)
			(padstack
				(mode front_inner_back)
				(layer "Inner"
					(shape circle)
					(size 0.4572 0.4572)
					(clearance 0.127)
				)
				(layer "B.Cu"
					(shape circle)
					(size 0.508 0.508)
					(clearance 0.1016)
				)
			)
		)
	)
	(footprint ""
		(layer "F.Cu")
		(at 77.806042 -350.098614 90)
		(property "Reference" "C144"
			(at 0 0 90)
			(layer "F.SilkS")
			(hide yes)
			(effects
				(font
					(size 1.27 1.27)
				)
			)
		)
		(property "Value" ""
			(at 0 0 90)
			(layer "F.Fab")
			(effects
				(font
					(size 1.27 1.27)
				)
			)
		)
		(duplicate_pad_numbers_are_jumpers no)
		(fp_line
			(start 0.299974 -0.150114)
			(end 0.299974 0.150114)
			(stroke
				(width 0.1)
				(type default)
			)
			(layer "F.Fab")
		)
		(fp_line
			(start -0.299974 -0.150114)
			(end 0.299974 -0.150114)
			(stroke
				(width 0.1)
				(type default)
			)
			(layer "F.Fab")
		)
		(fp_line
			(start 0.299974 0.150114)
			(end -0.299974 0.150114)
			(stroke
				(width 0.1)
				(type default)
			)
			(layer "F.Fab")
		)
		(fp_line
			(start -0.299974 0.150114)
			(end -0.299974 -0.150114)
			(stroke
				(width 0.1)
				(type default)
			)
			(layer "F.Fab")
		)
		(pad "1" smd rect
			(at -0.2667 0 90)
			(size 0.3048 0.381)
			(layers "F.Cu" "F.Mask" "F.Paste")
			(net "P5E_PEX0_STN6_TX_DN<104>")
		)
		(pad "2" smd rect
			(at 0.2667 0 90)
			(size 0.3048 0.381)
			(layers "F.Cu" "F.Mask" "F.Paste")
			(net "P5E_PEX0_STN6_TX_C_DN<104>")
		)
	)
	(footprint ""
		(layer "F.Cu")
		(at 252.98146 -195.573396 -90)
		(property "Reference" "R4301"
			(at 0 0 270)
			(layer "F.SilkS")
			(hide yes)
			(effects
				(font
					(size 1.27 1.27)
				)
			)
		)
		(property "Value" ""
			(at 0 0 270)
			(layer "F.Fab")
			(effects
				(font
					(size 1.27 1.27)
				)
			)
		)
		(duplicate_pad_numbers_are_jumpers no)
		(fp_line
			(start -0.7874 0.4064)
			(end -0.7874 -0.4064)
			(stroke
				(width 0.1524)
				(type default)
			)
			(layer "F.SilkS")
		)
		(fp_line
			(start 0.7874 0.4064)
			(end -0.7874 0.4064)
			(stroke
				(width 0.1524)
				(type default)
			)
			(layer "F.SilkS")
		)
		(fp_line
			(start -0.7874 -0.4064)
			(end 0.7874 -0.4064)
			(stroke
				(width 0.1524)
				(type default)
			)
			(layer "F.SilkS")
		)
		(fp_line
			(start 0.7874 -0.4064)
			(end 0.7874 0.4064)
			(stroke
				(width 0.1524)
				(type default)
			)
			(layer "F.SilkS")
		)
		(fp_line
			(start -0.67945 0.3048)
			(end -0.67945 -0.305054)
			(stroke
				(width 0.1)
				(type default)
			)
			(layer "F.Fab")
		)
		(fp_line
			(start -0.12065 0.3048)
			(end -0.67945 0.3048)
			(stroke
				(width 0.1)
				(type default)
			)
			(layer "F.Fab")
		)
		(fp_line
			(start 0.120396 0.3048)
			(end 0.120396 0.2794)
			(stroke
				(width 0.1)
				(type default)
			)
			(layer "F.Fab")
		)
		(fp_line
			(start 0.67945 0.3048)
			(end 0.120396 0.3048)
			(stroke
				(width 0.1)
				(type default)
			)
			(layer "F.Fab")
		)
		(fp_line
			(start -0.12065 0.2794)
			(end -0.12065 0.3048)
			(stroke
				(width 0.1)
				(type default)
			)
			(layer "F.Fab")
		)
		(fp_line
			(start 0.120396 0.2794)
			(end -0.12065 0.2794)
			(stroke
				(width 0.1)
				(type default)
			)
			(layer "F.Fab")
		)
		(fp_line
			(start -0.12065 -0.2794)
			(end 0.12065 -0.2794)
			(stroke
				(width 0.1)
				(type default)
			)
			(layer "F.Fab")
		)
		(fp_line
			(start 0.12065 -0.2794)
			(end 0.12065 -0.3048)
			(stroke
				(width 0.1)
				(type default)
			)
			(layer "F.Fab")
		)
		(fp_line
			(start 0.12065 -0.3048)
			(end 0.67945 -0.3048)
			(stroke
				(width 0.1)
				(type default)
			)
			(layer "F.Fab")
		)
		(fp_line
			(start 0.67945 -0.3048)
			(end 0.67945 0.3048)
			(stroke
				(width 0.1)
				(type default)
			)
			(layer "F.Fab")
		)
		(fp_line
			(start -0.67945 -0.305054)
			(end -0.12065 -0.305054)
			(stroke
				(width 0.1)
				(type default)
			)
			(layer "F.Fab")
		)
		(fp_line
			(start -0.12065 -0.305054)
			(end -0.12065 -0.2794)
			(stroke
				(width 0.1)
				(type default)
			)
			(layer "F.Fab")
		)
		(pad "1" smd circle
			(at -0.40005 0 270)
			(size 0 0)
			(layers "F.Cu" "F.Mask" "F.Paste")
			(net "JTAG_PLD_TCK")
		)
		(pad "2" smd circle
			(at 0.40005 0 270)
			(size 0 0)
			(layers "F.Cu" "F.Mask" "F.Paste")
			(net "JTAG_FPGA_TCK")
		)
	)
	(footprint ""
		(layer "F.Cu")
		(at 458.68971 -273.224752)
		(property "Reference" "C4389"
			(at 0 0 0)
			(layer "F.SilkS")
			(hide yes)
			(effects
				(font
					(size 1.27 1.27)
				)
			)
		)
		(property "Value" ""
			(at 0 0 0)
			(layer "F.Fab")
			(effects
				(font
					(size 1.27 1.27)
				)
			)
		)
		(duplicate_pad_numbers_are_jumpers no)
		(fp_line
			(start -1.2954 -0.5842)
			(end 1.2954 -0.5842)
			(stroke
				(width 0.1524)
				(type default)
			)
			(layer "F.SilkS")
		)
		(fp_line
			(start -1.2954 0.5842)
			(end -1.2954 -0.5842)
			(stroke
				(width 0.1524)
				(type default)
			)
			(layer "F.SilkS")
		)
		(fp_line
			(start 1.2954 -0.5842)
			(end 1.2954 0.5842)
			(stroke
				(width 0.1524)
				(type default)
			)
			(layer "F.SilkS")
		)
		(fp_line
			(start 1.2954 0.5842)
			(end -1.2954 0.5842)
			(stroke
				(width 0.1524)
				(type default)
			)
			(layer "F.SilkS")
		)
		(fp_line
			(start -1.1938 -0.4064)
			(end -0.8636 -0.4064)
			(stroke
				(width 0.1)
				(type default)
			)
			(layer "F.Fab")
		)
		(fp_line
			(start -1.1938 0.4064)
			(end -1.1938 -0.4064)
			(stroke
				(width 0.1)
				(type default)
			)
			(layer "F.Fab")
		)
		(fp_line
			(start -0.8636 -0.4572)
			(end 0.8636 -0.4572)
			(stroke
				(width 0.1)
				(type default)
			)
			(layer "F.Fab")
		)
		(fp_line
			(start -0.8636 -0.4064)
			(end -0.8636 -0.4572)
			(stroke
				(width 0.1)
				(type default)
			)
			(layer "F.Fab")
		)
		(fp_line
			(start -0.8636 0.4064)
			(end -1.1938 0.4064)
			(stroke
				(width 0.1)
				(type default)
			)
			(layer "F.Fab")
		)
		(fp_line
			(start -0.8636 0.4572)
			(end -0.8636 0.4064)
			(stroke
				(width 0.1)
				(type default)
			)
			(layer "F.Fab")
		)
		(fp_line
			(start 0.8636 -0.4572)
			(end 0.8636 -0.4064)
			(stroke
				(width 0.1)
				(type default)
			)
			(layer "F.Fab")
		)
		(fp_line
			(start 0.8636 -0.4064)
			(end 1.1938 -0.4064)
			(stroke
				(width 0.1)
				(type default)
			)
			(layer "F.Fab")
		)
		(fp_line
			(start 0.8636 0.4064)
			(end 0.8636 0.4572)
			(stroke
				(width 0.1)
				(type default)
			)
			(layer "F.Fab")
		)
		(fp_line
			(start 0.8636 0.4572)
			(end -0.8636 0.4572)
			(stroke
				(width 0.1)
				(type default)
			)
			(layer "F.Fab")
		)
		(fp_line
			(start 1.1938 -0.4064)
			(end 1.1938 0.4064)
			(stroke
				(width 0.1)
				(type default)
			)
			(layer "F.Fab")
		)
		(fp_line
			(start 1.1938 0.4064)
			(end 0.8636 0.4064)
			(stroke
				(width 0.1)
				(type default)
			)
			(layer "F.Fab")
		)
		(pad "1" smd rect
			(at -0.7366 0 270)
			(size 0.7112 0.8128)
			(layers "F.Cu" "F.Mask" "F.Paste")
			(net "P1V25_PEX3")
		)
		(pad "2" smd rect
			(at 0.7366 0 270)
			(size 0.7112 0.8128)
			(layers "F.Cu" "F.Mask" "F.Paste")
			(net "GND")
		)
	)
	(footprint ""
		(layer "F.Cu")
		(at 60.17895 -59.577986 -90)
		(property "Reference" "R890"
			(at 0 0 270)
			(layer "F.SilkS")
			(hide yes)
			(effects
				(font
					(size 1.27 1.27)
				)
			)
		)
		(property "Value" ""
			(at 0 0 270)
			(layer "F.Fab")
			(effects
				(font
					(size 1.27 1.27)
				)
			)
		)
		(duplicate_pad_numbers_are_jumpers no)
		(fp_line
			(start -0.7874 0.4064)
			(end -0.7874 -0.4064)
			(stroke
				(width 0.1524)
				(type default)
			)
			(layer "F.SilkS")
		)
		(fp_line
			(start 0.7874 0.4064)
			(end -0.7874 0.4064)
			(stroke
				(width 0.1524)
				(type default)
			)
			(layer "F.SilkS")
		)
		(fp_line
			(start -0.7874 -0.4064)
			(end 0.7874 -0.4064)
			(stroke
				(width 0.1524)
				(type default)
			)
			(layer "F.SilkS")
		)
		(fp_line
			(start 0.7874 -0.4064)
			(end 0.7874 0.4064)
			(stroke
				(width 0.1524)
				(type default)
			)
			(layer "F.SilkS")
		)
		(fp_line
			(start -0.67945 0.3048)
			(end -0.67945 -0.305054)
			(stroke
				(width 0.1)
				(type default)
			)
			(layer "F.Fab")
		)
		(fp_line
			(start -0.12065 0.3048)
			(end -0.67945 0.3048)
			(stroke
				(width 0.1)
				(type default)
			)
			(layer "F.Fab")
		)
		(fp_line
			(start 0.120396 0.3048)
			(end 0.120396 0.2794)
			(stroke
				(width 0.1)
				(type default)
			)
			(layer "F.Fab")
		)
		(fp_line
			(start 0.67945 0.3048)
			(end 0.120396 0.3048)
			(stroke
				(width 0.1)
				(type default)
			)
			(layer "F.Fab")
		)
		(fp_line
			(start -0.12065 0.2794)
			(end -0.12065 0.3048)
			(stroke
				(width 0.1)
				(type default)
			)
			(layer "F.Fab")
		)
		(fp_line
			(start 0.120396 0.2794)
			(end -0.12065 0.2794)
			(stroke
				(width 0.1)
				(type default)
			)
			(layer "F.Fab")
		)
		(fp_line
			(start -0.12065 -0.2794)
			(end 0.12065 -0.2794)
			(stroke
				(width 0.1)
				(type default)
			)
			(layer "F.Fab")
		)
		(fp_line
			(start 0.12065 -0.2794)
			(end 0.12065 -0.3048)
			(stroke
				(width 0.1)
				(type default)
			)
			(layer "F.Fab")
		)
		(fp_line
			(start 0.12065 -0.3048)
			(end 0.67945 -0.3048)
			(stroke
				(width 0.1)
				(type default)
			)
			(layer "F.Fab")
		)
		(fp_line
			(start 0.67945 -0.3048)
			(end 0.67945 0.3048)
			(stroke
				(width 0.1)
				(type default)
			)
			(layer "F.Fab")
		)
		(fp_line
			(start -0.67945 -0.305054)
			(end -0.12065 -0.305054)
			(stroke
				(width 0.1)
				(type default)
			)
			(layer "F.Fab")
		)
		(fp_line
			(start -0.12065 -0.305054)
			(end -0.12065 -0.2794)
			(stroke
				(width 0.1)
				(type default)
			)
			(layer "F.Fab")
		)
		(pad "1" smd circle
			(at -0.40005 0 270)
			(size 0 0)
			(layers "F.Cu" "F.Mask" "F.Paste")
			(net "P3V3_SSD2")
		)
		(pad "2" smd circle
			(at 0.40005 0 270)
			(size 0 0)
			(layers "F.Cu" "F.Mask" "F.Paste")
			(net "PWRGD_P3V3_SSD2")
		)
	)
	(footprint ""
		(layer "F.Cu")
		(at 258.891278 -346.703142 -90)
		(property "Reference" "R6649"
			(at 0 0 270)
			(layer "F.SilkS")
			(hide yes)
			(effects
				(font
					(size 1.27 1.27)
				)
			)
		)
		(property "Value" ""
			(at 0 0 270)
			(layer "F.Fab")
			(effects
				(font
					(size 1.27 1.27)
				)
			)
		)
		(duplicate_pad_numbers_are_jumpers no)
		(fp_line
			(start -0.7874 0.4064)
			(end -0.7874 -0.4064)
			(stroke
				(width 0.1524)
				(type default)
			)
			(layer "F.SilkS")
		)
		(fp_line
			(start 0.7874 0.4064)
			(end -0.7874 0.4064)
			(stroke
				(width 0.1524)
				(type default)
			)
			(layer "F.SilkS")
		)
		(fp_line
			(start -0.7874 -0.4064)
			(end 0.7874 -0.4064)
			(stroke
				(width 0.1524)
				(type default)
			)
			(layer "F.SilkS")
		)
		(fp_line
			(start 0.7874 -0.4064)
			(end 0.7874 0.4064)
			(stroke
				(width 0.1524)
				(type default)
			)
			(layer "F.SilkS")
		)
		(fp_line
			(start -0.67945 0.3048)
			(end -0.67945 -0.305054)
			(stroke
				(width 0.1)
				(type default)
			)
			(layer "F.Fab")
		)
		(fp_line
			(start -0.12065 0.3048)
			(end -0.67945 0.3048)
			(stroke
				(width 0.1)
				(type default)
			)
			(layer "F.Fab")
		)
		(fp_line
			(start 0.120396 0.3048)
			(end 0.120396 0.2794)
			(stroke
				(width 0.1)
				(type default)
			)
			(layer "F.Fab")
		)
		(fp_line
			(start 0.67945 0.3048)
			(end 0.120396 0.3048)
			(stroke
				(width 0.1)
				(type default)
			)
			(layer "F.Fab")
		)
		(fp_line
			(start -0.12065 0.2794)
			(end -0.12065 0.3048)
			(stroke
				(width 0.1)
				(type default)
			)
			(layer "F.Fab")
		)
		(fp_line
			(start 0.120396 0.2794)
			(end -0.12065 0.2794)
			(stroke
				(width 0.1)
				(type default)
			)
			(layer "F.Fab")
		)
		(fp_line
			(start -0.12065 -0.2794)
			(end 0.12065 -0.2794)
			(stroke
				(width 0.1)
				(type default)
			)
			(layer "F.Fab")
		)
		(fp_line
			(start 0.12065 -0.2794)
			(end 0.12065 -0.3048)
			(stroke
				(width 0.1)
				(type default)
			)
			(layer "F.Fab")
		)
		(fp_line
			(start 0.12065 -0.3048)
			(end 0.67945 -0.3048)
			(stroke
				(width 0.1)
				(type default)
			)
			(layer "F.Fab")
		)
		(fp_line
			(start 0.67945 -0.3048)
			(end 0.67945 0.3048)
			(stroke
				(width 0.1)
				(type default)
			)
			(layer "F.Fab")
		)
		(fp_line
			(start -0.67945 -0.305054)
			(end -0.12065 -0.305054)
			(stroke
				(width 0.1)
				(type default)
			)
			(layer "F.Fab")
		)
		(fp_line
			(start -0.12065 -0.305054)
			(end -0.12065 -0.2794)
			(stroke
				(width 0.1)
				(type default)
			)
			(layer "F.Fab")
		)
		(pad "1" smd circle
			(at -0.40005 0 270)
			(size 0 0)
			(layers "F.Cu" "F.Mask" "F.Paste")
			(net "HSC_CSOUT")
		)
		(pad "2" smd circle
			(at 0.40005 0 270)
			(size 0 0)
			(layers "F.Cu" "F.Mask" "F.Paste")
			(net "A_HSC_HIGH")
		)
	)
	(footprint ""
		(layer "F.Cu")
		(at 368.734594 -34.546286 180)
		(property "Reference" "C698"
			(at 0 0 180)
			(layer "F.SilkS")
			(hide yes)
			(effects
				(font
					(size 1.27 1.27)
				)
			)
		)
		(property "Value" ""
			(at 0 0 180)
			(layer "F.Fab")
			(effects
				(font
					(size 1.27 1.27)
				)
			)
		)
		(duplicate_pad_numbers_are_jumpers no)
		(fp_line
			(start 0.299974 0.150114)
			(end -0.299974 0.150114)
			(stroke
				(width 0.1)
				(type default)
			)
			(layer "F.Fab")
		)
		(fp_line
			(start 0.299974 -0.150114)
			(end 0.299974 0.150114)
			(stroke
				(width 0.1)
				(type default)
			)
			(layer "F.Fab")
		)
		(fp_line
			(start -0.299974 0.150114)
			(end -0.299974 -0.150114)
			(stroke
				(width 0.1)
				(type default)
			)
			(layer "F.Fab")
		)
		(fp_line
			(start -0.299974 -0.150114)
			(end 0.299974 -0.150114)
			(stroke
				(width 0.1)
				(type default)
			)
			(layer "F.Fab")
		)
		(pad "1" smd rect
			(at -0.2667 0 180)
			(size 0.3048 0.381)
			(layers "F.Cu" "F.Mask" "F.Paste")
			(net "P5E_PEX3_STN2_TX_DP<47>")
		)
		(pad "2" smd rect
			(at 0.2667 0 180)
			(size 0.3048 0.381)
			(layers "F.Cu" "F.Mask" "F.Paste")
			(net "P5E_PEX3_STN2_TX_C_DP<47>")
		)
	)
	(footprint ""
		(layer "F.Cu")
		(at 242.006882 -211.272882 -90)
		(property "Reference" "R479"
			(at 0 0 270)
			(layer "F.SilkS")
			(hide yes)
			(effects
				(font
					(size 1.27 1.27)
				)
			)
		)
		(property "Value" ""
			(at 0 0 270)
			(layer "F.Fab")
			(effects
				(font
					(size 1.27 1.27)
				)
			)
		)
		(duplicate_pad_numbers_are_jumpers no)
		(fp_line
			(start -0.7874 0.4064)
			(end -0.7874 -0.4064)
			(stroke
				(width 0.1524)
				(type default)
			)
			(layer "F.SilkS")
		)
		(fp_line
			(start 0.7874 0.4064)
			(end -0.7874 0.4064)
			(stroke
				(width 0.1524)
				(type default)
			)
			(layer "F.SilkS")
		)
		(fp_line
			(start -0.7874 -0.4064)
			(end 0.7874 -0.4064)
			(stroke
				(width 0.1524)
				(type default)
			)
			(layer "F.SilkS")
		)
		(fp_line
			(start 0.7874 -0.4064)
			(end 0.7874 0.4064)
			(stroke
				(width 0.1524)
				(type default)
			)
			(layer "F.SilkS")
		)
		(fp_line
			(start -0.67945 0.3048)
			(end -0.67945 -0.305054)
			(stroke
				(width 0.1)
				(type default)
			)
			(layer "F.Fab")
		)
		(fp_line
			(start -0.12065 0.3048)
			(end -0.67945 0.3048)
			(stroke
				(width 0.1)
				(type default)
			)
			(layer "F.Fab")
		)
		(fp_line
			(start 0.120396 0.3048)
			(end 0.120396 0.2794)
			(stroke
				(width 0.1)
				(type default)
			)
			(layer "F.Fab")
		)
		(fp_line
			(start 0.67945 0.3048)
			(end 0.120396 0.3048)
			(stroke
				(width 0.1)
				(type default)
			)
			(layer "F.Fab")
		)
		(fp_line
			(start -0.12065 0.2794)
			(end -0.12065 0.3048)
			(stroke
				(width 0.1)
				(type default)
			)
			(layer "F.Fab")
		)
		(fp_line
			(start 0.120396 0.2794)
			(end -0.12065 0.2794)
			(stroke
				(width 0.1)
				(type default)
			)
			(layer "F.Fab")
		)
		(fp_line
			(start -0.12065 -0.2794)
			(end 0.12065 -0.2794)
			(stroke
				(width 0.1)
				(type default)
			)
			(layer "F.Fab")
		)
		(fp_line
			(start 0.12065 -0.2794)
			(end 0.12065 -0.3048)
			(stroke
				(width 0.1)
				(type default)
			)
			(layer "F.Fab")
		)
		(fp_line
			(start 0.12065 -0.3048)
			(end 0.67945 -0.3048)
			(stroke
				(width 0.1)
				(type default)
			)
			(layer "F.Fab")
		)
		(fp_line
			(start 0.67945 -0.3048)
			(end 0.67945 0.3048)
			(stroke
				(width 0.1)
				(type default)
			)
			(layer "F.Fab")
		)
		(fp_line
			(start -0.67945 -0.305054)
			(end -0.12065 -0.305054)
			(stroke
				(width 0.1)
				(type default)
			)
			(layer "F.Fab")
		)
		(fp_line
			(start -0.12065 -0.305054)
			(end -0.12065 -0.2794)
			(stroke
				(width 0.1)
				(type default)
			)
			(layer "F.Fab")
		)
		(pad "1" smd circle
			(at -0.40005 0 270)
			(size 0 0)
			(layers "F.Cu" "F.Mask" "F.Paste")
			(net "P3V3")
		)
		(pad "2" smd circle
			(at 0.40005 0 270)
			(size 0 0)
			(layers "F.Cu" "F.Mask" "F.Paste")
			(net "P3V3_SCALED")
		)
	)
	(footprint ""
		(layer "F.Cu")
		(at 137.871962 -259.346192)
		(property "Reference" "R1322"
			(at 0 0 0)
			(layer "F.SilkS")
			(hide yes)
			(effects
				(font
					(size 1.27 1.27)
				)
			)
		)
		(property "Value" ""
			(at 0 0 0)
			(layer "F.Fab")
			(effects
				(font
					(size 1.27 1.27)
				)
			)
		)
		(duplicate_pad_numbers_are_jumpers no)
		(fp_line
			(start -0.7874 -0.4064)
			(end 0.7874 -0.4064)
			(stroke
				(width 0.1524)
				(type default)
			)
			(layer "F.SilkS")
		)
		(fp_line
			(start -0.7874 0.4064)
			(end -0.7874 -0.4064)
			(stroke
				(width 0.1524)
				(type default)
			)
			(layer "F.SilkS")
		)
		(fp_line
			(start 0.7874 -0.4064)
			(end 0.7874 0.4064)
			(stroke
				(width 0.1524)
				(type default)
			)
			(layer "F.SilkS")
		)
		(fp_line
			(start 0.7874 0.4064)
			(end -0.7874 0.4064)
			(stroke
				(width 0.1524)
				(type default)
			)
			(layer "F.SilkS")
		)
		(fp_line
			(start -0.67945 -0.305054)
			(end -0.12065 -0.305054)
			(stroke
				(width 0.1)
				(type default)
			)
			(layer "F.Fab")
		)
		(fp_line
			(start -0.67945 0.3048)
			(end -0.67945 -0.305054)
			(stroke
				(width 0.1)
				(type default)
			)
			(layer "F.Fab")
		)
		(fp_line
			(start -0.12065 -0.305054)
			(end -0.12065 -0.2794)
			(stroke
				(width 0.1)
				(type default)
			)
			(layer "F.Fab")
		)
		(fp_line
			(start -0.12065 -0.2794)
			(end 0.12065 -0.2794)
			(stroke
				(width 0.1)
				(type default)
			)
			(layer "F.Fab")
		)
		(fp_line
			(start -0.12065 0.2794)
			(end -0.12065 0.3048)
			(stroke
				(width 0.1)
				(type default)
			)
			(layer "F.Fab")
		)
		(fp_line
			(start -0.12065 0.3048)
			(end -0.67945 0.3048)
			(stroke
				(width 0.1)
				(type default)
			)
			(layer "F.Fab")
		)
		(fp_line
			(start 0.120396 0.2794)
			(end -0.12065 0.2794)
			(stroke
				(width 0.1)
				(type default)
			)
			(layer "F.Fab")
		)
		(fp_line
			(start 0.120396 0.3048)
			(end 0.120396 0.2794)
			(stroke
				(width 0.1)
				(type default)
			)
			(layer "F.Fab")
		)
		(fp_line
			(start 0.12065 -0.3048)
			(end 0.67945 -0.3048)
			(stroke
				(width 0.1)
				(type default)
			)
			(layer "F.Fab")
		)
		(fp_line
			(start 0.12065 -0.2794)
			(end 0.12065 -0.3048)
			(stroke
				(width 0.1)
				(type default)
			)
			(layer "F.Fab")
		)
		(fp_line
			(start 0.67945 -0.3048)
			(end 0.67945 0.3048)
			(stroke
				(width 0.1)
				(type default)
			)
			(layer "F.Fab")
		)
		(fp_line
			(start 0.67945 0.3048)
			(end 0.120396 0.3048)
			(stroke
				(width 0.1)
				(type default)
			)
			(layer "F.Fab")
		)
		(pad "1" smd circle
			(at -0.40005 0)
			(size 0 0)
			(layers "F.Cu" "F.Mask" "F.Paste")
			(net "PEX1_SYS_ERR_N")
		)
		(pad "2" smd circle
			(at 0.40005 0)
			(size 0 0)
			(layers "F.Cu" "F.Mask" "F.Paste")
			(net "PEX1_SYS_ERR_R_N")
		)
	)
	(footprint ""
		(layer "F.Cu")
		(at 402.795232 -35.48253)
		(property "Reference" "U397"
			(at -2.540762 0.63373 90)
			(unlocked yes)
			(layer "F.SilkS")
			(effects
				(font
					(size 0.7874 0.5842)
					(thickness 0.1524)
				)
				(justify left)
			)
		)
		(property "Value" ""
			(at 0 0 0)
			(layer "F.Fab")
			(effects
				(font
					(size 1.27 1.27)
				)
			)
		)
		(duplicate_pad_numbers_are_jumpers no)
		(fp_line
			(start -1.3462 -1.1938)
			(end -1.3462 1.1684)
			(stroke
				(width 0.1524)
				(type default)
			)
			(layer "F.SilkS")
		)
		(fp_line
			(start -1.3462 1.1938)
			(end 1.3462 1.1938)
			(stroke
				(width 0.1524)
				(type default)
			)
			(layer "F.SilkS")
		)
		(fp_line
			(start 1.3462 -1.1938)
			(end -1.3462 -1.1938)
			(stroke
				(width 0.1524)
				(type default)
			)
			(layer "F.SilkS")
		)
		(fp_line
			(start 1.3462 1.1938)
			(end 1.3462 -1.1938)
			(stroke
				(width 0.1524)
				(type default)
			)
			(layer "F.SilkS")
		)
		(fp_poly
			(pts
				(xy -1.447038 -0.760476) (xy -2.052066 -0.457962) (xy -2.052066 -1.06299)
			)
			(stroke
				(width 0)
				(type default)
			)
			(fill yes)
			(layer "F.SilkS")
		)
		(fp_line
			(start -0.674878 -1.124966)
			(end -0.674878 1.124966)
			(stroke
				(width 0.1)
				(type default)
			)
			(layer "F.Fab")
		)
		(fp_line
			(start -0.674878 1.124966)
			(end 0.674878 1.124966)
			(stroke
				(width 0.1)
				(type default)
			)
			(layer "F.Fab")
		)
		(fp_line
			(start 0.674878 -1.124966)
			(end -0.674878 -1.124966)
			(stroke
				(width 0.1)
				(type default)
			)
			(layer "F.Fab")
		)
		(fp_line
			(start 0.674878 1.124966)
			(end 0.674878 -1.124966)
			(stroke
				(width 0.1)
				(type default)
			)
			(layer "F.Fab")
		)
		(fp_poly
			(pts
				(xy -1.447038 -0.760476) (xy -2.052066 -0.457962) (xy -2.052066 -1.06299)
			)
			(stroke
				(width 0)
				(type default)
			)
			(fill yes)
			(layer "F.Fab")
		)
		(pad "1" smd rect
			(at -0.899922 -0.750062)
			(size 0.6096 0.6096)
			(layers "F.Cu" "F.Mask" "F.Paste")
			(net "PWRGD_P3V3_SSD14_R")
		)
		(pad "2" smd rect
			(at -0.899922 0 90)
			(size 0.4064 0.6096)
			(layers "F.Cu" "F.Mask" "F.Paste")
			(net "RST_SMB_SSD14_N")
		)
		(pad "3" smd rect
			(at -0.899922 0.750062)
			(size 0.6096 0.6096)
			(layers "F.Cu" "F.Mask" "F.Paste")
			(net "GND")
		)
		(pad "4" smd rect
			(at 0.899922 0.750062)
			(size 0.6096 0.6096)
			(layers "F.Cu" "F.Mask" "F.Paste")
			(net "RST_SMB_SSD14_ISO_N")
		)
		(pad "5" smd rect
			(at 0.899922 -0.750062)
			(size 0.6096 0.6096)
			(layers "F.Cu" "F.Mask" "F.Paste")
			(net "P3V3_AUX")
		)
	)
	(footprint ""
		(layer "F.Cu")
		(at 118.688358 -277.639272 180)
		(property "Reference" "PC111"
			(at 0 0 180)
			(layer "F.SilkS")
			(hide yes)
			(effects
				(font
					(size 1.27 1.27)
				)
			)
		)
		(property "Value" ""
			(at 0 0 180)
			(layer "F.Fab")
			(effects
				(font
					(size 1.27 1.27)
				)
			)
		)
		(duplicate_pad_numbers_are_jumpers no)
		(fp_line
			(start 1.524 0.762)
			(end -1.524 0.762)
			(stroke
				(width 0.1524)
				(type default)
			)
			(layer "F.SilkS")
		)
		(fp_line
			(start 1.524 -0.762)
			(end 1.524 0.762)
			(stroke
				(width 0.1524)
				(type default)
			)
			(layer "F.SilkS")
		)
		(fp_line
			(start -1.524 0.762)
			(end -1.524 -0.762)
			(stroke
				(width 0.1524)
				(type default)
			)
			(layer "F.SilkS")
		)
		(fp_line
			(start -1.524 -0.762)
			(end 1.524 -0.762)
			(stroke
				(width 0.1524)
				(type default)
			)
			(layer "F.SilkS")
		)
		(fp_line
			(start 1.1049 0.724916)
			(end 1.1049 -0.724916)
			(stroke
				(width 0.1)
				(type default)
			)
			(layer "F.Fab")
		)
		(fp_line
			(start 1.1049 -0.724916)
			(end -1.1049 -0.724916)
			(stroke
				(width 0.1)
				(type default)
			)
			(layer "F.Fab")
		)
		(fp_line
			(start -1.1049 0.724916)
			(end 1.1049 0.724916)
			(stroke
				(width 0.1)
				(type default)
			)
			(layer "F.Fab")
		)
		(fp_line
			(start -1.1049 -0.724916)
			(end -1.1049 0.724916)
			(stroke
				(width 0.1)
				(type default)
			)
			(layer "F.Fab")
		)
		(pad "1" smd rect
			(at -0.889 0)
			(size 1.016 1.27)
			(layers "F.Cu" "F.Mask" "F.Paste")
			(net "SW_P12V_P0V8_PEX1_FLT")
		)
		(pad "2" smd rect
			(at 0.889 0)
			(size 1.016 1.27)
			(layers "F.Cu" "F.Mask" "F.Paste")
			(net "GND")
		)
	)
	(footprint ""
		(layer "F.Cu")
		(at 283.262324 -22.955504 -90)
		(property "Reference" "C2737"
			(at 0 0 270)
			(layer "F.SilkS")
			(hide yes)
			(effects
				(font
					(size 1.27 1.27)
				)
			)
		)
		(property "Value" ""
			(at 0 0 270)
			(layer "F.Fab")
			(effects
				(font
					(size 1.27 1.27)
				)
			)
		)
		(duplicate_pad_numbers_are_jumpers no)
		(fp_line
			(start -0.7874 0.4064)
			(end -0.7874 -0.4064)
			(stroke
				(width 0.1524)
				(type default)
			)
			(layer "F.SilkS")
		)
		(fp_line
			(start 0.7874 0.4064)
			(end -0.7874 0.4064)
			(stroke
				(width 0.1524)
				(type default)
			)
			(layer "F.SilkS")
		)
		(fp_line
			(start -0.7874 -0.4064)
			(end 0.7874 -0.4064)
			(stroke
				(width 0.1524)
				(type default)
			)
			(layer "F.SilkS")
		)
		(fp_line
			(start 0.7874 -0.4064)
			(end 0.7874 0.4064)
			(stroke
				(width 0.1524)
				(type default)
			)
			(layer "F.SilkS")
		)
		(fp_line
			(start -0.67945 0.3048)
			(end -0.67945 -0.305054)
			(stroke
				(width 0.1)
				(type default)
			)
			(layer "F.Fab")
		)
		(fp_line
			(start -0.12065 0.3048)
			(end -0.67945 0.3048)
			(stroke
				(width 0.1)
				(type default)
			)
			(layer "F.Fab")
		)
		(fp_line
			(start 0.120396 0.3048)
			(end 0.120396 0.2794)
			(stroke
				(width 0.1)
				(type default)
			)
			(layer "F.Fab")
		)
		(fp_line
			(start 0.67945 0.3048)
			(end 0.120396 0.3048)
			(stroke
				(width 0.1)
				(type default)
			)
			(layer "F.Fab")
		)
		(fp_line
			(start -0.12065 0.2794)
			(end -0.12065 0.3048)
			(stroke
				(width 0.1)
				(type default)
			)
			(layer "F.Fab")
		)
		(fp_line
			(start 0.120396 0.2794)
			(end -0.12065 0.2794)
			(stroke
				(width 0.1)
				(type default)
			)
			(layer "F.Fab")
		)
		(fp_line
			(start -0.12065 -0.2794)
			(end 0.12065 -0.2794)
			(stroke
				(width 0.1)
				(type default)
			)
			(layer "F.Fab")
		)
		(fp_line
			(start 0.12065 -0.2794)
			(end 0.12065 -0.3048)
			(stroke
				(width 0.1)
				(type default)
			)
			(layer "F.Fab")
		)
		(fp_line
			(start 0.12065 -0.3048)
			(end 0.67945 -0.3048)
			(stroke
				(width 0.1)
				(type default)
			)
			(layer "F.Fab")
		)
		(fp_line
			(start 0.67945 -0.3048)
			(end 0.67945 0.3048)
			(stroke
				(width 0.1)
				(type default)
			)
			(layer "F.Fab")
		)
		(fp_line
			(start -0.67945 -0.305054)
			(end -0.12065 -0.305054)
			(stroke
				(width 0.1)
				(type default)
			)
			(layer "F.Fab")
		)
		(fp_line
			(start -0.12065 -0.305054)
			(end -0.12065 -0.2794)
			(stroke
				(width 0.1)
				(type default)
			)
			(layer "F.Fab")
		)
		(pad "1" smd circle
			(at -0.40005 0 270)
			(size 0 0)
			(layers "F.Cu" "F.Mask" "F.Paste")
			(net "GND")
		)
		(pad "2" smd circle
			(at 0.40005 0 270)
			(size 0 0)
			(layers "F.Cu" "F.Mask" "F.Paste")
			(net "P3V3_AUX")
		)
	)
	(footprint ""
		(layer "F.Cu")
		(at 38.599872 -154.327352 180)
		(property "Reference" "R26"
			(at 0 0 180)
			(layer "F.SilkS")
			(hide yes)
			(effects
				(font
					(size 1.27 1.27)
				)
			)
		)
		(property "Value" ""
			(at 0 0 180)
			(layer "F.Fab")
			(effects
				(font
					(size 1.27 1.27)
				)
			)
		)
		(duplicate_pad_numbers_are_jumpers no)
		(fp_line
			(start 0.7874 0.4064)
			(end -0.7874 0.4064)
			(stroke
				(width 0.1524)
				(type default)
			)
			(layer "F.SilkS")
		)
		(fp_line
			(start 0.7874 -0.4064)
			(end 0.7874 0.4064)
			(stroke
				(width 0.1524)
				(type default)
			)
			(layer "F.SilkS")
		)
		(fp_line
			(start -0.7874 0.4064)
			(end -0.7874 -0.4064)
			(stroke
				(width 0.1524)
				(type default)
			)
			(layer "F.SilkS")
		)
		(fp_line
			(start -0.7874 -0.4064)
			(end 0.7874 -0.4064)
			(stroke
				(width 0.1524)
				(type default)
			)
			(layer "F.SilkS")
		)
		(fp_line
			(start 0.67945 0.3048)
			(end 0.120396 0.3048)
			(stroke
				(width 0.1)
				(type default)
			)
			(layer "F.Fab")
		)
		(fp_line
			(start 0.67945 -0.3048)
			(end 0.67945 0.3048)
			(stroke
				(width 0.1)
				(type default)
			)
			(layer "F.Fab")
		)
		(fp_line
			(start 0.12065 -0.2794)
			(end 0.12065 -0.3048)
			(stroke
				(width 0.1)
				(type default)
			)
			(layer "F.Fab")
		)
		(fp_line
			(start 0.12065 -0.3048)
			(end 0.67945 -0.3048)
			(stroke
				(width 0.1)
				(type default)
			)
			(layer "F.Fab")
		)
		(fp_line
			(start 0.120396 0.3048)
			(end 0.120396 0.2794)
			(stroke
				(width 0.1)
				(type default)
			)
			(layer "F.Fab")
		)
		(fp_line
			(start 0.120396 0.2794)
			(end -0.12065 0.2794)
			(stroke
				(width 0.1)
				(type default)
			)
			(layer "F.Fab")
		)
		(fp_line
			(start -0.12065 0.3048)
			(end -0.67945 0.3048)
			(stroke
				(width 0.1)
				(type default)
			)
			(layer "F.Fab")
		)
		(fp_line
			(start -0.12065 0.2794)
			(end -0.12065 0.3048)
			(stroke
				(width 0.1)
				(type default)
			)
			(layer "F.Fab")
		)
		(fp_line
			(start -0.12065 -0.2794)
			(end 0.12065 -0.2794)
			(stroke
				(width 0.1)
				(type default)
			)
			(layer "F.Fab")
		)
		(fp_line
			(start -0.12065 -0.305054)
			(end -0.12065 -0.2794)
			(stroke
				(width 0.1)
				(type default)
			)
			(layer "F.Fab")
		)
		(fp_line
			(start -0.67945 0.3048)
			(end -0.67945 -0.305054)
			(stroke
				(width 0.1)
				(type default)
			)
			(layer "F.Fab")
		)
		(fp_line
			(start -0.67945 -0.305054)
			(end -0.12065 -0.305054)
			(stroke
				(width 0.1)
				(type default)
			)
			(layer "F.Fab")
		)
		(pad "1" smd circle
			(at -0.40005 0 180)
			(size 0 0)
			(layers "F.Cu" "F.Mask" "F.Paste")
			(net "NIC0_SLOT_ID0")
		)
		(pad "2" smd circle
			(at 0.40005 0 180)
			(size 0 0)
			(layers "F.Cu" "F.Mask" "F.Paste")
			(net "GND")
		)
	)
	(footprint ""
		(layer "F.Cu")
		(at 52.584096 -29.222954 -90)
		(property "Reference" "PC678"
			(at 0 0 270)
			(layer "F.SilkS")
			(hide yes)
			(effects
				(font
					(size 1.27 1.27)
				)
			)
		)
		(property "Value" ""
			(at 0 0 270)
			(layer "F.Fab")
			(effects
				(font
					(size 1.27 1.27)
				)
			)
		)
		(duplicate_pad_numbers_are_jumpers no)
		(fp_line
			(start -0.7874 0.4064)
			(end -0.7874 -0.4064)
			(stroke
				(width 0.1524)
				(type default)
			)
			(layer "F.SilkS")
		)
		(fp_line
			(start 0.7874 0.4064)
			(end -0.7874 0.4064)
			(stroke
				(width 0.1524)
				(type default)
			)
			(layer "F.SilkS")
		)
		(fp_line
			(start -0.7874 -0.4064)
			(end 0.7874 -0.4064)
			(stroke
				(width 0.1524)
				(type default)
			)
			(layer "F.SilkS")
		)
		(fp_line
			(start 0.7874 -0.4064)
			(end 0.7874 0.4064)
			(stroke
				(width 0.1524)
				(type default)
			)
			(layer "F.SilkS")
		)
		(fp_line
			(start -0.67945 0.3048)
			(end -0.67945 -0.305054)
			(stroke
				(width 0.1)
				(type default)
			)
			(layer "F.Fab")
		)
		(fp_line
			(start -0.12065 0.3048)
			(end -0.67945 0.3048)
			(stroke
				(width 0.1)
				(type default)
			)
			(layer "F.Fab")
		)
		(fp_line
			(start 0.120396 0.3048)
			(end 0.120396 0.2794)
			(stroke
				(width 0.1)
				(type default)
			)
			(layer "F.Fab")
		)
		(fp_line
			(start 0.67945 0.3048)
			(end 0.120396 0.3048)
			(stroke
				(width 0.1)
				(type default)
			)
			(layer "F.Fab")
		)
		(fp_line
			(start -0.12065 0.2794)
			(end -0.12065 0.3048)
			(stroke
				(width 0.1)
				(type default)
			)
			(layer "F.Fab")
		)
		(fp_line
			(start 0.120396 0.2794)
			(end -0.12065 0.2794)
			(stroke
				(width 0.1)
				(type default)
			)
			(layer "F.Fab")
		)
		(fp_line
			(start -0.12065 -0.2794)
			(end 0.12065 -0.2794)
			(stroke
				(width 0.1)
				(type default)
			)
			(layer "F.Fab")
		)
		(fp_line
			(start 0.12065 -0.2794)
			(end 0.12065 -0.3048)
			(stroke
				(width 0.1)
				(type default)
			)
			(layer "F.Fab")
		)
		(fp_line
			(start 0.12065 -0.3048)
			(end 0.67945 -0.3048)
			(stroke
				(width 0.1)
				(type default)
			)
			(layer "F.Fab")
		)
		(fp_line
			(start 0.67945 -0.3048)
			(end 0.67945 0.3048)
			(stroke
				(width 0.1)
				(type default)
			)
			(layer "F.Fab")
		)
		(fp_line
			(start -0.67945 -0.305054)
			(end -0.12065 -0.305054)
			(stroke
				(width 0.1)
				(type default)
			)
			(layer "F.Fab")
		)
		(fp_line
			(start -0.12065 -0.305054)
			(end -0.12065 -0.2794)
			(stroke
				(width 0.1)
				(type default)
			)
			(layer "F.Fab")
		)
		(pad "1" smd circle
			(at -0.40005 0 270)
			(size 0 0)
			(layers "F.Cu" "F.Mask" "F.Paste")
			(net "P3V3_AUX")
		)
		(pad "2" smd circle
			(at 0.40005 0 270)
			(size 0 0)
			(layers "F.Cu" "F.Mask" "F.Paste")
			(net "GND")
		)
	)
	(footprint ""
		(layer "F.Cu")
		(at 13.279374 -281.9654)
		(property "Reference" "PC218"
			(at 0 0 0)
			(layer "F.SilkS")
			(hide yes)
			(effects
				(font
					(size 1.27 1.27)
				)
			)
		)
		(property "Value" ""
			(at 0 0 0)
			(layer "F.Fab")
			(effects
				(font
					(size 1.27 1.27)
				)
			)
		)
		(duplicate_pad_numbers_are_jumpers no)
		(fp_line
			(start -2.750058 -1.988058)
			(end -2.750058 -0.9398)
			(stroke
				(width 0.1524)
				(type default)
			)
			(layer "F.SilkS")
		)
		(fp_line
			(start -2.750058 0.9398)
			(end -2.750058 1.988058)
			(stroke
				(width 0.1524)
				(type default)
			)
			(layer "F.SilkS")
		)
		(fp_line
			(start -2.750058 1.988058)
			(end -1.988058 2.750058)
			(stroke
				(width 0.1524)
				(type default)
			)
			(layer "F.SilkS")
		)
		(fp_line
			(start -1.988058 -2.750058)
			(end -2.750058 -1.988058)
			(stroke
				(width 0.1524)
				(type default)
			)
			(layer "F.SilkS")
		)
		(fp_line
			(start -1.988058 2.750058)
			(end 2.750058 2.750058)
			(stroke
				(width 0.1524)
				(type default)
			)
			(layer "F.SilkS")
		)
		(fp_line
			(start 2.750058 -2.750058)
			(end -1.988058 -2.750058)
			(stroke
				(width 0.1524)
				(type default)
			)
			(layer "F.SilkS")
		)
		(fp_line
			(start 2.750058 -0.9398)
			(end 2.750058 -2.750058)
			(stroke
				(width 0.1524)
				(type default)
			)
			(layer "F.SilkS")
		)
		(fp_line
			(start 2.750058 2.750058)
			(end 2.750058 0.9398)
			(stroke
				(width 0.1524)
				(type default)
			)
			(layer "F.SilkS")
		)
		(fp_line
			(start -2.750058 -2.750058)
			(end -2.750058 2.750058)
			(stroke
				(width 0.1)
				(type default)
			)
			(layer "F.Fab")
		)
		(fp_line
			(start -2.750058 2.750058)
			(end 2.750058 2.750058)
			(stroke
				(width 0.1)
				(type default)
			)
			(layer "F.Fab")
		)
		(fp_line
			(start 2.750058 -2.750058)
			(end -2.750058 -2.750058)
			(stroke
				(width 0.1)
				(type default)
			)
			(layer "F.Fab")
		)
		(fp_line
			(start 2.750058 2.750058)
			(end 2.750058 -2.750058)
			(stroke
				(width 0.1)
				(type default)
			)
			(layer "F.Fab")
		)
		(pad "1" smd rect
			(at -2.199894 0 90)
			(size 1.6002 3.0226)
			(layers "F.Cu" "F.Mask" "F.Paste")
			(net "P1V25_PEX0_R")
		)
		(pad "2" smd rect
			(at 2.199894 0 90)
			(size 1.6002 3.0226)
			(layers "F.Cu" "F.Mask" "F.Paste")
			(net "GND")
		)
	)
	(footprint ""
		(layer "F.Cu")
		(at 203.040234 -141.404848 -90)
		(property "Reference" "R196"
			(at 0 0 270)
			(layer "F.SilkS")
			(hide yes)
			(effects
				(font
					(size 1.27 1.27)
				)
			)
		)
		(property "Value" ""
			(at 0 0 270)
			(layer "F.Fab")
			(effects
				(font
					(size 1.27 1.27)
				)
			)
		)
		(duplicate_pad_numbers_are_jumpers no)
		(fp_line
			(start -0.7874 0.4064)
			(end -0.7874 -0.4064)
			(stroke
				(width 0.1524)
				(type default)
			)
			(layer "F.SilkS")
		)
		(fp_line
			(start 0.7874 0.4064)
			(end -0.7874 0.4064)
			(stroke
				(width 0.1524)
				(type default)
			)
			(layer "F.SilkS")
		)
		(fp_line
			(start -0.7874 -0.4064)
			(end 0.7874 -0.4064)
			(stroke
				(width 0.1524)
				(type default)
			)
			(layer "F.SilkS")
		)
		(fp_line
			(start 0.7874 -0.4064)
			(end 0.7874 0.4064)
			(stroke
				(width 0.1524)
				(type default)
			)
			(layer "F.SilkS")
		)
		(fp_line
			(start -0.67945 0.3048)
			(end -0.67945 -0.305054)
			(stroke
				(width 0.1)
				(type default)
			)
			(layer "F.Fab")
		)
		(fp_line
			(start -0.12065 0.3048)
			(end -0.67945 0.3048)
			(stroke
				(width 0.1)
				(type default)
			)
			(layer "F.Fab")
		)
		(fp_line
			(start 0.120396 0.3048)
			(end 0.120396 0.2794)
			(stroke
				(width 0.1)
				(type default)
			)
			(layer "F.Fab")
		)
		(fp_line
			(start 0.67945 0.3048)
			(end 0.120396 0.3048)
			(stroke
				(width 0.1)
				(type default)
			)
			(layer "F.Fab")
		)
		(fp_line
			(start -0.12065 0.2794)
			(end -0.12065 0.3048)
			(stroke
				(width 0.1)
				(type default)
			)
			(layer "F.Fab")
		)
		(fp_line
			(start 0.120396 0.2794)
			(end -0.12065 0.2794)
			(stroke
				(width 0.1)
				(type default)
			)
			(layer "F.Fab")
		)
		(fp_line
			(start -0.12065 -0.2794)
			(end 0.12065 -0.2794)
			(stroke
				(width 0.1)
				(type default)
			)
			(layer "F.Fab")
		)
		(fp_line
			(start 0.12065 -0.2794)
			(end 0.12065 -0.3048)
			(stroke
				(width 0.1)
				(type default)
			)
			(layer "F.Fab")
		)
		(fp_line
			(start 0.12065 -0.3048)
			(end 0.67945 -0.3048)
			(stroke
				(width 0.1)
				(type default)
			)
			(layer "F.Fab")
		)
		(fp_line
			(start 0.67945 -0.3048)
			(end 0.67945 0.3048)
			(stroke
				(width 0.1)
				(type default)
			)
			(layer "F.Fab")
		)
		(fp_line
			(start -0.67945 -0.305054)
			(end -0.12065 -0.305054)
			(stroke
				(width 0.1)
				(type default)
			)
			(layer "F.Fab")
		)
		(fp_line
			(start -0.12065 -0.305054)
			(end -0.12065 -0.2794)
			(stroke
				(width 0.1)
				(type default)
			)
			(layer "F.Fab")
		)
		(pad "1" smd circle
			(at -0.40005 0 270)
			(size 0 0)
			(layers "F.Cu" "F.Mask" "F.Paste")
			(net "PRSNT_NIC3_R_N")
		)
		(pad "2" smd circle
			(at 0.40005 0 270)
			(size 0 0)
			(layers "F.Cu" "F.Mask" "F.Paste")
			(net "PRSNT_NIC3_N")
		)
	)
	(footprint ""
		(layer "F.Cu")
		(at 363.474 -207.899 180)
		(property "Reference" "R4612"
			(at 0 0 180)
			(layer "F.SilkS")
			(hide yes)
			(effects
				(font
					(size 1.27 1.27)
				)
			)
		)
		(property "Value" ""
			(at 0 0 180)
			(layer "F.Fab")
			(effects
				(font
					(size 1.27 1.27)
				)
			)
		)
		(duplicate_pad_numbers_are_jumpers no)
		(fp_line
			(start 0.7874 0.4064)
			(end -0.7874 0.4064)
			(stroke
				(width 0.1524)
				(type default)
			)
			(layer "F.SilkS")
		)
		(fp_line
			(start 0.7874 -0.4064)
			(end 0.7874 0.4064)
			(stroke
				(width 0.1524)
				(type default)
			)
			(layer "F.SilkS")
		)
		(fp_line
			(start -0.7874 0.4064)
			(end -0.7874 -0.4064)
			(stroke
				(width 0.1524)
				(type default)
			)
			(layer "F.SilkS")
		)
		(fp_line
			(start -0.7874 -0.4064)
			(end 0.7874 -0.4064)
			(stroke
				(width 0.1524)
				(type default)
			)
			(layer "F.SilkS")
		)
		(fp_line
			(start 0.67945 0.3048)
			(end 0.120396 0.3048)
			(stroke
				(width 0.1)
				(type default)
			)
			(layer "F.Fab")
		)
		(fp_line
			(start 0.67945 -0.3048)
			(end 0.67945 0.3048)
			(stroke
				(width 0.1)
				(type default)
			)
			(layer "F.Fab")
		)
		(fp_line
			(start 0.12065 -0.2794)
			(end 0.12065 -0.3048)
			(stroke
				(width 0.1)
				(type default)
			)
			(layer "F.Fab")
		)
		(fp_line
			(start 0.12065 -0.3048)
			(end 0.67945 -0.3048)
			(stroke
				(width 0.1)
				(type default)
			)
			(layer "F.Fab")
		)
		(fp_line
			(start 0.120396 0.3048)
			(end 0.120396 0.2794)
			(stroke
				(width 0.1)
				(type default)
			)
			(layer "F.Fab")
		)
		(fp_line
			(start 0.120396 0.2794)
			(end -0.12065 0.2794)
			(stroke
				(width 0.1)
				(type default)
			)
			(layer "F.Fab")
		)
		(fp_line
			(start -0.12065 0.3048)
			(end -0.67945 0.3048)
			(stroke
				(width 0.1)
				(type default)
			)
			(layer "F.Fab")
		)
		(fp_line
			(start -0.12065 0.2794)
			(end -0.12065 0.3048)
			(stroke
				(width 0.1)
				(type default)
			)
			(layer "F.Fab")
		)
		(fp_line
			(start -0.12065 -0.2794)
			(end 0.12065 -0.2794)
			(stroke
				(width 0.1)
				(type default)
			)
			(layer "F.Fab")
		)
		(fp_line
			(start -0.12065 -0.305054)
			(end -0.12065 -0.2794)
			(stroke
				(width 0.1)
				(type default)
			)
			(layer "F.Fab")
		)
		(fp_line
			(start -0.67945 0.3048)
			(end -0.67945 -0.305054)
			(stroke
				(width 0.1)
				(type default)
			)
			(layer "F.Fab")
		)
		(fp_line
			(start -0.67945 -0.305054)
			(end -0.12065 -0.305054)
			(stroke
				(width 0.1)
				(type default)
			)
			(layer "F.Fab")
		)
		(pad "1" smd circle
			(at -0.40005 0 180)
			(size 0 0)
			(layers "F.Cu" "F.Mask" "F.Paste")
			(net "SSD1_PEX_PWR_EN_R")
		)
		(pad "2" smd circle
			(at 0.40005 0 180)
			(size 0 0)
			(layers "F.Cu" "F.Mask" "F.Paste")
			(net "GND")
		)
	)
	(footprint ""
		(layer "F.Cu")
		(at 365.922814 -22.867366 90)
		(property "Reference" "C3959"
			(at 0 0 90)
			(layer "F.SilkS")
			(hide yes)
			(effects
				(font
					(size 1.27 1.27)
				)
			)
		)
		(property "Value" ""
			(at 0 0 90)
			(layer "F.Fab")
			(effects
				(font
					(size 1.27 1.27)
				)
			)
		)
		(duplicate_pad_numbers_are_jumpers no)
		(fp_line
			(start 0.7874 -0.4064)
			(end 0.7874 0.4064)
			(stroke
				(width 0.1524)
				(type default)
			)
			(layer "F.SilkS")
		)
		(fp_line
			(start -0.7874 -0.4064)
			(end 0.7874 -0.4064)
			(stroke
				(width 0.1524)
				(type default)
			)
			(layer "F.SilkS")
		)
		(fp_line
			(start 0.7874 0.4064)
			(end -0.7874 0.4064)
			(stroke
				(width 0.1524)
				(type default)
			)
			(layer "F.SilkS")
		)
		(fp_line
			(start -0.7874 0.4064)
			(end -0.7874 -0.4064)
			(stroke
				(width 0.1524)
				(type default)
			)
			(layer "F.SilkS")
		)
		(fp_line
			(start -0.12065 -0.305054)
			(end -0.12065 -0.2794)
			(stroke
				(width 0.1)
				(type default)
			)
			(layer "F.Fab")
		)
		(fp_line
			(start -0.67945 -0.305054)
			(end -0.12065 -0.305054)
			(stroke
				(width 0.1)
				(type default)
			)
			(layer "F.Fab")
		)
		(fp_line
			(start 0.67945 -0.3048)
			(end 0.67945 0.3048)
			(stroke
				(width 0.1)
				(type default)
			)
			(layer "F.Fab")
		)
		(fp_line
			(start 0.12065 -0.3048)
			(end 0.67945 -0.3048)
			(stroke
				(width 0.1)
				(type default)
			)
			(layer "F.Fab")
		)
		(fp_line
			(start 0.12065 -0.2794)
			(end 0.12065 -0.3048)
			(stroke
				(width 0.1)
				(type default)
			)
			(layer "F.Fab")
		)
		(fp_line
			(start -0.12065 -0.2794)
			(end 0.12065 -0.2794)
			(stroke
				(width 0.1)
				(type default)
			)
			(layer "F.Fab")
		)
		(fp_line
			(start 0.120396 0.2794)
			(end -0.12065 0.2794)
			(stroke
				(width 0.1)
				(type default)
			)
			(layer "F.Fab")
		)
		(fp_line
			(start -0.12065 0.2794)
			(end -0.12065 0.3048)
			(stroke
				(width 0.1)
				(type default)
			)
			(layer "F.Fab")
		)
		(fp_line
			(start 0.67945 0.3048)
			(end 0.120396 0.3048)
			(stroke
				(width 0.1)
				(type default)
			)
			(layer "F.Fab")
		)
		(fp_line
			(start 0.120396 0.3048)
			(end 0.120396 0.2794)
			(stroke
				(width 0.1)
				(type default)
			)
			(layer "F.Fab")
		)
		(fp_line
			(start -0.12065 0.3048)
			(end -0.67945 0.3048)
			(stroke
				(width 0.1)
				(type default)
			)
			(layer "F.Fab")
		)
		(fp_line
			(start -0.67945 0.3048)
			(end -0.67945 -0.305054)
			(stroke
				(width 0.1)
				(type default)
			)
			(layer "F.Fab")
		)
		(pad "1" smd circle
			(at -0.40005 0 90)
			(size 0 0)
			(layers "F.Cu" "F.Mask" "F.Paste")
			(net "P12V_SSD12")
		)
		(pad "2" smd circle
			(at 0.40005 0 90)
			(size 0 0)
			(layers "F.Cu" "F.Mask" "F.Paste")
			(net "GND")
		)
	)
	(footprint ""
		(layer "F.Cu")
		(at 352.920554 -82.644234)
		(property "Reference" "R1627"
			(at 0 0 0)
			(layer "F.SilkS")
			(hide yes)
			(effects
				(font
					(size 1.27 1.27)
				)
			)
		)
		(property "Value" ""
			(at 0 0 0)
			(layer "F.Fab")
			(effects
				(font
					(size 1.27 1.27)
				)
			)
		)
		(duplicate_pad_numbers_are_jumpers no)
		(fp_line
			(start -0.7874 -0.4064)
			(end 0.7874 -0.4064)
			(stroke
				(width 0.1524)
				(type default)
			)
			(layer "F.SilkS")
		)
		(fp_line
			(start -0.7874 0.4064)
			(end -0.7874 -0.4064)
			(stroke
				(width 0.1524)
				(type default)
			)
			(layer "F.SilkS")
		)
		(fp_line
			(start 0.7874 -0.4064)
			(end 0.7874 0.4064)
			(stroke
				(width 0.1524)
				(type default)
			)
			(layer "F.SilkS")
		)
		(fp_line
			(start 0.7874 0.4064)
			(end -0.7874 0.4064)
			(stroke
				(width 0.1524)
				(type default)
			)
			(layer "F.SilkS")
		)
		(fp_line
			(start -0.67945 -0.305054)
			(end -0.12065 -0.305054)
			(stroke
				(width 0.1)
				(type default)
			)
			(layer "F.Fab")
		)
		(fp_line
			(start -0.67945 0.3048)
			(end -0.67945 -0.305054)
			(stroke
				(width 0.1)
				(type default)
			)
			(layer "F.Fab")
		)
		(fp_line
			(start -0.12065 -0.305054)
			(end -0.12065 -0.2794)
			(stroke
				(width 0.1)
				(type default)
			)
			(layer "F.Fab")
		)
		(fp_line
			(start -0.12065 -0.2794)
			(end 0.12065 -0.2794)
			(stroke
				(width 0.1)
				(type default)
			)
			(layer "F.Fab")
		)
		(fp_line
			(start -0.12065 0.2794)
			(end -0.12065 0.3048)
			(stroke
				(width 0.1)
				(type default)
			)
			(layer "F.Fab")
		)
		(fp_line
			(start -0.12065 0.3048)
			(end -0.67945 0.3048)
			(stroke
				(width 0.1)
				(type default)
			)
			(layer "F.Fab")
		)
		(fp_line
			(start 0.120396 0.2794)
			(end -0.12065 0.2794)
			(stroke
				(width 0.1)
				(type default)
			)
			(layer "F.Fab")
		)
		(fp_line
			(start 0.120396 0.3048)
			(end 0.120396 0.2794)
			(stroke
				(width 0.1)
				(type default)
			)
			(layer "F.Fab")
		)
		(fp_line
			(start 0.12065 -0.3048)
			(end 0.67945 -0.3048)
			(stroke
				(width 0.1)
				(type default)
			)
			(layer "F.Fab")
		)
		(fp_line
			(start 0.12065 -0.2794)
			(end 0.12065 -0.3048)
			(stroke
				(width 0.1)
				(type default)
			)
			(layer "F.Fab")
		)
		(fp_line
			(start 0.67945 -0.3048)
			(end 0.67945 0.3048)
			(stroke
				(width 0.1)
				(type default)
			)
			(layer "F.Fab")
		)
		(fp_line
			(start 0.67945 0.3048)
			(end 0.120396 0.3048)
			(stroke
				(width 0.1)
				(type default)
			)
			(layer "F.Fab")
		)
		(pad "1" smd circle
			(at -0.40005 0)
			(size 0 0)
			(layers "F.Cu" "F.Mask" "F.Paste")
			(net "SMB_BIC_I2C9_MUX1_SSD11_R_SDA")
		)
		(pad "2" smd circle
			(at 0.40005 0)
			(size 0 0)
			(layers "F.Cu" "F.Mask" "F.Paste")
			(net "SMB_BIC_I2C9_MUX1_SSD11_SDA")
		)
	)
	(footprint ""
		(layer "F.Cu")
		(at 14.261846 -208.993232 -90)
		(property "Reference" "C4414"
			(at 0 0 270)
			(layer "F.SilkS")
			(hide yes)
			(effects
				(font
					(size 1.27 1.27)
				)
			)
		)
		(property "Value" ""
			(at 0 0 270)
			(layer "F.Fab")
			(effects
				(font
					(size 1.27 1.27)
				)
			)
		)
		(duplicate_pad_numbers_are_jumpers no)
		(fp_line
			(start -0.7874 0.4064)
			(end -0.7874 -0.4064)
			(stroke
				(width 0.1524)
				(type default)
			)
			(layer "F.SilkS")
		)
		(fp_line
			(start 0.7874 0.4064)
			(end -0.7874 0.4064)
			(stroke
				(width 0.1524)
				(type default)
			)
			(layer "F.SilkS")
		)
		(fp_line
			(start -0.7874 -0.4064)
			(end 0.7874 -0.4064)
			(stroke
				(width 0.1524)
				(type default)
			)
			(layer "F.SilkS")
		)
		(fp_line
			(start 0.7874 -0.4064)
			(end 0.7874 0.4064)
			(stroke
				(width 0.1524)
				(type default)
			)
			(layer "F.SilkS")
		)
		(fp_line
			(start -0.67945 0.3048)
			(end -0.67945 -0.305054)
			(stroke
				(width 0.1)
				(type default)
			)
			(layer "F.Fab")
		)
		(fp_line
			(start -0.12065 0.3048)
			(end -0.67945 0.3048)
			(stroke
				(width 0.1)
				(type default)
			)
			(layer "F.Fab")
		)
		(fp_line
			(start 0.120396 0.3048)
			(end 0.120396 0.2794)
			(stroke
				(width 0.1)
				(type default)
			)
			(layer "F.Fab")
		)
		(fp_line
			(start 0.67945 0.3048)
			(end 0.120396 0.3048)
			(stroke
				(width 0.1)
				(type default)
			)
			(layer "F.Fab")
		)
		(fp_line
			(start -0.12065 0.2794)
			(end -0.12065 0.3048)
			(stroke
				(width 0.1)
				(type default)
			)
			(layer "F.Fab")
		)
		(fp_line
			(start 0.120396 0.2794)
			(end -0.12065 0.2794)
			(stroke
				(width 0.1)
				(type default)
			)
			(layer "F.Fab")
		)
		(fp_line
			(start -0.12065 -0.2794)
			(end 0.12065 -0.2794)
			(stroke
				(width 0.1)
				(type default)
			)
			(layer "F.Fab")
		)
		(fp_line
			(start 0.12065 -0.2794)
			(end 0.12065 -0.3048)
			(stroke
				(width 0.1)
				(type default)
			)
			(layer "F.Fab")
		)
		(fp_line
			(start 0.12065 -0.3048)
			(end 0.67945 -0.3048)
			(stroke
				(width 0.1)
				(type default)
			)
			(layer "F.Fab")
		)
		(fp_line
			(start 0.67945 -0.3048)
			(end 0.67945 0.3048)
			(stroke
				(width 0.1)
				(type default)
			)
			(layer "F.Fab")
		)
		(fp_line
			(start -0.67945 -0.305054)
			(end -0.12065 -0.305054)
			(stroke
				(width 0.1)
				(type default)
			)
			(layer "F.Fab")
		)
		(fp_line
			(start -0.12065 -0.305054)
			(end -0.12065 -0.2794)
			(stroke
				(width 0.1)
				(type default)
			)
			(layer "F.Fab")
		)
		(pad "1" smd circle
			(at -0.40005 0 270)
			(size 0 0)
			(layers "F.Cu" "F.Mask" "F.Paste")
			(net "P5V_AUX")
		)
		(pad "2" smd circle
			(at 0.40005 0 270)
			(size 0 0)
			(layers "F.Cu" "F.Mask" "F.Paste")
			(net "GND")
		)
	)
	(footprint ""
		(layer "F.Cu")
		(at 399.14322 -343.952322 90)
		(property "Reference" "C750"
			(at 0 0 90)
			(layer "F.SilkS")
			(hide yes)
			(effects
				(font
					(size 1.27 1.27)
				)
			)
		)
		(property "Value" ""
			(at 0 0 90)
			(layer "F.Fab")
			(effects
				(font
					(size 1.27 1.27)
				)
			)
		)
		(duplicate_pad_numbers_are_jumpers no)
		(fp_line
			(start 0.299974 -0.150114)
			(end 0.299974 0.150114)
			(stroke
				(width 0.1)
				(type default)
			)
			(layer "F.Fab")
		)
		(fp_line
			(start -0.299974 -0.150114)
			(end 0.299974 -0.150114)
			(stroke
				(width 0.1)
				(type default)
			)
			(layer "F.Fab")
		)
		(fp_line
			(start 0.299974 0.150114)
			(end -0.299974 0.150114)
			(stroke
				(width 0.1)
				(type default)
			)
			(layer "F.Fab")
		)
		(fp_line
			(start -0.299974 0.150114)
			(end -0.299974 -0.150114)
			(stroke
				(width 0.1)
				(type default)
			)
			(layer "F.Fab")
		)
		(pad "1" smd rect
			(at -0.2667 0 90)
			(size 0.3048 0.381)
			(layers "F.Cu" "F.Mask" "F.Paste")
			(net "P5E_PEX3_STN5_TX_DP<85>")
		)
		(pad "2" smd rect
			(at 0.2667 0 90)
			(size 0.3048 0.381)
			(layers "F.Cu" "F.Mask" "F.Paste")
			(net "P5E_PEX3_STN5_TX_C_DP<85>")
		)
	)
	(footprint ""
		(layer "F.Cu")
		(at 194.343782 -45.88891)
		(property "Reference" "R575"
			(at 0 0 0)
			(layer "F.SilkS")
			(hide yes)
			(effects
				(font
					(size 1.27 1.27)
				)
			)
		)
		(property "Value" ""
			(at 0 0 0)
			(layer "F.Fab")
			(effects
				(font
					(size 1.27 1.27)
				)
			)
		)
		(duplicate_pad_numbers_are_jumpers no)
		(fp_line
			(start -0.7874 -0.4064)
			(end 0.7874 -0.4064)
			(stroke
				(width 0.1524)
				(type default)
			)
			(layer "F.SilkS")
		)
		(fp_line
			(start -0.7874 0.4064)
			(end -0.7874 -0.4064)
			(stroke
				(width 0.1524)
				(type default)
			)
			(layer "F.SilkS")
		)
		(fp_line
			(start 0.7874 -0.4064)
			(end 0.7874 0.4064)
			(stroke
				(width 0.1524)
				(type default)
			)
			(layer "F.SilkS")
		)
		(fp_line
			(start 0.7874 0.4064)
			(end -0.7874 0.4064)
			(stroke
				(width 0.1524)
				(type default)
			)
			(layer "F.SilkS")
		)
		(fp_line
			(start -0.67945 -0.305054)
			(end -0.12065 -0.305054)
			(stroke
				(width 0.1)
				(type default)
			)
			(layer "F.Fab")
		)
		(fp_line
			(start -0.67945 0.3048)
			(end -0.67945 -0.305054)
			(stroke
				(width 0.1)
				(type default)
			)
			(layer "F.Fab")
		)
		(fp_line
			(start -0.12065 -0.305054)
			(end -0.12065 -0.2794)
			(stroke
				(width 0.1)
				(type default)
			)
			(layer "F.Fab")
		)
		(fp_line
			(start -0.12065 -0.2794)
			(end 0.12065 -0.2794)
			(stroke
				(width 0.1)
				(type default)
			)
			(layer "F.Fab")
		)
		(fp_line
			(start -0.12065 0.2794)
			(end -0.12065 0.3048)
			(stroke
				(width 0.1)
				(type default)
			)
			(layer "F.Fab")
		)
		(fp_line
			(start -0.12065 0.3048)
			(end -0.67945 0.3048)
			(stroke
				(width 0.1)
				(type default)
			)
			(layer "F.Fab")
		)
		(fp_line
			(start 0.120396 0.2794)
			(end -0.12065 0.2794)
			(stroke
				(width 0.1)
				(type default)
			)
			(layer "F.Fab")
		)
		(fp_line
			(start 0.120396 0.3048)
			(end 0.120396 0.2794)
			(stroke
				(width 0.1)
				(type default)
			)
			(layer "F.Fab")
		)
		(fp_line
			(start 0.12065 -0.3048)
			(end 0.67945 -0.3048)
			(stroke
				(width 0.1)
				(type default)
			)
			(layer "F.Fab")
		)
		(fp_line
			(start 0.12065 -0.2794)
			(end 0.12065 -0.3048)
			(stroke
				(width 0.1)
				(type default)
			)
			(layer "F.Fab")
		)
		(fp_line
			(start 0.67945 -0.3048)
			(end 0.67945 0.3048)
			(stroke
				(width 0.1)
				(type default)
			)
			(layer "F.Fab")
		)
		(fp_line
			(start 0.67945 0.3048)
			(end 0.120396 0.3048)
			(stroke
				(width 0.1)
				(type default)
			)
			(layer "F.Fab")
		)
		(pad "1" smd circle
			(at -0.40005 0)
			(size 0 0)
			(layers "F.Cu" "F.Mask" "F.Paste")
			(net "SSD6_ADC_A0")
		)
		(pad "2" smd circle
			(at 0.40005 0)
			(size 0 0)
			(layers "F.Cu" "F.Mask" "F.Paste")
			(net "GND")
		)
	)
	(footprint ""
		(layer "F.Cu")
		(at 461.33004 -258.331208 -90)
		(property "Reference" "R6564"
			(at 0 0 270)
			(layer "F.SilkS")
			(hide yes)
			(effects
				(font
					(size 1.27 1.27)
				)
			)
		)
		(property "Value" ""
			(at 0 0 270)
			(layer "F.Fab")
			(effects
				(font
					(size 1.27 1.27)
				)
			)
		)
		(duplicate_pad_numbers_are_jumpers no)
		(fp_line
			(start -0.7874 0.4064)
			(end -0.7874 -0.4064)
			(stroke
				(width 0.1524)
				(type default)
			)
			(layer "F.SilkS")
		)
		(fp_line
			(start 0.7874 0.4064)
			(end -0.7874 0.4064)
			(stroke
				(width 0.1524)
				(type default)
			)
			(layer "F.SilkS")
		)
		(fp_line
			(start -0.7874 -0.4064)
			(end 0.7874 -0.4064)
			(stroke
				(width 0.1524)
				(type default)
			)
			(layer "F.SilkS")
		)
		(fp_line
			(start 0.7874 -0.4064)
			(end 0.7874 0.4064)
			(stroke
				(width 0.1524)
				(type default)
			)
			(layer "F.SilkS")
		)
		(fp_line
			(start -0.67945 0.3048)
			(end -0.67945 -0.305054)
			(stroke
				(width 0.1)
				(type default)
			)
			(layer "F.Fab")
		)
		(fp_line
			(start -0.12065 0.3048)
			(end -0.67945 0.3048)
			(stroke
				(width 0.1)
				(type default)
			)
			(layer "F.Fab")
		)
		(fp_line
			(start 0.120396 0.3048)
			(end 0.120396 0.2794)
			(stroke
				(width 0.1)
				(type default)
			)
			(layer "F.Fab")
		)
		(fp_line
			(start 0.67945 0.3048)
			(end 0.120396 0.3048)
			(stroke
				(width 0.1)
				(type default)
			)
			(layer "F.Fab")
		)
		(fp_line
			(start -0.12065 0.2794)
			(end -0.12065 0.3048)
			(stroke
				(width 0.1)
				(type default)
			)
			(layer "F.Fab")
		)
		(fp_line
			(start 0.120396 0.2794)
			(end -0.12065 0.2794)
			(stroke
				(width 0.1)
				(type default)
			)
			(layer "F.Fab")
		)
		(fp_line
			(start -0.12065 -0.2794)
			(end 0.12065 -0.2794)
			(stroke
				(width 0.1)
				(type default)
			)
			(layer "F.Fab")
		)
		(fp_line
			(start 0.12065 -0.2794)
			(end 0.12065 -0.3048)
			(stroke
				(width 0.1)
				(type default)
			)
			(layer "F.Fab")
		)
		(fp_line
			(start 0.12065 -0.3048)
			(end 0.67945 -0.3048)
			(stroke
				(width 0.1)
				(type default)
			)
			(layer "F.Fab")
		)
		(fp_line
			(start 0.67945 -0.3048)
			(end 0.67945 0.3048)
			(stroke
				(width 0.1)
				(type default)
			)
			(layer "F.Fab")
		)
		(fp_line
			(start -0.67945 -0.305054)
			(end -0.12065 -0.305054)
			(stroke
				(width 0.1)
				(type default)
			)
			(layer "F.Fab")
		)
		(fp_line
			(start -0.12065 -0.305054)
			(end -0.12065 -0.2794)
			(stroke
				(width 0.1)
				(type default)
			)
			(layer "F.Fab")
		)
		(pad "1" smd circle
			(at -0.40005 0 270)
			(size 0 0)
			(layers "F.Cu" "F.Mask" "F.Paste")
			(net "P1V25_SERDES_VDDPLL_PEX3")
		)
		(pad "2" smd circle
			(at 0.40005 0 270)
			(size 0 0)
			(layers "F.Cu" "F.Mask" "F.Paste")
			(net "P1V25_SERDES_VDDPLL_PEX3_C11")
		)
	)
	(footprint ""
		(layer "F.Cu")
		(at 245.280434 -250.759722 -90)
		(property "Reference" "R6219"
			(at 0 0 270)
			(layer "F.SilkS")
			(hide yes)
			(effects
				(font
					(size 1.27 1.27)
				)
			)
		)
		(property "Value" ""
			(at 0 0 270)
			(layer "F.Fab")
			(effects
				(font
					(size 1.27 1.27)
				)
			)
		)
		(duplicate_pad_numbers_are_jumpers no)
		(fp_line
			(start -0.7874 0.4064)
			(end -0.7874 -0.4064)
			(stroke
				(width 0.1524)
				(type default)
			)
			(layer "F.SilkS")
		)
		(fp_line
			(start 0.7874 0.4064)
			(end -0.7874 0.4064)
			(stroke
				(width 0.1524)
				(type default)
			)
			(layer "F.SilkS")
		)
		(fp_line
			(start -0.7874 -0.4064)
			(end 0.7874 -0.4064)
			(stroke
				(width 0.1524)
				(type default)
			)
			(layer "F.SilkS")
		)
		(fp_line
			(start 0.7874 -0.4064)
			(end 0.7874 0.4064)
			(stroke
				(width 0.1524)
				(type default)
			)
			(layer "F.SilkS")
		)
		(fp_line
			(start -0.67945 0.3048)
			(end -0.67945 -0.305054)
			(stroke
				(width 0.1)
				(type default)
			)
			(layer "F.Fab")
		)
		(fp_line
			(start -0.12065 0.3048)
			(end -0.67945 0.3048)
			(stroke
				(width 0.1)
				(type default)
			)
			(layer "F.Fab")
		)
		(fp_line
			(start 0.120396 0.3048)
			(end 0.120396 0.2794)
			(stroke
				(width 0.1)
				(type default)
			)
			(layer "F.Fab")
		)
		(fp_line
			(start 0.67945 0.3048)
			(end 0.120396 0.3048)
			(stroke
				(width 0.1)
				(type default)
			)
			(layer "F.Fab")
		)
		(fp_line
			(start -0.12065 0.2794)
			(end -0.12065 0.3048)
			(stroke
				(width 0.1)
				(type default)
			)
			(layer "F.Fab")
		)
		(fp_line
			(start 0.120396 0.2794)
			(end -0.12065 0.2794)
			(stroke
				(width 0.1)
				(type default)
			)
			(layer "F.Fab")
		)
		(fp_line
			(start -0.12065 -0.2794)
			(end 0.12065 -0.2794)
			(stroke
				(width 0.1)
				(type default)
			)
			(layer "F.Fab")
		)
		(fp_line
			(start 0.12065 -0.2794)
			(end 0.12065 -0.3048)
			(stroke
				(width 0.1)
				(type default)
			)
			(layer "F.Fab")
		)
		(fp_line
			(start 0.12065 -0.3048)
			(end 0.67945 -0.3048)
			(stroke
				(width 0.1)
				(type default)
			)
			(layer "F.Fab")
		)
		(fp_line
			(start 0.67945 -0.3048)
			(end 0.67945 0.3048)
			(stroke
				(width 0.1)
				(type default)
			)
			(layer "F.Fab")
		)
		(fp_line
			(start -0.67945 -0.305054)
			(end -0.12065 -0.305054)
			(stroke
				(width 0.1)
				(type default)
			)
			(layer "F.Fab")
		)
		(fp_line
			(start -0.12065 -0.305054)
			(end -0.12065 -0.2794)
			(stroke
				(width 0.1)
				(type default)
			)
			(layer "F.Fab")
		)
		(pad "1" smd circle
			(at -0.40005 0 270)
			(size 0 0)
			(layers "F.Cu" "F.Mask" "F.Paste")
			(net "P3V3_AUX")
		)
		(pad "2" smd circle
			(at 0.40005 0 270)
			(size 0 0)
			(layers "F.Cu" "F.Mask" "F.Paste")
			(net "IRQ_BIC_RECOVER_IOEXP_N")
		)
	)
	(footprint ""
		(layer "F.Cu")
		(at 271.164812 -26.785062 180)
		(property "Reference" "J39"
			(at 4.057142 -11.087862 90)
			(unlocked yes)
			(layer "F.SilkS")
			(effects
				(font
					(size 0.7874 0.5842)
					(thickness 0.1524)
				)
			)
		)
		(property "Value" ""
			(at 0 0 180)
			(layer "F.Fab")
			(effects
				(font
					(size 1.27 1.27)
				)
			)
		)
		(duplicate_pad_numbers_are_jumpers no)
		(fp_line
			(start 3.150108 12.115038)
			(end 1.529334 12.115038)
			(stroke
				(width 0.1524)
				(type default)
			)
			(layer "F.SilkS")
		)
		(fp_line
			(start 3.074924 12.014962)
			(end 1.632204 12.014962)
			(stroke
				(width 0.1524)
				(type default)
			)
			(layer "F.SilkS")
		)
		(fp_line
			(start 1.632204 -12.014962)
			(end 3.074924 -12.014962)
			(stroke
				(width 0.1524)
				(type default)
			)
			(layer "F.SilkS")
		)
		(fp_line
			(start 1.529334 -12.115038)
			(end 3.150108 -12.115038)
			(stroke
				(width 0.1524)
				(type default)
			)
			(layer "F.SilkS")
		)
		(fp_line
			(start -1.529334 12.115038)
			(end -3.150108 12.115038)
			(stroke
				(width 0.1524)
				(type default)
			)
			(layer "F.SilkS")
		)
		(fp_line
			(start -1.632204 12.014962)
			(end -3.074924 12.014962)
			(stroke
				(width 0.1524)
				(type default)
			)
			(layer "F.SilkS")
		)
		(fp_line
			(start -3.074924 -12.014962)
			(end -1.632204 -12.014962)
			(stroke
				(width 0.1524)
				(type default)
			)
			(layer "F.SilkS")
		)
		(fp_line
			(start -3.150108 -12.115038)
			(end -1.529334 -12.115038)
			(stroke
				(width 0.1524)
				(type default)
			)
			(layer "F.SilkS")
		)
		(fp_poly
			(pts
				(xy 3.34391 -8.694928) (xy 3.766312 -9.962642) (xy 4.61137 -9.117584)
			)
			(stroke
				(width 0)
				(type default)
			)
			(fill yes)
			(layer "F.SilkS")
		)
		(fp_line
			(start 3.074924 12.014962)
			(end -3.074924 12.014962)
			(stroke
				(width 0.1)
				(type default)
			)
			(layer "F.Fab")
		)
		(fp_line
			(start 3.074924 -12.014962)
			(end 3.074924 12.014962)
			(stroke
				(width 0.1)
				(type default)
			)
			(layer "F.Fab")
		)
		(fp_line
			(start -3.074924 12.014962)
			(end -3.074924 -12.014962)
			(stroke
				(width 0.1)
				(type default)
			)
			(layer "F.Fab")
		)
		(fp_line
			(start -3.074924 -12.014962)
			(end 3.074924 -12.014962)
			(stroke
				(width 0.1)
				(type default)
			)
			(layer "F.Fab")
		)
		(fp_poly
			(pts
				(xy 3.348736 -7.994904) (xy 4.543806 -8.592566) (xy 4.543806 -7.397496)
			)
			(stroke
				(width 0)
				(type default)
			)
			(fill yes)
			(layer "F.Fab")
		)
		(pad "" np_thru_hole circle
			(at -1.75006 -9.815068 90)
			(size 1.1176 1.1176)
			(drill 1.1176)
			(layers "*.Cu" "*.Mask")
			(clearance 0.381)
			(thermal_gap 0.381)
		)
		(pad "" np_thru_hole circle
			(at 0 9.815068 90)
			(size 1.1176 1.1176)
			(drill 1.1176)
			(layers "*.Cu" "*.Mask")
			(clearance 0.381)
			(thermal_gap 0.381)
		)
		(pad "A1" smd rect
			(at 2.29997 -7.994904 90)
			(size 0.381 1.27)
			(layers "F.Cu" "F.Mask" "F.Paste")
			(net "GND")
		)
		(pad "A2" smd rect
			(at 2.29997 -7.394956 90)
			(size 0.381 1.27)
			(layers "F.Cu" "F.Mask" "F.Paste")
			(net "GND")
		)
		(pad "A3" smd rect
			(at 2.29997 -6.795008 90)
			(size 0.381 1.27)
			(layers "F.Cu" "F.Mask" "F.Paste")
			(net "GND")
		)
		(pad "A4" smd rect
			(at 2.29997 -6.19506 90)
			(size 0.381 1.27)
			(layers "F.Cu" "F.Mask" "F.Paste")
			(net "GND")
		)
		(pad "A5" smd rect
			(at 2.29997 -5.595112 90)
			(size 0.381 1.27)
			(layers "F.Cu" "F.Mask" "F.Paste")
			(net "GND")
		)
		(pad "A6" smd rect
			(at 2.29997 -4.99491 90)
			(size 0.381 1.27)
			(layers "F.Cu" "F.Mask" "F.Paste")
			(net "GND")
		)
		(pad "A7" smd rect
			(at 2.29997 -4.394962 90)
			(size 0.381 1.27)
			(layers "F.Cu" "F.Mask" "F.Paste")
			(net "SMB_ISO_SSD9_R_SCL")
		)
		(pad "A8" smd rect
			(at 2.29997 -3.795014 90)
			(size 0.381 1.27)
			(layers "F.Cu" "F.Mask" "F.Paste")
			(net "SMB_ISO_SSD9_R_SDA")
		)
		(pad "A9" smd rect
			(at 2.29997 -3.195066 90)
			(size 0.381 1.27)
			(layers "F.Cu" "F.Mask" "F.Paste")
			(net "RST_SMB_SSD9_ISO_R_N")
		)
		(pad "A10" smd rect
			(at 2.29997 -2.595118 90)
			(size 0.381 1.27)
			(layers "F.Cu" "F.Mask" "F.Paste")
			(net "SSD9_LED_ISO_R_N")
		)
		(pad "A11" smd rect
			(at 2.29997 -1.994916 90)
			(size 0.381 1.27)
			(layers "F.Cu" "F.Mask" "F.Paste")
			(net "PU_CLKREQ9")
		)
		(pad "A12" smd rect
			(at 2.29997 -1.394968 90)
			(size 0.381 1.27)
			(layers "F.Cu" "F.Mask" "F.Paste")
			(net "PRSNT_SSD9_N")
		)
		(pad "A13" smd rect
			(at 2.29997 -0.79502 90)
			(size 0.381 1.27)
			(layers "F.Cu" "F.Mask" "F.Paste")
			(net "GND")
		)
		(pad "A14" smd rect
			(at 2.29997 -0.195072 90)
			(size 0.381 1.27)
			(layers "F.Cu" "F.Mask" "F.Paste")
			(net "Net_8495")
		)
		(pad "A15" smd rect
			(at 2.29997 0.404876 90)
			(size 0.381 1.27)
			(layers "F.Cu" "F.Mask" "F.Paste")
			(net "Net_8494")
		)
		(pad "A16" smd rect
			(at 2.29997 1.005078 90)
			(size 0.381 1.27)
			(layers "F.Cu" "F.Mask" "F.Paste")
			(net "GND")
		)
		(pad "A17" smd rect
			(at 2.29997 1.605026 90)
			(size 0.381 1.27)
			(layers "F.Cu" "F.Mask" "F.Paste")
			(net "P5E_PEX2_STN2_RX_DN<40>")
		)
		(pad "A18" smd rect
			(at 2.29997 2.204974 90)
			(size 0.381 1.27)
			(layers "F.Cu" "F.Mask" "F.Paste")
			(net "P5E_PEX2_STN2_RX_DP<40>")
		)
		(pad "A19" smd rect
			(at 2.29997 2.804922 90)
			(size 0.381 1.27)
			(layers "F.Cu" "F.Mask" "F.Paste")
			(net "GND")
		)
		(pad "A20" smd rect
			(at 2.29997 3.405124 90)
			(size 0.381 1.27)
			(layers "F.Cu" "F.Mask" "F.Paste")
			(net "P5E_PEX2_STN2_RX_DN<41>")
		)
		(pad "A21" smd rect
			(at 2.29997 4.005072 90)
			(size 0.381 1.27)
			(layers "F.Cu" "F.Mask" "F.Paste")
			(net "P5E_PEX2_STN2_RX_DP<41>")
		)
		(pad "A22" smd rect
			(at 2.29997 4.60502 90)
			(size 0.381 1.27)
			(layers "F.Cu" "F.Mask" "F.Paste")
			(net "GND")
		)
		(pad "A23" smd rect
			(at 2.29997 5.204968 90)
			(size 0.381 1.27)
			(layers "F.Cu" "F.Mask" "F.Paste")
			(net "P5E_PEX2_STN2_RX_DN<42>")
		)
		(pad "A24" smd rect
			(at 2.29997 5.804916 90)
			(size 0.381 1.27)
			(layers "F.Cu" "F.Mask" "F.Paste")
			(net "P5E_PEX2_STN2_RX_DP<42>")
		)
		(pad "A25" smd rect
			(at 2.29997 6.405118 90)
			(size 0.381 1.27)
			(layers "F.Cu" "F.Mask" "F.Paste")
			(net "GND")
		)
		(pad "A26" smd rect
			(at 2.29997 7.005066 90)
			(size 0.381 1.27)
			(layers "F.Cu" "F.Mask" "F.Paste")
			(net "P5E_PEX2_STN2_RX_DN<43>")
		)
		(pad "A27" smd rect
			(at 2.29997 7.605014 90)
			(size 0.381 1.27)
			(layers "F.Cu" "F.Mask" "F.Paste")
			(net "P5E_PEX2_STN2_RX_DP<43>")
		)
		(pad "A28" smd rect
			(at 2.29997 8.204962 90)
			(size 0.381 1.27)
			(layers "F.Cu" "F.Mask" "F.Paste")
			(net "GND")
		)
		(pad "B1" smd rect
			(at -2.29997 -7.994904 90)
			(size 0.381 1.27)
			(layers "F.Cu" "F.Mask" "F.Paste")
			(net "P12V_SSD9")
		)
		(pad "B2" smd rect
			(at -2.29997 -7.394956 90)
			(size 0.381 1.27)
			(layers "F.Cu" "F.Mask" "F.Paste")
			(net "P12V_SSD9")
		)
		(pad "B3" smd rect
			(at -2.29997 -6.795008 90)
			(size 0.381 1.27)
			(layers "F.Cu" "F.Mask" "F.Paste")
			(net "P12V_SSD9")
		)
		(pad "B4" smd rect
			(at -2.29997 -6.19506 90)
			(size 0.381 1.27)
			(layers "F.Cu" "F.Mask" "F.Paste")
			(net "P12V_SSD9")
		)
		(pad "B5" smd rect
			(at -2.29997 -5.595112 90)
			(size 0.381 1.27)
			(layers "F.Cu" "F.Mask" "F.Paste")
			(net "P12V_SSD9")
		)
		(pad "B6" smd rect
			(at -2.29997 -4.99491 90)
			(size 0.381 1.27)
			(layers "F.Cu" "F.Mask" "F.Paste")
			(net "P12V_SSD9")
		)
		(pad "B7" smd rect
			(at -2.29997 -4.394962 90)
			(size 0.381 1.27)
			(layers "F.Cu" "F.Mask" "F.Paste")
			(net "Net_8496")
		)
		(pad "B8" smd rect
			(at -2.29997 -3.795014 90)
			(size 0.381 1.27)
			(layers "F.Cu" "F.Mask" "F.Paste")
			(net "Net_8493")
		)
		(pad "B9" smd rect
			(at -2.29997 -3.195066 90)
			(size 0.381 1.27)
			(layers "F.Cu" "F.Mask" "F.Paste")
			(net "DUALPORT_N_SSD9")
		)
		(pad "B10" smd rect
			(at -2.29997 -2.595118 90)
			(size 0.381 1.27)
			(layers "F.Cu" "F.Mask" "F.Paste")
			(net "RST_SSD9_PERST_R_N")
		)
		(pad "B11" smd rect
			(at -2.29997 -1.994916 90)
			(size 0.381 1.27)
			(layers "F.Cu" "F.Mask" "F.Paste")
			(net "P3V3_SSD9")
		)
		(pad "B12" smd rect
			(at -2.29997 -1.394968 90)
			(size 0.381 1.27)
			(layers "F.Cu" "F.Mask" "F.Paste")
			(net "SSD9_PWRDIS_R")
		)
		(pad "B13" smd rect
			(at -2.29997 -0.79502 90)
			(size 0.381 1.27)
			(layers "F.Cu" "F.Mask" "F.Paste")
			(net "GND")
		)
		(pad "B14" smd rect
			(at -2.29997 -0.195072 90)
			(size 0.381 1.27)
			(layers "F.Cu" "F.Mask" "F.Paste")
			(net "CLK_100M_DB800ZL_SSD9_R_DN")
		)
		(pad "B15" smd rect
			(at -2.29997 0.404876 90)
			(size 0.381 1.27)
			(layers "F.Cu" "F.Mask" "F.Paste")
			(net "CLK_100M_DB800ZL_SSD9_R_DP")
		)
		(pad "B16" smd rect
			(at -2.29997 1.005078 90)
			(size 0.381 1.27)
			(layers "F.Cu" "F.Mask" "F.Paste")
			(net "GND")
		)
		(pad "B17" smd rect
			(at -2.29997 1.605026 90)
			(size 0.381 1.27)
			(layers "F.Cu" "F.Mask" "F.Paste")
			(net "P5E_PEX2_STN2_TX_C_DN<40>")
		)
		(pad "B18" smd rect
			(at -2.29997 2.204974 90)
			(size 0.381 1.27)
			(layers "F.Cu" "F.Mask" "F.Paste")
			(net "P5E_PEX2_STN2_TX_C_DP<40>")
		)
		(pad "B19" smd rect
			(at -2.29997 2.804922 90)
			(size 0.381 1.27)
			(layers "F.Cu" "F.Mask" "F.Paste")
			(net "GND")
		)
		(pad "B20" smd rect
			(at -2.29997 3.405124 90)
			(size 0.381 1.27)
			(layers "F.Cu" "F.Mask" "F.Paste")
			(net "P5E_PEX2_STN2_TX_C_DN<41>")
		)
		(pad "B21" smd rect
			(at -2.29997 4.005072 90)
			(size 0.381 1.27)
			(layers "F.Cu" "F.Mask" "F.Paste")
			(net "P5E_PEX2_STN2_TX_C_DP<41>")
		)
		(pad "B22" smd rect
			(at -2.29997 4.60502 90)
			(size 0.381 1.27)
			(layers "F.Cu" "F.Mask" "F.Paste")
			(net "GND")
		)
		(pad "B23" smd rect
			(at -2.29997 5.204968 90)
			(size 0.381 1.27)
			(layers "F.Cu" "F.Mask" "F.Paste")
			(net "P5E_PEX2_STN2_TX_C_DN<42>")
		)
		(pad "B24" smd rect
			(at -2.29997 5.804916 90)
			(size 0.381 1.27)
			(layers "F.Cu" "F.Mask" "F.Paste")
			(net "P5E_PEX2_STN2_TX_C_DP<42>")
		)
		(pad "B25" smd rect
			(at -2.29997 6.405118 90)
			(size 0.381 1.27)
			(layers "F.Cu" "F.Mask" "F.Paste")
			(net "GND")
		)
		(pad "B26" smd rect
			(at -2.29997 7.005066 90)
			(size 0.381 1.27)
			(layers "F.Cu" "F.Mask" "F.Paste")
			(net "P5E_PEX2_STN2_TX_C_DN<43>")
		)
		(pad "B27" smd rect
			(at -2.29997 7.605014 90)
			(size 0.381 1.27)
			(layers "F.Cu" "F.Mask" "F.Paste")
			(net "P5E_PEX2_STN2_TX_C_DP<43>")
		)
		(pad "B28" smd rect
			(at -2.29997 8.204962 90)
			(size 0.381 1.27)
			(layers "F.Cu" "F.Mask" "F.Paste")
			(net "GND")
		)
		(pad "G1" thru_hole oval
			(at 0 -11.364976 90)
			(size 1.6256 3.4798)
			(drill oval 1.1176 2.4638)
			(layers "*.Cu" "*.Mask")
			(remove_unused_layers no)
			(net "GND")
			(clearance 0.127)
			(thermal_gap 0.127)
		)
		(pad "G2" thru_hole oval
			(at 0 11.364976 90)
			(size 1.6256 3.4798)
			(drill oval 1.1176 2.4638)
			(layers "*.Cu" "*.Mask")
			(remove_unused_layers no)
			(net "GND")
			(clearance 0.127)
			(thermal_gap 0.127)
		)
		(zone
			(layer "F.Cu")
			(hatch none 0.5)
			(connect_pads
				(clearance 0)
			)
			(min_thickness 0.25)
			(keepout
				(tracks not_allowed)
				(vias allowed)
				(pads allowed)
				(copperpour not_allowed)
				(footprints allowed)
			)
			(placement
				(enabled no)
				(sheetname "")
			)
			(fill
				(thermal_gap 0.5)
				(thermal_bridge_width 0.5)
				(island_removal_mode 0)
			)
			(polygon
				(pts
					(xy 272.544794 -38.850062) (xy 269.794736 -38.850062) (xy 269.794736 -35.900106) (xy 272.544794 -35.900106)
				)
			)
		)
		(zone
			(layer "F.Cu")
			(hatch none 0.5)
			(connect_pads
				(clearance 0)
			)
			(min_thickness 0.25)
			(keepout
				(tracks not_allowed)
				(vias allowed)
				(pads allowed)
				(copperpour not_allowed)
				(footprints allowed)
			)
			(placement
				(enabled no)
				(sheetname "")
			)
			(fill
				(thermal_gap 0.5)
				(thermal_bridge_width 0.5)
				(island_removal_mode 0)
			)
			(polygon
				(pts
					(xy 273.614896 -17.670018) (xy 269.78483 -17.670018) (xy 269.78483 -14.720062) (xy 273.614896 -14.720062)
				)
			)
		)
		(zone
			(layers "F.Cu" "B.Cu" "In1.Cu" "In2.Cu" "In3.Cu" "In4.Cu" "In5.Cu" "In6.Cu"
				"In7.Cu" "In8.Cu" "In9.Cu" "In10.Cu" "In11.Cu" "In12.Cu" "In13.Cu" "In14.Cu"
				"In15.Cu" "In16.Cu"
			)
			(hatch none 0.5)
			(connect_pads
				(clearance 0)
			)
			(min_thickness 0.25)
			(keepout
				(tracks not_allowed)
				(vias allowed)
				(pads allowed)
				(copperpour not_allowed)
				(footprints allowed)
			)
			(placement
				(enabled no)
				(sheetname "")
			)
			(fill
				(thermal_gap 0.5)
				(thermal_bridge_width 0.5)
				(island_removal_mode 0)
			)
			(polygon
				(pts
					(arc
						(start 272.130012 -36.60013)
						(mid 270.199612 -36.60013)
						(end 272.130012 -36.60013)
					)
				)
			)
		)
		(zone
			(layers "F.Cu" "B.Cu" "In1.Cu" "In2.Cu" "In3.Cu" "In4.Cu" "In5.Cu" "In6.Cu"
				"In7.Cu" "In8.Cu" "In9.Cu" "In10.Cu" "In11.Cu" "In12.Cu" "In13.Cu" "In14.Cu"
				"In15.Cu" "In16.Cu"
			)
			(hatch none 0.5)
			(connect_pads
				(clearance 0)
			)
			(min_thickness 0.25)
			(keepout
				(tracks not_allowed)
				(vias allowed)
				(pads allowed)
				(copperpour not_allowed)
				(footprints allowed)
			)
			(placement
				(enabled no)
				(sheetname "")
			)
			(fill
				(thermal_gap 0.5)
				(thermal_bridge_width 0.5)
				(island_removal_mode 0)
			)
			(polygon
				(pts
					(arc
						(start 273.880072 -16.969994)
						(mid 271.949672 -16.969994)
						(end 273.880072 -16.969994)
					)
				)
			)
		)
	)
	(footprint ""
		(layer "F.Cu")
		(at 267.871702 -350.098614 90)
		(property "Reference" "C613"
			(at 0 0 90)
			(layer "F.SilkS")
			(hide yes)
			(effects
				(font
					(size 1.27 1.27)
				)
			)
		)
		(property "Value" ""
			(at 0 0 90)
			(layer "F.Fab")
			(effects
				(font
					(size 1.27 1.27)
				)
			)
		)
		(duplicate_pad_numbers_are_jumpers no)
		(fp_line
			(start 0.299974 -0.150114)
			(end 0.299974 0.150114)
			(stroke
				(width 0.1)
				(type default)
			)
			(layer "F.Fab")
		)
		(fp_line
			(start -0.299974 -0.150114)
			(end 0.299974 -0.150114)
			(stroke
				(width 0.1)
				(type default)
			)
			(layer "F.Fab")
		)
		(fp_line
			(start 0.299974 0.150114)
			(end -0.299974 0.150114)
			(stroke
				(width 0.1)
				(type default)
			)
			(layer "F.Fab")
		)
		(fp_line
			(start -0.299974 0.150114)
			(end -0.299974 -0.150114)
			(stroke
				(width 0.1)
				(type default)
			)
			(layer "F.Fab")
		)
		(pad "1" smd rect
			(at -0.2667 0 90)
			(size 0.3048 0.381)
			(layers "F.Cu" "F.Mask" "F.Paste")
			(net "P5E_PEX2_STN7_TX_DP<112>")
		)
		(pad "2" smd rect
			(at 0.2667 0 90)
			(size 0.3048 0.381)
			(layers "F.Cu" "F.Mask" "F.Paste")
			(net "P5E_PEX2_STN7_TX_C_DP<112>")
		)
	)
	(footprint ""
		(layer "F.Cu")
		(at 255.702054 -254.850646 180)
		(property "Reference" "D3"
			(at 1.182878 -1.273048 0)
			(unlocked yes)
			(layer "F.SilkS")
			(effects
				(font
					(size 0.7874 0.5842)
					(thickness 0.1524)
				)
				(justify left)
			)
		)
		(property "Value" ""
			(at 0 0 180)
			(layer "F.Fab")
			(effects
				(font
					(size 1.27 1.27)
				)
			)
		)
		(duplicate_pad_numbers_are_jumpers no)
		(fp_line
			(start 1.16078 0.4826)
			(end -0.64008 0.4826)
			(stroke
				(width 0.1524)
				(type default)
			)
			(layer "F.SilkS")
		)
		(fp_line
			(start 1.16078 -0.4826)
			(end 1.16078 0.4826)
			(stroke
				(width 0.1524)
				(type default)
			)
			(layer "F.SilkS")
		)
		(fp_line
			(start 1.03378 0.4826)
			(end -0.79248 0.4826)
			(stroke
				(width 0.1524)
				(type default)
			)
			(layer "F.SilkS")
		)
		(fp_line
			(start 1.03378 -0.4826)
			(end 1.03378 0.4826)
			(stroke
				(width 0.1524)
				(type default)
			)
			(layer "F.SilkS")
		)
		(fp_line
			(start 0.90678 0.4826)
			(end -0.90678 0.4826)
			(stroke
				(width 0.1524)
				(type default)
			)
			(layer "F.SilkS")
		)
		(fp_line
			(start 0.90678 -0.4826)
			(end 0.90678 0.4826)
			(stroke
				(width 0.1524)
				(type default)
			)
			(layer "F.SilkS")
		)
		(fp_line
			(start -0.64008 -0.4826)
			(end 1.16078 -0.4826)
			(stroke
				(width 0.1524)
				(type default)
			)
			(layer "F.SilkS")
		)
		(fp_line
			(start -0.79248 -0.4826)
			(end 1.03378 -0.4826)
			(stroke
				(width 0.1524)
				(type default)
			)
			(layer "F.SilkS")
		)
		(fp_line
			(start -0.89408 -0.4826)
			(end 0.90678 -0.4826)
			(stroke
				(width 0.1524)
				(type default)
			)
			(layer "F.SilkS")
		)
		(fp_line
			(start -0.90678 0.4826)
			(end -0.90678 -0.4699)
			(stroke
				(width 0.1524)
				(type default)
			)
			(layer "F.SilkS")
		)
		(fp_line
			(start 0.499872 0.249936)
			(end -0.499872 0.249936)
			(stroke
				(width 0.1)
				(type default)
			)
			(layer "F.Fab")
		)
		(fp_line
			(start 0.499872 -0.249936)
			(end 0.499872 0.249936)
			(stroke
				(width 0.1)
				(type default)
			)
			(layer "F.Fab")
		)
		(fp_line
			(start -0.499872 0.249936)
			(end -0.499872 -0.249936)
			(stroke
				(width 0.1)
				(type default)
			)
			(layer "F.Fab")
		)
		(fp_line
			(start -0.499872 -0.249936)
			(end 0.499872 -0.249936)
			(stroke
				(width 0.1)
				(type default)
			)
			(layer "F.Fab")
		)
		(pad "A" smd rect
			(at -0.47498 0 180)
			(size 0.6096 0.7112)
			(layers "F.Cu" "F.Mask" "F.Paste")
			(net "LED_PEX2_SYS_ERR_N")
		)
		(pad "C" smd rect
			(at 0.47498 0 180)
			(size 0.6096 0.7112)
			(layers "F.Cu" "F.Mask" "F.Paste")
			(net "PEX2_SYS_ERR_3V3_N")
		)
	)
	(footprint ""
		(layer "F.Cu")
		(at 206.623158 -81.627472)
		(property "Reference" "R4305"
			(at 0 0 0)
			(layer "F.SilkS")
			(hide yes)
			(effects
				(font
					(size 1.27 1.27)
				)
			)
		)
		(property "Value" ""
			(at 0 0 0)
			(layer "F.Fab")
			(effects
				(font
					(size 1.27 1.27)
				)
			)
		)
		(duplicate_pad_numbers_are_jumpers no)
		(fp_line
			(start -0.7874 -0.4064)
			(end 0.7874 -0.4064)
			(stroke
				(width 0.1524)
				(type default)
			)
			(layer "F.SilkS")
		)
		(fp_line
			(start -0.7874 0.4064)
			(end -0.7874 -0.4064)
			(stroke
				(width 0.1524)
				(type default)
			)
			(layer "F.SilkS")
		)
		(fp_line
			(start 0.7874 -0.4064)
			(end 0.7874 0.4064)
			(stroke
				(width 0.1524)
				(type default)
			)
			(layer "F.SilkS")
		)
		(fp_line
			(start 0.7874 0.4064)
			(end -0.7874 0.4064)
			(stroke
				(width 0.1524)
				(type default)
			)
			(layer "F.SilkS")
		)
		(fp_line
			(start -0.67945 -0.305054)
			(end -0.12065 -0.305054)
			(stroke
				(width 0.1)
				(type default)
			)
			(layer "F.Fab")
		)
		(fp_line
			(start -0.67945 0.3048)
			(end -0.67945 -0.305054)
			(stroke
				(width 0.1)
				(type default)
			)
			(layer "F.Fab")
		)
		(fp_line
			(start -0.12065 -0.305054)
			(end -0.12065 -0.2794)
			(stroke
				(width 0.1)
				(type default)
			)
			(layer "F.Fab")
		)
		(fp_line
			(start -0.12065 -0.2794)
			(end 0.12065 -0.2794)
			(stroke
				(width 0.1)
				(type default)
			)
			(layer "F.Fab")
		)
		(fp_line
			(start -0.12065 0.2794)
			(end -0.12065 0.3048)
			(stroke
				(width 0.1)
				(type default)
			)
			(layer "F.Fab")
		)
		(fp_line
			(start -0.12065 0.3048)
			(end -0.67945 0.3048)
			(stroke
				(width 0.1)
				(type default)
			)
			(layer "F.Fab")
		)
		(fp_line
			(start 0.120396 0.2794)
			(end -0.12065 0.2794)
			(stroke
				(width 0.1)
				(type default)
			)
			(layer "F.Fab")
		)
		(fp_line
			(start 0.120396 0.3048)
			(end 0.120396 0.2794)
			(stroke
				(width 0.1)
				(type default)
			)
			(layer "F.Fab")
		)
		(fp_line
			(start 0.12065 -0.3048)
			(end 0.67945 -0.3048)
			(stroke
				(width 0.1)
				(type default)
			)
			(layer "F.Fab")
		)
		(fp_line
			(start 0.12065 -0.2794)
			(end 0.12065 -0.3048)
			(stroke
				(width 0.1)
				(type default)
			)
			(layer "F.Fab")
		)
		(fp_line
			(start 0.67945 -0.3048)
			(end 0.67945 0.3048)
			(stroke
				(width 0.1)
				(type default)
			)
			(layer "F.Fab")
		)
		(fp_line
			(start 0.67945 0.3048)
			(end 0.120396 0.3048)
			(stroke
				(width 0.1)
				(type default)
			)
			(layer "F.Fab")
		)
		(pad "1" smd circle
			(at -0.40005 0)
			(size 0 0)
			(layers "F.Cu" "F.Mask" "F.Paste")
			(net "SSD3_LED_R")
		)
		(pad "2" smd circle
			(at 0.40005 0)
			(size 0 0)
			(layers "F.Cu" "F.Mask" "F.Paste")
			(net "SSD3_LED")
		)
	)
	(footprint ""
		(layer "F.Cu")
		(at 460.103728 -309.679086)
		(property "Reference" "PC280"
			(at 0 0 0)
			(layer "F.SilkS")
			(hide yes)
			(effects
				(font
					(size 1.27 1.27)
				)
			)
		)
		(property "Value" ""
			(at 0 0 0)
			(layer "F.Fab")
			(effects
				(font
					(size 1.27 1.27)
				)
			)
		)
		(duplicate_pad_numbers_are_jumpers no)
		(fp_line
			(start -0.7874 -0.4064)
			(end 0.7874 -0.4064)
			(stroke
				(width 0.1524)
				(type default)
			)
			(layer "F.SilkS")
		)
		(fp_line
			(start -0.7874 0.4064)
			(end -0.7874 -0.4064)
			(stroke
				(width 0.1524)
				(type default)
			)
			(layer "F.SilkS")
		)
		(fp_line
			(start 0.7874 -0.4064)
			(end 0.7874 0.4064)
			(stroke
				(width 0.1524)
				(type default)
			)
			(layer "F.SilkS")
		)
		(fp_line
			(start 0.7874 0.4064)
			(end -0.7874 0.4064)
			(stroke
				(width 0.1524)
				(type default)
			)
			(layer "F.SilkS")
		)
		(fp_line
			(start -0.67945 -0.305054)
			(end -0.12065 -0.305054)
			(stroke
				(width 0.1)
				(type default)
			)
			(layer "F.Fab")
		)
		(fp_line
			(start -0.67945 0.3048)
			(end -0.67945 -0.305054)
			(stroke
				(width 0.1)
				(type default)
			)
			(layer "F.Fab")
		)
		(fp_line
			(start -0.12065 -0.305054)
			(end -0.12065 -0.2794)
			(stroke
				(width 0.1)
				(type default)
			)
			(layer "F.Fab")
		)
		(fp_line
			(start -0.12065 -0.2794)
			(end 0.12065 -0.2794)
			(stroke
				(width 0.1)
				(type default)
			)
			(layer "F.Fab")
		)
		(fp_line
			(start -0.12065 0.2794)
			(end -0.12065 0.3048)
			(stroke
				(width 0.1)
				(type default)
			)
			(layer "F.Fab")
		)
		(fp_line
			(start -0.12065 0.3048)
			(end -0.67945 0.3048)
			(stroke
				(width 0.1)
				(type default)
			)
			(layer "F.Fab")
		)
		(fp_line
			(start 0.120396 0.2794)
			(end -0.12065 0.2794)
			(stroke
				(width 0.1)
				(type default)
			)
			(layer "F.Fab")
		)
		(fp_line
			(start 0.120396 0.3048)
			(end 0.120396 0.2794)
			(stroke
				(width 0.1)
				(type default)
			)
			(layer "F.Fab")
		)
		(fp_line
			(start 0.12065 -0.3048)
			(end 0.67945 -0.3048)
			(stroke
				(width 0.1)
				(type default)
			)
			(layer "F.Fab")
		)
		(fp_line
			(start 0.12065 -0.2794)
			(end 0.12065 -0.3048)
			(stroke
				(width 0.1)
				(type default)
			)
			(layer "F.Fab")
		)
		(fp_line
			(start 0.67945 -0.3048)
			(end 0.67945 0.3048)
			(stroke
				(width 0.1)
				(type default)
			)
			(layer "F.Fab")
		)
		(fp_line
			(start 0.67945 0.3048)
			(end 0.120396 0.3048)
			(stroke
				(width 0.1)
				(type default)
			)
			(layer "F.Fab")
		)
		(pad "1" smd circle
			(at -0.40005 0)
			(size 0 0)
			(layers "F.Cu" "F.Mask" "F.Paste")
			(net "P1V25_PEX3_FB")
		)
		(pad "2" smd circle
			(at 0.40005 0)
			(size 0 0)
			(layers "F.Cu" "F.Mask" "F.Paste")
			(net "SH_P1V25_PEX3_FB_P")
		)
	)
	(footprint ""
		(layer "F.Cu")
		(at 233.444288 -97.258378 90)
		(property "Reference" "R1007"
			(at 0 0 90)
			(layer "F.SilkS")
			(hide yes)
			(effects
				(font
					(size 1.27 1.27)
				)
			)
		)
		(property "Value" ""
			(at 0 0 90)
			(layer "F.Fab")
			(effects
				(font
					(size 1.27 1.27)
				)
			)
		)
		(duplicate_pad_numbers_are_jumpers no)
		(fp_line
			(start 0.7874 -0.4064)
			(end 0.7874 0.4064)
			(stroke
				(width 0.1524)
				(type default)
			)
			(layer "F.SilkS")
		)
		(fp_line
			(start -0.7874 -0.4064)
			(end 0.7874 -0.4064)
			(stroke
				(width 0.1524)
				(type default)
			)
			(layer "F.SilkS")
		)
		(fp_line
			(start 0.7874 0.4064)
			(end -0.7874 0.4064)
			(stroke
				(width 0.1524)
				(type default)
			)
			(layer "F.SilkS")
		)
		(fp_line
			(start -0.7874 0.4064)
			(end -0.7874 -0.4064)
			(stroke
				(width 0.1524)
				(type default)
			)
			(layer "F.SilkS")
		)
		(fp_line
			(start -0.12065 -0.305054)
			(end -0.12065 -0.2794)
			(stroke
				(width 0.1)
				(type default)
			)
			(layer "F.Fab")
		)
		(fp_line
			(start -0.67945 -0.305054)
			(end -0.12065 -0.305054)
			(stroke
				(width 0.1)
				(type default)
			)
			(layer "F.Fab")
		)
		(fp_line
			(start 0.67945 -0.3048)
			(end 0.67945 0.3048)
			(stroke
				(width 0.1)
				(type default)
			)
			(layer "F.Fab")
		)
		(fp_line
			(start 0.12065 -0.3048)
			(end 0.67945 -0.3048)
			(stroke
				(width 0.1)
				(type default)
			)
			(layer "F.Fab")
		)
		(fp_line
			(start 0.12065 -0.2794)
			(end 0.12065 -0.3048)
			(stroke
				(width 0.1)
				(type default)
			)
			(layer "F.Fab")
		)
		(fp_line
			(start -0.12065 -0.2794)
			(end 0.12065 -0.2794)
			(stroke
				(width 0.1)
				(type default)
			)
			(layer "F.Fab")
		)
		(fp_line
			(start 0.120396 0.2794)
			(end -0.12065 0.2794)
			(stroke
				(width 0.1)
				(type default)
			)
			(layer "F.Fab")
		)
		(fp_line
			(start -0.12065 0.2794)
			(end -0.12065 0.3048)
			(stroke
				(width 0.1)
				(type default)
			)
			(layer "F.Fab")
		)
		(fp_line
			(start 0.67945 0.3048)
			(end 0.120396 0.3048)
			(stroke
				(width 0.1)
				(type default)
			)
			(layer "F.Fab")
		)
		(fp_line
			(start 0.120396 0.3048)
			(end 0.120396 0.2794)
			(stroke
				(width 0.1)
				(type default)
			)
			(layer "F.Fab")
		)
		(fp_line
			(start -0.12065 0.3048)
			(end -0.67945 0.3048)
			(stroke
				(width 0.1)
				(type default)
			)
			(layer "F.Fab")
		)
		(fp_line
			(start -0.67945 0.3048)
			(end -0.67945 -0.305054)
			(stroke
				(width 0.1)
				(type default)
			)
			(layer "F.Fab")
		)
		(pad "1" smd circle
			(at -0.40005 0 90)
			(size 0 0)
			(layers "F.Cu" "F.Mask" "F.Paste")
			(net "PEX_USB_HUB_TEST")
		)
		(pad "2" smd circle
			(at 0.40005 0 90)
			(size 0 0)
			(layers "F.Cu" "F.Mask" "F.Paste")
			(net "GND")
		)
	)
	(footprint ""
		(layer "F.Cu")
		(at 47.961042 -37.951156)
		(property "Reference" "Q135"
			(at 0.287274 -2.501138 0)
			(unlocked yes)
			(layer "F.SilkS")
			(effects
				(font
					(size 0.7874 0.5842)
					(thickness 0.1524)
				)
			)
		)
		(property "Value" ""
			(at 0 0 0)
			(layer "F.Fab")
			(effects
				(font
					(size 1.27 1.27)
				)
			)
		)
		(duplicate_pad_numbers_are_jumpers no)
		(fp_line
			(start -1.376172 -1.199896)
			(end -0.508 -1.199896)
			(stroke
				(width 0.1524)
				(type default)
			)
			(layer "F.SilkS")
		)
		(fp_line
			(start -1.376172 1.199896)
			(end -1.376172 -1.199896)
			(stroke
				(width 0.1524)
				(type default)
			)
			(layer "F.SilkS")
		)
		(fp_line
			(start -0.508 -1.199896)
			(end 0 -0.762)
			(stroke
				(width 0.1524)
				(type default)
			)
			(layer "F.SilkS")
		)
		(fp_line
			(start 0 -0.762)
			(end 0.508 -1.199896)
			(stroke
				(width 0.1524)
				(type default)
			)
			(layer "F.SilkS")
		)
		(fp_line
			(start 0.508 -1.199896)
			(end 1.376172 -1.199896)
			(stroke
				(width 0.1524)
				(type default)
			)
			(layer "F.SilkS")
		)
		(fp_line
			(start 1.376172 -1.199896)
			(end 1.376172 1.199896)
			(stroke
				(width 0.1524)
				(type default)
			)
			(layer "F.SilkS")
		)
		(fp_line
			(start 1.376172 1.199896)
			(end -1.376172 1.199896)
			(stroke
				(width 0.1524)
				(type default)
			)
			(layer "F.SilkS")
		)
		(fp_poly
			(pts
				(xy -1.525778 -1.087882) (xy -1.795272 -1.89611) (xy -2.334006 -1.357376)
			)
			(stroke
				(width 0)
				(type default)
			)
			(fill yes)
			(layer "F.SilkS")
		)
		(fp_line
			(start -0.674878 -1.100074)
			(end 0.674878 -1.100074)
			(stroke
				(width 0.1)
				(type default)
			)
			(layer "F.Fab")
		)
		(fp_line
			(start -0.674878 1.100074)
			(end -0.674878 -1.100074)
			(stroke
				(width 0.1)
				(type default)
			)
			(layer "F.Fab")
		)
		(fp_line
			(start 0.674878 -1.100074)
			(end 0.674878 1.100074)
			(stroke
				(width 0.1)
				(type default)
			)
			(layer "F.Fab")
		)
		(fp_line
			(start 0.674878 1.100074)
			(end -0.674878 1.100074)
			(stroke
				(width 0.1)
				(type default)
			)
			(layer "F.Fab")
		)
		(fp_poly
			(pts
				(xy -1.4605 -0.7493) (xy -2.2225 -1.1303) (xy -2.2225 -0.3683)
			)
			(stroke
				(width 0)
				(type default)
			)
			(fill yes)
			(layer "F.Fab")
		)
		(pad "1" smd rect
			(at -0.899922 -0.750062 270)
			(size 0.6096 0.6096)
			(layers "F.Cu" "F.Mask" "F.Paste")
			(net "GND")
		)
		(pad "2" smd rect
			(at -0.899922 0 270)
			(size 0.4064 0.6096)
			(layers "F.Cu" "F.Mask" "F.Paste")
			(net "P3V3_SSD2_PG_G1")
		)
		(pad "3" smd rect
			(at -0.899922 0.750062 270)
			(size 0.6096 0.6096)
			(layers "F.Cu" "F.Mask" "F.Paste")
			(net "PWRGD_P3V3_SSD2_D")
		)
		(pad "4" smd rect
			(at 0.899922 0.750062 270)
			(size 0.6096 0.6096)
			(layers "F.Cu" "F.Mask" "F.Paste")
			(net "GND")
		)
		(pad "5" smd rect
			(at 0.899922 0 270)
			(size 0.4064 0.6096)
			(layers "F.Cu" "F.Mask" "F.Paste")
			(net "P3V3_SSD2_PG_G2")
		)
		(pad "6" smd rect
			(at 0.899922 -0.750062 270)
			(size 0.6096 0.6096)
			(layers "F.Cu" "F.Mask" "F.Paste")
			(net "P3V3_SSD2_PG_G2")
		)
	)
	(footprint ""
		(layer "F.Cu")
		(at 27.332178 -32.848042 90)
		(property "Reference" "PC677"
			(at 0 0 90)
			(layer "F.SilkS")
			(hide yes)
			(effects
				(font
					(size 1.27 1.27)
				)
			)
		)
		(property "Value" ""
			(at 0 0 90)
			(layer "F.Fab")
			(effects
				(font
					(size 1.27 1.27)
				)
			)
		)
		(duplicate_pad_numbers_are_jumpers no)
		(fp_line
			(start 0.7874 -0.4064)
			(end 0.7874 0.4064)
			(stroke
				(width 0.1524)
				(type default)
			)
			(layer "F.SilkS")
		)
		(fp_line
			(start -0.7874 -0.4064)
			(end 0.7874 -0.4064)
			(stroke
				(width 0.1524)
				(type default)
			)
			(layer "F.SilkS")
		)
		(fp_line
			(start 0.7874 0.4064)
			(end -0.7874 0.4064)
			(stroke
				(width 0.1524)
				(type default)
			)
			(layer "F.SilkS")
		)
		(fp_line
			(start -0.7874 0.4064)
			(end -0.7874 -0.4064)
			(stroke
				(width 0.1524)
				(type default)
			)
			(layer "F.SilkS")
		)
		(fp_line
			(start -0.12065 -0.305054)
			(end -0.12065 -0.2794)
			(stroke
				(width 0.1)
				(type default)
			)
			(layer "F.Fab")
		)
		(fp_line
			(start -0.67945 -0.305054)
			(end -0.12065 -0.305054)
			(stroke
				(width 0.1)
				(type default)
			)
			(layer "F.Fab")
		)
		(fp_line
			(start 0.67945 -0.3048)
			(end 0.67945 0.3048)
			(stroke
				(width 0.1)
				(type default)
			)
			(layer "F.Fab")
		)
		(fp_line
			(start 0.12065 -0.3048)
			(end 0.67945 -0.3048)
			(stroke
				(width 0.1)
				(type default)
			)
			(layer "F.Fab")
		)
		(fp_line
			(start 0.12065 -0.2794)
			(end 0.12065 -0.3048)
			(stroke
				(width 0.1)
				(type default)
			)
			(layer "F.Fab")
		)
		(fp_line
			(start -0.12065 -0.2794)
			(end 0.12065 -0.2794)
			(stroke
				(width 0.1)
				(type default)
			)
			(layer "F.Fab")
		)
		(fp_line
			(start 0.120396 0.2794)
			(end -0.12065 0.2794)
			(stroke
				(width 0.1)
				(type default)
			)
			(layer "F.Fab")
		)
		(fp_line
			(start -0.12065 0.2794)
			(end -0.12065 0.3048)
			(stroke
				(width 0.1)
				(type default)
			)
			(layer "F.Fab")
		)
		(fp_line
			(start 0.67945 0.3048)
			(end 0.120396 0.3048)
			(stroke
				(width 0.1)
				(type default)
			)
			(layer "F.Fab")
		)
		(fp_line
			(start 0.120396 0.3048)
			(end 0.120396 0.2794)
			(stroke
				(width 0.1)
				(type default)
			)
			(layer "F.Fab")
		)
		(fp_line
			(start -0.12065 0.3048)
			(end -0.67945 0.3048)
			(stroke
				(width 0.1)
				(type default)
			)
			(layer "F.Fab")
		)
		(fp_line
			(start -0.67945 0.3048)
			(end -0.67945 -0.305054)
			(stroke
				(width 0.1)
				(type default)
			)
			(layer "F.Fab")
		)
		(pad "1" smd circle
			(at -0.40005 0 90)
			(size 0 0)
			(layers "F.Cu" "F.Mask" "F.Paste")
			(net "P3V3_SSD1_CO_DV_DT")
		)
		(pad "2" smd circle
			(at 0.40005 0 90)
			(size 0 0)
			(layers "F.Cu" "F.Mask" "F.Paste")
			(net "GND")
		)
	)
	(footprint ""
		(layer "F.Cu")
		(at 358.792526 -252.045978 180)
		(property "Reference" "R1762"
			(at 0 0 180)
			(layer "F.SilkS")
			(hide yes)
			(effects
				(font
					(size 1.27 1.27)
				)
			)
		)
		(property "Value" ""
			(at 0 0 180)
			(layer "F.Fab")
			(effects
				(font
					(size 1.27 1.27)
				)
			)
		)
		(duplicate_pad_numbers_are_jumpers no)
		(fp_line
			(start 0.7874 0.4064)
			(end -0.7874 0.4064)
			(stroke
				(width 0.1524)
				(type default)
			)
			(layer "F.SilkS")
		)
		(fp_line
			(start 0.7874 -0.4064)
			(end 0.7874 0.4064)
			(stroke
				(width 0.1524)
				(type default)
			)
			(layer "F.SilkS")
		)
		(fp_line
			(start -0.7874 0.4064)
			(end -0.7874 -0.4064)
			(stroke
				(width 0.1524)
				(type default)
			)
			(layer "F.SilkS")
		)
		(fp_line
			(start -0.7874 -0.4064)
			(end 0.7874 -0.4064)
			(stroke
				(width 0.1524)
				(type default)
			)
			(layer "F.SilkS")
		)
		(fp_line
			(start 0.67945 0.3048)
			(end 0.120396 0.3048)
			(stroke
				(width 0.1)
				(type default)
			)
			(layer "F.Fab")
		)
		(fp_line
			(start 0.67945 -0.3048)
			(end 0.67945 0.3048)
			(stroke
				(width 0.1)
				(type default)
			)
			(layer "F.Fab")
		)
		(fp_line
			(start 0.12065 -0.2794)
			(end 0.12065 -0.3048)
			(stroke
				(width 0.1)
				(type default)
			)
			(layer "F.Fab")
		)
		(fp_line
			(start 0.12065 -0.3048)
			(end 0.67945 -0.3048)
			(stroke
				(width 0.1)
				(type default)
			)
			(layer "F.Fab")
		)
		(fp_line
			(start 0.120396 0.3048)
			(end 0.120396 0.2794)
			(stroke
				(width 0.1)
				(type default)
			)
			(layer "F.Fab")
		)
		(fp_line
			(start 0.120396 0.2794)
			(end -0.12065 0.2794)
			(stroke
				(width 0.1)
				(type default)
			)
			(layer "F.Fab")
		)
		(fp_line
			(start -0.12065 0.3048)
			(end -0.67945 0.3048)
			(stroke
				(width 0.1)
				(type default)
			)
			(layer "F.Fab")
		)
		(fp_line
			(start -0.12065 0.2794)
			(end -0.12065 0.3048)
			(stroke
				(width 0.1)
				(type default)
			)
			(layer "F.Fab")
		)
		(fp_line
			(start -0.12065 -0.2794)
			(end 0.12065 -0.2794)
			(stroke
				(width 0.1)
				(type default)
			)
			(layer "F.Fab")
		)
		(fp_line
			(start -0.12065 -0.305054)
			(end -0.12065 -0.2794)
			(stroke
				(width 0.1)
				(type default)
			)
			(layer "F.Fab")
		)
		(fp_line
			(start -0.67945 0.3048)
			(end -0.67945 -0.305054)
			(stroke
				(width 0.1)
				(type default)
			)
			(layer "F.Fab")
		)
		(fp_line
			(start -0.67945 -0.305054)
			(end -0.12065 -0.305054)
			(stroke
				(width 0.1)
				(type default)
			)
			(layer "F.Fab")
		)
		(pad "1" smd circle
			(at -0.40005 0 180)
			(size 0 0)
			(layers "F.Cu" "F.Mask" "F.Paste")
			(net "P3V3_AUX")
		)
		(pad "2" smd circle
			(at 0.40005 0 180)
			(size 0 0)
			(layers "F.Cu" "F.Mask" "F.Paste")
			(net "SMB_BIC_I2C6_MUX_VR_R_SCL")
		)
	)
	(footprint ""
		(layer "F.Cu")
		(at 217.756486 -17.419574 180)
		(property "Reference" "R1677"
			(at 0 0 180)
			(layer "F.SilkS")
			(hide yes)
			(effects
				(font
					(size 1.27 1.27)
				)
			)
		)
		(property "Value" ""
			(at 0 0 180)
			(layer "F.Fab")
			(effects
				(font
					(size 1.27 1.27)
				)
			)
		)
		(duplicate_pad_numbers_are_jumpers no)
		(fp_line
			(start 0.7874 0.4064)
			(end -0.7874 0.4064)
			(stroke
				(width 0.1524)
				(type default)
			)
			(layer "F.SilkS")
		)
		(fp_line
			(start 0.7874 -0.4064)
			(end 0.7874 0.4064)
			(stroke
				(width 0.1524)
				(type default)
			)
			(layer "F.SilkS")
		)
		(fp_line
			(start -0.7874 0.4064)
			(end -0.7874 -0.4064)
			(stroke
				(width 0.1524)
				(type default)
			)
			(layer "F.SilkS")
		)
		(fp_line
			(start -0.7874 -0.4064)
			(end 0.7874 -0.4064)
			(stroke
				(width 0.1524)
				(type default)
			)
			(layer "F.SilkS")
		)
		(fp_line
			(start 0.67945 0.3048)
			(end 0.120396 0.3048)
			(stroke
				(width 0.1)
				(type default)
			)
			(layer "F.Fab")
		)
		(fp_line
			(start 0.67945 -0.3048)
			(end 0.67945 0.3048)
			(stroke
				(width 0.1)
				(type default)
			)
			(layer "F.Fab")
		)
		(fp_line
			(start 0.12065 -0.2794)
			(end 0.12065 -0.3048)
			(stroke
				(width 0.1)
				(type default)
			)
			(layer "F.Fab")
		)
		(fp_line
			(start 0.12065 -0.3048)
			(end 0.67945 -0.3048)
			(stroke
				(width 0.1)
				(type default)
			)
			(layer "F.Fab")
		)
		(fp_line
			(start 0.120396 0.3048)
			(end 0.120396 0.2794)
			(stroke
				(width 0.1)
				(type default)
			)
			(layer "F.Fab")
		)
		(fp_line
			(start 0.120396 0.2794)
			(end -0.12065 0.2794)
			(stroke
				(width 0.1)
				(type default)
			)
			(layer "F.Fab")
		)
		(fp_line
			(start -0.12065 0.3048)
			(end -0.67945 0.3048)
			(stroke
				(width 0.1)
				(type default)
			)
			(layer "F.Fab")
		)
		(fp_line
			(start -0.12065 0.2794)
			(end -0.12065 0.3048)
			(stroke
				(width 0.1)
				(type default)
			)
			(layer "F.Fab")
		)
		(fp_line
			(start -0.12065 -0.2794)
			(end 0.12065 -0.2794)
			(stroke
				(width 0.1)
				(type default)
			)
			(layer "F.Fab")
		)
		(fp_line
			(start -0.12065 -0.305054)
			(end -0.12065 -0.2794)
			(stroke
				(width 0.1)
				(type default)
			)
			(layer "F.Fab")
		)
		(fp_line
			(start -0.67945 0.3048)
			(end -0.67945 -0.305054)
			(stroke
				(width 0.1)
				(type default)
			)
			(layer "F.Fab")
		)
		(fp_line
			(start -0.67945 -0.305054)
			(end -0.12065 -0.305054)
			(stroke
				(width 0.1)
				(type default)
			)
			(layer "F.Fab")
		)
		(pad "1" smd circle
			(at -0.40005 0 180)
			(size 0 0)
			(layers "F.Cu" "F.Mask" "F.Paste")
			(net "P3V3_SSD7")
		)
		(pad "2" smd circle
			(at 0.40005 0 180)
			(size 0 0)
			(layers "F.Cu" "F.Mask" "F.Paste")
			(net "SMB_ISO_SSD7_SCL")
		)
	)
	(footprint ""
		(layer "F.Cu")
		(at 314.861448 -120.476772 180)
		(property "Reference" "C452"
			(at 0 0 180)
			(layer "F.SilkS")
			(hide yes)
			(effects
				(font
					(size 1.27 1.27)
				)
			)
		)
		(property "Value" ""
			(at 0 0 180)
			(layer "F.Fab")
			(effects
				(font
					(size 1.27 1.27)
				)
			)
		)
		(duplicate_pad_numbers_are_jumpers no)
		(fp_line
			(start 0.299974 0.150114)
			(end -0.299974 0.150114)
			(stroke
				(width 0.1)
				(type default)
			)
			(layer "F.Fab")
		)
		(fp_line
			(start 0.299974 -0.150114)
			(end 0.299974 0.150114)
			(stroke
				(width 0.1)
				(type default)
			)
			(layer "F.Fab")
		)
		(fp_line
			(start -0.299974 0.150114)
			(end -0.299974 -0.150114)
			(stroke
				(width 0.1)
				(type default)
			)
			(layer "F.Fab")
		)
		(fp_line
			(start -0.299974 -0.150114)
			(end 0.299974 -0.150114)
			(stroke
				(width 0.1)
				(type default)
			)
			(layer "F.Fab")
		)
		(pad "1" smd rect
			(at -0.2667 0 180)
			(size 0.3048 0.381)
			(layers "F.Cu" "F.Mask" "F.Paste")
			(net "P5E_PEX2_STN0_TX_DN<1>")
		)
		(pad "2" smd rect
			(at 0.2667 0 180)
			(size 0.3048 0.381)
			(layers "F.Cu" "F.Mask" "F.Paste")
			(net "P5E_PEX2_STN0_TX_C_DN<1>")
		)
	)
	(footprint ""
		(layer "F.Cu")
		(at 214.73033 -235.756958 90)
		(property "Reference" "R6359"
			(at 0 0 90)
			(layer "F.SilkS")
			(hide yes)
			(effects
				(font
					(size 1.27 1.27)
				)
			)
		)
		(property "Value" ""
			(at 0 0 90)
			(layer "F.Fab")
			(effects
				(font
					(size 1.27 1.27)
				)
			)
		)
		(duplicate_pad_numbers_are_jumpers no)
		(fp_line
			(start 0.7874 -0.4064)
			(end 0.7874 0.4064)
			(stroke
				(width 0.1524)
				(type default)
			)
			(layer "F.SilkS")
		)
		(fp_line
			(start -0.7874 -0.4064)
			(end 0.7874 -0.4064)
			(stroke
				(width 0.1524)
				(type default)
			)
			(layer "F.SilkS")
		)
		(fp_line
			(start 0.7874 0.4064)
			(end -0.7874 0.4064)
			(stroke
				(width 0.1524)
				(type default)
			)
			(layer "F.SilkS")
		)
		(fp_line
			(start -0.7874 0.4064)
			(end -0.7874 -0.4064)
			(stroke
				(width 0.1524)
				(type default)
			)
			(layer "F.SilkS")
		)
		(fp_line
			(start -0.12065 -0.305054)
			(end -0.12065 -0.2794)
			(stroke
				(width 0.1)
				(type default)
			)
			(layer "F.Fab")
		)
		(fp_line
			(start -0.67945 -0.305054)
			(end -0.12065 -0.305054)
			(stroke
				(width 0.1)
				(type default)
			)
			(layer "F.Fab")
		)
		(fp_line
			(start 0.67945 -0.3048)
			(end 0.67945 0.3048)
			(stroke
				(width 0.1)
				(type default)
			)
			(layer "F.Fab")
		)
		(fp_line
			(start 0.12065 -0.3048)
			(end 0.67945 -0.3048)
			(stroke
				(width 0.1)
				(type default)
			)
			(layer "F.Fab")
		)
		(fp_line
			(start 0.12065 -0.2794)
			(end 0.12065 -0.3048)
			(stroke
				(width 0.1)
				(type default)
			)
			(layer "F.Fab")
		)
		(fp_line
			(start -0.12065 -0.2794)
			(end 0.12065 -0.2794)
			(stroke
				(width 0.1)
				(type default)
			)
			(layer "F.Fab")
		)
		(fp_line
			(start 0.120396 0.2794)
			(end -0.12065 0.2794)
			(stroke
				(width 0.1)
				(type default)
			)
			(layer "F.Fab")
		)
		(fp_line
			(start -0.12065 0.2794)
			(end -0.12065 0.3048)
			(stroke
				(width 0.1)
				(type default)
			)
			(layer "F.Fab")
		)
		(fp_line
			(start 0.67945 0.3048)
			(end 0.120396 0.3048)
			(stroke
				(width 0.1)
				(type default)
			)
			(layer "F.Fab")
		)
		(fp_line
			(start 0.120396 0.3048)
			(end 0.120396 0.2794)
			(stroke
				(width 0.1)
				(type default)
			)
			(layer "F.Fab")
		)
		(fp_line
			(start -0.12065 0.3048)
			(end -0.67945 0.3048)
			(stroke
				(width 0.1)
				(type default)
			)
			(layer "F.Fab")
		)
		(fp_line
			(start -0.67945 0.3048)
			(end -0.67945 -0.305054)
			(stroke
				(width 0.1)
				(type default)
			)
			(layer "F.Fab")
		)
		(pad "1" smd circle
			(at -0.40005 0 90)
			(size 0 0)
			(layers "F.Cu" "F.Mask" "F.Paste")
			(net "SMB_PEX_LS_R_SDA")
		)
		(pad "2" smd circle
			(at 0.40005 0 90)
			(size 0 0)
			(layers "F.Cu" "F.Mask" "F.Paste")
			(net "SMB_PEX_LS_SDA")
		)
	)
	(footprint ""
		(layer "F.Cu")
		(at 321.20205 -306.074572 90)
		(property "Reference" "R1370"
			(at 0 0 90)
			(layer "F.SilkS")
			(hide yes)
			(effects
				(font
					(size 1.27 1.27)
				)
			)
		)
		(property "Value" ""
			(at 0 0 90)
			(layer "F.Fab")
			(effects
				(font
					(size 1.27 1.27)
				)
			)
		)
		(duplicate_pad_numbers_are_jumpers no)
		(fp_line
			(start 0.7874 -0.4064)
			(end 0.7874 0.4064)
			(stroke
				(width 0.1524)
				(type default)
			)
			(layer "F.SilkS")
		)
		(fp_line
			(start -0.7874 -0.4064)
			(end 0.7874 -0.4064)
			(stroke
				(width 0.1524)
				(type default)
			)
			(layer "F.SilkS")
		)
		(fp_line
			(start 0.7874 0.4064)
			(end -0.7874 0.4064)
			(stroke
				(width 0.1524)
				(type default)
			)
			(layer "F.SilkS")
		)
		(fp_line
			(start -0.7874 0.4064)
			(end -0.7874 -0.4064)
			(stroke
				(width 0.1524)
				(type default)
			)
			(layer "F.SilkS")
		)
		(fp_line
			(start -0.12065 -0.305054)
			(end -0.12065 -0.2794)
			(stroke
				(width 0.1)
				(type default)
			)
			(layer "F.Fab")
		)
		(fp_line
			(start -0.67945 -0.305054)
			(end -0.12065 -0.305054)
			(stroke
				(width 0.1)
				(type default)
			)
			(layer "F.Fab")
		)
		(fp_line
			(start 0.67945 -0.3048)
			(end 0.67945 0.3048)
			(stroke
				(width 0.1)
				(type default)
			)
			(layer "F.Fab")
		)
		(fp_line
			(start 0.12065 -0.3048)
			(end 0.67945 -0.3048)
			(stroke
				(width 0.1)
				(type default)
			)
			(layer "F.Fab")
		)
		(fp_line
			(start 0.12065 -0.2794)
			(end 0.12065 -0.3048)
			(stroke
				(width 0.1)
				(type default)
			)
			(layer "F.Fab")
		)
		(fp_line
			(start -0.12065 -0.2794)
			(end 0.12065 -0.2794)
			(stroke
				(width 0.1)
				(type default)
			)
			(layer "F.Fab")
		)
		(fp_line
			(start 0.120396 0.2794)
			(end -0.12065 0.2794)
			(stroke
				(width 0.1)
				(type default)
			)
			(layer "F.Fab")
		)
		(fp_line
			(start -0.12065 0.2794)
			(end -0.12065 0.3048)
			(stroke
				(width 0.1)
				(type default)
			)
			(layer "F.Fab")
		)
		(fp_line
			(start 0.67945 0.3048)
			(end 0.120396 0.3048)
			(stroke
				(width 0.1)
				(type default)
			)
			(layer "F.Fab")
		)
		(fp_line
			(start 0.120396 0.3048)
			(end 0.120396 0.2794)
			(stroke
				(width 0.1)
				(type default)
			)
			(layer "F.Fab")
		)
		(fp_line
			(start -0.12065 0.3048)
			(end -0.67945 0.3048)
			(stroke
				(width 0.1)
				(type default)
			)
			(layer "F.Fab")
		)
		(fp_line
			(start -0.67945 0.3048)
			(end -0.67945 -0.305054)
			(stroke
				(width 0.1)
				(type default)
			)
			(layer "F.Fab")
		)
		(pad "1" smd circle
			(at -0.40005 0 90)
			(size 0 0)
			(layers "F.Cu" "F.Mask" "F.Paste")
			(net "PEX2_SPARE4")
		)
		(pad "2" smd circle
			(at 0.40005 0 90)
			(size 0 0)
			(layers "F.Cu" "F.Mask" "F.Paste")
			(net "P1V8_PEX")
		)
	)
	(footprint ""
		(layer "F.Cu")
		(at 275.871432 -387.352032 -90)
		(property "Reference" "PC6604"
			(at 0 0 270)
			(layer "F.SilkS")
			(hide yes)
			(effects
				(font
					(size 1.27 1.27)
				)
			)
		)
		(property "Value" ""
			(at 0 0 270)
			(layer "F.Fab")
			(effects
				(font
					(size 1.27 1.27)
				)
			)
		)
		(duplicate_pad_numbers_are_jumpers no)
		(fp_line
			(start -0.7874 0.4064)
			(end -0.7874 -0.4064)
			(stroke
				(width 0.1524)
				(type default)
			)
			(layer "F.SilkS")
		)
		(fp_line
			(start 0.7874 0.4064)
			(end -0.7874 0.4064)
			(stroke
				(width 0.1524)
				(type default)
			)
			(layer "F.SilkS")
		)
		(fp_line
			(start -0.7874 -0.4064)
			(end 0.7874 -0.4064)
			(stroke
				(width 0.1524)
				(type default)
			)
			(layer "F.SilkS")
		)
		(fp_line
			(start 0.7874 -0.4064)
			(end 0.7874 0.4064)
			(stroke
				(width 0.1524)
				(type default)
			)
			(layer "F.SilkS")
		)
		(fp_line
			(start -0.67945 0.3048)
			(end -0.67945 -0.305054)
			(stroke
				(width 0.1)
				(type default)
			)
			(layer "F.Fab")
		)
		(fp_line
			(start -0.12065 0.3048)
			(end -0.67945 0.3048)
			(stroke
				(width 0.1)
				(type default)
			)
			(layer "F.Fab")
		)
		(fp_line
			(start 0.120396 0.3048)
			(end 0.120396 0.2794)
			(stroke
				(width 0.1)
				(type default)
			)
			(layer "F.Fab")
		)
		(fp_line
			(start 0.67945 0.3048)
			(end 0.120396 0.3048)
			(stroke
				(width 0.1)
				(type default)
			)
			(layer "F.Fab")
		)
		(fp_line
			(start -0.12065 0.2794)
			(end -0.12065 0.3048)
			(stroke
				(width 0.1)
				(type default)
			)
			(layer "F.Fab")
		)
		(fp_line
			(start 0.120396 0.2794)
			(end -0.12065 0.2794)
			(stroke
				(width 0.1)
				(type default)
			)
			(layer "F.Fab")
		)
		(fp_line
			(start -0.12065 -0.2794)
			(end 0.12065 -0.2794)
			(stroke
				(width 0.1)
				(type default)
			)
			(layer "F.Fab")
		)
		(fp_line
			(start 0.12065 -0.2794)
			(end 0.12065 -0.3048)
			(stroke
				(width 0.1)
				(type default)
			)
			(layer "F.Fab")
		)
		(fp_line
			(start 0.12065 -0.3048)
			(end 0.67945 -0.3048)
			(stroke
				(width 0.1)
				(type default)
			)
			(layer "F.Fab")
		)
		(fp_line
			(start 0.67945 -0.3048)
			(end 0.67945 0.3048)
			(stroke
				(width 0.1)
				(type default)
			)
			(layer "F.Fab")
		)
		(fp_line
			(start -0.67945 -0.305054)
			(end -0.12065 -0.305054)
			(stroke
				(width 0.1)
				(type default)
			)
			(layer "F.Fab")
		)
		(fp_line
			(start -0.12065 -0.305054)
			(end -0.12065 -0.2794)
			(stroke
				(width 0.1)
				(type default)
			)
			(layer "F.Fab")
		)
		(pad "1" smd circle
			(at -0.40005 0 270)
			(size 0 0)
			(layers "F.Cu" "F.Mask" "F.Paste")
			(net "P3V3_AUX")
		)
		(pad "2" smd circle
			(at 0.40005 0 270)
			(size 0 0)
			(layers "F.Cu" "F.Mask" "F.Paste")
			(net "GND")
		)
	)
	(footprint ""
		(layer "F.Cu")
		(at 239.813338 -134.042404)
		(property "Reference" "R4445"
			(at 0 0 0)
			(layer "F.SilkS")
			(hide yes)
			(effects
				(font
					(size 1.27 1.27)
				)
			)
		)
		(property "Value" ""
			(at 0 0 0)
			(layer "F.Fab")
			(effects
				(font
					(size 1.27 1.27)
				)
			)
		)
		(duplicate_pad_numbers_are_jumpers no)
		(fp_line
			(start -0.7874 -0.4064)
			(end 0.7874 -0.4064)
			(stroke
				(width 0.1524)
				(type default)
			)
			(layer "F.SilkS")
		)
		(fp_line
			(start -0.7874 0.4064)
			(end -0.7874 -0.4064)
			(stroke
				(width 0.1524)
				(type default)
			)
			(layer "F.SilkS")
		)
		(fp_line
			(start 0.7874 -0.4064)
			(end 0.7874 0.4064)
			(stroke
				(width 0.1524)
				(type default)
			)
			(layer "F.SilkS")
		)
		(fp_line
			(start 0.7874 0.4064)
			(end -0.7874 0.4064)
			(stroke
				(width 0.1524)
				(type default)
			)
			(layer "F.SilkS")
		)
		(fp_line
			(start -0.67945 -0.305054)
			(end -0.12065 -0.305054)
			(stroke
				(width 0.1)
				(type default)
			)
			(layer "F.Fab")
		)
		(fp_line
			(start -0.67945 0.3048)
			(end -0.67945 -0.305054)
			(stroke
				(width 0.1)
				(type default)
			)
			(layer "F.Fab")
		)
		(fp_line
			(start -0.12065 -0.305054)
			(end -0.12065 -0.2794)
			(stroke
				(width 0.1)
				(type default)
			)
			(layer "F.Fab")
		)
		(fp_line
			(start -0.12065 -0.2794)
			(end 0.12065 -0.2794)
			(stroke
				(width 0.1)
				(type default)
			)
			(layer "F.Fab")
		)
		(fp_line
			(start -0.12065 0.2794)
			(end -0.12065 0.3048)
			(stroke
				(width 0.1)
				(type default)
			)
			(layer "F.Fab")
		)
		(fp_line
			(start -0.12065 0.3048)
			(end -0.67945 0.3048)
			(stroke
				(width 0.1)
				(type default)
			)
			(layer "F.Fab")
		)
		(fp_line
			(start 0.120396 0.2794)
			(end -0.12065 0.2794)
			(stroke
				(width 0.1)
				(type default)
			)
			(layer "F.Fab")
		)
		(fp_line
			(start 0.120396 0.3048)
			(end 0.120396 0.2794)
			(stroke
				(width 0.1)
				(type default)
			)
			(layer "F.Fab")
		)
		(fp_line
			(start 0.12065 -0.3048)
			(end 0.67945 -0.3048)
			(stroke
				(width 0.1)
				(type default)
			)
			(layer "F.Fab")
		)
		(fp_line
			(start 0.12065 -0.2794)
			(end 0.12065 -0.3048)
			(stroke
				(width 0.1)
				(type default)
			)
			(layer "F.Fab")
		)
		(fp_line
			(start 0.67945 -0.3048)
			(end 0.67945 0.3048)
			(stroke
				(width 0.1)
				(type default)
			)
			(layer "F.Fab")
		)
		(fp_line
			(start 0.67945 0.3048)
			(end 0.120396 0.3048)
			(stroke
				(width 0.1)
				(type default)
			)
			(layer "F.Fab")
		)
		(pad "1" smd circle
			(at -0.40005 0)
			(size 0 0)
			(layers "F.Cu" "F.Mask" "F.Paste")
			(net "HP_NIC4_EN")
		)
		(pad "2" smd circle
			(at 0.40005 0)
			(size 0 0)
			(layers "F.Cu" "F.Mask" "F.Paste")
			(net "P12V_NIC4_EN_R")
		)
	)
	(footprint ""
		(layer "F.Cu")
		(at 249.051572 -124.120656 -90)
		(property "Reference" "PC454"
			(at 0 0 270)
			(layer "F.SilkS")
			(hide yes)
			(effects
				(font
					(size 1.27 1.27)
				)
			)
		)
		(property "Value" ""
			(at 0 0 270)
			(layer "F.Fab")
			(effects
				(font
					(size 1.27 1.27)
				)
			)
		)
		(duplicate_pad_numbers_are_jumpers no)
		(fp_line
			(start -0.7874 0.4064)
			(end -0.7874 -0.4064)
			(stroke
				(width 0.1524)
				(type default)
			)
			(layer "F.SilkS")
		)
		(fp_line
			(start 0.7874 0.4064)
			(end -0.7874 0.4064)
			(stroke
				(width 0.1524)
				(type default)
			)
			(layer "F.SilkS")
		)
		(fp_line
			(start -0.7874 -0.4064)
			(end 0.7874 -0.4064)
			(stroke
				(width 0.1524)
				(type default)
			)
			(layer "F.SilkS")
		)
		(fp_line
			(start 0.7874 -0.4064)
			(end 0.7874 0.4064)
			(stroke
				(width 0.1524)
				(type default)
			)
			(layer "F.SilkS")
		)
		(fp_line
			(start -0.67945 0.3048)
			(end -0.67945 -0.305054)
			(stroke
				(width 0.1)
				(type default)
			)
			(layer "F.Fab")
		)
		(fp_line
			(start -0.12065 0.3048)
			(end -0.67945 0.3048)
			(stroke
				(width 0.1)
				(type default)
			)
			(layer "F.Fab")
		)
		(fp_line
			(start 0.120396 0.3048)
			(end 0.120396 0.2794)
			(stroke
				(width 0.1)
				(type default)
			)
			(layer "F.Fab")
		)
		(fp_line
			(start 0.67945 0.3048)
			(end 0.120396 0.3048)
			(stroke
				(width 0.1)
				(type default)
			)
			(layer "F.Fab")
		)
		(fp_line
			(start -0.12065 0.2794)
			(end -0.12065 0.3048)
			(stroke
				(width 0.1)
				(type default)
			)
			(layer "F.Fab")
		)
		(fp_line
			(start 0.120396 0.2794)
			(end -0.12065 0.2794)
			(stroke
				(width 0.1)
				(type default)
			)
			(layer "F.Fab")
		)
		(fp_line
			(start -0.12065 -0.2794)
			(end 0.12065 -0.2794)
			(stroke
				(width 0.1)
				(type default)
			)
			(layer "F.Fab")
		)
		(fp_line
			(start 0.12065 -0.2794)
			(end 0.12065 -0.3048)
			(stroke
				(width 0.1)
				(type default)
			)
			(layer "F.Fab")
		)
		(fp_line
			(start 0.12065 -0.3048)
			(end 0.67945 -0.3048)
			(stroke
				(width 0.1)
				(type default)
			)
			(layer "F.Fab")
		)
		(fp_line
			(start 0.67945 -0.3048)
			(end 0.67945 0.3048)
			(stroke
				(width 0.1)
				(type default)
			)
			(layer "F.Fab")
		)
		(fp_line
			(start -0.67945 -0.305054)
			(end -0.12065 -0.305054)
			(stroke
				(width 0.1)
				(type default)
			)
			(layer "F.Fab")
		)
		(fp_line
			(start -0.12065 -0.305054)
			(end -0.12065 -0.2794)
			(stroke
				(width 0.1)
				(type default)
			)
			(layer "F.Fab")
		)
		(pad "1" smd circle
			(at -0.40005 0 270)
			(size 0 0)
			(layers "F.Cu" "F.Mask" "F.Paste")
			(net "P3V3_NIC4")
		)
		(pad "2" smd circle
			(at 0.40005 0 270)
			(size 0 0)
			(layers "F.Cu" "F.Mask" "F.Paste")
			(net "GND")
		)
	)
	(footprint ""
		(layer "F.Cu")
		(at 430.961546 -124.991114 180)
		(property "Reference" "C658"
			(at 0 0 180)
			(layer "F.SilkS")
			(hide yes)
			(effects
				(font
					(size 1.27 1.27)
				)
			)
		)
		(property "Value" ""
			(at 0 0 180)
			(layer "F.Fab")
			(effects
				(font
					(size 1.27 1.27)
				)
			)
		)
		(duplicate_pad_numbers_are_jumpers no)
		(fp_line
			(start 0.299974 0.150114)
			(end -0.299974 0.150114)
			(stroke
				(width 0.1)
				(type default)
			)
			(layer "F.Fab")
		)
		(fp_line
			(start 0.299974 -0.150114)
			(end 0.299974 0.150114)
			(stroke
				(width 0.1)
				(type default)
			)
			(layer "F.Fab")
		)
		(fp_line
			(start -0.299974 0.150114)
			(end -0.299974 -0.150114)
			(stroke
				(width 0.1)
				(type default)
			)
			(layer "F.Fab")
		)
		(fp_line
			(start -0.299974 -0.150114)
			(end 0.299974 -0.150114)
			(stroke
				(width 0.1)
				(type default)
			)
			(layer "F.Fab")
		)
		(pad "1" smd rect
			(at -0.2667 0 180)
			(size 0.3048 0.381)
			(layers "F.Cu" "F.Mask" "F.Paste")
			(net "P5E_PEX3_STN0_TX_DP<3>")
		)
		(pad "2" smd rect
			(at 0.2667 0 180)
			(size 0.3048 0.381)
			(layers "F.Cu" "F.Mask" "F.Paste")
			(net "P5E_PEX3_STN0_TX_C_DP<3>")
		)
	)
	(footprint ""
		(layer "F.Cu")
		(at 19.24685 -37.47516)
		(property "Reference" "R5875"
			(at 0 0 0)
			(layer "F.SilkS")
			(hide yes)
			(effects
				(font
					(size 1.27 1.27)
				)
			)
		)
		(property "Value" ""
			(at 0 0 0)
			(layer "F.Fab")
			(effects
				(font
					(size 1.27 1.27)
				)
			)
		)
		(duplicate_pad_numbers_are_jumpers no)
		(fp_line
			(start -0.7874 -0.4064)
			(end 0.7874 -0.4064)
			(stroke
				(width 0.1524)
				(type default)
			)
			(layer "F.SilkS")
		)
		(fp_line
			(start -0.7874 0.4064)
			(end -0.7874 -0.4064)
			(stroke
				(width 0.1524)
				(type default)
			)
			(layer "F.SilkS")
		)
		(fp_line
			(start 0.7874 -0.4064)
			(end 0.7874 0.4064)
			(stroke
				(width 0.1524)
				(type default)
			)
			(layer "F.SilkS")
		)
		(fp_line
			(start 0.7874 0.4064)
			(end -0.7874 0.4064)
			(stroke
				(width 0.1524)
				(type default)
			)
			(layer "F.SilkS")
		)
		(fp_line
			(start -0.67945 -0.305054)
			(end -0.12065 -0.305054)
			(stroke
				(width 0.1)
				(type default)
			)
			(layer "F.Fab")
		)
		(fp_line
			(start -0.67945 0.3048)
			(end -0.67945 -0.305054)
			(stroke
				(width 0.1)
				(type default)
			)
			(layer "F.Fab")
		)
		(fp_line
			(start -0.12065 -0.305054)
			(end -0.12065 -0.2794)
			(stroke
				(width 0.1)
				(type default)
			)
			(layer "F.Fab")
		)
		(fp_line
			(start -0.12065 -0.2794)
			(end 0.12065 -0.2794)
			(stroke
				(width 0.1)
				(type default)
			)
			(layer "F.Fab")
		)
		(fp_line
			(start -0.12065 0.2794)
			(end -0.12065 0.3048)
			(stroke
				(width 0.1)
				(type default)
			)
			(layer "F.Fab")
		)
		(fp_line
			(start -0.12065 0.3048)
			(end -0.67945 0.3048)
			(stroke
				(width 0.1)
				(type default)
			)
			(layer "F.Fab")
		)
		(fp_line
			(start 0.120396 0.2794)
			(end -0.12065 0.2794)
			(stroke
				(width 0.1)
				(type default)
			)
			(layer "F.Fab")
		)
		(fp_line
			(start 0.120396 0.3048)
			(end 0.120396 0.2794)
			(stroke
				(width 0.1)
				(type default)
			)
			(layer "F.Fab")
		)
		(fp_line
			(start 0.12065 -0.3048)
			(end 0.67945 -0.3048)
			(stroke
				(width 0.1)
				(type default)
			)
			(layer "F.Fab")
		)
		(fp_line
			(start 0.12065 -0.2794)
			(end 0.12065 -0.3048)
			(stroke
				(width 0.1)
				(type default)
			)
			(layer "F.Fab")
		)
		(fp_line
			(start 0.67945 -0.3048)
			(end 0.67945 0.3048)
			(stroke
				(width 0.1)
				(type default)
			)
			(layer "F.Fab")
		)
		(fp_line
			(start 0.67945 0.3048)
			(end 0.120396 0.3048)
			(stroke
				(width 0.1)
				(type default)
			)
			(layer "F.Fab")
		)
		(pad "1" smd circle
			(at -0.40005 0)
			(size 0 0)
			(layers "F.Cu" "F.Mask" "F.Paste")
			(net "P3V3_SSD1")
		)
		(pad "2" smd circle
			(at 0.40005 0)
			(size 0 0)
			(layers "F.Cu" "F.Mask" "F.Paste")
			(net "P3V3_SSD1_PG_G1")
		)
	)
	(footprint ""
		(layer "F.Cu")
		(at 69.792342 -32.739584 180)
		(property "Reference" "C83"
			(at 0 0 180)
			(layer "F.SilkS")
			(hide yes)
			(effects
				(font
					(size 1.27 1.27)
				)
			)
		)
		(property "Value" ""
			(at 0 0 180)
			(layer "F.Fab")
			(effects
				(font
					(size 1.27 1.27)
				)
			)
		)
		(duplicate_pad_numbers_are_jumpers no)
		(fp_line
			(start 0.299974 0.150114)
			(end -0.299974 0.150114)
			(stroke
				(width 0.1)
				(type default)
			)
			(layer "F.Fab")
		)
		(fp_line
			(start 0.299974 -0.150114)
			(end 0.299974 0.150114)
			(stroke
				(width 0.1)
				(type default)
			)
			(layer "F.Fab")
		)
		(fp_line
			(start -0.299974 0.150114)
			(end -0.299974 -0.150114)
			(stroke
				(width 0.1)
				(type default)
			)
			(layer "F.Fab")
		)
		(fp_line
			(start -0.299974 -0.150114)
			(end 0.299974 -0.150114)
			(stroke
				(width 0.1)
				(type default)
			)
			(layer "F.Fab")
		)
		(pad "1" smd rect
			(at -0.2667 0 180)
			(size 0.3048 0.381)
			(layers "F.Cu" "F.Mask" "F.Paste")
			(net "P5E_PEX0_STN2_TX_DP<38>")
		)
		(pad "2" smd rect
			(at 0.2667 0 180)
			(size 0.3048 0.381)
			(layers "F.Cu" "F.Mask" "F.Paste")
			(net "P5E_PEX0_STN2_TX_C_DP<38>")
		)
	)
	(footprint ""
		(layer "F.Cu")
		(at 240.121948 -85.551518)
		(property "Reference" "R6286"
			(at 0 0 0)
			(layer "F.SilkS")
			(hide yes)
			(effects
				(font
					(size 1.27 1.27)
				)
			)
		)
		(property "Value" ""
			(at 0 0 0)
			(layer "F.Fab")
			(effects
				(font
					(size 1.27 1.27)
				)
			)
		)
		(duplicate_pad_numbers_are_jumpers no)
		(fp_line
			(start 0.003302 -0.4064)
			(end 0.7874 -0.4064)
			(stroke
				(width 0.1524)
				(type default)
			)
			(layer "F.SilkS")
		)
		(fp_line
			(start 0.7874 -0.4064)
			(end 0.7874 0.4064)
			(stroke
				(width 0.1524)
				(type default)
			)
			(layer "F.SilkS")
		)
		(fp_line
			(start 0.7874 0.4064)
			(end -0.7874 0.4064)
			(stroke
				(width 0.1524)
				(type default)
			)
			(layer "F.SilkS")
		)
		(fp_line
			(start -0.67945 -0.305054)
			(end -0.12065 -0.305054)
			(stroke
				(width 0.1)
				(type default)
			)
			(layer "F.Fab")
		)
		(fp_line
			(start -0.67945 0.3048)
			(end -0.67945 -0.305054)
			(stroke
				(width 0.1)
				(type default)
			)
			(layer "F.Fab")
		)
		(fp_line
			(start -0.12065 -0.305054)
			(end -0.12065 -0.2794)
			(stroke
				(width 0.1)
				(type default)
			)
			(layer "F.Fab")
		)
		(fp_line
			(start -0.12065 -0.2794)
			(end 0.12065 -0.2794)
			(stroke
				(width 0.1)
				(type default)
			)
			(layer "F.Fab")
		)
		(fp_line
			(start -0.12065 0.2794)
			(end -0.12065 0.3048)
			(stroke
				(width 0.1)
				(type default)
			)
			(layer "F.Fab")
		)
		(fp_line
			(start -0.12065 0.3048)
			(end -0.67945 0.3048)
			(stroke
				(width 0.1)
				(type default)
			)
			(layer "F.Fab")
		)
		(fp_line
			(start 0.120396 0.2794)
			(end -0.12065 0.2794)
			(stroke
				(width 0.1)
				(type default)
			)
			(layer "F.Fab")
		)
		(fp_line
			(start 0.120396 0.3048)
			(end 0.120396 0.2794)
			(stroke
				(width 0.1)
				(type default)
			)
			(layer "F.Fab")
		)
		(fp_line
			(start 0.12065 -0.3048)
			(end 0.67945 -0.3048)
			(stroke
				(width 0.1)
				(type default)
			)
			(layer "F.Fab")
		)
		(fp_line
			(start 0.12065 -0.2794)
			(end 0.12065 -0.3048)
			(stroke
				(width 0.1)
				(type default)
			)
			(layer "F.Fab")
		)
		(fp_line
			(start 0.67945 -0.3048)
			(end 0.67945 0.3048)
			(stroke
				(width 0.1)
				(type default)
			)
			(layer "F.Fab")
		)
		(fp_line
			(start 0.67945 0.3048)
			(end 0.120396 0.3048)
			(stroke
				(width 0.1)
				(type default)
			)
			(layer "F.Fab")
		)
		(pad "1" smd rect
			(at -0.40005 0 180)
			(size 0.4572 0.508)
			(layers "F.Cu" "F.Mask" "F.Paste")
			(net "USB2_FT4232_CLI_DP")
		)
		(pad "2" smd rect
			(at 0.40005 0 180)
			(size 0.4572 0.508)
			(layers "F.Cu" "F.Mask" "F.Paste")
			(net "GND")
		)
	)
	(footprint ""
		(layer "F.Cu")
		(at 251.423678 -152.71115 90)
		(property "Reference" "R730"
			(at 0 0 90)
			(layer "F.SilkS")
			(hide yes)
			(effects
				(font
					(size 1.27 1.27)
				)
			)
		)
		(property "Value" ""
			(at 0 0 90)
			(layer "F.Fab")
			(effects
				(font
					(size 1.27 1.27)
				)
			)
		)
		(duplicate_pad_numbers_are_jumpers no)
		(fp_line
			(start 0.7874 -0.4064)
			(end 0.7874 0.4064)
			(stroke
				(width 0.1524)
				(type default)
			)
			(layer "F.SilkS")
		)
		(fp_line
			(start -0.7874 -0.4064)
			(end 0.7874 -0.4064)
			(stroke
				(width 0.1524)
				(type default)
			)
			(layer "F.SilkS")
		)
		(fp_line
			(start 0.7874 0.4064)
			(end -0.7874 0.4064)
			(stroke
				(width 0.1524)
				(type default)
			)
			(layer "F.SilkS")
		)
		(fp_line
			(start -0.7874 0.4064)
			(end -0.7874 -0.4064)
			(stroke
				(width 0.1524)
				(type default)
			)
			(layer "F.SilkS")
		)
		(fp_line
			(start -0.12065 -0.305054)
			(end -0.12065 -0.2794)
			(stroke
				(width 0.1)
				(type default)
			)
			(layer "F.Fab")
		)
		(fp_line
			(start -0.67945 -0.305054)
			(end -0.12065 -0.305054)
			(stroke
				(width 0.1)
				(type default)
			)
			(layer "F.Fab")
		)
		(fp_line
			(start 0.67945 -0.3048)
			(end 0.67945 0.3048)
			(stroke
				(width 0.1)
				(type default)
			)
			(layer "F.Fab")
		)
		(fp_line
			(start 0.12065 -0.3048)
			(end 0.67945 -0.3048)
			(stroke
				(width 0.1)
				(type default)
			)
			(layer "F.Fab")
		)
		(fp_line
			(start 0.12065 -0.2794)
			(end 0.12065 -0.3048)
			(stroke
				(width 0.1)
				(type default)
			)
			(layer "F.Fab")
		)
		(fp_line
			(start -0.12065 -0.2794)
			(end 0.12065 -0.2794)
			(stroke
				(width 0.1)
				(type default)
			)
			(layer "F.Fab")
		)
		(fp_line
			(start 0.120396 0.2794)
			(end -0.12065 0.2794)
			(stroke
				(width 0.1)
				(type default)
			)
			(layer "F.Fab")
		)
		(fp_line
			(start -0.12065 0.2794)
			(end -0.12065 0.3048)
			(stroke
				(width 0.1)
				(type default)
			)
			(layer "F.Fab")
		)
		(fp_line
			(start 0.67945 0.3048)
			(end 0.120396 0.3048)
			(stroke
				(width 0.1)
				(type default)
			)
			(layer "F.Fab")
		)
		(fp_line
			(start 0.120396 0.3048)
			(end 0.120396 0.2794)
			(stroke
				(width 0.1)
				(type default)
			)
			(layer "F.Fab")
		)
		(fp_line
			(start -0.12065 0.3048)
			(end -0.67945 0.3048)
			(stroke
				(width 0.1)
				(type default)
			)
			(layer "F.Fab")
		)
		(fp_line
			(start -0.67945 0.3048)
			(end -0.67945 -0.305054)
			(stroke
				(width 0.1)
				(type default)
			)
			(layer "F.Fab")
		)
		(pad "1" smd circle
			(at -0.40005 0 90)
			(size 0 0)
			(layers "F.Cu" "F.Mask" "F.Paste")
			(net "NIC4_ADC_A0")
		)
		(pad "2" smd circle
			(at 0.40005 0 90)
			(size 0 0)
			(layers "F.Cu" "F.Mask" "F.Paste")
			(net "GND")
		)
	)
	(footprint ""
		(layer "F.Cu")
		(at 258.46786 -56.353456)
		(property "Reference" "C2869"
			(at 0 0 0)
			(layer "F.SilkS")
			(hide yes)
			(effects
				(font
					(size 1.27 1.27)
				)
			)
		)
		(property "Value" ""
			(at 0 0 0)
			(layer "F.Fab")
			(effects
				(font
					(size 1.27 1.27)
				)
			)
		)
		(duplicate_pad_numbers_are_jumpers no)
		(fp_line
			(start -0.7874 -0.4064)
			(end 0.7874 -0.4064)
			(stroke
				(width 0.1524)
				(type default)
			)
			(layer "F.SilkS")
		)
		(fp_line
			(start -0.7874 0.4064)
			(end -0.7874 -0.4064)
			(stroke
				(width 0.1524)
				(type default)
			)
			(layer "F.SilkS")
		)
		(fp_line
			(start 0.7874 -0.4064)
			(end 0.7874 0.4064)
			(stroke
				(width 0.1524)
				(type default)
			)
			(layer "F.SilkS")
		)
		(fp_line
			(start 0.7874 0.4064)
			(end -0.7874 0.4064)
			(stroke
				(width 0.1524)
				(type default)
			)
			(layer "F.SilkS")
		)
		(fp_line
			(start -0.67945 -0.305054)
			(end -0.12065 -0.305054)
			(stroke
				(width 0.1)
				(type default)
			)
			(layer "F.Fab")
		)
		(fp_line
			(start -0.67945 0.3048)
			(end -0.67945 -0.305054)
			(stroke
				(width 0.1)
				(type default)
			)
			(layer "F.Fab")
		)
		(fp_line
			(start -0.12065 -0.305054)
			(end -0.12065 -0.2794)
			(stroke
				(width 0.1)
				(type default)
			)
			(layer "F.Fab")
		)
		(fp_line
			(start -0.12065 -0.2794)
			(end 0.12065 -0.2794)
			(stroke
				(width 0.1)
				(type default)
			)
			(layer "F.Fab")
		)
		(fp_line
			(start -0.12065 0.2794)
			(end -0.12065 0.3048)
			(stroke
				(width 0.1)
				(type default)
			)
			(layer "F.Fab")
		)
		(fp_line
			(start -0.12065 0.3048)
			(end -0.67945 0.3048)
			(stroke
				(width 0.1)
				(type default)
			)
			(layer "F.Fab")
		)
		(fp_line
			(start 0.120396 0.2794)
			(end -0.12065 0.2794)
			(stroke
				(width 0.1)
				(type default)
			)
			(layer "F.Fab")
		)
		(fp_line
			(start 0.120396 0.3048)
			(end 0.120396 0.2794)
			(stroke
				(width 0.1)
				(type default)
			)
			(layer "F.Fab")
		)
		(fp_line
			(start 0.12065 -0.3048)
			(end 0.67945 -0.3048)
			(stroke
				(width 0.1)
				(type default)
			)
			(layer "F.Fab")
		)
		(fp_line
			(start 0.12065 -0.2794)
			(end 0.12065 -0.3048)
			(stroke
				(width 0.1)
				(type default)
			)
			(layer "F.Fab")
		)
		(fp_line
			(start 0.67945 -0.3048)
			(end 0.67945 0.3048)
			(stroke
				(width 0.1)
				(type default)
			)
			(layer "F.Fab")
		)
		(fp_line
			(start 0.67945 0.3048)
			(end 0.120396 0.3048)
			(stroke
				(width 0.1)
				(type default)
			)
			(layer "F.Fab")
		)
		(pad "1" smd circle
			(at -0.40005 0)
			(size 0 0)
			(layers "F.Cu" "F.Mask" "F.Paste")
			(net "SSD8_PWR_EN_R")
		)
		(pad "2" smd circle
			(at 0.40005 0)
			(size 0 0)
			(layers "F.Cu" "F.Mask" "F.Paste")
			(net "GND")
		)
	)
	(footprint ""
		(layer "F.Cu")
		(at 81.357724 -27.006296 -90)
		(property "Reference" "PR6925"
			(at 0 0 270)
			(layer "F.SilkS")
			(hide yes)
			(effects
				(font
					(size 1.27 1.27)
				)
			)
		)
		(property "Value" ""
			(at 0 0 270)
			(layer "F.Fab")
			(effects
				(font
					(size 1.27 1.27)
				)
			)
		)
		(duplicate_pad_numbers_are_jumpers no)
		(fp_line
			(start -0.7874 0.4064)
			(end -0.7874 -0.4064)
			(stroke
				(width 0.1524)
				(type default)
			)
			(layer "F.SilkS")
		)
		(fp_line
			(start 0.7874 0.4064)
			(end -0.7874 0.4064)
			(stroke
				(width 0.1524)
				(type default)
			)
			(layer "F.SilkS")
		)
		(fp_line
			(start -0.7874 -0.4064)
			(end 0.7874 -0.4064)
			(stroke
				(width 0.1524)
				(type default)
			)
			(layer "F.SilkS")
		)
		(fp_line
			(start 0.7874 -0.4064)
			(end 0.7874 0.4064)
			(stroke
				(width 0.1524)
				(type default)
			)
			(layer "F.SilkS")
		)
		(fp_line
			(start -0.67945 0.3048)
			(end -0.67945 -0.305054)
			(stroke
				(width 0.1)
				(type default)
			)
			(layer "F.Fab")
		)
		(fp_line
			(start -0.12065 0.3048)
			(end -0.67945 0.3048)
			(stroke
				(width 0.1)
				(type default)
			)
			(layer "F.Fab")
		)
		(fp_line
			(start 0.120396 0.3048)
			(end 0.120396 0.2794)
			(stroke
				(width 0.1)
				(type default)
			)
			(layer "F.Fab")
		)
		(fp_line
			(start 0.67945 0.3048)
			(end 0.120396 0.3048)
			(stroke
				(width 0.1)
				(type default)
			)
			(layer "F.Fab")
		)
		(fp_line
			(start -0.12065 0.2794)
			(end -0.12065 0.3048)
			(stroke
				(width 0.1)
				(type default)
			)
			(layer "F.Fab")
		)
		(fp_line
			(start 0.120396 0.2794)
			(end -0.12065 0.2794)
			(stroke
				(width 0.1)
				(type default)
			)
			(layer "F.Fab")
		)
		(fp_line
			(start -0.12065 -0.2794)
			(end 0.12065 -0.2794)
			(stroke
				(width 0.1)
				(type default)
			)
			(layer "F.Fab")
		)
		(fp_line
			(start 0.12065 -0.2794)
			(end 0.12065 -0.3048)
			(stroke
				(width 0.1)
				(type default)
			)
			(layer "F.Fab")
		)
		(fp_line
			(start 0.12065 -0.3048)
			(end 0.67945 -0.3048)
			(stroke
				(width 0.1)
				(type default)
			)
			(layer "F.Fab")
		)
		(fp_line
			(start 0.67945 -0.3048)
			(end 0.67945 0.3048)
			(stroke
				(width 0.1)
				(type default)
			)
			(layer "F.Fab")
		)
		(fp_line
			(start -0.67945 -0.305054)
			(end -0.12065 -0.305054)
			(stroke
				(width 0.1)
				(type default)
			)
			(layer "F.Fab")
		)
		(fp_line
			(start -0.12065 -0.305054)
			(end -0.12065 -0.2794)
			(stroke
				(width 0.1)
				(type default)
			)
			(layer "F.Fab")
		)
		(pad "1" smd circle
			(at -0.40005 0 270)
			(size 0 0)
			(layers "F.Cu" "F.Mask" "F.Paste")
			(net "P3V3_SSD3_CO_MODE")
		)
		(pad "2" smd circle
			(at 0.40005 0 270)
			(size 0 0)
			(layers "F.Cu" "F.Mask" "F.Paste")
			(net "GND")
		)
	)
	(footprint ""
		(layer "F.Cu")
		(at 228.79304 -93.057726)
		(property "Reference" "R1021"
			(at 0 0 0)
			(layer "F.SilkS")
			(hide yes)
			(effects
				(font
					(size 1.27 1.27)
				)
			)
		)
		(property "Value" ""
			(at 0 0 0)
			(layer "F.Fab")
			(effects
				(font
					(size 1.27 1.27)
				)
			)
		)
		(duplicate_pad_numbers_are_jumpers no)
		(fp_line
			(start -0.7874 -0.4064)
			(end 0.7874 -0.4064)
			(stroke
				(width 0.1524)
				(type default)
			)
			(layer "F.SilkS")
		)
		(fp_line
			(start -0.7874 0.4064)
			(end -0.7874 -0.4064)
			(stroke
				(width 0.1524)
				(type default)
			)
			(layer "F.SilkS")
		)
		(fp_line
			(start 0.7874 -0.4064)
			(end 0.7874 0.4064)
			(stroke
				(width 0.1524)
				(type default)
			)
			(layer "F.SilkS")
		)
		(fp_line
			(start 0.7874 0.4064)
			(end -0.7874 0.4064)
			(stroke
				(width 0.1524)
				(type default)
			)
			(layer "F.SilkS")
		)
		(fp_line
			(start -0.67945 -0.305054)
			(end -0.12065 -0.305054)
			(stroke
				(width 0.1)
				(type default)
			)
			(layer "F.Fab")
		)
		(fp_line
			(start -0.67945 0.3048)
			(end -0.67945 -0.305054)
			(stroke
				(width 0.1)
				(type default)
			)
			(layer "F.Fab")
		)
		(fp_line
			(start -0.12065 -0.305054)
			(end -0.12065 -0.2794)
			(stroke
				(width 0.1)
				(type default)
			)
			(layer "F.Fab")
		)
		(fp_line
			(start -0.12065 -0.2794)
			(end 0.12065 -0.2794)
			(stroke
				(width 0.1)
				(type default)
			)
			(layer "F.Fab")
		)
		(fp_line
			(start -0.12065 0.2794)
			(end -0.12065 0.3048)
			(stroke
				(width 0.1)
				(type default)
			)
			(layer "F.Fab")
		)
		(fp_line
			(start -0.12065 0.3048)
			(end -0.67945 0.3048)
			(stroke
				(width 0.1)
				(type default)
			)
			(layer "F.Fab")
		)
		(fp_line
			(start 0.120396 0.2794)
			(end -0.12065 0.2794)
			(stroke
				(width 0.1)
				(type default)
			)
			(layer "F.Fab")
		)
		(fp_line
			(start 0.120396 0.3048)
			(end 0.120396 0.2794)
			(stroke
				(width 0.1)
				(type default)
			)
			(layer "F.Fab")
		)
		(fp_line
			(start 0.12065 -0.3048)
			(end 0.67945 -0.3048)
			(stroke
				(width 0.1)
				(type default)
			)
			(layer "F.Fab")
		)
		(fp_line
			(start 0.12065 -0.2794)
			(end 0.12065 -0.3048)
			(stroke
				(width 0.1)
				(type default)
			)
			(layer "F.Fab")
		)
		(fp_line
			(start 0.67945 -0.3048)
			(end 0.67945 0.3048)
			(stroke
				(width 0.1)
				(type default)
			)
			(layer "F.Fab")
		)
		(fp_line
			(start 0.67945 0.3048)
			(end 0.120396 0.3048)
			(stroke
				(width 0.1)
				(type default)
			)
			(layer "F.Fab")
		)
		(pad "1" smd circle
			(at -0.40005 0)
			(size 0 0)
			(layers "F.Cu" "F.Mask" "F.Paste")
			(net "GND")
		)
		(pad "2" smd circle
			(at 0.40005 0)
			(size 0 0)
			(layers "F.Cu" "F.Mask" "F.Paste")
			(net "PEX_USB_HUB_PSELF")
		)
	)
	(footprint ""
		(layer "F.Cu")
		(at 328.126344 -25.432004 -90)
		(property "Reference" "C976"
			(at 0 0 270)
			(layer "F.SilkS")
			(hide yes)
			(effects
				(font
					(size 1.27 1.27)
				)
			)
		)
		(property "Value" ""
			(at 0 0 270)
			(layer "F.Fab")
			(effects
				(font
					(size 1.27 1.27)
				)
			)
		)
		(duplicate_pad_numbers_are_jumpers no)
		(fp_line
			(start -0.7874 0.4064)
			(end -0.7874 -0.4064)
			(stroke
				(width 0.1524)
				(type default)
			)
			(layer "F.SilkS")
		)
		(fp_line
			(start 0.7874 0.4064)
			(end -0.7874 0.4064)
			(stroke
				(width 0.1524)
				(type default)
			)
			(layer "F.SilkS")
		)
		(fp_line
			(start -0.7874 -0.4064)
			(end 0.7874 -0.4064)
			(stroke
				(width 0.1524)
				(type default)
			)
			(layer "F.SilkS")
		)
		(fp_line
			(start 0.7874 -0.4064)
			(end 0.7874 0.4064)
			(stroke
				(width 0.1524)
				(type default)
			)
			(layer "F.SilkS")
		)
		(fp_line
			(start -0.67945 0.3048)
			(end -0.67945 -0.305054)
			(stroke
				(width 0.1)
				(type default)
			)
			(layer "F.Fab")
		)
		(fp_line
			(start -0.12065 0.3048)
			(end -0.67945 0.3048)
			(stroke
				(width 0.1)
				(type default)
			)
			(layer "F.Fab")
		)
		(fp_line
			(start 0.120396 0.3048)
			(end 0.120396 0.2794)
			(stroke
				(width 0.1)
				(type default)
			)
			(layer "F.Fab")
		)
		(fp_line
			(start 0.67945 0.3048)
			(end 0.120396 0.3048)
			(stroke
				(width 0.1)
				(type default)
			)
			(layer "F.Fab")
		)
		(fp_line
			(start -0.12065 0.2794)
			(end -0.12065 0.3048)
			(stroke
				(width 0.1)
				(type default)
			)
			(layer "F.Fab")
		)
		(fp_line
			(start 0.120396 0.2794)
			(end -0.12065 0.2794)
			(stroke
				(width 0.1)
				(type default)
			)
			(layer "F.Fab")
		)
		(fp_line
			(start -0.12065 -0.2794)
			(end 0.12065 -0.2794)
			(stroke
				(width 0.1)
				(type default)
			)
			(layer "F.Fab")
		)
		(fp_line
			(start 0.12065 -0.2794)
			(end 0.12065 -0.3048)
			(stroke
				(width 0.1)
				(type default)
			)
			(layer "F.Fab")
		)
		(fp_line
			(start 0.12065 -0.3048)
			(end 0.67945 -0.3048)
			(stroke
				(width 0.1)
				(type default)
			)
			(layer "F.Fab")
		)
		(fp_line
			(start 0.67945 -0.3048)
			(end 0.67945 0.3048)
			(stroke
				(width 0.1)
				(type default)
			)
			(layer "F.Fab")
		)
		(fp_line
			(start -0.67945 -0.305054)
			(end -0.12065 -0.305054)
			(stroke
				(width 0.1)
				(type default)
			)
			(layer "F.Fab")
		)
		(fp_line
			(start -0.12065 -0.305054)
			(end -0.12065 -0.2794)
			(stroke
				(width 0.1)
				(type default)
			)
			(layer "F.Fab")
		)
		(pad "1" smd circle
			(at -0.40005 0 270)
			(size 0 0)
			(layers "F.Cu" "F.Mask" "F.Paste")
			(net "GND")
		)
		(pad "2" smd circle
			(at 0.40005 0 270)
			(size 0 0)
			(layers "F.Cu" "F.Mask" "F.Paste")
			(net "P3V3_SSD11")
		)
	)
	(footprint ""
		(layer "F.Cu")
		(at 95.271336 -121.291858)
		(property "Reference" "PU48"
			(at -0.863854 2.828798 0)
			(unlocked yes)
			(layer "F.SilkS")
			(effects
				(font
					(size 0.7874 0.5842)
					(thickness 0.1524)
				)
				(justify left)
			)
		)
		(property "Value" ""
			(at 0 0 0)
			(layer "F.Fab")
			(effects
				(font
					(size 1.27 1.27)
				)
			)
		)
		(duplicate_pad_numbers_are_jumpers no)
		(fp_line
			(start -1.943608 -1.549908)
			(end 1.943608 -1.549908)
			(stroke
				(width 0.1524)
				(type default)
			)
			(layer "F.SilkS")
		)
		(fp_line
			(start -1.943608 1.549908)
			(end -1.943608 -1.549908)
			(stroke
				(width 0.1524)
				(type default)
			)
			(layer "F.SilkS")
		)
		(fp_line
			(start 1.943608 -1.549908)
			(end 1.943608 1.549908)
			(stroke
				(width 0.1524)
				(type default)
			)
			(layer "F.SilkS")
		)
		(fp_line
			(start 1.943608 1.549908)
			(end -1.943608 1.549908)
			(stroke
				(width 0.1524)
				(type default)
			)
			(layer "F.SilkS")
		)
		(fp_poly
			(pts
				(xy -2.019808 -1.549908) (xy -1.257808 -1.549908) (xy -1.257808 -1.880108) (xy -2.019808 -1.880108)
			)
			(stroke
				(width 0)
				(type default)
			)
			(fill yes)
			(layer "F.SilkS")
		)
		(fp_line
			(start -1.549908 -1.549908)
			(end 1.549908 -1.549908)
			(stroke
				(width 0.1)
				(type default)
			)
			(layer "F.Fab")
		)
		(fp_line
			(start -1.549908 1.549908)
			(end -1.549908 -1.549908)
			(stroke
				(width 0.1)
				(type default)
			)
			(layer "F.Fab")
		)
		(fp_line
			(start 1.549908 -1.549908)
			(end 1.549908 1.549908)
			(stroke
				(width 0.1)
				(type default)
			)
			(layer "F.Fab")
		)
		(fp_line
			(start 1.549908 1.549908)
			(end -1.549908 1.549908)
			(stroke
				(width 0.1)
				(type default)
			)
			(layer "F.Fab")
		)
		(fp_poly
			(pts
				(xy -2.019808 -1.549908) (xy -1.257808 -1.549908) (xy -1.257808 -1.880108) (xy -2.019808 -1.880108)
			)
			(stroke
				(width 0)
				(type default)
			)
			(fill yes)
			(layer "F.Fab")
		)
		(pad "1" smd rect
			(at -1.500124 -1.249934 270)
			(size 0.2794 0.6096)
			(layers "F.Cu" "F.Mask" "F.Paste")
			(net "P3V3_NIC1")
		)
		(pad "2" smd rect
			(at -1.500124 -0.750062 270)
			(size 0.2794 0.6096)
			(layers "F.Cu" "F.Mask" "F.Paste")
			(net "P3V3_NIC1")
		)
		(pad "3" smd rect
			(at -1.500124 -0.249936 270)
			(size 0.2794 0.6096)
			(layers "F.Cu" "F.Mask" "F.Paste")
			(net "P3V3_NIC1")
		)
		(pad "4" smd rect
			(at -1.500124 0.249936 270)
			(size 0.2794 0.6096)
			(layers "F.Cu" "F.Mask" "F.Paste")
			(net "P3V3_NIC1")
		)
		(pad "5" smd rect
			(at -1.500124 0.750062 270)
			(size 0.2794 0.6096)
			(layers "F.Cu" "F.Mask" "F.Paste")
			(net "P3V3_NIC1")
		)
		(pad "6" smd rect
			(at -1.500124 1.249934 270)
			(size 0.2794 0.6096)
			(layers "F.Cu" "F.Mask" "F.Paste")
			(net "GND")
		)
		(pad "7" smd rect
			(at 1.500124 1.249934 270)
			(size 0.2794 0.6096)
			(layers "F.Cu" "F.Mask" "F.Paste")
			(net "P3V3_NIC1_SS")
		)
		(pad "8" smd rect
			(at 1.500124 0.750062 270)
			(size 0.2794 0.6096)
			(layers "F.Cu" "F.Mask" "F.Paste")
			(net "PWRGD_P3V3_NIC1")
		)
		(pad "9" smd rect
			(at 1.500124 0.249936 270)
			(size 0.2794 0.6096)
			(layers "F.Cu" "F.Mask" "F.Paste")
			(net "P3V3_NIC1_OCP")
		)
		(pad "10" smd rect
			(at 1.500124 -0.249936 270)
			(size 0.2794 0.6096)
			(layers "F.Cu" "F.Mask" "F.Paste")
			(net "P5V_AUX")
		)
		(pad "11" smd rect
			(at 1.500124 -0.750062 270)
			(size 0.2794 0.6096)
			(layers "F.Cu" "F.Mask" "F.Paste")
			(net "HP_NIC1_EN")
		)
		(pad "12" smd rect
			(at 1.500124 -1.249934 270)
			(size 0.2794 0.6096)
			(layers "F.Cu" "F.Mask" "F.Paste")
			(net "P3V3_AUX")
		)
		(pad "13" smd rect
			(at 0 0)
			(size 1.9812 2.7178)
			(layers "F.Cu" "F.Mask" "F.Paste")
			(net "P3V3_AUX")
		)
		(zone
			(layer "F.Cu")
			(hatch none 0.5)
			(connect_pads
				(clearance 0)
			)
			(min_thickness 0.25)
			(keepout
				(tracks not_allowed)
				(vias allowed)
				(pads allowed)
				(copperpour not_allowed)
				(footprints allowed)
			)
			(placement
				(enabled no)
				(sheetname "")
			)
			(fill
				(thermal_gap 0.5)
				(thermal_bridge_width 0.5)
				(island_removal_mode 0)
			)
			(polygon
				(pts
					(xy 96.414336 -122.841258) (xy 96.414336 -122.714258) (xy 96.414336 -119.742458) (xy 96.414336 -119.74195)
					(xy 94.128336 -119.74195) (xy 94.128336 -119.742458) (xy 94.128336 -119.869458) (xy 94.128336 -121.291858)
					(xy 94.229936 -121.291858) (xy 94.229936 -119.869458) (xy 96.312736 -119.869458) (xy 96.312736 -122.714258)
					(xy 94.229936 -122.714258) (xy 94.229936 -121.317258) (xy 94.128336 -121.317258) (xy 94.128336 -122.714258)
					(xy 94.128336 -122.841258) (xy 94.128336 -122.841766) (xy 96.414336 -122.841766)
				)
			)
		)
	)
	(footprint ""
		(layer "F.Cu")
		(at 258.242562 -212.765386 180)
		(property "Reference" "R2520"
			(at 0 0 180)
			(layer "F.SilkS")
			(hide yes)
			(effects
				(font
					(size 1.27 1.27)
				)
			)
		)
		(property "Value" ""
			(at 0 0 180)
			(layer "F.Fab")
			(effects
				(font
					(size 1.27 1.27)
				)
			)
		)
		(duplicate_pad_numbers_are_jumpers no)
		(fp_line
			(start 0.7874 0.4064)
			(end -0.7874 0.4064)
			(stroke
				(width 0.1524)
				(type default)
			)
			(layer "F.SilkS")
		)
		(fp_line
			(start 0.7874 -0.4064)
			(end 0.7874 0.4064)
			(stroke
				(width 0.1524)
				(type default)
			)
			(layer "F.SilkS")
		)
		(fp_line
			(start -0.7874 0.4064)
			(end -0.7874 -0.4064)
			(stroke
				(width 0.1524)
				(type default)
			)
			(layer "F.SilkS")
		)
		(fp_line
			(start -0.7874 -0.4064)
			(end 0.7874 -0.4064)
			(stroke
				(width 0.1524)
				(type default)
			)
			(layer "F.SilkS")
		)
		(fp_line
			(start 0.67945 0.3048)
			(end 0.120396 0.3048)
			(stroke
				(width 0.1)
				(type default)
			)
			(layer "F.Fab")
		)
		(fp_line
			(start 0.67945 -0.3048)
			(end 0.67945 0.3048)
			(stroke
				(width 0.1)
				(type default)
			)
			(layer "F.Fab")
		)
		(fp_line
			(start 0.12065 -0.2794)
			(end 0.12065 -0.3048)
			(stroke
				(width 0.1)
				(type default)
			)
			(layer "F.Fab")
		)
		(fp_line
			(start 0.12065 -0.3048)
			(end 0.67945 -0.3048)
			(stroke
				(width 0.1)
				(type default)
			)
			(layer "F.Fab")
		)
		(fp_line
			(start 0.120396 0.3048)
			(end 0.120396 0.2794)
			(stroke
				(width 0.1)
				(type default)
			)
			(layer "F.Fab")
		)
		(fp_line
			(start 0.120396 0.2794)
			(end -0.12065 0.2794)
			(stroke
				(width 0.1)
				(type default)
			)
			(layer "F.Fab")
		)
		(fp_line
			(start -0.12065 0.3048)
			(end -0.67945 0.3048)
			(stroke
				(width 0.1)
				(type default)
			)
			(layer "F.Fab")
		)
		(fp_line
			(start -0.12065 0.2794)
			(end -0.12065 0.3048)
			(stroke
				(width 0.1)
				(type default)
			)
			(layer "F.Fab")
		)
		(fp_line
			(start -0.12065 -0.2794)
			(end 0.12065 -0.2794)
			(stroke
				(width 0.1)
				(type default)
			)
			(layer "F.Fab")
		)
		(fp_line
			(start -0.12065 -0.305054)
			(end -0.12065 -0.2794)
			(stroke
				(width 0.1)
				(type default)
			)
			(layer "F.Fab")
		)
		(fp_line
			(start -0.67945 0.3048)
			(end -0.67945 -0.305054)
			(stroke
				(width 0.1)
				(type default)
			)
			(layer "F.Fab")
		)
		(fp_line
			(start -0.67945 -0.305054)
			(end -0.12065 -0.305054)
			(stroke
				(width 0.1)
				(type default)
			)
			(layer "F.Fab")
		)
		(pad "1" smd circle
			(at -0.40005 0 180)
			(size 0 0)
			(layers "F.Cu" "F.Mask" "F.Paste")
			(net "P3V3_AUX")
		)
		(pad "2" smd circle
			(at 0.40005 0 180)
			(size 0 0)
			(layers "F.Cu" "F.Mask" "F.Paste")
			(net "PWR_EN_P1V2_AUX_R")
		)
	)
	(footprint ""
		(layer "F.Cu")
		(at 165.269672 -350.098614 90)
		(property "Reference" "C398"
			(at 0 0 90)
			(layer "F.SilkS")
			(hide yes)
			(effects
				(font
					(size 1.27 1.27)
				)
			)
		)
		(property "Value" ""
			(at 0 0 90)
			(layer "F.Fab")
			(effects
				(font
					(size 1.27 1.27)
				)
			)
		)
		(duplicate_pad_numbers_are_jumpers no)
		(fp_line
			(start 0.299974 -0.150114)
			(end 0.299974 0.150114)
			(stroke
				(width 0.1)
				(type default)
			)
			(layer "F.Fab")
		)
		(fp_line
			(start -0.299974 -0.150114)
			(end 0.299974 -0.150114)
			(stroke
				(width 0.1)
				(type default)
			)
			(layer "F.Fab")
		)
		(fp_line
			(start 0.299974 0.150114)
			(end -0.299974 0.150114)
			(stroke
				(width 0.1)
				(type default)
			)
			(layer "F.Fab")
		)
		(fp_line
			(start -0.299974 0.150114)
			(end -0.299974 -0.150114)
			(stroke
				(width 0.1)
				(type default)
			)
			(layer "F.Fab")
		)
		(pad "1" smd rect
			(at -0.2667 0 90)
			(size 0.3048 0.381)
			(layers "F.Cu" "F.Mask" "F.Paste")
			(net "P5E_PEX1_STN7_TX_DP<114>")
		)
		(pad "2" smd rect
			(at 0.2667 0 90)
			(size 0.3048 0.381)
			(layers "F.Cu" "F.Mask" "F.Paste")
			(net "P5E_PEX1_STN7_TX_C_DP<114>")
		)
	)
	(footprint ""
		(layer "F.Cu")
		(at 168.343834 -45.88891)
		(property "Reference" "R564"
			(at 0 0 0)
			(layer "F.SilkS")
			(hide yes)
			(effects
				(font
					(size 1.27 1.27)
				)
			)
		)
		(property "Value" ""
			(at 0 0 0)
			(layer "F.Fab")
			(effects
				(font
					(size 1.27 1.27)
				)
			)
		)
		(duplicate_pad_numbers_are_jumpers no)
		(fp_line
			(start -0.7874 -0.4064)
			(end 0.7874 -0.4064)
			(stroke
				(width 0.1524)
				(type default)
			)
			(layer "F.SilkS")
		)
		(fp_line
			(start -0.7874 0.4064)
			(end -0.7874 -0.4064)
			(stroke
				(width 0.1524)
				(type default)
			)
			(layer "F.SilkS")
		)
		(fp_line
			(start 0.7874 -0.4064)
			(end 0.7874 0.4064)
			(stroke
				(width 0.1524)
				(type default)
			)
			(layer "F.SilkS")
		)
		(fp_line
			(start 0.7874 0.4064)
			(end -0.7874 0.4064)
			(stroke
				(width 0.1524)
				(type default)
			)
			(layer "F.SilkS")
		)
		(fp_line
			(start -0.67945 -0.305054)
			(end -0.12065 -0.305054)
			(stroke
				(width 0.1)
				(type default)
			)
			(layer "F.Fab")
		)
		(fp_line
			(start -0.67945 0.3048)
			(end -0.67945 -0.305054)
			(stroke
				(width 0.1)
				(type default)
			)
			(layer "F.Fab")
		)
		(fp_line
			(start -0.12065 -0.305054)
			(end -0.12065 -0.2794)
			(stroke
				(width 0.1)
				(type default)
			)
			(layer "F.Fab")
		)
		(fp_line
			(start -0.12065 -0.2794)
			(end 0.12065 -0.2794)
			(stroke
				(width 0.1)
				(type default)
			)
			(layer "F.Fab")
		)
		(fp_line
			(start -0.12065 0.2794)
			(end -0.12065 0.3048)
			(stroke
				(width 0.1)
				(type default)
			)
			(layer "F.Fab")
		)
		(fp_line
			(start -0.12065 0.3048)
			(end -0.67945 0.3048)
			(stroke
				(width 0.1)
				(type default)
			)
			(layer "F.Fab")
		)
		(fp_line
			(start 0.120396 0.2794)
			(end -0.12065 0.2794)
			(stroke
				(width 0.1)
				(type default)
			)
			(layer "F.Fab")
		)
		(fp_line
			(start 0.120396 0.3048)
			(end 0.120396 0.2794)
			(stroke
				(width 0.1)
				(type default)
			)
			(layer "F.Fab")
		)
		(fp_line
			(start 0.12065 -0.3048)
			(end 0.67945 -0.3048)
			(stroke
				(width 0.1)
				(type default)
			)
			(layer "F.Fab")
		)
		(fp_line
			(start 0.12065 -0.2794)
			(end 0.12065 -0.3048)
			(stroke
				(width 0.1)
				(type default)
			)
			(layer "F.Fab")
		)
		(fp_line
			(start 0.67945 -0.3048)
			(end 0.67945 0.3048)
			(stroke
				(width 0.1)
				(type default)
			)
			(layer "F.Fab")
		)
		(fp_line
			(start 0.67945 0.3048)
			(end 0.120396 0.3048)
			(stroke
				(width 0.1)
				(type default)
			)
			(layer "F.Fab")
		)
		(pad "1" smd circle
			(at -0.40005 0)
			(size 0 0)
			(layers "F.Cu" "F.Mask" "F.Paste")
			(net "SSD5_ADC_A0")
		)
		(pad "2" smd circle
			(at 0.40005 0)
			(size 0 0)
			(layers "F.Cu" "F.Mask" "F.Paste")
			(net "GND")
		)
	)
	(footprint ""
		(layer "F.Cu")
		(at 144.554956 -22.961346 90)
		(property "Reference" "R1659"
			(at 0 0 90)
			(layer "F.SilkS")
			(hide yes)
			(effects
				(font
					(size 1.27 1.27)
				)
			)
		)
		(property "Value" ""
			(at 0 0 90)
			(layer "F.Fab")
			(effects
				(font
					(size 1.27 1.27)
				)
			)
		)
		(duplicate_pad_numbers_are_jumpers no)
		(fp_line
			(start 0.7874 -0.4064)
			(end 0.7874 0.4064)
			(stroke
				(width 0.1524)
				(type default)
			)
			(layer "F.SilkS")
		)
		(fp_line
			(start -0.7874 -0.4064)
			(end 0.7874 -0.4064)
			(stroke
				(width 0.1524)
				(type default)
			)
			(layer "F.SilkS")
		)
		(fp_line
			(start 0.7874 0.4064)
			(end -0.7874 0.4064)
			(stroke
				(width 0.1524)
				(type default)
			)
			(layer "F.SilkS")
		)
		(fp_line
			(start -0.7874 0.4064)
			(end -0.7874 -0.4064)
			(stroke
				(width 0.1524)
				(type default)
			)
			(layer "F.SilkS")
		)
		(fp_line
			(start -0.12065 -0.305054)
			(end -0.12065 -0.2794)
			(stroke
				(width 0.1)
				(type default)
			)
			(layer "F.Fab")
		)
		(fp_line
			(start -0.67945 -0.305054)
			(end -0.12065 -0.305054)
			(stroke
				(width 0.1)
				(type default)
			)
			(layer "F.Fab")
		)
		(fp_line
			(start 0.67945 -0.3048)
			(end 0.67945 0.3048)
			(stroke
				(width 0.1)
				(type default)
			)
			(layer "F.Fab")
		)
		(fp_line
			(start 0.12065 -0.3048)
			(end 0.67945 -0.3048)
			(stroke
				(width 0.1)
				(type default)
			)
			(layer "F.Fab")
		)
		(fp_line
			(start 0.12065 -0.2794)
			(end 0.12065 -0.3048)
			(stroke
				(width 0.1)
				(type default)
			)
			(layer "F.Fab")
		)
		(fp_line
			(start -0.12065 -0.2794)
			(end 0.12065 -0.2794)
			(stroke
				(width 0.1)
				(type default)
			)
			(layer "F.Fab")
		)
		(fp_line
			(start 0.120396 0.2794)
			(end -0.12065 0.2794)
			(stroke
				(width 0.1)
				(type default)
			)
			(layer "F.Fab")
		)
		(fp_line
			(start -0.12065 0.2794)
			(end -0.12065 0.3048)
			(stroke
				(width 0.1)
				(type default)
			)
			(layer "F.Fab")
		)
		(fp_line
			(start 0.67945 0.3048)
			(end 0.120396 0.3048)
			(stroke
				(width 0.1)
				(type default)
			)
			(layer "F.Fab")
		)
		(fp_line
			(start 0.120396 0.3048)
			(end 0.120396 0.2794)
			(stroke
				(width 0.1)
				(type default)
			)
			(layer "F.Fab")
		)
		(fp_line
			(start -0.12065 0.3048)
			(end -0.67945 0.3048)
			(stroke
				(width 0.1)
				(type default)
			)
			(layer "F.Fab")
		)
		(fp_line
			(start -0.67945 0.3048)
			(end -0.67945 -0.305054)
			(stroke
				(width 0.1)
				(type default)
			)
			(layer "F.Fab")
		)
		(pad "1" smd circle
			(at -0.40005 0 90)
			(size 0 0)
			(layers "F.Cu" "F.Mask" "F.Paste")
			(net "SMB_SSD4_ISO_EN")
		)
		(pad "2" smd circle
			(at 0.40005 0 90)
			(size 0 0)
			(layers "F.Cu" "F.Mask" "F.Paste")
			(net "P3V3_AUX")
		)
	)
	(footprint ""
		(layer "F.Cu")
		(at 171.929044 -116.5352 180)
		(property "Reference" "R142"
			(at 0 0 180)
			(layer "F.SilkS")
			(hide yes)
			(effects
				(font
					(size 1.27 1.27)
				)
			)
		)
		(property "Value" ""
			(at 0 0 180)
			(layer "F.Fab")
			(effects
				(font
					(size 1.27 1.27)
				)
			)
		)
		(duplicate_pad_numbers_are_jumpers no)
		(fp_line
			(start 0.7874 0.4064)
			(end -0.7874 0.4064)
			(stroke
				(width 0.1524)
				(type default)
			)
			(layer "F.SilkS")
		)
		(fp_line
			(start 0.7874 -0.4064)
			(end 0.7874 0.4064)
			(stroke
				(width 0.1524)
				(type default)
			)
			(layer "F.SilkS")
		)
		(fp_line
			(start -0.7874 0.4064)
			(end -0.7874 -0.4064)
			(stroke
				(width 0.1524)
				(type default)
			)
			(layer "F.SilkS")
		)
		(fp_line
			(start -0.7874 -0.4064)
			(end 0.7874 -0.4064)
			(stroke
				(width 0.1524)
				(type default)
			)
			(layer "F.SilkS")
		)
		(fp_line
			(start 0.67945 0.3048)
			(end 0.120396 0.3048)
			(stroke
				(width 0.1)
				(type default)
			)
			(layer "F.Fab")
		)
		(fp_line
			(start 0.67945 -0.3048)
			(end 0.67945 0.3048)
			(stroke
				(width 0.1)
				(type default)
			)
			(layer "F.Fab")
		)
		(fp_line
			(start 0.12065 -0.2794)
			(end 0.12065 -0.3048)
			(stroke
				(width 0.1)
				(type default)
			)
			(layer "F.Fab")
		)
		(fp_line
			(start 0.12065 -0.3048)
			(end 0.67945 -0.3048)
			(stroke
				(width 0.1)
				(type default)
			)
			(layer "F.Fab")
		)
		(fp_line
			(start 0.120396 0.3048)
			(end 0.120396 0.2794)
			(stroke
				(width 0.1)
				(type default)
			)
			(layer "F.Fab")
		)
		(fp_line
			(start 0.120396 0.2794)
			(end -0.12065 0.2794)
			(stroke
				(width 0.1)
				(type default)
			)
			(layer "F.Fab")
		)
		(fp_line
			(start -0.12065 0.3048)
			(end -0.67945 0.3048)
			(stroke
				(width 0.1)
				(type default)
			)
			(layer "F.Fab")
		)
		(fp_line
			(start -0.12065 0.2794)
			(end -0.12065 0.3048)
			(stroke
				(width 0.1)
				(type default)
			)
			(layer "F.Fab")
		)
		(fp_line
			(start -0.12065 -0.2794)
			(end 0.12065 -0.2794)
			(stroke
				(width 0.1)
				(type default)
			)
			(layer "F.Fab")
		)
		(fp_line
			(start -0.12065 -0.305054)
			(end -0.12065 -0.2794)
			(stroke
				(width 0.1)
				(type default)
			)
			(layer "F.Fab")
		)
		(fp_line
			(start -0.67945 0.3048)
			(end -0.67945 -0.305054)
			(stroke
				(width 0.1)
				(type default)
			)
			(layer "F.Fab")
		)
		(fp_line
			(start -0.67945 -0.305054)
			(end -0.12065 -0.305054)
			(stroke
				(width 0.1)
				(type default)
			)
			(layer "F.Fab")
		)
		(pad "1" smd circle
			(at -0.40005 0 180)
			(size 0 0)
			(layers "F.Cu" "F.Mask" "F.Paste")
			(net "PRSNT_NIC2_N")
		)
		(pad "2" smd circle
			(at 0.40005 0 180)
			(size 0 0)
			(layers "F.Cu" "F.Mask" "F.Paste")
			(net "PRSNTB1_NIC2_N")
		)
	)
	(footprint ""
		(layer "F.Cu")
		(at 98.048318 -391.0838)
		(property "Reference" "R5448"
			(at 0 0 0)
			(layer "F.SilkS")
			(hide yes)
			(effects
				(font
					(size 1.27 1.27)
				)
			)
		)
		(property "Value" ""
			(at 0 0 0)
			(layer "F.Fab")
			(effects
				(font
					(size 1.27 1.27)
				)
			)
		)
		(duplicate_pad_numbers_are_jumpers no)
		(fp_line
			(start -0.7874 -0.4064)
			(end 0.7874 -0.4064)
			(stroke
				(width 0.1524)
				(type default)
			)
			(layer "F.SilkS")
		)
		(fp_line
			(start -0.7874 0.4064)
			(end -0.7874 -0.4064)
			(stroke
				(width 0.1524)
				(type default)
			)
			(layer "F.SilkS")
		)
		(fp_line
			(start 0.7874 -0.4064)
			(end 0.7874 0.4064)
			(stroke
				(width 0.1524)
				(type default)
			)
			(layer "F.SilkS")
		)
		(fp_line
			(start 0.7874 0.4064)
			(end -0.7874 0.4064)
			(stroke
				(width 0.1524)
				(type default)
			)
			(layer "F.SilkS")
		)
		(fp_line
			(start -0.67945 -0.305054)
			(end -0.12065 -0.305054)
			(stroke
				(width 0.1)
				(type default)
			)
			(layer "F.Fab")
		)
		(fp_line
			(start -0.67945 0.3048)
			(end -0.67945 -0.305054)
			(stroke
				(width 0.1)
				(type default)
			)
			(layer "F.Fab")
		)
		(fp_line
			(start -0.12065 -0.305054)
			(end -0.12065 -0.2794)
			(stroke
				(width 0.1)
				(type default)
			)
			(layer "F.Fab")
		)
		(fp_line
			(start -0.12065 -0.2794)
			(end 0.12065 -0.2794)
			(stroke
				(width 0.1)
				(type default)
			)
			(layer "F.Fab")
		)
		(fp_line
			(start -0.12065 0.2794)
			(end -0.12065 0.3048)
			(stroke
				(width 0.1)
				(type default)
			)
			(layer "F.Fab")
		)
		(fp_line
			(start -0.12065 0.3048)
			(end -0.67945 0.3048)
			(stroke
				(width 0.1)
				(type default)
			)
			(layer "F.Fab")
		)
		(fp_line
			(start 0.120396 0.2794)
			(end -0.12065 0.2794)
			(stroke
				(width 0.1)
				(type default)
			)
			(layer "F.Fab")
		)
		(fp_line
			(start 0.120396 0.3048)
			(end 0.120396 0.2794)
			(stroke
				(width 0.1)
				(type default)
			)
			(layer "F.Fab")
		)
		(fp_line
			(start 0.12065 -0.3048)
			(end 0.67945 -0.3048)
			(stroke
				(width 0.1)
				(type default)
			)
			(layer "F.Fab")
		)
		(fp_line
			(start 0.12065 -0.2794)
			(end 0.12065 -0.3048)
			(stroke
				(width 0.1)
				(type default)
			)
			(layer "F.Fab")
		)
		(fp_line
			(start 0.67945 -0.3048)
			(end 0.67945 0.3048)
			(stroke
				(width 0.1)
				(type default)
			)
			(layer "F.Fab")
		)
		(fp_line
			(start 0.67945 0.3048)
			(end 0.120396 0.3048)
			(stroke
				(width 0.1)
				(type default)
			)
			(layer "F.Fab")
		)
		(pad "1" smd circle
			(at -0.40005 0)
			(size 0 0)
			(layers "F.Cu" "F.Mask" "F.Paste")
			(net "P3V3_AUX")
		)
		(pad "2" smd circle
			(at 0.40005 0)
			(size 0 0)
			(layers "F.Cu" "F.Mask" "F.Paste")
			(net "BIC_USB_HUB_OVCUR1")
		)
	)
	(footprint ""
		(layer "F.Cu")
		(at 263.898634 -309.570628 45)
		(property "Reference" "R1351"
			(at 0 0 45)
			(layer "F.SilkS")
			(hide yes)
			(effects
				(font
					(size 1.27 1.27)
				)
			)
		)
		(property "Value" ""
			(at 0 0 45)
			(layer "F.Fab")
			(effects
				(font
					(size 1.27 1.27)
				)
			)
		)
		(duplicate_pad_numbers_are_jumpers no)
		(fp_line
			(start -0.787389 -0.406267)
			(end 0.787389 -0.406267)
			(stroke
				(width 0.1524)
				(type default)
			)
			(layer "F.SilkS")
		)
		(fp_line
			(start -0.787389 0.406267)
			(end -0.787389 -0.406267)
			(stroke
				(width 0.1524)
				(type default)
			)
			(layer "F.SilkS")
		)
		(fp_line
			(start 0.787389 -0.406267)
			(end 0.787389 0.406267)
			(stroke
				(width 0.1524)
				(type default)
			)
			(layer "F.SilkS")
		)
		(fp_line
			(start 0.787389 0.406267)
			(end -0.787389 0.406267)
			(stroke
				(width 0.1524)
				(type default)
			)
			(layer "F.SilkS")
		)
		(fp_line
			(start -0.679446 -0.305149)
			(end -0.120695 -0.304969)
			(stroke
				(width 0.1)
				(type default)
			)
			(layer "F.Fab")
		)
		(fp_line
			(start -0.120695 -0.304969)
			(end -0.120695 -0.279466)
			(stroke
				(width 0.1)
				(type default)
			)
			(layer "F.Fab")
		)
		(fp_line
			(start -0.120695 -0.279466)
			(end 0.120695 -0.279466)
			(stroke
				(width 0.1)
				(type default)
			)
			(layer "F.Fab")
		)
		(fp_line
			(start -0.679446 0.30479)
			(end -0.679446 -0.305149)
			(stroke
				(width 0.1)
				(type default)
			)
			(layer "F.Fab")
		)
		(fp_line
			(start 0.120515 -0.30479)
			(end 0.679446 -0.30479)
			(stroke
				(width 0.1)
				(type default)
			)
			(layer "F.Fab")
		)
		(fp_line
			(start 0.120695 -0.279466)
			(end 0.120515 -0.30479)
			(stroke
				(width 0.1)
				(type default)
			)
			(layer "F.Fab")
		)
		(fp_line
			(start -0.120695 0.279466)
			(end -0.120515 0.30479)
			(stroke
				(width 0.1)
				(type default)
			)
			(layer "F.Fab")
		)
		(fp_line
			(start -0.120515 0.30479)
			(end -0.679446 0.30479)
			(stroke
				(width 0.1)
				(type default)
			)
			(layer "F.Fab")
		)
		(fp_line
			(start 0.679446 -0.30479)
			(end 0.679446 0.30479)
			(stroke
				(width 0.1)
				(type default)
			)
			(layer "F.Fab")
		)
		(fp_line
			(start 0.120335 0.279466)
			(end -0.120695 0.279466)
			(stroke
				(width 0.1)
				(type default)
			)
			(layer "F.Fab")
		)
		(fp_line
			(start 0.120515 0.30479)
			(end 0.120335 0.279466)
			(stroke
				(width 0.1)
				(type default)
			)
			(layer "F.Fab")
		)
		(fp_line
			(start 0.679446 0.30479)
			(end 0.120515 0.30479)
			(stroke
				(width 0.1)
				(type default)
			)
			(layer "F.Fab")
		)
		(pad "1" smd circle
			(at -0.40005 0 45)
			(size 0 0)
			(layers "F.Cu" "F.Mask" "F.Paste")
			(net "GND")
		)
		(pad "2" smd circle
			(at 0.40005 0 45)
			(size 0 0)
			(layers "F.Cu" "F.Mask" "F.Paste")
			(net "PEX2_DBG_MODE0")
		)
	)
	(footprint ""
		(layer "F.Cu")
		(at 254.685546 -207.1116 -90)
		(property "Reference" "R5068"
			(at 0 0 270)
			(layer "F.SilkS")
			(hide yes)
			(effects
				(font
					(size 1.27 1.27)
				)
			)
		)
		(property "Value" ""
			(at 0 0 270)
			(layer "F.Fab")
			(effects
				(font
					(size 1.27 1.27)
				)
			)
		)
		(duplicate_pad_numbers_are_jumpers no)
		(fp_line
			(start -0.7874 0.4064)
			(end -0.7874 -0.4064)
			(stroke
				(width 0.1524)
				(type default)
			)
			(layer "F.SilkS")
		)
		(fp_line
			(start 0.7874 0.4064)
			(end -0.7874 0.4064)
			(stroke
				(width 0.1524)
				(type default)
			)
			(layer "F.SilkS")
		)
		(fp_line
			(start -0.7874 -0.4064)
			(end 0.7874 -0.4064)
			(stroke
				(width 0.1524)
				(type default)
			)
			(layer "F.SilkS")
		)
		(fp_line
			(start 0.7874 -0.4064)
			(end 0.7874 0.4064)
			(stroke
				(width 0.1524)
				(type default)
			)
			(layer "F.SilkS")
		)
		(fp_line
			(start -0.67945 0.3048)
			(end -0.67945 -0.305054)
			(stroke
				(width 0.1)
				(type default)
			)
			(layer "F.Fab")
		)
		(fp_line
			(start -0.12065 0.3048)
			(end -0.67945 0.3048)
			(stroke
				(width 0.1)
				(type default)
			)
			(layer "F.Fab")
		)
		(fp_line
			(start 0.120396 0.3048)
			(end 0.120396 0.2794)
			(stroke
				(width 0.1)
				(type default)
			)
			(layer "F.Fab")
		)
		(fp_line
			(start 0.67945 0.3048)
			(end 0.120396 0.3048)
			(stroke
				(width 0.1)
				(type default)
			)
			(layer "F.Fab")
		)
		(fp_line
			(start -0.12065 0.2794)
			(end -0.12065 0.3048)
			(stroke
				(width 0.1)
				(type default)
			)
			(layer "F.Fab")
		)
		(fp_line
			(start 0.120396 0.2794)
			(end -0.12065 0.2794)
			(stroke
				(width 0.1)
				(type default)
			)
			(layer "F.Fab")
		)
		(fp_line
			(start -0.12065 -0.2794)
			(end 0.12065 -0.2794)
			(stroke
				(width 0.1)
				(type default)
			)
			(layer "F.Fab")
		)
		(fp_line
			(start 0.12065 -0.2794)
			(end 0.12065 -0.3048)
			(stroke
				(width 0.1)
				(type default)
			)
			(layer "F.Fab")
		)
		(fp_line
			(start 0.12065 -0.3048)
			(end 0.67945 -0.3048)
			(stroke
				(width 0.1)
				(type default)
			)
			(layer "F.Fab")
		)
		(fp_line
			(start 0.67945 -0.3048)
			(end 0.67945 0.3048)
			(stroke
				(width 0.1)
				(type default)
			)
			(layer "F.Fab")
		)
		(fp_line
			(start -0.67945 -0.305054)
			(end -0.12065 -0.305054)
			(stroke
				(width 0.1)
				(type default)
			)
			(layer "F.Fab")
		)
		(fp_line
			(start -0.12065 -0.305054)
			(end -0.12065 -0.2794)
			(stroke
				(width 0.1)
				(type default)
			)
			(layer "F.Fab")
		)
		(pad "1" smd circle
			(at -0.40005 0 270)
			(size 0 0)
			(layers "F.Cu" "F.Mask" "F.Paste")
			(net "P3V3_AUX")
		)
		(pad "2" smd circle
			(at 0.40005 0 270)
			(size 0 0)
			(layers "F.Cu" "F.Mask" "F.Paste")
			(net "JTAG_BIC_TDO_R")
		)
	)
	(footprint ""
		(layer "F.Cu")
		(at 233.769916 -274.531328 180)
		(property "Reference" "C4335"
			(at 0 0 180)
			(layer "F.SilkS")
			(hide yes)
			(effects
				(font
					(size 1.27 1.27)
				)
			)
		)
		(property "Value" ""
			(at 0 0 180)
			(layer "F.Fab")
			(effects
				(font
					(size 1.27 1.27)
				)
			)
		)
		(duplicate_pad_numbers_are_jumpers no)
		(fp_line
			(start 0.299974 0.150114)
			(end -0.299974 0.150114)
			(stroke
				(width 0.1)
				(type default)
			)
			(layer "F.Fab")
		)
		(fp_line
			(start 0.299974 -0.150114)
			(end 0.299974 0.150114)
			(stroke
				(width 0.1)
				(type default)
			)
			(layer "F.Fab")
		)
		(fp_line
			(start -0.299974 0.150114)
			(end -0.299974 -0.150114)
			(stroke
				(width 0.1)
				(type default)
			)
			(layer "F.Fab")
		)
		(fp_line
			(start -0.299974 -0.150114)
			(end 0.299974 -0.150114)
			(stroke
				(width 0.1)
				(type default)
			)
			(layer "F.Fab")
		)
		(pad "1" smd rect
			(at -0.2667 0 180)
			(size 0.3048 0.381)
			(layers "F.Cu" "F.Mask" "F.Paste")
			(net "P1V25_PEX2")
		)
		(pad "2" smd rect
			(at 0.2667 0 180)
			(size 0.3048 0.381)
			(layers "F.Cu" "F.Mask" "F.Paste")
			(net "GND")
		)
	)
	(footprint ""
		(layer "F.Cu")
		(at 366.955578 -86.070694 180)
		(property "Reference" "R1624"
			(at 0 0 180)
			(layer "F.SilkS")
			(hide yes)
			(effects
				(font
					(size 1.27 1.27)
				)
			)
		)
		(property "Value" ""
			(at 0 0 180)
			(layer "F.Fab")
			(effects
				(font
					(size 1.27 1.27)
				)
			)
		)
		(duplicate_pad_numbers_are_jumpers no)
		(fp_line
			(start 0.7874 0.4064)
			(end -0.7874 0.4064)
			(stroke
				(width 0.1524)
				(type default)
			)
			(layer "F.SilkS")
		)
		(fp_line
			(start 0.7874 -0.4064)
			(end 0.7874 0.4064)
			(stroke
				(width 0.1524)
				(type default)
			)
			(layer "F.SilkS")
		)
		(fp_line
			(start -0.7874 0.4064)
			(end -0.7874 -0.4064)
			(stroke
				(width 0.1524)
				(type default)
			)
			(layer "F.SilkS")
		)
		(fp_line
			(start -0.7874 -0.4064)
			(end 0.7874 -0.4064)
			(stroke
				(width 0.1524)
				(type default)
			)
			(layer "F.SilkS")
		)
		(fp_line
			(start 0.67945 0.3048)
			(end 0.120396 0.3048)
			(stroke
				(width 0.1)
				(type default)
			)
			(layer "F.Fab")
		)
		(fp_line
			(start 0.67945 -0.3048)
			(end 0.67945 0.3048)
			(stroke
				(width 0.1)
				(type default)
			)
			(layer "F.Fab")
		)
		(fp_line
			(start 0.12065 -0.2794)
			(end 0.12065 -0.3048)
			(stroke
				(width 0.1)
				(type default)
			)
			(layer "F.Fab")
		)
		(fp_line
			(start 0.12065 -0.3048)
			(end 0.67945 -0.3048)
			(stroke
				(width 0.1)
				(type default)
			)
			(layer "F.Fab")
		)
		(fp_line
			(start 0.120396 0.3048)
			(end 0.120396 0.2794)
			(stroke
				(width 0.1)
				(type default)
			)
			(layer "F.Fab")
		)
		(fp_line
			(start 0.120396 0.2794)
			(end -0.12065 0.2794)
			(stroke
				(width 0.1)
				(type default)
			)
			(layer "F.Fab")
		)
		(fp_line
			(start -0.12065 0.3048)
			(end -0.67945 0.3048)
			(stroke
				(width 0.1)
				(type default)
			)
			(layer "F.Fab")
		)
		(fp_line
			(start -0.12065 0.2794)
			(end -0.12065 0.3048)
			(stroke
				(width 0.1)
				(type default)
			)
			(layer "F.Fab")
		)
		(fp_line
			(start -0.12065 -0.2794)
			(end 0.12065 -0.2794)
			(stroke
				(width 0.1)
				(type default)
			)
			(layer "F.Fab")
		)
		(fp_line
			(start -0.12065 -0.305054)
			(end -0.12065 -0.2794)
			(stroke
				(width 0.1)
				(type default)
			)
			(layer "F.Fab")
		)
		(fp_line
			(start -0.67945 0.3048)
			(end -0.67945 -0.305054)
			(stroke
				(width 0.1)
				(type default)
			)
			(layer "F.Fab")
		)
		(fp_line
			(start -0.67945 -0.305054)
			(end -0.12065 -0.305054)
			(stroke
				(width 0.1)
				(type default)
			)
			(layer "F.Fab")
		)
		(pad "1" smd circle
			(at -0.40005 0 180)
			(size 0 0)
			(layers "F.Cu" "F.Mask" "F.Paste")
			(net "SMB_BIC_I2C9_MUX1_SSD14_R_SDA")
		)
		(pad "2" smd circle
			(at 0.40005 0 180)
			(size 0 0)
			(layers "F.Cu" "F.Mask" "F.Paste")
			(net "SMB_BIC_I2C9_MUX1_SSD14_SDA")
		)
	)
	(footprint ""
		(layer "F.Cu")
		(at 20.514564 -66.32194 90)
		(property "Reference" "R5835"
			(at 0 0 90)
			(layer "F.SilkS")
			(hide yes)
			(effects
				(font
					(size 1.27 1.27)
				)
			)
		)
		(property "Value" ""
			(at 0 0 90)
			(layer "F.Fab")
			(effects
				(font
					(size 1.27 1.27)
				)
			)
		)
		(duplicate_pad_numbers_are_jumpers no)
		(fp_line
			(start 0.7874 -0.4064)
			(end 0.7874 0.4064)
			(stroke
				(width 0.1524)
				(type default)
			)
			(layer "F.SilkS")
		)
		(fp_line
			(start -0.7874 -0.4064)
			(end 0.7874 -0.4064)
			(stroke
				(width 0.1524)
				(type default)
			)
			(layer "F.SilkS")
		)
		(fp_line
			(start 0.7874 0.4064)
			(end -0.7874 0.4064)
			(stroke
				(width 0.1524)
				(type default)
			)
			(layer "F.SilkS")
		)
		(fp_line
			(start -0.7874 0.4064)
			(end -0.7874 -0.4064)
			(stroke
				(width 0.1524)
				(type default)
			)
			(layer "F.SilkS")
		)
		(fp_line
			(start -0.12065 -0.305054)
			(end -0.12065 -0.2794)
			(stroke
				(width 0.1)
				(type default)
			)
			(layer "F.Fab")
		)
		(fp_line
			(start -0.67945 -0.305054)
			(end -0.12065 -0.305054)
			(stroke
				(width 0.1)
				(type default)
			)
			(layer "F.Fab")
		)
		(fp_line
			(start 0.67945 -0.3048)
			(end 0.67945 0.3048)
			(stroke
				(width 0.1)
				(type default)
			)
			(layer "F.Fab")
		)
		(fp_line
			(start 0.12065 -0.3048)
			(end 0.67945 -0.3048)
			(stroke
				(width 0.1)
				(type default)
			)
			(layer "F.Fab")
		)
		(fp_line
			(start 0.12065 -0.2794)
			(end 0.12065 -0.3048)
			(stroke
				(width 0.1)
				(type default)
			)
			(layer "F.Fab")
		)
		(fp_line
			(start -0.12065 -0.2794)
			(end 0.12065 -0.2794)
			(stroke
				(width 0.1)
				(type default)
			)
			(layer "F.Fab")
		)
		(fp_line
			(start 0.120396 0.2794)
			(end -0.12065 0.2794)
			(stroke
				(width 0.1)
				(type default)
			)
			(layer "F.Fab")
		)
		(fp_line
			(start -0.12065 0.2794)
			(end -0.12065 0.3048)
			(stroke
				(width 0.1)
				(type default)
			)
			(layer "F.Fab")
		)
		(fp_line
			(start 0.67945 0.3048)
			(end 0.120396 0.3048)
			(stroke
				(width 0.1)
				(type default)
			)
			(layer "F.Fab")
		)
		(fp_line
			(start 0.120396 0.3048)
			(end 0.120396 0.2794)
			(stroke
				(width 0.1)
				(type default)
			)
			(layer "F.Fab")
		)
		(fp_line
			(start -0.12065 0.3048)
			(end -0.67945 0.3048)
			(stroke
				(width 0.1)
				(type default)
			)
			(layer "F.Fab")
		)
		(fp_line
			(start -0.67945 0.3048)
			(end -0.67945 -0.305054)
			(stroke
				(width 0.1)
				(type default)
			)
			(layer "F.Fab")
		)
		(pad "1" smd circle
			(at -0.40005 0 90)
			(size 0 0)
			(layers "F.Cu" "F.Mask" "F.Paste")
			(net "SSD0_PWR_EN_R")
		)
		(pad "2" smd circle
			(at 0.40005 0 90)
			(size 0 0)
			(layers "F.Cu" "F.Mask" "F.Paste")
			(net "P12V_SSD0_CO_EN")
		)
	)
	(footprint ""
		(layer "F.Cu")
		(at 125.186948 -350.098614 90)
		(property "Reference" "C369"
			(at 0 0 90)
			(layer "F.SilkS")
			(hide yes)
			(effects
				(font
					(size 1.27 1.27)
				)
			)
		)
		(property "Value" ""
			(at 0 0 90)
			(layer "F.Fab")
			(effects
				(font
					(size 1.27 1.27)
				)
			)
		)
		(duplicate_pad_numbers_are_jumpers no)
		(fp_line
			(start 0.299974 -0.150114)
			(end 0.299974 0.150114)
			(stroke
				(width 0.1)
				(type default)
			)
			(layer "F.Fab")
		)
		(fp_line
			(start -0.299974 -0.150114)
			(end 0.299974 -0.150114)
			(stroke
				(width 0.1)
				(type default)
			)
			(layer "F.Fab")
		)
		(fp_line
			(start 0.299974 0.150114)
			(end -0.299974 0.150114)
			(stroke
				(width 0.1)
				(type default)
			)
			(layer "F.Fab")
		)
		(fp_line
			(start -0.299974 0.150114)
			(end -0.299974 -0.150114)
			(stroke
				(width 0.1)
				(type default)
			)
			(layer "F.Fab")
		)
		(pad "1" smd rect
			(at -0.2667 0 90)
			(size 0.3048 0.381)
			(layers "F.Cu" "F.Mask" "F.Paste")
			(net "P5E_PEX1_STN6_TX_DN<97>")
		)
		(pad "2" smd rect
			(at 0.2667 0 90)
			(size 0.3048 0.381)
			(layers "F.Cu" "F.Mask" "F.Paste")
			(net "P5E_PEX1_STN6_TX_C_DN<97>")
		)
	)
	(footprint ""
		(layer "F.Cu")
		(at 38.608 -159.4104 180)
		(property "Reference" "R2"
			(at 0 0 180)
			(layer "F.SilkS")
			(hide yes)
			(effects
				(font
					(size 1.27 1.27)
				)
			)
		)
		(property "Value" ""
			(at 0 0 180)
			(layer "F.Fab")
			(effects
				(font
					(size 1.27 1.27)
				)
			)
		)
		(duplicate_pad_numbers_are_jumpers no)
		(fp_line
			(start 0.7874 0.4064)
			(end -0.7874 0.4064)
			(stroke
				(width 0.1524)
				(type default)
			)
			(layer "F.SilkS")
		)
		(fp_line
			(start 0.7874 -0.4064)
			(end 0.7874 0.4064)
			(stroke
				(width 0.1524)
				(type default)
			)
			(layer "F.SilkS")
		)
		(fp_line
			(start -0.7874 0.4064)
			(end -0.7874 -0.4064)
			(stroke
				(width 0.1524)
				(type default)
			)
			(layer "F.SilkS")
		)
		(fp_line
			(start -0.7874 -0.4064)
			(end 0.7874 -0.4064)
			(stroke
				(width 0.1524)
				(type default)
			)
			(layer "F.SilkS")
		)
		(fp_line
			(start 0.67945 0.3048)
			(end 0.120396 0.3048)
			(stroke
				(width 0.1)
				(type default)
			)
			(layer "F.Fab")
		)
		(fp_line
			(start 0.67945 -0.3048)
			(end 0.67945 0.3048)
			(stroke
				(width 0.1)
				(type default)
			)
			(layer "F.Fab")
		)
		(fp_line
			(start 0.12065 -0.2794)
			(end 0.12065 -0.3048)
			(stroke
				(width 0.1)
				(type default)
			)
			(layer "F.Fab")
		)
		(fp_line
			(start 0.12065 -0.3048)
			(end 0.67945 -0.3048)
			(stroke
				(width 0.1)
				(type default)
			)
			(layer "F.Fab")
		)
		(fp_line
			(start 0.120396 0.3048)
			(end 0.120396 0.2794)
			(stroke
				(width 0.1)
				(type default)
			)
			(layer "F.Fab")
		)
		(fp_line
			(start 0.120396 0.2794)
			(end -0.12065 0.2794)
			(stroke
				(width 0.1)
				(type default)
			)
			(layer "F.Fab")
		)
		(fp_line
			(start -0.12065 0.3048)
			(end -0.67945 0.3048)
			(stroke
				(width 0.1)
				(type default)
			)
			(layer "F.Fab")
		)
		(fp_line
			(start -0.12065 0.2794)
			(end -0.12065 0.3048)
			(stroke
				(width 0.1)
				(type default)
			)
			(layer "F.Fab")
		)
		(fp_line
			(start -0.12065 -0.2794)
			(end 0.12065 -0.2794)
			(stroke
				(width 0.1)
				(type default)
			)
			(layer "F.Fab")
		)
		(fp_line
			(start -0.12065 -0.305054)
			(end -0.12065 -0.2794)
			(stroke
				(width 0.1)
				(type default)
			)
			(layer "F.Fab")
		)
		(fp_line
			(start -0.67945 0.3048)
			(end -0.67945 -0.305054)
			(stroke
				(width 0.1)
				(type default)
			)
			(layer "F.Fab")
		)
		(fp_line
			(start -0.67945 -0.305054)
			(end -0.12065 -0.305054)
			(stroke
				(width 0.1)
				(type default)
			)
			(layer "F.Fab")
		)
		(pad "1" smd circle
			(at -0.40005 0 180)
			(size 0 0)
			(layers "F.Cu" "F.Mask" "F.Paste")
			(net "NIC0_MAIN_PWR_EN_R")
		)
		(pad "2" smd circle
			(at 0.40005 0 180)
			(size 0 0)
			(layers "F.Cu" "F.Mask" "F.Paste")
			(net "NIC0_MAIN_PWR_EN")
		)
	)
	(footprint ""
		(layer "F.Cu")
		(at 209.825844 -124.260864)
		(property "Reference" "PC485"
			(at 0 0 0)
			(layer "F.SilkS")
			(hide yes)
			(effects
				(font
					(size 1.27 1.27)
				)
			)
		)
		(property "Value" ""
			(at 0 0 0)
			(layer "F.Fab")
			(effects
				(font
					(size 1.27 1.27)
				)
			)
		)
		(duplicate_pad_numbers_are_jumpers no)
		(fp_line
			(start -1.524 -0.762)
			(end 1.524 -0.762)
			(stroke
				(width 0.1524)
				(type default)
			)
			(layer "F.SilkS")
		)
		(fp_line
			(start -1.524 0.762)
			(end -1.524 -0.762)
			(stroke
				(width 0.1524)
				(type default)
			)
			(layer "F.SilkS")
		)
		(fp_line
			(start 1.524 -0.762)
			(end 1.524 0.762)
			(stroke
				(width 0.1524)
				(type default)
			)
			(layer "F.SilkS")
		)
		(fp_line
			(start 1.524 0.762)
			(end -1.524 0.762)
			(stroke
				(width 0.1524)
				(type default)
			)
			(layer "F.SilkS")
		)
		(fp_line
			(start -1.1049 -0.724916)
			(end -1.1049 0.724916)
			(stroke
				(width 0.1)
				(type default)
			)
			(layer "F.Fab")
		)
		(fp_line
			(start -1.1049 0.724916)
			(end 1.1049 0.724916)
			(stroke
				(width 0.1)
				(type default)
			)
			(layer "F.Fab")
		)
		(fp_line
			(start 1.1049 -0.724916)
			(end -1.1049 -0.724916)
			(stroke
				(width 0.1)
				(type default)
			)
			(layer "F.Fab")
		)
		(fp_line
			(start 1.1049 0.724916)
			(end 1.1049 -0.724916)
			(stroke
				(width 0.1)
				(type default)
			)
			(layer "F.Fab")
		)
		(pad "1" smd rect
			(at -0.889 0 180)
			(size 1.016 1.27)
			(layers "F.Cu" "F.Mask" "F.Paste")
			(net "GND")
		)
		(pad "2" smd rect
			(at 0.889 0 180)
			(size 1.016 1.27)
			(layers "F.Cu" "F.Mask" "F.Paste")
			(net "P3V3_AUX")
		)
	)
	(footprint ""
		(layer "F.Cu")
		(at 142.678658 -308.611524 45)
		(property "Reference" "R4361"
			(at 0 0 45)
			(layer "F.SilkS")
			(hide yes)
			(effects
				(font
					(size 1.27 1.27)
				)
			)
		)
		(property "Value" ""
			(at 0 0 45)
			(layer "F.Fab")
			(effects
				(font
					(size 1.27 1.27)
				)
			)
		)
		(duplicate_pad_numbers_are_jumpers no)
		(fp_line
			(start -0.787389 -0.406267)
			(end 0.787389 -0.406267)
			(stroke
				(width 0.1524)
				(type default)
			)
			(layer "F.SilkS")
		)
		(fp_line
			(start -0.787389 0.406267)
			(end -0.787389 -0.406267)
			(stroke
				(width 0.1524)
				(type default)
			)
			(layer "F.SilkS")
		)
		(fp_line
			(start 0.787389 -0.406267)
			(end 0.787389 0.406267)
			(stroke
				(width 0.1524)
				(type default)
			)
			(layer "F.SilkS")
		)
		(fp_line
			(start 0.787389 0.406267)
			(end -0.787389 0.406267)
			(stroke
				(width 0.1524)
				(type default)
			)
			(layer "F.SilkS")
		)
		(fp_line
			(start -0.679446 -0.305149)
			(end -0.120695 -0.304969)
			(stroke
				(width 0.1)
				(type default)
			)
			(layer "F.Fab")
		)
		(fp_line
			(start -0.120695 -0.304969)
			(end -0.120695 -0.279466)
			(stroke
				(width 0.1)
				(type default)
			)
			(layer "F.Fab")
		)
		(fp_line
			(start -0.120695 -0.279466)
			(end 0.120695 -0.279466)
			(stroke
				(width 0.1)
				(type default)
			)
			(layer "F.Fab")
		)
		(fp_line
			(start -0.679446 0.30479)
			(end -0.679446 -0.305149)
			(stroke
				(width 0.1)
				(type default)
			)
			(layer "F.Fab")
		)
		(fp_line
			(start 0.120515 -0.30479)
			(end 0.679446 -0.30479)
			(stroke
				(width 0.1)
				(type default)
			)
			(layer "F.Fab")
		)
		(fp_line
			(start 0.120695 -0.279466)
			(end 0.120515 -0.30479)
			(stroke
				(width 0.1)
				(type default)
			)
			(layer "F.Fab")
		)
		(fp_line
			(start -0.120695 0.279466)
			(end -0.120515 0.30479)
			(stroke
				(width 0.1)
				(type default)
			)
			(layer "F.Fab")
		)
		(fp_line
			(start -0.120515 0.30479)
			(end -0.679446 0.30479)
			(stroke
				(width 0.1)
				(type default)
			)
			(layer "F.Fab")
		)
		(fp_line
			(start 0.679446 -0.30479)
			(end 0.679446 0.30479)
			(stroke
				(width 0.1)
				(type default)
			)
			(layer "F.Fab")
		)
		(fp_line
			(start 0.120335 0.279466)
			(end -0.120695 0.279466)
			(stroke
				(width 0.1)
				(type default)
			)
			(layer "F.Fab")
		)
		(fp_line
			(start 0.120515 0.30479)
			(end 0.120335 0.279466)
			(stroke
				(width 0.1)
				(type default)
			)
			(layer "F.Fab")
		)
		(fp_line
			(start 0.679446 0.30479)
			(end 0.120515 0.30479)
			(stroke
				(width 0.1)
				(type default)
			)
			(layer "F.Fab")
		)
		(pad "1" smd circle
			(at -0.40005 0 45)
			(size 0 0)
			(layers "F.Cu" "F.Mask" "F.Paste")
			(net "P1V8_PEX")
		)
		(pad "2" smd circle
			(at 0.40005 0 45)
			(size 0 0)
			(layers "F.Cu" "F.Mask" "F.Paste")
			(net "IRQ_PEX1_CLKREQ_INT_N")
		)
	)
	(footprint ""
		(layer "F.Cu")
		(at 155.380436 -99.288854)
		(property "Reference" "C274"
			(at 0 0 0)
			(layer "F.SilkS")
			(hide yes)
			(effects
				(font
					(size 1.27 1.27)
				)
			)
		)
		(property "Value" ""
			(at 0 0 0)
			(layer "F.Fab")
			(effects
				(font
					(size 1.27 1.27)
				)
			)
		)
		(duplicate_pad_numbers_are_jumpers no)
		(fp_line
			(start -0.299974 -0.150114)
			(end 0.299974 -0.150114)
			(stroke
				(width 0.1)
				(type default)
			)
			(layer "F.Fab")
		)
		(fp_line
			(start -0.299974 0.150114)
			(end -0.299974 -0.150114)
			(stroke
				(width 0.1)
				(type default)
			)
			(layer "F.Fab")
		)
		(fp_line
			(start 0.299974 -0.150114)
			(end 0.299974 0.150114)
			(stroke
				(width 0.1)
				(type default)
			)
			(layer "F.Fab")
		)
		(fp_line
			(start 0.299974 0.150114)
			(end -0.299974 0.150114)
			(stroke
				(width 0.1)
				(type default)
			)
			(layer "F.Fab")
		)
		(pad "1" smd rect
			(at -0.2667 0)
			(size 0.3048 0.381)
			(layers "F.Cu" "F.Mask" "F.Paste")
			(net "P5E_PEX1_STN1_TX_DP<16>")
		)
		(pad "2" smd rect
			(at 0.2667 0)
			(size 0.3048 0.381)
			(layers "F.Cu" "F.Mask" "F.Paste")
			(net "P5E_PEX1_STN1_TX_C_DP<16>")
		)
	)
	(footprint ""
		(layer "F.Cu")
		(at 385.548124 -102.009702)
		(property "Reference" "C695"
			(at 0 0 0)
			(layer "F.SilkS")
			(hide yes)
			(effects
				(font
					(size 1.27 1.27)
				)
			)
		)
		(property "Value" ""
			(at 0 0 0)
			(layer "F.Fab")
			(effects
				(font
					(size 1.27 1.27)
				)
			)
		)
		(duplicate_pad_numbers_are_jumpers no)
		(fp_line
			(start -0.299974 -0.150114)
			(end 0.299974 -0.150114)
			(stroke
				(width 0.1)
				(type default)
			)
			(layer "F.Fab")
		)
		(fp_line
			(start -0.299974 0.150114)
			(end -0.299974 -0.150114)
			(stroke
				(width 0.1)
				(type default)
			)
			(layer "F.Fab")
		)
		(fp_line
			(start 0.299974 -0.150114)
			(end 0.299974 0.150114)
			(stroke
				(width 0.1)
				(type default)
			)
			(layer "F.Fab")
		)
		(fp_line
			(start 0.299974 0.150114)
			(end -0.299974 0.150114)
			(stroke
				(width 0.1)
				(type default)
			)
			(layer "F.Fab")
		)
		(pad "1" smd rect
			(at -0.2667 0)
			(size 0.3048 0.381)
			(layers "F.Cu" "F.Mask" "F.Paste")
			(net "P5E_PEX3_STN1_TX_DP<17>")
		)
		(pad "2" smd rect
			(at 0.2667 0)
			(size 0.3048 0.381)
			(layers "F.Cu" "F.Mask" "F.Paste")
			(net "P5E_PEX3_STN1_TX_C_DP<17>")
		)
	)
	(footprint ""
		(layer "F.Cu")
		(at 219.014294 -179.11318 180)
		(property "Reference" "R5502"
			(at 0 0 180)
			(layer "F.SilkS")
			(hide yes)
			(effects
				(font
					(size 1.27 1.27)
				)
			)
		)
		(property "Value" ""
			(at 0 0 180)
			(layer "F.Fab")
			(effects
				(font
					(size 1.27 1.27)
				)
			)
		)
		(duplicate_pad_numbers_are_jumpers no)
		(fp_line
			(start 0.7874 0.4064)
			(end -0.7874 0.4064)
			(stroke
				(width 0.1524)
				(type default)
			)
			(layer "F.SilkS")
		)
		(fp_line
			(start 0.7874 -0.4064)
			(end 0.7874 0.4064)
			(stroke
				(width 0.1524)
				(type default)
			)
			(layer "F.SilkS")
		)
		(fp_line
			(start -0.7874 0.4064)
			(end -0.7874 -0.4064)
			(stroke
				(width 0.1524)
				(type default)
			)
			(layer "F.SilkS")
		)
		(fp_line
			(start -0.7874 -0.4064)
			(end 0.7874 -0.4064)
			(stroke
				(width 0.1524)
				(type default)
			)
			(layer "F.SilkS")
		)
		(fp_line
			(start 0.67945 0.3048)
			(end 0.120396 0.3048)
			(stroke
				(width 0.1)
				(type default)
			)
			(layer "F.Fab")
		)
		(fp_line
			(start 0.67945 -0.3048)
			(end 0.67945 0.3048)
			(stroke
				(width 0.1)
				(type default)
			)
			(layer "F.Fab")
		)
		(fp_line
			(start 0.12065 -0.2794)
			(end 0.12065 -0.3048)
			(stroke
				(width 0.1)
				(type default)
			)
			(layer "F.Fab")
		)
		(fp_line
			(start 0.12065 -0.3048)
			(end 0.67945 -0.3048)
			(stroke
				(width 0.1)
				(type default)
			)
			(layer "F.Fab")
		)
		(fp_line
			(start 0.120396 0.3048)
			(end 0.120396 0.2794)
			(stroke
				(width 0.1)
				(type default)
			)
			(layer "F.Fab")
		)
		(fp_line
			(start 0.120396 0.2794)
			(end -0.12065 0.2794)
			(stroke
				(width 0.1)
				(type default)
			)
			(layer "F.Fab")
		)
		(fp_line
			(start -0.12065 0.3048)
			(end -0.67945 0.3048)
			(stroke
				(width 0.1)
				(type default)
			)
			(layer "F.Fab")
		)
		(fp_line
			(start -0.12065 0.2794)
			(end -0.12065 0.3048)
			(stroke
				(width 0.1)
				(type default)
			)
			(layer "F.Fab")
		)
		(fp_line
			(start -0.12065 -0.2794)
			(end 0.12065 -0.2794)
			(stroke
				(width 0.1)
				(type default)
			)
			(layer "F.Fab")
		)
		(fp_line
			(start -0.12065 -0.305054)
			(end -0.12065 -0.2794)
			(stroke
				(width 0.1)
				(type default)
			)
			(layer "F.Fab")
		)
		(fp_line
			(start -0.67945 0.3048)
			(end -0.67945 -0.305054)
			(stroke
				(width 0.1)
				(type default)
			)
			(layer "F.Fab")
		)
		(fp_line
			(start -0.67945 -0.305054)
			(end -0.12065 -0.305054)
			(stroke
				(width 0.1)
				(type default)
			)
			(layer "F.Fab")
		)
		(pad "1" smd circle
			(at -0.40005 0 180)
			(size 0 0)
			(layers "F.Cu" "F.Mask" "F.Paste")
			(net "RST_FW_BIC_PLTRST")
		)
		(pad "2" smd circle
			(at 0.40005 0 180)
			(size 0 0)
			(layers "F.Cu" "F.Mask" "F.Paste")
			(net "RST_FW_BIC_PLTRST_R")
		)
	)
	(footprint ""
		(layer "F.Cu")
		(at 175.0949 -97.718372 180)
		(property "Reference" "R201"
			(at 0 0 180)
			(layer "F.SilkS")
			(hide yes)
			(effects
				(font
					(size 1.27 1.27)
				)
			)
		)
		(property "Value" ""
			(at 0 0 180)
			(layer "F.Fab")
			(effects
				(font
					(size 1.27 1.27)
				)
			)
		)
		(duplicate_pad_numbers_are_jumpers no)
		(fp_line
			(start 0.7874 0.4064)
			(end -0.7874 0.4064)
			(stroke
				(width 0.1524)
				(type default)
			)
			(layer "F.SilkS")
		)
		(fp_line
			(start 0.7874 -0.4064)
			(end 0.7874 0.4064)
			(stroke
				(width 0.1524)
				(type default)
			)
			(layer "F.SilkS")
		)
		(fp_line
			(start -0.7874 0.4064)
			(end -0.7874 -0.4064)
			(stroke
				(width 0.1524)
				(type default)
			)
			(layer "F.SilkS")
		)
		(fp_line
			(start -0.7874 -0.4064)
			(end 0.7874 -0.4064)
			(stroke
				(width 0.1524)
				(type default)
			)
			(layer "F.SilkS")
		)
		(fp_line
			(start 0.67945 0.3048)
			(end 0.120396 0.3048)
			(stroke
				(width 0.1)
				(type default)
			)
			(layer "F.Fab")
		)
		(fp_line
			(start 0.67945 -0.3048)
			(end 0.67945 0.3048)
			(stroke
				(width 0.1)
				(type default)
			)
			(layer "F.Fab")
		)
		(fp_line
			(start 0.12065 -0.2794)
			(end 0.12065 -0.3048)
			(stroke
				(width 0.1)
				(type default)
			)
			(layer "F.Fab")
		)
		(fp_line
			(start 0.12065 -0.3048)
			(end 0.67945 -0.3048)
			(stroke
				(width 0.1)
				(type default)
			)
			(layer "F.Fab")
		)
		(fp_line
			(start 0.120396 0.3048)
			(end 0.120396 0.2794)
			(stroke
				(width 0.1)
				(type default)
			)
			(layer "F.Fab")
		)
		(fp_line
			(start 0.120396 0.2794)
			(end -0.12065 0.2794)
			(stroke
				(width 0.1)
				(type default)
			)
			(layer "F.Fab")
		)
		(fp_line
			(start -0.12065 0.3048)
			(end -0.67945 0.3048)
			(stroke
				(width 0.1)
				(type default)
			)
			(layer "F.Fab")
		)
		(fp_line
			(start -0.12065 0.2794)
			(end -0.12065 0.3048)
			(stroke
				(width 0.1)
				(type default)
			)
			(layer "F.Fab")
		)
		(fp_line
			(start -0.12065 -0.2794)
			(end 0.12065 -0.2794)
			(stroke
				(width 0.1)
				(type default)
			)
			(layer "F.Fab")
		)
		(fp_line
			(start -0.12065 -0.305054)
			(end -0.12065 -0.2794)
			(stroke
				(width 0.1)
				(type default)
			)
			(layer "F.Fab")
		)
		(fp_line
			(start -0.67945 0.3048)
			(end -0.67945 -0.305054)
			(stroke
				(width 0.1)
				(type default)
			)
			(layer "F.Fab")
		)
		(fp_line
			(start -0.67945 -0.305054)
			(end -0.12065 -0.305054)
			(stroke
				(width 0.1)
				(type default)
			)
			(layer "F.Fab")
		)
		(pad "1" smd circle
			(at -0.40005 0 180)
			(size 0 0)
			(layers "F.Cu" "F.Mask" "F.Paste")
			(net "RST_NIC3_PERST3_R_N")
		)
		(pad "2" smd circle
			(at 0.40005 0 180)
			(size 0 0)
			(layers "F.Cu" "F.Mask" "F.Paste")
			(net "RST_HP_NIC3_BUF_N")
		)
	)
	(footprint ""
		(layer "F.Cu")
		(at 418.226494 -25.432004 -90)
		(property "Reference" "C979"
			(at 0 0 270)
			(layer "F.SilkS")
			(hide yes)
			(effects
				(font
					(size 1.27 1.27)
				)
			)
		)
		(property "Value" ""
			(at 0 0 270)
			(layer "F.Fab")
			(effects
				(font
					(size 1.27 1.27)
				)
			)
		)
		(duplicate_pad_numbers_are_jumpers no)
		(fp_line
			(start -0.7874 0.4064)
			(end -0.7874 -0.4064)
			(stroke
				(width 0.1524)
				(type default)
			)
			(layer "F.SilkS")
		)
		(fp_line
			(start 0.7874 0.4064)
			(end -0.7874 0.4064)
			(stroke
				(width 0.1524)
				(type default)
			)
			(layer "F.SilkS")
		)
		(fp_line
			(start -0.7874 -0.4064)
			(end 0.7874 -0.4064)
			(stroke
				(width 0.1524)
				(type default)
			)
			(layer "F.SilkS")
		)
		(fp_line
			(start 0.7874 -0.4064)
			(end 0.7874 0.4064)
			(stroke
				(width 0.1524)
				(type default)
			)
			(layer "F.SilkS")
		)
		(fp_line
			(start -0.67945 0.3048)
			(end -0.67945 -0.305054)
			(stroke
				(width 0.1)
				(type default)
			)
			(layer "F.Fab")
		)
		(fp_line
			(start -0.12065 0.3048)
			(end -0.67945 0.3048)
			(stroke
				(width 0.1)
				(type default)
			)
			(layer "F.Fab")
		)
		(fp_line
			(start 0.120396 0.3048)
			(end 0.120396 0.2794)
			(stroke
				(width 0.1)
				(type default)
			)
			(layer "F.Fab")
		)
		(fp_line
			(start 0.67945 0.3048)
			(end 0.120396 0.3048)
			(stroke
				(width 0.1)
				(type default)
			)
			(layer "F.Fab")
		)
		(fp_line
			(start -0.12065 0.2794)
			(end -0.12065 0.3048)
			(stroke
				(width 0.1)
				(type default)
			)
			(layer "F.Fab")
		)
		(fp_line
			(start 0.120396 0.2794)
			(end -0.12065 0.2794)
			(stroke
				(width 0.1)
				(type default)
			)
			(layer "F.Fab")
		)
		(fp_line
			(start -0.12065 -0.2794)
			(end 0.12065 -0.2794)
			(stroke
				(width 0.1)
				(type default)
			)
			(layer "F.Fab")
		)
		(fp_line
			(start 0.12065 -0.2794)
			(end 0.12065 -0.3048)
			(stroke
				(width 0.1)
				(type default)
			)
			(layer "F.Fab")
		)
		(fp_line
			(start 0.12065 -0.3048)
			(end 0.67945 -0.3048)
			(stroke
				(width 0.1)
				(type default)
			)
			(layer "F.Fab")
		)
		(fp_line
			(start 0.67945 -0.3048)
			(end 0.67945 0.3048)
			(stroke
				(width 0.1)
				(type default)
			)
			(layer "F.Fab")
		)
		(fp_line
			(start -0.67945 -0.305054)
			(end -0.12065 -0.305054)
			(stroke
				(width 0.1)
				(type default)
			)
			(layer "F.Fab")
		)
		(fp_line
			(start -0.12065 -0.305054)
			(end -0.12065 -0.2794)
			(stroke
				(width 0.1)
				(type default)
			)
			(layer "F.Fab")
		)
		(pad "1" smd circle
			(at -0.40005 0 270)
			(size 0 0)
			(layers "F.Cu" "F.Mask" "F.Paste")
			(net "GND")
		)
		(pad "2" smd circle
			(at 0.40005 0 270)
			(size 0 0)
			(layers "F.Cu" "F.Mask" "F.Paste")
			(net "P3V3_SSD14")
		)
	)
	(footprint ""
		(layer "F.Cu")
		(at 284.443678 -46.90491)
		(property "Reference" "R607"
			(at 0 0 0)
			(layer "F.SilkS")
			(hide yes)
			(effects
				(font
					(size 1.27 1.27)
				)
			)
		)
		(property "Value" ""
			(at 0 0 0)
			(layer "F.Fab")
			(effects
				(font
					(size 1.27 1.27)
				)
			)
		)
		(duplicate_pad_numbers_are_jumpers no)
		(fp_line
			(start -0.7874 -0.4064)
			(end 0.7874 -0.4064)
			(stroke
				(width 0.1524)
				(type default)
			)
			(layer "F.SilkS")
		)
		(fp_line
			(start -0.7874 0.4064)
			(end -0.7874 -0.4064)
			(stroke
				(width 0.1524)
				(type default)
			)
			(layer "F.SilkS")
		)
		(fp_line
			(start 0.7874 -0.4064)
			(end 0.7874 0.4064)
			(stroke
				(width 0.1524)
				(type default)
			)
			(layer "F.SilkS")
		)
		(fp_line
			(start 0.7874 0.4064)
			(end -0.7874 0.4064)
			(stroke
				(width 0.1524)
				(type default)
			)
			(layer "F.SilkS")
		)
		(fp_line
			(start -0.67945 -0.305054)
			(end -0.12065 -0.305054)
			(stroke
				(width 0.1)
				(type default)
			)
			(layer "F.Fab")
		)
		(fp_line
			(start -0.67945 0.3048)
			(end -0.67945 -0.305054)
			(stroke
				(width 0.1)
				(type default)
			)
			(layer "F.Fab")
		)
		(fp_line
			(start -0.12065 -0.305054)
			(end -0.12065 -0.2794)
			(stroke
				(width 0.1)
				(type default)
			)
			(layer "F.Fab")
		)
		(fp_line
			(start -0.12065 -0.2794)
			(end 0.12065 -0.2794)
			(stroke
				(width 0.1)
				(type default)
			)
			(layer "F.Fab")
		)
		(fp_line
			(start -0.12065 0.2794)
			(end -0.12065 0.3048)
			(stroke
				(width 0.1)
				(type default)
			)
			(layer "F.Fab")
		)
		(fp_line
			(start -0.12065 0.3048)
			(end -0.67945 0.3048)
			(stroke
				(width 0.1)
				(type default)
			)
			(layer "F.Fab")
		)
		(fp_line
			(start 0.120396 0.2794)
			(end -0.12065 0.2794)
			(stroke
				(width 0.1)
				(type default)
			)
			(layer "F.Fab")
		)
		(fp_line
			(start 0.120396 0.3048)
			(end 0.120396 0.2794)
			(stroke
				(width 0.1)
				(type default)
			)
			(layer "F.Fab")
		)
		(fp_line
			(start 0.12065 -0.3048)
			(end 0.67945 -0.3048)
			(stroke
				(width 0.1)
				(type default)
			)
			(layer "F.Fab")
		)
		(fp_line
			(start 0.12065 -0.2794)
			(end 0.12065 -0.3048)
			(stroke
				(width 0.1)
				(type default)
			)
			(layer "F.Fab")
		)
		(fp_line
			(start 0.67945 -0.3048)
			(end 0.67945 0.3048)
			(stroke
				(width 0.1)
				(type default)
			)
			(layer "F.Fab")
		)
		(fp_line
			(start 0.67945 0.3048)
			(end 0.120396 0.3048)
			(stroke
				(width 0.1)
				(type default)
			)
			(layer "F.Fab")
		)
		(pad "1" smd circle
			(at -0.40005 0)
			(size 0 0)
			(layers "F.Cu" "F.Mask" "F.Paste")
			(net "SSD9_ADC_ALERT_N")
		)
		(pad "2" smd circle
			(at 0.40005 0)
			(size 0 0)
			(layers "F.Cu" "F.Mask" "F.Paste")
			(net "SSD_8_15_ADC_ALERT_N")
		)
	)
	(footprint ""
		(layer "F.Cu")
		(at 489.627164 -528.154392 180)
		(property "Reference" "PEX0_HS"
			(at 0.127 -0.593598 0)
			(unlocked yes)
			(layer "F.SilkS")
			(effects
				(font
					(size 0.254 0.127)
					(thickness 0.000001)
				)
			)
		)
		(property "Value" ""
			(at 0 0 180)
			(layer "F.Fab")
			(effects
				(font
					(size 1.27 1.27)
				)
			)
		)
		(duplicate_pad_numbers_are_jumpers no)
		(pad "1" smd circle
			(at 0 0 180)
			(size 0.762 0.762)
			(layers "F.Cu" "F.Mask" "F.Paste")
			(net "Net_9124")
		)
	)
	(footprint ""
		(layer "F.Cu")
		(at 438.939432 -293.47287 -90)
		(property "Reference" "U316"
			(at -0.309118 -5.440172 90)
			(unlocked yes)
			(layer "F.SilkS")
			(effects
				(font
					(size 0.7874 0.5842)
					(thickness 0.1524)
				)
			)
		)
		(property "Value" ""
			(at 0 0 270)
			(layer "F.Fab")
			(effects
				(font
					(size 1.27 1.27)
				)
			)
		)
		(duplicate_pad_numbers_are_jumpers no)
		(fp_line
			(start -1.463548 1.549908)
			(end -1.463548 -1.549908)
			(stroke
				(width 0.1524)
				(type default)
			)
			(layer "F.SilkS")
		)
		(fp_line
			(start 1.463548 1.549908)
			(end -1.463548 1.549908)
			(stroke
				(width 0.1524)
				(type default)
			)
			(layer "F.SilkS")
		)
		(fp_line
			(start 0 -0.762)
			(end 0.762 -1.549908)
			(stroke
				(width 0.1524)
				(type default)
			)
			(layer "F.SilkS")
		)
		(fp_line
			(start -1.463548 -1.549908)
			(end -0.787908 -1.549908)
			(stroke
				(width 0.1524)
				(type default)
			)
			(layer "F.SilkS")
		)
		(fp_line
			(start -0.787908 -1.549908)
			(end 0 -0.762)
			(stroke
				(width 0.1524)
				(type default)
			)
			(layer "F.SilkS")
		)
		(fp_line
			(start 0.762 -1.549908)
			(end 1.463548 -1.549908)
			(stroke
				(width 0.1524)
				(type default)
			)
			(layer "F.SilkS")
		)
		(fp_line
			(start 1.463548 -1.549908)
			(end 1.463548 1.549908)
			(stroke
				(width 0.1524)
				(type default)
			)
			(layer "F.SilkS")
		)
		(fp_poly
			(pts
				(xy -3.4798 -1.359916) (xy -2.86004 -1.050036) (xy -3.4798 -0.740156)
			)
			(stroke
				(width 0)
				(type default)
			)
			(fill yes)
			(layer "F.SilkS")
		)
		(fp_line
			(start -1.549908 1.549908)
			(end -1.549908 -1.549908)
			(stroke
				(width 0.1)
				(type default)
			)
			(layer "F.Fab")
		)
		(fp_line
			(start 1.549908 1.549908)
			(end -1.549908 1.549908)
			(stroke
				(width 0.1)
				(type default)
			)
			(layer "F.Fab")
		)
		(fp_line
			(start -1.549908 -1.549908)
			(end 1.549908 -1.549908)
			(stroke
				(width 0.1)
				(type default)
			)
			(layer "F.Fab")
		)
		(fp_line
			(start 1.549908 -1.549908)
			(end 1.549908 1.549908)
			(stroke
				(width 0.1)
				(type default)
			)
			(layer "F.Fab")
		)
		(fp_poly
			(pts
				(xy -3.4798 -1.359916) (xy -2.86004 -1.050036) (xy -3.4798 -0.740156)
			)
			(stroke
				(width 0)
				(type default)
			)
			(fill yes)
			(layer "F.Fab")
		)
		(pad "1" smd rect
			(at -2.175002 -1.050036)
			(size 0.6096 1.1684)
			(layers "F.Cu" "F.Mask" "F.Paste")
			(net "P1V8_PEX")
		)
		(pad "2" smd rect
			(at -2.175002 -0.32512)
			(size 0.4318 1.1684)
			(layers "F.Cu" "F.Mask" "F.Paste")
			(net "I2C_PEX3_HOST_R_SCL")
		)
		(pad "3" smd rect
			(at -2.175002 0.32512)
			(size 0.4318 1.1684)
			(layers "F.Cu" "F.Mask" "F.Paste")
			(net "I2C_PEX3_HOST_R_SDA")
		)
		(pad "4" smd rect
			(at -2.175002 1.050036)
			(size 0.6096 1.1684)
			(layers "F.Cu" "F.Mask" "F.Paste")
			(net "GND")
		)
		(pad "5" smd rect
			(at 2.175002 1.050036)
			(size 0.6096 1.1684)
			(layers "F.Cu" "F.Mask" "F.Paste")
			(net "PWRGD_P1V8_PEX3_R")
		)
		(pad "6" smd rect
			(at 2.175002 0.32512)
			(size 0.4318 1.1684)
			(layers "F.Cu" "F.Mask" "F.Paste")
			(net "SMB_PEX3_HOST_LS_SDA")
		)
		(pad "7" smd rect
			(at 2.175002 -0.32512)
			(size 0.4318 1.1684)
			(layers "F.Cu" "F.Mask" "F.Paste")
			(net "SMB_PEX3_HOST_LS_SCL")
		)
		(pad "8" smd rect
			(at 2.175002 -1.050036)
			(size 0.6096 1.1684)
			(layers "F.Cu" "F.Mask" "F.Paste")
			(net "P3V3_AUX")
		)
	)
	(footprint ""
		(layer "F.Cu")
		(at 145.273268 -392.62939 -90)
		(property "Reference" "C4078"
			(at 0 0 270)
			(layer "F.SilkS")
			(hide yes)
			(effects
				(font
					(size 1.27 1.27)
				)
			)
		)
		(property "Value" ""
			(at 0 0 270)
			(layer "F.Fab")
			(effects
				(font
					(size 1.27 1.27)
				)
			)
		)
		(duplicate_pad_numbers_are_jumpers no)
		(fp_line
			(start -0.7874 0.4064)
			(end -0.7874 -0.4064)
			(stroke
				(width 0.1524)
				(type default)
			)
			(layer "F.SilkS")
		)
		(fp_line
			(start 0.7874 0.4064)
			(end -0.7874 0.4064)
			(stroke
				(width 0.1524)
				(type default)
			)
			(layer "F.SilkS")
		)
		(fp_line
			(start -0.7874 -0.4064)
			(end 0.7874 -0.4064)
			(stroke
				(width 0.1524)
				(type default)
			)
			(layer "F.SilkS")
		)
		(fp_line
			(start 0.7874 -0.4064)
			(end 0.7874 0.4064)
			(stroke
				(width 0.1524)
				(type default)
			)
			(layer "F.SilkS")
		)
		(fp_line
			(start -0.67945 0.3048)
			(end -0.67945 -0.305054)
			(stroke
				(width 0.1)
				(type default)
			)
			(layer "F.Fab")
		)
		(fp_line
			(start -0.12065 0.3048)
			(end -0.67945 0.3048)
			(stroke
				(width 0.1)
				(type default)
			)
			(layer "F.Fab")
		)
		(fp_line
			(start 0.120396 0.3048)
			(end 0.120396 0.2794)
			(stroke
				(width 0.1)
				(type default)
			)
			(layer "F.Fab")
		)
		(fp_line
			(start 0.67945 0.3048)
			(end 0.120396 0.3048)
			(stroke
				(width 0.1)
				(type default)
			)
			(layer "F.Fab")
		)
		(fp_line
			(start -0.12065 0.2794)
			(end -0.12065 0.3048)
			(stroke
				(width 0.1)
				(type default)
			)
			(layer "F.Fab")
		)
		(fp_line
			(start 0.120396 0.2794)
			(end -0.12065 0.2794)
			(stroke
				(width 0.1)
				(type default)
			)
			(layer "F.Fab")
		)
		(fp_line
			(start -0.12065 -0.2794)
			(end 0.12065 -0.2794)
			(stroke
				(width 0.1)
				(type default)
			)
			(layer "F.Fab")
		)
		(fp_line
			(start 0.12065 -0.2794)
			(end 0.12065 -0.3048)
			(stroke
				(width 0.1)
				(type default)
			)
			(layer "F.Fab")
		)
		(fp_line
			(start 0.12065 -0.3048)
			(end 0.67945 -0.3048)
			(stroke
				(width 0.1)
				(type default)
			)
			(layer "F.Fab")
		)
		(fp_line
			(start 0.67945 -0.3048)
			(end 0.67945 0.3048)
			(stroke
				(width 0.1)
				(type default)
			)
			(layer "F.Fab")
		)
		(fp_line
			(start -0.67945 -0.305054)
			(end -0.12065 -0.305054)
			(stroke
				(width 0.1)
				(type default)
			)
			(layer "F.Fab")
		)
		(fp_line
			(start -0.12065 -0.305054)
			(end -0.12065 -0.2794)
			(stroke
				(width 0.1)
				(type default)
			)
			(layer "F.Fab")
		)
		(pad "1" smd circle
			(at -0.40005 0 270)
			(size 0 0)
			(layers "F.Cu" "F.Mask" "F.Paste")
			(net "GND")
		)
		(pad "2" smd circle
			(at 0.40005 0 270)
			(size 0 0)
			(layers "F.Cu" "F.Mask" "F.Paste")
			(net "GPU_FPGA_BOOT_EN")
		)
	)
	(footprint ""
		(layer "F.Cu")
		(at 113.561114 -262.703564 180)
		(property "Reference" "PR82"
			(at 0 0 180)
			(layer "F.SilkS")
			(hide yes)
			(effects
				(font
					(size 1.27 1.27)
				)
			)
		)
		(property "Value" ""
			(at 0 0 180)
			(layer "F.Fab")
			(effects
				(font
					(size 1.27 1.27)
				)
			)
		)
		(duplicate_pad_numbers_are_jumpers no)
		(fp_line
			(start 0.7874 0.4064)
			(end -0.7874 0.4064)
			(stroke
				(width 0.1524)
				(type default)
			)
			(layer "F.SilkS")
		)
		(fp_line
			(start 0.7874 -0.4064)
			(end 0.7874 0.4064)
			(stroke
				(width 0.1524)
				(type default)
			)
			(layer "F.SilkS")
		)
		(fp_line
			(start -0.7874 0.4064)
			(end -0.7874 -0.4064)
			(stroke
				(width 0.1524)
				(type default)
			)
			(layer "F.SilkS")
		)
		(fp_line
			(start -0.7874 -0.4064)
			(end 0.7874 -0.4064)
			(stroke
				(width 0.1524)
				(type default)
			)
			(layer "F.SilkS")
		)
		(fp_line
			(start 0.67945 0.3048)
			(end 0.120396 0.3048)
			(stroke
				(width 0.1)
				(type default)
			)
			(layer "F.Fab")
		)
		(fp_line
			(start 0.67945 -0.3048)
			(end 0.67945 0.3048)
			(stroke
				(width 0.1)
				(type default)
			)
			(layer "F.Fab")
		)
		(fp_line
			(start 0.12065 -0.2794)
			(end 0.12065 -0.3048)
			(stroke
				(width 0.1)
				(type default)
			)
			(layer "F.Fab")
		)
		(fp_line
			(start 0.12065 -0.3048)
			(end 0.67945 -0.3048)
			(stroke
				(width 0.1)
				(type default)
			)
			(layer "F.Fab")
		)
		(fp_line
			(start 0.120396 0.3048)
			(end 0.120396 0.2794)
			(stroke
				(width 0.1)
				(type default)
			)
			(layer "F.Fab")
		)
		(fp_line
			(start 0.120396 0.2794)
			(end -0.12065 0.2794)
			(stroke
				(width 0.1)
				(type default)
			)
			(layer "F.Fab")
		)
		(fp_line
			(start -0.12065 0.3048)
			(end -0.67945 0.3048)
			(stroke
				(width 0.1)
				(type default)
			)
			(layer "F.Fab")
		)
		(fp_line
			(start -0.12065 0.2794)
			(end -0.12065 0.3048)
			(stroke
				(width 0.1)
				(type default)
			)
			(layer "F.Fab")
		)
		(fp_line
			(start -0.12065 -0.2794)
			(end 0.12065 -0.2794)
			(stroke
				(width 0.1)
				(type default)
			)
			(layer "F.Fab")
		)
		(fp_line
			(start -0.12065 -0.305054)
			(end -0.12065 -0.2794)
			(stroke
				(width 0.1)
				(type default)
			)
			(layer "F.Fab")
		)
		(fp_line
			(start -0.67945 0.3048)
			(end -0.67945 -0.305054)
			(stroke
				(width 0.1)
				(type default)
			)
			(layer "F.Fab")
		)
		(fp_line
			(start -0.67945 -0.305054)
			(end -0.12065 -0.305054)
			(stroke
				(width 0.1)
				(type default)
			)
			(layer "F.Fab")
		)
		(pad "1" smd circle
			(at -0.40005 0 180)
			(size 0 0)
			(layers "F.Cu" "F.Mask" "F.Paste")
			(net "P0V8_PEX0_VR_CONFIG")
		)
		(pad "2" smd circle
			(at 0.40005 0 180)
			(size 0 0)
			(layers "F.Cu" "F.Mask" "F.Paste")
			(net "P3V3_AUX")
		)
	)
	(footprint ""
		(layer "F.Cu")
		(at 327.82256 -22.867366 90)
		(property "Reference" "C3952"
			(at 0 0 90)
			(layer "F.SilkS")
			(hide yes)
			(effects
				(font
					(size 1.27 1.27)
				)
			)
		)
		(property "Value" ""
			(at 0 0 90)
			(layer "F.Fab")
			(effects
				(font
					(size 1.27 1.27)
				)
			)
		)
		(duplicate_pad_numbers_are_jumpers no)
		(fp_line
			(start 0.7874 -0.4064)
			(end 0.7874 0.4064)
			(stroke
				(width 0.1524)
				(type default)
			)
			(layer "F.SilkS")
		)
		(fp_line
			(start -0.7874 -0.4064)
			(end 0.7874 -0.4064)
			(stroke
				(width 0.1524)
				(type default)
			)
			(layer "F.SilkS")
		)
		(fp_line
			(start 0.7874 0.4064)
			(end -0.7874 0.4064)
			(stroke
				(width 0.1524)
				(type default)
			)
			(layer "F.SilkS")
		)
		(fp_line
			(start -0.7874 0.4064)
			(end -0.7874 -0.4064)
			(stroke
				(width 0.1524)
				(type default)
			)
			(layer "F.SilkS")
		)
		(fp_line
			(start -0.12065 -0.305054)
			(end -0.12065 -0.2794)
			(stroke
				(width 0.1)
				(type default)
			)
			(layer "F.Fab")
		)
		(fp_line
			(start -0.67945 -0.305054)
			(end -0.12065 -0.305054)
			(stroke
				(width 0.1)
				(type default)
			)
			(layer "F.Fab")
		)
		(fp_line
			(start 0.67945 -0.3048)
			(end 0.67945 0.3048)
			(stroke
				(width 0.1)
				(type default)
			)
			(layer "F.Fab")
		)
		(fp_line
			(start 0.12065 -0.3048)
			(end 0.67945 -0.3048)
			(stroke
				(width 0.1)
				(type default)
			)
			(layer "F.Fab")
		)
		(fp_line
			(start 0.12065 -0.2794)
			(end 0.12065 -0.3048)
			(stroke
				(width 0.1)
				(type default)
			)
			(layer "F.Fab")
		)
		(fp_line
			(start -0.12065 -0.2794)
			(end 0.12065 -0.2794)
			(stroke
				(width 0.1)
				(type default)
			)
			(layer "F.Fab")
		)
		(fp_line
			(start 0.120396 0.2794)
			(end -0.12065 0.2794)
			(stroke
				(width 0.1)
				(type default)
			)
			(layer "F.Fab")
		)
		(fp_line
			(start -0.12065 0.2794)
			(end -0.12065 0.3048)
			(stroke
				(width 0.1)
				(type default)
			)
			(layer "F.Fab")
		)
		(fp_line
			(start 0.67945 0.3048)
			(end 0.120396 0.3048)
			(stroke
				(width 0.1)
				(type default)
			)
			(layer "F.Fab")
		)
		(fp_line
			(start 0.120396 0.3048)
			(end 0.120396 0.2794)
			(stroke
				(width 0.1)
				(type default)
			)
			(layer "F.Fab")
		)
		(fp_line
			(start -0.12065 0.3048)
			(end -0.67945 0.3048)
			(stroke
				(width 0.1)
				(type default)
			)
			(layer "F.Fab")
		)
		(fp_line
			(start -0.67945 0.3048)
			(end -0.67945 -0.305054)
			(stroke
				(width 0.1)
				(type default)
			)
			(layer "F.Fab")
		)
		(pad "1" smd circle
			(at -0.40005 0 90)
			(size 0 0)
			(layers "F.Cu" "F.Mask" "F.Paste")
			(net "P12V_SSD11")
		)
		(pad "2" smd circle
			(at 0.40005 0 90)
			(size 0 0)
			(layers "F.Cu" "F.Mask" "F.Paste")
			(net "GND")
		)
	)
	(footprint ""
		(layer "F.Cu")
		(at 268.838426 -134.923276)
		(property "Reference" "C458"
			(at 0 0 0)
			(layer "F.SilkS")
			(hide yes)
			(effects
				(font
					(size 1.27 1.27)
				)
			)
		)
		(property "Value" ""
			(at 0 0 0)
			(layer "F.Fab")
			(effects
				(font
					(size 1.27 1.27)
				)
			)
		)
		(duplicate_pad_numbers_are_jumpers no)
		(fp_line
			(start -0.299974 -0.150114)
			(end 0.299974 -0.150114)
			(stroke
				(width 0.1)
				(type default)
			)
			(layer "F.Fab")
		)
		(fp_line
			(start -0.299974 0.150114)
			(end -0.299974 -0.150114)
			(stroke
				(width 0.1)
				(type default)
			)
			(layer "F.Fab")
		)
		(fp_line
			(start 0.299974 -0.150114)
			(end 0.299974 0.150114)
			(stroke
				(width 0.1)
				(type default)
			)
			(layer "F.Fab")
		)
		(fp_line
			(start 0.299974 0.150114)
			(end -0.299974 0.150114)
			(stroke
				(width 0.1)
				(type default)
			)
			(layer "F.Fab")
		)
		(pad "1" smd rect
			(at -0.2667 0)
			(size 0.3048 0.381)
			(layers "F.Cu" "F.Mask" "F.Paste")
			(net "P5E_PEX2_STN1_TX_DN<30>")
		)
		(pad "2" smd rect
			(at 0.2667 0)
			(size 0.3048 0.381)
			(layers "F.Cu" "F.Mask" "F.Paste")
			(net "P5E_PEX2_STN1_TX_C_DN<30>")
		)
	)
	(footprint ""
		(layer "F.Cu")
		(at 47.885604 -25.1587 -90)
		(property "Reference" "R5734"
			(at 0 0 270)
			(layer "F.SilkS")
			(hide yes)
			(effects
				(font
					(size 1.27 1.27)
				)
			)
		)
		(property "Value" ""
			(at 0 0 270)
			(layer "F.Fab")
			(effects
				(font
					(size 1.27 1.27)
				)
			)
		)
		(duplicate_pad_numbers_are_jumpers no)
		(fp_line
			(start -0.7874 0.4064)
			(end -0.7874 -0.4064)
			(stroke
				(width 0.1524)
				(type default)
			)
			(layer "F.SilkS")
		)
		(fp_line
			(start 0.7874 0.4064)
			(end -0.7874 0.4064)
			(stroke
				(width 0.1524)
				(type default)
			)
			(layer "F.SilkS")
		)
		(fp_line
			(start -0.7874 -0.4064)
			(end 0.7874 -0.4064)
			(stroke
				(width 0.1524)
				(type default)
			)
			(layer "F.SilkS")
		)
		(fp_line
			(start 0.7874 -0.4064)
			(end 0.7874 0.4064)
			(stroke
				(width 0.1524)
				(type default)
			)
			(layer "F.SilkS")
		)
		(fp_line
			(start -0.67945 0.3048)
			(end -0.67945 -0.305054)
			(stroke
				(width 0.1)
				(type default)
			)
			(layer "F.Fab")
		)
		(fp_line
			(start -0.12065 0.3048)
			(end -0.67945 0.3048)
			(stroke
				(width 0.1)
				(type default)
			)
			(layer "F.Fab")
		)
		(fp_line
			(start 0.120396 0.3048)
			(end 0.120396 0.2794)
			(stroke
				(width 0.1)
				(type default)
			)
			(layer "F.Fab")
		)
		(fp_line
			(start 0.67945 0.3048)
			(end 0.120396 0.3048)
			(stroke
				(width 0.1)
				(type default)
			)
			(layer "F.Fab")
		)
		(fp_line
			(start -0.12065 0.2794)
			(end -0.12065 0.3048)
			(stroke
				(width 0.1)
				(type default)
			)
			(layer "F.Fab")
		)
		(fp_line
			(start 0.120396 0.2794)
			(end -0.12065 0.2794)
			(stroke
				(width 0.1)
				(type default)
			)
			(layer "F.Fab")
		)
		(fp_line
			(start -0.12065 -0.2794)
			(end 0.12065 -0.2794)
			(stroke
				(width 0.1)
				(type default)
			)
			(layer "F.Fab")
		)
		(fp_line
			(start 0.12065 -0.2794)
			(end 0.12065 -0.3048)
			(stroke
				(width 0.1)
				(type default)
			)
			(layer "F.Fab")
		)
		(fp_line
			(start 0.12065 -0.3048)
			(end 0.67945 -0.3048)
			(stroke
				(width 0.1)
				(type default)
			)
			(layer "F.Fab")
		)
		(fp_line
			(start 0.67945 -0.3048)
			(end 0.67945 0.3048)
			(stroke
				(width 0.1)
				(type default)
			)
			(layer "F.Fab")
		)
		(fp_line
			(start -0.67945 -0.305054)
			(end -0.12065 -0.305054)
			(stroke
				(width 0.1)
				(type default)
			)
			(layer "F.Fab")
		)
		(fp_line
			(start -0.12065 -0.305054)
			(end -0.12065 -0.2794)
			(stroke
				(width 0.1)
				(type default)
			)
			(layer "F.Fab")
		)
		(pad "1" smd circle
			(at -0.40005 0 270)
			(size 0 0)
			(layers "F.Cu" "F.Mask" "F.Paste")
			(net "SSD1_LED_ISO_N")
		)
		(pad "2" smd circle
			(at 0.40005 0 270)
			(size 0 0)
			(layers "F.Cu" "F.Mask" "F.Paste")
			(net "SSD1_LED_ISO_R_N")
		)
	)
	(footprint ""
		(layer "F.Cu")
		(at 108.441236 -303.649634 90)
		(property "Reference" "PC69"
			(at 0 0 90)
			(layer "F.SilkS")
			(hide yes)
			(effects
				(font
					(size 1.27 1.27)
				)
			)
		)
		(property "Value" ""
			(at 0 0 90)
			(layer "F.Fab")
			(effects
				(font
					(size 1.27 1.27)
				)
			)
		)
		(duplicate_pad_numbers_are_jumpers no)
		(fp_line
			(start 1.524 -0.762)
			(end 1.524 0.762)
			(stroke
				(width 0.1524)
				(type default)
			)
			(layer "F.SilkS")
		)
		(fp_line
			(start -1.524 -0.762)
			(end 1.524 -0.762)
			(stroke
				(width 0.1524)
				(type default)
			)
			(layer "F.SilkS")
		)
		(fp_line
			(start 1.524 0.762)
			(end -1.524 0.762)
			(stroke
				(width 0.1524)
				(type default)
			)
			(layer "F.SilkS")
		)
		(fp_line
			(start -1.524 0.762)
			(end -1.524 -0.762)
			(stroke
				(width 0.1524)
				(type default)
			)
			(layer "F.SilkS")
		)
		(fp_line
			(start 1.1049 -0.724916)
			(end -1.1049 -0.724916)
			(stroke
				(width 0.1)
				(type default)
			)
			(layer "F.Fab")
		)
		(fp_line
			(start -1.1049 -0.724916)
			(end -1.1049 0.724916)
			(stroke
				(width 0.1)
				(type default)
			)
			(layer "F.Fab")
		)
		(fp_line
			(start 1.1049 0.724916)
			(end 1.1049 -0.724916)
			(stroke
				(width 0.1)
				(type default)
			)
			(layer "F.Fab")
		)
		(fp_line
			(start -1.1049 0.724916)
			(end 1.1049 0.724916)
			(stroke
				(width 0.1)
				(type default)
			)
			(layer "F.Fab")
		)
		(pad "1" smd rect
			(at -0.889 0 270)
			(size 1.016 1.27)
			(layers "F.Cu" "F.Mask" "F.Paste")
			(net "P0V8_PEX0")
		)
		(pad "2" smd rect
			(at 0.889 0 270)
			(size 1.016 1.27)
			(layers "F.Cu" "F.Mask" "F.Paste")
			(net "GND")
		)
	)
	(footprint ""
		(layer "F.Cu")
		(at 349.907098 -282.421584 -90)
		(property "Reference" "PC155"
			(at 0 0 270)
			(layer "F.SilkS")
			(hide yes)
			(effects
				(font
					(size 1.27 1.27)
				)
			)
		)
		(property "Value" ""
			(at 0 0 270)
			(layer "F.Fab")
			(effects
				(font
					(size 1.27 1.27)
				)
			)
		)
		(duplicate_pad_numbers_are_jumpers no)
		(fp_line
			(start -0.7874 0.4064)
			(end -0.7874 -0.4064)
			(stroke
				(width 0.1524)
				(type default)
			)
			(layer "F.SilkS")
		)
		(fp_line
			(start 0.7874 0.4064)
			(end -0.7874 0.4064)
			(stroke
				(width 0.1524)
				(type default)
			)
			(layer "F.SilkS")
		)
		(fp_line
			(start -0.7874 -0.4064)
			(end 0.7874 -0.4064)
			(stroke
				(width 0.1524)
				(type default)
			)
			(layer "F.SilkS")
		)
		(fp_line
			(start 0.7874 -0.4064)
			(end 0.7874 0.4064)
			(stroke
				(width 0.1524)
				(type default)
			)
			(layer "F.SilkS")
		)
		(fp_line
			(start -0.67945 0.3048)
			(end -0.67945 -0.305054)
			(stroke
				(width 0.1)
				(type default)
			)
			(layer "F.Fab")
		)
		(fp_line
			(start -0.12065 0.3048)
			(end -0.67945 0.3048)
			(stroke
				(width 0.1)
				(type default)
			)
			(layer "F.Fab")
		)
		(fp_line
			(start 0.120396 0.3048)
			(end 0.120396 0.2794)
			(stroke
				(width 0.1)
				(type default)
			)
			(layer "F.Fab")
		)
		(fp_line
			(start 0.67945 0.3048)
			(end 0.120396 0.3048)
			(stroke
				(width 0.1)
				(type default)
			)
			(layer "F.Fab")
		)
		(fp_line
			(start -0.12065 0.2794)
			(end -0.12065 0.3048)
			(stroke
				(width 0.1)
				(type default)
			)
			(layer "F.Fab")
		)
		(fp_line
			(start 0.120396 0.2794)
			(end -0.12065 0.2794)
			(stroke
				(width 0.1)
				(type default)
			)
			(layer "F.Fab")
		)
		(fp_line
			(start -0.12065 -0.2794)
			(end 0.12065 -0.2794)
			(stroke
				(width 0.1)
				(type default)
			)
			(layer "F.Fab")
		)
		(fp_line
			(start 0.12065 -0.2794)
			(end 0.12065 -0.3048)
			(stroke
				(width 0.1)
				(type default)
			)
			(layer "F.Fab")
		)
		(fp_line
			(start 0.12065 -0.3048)
			(end 0.67945 -0.3048)
			(stroke
				(width 0.1)
				(type default)
			)
			(layer "F.Fab")
		)
		(fp_line
			(start 0.67945 -0.3048)
			(end 0.67945 0.3048)
			(stroke
				(width 0.1)
				(type default)
			)
			(layer "F.Fab")
		)
		(fp_line
			(start -0.67945 -0.305054)
			(end -0.12065 -0.305054)
			(stroke
				(width 0.1)
				(type default)
			)
			(layer "F.Fab")
		)
		(fp_line
			(start -0.12065 -0.305054)
			(end -0.12065 -0.2794)
			(stroke
				(width 0.1)
				(type default)
			)
			(layer "F.Fab")
		)
		(pad "1" smd circle
			(at -0.40005 0 270)
			(size 0 0)
			(layers "F.Cu" "F.Mask" "F.Paste")
			(net "P0V8_PEX2_VCC2")
		)
		(pad "2" smd circle
			(at 0.40005 0 270)
			(size 0 0)
			(layers "F.Cu" "F.Mask" "F.Paste")
			(net "GND")
		)
	)
	(footprint ""
		(layer "F.Cu")
		(at 4.51866 -380.182628)
		(property "Reference" "C4459"
			(at 0 0 0)
			(layer "F.SilkS")
			(hide yes)
			(effects
				(font
					(size 1.27 1.27)
				)
			)
		)
		(property "Value" ""
			(at 0 0 0)
			(layer "F.Fab")
			(effects
				(font
					(size 1.27 1.27)
				)
			)
		)
		(duplicate_pad_numbers_are_jumpers no)
		(fp_line
			(start -0.7874 -0.4064)
			(end 0.7874 -0.4064)
			(stroke
				(width 0.1524)
				(type default)
			)
			(layer "F.SilkS")
		)
		(fp_line
			(start -0.7874 0.4064)
			(end -0.7874 -0.4064)
			(stroke
				(width 0.1524)
				(type default)
			)
			(layer "F.SilkS")
		)
		(fp_line
			(start 0.7874 -0.4064)
			(end 0.7874 0.4064)
			(stroke
				(width 0.1524)
				(type default)
			)
			(layer "F.SilkS")
		)
		(fp_line
			(start 0.7874 0.4064)
			(end -0.7874 0.4064)
			(stroke
				(width 0.1524)
				(type default)
			)
			(layer "F.SilkS")
		)
		(fp_line
			(start -0.67945 -0.305054)
			(end -0.12065 -0.305054)
			(stroke
				(width 0.1)
				(type default)
			)
			(layer "F.Fab")
		)
		(fp_line
			(start -0.67945 0.3048)
			(end -0.67945 -0.305054)
			(stroke
				(width 0.1)
				(type default)
			)
			(layer "F.Fab")
		)
		(fp_line
			(start -0.12065 -0.305054)
			(end -0.12065 -0.2794)
			(stroke
				(width 0.1)
				(type default)
			)
			(layer "F.Fab")
		)
		(fp_line
			(start -0.12065 -0.2794)
			(end 0.12065 -0.2794)
			(stroke
				(width 0.1)
				(type default)
			)
			(layer "F.Fab")
		)
		(fp_line
			(start -0.12065 0.2794)
			(end -0.12065 0.3048)
			(stroke
				(width 0.1)
				(type default)
			)
			(layer "F.Fab")
		)
		(fp_line
			(start -0.12065 0.3048)
			(end -0.67945 0.3048)
			(stroke
				(width 0.1)
				(type default)
			)
			(layer "F.Fab")
		)
		(fp_line
			(start 0.120396 0.2794)
			(end -0.12065 0.2794)
			(stroke
				(width 0.1)
				(type default)
			)
			(layer "F.Fab")
		)
		(fp_line
			(start 0.120396 0.3048)
			(end 0.120396 0.2794)
			(stroke
				(width 0.1)
				(type default)
			)
			(layer "F.Fab")
		)
		(fp_line
			(start 0.12065 -0.3048)
			(end 0.67945 -0.3048)
			(stroke
				(width 0.1)
				(type default)
			)
			(layer "F.Fab")
		)
		(fp_line
			(start 0.12065 -0.2794)
			(end 0.12065 -0.3048)
			(stroke
				(width 0.1)
				(type default)
			)
			(layer "F.Fab")
		)
		(fp_line
			(start 0.67945 -0.3048)
			(end 0.67945 0.3048)
			(stroke
				(width 0.1)
				(type default)
			)
			(layer "F.Fab")
		)
		(fp_line
			(start 0.67945 0.3048)
			(end 0.120396 0.3048)
			(stroke
				(width 0.1)
				(type default)
			)
			(layer "F.Fab")
		)
		(pad "1" smd circle
			(at -0.40005 0)
			(size 0 0)
			(layers "F.Cu" "F.Mask" "F.Paste")
			(net "BIC_USB_8042_HUB_XIN")
		)
		(pad "2" smd circle
			(at 0.40005 0)
			(size 0 0)
			(layers "F.Cu" "F.Mask" "F.Paste")
			(net "GND")
		)
	)
	(footprint ""
		(layer "F.Cu")
		(at 460.611982 -108.737654 180)
		(property "Reference" "C982"
			(at 0 0 180)
			(layer "F.SilkS")
			(hide yes)
			(effects
				(font
					(size 1.27 1.27)
				)
			)
		)
		(property "Value" ""
			(at 0 0 180)
			(layer "F.Fab")
			(effects
				(font
					(size 1.27 1.27)
				)
			)
		)
		(duplicate_pad_numbers_are_jumpers no)
		(fp_line
			(start 0.7874 0.4064)
			(end -0.7874 0.4064)
			(stroke
				(width 0.1524)
				(type default)
			)
			(layer "F.SilkS")
		)
		(fp_line
			(start 0.7874 -0.4064)
			(end 0.7874 0.4064)
			(stroke
				(width 0.1524)
				(type default)
			)
			(layer "F.SilkS")
		)
		(fp_line
			(start -0.7874 0.4064)
			(end -0.7874 -0.4064)
			(stroke
				(width 0.1524)
				(type default)
			)
			(layer "F.SilkS")
		)
		(fp_line
			(start -0.7874 -0.4064)
			(end 0.7874 -0.4064)
			(stroke
				(width 0.1524)
				(type default)
			)
			(layer "F.SilkS")
		)
		(fp_line
			(start 0.67945 0.3048)
			(end 0.120396 0.3048)
			(stroke
				(width 0.1)
				(type default)
			)
			(layer "F.Fab")
		)
		(fp_line
			(start 0.67945 -0.3048)
			(end 0.67945 0.3048)
			(stroke
				(width 0.1)
				(type default)
			)
			(layer "F.Fab")
		)
		(fp_line
			(start 0.12065 -0.2794)
			(end 0.12065 -0.3048)
			(stroke
				(width 0.1)
				(type default)
			)
			(layer "F.Fab")
		)
		(fp_line
			(start 0.12065 -0.3048)
			(end 0.67945 -0.3048)
			(stroke
				(width 0.1)
				(type default)
			)
			(layer "F.Fab")
		)
		(fp_line
			(start 0.120396 0.3048)
			(end 0.120396 0.2794)
			(stroke
				(width 0.1)
				(type default)
			)
			(layer "F.Fab")
		)
		(fp_line
			(start 0.120396 0.2794)
			(end -0.12065 0.2794)
			(stroke
				(width 0.1)
				(type default)
			)
			(layer "F.Fab")
		)
		(fp_line
			(start -0.12065 0.3048)
			(end -0.67945 0.3048)
			(stroke
				(width 0.1)
				(type default)
			)
			(layer "F.Fab")
		)
		(fp_line
			(start -0.12065 0.2794)
			(end -0.12065 0.3048)
			(stroke
				(width 0.1)
				(type default)
			)
			(layer "F.Fab")
		)
		(fp_line
			(start -0.12065 -0.2794)
			(end 0.12065 -0.2794)
			(stroke
				(width 0.1)
				(type default)
			)
			(layer "F.Fab")
		)
		(fp_line
			(start -0.12065 -0.305054)
			(end -0.12065 -0.2794)
			(stroke
				(width 0.1)
				(type default)
			)
			(layer "F.Fab")
		)
		(fp_line
			(start -0.67945 0.3048)
			(end -0.67945 -0.305054)
			(stroke
				(width 0.1)
				(type default)
			)
			(layer "F.Fab")
		)
		(fp_line
			(start -0.67945 -0.305054)
			(end -0.12065 -0.305054)
			(stroke
				(width 0.1)
				(type default)
			)
			(layer "F.Fab")
		)
		(pad "1" smd circle
			(at -0.40005 0 180)
			(size 0 0)
			(layers "F.Cu" "F.Mask" "F.Paste")
			(net "GND")
		)
		(pad "2" smd circle
			(at 0.40005 0 180)
			(size 0 0)
			(layers "F.Cu" "F.Mask" "F.Paste")
			(net "P12V_NIC7_CO_EN")
		)
	)
	(footprint ""
		(layer "F.Cu")
		(at 13.953744 -115.147852 -90)
		(property "Reference" "PC658"
			(at 0 0 270)
			(layer "F.SilkS")
			(hide yes)
			(effects
				(font
					(size 1.27 1.27)
				)
			)
		)
		(property "Value" ""
			(at 0 0 270)
			(layer "F.Fab")
			(effects
				(font
					(size 1.27 1.27)
				)
			)
		)
		(duplicate_pad_numbers_are_jumpers no)
		(fp_line
			(start -0.7874 0.4064)
			(end -0.7874 -0.4064)
			(stroke
				(width 0.1524)
				(type default)
			)
			(layer "F.SilkS")
		)
		(fp_line
			(start 0.7874 0.4064)
			(end -0.7874 0.4064)
			(stroke
				(width 0.1524)
				(type default)
			)
			(layer "F.SilkS")
		)
		(fp_line
			(start -0.7874 -0.4064)
			(end 0.7874 -0.4064)
			(stroke
				(width 0.1524)
				(type default)
			)
			(layer "F.SilkS")
		)
		(fp_line
			(start 0.7874 -0.4064)
			(end 0.7874 0.4064)
			(stroke
				(width 0.1524)
				(type default)
			)
			(layer "F.SilkS")
		)
		(fp_line
			(start -0.67945 0.3048)
			(end -0.67945 -0.305054)
			(stroke
				(width 0.1)
				(type default)
			)
			(layer "F.Fab")
		)
		(fp_line
			(start -0.12065 0.3048)
			(end -0.67945 0.3048)
			(stroke
				(width 0.1)
				(type default)
			)
			(layer "F.Fab")
		)
		(fp_line
			(start 0.120396 0.3048)
			(end 0.120396 0.2794)
			(stroke
				(width 0.1)
				(type default)
			)
			(layer "F.Fab")
		)
		(fp_line
			(start 0.67945 0.3048)
			(end 0.120396 0.3048)
			(stroke
				(width 0.1)
				(type default)
			)
			(layer "F.Fab")
		)
		(fp_line
			(start -0.12065 0.2794)
			(end -0.12065 0.3048)
			(stroke
				(width 0.1)
				(type default)
			)
			(layer "F.Fab")
		)
		(fp_line
			(start 0.120396 0.2794)
			(end -0.12065 0.2794)
			(stroke
				(width 0.1)
				(type default)
			)
			(layer "F.Fab")
		)
		(fp_line
			(start -0.12065 -0.2794)
			(end 0.12065 -0.2794)
			(stroke
				(width 0.1)
				(type default)
			)
			(layer "F.Fab")
		)
		(fp_line
			(start 0.12065 -0.2794)
			(end 0.12065 -0.3048)
			(stroke
				(width 0.1)
				(type default)
			)
			(layer "F.Fab")
		)
		(fp_line
			(start 0.12065 -0.3048)
			(end 0.67945 -0.3048)
			(stroke
				(width 0.1)
				(type default)
			)
			(layer "F.Fab")
		)
		(fp_line
			(start 0.67945 -0.3048)
			(end 0.67945 0.3048)
			(stroke
				(width 0.1)
				(type default)
			)
			(layer "F.Fab")
		)
		(fp_line
			(start -0.67945 -0.305054)
			(end -0.12065 -0.305054)
			(stroke
				(width 0.1)
				(type default)
			)
			(layer "F.Fab")
		)
		(fp_line
			(start -0.12065 -0.305054)
			(end -0.12065 -0.2794)
			(stroke
				(width 0.1)
				(type default)
			)
			(layer "F.Fab")
		)
		(pad "1" smd circle
			(at -0.40005 0 270)
			(size 0 0)
			(layers "F.Cu" "F.Mask" "F.Paste")
			(net "P3V3_AUX")
		)
		(pad "2" smd circle
			(at 0.40005 0 270)
			(size 0 0)
			(layers "F.Cu" "F.Mask" "F.Paste")
			(net "GND")
		)
	)
	(footprint ""
		(layer "F.Cu")
		(at 124.991114 -252.416564 90)
		(property "Reference" "R828"
			(at 0 0 90)
			(layer "F.SilkS")
			(hide yes)
			(effects
				(font
					(size 1.27 1.27)
				)
			)
		)
		(property "Value" ""
			(at 0 0 90)
			(layer "F.Fab")
			(effects
				(font
					(size 1.27 1.27)
				)
			)
		)
		(duplicate_pad_numbers_are_jumpers no)
		(fp_line
			(start 0.7874 -0.4064)
			(end 0.7874 0.4064)
			(stroke
				(width 0.1524)
				(type default)
			)
			(layer "F.SilkS")
		)
		(fp_line
			(start -0.7874 -0.4064)
			(end 0.7874 -0.4064)
			(stroke
				(width 0.1524)
				(type default)
			)
			(layer "F.SilkS")
		)
		(fp_line
			(start 0.7874 0.4064)
			(end -0.7874 0.4064)
			(stroke
				(width 0.1524)
				(type default)
			)
			(layer "F.SilkS")
		)
		(fp_line
			(start -0.7874 0.4064)
			(end -0.7874 -0.4064)
			(stroke
				(width 0.1524)
				(type default)
			)
			(layer "F.SilkS")
		)
		(fp_line
			(start -0.12065 -0.305054)
			(end -0.12065 -0.2794)
			(stroke
				(width 0.1)
				(type default)
			)
			(layer "F.Fab")
		)
		(fp_line
			(start -0.67945 -0.305054)
			(end -0.12065 -0.305054)
			(stroke
				(width 0.1)
				(type default)
			)
			(layer "F.Fab")
		)
		(fp_line
			(start 0.67945 -0.3048)
			(end 0.67945 0.3048)
			(stroke
				(width 0.1)
				(type default)
			)
			(layer "F.Fab")
		)
		(fp_line
			(start 0.12065 -0.3048)
			(end 0.67945 -0.3048)
			(stroke
				(width 0.1)
				(type default)
			)
			(layer "F.Fab")
		)
		(fp_line
			(start 0.12065 -0.2794)
			(end 0.12065 -0.3048)
			(stroke
				(width 0.1)
				(type default)
			)
			(layer "F.Fab")
		)
		(fp_line
			(start -0.12065 -0.2794)
			(end 0.12065 -0.2794)
			(stroke
				(width 0.1)
				(type default)
			)
			(layer "F.Fab")
		)
		(fp_line
			(start 0.120396 0.2794)
			(end -0.12065 0.2794)
			(stroke
				(width 0.1)
				(type default)
			)
			(layer "F.Fab")
		)
		(fp_line
			(start -0.12065 0.2794)
			(end -0.12065 0.3048)
			(stroke
				(width 0.1)
				(type default)
			)
			(layer "F.Fab")
		)
		(fp_line
			(start 0.67945 0.3048)
			(end 0.120396 0.3048)
			(stroke
				(width 0.1)
				(type default)
			)
			(layer "F.Fab")
		)
		(fp_line
			(start 0.120396 0.3048)
			(end 0.120396 0.2794)
			(stroke
				(width 0.1)
				(type default)
			)
			(layer "F.Fab")
		)
		(fp_line
			(start -0.12065 0.3048)
			(end -0.67945 0.3048)
			(stroke
				(width 0.1)
				(type default)
			)
			(layer "F.Fab")
		)
		(fp_line
			(start -0.67945 0.3048)
			(end -0.67945 -0.305054)
			(stroke
				(width 0.1)
				(type default)
			)
			(layer "F.Fab")
		)
		(pad "1" smd circle
			(at -0.40005 0 90)
			(size 0 0)
			(layers "F.Cu" "F.Mask" "F.Paste")
			(net "SMB_BIC_I2C6_MUX_VR_R_SCL")
		)
		(pad "2" smd circle
			(at 0.40005 0 90)
			(size 0 0)
			(layers "F.Cu" "F.Mask" "F.Paste")
			(net "SMB_VR_P0V8_PEX0_SCL")
		)
	)
	(footprint ""
		(layer "F.Cu")
		(at 227.581206 -254.18542 -90)
		(property "Reference" "C4298"
			(at 0 0 270)
			(layer "F.SilkS")
			(hide yes)
			(effects
				(font
					(size 1.27 1.27)
				)
			)
		)
		(property "Value" ""
			(at 0 0 270)
			(layer "F.Fab")
			(effects
				(font
					(size 1.27 1.27)
				)
			)
		)
		(duplicate_pad_numbers_are_jumpers no)
		(fp_line
			(start -1.2954 0.5842)
			(end -1.2954 -0.5842)
			(stroke
				(width 0.1524)
				(type default)
			)
			(layer "F.SilkS")
		)
		(fp_line
			(start 1.2954 0.5842)
			(end -1.2954 0.5842)
			(stroke
				(width 0.1524)
				(type default)
			)
			(layer "F.SilkS")
		)
		(fp_line
			(start -1.2954 -0.5842)
			(end 1.2954 -0.5842)
			(stroke
				(width 0.1524)
				(type default)
			)
			(layer "F.SilkS")
		)
		(fp_line
			(start 1.2954 -0.5842)
			(end 1.2954 0.5842)
			(stroke
				(width 0.1524)
				(type default)
			)
			(layer "F.SilkS")
		)
		(fp_line
			(start -0.8636 0.4572)
			(end -0.8636 0.4064)
			(stroke
				(width 0.1)
				(type default)
			)
			(layer "F.Fab")
		)
		(fp_line
			(start 0.8636 0.4572)
			(end -0.8636 0.4572)
			(stroke
				(width 0.1)
				(type default)
			)
			(layer "F.Fab")
		)
		(fp_line
			(start -1.1938 0.4064)
			(end -1.1938 -0.4064)
			(stroke
				(width 0.1)
				(type default)
			)
			(layer "F.Fab")
		)
		(fp_line
			(start -0.8636 0.4064)
			(end -1.1938 0.4064)
			(stroke
				(width 0.1)
				(type default)
			)
			(layer "F.Fab")
		)
		(fp_line
			(start 0.8636 0.4064)
			(end 0.8636 0.4572)
			(stroke
				(width 0.1)
				(type default)
			)
			(layer "F.Fab")
		)
		(fp_line
			(start 1.1938 0.4064)
			(end 0.8636 0.4064)
			(stroke
				(width 0.1)
				(type default)
			)
			(layer "F.Fab")
		)
		(fp_line
			(start -1.1938 -0.4064)
			(end -0.8636 -0.4064)
			(stroke
				(width 0.1)
				(type default)
			)
			(layer "F.Fab")
		)
		(fp_line
			(start -0.8636 -0.4064)
			(end -0.8636 -0.4572)
			(stroke
				(width 0.1)
				(type default)
			)
			(layer "F.Fab")
		)
		(fp_line
			(start 0.8636 -0.4064)
			(end 1.1938 -0.4064)
			(stroke
				(width 0.1)
				(type default)
			)
			(layer "F.Fab")
		)
		(fp_line
			(start 1.1938 -0.4064)
			(end 1.1938 0.4064)
			(stroke
				(width 0.1)
				(type default)
			)
			(layer "F.Fab")
		)
		(fp_line
			(start -0.8636 -0.4572)
			(end 0.8636 -0.4572)
			(stroke
				(width 0.1)
				(type default)
			)
			(layer "F.Fab")
		)
		(fp_line
			(start 0.8636 -0.4572)
			(end 0.8636 -0.4064)
			(stroke
				(width 0.1)
				(type default)
			)
			(layer "F.Fab")
		)
		(pad "1" smd rect
			(at -0.7366 0 180)
			(size 0.7112 0.8128)
			(layers "F.Cu" "F.Mask" "F.Paste")
			(net "P1V25_SERDES_VDDPLL_PEX1_C8")
		)
		(pad "2" smd rect
			(at 0.7366 0 180)
			(size 0.7112 0.8128)
			(layers "F.Cu" "F.Mask" "F.Paste")
			(net "GND")
		)
	)
	(footprint ""
		(layer "F.Cu")
		(at 393.669266 -89.500202)
		(property "Reference" "R1761"
			(at 0 0 0)
			(layer "F.SilkS")
			(hide yes)
			(effects
				(font
					(size 1.27 1.27)
				)
			)
		)
		(property "Value" ""
			(at 0 0 0)
			(layer "F.Fab")
			(effects
				(font
					(size 1.27 1.27)
				)
			)
		)
		(duplicate_pad_numbers_are_jumpers no)
		(fp_line
			(start -0.7874 -0.4064)
			(end 0.7874 -0.4064)
			(stroke
				(width 0.1524)
				(type default)
			)
			(layer "F.SilkS")
		)
		(fp_line
			(start -0.7874 0.4064)
			(end -0.7874 -0.4064)
			(stroke
				(width 0.1524)
				(type default)
			)
			(layer "F.SilkS")
		)
		(fp_line
			(start 0.7874 -0.4064)
			(end 0.7874 0.4064)
			(stroke
				(width 0.1524)
				(type default)
			)
			(layer "F.SilkS")
		)
		(fp_line
			(start 0.7874 0.4064)
			(end -0.7874 0.4064)
			(stroke
				(width 0.1524)
				(type default)
			)
			(layer "F.SilkS")
		)
		(fp_line
			(start -0.67945 -0.305054)
			(end -0.12065 -0.305054)
			(stroke
				(width 0.1)
				(type default)
			)
			(layer "F.Fab")
		)
		(fp_line
			(start -0.67945 0.3048)
			(end -0.67945 -0.305054)
			(stroke
				(width 0.1)
				(type default)
			)
			(layer "F.Fab")
		)
		(fp_line
			(start -0.12065 -0.305054)
			(end -0.12065 -0.2794)
			(stroke
				(width 0.1)
				(type default)
			)
			(layer "F.Fab")
		)
		(fp_line
			(start -0.12065 -0.2794)
			(end 0.12065 -0.2794)
			(stroke
				(width 0.1)
				(type default)
			)
			(layer "F.Fab")
		)
		(fp_line
			(start -0.12065 0.2794)
			(end -0.12065 0.3048)
			(stroke
				(width 0.1)
				(type default)
			)
			(layer "F.Fab")
		)
		(fp_line
			(start -0.12065 0.3048)
			(end -0.67945 0.3048)
			(stroke
				(width 0.1)
				(type default)
			)
			(layer "F.Fab")
		)
		(fp_line
			(start 0.120396 0.2794)
			(end -0.12065 0.2794)
			(stroke
				(width 0.1)
				(type default)
			)
			(layer "F.Fab")
		)
		(fp_line
			(start 0.120396 0.3048)
			(end 0.120396 0.2794)
			(stroke
				(width 0.1)
				(type default)
			)
			(layer "F.Fab")
		)
		(fp_line
			(start 0.12065 -0.3048)
			(end 0.67945 -0.3048)
			(stroke
				(width 0.1)
				(type default)
			)
			(layer "F.Fab")
		)
		(fp_line
			(start 0.12065 -0.2794)
			(end 0.12065 -0.3048)
			(stroke
				(width 0.1)
				(type default)
			)
			(layer "F.Fab")
		)
		(fp_line
			(start 0.67945 -0.3048)
			(end 0.67945 0.3048)
			(stroke
				(width 0.1)
				(type default)
			)
			(layer "F.Fab")
		)
		(fp_line
			(start 0.67945 0.3048)
			(end 0.120396 0.3048)
			(stroke
				(width 0.1)
				(type default)
			)
			(layer "F.Fab")
		)
		(pad "1" smd circle
			(at -0.40005 0)
			(size 0 0)
			(layers "F.Cu" "F.Mask" "F.Paste")
			(net "BIC_I2C6_MUX_A2")
		)
		(pad "2" smd circle
			(at 0.40005 0)
			(size 0 0)
			(layers "F.Cu" "F.Mask" "F.Paste")
			(net "GND")
		)
	)
	(footprint ""
		(layer "F.Cu")
		(at 354.130864 -280.44902 -90)
		(property "Reference" "PR157"
			(at 0 0 270)
			(layer "F.SilkS")
			(hide yes)
			(effects
				(font
					(size 1.27 1.27)
				)
			)
		)
		(property "Value" ""
			(at 0 0 270)
			(layer "F.Fab")
			(effects
				(font
					(size 1.27 1.27)
				)
			)
		)
		(duplicate_pad_numbers_are_jumpers no)
		(fp_line
			(start -0.7874 0.4064)
			(end -0.7874 -0.4064)
			(stroke
				(width 0.1524)
				(type default)
			)
			(layer "F.SilkS")
		)
		(fp_line
			(start 0.7874 0.4064)
			(end -0.7874 0.4064)
			(stroke
				(width 0.1524)
				(type default)
			)
			(layer "F.SilkS")
		)
		(fp_line
			(start -0.7874 -0.4064)
			(end 0.7874 -0.4064)
			(stroke
				(width 0.1524)
				(type default)
			)
			(layer "F.SilkS")
		)
		(fp_line
			(start 0.7874 -0.4064)
			(end 0.7874 0.4064)
			(stroke
				(width 0.1524)
				(type default)
			)
			(layer "F.SilkS")
		)
		(fp_line
			(start -0.67945 0.3048)
			(end -0.67945 -0.305054)
			(stroke
				(width 0.1)
				(type default)
			)
			(layer "F.Fab")
		)
		(fp_line
			(start -0.12065 0.3048)
			(end -0.67945 0.3048)
			(stroke
				(width 0.1)
				(type default)
			)
			(layer "F.Fab")
		)
		(fp_line
			(start 0.120396 0.3048)
			(end 0.120396 0.2794)
			(stroke
				(width 0.1)
				(type default)
			)
			(layer "F.Fab")
		)
		(fp_line
			(start 0.67945 0.3048)
			(end 0.120396 0.3048)
			(stroke
				(width 0.1)
				(type default)
			)
			(layer "F.Fab")
		)
		(fp_line
			(start -0.12065 0.2794)
			(end -0.12065 0.3048)
			(stroke
				(width 0.1)
				(type default)
			)
			(layer "F.Fab")
		)
		(fp_line
			(start 0.120396 0.2794)
			(end -0.12065 0.2794)
			(stroke
				(width 0.1)
				(type default)
			)
			(layer "F.Fab")
		)
		(fp_line
			(start -0.12065 -0.2794)
			(end 0.12065 -0.2794)
			(stroke
				(width 0.1)
				(type default)
			)
			(layer "F.Fab")
		)
		(fp_line
			(start 0.12065 -0.2794)
			(end 0.12065 -0.3048)
			(stroke
				(width 0.1)
				(type default)
			)
			(layer "F.Fab")
		)
		(fp_line
			(start 0.12065 -0.3048)
			(end 0.67945 -0.3048)
			(stroke
				(width 0.1)
				(type default)
			)
			(layer "F.Fab")
		)
		(fp_line
			(start 0.67945 -0.3048)
			(end 0.67945 0.3048)
			(stroke
				(width 0.1)
				(type default)
			)
			(layer "F.Fab")
		)
		(fp_line
			(start -0.67945 -0.305054)
			(end -0.12065 -0.305054)
			(stroke
				(width 0.1)
				(type default)
			)
			(layer "F.Fab")
		)
		(fp_line
			(start -0.12065 -0.305054)
			(end -0.12065 -0.2794)
			(stroke
				(width 0.1)
				(type default)
			)
			(layer "F.Fab")
		)
		(pad "1" smd circle
			(at -0.40005 0 270)
			(size 0 0)
			(layers "F.Cu" "F.Mask" "F.Paste")
			(net "SW_P0V8_PEX3_BOOT1")
		)
		(pad "2" smd circle
			(at 0.40005 0 270)
			(size 0 0)
			(layers "F.Cu" "F.Mask" "F.Paste")
			(net "SW_P0V8_PEX3_BOOT1_R")
		)
	)
	(footprint ""
		(layer "F.Cu")
		(at 89.327482 -356.244906 90)
		(property "Reference" "C99"
			(at 0 0 90)
			(layer "F.SilkS")
			(hide yes)
			(effects
				(font
					(size 1.27 1.27)
				)
			)
		)
		(property "Value" ""
			(at 0 0 90)
			(layer "F.Fab")
			(effects
				(font
					(size 1.27 1.27)
				)
			)
		)
		(duplicate_pad_numbers_are_jumpers no)
		(fp_line
			(start 0.299974 -0.150114)
			(end 0.299974 0.150114)
			(stroke
				(width 0.1)
				(type default)
			)
			(layer "F.Fab")
		)
		(fp_line
			(start -0.299974 -0.150114)
			(end 0.299974 -0.150114)
			(stroke
				(width 0.1)
				(type default)
			)
			(layer "F.Fab")
		)
		(fp_line
			(start 0.299974 0.150114)
			(end -0.299974 0.150114)
			(stroke
				(width 0.1)
				(type default)
			)
			(layer "F.Fab")
		)
		(fp_line
			(start -0.299974 0.150114)
			(end -0.299974 -0.150114)
			(stroke
				(width 0.1)
				(type default)
			)
			(layer "F.Fab")
		)
		(pad "1" smd rect
			(at -0.2667 0 90)
			(size 0.3048 0.381)
			(layers "F.Cu" "F.Mask" "F.Paste")
			(net "P5E_PEX0_STN5_TX_DP<94>")
		)
		(pad "2" smd rect
			(at 0.2667 0 90)
			(size 0.3048 0.381)
			(layers "F.Cu" "F.Mask" "F.Paste")
			(net "P5E_PEX0_STN5_TX_C_DP<94>")
		)
	)
	(footprint ""
		(layer "F.Cu")
		(at 41.069768 -343.952322 90)
		(property "Reference" "C172"
			(at 0 0 90)
			(layer "F.SilkS")
			(hide yes)
			(effects
				(font
					(size 1.27 1.27)
				)
			)
		)
		(property "Value" ""
			(at 0 0 90)
			(layer "F.Fab")
			(effects
				(font
					(size 1.27 1.27)
				)
			)
		)
		(duplicate_pad_numbers_are_jumpers no)
		(fp_line
			(start 0.299974 -0.150114)
			(end 0.299974 0.150114)
			(stroke
				(width 0.1)
				(type default)
			)
			(layer "F.Fab")
		)
		(fp_line
			(start -0.299974 -0.150114)
			(end 0.299974 -0.150114)
			(stroke
				(width 0.1)
				(type default)
			)
			(layer "F.Fab")
		)
		(fp_line
			(start 0.299974 0.150114)
			(end -0.299974 0.150114)
			(stroke
				(width 0.1)
				(type default)
			)
			(layer "F.Fab")
		)
		(fp_line
			(start -0.299974 0.150114)
			(end -0.299974 -0.150114)
			(stroke
				(width 0.1)
				(type default)
			)
			(layer "F.Fab")
		)
		(pad "1" smd rect
			(at -0.2667 0 90)
			(size 0.3048 0.381)
			(layers "F.Cu" "F.Mask" "F.Paste")
			(net "P5E_PEX0_STN7_TX_DN<122>")
		)
		(pad "2" smd rect
			(at 0.2667 0 90)
			(size 0.3048 0.381)
			(layers "F.Cu" "F.Mask" "F.Paste")
			(net "P5E_PEX0_STN7_TX_C_DN<122>")
		)
	)
	(footprint ""
		(layer "F.Cu")
		(at 289.594036 -29.507688 -90)
		(property "Reference" "PC951"
			(at 0 0 270)
			(layer "F.SilkS")
			(hide yes)
			(effects
				(font
					(size 1.27 1.27)
				)
			)
		)
		(property "Value" ""
			(at 0 0 270)
			(layer "F.Fab")
			(effects
				(font
					(size 1.27 1.27)
				)
			)
		)
		(duplicate_pad_numbers_are_jumpers no)
		(fp_line
			(start -1.524 0.762)
			(end -1.524 -0.762)
			(stroke
				(width 0.1524)
				(type default)
			)
			(layer "F.SilkS")
		)
		(fp_line
			(start 1.524 0.762)
			(end -1.524 0.762)
			(stroke
				(width 0.1524)
				(type default)
			)
			(layer "F.SilkS")
		)
		(fp_line
			(start -1.524 -0.762)
			(end 1.524 -0.762)
			(stroke
				(width 0.1524)
				(type default)
			)
			(layer "F.SilkS")
		)
		(fp_line
			(start 1.524 -0.762)
			(end 1.524 0.762)
			(stroke
				(width 0.1524)
				(type default)
			)
			(layer "F.SilkS")
		)
		(fp_line
			(start -1.1049 0.724916)
			(end 1.1049 0.724916)
			(stroke
				(width 0.1)
				(type default)
			)
			(layer "F.Fab")
		)
		(fp_line
			(start 1.1049 0.724916)
			(end 1.1049 -0.724916)
			(stroke
				(width 0.1)
				(type default)
			)
			(layer "F.Fab")
		)
		(fp_line
			(start -1.1049 -0.724916)
			(end -1.1049 0.724916)
			(stroke
				(width 0.1)
				(type default)
			)
			(layer "F.Fab")
		)
		(fp_line
			(start 1.1049 -0.724916)
			(end -1.1049 -0.724916)
			(stroke
				(width 0.1)
				(type default)
			)
			(layer "F.Fab")
		)
		(pad "1" smd rect
			(at -0.889 0 90)
			(size 1.016 1.27)
			(layers "F.Cu" "F.Mask" "F.Paste")
			(net "P3V3_SSD10")
		)
		(pad "2" smd rect
			(at 0.889 0 90)
			(size 1.016 1.27)
			(layers "F.Cu" "F.Mask" "F.Paste")
			(net "GND")
		)
	)
	(footprint ""
		(layer "F.Cu")
		(at 389.81634 -343.952322 90)
		(property "Reference" "C744"
			(at 0 0 90)
			(layer "F.SilkS")
			(hide yes)
			(effects
				(font
					(size 1.27 1.27)
				)
			)
		)
		(property "Value" ""
			(at 0 0 90)
			(layer "F.Fab")
			(effects
				(font
					(size 1.27 1.27)
				)
			)
		)
		(duplicate_pad_numbers_are_jumpers no)
		(fp_line
			(start 0.299974 -0.150114)
			(end 0.299974 0.150114)
			(stroke
				(width 0.1)
				(type default)
			)
			(layer "F.Fab")
		)
		(fp_line
			(start -0.299974 -0.150114)
			(end 0.299974 -0.150114)
			(stroke
				(width 0.1)
				(type default)
			)
			(layer "F.Fab")
		)
		(fp_line
			(start 0.299974 0.150114)
			(end -0.299974 0.150114)
			(stroke
				(width 0.1)
				(type default)
			)
			(layer "F.Fab")
		)
		(fp_line
			(start -0.299974 0.150114)
			(end -0.299974 -0.150114)
			(stroke
				(width 0.1)
				(type default)
			)
			(layer "F.Fab")
		)
		(pad "1" smd rect
			(at -0.2667 0 90)
			(size 0.3048 0.381)
			(layers "F.Cu" "F.Mask" "F.Paste")
			(net "P5E_PEX3_STN5_TX_DP<88>")
		)
		(pad "2" smd rect
			(at 0.2667 0 90)
			(size 0.3048 0.381)
			(layers "F.Cu" "F.Mask" "F.Paste")
			(net "P5E_PEX3_STN5_TX_C_DP<88>")
		)
	)
	(footprint ""
		(layer "F.Cu")
		(at 336.042 -163.83 180)
		(property "Reference" "R4807"
			(at 0 0 180)
			(layer "F.SilkS")
			(hide yes)
			(effects
				(font
					(size 1.27 1.27)
				)
			)
		)
		(property "Value" ""
			(at 0 0 180)
			(layer "F.Fab")
			(effects
				(font
					(size 1.27 1.27)
				)
			)
		)
		(duplicate_pad_numbers_are_jumpers no)
		(fp_line
			(start 0.7874 0.4064)
			(end -0.7874 0.4064)
			(stroke
				(width 0.1524)
				(type default)
			)
			(layer "F.SilkS")
		)
		(fp_line
			(start 0.7874 -0.4064)
			(end 0.7874 0.4064)
			(stroke
				(width 0.1524)
				(type default)
			)
			(layer "F.SilkS")
		)
		(fp_line
			(start -0.7874 0.4064)
			(end -0.7874 -0.4064)
			(stroke
				(width 0.1524)
				(type default)
			)
			(layer "F.SilkS")
		)
		(fp_line
			(start -0.7874 -0.4064)
			(end 0.7874 -0.4064)
			(stroke
				(width 0.1524)
				(type default)
			)
			(layer "F.SilkS")
		)
		(fp_line
			(start 0.67945 0.3048)
			(end 0.120396 0.3048)
			(stroke
				(width 0.1)
				(type default)
			)
			(layer "F.Fab")
		)
		(fp_line
			(start 0.67945 -0.3048)
			(end 0.67945 0.3048)
			(stroke
				(width 0.1)
				(type default)
			)
			(layer "F.Fab")
		)
		(fp_line
			(start 0.12065 -0.2794)
			(end 0.12065 -0.3048)
			(stroke
				(width 0.1)
				(type default)
			)
			(layer "F.Fab")
		)
		(fp_line
			(start 0.12065 -0.3048)
			(end 0.67945 -0.3048)
			(stroke
				(width 0.1)
				(type default)
			)
			(layer "F.Fab")
		)
		(fp_line
			(start 0.120396 0.3048)
			(end 0.120396 0.2794)
			(stroke
				(width 0.1)
				(type default)
			)
			(layer "F.Fab")
		)
		(fp_line
			(start 0.120396 0.2794)
			(end -0.12065 0.2794)
			(stroke
				(width 0.1)
				(type default)
			)
			(layer "F.Fab")
		)
		(fp_line
			(start -0.12065 0.3048)
			(end -0.67945 0.3048)
			(stroke
				(width 0.1)
				(type default)
			)
			(layer "F.Fab")
		)
		(fp_line
			(start -0.12065 0.2794)
			(end -0.12065 0.3048)
			(stroke
				(width 0.1)
				(type default)
			)
			(layer "F.Fab")
		)
		(fp_line
			(start -0.12065 -0.2794)
			(end 0.12065 -0.2794)
			(stroke
				(width 0.1)
				(type default)
			)
			(layer "F.Fab")
		)
		(fp_line
			(start -0.12065 -0.305054)
			(end -0.12065 -0.2794)
			(stroke
				(width 0.1)
				(type default)
			)
			(layer "F.Fab")
		)
		(fp_line
			(start -0.67945 0.3048)
			(end -0.67945 -0.305054)
			(stroke
				(width 0.1)
				(type default)
			)
			(layer "F.Fab")
		)
		(fp_line
			(start -0.67945 -0.305054)
			(end -0.12065 -0.305054)
			(stroke
				(width 0.1)
				(type default)
			)
			(layer "F.Fab")
		)
		(pad "1" smd circle
			(at -0.40005 0 180)
			(size 0 0)
			(layers "F.Cu" "F.Mask" "F.Paste")
			(net "PEX3_PCA9555_INT_R_N")
		)
		(pad "2" smd circle
			(at 0.40005 0 180)
			(size 0 0)
			(layers "F.Cu" "F.Mask" "F.Paste")
			(net "PEX3_PCA9555_INT_N")
		)
	)
	(footprint ""
		(layer "F.Cu")
		(at 387.580632 -102.888796)
		(property "Reference" "C692"
			(at 0 0 0)
			(layer "F.SilkS")
			(hide yes)
			(effects
				(font
					(size 1.27 1.27)
				)
			)
		)
		(property "Value" ""
			(at 0 0 0)
			(layer "F.Fab")
			(effects
				(font
					(size 1.27 1.27)
				)
			)
		)
		(duplicate_pad_numbers_are_jumpers no)
		(fp_line
			(start -0.299974 -0.150114)
			(end 0.299974 -0.150114)
			(stroke
				(width 0.1)
				(type default)
			)
			(layer "F.Fab")
		)
		(fp_line
			(start -0.299974 0.150114)
			(end -0.299974 -0.150114)
			(stroke
				(width 0.1)
				(type default)
			)
			(layer "F.Fab")
		)
		(fp_line
			(start 0.299974 -0.150114)
			(end 0.299974 0.150114)
			(stroke
				(width 0.1)
				(type default)
			)
			(layer "F.Fab")
		)
		(fp_line
			(start 0.299974 0.150114)
			(end -0.299974 0.150114)
			(stroke
				(width 0.1)
				(type default)
			)
			(layer "F.Fab")
		)
		(pad "1" smd rect
			(at -0.2667 0)
			(size 0.3048 0.381)
			(layers "F.Cu" "F.Mask" "F.Paste")
			(net "P5E_PEX3_STN1_TX_DP<18>")
		)
		(pad "2" smd rect
			(at 0.2667 0)
			(size 0.3048 0.381)
			(layers "F.Cu" "F.Mask" "F.Paste")
			(net "P5E_PEX3_STN1_TX_C_DP<18>")
		)
	)
	(footprint ""
		(layer "F.Cu")
		(at 132.41274 -118.378986 90)
		(property "Reference" "PC790"
			(at 0 0 90)
			(layer "F.SilkS")
			(hide yes)
			(effects
				(font
					(size 1.27 1.27)
				)
			)
		)
		(property "Value" ""
			(at 0 0 90)
			(layer "F.Fab")
			(effects
				(font
					(size 1.27 1.27)
				)
			)
		)
		(duplicate_pad_numbers_are_jumpers no)
		(fp_line
			(start 0.7874 -0.4064)
			(end 0.7874 0.4064)
			(stroke
				(width 0.1524)
				(type default)
			)
			(layer "F.SilkS")
		)
		(fp_line
			(start -0.7874 -0.4064)
			(end 0.7874 -0.4064)
			(stroke
				(width 0.1524)
				(type default)
			)
			(layer "F.SilkS")
		)
		(fp_line
			(start 0.7874 0.4064)
			(end -0.7874 0.4064)
			(stroke
				(width 0.1524)
				(type default)
			)
			(layer "F.SilkS")
		)
		(fp_line
			(start -0.7874 0.4064)
			(end -0.7874 -0.4064)
			(stroke
				(width 0.1524)
				(type default)
			)
			(layer "F.SilkS")
		)
		(fp_line
			(start -0.12065 -0.305054)
			(end -0.12065 -0.2794)
			(stroke
				(width 0.1)
				(type default)
			)
			(layer "F.Fab")
		)
		(fp_line
			(start -0.67945 -0.305054)
			(end -0.12065 -0.305054)
			(stroke
				(width 0.1)
				(type default)
			)
			(layer "F.Fab")
		)
		(fp_line
			(start 0.67945 -0.3048)
			(end 0.67945 0.3048)
			(stroke
				(width 0.1)
				(type default)
			)
			(layer "F.Fab")
		)
		(fp_line
			(start 0.12065 -0.3048)
			(end 0.67945 -0.3048)
			(stroke
				(width 0.1)
				(type default)
			)
			(layer "F.Fab")
		)
		(fp_line
			(start 0.12065 -0.2794)
			(end 0.12065 -0.3048)
			(stroke
				(width 0.1)
				(type default)
			)
			(layer "F.Fab")
		)
		(fp_line
			(start -0.12065 -0.2794)
			(end 0.12065 -0.2794)
			(stroke
				(width 0.1)
				(type default)
			)
			(layer "F.Fab")
		)
		(fp_line
			(start 0.120396 0.2794)
			(end -0.12065 0.2794)
			(stroke
				(width 0.1)
				(type default)
			)
			(layer "F.Fab")
		)
		(fp_line
			(start -0.12065 0.2794)
			(end -0.12065 0.3048)
			(stroke
				(width 0.1)
				(type default)
			)
			(layer "F.Fab")
		)
		(fp_line
			(start 0.67945 0.3048)
			(end 0.120396 0.3048)
			(stroke
				(width 0.1)
				(type default)
			)
			(layer "F.Fab")
		)
		(fp_line
			(start 0.120396 0.3048)
			(end 0.120396 0.2794)
			(stroke
				(width 0.1)
				(type default)
			)
			(layer "F.Fab")
		)
		(fp_line
			(start -0.12065 0.3048)
			(end -0.67945 0.3048)
			(stroke
				(width 0.1)
				(type default)
			)
			(layer "F.Fab")
		)
		(fp_line
			(start -0.67945 0.3048)
			(end -0.67945 -0.305054)
			(stroke
				(width 0.1)
				(type default)
			)
			(layer "F.Fab")
		)
		(pad "1" smd circle
			(at -0.40005 0 90)
			(size 0 0)
			(layers "F.Cu" "F.Mask" "F.Paste")
			(net "P3V3_NIC2_CO_GATE")
		)
		(pad "2" smd circle
			(at 0.40005 0 90)
			(size 0 0)
			(layers "F.Cu" "F.Mask" "F.Paste")
			(net "GND")
		)
	)
	(footprint ""
		(layer "F.Cu")
		(at 232.409746 -121.778268 180)
		(property "Reference" "PR6888"
			(at 0 0 180)
			(layer "F.SilkS")
			(hide yes)
			(effects
				(font
					(size 1.27 1.27)
				)
			)
		)
		(property "Value" ""
			(at 0 0 180)
			(layer "F.Fab")
			(effects
				(font
					(size 1.27 1.27)
				)
			)
		)
		(duplicate_pad_numbers_are_jumpers no)
		(fp_line
			(start 0.7874 0.4064)
			(end -0.7874 0.4064)
			(stroke
				(width 0.1524)
				(type default)
			)
			(layer "F.SilkS")
		)
		(fp_line
			(start 0.7874 -0.4064)
			(end 0.7874 0.4064)
			(stroke
				(width 0.1524)
				(type default)
			)
			(layer "F.SilkS")
		)
		(fp_line
			(start -0.7874 0.4064)
			(end -0.7874 -0.4064)
			(stroke
				(width 0.1524)
				(type default)
			)
			(layer "F.SilkS")
		)
		(fp_line
			(start -0.7874 -0.4064)
			(end 0.7874 -0.4064)
			(stroke
				(width 0.1524)
				(type default)
			)
			(layer "F.SilkS")
		)
		(fp_line
			(start 0.67945 0.3048)
			(end 0.120396 0.3048)
			(stroke
				(width 0.1)
				(type default)
			)
			(layer "F.Fab")
		)
		(fp_line
			(start 0.67945 -0.3048)
			(end 0.67945 0.3048)
			(stroke
				(width 0.1)
				(type default)
			)
			(layer "F.Fab")
		)
		(fp_line
			(start 0.12065 -0.2794)
			(end 0.12065 -0.3048)
			(stroke
				(width 0.1)
				(type default)
			)
			(layer "F.Fab")
		)
		(fp_line
			(start 0.12065 -0.3048)
			(end 0.67945 -0.3048)
			(stroke
				(width 0.1)
				(type default)
			)
			(layer "F.Fab")
		)
		(fp_line
			(start 0.120396 0.3048)
			(end 0.120396 0.2794)
			(stroke
				(width 0.1)
				(type default)
			)
			(layer "F.Fab")
		)
		(fp_line
			(start 0.120396 0.2794)
			(end -0.12065 0.2794)
			(stroke
				(width 0.1)
				(type default)
			)
			(layer "F.Fab")
		)
		(fp_line
			(start -0.12065 0.3048)
			(end -0.67945 0.3048)
			(stroke
				(width 0.1)
				(type default)
			)
			(layer "F.Fab")
		)
		(fp_line
			(start -0.12065 0.2794)
			(end -0.12065 0.3048)
			(stroke
				(width 0.1)
				(type default)
			)
			(layer "F.Fab")
		)
		(fp_line
			(start -0.12065 -0.2794)
			(end 0.12065 -0.2794)
			(stroke
				(width 0.1)
				(type default)
			)
			(layer "F.Fab")
		)
		(fp_line
			(start -0.12065 -0.305054)
			(end -0.12065 -0.2794)
			(stroke
				(width 0.1)
				(type default)
			)
			(layer "F.Fab")
		)
		(fp_line
			(start -0.67945 0.3048)
			(end -0.67945 -0.305054)
			(stroke
				(width 0.1)
				(type default)
			)
			(layer "F.Fab")
		)
		(fp_line
			(start -0.67945 -0.305054)
			(end -0.12065 -0.305054)
			(stroke
				(width 0.1)
				(type default)
			)
			(layer "F.Fab")
		)
		(pad "1" smd circle
			(at -0.40005 0 180)
			(size 0 0)
			(layers "F.Cu" "F.Mask" "F.Paste")
			(net "P12V_NIC3_CO_OV_FB")
		)
		(pad "2" smd circle
			(at 0.40005 0 180)
			(size 0 0)
			(layers "F.Cu" "F.Mask" "F.Paste")
			(net "P12V_NIC3_R")
		)
	)
	(footprint ""
		(layer "F.Cu")
		(at 336.042 -149.987 180)
		(property "Reference" "R4828"
			(at 0 0 180)
			(layer "F.SilkS")
			(hide yes)
			(effects
				(font
					(size 1.27 1.27)
				)
			)
		)
		(property "Value" ""
			(at 0 0 180)
			(layer "F.Fab")
			(effects
				(font
					(size 1.27 1.27)
				)
			)
		)
		(duplicate_pad_numbers_are_jumpers no)
		(fp_line
			(start 0.7874 0.4064)
			(end -0.7874 0.4064)
			(stroke
				(width 0.1524)
				(type default)
			)
			(layer "F.SilkS")
		)
		(fp_line
			(start 0.7874 -0.4064)
			(end 0.7874 0.4064)
			(stroke
				(width 0.1524)
				(type default)
			)
			(layer "F.SilkS")
		)
		(fp_line
			(start -0.7874 0.4064)
			(end -0.7874 -0.4064)
			(stroke
				(width 0.1524)
				(type default)
			)
			(layer "F.SilkS")
		)
		(fp_line
			(start -0.7874 -0.4064)
			(end 0.7874 -0.4064)
			(stroke
				(width 0.1524)
				(type default)
			)
			(layer "F.SilkS")
		)
		(fp_line
			(start 0.67945 0.3048)
			(end 0.120396 0.3048)
			(stroke
				(width 0.1)
				(type default)
			)
			(layer "F.Fab")
		)
		(fp_line
			(start 0.67945 -0.3048)
			(end 0.67945 0.3048)
			(stroke
				(width 0.1)
				(type default)
			)
			(layer "F.Fab")
		)
		(fp_line
			(start 0.12065 -0.2794)
			(end 0.12065 -0.3048)
			(stroke
				(width 0.1)
				(type default)
			)
			(layer "F.Fab")
		)
		(fp_line
			(start 0.12065 -0.3048)
			(end 0.67945 -0.3048)
			(stroke
				(width 0.1)
				(type default)
			)
			(layer "F.Fab")
		)
		(fp_line
			(start 0.120396 0.3048)
			(end 0.120396 0.2794)
			(stroke
				(width 0.1)
				(type default)
			)
			(layer "F.Fab")
		)
		(fp_line
			(start 0.120396 0.2794)
			(end -0.12065 0.2794)
			(stroke
				(width 0.1)
				(type default)
			)
			(layer "F.Fab")
		)
		(fp_line
			(start -0.12065 0.3048)
			(end -0.67945 0.3048)
			(stroke
				(width 0.1)
				(type default)
			)
			(layer "F.Fab")
		)
		(fp_line
			(start -0.12065 0.2794)
			(end -0.12065 0.3048)
			(stroke
				(width 0.1)
				(type default)
			)
			(layer "F.Fab")
		)
		(fp_line
			(start -0.12065 -0.2794)
			(end 0.12065 -0.2794)
			(stroke
				(width 0.1)
				(type default)
			)
			(layer "F.Fab")
		)
		(fp_line
			(start -0.12065 -0.305054)
			(end -0.12065 -0.2794)
			(stroke
				(width 0.1)
				(type default)
			)
			(layer "F.Fab")
		)
		(fp_line
			(start -0.67945 0.3048)
			(end -0.67945 -0.305054)
			(stroke
				(width 0.1)
				(type default)
			)
			(layer "F.Fab")
		)
		(fp_line
			(start -0.67945 -0.305054)
			(end -0.12065 -0.305054)
			(stroke
				(width 0.1)
				(type default)
			)
			(layer "F.Fab")
		)
		(pad "1" smd circle
			(at -0.40005 0 180)
			(size 0 0)
			(layers "F.Cu" "F.Mask" "F.Paste")
			(net "PCA9555_1_PEX3_A1")
		)
		(pad "2" smd circle
			(at 0.40005 0 180)
			(size 0 0)
			(layers "F.Cu" "F.Mask" "F.Paste")
			(net "P3V3_AUX")
		)
	)
	(footprint ""
		(layer "F.Cu")
		(at 335.154524 -343.952322 90)
		(property "Reference" "C530"
			(at 0 0 90)
			(layer "F.SilkS")
			(hide yes)
			(effects
				(font
					(size 1.27 1.27)
				)
			)
		)
		(property "Value" ""
			(at 0 0 90)
			(layer "F.Fab")
			(effects
				(font
					(size 1.27 1.27)
				)
			)
		)
		(duplicate_pad_numbers_are_jumpers no)
		(fp_line
			(start 0.299974 -0.150114)
			(end 0.299974 0.150114)
			(stroke
				(width 0.1)
				(type default)
			)
			(layer "F.Fab")
		)
		(fp_line
			(start -0.299974 -0.150114)
			(end 0.299974 -0.150114)
			(stroke
				(width 0.1)
				(type default)
			)
			(layer "F.Fab")
		)
		(fp_line
			(start 0.299974 0.150114)
			(end -0.299974 0.150114)
			(stroke
				(width 0.1)
				(type default)
			)
			(layer "F.Fab")
		)
		(fp_line
			(start -0.299974 0.150114)
			(end -0.299974 -0.150114)
			(stroke
				(width 0.1)
				(type default)
			)
			(layer "F.Fab")
		)
		(pad "1" smd rect
			(at -0.2667 0 90)
			(size 0.3048 0.381)
			(layers "F.Cu" "F.Mask" "F.Paste")
			(net "P5E_PEX2_STN5_TX_DN<90>")
		)
		(pad "2" smd rect
			(at 0.2667 0 90)
			(size 0.3048 0.381)
			(layers "F.Cu" "F.Mask" "F.Paste")
			(net "P5E_PEX2_STN5_TX_C_DN<90>")
		)
	)
	(footprint ""
		(layer "F.Cu")
		(at 419.05301 -221.32163 180)
		(property "Reference" "R6615"
			(at 0 0 180)
			(layer "F.SilkS")
			(hide yes)
			(effects
				(font
					(size 1.27 1.27)
				)
			)
		)
		(property "Value" ""
			(at 0 0 180)
			(layer "F.Fab")
			(effects
				(font
					(size 1.27 1.27)
				)
			)
		)
		(duplicate_pad_numbers_are_jumpers no)
		(fp_line
			(start 0.7874 0.4064)
			(end -0.7874 0.4064)
			(stroke
				(width 0.1524)
				(type default)
			)
			(layer "F.SilkS")
		)
		(fp_line
			(start 0.7874 -0.4064)
			(end 0.7874 0.4064)
			(stroke
				(width 0.1524)
				(type default)
			)
			(layer "F.SilkS")
		)
		(fp_line
			(start -0.7874 0.4064)
			(end -0.7874 -0.4064)
			(stroke
				(width 0.1524)
				(type default)
			)
			(layer "F.SilkS")
		)
		(fp_line
			(start -0.7874 -0.4064)
			(end 0.7874 -0.4064)
			(stroke
				(width 0.1524)
				(type default)
			)
			(layer "F.SilkS")
		)
		(fp_line
			(start 0.67945 0.3048)
			(end 0.120396 0.3048)
			(stroke
				(width 0.1)
				(type default)
			)
			(layer "F.Fab")
		)
		(fp_line
			(start 0.67945 -0.3048)
			(end 0.67945 0.3048)
			(stroke
				(width 0.1)
				(type default)
			)
			(layer "F.Fab")
		)
		(fp_line
			(start 0.12065 -0.2794)
			(end 0.12065 -0.3048)
			(stroke
				(width 0.1)
				(type default)
			)
			(layer "F.Fab")
		)
		(fp_line
			(start 0.12065 -0.3048)
			(end 0.67945 -0.3048)
			(stroke
				(width 0.1)
				(type default)
			)
			(layer "F.Fab")
		)
		(fp_line
			(start 0.120396 0.3048)
			(end 0.120396 0.2794)
			(stroke
				(width 0.1)
				(type default)
			)
			(layer "F.Fab")
		)
		(fp_line
			(start 0.120396 0.2794)
			(end -0.12065 0.2794)
			(stroke
				(width 0.1)
				(type default)
			)
			(layer "F.Fab")
		)
		(fp_line
			(start -0.12065 0.3048)
			(end -0.67945 0.3048)
			(stroke
				(width 0.1)
				(type default)
			)
			(layer "F.Fab")
		)
		(fp_line
			(start -0.12065 0.2794)
			(end -0.12065 0.3048)
			(stroke
				(width 0.1)
				(type default)
			)
			(layer "F.Fab")
		)
		(fp_line
			(start -0.12065 -0.2794)
			(end 0.12065 -0.2794)
			(stroke
				(width 0.1)
				(type default)
			)
			(layer "F.Fab")
		)
		(fp_line
			(start -0.12065 -0.305054)
			(end -0.12065 -0.2794)
			(stroke
				(width 0.1)
				(type default)
			)
			(layer "F.Fab")
		)
		(fp_line
			(start -0.67945 0.3048)
			(end -0.67945 -0.305054)
			(stroke
				(width 0.1)
				(type default)
			)
			(layer "F.Fab")
		)
		(fp_line
			(start -0.67945 -0.305054)
			(end -0.12065 -0.305054)
			(stroke
				(width 0.1)
				(type default)
			)
			(layer "F.Fab")
		)
		(pad "1" smd circle
			(at -0.40005 0 180)
			(size 0 0)
			(layers "F.Cu" "F.Mask" "F.Paste")
			(net "UART_PEX0_SDB_R_RX")
		)
		(pad "2" smd circle
			(at 0.40005 0 180)
			(size 0 0)
			(layers "F.Cu" "F.Mask" "F.Paste")
			(net "UART_PEX0_SDB_R1_RX")
		)
	)
	(footprint ""
		(layer "F.Cu")
		(at 271.480534 -103.803196)
		(property "Reference" "C482"
			(at 0 0 0)
			(layer "F.SilkS")
			(hide yes)
			(effects
				(font
					(size 1.27 1.27)
				)
			)
		)
		(property "Value" ""
			(at 0 0 0)
			(layer "F.Fab")
			(effects
				(font
					(size 1.27 1.27)
				)
			)
		)
		(duplicate_pad_numbers_are_jumpers no)
		(fp_line
			(start -0.299974 -0.150114)
			(end 0.299974 -0.150114)
			(stroke
				(width 0.1)
				(type default)
			)
			(layer "F.Fab")
		)
		(fp_line
			(start -0.299974 0.150114)
			(end -0.299974 -0.150114)
			(stroke
				(width 0.1)
				(type default)
			)
			(layer "F.Fab")
		)
		(fp_line
			(start 0.299974 -0.150114)
			(end 0.299974 0.150114)
			(stroke
				(width 0.1)
				(type default)
			)
			(layer "F.Fab")
		)
		(fp_line
			(start 0.299974 0.150114)
			(end -0.299974 0.150114)
			(stroke
				(width 0.1)
				(type default)
			)
			(layer "F.Fab")
		)
		(pad "1" smd rect
			(at -0.2667 0)
			(size 0.3048 0.381)
			(layers "F.Cu" "F.Mask" "F.Paste")
			(net "P5E_PEX2_STN1_TX_DN<18>")
		)
		(pad "2" smd rect
			(at 0.2667 0)
			(size 0.3048 0.381)
			(layers "F.Cu" "F.Mask" "F.Paste")
			(net "P5E_PEX2_STN1_TX_C_DN<18>")
		)
	)
	(footprint ""
		(layer "F.Cu")
		(at 336.042 -184.023 180)
		(property "Reference" "R4746"
			(at 0 0 180)
			(layer "F.SilkS")
			(hide yes)
			(effects
				(font
					(size 1.27 1.27)
				)
			)
		)
		(property "Value" ""
			(at 0 0 180)
			(layer "F.Fab")
			(effects
				(font
					(size 1.27 1.27)
				)
			)
		)
		(duplicate_pad_numbers_are_jumpers no)
		(fp_line
			(start 0.7874 0.4064)
			(end -0.7874 0.4064)
			(stroke
				(width 0.1524)
				(type default)
			)
			(layer "F.SilkS")
		)
		(fp_line
			(start 0.7874 -0.4064)
			(end 0.7874 0.4064)
			(stroke
				(width 0.1524)
				(type default)
			)
			(layer "F.SilkS")
		)
		(fp_line
			(start -0.7874 0.4064)
			(end -0.7874 -0.4064)
			(stroke
				(width 0.1524)
				(type default)
			)
			(layer "F.SilkS")
		)
		(fp_line
			(start -0.7874 -0.4064)
			(end 0.7874 -0.4064)
			(stroke
				(width 0.1524)
				(type default)
			)
			(layer "F.SilkS")
		)
		(fp_line
			(start 0.67945 0.3048)
			(end 0.120396 0.3048)
			(stroke
				(width 0.1)
				(type default)
			)
			(layer "F.Fab")
		)
		(fp_line
			(start 0.67945 -0.3048)
			(end 0.67945 0.3048)
			(stroke
				(width 0.1)
				(type default)
			)
			(layer "F.Fab")
		)
		(fp_line
			(start 0.12065 -0.2794)
			(end 0.12065 -0.3048)
			(stroke
				(width 0.1)
				(type default)
			)
			(layer "F.Fab")
		)
		(fp_line
			(start 0.12065 -0.3048)
			(end 0.67945 -0.3048)
			(stroke
				(width 0.1)
				(type default)
			)
			(layer "F.Fab")
		)
		(fp_line
			(start 0.120396 0.3048)
			(end 0.120396 0.2794)
			(stroke
				(width 0.1)
				(type default)
			)
			(layer "F.Fab")
		)
		(fp_line
			(start 0.120396 0.2794)
			(end -0.12065 0.2794)
			(stroke
				(width 0.1)
				(type default)
			)
			(layer "F.Fab")
		)
		(fp_line
			(start -0.12065 0.3048)
			(end -0.67945 0.3048)
			(stroke
				(width 0.1)
				(type default)
			)
			(layer "F.Fab")
		)
		(fp_line
			(start -0.12065 0.2794)
			(end -0.12065 0.3048)
			(stroke
				(width 0.1)
				(type default)
			)
			(layer "F.Fab")
		)
		(fp_line
			(start -0.12065 -0.2794)
			(end 0.12065 -0.2794)
			(stroke
				(width 0.1)
				(type default)
			)
			(layer "F.Fab")
		)
		(fp_line
			(start -0.12065 -0.305054)
			(end -0.12065 -0.2794)
			(stroke
				(width 0.1)
				(type default)
			)
			(layer "F.Fab")
		)
		(fp_line
			(start -0.67945 0.3048)
			(end -0.67945 -0.305054)
			(stroke
				(width 0.1)
				(type default)
			)
			(layer "F.Fab")
		)
		(fp_line
			(start -0.67945 -0.305054)
			(end -0.12065 -0.305054)
			(stroke
				(width 0.1)
				(type default)
			)
			(layer "F.Fab")
		)
		(pad "1" smd circle
			(at -0.40005 0 180)
			(size 0 0)
			(layers "F.Cu" "F.Mask" "F.Paste")
			(net "PCA9555_0_PEX2_A2")
		)
		(pad "2" smd circle
			(at 0.40005 0 180)
			(size 0 0)
			(layers "F.Cu" "F.Mask" "F.Paste")
			(net "P3V3_AUX")
		)
	)
	(footprint ""
		(layer "F.Cu")
		(at 457.817728 -258.331208 -90)
		(property "Reference" "R6555"
			(at 0 0 270)
			(layer "F.SilkS")
			(hide yes)
			(effects
				(font
					(size 1.27 1.27)
				)
			)
		)
		(property "Value" ""
			(at 0 0 270)
			(layer "F.Fab")
			(effects
				(font
					(size 1.27 1.27)
				)
			)
		)
		(duplicate_pad_numbers_are_jumpers no)
		(fp_line
			(start -0.7874 0.4064)
			(end -0.7874 -0.4064)
			(stroke
				(width 0.1524)
				(type default)
			)
			(layer "F.SilkS")
		)
		(fp_line
			(start 0.7874 0.4064)
			(end -0.7874 0.4064)
			(stroke
				(width 0.1524)
				(type default)
			)
			(layer "F.SilkS")
		)
		(fp_line
			(start -0.7874 -0.4064)
			(end 0.7874 -0.4064)
			(stroke
				(width 0.1524)
				(type default)
			)
			(layer "F.SilkS")
		)
		(fp_line
			(start 0.7874 -0.4064)
			(end 0.7874 0.4064)
			(stroke
				(width 0.1524)
				(type default)
			)
			(layer "F.SilkS")
		)
		(fp_line
			(start -0.67945 0.3048)
			(end -0.67945 -0.305054)
			(stroke
				(width 0.1)
				(type default)
			)
			(layer "F.Fab")
		)
		(fp_line
			(start -0.12065 0.3048)
			(end -0.67945 0.3048)
			(stroke
				(width 0.1)
				(type default)
			)
			(layer "F.Fab")
		)
		(fp_line
			(start 0.120396 0.3048)
			(end 0.120396 0.2794)
			(stroke
				(width 0.1)
				(type default)
			)
			(layer "F.Fab")
		)
		(fp_line
			(start 0.67945 0.3048)
			(end 0.120396 0.3048)
			(stroke
				(width 0.1)
				(type default)
			)
			(layer "F.Fab")
		)
		(fp_line
			(start -0.12065 0.2794)
			(end -0.12065 0.3048)
			(stroke
				(width 0.1)
				(type default)
			)
			(layer "F.Fab")
		)
		(fp_line
			(start 0.120396 0.2794)
			(end -0.12065 0.2794)
			(stroke
				(width 0.1)
				(type default)
			)
			(layer "F.Fab")
		)
		(fp_line
			(start -0.12065 -0.2794)
			(end 0.12065 -0.2794)
			(stroke
				(width 0.1)
				(type default)
			)
			(layer "F.Fab")
		)
		(fp_line
			(start 0.12065 -0.2794)
			(end 0.12065 -0.3048)
			(stroke
				(width 0.1)
				(type default)
			)
			(layer "F.Fab")
		)
		(fp_line
			(start 0.12065 -0.3048)
			(end 0.67945 -0.3048)
			(stroke
				(width 0.1)
				(type default)
			)
			(layer "F.Fab")
		)
		(fp_line
			(start 0.67945 -0.3048)
			(end 0.67945 0.3048)
			(stroke
				(width 0.1)
				(type default)
			)
			(layer "F.Fab")
		)
		(fp_line
			(start -0.67945 -0.305054)
			(end -0.12065 -0.305054)
			(stroke
				(width 0.1)
				(type default)
			)
			(layer "F.Fab")
		)
		(fp_line
			(start -0.12065 -0.305054)
			(end -0.12065 -0.2794)
			(stroke
				(width 0.1)
				(type default)
			)
			(layer "F.Fab")
		)
		(pad "1" smd circle
			(at -0.40005 0 270)
			(size 0 0)
			(layers "F.Cu" "F.Mask" "F.Paste")
			(net "P1V25_SERDES_VDDPLL_PEX3")
		)
		(pad "2" smd circle
			(at 0.40005 0 270)
			(size 0 0)
			(layers "F.Cu" "F.Mask" "F.Paste")
			(net "P1V25_SERDES_VDDPLL_PEX3_C4")
		)
	)
	(footprint ""
		(layer "F.Cu")
		(at 130.430016 -193.143378 -90)
		(property "Reference" "R6668"
			(at 0 0 270)
			(layer "F.SilkS")
			(hide yes)
			(effects
				(font
					(size 1.27 1.27)
				)
			)
		)
		(property "Value" ""
			(at 0 0 270)
			(layer "F.Fab")
			(effects
				(font
					(size 1.27 1.27)
				)
			)
		)
		(duplicate_pad_numbers_are_jumpers no)
		(fp_line
			(start -0.7874 0.4064)
			(end -0.7874 -0.4064)
			(stroke
				(width 0.1524)
				(type default)
			)
			(layer "F.SilkS")
		)
		(fp_line
			(start 0.7874 0.4064)
			(end -0.7874 0.4064)
			(stroke
				(width 0.1524)
				(type default)
			)
			(layer "F.SilkS")
		)
		(fp_line
			(start -0.7874 -0.4064)
			(end 0.7874 -0.4064)
			(stroke
				(width 0.1524)
				(type default)
			)
			(layer "F.SilkS")
		)
		(fp_line
			(start 0.7874 -0.4064)
			(end 0.7874 0.4064)
			(stroke
				(width 0.1524)
				(type default)
			)
			(layer "F.SilkS")
		)
		(fp_line
			(start -0.67945 0.3048)
			(end -0.67945 -0.305054)
			(stroke
				(width 0.1)
				(type default)
			)
			(layer "F.Fab")
		)
		(fp_line
			(start -0.12065 0.3048)
			(end -0.67945 0.3048)
			(stroke
				(width 0.1)
				(type default)
			)
			(layer "F.Fab")
		)
		(fp_line
			(start 0.120396 0.3048)
			(end 0.120396 0.2794)
			(stroke
				(width 0.1)
				(type default)
			)
			(layer "F.Fab")
		)
		(fp_line
			(start 0.67945 0.3048)
			(end 0.120396 0.3048)
			(stroke
				(width 0.1)
				(type default)
			)
			(layer "F.Fab")
		)
		(fp_line
			(start -0.12065 0.2794)
			(end -0.12065 0.3048)
			(stroke
				(width 0.1)
				(type default)
			)
			(layer "F.Fab")
		)
		(fp_line
			(start 0.120396 0.2794)
			(end -0.12065 0.2794)
			(stroke
				(width 0.1)
				(type default)
			)
			(layer "F.Fab")
		)
		(fp_line
			(start -0.12065 -0.2794)
			(end 0.12065 -0.2794)
			(stroke
				(width 0.1)
				(type default)
			)
			(layer "F.Fab")
		)
		(fp_line
			(start 0.12065 -0.2794)
			(end 0.12065 -0.3048)
			(stroke
				(width 0.1)
				(type default)
			)
			(layer "F.Fab")
		)
		(fp_line
			(start 0.12065 -0.3048)
			(end 0.67945 -0.3048)
			(stroke
				(width 0.1)
				(type default)
			)
			(layer "F.Fab")
		)
		(fp_line
			(start 0.67945 -0.3048)
			(end 0.67945 0.3048)
			(stroke
				(width 0.1)
				(type default)
			)
			(layer "F.Fab")
		)
		(fp_line
			(start -0.67945 -0.305054)
			(end -0.12065 -0.305054)
			(stroke
				(width 0.1)
				(type default)
			)
			(layer "F.Fab")
		)
		(fp_line
			(start -0.12065 -0.305054)
			(end -0.12065 -0.2794)
			(stroke
				(width 0.1)
				(type default)
			)
			(layer "F.Fab")
		)
		(pad "1" smd circle
			(at -0.40005 0 270)
			(size 0 0)
			(layers "F.Cu" "F.Mask" "F.Paste")
			(net "NIC7_CLK_EN_BUF_N")
		)
		(pad "2" smd circle
			(at 0.40005 0 270)
			(size 0 0)
			(layers "F.Cu" "F.Mask" "F.Paste")
			(net "NIC7_CLK_EN_BUF_R_N")
		)
	)
	(footprint ""
		(layer "F.Cu")
		(at 268.838426 -111.895382)
		(property "Reference" "C471"
			(at 0 0 0)
			(layer "F.SilkS")
			(hide yes)
			(effects
				(font
					(size 1.27 1.27)
				)
			)
		)
		(property "Value" ""
			(at 0 0 0)
			(layer "F.Fab")
			(effects
				(font
					(size 1.27 1.27)
				)
			)
		)
		(duplicate_pad_numbers_are_jumpers no)
		(fp_line
			(start -0.299974 -0.150114)
			(end 0.299974 -0.150114)
			(stroke
				(width 0.1)
				(type default)
			)
			(layer "F.Fab")
		)
		(fp_line
			(start -0.299974 0.150114)
			(end -0.299974 -0.150114)
			(stroke
				(width 0.1)
				(type default)
			)
			(layer "F.Fab")
		)
		(fp_line
			(start 0.299974 -0.150114)
			(end 0.299974 0.150114)
			(stroke
				(width 0.1)
				(type default)
			)
			(layer "F.Fab")
		)
		(fp_line
			(start 0.299974 0.150114)
			(end -0.299974 0.150114)
			(stroke
				(width 0.1)
				(type default)
			)
			(layer "F.Fab")
		)
		(pad "1" smd rect
			(at -0.2667 0)
			(size 0.3048 0.381)
			(layers "F.Cu" "F.Mask" "F.Paste")
			(net "P5E_PEX2_STN1_TX_DN<23>")
		)
		(pad "2" smd rect
			(at 0.2667 0)
			(size 0.3048 0.381)
			(layers "F.Cu" "F.Mask" "F.Paste")
			(net "P5E_PEX2_STN1_TX_C_DN<23>")
		)
	)
	(footprint ""
		(layer "F.Cu")
		(at 420.73449 -33.631886 180)
		(property "Reference" "C715"
			(at 0 0 180)
			(layer "F.SilkS")
			(hide yes)
			(effects
				(font
					(size 1.27 1.27)
				)
			)
		)
		(property "Value" ""
			(at 0 0 180)
			(layer "F.Fab")
			(effects
				(font
					(size 1.27 1.27)
				)
			)
		)
		(duplicate_pad_numbers_are_jumpers no)
		(fp_line
			(start 0.299974 0.150114)
			(end -0.299974 0.150114)
			(stroke
				(width 0.1)
				(type default)
			)
			(layer "F.Fab")
		)
		(fp_line
			(start 0.299974 -0.150114)
			(end 0.299974 0.150114)
			(stroke
				(width 0.1)
				(type default)
			)
			(layer "F.Fab")
		)
		(fp_line
			(start -0.299974 0.150114)
			(end -0.299974 -0.150114)
			(stroke
				(width 0.1)
				(type default)
			)
			(layer "F.Fab")
		)
		(fp_line
			(start -0.299974 -0.150114)
			(end 0.299974 -0.150114)
			(stroke
				(width 0.1)
				(type default)
			)
			(layer "F.Fab")
		)
		(pad "1" smd rect
			(at -0.2667 0 180)
			(size 0.3048 0.381)
			(layers "F.Cu" "F.Mask" "F.Paste")
			(net "P5E_PEX3_STN2_TX_DN<39>")
		)
		(pad "2" smd rect
			(at 0.2667 0 180)
			(size 0.3048 0.381)
			(layers "F.Cu" "F.Mask" "F.Paste")
			(net "P5E_PEX3_STN2_TX_C_DN<39>")
		)
	)
	(footprint ""
		(layer "F.Cu")
		(at 366.955578 -81.498694 180)
		(property "Reference" "R1616"
			(at 0 0 180)
			(layer "F.SilkS")
			(hide yes)
			(effects
				(font
					(size 1.27 1.27)
				)
			)
		)
		(property "Value" ""
			(at 0 0 180)
			(layer "F.Fab")
			(effects
				(font
					(size 1.27 1.27)
				)
			)
		)
		(duplicate_pad_numbers_are_jumpers no)
		(fp_line
			(start 0.7874 0.4064)
			(end -0.7874 0.4064)
			(stroke
				(width 0.1524)
				(type default)
			)
			(layer "F.SilkS")
		)
		(fp_line
			(start 0.7874 -0.4064)
			(end 0.7874 0.4064)
			(stroke
				(width 0.1524)
				(type default)
			)
			(layer "F.SilkS")
		)
		(fp_line
			(start -0.7874 0.4064)
			(end -0.7874 -0.4064)
			(stroke
				(width 0.1524)
				(type default)
			)
			(layer "F.SilkS")
		)
		(fp_line
			(start -0.7874 -0.4064)
			(end 0.7874 -0.4064)
			(stroke
				(width 0.1524)
				(type default)
			)
			(layer "F.SilkS")
		)
		(fp_line
			(start 0.67945 0.3048)
			(end 0.120396 0.3048)
			(stroke
				(width 0.1)
				(type default)
			)
			(layer "F.Fab")
		)
		(fp_line
			(start 0.67945 -0.3048)
			(end 0.67945 0.3048)
			(stroke
				(width 0.1)
				(type default)
			)
			(layer "F.Fab")
		)
		(fp_line
			(start 0.12065 -0.2794)
			(end 0.12065 -0.3048)
			(stroke
				(width 0.1)
				(type default)
			)
			(layer "F.Fab")
		)
		(fp_line
			(start 0.12065 -0.3048)
			(end 0.67945 -0.3048)
			(stroke
				(width 0.1)
				(type default)
			)
			(layer "F.Fab")
		)
		(fp_line
			(start 0.120396 0.3048)
			(end 0.120396 0.2794)
			(stroke
				(width 0.1)
				(type default)
			)
			(layer "F.Fab")
		)
		(fp_line
			(start 0.120396 0.2794)
			(end -0.12065 0.2794)
			(stroke
				(width 0.1)
				(type default)
			)
			(layer "F.Fab")
		)
		(fp_line
			(start -0.12065 0.3048)
			(end -0.67945 0.3048)
			(stroke
				(width 0.1)
				(type default)
			)
			(layer "F.Fab")
		)
		(fp_line
			(start -0.12065 0.2794)
			(end -0.12065 0.3048)
			(stroke
				(width 0.1)
				(type default)
			)
			(layer "F.Fab")
		)
		(fp_line
			(start -0.12065 -0.2794)
			(end 0.12065 -0.2794)
			(stroke
				(width 0.1)
				(type default)
			)
			(layer "F.Fab")
		)
		(fp_line
			(start -0.12065 -0.305054)
			(end -0.12065 -0.2794)
			(stroke
				(width 0.1)
				(type default)
			)
			(layer "F.Fab")
		)
		(fp_line
			(start -0.67945 0.3048)
			(end -0.67945 -0.305054)
			(stroke
				(width 0.1)
				(type default)
			)
			(layer "F.Fab")
		)
		(fp_line
			(start -0.67945 -0.305054)
			(end -0.12065 -0.305054)
			(stroke
				(width 0.1)
				(type default)
			)
			(layer "F.Fab")
		)
		(pad "1" smd circle
			(at -0.40005 0 180)
			(size 0 0)
			(layers "F.Cu" "F.Mask" "F.Paste")
			(net "SMB_BIC_I2C9_MUX1_SSD12_R_SDA")
		)
		(pad "2" smd circle
			(at 0.40005 0 180)
			(size 0 0)
			(layers "F.Cu" "F.Mask" "F.Paste")
			(net "SMB_BIC_I2C9_MUX1_SSD12_SDA")
		)
	)
	(footprint ""
		(layer "F.Cu")
		(at 72.7202 -226.673156 90)
		(property "Reference" "R6637"
			(at 0 0 90)
			(layer "F.SilkS")
			(hide yes)
			(effects
				(font
					(size 1.27 1.27)
				)
			)
		)
		(property "Value" ""
			(at 0 0 90)
			(layer "F.Fab")
			(effects
				(font
					(size 1.27 1.27)
				)
			)
		)
		(duplicate_pad_numbers_are_jumpers no)
		(fp_line
			(start 0.7874 -0.4064)
			(end 0.7874 0.4064)
			(stroke
				(width 0.1524)
				(type default)
			)
			(layer "F.SilkS")
		)
		(fp_line
			(start -0.7874 -0.4064)
			(end 0.7874 -0.4064)
			(stroke
				(width 0.1524)
				(type default)
			)
			(layer "F.SilkS")
		)
		(fp_line
			(start 0.7874 0.4064)
			(end -0.7874 0.4064)
			(stroke
				(width 0.1524)
				(type default)
			)
			(layer "F.SilkS")
		)
		(fp_line
			(start -0.7874 0.4064)
			(end -0.7874 -0.4064)
			(stroke
				(width 0.1524)
				(type default)
			)
			(layer "F.SilkS")
		)
		(fp_line
			(start -0.12065 -0.305054)
			(end -0.12065 -0.2794)
			(stroke
				(width 0.1)
				(type default)
			)
			(layer "F.Fab")
		)
		(fp_line
			(start -0.67945 -0.305054)
			(end -0.12065 -0.305054)
			(stroke
				(width 0.1)
				(type default)
			)
			(layer "F.Fab")
		)
		(fp_line
			(start 0.67945 -0.3048)
			(end 0.67945 0.3048)
			(stroke
				(width 0.1)
				(type default)
			)
			(layer "F.Fab")
		)
		(fp_line
			(start 0.12065 -0.3048)
			(end 0.67945 -0.3048)
			(stroke
				(width 0.1)
				(type default)
			)
			(layer "F.Fab")
		)
		(fp_line
			(start 0.12065 -0.2794)
			(end 0.12065 -0.3048)
			(stroke
				(width 0.1)
				(type default)
			)
			(layer "F.Fab")
		)
		(fp_line
			(start -0.12065 -0.2794)
			(end 0.12065 -0.2794)
			(stroke
				(width 0.1)
				(type default)
			)
			(layer "F.Fab")
		)
		(fp_line
			(start 0.120396 0.2794)
			(end -0.12065 0.2794)
			(stroke
				(width 0.1)
				(type default)
			)
			(layer "F.Fab")
		)
		(fp_line
			(start -0.12065 0.2794)
			(end -0.12065 0.3048)
			(stroke
				(width 0.1)
				(type default)
			)
			(layer "F.Fab")
		)
		(fp_line
			(start 0.67945 0.3048)
			(end 0.120396 0.3048)
			(stroke
				(width 0.1)
				(type default)
			)
			(layer "F.Fab")
		)
		(fp_line
			(start 0.120396 0.3048)
			(end 0.120396 0.2794)
			(stroke
				(width 0.1)
				(type default)
			)
			(layer "F.Fab")
		)
		(fp_line
			(start -0.12065 0.3048)
			(end -0.67945 0.3048)
			(stroke
				(width 0.1)
				(type default)
			)
			(layer "F.Fab")
		)
		(fp_line
			(start -0.67945 0.3048)
			(end -0.67945 -0.305054)
			(stroke
				(width 0.1)
				(type default)
			)
			(layer "F.Fab")
		)
		(pad "1" smd circle
			(at -0.40005 0 90)
			(size 0 0)
			(layers "F.Cu" "F.Mask" "F.Paste")
			(net "UART_PEX1_CLI_R_RX")
		)
		(pad "2" smd circle
			(at 0.40005 0 90)
			(size 0 0)
			(layers "F.Cu" "F.Mask" "F.Paste")
			(net "UART_PEX1_CLI_R1_RX")
		)
	)
	(footprint ""
		(layer "F.Cu")
		(at 334.01 -245.237 90)
		(property "Reference" "R1800"
			(at 0 0 90)
			(layer "F.SilkS")
			(hide yes)
			(effects
				(font
					(size 1.27 1.27)
				)
			)
		)
		(property "Value" ""
			(at 0 0 90)
			(layer "F.Fab")
			(effects
				(font
					(size 1.27 1.27)
				)
			)
		)
		(duplicate_pad_numbers_are_jumpers no)
		(fp_line
			(start 0.7874 -0.4064)
			(end 0.7874 0.4064)
			(stroke
				(width 0.1524)
				(type default)
			)
			(layer "F.SilkS")
		)
		(fp_line
			(start -0.7874 -0.4064)
			(end 0.7874 -0.4064)
			(stroke
				(width 0.1524)
				(type default)
			)
			(layer "F.SilkS")
		)
		(fp_line
			(start 0.7874 0.4064)
			(end -0.7874 0.4064)
			(stroke
				(width 0.1524)
				(type default)
			)
			(layer "F.SilkS")
		)
		(fp_line
			(start -0.7874 0.4064)
			(end -0.7874 -0.4064)
			(stroke
				(width 0.1524)
				(type default)
			)
			(layer "F.SilkS")
		)
		(fp_line
			(start -0.12065 -0.305054)
			(end -0.12065 -0.2794)
			(stroke
				(width 0.1)
				(type default)
			)
			(layer "F.Fab")
		)
		(fp_line
			(start -0.67945 -0.305054)
			(end -0.12065 -0.305054)
			(stroke
				(width 0.1)
				(type default)
			)
			(layer "F.Fab")
		)
		(fp_line
			(start 0.67945 -0.3048)
			(end 0.67945 0.3048)
			(stroke
				(width 0.1)
				(type default)
			)
			(layer "F.Fab")
		)
		(fp_line
			(start 0.12065 -0.3048)
			(end 0.67945 -0.3048)
			(stroke
				(width 0.1)
				(type default)
			)
			(layer "F.Fab")
		)
		(fp_line
			(start 0.12065 -0.2794)
			(end 0.12065 -0.3048)
			(stroke
				(width 0.1)
				(type default)
			)
			(layer "F.Fab")
		)
		(fp_line
			(start -0.12065 -0.2794)
			(end 0.12065 -0.2794)
			(stroke
				(width 0.1)
				(type default)
			)
			(layer "F.Fab")
		)
		(fp_line
			(start 0.120396 0.2794)
			(end -0.12065 0.2794)
			(stroke
				(width 0.1)
				(type default)
			)
			(layer "F.Fab")
		)
		(fp_line
			(start -0.12065 0.2794)
			(end -0.12065 0.3048)
			(stroke
				(width 0.1)
				(type default)
			)
			(layer "F.Fab")
		)
		(fp_line
			(start 0.67945 0.3048)
			(end 0.120396 0.3048)
			(stroke
				(width 0.1)
				(type default)
			)
			(layer "F.Fab")
		)
		(fp_line
			(start 0.120396 0.3048)
			(end 0.120396 0.2794)
			(stroke
				(width 0.1)
				(type default)
			)
			(layer "F.Fab")
		)
		(fp_line
			(start -0.12065 0.3048)
			(end -0.67945 0.3048)
			(stroke
				(width 0.1)
				(type default)
			)
			(layer "F.Fab")
		)
		(fp_line
			(start -0.67945 0.3048)
			(end -0.67945 -0.305054)
			(stroke
				(width 0.1)
				(type default)
			)
			(layer "F.Fab")
		)
		(pad "1" smd circle
			(at -0.40005 0 90)
			(size 0 0)
			(layers "F.Cu" "F.Mask" "F.Paste")
			(net "MB_SWB_PWRGD_BUF")
		)
		(pad "2" smd circle
			(at 0.40005 0 90)
			(size 0 0)
			(layers "F.Cu" "F.Mask" "F.Paste")
			(net "MB_SWB_PWRGD_BUF_R")
		)
	)
	(footprint ""
		(layer "F.Cu")
		(at 330.857098 -102.088442)
		(property "Reference" "PC322"
			(at 0 0 0)
			(layer "F.SilkS")
			(hide yes)
			(effects
				(font
					(size 1.27 1.27)
				)
			)
		)
		(property "Value" ""
			(at 0 0 0)
			(layer "F.Fab")
			(effects
				(font
					(size 1.27 1.27)
				)
			)
		)
		(duplicate_pad_numbers_are_jumpers no)
		(fp_line
			(start -0.7874 -0.4064)
			(end 0.7874 -0.4064)
			(stroke
				(width 0.1524)
				(type default)
			)
			(layer "F.SilkS")
		)
		(fp_line
			(start -0.7874 0.4064)
			(end -0.7874 -0.4064)
			(stroke
				(width 0.1524)
				(type default)
			)
			(layer "F.SilkS")
		)
		(fp_line
			(start 0.7874 -0.4064)
			(end 0.7874 0.4064)
			(stroke
				(width 0.1524)
				(type default)
			)
			(layer "F.SilkS")
		)
		(fp_line
			(start 0.7874 0.4064)
			(end -0.7874 0.4064)
			(stroke
				(width 0.1524)
				(type default)
			)
			(layer "F.SilkS")
		)
		(fp_line
			(start -0.67945 -0.305054)
			(end -0.12065 -0.305054)
			(stroke
				(width 0.1)
				(type default)
			)
			(layer "F.Fab")
		)
		(fp_line
			(start -0.67945 0.3048)
			(end -0.67945 -0.305054)
			(stroke
				(width 0.1)
				(type default)
			)
			(layer "F.Fab")
		)
		(fp_line
			(start -0.12065 -0.305054)
			(end -0.12065 -0.2794)
			(stroke
				(width 0.1)
				(type default)
			)
			(layer "F.Fab")
		)
		(fp_line
			(start -0.12065 -0.2794)
			(end 0.12065 -0.2794)
			(stroke
				(width 0.1)
				(type default)
			)
			(layer "F.Fab")
		)
		(fp_line
			(start -0.12065 0.2794)
			(end -0.12065 0.3048)
			(stroke
				(width 0.1)
				(type default)
			)
			(layer "F.Fab")
		)
		(fp_line
			(start -0.12065 0.3048)
			(end -0.67945 0.3048)
			(stroke
				(width 0.1)
				(type default)
			)
			(layer "F.Fab")
		)
		(fp_line
			(start 0.120396 0.2794)
			(end -0.12065 0.2794)
			(stroke
				(width 0.1)
				(type default)
			)
			(layer "F.Fab")
		)
		(fp_line
			(start 0.120396 0.3048)
			(end 0.120396 0.2794)
			(stroke
				(width 0.1)
				(type default)
			)
			(layer "F.Fab")
		)
		(fp_line
			(start 0.12065 -0.3048)
			(end 0.67945 -0.3048)
			(stroke
				(width 0.1)
				(type default)
			)
			(layer "F.Fab")
		)
		(fp_line
			(start 0.12065 -0.2794)
			(end 0.12065 -0.3048)
			(stroke
				(width 0.1)
				(type default)
			)
			(layer "F.Fab")
		)
		(fp_line
			(start 0.67945 -0.3048)
			(end 0.67945 0.3048)
			(stroke
				(width 0.1)
				(type default)
			)
			(layer "F.Fab")
		)
		(fp_line
			(start 0.67945 0.3048)
			(end 0.120396 0.3048)
			(stroke
				(width 0.1)
				(type default)
			)
			(layer "F.Fab")
		)
		(pad "1" smd circle
			(at -0.40005 0)
			(size 0 0)
			(layers "F.Cu" "F.Mask" "F.Paste")
			(net "P12V_NIC5_R")
		)
		(pad "2" smd circle
			(at 0.40005 0)
			(size 0 0)
			(layers "F.Cu" "F.Mask" "F.Paste")
			(net "GND")
		)
	)
	(footprint ""
		(layer "F.Cu")
		(at 101.829362 -384.805174 -90)
		(property "Reference" "R6727"
			(at 0 0 270)
			(layer "F.SilkS")
			(hide yes)
			(effects
				(font
					(size 1.27 1.27)
				)
			)
		)
		(property "Value" ""
			(at 0 0 270)
			(layer "F.Fab")
			(effects
				(font
					(size 1.27 1.27)
				)
			)
		)
		(duplicate_pad_numbers_are_jumpers no)
		(fp_line
			(start -0.7874 0.4064)
			(end -0.7874 -0.4064)
			(stroke
				(width 0.1524)
				(type default)
			)
			(layer "F.SilkS")
		)
		(fp_line
			(start 0.7874 0.4064)
			(end -0.017018 0.4064)
			(stroke
				(width 0.1524)
				(type default)
			)
			(layer "F.SilkS")
		)
		(fp_line
			(start -0.7874 -0.4064)
			(end 0.7874 -0.4064)
			(stroke
				(width 0.1524)
				(type default)
			)
			(layer "F.SilkS")
		)
		(fp_line
			(start -0.67945 0.3048)
			(end -0.67945 -0.305054)
			(stroke
				(width 0.1)
				(type default)
			)
			(layer "F.Fab")
		)
		(fp_line
			(start -0.12065 0.3048)
			(end -0.67945 0.3048)
			(stroke
				(width 0.1)
				(type default)
			)
			(layer "F.Fab")
		)
		(fp_line
			(start 0.120396 0.3048)
			(end 0.120396 0.2794)
			(stroke
				(width 0.1)
				(type default)
			)
			(layer "F.Fab")
		)
		(fp_line
			(start 0.67945 0.3048)
			(end 0.120396 0.3048)
			(stroke
				(width 0.1)
				(type default)
			)
			(layer "F.Fab")
		)
		(fp_line
			(start -0.12065 0.2794)
			(end -0.12065 0.3048)
			(stroke
				(width 0.1)
				(type default)
			)
			(layer "F.Fab")
		)
		(fp_line
			(start 0.120396 0.2794)
			(end -0.12065 0.2794)
			(stroke
				(width 0.1)
				(type default)
			)
			(layer "F.Fab")
		)
		(fp_line
			(start -0.12065 -0.2794)
			(end 0.12065 -0.2794)
			(stroke
				(width 0.1)
				(type default)
			)
			(layer "F.Fab")
		)
		(fp_line
			(start 0.12065 -0.2794)
			(end 0.12065 -0.3048)
			(stroke
				(width 0.1)
				(type default)
			)
			(layer "F.Fab")
		)
		(fp_line
			(start 0.12065 -0.3048)
			(end 0.67945 -0.3048)
			(stroke
				(width 0.1)
				(type default)
			)
			(layer "F.Fab")
		)
		(fp_line
			(start 0.67945 -0.3048)
			(end 0.67945 0.3048)
			(stroke
				(width 0.1)
				(type default)
			)
			(layer "F.Fab")
		)
		(fp_line
			(start -0.67945 -0.305054)
			(end -0.12065 -0.305054)
			(stroke
				(width 0.1)
				(type default)
			)
			(layer "F.Fab")
		)
		(fp_line
			(start -0.12065 -0.305054)
			(end -0.12065 -0.2794)
			(stroke
				(width 0.1)
				(type default)
			)
			(layer "F.Fab")
		)
		(pad "1" smd rect
			(at -0.40005 0 90)
			(size 0.4572 0.508)
			(layers "F.Cu" "F.Mask" "F.Paste")
			(net "USB2_MB_BMC_DP")
		)
		(pad "2" smd rect
			(at 0.40005 0 90)
			(size 0.4572 0.508)
			(layers "F.Cu" "F.Mask" "F.Paste")
			(net "USB2_MB_BMC_USB8042_DP")
		)
	)
	(footprint ""
		(layer "F.Cu")
		(at 45.498512 -66.32194 -90)
		(property "Reference" "PC640"
			(at 0 0 270)
			(layer "F.SilkS")
			(hide yes)
			(effects
				(font
					(size 1.27 1.27)
				)
			)
		)
		(property "Value" ""
			(at 0 0 270)
			(layer "F.Fab")
			(effects
				(font
					(size 1.27 1.27)
				)
			)
		)
		(duplicate_pad_numbers_are_jumpers no)
		(fp_line
			(start -0.7874 0.4064)
			(end -0.7874 -0.4064)
			(stroke
				(width 0.1524)
				(type default)
			)
			(layer "F.SilkS")
		)
		(fp_line
			(start 0.7874 0.4064)
			(end -0.7874 0.4064)
			(stroke
				(width 0.1524)
				(type default)
			)
			(layer "F.SilkS")
		)
		(fp_line
			(start -0.7874 -0.4064)
			(end 0.7874 -0.4064)
			(stroke
				(width 0.1524)
				(type default)
			)
			(layer "F.SilkS")
		)
		(fp_line
			(start 0.7874 -0.4064)
			(end 0.7874 0.4064)
			(stroke
				(width 0.1524)
				(type default)
			)
			(layer "F.SilkS")
		)
		(fp_line
			(start -0.67945 0.3048)
			(end -0.67945 -0.305054)
			(stroke
				(width 0.1)
				(type default)
			)
			(layer "F.Fab")
		)
		(fp_line
			(start -0.12065 0.3048)
			(end -0.67945 0.3048)
			(stroke
				(width 0.1)
				(type default)
			)
			(layer "F.Fab")
		)
		(fp_line
			(start 0.120396 0.3048)
			(end 0.120396 0.2794)
			(stroke
				(width 0.1)
				(type default)
			)
			(layer "F.Fab")
		)
		(fp_line
			(start 0.67945 0.3048)
			(end 0.120396 0.3048)
			(stroke
				(width 0.1)
				(type default)
			)
			(layer "F.Fab")
		)
		(fp_line
			(start -0.12065 0.2794)
			(end -0.12065 0.3048)
			(stroke
				(width 0.1)
				(type default)
			)
			(layer "F.Fab")
		)
		(fp_line
			(start 0.120396 0.2794)
			(end -0.12065 0.2794)
			(stroke
				(width 0.1)
				(type default)
			)
			(layer "F.Fab")
		)
		(fp_line
			(start -0.12065 -0.2794)
			(end 0.12065 -0.2794)
			(stroke
				(width 0.1)
				(type default)
			)
			(layer "F.Fab")
		)
		(fp_line
			(start 0.12065 -0.2794)
			(end 0.12065 -0.3048)
			(stroke
				(width 0.1)
				(type default)
			)
			(layer "F.Fab")
		)
		(fp_line
			(start 0.12065 -0.3048)
			(end 0.67945 -0.3048)
			(stroke
				(width 0.1)
				(type default)
			)
			(layer "F.Fab")
		)
		(fp_line
			(start 0.67945 -0.3048)
			(end 0.67945 0.3048)
			(stroke
				(width 0.1)
				(type default)
			)
			(layer "F.Fab")
		)
		(fp_line
			(start -0.67945 -0.305054)
			(end -0.12065 -0.305054)
			(stroke
				(width 0.1)
				(type default)
			)
			(layer "F.Fab")
		)
		(fp_line
			(start -0.12065 -0.305054)
			(end -0.12065 -0.2794)
			(stroke
				(width 0.1)
				(type default)
			)
			(layer "F.Fab")
		)
		(pad "1" smd circle
			(at -0.40005 0 270)
			(size 0 0)
			(layers "F.Cu" "F.Mask" "F.Paste")
			(net "P12V_SSD1_CO_GATE")
		)
		(pad "2" smd circle
			(at 0.40005 0 270)
			(size 0 0)
			(layers "F.Cu" "F.Mask" "F.Paste")
			(net "GND")
		)
	)
	(footprint ""
		(layer "F.Cu")
		(at 105.744772 -92.366846 90)
		(property "Reference" "R1133"
			(at 0 0 90)
			(layer "F.SilkS")
			(hide yes)
			(effects
				(font
					(size 1.27 1.27)
				)
			)
		)
		(property "Value" ""
			(at 0 0 90)
			(layer "F.Fab")
			(effects
				(font
					(size 1.27 1.27)
				)
			)
		)
		(duplicate_pad_numbers_are_jumpers no)
		(fp_line
			(start 0.7874 -0.4064)
			(end 0.7874 0.4064)
			(stroke
				(width 0.1524)
				(type default)
			)
			(layer "F.SilkS")
		)
		(fp_line
			(start -0.7874 -0.4064)
			(end 0.7874 -0.4064)
			(stroke
				(width 0.1524)
				(type default)
			)
			(layer "F.SilkS")
		)
		(fp_line
			(start 0.7874 0.4064)
			(end -0.7874 0.4064)
			(stroke
				(width 0.1524)
				(type default)
			)
			(layer "F.SilkS")
		)
		(fp_line
			(start -0.7874 0.4064)
			(end -0.7874 -0.4064)
			(stroke
				(width 0.1524)
				(type default)
			)
			(layer "F.SilkS")
		)
		(fp_line
			(start -0.12065 -0.305054)
			(end -0.12065 -0.2794)
			(stroke
				(width 0.1)
				(type default)
			)
			(layer "F.Fab")
		)
		(fp_line
			(start -0.67945 -0.305054)
			(end -0.12065 -0.305054)
			(stroke
				(width 0.1)
				(type default)
			)
			(layer "F.Fab")
		)
		(fp_line
			(start 0.67945 -0.3048)
			(end 0.67945 0.3048)
			(stroke
				(width 0.1)
				(type default)
			)
			(layer "F.Fab")
		)
		(fp_line
			(start 0.12065 -0.3048)
			(end 0.67945 -0.3048)
			(stroke
				(width 0.1)
				(type default)
			)
			(layer "F.Fab")
		)
		(fp_line
			(start 0.12065 -0.2794)
			(end 0.12065 -0.3048)
			(stroke
				(width 0.1)
				(type default)
			)
			(layer "F.Fab")
		)
		(fp_line
			(start -0.12065 -0.2794)
			(end 0.12065 -0.2794)
			(stroke
				(width 0.1)
				(type default)
			)
			(layer "F.Fab")
		)
		(fp_line
			(start 0.120396 0.2794)
			(end -0.12065 0.2794)
			(stroke
				(width 0.1)
				(type default)
			)
			(layer "F.Fab")
		)
		(fp_line
			(start -0.12065 0.2794)
			(end -0.12065 0.3048)
			(stroke
				(width 0.1)
				(type default)
			)
			(layer "F.Fab")
		)
		(fp_line
			(start 0.67945 0.3048)
			(end 0.120396 0.3048)
			(stroke
				(width 0.1)
				(type default)
			)
			(layer "F.Fab")
		)
		(fp_line
			(start 0.120396 0.3048)
			(end 0.120396 0.2794)
			(stroke
				(width 0.1)
				(type default)
			)
			(layer "F.Fab")
		)
		(fp_line
			(start -0.12065 0.3048)
			(end -0.67945 0.3048)
			(stroke
				(width 0.1)
				(type default)
			)
			(layer "F.Fab")
		)
		(fp_line
			(start -0.67945 0.3048)
			(end -0.67945 -0.305054)
			(stroke
				(width 0.1)
				(type default)
			)
			(layer "F.Fab")
		)
		(pad "1" smd circle
			(at -0.40005 0 90)
			(size 0 0)
			(layers "F.Cu" "F.Mask" "F.Paste")
			(net "PU_9ZXL0851_0_7_HBW")
		)
		(pad "2" smd circle
			(at 0.40005 0 90)
			(size 0 0)
			(layers "F.Cu" "F.Mask" "F.Paste")
			(net "GND")
		)
	)
	(footprint ""
		(layer "F.Cu")
		(at 326.303386 -96.811592 90)
		(property "Reference" "R742"
			(at 0 0 90)
			(layer "F.SilkS")
			(hide yes)
			(effects
				(font
					(size 1.27 1.27)
				)
			)
		)
		(property "Value" ""
			(at 0 0 90)
			(layer "F.Fab")
			(effects
				(font
					(size 1.27 1.27)
				)
			)
		)
		(duplicate_pad_numbers_are_jumpers no)
		(fp_line
			(start 0.7874 -0.4064)
			(end 0.7874 0.4064)
			(stroke
				(width 0.1524)
				(type default)
			)
			(layer "F.SilkS")
		)
		(fp_line
			(start -0.7874 -0.4064)
			(end 0.7874 -0.4064)
			(stroke
				(width 0.1524)
				(type default)
			)
			(layer "F.SilkS")
		)
		(fp_line
			(start 0.7874 0.4064)
			(end -0.7874 0.4064)
			(stroke
				(width 0.1524)
				(type default)
			)
			(layer "F.SilkS")
		)
		(fp_line
			(start -0.7874 0.4064)
			(end -0.7874 -0.4064)
			(stroke
				(width 0.1524)
				(type default)
			)
			(layer "F.SilkS")
		)
		(fp_line
			(start -0.12065 -0.305054)
			(end -0.12065 -0.2794)
			(stroke
				(width 0.1)
				(type default)
			)
			(layer "F.Fab")
		)
		(fp_line
			(start -0.67945 -0.305054)
			(end -0.12065 -0.305054)
			(stroke
				(width 0.1)
				(type default)
			)
			(layer "F.Fab")
		)
		(fp_line
			(start 0.67945 -0.3048)
			(end 0.67945 0.3048)
			(stroke
				(width 0.1)
				(type default)
			)
			(layer "F.Fab")
		)
		(fp_line
			(start 0.12065 -0.3048)
			(end 0.67945 -0.3048)
			(stroke
				(width 0.1)
				(type default)
			)
			(layer "F.Fab")
		)
		(fp_line
			(start 0.12065 -0.2794)
			(end 0.12065 -0.3048)
			(stroke
				(width 0.1)
				(type default)
			)
			(layer "F.Fab")
		)
		(fp_line
			(start -0.12065 -0.2794)
			(end 0.12065 -0.2794)
			(stroke
				(width 0.1)
				(type default)
			)
			(layer "F.Fab")
		)
		(fp_line
			(start 0.120396 0.2794)
			(end -0.12065 0.2794)
			(stroke
				(width 0.1)
				(type default)
			)
			(layer "F.Fab")
		)
		(fp_line
			(start -0.12065 0.2794)
			(end -0.12065 0.3048)
			(stroke
				(width 0.1)
				(type default)
			)
			(layer "F.Fab")
		)
		(fp_line
			(start 0.67945 0.3048)
			(end 0.120396 0.3048)
			(stroke
				(width 0.1)
				(type default)
			)
			(layer "F.Fab")
		)
		(fp_line
			(start 0.120396 0.3048)
			(end 0.120396 0.2794)
			(stroke
				(width 0.1)
				(type default)
			)
			(layer "F.Fab")
		)
		(fp_line
			(start -0.12065 0.3048)
			(end -0.67945 0.3048)
			(stroke
				(width 0.1)
				(type default)
			)
			(layer "F.Fab")
		)
		(fp_line
			(start -0.67945 0.3048)
			(end -0.67945 -0.305054)
			(stroke
				(width 0.1)
				(type default)
			)
			(layer "F.Fab")
		)
		(pad "1" smd circle
			(at -0.40005 0 90)
			(size 0 0)
			(layers "F.Cu" "F.Mask" "F.Paste")
			(net "SMB_BIC_I2C6_MUX_NIC_ADC_R_SCL")
		)
		(pad "2" smd circle
			(at 0.40005 0 90)
			(size 0 0)
			(layers "F.Cu" "F.Mask" "F.Paste")
			(net "SMB_NIC5_ADC_SCL")
		)
	)
	(footprint ""
		(layer "F.Cu")
		(at 73.53046 -66.32194 -90)
		(property "Reference" "PC656"
			(at 0 0 270)
			(layer "F.SilkS")
			(hide yes)
			(effects
				(font
					(size 1.27 1.27)
				)
			)
		)
		(property "Value" ""
			(at 0 0 270)
			(layer "F.Fab")
			(effects
				(font
					(size 1.27 1.27)
				)
			)
		)
		(duplicate_pad_numbers_are_jumpers no)
		(fp_line
			(start -0.7874 0.4064)
			(end -0.7874 -0.4064)
			(stroke
				(width 0.1524)
				(type default)
			)
			(layer "F.SilkS")
		)
		(fp_line
			(start 0.7874 0.4064)
			(end -0.7874 0.4064)
			(stroke
				(width 0.1524)
				(type default)
			)
			(layer "F.SilkS")
		)
		(fp_line
			(start -0.7874 -0.4064)
			(end 0.7874 -0.4064)
			(stroke
				(width 0.1524)
				(type default)
			)
			(layer "F.SilkS")
		)
		(fp_line
			(start 0.7874 -0.4064)
			(end 0.7874 0.4064)
			(stroke
				(width 0.1524)
				(type default)
			)
			(layer "F.SilkS")
		)
		(fp_line
			(start -0.67945 0.3048)
			(end -0.67945 -0.305054)
			(stroke
				(width 0.1)
				(type default)
			)
			(layer "F.Fab")
		)
		(fp_line
			(start -0.12065 0.3048)
			(end -0.67945 0.3048)
			(stroke
				(width 0.1)
				(type default)
			)
			(layer "F.Fab")
		)
		(fp_line
			(start 0.120396 0.3048)
			(end 0.120396 0.2794)
			(stroke
				(width 0.1)
				(type default)
			)
			(layer "F.Fab")
		)
		(fp_line
			(start 0.67945 0.3048)
			(end 0.120396 0.3048)
			(stroke
				(width 0.1)
				(type default)
			)
			(layer "F.Fab")
		)
		(fp_line
			(start -0.12065 0.2794)
			(end -0.12065 0.3048)
			(stroke
				(width 0.1)
				(type default)
			)
			(layer "F.Fab")
		)
		(fp_line
			(start 0.120396 0.2794)
			(end -0.12065 0.2794)
			(stroke
				(width 0.1)
				(type default)
			)
			(layer "F.Fab")
		)
		(fp_line
			(start -0.12065 -0.2794)
			(end 0.12065 -0.2794)
			(stroke
				(width 0.1)
				(type default)
			)
			(layer "F.Fab")
		)
		(fp_line
			(start 0.12065 -0.2794)
			(end 0.12065 -0.3048)
			(stroke
				(width 0.1)
				(type default)
			)
			(layer "F.Fab")
		)
		(fp_line
			(start 0.12065 -0.3048)
			(end 0.67945 -0.3048)
			(stroke
				(width 0.1)
				(type default)
			)
			(layer "F.Fab")
		)
		(fp_line
			(start 0.67945 -0.3048)
			(end 0.67945 0.3048)
			(stroke
				(width 0.1)
				(type default)
			)
			(layer "F.Fab")
		)
		(fp_line
			(start -0.67945 -0.305054)
			(end -0.12065 -0.305054)
			(stroke
				(width 0.1)
				(type default)
			)
			(layer "F.Fab")
		)
		(fp_line
			(start -0.12065 -0.305054)
			(end -0.12065 -0.2794)
			(stroke
				(width 0.1)
				(type default)
			)
			(layer "F.Fab")
		)
		(pad "1" smd circle
			(at -0.40005 0 270)
			(size 0 0)
			(layers "F.Cu" "F.Mask" "F.Paste")
			(net "P12V_SSD2_CO_DV_DT")
		)
		(pad "2" smd circle
			(at 0.40005 0 270)
			(size 0 0)
			(layers "F.Cu" "F.Mask" "F.Paste")
			(net "GND")
		)
	)
	(footprint ""
		(layer "F.Cu")
		(at 280.847038 -54.3941)
		(property "Reference" "PU40"
			(at -2.000758 2.902204 0)
			(unlocked yes)
			(layer "F.SilkS")
			(effects
				(font
					(size 0.7874 0.5842)
					(thickness 0.1524)
				)
				(justify left)
			)
		)
		(property "Value" ""
			(at 0 0 0)
			(layer "F.Fab")
			(effects
				(font
					(size 1.27 1.27)
				)
			)
		)
		(duplicate_pad_numbers_are_jumpers no)
		(fp_line
			(start -1.943608 -1.549908)
			(end 1.943608 -1.549908)
			(stroke
				(width 0.1524)
				(type default)
			)
			(layer "F.SilkS")
		)
		(fp_line
			(start -1.943608 1.549908)
			(end -1.943608 -1.549908)
			(stroke
				(width 0.1524)
				(type default)
			)
			(layer "F.SilkS")
		)
		(fp_line
			(start 1.943608 -1.549908)
			(end 1.943608 1.549908)
			(stroke
				(width 0.1524)
				(type default)
			)
			(layer "F.SilkS")
		)
		(fp_line
			(start 1.943608 1.549908)
			(end -1.943608 1.549908)
			(stroke
				(width 0.1524)
				(type default)
			)
			(layer "F.SilkS")
		)
		(fp_poly
			(pts
				(xy -2.019808 -1.549908) (xy -1.257808 -1.549908) (xy -1.257808 -1.880108) (xy -2.019808 -1.880108)
			)
			(stroke
				(width 0)
				(type default)
			)
			(fill yes)
			(layer "F.SilkS")
		)
		(fp_line
			(start -1.549908 -1.549908)
			(end 1.549908 -1.549908)
			(stroke
				(width 0.1)
				(type default)
			)
			(layer "F.Fab")
		)
		(fp_line
			(start -1.549908 1.549908)
			(end -1.549908 -1.549908)
			(stroke
				(width 0.1)
				(type default)
			)
			(layer "F.Fab")
		)
		(fp_line
			(start 1.549908 -1.549908)
			(end 1.549908 1.549908)
			(stroke
				(width 0.1)
				(type default)
			)
			(layer "F.Fab")
		)
		(fp_line
			(start 1.549908 1.549908)
			(end -1.549908 1.549908)
			(stroke
				(width 0.1)
				(type default)
			)
			(layer "F.Fab")
		)
		(fp_poly
			(pts
				(xy -2.019808 -1.549908) (xy -1.257808 -1.549908) (xy -1.257808 -1.880108) (xy -2.019808 -1.880108)
			)
			(stroke
				(width 0)
				(type default)
			)
			(fill yes)
			(layer "F.Fab")
		)
		(pad "1" smd rect
			(at -1.500124 -1.249934 270)
			(size 0.2794 0.6096)
			(layers "F.Cu" "F.Mask" "F.Paste")
			(net "P12V_SSD9_R")
		)
		(pad "2" smd rect
			(at -1.500124 -0.750062 270)
			(size 0.2794 0.6096)
			(layers "F.Cu" "F.Mask" "F.Paste")
			(net "P12V_SSD9_R")
		)
		(pad "3" smd rect
			(at -1.500124 -0.249936 270)
			(size 0.2794 0.6096)
			(layers "F.Cu" "F.Mask" "F.Paste")
			(net "P12V_SSD9_R")
		)
		(pad "4" smd rect
			(at -1.500124 0.249936 270)
			(size 0.2794 0.6096)
			(layers "F.Cu" "F.Mask" "F.Paste")
			(net "P12V_SSD9_R")
		)
		(pad "5" smd rect
			(at -1.500124 0.750062 270)
			(size 0.2794 0.6096)
			(layers "F.Cu" "F.Mask" "F.Paste")
			(net "P12V_SSD9_R")
		)
		(pad "6" smd rect
			(at -1.500124 1.249934 270)
			(size 0.2794 0.6096)
			(layers "F.Cu" "F.Mask" "F.Paste")
			(net "GND")
		)
		(pad "7" smd rect
			(at 1.500124 1.249934 270)
			(size 0.2794 0.6096)
			(layers "F.Cu" "F.Mask" "F.Paste")
			(net "P12V_SSD9_SS")
		)
		(pad "8" smd rect
			(at 1.500124 0.750062 270)
			(size 0.2794 0.6096)
			(layers "F.Cu" "F.Mask" "F.Paste")
			(net "PWRGD_P12V_SSD9")
		)
		(pad "9" smd rect
			(at 1.500124 0.249936 270)
			(size 0.2794 0.6096)
			(layers "F.Cu" "F.Mask" "F.Paste")
			(net "P12V_SSD9_OCP")
		)
		(pad "10" smd rect
			(at 1.500124 -0.249936 270)
			(size 0.2794 0.6096)
			(layers "F.Cu" "F.Mask" "F.Paste")
			(net "P5V_AUX")
		)
		(pad "11" smd rect
			(at 1.500124 -0.750062 270)
			(size 0.2794 0.6096)
			(layers "F.Cu" "F.Mask" "F.Paste")
			(net "SSD9_PWR_EN_R")
		)
		(pad "12" smd rect
			(at 1.500124 -1.249934 270)
			(size 0.2794 0.6096)
			(layers "F.Cu" "F.Mask" "F.Paste")
			(net "P12V_AUX")
		)
		(pad "13" smd rect
			(at 0 0)
			(size 1.9812 2.7178)
			(layers "F.Cu" "F.Mask" "F.Paste")
			(net "P12V_AUX")
		)
		(zone
			(layer "F.Cu")
			(hatch none 0.5)
			(connect_pads
				(clearance 0)
			)
			(min_thickness 0.25)
			(keepout
				(tracks not_allowed)
				(vias allowed)
				(pads allowed)
				(copperpour not_allowed)
				(footprints allowed)
			)
			(placement
				(enabled no)
				(sheetname "")
			)
			(fill
				(thermal_gap 0.5)
				(thermal_bridge_width 0.5)
				(island_removal_mode 0)
			)
			(polygon
				(pts
					(xy 281.990038 -55.9435) (xy 281.990038 -55.8165) (xy 281.990038 -52.8447) (xy 281.990038 -52.844192)
					(xy 279.704038 -52.844192) (xy 279.704038 -52.8447) (xy 279.704038 -52.9717) (xy 279.704038 -54.3941)
					(xy 279.805638 -54.3941) (xy 279.805638 -52.9717) (xy 281.888438 -52.9717) (xy 281.888438 -55.8165)
					(xy 279.805638 -55.8165) (xy 279.805638 -54.4195) (xy 279.704038 -54.4195) (xy 279.704038 -55.8165)
					(xy 279.704038 -55.9435) (xy 279.704038 -55.944008) (xy 281.990038 -55.944008)
				)
			)
		)
	)
	(footprint ""
		(layer "F.Cu")
		(at 307.867812 -19.453098)
		(property "Reference" "R1709"
			(at 0 0 0)
			(layer "F.SilkS")
			(hide yes)
			(effects
				(font
					(size 1.27 1.27)
				)
			)
		)
		(property "Value" ""
			(at 0 0 0)
			(layer "F.Fab")
			(effects
				(font
					(size 1.27 1.27)
				)
			)
		)
		(duplicate_pad_numbers_are_jumpers no)
		(fp_line
			(start -0.7874 -0.4064)
			(end 0.7874 -0.4064)
			(stroke
				(width 0.1524)
				(type default)
			)
			(layer "F.SilkS")
		)
		(fp_line
			(start -0.7874 0.4064)
			(end -0.7874 -0.4064)
			(stroke
				(width 0.1524)
				(type default)
			)
			(layer "F.SilkS")
		)
		(fp_line
			(start 0.7874 -0.4064)
			(end 0.7874 0.4064)
			(stroke
				(width 0.1524)
				(type default)
			)
			(layer "F.SilkS")
		)
		(fp_line
			(start 0.7874 0.4064)
			(end -0.7874 0.4064)
			(stroke
				(width 0.1524)
				(type default)
			)
			(layer "F.SilkS")
		)
		(fp_line
			(start -0.67945 -0.305054)
			(end -0.12065 -0.305054)
			(stroke
				(width 0.1)
				(type default)
			)
			(layer "F.Fab")
		)
		(fp_line
			(start -0.67945 0.3048)
			(end -0.67945 -0.305054)
			(stroke
				(width 0.1)
				(type default)
			)
			(layer "F.Fab")
		)
		(fp_line
			(start -0.12065 -0.305054)
			(end -0.12065 -0.2794)
			(stroke
				(width 0.1)
				(type default)
			)
			(layer "F.Fab")
		)
		(fp_line
			(start -0.12065 -0.2794)
			(end 0.12065 -0.2794)
			(stroke
				(width 0.1)
				(type default)
			)
			(layer "F.Fab")
		)
		(fp_line
			(start -0.12065 0.2794)
			(end -0.12065 0.3048)
			(stroke
				(width 0.1)
				(type default)
			)
			(layer "F.Fab")
		)
		(fp_line
			(start -0.12065 0.3048)
			(end -0.67945 0.3048)
			(stroke
				(width 0.1)
				(type default)
			)
			(layer "F.Fab")
		)
		(fp_line
			(start 0.120396 0.2794)
			(end -0.12065 0.2794)
			(stroke
				(width 0.1)
				(type default)
			)
			(layer "F.Fab")
		)
		(fp_line
			(start 0.120396 0.3048)
			(end 0.120396 0.2794)
			(stroke
				(width 0.1)
				(type default)
			)
			(layer "F.Fab")
		)
		(fp_line
			(start 0.12065 -0.3048)
			(end 0.67945 -0.3048)
			(stroke
				(width 0.1)
				(type default)
			)
			(layer "F.Fab")
		)
		(fp_line
			(start 0.12065 -0.2794)
			(end 0.12065 -0.3048)
			(stroke
				(width 0.1)
				(type default)
			)
			(layer "F.Fab")
		)
		(fp_line
			(start 0.67945 -0.3048)
			(end 0.67945 0.3048)
			(stroke
				(width 0.1)
				(type default)
			)
			(layer "F.Fab")
		)
		(fp_line
			(start 0.67945 0.3048)
			(end 0.120396 0.3048)
			(stroke
				(width 0.1)
				(type default)
			)
			(layer "F.Fab")
		)
		(pad "1" smd circle
			(at -0.40005 0)
			(size 0 0)
			(layers "F.Cu" "F.Mask" "F.Paste")
			(net "SMB_ISO_SSD10_R_SDA")
		)
		(pad "2" smd circle
			(at 0.40005 0)
			(size 0 0)
			(layers "F.Cu" "F.Mask" "F.Paste")
			(net "SMB_ISO_SSD10_SDA")
		)
	)
	(footprint ""
		(layer "F.Cu")
		(at 332.679548 -193.669412)
		(property "Reference" "U324"
			(at -1.311148 -4.804918 0)
			(unlocked yes)
			(layer "F.SilkS")
			(effects
				(font
					(size 0.7874 0.5842)
					(thickness 0.1524)
				)
				(justify left)
			)
		)
		(property "Value" ""
			(at 0 0 0)
			(layer "F.Fab")
			(effects
				(font
					(size 1.27 1.27)
				)
			)
		)
		(duplicate_pad_numbers_are_jumpers no)
		(fp_line
			(start -2.097532 -3.949954)
			(end -2.097532 3.949954)
			(stroke
				(width 0.1524)
				(type default)
			)
			(layer "F.SilkS")
		)
		(fp_line
			(start -2.097532 3.949954)
			(end 2.097532 3.949954)
			(stroke
				(width 0.1524)
				(type default)
			)
			(layer "F.SilkS")
		)
		(fp_line
			(start -1.409954 -3.949954)
			(end -2.097532 -3.949954)
			(stroke
				(width 0.1524)
				(type default)
			)
			(layer "F.SilkS")
		)
		(fp_line
			(start 0 -2.54)
			(end -1.409954 -3.949954)
			(stroke
				(width 0.1524)
				(type default)
			)
			(layer "F.SilkS")
		)
		(fp_line
			(start 1.409954 -3.949954)
			(end 0 -2.54)
			(stroke
				(width 0.1524)
				(type default)
			)
			(layer "F.SilkS")
		)
		(fp_line
			(start 2.097532 -3.949954)
			(end 1.409954 -3.949954)
			(stroke
				(width 0.1524)
				(type default)
			)
			(layer "F.SilkS")
		)
		(fp_line
			(start 2.097532 3.949954)
			(end 2.097532 -3.949954)
			(stroke
				(width 0.1524)
				(type default)
			)
			(layer "F.SilkS")
		)
		(fp_poly
			(pts
				(xy -4.132072 -4.97205) (xy -4.850638 -4.253738) (xy -3.772916 -3.894582)
			)
			(stroke
				(width 0)
				(type default)
			)
			(fill yes)
			(layer "F.SilkS")
		)
		(fp_line
			(start -2.249932 -3.949954)
			(end -2.249932 3.949954)
			(stroke
				(width 0.1)
				(type default)
			)
			(layer "F.Fab")
		)
		(fp_line
			(start -2.249932 3.949954)
			(end 2.249932 3.949954)
			(stroke
				(width 0.1)
				(type default)
			)
			(layer "F.Fab")
		)
		(fp_line
			(start 2.249932 -3.949954)
			(end -2.249932 -3.949954)
			(stroke
				(width 0.1)
				(type default)
			)
			(layer "F.Fab")
		)
		(fp_line
			(start 2.249932 3.949954)
			(end 2.249932 -3.949954)
			(stroke
				(width 0.1)
				(type default)
			)
			(layer "F.Fab")
		)
		(fp_poly
			(pts
				(xy -4.7498 -4.182872) (xy -4.7498 -3.166872) (xy -3.7338 -3.674872)
			)
			(stroke
				(width 0)
				(type default)
			)
			(fill yes)
			(layer "F.Fab")
		)
		(pad "1" smd rect
			(at -2.925064 -3.674872 270)
			(size 0.6096 1.3716)
			(layers "F.Cu" "F.Mask" "F.Paste")
			(net "IRQ_IOEXP_DBV2_N")
		)
		(pad "2" smd rect
			(at -2.925064 -2.925064 270)
			(size 0.4064 1.3716)
			(layers "F.Cu" "F.Mask" "F.Paste")
			(net "IOEXP_DBV2_A1")
		)
		(pad "3" smd rect
			(at -2.925064 -2.275078 270)
			(size 0.4064 1.3716)
			(layers "F.Cu" "F.Mask" "F.Paste")
			(net "IOEXP_DBV2_A2")
		)
		(pad "4" smd rect
			(at -2.925064 -1.625092 270)
			(size 0.4064 1.3716)
			(layers "F.Cu" "F.Mask" "F.Paste")
			(net "LED_POSTCODE_0")
		)
		(pad "5" smd rect
			(at -2.925064 -0.975106 270)
			(size 0.4064 1.3716)
			(layers "F.Cu" "F.Mask" "F.Paste")
			(net "LED_POSTCODE_1")
		)
		(pad "6" smd rect
			(at -2.925064 -0.32512 270)
			(size 0.4064 1.3716)
			(layers "F.Cu" "F.Mask" "F.Paste")
			(net "LED_POSTCODE_2")
		)
		(pad "7" smd rect
			(at -2.925064 0.32512 270)
			(size 0.4064 1.3716)
			(layers "F.Cu" "F.Mask" "F.Paste")
			(net "LED_POSTCODE_3")
		)
		(pad "8" smd rect
			(at -2.925064 0.975106 270)
			(size 0.4064 1.3716)
			(layers "F.Cu" "F.Mask" "F.Paste")
			(net "LED_POSTCODE_4")
		)
		(pad "9" smd rect
			(at -2.925064 1.625092 270)
			(size 0.4064 1.3716)
			(layers "F.Cu" "F.Mask" "F.Paste")
			(net "LED_POSTCODE_5")
		)
		(pad "10" smd rect
			(at -2.925064 2.275078 270)
			(size 0.4064 1.3716)
			(layers "F.Cu" "F.Mask" "F.Paste")
			(net "LED_POSTCODE_6")
		)
		(pad "11" smd rect
			(at -2.925064 2.925064 270)
			(size 0.4064 1.3716)
			(layers "F.Cu" "F.Mask" "F.Paste")
			(net "LED_POSTCODE_7")
		)
		(pad "12" smd rect
			(at -2.925064 3.674872 270)
			(size 0.6096 1.3716)
			(layers "F.Cu" "F.Mask" "F.Paste")
			(net "GND")
		)
		(pad "13" smd rect
			(at 2.925064 3.674872 270)
			(size 0.6096 1.3716)
			(layers "F.Cu" "F.Mask" "F.Paste")
			(net "USB_DEBUG_RST_BTN_N")
		)
		(pad "14" smd rect
			(at 2.925064 2.925064 270)
			(size 0.4064 1.3716)
			(layers "F.Cu" "F.Mask" "F.Paste")
			(net "USB_DEBUG_PWR_BTN_N")
		)
		(pad "15" smd rect
			(at 2.925064 2.275078 270)
			(size 0.4064 1.3716)
			(layers "F.Cu" "F.Mask" "F.Paste")
			(net "PWRGD_SYS_PWROK")
		)
		(pad "16" smd rect
			(at 2.925064 1.625092 270)
			(size 0.4064 1.3716)
			(layers "F.Cu" "F.Mask" "F.Paste")
			(net "RST_PLTRST_N")
		)
		(pad "17" smd rect
			(at 2.925064 0.975106 270)
			(size 0.4064 1.3716)
			(layers "F.Cu" "F.Mask" "F.Paste")
			(net "PWRGD_DSW_PWROK")
		)
		(pad "18" smd rect
			(at 2.925064 0.32512 270)
			(size 0.4064 1.3716)
			(layers "F.Cu" "F.Mask" "F.Paste")
			(net "FM_CPU_CATERR_MSMI_LVT3_N")
		)
		(pad "19" smd rect
			(at 2.925064 -0.32512 270)
			(size 0.4064 1.3716)
			(layers "F.Cu" "F.Mask" "F.Paste")
			(net "FM_SLPS3_N")
		)
		(pad "20" smd rect
			(at 2.925064 -0.975106 270)
			(size 0.4064 1.3716)
			(layers "F.Cu" "F.Mask" "F.Paste")
			(net "FM_SOL_UART_CH_SEL")
		)
		(pad "21" smd rect
			(at 2.925064 -1.625092 270)
			(size 0.4064 1.3716)
			(layers "F.Cu" "F.Mask" "F.Paste")
			(net "IOEXP_DBV2_A0")
		)
		(pad "22" smd rect
			(at 2.925064 -2.275078 270)
			(size 0.4064 1.3716)
			(layers "F.Cu" "F.Mask" "F.Paste")
			(net "SMB_IO_DEBUG_CARD_R_SCL")
		)
		(pad "23" smd rect
			(at 2.925064 -2.925064 270)
			(size 0.4064 1.3716)
			(layers "F.Cu" "F.Mask" "F.Paste")
			(net "SMB_IO_DEBUG_CARD_R_SDA")
		)
		(pad "24" smd rect
			(at 2.925064 -3.674872 270)
			(size 0.6096 1.3716)
			(layers "F.Cu" "F.Mask" "F.Paste")
			(net "P3V3_AUX")
		)
	)
	(footprint ""
		(layer "F.Cu")
		(at 295.877742 -117.566186)
		(property "Reference" "R296"
			(at 0 0 0)
			(layer "F.SilkS")
			(hide yes)
			(effects
				(font
					(size 1.27 1.27)
				)
			)
		)
		(property "Value" ""
			(at 0 0 0)
			(layer "F.Fab")
			(effects
				(font
					(size 1.27 1.27)
				)
			)
		)
		(duplicate_pad_numbers_are_jumpers no)
		(fp_line
			(start -0.7874 -0.4064)
			(end 0.7874 -0.4064)
			(stroke
				(width 0.1524)
				(type default)
			)
			(layer "F.SilkS")
		)
		(fp_line
			(start -0.7874 0.4064)
			(end -0.7874 -0.4064)
			(stroke
				(width 0.1524)
				(type default)
			)
			(layer "F.SilkS")
		)
		(fp_line
			(start 0.7874 -0.4064)
			(end 0.7874 0.4064)
			(stroke
				(width 0.1524)
				(type default)
			)
			(layer "F.SilkS")
		)
		(fp_line
			(start 0.7874 0.4064)
			(end -0.7874 0.4064)
			(stroke
				(width 0.1524)
				(type default)
			)
			(layer "F.SilkS")
		)
		(fp_line
			(start -0.67945 -0.305054)
			(end -0.12065 -0.305054)
			(stroke
				(width 0.1)
				(type default)
			)
			(layer "F.Fab")
		)
		(fp_line
			(start -0.67945 0.3048)
			(end -0.67945 -0.305054)
			(stroke
				(width 0.1)
				(type default)
			)
			(layer "F.Fab")
		)
		(fp_line
			(start -0.12065 -0.305054)
			(end -0.12065 -0.2794)
			(stroke
				(width 0.1)
				(type default)
			)
			(layer "F.Fab")
		)
		(fp_line
			(start -0.12065 -0.2794)
			(end 0.12065 -0.2794)
			(stroke
				(width 0.1)
				(type default)
			)
			(layer "F.Fab")
		)
		(fp_line
			(start -0.12065 0.2794)
			(end -0.12065 0.3048)
			(stroke
				(width 0.1)
				(type default)
			)
			(layer "F.Fab")
		)
		(fp_line
			(start -0.12065 0.3048)
			(end -0.67945 0.3048)
			(stroke
				(width 0.1)
				(type default)
			)
			(layer "F.Fab")
		)
		(fp_line
			(start 0.120396 0.2794)
			(end -0.12065 0.2794)
			(stroke
				(width 0.1)
				(type default)
			)
			(layer "F.Fab")
		)
		(fp_line
			(start 0.120396 0.3048)
			(end 0.120396 0.2794)
			(stroke
				(width 0.1)
				(type default)
			)
			(layer "F.Fab")
		)
		(fp_line
			(start 0.12065 -0.3048)
			(end 0.67945 -0.3048)
			(stroke
				(width 0.1)
				(type default)
			)
			(layer "F.Fab")
		)
		(fp_line
			(start 0.12065 -0.2794)
			(end 0.12065 -0.3048)
			(stroke
				(width 0.1)
				(type default)
			)
			(layer "F.Fab")
		)
		(fp_line
			(start 0.67945 -0.3048)
			(end 0.67945 0.3048)
			(stroke
				(width 0.1)
				(type default)
			)
			(layer "F.Fab")
		)
		(fp_line
			(start 0.67945 0.3048)
			(end 0.120396 0.3048)
			(stroke
				(width 0.1)
				(type default)
			)
			(layer "F.Fab")
		)
		(pad "1" smd circle
			(at -0.40005 0)
			(size 0 0)
			(layers "F.Cu" "F.Mask" "F.Paste")
			(net "PRSNT_NIC5_N")
		)
		(pad "2" smd circle
			(at 0.40005 0)
			(size 0 0)
			(layers "F.Cu" "F.Mask" "F.Paste")
			(net "PRSNTB2_NIC5_N")
		)
	)
	(footprint ""
		(layer "F.Cu")
		(at 396.03426 -356.244906 90)
		(property "Reference" "C736"
			(at 0 0 90)
			(layer "F.SilkS")
			(hide yes)
			(effects
				(font
					(size 1.27 1.27)
				)
			)
		)
		(property "Value" ""
			(at 0 0 90)
			(layer "F.Fab")
			(effects
				(font
					(size 1.27 1.27)
				)
			)
		)
		(duplicate_pad_numbers_are_jumpers no)
		(fp_line
			(start 0.299974 -0.150114)
			(end 0.299974 0.150114)
			(stroke
				(width 0.1)
				(type default)
			)
			(layer "F.Fab")
		)
		(fp_line
			(start -0.299974 -0.150114)
			(end 0.299974 -0.150114)
			(stroke
				(width 0.1)
				(type default)
			)
			(layer "F.Fab")
		)
		(fp_line
			(start 0.299974 0.150114)
			(end -0.299974 0.150114)
			(stroke
				(width 0.1)
				(type default)
			)
			(layer "F.Fab")
		)
		(fp_line
			(start -0.299974 0.150114)
			(end -0.299974 -0.150114)
			(stroke
				(width 0.1)
				(type default)
			)
			(layer "F.Fab")
		)
		(pad "1" smd rect
			(at -0.2667 0 90)
			(size 0.3048 0.381)
			(layers "F.Cu" "F.Mask" "F.Paste")
			(net "P5E_PEX3_STN5_TX_DP<92>")
		)
		(pad "2" smd rect
			(at 0.2667 0 90)
			(size 0.3048 0.381)
			(layers "F.Cu" "F.Mask" "F.Paste")
			(net "P5E_PEX3_STN5_TX_C_DP<92>")
		)
	)
	(footprint ""
		(layer "F.Cu")
		(at 98.975672 -118.467886)
		(property "Reference" "PC470"
			(at 0 0 0)
			(layer "F.SilkS")
			(hide yes)
			(effects
				(font
					(size 1.27 1.27)
				)
			)
		)
		(property "Value" ""
			(at 0 0 0)
			(layer "F.Fab")
			(effects
				(font
					(size 1.27 1.27)
				)
			)
		)
		(duplicate_pad_numbers_are_jumpers no)
		(fp_line
			(start -0.7874 -0.4064)
			(end 0.7874 -0.4064)
			(stroke
				(width 0.1524)
				(type default)
			)
			(layer "F.SilkS")
		)
		(fp_line
			(start -0.7874 0.4064)
			(end -0.7874 -0.4064)
			(stroke
				(width 0.1524)
				(type default)
			)
			(layer "F.SilkS")
		)
		(fp_line
			(start 0.7874 -0.4064)
			(end 0.7874 0.4064)
			(stroke
				(width 0.1524)
				(type default)
			)
			(layer "F.SilkS")
		)
		(fp_line
			(start 0.7874 0.4064)
			(end -0.7874 0.4064)
			(stroke
				(width 0.1524)
				(type default)
			)
			(layer "F.SilkS")
		)
		(fp_line
			(start -0.67945 -0.305054)
			(end -0.12065 -0.305054)
			(stroke
				(width 0.1)
				(type default)
			)
			(layer "F.Fab")
		)
		(fp_line
			(start -0.67945 0.3048)
			(end -0.67945 -0.305054)
			(stroke
				(width 0.1)
				(type default)
			)
			(layer "F.Fab")
		)
		(fp_line
			(start -0.12065 -0.305054)
			(end -0.12065 -0.2794)
			(stroke
				(width 0.1)
				(type default)
			)
			(layer "F.Fab")
		)
		(fp_line
			(start -0.12065 -0.2794)
			(end 0.12065 -0.2794)
			(stroke
				(width 0.1)
				(type default)
			)
			(layer "F.Fab")
		)
		(fp_line
			(start -0.12065 0.2794)
			(end -0.12065 0.3048)
			(stroke
				(width 0.1)
				(type default)
			)
			(layer "F.Fab")
		)
		(fp_line
			(start -0.12065 0.3048)
			(end -0.67945 0.3048)
			(stroke
				(width 0.1)
				(type default)
			)
			(layer "F.Fab")
		)
		(fp_line
			(start 0.120396 0.2794)
			(end -0.12065 0.2794)
			(stroke
				(width 0.1)
				(type default)
			)
			(layer "F.Fab")
		)
		(fp_line
			(start 0.120396 0.3048)
			(end 0.120396 0.2794)
			(stroke
				(width 0.1)
				(type default)
			)
			(layer "F.Fab")
		)
		(fp_line
			(start 0.12065 -0.3048)
			(end 0.67945 -0.3048)
			(stroke
				(width 0.1)
				(type default)
			)
			(layer "F.Fab")
		)
		(fp_line
			(start 0.12065 -0.2794)
			(end 0.12065 -0.3048)
			(stroke
				(width 0.1)
				(type default)
			)
			(layer "F.Fab")
		)
		(fp_line
			(start 0.67945 -0.3048)
			(end 0.67945 0.3048)
			(stroke
				(width 0.1)
				(type default)
			)
			(layer "F.Fab")
		)
		(fp_line
			(start 0.67945 0.3048)
			(end 0.120396 0.3048)
			(stroke
				(width 0.1)
				(type default)
			)
			(layer "F.Fab")
		)
		(pad "1" smd circle
			(at -0.40005 0)
			(size 0 0)
			(layers "F.Cu" "F.Mask" "F.Paste")
			(net "P3V3_NIC1_SS")
		)
		(pad "2" smd circle
			(at 0.40005 0)
			(size 0 0)
			(layers "F.Cu" "F.Mask" "F.Paste")
			(net "GND")
		)
	)
	(footprint ""
		(layer "F.Cu")
		(at 322.217542 -304.036476 90)
		(property "Reference" "R1384"
			(at 0 0 90)
			(layer "F.SilkS")
			(hide yes)
			(effects
				(font
					(size 1.27 1.27)
				)
			)
		)
		(property "Value" ""
			(at 0 0 90)
			(layer "F.Fab")
			(effects
				(font
					(size 1.27 1.27)
				)
			)
		)
		(duplicate_pad_numbers_are_jumpers no)
		(fp_line
			(start 0.7874 -0.4064)
			(end 0.7874 0.4064)
			(stroke
				(width 0.1524)
				(type default)
			)
			(layer "F.SilkS")
		)
		(fp_line
			(start -0.7874 -0.4064)
			(end 0.7874 -0.4064)
			(stroke
				(width 0.1524)
				(type default)
			)
			(layer "F.SilkS")
		)
		(fp_line
			(start 0.7874 0.4064)
			(end -0.7874 0.4064)
			(stroke
				(width 0.1524)
				(type default)
			)
			(layer "F.SilkS")
		)
		(fp_line
			(start -0.7874 0.4064)
			(end -0.7874 -0.4064)
			(stroke
				(width 0.1524)
				(type default)
			)
			(layer "F.SilkS")
		)
		(fp_line
			(start -0.12065 -0.305054)
			(end -0.12065 -0.2794)
			(stroke
				(width 0.1)
				(type default)
			)
			(layer "F.Fab")
		)
		(fp_line
			(start -0.67945 -0.305054)
			(end -0.12065 -0.305054)
			(stroke
				(width 0.1)
				(type default)
			)
			(layer "F.Fab")
		)
		(fp_line
			(start 0.67945 -0.3048)
			(end 0.67945 0.3048)
			(stroke
				(width 0.1)
				(type default)
			)
			(layer "F.Fab")
		)
		(fp_line
			(start 0.12065 -0.3048)
			(end 0.67945 -0.3048)
			(stroke
				(width 0.1)
				(type default)
			)
			(layer "F.Fab")
		)
		(fp_line
			(start 0.12065 -0.2794)
			(end 0.12065 -0.3048)
			(stroke
				(width 0.1)
				(type default)
			)
			(layer "F.Fab")
		)
		(fp_line
			(start -0.12065 -0.2794)
			(end 0.12065 -0.2794)
			(stroke
				(width 0.1)
				(type default)
			)
			(layer "F.Fab")
		)
		(fp_line
			(start 0.120396 0.2794)
			(end -0.12065 0.2794)
			(stroke
				(width 0.1)
				(type default)
			)
			(layer "F.Fab")
		)
		(fp_line
			(start -0.12065 0.2794)
			(end -0.12065 0.3048)
			(stroke
				(width 0.1)
				(type default)
			)
			(layer "F.Fab")
		)
		(fp_line
			(start 0.67945 0.3048)
			(end 0.120396 0.3048)
			(stroke
				(width 0.1)
				(type default)
			)
			(layer "F.Fab")
		)
		(fp_line
			(start 0.120396 0.3048)
			(end 0.120396 0.2794)
			(stroke
				(width 0.1)
				(type default)
			)
			(layer "F.Fab")
		)
		(fp_line
			(start -0.12065 0.3048)
			(end -0.67945 0.3048)
			(stroke
				(width 0.1)
				(type default)
			)
			(layer "F.Fab")
		)
		(fp_line
			(start -0.67945 0.3048)
			(end -0.67945 -0.305054)
			(stroke
				(width 0.1)
				(type default)
			)
			(layer "F.Fab")
		)
		(pad "1" smd circle
			(at -0.40005 0 90)
			(size 0 0)
			(layers "F.Cu" "F.Mask" "F.Paste")
			(net "GND")
		)
		(pad "2" smd circle
			(at 0.40005 0 90)
			(size 0 0)
			(layers "F.Cu" "F.Mask" "F.Paste")
			(net "PEX2_SPARE3")
		)
	)
	(footprint ""
		(layer "F.Cu")
		(at 153.650442 -252.356874 -90)
		(property "Reference" "R1299"
			(at 0 0 270)
			(layer "F.SilkS")
			(hide yes)
			(effects
				(font
					(size 1.27 1.27)
				)
			)
		)
		(property "Value" ""
			(at 0 0 270)
			(layer "F.Fab")
			(effects
				(font
					(size 1.27 1.27)
				)
			)
		)
		(duplicate_pad_numbers_are_jumpers no)
		(fp_line
			(start -0.7874 0.4064)
			(end -0.7874 -0.4064)
			(stroke
				(width 0.1524)
				(type default)
			)
			(layer "F.SilkS")
		)
		(fp_line
			(start 0.7874 0.4064)
			(end -0.7874 0.4064)
			(stroke
				(width 0.1524)
				(type default)
			)
			(layer "F.SilkS")
		)
		(fp_line
			(start -0.7874 -0.4064)
			(end 0.7874 -0.4064)
			(stroke
				(width 0.1524)
				(type default)
			)
			(layer "F.SilkS")
		)
		(fp_line
			(start 0.7874 -0.4064)
			(end 0.7874 0.4064)
			(stroke
				(width 0.1524)
				(type default)
			)
			(layer "F.SilkS")
		)
		(fp_line
			(start -0.67945 0.3048)
			(end -0.67945 -0.305054)
			(stroke
				(width 0.1)
				(type default)
			)
			(layer "F.Fab")
		)
		(fp_line
			(start -0.12065 0.3048)
			(end -0.67945 0.3048)
			(stroke
				(width 0.1)
				(type default)
			)
			(layer "F.Fab")
		)
		(fp_line
			(start 0.120396 0.3048)
			(end 0.120396 0.2794)
			(stroke
				(width 0.1)
				(type default)
			)
			(layer "F.Fab")
		)
		(fp_line
			(start 0.67945 0.3048)
			(end 0.120396 0.3048)
			(stroke
				(width 0.1)
				(type default)
			)
			(layer "F.Fab")
		)
		(fp_line
			(start -0.12065 0.2794)
			(end -0.12065 0.3048)
			(stroke
				(width 0.1)
				(type default)
			)
			(layer "F.Fab")
		)
		(fp_line
			(start 0.120396 0.2794)
			(end -0.12065 0.2794)
			(stroke
				(width 0.1)
				(type default)
			)
			(layer "F.Fab")
		)
		(fp_line
			(start -0.12065 -0.2794)
			(end 0.12065 -0.2794)
			(stroke
				(width 0.1)
				(type default)
			)
			(layer "F.Fab")
		)
		(fp_line
			(start 0.12065 -0.2794)
			(end 0.12065 -0.3048)
			(stroke
				(width 0.1)
				(type default)
			)
			(layer "F.Fab")
		)
		(fp_line
			(start 0.12065 -0.3048)
			(end 0.67945 -0.3048)
			(stroke
				(width 0.1)
				(type default)
			)
			(layer "F.Fab")
		)
		(fp_line
			(start 0.67945 -0.3048)
			(end 0.67945 0.3048)
			(stroke
				(width 0.1)
				(type default)
			)
			(layer "F.Fab")
		)
		(fp_line
			(start -0.67945 -0.305054)
			(end -0.12065 -0.305054)
			(stroke
				(width 0.1)
				(type default)
			)
			(layer "F.Fab")
		)
		(fp_line
			(start -0.12065 -0.305054)
			(end -0.12065 -0.2794)
			(stroke
				(width 0.1)
				(type default)
			)
			(layer "F.Fab")
		)
		(pad "1" smd circle
			(at -0.40005 0 270)
			(size 0 0)
			(layers "F.Cu" "F.Mask" "F.Paste")
			(net "GND")
		)
		(pad "2" smd circle
			(at 0.40005 0 270)
			(size 0 0)
			(layers "F.Cu" "F.Mask" "F.Paste")
			(net "PEX1_MODE_SEL10")
		)
	)
	(footprint ""
		(layer "F.Cu")
		(at 124.07519 -105.134918 90)
		(property "Reference" "R5827"
			(at 0 0 90)
			(layer "F.SilkS")
			(hide yes)
			(effects
				(font
					(size 1.27 1.27)
				)
			)
		)
		(property "Value" ""
			(at 0 0 90)
			(layer "F.Fab")
			(effects
				(font
					(size 1.27 1.27)
				)
			)
		)
		(duplicate_pad_numbers_are_jumpers no)
		(fp_line
			(start 0.7874 -0.4064)
			(end 0.7874 0.4064)
			(stroke
				(width 0.1524)
				(type default)
			)
			(layer "F.SilkS")
		)
		(fp_line
			(start -0.7874 -0.4064)
			(end 0.7874 -0.4064)
			(stroke
				(width 0.1524)
				(type default)
			)
			(layer "F.SilkS")
		)
		(fp_line
			(start 0.7874 0.4064)
			(end -0.7874 0.4064)
			(stroke
				(width 0.1524)
				(type default)
			)
			(layer "F.SilkS")
		)
		(fp_line
			(start -0.7874 0.4064)
			(end -0.7874 -0.4064)
			(stroke
				(width 0.1524)
				(type default)
			)
			(layer "F.SilkS")
		)
		(fp_line
			(start -0.12065 -0.305054)
			(end -0.12065 -0.2794)
			(stroke
				(width 0.1)
				(type default)
			)
			(layer "F.Fab")
		)
		(fp_line
			(start -0.67945 -0.305054)
			(end -0.12065 -0.305054)
			(stroke
				(width 0.1)
				(type default)
			)
			(layer "F.Fab")
		)
		(fp_line
			(start 0.67945 -0.3048)
			(end 0.67945 0.3048)
			(stroke
				(width 0.1)
				(type default)
			)
			(layer "F.Fab")
		)
		(fp_line
			(start 0.12065 -0.3048)
			(end 0.67945 -0.3048)
			(stroke
				(width 0.1)
				(type default)
			)
			(layer "F.Fab")
		)
		(fp_line
			(start 0.12065 -0.2794)
			(end 0.12065 -0.3048)
			(stroke
				(width 0.1)
				(type default)
			)
			(layer "F.Fab")
		)
		(fp_line
			(start -0.12065 -0.2794)
			(end 0.12065 -0.2794)
			(stroke
				(width 0.1)
				(type default)
			)
			(layer "F.Fab")
		)
		(fp_line
			(start 0.120396 0.2794)
			(end -0.12065 0.2794)
			(stroke
				(width 0.1)
				(type default)
			)
			(layer "F.Fab")
		)
		(fp_line
			(start -0.12065 0.2794)
			(end -0.12065 0.3048)
			(stroke
				(width 0.1)
				(type default)
			)
			(layer "F.Fab")
		)
		(fp_line
			(start 0.67945 0.3048)
			(end 0.120396 0.3048)
			(stroke
				(width 0.1)
				(type default)
			)
			(layer "F.Fab")
		)
		(fp_line
			(start 0.120396 0.3048)
			(end 0.120396 0.2794)
			(stroke
				(width 0.1)
				(type default)
			)
			(layer "F.Fab")
		)
		(fp_line
			(start -0.12065 0.3048)
			(end -0.67945 0.3048)
			(stroke
				(width 0.1)
				(type default)
			)
			(layer "F.Fab")
		)
		(fp_line
			(start -0.67945 0.3048)
			(end -0.67945 -0.305054)
			(stroke
				(width 0.1)
				(type default)
			)
			(layer "F.Fab")
		)
		(pad "1" smd circle
			(at -0.40005 0 90)
			(size 0 0)
			(layers "F.Cu" "F.Mask" "F.Paste")
			(net "P3V3_AUX")
		)
		(pad "2" smd circle
			(at 0.40005 0 90)
			(size 0 0)
			(layers "F.Cu" "F.Mask" "F.Paste")
			(net "P3V3_PG_G2")
		)
	)
	(footprint ""
		(layer "F.Cu")
		(at 359.156 -185.166)
		(property "Reference" "R4601"
			(at 0 0 0)
			(layer "F.SilkS")
			(hide yes)
			(effects
				(font
					(size 1.27 1.27)
				)
			)
		)
		(property "Value" ""
			(at 0 0 0)
			(layer "F.Fab")
			(effects
				(font
					(size 1.27 1.27)
				)
			)
		)
		(duplicate_pad_numbers_are_jumpers no)
		(fp_line
			(start -0.7874 -0.4064)
			(end 0.7874 -0.4064)
			(stroke
				(width 0.1524)
				(type default)
			)
			(layer "F.SilkS")
		)
		(fp_line
			(start -0.7874 0.4064)
			(end -0.7874 -0.4064)
			(stroke
				(width 0.1524)
				(type default)
			)
			(layer "F.SilkS")
		)
		(fp_line
			(start 0.7874 -0.4064)
			(end 0.7874 0.4064)
			(stroke
				(width 0.1524)
				(type default)
			)
			(layer "F.SilkS")
		)
		(fp_line
			(start 0.7874 0.4064)
			(end -0.7874 0.4064)
			(stroke
				(width 0.1524)
				(type default)
			)
			(layer "F.SilkS")
		)
		(fp_line
			(start -0.67945 -0.305054)
			(end -0.12065 -0.305054)
			(stroke
				(width 0.1)
				(type default)
			)
			(layer "F.Fab")
		)
		(fp_line
			(start -0.67945 0.3048)
			(end -0.67945 -0.305054)
			(stroke
				(width 0.1)
				(type default)
			)
			(layer "F.Fab")
		)
		(fp_line
			(start -0.12065 -0.305054)
			(end -0.12065 -0.2794)
			(stroke
				(width 0.1)
				(type default)
			)
			(layer "F.Fab")
		)
		(fp_line
			(start -0.12065 -0.2794)
			(end 0.12065 -0.2794)
			(stroke
				(width 0.1)
				(type default)
			)
			(layer "F.Fab")
		)
		(fp_line
			(start -0.12065 0.2794)
			(end -0.12065 0.3048)
			(stroke
				(width 0.1)
				(type default)
			)
			(layer "F.Fab")
		)
		(fp_line
			(start -0.12065 0.3048)
			(end -0.67945 0.3048)
			(stroke
				(width 0.1)
				(type default)
			)
			(layer "F.Fab")
		)
		(fp_line
			(start 0.120396 0.2794)
			(end -0.12065 0.2794)
			(stroke
				(width 0.1)
				(type default)
			)
			(layer "F.Fab")
		)
		(fp_line
			(start 0.120396 0.3048)
			(end 0.120396 0.2794)
			(stroke
				(width 0.1)
				(type default)
			)
			(layer "F.Fab")
		)
		(fp_line
			(start 0.12065 -0.3048)
			(end 0.67945 -0.3048)
			(stroke
				(width 0.1)
				(type default)
			)
			(layer "F.Fab")
		)
		(fp_line
			(start 0.12065 -0.2794)
			(end 0.12065 -0.3048)
			(stroke
				(width 0.1)
				(type default)
			)
			(layer "F.Fab")
		)
		(fp_line
			(start 0.67945 -0.3048)
			(end 0.67945 0.3048)
			(stroke
				(width 0.1)
				(type default)
			)
			(layer "F.Fab")
		)
		(fp_line
			(start 0.67945 0.3048)
			(end 0.120396 0.3048)
			(stroke
				(width 0.1)
				(type default)
			)
			(layer "F.Fab")
		)
		(pad "1" smd circle
			(at -0.40005 0)
			(size 0 0)
			(layers "F.Cu" "F.Mask" "F.Paste")
			(net "P3V3_AUX")
		)
		(pad "2" smd circle
			(at 0.40005 0)
			(size 0 0)
			(layers "F.Cu" "F.Mask" "F.Paste")
			(net "SSD3_PEX_PWR_EN_R")
		)
	)
	(footprint ""
		(layer "F.Cu")
		(at 364.945168 -395.463014 -90)
		(property "Reference" "R6772"
			(at 0 0 270)
			(layer "F.SilkS")
			(hide yes)
			(effects
				(font
					(size 1.27 1.27)
				)
			)
		)
		(property "Value" ""
			(at 0 0 270)
			(layer "F.Fab")
			(effects
				(font
					(size 1.27 1.27)
				)
			)
		)
		(duplicate_pad_numbers_are_jumpers no)
		(fp_line
			(start -0.7874 0.4064)
			(end -0.7874 -0.4064)
			(stroke
				(width 0.1524)
				(type default)
			)
			(layer "F.SilkS")
		)
		(fp_line
			(start 0.7874 0.4064)
			(end -0.7874 0.4064)
			(stroke
				(width 0.1524)
				(type default)
			)
			(layer "F.SilkS")
		)
		(fp_line
			(start -0.7874 -0.4064)
			(end 0.7874 -0.4064)
			(stroke
				(width 0.1524)
				(type default)
			)
			(layer "F.SilkS")
		)
		(fp_line
			(start 0.7874 -0.4064)
			(end 0.7874 0.4064)
			(stroke
				(width 0.1524)
				(type default)
			)
			(layer "F.SilkS")
		)
		(fp_line
			(start -0.67945 0.3048)
			(end -0.67945 -0.305054)
			(stroke
				(width 0.1)
				(type default)
			)
			(layer "F.Fab")
		)
		(fp_line
			(start -0.12065 0.3048)
			(end -0.67945 0.3048)
			(stroke
				(width 0.1)
				(type default)
			)
			(layer "F.Fab")
		)
		(fp_line
			(start 0.120396 0.3048)
			(end 0.120396 0.2794)
			(stroke
				(width 0.1)
				(type default)
			)
			(layer "F.Fab")
		)
		(fp_line
			(start 0.67945 0.3048)
			(end 0.120396 0.3048)
			(stroke
				(width 0.1)
				(type default)
			)
			(layer "F.Fab")
		)
		(fp_line
			(start -0.12065 0.2794)
			(end -0.12065 0.3048)
			(stroke
				(width 0.1)
				(type default)
			)
			(layer "F.Fab")
		)
		(fp_line
			(start 0.120396 0.2794)
			(end -0.12065 0.2794)
			(stroke
				(width 0.1)
				(type default)
			)
			(layer "F.Fab")
		)
		(fp_line
			(start -0.12065 -0.2794)
			(end 0.12065 -0.2794)
			(stroke
				(width 0.1)
				(type default)
			)
			(layer "F.Fab")
		)
		(fp_line
			(start 0.12065 -0.2794)
			(end 0.12065 -0.3048)
			(stroke
				(width 0.1)
				(type default)
			)
			(layer "F.Fab")
		)
		(fp_line
			(start 0.12065 -0.3048)
			(end 0.67945 -0.3048)
			(stroke
				(width 0.1)
				(type default)
			)
			(layer "F.Fab")
		)
		(fp_line
			(start 0.67945 -0.3048)
			(end 0.67945 0.3048)
			(stroke
				(width 0.1)
				(type default)
			)
			(layer "F.Fab")
		)
		(fp_line
			(start -0.67945 -0.305054)
			(end -0.12065 -0.305054)
			(stroke
				(width 0.1)
				(type default)
			)
			(layer "F.Fab")
		)
		(fp_line
			(start -0.12065 -0.305054)
			(end -0.12065 -0.2794)
			(stroke
				(width 0.1)
				(type default)
			)
			(layer "F.Fab")
		)
		(pad "1" smd circle
			(at -0.40005 0 270)
			(size 0 0)
			(layers "F.Cu" "F.Mask" "F.Paste")
			(net "PRSNT_SWB_B1_N")
		)
		(pad "2" smd circle
			(at 0.40005 0 270)
			(size 0 0)
			(layers "F.Cu" "F.Mask" "F.Paste")
			(net "GND")
		)
	)
	(footprint ""
		(layer "F.Cu")
		(at 115.860068 -350.098614 90)
		(property "Reference" "C343"
			(at 0 0 90)
			(layer "F.SilkS")
			(hide yes)
			(effects
				(font
					(size 1.27 1.27)
				)
			)
		)
		(property "Value" ""
			(at 0 0 90)
			(layer "F.Fab")
			(effects
				(font
					(size 1.27 1.27)
				)
			)
		)
		(duplicate_pad_numbers_are_jumpers no)
		(fp_line
			(start 0.299974 -0.150114)
			(end 0.299974 0.150114)
			(stroke
				(width 0.1)
				(type default)
			)
			(layer "F.Fab")
		)
		(fp_line
			(start -0.299974 -0.150114)
			(end 0.299974 -0.150114)
			(stroke
				(width 0.1)
				(type default)
			)
			(layer "F.Fab")
		)
		(fp_line
			(start 0.299974 0.150114)
			(end -0.299974 0.150114)
			(stroke
				(width 0.1)
				(type default)
			)
			(layer "F.Fab")
		)
		(fp_line
			(start -0.299974 0.150114)
			(end -0.299974 -0.150114)
			(stroke
				(width 0.1)
				(type default)
			)
			(layer "F.Fab")
		)
		(pad "1" smd rect
			(at -0.2667 0 90)
			(size 0.3048 0.381)
			(layers "F.Cu" "F.Mask" "F.Paste")
			(net "P5E_PEX1_STN6_TX_DN<110>")
		)
		(pad "2" smd rect
			(at 0.2667 0 90)
			(size 0.3048 0.381)
			(layers "F.Cu" "F.Mask" "F.Paste")
			(net "P5E_PEX1_STN6_TX_C_DN<110>")
		)
	)
	(footprint ""
		(layer "F.Cu")
		(at 10.11047 -126.995428 180)
		(property "Reference" "PC458"
			(at 0 0 180)
			(layer "F.SilkS")
			(hide yes)
			(effects
				(font
					(size 1.27 1.27)
				)
			)
		)
		(property "Value" ""
			(at 0 0 180)
			(layer "F.Fab")
			(effects
				(font
					(size 1.27 1.27)
				)
			)
		)
		(duplicate_pad_numbers_are_jumpers no)
		(fp_line
			(start 0.7874 0.4064)
			(end -0.7874 0.4064)
			(stroke
				(width 0.1524)
				(type default)
			)
			(layer "F.SilkS")
		)
		(fp_line
			(start 0.7874 -0.4064)
			(end 0.7874 0.4064)
			(stroke
				(width 0.1524)
				(type default)
			)
			(layer "F.SilkS")
		)
		(fp_line
			(start -0.7874 0.4064)
			(end -0.7874 -0.4064)
			(stroke
				(width 0.1524)
				(type default)
			)
			(layer "F.SilkS")
		)
		(fp_line
			(start -0.7874 -0.4064)
			(end 0.7874 -0.4064)
			(stroke
				(width 0.1524)
				(type default)
			)
			(layer "F.SilkS")
		)
		(fp_line
			(start 0.67945 0.3048)
			(end 0.120396 0.3048)
			(stroke
				(width 0.1)
				(type default)
			)
			(layer "F.Fab")
		)
		(fp_line
			(start 0.67945 -0.3048)
			(end 0.67945 0.3048)
			(stroke
				(width 0.1)
				(type default)
			)
			(layer "F.Fab")
		)
		(fp_line
			(start 0.12065 -0.2794)
			(end 0.12065 -0.3048)
			(stroke
				(width 0.1)
				(type default)
			)
			(layer "F.Fab")
		)
		(fp_line
			(start 0.12065 -0.3048)
			(end 0.67945 -0.3048)
			(stroke
				(width 0.1)
				(type default)
			)
			(layer "F.Fab")
		)
		(fp_line
			(start 0.120396 0.3048)
			(end 0.120396 0.2794)
			(stroke
				(width 0.1)
				(type default)
			)
			(layer "F.Fab")
		)
		(fp_line
			(start 0.120396 0.2794)
			(end -0.12065 0.2794)
			(stroke
				(width 0.1)
				(type default)
			)
			(layer "F.Fab")
		)
		(fp_line
			(start -0.12065 0.3048)
			(end -0.67945 0.3048)
			(stroke
				(width 0.1)
				(type default)
			)
			(layer "F.Fab")
		)
		(fp_line
			(start -0.12065 0.2794)
			(end -0.12065 0.3048)
			(stroke
				(width 0.1)
				(type default)
			)
			(layer "F.Fab")
		)
		(fp_line
			(start -0.12065 -0.2794)
			(end 0.12065 -0.2794)
			(stroke
				(width 0.1)
				(type default)
			)
			(layer "F.Fab")
		)
		(fp_line
			(start -0.12065 -0.305054)
			(end -0.12065 -0.2794)
			(stroke
				(width 0.1)
				(type default)
			)
			(layer "F.Fab")
		)
		(fp_line
			(start -0.67945 0.3048)
			(end -0.67945 -0.305054)
			(stroke
				(width 0.1)
				(type default)
			)
			(layer "F.Fab")
		)
		(fp_line
			(start -0.67945 -0.305054)
			(end -0.12065 -0.305054)
			(stroke
				(width 0.1)
				(type default)
			)
			(layer "F.Fab")
		)
		(pad "1" smd circle
			(at -0.40005 0 180)
			(size 0 0)
			(layers "F.Cu" "F.Mask" "F.Paste")
			(net "P3V3_NIC0_SS")
		)
		(pad "2" smd circle
			(at 0.40005 0 180)
			(size 0 0)
			(layers "F.Cu" "F.Mask" "F.Paste")
			(net "GND")
		)
	)
	(footprint ""
		(layer "F.Cu")
		(at 10.530586 -146.099276 180)
		(property "Reference" "PC600"
			(at 0 0 180)
			(layer "F.SilkS")
			(hide yes)
			(effects
				(font
					(size 1.27 1.27)
				)
			)
		)
		(property "Value" ""
			(at 0 0 180)
			(layer "F.Fab")
			(effects
				(font
					(size 1.27 1.27)
				)
			)
		)
		(duplicate_pad_numbers_are_jumpers no)
		(fp_line
			(start 1.524 0.762)
			(end -1.524 0.762)
			(stroke
				(width 0.1524)
				(type default)
			)
			(layer "F.SilkS")
		)
		(fp_line
			(start 1.524 -0.762)
			(end 1.524 0.762)
			(stroke
				(width 0.1524)
				(type default)
			)
			(layer "F.SilkS")
		)
		(fp_line
			(start -1.524 0.762)
			(end -1.524 -0.762)
			(stroke
				(width 0.1524)
				(type default)
			)
			(layer "F.SilkS")
		)
		(fp_line
			(start -1.524 -0.762)
			(end 1.524 -0.762)
			(stroke
				(width 0.1524)
				(type default)
			)
			(layer "F.SilkS")
		)
		(fp_line
			(start 1.1049 0.724916)
			(end 1.1049 -0.724916)
			(stroke
				(width 0.1)
				(type default)
			)
			(layer "F.Fab")
		)
		(fp_line
			(start 1.1049 -0.724916)
			(end -1.1049 -0.724916)
			(stroke
				(width 0.1)
				(type default)
			)
			(layer "F.Fab")
		)
		(fp_line
			(start -1.1049 0.724916)
			(end 1.1049 0.724916)
			(stroke
				(width 0.1)
				(type default)
			)
			(layer "F.Fab")
		)
		(fp_line
			(start -1.1049 -0.724916)
			(end -1.1049 0.724916)
			(stroke
				(width 0.1)
				(type default)
			)
			(layer "F.Fab")
		)
		(pad "1" smd rect
			(at -0.889 0)
			(size 1.016 1.27)
			(layers "F.Cu" "F.Mask" "F.Paste")
			(net "P12V_NIC0_R")
		)
		(pad "2" smd rect
			(at 0.889 0)
			(size 1.016 1.27)
			(layers "F.Cu" "F.Mask" "F.Paste")
			(net "GND")
		)
	)
	(footprint ""
		(layer "F.Cu")
		(at 354.05441 -48.21809)
		(property "Reference" "PD69"
			(at -3.48361 2.29616 0)
			(unlocked yes)
			(layer "F.SilkS")
			(effects
				(font
					(size 0.7874 0.5842)
					(thickness 0.1524)
				)
				(justify left)
			)
		)
		(property "Value" ""
			(at 0 0 0)
			(layer "F.Fab")
			(effects
				(font
					(size 1.27 1.27)
				)
			)
		)
		(duplicate_pad_numbers_are_jumpers no)
		(fp_line
			(start -3.400044 -1.459992)
			(end 4.107942 -1.459992)
			(stroke
				(width 0.1524)
				(type default)
			)
			(layer "F.SilkS")
		)
		(fp_line
			(start -3.400044 1.459992)
			(end -3.400044 -1.459992)
			(stroke
				(width 0.1524)
				(type default)
			)
			(layer "F.SilkS")
		)
		(fp_line
			(start 4.107942 -1.459992)
			(end 4.107942 1.459992)
			(stroke
				(width 0.1524)
				(type default)
			)
			(layer "F.SilkS")
		)
		(fp_line
			(start 4.107942 1.459992)
			(end -3.400044 1.459992)
			(stroke
				(width 0.1524)
				(type default)
			)
			(layer "F.SilkS")
		)
		(fp_poly
			(pts
				(xy 4.107942 -1.459992) (xy 4.107942 1.459992) (xy 3.308096 1.459992) (xy 3.308096 -1.459992)
			)
			(stroke
				(width 0)
				(type default)
			)
			(fill yes)
			(layer "F.SilkS")
		)
		(fp_line
			(start -2.29997 -1.459992)
			(end 2.29997 -1.459992)
			(stroke
				(width 0.1)
				(type default)
			)
			(layer "F.Fab")
		)
		(fp_line
			(start -2.29997 1.459992)
			(end -2.29997 -1.459992)
			(stroke
				(width 0.1)
				(type default)
			)
			(layer "F.Fab")
		)
		(fp_line
			(start 2.29997 -1.459992)
			(end 2.29997 1.459992)
			(stroke
				(width 0.1)
				(type default)
			)
			(layer "F.Fab")
		)
		(fp_line
			(start 2.29997 1.459992)
			(end -2.29997 1.459992)
			(stroke
				(width 0.1)
				(type default)
			)
			(layer "F.Fab")
		)
		(fp_text user "+"
			(at -4.7752 -0.12065 0)
			(unlocked yes)
			(layer "F.SilkS")
			(effects
				(font
					(size 1.905 1.4224)
					(thickness 0.1524)
				)
				(justify left)
			)
		)
		(fp_text user "-"
			(at 5.4102 0.29845 180)
			(unlocked yes)
			(layer "F.SilkS")
			(effects
				(font
					(size 1.905 1.4224)
					(thickness 0.1524)
				)
				(justify left)
			)
		)
		(fp_text user "+"
			(at -4.7752 -0.12065 0)
			(unlocked yes)
			(layer "F.Fab")
			(effects
				(font
					(size 1.905 1.4224)
					(thickness 0.1524)
				)
				(justify left)
			)
		)
		(fp_text user "-"
			(at 5.4102 0.29845 180)
			(unlocked yes)
			(layer "F.Fab")
			(effects
				(font
					(size 1.905 1.4224)
					(thickness 0.1524)
				)
				(justify left)
			)
		)
		(pad "A" smd rect
			(at -1.999996 0 90)
			(size 1.7018 2.5146)
			(layers "F.Cu" "F.Mask" "F.Paste")
			(net "GND")
		)
		(pad "C" smd rect
			(at 1.999996 0 90)
			(size 1.7018 2.5146)
			(layers "F.Cu" "F.Mask" "F.Paste")
			(net "P3V3_SSD12")
		)
	)
	(footprint ""
		(layer "F.Cu")
		(at 335.154524 -350.098614 90)
		(property "Reference" "C572"
			(at 0 0 90)
			(layer "F.SilkS")
			(hide yes)
			(effects
				(font
					(size 1.27 1.27)
				)
			)
		)
		(property "Value" ""
			(at 0 0 90)
			(layer "F.Fab")
			(effects
				(font
					(size 1.27 1.27)
				)
			)
		)
		(duplicate_pad_numbers_are_jumpers no)
		(fp_line
			(start 0.299974 -0.150114)
			(end 0.299974 0.150114)
			(stroke
				(width 0.1)
				(type default)
			)
			(layer "F.Fab")
		)
		(fp_line
			(start -0.299974 -0.150114)
			(end 0.299974 -0.150114)
			(stroke
				(width 0.1)
				(type default)
			)
			(layer "F.Fab")
		)
		(fp_line
			(start 0.299974 0.150114)
			(end -0.299974 0.150114)
			(stroke
				(width 0.1)
				(type default)
			)
			(layer "F.Fab")
		)
		(fp_line
			(start -0.299974 0.150114)
			(end -0.299974 -0.150114)
			(stroke
				(width 0.1)
				(type default)
			)
			(layer "F.Fab")
		)
		(pad "1" smd rect
			(at -0.2667 0 90)
			(size 0.3048 0.381)
			(layers "F.Cu" "F.Mask" "F.Paste")
			(net "P5E_PEX2_STN6_TX_DN<101>")
		)
		(pad "2" smd rect
			(at 0.2667 0 90)
			(size 0.3048 0.381)
			(layers "F.Cu" "F.Mask" "F.Paste")
			(net "P5E_PEX2_STN6_TX_C_DN<101>")
		)
	)
	(footprint ""
		(layer "F.Cu")
		(at 362.268262 -357.956358 -90)
		(property "Reference" "R6448"
			(at 0 0 270)
			(layer "F.SilkS")
			(hide yes)
			(effects
				(font
					(size 1.27 1.27)
				)
			)
		)
		(property "Value" ""
			(at 0 0 270)
			(layer "F.Fab")
			(effects
				(font
					(size 1.27 1.27)
				)
			)
		)
		(duplicate_pad_numbers_are_jumpers no)
		(fp_line
			(start -0.7874 0.4064)
			(end -0.7874 -0.4064)
			(stroke
				(width 0.1524)
				(type default)
			)
			(layer "F.SilkS")
		)
		(fp_line
			(start 0.7874 0.4064)
			(end -0.7874 0.4064)
			(stroke
				(width 0.1524)
				(type default)
			)
			(layer "F.SilkS")
		)
		(fp_line
			(start -0.7874 -0.4064)
			(end 0.7874 -0.4064)
			(stroke
				(width 0.1524)
				(type default)
			)
			(layer "F.SilkS")
		)
		(fp_line
			(start 0.7874 -0.4064)
			(end 0.7874 0.4064)
			(stroke
				(width 0.1524)
				(type default)
			)
			(layer "F.SilkS")
		)
		(fp_line
			(start -0.67945 0.3048)
			(end -0.67945 -0.305054)
			(stroke
				(width 0.1)
				(type default)
			)
			(layer "F.Fab")
		)
		(fp_line
			(start -0.12065 0.3048)
			(end -0.67945 0.3048)
			(stroke
				(width 0.1)
				(type default)
			)
			(layer "F.Fab")
		)
		(fp_line
			(start 0.120396 0.3048)
			(end 0.120396 0.2794)
			(stroke
				(width 0.1)
				(type default)
			)
			(layer "F.Fab")
		)
		(fp_line
			(start 0.67945 0.3048)
			(end 0.120396 0.3048)
			(stroke
				(width 0.1)
				(type default)
			)
			(layer "F.Fab")
		)
		(fp_line
			(start -0.12065 0.2794)
			(end -0.12065 0.3048)
			(stroke
				(width 0.1)
				(type default)
			)
			(layer "F.Fab")
		)
		(fp_line
			(start 0.120396 0.2794)
			(end -0.12065 0.2794)
			(stroke
				(width 0.1)
				(type default)
			)
			(layer "F.Fab")
		)
		(fp_line
			(start -0.12065 -0.2794)
			(end 0.12065 -0.2794)
			(stroke
				(width 0.1)
				(type default)
			)
			(layer "F.Fab")
		)
		(fp_line
			(start 0.12065 -0.2794)
			(end 0.12065 -0.3048)
			(stroke
				(width 0.1)
				(type default)
			)
			(layer "F.Fab")
		)
		(fp_line
			(start 0.12065 -0.3048)
			(end 0.67945 -0.3048)
			(stroke
				(width 0.1)
				(type default)
			)
			(layer "F.Fab")
		)
		(fp_line
			(start 0.67945 -0.3048)
			(end 0.67945 0.3048)
			(stroke
				(width 0.1)
				(type default)
			)
			(layer "F.Fab")
		)
		(fp_line
			(start -0.67945 -0.305054)
			(end -0.12065 -0.305054)
			(stroke
				(width 0.1)
				(type default)
			)
			(layer "F.Fab")
		)
		(fp_line
			(start -0.12065 -0.305054)
			(end -0.12065 -0.2794)
			(stroke
				(width 0.1)
				(type default)
			)
			(layer "F.Fab")
		)
		(pad "1" smd circle
			(at -0.40005 0 270)
			(size 0 0)
			(layers "F.Cu" "F.Mask" "F.Paste")
			(net "MB_SWB_PWR_EN")
		)
		(pad "2" smd circle
			(at 0.40005 0 270)
			(size 0 0)
			(layers "F.Cu" "F.Mask" "F.Paste")
			(net "GND")
		)
	)
	(footprint ""
		(layer "F.Cu")
		(at 237.494064 -34.248852)
		(property "Reference" "R5683"
			(at 0 0 0)
			(layer "F.SilkS")
			(hide yes)
			(effects
				(font
					(size 1.27 1.27)
				)
			)
		)
		(property "Value" ""
			(at 0 0 0)
			(layer "F.Fab")
			(effects
				(font
					(size 1.27 1.27)
				)
			)
		)
		(duplicate_pad_numbers_are_jumpers no)
		(fp_line
			(start -0.7874 -0.4064)
			(end 0.7874 -0.4064)
			(stroke
				(width 0.1524)
				(type default)
			)
			(layer "F.SilkS")
		)
		(fp_line
			(start -0.7874 0.4064)
			(end -0.7874 -0.4064)
			(stroke
				(width 0.1524)
				(type default)
			)
			(layer "F.SilkS")
		)
		(fp_line
			(start 0.7874 -0.4064)
			(end 0.7874 0.4064)
			(stroke
				(width 0.1524)
				(type default)
			)
			(layer "F.SilkS")
		)
		(fp_line
			(start 0.7874 0.4064)
			(end -0.7874 0.4064)
			(stroke
				(width 0.1524)
				(type default)
			)
			(layer "F.SilkS")
		)
		(fp_line
			(start -0.67945 -0.305054)
			(end -0.12065 -0.305054)
			(stroke
				(width 0.1)
				(type default)
			)
			(layer "F.Fab")
		)
		(fp_line
			(start -0.67945 0.3048)
			(end -0.67945 -0.305054)
			(stroke
				(width 0.1)
				(type default)
			)
			(layer "F.Fab")
		)
		(fp_line
			(start -0.12065 -0.305054)
			(end -0.12065 -0.2794)
			(stroke
				(width 0.1)
				(type default)
			)
			(layer "F.Fab")
		)
		(fp_line
			(start -0.12065 -0.2794)
			(end 0.12065 -0.2794)
			(stroke
				(width 0.1)
				(type default)
			)
			(layer "F.Fab")
		)
		(fp_line
			(start -0.12065 0.2794)
			(end -0.12065 0.3048)
			(stroke
				(width 0.1)
				(type default)
			)
			(layer "F.Fab")
		)
		(fp_line
			(start -0.12065 0.3048)
			(end -0.67945 0.3048)
			(stroke
				(width 0.1)
				(type default)
			)
			(layer "F.Fab")
		)
		(fp_line
			(start 0.120396 0.2794)
			(end -0.12065 0.2794)
			(stroke
				(width 0.1)
				(type default)
			)
			(layer "F.Fab")
		)
		(fp_line
			(start 0.120396 0.3048)
			(end 0.120396 0.2794)
			(stroke
				(width 0.1)
				(type default)
			)
			(layer "F.Fab")
		)
		(fp_line
			(start 0.12065 -0.3048)
			(end 0.67945 -0.3048)
			(stroke
				(width 0.1)
				(type default)
			)
			(layer "F.Fab")
		)
		(fp_line
			(start 0.12065 -0.2794)
			(end 0.12065 -0.3048)
			(stroke
				(width 0.1)
				(type default)
			)
			(layer "F.Fab")
		)
		(fp_line
			(start 0.67945 -0.3048)
			(end 0.67945 0.3048)
			(stroke
				(width 0.1)
				(type default)
			)
			(layer "F.Fab")
		)
		(fp_line
			(start 0.67945 0.3048)
			(end 0.120396 0.3048)
			(stroke
				(width 0.1)
				(type default)
			)
			(layer "F.Fab")
		)
		(pad "1" smd circle
			(at -0.40005 0)
			(size 0 0)
			(layers "F.Cu" "F.Mask" "F.Paste")
			(net "RST_SMB_SSD8_ISO_N")
		)
		(pad "2" smd circle
			(at 0.40005 0)
			(size 0 0)
			(layers "F.Cu" "F.Mask" "F.Paste")
			(net "P3V3_SSD8")
		)
	)
	(footprint ""
		(layer "F.Cu")
		(at 292.378892 -59.577986 -90)
		(property "Reference" "R898"
			(at 0 0 270)
			(layer "F.SilkS")
			(hide yes)
			(effects
				(font
					(size 1.27 1.27)
				)
			)
		)
		(property "Value" ""
			(at 0 0 270)
			(layer "F.Fab")
			(effects
				(font
					(size 1.27 1.27)
				)
			)
		)
		(duplicate_pad_numbers_are_jumpers no)
		(fp_line
			(start -0.7874 0.4064)
			(end -0.7874 -0.4064)
			(stroke
				(width 0.1524)
				(type default)
			)
			(layer "F.SilkS")
		)
		(fp_line
			(start 0.7874 0.4064)
			(end -0.7874 0.4064)
			(stroke
				(width 0.1524)
				(type default)
			)
			(layer "F.SilkS")
		)
		(fp_line
			(start -0.7874 -0.4064)
			(end 0.7874 -0.4064)
			(stroke
				(width 0.1524)
				(type default)
			)
			(layer "F.SilkS")
		)
		(fp_line
			(start 0.7874 -0.4064)
			(end 0.7874 0.4064)
			(stroke
				(width 0.1524)
				(type default)
			)
			(layer "F.SilkS")
		)
		(fp_line
			(start -0.67945 0.3048)
			(end -0.67945 -0.305054)
			(stroke
				(width 0.1)
				(type default)
			)
			(layer "F.Fab")
		)
		(fp_line
			(start -0.12065 0.3048)
			(end -0.67945 0.3048)
			(stroke
				(width 0.1)
				(type default)
			)
			(layer "F.Fab")
		)
		(fp_line
			(start 0.120396 0.3048)
			(end 0.120396 0.2794)
			(stroke
				(width 0.1)
				(type default)
			)
			(layer "F.Fab")
		)
		(fp_line
			(start 0.67945 0.3048)
			(end 0.120396 0.3048)
			(stroke
				(width 0.1)
				(type default)
			)
			(layer "F.Fab")
		)
		(fp_line
			(start -0.12065 0.2794)
			(end -0.12065 0.3048)
			(stroke
				(width 0.1)
				(type default)
			)
			(layer "F.Fab")
		)
		(fp_line
			(start 0.120396 0.2794)
			(end -0.12065 0.2794)
			(stroke
				(width 0.1)
				(type default)
			)
			(layer "F.Fab")
		)
		(fp_line
			(start -0.12065 -0.2794)
			(end 0.12065 -0.2794)
			(stroke
				(width 0.1)
				(type default)
			)
			(layer "F.Fab")
		)
		(fp_line
			(start 0.12065 -0.2794)
			(end 0.12065 -0.3048)
			(stroke
				(width 0.1)
				(type default)
			)
			(layer "F.Fab")
		)
		(fp_line
			(start 0.12065 -0.3048)
			(end 0.67945 -0.3048)
			(stroke
				(width 0.1)
				(type default)
			)
			(layer "F.Fab")
		)
		(fp_line
			(start 0.67945 -0.3048)
			(end 0.67945 0.3048)
			(stroke
				(width 0.1)
				(type default)
			)
			(layer "F.Fab")
		)
		(fp_line
			(start -0.67945 -0.305054)
			(end -0.12065 -0.305054)
			(stroke
				(width 0.1)
				(type default)
			)
			(layer "F.Fab")
		)
		(fp_line
			(start -0.12065 -0.305054)
			(end -0.12065 -0.2794)
			(stroke
				(width 0.1)
				(type default)
			)
			(layer "F.Fab")
		)
		(pad "1" smd circle
			(at -0.40005 0 270)
			(size 0 0)
			(layers "F.Cu" "F.Mask" "F.Paste")
			(net "P3V3_SSD10")
		)
		(pad "2" smd circle
			(at 0.40005 0 270)
			(size 0 0)
			(layers "F.Cu" "F.Mask" "F.Paste")
			(net "PWRGD_P3V3_SSD10")
		)
	)
	(footprint ""
		(layer "F.Cu")
		(at 112.88776 -129.285746 180)
		(property "Reference" "PC298"
			(at 0 0 180)
			(layer "F.SilkS")
			(hide yes)
			(effects
				(font
					(size 1.27 1.27)
				)
			)
		)
		(property "Value" ""
			(at 0 0 180)
			(layer "F.Fab")
			(effects
				(font
					(size 1.27 1.27)
				)
			)
		)
		(duplicate_pad_numbers_are_jumpers no)
		(fp_line
			(start 0.7874 0.4064)
			(end -0.7874 0.4064)
			(stroke
				(width 0.1524)
				(type default)
			)
			(layer "F.SilkS")
		)
		(fp_line
			(start 0.7874 -0.4064)
			(end 0.7874 0.4064)
			(stroke
				(width 0.1524)
				(type default)
			)
			(layer "F.SilkS")
		)
		(fp_line
			(start -0.7874 0.4064)
			(end -0.7874 -0.4064)
			(stroke
				(width 0.1524)
				(type default)
			)
			(layer "F.SilkS")
		)
		(fp_line
			(start -0.7874 -0.4064)
			(end 0.7874 -0.4064)
			(stroke
				(width 0.1524)
				(type default)
			)
			(layer "F.SilkS")
		)
		(fp_line
			(start 0.67945 0.3048)
			(end 0.120396 0.3048)
			(stroke
				(width 0.1)
				(type default)
			)
			(layer "F.Fab")
		)
		(fp_line
			(start 0.67945 -0.3048)
			(end 0.67945 0.3048)
			(stroke
				(width 0.1)
				(type default)
			)
			(layer "F.Fab")
		)
		(fp_line
			(start 0.12065 -0.2794)
			(end 0.12065 -0.3048)
			(stroke
				(width 0.1)
				(type default)
			)
			(layer "F.Fab")
		)
		(fp_line
			(start 0.12065 -0.3048)
			(end 0.67945 -0.3048)
			(stroke
				(width 0.1)
				(type default)
			)
			(layer "F.Fab")
		)
		(fp_line
			(start 0.120396 0.3048)
			(end 0.120396 0.2794)
			(stroke
				(width 0.1)
				(type default)
			)
			(layer "F.Fab")
		)
		(fp_line
			(start 0.120396 0.2794)
			(end -0.12065 0.2794)
			(stroke
				(width 0.1)
				(type default)
			)
			(layer "F.Fab")
		)
		(fp_line
			(start -0.12065 0.3048)
			(end -0.67945 0.3048)
			(stroke
				(width 0.1)
				(type default)
			)
			(layer "F.Fab")
		)
		(fp_line
			(start -0.12065 0.2794)
			(end -0.12065 0.3048)
			(stroke
				(width 0.1)
				(type default)
			)
			(layer "F.Fab")
		)
		(fp_line
			(start -0.12065 -0.2794)
			(end 0.12065 -0.2794)
			(stroke
				(width 0.1)
				(type default)
			)
			(layer "F.Fab")
		)
		(fp_line
			(start -0.12065 -0.305054)
			(end -0.12065 -0.2794)
			(stroke
				(width 0.1)
				(type default)
			)
			(layer "F.Fab")
		)
		(fp_line
			(start -0.67945 0.3048)
			(end -0.67945 -0.305054)
			(stroke
				(width 0.1)
				(type default)
			)
			(layer "F.Fab")
		)
		(fp_line
			(start -0.67945 -0.305054)
			(end -0.12065 -0.305054)
			(stroke
				(width 0.1)
				(type default)
			)
			(layer "F.Fab")
		)
		(pad "1" smd circle
			(at -0.40005 0 180)
			(size 0 0)
			(layers "F.Cu" "F.Mask" "F.Paste")
			(net "P3V3_AUX")
		)
		(pad "2" smd circle
			(at 0.40005 0 180)
			(size 0 0)
			(layers "F.Cu" "F.Mask" "F.Paste")
			(net "GND")
		)
	)
	(footprint ""
		(layer "F.Cu")
		(at 178.591718 -161.881566 90)
		(property "Reference" "Q120"
			(at -0.032766 -2.009648 90)
			(unlocked yes)
			(layer "F.SilkS")
			(effects
				(font
					(size 0.7874 0.5842)
					(thickness 0.1524)
				)
			)
		)
		(property "Value" ""
			(at 0 0 90)
			(layer "F.Fab")
			(effects
				(font
					(size 1.27 1.27)
				)
			)
		)
		(duplicate_pad_numbers_are_jumpers no)
		(fp_line
			(start 1.376172 -1.199896)
			(end 1.376172 1.199896)
			(stroke
				(width 0.1524)
				(type default)
			)
			(layer "F.SilkS")
		)
		(fp_line
			(start 0.508 -1.199896)
			(end 1.376172 -1.199896)
			(stroke
				(width 0.1524)
				(type default)
			)
			(layer "F.SilkS")
		)
		(fp_line
			(start -0.508 -1.199896)
			(end 0 -0.762)
			(stroke
				(width 0.1524)
				(type default)
			)
			(layer "F.SilkS")
		)
		(fp_line
			(start -1.376172 -1.199896)
			(end -0.508 -1.199896)
			(stroke
				(width 0.1524)
				(type default)
			)
			(layer "F.SilkS")
		)
		(fp_line
			(start 0 -0.762)
			(end 0.508 -1.199896)
			(stroke
				(width 0.1524)
				(type default)
			)
			(layer "F.SilkS")
		)
		(fp_line
			(start 1.376172 1.199896)
			(end -1.376172 1.199896)
			(stroke
				(width 0.1524)
				(type default)
			)
			(layer "F.SilkS")
		)
		(fp_line
			(start -1.376172 1.199896)
			(end -1.376172 -1.199896)
			(stroke
				(width 0.1524)
				(type default)
			)
			(layer "F.SilkS")
		)
		(fp_poly
			(pts
				(xy -1.537462 -1.195578) (xy -1.806956 -2.003806) (xy -2.34569 -1.465072)
			)
			(stroke
				(width 0)
				(type default)
			)
			(fill yes)
			(layer "F.SilkS")
		)
		(fp_line
			(start 0.674878 -1.100074)
			(end 0.674878 1.100074)
			(stroke
				(width 0.1)
				(type default)
			)
			(layer "F.Fab")
		)
		(fp_line
			(start -0.674878 -1.100074)
			(end 0.674878 -1.100074)
			(stroke
				(width 0.1)
				(type default)
			)
			(layer "F.Fab")
		)
		(fp_line
			(start 0.674878 1.100074)
			(end -0.674878 1.100074)
			(stroke
				(width 0.1)
				(type default)
			)
			(layer "F.Fab")
		)
		(fp_line
			(start -0.674878 1.100074)
			(end -0.674878 -1.100074)
			(stroke
				(width 0.1)
				(type default)
			)
			(layer "F.Fab")
		)
		(fp_poly
			(pts
				(xy -1.4605 -0.7493) (xy -2.2225 -1.1303) (xy -2.2225 -0.3683)
			)
			(stroke
				(width 0)
				(type default)
			)
			(fill yes)
			(layer "F.Fab")
		)
		(pad "1" smd rect
			(at -0.899922 -0.750062)
			(size 0.6096 0.6096)
			(layers "F.Cu" "F.Mask" "F.Paste")
			(net "GND")
		)
		(pad "2" smd rect
			(at -0.899922 0)
			(size 0.4064 0.6096)
			(layers "F.Cu" "F.Mask" "F.Paste")
			(net "FM_SYS_THROTTLE_NIC2")
		)
		(pad "3" smd rect
			(at -0.899922 0.750062)
			(size 0.6096 0.6096)
			(layers "F.Cu" "F.Mask" "F.Paste")
			(net "NIC3_PWRBRK_N")
		)
		(pad "4" smd rect
			(at 0.899922 0.750062)
			(size 0.6096 0.6096)
			(layers "F.Cu" "F.Mask" "F.Paste")
			(net "GND")
		)
		(pad "5" smd rect
			(at 0.899922 0)
			(size 0.4064 0.6096)
			(layers "F.Cu" "F.Mask" "F.Paste")
			(net "FM_SYS_THROTTLE_NIC3")
		)
		(pad "6" smd rect
			(at 0.899922 -0.750062)
			(size 0.6096 0.6096)
			(layers "F.Cu" "F.Mask" "F.Paste")
			(net "NIC2_PWRBRK_N")
		)
	)
	(footprint ""
		(layer "F.Cu")
		(at 119.457978 -27.006296 -90)
		(property "Reference" "PR7107"
			(at 0 0 270)
			(layer "F.SilkS")
			(hide yes)
			(effects
				(font
					(size 1.27 1.27)
				)
			)
		)
		(property "Value" ""
			(at 0 0 270)
			(layer "F.Fab")
			(effects
				(font
					(size 1.27 1.27)
				)
			)
		)
		(duplicate_pad_numbers_are_jumpers no)
		(fp_line
			(start -0.7874 0.4064)
			(end -0.7874 -0.4064)
			(stroke
				(width 0.1524)
				(type default)
			)
			(layer "F.SilkS")
		)
		(fp_line
			(start 0.7874 0.4064)
			(end -0.7874 0.4064)
			(stroke
				(width 0.1524)
				(type default)
			)
			(layer "F.SilkS")
		)
		(fp_line
			(start -0.7874 -0.4064)
			(end 0.7874 -0.4064)
			(stroke
				(width 0.1524)
				(type default)
			)
			(layer "F.SilkS")
		)
		(fp_line
			(start 0.7874 -0.4064)
			(end 0.7874 0.4064)
			(stroke
				(width 0.1524)
				(type default)
			)
			(layer "F.SilkS")
		)
		(fp_line
			(start -0.67945 0.3048)
			(end -0.67945 -0.305054)
			(stroke
				(width 0.1)
				(type default)
			)
			(layer "F.Fab")
		)
		(fp_line
			(start -0.12065 0.3048)
			(end -0.67945 0.3048)
			(stroke
				(width 0.1)
				(type default)
			)
			(layer "F.Fab")
		)
		(fp_line
			(start 0.120396 0.3048)
			(end 0.120396 0.2794)
			(stroke
				(width 0.1)
				(type default)
			)
			(layer "F.Fab")
		)
		(fp_line
			(start 0.67945 0.3048)
			(end 0.120396 0.3048)
			(stroke
				(width 0.1)
				(type default)
			)
			(layer "F.Fab")
		)
		(fp_line
			(start -0.12065 0.2794)
			(end -0.12065 0.3048)
			(stroke
				(width 0.1)
				(type default)
			)
			(layer "F.Fab")
		)
		(fp_line
			(start 0.120396 0.2794)
			(end -0.12065 0.2794)
			(stroke
				(width 0.1)
				(type default)
			)
			(layer "F.Fab")
		)
		(fp_line
			(start -0.12065 -0.2794)
			(end 0.12065 -0.2794)
			(stroke
				(width 0.1)
				(type default)
			)
			(layer "F.Fab")
		)
		(fp_line
			(start 0.12065 -0.2794)
			(end 0.12065 -0.3048)
			(stroke
				(width 0.1)
				(type default)
			)
			(layer "F.Fab")
		)
		(fp_line
			(start 0.12065 -0.3048)
			(end 0.67945 -0.3048)
			(stroke
				(width 0.1)
				(type default)
			)
			(layer "F.Fab")
		)
		(fp_line
			(start 0.67945 -0.3048)
			(end 0.67945 0.3048)
			(stroke
				(width 0.1)
				(type default)
			)
			(layer "F.Fab")
		)
		(fp_line
			(start -0.67945 -0.305054)
			(end -0.12065 -0.305054)
			(stroke
				(width 0.1)
				(type default)
			)
			(layer "F.Fab")
		)
		(fp_line
			(start -0.12065 -0.305054)
			(end -0.12065 -0.2794)
			(stroke
				(width 0.1)
				(type default)
			)
			(layer "F.Fab")
		)
		(pad "1" smd circle
			(at -0.40005 0 270)
			(size 0 0)
			(layers "F.Cu" "F.Mask" "F.Paste")
			(net "P3V3_SSD4_CO_MODE")
		)
		(pad "2" smd circle
			(at 0.40005 0 270)
			(size 0 0)
			(layers "F.Cu" "F.Mask" "F.Paste")
			(net "GND")
		)
	)
	(footprint ""
		(layer "F.Cu")
		(at 336.042 -142.875)
		(property "Reference" "R4790"
			(at 0 0 0)
			(layer "F.SilkS")
			(hide yes)
			(effects
				(font
					(size 1.27 1.27)
				)
			)
		)
		(property "Value" ""
			(at 0 0 0)
			(layer "F.Fab")
			(effects
				(font
					(size 1.27 1.27)
				)
			)
		)
		(duplicate_pad_numbers_are_jumpers no)
		(fp_line
			(start -0.7874 -0.4064)
			(end 0.7874 -0.4064)
			(stroke
				(width 0.1524)
				(type default)
			)
			(layer "F.SilkS")
		)
		(fp_line
			(start -0.7874 0.4064)
			(end -0.7874 -0.4064)
			(stroke
				(width 0.1524)
				(type default)
			)
			(layer "F.SilkS")
		)
		(fp_line
			(start 0.7874 -0.4064)
			(end 0.7874 0.4064)
			(stroke
				(width 0.1524)
				(type default)
			)
			(layer "F.SilkS")
		)
		(fp_line
			(start 0.7874 0.4064)
			(end -0.7874 0.4064)
			(stroke
				(width 0.1524)
				(type default)
			)
			(layer "F.SilkS")
		)
		(fp_line
			(start -0.67945 -0.305054)
			(end -0.12065 -0.305054)
			(stroke
				(width 0.1)
				(type default)
			)
			(layer "F.Fab")
		)
		(fp_line
			(start -0.67945 0.3048)
			(end -0.67945 -0.305054)
			(stroke
				(width 0.1)
				(type default)
			)
			(layer "F.Fab")
		)
		(fp_line
			(start -0.12065 -0.305054)
			(end -0.12065 -0.2794)
			(stroke
				(width 0.1)
				(type default)
			)
			(layer "F.Fab")
		)
		(fp_line
			(start -0.12065 -0.2794)
			(end 0.12065 -0.2794)
			(stroke
				(width 0.1)
				(type default)
			)
			(layer "F.Fab")
		)
		(fp_line
			(start -0.12065 0.2794)
			(end -0.12065 0.3048)
			(stroke
				(width 0.1)
				(type default)
			)
			(layer "F.Fab")
		)
		(fp_line
			(start -0.12065 0.3048)
			(end -0.67945 0.3048)
			(stroke
				(width 0.1)
				(type default)
			)
			(layer "F.Fab")
		)
		(fp_line
			(start 0.120396 0.2794)
			(end -0.12065 0.2794)
			(stroke
				(width 0.1)
				(type default)
			)
			(layer "F.Fab")
		)
		(fp_line
			(start 0.120396 0.3048)
			(end 0.120396 0.2794)
			(stroke
				(width 0.1)
				(type default)
			)
			(layer "F.Fab")
		)
		(fp_line
			(start 0.12065 -0.3048)
			(end 0.67945 -0.3048)
			(stroke
				(width 0.1)
				(type default)
			)
			(layer "F.Fab")
		)
		(fp_line
			(start 0.12065 -0.2794)
			(end 0.12065 -0.3048)
			(stroke
				(width 0.1)
				(type default)
			)
			(layer "F.Fab")
		)
		(fp_line
			(start 0.67945 -0.3048)
			(end 0.67945 0.3048)
			(stroke
				(width 0.1)
				(type default)
			)
			(layer "F.Fab")
		)
		(fp_line
			(start 0.67945 0.3048)
			(end 0.120396 0.3048)
			(stroke
				(width 0.1)
				(type default)
			)
			(layer "F.Fab")
		)
		(pad "1" smd circle
			(at -0.40005 0)
			(size 0 0)
			(layers "F.Cu" "F.Mask" "F.Paste")
			(net "P3V3_AUX")
		)
		(pad "2" smd circle
			(at 0.40005 0)
			(size 0 0)
			(layers "F.Cu" "F.Mask" "F.Paste")
			(net "SSD15_PEX_PWR_EN_R")
		)
	)
	(footprint ""
		(layer "F.Cu")
		(at 449.179188 -415.621216 90)
		(property "Reference" "R5600"
			(at 0 0 90)
			(layer "F.SilkS")
			(hide yes)
			(effects
				(font
					(size 1.27 1.27)
				)
			)
		)
		(property "Value" ""
			(at 0 0 90)
			(layer "F.Fab")
			(effects
				(font
					(size 1.27 1.27)
				)
			)
		)
		(duplicate_pad_numbers_are_jumpers no)
		(fp_line
			(start 0.7874 -0.4064)
			(end 0.7874 0.4064)
			(stroke
				(width 0.1524)
				(type default)
			)
			(layer "F.SilkS")
		)
		(fp_line
			(start -0.7874 -0.4064)
			(end 0.7874 -0.4064)
			(stroke
				(width 0.1524)
				(type default)
			)
			(layer "F.SilkS")
		)
		(fp_line
			(start 0.7874 0.4064)
			(end -0.7874 0.4064)
			(stroke
				(width 0.1524)
				(type default)
			)
			(layer "F.SilkS")
		)
		(fp_line
			(start -0.7874 0.4064)
			(end -0.7874 -0.4064)
			(stroke
				(width 0.1524)
				(type default)
			)
			(layer "F.SilkS")
		)
		(fp_line
			(start -0.12065 -0.305054)
			(end -0.12065 -0.2794)
			(stroke
				(width 0.1)
				(type default)
			)
			(layer "F.Fab")
		)
		(fp_line
			(start -0.67945 -0.305054)
			(end -0.12065 -0.305054)
			(stroke
				(width 0.1)
				(type default)
			)
			(layer "F.Fab")
		)
		(fp_line
			(start 0.67945 -0.3048)
			(end 0.67945 0.3048)
			(stroke
				(width 0.1)
				(type default)
			)
			(layer "F.Fab")
		)
		(fp_line
			(start 0.12065 -0.3048)
			(end 0.67945 -0.3048)
			(stroke
				(width 0.1)
				(type default)
			)
			(layer "F.Fab")
		)
		(fp_line
			(start 0.12065 -0.2794)
			(end 0.12065 -0.3048)
			(stroke
				(width 0.1)
				(type default)
			)
			(layer "F.Fab")
		)
		(fp_line
			(start -0.12065 -0.2794)
			(end 0.12065 -0.2794)
			(stroke
				(width 0.1)
				(type default)
			)
			(layer "F.Fab")
		)
		(fp_line
			(start 0.120396 0.2794)
			(end -0.12065 0.2794)
			(stroke
				(width 0.1)
				(type default)
			)
			(layer "F.Fab")
		)
		(fp_line
			(start -0.12065 0.2794)
			(end -0.12065 0.3048)
			(stroke
				(width 0.1)
				(type default)
			)
			(layer "F.Fab")
		)
		(fp_line
			(start 0.67945 0.3048)
			(end 0.120396 0.3048)
			(stroke
				(width 0.1)
				(type default)
			)
			(layer "F.Fab")
		)
		(fp_line
			(start 0.120396 0.3048)
			(end 0.120396 0.2794)
			(stroke
				(width 0.1)
				(type default)
			)
			(layer "F.Fab")
		)
		(fp_line
			(start -0.12065 0.3048)
			(end -0.67945 0.3048)
			(stroke
				(width 0.1)
				(type default)
			)
			(layer "F.Fab")
		)
		(fp_line
			(start -0.67945 0.3048)
			(end -0.67945 -0.305054)
			(stroke
				(width 0.1)
				(type default)
			)
			(layer "F.Fab")
		)
		(pad "1" smd circle
			(at -0.40005 0 90)
			(size 0 0)
			(layers "F.Cu" "F.Mask" "F.Paste")
			(net "LM75_1_A1")
		)
		(pad "2" smd circle
			(at 0.40005 0 90)
			(size 0 0)
			(layers "F.Cu" "F.Mask" "F.Paste")
			(net "P3V3_AUX")
		)
	)
	(footprint ""
		(layer "F.Cu")
		(at 130.490468 -350.098614 90)
		(property "Reference" "C2271"
			(at 0 0 90)
			(layer "F.SilkS")
			(hide yes)
			(effects
				(font
					(size 1.27 1.27)
				)
			)
		)
		(property "Value" ""
			(at 0 0 90)
			(layer "F.Fab")
			(effects
				(font
					(size 1.27 1.27)
				)
			)
		)
		(duplicate_pad_numbers_are_jumpers no)
		(fp_line
			(start 0.299974 -0.150114)
			(end 0.299974 0.150114)
			(stroke
				(width 0.1)
				(type default)
			)
			(layer "F.Fab")
		)
		(fp_line
			(start -0.299974 -0.150114)
			(end 0.299974 -0.150114)
			(stroke
				(width 0.1)
				(type default)
			)
			(layer "F.Fab")
		)
		(fp_line
			(start 0.299974 0.150114)
			(end -0.299974 0.150114)
			(stroke
				(width 0.1)
				(type default)
			)
			(layer "F.Fab")
		)
		(fp_line
			(start -0.299974 0.150114)
			(end -0.299974 -0.150114)
			(stroke
				(width 0.1)
				(type default)
			)
			(layer "F.Fab")
		)
		(pad "1" smd rect
			(at -0.2667 0 90)
			(size 0.3048 0.381)
			(layers "F.Cu" "F.Mask" "F.Paste")
			(net "P5E_PEX1_STN5_TX_DP<81>")
		)
		(pad "2" smd rect
			(at 0.2667 0 90)
			(size 0.3048 0.381)
			(layers "F.Cu" "F.Mask" "F.Paste")
			(net "P5E_PEX1_STN5_TX_C_DP<81>")
		)
	)
	(footprint ""
		(layer "F.Cu")
		(at 23.128478 -260.807708 90)
		(property "Reference" "R5727"
			(at 0 0 90)
			(layer "F.SilkS")
			(hide yes)
			(effects
				(font
					(size 1.27 1.27)
				)
			)
		)
		(property "Value" ""
			(at 0 0 90)
			(layer "F.Fab")
			(effects
				(font
					(size 1.27 1.27)
				)
			)
		)
		(duplicate_pad_numbers_are_jumpers no)
		(fp_line
			(start 0.7874 -0.4064)
			(end 0.7874 0.4064)
			(stroke
				(width 0.1524)
				(type default)
			)
			(layer "F.SilkS")
		)
		(fp_line
			(start -0.7874 -0.4064)
			(end 0.7874 -0.4064)
			(stroke
				(width 0.1524)
				(type default)
			)
			(layer "F.SilkS")
		)
		(fp_line
			(start 0.7874 0.4064)
			(end -0.7874 0.4064)
			(stroke
				(width 0.1524)
				(type default)
			)
			(layer "F.SilkS")
		)
		(fp_line
			(start -0.7874 0.4064)
			(end -0.7874 -0.4064)
			(stroke
				(width 0.1524)
				(type default)
			)
			(layer "F.SilkS")
		)
		(fp_line
			(start -0.12065 -0.305054)
			(end -0.12065 -0.2794)
			(stroke
				(width 0.1)
				(type default)
			)
			(layer "F.Fab")
		)
		(fp_line
			(start -0.67945 -0.305054)
			(end -0.12065 -0.305054)
			(stroke
				(width 0.1)
				(type default)
			)
			(layer "F.Fab")
		)
		(fp_line
			(start 0.67945 -0.3048)
			(end 0.67945 0.3048)
			(stroke
				(width 0.1)
				(type default)
			)
			(layer "F.Fab")
		)
		(fp_line
			(start 0.12065 -0.3048)
			(end 0.67945 -0.3048)
			(stroke
				(width 0.1)
				(type default)
			)
			(layer "F.Fab")
		)
		(fp_line
			(start 0.12065 -0.2794)
			(end 0.12065 -0.3048)
			(stroke
				(width 0.1)
				(type default)
			)
			(layer "F.Fab")
		)
		(fp_line
			(start -0.12065 -0.2794)
			(end 0.12065 -0.2794)
			(stroke
				(width 0.1)
				(type default)
			)
			(layer "F.Fab")
		)
		(fp_line
			(start 0.120396 0.2794)
			(end -0.12065 0.2794)
			(stroke
				(width 0.1)
				(type default)
			)
			(layer "F.Fab")
		)
		(fp_line
			(start -0.12065 0.2794)
			(end -0.12065 0.3048)
			(stroke
				(width 0.1)
				(type default)
			)
			(layer "F.Fab")
		)
		(fp_line
			(start 0.67945 0.3048)
			(end 0.120396 0.3048)
			(stroke
				(width 0.1)
				(type default)
			)
			(layer "F.Fab")
		)
		(fp_line
			(start 0.120396 0.3048)
			(end 0.120396 0.2794)
			(stroke
				(width 0.1)
				(type default)
			)
			(layer "F.Fab")
		)
		(fp_line
			(start -0.12065 0.3048)
			(end -0.67945 0.3048)
			(stroke
				(width 0.1)
				(type default)
			)
			(layer "F.Fab")
		)
		(fp_line
			(start -0.67945 0.3048)
			(end -0.67945 -0.305054)
			(stroke
				(width 0.1)
				(type default)
			)
			(layer "F.Fab")
		)
		(pad "1" smd circle
			(at -0.40005 0 90)
			(size 0 0)
			(layers "F.Cu" "F.Mask" "F.Paste")
			(net "PEX0_SYS_ERR_N_G")
		)
		(pad "2" smd circle
			(at 0.40005 0 90)
			(size 0 0)
			(layers "F.Cu" "F.Mask" "F.Paste")
			(net "PEX0_SYS_ERR_FPGA")
		)
	)
	(footprint ""
		(layer "F.Cu")
		(at 131.89839 -184.656984 -90)
		(property "Reference" "R1115"
			(at 0 0 270)
			(layer "F.SilkS")
			(hide yes)
			(effects
				(font
					(size 1.27 1.27)
				)
			)
		)
		(property "Value" ""
			(at 0 0 270)
			(layer "F.Fab")
			(effects
				(font
					(size 1.27 1.27)
				)
			)
		)
		(duplicate_pad_numbers_are_jumpers no)
		(fp_line
			(start 0.7874 0.4064)
			(end -0.7874 0.4064)
			(stroke
				(width 0.1524)
				(type default)
			)
			(layer "F.SilkS")
		)
		(fp_line
			(start -0.67945 0.3048)
			(end -0.67945 -0.305054)
			(stroke
				(width 0.1)
				(type default)
			)
			(layer "F.Fab")
		)
		(fp_line
			(start -0.12065 0.3048)
			(end -0.67945 0.3048)
			(stroke
				(width 0.1)
				(type default)
			)
			(layer "F.Fab")
		)
		(fp_line
			(start 0.120396 0.3048)
			(end 0.120396 0.2794)
			(stroke
				(width 0.1)
				(type default)
			)
			(layer "F.Fab")
		)
		(fp_line
			(start 0.67945 0.3048)
			(end 0.120396 0.3048)
			(stroke
				(width 0.1)
				(type default)
			)
			(layer "F.Fab")
		)
		(fp_line
			(start -0.12065 0.2794)
			(end -0.12065 0.3048)
			(stroke
				(width 0.1)
				(type default)
			)
			(layer "F.Fab")
		)
		(fp_line
			(start 0.120396 0.2794)
			(end -0.12065 0.2794)
			(stroke
				(width 0.1)
				(type default)
			)
			(layer "F.Fab")
		)
		(fp_line
			(start -0.12065 -0.2794)
			(end 0.12065 -0.2794)
			(stroke
				(width 0.1)
				(type default)
			)
			(layer "F.Fab")
		)
		(fp_line
			(start 0.12065 -0.2794)
			(end 0.12065 -0.3048)
			(stroke
				(width 0.1)
				(type default)
			)
			(layer "F.Fab")
		)
		(fp_line
			(start 0.12065 -0.3048)
			(end 0.67945 -0.3048)
			(stroke
				(width 0.1)
				(type default)
			)
			(layer "F.Fab")
		)
		(fp_line
			(start 0.67945 -0.3048)
			(end 0.67945 0.3048)
			(stroke
				(width 0.1)
				(type default)
			)
			(layer "F.Fab")
		)
		(fp_line
			(start -0.67945 -0.305054)
			(end -0.12065 -0.305054)
			(stroke
				(width 0.1)
				(type default)
			)
			(layer "F.Fab")
		)
		(fp_line
			(start -0.12065 -0.305054)
			(end -0.12065 -0.2794)
			(stroke
				(width 0.1)
				(type default)
			)
			(layer "F.Fab")
		)
		(pad "1" smd circle
			(at -0.40005 0 270)
			(size 0 0)
			(layers "F.Cu" "F.Mask" "F.Paste")
			(net "CLK_100M_DB2000QL_GPU_REF1_R_DN")
		)
		(pad "2" smd circle
			(at 0.40005 0 270)
			(size 0 0)
			(layers "F.Cu" "F.Mask" "F.Paste")
			(net "CLK_100M_DB2000QL_GPU_REF1_DN")
		)
	)
	(footprint ""
		(layer "F.Cu")
		(at 191.817498 -402.672296 90)
		(property "Reference" "R6825"
			(at 0 0 90)
			(layer "F.SilkS")
			(hide yes)
			(effects
				(font
					(size 1.27 1.27)
				)
			)
		)
		(property "Value" ""
			(at 0 0 90)
			(layer "F.Fab")
			(effects
				(font
					(size 1.27 1.27)
				)
			)
		)
		(duplicate_pad_numbers_are_jumpers no)
		(fp_line
			(start 0.7874 -0.4064)
			(end 0.7874 0.4064)
			(stroke
				(width 0.1524)
				(type default)
			)
			(layer "F.SilkS")
		)
		(fp_line
			(start -0.7874 -0.4064)
			(end 0.7874 -0.4064)
			(stroke
				(width 0.1524)
				(type default)
			)
			(layer "F.SilkS")
		)
		(fp_line
			(start 0.7874 0.4064)
			(end -0.7874 0.4064)
			(stroke
				(width 0.1524)
				(type default)
			)
			(layer "F.SilkS")
		)
		(fp_line
			(start -0.7874 0.4064)
			(end -0.7874 -0.4064)
			(stroke
				(width 0.1524)
				(type default)
			)
			(layer "F.SilkS")
		)
		(fp_line
			(start -0.12065 -0.305054)
			(end -0.12065 -0.2794)
			(stroke
				(width 0.1)
				(type default)
			)
			(layer "F.Fab")
		)
		(fp_line
			(start -0.67945 -0.305054)
			(end -0.12065 -0.305054)
			(stroke
				(width 0.1)
				(type default)
			)
			(layer "F.Fab")
		)
		(fp_line
			(start 0.67945 -0.3048)
			(end 0.67945 0.3048)
			(stroke
				(width 0.1)
				(type default)
			)
			(layer "F.Fab")
		)
		(fp_line
			(start 0.12065 -0.3048)
			(end 0.67945 -0.3048)
			(stroke
				(width 0.1)
				(type default)
			)
			(layer "F.Fab")
		)
		(fp_line
			(start 0.12065 -0.2794)
			(end 0.12065 -0.3048)
			(stroke
				(width 0.1)
				(type default)
			)
			(layer "F.Fab")
		)
		(fp_line
			(start -0.12065 -0.2794)
			(end 0.12065 -0.2794)
			(stroke
				(width 0.1)
				(type default)
			)
			(layer "F.Fab")
		)
		(fp_line
			(start 0.120396 0.2794)
			(end -0.12065 0.2794)
			(stroke
				(width 0.1)
				(type default)
			)
			(layer "F.Fab")
		)
		(fp_line
			(start -0.12065 0.2794)
			(end -0.12065 0.3048)
			(stroke
				(width 0.1)
				(type default)
			)
			(layer "F.Fab")
		)
		(fp_line
			(start 0.67945 0.3048)
			(end 0.120396 0.3048)
			(stroke
				(width 0.1)
				(type default)
			)
			(layer "F.Fab")
		)
		(fp_line
			(start 0.120396 0.3048)
			(end 0.120396 0.2794)
			(stroke
				(width 0.1)
				(type default)
			)
			(layer "F.Fab")
		)
		(fp_line
			(start -0.12065 0.3048)
			(end -0.67945 0.3048)
			(stroke
				(width 0.1)
				(type default)
			)
			(layer "F.Fab")
		)
		(fp_line
			(start -0.67945 0.3048)
			(end -0.67945 -0.305054)
			(stroke
				(width 0.1)
				(type default)
			)
			(layer "F.Fab")
		)
		(pad "1" smd circle
			(at -0.40005 0 90)
			(size 0 0)
			(layers "F.Cu" "F.Mask" "F.Paste")
			(net "P12V_AUX")
		)
		(pad "2" smd circle
			(at 0.40005 0 90)
			(size 0 0)
			(layers "F.Cu" "F.Mask" "F.Paste")
			(net "FM_UV_LT6700_VS")
		)
	)
	(footprint ""
		(layer "F.Cu")
		(at 332.994 -245.237 90)
		(property "Reference" "R1798"
			(at 0 0 90)
			(layer "F.SilkS")
			(hide yes)
			(effects
				(font
					(size 1.27 1.27)
				)
			)
		)
		(property "Value" ""
			(at 0 0 90)
			(layer "F.Fab")
			(effects
				(font
					(size 1.27 1.27)
				)
			)
		)
		(duplicate_pad_numbers_are_jumpers no)
		(fp_line
			(start 0.7874 -0.4064)
			(end 0.7874 0.4064)
			(stroke
				(width 0.1524)
				(type default)
			)
			(layer "F.SilkS")
		)
		(fp_line
			(start -0.7874 -0.4064)
			(end 0.7874 -0.4064)
			(stroke
				(width 0.1524)
				(type default)
			)
			(layer "F.SilkS")
		)
		(fp_line
			(start 0.7874 0.4064)
			(end -0.7874 0.4064)
			(stroke
				(width 0.1524)
				(type default)
			)
			(layer "F.SilkS")
		)
		(fp_line
			(start -0.7874 0.4064)
			(end -0.7874 -0.4064)
			(stroke
				(width 0.1524)
				(type default)
			)
			(layer "F.SilkS")
		)
		(fp_line
			(start -0.12065 -0.305054)
			(end -0.12065 -0.2794)
			(stroke
				(width 0.1)
				(type default)
			)
			(layer "F.Fab")
		)
		(fp_line
			(start -0.67945 -0.305054)
			(end -0.12065 -0.305054)
			(stroke
				(width 0.1)
				(type default)
			)
			(layer "F.Fab")
		)
		(fp_line
			(start 0.67945 -0.3048)
			(end 0.67945 0.3048)
			(stroke
				(width 0.1)
				(type default)
			)
			(layer "F.Fab")
		)
		(fp_line
			(start 0.12065 -0.3048)
			(end 0.67945 -0.3048)
			(stroke
				(width 0.1)
				(type default)
			)
			(layer "F.Fab")
		)
		(fp_line
			(start 0.12065 -0.2794)
			(end 0.12065 -0.3048)
			(stroke
				(width 0.1)
				(type default)
			)
			(layer "F.Fab")
		)
		(fp_line
			(start -0.12065 -0.2794)
			(end 0.12065 -0.2794)
			(stroke
				(width 0.1)
				(type default)
			)
			(layer "F.Fab")
		)
		(fp_line
			(start 0.120396 0.2794)
			(end -0.12065 0.2794)
			(stroke
				(width 0.1)
				(type default)
			)
			(layer "F.Fab")
		)
		(fp_line
			(start -0.12065 0.2794)
			(end -0.12065 0.3048)
			(stroke
				(width 0.1)
				(type default)
			)
			(layer "F.Fab")
		)
		(fp_line
			(start 0.67945 0.3048)
			(end 0.120396 0.3048)
			(stroke
				(width 0.1)
				(type default)
			)
			(layer "F.Fab")
		)
		(fp_line
			(start 0.120396 0.3048)
			(end 0.120396 0.2794)
			(stroke
				(width 0.1)
				(type default)
			)
			(layer "F.Fab")
		)
		(fp_line
			(start -0.12065 0.3048)
			(end -0.67945 0.3048)
			(stroke
				(width 0.1)
				(type default)
			)
			(layer "F.Fab")
		)
		(fp_line
			(start -0.67945 0.3048)
			(end -0.67945 -0.305054)
			(stroke
				(width 0.1)
				(type default)
			)
			(layer "F.Fab")
		)
		(pad "1" smd circle
			(at -0.40005 0 90)
			(size 0 0)
			(layers "F.Cu" "F.Mask" "F.Paste")
			(net "P3V3_AUX")
		)
		(pad "2" smd circle
			(at 0.40005 0 90)
			(size 0 0)
			(layers "F.Cu" "F.Mask" "F.Paste")
			(net "MB_SWB_PWRGD_BUF_R")
		)
	)
	(footprint ""
		(layer "F.Cu")
		(at 3.631692 -377.270518)
		(property "Reference" "Y9"
			(at 0.801624 3.378962 0)
			(unlocked yes)
			(layer "F.SilkS")
			(effects
				(font
					(size 0.7874 0.5842)
					(thickness 0.1524)
				)
				(justify left)
			)
		)
		(property "Value" ""
			(at 0 0 0)
			(layer "F.Fab")
			(effects
				(font
					(size 1.27 1.27)
				)
			)
		)
		(duplicate_pad_numbers_are_jumpers no)
		(fp_line
			(start -1.6002 -1.9558)
			(end 1.6002 -1.9558)
			(stroke
				(width 0.1524)
				(type default)
			)
			(layer "F.SilkS")
		)
		(fp_line
			(start -1.6002 1.9558)
			(end -1.6002 -1.9558)
			(stroke
				(width 0.1524)
				(type default)
			)
			(layer "F.SilkS")
		)
		(fp_line
			(start 1.6002 -1.9558)
			(end 1.6002 1.9558)
			(stroke
				(width 0.1524)
				(type default)
			)
			(layer "F.SilkS")
		)
		(fp_line
			(start 1.6002 1.9558)
			(end -1.6002 1.9558)
			(stroke
				(width 0.1524)
				(type default)
			)
			(layer "F.SilkS")
		)
		(fp_poly
			(pts
				(xy -1.7145 -1.0668) (xy -2.8067 -1.651) (xy -2.8067 -0.5842)
			)
			(stroke
				(width 0)
				(type default)
			)
			(fill yes)
			(layer "F.SilkS")
		)
		(fp_line
			(start -1.299972 -1.649984)
			(end 1.299972 -1.649984)
			(stroke
				(width 0.1)
				(type default)
			)
			(layer "F.Fab")
		)
		(fp_line
			(start -1.299972 1.649984)
			(end -1.299972 -1.649984)
			(stroke
				(width 0.1)
				(type default)
			)
			(layer "F.Fab")
		)
		(fp_line
			(start 1.299972 -1.649984)
			(end 1.299972 1.649984)
			(stroke
				(width 0.1)
				(type default)
			)
			(layer "F.Fab")
		)
		(fp_line
			(start 1.299972 1.649984)
			(end -1.299972 1.649984)
			(stroke
				(width 0.1)
				(type default)
			)
			(layer "F.Fab")
		)
		(fp_poly
			(pts
				(xy -1.7145 -1.0668) (xy -2.8067 -1.651) (xy -2.8067 -0.5842)
			)
			(stroke
				(width 0)
				(type default)
			)
			(fill yes)
			(layer "F.Fab")
		)
		(pad "1" smd rect
			(at -0.849884 -1.100074)
			(size 1.2192 1.4224)
			(layers "F.Cu" "F.Mask" "F.Paste")
			(net "BIC_USB_8042_HUB_XOUT")
		)
		(pad "2" smd rect
			(at -0.849884 1.100074)
			(size 1.2192 1.4224)
			(layers "F.Cu" "F.Mask" "F.Paste")
			(net "GND")
		)
		(pad "3" smd rect
			(at 0.849884 1.100074)
			(size 1.2192 1.4224)
			(layers "F.Cu" "F.Mask" "F.Paste")
			(net "BIC_USB_8042_HUB_XIN")
		)
		(pad "4" smd rect
			(at 0.849884 -1.100074)
			(size 1.2192 1.4224)
			(layers "F.Cu" "F.Mask" "F.Paste")
			(net "GND")
		)
	)
	(footprint ""
		(layer "F.Cu")
		(at 444.09233 -31.825184 180)
		(property "Reference" "C725"
			(at 0 0 180)
			(layer "F.SilkS")
			(hide yes)
			(effects
				(font
					(size 1.27 1.27)
				)
			)
		)
		(property "Value" ""
			(at 0 0 180)
			(layer "F.Fab")
			(effects
				(font
					(size 1.27 1.27)
				)
			)
		)
		(duplicate_pad_numbers_are_jumpers no)
		(fp_line
			(start 0.299974 0.150114)
			(end -0.299974 0.150114)
			(stroke
				(width 0.1)
				(type default)
			)
			(layer "F.Fab")
		)
		(fp_line
			(start 0.299974 -0.150114)
			(end 0.299974 0.150114)
			(stroke
				(width 0.1)
				(type default)
			)
			(layer "F.Fab")
		)
		(fp_line
			(start -0.299974 0.150114)
			(end -0.299974 -0.150114)
			(stroke
				(width 0.1)
				(type default)
			)
			(layer "F.Fab")
		)
		(fp_line
			(start -0.299974 -0.150114)
			(end 0.299974 -0.150114)
			(stroke
				(width 0.1)
				(type default)
			)
			(layer "F.Fab")
		)
		(pad "1" smd rect
			(at -0.2667 0 180)
			(size 0.3048 0.381)
			(layers "F.Cu" "F.Mask" "F.Paste")
			(net "P5E_PEX3_STN2_TX_DN<34>")
		)
		(pad "2" smd rect
			(at 0.2667 0 180)
			(size 0.3048 0.381)
			(layers "F.Cu" "F.Mask" "F.Paste")
			(net "P5E_PEX3_STN2_TX_C_DN<34>")
		)
	)
	(footprint ""
		(layer "F.Cu")
		(at 198.93661 -368.5921 -90)
		(property "Reference" "PC5"
			(at 0 0 270)
			(layer "F.SilkS")
			(hide yes)
			(effects
				(font
					(size 1.27 1.27)
				)
			)
		)
		(property "Value" ""
			(at 0 0 270)
			(layer "F.Fab")
			(effects
				(font
					(size 1.27 1.27)
				)
			)
		)
		(duplicate_pad_numbers_are_jumpers no)
		(fp_line
			(start -0.7874 0.4064)
			(end -0.7874 -0.4064)
			(stroke
				(width 0.1524)
				(type default)
			)
			(layer "F.SilkS")
		)
		(fp_line
			(start 0.7874 0.4064)
			(end -0.7874 0.4064)
			(stroke
				(width 0.1524)
				(type default)
			)
			(layer "F.SilkS")
		)
		(fp_line
			(start -0.7874 -0.4064)
			(end 0.7874 -0.4064)
			(stroke
				(width 0.1524)
				(type default)
			)
			(layer "F.SilkS")
		)
		(fp_line
			(start 0.7874 -0.4064)
			(end 0.7874 0.4064)
			(stroke
				(width 0.1524)
				(type default)
			)
			(layer "F.SilkS")
		)
		(fp_line
			(start -0.67945 0.3048)
			(end -0.67945 -0.305054)
			(stroke
				(width 0.1)
				(type default)
			)
			(layer "F.Fab")
		)
		(fp_line
			(start -0.12065 0.3048)
			(end -0.67945 0.3048)
			(stroke
				(width 0.1)
				(type default)
			)
			(layer "F.Fab")
		)
		(fp_line
			(start 0.120396 0.3048)
			(end 0.120396 0.2794)
			(stroke
				(width 0.1)
				(type default)
			)
			(layer "F.Fab")
		)
		(fp_line
			(start 0.67945 0.3048)
			(end 0.120396 0.3048)
			(stroke
				(width 0.1)
				(type default)
			)
			(layer "F.Fab")
		)
		(fp_line
			(start -0.12065 0.2794)
			(end -0.12065 0.3048)
			(stroke
				(width 0.1)
				(type default)
			)
			(layer "F.Fab")
		)
		(fp_line
			(start 0.120396 0.2794)
			(end -0.12065 0.2794)
			(stroke
				(width 0.1)
				(type default)
			)
			(layer "F.Fab")
		)
		(fp_line
			(start -0.12065 -0.2794)
			(end 0.12065 -0.2794)
			(stroke
				(width 0.1)
				(type default)
			)
			(layer "F.Fab")
		)
		(fp_line
			(start 0.12065 -0.2794)
			(end 0.12065 -0.3048)
			(stroke
				(width 0.1)
				(type default)
			)
			(layer "F.Fab")
		)
		(fp_line
			(start 0.12065 -0.3048)
			(end 0.67945 -0.3048)
			(stroke
				(width 0.1)
				(type default)
			)
			(layer "F.Fab")
		)
		(fp_line
			(start 0.67945 -0.3048)
			(end 0.67945 0.3048)
			(stroke
				(width 0.1)
				(type default)
			)
			(layer "F.Fab")
		)
		(fp_line
			(start -0.67945 -0.305054)
			(end -0.12065 -0.305054)
			(stroke
				(width 0.1)
				(type default)
			)
			(layer "F.Fab")
		)
		(fp_line
			(start -0.12065 -0.305054)
			(end -0.12065 -0.2794)
			(stroke
				(width 0.1)
				(type default)
			)
			(layer "F.Fab")
		)
		(pad "1" smd circle
			(at -0.40005 0 270)
			(size 0 0)
			(layers "F.Cu" "F.Mask" "F.Paste")
			(net "HSC_VDD_R")
		)
		(pad "2" smd circle
			(at 0.40005 0 270)
			(size 0 0)
			(layers "F.Cu" "F.Mask" "F.Paste")
			(net "AGND_HSC")
		)
	)
	(footprint ""
		(layer "F.Cu")
		(at 38.608 -157.3784 180)
		(property "Reference" "R12"
			(at 0 0 180)
			(layer "F.SilkS")
			(hide yes)
			(effects
				(font
					(size 1.27 1.27)
				)
			)
		)
		(property "Value" ""
			(at 0 0 180)
			(layer "F.Fab")
			(effects
				(font
					(size 1.27 1.27)
				)
			)
		)
		(duplicate_pad_numbers_are_jumpers no)
		(fp_line
			(start 0.7874 0.4064)
			(end -0.7874 0.4064)
			(stroke
				(width 0.1524)
				(type default)
			)
			(layer "F.SilkS")
		)
		(fp_line
			(start 0.7874 -0.4064)
			(end 0.7874 0.4064)
			(stroke
				(width 0.1524)
				(type default)
			)
			(layer "F.SilkS")
		)
		(fp_line
			(start -0.7874 0.4064)
			(end -0.7874 -0.4064)
			(stroke
				(width 0.1524)
				(type default)
			)
			(layer "F.SilkS")
		)
		(fp_line
			(start -0.7874 -0.4064)
			(end 0.7874 -0.4064)
			(stroke
				(width 0.1524)
				(type default)
			)
			(layer "F.SilkS")
		)
		(fp_line
			(start 0.67945 0.3048)
			(end 0.120396 0.3048)
			(stroke
				(width 0.1)
				(type default)
			)
			(layer "F.Fab")
		)
		(fp_line
			(start 0.67945 -0.3048)
			(end 0.67945 0.3048)
			(stroke
				(width 0.1)
				(type default)
			)
			(layer "F.Fab")
		)
		(fp_line
			(start 0.12065 -0.2794)
			(end 0.12065 -0.3048)
			(stroke
				(width 0.1)
				(type default)
			)
			(layer "F.Fab")
		)
		(fp_line
			(start 0.12065 -0.3048)
			(end 0.67945 -0.3048)
			(stroke
				(width 0.1)
				(type default)
			)
			(layer "F.Fab")
		)
		(fp_line
			(start 0.120396 0.3048)
			(end 0.120396 0.2794)
			(stroke
				(width 0.1)
				(type default)
			)
			(layer "F.Fab")
		)
		(fp_line
			(start 0.120396 0.2794)
			(end -0.12065 0.2794)
			(stroke
				(width 0.1)
				(type default)
			)
			(layer "F.Fab")
		)
		(fp_line
			(start -0.12065 0.3048)
			(end -0.67945 0.3048)
			(stroke
				(width 0.1)
				(type default)
			)
			(layer "F.Fab")
		)
		(fp_line
			(start -0.12065 0.2794)
			(end -0.12065 0.3048)
			(stroke
				(width 0.1)
				(type default)
			)
			(layer "F.Fab")
		)
		(fp_line
			(start -0.12065 -0.2794)
			(end 0.12065 -0.2794)
			(stroke
				(width 0.1)
				(type default)
			)
			(layer "F.Fab")
		)
		(fp_line
			(start -0.12065 -0.305054)
			(end -0.12065 -0.2794)
			(stroke
				(width 0.1)
				(type default)
			)
			(layer "F.Fab")
		)
		(fp_line
			(start -0.67945 0.3048)
			(end -0.67945 -0.305054)
			(stroke
				(width 0.1)
				(type default)
			)
			(layer "F.Fab")
		)
		(fp_line
			(start -0.67945 -0.305054)
			(end -0.12065 -0.305054)
			(stroke
				(width 0.1)
				(type default)
			)
			(layer "F.Fab")
		)
		(pad "1" smd circle
			(at -0.40005 0 180)
			(size 0 0)
			(layers "F.Cu" "F.Mask" "F.Paste")
			(net "NIC0_DATA_IN")
		)
		(pad "2" smd circle
			(at 0.40005 0 180)
			(size 0 0)
			(layers "F.Cu" "F.Mask" "F.Paste")
			(net "P3V3_NIC0")
		)
	)
	(footprint ""
		(layer "F.Cu")
		(at 5.617718 -264.586466 180)
		(property "Reference" "R6127"
			(at 0 0 180)
			(layer "F.SilkS")
			(hide yes)
			(effects
				(font
					(size 1.27 1.27)
				)
			)
		)
		(property "Value" ""
			(at 0 0 180)
			(layer "F.Fab")
			(effects
				(font
					(size 1.27 1.27)
				)
			)
		)
		(duplicate_pad_numbers_are_jumpers no)
		(fp_line
			(start 2.576322 1.1303)
			(end -2.576322 1.1303)
			(stroke
				(width 0.1524)
				(type default)
			)
			(layer "F.SilkS")
		)
		(fp_line
			(start 2.576322 -1.1303)
			(end 2.576322 1.1303)
			(stroke
				(width 0.1524)
				(type default)
			)
			(layer "F.SilkS")
		)
		(fp_line
			(start -2.576322 1.1303)
			(end -2.576322 -1.1303)
			(stroke
				(width 0.1524)
				(type default)
			)
			(layer "F.SilkS")
		)
		(fp_line
			(start -2.576322 -1.1303)
			(end 2.576322 -1.1303)
			(stroke
				(width 0.1524)
				(type default)
			)
			(layer "F.SilkS")
		)
		(fp_line
			(start 1.649984 0.899922)
			(end 1.649984 -0.899922)
			(stroke
				(width 0.1)
				(type default)
			)
			(layer "F.Fab")
		)
		(fp_line
			(start 1.649984 -0.899922)
			(end -1.649984 -0.899922)
			(stroke
				(width 0.1)
				(type default)
			)
			(layer "F.Fab")
		)
		(fp_line
			(start -1.649984 0.899922)
			(end 1.649984 0.899922)
			(stroke
				(width 0.1)
				(type default)
			)
			(layer "F.Fab")
		)
		(fp_line
			(start -1.649984 -0.899922)
			(end -1.649984 0.899922)
			(stroke
				(width 0.1)
				(type default)
			)
			(layer "F.Fab")
		)
		(pad "1A" smd rect
			(at -1.700022 0 180)
			(size 1.4986 2.0066)
			(layers "F.Cu" "F.Mask" "F.Paste")
			(net "P1V25_PEX0")
		)
		(pad "1B" smd rect
			(at -1.077722 0 180)
			(size 0.254 0.508)
			(layers "F.Cu" "F.Mask" "F.Paste")
			(net "P1V25_PEX0")
		)
		(pad "2A" smd rect
			(at 1.700022 0 180)
			(size 1.4986 2.0066)
			(layers "F.Cu" "F.Mask" "F.Paste")
			(net "P1V25_SERDES_VDDPLL_PEX0")
		)
		(pad "2B" smd rect
			(at 1.077722 0 180)
			(size 0.254 0.508)
			(layers "F.Cu" "F.Mask" "F.Paste")
			(net "P1V25_SERDES_VDDPLL_PEX0")
		)
	)
	(footprint ""
		(layer "F.Cu")
		(at 425.36237 -22.955504 -90)
		(property "Reference" "C2733"
			(at 0 0 270)
			(layer "F.SilkS")
			(hide yes)
			(effects
				(font
					(size 1.27 1.27)
				)
			)
		)
		(property "Value" ""
			(at 0 0 270)
			(layer "F.Fab")
			(effects
				(font
					(size 1.27 1.27)
				)
			)
		)
		(duplicate_pad_numbers_are_jumpers no)
		(fp_line
			(start -0.7874 0.4064)
			(end -0.7874 -0.4064)
			(stroke
				(width 0.1524)
				(type default)
			)
			(layer "F.SilkS")
		)
		(fp_line
			(start 0.7874 0.4064)
			(end -0.7874 0.4064)
			(stroke
				(width 0.1524)
				(type default)
			)
			(layer "F.SilkS")
		)
		(fp_line
			(start -0.7874 -0.4064)
			(end 0.7874 -0.4064)
			(stroke
				(width 0.1524)
				(type default)
			)
			(layer "F.SilkS")
		)
		(fp_line
			(start 0.7874 -0.4064)
			(end 0.7874 0.4064)
			(stroke
				(width 0.1524)
				(type default)
			)
			(layer "F.SilkS")
		)
		(fp_line
			(start -0.67945 0.3048)
			(end -0.67945 -0.305054)
			(stroke
				(width 0.1)
				(type default)
			)
			(layer "F.Fab")
		)
		(fp_line
			(start -0.12065 0.3048)
			(end -0.67945 0.3048)
			(stroke
				(width 0.1)
				(type default)
			)
			(layer "F.Fab")
		)
		(fp_line
			(start 0.120396 0.3048)
			(end 0.120396 0.2794)
			(stroke
				(width 0.1)
				(type default)
			)
			(layer "F.Fab")
		)
		(fp_line
			(start 0.67945 0.3048)
			(end 0.120396 0.3048)
			(stroke
				(width 0.1)
				(type default)
			)
			(layer "F.Fab")
		)
		(fp_line
			(start -0.12065 0.2794)
			(end -0.12065 0.3048)
			(stroke
				(width 0.1)
				(type default)
			)
			(layer "F.Fab")
		)
		(fp_line
			(start 0.120396 0.2794)
			(end -0.12065 0.2794)
			(stroke
				(width 0.1)
				(type default)
			)
			(layer "F.Fab")
		)
		(fp_line
			(start -0.12065 -0.2794)
			(end 0.12065 -0.2794)
			(stroke
				(width 0.1)
				(type default)
			)
			(layer "F.Fab")
		)
		(fp_line
			(start 0.12065 -0.2794)
			(end 0.12065 -0.3048)
			(stroke
				(width 0.1)
				(type default)
			)
			(layer "F.Fab")
		)
		(fp_line
			(start 0.12065 -0.3048)
			(end 0.67945 -0.3048)
			(stroke
				(width 0.1)
				(type default)
			)
			(layer "F.Fab")
		)
		(fp_line
			(start 0.67945 -0.3048)
			(end 0.67945 0.3048)
			(stroke
				(width 0.1)
				(type default)
			)
			(layer "F.Fab")
		)
		(fp_line
			(start -0.67945 -0.305054)
			(end -0.12065 -0.305054)
			(stroke
				(width 0.1)
				(type default)
			)
			(layer "F.Fab")
		)
		(fp_line
			(start -0.12065 -0.305054)
			(end -0.12065 -0.2794)
			(stroke
				(width 0.1)
				(type default)
			)
			(layer "F.Fab")
		)
		(pad "1" smd circle
			(at -0.40005 0 270)
			(size 0 0)
			(layers "F.Cu" "F.Mask" "F.Paste")
			(net "GND")
		)
		(pad "2" smd circle
			(at 0.40005 0 270)
			(size 0 0)
			(layers "F.Cu" "F.Mask" "F.Paste")
			(net "P3V3_AUX")
		)
	)
	(footprint ""
		(layer "F.Cu")
		(at 190.061088 -37.951156)
		(property "Reference" "Q223"
			(at -0.018288 -1.925574 0)
			(unlocked yes)
			(layer "F.SilkS")
			(effects
				(font
					(size 0.7874 0.5842)
					(thickness 0.1524)
				)
			)
		)
		(property "Value" ""
			(at 0 0 0)
			(layer "F.Fab")
			(effects
				(font
					(size 1.27 1.27)
				)
			)
		)
		(duplicate_pad_numbers_are_jumpers no)
		(fp_line
			(start -1.376172 -1.199896)
			(end -0.508 -1.199896)
			(stroke
				(width 0.1524)
				(type default)
			)
			(layer "F.SilkS")
		)
		(fp_line
			(start -1.376172 1.199896)
			(end -1.376172 -1.199896)
			(stroke
				(width 0.1524)
				(type default)
			)
			(layer "F.SilkS")
		)
		(fp_line
			(start -0.508 -1.199896)
			(end 0 -0.762)
			(stroke
				(width 0.1524)
				(type default)
			)
			(layer "F.SilkS")
		)
		(fp_line
			(start 0 -0.762)
			(end 0.508 -1.199896)
			(stroke
				(width 0.1524)
				(type default)
			)
			(layer "F.SilkS")
		)
		(fp_line
			(start 0.508 -1.199896)
			(end 1.376172 -1.199896)
			(stroke
				(width 0.1524)
				(type default)
			)
			(layer "F.SilkS")
		)
		(fp_line
			(start 1.376172 -1.199896)
			(end 1.376172 1.199896)
			(stroke
				(width 0.1524)
				(type default)
			)
			(layer "F.SilkS")
		)
		(fp_line
			(start 1.376172 1.199896)
			(end -1.376172 1.199896)
			(stroke
				(width 0.1524)
				(type default)
			)
			(layer "F.SilkS")
		)
		(fp_poly
			(pts
				(xy -1.500886 -1.23571) (xy -1.77038 -2.043938) (xy -2.309114 -1.50495)
			)
			(stroke
				(width 0)
				(type default)
			)
			(fill yes)
			(layer "F.SilkS")
		)
		(fp_line
			(start -0.674878 -1.100074)
			(end 0.674878 -1.100074)
			(stroke
				(width 0.1)
				(type default)
			)
			(layer "F.Fab")
		)
		(fp_line
			(start -0.674878 1.100074)
			(end -0.674878 -1.100074)
			(stroke
				(width 0.1)
				(type default)
			)
			(layer "F.Fab")
		)
		(fp_line
			(start 0.674878 -1.100074)
			(end 0.674878 1.100074)
			(stroke
				(width 0.1)
				(type default)
			)
			(layer "F.Fab")
		)
		(fp_line
			(start 0.674878 1.100074)
			(end -0.674878 1.100074)
			(stroke
				(width 0.1)
				(type default)
			)
			(layer "F.Fab")
		)
		(fp_poly
			(pts
				(xy -1.4605 -0.7493) (xy -2.2225 -1.1303) (xy -2.2225 -0.3683)
			)
			(stroke
				(width 0)
				(type default)
			)
			(fill yes)
			(layer "F.Fab")
		)
		(pad "1" smd rect
			(at -0.899922 -0.750062 270)
			(size 0.6096 0.6096)
			(layers "F.Cu" "F.Mask" "F.Paste")
			(net "GND")
		)
		(pad "2" smd rect
			(at -0.899922 0 270)
			(size 0.4064 0.6096)
			(layers "F.Cu" "F.Mask" "F.Paste")
			(net "P3V3_SSD7_PG_G1")
		)
		(pad "3" smd rect
			(at -0.899922 0.750062 270)
			(size 0.6096 0.6096)
			(layers "F.Cu" "F.Mask" "F.Paste")
			(net "PWRGD_P3V3_SSD7_D")
		)
		(pad "4" smd rect
			(at 0.899922 0.750062 270)
			(size 0.6096 0.6096)
			(layers "F.Cu" "F.Mask" "F.Paste")
			(net "GND")
		)
		(pad "5" smd rect
			(at 0.899922 0 270)
			(size 0.4064 0.6096)
			(layers "F.Cu" "F.Mask" "F.Paste")
			(net "P3V3_SSD7_PG_G2")
		)
		(pad "6" smd rect
			(at 0.899922 -0.750062 270)
			(size 0.6096 0.6096)
			(layers "F.Cu" "F.Mask" "F.Paste")
			(net "P3V3_SSD7_PG_G2")
		)
	)
	(footprint ""
		(layer "F.Cu")
		(at 145.643854 -311.725564 45)
		(property "Reference" "R1283"
			(at 0 0 45)
			(layer "F.SilkS")
			(hide yes)
			(effects
				(font
					(size 1.27 1.27)
				)
			)
		)
		(property "Value" ""
			(at 0 0 45)
			(layer "F.Fab")
			(effects
				(font
					(size 1.27 1.27)
				)
			)
		)
		(duplicate_pad_numbers_are_jumpers no)
		(fp_line
			(start -0.787389 -0.406267)
			(end 0.787389 -0.406267)
			(stroke
				(width 0.1524)
				(type default)
			)
			(layer "F.SilkS")
		)
		(fp_line
			(start -0.787389 0.406267)
			(end -0.787389 -0.406267)
			(stroke
				(width 0.1524)
				(type default)
			)
			(layer "F.SilkS")
		)
		(fp_line
			(start 0.787389 -0.406267)
			(end 0.787389 0.406267)
			(stroke
				(width 0.1524)
				(type default)
			)
			(layer "F.SilkS")
		)
		(fp_line
			(start 0.787389 0.406267)
			(end -0.787389 0.406267)
			(stroke
				(width 0.1524)
				(type default)
			)
			(layer "F.SilkS")
		)
		(fp_line
			(start -0.679446 -0.305149)
			(end -0.120695 -0.304969)
			(stroke
				(width 0.1)
				(type default)
			)
			(layer "F.Fab")
		)
		(fp_line
			(start -0.120695 -0.304969)
			(end -0.120695 -0.279466)
			(stroke
				(width 0.1)
				(type default)
			)
			(layer "F.Fab")
		)
		(fp_line
			(start -0.120695 -0.279466)
			(end 0.120695 -0.279466)
			(stroke
				(width 0.1)
				(type default)
			)
			(layer "F.Fab")
		)
		(fp_line
			(start -0.679446 0.30479)
			(end -0.679446 -0.305149)
			(stroke
				(width 0.1)
				(type default)
			)
			(layer "F.Fab")
		)
		(fp_line
			(start 0.120515 -0.30479)
			(end 0.679446 -0.30479)
			(stroke
				(width 0.1)
				(type default)
			)
			(layer "F.Fab")
		)
		(fp_line
			(start 0.120695 -0.279466)
			(end 0.120515 -0.30479)
			(stroke
				(width 0.1)
				(type default)
			)
			(layer "F.Fab")
		)
		(fp_line
			(start -0.120695 0.279466)
			(end -0.120515 0.30479)
			(stroke
				(width 0.1)
				(type default)
			)
			(layer "F.Fab")
		)
		(fp_line
			(start -0.120515 0.30479)
			(end -0.679446 0.30479)
			(stroke
				(width 0.1)
				(type default)
			)
			(layer "F.Fab")
		)
		(fp_line
			(start 0.679446 -0.30479)
			(end 0.679446 0.30479)
			(stroke
				(width 0.1)
				(type default)
			)
			(layer "F.Fab")
		)
		(fp_line
			(start 0.120335 0.279466)
			(end -0.120695 0.279466)
			(stroke
				(width 0.1)
				(type default)
			)
			(layer "F.Fab")
		)
		(fp_line
			(start 0.120515 0.30479)
			(end 0.120335 0.279466)
			(stroke
				(width 0.1)
				(type default)
			)
			(layer "F.Fab")
		)
		(fp_line
			(start 0.679446 0.30479)
			(end 0.120515 0.30479)
			(stroke
				(width 0.1)
				(type default)
			)
			(layer "F.Fab")
		)
		(pad "1" smd circle
			(at -0.40005 0 45)
			(size 0 0)
			(layers "F.Cu" "F.Mask" "F.Paste")
			(net "GND")
		)
		(pad "2" smd circle
			(at 0.40005 0 45)
			(size 0 0)
			(layers "F.Cu" "F.Mask" "F.Paste")
			(net "PEX1_DBG_SEL1")
		)
	)
	(footprint ""
		(layer "F.Cu")
		(at 7.613396 -138.360404 180)
		(property "Reference" "R4442"
			(at 0 0 180)
			(layer "F.SilkS")
			(hide yes)
			(effects
				(font
					(size 1.27 1.27)
				)
			)
		)
		(property "Value" ""
			(at 0 0 180)
			(layer "F.Fab")
			(effects
				(font
					(size 1.27 1.27)
				)
			)
		)
		(duplicate_pad_numbers_are_jumpers no)
		(fp_line
			(start 0.7874 0.4064)
			(end -0.7874 0.4064)
			(stroke
				(width 0.1524)
				(type default)
			)
			(layer "F.SilkS")
		)
		(fp_line
			(start 0.7874 -0.4064)
			(end 0.7874 0.4064)
			(stroke
				(width 0.1524)
				(type default)
			)
			(layer "F.SilkS")
		)
		(fp_line
			(start -0.7874 0.4064)
			(end -0.7874 -0.4064)
			(stroke
				(width 0.1524)
				(type default)
			)
			(layer "F.SilkS")
		)
		(fp_line
			(start -0.7874 -0.4064)
			(end 0.7874 -0.4064)
			(stroke
				(width 0.1524)
				(type default)
			)
			(layer "F.SilkS")
		)
		(fp_line
			(start 0.67945 0.3048)
			(end 0.120396 0.3048)
			(stroke
				(width 0.1)
				(type default)
			)
			(layer "F.Fab")
		)
		(fp_line
			(start 0.67945 -0.3048)
			(end 0.67945 0.3048)
			(stroke
				(width 0.1)
				(type default)
			)
			(layer "F.Fab")
		)
		(fp_line
			(start 0.12065 -0.2794)
			(end 0.12065 -0.3048)
			(stroke
				(width 0.1)
				(type default)
			)
			(layer "F.Fab")
		)
		(fp_line
			(start 0.12065 -0.3048)
			(end 0.67945 -0.3048)
			(stroke
				(width 0.1)
				(type default)
			)
			(layer "F.Fab")
		)
		(fp_line
			(start 0.120396 0.3048)
			(end 0.120396 0.2794)
			(stroke
				(width 0.1)
				(type default)
			)
			(layer "F.Fab")
		)
		(fp_line
			(start 0.120396 0.2794)
			(end -0.12065 0.2794)
			(stroke
				(width 0.1)
				(type default)
			)
			(layer "F.Fab")
		)
		(fp_line
			(start -0.12065 0.3048)
			(end -0.67945 0.3048)
			(stroke
				(width 0.1)
				(type default)
			)
			(layer "F.Fab")
		)
		(fp_line
			(start -0.12065 0.2794)
			(end -0.12065 0.3048)
			(stroke
				(width 0.1)
				(type default)
			)
			(layer "F.Fab")
		)
		(fp_line
			(start -0.12065 -0.2794)
			(end 0.12065 -0.2794)
			(stroke
				(width 0.1)
				(type default)
			)
			(layer "F.Fab")
		)
		(fp_line
			(start -0.12065 -0.305054)
			(end -0.12065 -0.2794)
			(stroke
				(width 0.1)
				(type default)
			)
			(layer "F.Fab")
		)
		(fp_line
			(start -0.67945 0.3048)
			(end -0.67945 -0.305054)
			(stroke
				(width 0.1)
				(type default)
			)
			(layer "F.Fab")
		)
		(fp_line
			(start -0.67945 -0.305054)
			(end -0.12065 -0.305054)
			(stroke
				(width 0.1)
				(type default)
			)
			(layer "F.Fab")
		)
		(pad "1" smd circle
			(at -0.40005 0 180)
			(size 0 0)
			(layers "F.Cu" "F.Mask" "F.Paste")
			(net "PWRGD_P12V_NIC0")
		)
		(pad "2" smd circle
			(at 0.40005 0 180)
			(size 0 0)
			(layers "F.Cu" "F.Mask" "F.Paste")
			(net "PWRGD_P12V_NIC0_R")
		)
	)
	(footprint ""
		(layer "F.Cu")
		(at 69.926454 -25.432004 -90)
		(property "Reference" "C967"
			(at 0 0 270)
			(layer "F.SilkS")
			(hide yes)
			(effects
				(font
					(size 1.27 1.27)
				)
			)
		)
		(property "Value" ""
			(at 0 0 270)
			(layer "F.Fab")
			(effects
				(font
					(size 1.27 1.27)
				)
			)
		)
		(duplicate_pad_numbers_are_jumpers no)
		(fp_line
			(start -0.7874 0.4064)
			(end -0.7874 -0.4064)
			(stroke
				(width 0.1524)
				(type default)
			)
			(layer "F.SilkS")
		)
		(fp_line
			(start 0.7874 0.4064)
			(end -0.7874 0.4064)
			(stroke
				(width 0.1524)
				(type default)
			)
			(layer "F.SilkS")
		)
		(fp_line
			(start -0.7874 -0.4064)
			(end 0.7874 -0.4064)
			(stroke
				(width 0.1524)
				(type default)
			)
			(layer "F.SilkS")
		)
		(fp_line
			(start 0.7874 -0.4064)
			(end 0.7874 0.4064)
			(stroke
				(width 0.1524)
				(type default)
			)
			(layer "F.SilkS")
		)
		(fp_line
			(start -0.67945 0.3048)
			(end -0.67945 -0.305054)
			(stroke
				(width 0.1)
				(type default)
			)
			(layer "F.Fab")
		)
		(fp_line
			(start -0.12065 0.3048)
			(end -0.67945 0.3048)
			(stroke
				(width 0.1)
				(type default)
			)
			(layer "F.Fab")
		)
		(fp_line
			(start 0.120396 0.3048)
			(end 0.120396 0.2794)
			(stroke
				(width 0.1)
				(type default)
			)
			(layer "F.Fab")
		)
		(fp_line
			(start 0.67945 0.3048)
			(end 0.120396 0.3048)
			(stroke
				(width 0.1)
				(type default)
			)
			(layer "F.Fab")
		)
		(fp_line
			(start -0.12065 0.2794)
			(end -0.12065 0.3048)
			(stroke
				(width 0.1)
				(type default)
			)
			(layer "F.Fab")
		)
		(fp_line
			(start 0.120396 0.2794)
			(end -0.12065 0.2794)
			(stroke
				(width 0.1)
				(type default)
			)
			(layer "F.Fab")
		)
		(fp_line
			(start -0.12065 -0.2794)
			(end 0.12065 -0.2794)
			(stroke
				(width 0.1)
				(type default)
			)
			(layer "F.Fab")
		)
		(fp_line
			(start 0.12065 -0.2794)
			(end 0.12065 -0.3048)
			(stroke
				(width 0.1)
				(type default)
			)
			(layer "F.Fab")
		)
		(fp_line
			(start 0.12065 -0.3048)
			(end 0.67945 -0.3048)
			(stroke
				(width 0.1)
				(type default)
			)
			(layer "F.Fab")
		)
		(fp_line
			(start 0.67945 -0.3048)
			(end 0.67945 0.3048)
			(stroke
				(width 0.1)
				(type default)
			)
			(layer "F.Fab")
		)
		(fp_line
			(start -0.67945 -0.305054)
			(end -0.12065 -0.305054)
			(stroke
				(width 0.1)
				(type default)
			)
			(layer "F.Fab")
		)
		(fp_line
			(start -0.12065 -0.305054)
			(end -0.12065 -0.2794)
			(stroke
				(width 0.1)
				(type default)
			)
			(layer "F.Fab")
		)
		(pad "1" smd circle
			(at -0.40005 0 270)
			(size 0 0)
			(layers "F.Cu" "F.Mask" "F.Paste")
			(net "GND")
		)
		(pad "2" smd circle
			(at 0.40005 0 270)
			(size 0 0)
			(layers "F.Cu" "F.Mask" "F.Paste")
			(net "P3V3_SSD2")
		)
	)
	(footprint ""
		(layer "F.Cu")
		(at 381.40386 -343.952322 90)
		(property "Reference" "C787"
			(at 0 0 90)
			(layer "F.SilkS")
			(hide yes)
			(effects
				(font
					(size 1.27 1.27)
				)
			)
		)
		(property "Value" ""
			(at 0 0 90)
			(layer "F.Fab")
			(effects
				(font
					(size 1.27 1.27)
				)
			)
		)
		(duplicate_pad_numbers_are_jumpers no)
		(fp_line
			(start 0.299974 -0.150114)
			(end 0.299974 0.150114)
			(stroke
				(width 0.1)
				(type default)
			)
			(layer "F.Fab")
		)
		(fp_line
			(start -0.299974 -0.150114)
			(end 0.299974 -0.150114)
			(stroke
				(width 0.1)
				(type default)
			)
			(layer "F.Fab")
		)
		(fp_line
			(start 0.299974 0.150114)
			(end -0.299974 0.150114)
			(stroke
				(width 0.1)
				(type default)
			)
			(layer "F.Fab")
		)
		(fp_line
			(start -0.299974 0.150114)
			(end -0.299974 -0.150114)
			(stroke
				(width 0.1)
				(type default)
			)
			(layer "F.Fab")
		)
		(pad "1" smd rect
			(at -0.2667 0 90)
			(size 0.3048 0.381)
			(layers "F.Cu" "F.Mask" "F.Paste")
			(net "P5E_PEX3_STN6_TX_DN<99>")
		)
		(pad "2" smd rect
			(at 0.2667 0 90)
			(size 0.3048 0.381)
			(layers "F.Cu" "F.Mask" "F.Paste")
			(net "P5E_PEX3_STN6_TX_C_DN<99>")
		)
	)
	(footprint ""
		(layer "F.Cu")
		(at 196.119242 -154.304746 180)
		(property "Reference" "C214"
			(at 0 0 180)
			(layer "F.SilkS")
			(hide yes)
			(effects
				(font
					(size 1.27 1.27)
				)
			)
		)
		(property "Value" ""
			(at 0 0 180)
			(layer "F.Fab")
			(effects
				(font
					(size 1.27 1.27)
				)
			)
		)
		(duplicate_pad_numbers_are_jumpers no)
		(fp_line
			(start 0.299974 0.150114)
			(end -0.299974 0.150114)
			(stroke
				(width 0.1)
				(type default)
			)
			(layer "F.Fab")
		)
		(fp_line
			(start 0.299974 -0.150114)
			(end 0.299974 0.150114)
			(stroke
				(width 0.1)
				(type default)
			)
			(layer "F.Fab")
		)
		(fp_line
			(start -0.299974 0.150114)
			(end -0.299974 -0.150114)
			(stroke
				(width 0.1)
				(type default)
			)
			(layer "F.Fab")
		)
		(fp_line
			(start -0.299974 -0.150114)
			(end 0.299974 -0.150114)
			(stroke
				(width 0.1)
				(type default)
			)
			(layer "F.Fab")
		)
		(pad "1" smd rect
			(at -0.2667 0 180)
			(size 0.3048 0.381)
			(layers "F.Cu" "F.Mask" "F.Paste")
			(net "P5E_PEX1_STN0_TX_DN<14>")
		)
		(pad "2" smd rect
			(at 0.2667 0 180)
			(size 0.3048 0.381)
			(layers "F.Cu" "F.Mask" "F.Paste")
			(net "P5E_PEX1_STN0_TX_C_DN<14>")
		)
	)
	(footprint ""
		(layer "F.Cu")
		(at 228.103684 -257.99796 -90)
		(property "Reference" "R6501"
			(at 0 0 270)
			(layer "F.SilkS")
			(hide yes)
			(effects
				(font
					(size 1.27 1.27)
				)
			)
		)
		(property "Value" ""
			(at 0 0 270)
			(layer "F.Fab")
			(effects
				(font
					(size 1.27 1.27)
				)
			)
		)
		(duplicate_pad_numbers_are_jumpers no)
		(fp_line
			(start -0.7874 0.4064)
			(end -0.7874 -0.4064)
			(stroke
				(width 0.1524)
				(type default)
			)
			(layer "F.SilkS")
		)
		(fp_line
			(start 0.7874 0.4064)
			(end -0.7874 0.4064)
			(stroke
				(width 0.1524)
				(type default)
			)
			(layer "F.SilkS")
		)
		(fp_line
			(start -0.7874 -0.4064)
			(end 0.7874 -0.4064)
			(stroke
				(width 0.1524)
				(type default)
			)
			(layer "F.SilkS")
		)
		(fp_line
			(start 0.7874 -0.4064)
			(end 0.7874 0.4064)
			(stroke
				(width 0.1524)
				(type default)
			)
			(layer "F.SilkS")
		)
		(fp_line
			(start -0.67945 0.3048)
			(end -0.67945 -0.305054)
			(stroke
				(width 0.1)
				(type default)
			)
			(layer "F.Fab")
		)
		(fp_line
			(start -0.12065 0.3048)
			(end -0.67945 0.3048)
			(stroke
				(width 0.1)
				(type default)
			)
			(layer "F.Fab")
		)
		(fp_line
			(start 0.120396 0.3048)
			(end 0.120396 0.2794)
			(stroke
				(width 0.1)
				(type default)
			)
			(layer "F.Fab")
		)
		(fp_line
			(start 0.67945 0.3048)
			(end 0.120396 0.3048)
			(stroke
				(width 0.1)
				(type default)
			)
			(layer "F.Fab")
		)
		(fp_line
			(start -0.12065 0.2794)
			(end -0.12065 0.3048)
			(stroke
				(width 0.1)
				(type default)
			)
			(layer "F.Fab")
		)
		(fp_line
			(start 0.120396 0.2794)
			(end -0.12065 0.2794)
			(stroke
				(width 0.1)
				(type default)
			)
			(layer "F.Fab")
		)
		(fp_line
			(start -0.12065 -0.2794)
			(end 0.12065 -0.2794)
			(stroke
				(width 0.1)
				(type default)
			)
			(layer "F.Fab")
		)
		(fp_line
			(start 0.12065 -0.2794)
			(end 0.12065 -0.3048)
			(stroke
				(width 0.1)
				(type default)
			)
			(layer "F.Fab")
		)
		(fp_line
			(start 0.12065 -0.3048)
			(end 0.67945 -0.3048)
			(stroke
				(width 0.1)
				(type default)
			)
			(layer "F.Fab")
		)
		(fp_line
			(start 0.67945 -0.3048)
			(end 0.67945 0.3048)
			(stroke
				(width 0.1)
				(type default)
			)
			(layer "F.Fab")
		)
		(fp_line
			(start -0.67945 -0.305054)
			(end -0.12065 -0.305054)
			(stroke
				(width 0.1)
				(type default)
			)
			(layer "F.Fab")
		)
		(fp_line
			(start -0.12065 -0.305054)
			(end -0.12065 -0.2794)
			(stroke
				(width 0.1)
				(type default)
			)
			(layer "F.Fab")
		)
		(pad "1" smd circle
			(at -0.40005 0 270)
			(size 0 0)
			(layers "F.Cu" "F.Mask" "F.Paste")
			(net "P1V25_SERDES_VDDPLL_PEX1")
		)
		(pad "2" smd circle
			(at 0.40005 0 270)
			(size 0 0)
			(layers "F.Cu" "F.Mask" "F.Paste")
			(net "P1V25_SERDES_VDDPLL_PEX1_C8")
		)
	)
	(footprint ""
		(layer "F.Cu")
		(at 381.587756 -291.619432)
		(property "Reference" "C3564"
			(at 0 0 0)
			(layer "F.SilkS")
			(hide yes)
			(effects
				(font
					(size 1.27 1.27)
				)
			)
		)
		(property "Value" ""
			(at 0 0 0)
			(layer "F.Fab")
			(effects
				(font
					(size 1.27 1.27)
				)
			)
		)
		(duplicate_pad_numbers_are_jumpers no)
		(fp_line
			(start -1.2954 -0.5842)
			(end 1.2954 -0.5842)
			(stroke
				(width 0.1524)
				(type default)
			)
			(layer "F.SilkS")
		)
		(fp_line
			(start -1.2954 0.5842)
			(end -1.2954 -0.5842)
			(stroke
				(width 0.1524)
				(type default)
			)
			(layer "F.SilkS")
		)
		(fp_line
			(start 1.2954 -0.5842)
			(end 1.2954 0.5842)
			(stroke
				(width 0.1524)
				(type default)
			)
			(layer "F.SilkS")
		)
		(fp_line
			(start 1.2954 0.5842)
			(end -1.2954 0.5842)
			(stroke
				(width 0.1524)
				(type default)
			)
			(layer "F.SilkS")
		)
		(fp_line
			(start -1.1938 -0.4064)
			(end -0.8636 -0.4064)
			(stroke
				(width 0.1)
				(type default)
			)
			(layer "F.Fab")
		)
		(fp_line
			(start -1.1938 0.4064)
			(end -1.1938 -0.4064)
			(stroke
				(width 0.1)
				(type default)
			)
			(layer "F.Fab")
		)
		(fp_line
			(start -0.8636 -0.4572)
			(end 0.8636 -0.4572)
			(stroke
				(width 0.1)
				(type default)
			)
			(layer "F.Fab")
		)
		(fp_line
			(start -0.8636 -0.4064)
			(end -0.8636 -0.4572)
			(stroke
				(width 0.1)
				(type default)
			)
			(layer "F.Fab")
		)
		(fp_line
			(start -0.8636 0.4064)
			(end -1.1938 0.4064)
			(stroke
				(width 0.1)
				(type default)
			)
			(layer "F.Fab")
		)
		(fp_line
			(start -0.8636 0.4572)
			(end -0.8636 0.4064)
			(stroke
				(width 0.1)
				(type default)
			)
			(layer "F.Fab")
		)
		(fp_line
			(start 0.8636 -0.4572)
			(end 0.8636 -0.4064)
			(stroke
				(width 0.1)
				(type default)
			)
			(layer "F.Fab")
		)
		(fp_line
			(start 0.8636 -0.4064)
			(end 1.1938 -0.4064)
			(stroke
				(width 0.1)
				(type default)
			)
			(layer "F.Fab")
		)
		(fp_line
			(start 0.8636 0.4064)
			(end 0.8636 0.4572)
			(stroke
				(width 0.1)
				(type default)
			)
			(layer "F.Fab")
		)
		(fp_line
			(start 0.8636 0.4572)
			(end -0.8636 0.4572)
			(stroke
				(width 0.1)
				(type default)
			)
			(layer "F.Fab")
		)
		(fp_line
			(start 1.1938 -0.4064)
			(end 1.1938 0.4064)
			(stroke
				(width 0.1)
				(type default)
			)
			(layer "F.Fab")
		)
		(fp_line
			(start 1.1938 0.4064)
			(end 0.8636 0.4064)
			(stroke
				(width 0.1)
				(type default)
			)
			(layer "F.Fab")
		)
		(pad "1" smd rect
			(at -0.7366 0 270)
			(size 0.7112 0.8128)
			(layers "F.Cu" "F.Mask" "F.Paste")
			(net "PCEPLL4_VDDA18_PEX3")
		)
		(pad "2" smd rect
			(at 0.7366 0 270)
			(size 0.7112 0.8128)
			(layers "F.Cu" "F.Mask" "F.Paste")
			(net "GND")
		)
	)
	(footprint ""
		(layer "F.Cu")
		(at 340.729316 -308.524148 -90)
		(property "Reference" "C4319"
			(at 0 0 270)
			(layer "F.SilkS")
			(hide yes)
			(effects
				(font
					(size 1.27 1.27)
				)
			)
		)
		(property "Value" ""
			(at 0 0 270)
			(layer "F.Fab")
			(effects
				(font
					(size 1.27 1.27)
				)
			)
		)
		(duplicate_pad_numbers_are_jumpers no)
		(fp_line
			(start -1.2954 0.5842)
			(end -1.2954 -0.5842)
			(stroke
				(width 0.1524)
				(type default)
			)
			(layer "F.SilkS")
		)
		(fp_line
			(start 1.2954 0.5842)
			(end -1.2954 0.5842)
			(stroke
				(width 0.1524)
				(type default)
			)
			(layer "F.SilkS")
		)
		(fp_line
			(start -1.2954 -0.5842)
			(end 1.2954 -0.5842)
			(stroke
				(width 0.1524)
				(type default)
			)
			(layer "F.SilkS")
		)
		(fp_line
			(start 1.2954 -0.5842)
			(end 1.2954 0.5842)
			(stroke
				(width 0.1524)
				(type default)
			)
			(layer "F.SilkS")
		)
		(fp_line
			(start -0.8636 0.4572)
			(end -0.8636 0.4064)
			(stroke
				(width 0.1)
				(type default)
			)
			(layer "F.Fab")
		)
		(fp_line
			(start 0.8636 0.4572)
			(end -0.8636 0.4572)
			(stroke
				(width 0.1)
				(type default)
			)
			(layer "F.Fab")
		)
		(fp_line
			(start -1.1938 0.4064)
			(end -1.1938 -0.4064)
			(stroke
				(width 0.1)
				(type default)
			)
			(layer "F.Fab")
		)
		(fp_line
			(start -0.8636 0.4064)
			(end -1.1938 0.4064)
			(stroke
				(width 0.1)
				(type default)
			)
			(layer "F.Fab")
		)
		(fp_line
			(start 0.8636 0.4064)
			(end 0.8636 0.4572)
			(stroke
				(width 0.1)
				(type default)
			)
			(layer "F.Fab")
		)
		(fp_line
			(start 1.1938 0.4064)
			(end 0.8636 0.4064)
			(stroke
				(width 0.1)
				(type default)
			)
			(layer "F.Fab")
		)
		(fp_line
			(start -1.1938 -0.4064)
			(end -0.8636 -0.4064)
			(stroke
				(width 0.1)
				(type default)
			)
			(layer "F.Fab")
		)
		(fp_line
			(start -0.8636 -0.4064)
			(end -0.8636 -0.4572)
			(stroke
				(width 0.1)
				(type default)
			)
			(layer "F.Fab")
		)
		(fp_line
			(start 0.8636 -0.4064)
			(end 1.1938 -0.4064)
			(stroke
				(width 0.1)
				(type default)
			)
			(layer "F.Fab")
		)
		(fp_line
			(start 1.1938 -0.4064)
			(end 1.1938 0.4064)
			(stroke
				(width 0.1)
				(type default)
			)
			(layer "F.Fab")
		)
		(fp_line
			(start -0.8636 -0.4572)
			(end 0.8636 -0.4572)
			(stroke
				(width 0.1)
				(type default)
			)
			(layer "F.Fab")
		)
		(fp_line
			(start 0.8636 -0.4572)
			(end 0.8636 -0.4064)
			(stroke
				(width 0.1)
				(type default)
			)
			(layer "F.Fab")
		)
		(pad "1" smd rect
			(at -0.7366 0 180)
			(size 0.7112 0.8128)
			(layers "F.Cu" "F.Mask" "F.Paste")
			(net "P0V8_PEX2")
		)
		(pad "2" smd rect
			(at 0.7366 0 180)
			(size 0.7112 0.8128)
			(layers "F.Cu" "F.Mask" "F.Paste")
			(net "GND")
		)
	)
	(footprint ""
		(layer "F.Cu")
		(at 322.718684 -356.244906 90)
		(property "Reference" "C540"
			(at 0 0 90)
			(layer "F.SilkS")
			(hide yes)
			(effects
				(font
					(size 1.27 1.27)
				)
			)
		)
		(property "Value" ""
			(at 0 0 90)
			(layer "F.Fab")
			(effects
				(font
					(size 1.27 1.27)
				)
			)
		)
		(duplicate_pad_numbers_are_jumpers no)
		(fp_line
			(start 0.299974 -0.150114)
			(end 0.299974 0.150114)
			(stroke
				(width 0.1)
				(type default)
			)
			(layer "F.Fab")
		)
		(fp_line
			(start -0.299974 -0.150114)
			(end 0.299974 -0.150114)
			(stroke
				(width 0.1)
				(type default)
			)
			(layer "F.Fab")
		)
		(fp_line
			(start 0.299974 0.150114)
			(end -0.299974 0.150114)
			(stroke
				(width 0.1)
				(type default)
			)
			(layer "F.Fab")
		)
		(fp_line
			(start -0.299974 0.150114)
			(end -0.299974 -0.150114)
			(stroke
				(width 0.1)
				(type default)
			)
			(layer "F.Fab")
		)
		(pad "1" smd rect
			(at -0.2667 0 90)
			(size 0.3048 0.381)
			(layers "F.Cu" "F.Mask" "F.Paste")
			(net "P5E_PEX2_STN5_TX_DN<85>")
		)
		(pad "2" smd rect
			(at 0.2667 0 90)
			(size 0.3048 0.381)
			(layers "F.Cu" "F.Mask" "F.Paste")
			(net "P5E_PEX2_STN5_TX_C_DN<85>")
		)
	)
	(footprint ""
		(layer "F.Cu")
		(at 364.234222 -135.77697 -90)
		(property "Reference" "PC819"
			(at 0 0 270)
			(layer "F.SilkS")
			(hide yes)
			(effects
				(font
					(size 1.27 1.27)
				)
			)
		)
		(property "Value" ""
			(at 0 0 270)
			(layer "F.Fab")
			(effects
				(font
					(size 1.27 1.27)
				)
			)
		)
		(duplicate_pad_numbers_are_jumpers no)
		(fp_line
			(start -1.524 0.762)
			(end -1.524 -0.762)
			(stroke
				(width 0.1524)
				(type default)
			)
			(layer "F.SilkS")
		)
		(fp_line
			(start 1.524 0.762)
			(end -1.524 0.762)
			(stroke
				(width 0.1524)
				(type default)
			)
			(layer "F.SilkS")
		)
		(fp_line
			(start -1.524 -0.762)
			(end 1.524 -0.762)
			(stroke
				(width 0.1524)
				(type default)
			)
			(layer "F.SilkS")
		)
		(fp_line
			(start 1.524 -0.762)
			(end 1.524 0.762)
			(stroke
				(width 0.1524)
				(type default)
			)
			(layer "F.SilkS")
		)
		(fp_line
			(start -1.1049 0.724916)
			(end 1.1049 0.724916)
			(stroke
				(width 0.1)
				(type default)
			)
			(layer "F.Fab")
		)
		(fp_line
			(start 1.1049 0.724916)
			(end 1.1049 -0.724916)
			(stroke
				(width 0.1)
				(type default)
			)
			(layer "F.Fab")
		)
		(fp_line
			(start -1.1049 -0.724916)
			(end -1.1049 0.724916)
			(stroke
				(width 0.1)
				(type default)
			)
			(layer "F.Fab")
		)
		(fp_line
			(start 1.1049 -0.724916)
			(end -1.1049 -0.724916)
			(stroke
				(width 0.1)
				(type default)
			)
			(layer "F.Fab")
		)
		(pad "1" smd rect
			(at -0.889 0 90)
			(size 1.016 1.27)
			(layers "F.Cu" "F.Mask" "F.Paste")
			(net "P12V_NIC6_R")
		)
		(pad "2" smd rect
			(at 0.889 0 90)
			(size 1.016 1.27)
			(layers "F.Cu" "F.Mask" "F.Paste")
			(net "GND")
		)
	)
	(footprint ""
		(layer "F.Cu")
		(at 155.380436 -110.088934)
		(property "Reference" "C262"
			(at 0 0 0)
			(layer "F.SilkS")
			(hide yes)
			(effects
				(font
					(size 1.27 1.27)
				)
			)
		)
		(property "Value" ""
			(at 0 0 0)
			(layer "F.Fab")
			(effects
				(font
					(size 1.27 1.27)
				)
			)
		)
		(duplicate_pad_numbers_are_jumpers no)
		(fp_line
			(start -0.299974 -0.150114)
			(end 0.299974 -0.150114)
			(stroke
				(width 0.1)
				(type default)
			)
			(layer "F.Fab")
		)
		(fp_line
			(start -0.299974 0.150114)
			(end -0.299974 -0.150114)
			(stroke
				(width 0.1)
				(type default)
			)
			(layer "F.Fab")
		)
		(fp_line
			(start 0.299974 -0.150114)
			(end 0.299974 0.150114)
			(stroke
				(width 0.1)
				(type default)
			)
			(layer "F.Fab")
		)
		(fp_line
			(start 0.299974 0.150114)
			(end -0.299974 0.150114)
			(stroke
				(width 0.1)
				(type default)
			)
			(layer "F.Fab")
		)
		(pad "1" smd rect
			(at -0.2667 0)
			(size 0.3048 0.381)
			(layers "F.Cu" "F.Mask" "F.Paste")
			(net "P5E_PEX1_STN1_TX_DP<22>")
		)
		(pad "2" smd rect
			(at 0.2667 0)
			(size 0.3048 0.381)
			(layers "F.Cu" "F.Mask" "F.Paste")
			(net "P5E_PEX1_STN1_TX_C_DP<22>")
		)
	)
	(footprint ""
		(layer "F.Cu")
		(at 235.965746 -120.381268 90)
		(property "Reference" "PR6896"
			(at 0 0 90)
			(layer "F.SilkS")
			(hide yes)
			(effects
				(font
					(size 1.27 1.27)
				)
			)
		)
		(property "Value" ""
			(at 0 0 90)
			(layer "F.Fab")
			(effects
				(font
					(size 1.27 1.27)
				)
			)
		)
		(duplicate_pad_numbers_are_jumpers no)
		(fp_line
			(start 0.7874 -0.4064)
			(end 0.7874 0.4064)
			(stroke
				(width 0.1524)
				(type default)
			)
			(layer "F.SilkS")
		)
		(fp_line
			(start -0.7874 -0.4064)
			(end 0.7874 -0.4064)
			(stroke
				(width 0.1524)
				(type default)
			)
			(layer "F.SilkS")
		)
		(fp_line
			(start 0.7874 0.4064)
			(end -0.7874 0.4064)
			(stroke
				(width 0.1524)
				(type default)
			)
			(layer "F.SilkS")
		)
		(fp_line
			(start -0.7874 0.4064)
			(end -0.7874 -0.4064)
			(stroke
				(width 0.1524)
				(type default)
			)
			(layer "F.SilkS")
		)
		(fp_line
			(start -0.12065 -0.305054)
			(end -0.12065 -0.2794)
			(stroke
				(width 0.1)
				(type default)
			)
			(layer "F.Fab")
		)
		(fp_line
			(start -0.67945 -0.305054)
			(end -0.12065 -0.305054)
			(stroke
				(width 0.1)
				(type default)
			)
			(layer "F.Fab")
		)
		(fp_line
			(start 0.67945 -0.3048)
			(end 0.67945 0.3048)
			(stroke
				(width 0.1)
				(type default)
			)
			(layer "F.Fab")
		)
		(fp_line
			(start 0.12065 -0.3048)
			(end 0.67945 -0.3048)
			(stroke
				(width 0.1)
				(type default)
			)
			(layer "F.Fab")
		)
		(fp_line
			(start 0.12065 -0.2794)
			(end 0.12065 -0.3048)
			(stroke
				(width 0.1)
				(type default)
			)
			(layer "F.Fab")
		)
		(fp_line
			(start -0.12065 -0.2794)
			(end 0.12065 -0.2794)
			(stroke
				(width 0.1)
				(type default)
			)
			(layer "F.Fab")
		)
		(fp_line
			(start 0.120396 0.2794)
			(end -0.12065 0.2794)
			(stroke
				(width 0.1)
				(type default)
			)
			(layer "F.Fab")
		)
		(fp_line
			(start -0.12065 0.2794)
			(end -0.12065 0.3048)
			(stroke
				(width 0.1)
				(type default)
			)
			(layer "F.Fab")
		)
		(fp_line
			(start 0.67945 0.3048)
			(end 0.120396 0.3048)
			(stroke
				(width 0.1)
				(type default)
			)
			(layer "F.Fab")
		)
		(fp_line
			(start 0.120396 0.3048)
			(end 0.120396 0.2794)
			(stroke
				(width 0.1)
				(type default)
			)
			(layer "F.Fab")
		)
		(fp_line
			(start -0.12065 0.3048)
			(end -0.67945 0.3048)
			(stroke
				(width 0.1)
				(type default)
			)
			(layer "F.Fab")
		)
		(fp_line
			(start -0.67945 0.3048)
			(end -0.67945 -0.305054)
			(stroke
				(width 0.1)
				(type default)
			)
			(layer "F.Fab")
		)
		(pad "1" smd circle
			(at -0.40005 0 90)
			(size 0 0)
			(layers "F.Cu" "F.Mask" "F.Paste")
			(net "P12V_NIC3_CO_FLTB")
		)
		(pad "2" smd circle
			(at 0.40005 0 90)
			(size 0 0)
			(layers "F.Cu" "F.Mask" "F.Paste")
			(net "P3V3_AUX")
		)
	)
	(footprint ""
		(layer "F.Cu")
		(at 462.804764 -521.743686 180)
		(property "Reference" "SCREW_3"
			(at -3.2385 -1.402334 0)
			(unlocked yes)
			(layer "B.SilkS")
			(effects
				(font
					(size 0.7874 0.5842)
					(thickness 0.1524)
				)
				(justify mirror)
			)
		)
		(property "Value" ""
			(at 0 0 180)
			(layer "F.Fab")
			(effects
				(font
					(size 1.27 1.27)
				)
			)
		)
		(duplicate_pad_numbers_are_jumpers no)
		(pad "1" thru_hole circle
			(at 0 0 180)
			(size 0.4572 0.4572)
			(drill 0.2032)
			(layers "*.Cu" "*.Mask")
			(remove_unused_layers no)
			(net "Net_9161")
			(clearance 0.127)
			(thermal_gap 0.127)
			(padstack
				(mode front_inner_back)
				(layer "Inner"
					(shape circle)
					(size 0.4572 0.4572)
					(clearance 0.127)
				)
				(layer "B.Cu"
					(shape circle)
					(size 0.508 0.508)
					(clearance 0.1016)
				)
			)
		)
	)
	(footprint ""
		(layer "F.Cu")
		(at 187.032392 -350.098614 90)
		(property "Reference" "C2536"
			(at 0 0 90)
			(layer "F.SilkS")
			(hide yes)
			(effects
				(font
					(size 1.27 1.27)
				)
			)
		)
		(property "Value" ""
			(at 0 0 90)
			(layer "F.Fab")
			(effects
				(font
					(size 1.27 1.27)
				)
			)
		)
		(duplicate_pad_numbers_are_jumpers no)
		(fp_line
			(start 0.299974 -0.150114)
			(end 0.299974 0.150114)
			(stroke
				(width 0.1)
				(type default)
			)
			(layer "F.Fab")
		)
		(fp_line
			(start -0.299974 -0.150114)
			(end 0.299974 -0.150114)
			(stroke
				(width 0.1)
				(type default)
			)
			(layer "F.Fab")
		)
		(fp_line
			(start 0.299974 0.150114)
			(end -0.299974 0.150114)
			(stroke
				(width 0.1)
				(type default)
			)
			(layer "F.Fab")
		)
		(fp_line
			(start -0.299974 0.150114)
			(end -0.299974 -0.150114)
			(stroke
				(width 0.1)
				(type default)
			)
			(layer "F.Fab")
		)
		(pad "1" smd rect
			(at -0.2667 0 90)
			(size 0.3048 0.381)
			(layers "F.Cu" "F.Mask" "F.Paste")
			(net "P5E_PEX1_STN4_TX_DP<67>")
		)
		(pad "2" smd rect
			(at 0.2667 0 90)
			(size 0.3048 0.381)
			(layers "F.Cu" "F.Mask" "F.Paste")
			(net "P5E_PEX1_STN4_TX_C_DP<67>")
		)
	)
	(footprint ""
		(layer "F.Cu")
		(at 340.561422 -188.38545 180)
		(property "Reference" "R4239"
			(at 0 0 180)
			(layer "F.SilkS")
			(hide yes)
			(effects
				(font
					(size 1.27 1.27)
				)
			)
		)
		(property "Value" ""
			(at 0 0 180)
			(layer "F.Fab")
			(effects
				(font
					(size 1.27 1.27)
				)
			)
		)
		(duplicate_pad_numbers_are_jumpers no)
		(fp_line
			(start 0.7874 0.4064)
			(end -0.7874 0.4064)
			(stroke
				(width 0.1524)
				(type default)
			)
			(layer "F.SilkS")
		)
		(fp_line
			(start 0.7874 -0.4064)
			(end 0.7874 0.4064)
			(stroke
				(width 0.1524)
				(type default)
			)
			(layer "F.SilkS")
		)
		(fp_line
			(start -0.7874 0.4064)
			(end -0.7874 -0.4064)
			(stroke
				(width 0.1524)
				(type default)
			)
			(layer "F.SilkS")
		)
		(fp_line
			(start -0.7874 -0.4064)
			(end 0.7874 -0.4064)
			(stroke
				(width 0.1524)
				(type default)
			)
			(layer "F.SilkS")
		)
		(fp_line
			(start 0.67945 0.3048)
			(end 0.120396 0.3048)
			(stroke
				(width 0.1)
				(type default)
			)
			(layer "F.Fab")
		)
		(fp_line
			(start 0.67945 -0.3048)
			(end 0.67945 0.3048)
			(stroke
				(width 0.1)
				(type default)
			)
			(layer "F.Fab")
		)
		(fp_line
			(start 0.12065 -0.2794)
			(end 0.12065 -0.3048)
			(stroke
				(width 0.1)
				(type default)
			)
			(layer "F.Fab")
		)
		(fp_line
			(start 0.12065 -0.3048)
			(end 0.67945 -0.3048)
			(stroke
				(width 0.1)
				(type default)
			)
			(layer "F.Fab")
		)
		(fp_line
			(start 0.120396 0.3048)
			(end 0.120396 0.2794)
			(stroke
				(width 0.1)
				(type default)
			)
			(layer "F.Fab")
		)
		(fp_line
			(start 0.120396 0.2794)
			(end -0.12065 0.2794)
			(stroke
				(width 0.1)
				(type default)
			)
			(layer "F.Fab")
		)
		(fp_line
			(start -0.12065 0.3048)
			(end -0.67945 0.3048)
			(stroke
				(width 0.1)
				(type default)
			)
			(layer "F.Fab")
		)
		(fp_line
			(start -0.12065 0.2794)
			(end -0.12065 0.3048)
			(stroke
				(width 0.1)
				(type default)
			)
			(layer "F.Fab")
		)
		(fp_line
			(start -0.12065 -0.2794)
			(end 0.12065 -0.2794)
			(stroke
				(width 0.1)
				(type default)
			)
			(layer "F.Fab")
		)
		(fp_line
			(start -0.12065 -0.305054)
			(end -0.12065 -0.2794)
			(stroke
				(width 0.1)
				(type default)
			)
			(layer "F.Fab")
		)
		(fp_line
			(start -0.67945 0.3048)
			(end -0.67945 -0.305054)
			(stroke
				(width 0.1)
				(type default)
			)
			(layer "F.Fab")
		)
		(fp_line
			(start -0.67945 -0.305054)
			(end -0.12065 -0.305054)
			(stroke
				(width 0.1)
				(type default)
			)
			(layer "F.Fab")
		)
		(pad "1" smd circle
			(at -0.40005 0 180)
			(size 0 0)
			(layers "F.Cu" "F.Mask" "F.Paste")
			(net "P3V3_AUX")
		)
		(pad "2" smd circle
			(at 0.40005 0 180)
			(size 0 0)
			(layers "F.Cu" "F.Mask" "F.Paste")
			(net "USB_DEBUG_PWR_BTN_N")
		)
	)
	(footprint ""
		(layer "F.Cu")
		(at 22.647148 -54.3941)
		(property "Reference" "PU30"
			(at -1.670812 3.085592 0)
			(unlocked yes)
			(layer "F.SilkS")
			(effects
				(font
					(size 0.7874 0.5842)
					(thickness 0.1524)
				)
				(justify left)
			)
		)
		(property "Value" ""
			(at 0 0 0)
			(layer "F.Fab")
			(effects
				(font
					(size 1.27 1.27)
				)
			)
		)
		(duplicate_pad_numbers_are_jumpers no)
		(fp_line
			(start -1.943608 -1.549908)
			(end 1.943608 -1.549908)
			(stroke
				(width 0.1524)
				(type default)
			)
			(layer "F.SilkS")
		)
		(fp_line
			(start -1.943608 1.549908)
			(end -1.943608 -1.549908)
			(stroke
				(width 0.1524)
				(type default)
			)
			(layer "F.SilkS")
		)
		(fp_line
			(start 1.943608 -1.549908)
			(end 1.943608 1.549908)
			(stroke
				(width 0.1524)
				(type default)
			)
			(layer "F.SilkS")
		)
		(fp_line
			(start 1.943608 1.549908)
			(end -1.943608 1.549908)
			(stroke
				(width 0.1524)
				(type default)
			)
			(layer "F.SilkS")
		)
		(fp_poly
			(pts
				(xy -2.019808 -1.549908) (xy -1.257808 -1.549908) (xy -1.257808 -1.880108) (xy -2.019808 -1.880108)
			)
			(stroke
				(width 0)
				(type default)
			)
			(fill yes)
			(layer "F.SilkS")
		)
		(fp_line
			(start -1.549908 -1.549908)
			(end 1.549908 -1.549908)
			(stroke
				(width 0.1)
				(type default)
			)
			(layer "F.Fab")
		)
		(fp_line
			(start -1.549908 1.549908)
			(end -1.549908 -1.549908)
			(stroke
				(width 0.1)
				(type default)
			)
			(layer "F.Fab")
		)
		(fp_line
			(start 1.549908 -1.549908)
			(end 1.549908 1.549908)
			(stroke
				(width 0.1)
				(type default)
			)
			(layer "F.Fab")
		)
		(fp_line
			(start 1.549908 1.549908)
			(end -1.549908 1.549908)
			(stroke
				(width 0.1)
				(type default)
			)
			(layer "F.Fab")
		)
		(fp_poly
			(pts
				(xy -2.019808 -1.549908) (xy -1.257808 -1.549908) (xy -1.257808 -1.880108) (xy -2.019808 -1.880108)
			)
			(stroke
				(width 0)
				(type default)
			)
			(fill yes)
			(layer "F.Fab")
		)
		(pad "1" smd rect
			(at -1.500124 -1.249934 270)
			(size 0.2794 0.6096)
			(layers "F.Cu" "F.Mask" "F.Paste")
			(net "P12V_SSD0_R")
		)
		(pad "2" smd rect
			(at -1.500124 -0.750062 270)
			(size 0.2794 0.6096)
			(layers "F.Cu" "F.Mask" "F.Paste")
			(net "P12V_SSD0_R")
		)
		(pad "3" smd rect
			(at -1.500124 -0.249936 270)
			(size 0.2794 0.6096)
			(layers "F.Cu" "F.Mask" "F.Paste")
			(net "P12V_SSD0_R")
		)
		(pad "4" smd rect
			(at -1.500124 0.249936 270)
			(size 0.2794 0.6096)
			(layers "F.Cu" "F.Mask" "F.Paste")
			(net "P12V_SSD0_R")
		)
		(pad "5" smd rect
			(at -1.500124 0.750062 270)
			(size 0.2794 0.6096)
			(layers "F.Cu" "F.Mask" "F.Paste")
			(net "P12V_SSD0_R")
		)
		(pad "6" smd rect
			(at -1.500124 1.249934 270)
			(size 0.2794 0.6096)
			(layers "F.Cu" "F.Mask" "F.Paste")
			(net "GND")
		)
		(pad "7" smd rect
			(at 1.500124 1.249934 270)
			(size 0.2794 0.6096)
			(layers "F.Cu" "F.Mask" "F.Paste")
			(net "P12V_SSD0_SS")
		)
		(pad "8" smd rect
			(at 1.500124 0.750062 270)
			(size 0.2794 0.6096)
			(layers "F.Cu" "F.Mask" "F.Paste")
			(net "PWRGD_P12V_SSD0")
		)
		(pad "9" smd rect
			(at 1.500124 0.249936 270)
			(size 0.2794 0.6096)
			(layers "F.Cu" "F.Mask" "F.Paste")
			(net "P12V_SSD0_OCP")
		)
		(pad "10" smd rect
			(at 1.500124 -0.249936 270)
			(size 0.2794 0.6096)
			(layers "F.Cu" "F.Mask" "F.Paste")
			(net "P5V_AUX")
		)
		(pad "11" smd rect
			(at 1.500124 -0.750062 270)
			(size 0.2794 0.6096)
			(layers "F.Cu" "F.Mask" "F.Paste")
			(net "SSD0_PWR_EN_R")
		)
		(pad "12" smd rect
			(at 1.500124 -1.249934 270)
			(size 0.2794 0.6096)
			(layers "F.Cu" "F.Mask" "F.Paste")
			(net "P12V_AUX")
		)
		(pad "13" smd rect
			(at 0 0)
			(size 1.9812 2.7178)
			(layers "F.Cu" "F.Mask" "F.Paste")
			(net "P12V_AUX")
		)
		(zone
			(layer "F.Cu")
			(hatch none 0.5)
			(connect_pads
				(clearance 0)
			)
			(min_thickness 0.25)
			(keepout
				(tracks not_allowed)
				(vias allowed)
				(pads allowed)
				(copperpour not_allowed)
				(footprints allowed)
			)
			(placement
				(enabled no)
				(sheetname "")
			)
			(fill
				(thermal_gap 0.5)
				(thermal_bridge_width 0.5)
				(island_removal_mode 0)
			)
			(polygon
				(pts
					(xy 23.790148 -55.9435) (xy 23.790148 -55.8165) (xy 23.790148 -52.8447) (xy 23.790148 -52.844192)
					(xy 21.504148 -52.844192) (xy 21.504148 -52.8447) (xy 21.504148 -52.9717) (xy 21.504148 -54.3941)
					(xy 21.605748 -54.3941) (xy 21.605748 -52.9717) (xy 23.688548 -52.9717) (xy 23.688548 -55.8165)
					(xy 21.605748 -55.8165) (xy 21.605748 -54.4195) (xy 21.504148 -54.4195) (xy 21.504148 -55.8165)
					(xy 21.504148 -55.9435) (xy 21.504148 -55.944008) (xy 23.790148 -55.944008)
				)
			)
		)
	)
	(footprint ""
		(layer "F.Cu")
		(at 95.79229 -31.825184 180)
		(property "Reference" "C92"
			(at 0 0 180)
			(layer "F.SilkS")
			(hide yes)
			(effects
				(font
					(size 1.27 1.27)
				)
			)
		)
		(property "Value" ""
			(at 0 0 180)
			(layer "F.Fab")
			(effects
				(font
					(size 1.27 1.27)
				)
			)
		)
		(duplicate_pad_numbers_are_jumpers no)
		(fp_line
			(start 0.299974 0.150114)
			(end -0.299974 0.150114)
			(stroke
				(width 0.1)
				(type default)
			)
			(layer "F.Fab")
		)
		(fp_line
			(start 0.299974 -0.150114)
			(end 0.299974 0.150114)
			(stroke
				(width 0.1)
				(type default)
			)
			(layer "F.Fab")
		)
		(fp_line
			(start -0.299974 0.150114)
			(end -0.299974 -0.150114)
			(stroke
				(width 0.1)
				(type default)
			)
			(layer "F.Fab")
		)
		(fp_line
			(start -0.299974 -0.150114)
			(end 0.299974 -0.150114)
			(stroke
				(width 0.1)
				(type default)
			)
			(layer "F.Fab")
		)
		(pad "1" smd rect
			(at -0.2667 0 180)
			(size 0.3048 0.381)
			(layers "F.Cu" "F.Mask" "F.Paste")
			(net "P5E_PEX0_STN2_TX_DN<34>")
		)
		(pad "2" smd rect
			(at 0.2667 0 180)
			(size 0.3048 0.381)
			(layers "F.Cu" "F.Mask" "F.Paste")
			(net "P5E_PEX0_STN2_TX_C_DN<34>")
		)
	)
	(footprint ""
		(layer "F.Cu")
		(at 36.2458 -258.463034)
		(property "Reference" "C3045"
			(at 0 0 0)
			(layer "F.SilkS")
			(hide yes)
			(effects
				(font
					(size 1.27 1.27)
				)
			)
		)
		(property "Value" ""
			(at 0 0 0)
			(layer "F.Fab")
			(effects
				(font
					(size 1.27 1.27)
				)
			)
		)
		(duplicate_pad_numbers_are_jumpers no)
		(fp_line
			(start -1.2954 -0.5842)
			(end 1.2954 -0.5842)
			(stroke
				(width 0.1524)
				(type default)
			)
			(layer "F.SilkS")
		)
		(fp_line
			(start -1.2954 0.5842)
			(end -1.2954 -0.5842)
			(stroke
				(width 0.1524)
				(type default)
			)
			(layer "F.SilkS")
		)
		(fp_line
			(start 1.2954 -0.5842)
			(end 1.2954 0.5842)
			(stroke
				(width 0.1524)
				(type default)
			)
			(layer "F.SilkS")
		)
		(fp_line
			(start 1.2954 0.5842)
			(end -1.2954 0.5842)
			(stroke
				(width 0.1524)
				(type default)
			)
			(layer "F.SilkS")
		)
		(fp_line
			(start -1.1938 -0.4064)
			(end -0.8636 -0.4064)
			(stroke
				(width 0.1)
				(type default)
			)
			(layer "F.Fab")
		)
		(fp_line
			(start -1.1938 0.4064)
			(end -1.1938 -0.4064)
			(stroke
				(width 0.1)
				(type default)
			)
			(layer "F.Fab")
		)
		(fp_line
			(start -0.8636 -0.4572)
			(end 0.8636 -0.4572)
			(stroke
				(width 0.1)
				(type default)
			)
			(layer "F.Fab")
		)
		(fp_line
			(start -0.8636 -0.4064)
			(end -0.8636 -0.4572)
			(stroke
				(width 0.1)
				(type default)
			)
			(layer "F.Fab")
		)
		(fp_line
			(start -0.8636 0.4064)
			(end -1.1938 0.4064)
			(stroke
				(width 0.1)
				(type default)
			)
			(layer "F.Fab")
		)
		(fp_line
			(start -0.8636 0.4572)
			(end -0.8636 0.4064)
			(stroke
				(width 0.1)
				(type default)
			)
			(layer "F.Fab")
		)
		(fp_line
			(start 0.8636 -0.4572)
			(end 0.8636 -0.4064)
			(stroke
				(width 0.1)
				(type default)
			)
			(layer "F.Fab")
		)
		(fp_line
			(start 0.8636 -0.4064)
			(end 1.1938 -0.4064)
			(stroke
				(width 0.1)
				(type default)
			)
			(layer "F.Fab")
		)
		(fp_line
			(start 0.8636 0.4064)
			(end 0.8636 0.4572)
			(stroke
				(width 0.1)
				(type default)
			)
			(layer "F.Fab")
		)
		(fp_line
			(start 0.8636 0.4572)
			(end -0.8636 0.4572)
			(stroke
				(width 0.1)
				(type default)
			)
			(layer "F.Fab")
		)
		(fp_line
			(start 1.1938 -0.4064)
			(end 1.1938 0.4064)
			(stroke
				(width 0.1)
				(type default)
			)
			(layer "F.Fab")
		)
		(fp_line
			(start 1.1938 0.4064)
			(end 0.8636 0.4064)
			(stroke
				(width 0.1)
				(type default)
			)
			(layer "F.Fab")
		)
		(pad "1" smd rect
			(at -0.7366 0 270)
			(size 0.7112 0.8128)
			(layers "F.Cu" "F.Mask" "F.Paste")
			(net "PCEPLL5_VDDA18_PEX0")
		)
		(pad "2" smd rect
			(at 0.7366 0 270)
			(size 0.7112 0.8128)
			(layers "F.Cu" "F.Mask" "F.Paste")
			(net "GND")
		)
	)
	(footprint ""
		(layer "F.Cu")
		(at 209.09788 -296.365168 90)
		(property "Reference" "C2757"
			(at 0 0 90)
			(layer "F.SilkS")
			(hide yes)
			(effects
				(font
					(size 1.27 1.27)
				)
			)
		)
		(property "Value" ""
			(at 0 0 90)
			(layer "F.Fab")
			(effects
				(font
					(size 1.27 1.27)
				)
			)
		)
		(duplicate_pad_numbers_are_jumpers no)
		(fp_line
			(start 0.7874 -0.4064)
			(end 0.7874 0.4064)
			(stroke
				(width 0.1524)
				(type default)
			)
			(layer "F.SilkS")
		)
		(fp_line
			(start -0.7874 -0.4064)
			(end 0.7874 -0.4064)
			(stroke
				(width 0.1524)
				(type default)
			)
			(layer "F.SilkS")
		)
		(fp_line
			(start 0.7874 0.4064)
			(end -0.7874 0.4064)
			(stroke
				(width 0.1524)
				(type default)
			)
			(layer "F.SilkS")
		)
		(fp_line
			(start -0.7874 0.4064)
			(end -0.7874 -0.4064)
			(stroke
				(width 0.1524)
				(type default)
			)
			(layer "F.SilkS")
		)
		(fp_line
			(start -0.12065 -0.305054)
			(end -0.12065 -0.2794)
			(stroke
				(width 0.1)
				(type default)
			)
			(layer "F.Fab")
		)
		(fp_line
			(start -0.67945 -0.305054)
			(end -0.12065 -0.305054)
			(stroke
				(width 0.1)
				(type default)
			)
			(layer "F.Fab")
		)
		(fp_line
			(start 0.67945 -0.3048)
			(end 0.67945 0.3048)
			(stroke
				(width 0.1)
				(type default)
			)
			(layer "F.Fab")
		)
		(fp_line
			(start 0.12065 -0.3048)
			(end 0.67945 -0.3048)
			(stroke
				(width 0.1)
				(type default)
			)
			(layer "F.Fab")
		)
		(fp_line
			(start 0.12065 -0.2794)
			(end 0.12065 -0.3048)
			(stroke
				(width 0.1)
				(type default)
			)
			(layer "F.Fab")
		)
		(fp_line
			(start -0.12065 -0.2794)
			(end 0.12065 -0.2794)
			(stroke
				(width 0.1)
				(type default)
			)
			(layer "F.Fab")
		)
		(fp_line
			(start 0.120396 0.2794)
			(end -0.12065 0.2794)
			(stroke
				(width 0.1)
				(type default)
			)
			(layer "F.Fab")
		)
		(fp_line
			(start -0.12065 0.2794)
			(end -0.12065 0.3048)
			(stroke
				(width 0.1)
				(type default)
			)
			(layer "F.Fab")
		)
		(fp_line
			(start 0.67945 0.3048)
			(end 0.120396 0.3048)
			(stroke
				(width 0.1)
				(type default)
			)
			(layer "F.Fab")
		)
		(fp_line
			(start 0.120396 0.3048)
			(end 0.120396 0.2794)
			(stroke
				(width 0.1)
				(type default)
			)
			(layer "F.Fab")
		)
		(fp_line
			(start -0.12065 0.3048)
			(end -0.67945 0.3048)
			(stroke
				(width 0.1)
				(type default)
			)
			(layer "F.Fab")
		)
		(fp_line
			(start -0.67945 0.3048)
			(end -0.67945 -0.305054)
			(stroke
				(width 0.1)
				(type default)
			)
			(layer "F.Fab")
		)
		(pad "1" smd circle
			(at -0.40005 0 90)
			(size 0 0)
			(layers "F.Cu" "F.Mask" "F.Paste")
			(net "GND")
		)
		(pad "2" smd circle
			(at 0.40005 0 90)
			(size 0 0)
			(layers "F.Cu" "F.Mask" "F.Paste")
			(net "P1V8_PEX")
		)
	)
	(footprint ""
		(layer "F.Cu")
		(at 239.333024 -254.18542 -90)
		(property "Reference" "C4341"
			(at 0 0 270)
			(layer "F.SilkS")
			(hide yes)
			(effects
				(font
					(size 1.27 1.27)
				)
			)
		)
		(property "Value" ""
			(at 0 0 270)
			(layer "F.Fab")
			(effects
				(font
					(size 1.27 1.27)
				)
			)
		)
		(duplicate_pad_numbers_are_jumpers no)
		(fp_line
			(start -1.2954 0.5842)
			(end -1.2954 -0.5842)
			(stroke
				(width 0.1524)
				(type default)
			)
			(layer "F.SilkS")
		)
		(fp_line
			(start 1.2954 0.5842)
			(end -1.2954 0.5842)
			(stroke
				(width 0.1524)
				(type default)
			)
			(layer "F.SilkS")
		)
		(fp_line
			(start -1.2954 -0.5842)
			(end 1.2954 -0.5842)
			(stroke
				(width 0.1524)
				(type default)
			)
			(layer "F.SilkS")
		)
		(fp_line
			(start 1.2954 -0.5842)
			(end 1.2954 0.5842)
			(stroke
				(width 0.1524)
				(type default)
			)
			(layer "F.SilkS")
		)
		(fp_line
			(start -0.8636 0.4572)
			(end -0.8636 0.4064)
			(stroke
				(width 0.1)
				(type default)
			)
			(layer "F.Fab")
		)
		(fp_line
			(start 0.8636 0.4572)
			(end -0.8636 0.4572)
			(stroke
				(width 0.1)
				(type default)
			)
			(layer "F.Fab")
		)
		(fp_line
			(start -1.1938 0.4064)
			(end -1.1938 -0.4064)
			(stroke
				(width 0.1)
				(type default)
			)
			(layer "F.Fab")
		)
		(fp_line
			(start -0.8636 0.4064)
			(end -1.1938 0.4064)
			(stroke
				(width 0.1)
				(type default)
			)
			(layer "F.Fab")
		)
		(fp_line
			(start 0.8636 0.4064)
			(end 0.8636 0.4572)
			(stroke
				(width 0.1)
				(type default)
			)
			(layer "F.Fab")
		)
		(fp_line
			(start 1.1938 0.4064)
			(end 0.8636 0.4064)
			(stroke
				(width 0.1)
				(type default)
			)
			(layer "F.Fab")
		)
		(fp_line
			(start -1.1938 -0.4064)
			(end -0.8636 -0.4064)
			(stroke
				(width 0.1)
				(type default)
			)
			(layer "F.Fab")
		)
		(fp_line
			(start -0.8636 -0.4064)
			(end -0.8636 -0.4572)
			(stroke
				(width 0.1)
				(type default)
			)
			(layer "F.Fab")
		)
		(fp_line
			(start 0.8636 -0.4064)
			(end 1.1938 -0.4064)
			(stroke
				(width 0.1)
				(type default)
			)
			(layer "F.Fab")
		)
		(fp_line
			(start 1.1938 -0.4064)
			(end 1.1938 0.4064)
			(stroke
				(width 0.1)
				(type default)
			)
			(layer "F.Fab")
		)
		(fp_line
			(start -0.8636 -0.4572)
			(end 0.8636 -0.4572)
			(stroke
				(width 0.1)
				(type default)
			)
			(layer "F.Fab")
		)
		(fp_line
			(start 0.8636 -0.4572)
			(end 0.8636 -0.4064)
			(stroke
				(width 0.1)
				(type default)
			)
			(layer "F.Fab")
		)
		(pad "1" smd rect
			(at -0.7366 0 180)
			(size 0.7112 0.8128)
			(layers "F.Cu" "F.Mask" "F.Paste")
			(net "P1V25_SERDES_VDDPLL_PEX2_C3")
		)
		(pad "2" smd rect
			(at 0.7366 0 180)
			(size 0.7112 0.8128)
			(layers "F.Cu" "F.Mask" "F.Paste")
			(net "GND")
		)
	)
	(footprint ""
		(layer "F.Cu")
		(at 142.710662 -18.61439 90)
		(property "Reference" "U130"
			(at -1.49479 2.273808 90)
			(unlocked yes)
			(layer "F.SilkS")
			(effects
				(font
					(size 0.7874 0.5842)
					(thickness 0.1524)
				)
				(justify left)
			)
		)
		(property "Value" ""
			(at 0 0 90)
			(layer "F.Fab")
			(effects
				(font
					(size 1.27 1.27)
				)
			)
		)
		(duplicate_pad_numbers_are_jumpers no)
		(fp_line
			(start 1.463548 -1.549908)
			(end 1.463548 1.549908)
			(stroke
				(width 0.1524)
				(type default)
			)
			(layer "F.SilkS")
		)
		(fp_line
			(start 0.762 -1.549908)
			(end 1.463548 -1.549908)
			(stroke
				(width 0.1524)
				(type default)
			)
			(layer "F.SilkS")
		)
		(fp_line
			(start -0.787908 -1.549908)
			(end 0 -0.762)
			(stroke
				(width 0.1524)
				(type default)
			)
			(layer "F.SilkS")
		)
		(fp_line
			(start -1.463548 -1.549908)
			(end -0.787908 -1.549908)
			(stroke
				(width 0.1524)
				(type default)
			)
			(layer "F.SilkS")
		)
		(fp_line
			(start 0 -0.762)
			(end 0.762 -1.549908)
			(stroke
				(width 0.1524)
				(type default)
			)
			(layer "F.SilkS")
		)
		(fp_line
			(start 1.463548 1.549908)
			(end -1.463548 1.549908)
			(stroke
				(width 0.1524)
				(type default)
			)
			(layer "F.SilkS")
		)
		(fp_line
			(start -1.463548 1.549908)
			(end -1.463548 -1.549908)
			(stroke
				(width 0.1524)
				(type default)
			)
			(layer "F.SilkS")
		)
		(fp_poly
			(pts
				(xy -3.4798 -1.359916) (xy -2.86004 -1.050036) (xy -3.4798 -0.740156)
			)
			(stroke
				(width 0)
				(type default)
			)
			(fill yes)
			(layer "F.SilkS")
		)
		(fp_line
			(start 1.549908 -1.549908)
			(end 1.549908 1.549908)
			(stroke
				(width 0.1)
				(type default)
			)
			(layer "F.Fab")
		)
		(fp_line
			(start -1.549908 -1.549908)
			(end 1.549908 -1.549908)
			(stroke
				(width 0.1)
				(type default)
			)
			(layer "F.Fab")
		)
		(fp_line
			(start 1.549908 1.549908)
			(end -1.549908 1.549908)
			(stroke
				(width 0.1)
				(type default)
			)
			(layer "F.Fab")
		)
		(fp_line
			(start -1.549908 1.549908)
			(end -1.549908 -1.549908)
			(stroke
				(width 0.1)
				(type default)
			)
			(layer "F.Fab")
		)
		(fp_poly
			(pts
				(xy -3.4798 -1.359916) (xy -2.86004 -1.050036) (xy -3.4798 -0.740156)
			)
			(stroke
				(width 0)
				(type default)
			)
			(fill yes)
			(layer "F.Fab")
		)
		(pad "1" smd rect
			(at -2.175002 -1.050036 180)
			(size 0.6096 1.1684)
			(layers "F.Cu" "F.Mask" "F.Paste")
			(net "P3V3_SSD4")
		)
		(pad "2" smd rect
			(at -2.175002 -0.32512 180)
			(size 0.4318 1.1684)
			(layers "F.Cu" "F.Mask" "F.Paste")
			(net "SMB_ISO_SSD4_SCL")
		)
		(pad "3" smd rect
			(at -2.175002 0.32512 180)
			(size 0.4318 1.1684)
			(layers "F.Cu" "F.Mask" "F.Paste")
			(net "SMB_ISO_SSD4_SDA")
		)
		(pad "4" smd rect
			(at -2.175002 1.050036 180)
			(size 0.6096 1.1684)
			(layers "F.Cu" "F.Mask" "F.Paste")
			(net "GND")
		)
		(pad "5" smd rect
			(at 2.175002 1.050036 180)
			(size 0.6096 1.1684)
			(layers "F.Cu" "F.Mask" "F.Paste")
			(net "SMB_SSD4_ISO_EN")
		)
		(pad "6" smd rect
			(at 2.175002 0.32512 180)
			(size 0.4318 1.1684)
			(layers "F.Cu" "F.Mask" "F.Paste")
			(net "SMB_BIC_I2C9_MUX0_SSD4_R_SDA")
		)
		(pad "7" smd rect
			(at 2.175002 -0.32512 180)
			(size 0.4318 1.1684)
			(layers "F.Cu" "F.Mask" "F.Paste")
			(net "SMB_BIC_I2C9_MUX0_SSD4_R_SCL")
		)
		(pad "8" smd rect
			(at 2.175002 -1.050036 180)
			(size 0.6096 1.1684)
			(layers "F.Cu" "F.Mask" "F.Paste")
			(net "P3V3_AUX")
		)
	)
	(footprint ""
		(layer "F.Cu")
		(at 179.570634 -138.864848)
		(property "Reference" "R193"
			(at 0 0 0)
			(layer "F.SilkS")
			(hide yes)
			(effects
				(font
					(size 1.27 1.27)
				)
			)
		)
		(property "Value" ""
			(at 0 0 0)
			(layer "F.Fab")
			(effects
				(font
					(size 1.27 1.27)
				)
			)
		)
		(duplicate_pad_numbers_are_jumpers no)
		(fp_line
			(start -0.7874 -0.4064)
			(end 0.7874 -0.4064)
			(stroke
				(width 0.1524)
				(type default)
			)
			(layer "F.SilkS")
		)
		(fp_line
			(start -0.7874 0.4064)
			(end -0.7874 -0.4064)
			(stroke
				(width 0.1524)
				(type default)
			)
			(layer "F.SilkS")
		)
		(fp_line
			(start 0.7874 -0.4064)
			(end 0.7874 0.4064)
			(stroke
				(width 0.1524)
				(type default)
			)
			(layer "F.SilkS")
		)
		(fp_line
			(start 0.7874 0.4064)
			(end -0.7874 0.4064)
			(stroke
				(width 0.1524)
				(type default)
			)
			(layer "F.SilkS")
		)
		(fp_line
			(start -0.67945 -0.305054)
			(end -0.12065 -0.305054)
			(stroke
				(width 0.1)
				(type default)
			)
			(layer "F.Fab")
		)
		(fp_line
			(start -0.67945 0.3048)
			(end -0.67945 -0.305054)
			(stroke
				(width 0.1)
				(type default)
			)
			(layer "F.Fab")
		)
		(fp_line
			(start -0.12065 -0.305054)
			(end -0.12065 -0.2794)
			(stroke
				(width 0.1)
				(type default)
			)
			(layer "F.Fab")
		)
		(fp_line
			(start -0.12065 -0.2794)
			(end 0.12065 -0.2794)
			(stroke
				(width 0.1)
				(type default)
			)
			(layer "F.Fab")
		)
		(fp_line
			(start -0.12065 0.2794)
			(end -0.12065 0.3048)
			(stroke
				(width 0.1)
				(type default)
			)
			(layer "F.Fab")
		)
		(fp_line
			(start -0.12065 0.3048)
			(end -0.67945 0.3048)
			(stroke
				(width 0.1)
				(type default)
			)
			(layer "F.Fab")
		)
		(fp_line
			(start 0.120396 0.2794)
			(end -0.12065 0.2794)
			(stroke
				(width 0.1)
				(type default)
			)
			(layer "F.Fab")
		)
		(fp_line
			(start 0.120396 0.3048)
			(end 0.120396 0.2794)
			(stroke
				(width 0.1)
				(type default)
			)
			(layer "F.Fab")
		)
		(fp_line
			(start 0.12065 -0.3048)
			(end 0.67945 -0.3048)
			(stroke
				(width 0.1)
				(type default)
			)
			(layer "F.Fab")
		)
		(fp_line
			(start 0.12065 -0.2794)
			(end 0.12065 -0.3048)
			(stroke
				(width 0.1)
				(type default)
			)
			(layer "F.Fab")
		)
		(fp_line
			(start 0.67945 -0.3048)
			(end 0.67945 0.3048)
			(stroke
				(width 0.1)
				(type default)
			)
			(layer "F.Fab")
		)
		(fp_line
			(start 0.67945 0.3048)
			(end 0.120396 0.3048)
			(stroke
				(width 0.1)
				(type default)
			)
			(layer "F.Fab")
		)
		(pad "1" smd circle
			(at -0.40005 0)
			(size 0 0)
			(layers "F.Cu" "F.Mask" "F.Paste")
			(net "PRSNT_NIC3_N")
		)
		(pad "2" smd circle
			(at 0.40005 0)
			(size 0 0)
			(layers "F.Cu" "F.Mask" "F.Paste")
			(net "PRSNTB1_NIC3_N")
		)
	)
	(footprint ""
		(layer "F.Cu")
		(at 331.131164 -356.244906 90)
		(property "Reference" "C569"
			(at 0 0 90)
			(layer "F.SilkS")
			(hide yes)
			(effects
				(font
					(size 1.27 1.27)
				)
			)
		)
		(property "Value" ""
			(at 0 0 90)
			(layer "F.Fab")
			(effects
				(font
					(size 1.27 1.27)
				)
			)
		)
		(duplicate_pad_numbers_are_jumpers no)
		(fp_line
			(start 0.299974 -0.150114)
			(end 0.299974 0.150114)
			(stroke
				(width 0.1)
				(type default)
			)
			(layer "F.Fab")
		)
		(fp_line
			(start -0.299974 -0.150114)
			(end 0.299974 -0.150114)
			(stroke
				(width 0.1)
				(type default)
			)
			(layer "F.Fab")
		)
		(fp_line
			(start 0.299974 0.150114)
			(end -0.299974 0.150114)
			(stroke
				(width 0.1)
				(type default)
			)
			(layer "F.Fab")
		)
		(fp_line
			(start -0.299974 0.150114)
			(end -0.299974 -0.150114)
			(stroke
				(width 0.1)
				(type default)
			)
			(layer "F.Fab")
		)
		(pad "1" smd rect
			(at -0.2667 0 90)
			(size 0.3048 0.381)
			(layers "F.Cu" "F.Mask" "F.Paste")
			(net "P5E_PEX2_STN6_TX_DP<102>")
		)
		(pad "2" smd rect
			(at 0.2667 0 90)
			(size 0.3048 0.381)
			(layers "F.Cu" "F.Mask" "F.Paste")
			(net "P5E_PEX2_STN6_TX_C_DP<102>")
		)
	)
	(footprint ""
		(layer "F.Cu")
		(at 316.775592 -36.915598 -90)
		(property "Reference" "R5583"
			(at 0 0 270)
			(layer "F.SilkS")
			(hide yes)
			(effects
				(font
					(size 1.27 1.27)
				)
			)
		)
		(property "Value" ""
			(at 0 0 270)
			(layer "F.Fab")
			(effects
				(font
					(size 1.27 1.27)
				)
			)
		)
		(duplicate_pad_numbers_are_jumpers no)
		(fp_line
			(start -0.7874 0.4064)
			(end -0.7874 -0.4064)
			(stroke
				(width 0.1524)
				(type default)
			)
			(layer "F.SilkS")
		)
		(fp_line
			(start 0.7874 0.4064)
			(end -0.7874 0.4064)
			(stroke
				(width 0.1524)
				(type default)
			)
			(layer "F.SilkS")
		)
		(fp_line
			(start -0.7874 -0.4064)
			(end 0.7874 -0.4064)
			(stroke
				(width 0.1524)
				(type default)
			)
			(layer "F.SilkS")
		)
		(fp_line
			(start 0.7874 -0.4064)
			(end 0.7874 0.4064)
			(stroke
				(width 0.1524)
				(type default)
			)
			(layer "F.SilkS")
		)
		(fp_line
			(start -0.67945 0.3048)
			(end -0.67945 -0.305054)
			(stroke
				(width 0.1)
				(type default)
			)
			(layer "F.Fab")
		)
		(fp_line
			(start -0.12065 0.3048)
			(end -0.67945 0.3048)
			(stroke
				(width 0.1)
				(type default)
			)
			(layer "F.Fab")
		)
		(fp_line
			(start 0.120396 0.3048)
			(end 0.120396 0.2794)
			(stroke
				(width 0.1)
				(type default)
			)
			(layer "F.Fab")
		)
		(fp_line
			(start 0.67945 0.3048)
			(end 0.120396 0.3048)
			(stroke
				(width 0.1)
				(type default)
			)
			(layer "F.Fab")
		)
		(fp_line
			(start -0.12065 0.2794)
			(end -0.12065 0.3048)
			(stroke
				(width 0.1)
				(type default)
			)
			(layer "F.Fab")
		)
		(fp_line
			(start 0.120396 0.2794)
			(end -0.12065 0.2794)
			(stroke
				(width 0.1)
				(type default)
			)
			(layer "F.Fab")
		)
		(fp_line
			(start -0.12065 -0.2794)
			(end 0.12065 -0.2794)
			(stroke
				(width 0.1)
				(type default)
			)
			(layer "F.Fab")
		)
		(fp_line
			(start 0.12065 -0.2794)
			(end 0.12065 -0.3048)
			(stroke
				(width 0.1)
				(type default)
			)
			(layer "F.Fab")
		)
		(fp_line
			(start 0.12065 -0.3048)
			(end 0.67945 -0.3048)
			(stroke
				(width 0.1)
				(type default)
			)
			(layer "F.Fab")
		)
		(fp_line
			(start 0.67945 -0.3048)
			(end 0.67945 0.3048)
			(stroke
				(width 0.1)
				(type default)
			)
			(layer "F.Fab")
		)
		(fp_line
			(start -0.67945 -0.305054)
			(end -0.12065 -0.305054)
			(stroke
				(width 0.1)
				(type default)
			)
			(layer "F.Fab")
		)
		(fp_line
			(start -0.12065 -0.305054)
			(end -0.12065 -0.2794)
			(stroke
				(width 0.1)
				(type default)
			)
			(layer "F.Fab")
		)
		(pad "1" smd circle
			(at -0.40005 0 270)
			(size 0 0)
			(layers "F.Cu" "F.Mask" "F.Paste")
			(net "PRSNT_SSD11_R1_N")
		)
		(pad "2" smd circle
			(at 0.40005 0 270)
			(size 0 0)
			(layers "F.Cu" "F.Mask" "F.Paste")
			(net "PRSNT_SSD11_R_N")
		)
	)
	(footprint ""
		(layer "F.Cu")
		(at 3.630168 -24.945594 90)
		(property "Reference" "R1639"
			(at 0 0 90)
			(layer "F.SilkS")
			(hide yes)
			(effects
				(font
					(size 1.27 1.27)
				)
			)
		)
		(property "Value" ""
			(at 0 0 90)
			(layer "F.Fab")
			(effects
				(font
					(size 1.27 1.27)
				)
			)
		)
		(duplicate_pad_numbers_are_jumpers no)
		(fp_line
			(start 0.7874 -0.4064)
			(end 0.7874 0.4064)
			(stroke
				(width 0.1524)
				(type default)
			)
			(layer "F.SilkS")
		)
		(fp_line
			(start -0.7874 -0.4064)
			(end 0.7874 -0.4064)
			(stroke
				(width 0.1524)
				(type default)
			)
			(layer "F.SilkS")
		)
		(fp_line
			(start 0.7874 0.4064)
			(end -0.7874 0.4064)
			(stroke
				(width 0.1524)
				(type default)
			)
			(layer "F.SilkS")
		)
		(fp_line
			(start -0.7874 0.4064)
			(end -0.7874 -0.4064)
			(stroke
				(width 0.1524)
				(type default)
			)
			(layer "F.SilkS")
		)
		(fp_line
			(start -0.12065 -0.305054)
			(end -0.12065 -0.2794)
			(stroke
				(width 0.1)
				(type default)
			)
			(layer "F.Fab")
		)
		(fp_line
			(start -0.67945 -0.305054)
			(end -0.12065 -0.305054)
			(stroke
				(width 0.1)
				(type default)
			)
			(layer "F.Fab")
		)
		(fp_line
			(start 0.67945 -0.3048)
			(end 0.67945 0.3048)
			(stroke
				(width 0.1)
				(type default)
			)
			(layer "F.Fab")
		)
		(fp_line
			(start 0.12065 -0.3048)
			(end 0.67945 -0.3048)
			(stroke
				(width 0.1)
				(type default)
			)
			(layer "F.Fab")
		)
		(fp_line
			(start 0.12065 -0.2794)
			(end 0.12065 -0.3048)
			(stroke
				(width 0.1)
				(type default)
			)
			(layer "F.Fab")
		)
		(fp_line
			(start -0.12065 -0.2794)
			(end 0.12065 -0.2794)
			(stroke
				(width 0.1)
				(type default)
			)
			(layer "F.Fab")
		)
		(fp_line
			(start 0.120396 0.2794)
			(end -0.12065 0.2794)
			(stroke
				(width 0.1)
				(type default)
			)
			(layer "F.Fab")
		)
		(fp_line
			(start -0.12065 0.2794)
			(end -0.12065 0.3048)
			(stroke
				(width 0.1)
				(type default)
			)
			(layer "F.Fab")
		)
		(fp_line
			(start 0.67945 0.3048)
			(end 0.120396 0.3048)
			(stroke
				(width 0.1)
				(type default)
			)
			(layer "F.Fab")
		)
		(fp_line
			(start 0.120396 0.3048)
			(end 0.120396 0.2794)
			(stroke
				(width 0.1)
				(type default)
			)
			(layer "F.Fab")
		)
		(fp_line
			(start -0.12065 0.3048)
			(end -0.67945 0.3048)
			(stroke
				(width 0.1)
				(type default)
			)
			(layer "F.Fab")
		)
		(fp_line
			(start -0.67945 0.3048)
			(end -0.67945 -0.305054)
			(stroke
				(width 0.1)
				(type default)
			)
			(layer "F.Fab")
		)
		(pad "1" smd circle
			(at -0.40005 0 90)
			(size 0 0)
			(layers "F.Cu" "F.Mask" "F.Paste")
			(net "SMB_ISO_SSD0_R_SDA")
		)
		(pad "2" smd circle
			(at 0.40005 0 90)
			(size 0 0)
			(layers "F.Cu" "F.Mask" "F.Paste")
			(net "SMB_ISO_SSD0_SDA")
		)
	)
	(footprint ""
		(layer "F.Cu")
		(at 411.97784 -116.550186 180)
		(property "Reference" "R364"
			(at 0 0 180)
			(layer "F.SilkS")
			(hide yes)
			(effects
				(font
					(size 1.27 1.27)
				)
			)
		)
		(property "Value" ""
			(at 0 0 180)
			(layer "F.Fab")
			(effects
				(font
					(size 1.27 1.27)
				)
			)
		)
		(duplicate_pad_numbers_are_jumpers no)
		(fp_line
			(start 0.7874 0.4064)
			(end -0.7874 0.4064)
			(stroke
				(width 0.1524)
				(type default)
			)
			(layer "F.SilkS")
		)
		(fp_line
			(start 0.7874 -0.4064)
			(end 0.7874 0.4064)
			(stroke
				(width 0.1524)
				(type default)
			)
			(layer "F.SilkS")
		)
		(fp_line
			(start -0.7874 0.4064)
			(end -0.7874 -0.4064)
			(stroke
				(width 0.1524)
				(type default)
			)
			(layer "F.SilkS")
		)
		(fp_line
			(start -0.7874 -0.4064)
			(end 0.7874 -0.4064)
			(stroke
				(width 0.1524)
				(type default)
			)
			(layer "F.SilkS")
		)
		(fp_line
			(start 0.67945 0.3048)
			(end 0.120396 0.3048)
			(stroke
				(width 0.1)
				(type default)
			)
			(layer "F.Fab")
		)
		(fp_line
			(start 0.67945 -0.3048)
			(end 0.67945 0.3048)
			(stroke
				(width 0.1)
				(type default)
			)
			(layer "F.Fab")
		)
		(fp_line
			(start 0.12065 -0.2794)
			(end 0.12065 -0.3048)
			(stroke
				(width 0.1)
				(type default)
			)
			(layer "F.Fab")
		)
		(fp_line
			(start 0.12065 -0.3048)
			(end 0.67945 -0.3048)
			(stroke
				(width 0.1)
				(type default)
			)
			(layer "F.Fab")
		)
		(fp_line
			(start 0.120396 0.3048)
			(end 0.120396 0.2794)
			(stroke
				(width 0.1)
				(type default)
			)
			(layer "F.Fab")
		)
		(fp_line
			(start 0.120396 0.2794)
			(end -0.12065 0.2794)
			(stroke
				(width 0.1)
				(type default)
			)
			(layer "F.Fab")
		)
		(fp_line
			(start -0.12065 0.3048)
			(end -0.67945 0.3048)
			(stroke
				(width 0.1)
				(type default)
			)
			(layer "F.Fab")
		)
		(fp_line
			(start -0.12065 0.2794)
			(end -0.12065 0.3048)
			(stroke
				(width 0.1)
				(type default)
			)
			(layer "F.Fab")
		)
		(fp_line
			(start -0.12065 -0.2794)
			(end 0.12065 -0.2794)
			(stroke
				(width 0.1)
				(type default)
			)
			(layer "F.Fab")
		)
		(fp_line
			(start -0.12065 -0.305054)
			(end -0.12065 -0.2794)
			(stroke
				(width 0.1)
				(type default)
			)
			(layer "F.Fab")
		)
		(fp_line
			(start -0.67945 0.3048)
			(end -0.67945 -0.305054)
			(stroke
				(width 0.1)
				(type default)
			)
			(layer "F.Fab")
		)
		(fp_line
			(start -0.67945 -0.305054)
			(end -0.12065 -0.305054)
			(stroke
				(width 0.1)
				(type default)
			)
			(layer "F.Fab")
		)
		(pad "1" smd circle
			(at -0.40005 0 180)
			(size 0 0)
			(layers "F.Cu" "F.Mask" "F.Paste")
			(net "PRSNTB2_NIC7_N")
		)
		(pad "2" smd circle
			(at 0.40005 0 180)
			(size 0 0)
			(layers "F.Cu" "F.Mask" "F.Paste")
			(net "P3V3_AUX")
		)
	)
	(footprint ""
		(layer "F.Cu")
		(at 339.598 -201.168 -90)
		(property "Reference" "R4140"
			(at 0 0 270)
			(layer "F.SilkS")
			(hide yes)
			(effects
				(font
					(size 1.27 1.27)
				)
			)
		)
		(property "Value" ""
			(at 0 0 270)
			(layer "F.Fab")
			(effects
				(font
					(size 1.27 1.27)
				)
			)
		)
		(duplicate_pad_numbers_are_jumpers no)
		(fp_line
			(start -0.7874 0.4064)
			(end -0.7874 -0.4064)
			(stroke
				(width 0.1524)
				(type default)
			)
			(layer "F.SilkS")
		)
		(fp_line
			(start 0.7874 0.4064)
			(end -0.7874 0.4064)
			(stroke
				(width 0.1524)
				(type default)
			)
			(layer "F.SilkS")
		)
		(fp_line
			(start -0.7874 -0.4064)
			(end 0.7874 -0.4064)
			(stroke
				(width 0.1524)
				(type default)
			)
			(layer "F.SilkS")
		)
		(fp_line
			(start 0.7874 -0.4064)
			(end 0.7874 0.4064)
			(stroke
				(width 0.1524)
				(type default)
			)
			(layer "F.SilkS")
		)
		(fp_line
			(start -0.67945 0.3048)
			(end -0.67945 -0.305054)
			(stroke
				(width 0.1)
				(type default)
			)
			(layer "F.Fab")
		)
		(fp_line
			(start -0.12065 0.3048)
			(end -0.67945 0.3048)
			(stroke
				(width 0.1)
				(type default)
			)
			(layer "F.Fab")
		)
		(fp_line
			(start 0.120396 0.3048)
			(end 0.120396 0.2794)
			(stroke
				(width 0.1)
				(type default)
			)
			(layer "F.Fab")
		)
		(fp_line
			(start 0.67945 0.3048)
			(end 0.120396 0.3048)
			(stroke
				(width 0.1)
				(type default)
			)
			(layer "F.Fab")
		)
		(fp_line
			(start -0.12065 0.2794)
			(end -0.12065 0.3048)
			(stroke
				(width 0.1)
				(type default)
			)
			(layer "F.Fab")
		)
		(fp_line
			(start 0.120396 0.2794)
			(end -0.12065 0.2794)
			(stroke
				(width 0.1)
				(type default)
			)
			(layer "F.Fab")
		)
		(fp_line
			(start -0.12065 -0.2794)
			(end 0.12065 -0.2794)
			(stroke
				(width 0.1)
				(type default)
			)
			(layer "F.Fab")
		)
		(fp_line
			(start 0.12065 -0.2794)
			(end 0.12065 -0.3048)
			(stroke
				(width 0.1)
				(type default)
			)
			(layer "F.Fab")
		)
		(fp_line
			(start 0.12065 -0.3048)
			(end 0.67945 -0.3048)
			(stroke
				(width 0.1)
				(type default)
			)
			(layer "F.Fab")
		)
		(fp_line
			(start 0.67945 -0.3048)
			(end 0.67945 0.3048)
			(stroke
				(width 0.1)
				(type default)
			)
			(layer "F.Fab")
		)
		(fp_line
			(start -0.67945 -0.305054)
			(end -0.12065 -0.305054)
			(stroke
				(width 0.1)
				(type default)
			)
			(layer "F.Fab")
		)
		(fp_line
			(start -0.12065 -0.305054)
			(end -0.12065 -0.2794)
			(stroke
				(width 0.1)
				(type default)
			)
			(layer "F.Fab")
		)
		(pad "1" smd circle
			(at -0.40005 0 270)
			(size 0 0)
			(layers "F.Cu" "F.Mask" "F.Paste")
			(net "SSD14_PWRDIS")
		)
		(pad "2" smd circle
			(at 0.40005 0 270)
			(size 0 0)
			(layers "F.Cu" "F.Mask" "F.Paste")
			(net "SSD14_PWRDIS_R")
		)
	)
	(footprint ""
		(layer "F.Cu")
		(at 216.480136 -179.848256 -90)
		(property "Reference" "R5418"
			(at 0 0 270)
			(layer "F.SilkS")
			(hide yes)
			(effects
				(font
					(size 1.27 1.27)
				)
			)
		)
		(property "Value" ""
			(at 0 0 270)
			(layer "F.Fab")
			(effects
				(font
					(size 1.27 1.27)
				)
			)
		)
		(duplicate_pad_numbers_are_jumpers no)
		(fp_line
			(start -0.7874 0.4064)
			(end -0.7874 -0.4064)
			(stroke
				(width 0.1524)
				(type default)
			)
			(layer "F.SilkS")
		)
		(fp_line
			(start 0.7874 0.4064)
			(end -0.7874 0.4064)
			(stroke
				(width 0.1524)
				(type default)
			)
			(layer "F.SilkS")
		)
		(fp_line
			(start -0.7874 -0.4064)
			(end 0.7874 -0.4064)
			(stroke
				(width 0.1524)
				(type default)
			)
			(layer "F.SilkS")
		)
		(fp_line
			(start 0.7874 -0.4064)
			(end 0.7874 0.4064)
			(stroke
				(width 0.1524)
				(type default)
			)
			(layer "F.SilkS")
		)
		(fp_line
			(start -0.67945 0.3048)
			(end -0.67945 -0.305054)
			(stroke
				(width 0.1)
				(type default)
			)
			(layer "F.Fab")
		)
		(fp_line
			(start -0.12065 0.3048)
			(end -0.67945 0.3048)
			(stroke
				(width 0.1)
				(type default)
			)
			(layer "F.Fab")
		)
		(fp_line
			(start 0.120396 0.3048)
			(end 0.120396 0.2794)
			(stroke
				(width 0.1)
				(type default)
			)
			(layer "F.Fab")
		)
		(fp_line
			(start 0.67945 0.3048)
			(end 0.120396 0.3048)
			(stroke
				(width 0.1)
				(type default)
			)
			(layer "F.Fab")
		)
		(fp_line
			(start -0.12065 0.2794)
			(end -0.12065 0.3048)
			(stroke
				(width 0.1)
				(type default)
			)
			(layer "F.Fab")
		)
		(fp_line
			(start 0.120396 0.2794)
			(end -0.12065 0.2794)
			(stroke
				(width 0.1)
				(type default)
			)
			(layer "F.Fab")
		)
		(fp_line
			(start -0.12065 -0.2794)
			(end 0.12065 -0.2794)
			(stroke
				(width 0.1)
				(type default)
			)
			(layer "F.Fab")
		)
		(fp_line
			(start 0.12065 -0.2794)
			(end 0.12065 -0.3048)
			(stroke
				(width 0.1)
				(type default)
			)
			(layer "F.Fab")
		)
		(fp_line
			(start 0.12065 -0.3048)
			(end 0.67945 -0.3048)
			(stroke
				(width 0.1)
				(type default)
			)
			(layer "F.Fab")
		)
		(fp_line
			(start 0.67945 -0.3048)
			(end 0.67945 0.3048)
			(stroke
				(width 0.1)
				(type default)
			)
			(layer "F.Fab")
		)
		(fp_line
			(start -0.67945 -0.305054)
			(end -0.12065 -0.305054)
			(stroke
				(width 0.1)
				(type default)
			)
			(layer "F.Fab")
		)
		(fp_line
			(start -0.12065 -0.305054)
			(end -0.12065 -0.2794)
			(stroke
				(width 0.1)
				(type default)
			)
			(layer "F.Fab")
		)
		(pad "1" smd circle
			(at -0.40005 0 270)
			(size 0 0)
			(layers "F.Cu" "F.Mask" "F.Paste")
			(net "SEL_FLASH_PEX0_BUF_R")
		)
		(pad "2" smd circle
			(at 0.40005 0 270)
			(size 0 0)
			(layers "F.Cu" "F.Mask" "F.Paste")
			(net "P3V3_AUX")
		)
	)
	(footprint ""
		(layer "F.Cu")
		(at 141.162532 -22.955504 -90)
		(property "Reference" "C2719"
			(at 0 0 270)
			(layer "F.SilkS")
			(hide yes)
			(effects
				(font
					(size 1.27 1.27)
				)
			)
		)
		(property "Value" ""
			(at 0 0 270)
			(layer "F.Fab")
			(effects
				(font
					(size 1.27 1.27)
				)
			)
		)
		(duplicate_pad_numbers_are_jumpers no)
		(fp_line
			(start -0.7874 0.4064)
			(end -0.7874 -0.4064)
			(stroke
				(width 0.1524)
				(type default)
			)
			(layer "F.SilkS")
		)
		(fp_line
			(start 0.7874 0.4064)
			(end -0.7874 0.4064)
			(stroke
				(width 0.1524)
				(type default)
			)
			(layer "F.SilkS")
		)
		(fp_line
			(start -0.7874 -0.4064)
			(end 0.7874 -0.4064)
			(stroke
				(width 0.1524)
				(type default)
			)
			(layer "F.SilkS")
		)
		(fp_line
			(start 0.7874 -0.4064)
			(end 0.7874 0.4064)
			(stroke
				(width 0.1524)
				(type default)
			)
			(layer "F.SilkS")
		)
		(fp_line
			(start -0.67945 0.3048)
			(end -0.67945 -0.305054)
			(stroke
				(width 0.1)
				(type default)
			)
			(layer "F.Fab")
		)
		(fp_line
			(start -0.12065 0.3048)
			(end -0.67945 0.3048)
			(stroke
				(width 0.1)
				(type default)
			)
			(layer "F.Fab")
		)
		(fp_line
			(start 0.120396 0.3048)
			(end 0.120396 0.2794)
			(stroke
				(width 0.1)
				(type default)
			)
			(layer "F.Fab")
		)
		(fp_line
			(start 0.67945 0.3048)
			(end 0.120396 0.3048)
			(stroke
				(width 0.1)
				(type default)
			)
			(layer "F.Fab")
		)
		(fp_line
			(start -0.12065 0.2794)
			(end -0.12065 0.3048)
			(stroke
				(width 0.1)
				(type default)
			)
			(layer "F.Fab")
		)
		(fp_line
			(start 0.120396 0.2794)
			(end -0.12065 0.2794)
			(stroke
				(width 0.1)
				(type default)
			)
			(layer "F.Fab")
		)
		(fp_line
			(start -0.12065 -0.2794)
			(end 0.12065 -0.2794)
			(stroke
				(width 0.1)
				(type default)
			)
			(layer "F.Fab")
		)
		(fp_line
			(start 0.12065 -0.2794)
			(end 0.12065 -0.3048)
			(stroke
				(width 0.1)
				(type default)
			)
			(layer "F.Fab")
		)
		(fp_line
			(start 0.12065 -0.3048)
			(end 0.67945 -0.3048)
			(stroke
				(width 0.1)
				(type default)
			)
			(layer "F.Fab")
		)
		(fp_line
			(start 0.67945 -0.3048)
			(end 0.67945 0.3048)
			(stroke
				(width 0.1)
				(type default)
			)
			(layer "F.Fab")
		)
		(fp_line
			(start -0.67945 -0.305054)
			(end -0.12065 -0.305054)
			(stroke
				(width 0.1)
				(type default)
			)
			(layer "F.Fab")
		)
		(fp_line
			(start -0.12065 -0.305054)
			(end -0.12065 -0.2794)
			(stroke
				(width 0.1)
				(type default)
			)
			(layer "F.Fab")
		)
		(pad "1" smd circle
			(at -0.40005 0 270)
			(size 0 0)
			(layers "F.Cu" "F.Mask" "F.Paste")
			(net "GND")
		)
		(pad "2" smd circle
			(at 0.40005 0 270)
			(size 0 0)
			(layers "F.Cu" "F.Mask" "F.Paste")
			(net "P3V3_AUX")
		)
	)
	(footprint ""
		(layer "F.Cu")
		(at 426.75937 -22.955504 90)
		(property "Reference" "R1741"
			(at 0 0 90)
			(layer "F.SilkS")
			(hide yes)
			(effects
				(font
					(size 1.27 1.27)
				)
			)
		)
		(property "Value" ""
			(at 0 0 90)
			(layer "F.Fab")
			(effects
				(font
					(size 1.27 1.27)
				)
			)
		)
		(duplicate_pad_numbers_are_jumpers no)
		(fp_line
			(start 0.7874 -0.4064)
			(end 0.7874 0.4064)
			(stroke
				(width 0.1524)
				(type default)
			)
			(layer "F.SilkS")
		)
		(fp_line
			(start -0.7874 -0.4064)
			(end 0.7874 -0.4064)
			(stroke
				(width 0.1524)
				(type default)
			)
			(layer "F.SilkS")
		)
		(fp_line
			(start 0.7874 0.4064)
			(end -0.7874 0.4064)
			(stroke
				(width 0.1524)
				(type default)
			)
			(layer "F.SilkS")
		)
		(fp_line
			(start -0.7874 0.4064)
			(end -0.7874 -0.4064)
			(stroke
				(width 0.1524)
				(type default)
			)
			(layer "F.SilkS")
		)
		(fp_line
			(start -0.12065 -0.305054)
			(end -0.12065 -0.2794)
			(stroke
				(width 0.1)
				(type default)
			)
			(layer "F.Fab")
		)
		(fp_line
			(start -0.67945 -0.305054)
			(end -0.12065 -0.305054)
			(stroke
				(width 0.1)
				(type default)
			)
			(layer "F.Fab")
		)
		(fp_line
			(start 0.67945 -0.3048)
			(end 0.67945 0.3048)
			(stroke
				(width 0.1)
				(type default)
			)
			(layer "F.Fab")
		)
		(fp_line
			(start 0.12065 -0.3048)
			(end 0.67945 -0.3048)
			(stroke
				(width 0.1)
				(type default)
			)
			(layer "F.Fab")
		)
		(fp_line
			(start 0.12065 -0.2794)
			(end 0.12065 -0.3048)
			(stroke
				(width 0.1)
				(type default)
			)
			(layer "F.Fab")
		)
		(fp_line
			(start -0.12065 -0.2794)
			(end 0.12065 -0.2794)
			(stroke
				(width 0.1)
				(type default)
			)
			(layer "F.Fab")
		)
		(fp_line
			(start 0.120396 0.2794)
			(end -0.12065 0.2794)
			(stroke
				(width 0.1)
				(type default)
			)
			(layer "F.Fab")
		)
		(fp_line
			(start -0.12065 0.2794)
			(end -0.12065 0.3048)
			(stroke
				(width 0.1)
				(type default)
			)
			(layer "F.Fab")
		)
		(fp_line
			(start 0.67945 0.3048)
			(end 0.120396 0.3048)
			(stroke
				(width 0.1)
				(type default)
			)
			(layer "F.Fab")
		)
		(fp_line
			(start 0.120396 0.3048)
			(end 0.120396 0.2794)
			(stroke
				(width 0.1)
				(type default)
			)
			(layer "F.Fab")
		)
		(fp_line
			(start -0.12065 0.3048)
			(end -0.67945 0.3048)
			(stroke
				(width 0.1)
				(type default)
			)
			(layer "F.Fab")
		)
		(fp_line
			(start -0.67945 0.3048)
			(end -0.67945 -0.305054)
			(stroke
				(width 0.1)
				(type default)
			)
			(layer "F.Fab")
		)
		(pad "1" smd circle
			(at -0.40005 0 90)
			(size 0 0)
			(layers "F.Cu" "F.Mask" "F.Paste")
			(net "SMB_BIC_I2C9_MUX1_SSD14_R_SCL")
		)
		(pad "2" smd circle
			(at 0.40005 0 90)
			(size 0 0)
			(layers "F.Cu" "F.Mask" "F.Paste")
			(net "SMB_ISO_SSD14_SCL")
		)
	)
	(footprint ""
		(layer "F.Cu")
		(at 100.820474 -70.307454 90)
		(property "Reference" "PC638"
			(at 0 0 90)
			(layer "F.SilkS")
			(hide yes)
			(effects
				(font
					(size 1.27 1.27)
				)
			)
		)
		(property "Value" ""
			(at 0 0 90)
			(layer "F.Fab")
			(effects
				(font
					(size 1.27 1.27)
				)
			)
		)
		(duplicate_pad_numbers_are_jumpers no)
		(fp_line
			(start 0.7874 -0.4064)
			(end 0.7874 0.4064)
			(stroke
				(width 0.1524)
				(type default)
			)
			(layer "F.SilkS")
		)
		(fp_line
			(start -0.7874 -0.4064)
			(end 0.7874 -0.4064)
			(stroke
				(width 0.1524)
				(type default)
			)
			(layer "F.SilkS")
		)
		(fp_line
			(start 0.7874 0.4064)
			(end -0.7874 0.4064)
			(stroke
				(width 0.1524)
				(type default)
			)
			(layer "F.SilkS")
		)
		(fp_line
			(start -0.7874 0.4064)
			(end -0.7874 -0.4064)
			(stroke
				(width 0.1524)
				(type default)
			)
			(layer "F.SilkS")
		)
		(fp_line
			(start -0.12065 -0.305054)
			(end -0.12065 -0.2794)
			(stroke
				(width 0.1)
				(type default)
			)
			(layer "F.Fab")
		)
		(fp_line
			(start -0.67945 -0.305054)
			(end -0.12065 -0.305054)
			(stroke
				(width 0.1)
				(type default)
			)
			(layer "F.Fab")
		)
		(fp_line
			(start 0.67945 -0.3048)
			(end 0.67945 0.3048)
			(stroke
				(width 0.1)
				(type default)
			)
			(layer "F.Fab")
		)
		(fp_line
			(start 0.12065 -0.3048)
			(end 0.67945 -0.3048)
			(stroke
				(width 0.1)
				(type default)
			)
			(layer "F.Fab")
		)
		(fp_line
			(start 0.12065 -0.2794)
			(end 0.12065 -0.3048)
			(stroke
				(width 0.1)
				(type default)
			)
			(layer "F.Fab")
		)
		(fp_line
			(start -0.12065 -0.2794)
			(end 0.12065 -0.2794)
			(stroke
				(width 0.1)
				(type default)
			)
			(layer "F.Fab")
		)
		(fp_line
			(start 0.120396 0.2794)
			(end -0.12065 0.2794)
			(stroke
				(width 0.1)
				(type default)
			)
			(layer "F.Fab")
		)
		(fp_line
			(start -0.12065 0.2794)
			(end -0.12065 0.3048)
			(stroke
				(width 0.1)
				(type default)
			)
			(layer "F.Fab")
		)
		(fp_line
			(start 0.67945 0.3048)
			(end 0.120396 0.3048)
			(stroke
				(width 0.1)
				(type default)
			)
			(layer "F.Fab")
		)
		(fp_line
			(start 0.120396 0.3048)
			(end 0.120396 0.2794)
			(stroke
				(width 0.1)
				(type default)
			)
			(layer "F.Fab")
		)
		(fp_line
			(start -0.12065 0.3048)
			(end -0.67945 0.3048)
			(stroke
				(width 0.1)
				(type default)
			)
			(layer "F.Fab")
		)
		(fp_line
			(start -0.67945 0.3048)
			(end -0.67945 -0.305054)
			(stroke
				(width 0.1)
				(type default)
			)
			(layer "F.Fab")
		)
		(pad "1" smd circle
			(at -0.40005 0 90)
			(size 0 0)
			(layers "F.Cu" "F.Mask" "F.Paste")
			(net "P12V_AUX")
		)
		(pad "2" smd circle
			(at 0.40005 0 90)
			(size 0 0)
			(layers "F.Cu" "F.Mask" "F.Paste")
			(net "GND")
		)
	)
	(footprint ""
		(layer "F.Cu")
		(at 152.738328 -112.809782)
		(property "Reference" "C261"
			(at 0 0 0)
			(layer "F.SilkS")
			(hide yes)
			(effects
				(font
					(size 1.27 1.27)
				)
			)
		)
		(property "Value" ""
			(at 0 0 0)
			(layer "F.Fab")
			(effects
				(font
					(size 1.27 1.27)
				)
			)
		)
		(duplicate_pad_numbers_are_jumpers no)
		(fp_line
			(start -0.299974 -0.150114)
			(end 0.299974 -0.150114)
			(stroke
				(width 0.1)
				(type default)
			)
			(layer "F.Fab")
		)
		(fp_line
			(start -0.299974 0.150114)
			(end -0.299974 -0.150114)
			(stroke
				(width 0.1)
				(type default)
			)
			(layer "F.Fab")
		)
		(fp_line
			(start 0.299974 -0.150114)
			(end 0.299974 0.150114)
			(stroke
				(width 0.1)
				(type default)
			)
			(layer "F.Fab")
		)
		(fp_line
			(start 0.299974 0.150114)
			(end -0.299974 0.150114)
			(stroke
				(width 0.1)
				(type default)
			)
			(layer "F.Fab")
		)
		(pad "1" smd rect
			(at -0.2667 0)
			(size 0.3048 0.381)
			(layers "F.Cu" "F.Mask" "F.Paste")
			(net "P5E_PEX1_STN1_TX_DP<23>")
		)
		(pad "2" smd rect
			(at 0.2667 0)
			(size 0.3048 0.381)
			(layers "F.Cu" "F.Mask" "F.Paste")
			(net "P5E_PEX1_STN1_TX_C_DP<23>")
		)
	)
	(footprint ""
		(layer "F.Cu")
		(at 363.474 -211.963 180)
		(property "Reference" "R4611"
			(at 0 0 180)
			(layer "F.SilkS")
			(hide yes)
			(effects
				(font
					(size 1.27 1.27)
				)
			)
		)
		(property "Value" ""
			(at 0 0 180)
			(layer "F.Fab")
			(effects
				(font
					(size 1.27 1.27)
				)
			)
		)
		(duplicate_pad_numbers_are_jumpers no)
		(fp_line
			(start 0.7874 0.4064)
			(end -0.7874 0.4064)
			(stroke
				(width 0.1524)
				(type default)
			)
			(layer "F.SilkS")
		)
		(fp_line
			(start 0.7874 -0.4064)
			(end 0.7874 0.4064)
			(stroke
				(width 0.1524)
				(type default)
			)
			(layer "F.SilkS")
		)
		(fp_line
			(start -0.7874 0.4064)
			(end -0.7874 -0.4064)
			(stroke
				(width 0.1524)
				(type default)
			)
			(layer "F.SilkS")
		)
		(fp_line
			(start -0.7874 -0.4064)
			(end 0.7874 -0.4064)
			(stroke
				(width 0.1524)
				(type default)
			)
			(layer "F.SilkS")
		)
		(fp_line
			(start 0.67945 0.3048)
			(end 0.120396 0.3048)
			(stroke
				(width 0.1)
				(type default)
			)
			(layer "F.Fab")
		)
		(fp_line
			(start 0.67945 -0.3048)
			(end 0.67945 0.3048)
			(stroke
				(width 0.1)
				(type default)
			)
			(layer "F.Fab")
		)
		(fp_line
			(start 0.12065 -0.2794)
			(end 0.12065 -0.3048)
			(stroke
				(width 0.1)
				(type default)
			)
			(layer "F.Fab")
		)
		(fp_line
			(start 0.12065 -0.3048)
			(end 0.67945 -0.3048)
			(stroke
				(width 0.1)
				(type default)
			)
			(layer "F.Fab")
		)
		(fp_line
			(start 0.120396 0.3048)
			(end 0.120396 0.2794)
			(stroke
				(width 0.1)
				(type default)
			)
			(layer "F.Fab")
		)
		(fp_line
			(start 0.120396 0.2794)
			(end -0.12065 0.2794)
			(stroke
				(width 0.1)
				(type default)
			)
			(layer "F.Fab")
		)
		(fp_line
			(start -0.12065 0.3048)
			(end -0.67945 0.3048)
			(stroke
				(width 0.1)
				(type default)
			)
			(layer "F.Fab")
		)
		(fp_line
			(start -0.12065 0.2794)
			(end -0.12065 0.3048)
			(stroke
				(width 0.1)
				(type default)
			)
			(layer "F.Fab")
		)
		(fp_line
			(start -0.12065 -0.2794)
			(end 0.12065 -0.2794)
			(stroke
				(width 0.1)
				(type default)
			)
			(layer "F.Fab")
		)
		(fp_line
			(start -0.12065 -0.305054)
			(end -0.12065 -0.2794)
			(stroke
				(width 0.1)
				(type default)
			)
			(layer "F.Fab")
		)
		(fp_line
			(start -0.67945 0.3048)
			(end -0.67945 -0.305054)
			(stroke
				(width 0.1)
				(type default)
			)
			(layer "F.Fab")
		)
		(fp_line
			(start -0.67945 -0.305054)
			(end -0.12065 -0.305054)
			(stroke
				(width 0.1)
				(type default)
			)
			(layer "F.Fab")
		)
		(pad "1" smd circle
			(at -0.40005 0 180)
			(size 0 0)
			(layers "F.Cu" "F.Mask" "F.Paste")
			(net "SSD0_PEX_PWR_EN_R")
		)
		(pad "2" smd circle
			(at 0.40005 0 180)
			(size 0 0)
			(layers "F.Cu" "F.Mask" "F.Paste")
			(net "GND")
		)
	)
	(footprint ""
		(layer "F.Cu")
		(at 73.28281 -80.739742)
		(property "Reference" "R101"
			(at 0 0 0)
			(layer "F.SilkS")
			(hide yes)
			(effects
				(font
					(size 1.27 1.27)
				)
			)
		)
		(property "Value" ""
			(at 0 0 0)
			(layer "F.Fab")
			(effects
				(font
					(size 1.27 1.27)
				)
			)
		)
		(duplicate_pad_numbers_are_jumpers no)
		(fp_line
			(start -0.7874 -0.4064)
			(end 0.7874 -0.4064)
			(stroke
				(width 0.1524)
				(type default)
			)
			(layer "F.SilkS")
		)
		(fp_line
			(start -0.7874 0.4064)
			(end -0.7874 -0.4064)
			(stroke
				(width 0.1524)
				(type default)
			)
			(layer "F.SilkS")
		)
		(fp_line
			(start 0.7874 -0.4064)
			(end 0.7874 0.4064)
			(stroke
				(width 0.1524)
				(type default)
			)
			(layer "F.SilkS")
		)
		(fp_line
			(start 0.7874 0.4064)
			(end -0.7874 0.4064)
			(stroke
				(width 0.1524)
				(type default)
			)
			(layer "F.SilkS")
		)
		(fp_line
			(start -0.67945 -0.305054)
			(end -0.12065 -0.305054)
			(stroke
				(width 0.1)
				(type default)
			)
			(layer "F.Fab")
		)
		(fp_line
			(start -0.67945 0.3048)
			(end -0.67945 -0.305054)
			(stroke
				(width 0.1)
				(type default)
			)
			(layer "F.Fab")
		)
		(fp_line
			(start -0.12065 -0.305054)
			(end -0.12065 -0.2794)
			(stroke
				(width 0.1)
				(type default)
			)
			(layer "F.Fab")
		)
		(fp_line
			(start -0.12065 -0.2794)
			(end 0.12065 -0.2794)
			(stroke
				(width 0.1)
				(type default)
			)
			(layer "F.Fab")
		)
		(fp_line
			(start -0.12065 0.2794)
			(end -0.12065 0.3048)
			(stroke
				(width 0.1)
				(type default)
			)
			(layer "F.Fab")
		)
		(fp_line
			(start -0.12065 0.3048)
			(end -0.67945 0.3048)
			(stroke
				(width 0.1)
				(type default)
			)
			(layer "F.Fab")
		)
		(fp_line
			(start 0.120396 0.2794)
			(end -0.12065 0.2794)
			(stroke
				(width 0.1)
				(type default)
			)
			(layer "F.Fab")
		)
		(fp_line
			(start 0.120396 0.3048)
			(end 0.120396 0.2794)
			(stroke
				(width 0.1)
				(type default)
			)
			(layer "F.Fab")
		)
		(fp_line
			(start 0.12065 -0.3048)
			(end 0.67945 -0.3048)
			(stroke
				(width 0.1)
				(type default)
			)
			(layer "F.Fab")
		)
		(fp_line
			(start 0.12065 -0.2794)
			(end 0.12065 -0.3048)
			(stroke
				(width 0.1)
				(type default)
			)
			(layer "F.Fab")
		)
		(fp_line
			(start 0.67945 -0.3048)
			(end 0.67945 0.3048)
			(stroke
				(width 0.1)
				(type default)
			)
			(layer "F.Fab")
		)
		(fp_line
			(start 0.67945 0.3048)
			(end 0.120396 0.3048)
			(stroke
				(width 0.1)
				(type default)
			)
			(layer "F.Fab")
		)
		(pad "1" smd circle
			(at -0.40005 0)
			(size 0 0)
			(layers "F.Cu" "F.Mask" "F.Paste")
			(net "P3V3_AUX")
		)
		(pad "2" smd circle
			(at 0.40005 0)
			(size 0 0)
			(layers "F.Cu" "F.Mask" "F.Paste")
			(net "HP_NIC1_HSC_PWRGD_N")
		)
	)
	(footprint ""
		(layer "F.Cu")
		(at 431.950114 -50.96383 180)
		(property "Reference" "PC584"
			(at 0 0 180)
			(layer "F.SilkS")
			(hide yes)
			(effects
				(font
					(size 1.27 1.27)
				)
			)
		)
		(property "Value" ""
			(at 0 0 180)
			(layer "F.Fab")
			(effects
				(font
					(size 1.27 1.27)
				)
			)
		)
		(duplicate_pad_numbers_are_jumpers no)
		(fp_line
			(start 1.524 0.762)
			(end -1.524 0.762)
			(stroke
				(width 0.1524)
				(type default)
			)
			(layer "F.SilkS")
		)
		(fp_line
			(start 1.524 -0.762)
			(end 1.524 0.762)
			(stroke
				(width 0.1524)
				(type default)
			)
			(layer "F.SilkS")
		)
		(fp_line
			(start -1.524 0.762)
			(end -1.524 -0.762)
			(stroke
				(width 0.1524)
				(type default)
			)
			(layer "F.SilkS")
		)
		(fp_line
			(start -1.524 -0.762)
			(end 1.524 -0.762)
			(stroke
				(width 0.1524)
				(type default)
			)
			(layer "F.SilkS")
		)
		(fp_line
			(start 1.1049 0.724916)
			(end 1.1049 -0.724916)
			(stroke
				(width 0.1)
				(type default)
			)
			(layer "F.Fab")
		)
		(fp_line
			(start 1.1049 -0.724916)
			(end -1.1049 -0.724916)
			(stroke
				(width 0.1)
				(type default)
			)
			(layer "F.Fab")
		)
		(fp_line
			(start -1.1049 0.724916)
			(end 1.1049 0.724916)
			(stroke
				(width 0.1)
				(type default)
			)
			(layer "F.Fab")
		)
		(fp_line
			(start -1.1049 -0.724916)
			(end -1.1049 0.724916)
			(stroke
				(width 0.1)
				(type default)
			)
			(layer "F.Fab")
		)
		(pad "1" smd rect
			(at -0.889 0)
			(size 1.016 1.27)
			(layers "F.Cu" "F.Mask" "F.Paste")
			(net "P3V3_SSD15")
		)
		(pad "2" smd rect
			(at 0.889 0)
			(size 1.016 1.27)
			(layers "F.Cu" "F.Mask" "F.Paste")
			(net "GND")
		)
	)
	(footprint ""
		(layer "F.Cu")
		(at 324.738746 -122.798332 90)
		(property "Reference" "PC466"
			(at 0 0 90)
			(layer "F.SilkS")
			(hide yes)
			(effects
				(font
					(size 1.27 1.27)
				)
			)
		)
		(property "Value" ""
			(at 0 0 90)
			(layer "F.Fab")
			(effects
				(font
					(size 1.27 1.27)
				)
			)
		)
		(duplicate_pad_numbers_are_jumpers no)
		(fp_line
			(start 0.7874 -0.4064)
			(end 0.7874 0.4064)
			(stroke
				(width 0.1524)
				(type default)
			)
			(layer "F.SilkS")
		)
		(fp_line
			(start -0.7874 -0.4064)
			(end 0.7874 -0.4064)
			(stroke
				(width 0.1524)
				(type default)
			)
			(layer "F.SilkS")
		)
		(fp_line
			(start 0.7874 0.4064)
			(end -0.7874 0.4064)
			(stroke
				(width 0.1524)
				(type default)
			)
			(layer "F.SilkS")
		)
		(fp_line
			(start -0.7874 0.4064)
			(end -0.7874 -0.4064)
			(stroke
				(width 0.1524)
				(type default)
			)
			(layer "F.SilkS")
		)
		(fp_line
			(start -0.12065 -0.305054)
			(end -0.12065 -0.2794)
			(stroke
				(width 0.1)
				(type default)
			)
			(layer "F.Fab")
		)
		(fp_line
			(start -0.67945 -0.305054)
			(end -0.12065 -0.305054)
			(stroke
				(width 0.1)
				(type default)
			)
			(layer "F.Fab")
		)
		(fp_line
			(start 0.67945 -0.3048)
			(end 0.67945 0.3048)
			(stroke
				(width 0.1)
				(type default)
			)
			(layer "F.Fab")
		)
		(fp_line
			(start 0.12065 -0.3048)
			(end 0.67945 -0.3048)
			(stroke
				(width 0.1)
				(type default)
			)
			(layer "F.Fab")
		)
		(fp_line
			(start 0.12065 -0.2794)
			(end 0.12065 -0.3048)
			(stroke
				(width 0.1)
				(type default)
			)
			(layer "F.Fab")
		)
		(fp_line
			(start -0.12065 -0.2794)
			(end 0.12065 -0.2794)
			(stroke
				(width 0.1)
				(type default)
			)
			(layer "F.Fab")
		)
		(fp_line
			(start 0.120396 0.2794)
			(end -0.12065 0.2794)
			(stroke
				(width 0.1)
				(type default)
			)
			(layer "F.Fab")
		)
		(fp_line
			(start -0.12065 0.2794)
			(end -0.12065 0.3048)
			(stroke
				(width 0.1)
				(type default)
			)
			(layer "F.Fab")
		)
		(fp_line
			(start 0.67945 0.3048)
			(end 0.120396 0.3048)
			(stroke
				(width 0.1)
				(type default)
			)
			(layer "F.Fab")
		)
		(fp_line
			(start 0.120396 0.3048)
			(end 0.120396 0.2794)
			(stroke
				(width 0.1)
				(type default)
			)
			(layer "F.Fab")
		)
		(fp_line
			(start -0.12065 0.3048)
			(end -0.67945 0.3048)
			(stroke
				(width 0.1)
				(type default)
			)
			(layer "F.Fab")
		)
		(fp_line
			(start -0.67945 0.3048)
			(end -0.67945 -0.305054)
			(stroke
				(width 0.1)
				(type default)
			)
			(layer "F.Fab")
		)
		(pad "1" smd circle
			(at -0.40005 0 90)
			(size 0 0)
			(layers "F.Cu" "F.Mask" "F.Paste")
			(net "P3V3_NIC5")
		)
		(pad "2" smd circle
			(at 0.40005 0 90)
			(size 0 0)
			(layers "F.Cu" "F.Mask" "F.Paste")
			(net "GND")
		)
	)
	(footprint ""
		(layer "F.Cu")
		(at 258.225036 -14.735302 180)
		(property "Reference" "C2728"
			(at 0 0 180)
			(layer "F.SilkS")
			(hide yes)
			(effects
				(font
					(size 1.27 1.27)
				)
			)
		)
		(property "Value" ""
			(at 0 0 180)
			(layer "F.Fab")
			(effects
				(font
					(size 1.27 1.27)
				)
			)
		)
		(duplicate_pad_numbers_are_jumpers no)
		(fp_line
			(start 0.7874 0.4064)
			(end -0.7874 0.4064)
			(stroke
				(width 0.1524)
				(type default)
			)
			(layer "F.SilkS")
		)
		(fp_line
			(start 0.7874 -0.4064)
			(end 0.7874 0.4064)
			(stroke
				(width 0.1524)
				(type default)
			)
			(layer "F.SilkS")
		)
		(fp_line
			(start -0.7874 0.4064)
			(end -0.7874 -0.4064)
			(stroke
				(width 0.1524)
				(type default)
			)
			(layer "F.SilkS")
		)
		(fp_line
			(start -0.7874 -0.4064)
			(end 0.7874 -0.4064)
			(stroke
				(width 0.1524)
				(type default)
			)
			(layer "F.SilkS")
		)
		(fp_line
			(start 0.67945 0.3048)
			(end 0.120396 0.3048)
			(stroke
				(width 0.1)
				(type default)
			)
			(layer "F.Fab")
		)
		(fp_line
			(start 0.67945 -0.3048)
			(end 0.67945 0.3048)
			(stroke
				(width 0.1)
				(type default)
			)
			(layer "F.Fab")
		)
		(fp_line
			(start 0.12065 -0.2794)
			(end 0.12065 -0.3048)
			(stroke
				(width 0.1)
				(type default)
			)
			(layer "F.Fab")
		)
		(fp_line
			(start 0.12065 -0.3048)
			(end 0.67945 -0.3048)
			(stroke
				(width 0.1)
				(type default)
			)
			(layer "F.Fab")
		)
		(fp_line
			(start 0.120396 0.3048)
			(end 0.120396 0.2794)
			(stroke
				(width 0.1)
				(type default)
			)
			(layer "F.Fab")
		)
		(fp_line
			(start 0.120396 0.2794)
			(end -0.12065 0.2794)
			(stroke
				(width 0.1)
				(type default)
			)
			(layer "F.Fab")
		)
		(fp_line
			(start -0.12065 0.3048)
			(end -0.67945 0.3048)
			(stroke
				(width 0.1)
				(type default)
			)
			(layer "F.Fab")
		)
		(fp_line
			(start -0.12065 0.2794)
			(end -0.12065 0.3048)
			(stroke
				(width 0.1)
				(type default)
			)
			(layer "F.Fab")
		)
		(fp_line
			(start -0.12065 -0.2794)
			(end 0.12065 -0.2794)
			(stroke
				(width 0.1)
				(type default)
			)
			(layer "F.Fab")
		)
		(fp_line
			(start -0.12065 -0.305054)
			(end -0.12065 -0.2794)
			(stroke
				(width 0.1)
				(type default)
			)
			(layer "F.Fab")
		)
		(fp_line
			(start -0.67945 0.3048)
			(end -0.67945 -0.305054)
			(stroke
				(width 0.1)
				(type default)
			)
			(layer "F.Fab")
		)
		(fp_line
			(start -0.67945 -0.305054)
			(end -0.12065 -0.305054)
			(stroke
				(width 0.1)
				(type default)
			)
			(layer "F.Fab")
		)
		(pad "1" smd circle
			(at -0.40005 0 180)
			(size 0 0)
			(layers "F.Cu" "F.Mask" "F.Paste")
			(net "GND")
		)
		(pad "2" smd circle
			(at 0.40005 0 180)
			(size 0 0)
			(layers "F.Cu" "F.Mask" "F.Paste")
			(net "P3V3_SSD8")
		)
	)
	(footprint ""
		(layer "F.Cu")
		(at 402.754846 -22.961346 90)
		(property "Reference" "R1718"
			(at 0 0 90)
			(layer "F.SilkS")
			(hide yes)
			(effects
				(font
					(size 1.27 1.27)
				)
			)
		)
		(property "Value" ""
			(at 0 0 90)
			(layer "F.Fab")
			(effects
				(font
					(size 1.27 1.27)
				)
			)
		)
		(duplicate_pad_numbers_are_jumpers no)
		(fp_line
			(start 0.7874 -0.4064)
			(end 0.7874 0.4064)
			(stroke
				(width 0.1524)
				(type default)
			)
			(layer "F.SilkS")
		)
		(fp_line
			(start -0.7874 -0.4064)
			(end 0.7874 -0.4064)
			(stroke
				(width 0.1524)
				(type default)
			)
			(layer "F.SilkS")
		)
		(fp_line
			(start 0.7874 0.4064)
			(end -0.7874 0.4064)
			(stroke
				(width 0.1524)
				(type default)
			)
			(layer "F.SilkS")
		)
		(fp_line
			(start -0.7874 0.4064)
			(end -0.7874 -0.4064)
			(stroke
				(width 0.1524)
				(type default)
			)
			(layer "F.SilkS")
		)
		(fp_line
			(start -0.12065 -0.305054)
			(end -0.12065 -0.2794)
			(stroke
				(width 0.1)
				(type default)
			)
			(layer "F.Fab")
		)
		(fp_line
			(start -0.67945 -0.305054)
			(end -0.12065 -0.305054)
			(stroke
				(width 0.1)
				(type default)
			)
			(layer "F.Fab")
		)
		(fp_line
			(start 0.67945 -0.3048)
			(end 0.67945 0.3048)
			(stroke
				(width 0.1)
				(type default)
			)
			(layer "F.Fab")
		)
		(fp_line
			(start 0.12065 -0.3048)
			(end 0.67945 -0.3048)
			(stroke
				(width 0.1)
				(type default)
			)
			(layer "F.Fab")
		)
		(fp_line
			(start 0.12065 -0.2794)
			(end 0.12065 -0.3048)
			(stroke
				(width 0.1)
				(type default)
			)
			(layer "F.Fab")
		)
		(fp_line
			(start -0.12065 -0.2794)
			(end 0.12065 -0.2794)
			(stroke
				(width 0.1)
				(type default)
			)
			(layer "F.Fab")
		)
		(fp_line
			(start 0.120396 0.2794)
			(end -0.12065 0.2794)
			(stroke
				(width 0.1)
				(type default)
			)
			(layer "F.Fab")
		)
		(fp_line
			(start -0.12065 0.2794)
			(end -0.12065 0.3048)
			(stroke
				(width 0.1)
				(type default)
			)
			(layer "F.Fab")
		)
		(fp_line
			(start 0.67945 0.3048)
			(end 0.120396 0.3048)
			(stroke
				(width 0.1)
				(type default)
			)
			(layer "F.Fab")
		)
		(fp_line
			(start 0.120396 0.3048)
			(end 0.120396 0.2794)
			(stroke
				(width 0.1)
				(type default)
			)
			(layer "F.Fab")
		)
		(fp_line
			(start -0.12065 0.3048)
			(end -0.67945 0.3048)
			(stroke
				(width 0.1)
				(type default)
			)
			(layer "F.Fab")
		)
		(fp_line
			(start -0.67945 0.3048)
			(end -0.67945 -0.305054)
			(stroke
				(width 0.1)
				(type default)
			)
			(layer "F.Fab")
		)
		(pad "1" smd circle
			(at -0.40005 0 90)
			(size 0 0)
			(layers "F.Cu" "F.Mask" "F.Paste")
			(net "SMB_SSD13_ISO_EN")
		)
		(pad "2" smd circle
			(at 0.40005 0 90)
			(size 0 0)
			(layers "F.Cu" "F.Mask" "F.Paste")
			(net "P3V3_AUX")
		)
	)
	(footprint ""
		(layer "F.Cu")
		(at 31.589472 -63.56223)
		(property "Reference" "Q128"
			(at -0.548132 -2.284476 0)
			(unlocked yes)
			(layer "F.SilkS")
			(effects
				(font
					(size 0.7874 0.5842)
					(thickness 0.1524)
				)
			)
		)
		(property "Value" ""
			(at 0 0 0)
			(layer "F.Fab")
			(effects
				(font
					(size 1.27 1.27)
				)
			)
		)
		(duplicate_pad_numbers_are_jumpers no)
		(fp_line
			(start -1.376172 -1.199896)
			(end -0.508 -1.199896)
			(stroke
				(width 0.1524)
				(type default)
			)
			(layer "F.SilkS")
		)
		(fp_line
			(start -1.376172 1.199896)
			(end -1.376172 -1.199896)
			(stroke
				(width 0.1524)
				(type default)
			)
			(layer "F.SilkS")
		)
		(fp_line
			(start -0.508 -1.199896)
			(end 0 -0.762)
			(stroke
				(width 0.1524)
				(type default)
			)
			(layer "F.SilkS")
		)
		(fp_line
			(start 0 -0.762)
			(end 0.508 -1.199896)
			(stroke
				(width 0.1524)
				(type default)
			)
			(layer "F.SilkS")
		)
		(fp_line
			(start 0.508 -1.199896)
			(end 1.376172 -1.199896)
			(stroke
				(width 0.1524)
				(type default)
			)
			(layer "F.SilkS")
		)
		(fp_line
			(start 1.376172 -1.199896)
			(end 1.376172 1.199896)
			(stroke
				(width 0.1524)
				(type default)
			)
			(layer "F.SilkS")
		)
		(fp_line
			(start 1.376172 1.199896)
			(end -1.376172 1.199896)
			(stroke
				(width 0.1524)
				(type default)
			)
			(layer "F.SilkS")
		)
		(fp_poly
			(pts
				(xy -1.550924 -0.930402) (xy -1.820418 -1.73863) (xy -2.359152 -1.199896)
			)
			(stroke
				(width 0)
				(type default)
			)
			(fill yes)
			(layer "F.SilkS")
		)
		(fp_line
			(start -0.674878 -1.100074)
			(end 0.674878 -1.100074)
			(stroke
				(width 0.1)
				(type default)
			)
			(layer "F.Fab")
		)
		(fp_line
			(start -0.674878 1.100074)
			(end -0.674878 -1.100074)
			(stroke
				(width 0.1)
				(type default)
			)
			(layer "F.Fab")
		)
		(fp_line
			(start 0.674878 -1.100074)
			(end 0.674878 1.100074)
			(stroke
				(width 0.1)
				(type default)
			)
			(layer "F.Fab")
		)
		(fp_line
			(start 0.674878 1.100074)
			(end -0.674878 1.100074)
			(stroke
				(width 0.1)
				(type default)
			)
			(layer "F.Fab")
		)
		(fp_poly
			(pts
				(xy -1.4605 -0.7493) (xy -2.2225 -1.1303) (xy -2.2225 -0.3683)
			)
			(stroke
				(width 0)
				(type default)
			)
			(fill yes)
			(layer "F.Fab")
		)
		(pad "1" smd rect
			(at -0.899922 -0.750062 270)
			(size 0.6096 0.6096)
			(layers "F.Cu" "F.Mask" "F.Paste")
			(net "GND")
		)
		(pad "2" smd rect
			(at -0.899922 0 270)
			(size 0.4064 0.6096)
			(layers "F.Cu" "F.Mask" "F.Paste")
			(net "P12V_SSD1_PG_G1")
		)
		(pad "3" smd rect
			(at -0.899922 0.750062 270)
			(size 0.6096 0.6096)
			(layers "F.Cu" "F.Mask" "F.Paste")
			(net "PWRGD_P12V_SSD1_D")
		)
		(pad "4" smd rect
			(at 0.899922 0.750062 270)
			(size 0.6096 0.6096)
			(layers "F.Cu" "F.Mask" "F.Paste")
			(net "GND")
		)
		(pad "5" smd rect
			(at 0.899922 0 270)
			(size 0.4064 0.6096)
			(layers "F.Cu" "F.Mask" "F.Paste")
			(net "P12V_SSD1_PG_G2")
		)
		(pad "6" smd rect
			(at 0.899922 -0.750062 270)
			(size 0.6096 0.6096)
			(layers "F.Cu" "F.Mask" "F.Paste")
			(net "P12V_SSD1_PG_G2")
		)
	)
	(footprint ""
		(layer "F.Cu")
		(at 409.015438 -86.424008 180)
		(property "Reference" "R6268"
			(at 0 0 180)
			(layer "F.SilkS")
			(hide yes)
			(effects
				(font
					(size 1.27 1.27)
				)
			)
		)
		(property "Value" ""
			(at 0 0 180)
			(layer "F.Fab")
			(effects
				(font
					(size 1.27 1.27)
				)
			)
		)
		(duplicate_pad_numbers_are_jumpers no)
		(fp_line
			(start 0.7874 0.4064)
			(end -0.7874 0.4064)
			(stroke
				(width 0.1524)
				(type default)
			)
			(layer "F.SilkS")
		)
		(fp_line
			(start 0.7874 -0.4064)
			(end 0.7874 0.4064)
			(stroke
				(width 0.1524)
				(type default)
			)
			(layer "F.SilkS")
		)
		(fp_line
			(start -0.7874 0.4064)
			(end -0.7874 -0.4064)
			(stroke
				(width 0.1524)
				(type default)
			)
			(layer "F.SilkS")
		)
		(fp_line
			(start -0.7874 -0.4064)
			(end 0.7874 -0.4064)
			(stroke
				(width 0.1524)
				(type default)
			)
			(layer "F.SilkS")
		)
		(fp_line
			(start 0.67945 0.3048)
			(end 0.120396 0.3048)
			(stroke
				(width 0.1)
				(type default)
			)
			(layer "F.Fab")
		)
		(fp_line
			(start 0.67945 -0.3048)
			(end 0.67945 0.3048)
			(stroke
				(width 0.1)
				(type default)
			)
			(layer "F.Fab")
		)
		(fp_line
			(start 0.12065 -0.2794)
			(end 0.12065 -0.3048)
			(stroke
				(width 0.1)
				(type default)
			)
			(layer "F.Fab")
		)
		(fp_line
			(start 0.12065 -0.3048)
			(end 0.67945 -0.3048)
			(stroke
				(width 0.1)
				(type default)
			)
			(layer "F.Fab")
		)
		(fp_line
			(start 0.120396 0.3048)
			(end 0.120396 0.2794)
			(stroke
				(width 0.1)
				(type default)
			)
			(layer "F.Fab")
		)
		(fp_line
			(start 0.120396 0.2794)
			(end -0.12065 0.2794)
			(stroke
				(width 0.1)
				(type default)
			)
			(layer "F.Fab")
		)
		(fp_line
			(start -0.12065 0.3048)
			(end -0.67945 0.3048)
			(stroke
				(width 0.1)
				(type default)
			)
			(layer "F.Fab")
		)
		(fp_line
			(start -0.12065 0.2794)
			(end -0.12065 0.3048)
			(stroke
				(width 0.1)
				(type default)
			)
			(layer "F.Fab")
		)
		(fp_line
			(start -0.12065 -0.2794)
			(end 0.12065 -0.2794)
			(stroke
				(width 0.1)
				(type default)
			)
			(layer "F.Fab")
		)
		(fp_line
			(start -0.12065 -0.305054)
			(end -0.12065 -0.2794)
			(stroke
				(width 0.1)
				(type default)
			)
			(layer "F.Fab")
		)
		(fp_line
			(start -0.67945 0.3048)
			(end -0.67945 -0.305054)
			(stroke
				(width 0.1)
				(type default)
			)
			(layer "F.Fab")
		)
		(fp_line
			(start -0.67945 -0.305054)
			(end -0.12065 -0.305054)
			(stroke
				(width 0.1)
				(type default)
			)
			(layer "F.Fab")
		)
		(pad "1" smd circle
			(at -0.40005 0 180)
			(size 0 0)
			(layers "F.Cu" "F.Mask" "F.Paste")
			(net "SMB_CLK_ISO_R_SCL_R1")
		)
		(pad "2" smd circle
			(at 0.40005 0 180)
			(size 0 0)
			(layers "F.Cu" "F.Mask" "F.Paste")
			(net "SMB_CLK_ISO_SCL")
		)
	)
	(footprint ""
		(layer "F.Cu")
		(at 303.446688 -38.49116 180)
		(property "Reference" "R6101"
			(at 0 0 180)
			(layer "F.SilkS")
			(hide yes)
			(effects
				(font
					(size 1.27 1.27)
				)
			)
		)
		(property "Value" ""
			(at 0 0 180)
			(layer "F.Fab")
			(effects
				(font
					(size 1.27 1.27)
				)
			)
		)
		(duplicate_pad_numbers_are_jumpers no)
		(fp_line
			(start 0.7874 0.4064)
			(end -0.7874 0.4064)
			(stroke
				(width 0.1524)
				(type default)
			)
			(layer "F.SilkS")
		)
		(fp_line
			(start 0.7874 -0.4064)
			(end 0.7874 0.4064)
			(stroke
				(width 0.1524)
				(type default)
			)
			(layer "F.SilkS")
		)
		(fp_line
			(start -0.7874 0.4064)
			(end -0.7874 -0.4064)
			(stroke
				(width 0.1524)
				(type default)
			)
			(layer "F.SilkS")
		)
		(fp_line
			(start -0.7874 -0.4064)
			(end 0.7874 -0.4064)
			(stroke
				(width 0.1524)
				(type default)
			)
			(layer "F.SilkS")
		)
		(fp_line
			(start 0.67945 0.3048)
			(end 0.120396 0.3048)
			(stroke
				(width 0.1)
				(type default)
			)
			(layer "F.Fab")
		)
		(fp_line
			(start 0.67945 -0.3048)
			(end 0.67945 0.3048)
			(stroke
				(width 0.1)
				(type default)
			)
			(layer "F.Fab")
		)
		(fp_line
			(start 0.12065 -0.2794)
			(end 0.12065 -0.3048)
			(stroke
				(width 0.1)
				(type default)
			)
			(layer "F.Fab")
		)
		(fp_line
			(start 0.12065 -0.3048)
			(end 0.67945 -0.3048)
			(stroke
				(width 0.1)
				(type default)
			)
			(layer "F.Fab")
		)
		(fp_line
			(start 0.120396 0.3048)
			(end 0.120396 0.2794)
			(stroke
				(width 0.1)
				(type default)
			)
			(layer "F.Fab")
		)
		(fp_line
			(start 0.120396 0.2794)
			(end -0.12065 0.2794)
			(stroke
				(width 0.1)
				(type default)
			)
			(layer "F.Fab")
		)
		(fp_line
			(start -0.12065 0.3048)
			(end -0.67945 0.3048)
			(stroke
				(width 0.1)
				(type default)
			)
			(layer "F.Fab")
		)
		(fp_line
			(start -0.12065 0.2794)
			(end -0.12065 0.3048)
			(stroke
				(width 0.1)
				(type default)
			)
			(layer "F.Fab")
		)
		(fp_line
			(start -0.12065 -0.2794)
			(end 0.12065 -0.2794)
			(stroke
				(width 0.1)
				(type default)
			)
			(layer "F.Fab")
		)
		(fp_line
			(start -0.12065 -0.305054)
			(end -0.12065 -0.2794)
			(stroke
				(width 0.1)
				(type default)
			)
			(layer "F.Fab")
		)
		(fp_line
			(start -0.67945 0.3048)
			(end -0.67945 -0.305054)
			(stroke
				(width 0.1)
				(type default)
			)
			(layer "F.Fab")
		)
		(fp_line
			(start -0.67945 -0.305054)
			(end -0.12065 -0.305054)
			(stroke
				(width 0.1)
				(type default)
			)
			(layer "F.Fab")
		)
		(pad "1" smd circle
			(at -0.40005 0 180)
			(size 0 0)
			(layers "F.Cu" "F.Mask" "F.Paste")
			(net "P3V3_SSD11_PG_G1")
		)
		(pad "2" smd circle
			(at 0.40005 0 180)
			(size 0 0)
			(layers "F.Cu" "F.Mask" "F.Paste")
			(net "GND")
		)
	)
	(footprint ""
		(layer "F.Cu")
		(at 226.34321 -318.648588 -90)
		(property "Reference" "PL19"
			(at 0 0 270)
			(layer "F.SilkS")
			(hide yes)
			(effects
				(font
					(size 1.27 1.27)
				)
			)
		)
		(property "Value" ""
			(at 0 0 270)
			(layer "F.Fab")
			(effects
				(font
					(size 1.27 1.27)
				)
			)
		)
		(duplicate_pad_numbers_are_jumpers no)
		(fp_line
			(start -1.27 0.5842)
			(end -1.27 -0.5842)
			(stroke
				(width 0.1524)
				(type default)
			)
			(layer "F.SilkS")
		)
		(fp_line
			(start 1.27 0.5842)
			(end -1.27 0.5842)
			(stroke
				(width 0.1524)
				(type default)
			)
			(layer "F.SilkS")
		)
		(fp_line
			(start 1.27 0.5842)
			(end 1.27 -0.5842)
			(stroke
				(width 0.1524)
				(type default)
			)
			(layer "F.SilkS")
		)
		(fp_line
			(start -1.27 -0.5588)
			(end -1.27 -0.5842)
			(stroke
				(width 0.1524)
				(type default)
			)
			(layer "F.SilkS")
		)
		(fp_line
			(start -1.27 -0.5842)
			(end 1.27 -0.5842)
			(stroke
				(width 0.1524)
				(type default)
			)
			(layer "F.SilkS")
		)
		(fp_line
			(start -0.9144 0.508)
			(end -0.9144 0.406654)
			(stroke
				(width 0.1)
				(type default)
			)
			(layer "F.Fab")
		)
		(fp_line
			(start 0.9144 0.508)
			(end -0.9144 0.508)
			(stroke
				(width 0.1)
				(type default)
			)
			(layer "F.Fab")
		)
		(fp_line
			(start -1.194308 0.406654)
			(end -1.194308 -0.406654)
			(stroke
				(width 0.1)
				(type default)
			)
			(layer "F.Fab")
		)
		(fp_line
			(start -0.9144 0.406654)
			(end -1.194308 0.406654)
			(stroke
				(width 0.1)
				(type default)
			)
			(layer "F.Fab")
		)
		(fp_line
			(start 0.9144 0.4064)
			(end 0.9144 0.508)
			(stroke
				(width 0.1)
				(type default)
			)
			(layer "F.Fab")
		)
		(fp_line
			(start 1.1938 0.4064)
			(end 0.9144 0.4064)
			(stroke
				(width 0.1)
				(type default)
			)
			(layer "F.Fab")
		)
		(fp_line
			(start -1.194308 -0.406654)
			(end -0.9144 -0.406654)
			(stroke
				(width 0.1)
				(type default)
			)
			(layer "F.Fab")
		)
		(fp_line
			(start -0.9144 -0.406654)
			(end -0.9144 -0.508)
			(stroke
				(width 0.1)
				(type default)
			)
			(layer "F.Fab")
		)
		(fp_line
			(start 0.9144 -0.406654)
			(end 1.1938 -0.406654)
			(stroke
				(width 0.1)
				(type default)
			)
			(layer "F.Fab")
		)
		(fp_line
			(start 1.1938 -0.406654)
			(end 1.1938 0.4064)
			(stroke
				(width 0.1)
				(type default)
			)
			(layer "F.Fab")
		)
		(fp_line
			(start -0.9144 -0.508)
			(end 0.9144 -0.508)
			(stroke
				(width 0.1)
				(type default)
			)
			(layer "F.Fab")
		)
		(fp_line
			(start 0.9144 -0.508)
			(end 0.9144 -0.406654)
			(stroke
				(width 0.1)
				(type default)
			)
			(layer "F.Fab")
		)
		(pad "1" smd rect
			(at -0.7366 0 180)
			(size 0.7112 0.8128)
			(layers "F.Cu" "F.Mask" "F.Paste")
			(net "P12V_AUX")
		)
		(pad "2" smd rect
			(at 0.7366 0 180)
			(size 0.7112 0.8128)
			(layers "F.Cu" "F.Mask" "F.Paste")
			(net "SW_P12V_P1V25_PEX1_FLT")
		)
	)
	(footprint ""
		(layer "F.Cu")
		(at 219.164408 -29.079952 180)
		(property "Reference" "R6205"
			(at 0 0 180)
			(layer "F.SilkS")
			(hide yes)
			(effects
				(font
					(size 1.27 1.27)
				)
			)
		)
		(property "Value" ""
			(at 0 0 180)
			(layer "F.Fab")
			(effects
				(font
					(size 1.27 1.27)
				)
			)
		)
		(duplicate_pad_numbers_are_jumpers no)
		(fp_line
			(start 0.7874 0.4064)
			(end -0.7874 0.4064)
			(stroke
				(width 0.1524)
				(type default)
			)
			(layer "F.SilkS")
		)
		(fp_line
			(start 0.7874 -0.4064)
			(end 0.7874 0.4064)
			(stroke
				(width 0.1524)
				(type default)
			)
			(layer "F.SilkS")
		)
		(fp_line
			(start -0.7874 0.4064)
			(end -0.7874 -0.4064)
			(stroke
				(width 0.1524)
				(type default)
			)
			(layer "F.SilkS")
		)
		(fp_line
			(start -0.7874 -0.4064)
			(end 0.7874 -0.4064)
			(stroke
				(width 0.1524)
				(type default)
			)
			(layer "F.SilkS")
		)
		(fp_line
			(start 0.67945 0.3048)
			(end 0.120396 0.3048)
			(stroke
				(width 0.1)
				(type default)
			)
			(layer "F.Fab")
		)
		(fp_line
			(start 0.67945 -0.3048)
			(end 0.67945 0.3048)
			(stroke
				(width 0.1)
				(type default)
			)
			(layer "F.Fab")
		)
		(fp_line
			(start 0.12065 -0.2794)
			(end 0.12065 -0.3048)
			(stroke
				(width 0.1)
				(type default)
			)
			(layer "F.Fab")
		)
		(fp_line
			(start 0.12065 -0.3048)
			(end 0.67945 -0.3048)
			(stroke
				(width 0.1)
				(type default)
			)
			(layer "F.Fab")
		)
		(fp_line
			(start 0.120396 0.3048)
			(end 0.120396 0.2794)
			(stroke
				(width 0.1)
				(type default)
			)
			(layer "F.Fab")
		)
		(fp_line
			(start 0.120396 0.2794)
			(end -0.12065 0.2794)
			(stroke
				(width 0.1)
				(type default)
			)
			(layer "F.Fab")
		)
		(fp_line
			(start -0.12065 0.3048)
			(end -0.67945 0.3048)
			(stroke
				(width 0.1)
				(type default)
			)
			(layer "F.Fab")
		)
		(fp_line
			(start -0.12065 0.2794)
			(end -0.12065 0.3048)
			(stroke
				(width 0.1)
				(type default)
			)
			(layer "F.Fab")
		)
		(fp_line
			(start -0.12065 -0.2794)
			(end 0.12065 -0.2794)
			(stroke
				(width 0.1)
				(type default)
			)
			(layer "F.Fab")
		)
		(fp_line
			(start -0.12065 -0.305054)
			(end -0.12065 -0.2794)
			(stroke
				(width 0.1)
				(type default)
			)
			(layer "F.Fab")
		)
		(fp_line
			(start -0.67945 0.3048)
			(end -0.67945 -0.305054)
			(stroke
				(width 0.1)
				(type default)
			)
			(layer "F.Fab")
		)
		(fp_line
			(start -0.67945 -0.305054)
			(end -0.12065 -0.305054)
			(stroke
				(width 0.1)
				(type default)
			)
			(layer "F.Fab")
		)
		(pad "1" smd circle
			(at -0.40005 0 180)
			(size 0 0)
			(layers "F.Cu" "F.Mask" "F.Paste")
			(net "GND")
		)
		(pad "2" smd circle
			(at 0.40005 0 180)
			(size 0 0)
			(layers "F.Cu" "F.Mask" "F.Paste")
			(net "SSD7_PWRDIS_R")
		)
	)
	(footprint ""
		(layer "F.Cu")
		(at 264.539984 -77.279754 90)
		(property "Reference" "R1059"
			(at 0 0 90)
			(layer "F.SilkS")
			(hide yes)
			(effects
				(font
					(size 1.27 1.27)
				)
			)
		)
		(property "Value" ""
			(at 0 0 90)
			(layer "F.Fab")
			(effects
				(font
					(size 1.27 1.27)
				)
			)
		)
		(duplicate_pad_numbers_are_jumpers no)
		(fp_line
			(start 0.7874 -0.4064)
			(end 0.7874 0.4064)
			(stroke
				(width 0.1524)
				(type default)
			)
			(layer "F.SilkS")
		)
		(fp_line
			(start -0.7874 -0.4064)
			(end 0.7874 -0.4064)
			(stroke
				(width 0.1524)
				(type default)
			)
			(layer "F.SilkS")
		)
		(fp_line
			(start 0.7874 0.4064)
			(end -0.7874 0.4064)
			(stroke
				(width 0.1524)
				(type default)
			)
			(layer "F.SilkS")
		)
		(fp_line
			(start -0.7874 0.4064)
			(end -0.7874 -0.4064)
			(stroke
				(width 0.1524)
				(type default)
			)
			(layer "F.SilkS")
		)
		(fp_line
			(start -0.12065 -0.305054)
			(end -0.12065 -0.2794)
			(stroke
				(width 0.1)
				(type default)
			)
			(layer "F.Fab")
		)
		(fp_line
			(start -0.67945 -0.305054)
			(end -0.12065 -0.305054)
			(stroke
				(width 0.1)
				(type default)
			)
			(layer "F.Fab")
		)
		(fp_line
			(start 0.67945 -0.3048)
			(end 0.67945 0.3048)
			(stroke
				(width 0.1)
				(type default)
			)
			(layer "F.Fab")
		)
		(fp_line
			(start 0.12065 -0.3048)
			(end 0.67945 -0.3048)
			(stroke
				(width 0.1)
				(type default)
			)
			(layer "F.Fab")
		)
		(fp_line
			(start 0.12065 -0.2794)
			(end 0.12065 -0.3048)
			(stroke
				(width 0.1)
				(type default)
			)
			(layer "F.Fab")
		)
		(fp_line
			(start -0.12065 -0.2794)
			(end 0.12065 -0.2794)
			(stroke
				(width 0.1)
				(type default)
			)
			(layer "F.Fab")
		)
		(fp_line
			(start 0.120396 0.2794)
			(end -0.12065 0.2794)
			(stroke
				(width 0.1)
				(type default)
			)
			(layer "F.Fab")
		)
		(fp_line
			(start -0.12065 0.2794)
			(end -0.12065 0.3048)
			(stroke
				(width 0.1)
				(type default)
			)
			(layer "F.Fab")
		)
		(fp_line
			(start 0.67945 0.3048)
			(end 0.120396 0.3048)
			(stroke
				(width 0.1)
				(type default)
			)
			(layer "F.Fab")
		)
		(fp_line
			(start 0.120396 0.3048)
			(end 0.120396 0.2794)
			(stroke
				(width 0.1)
				(type default)
			)
			(layer "F.Fab")
		)
		(fp_line
			(start -0.12065 0.3048)
			(end -0.67945 0.3048)
			(stroke
				(width 0.1)
				(type default)
			)
			(layer "F.Fab")
		)
		(fp_line
			(start -0.67945 0.3048)
			(end -0.67945 -0.305054)
			(stroke
				(width 0.1)
				(type default)
			)
			(layer "F.Fab")
		)
		(pad "1" smd circle
			(at -0.40005 0 90)
			(size 0 0)
			(layers "F.Cu" "F.Mask" "F.Paste")
			(net "GND")
		)
		(pad "2" smd circle
			(at 0.40005 0 90)
			(size 0 0)
			(layers "F.Cu" "F.Mask" "F.Paste")
			(net "CLK_BUFFER_9ZXL0851E_8_15_OE2_N")
		)
	)
	(footprint ""
		(layer "F.Cu")
		(at 91.0336 -304.036476 90)
		(property "Reference" "R1250"
			(at 0 0 90)
			(layer "F.SilkS")
			(hide yes)
			(effects
				(font
					(size 1.27 1.27)
				)
			)
		)
		(property "Value" ""
			(at 0 0 90)
			(layer "F.Fab")
			(effects
				(font
					(size 1.27 1.27)
				)
			)
		)
		(duplicate_pad_numbers_are_jumpers no)
		(fp_line
			(start 0.7874 -0.4064)
			(end 0.7874 0.4064)
			(stroke
				(width 0.1524)
				(type default)
			)
			(layer "F.SilkS")
		)
		(fp_line
			(start -0.7874 -0.4064)
			(end 0.7874 -0.4064)
			(stroke
				(width 0.1524)
				(type default)
			)
			(layer "F.SilkS")
		)
		(fp_line
			(start 0.7874 0.4064)
			(end -0.7874 0.4064)
			(stroke
				(width 0.1524)
				(type default)
			)
			(layer "F.SilkS")
		)
		(fp_line
			(start -0.7874 0.4064)
			(end -0.7874 -0.4064)
			(stroke
				(width 0.1524)
				(type default)
			)
			(layer "F.SilkS")
		)
		(fp_line
			(start -0.12065 -0.305054)
			(end -0.12065 -0.2794)
			(stroke
				(width 0.1)
				(type default)
			)
			(layer "F.Fab")
		)
		(fp_line
			(start -0.67945 -0.305054)
			(end -0.12065 -0.305054)
			(stroke
				(width 0.1)
				(type default)
			)
			(layer "F.Fab")
		)
		(fp_line
			(start 0.67945 -0.3048)
			(end 0.67945 0.3048)
			(stroke
				(width 0.1)
				(type default)
			)
			(layer "F.Fab")
		)
		(fp_line
			(start 0.12065 -0.3048)
			(end 0.67945 -0.3048)
			(stroke
				(width 0.1)
				(type default)
			)
			(layer "F.Fab")
		)
		(fp_line
			(start 0.12065 -0.2794)
			(end 0.12065 -0.3048)
			(stroke
				(width 0.1)
				(type default)
			)
			(layer "F.Fab")
		)
		(fp_line
			(start -0.12065 -0.2794)
			(end 0.12065 -0.2794)
			(stroke
				(width 0.1)
				(type default)
			)
			(layer "F.Fab")
		)
		(fp_line
			(start 0.120396 0.2794)
			(end -0.12065 0.2794)
			(stroke
				(width 0.1)
				(type default)
			)
			(layer "F.Fab")
		)
		(fp_line
			(start -0.12065 0.2794)
			(end -0.12065 0.3048)
			(stroke
				(width 0.1)
				(type default)
			)
			(layer "F.Fab")
		)
		(fp_line
			(start 0.67945 0.3048)
			(end 0.120396 0.3048)
			(stroke
				(width 0.1)
				(type default)
			)
			(layer "F.Fab")
		)
		(fp_line
			(start 0.120396 0.3048)
			(end 0.120396 0.2794)
			(stroke
				(width 0.1)
				(type default)
			)
			(layer "F.Fab")
		)
		(fp_line
			(start -0.12065 0.3048)
			(end -0.67945 0.3048)
			(stroke
				(width 0.1)
				(type default)
			)
			(layer "F.Fab")
		)
		(fp_line
			(start -0.67945 0.3048)
			(end -0.67945 -0.305054)
			(stroke
				(width 0.1)
				(type default)
			)
			(layer "F.Fab")
		)
		(pad "1" smd circle
			(at -0.40005 0 90)
			(size 0 0)
			(layers "F.Cu" "F.Mask" "F.Paste")
			(net "GND")
		)
		(pad "2" smd circle
			(at 0.40005 0 90)
			(size 0 0)
			(layers "F.Cu" "F.Mask" "F.Paste")
			(net "PEX0_SPARE1")
		)
	)
	(footprint ""
		(layer "F.Cu")
		(at 217.235786 -217.286586 180)
		(property "Reference" "R1501"
			(at 0 0 180)
			(layer "F.SilkS")
			(hide yes)
			(effects
				(font
					(size 1.27 1.27)
				)
			)
		)
		(property "Value" ""
			(at 0 0 180)
			(layer "F.Fab")
			(effects
				(font
					(size 1.27 1.27)
				)
			)
		)
		(duplicate_pad_numbers_are_jumpers no)
		(fp_line
			(start 0.7874 0.4064)
			(end -0.7874 0.4064)
			(stroke
				(width 0.1524)
				(type default)
			)
			(layer "F.SilkS")
		)
		(fp_line
			(start 0.7874 -0.4064)
			(end 0.7874 0.4064)
			(stroke
				(width 0.1524)
				(type default)
			)
			(layer "F.SilkS")
		)
		(fp_line
			(start -0.7874 0.4064)
			(end -0.7874 -0.4064)
			(stroke
				(width 0.1524)
				(type default)
			)
			(layer "F.SilkS")
		)
		(fp_line
			(start -0.7874 -0.4064)
			(end 0.7874 -0.4064)
			(stroke
				(width 0.1524)
				(type default)
			)
			(layer "F.SilkS")
		)
		(fp_line
			(start 0.67945 0.3048)
			(end 0.120396 0.3048)
			(stroke
				(width 0.1)
				(type default)
			)
			(layer "F.Fab")
		)
		(fp_line
			(start 0.67945 -0.3048)
			(end 0.67945 0.3048)
			(stroke
				(width 0.1)
				(type default)
			)
			(layer "F.Fab")
		)
		(fp_line
			(start 0.12065 -0.2794)
			(end 0.12065 -0.3048)
			(stroke
				(width 0.1)
				(type default)
			)
			(layer "F.Fab")
		)
		(fp_line
			(start 0.12065 -0.3048)
			(end 0.67945 -0.3048)
			(stroke
				(width 0.1)
				(type default)
			)
			(layer "F.Fab")
		)
		(fp_line
			(start 0.120396 0.3048)
			(end 0.120396 0.2794)
			(stroke
				(width 0.1)
				(type default)
			)
			(layer "F.Fab")
		)
		(fp_line
			(start 0.120396 0.2794)
			(end -0.12065 0.2794)
			(stroke
				(width 0.1)
				(type default)
			)
			(layer "F.Fab")
		)
		(fp_line
			(start -0.12065 0.3048)
			(end -0.67945 0.3048)
			(stroke
				(width 0.1)
				(type default)
			)
			(layer "F.Fab")
		)
		(fp_line
			(start -0.12065 0.2794)
			(end -0.12065 0.3048)
			(stroke
				(width 0.1)
				(type default)
			)
			(layer "F.Fab")
		)
		(fp_line
			(start -0.12065 -0.2794)
			(end 0.12065 -0.2794)
			(stroke
				(width 0.1)
				(type default)
			)
			(layer "F.Fab")
		)
		(fp_line
			(start -0.12065 -0.305054)
			(end -0.12065 -0.2794)
			(stroke
				(width 0.1)
				(type default)
			)
			(layer "F.Fab")
		)
		(fp_line
			(start -0.67945 0.3048)
			(end -0.67945 -0.305054)
			(stroke
				(width 0.1)
				(type default)
			)
			(layer "F.Fab")
		)
		(fp_line
			(start -0.67945 -0.305054)
			(end -0.12065 -0.305054)
			(stroke
				(width 0.1)
				(type default)
			)
			(layer "F.Fab")
		)
		(pad "1" smd circle
			(at -0.40005 0 180)
			(size 0 0)
			(layers "F.Cu" "F.Mask" "F.Paste")
			(net "SMB_NIC5_SDA")
		)
		(pad "2" smd circle
			(at 0.40005 0 180)
			(size 0 0)
			(layers "F.Cu" "F.Mask" "F.Paste")
			(net "SMB_NIC5_R_SDA")
		)
	)
	(footprint ""
		(layer "F.Cu")
		(at 366.731296 -123.903994 -90)
		(property "Reference" "PC479"
			(at 0 0 270)
			(layer "F.SilkS")
			(hide yes)
			(effects
				(font
					(size 1.27 1.27)
				)
			)
		)
		(property "Value" ""
			(at 0 0 270)
			(layer "F.Fab")
			(effects
				(font
					(size 1.27 1.27)
				)
			)
		)
		(duplicate_pad_numbers_are_jumpers no)
		(fp_line
			(start -1.524 0.762)
			(end -1.524 -0.762)
			(stroke
				(width 0.1524)
				(type default)
			)
			(layer "F.SilkS")
		)
		(fp_line
			(start 1.524 0.762)
			(end -1.524 0.762)
			(stroke
				(width 0.1524)
				(type default)
			)
			(layer "F.SilkS")
		)
		(fp_line
			(start -1.524 -0.762)
			(end 1.524 -0.762)
			(stroke
				(width 0.1524)
				(type default)
			)
			(layer "F.SilkS")
		)
		(fp_line
			(start 1.524 -0.762)
			(end 1.524 0.762)
			(stroke
				(width 0.1524)
				(type default)
			)
			(layer "F.SilkS")
		)
		(fp_line
			(start -1.1049 0.724916)
			(end 1.1049 0.724916)
			(stroke
				(width 0.1)
				(type default)
			)
			(layer "F.Fab")
		)
		(fp_line
			(start 1.1049 0.724916)
			(end 1.1049 -0.724916)
			(stroke
				(width 0.1)
				(type default)
			)
			(layer "F.Fab")
		)
		(fp_line
			(start -1.1049 -0.724916)
			(end -1.1049 0.724916)
			(stroke
				(width 0.1)
				(type default)
			)
			(layer "F.Fab")
		)
		(fp_line
			(start 1.1049 -0.724916)
			(end -1.1049 -0.724916)
			(stroke
				(width 0.1)
				(type default)
			)
			(layer "F.Fab")
		)
		(pad "1" smd rect
			(at -0.889 0 90)
			(size 1.016 1.27)
			(layers "F.Cu" "F.Mask" "F.Paste")
			(net "P3V3_NIC6")
		)
		(pad "2" smd rect
			(at 0.889 0 90)
			(size 1.016 1.27)
			(layers "F.Cu" "F.Mask" "F.Paste")
			(net "GND")
		)
	)
	(footprint ""
		(layer "F.Cu")
		(at 420.87546 -69.47916 180)
		(property "Reference" "PU117"
			(at -2.03581 4.13004 90)
			(unlocked yes)
			(layer "F.SilkS")
			(effects
				(font
					(size 0.7874 0.5842)
					(thickness 0.1524)
				)
			)
		)
		(property "Value" ""
			(at 0 0 180)
			(layer "F.Fab")
			(effects
				(font
					(size 1.27 1.27)
				)
			)
		)
		(duplicate_pad_numbers_are_jumpers no)
		(fp_line
			(start 1.239774 1.495298)
			(end -1.239774 1.495298)
			(stroke
				(width 0.1524)
				(type default)
			)
			(layer "F.SilkS")
		)
		(fp_line
			(start 1.239774 -1.495298)
			(end 1.239774 1.495298)
			(stroke
				(width 0.1524)
				(type default)
			)
			(layer "F.SilkS")
		)
		(fp_line
			(start -1.239774 1.495298)
			(end -1.239774 -1.495298)
			(stroke
				(width 0.1524)
				(type default)
			)
			(layer "F.SilkS")
		)
		(fp_line
			(start -1.239774 -1.495298)
			(end 1.239774 -1.495298)
			(stroke
				(width 0.1524)
				(type default)
			)
			(layer "F.SilkS")
		)
		(fp_poly
			(pts
				(xy -1.713738 -1.337564) (xy -2.43205 -0.619252) (xy -1.354328 -0.260096)
			)
			(stroke
				(width 0)
				(type default)
			)
			(fill yes)
			(layer "F.SilkS")
		)
		(fp_line
			(start 0.8001 1.050036)
			(end -0.8001 1.050036)
			(stroke
				(width 0.1)
				(type default)
			)
			(layer "F.Fab")
		)
		(fp_line
			(start 0.8001 -1.050036)
			(end 0.8001 1.050036)
			(stroke
				(width 0.1)
				(type default)
			)
			(layer "F.Fab")
		)
		(fp_line
			(start -0.8001 1.050036)
			(end -0.8001 -1.050036)
			(stroke
				(width 0.1)
				(type default)
			)
			(layer "F.Fab")
		)
		(fp_line
			(start -0.8001 -1.050036)
			(end 0.8001 -1.050036)
			(stroke
				(width 0.1)
				(type default)
			)
			(layer "F.Fab")
		)
		(fp_poly
			(pts
				(xy -2.458974 -0.508) (xy -2.458974 0.508) (xy -1.442974 0)
			)
			(stroke
				(width 0)
				(type default)
			)
			(fill yes)
			(layer "F.Fab")
		)
		(pad "1_2" smd circle
			(at -0.374904 0 270)
			(size 0 0)
			(layers "F.Cu" "F.Mask" "F.Paste")
			(net "P12V_AUX")
		)
		(pad "3" smd rect
			(at -0.499872 0.999998 180)
			(size 0.254 0.7112)
			(layers "F.Cu" "F.Mask" "F.Paste")
			(net "GND")
		)
		(pad "4" smd rect
			(at 0 0.999998 180)
			(size 0.254 0.7112)
			(layers "F.Cu" "F.Mask" "F.Paste")
			(net "P12V_SSD14_CO_ILIMIT")
		)
		(pad "5" smd rect
			(at 0.499872 0.999998 180)
			(size 0.254 0.7112)
			(layers "F.Cu" "F.Mask" "F.Paste")
			(net "P12V_SSD14_CO_MODE")
		)
		(pad "6_7" smd circle
			(at 0.374904 0 90)
			(size 0 0)
			(layers "F.Cu" "F.Mask" "F.Paste")
			(net "P12V_SSD14_R")
		)
		(pad "8" smd rect
			(at 0.499872 -0.999998 180)
			(size 0.254 0.7112)
			(layers "F.Cu" "F.Mask" "F.Paste")
			(net "P12V_SSD14_CO_GATE")
		)
		(pad "9" smd rect
			(at 0 -0.999998 180)
			(size 0.254 0.7112)
			(layers "F.Cu" "F.Mask" "F.Paste")
			(net "P12V_SSD14_CO_EN")
		)
		(pad "10" smd rect
			(at -0.499872 -0.999998 180)
			(size 0.254 0.7112)
			(layers "F.Cu" "F.Mask" "F.Paste")
			(net "P12V_SSD14_CO_DV_DT")
		)
	)
	(footprint ""
		(layer "F.Cu")
		(at 355.403404 -59.571636 90)
		(property "Reference" "PR274"
			(at 0 0 90)
			(layer "F.SilkS")
			(hide yes)
			(effects
				(font
					(size 1.27 1.27)
				)
			)
		)
		(property "Value" ""
			(at 0 0 90)
			(layer "F.Fab")
			(effects
				(font
					(size 1.27 1.27)
				)
			)
		)
		(duplicate_pad_numbers_are_jumpers no)
		(fp_line
			(start 0.7874 -0.4064)
			(end 0.7874 0.4064)
			(stroke
				(width 0.1524)
				(type default)
			)
			(layer "F.SilkS")
		)
		(fp_line
			(start -0.7874 -0.4064)
			(end 0.7874 -0.4064)
			(stroke
				(width 0.1524)
				(type default)
			)
			(layer "F.SilkS")
		)
		(fp_line
			(start 0.7874 0.4064)
			(end -0.7874 0.4064)
			(stroke
				(width 0.1524)
				(type default)
			)
			(layer "F.SilkS")
		)
		(fp_line
			(start -0.7874 0.4064)
			(end -0.7874 -0.4064)
			(stroke
				(width 0.1524)
				(type default)
			)
			(layer "F.SilkS")
		)
		(fp_line
			(start -0.12065 -0.305054)
			(end -0.12065 -0.2794)
			(stroke
				(width 0.1)
				(type default)
			)
			(layer "F.Fab")
		)
		(fp_line
			(start -0.67945 -0.305054)
			(end -0.12065 -0.305054)
			(stroke
				(width 0.1)
				(type default)
			)
			(layer "F.Fab")
		)
		(fp_line
			(start 0.67945 -0.3048)
			(end 0.67945 0.3048)
			(stroke
				(width 0.1)
				(type default)
			)
			(layer "F.Fab")
		)
		(fp_line
			(start 0.12065 -0.3048)
			(end 0.67945 -0.3048)
			(stroke
				(width 0.1)
				(type default)
			)
			(layer "F.Fab")
		)
		(fp_line
			(start 0.12065 -0.2794)
			(end 0.12065 -0.3048)
			(stroke
				(width 0.1)
				(type default)
			)
			(layer "F.Fab")
		)
		(fp_line
			(start -0.12065 -0.2794)
			(end 0.12065 -0.2794)
			(stroke
				(width 0.1)
				(type default)
			)
			(layer "F.Fab")
		)
		(fp_line
			(start 0.120396 0.2794)
			(end -0.12065 0.2794)
			(stroke
				(width 0.1)
				(type default)
			)
			(layer "F.Fab")
		)
		(fp_line
			(start -0.12065 0.2794)
			(end -0.12065 0.3048)
			(stroke
				(width 0.1)
				(type default)
			)
			(layer "F.Fab")
		)
		(fp_line
			(start 0.67945 0.3048)
			(end 0.120396 0.3048)
			(stroke
				(width 0.1)
				(type default)
			)
			(layer "F.Fab")
		)
		(fp_line
			(start 0.120396 0.3048)
			(end 0.120396 0.2794)
			(stroke
				(width 0.1)
				(type default)
			)
			(layer "F.Fab")
		)
		(fp_line
			(start -0.12065 0.3048)
			(end -0.67945 0.3048)
			(stroke
				(width 0.1)
				(type default)
			)
			(layer "F.Fab")
		)
		(fp_line
			(start -0.67945 0.3048)
			(end -0.67945 -0.305054)
			(stroke
				(width 0.1)
				(type default)
			)
			(layer "F.Fab")
		)
		(pad "1" smd circle
			(at -0.40005 0 90)
			(size 0 0)
			(layers "F.Cu" "F.Mask" "F.Paste")
			(net "P3V3_SSD12_OCP")
		)
		(pad "2" smd circle
			(at 0.40005 0 90)
			(size 0 0)
			(layers "F.Cu" "F.Mask" "F.Paste")
			(net "GND")
		)
	)
	(footprint ""
		(layer "F.Cu")
		(at 350.380554 -83.787234)
		(property "Reference" "R1596"
			(at 0 0 0)
			(layer "F.SilkS")
			(hide yes)
			(effects
				(font
					(size 1.27 1.27)
				)
			)
		)
		(property "Value" ""
			(at 0 0 0)
			(layer "F.Fab")
			(effects
				(font
					(size 1.27 1.27)
				)
			)
		)
		(duplicate_pad_numbers_are_jumpers no)
		(fp_line
			(start -0.7874 -0.4064)
			(end 0.7874 -0.4064)
			(stroke
				(width 0.1524)
				(type default)
			)
			(layer "F.SilkS")
		)
		(fp_line
			(start -0.7874 0.4064)
			(end -0.7874 -0.4064)
			(stroke
				(width 0.1524)
				(type default)
			)
			(layer "F.SilkS")
		)
		(fp_line
			(start 0.7874 -0.4064)
			(end 0.7874 0.4064)
			(stroke
				(width 0.1524)
				(type default)
			)
			(layer "F.SilkS")
		)
		(fp_line
			(start 0.7874 0.4064)
			(end -0.7874 0.4064)
			(stroke
				(width 0.1524)
				(type default)
			)
			(layer "F.SilkS")
		)
		(fp_line
			(start -0.67945 -0.305054)
			(end -0.12065 -0.305054)
			(stroke
				(width 0.1)
				(type default)
			)
			(layer "F.Fab")
		)
		(fp_line
			(start -0.67945 0.3048)
			(end -0.67945 -0.305054)
			(stroke
				(width 0.1)
				(type default)
			)
			(layer "F.Fab")
		)
		(fp_line
			(start -0.12065 -0.305054)
			(end -0.12065 -0.2794)
			(stroke
				(width 0.1)
				(type default)
			)
			(layer "F.Fab")
		)
		(fp_line
			(start -0.12065 -0.2794)
			(end 0.12065 -0.2794)
			(stroke
				(width 0.1)
				(type default)
			)
			(layer "F.Fab")
		)
		(fp_line
			(start -0.12065 0.2794)
			(end -0.12065 0.3048)
			(stroke
				(width 0.1)
				(type default)
			)
			(layer "F.Fab")
		)
		(fp_line
			(start -0.12065 0.3048)
			(end -0.67945 0.3048)
			(stroke
				(width 0.1)
				(type default)
			)
			(layer "F.Fab")
		)
		(fp_line
			(start 0.120396 0.2794)
			(end -0.12065 0.2794)
			(stroke
				(width 0.1)
				(type default)
			)
			(layer "F.Fab")
		)
		(fp_line
			(start 0.120396 0.3048)
			(end 0.120396 0.2794)
			(stroke
				(width 0.1)
				(type default)
			)
			(layer "F.Fab")
		)
		(fp_line
			(start 0.12065 -0.3048)
			(end 0.67945 -0.3048)
			(stroke
				(width 0.1)
				(type default)
			)
			(layer "F.Fab")
		)
		(fp_line
			(start 0.12065 -0.2794)
			(end 0.12065 -0.3048)
			(stroke
				(width 0.1)
				(type default)
			)
			(layer "F.Fab")
		)
		(fp_line
			(start 0.67945 -0.3048)
			(end 0.67945 0.3048)
			(stroke
				(width 0.1)
				(type default)
			)
			(layer "F.Fab")
		)
		(fp_line
			(start 0.67945 0.3048)
			(end 0.120396 0.3048)
			(stroke
				(width 0.1)
				(type default)
			)
			(layer "F.Fab")
		)
		(pad "1" smd circle
			(at -0.40005 0)
			(size 0 0)
			(layers "F.Cu" "F.Mask" "F.Paste")
			(net "P3V3_AUX")
		)
		(pad "2" smd circle
			(at 0.40005 0)
			(size 0 0)
			(layers "F.Cu" "F.Mask" "F.Paste")
			(net "SMB_BIC_I2C9_MUX1_SSD10_R_SCL")
		)
	)
	(footprint ""
		(layer "F.Cu")
		(at 294.50919 -213.523068 -90)
		(property "Reference" "R3401"
			(at 0 0 270)
			(layer "F.SilkS")
			(hide yes)
			(effects
				(font
					(size 1.27 1.27)
				)
			)
		)
		(property "Value" ""
			(at 0 0 270)
			(layer "F.Fab")
			(effects
				(font
					(size 1.27 1.27)
				)
			)
		)
		(duplicate_pad_numbers_are_jumpers no)
		(fp_line
			(start -0.7874 0.4064)
			(end -0.7874 -0.4064)
			(stroke
				(width 0.1524)
				(type default)
			)
			(layer "F.SilkS")
		)
		(fp_line
			(start 0.7874 0.4064)
			(end -0.7874 0.4064)
			(stroke
				(width 0.1524)
				(type default)
			)
			(layer "F.SilkS")
		)
		(fp_line
			(start -0.7874 -0.4064)
			(end 0.7874 -0.4064)
			(stroke
				(width 0.1524)
				(type default)
			)
			(layer "F.SilkS")
		)
		(fp_line
			(start 0.7874 -0.4064)
			(end 0.7874 0.4064)
			(stroke
				(width 0.1524)
				(type default)
			)
			(layer "F.SilkS")
		)
		(fp_line
			(start -0.67945 0.3048)
			(end -0.67945 -0.305054)
			(stroke
				(width 0.1)
				(type default)
			)
			(layer "F.Fab")
		)
		(fp_line
			(start -0.12065 0.3048)
			(end -0.67945 0.3048)
			(stroke
				(width 0.1)
				(type default)
			)
			(layer "F.Fab")
		)
		(fp_line
			(start 0.120396 0.3048)
			(end 0.120396 0.2794)
			(stroke
				(width 0.1)
				(type default)
			)
			(layer "F.Fab")
		)
		(fp_line
			(start 0.67945 0.3048)
			(end 0.120396 0.3048)
			(stroke
				(width 0.1)
				(type default)
			)
			(layer "F.Fab")
		)
		(fp_line
			(start -0.12065 0.2794)
			(end -0.12065 0.3048)
			(stroke
				(width 0.1)
				(type default)
			)
			(layer "F.Fab")
		)
		(fp_line
			(start 0.120396 0.2794)
			(end -0.12065 0.2794)
			(stroke
				(width 0.1)
				(type default)
			)
			(layer "F.Fab")
		)
		(fp_line
			(start -0.12065 -0.2794)
			(end 0.12065 -0.2794)
			(stroke
				(width 0.1)
				(type default)
			)
			(layer "F.Fab")
		)
		(fp_line
			(start 0.12065 -0.2794)
			(end 0.12065 -0.3048)
			(stroke
				(width 0.1)
				(type default)
			)
			(layer "F.Fab")
		)
		(fp_line
			(start 0.12065 -0.3048)
			(end 0.67945 -0.3048)
			(stroke
				(width 0.1)
				(type default)
			)
			(layer "F.Fab")
		)
		(fp_line
			(start 0.67945 -0.3048)
			(end 0.67945 0.3048)
			(stroke
				(width 0.1)
				(type default)
			)
			(layer "F.Fab")
		)
		(fp_line
			(start -0.67945 -0.305054)
			(end -0.12065 -0.305054)
			(stroke
				(width 0.1)
				(type default)
			)
			(layer "F.Fab")
		)
		(fp_line
			(start -0.12065 -0.305054)
			(end -0.12065 -0.2794)
			(stroke
				(width 0.1)
				(type default)
			)
			(layer "F.Fab")
		)
		(pad "1" smd circle
			(at -0.40005 0 270)
			(size 0 0)
			(layers "F.Cu" "F.Mask" "F.Paste")
			(net "SPI_BIC1_MISO_LS23_R2")
		)
		(pad "2" smd circle
			(at 0.40005 0 270)
			(size 0 0)
			(layers "F.Cu" "F.Mask" "F.Paste")
			(net "SPI_BIC1_MISO_LS23_R")
		)
	)
	(footprint ""
		(layer "F.Cu")
		(at 212.0265 -25.432004 -90)
		(property "Reference" "C972"
			(at 0 0 270)
			(layer "F.SilkS")
			(hide yes)
			(effects
				(font
					(size 1.27 1.27)
				)
			)
		)
		(property "Value" ""
			(at 0 0 270)
			(layer "F.Fab")
			(effects
				(font
					(size 1.27 1.27)
				)
			)
		)
		(duplicate_pad_numbers_are_jumpers no)
		(fp_line
			(start -0.7874 0.4064)
			(end -0.7874 -0.4064)
			(stroke
				(width 0.1524)
				(type default)
			)
			(layer "F.SilkS")
		)
		(fp_line
			(start 0.7874 0.4064)
			(end -0.7874 0.4064)
			(stroke
				(width 0.1524)
				(type default)
			)
			(layer "F.SilkS")
		)
		(fp_line
			(start -0.7874 -0.4064)
			(end 0.7874 -0.4064)
			(stroke
				(width 0.1524)
				(type default)
			)
			(layer "F.SilkS")
		)
		(fp_line
			(start 0.7874 -0.4064)
			(end 0.7874 0.4064)
			(stroke
				(width 0.1524)
				(type default)
			)
			(layer "F.SilkS")
		)
		(fp_line
			(start -0.67945 0.3048)
			(end -0.67945 -0.305054)
			(stroke
				(width 0.1)
				(type default)
			)
			(layer "F.Fab")
		)
		(fp_line
			(start -0.12065 0.3048)
			(end -0.67945 0.3048)
			(stroke
				(width 0.1)
				(type default)
			)
			(layer "F.Fab")
		)
		(fp_line
			(start 0.120396 0.3048)
			(end 0.120396 0.2794)
			(stroke
				(width 0.1)
				(type default)
			)
			(layer "F.Fab")
		)
		(fp_line
			(start 0.67945 0.3048)
			(end 0.120396 0.3048)
			(stroke
				(width 0.1)
				(type default)
			)
			(layer "F.Fab")
		)
		(fp_line
			(start -0.12065 0.2794)
			(end -0.12065 0.3048)
			(stroke
				(width 0.1)
				(type default)
			)
			(layer "F.Fab")
		)
		(fp_line
			(start 0.120396 0.2794)
			(end -0.12065 0.2794)
			(stroke
				(width 0.1)
				(type default)
			)
			(layer "F.Fab")
		)
		(fp_line
			(start -0.12065 -0.2794)
			(end 0.12065 -0.2794)
			(stroke
				(width 0.1)
				(type default)
			)
			(layer "F.Fab")
		)
		(fp_line
			(start 0.12065 -0.2794)
			(end 0.12065 -0.3048)
			(stroke
				(width 0.1)
				(type default)
			)
			(layer "F.Fab")
		)
		(fp_line
			(start 0.12065 -0.3048)
			(end 0.67945 -0.3048)
			(stroke
				(width 0.1)
				(type default)
			)
			(layer "F.Fab")
		)
		(fp_line
			(start 0.67945 -0.3048)
			(end 0.67945 0.3048)
			(stroke
				(width 0.1)
				(type default)
			)
			(layer "F.Fab")
		)
		(fp_line
			(start -0.67945 -0.305054)
			(end -0.12065 -0.305054)
			(stroke
				(width 0.1)
				(type default)
			)
			(layer "F.Fab")
		)
		(fp_line
			(start -0.12065 -0.305054)
			(end -0.12065 -0.2794)
			(stroke
				(width 0.1)
				(type default)
			)
			(layer "F.Fab")
		)
		(pad "1" smd circle
			(at -0.40005 0 270)
			(size 0 0)
			(layers "F.Cu" "F.Mask" "F.Paste")
			(net "GND")
		)
		(pad "2" smd circle
			(at 0.40005 0 270)
			(size 0 0)
			(layers "F.Cu" "F.Mask" "F.Paste")
			(net "P3V3_SSD7")
		)
	)
	(footprint ""
		(layer "F.Cu")
		(at 61.346842 -350.098614 90)
		(property "Reference" "C127"
			(at 0 0 90)
			(layer "F.SilkS")
			(hide yes)
			(effects
				(font
					(size 1.27 1.27)
				)
			)
		)
		(property "Value" ""
			(at 0 0 90)
			(layer "F.Fab")
			(effects
				(font
					(size 1.27 1.27)
				)
			)
		)
		(duplicate_pad_numbers_are_jumpers no)
		(fp_line
			(start 0.299974 -0.150114)
			(end 0.299974 0.150114)
			(stroke
				(width 0.1)
				(type default)
			)
			(layer "F.Fab")
		)
		(fp_line
			(start -0.299974 -0.150114)
			(end 0.299974 -0.150114)
			(stroke
				(width 0.1)
				(type default)
			)
			(layer "F.Fab")
		)
		(fp_line
			(start 0.299974 0.150114)
			(end -0.299974 0.150114)
			(stroke
				(width 0.1)
				(type default)
			)
			(layer "F.Fab")
		)
		(fp_line
			(start -0.299974 0.150114)
			(end -0.299974 -0.150114)
			(stroke
				(width 0.1)
				(type default)
			)
			(layer "F.Fab")
		)
		(pad "1" smd rect
			(at -0.2667 0 90)
			(size 0.3048 0.381)
			(layers "F.Cu" "F.Mask" "F.Paste")
			(net "P5E_PEX0_STN5_TX_DP<80>")
		)
		(pad "2" smd rect
			(at 0.2667 0 90)
			(size 0.3048 0.381)
			(layers "F.Cu" "F.Mask" "F.Paste")
			(net "P5E_PEX0_STN5_TX_C_DP<80>")
		)
	)
	(footprint ""
		(layer "F.Cu")
		(at 378.382022 -283.389832 180)
		(property "Reference" "C3584"
			(at 0 0 180)
			(layer "F.SilkS")
			(hide yes)
			(effects
				(font
					(size 1.27 1.27)
				)
			)
		)
		(property "Value" ""
			(at 0 0 180)
			(layer "F.Fab")
			(effects
				(font
					(size 1.27 1.27)
				)
			)
		)
		(duplicate_pad_numbers_are_jumpers no)
		(fp_line
			(start 1.2954 0.5842)
			(end -1.2954 0.5842)
			(stroke
				(width 0.1524)
				(type default)
			)
			(layer "F.SilkS")
		)
		(fp_line
			(start 1.2954 -0.5842)
			(end 1.2954 0.5842)
			(stroke
				(width 0.1524)
				(type default)
			)
			(layer "F.SilkS")
		)
		(fp_line
			(start -1.2954 0.5842)
			(end -1.2954 -0.5842)
			(stroke
				(width 0.1524)
				(type default)
			)
			(layer "F.SilkS")
		)
		(fp_line
			(start -1.2954 -0.5842)
			(end 1.2954 -0.5842)
			(stroke
				(width 0.1524)
				(type default)
			)
			(layer "F.SilkS")
		)
		(fp_line
			(start 1.1938 0.4064)
			(end 0.8636 0.4064)
			(stroke
				(width 0.1)
				(type default)
			)
			(layer "F.Fab")
		)
		(fp_line
			(start 1.1938 -0.4064)
			(end 1.1938 0.4064)
			(stroke
				(width 0.1)
				(type default)
			)
			(layer "F.Fab")
		)
		(fp_line
			(start 0.8636 0.4572)
			(end -0.8636 0.4572)
			(stroke
				(width 0.1)
				(type default)
			)
			(layer "F.Fab")
		)
		(fp_line
			(start 0.8636 0.4064)
			(end 0.8636 0.4572)
			(stroke
				(width 0.1)
				(type default)
			)
			(layer "F.Fab")
		)
		(fp_line
			(start 0.8636 -0.4064)
			(end 1.1938 -0.4064)
			(stroke
				(width 0.1)
				(type default)
			)
			(layer "F.Fab")
		)
		(fp_line
			(start 0.8636 -0.4572)
			(end 0.8636 -0.4064)
			(stroke
				(width 0.1)
				(type default)
			)
			(layer "F.Fab")
		)
		(fp_line
			(start -0.8636 0.4572)
			(end -0.8636 0.4064)
			(stroke
				(width 0.1)
				(type default)
			)
			(layer "F.Fab")
		)
		(fp_line
			(start -0.8636 0.4064)
			(end -1.1938 0.4064)
			(stroke
				(width 0.1)
				(type default)
			)
			(layer "F.Fab")
		)
		(fp_line
			(start -0.8636 -0.4064)
			(end -0.8636 -0.4572)
			(stroke
				(width 0.1)
				(type default)
			)
			(layer "F.Fab")
		)
		(fp_line
			(start -0.8636 -0.4572)
			(end 0.8636 -0.4572)
			(stroke
				(width 0.1)
				(type default)
			)
			(layer "F.Fab")
		)
		(fp_line
			(start -1.1938 0.4064)
			(end -1.1938 -0.4064)
			(stroke
				(width 0.1)
				(type default)
			)
			(layer "F.Fab")
		)
		(fp_line
			(start -1.1938 -0.4064)
			(end -0.8636 -0.4064)
			(stroke
				(width 0.1)
				(type default)
			)
			(layer "F.Fab")
		)
		(pad "1" smd rect
			(at -0.7366 0 90)
			(size 0.7112 0.8128)
			(layers "F.Cu" "F.Mask" "F.Paste")
			(net "PCEPLL7_VDDA18_PEX3_R")
		)
		(pad "2" smd rect
			(at 0.7366 0 90)
			(size 0.7112 0.8128)
			(layers "F.Cu" "F.Mask" "F.Paste")
			(net "GND")
		)
	)
	(footprint ""
		(layer "F.Cu")
		(at 445.022478 -44.341542 90)
		(property "Reference" "R679"
			(at 0 0 90)
			(layer "F.SilkS")
			(hide yes)
			(effects
				(font
					(size 1.27 1.27)
				)
			)
		)
		(property "Value" ""
			(at 0 0 90)
			(layer "F.Fab")
			(effects
				(font
					(size 1.27 1.27)
				)
			)
		)
		(duplicate_pad_numbers_are_jumpers no)
		(fp_line
			(start 0.7874 -0.4064)
			(end 0.7874 0.4064)
			(stroke
				(width 0.1524)
				(type default)
			)
			(layer "F.SilkS")
		)
		(fp_line
			(start -0.7874 -0.4064)
			(end 0.7874 -0.4064)
			(stroke
				(width 0.1524)
				(type default)
			)
			(layer "F.SilkS")
		)
		(fp_line
			(start 0.7874 0.4064)
			(end -0.7874 0.4064)
			(stroke
				(width 0.1524)
				(type default)
			)
			(layer "F.SilkS")
		)
		(fp_line
			(start -0.7874 0.4064)
			(end -0.7874 -0.4064)
			(stroke
				(width 0.1524)
				(type default)
			)
			(layer "F.SilkS")
		)
		(fp_line
			(start -0.12065 -0.305054)
			(end -0.12065 -0.2794)
			(stroke
				(width 0.1)
				(type default)
			)
			(layer "F.Fab")
		)
		(fp_line
			(start -0.67945 -0.305054)
			(end -0.12065 -0.305054)
			(stroke
				(width 0.1)
				(type default)
			)
			(layer "F.Fab")
		)
		(fp_line
			(start 0.67945 -0.3048)
			(end 0.67945 0.3048)
			(stroke
				(width 0.1)
				(type default)
			)
			(layer "F.Fab")
		)
		(fp_line
			(start 0.12065 -0.3048)
			(end 0.67945 -0.3048)
			(stroke
				(width 0.1)
				(type default)
			)
			(layer "F.Fab")
		)
		(fp_line
			(start 0.12065 -0.2794)
			(end 0.12065 -0.3048)
			(stroke
				(width 0.1)
				(type default)
			)
			(layer "F.Fab")
		)
		(fp_line
			(start -0.12065 -0.2794)
			(end 0.12065 -0.2794)
			(stroke
				(width 0.1)
				(type default)
			)
			(layer "F.Fab")
		)
		(fp_line
			(start 0.120396 0.2794)
			(end -0.12065 0.2794)
			(stroke
				(width 0.1)
				(type default)
			)
			(layer "F.Fab")
		)
		(fp_line
			(start -0.12065 0.2794)
			(end -0.12065 0.3048)
			(stroke
				(width 0.1)
				(type default)
			)
			(layer "F.Fab")
		)
		(fp_line
			(start 0.67945 0.3048)
			(end 0.120396 0.3048)
			(stroke
				(width 0.1)
				(type default)
			)
			(layer "F.Fab")
		)
		(fp_line
			(start 0.120396 0.3048)
			(end 0.120396 0.2794)
			(stroke
				(width 0.1)
				(type default)
			)
			(layer "F.Fab")
		)
		(fp_line
			(start -0.12065 0.3048)
			(end -0.67945 0.3048)
			(stroke
				(width 0.1)
				(type default)
			)
			(layer "F.Fab")
		)
		(fp_line
			(start -0.67945 0.3048)
			(end -0.67945 -0.305054)
			(stroke
				(width 0.1)
				(type default)
			)
			(layer "F.Fab")
		)
		(pad "1" smd circle
			(at -0.40005 0 90)
			(size 0 0)
			(layers "F.Cu" "F.Mask" "F.Paste")
			(net "P12V_SSD15")
		)
		(pad "2" smd circle
			(at 0.40005 0 90)
			(size 0 0)
			(layers "F.Cu" "F.Mask" "F.Paste")
			(net "P12V_SSD15_VIN_N")
		)
	)
	(footprint ""
		(layer "F.Cu")
		(at 454.955148 -50.981864 180)
		(property "Reference" "R1755"
			(at 0 0 180)
			(layer "F.SilkS")
			(hide yes)
			(effects
				(font
					(size 1.27 1.27)
				)
			)
		)
		(property "Value" ""
			(at 0 0 180)
			(layer "F.Fab")
			(effects
				(font
					(size 1.27 1.27)
				)
			)
		)
		(duplicate_pad_numbers_are_jumpers no)
		(fp_line
			(start 0.7874 0.4064)
			(end -0.7874 0.4064)
			(stroke
				(width 0.1524)
				(type default)
			)
			(layer "F.SilkS")
		)
		(fp_line
			(start 0.7874 -0.4064)
			(end 0.7874 0.4064)
			(stroke
				(width 0.1524)
				(type default)
			)
			(layer "F.SilkS")
		)
		(fp_line
			(start -0.7874 0.4064)
			(end -0.7874 -0.4064)
			(stroke
				(width 0.1524)
				(type default)
			)
			(layer "F.SilkS")
		)
		(fp_line
			(start -0.7874 -0.4064)
			(end 0.7874 -0.4064)
			(stroke
				(width 0.1524)
				(type default)
			)
			(layer "F.SilkS")
		)
		(fp_line
			(start 0.67945 0.3048)
			(end 0.120396 0.3048)
			(stroke
				(width 0.1)
				(type default)
			)
			(layer "F.Fab")
		)
		(fp_line
			(start 0.67945 -0.3048)
			(end 0.67945 0.3048)
			(stroke
				(width 0.1)
				(type default)
			)
			(layer "F.Fab")
		)
		(fp_line
			(start 0.12065 -0.2794)
			(end 0.12065 -0.3048)
			(stroke
				(width 0.1)
				(type default)
			)
			(layer "F.Fab")
		)
		(fp_line
			(start 0.12065 -0.3048)
			(end 0.67945 -0.3048)
			(stroke
				(width 0.1)
				(type default)
			)
			(layer "F.Fab")
		)
		(fp_line
			(start 0.120396 0.3048)
			(end 0.120396 0.2794)
			(stroke
				(width 0.1)
				(type default)
			)
			(layer "F.Fab")
		)
		(fp_line
			(start 0.120396 0.2794)
			(end -0.12065 0.2794)
			(stroke
				(width 0.1)
				(type default)
			)
			(layer "F.Fab")
		)
		(fp_line
			(start -0.12065 0.3048)
			(end -0.67945 0.3048)
			(stroke
				(width 0.1)
				(type default)
			)
			(layer "F.Fab")
		)
		(fp_line
			(start -0.12065 0.2794)
			(end -0.12065 0.3048)
			(stroke
				(width 0.1)
				(type default)
			)
			(layer "F.Fab")
		)
		(fp_line
			(start -0.12065 -0.2794)
			(end 0.12065 -0.2794)
			(stroke
				(width 0.1)
				(type default)
			)
			(layer "F.Fab")
		)
		(fp_line
			(start -0.12065 -0.305054)
			(end -0.12065 -0.2794)
			(stroke
				(width 0.1)
				(type default)
			)
			(layer "F.Fab")
		)
		(fp_line
			(start -0.67945 0.3048)
			(end -0.67945 -0.305054)
			(stroke
				(width 0.1)
				(type default)
			)
			(layer "F.Fab")
		)
		(fp_line
			(start -0.67945 -0.305054)
			(end -0.12065 -0.305054)
			(stroke
				(width 0.1)
				(type default)
			)
			(layer "F.Fab")
		)
		(pad "1" smd circle
			(at -0.40005 0 180)
			(size 0 0)
			(layers "F.Cu" "F.Mask" "F.Paste")
			(net "P3V3_AUX")
		)
		(pad "2" smd circle
			(at 0.40005 0 180)
			(size 0 0)
			(layers "F.Cu" "F.Mask" "F.Paste")
			(net "SMB_BIC_I2C6_MUX_SSD_8_15_ADC_R_SCL")
		)
	)
	(footprint ""
		(layer "F.Cu")
		(at 464.654646 -526.370296 180)
		(property "Reference" "SCREW_SSD5_2"
			(at -5.207 -1.402334 0)
			(unlocked yes)
			(layer "B.SilkS")
			(effects
				(font
					(size 0.7874 0.5842)
					(thickness 0.1524)
				)
				(justify mirror)
			)
		)
		(property "Value" ""
			(at 0 0 180)
			(layer "F.Fab")
			(effects
				(font
					(size 1.27 1.27)
				)
			)
		)
		(duplicate_pad_numbers_are_jumpers no)
		(pad "1" thru_hole circle
			(at 0 0 180)
			(size 0.4572 0.4572)
			(drill 0.2032)
			(layers "*.Cu" "*.Mask")
			(remove_unused_layers no)
			(net "Net_9133")
			(clearance 0.127)
			(thermal_gap 0.127)
			(padstack
				(mode front_inner_back)
				(layer "Inner"
					(shape circle)
					(size 0.4572 0.4572)
					(clearance 0.127)
				)
				(layer "B.Cu"
					(shape circle)
					(size 0.508 0.508)
					(clearance 0.1016)
				)
			)
		)
	)
	(footprint ""
		(layer "F.Cu")
		(at 344.481404 -343.952322 90)
		(property "Reference" "C580"
			(at 0 0 90)
			(layer "F.SilkS")
			(hide yes)
			(effects
				(font
					(size 1.27 1.27)
				)
			)
		)
		(property "Value" ""
			(at 0 0 90)
			(layer "F.Fab")
			(effects
				(font
					(size 1.27 1.27)
				)
			)
		)
		(duplicate_pad_numbers_are_jumpers no)
		(fp_line
			(start 0.299974 -0.150114)
			(end 0.299974 0.150114)
			(stroke
				(width 0.1)
				(type default)
			)
			(layer "F.Fab")
		)
		(fp_line
			(start -0.299974 -0.150114)
			(end 0.299974 -0.150114)
			(stroke
				(width 0.1)
				(type default)
			)
			(layer "F.Fab")
		)
		(fp_line
			(start 0.299974 0.150114)
			(end -0.299974 0.150114)
			(stroke
				(width 0.1)
				(type default)
			)
			(layer "F.Fab")
		)
		(fp_line
			(start -0.299974 0.150114)
			(end -0.299974 -0.150114)
			(stroke
				(width 0.1)
				(type default)
			)
			(layer "F.Fab")
		)
		(pad "1" smd rect
			(at -0.2667 0 90)
			(size 0.3048 0.381)
			(layers "F.Cu" "F.Mask" "F.Paste")
			(net "P5E_PEX2_STN6_TX_DN<97>")
		)
		(pad "2" smd rect
			(at 0.2667 0 90)
			(size 0.3048 0.381)
			(layers "F.Cu" "F.Mask" "F.Paste")
			(net "P5E_PEX2_STN6_TX_C_DN<97>")
		)
	)
	(footprint ""
		(layer "F.Cu")
		(at 28.823666 -306.366418 45)
		(property "Reference" "R1252"
			(at 0 0 45)
			(layer "F.SilkS")
			(hide yes)
			(effects
				(font
					(size 1.27 1.27)
				)
			)
		)
		(property "Value" ""
			(at 0 0 45)
			(layer "F.Fab")
			(effects
				(font
					(size 1.27 1.27)
				)
			)
		)
		(duplicate_pad_numbers_are_jumpers no)
		(fp_line
			(start -0.787389 -0.406267)
			(end 0.787389 -0.406267)
			(stroke
				(width 0.1524)
				(type default)
			)
			(layer "F.SilkS")
		)
		(fp_line
			(start -0.787389 0.406267)
			(end -0.787389 -0.406267)
			(stroke
				(width 0.1524)
				(type default)
			)
			(layer "F.SilkS")
		)
		(fp_line
			(start 0.787389 -0.406267)
			(end 0.787389 0.406267)
			(stroke
				(width 0.1524)
				(type default)
			)
			(layer "F.SilkS")
		)
		(fp_line
			(start 0.787389 0.406267)
			(end -0.787389 0.406267)
			(stroke
				(width 0.1524)
				(type default)
			)
			(layer "F.SilkS")
		)
		(fp_line
			(start -0.679446 -0.305149)
			(end -0.120695 -0.304969)
			(stroke
				(width 0.1)
				(type default)
			)
			(layer "F.Fab")
		)
		(fp_line
			(start -0.120695 -0.304969)
			(end -0.120695 -0.279466)
			(stroke
				(width 0.1)
				(type default)
			)
			(layer "F.Fab")
		)
		(fp_line
			(start -0.120695 -0.279466)
			(end 0.120695 -0.279466)
			(stroke
				(width 0.1)
				(type default)
			)
			(layer "F.Fab")
		)
		(fp_line
			(start -0.679446 0.30479)
			(end -0.679446 -0.305149)
			(stroke
				(width 0.1)
				(type default)
			)
			(layer "F.Fab")
		)
		(fp_line
			(start 0.120515 -0.30479)
			(end 0.679446 -0.30479)
			(stroke
				(width 0.1)
				(type default)
			)
			(layer "F.Fab")
		)
		(fp_line
			(start 0.120695 -0.279466)
			(end 0.120515 -0.30479)
			(stroke
				(width 0.1)
				(type default)
			)
			(layer "F.Fab")
		)
		(fp_line
			(start -0.120695 0.279466)
			(end -0.120515 0.30479)
			(stroke
				(width 0.1)
				(type default)
			)
			(layer "F.Fab")
		)
		(fp_line
			(start -0.120515 0.30479)
			(end -0.679446 0.30479)
			(stroke
				(width 0.1)
				(type default)
			)
			(layer "F.Fab")
		)
		(fp_line
			(start 0.679446 -0.30479)
			(end 0.679446 0.30479)
			(stroke
				(width 0.1)
				(type default)
			)
			(layer "F.Fab")
		)
		(fp_line
			(start 0.120335 0.279466)
			(end -0.120695 0.279466)
			(stroke
				(width 0.1)
				(type default)
			)
			(layer "F.Fab")
		)
		(fp_line
			(start 0.120515 0.30479)
			(end 0.120335 0.279466)
			(stroke
				(width 0.1)
				(type default)
			)
			(layer "F.Fab")
		)
		(fp_line
			(start 0.679446 0.30479)
			(end 0.120515 0.30479)
			(stroke
				(width 0.1)
				(type default)
			)
			(layer "F.Fab")
		)
		(pad "1" smd circle
			(at -0.40005 0 45)
			(size 0 0)
			(layers "F.Cu" "F.Mask" "F.Paste")
			(net "GND")
		)
		(pad "2" smd circle
			(at 0.40005 0 45)
			(size 0 0)
			(layers "F.Cu" "F.Mask" "F.Paste")
			(net "PEX0_DFT_IDDT")
		)
	)
	(footprint ""
		(layer "F.Cu")
		(at 405.14778 -40.037258 90)
		(property "Reference" "U376"
			(at 0.196342 2.37109 90)
			(unlocked yes)
			(layer "F.SilkS")
			(effects
				(font
					(size 0.7874 0.5842)
					(thickness 0.1524)
				)
			)
		)
		(property "Value" ""
			(at 0 0 90)
			(layer "F.Fab")
			(effects
				(font
					(size 1.27 1.27)
				)
			)
		)
		(duplicate_pad_numbers_are_jumpers no)
		(fp_line
			(start -1.949958 -1.610106)
			(end 1.949958 -1.610106)
			(stroke
				(width 0.1524)
				(type default)
			)
			(layer "F.SilkS")
		)
		(fp_line
			(start 1.949958 -1.560068)
			(end 1.949958 1.610106)
			(stroke
				(width 0.1524)
				(type default)
			)
			(layer "F.SilkS")
		)
		(fp_line
			(start 1.949958 1.610106)
			(end -1.949958 1.610106)
			(stroke
				(width 0.1524)
				(type default)
			)
			(layer "F.SilkS")
		)
		(fp_line
			(start -1.949958 1.610106)
			(end -1.949958 -1.610106)
			(stroke
				(width 0.1524)
				(type default)
			)
			(layer "F.SilkS")
		)
		(fp_line
			(start 0.750062 -1.560068)
			(end 0.750062 1.560068)
			(stroke
				(width 0.1)
				(type default)
			)
			(layer "F.Fab")
		)
		(fp_line
			(start -0.750062 -1.560068)
			(end 0.750062 -1.560068)
			(stroke
				(width 0.1)
				(type default)
			)
			(layer "F.Fab")
		)
		(fp_line
			(start 0.750062 1.560068)
			(end -0.750062 1.560068)
			(stroke
				(width 0.1)
				(type default)
			)
			(layer "F.Fab")
		)
		(fp_line
			(start -0.750062 1.560068)
			(end -0.750062 -1.560068)
			(stroke
				(width 0.1)
				(type default)
			)
			(layer "F.Fab")
		)
		(pad "D" smd rect
			(at 1.100074 0)
			(size 1.016 1.4224)
			(layers "F.Cu" "F.Mask" "F.Paste")
			(net "SSD14_AUX_P3V3_EN")
		)
		(pad "G" smd rect
			(at -1.100074 -0.94996)
			(size 1.016 1.4224)
			(layers "F.Cu" "F.Mask" "F.Paste")
			(net "PRSNT_SSD14_R1_N")
		)
		(pad "S" smd rect
			(at -1.100074 0.94996)
			(size 1.016 1.4224)
			(layers "F.Cu" "F.Mask" "F.Paste")
			(net "GND")
		)
	)
	(footprint ""
		(layer "F.Cu")
		(at 228.305614 -284.252162)
		(property "Reference" "PC239"
			(at 0 0 0)
			(layer "F.SilkS")
			(hide yes)
			(effects
				(font
					(size 1.27 1.27)
				)
			)
		)
		(property "Value" ""
			(at 0 0 0)
			(layer "F.Fab")
			(effects
				(font
					(size 1.27 1.27)
				)
			)
		)
		(duplicate_pad_numbers_are_jumpers no)
		(fp_line
			(start -2.750058 -1.988058)
			(end -2.750058 -0.9398)
			(stroke
				(width 0.1524)
				(type default)
			)
			(layer "F.SilkS")
		)
		(fp_line
			(start -2.750058 0.9398)
			(end -2.750058 1.988058)
			(stroke
				(width 0.1524)
				(type default)
			)
			(layer "F.SilkS")
		)
		(fp_line
			(start -2.750058 1.988058)
			(end -1.988058 2.750058)
			(stroke
				(width 0.1524)
				(type default)
			)
			(layer "F.SilkS")
		)
		(fp_line
			(start -1.988058 -2.750058)
			(end -2.750058 -1.988058)
			(stroke
				(width 0.1524)
				(type default)
			)
			(layer "F.SilkS")
		)
		(fp_line
			(start -1.988058 2.750058)
			(end 2.750058 2.750058)
			(stroke
				(width 0.1524)
				(type default)
			)
			(layer "F.SilkS")
		)
		(fp_line
			(start 2.750058 -2.750058)
			(end -1.988058 -2.750058)
			(stroke
				(width 0.1524)
				(type default)
			)
			(layer "F.SilkS")
		)
		(fp_line
			(start 2.750058 -0.9398)
			(end 2.750058 -2.750058)
			(stroke
				(width 0.1524)
				(type default)
			)
			(layer "F.SilkS")
		)
		(fp_line
			(start 2.750058 2.750058)
			(end 2.750058 0.9398)
			(stroke
				(width 0.1524)
				(type default)
			)
			(layer "F.SilkS")
		)
		(fp_line
			(start -2.750058 -2.750058)
			(end -2.750058 2.750058)
			(stroke
				(width 0.1)
				(type default)
			)
			(layer "F.Fab")
		)
		(fp_line
			(start -2.750058 2.750058)
			(end 2.750058 2.750058)
			(stroke
				(width 0.1)
				(type default)
			)
			(layer "F.Fab")
		)
		(fp_line
			(start 2.750058 -2.750058)
			(end -2.750058 -2.750058)
			(stroke
				(width 0.1)
				(type default)
			)
			(layer "F.Fab")
		)
		(fp_line
			(start 2.750058 2.750058)
			(end 2.750058 -2.750058)
			(stroke
				(width 0.1)
				(type default)
			)
			(layer "F.Fab")
		)
		(pad "1" smd rect
			(at -2.199894 0 90)
			(size 1.6002 3.0226)
			(layers "F.Cu" "F.Mask" "F.Paste")
			(net "P1V25_PEX1_R")
		)
		(pad "2" smd rect
			(at 2.199894 0 90)
			(size 1.6002 3.0226)
			(layers "F.Cu" "F.Mask" "F.Paste")
			(net "GND")
		)
	)
	(footprint ""
		(layer "F.Cu")
		(at 434.057806 -299.04055 -90)
		(property "Reference" "C4188"
			(at 0 0 270)
			(layer "F.SilkS")
			(hide yes)
			(effects
				(font
					(size 1.27 1.27)
				)
			)
		)
		(property "Value" ""
			(at 0 0 270)
			(layer "F.Fab")
			(effects
				(font
					(size 1.27 1.27)
				)
			)
		)
		(duplicate_pad_numbers_are_jumpers no)
		(fp_line
			(start -0.7874 0.4064)
			(end -0.7874 -0.4064)
			(stroke
				(width 0.1524)
				(type default)
			)
			(layer "F.SilkS")
		)
		(fp_line
			(start 0.7874 0.4064)
			(end -0.7874 0.4064)
			(stroke
				(width 0.1524)
				(type default)
			)
			(layer "F.SilkS")
		)
		(fp_line
			(start -0.7874 -0.4064)
			(end 0.7874 -0.4064)
			(stroke
				(width 0.1524)
				(type default)
			)
			(layer "F.SilkS")
		)
		(fp_line
			(start 0.7874 -0.4064)
			(end 0.7874 0.4064)
			(stroke
				(width 0.1524)
				(type default)
			)
			(layer "F.SilkS")
		)
		(fp_line
			(start -0.67945 0.3048)
			(end -0.67945 -0.305054)
			(stroke
				(width 0.1)
				(type default)
			)
			(layer "F.Fab")
		)
		(fp_line
			(start -0.12065 0.3048)
			(end -0.67945 0.3048)
			(stroke
				(width 0.1)
				(type default)
			)
			(layer "F.Fab")
		)
		(fp_line
			(start 0.120396 0.3048)
			(end 0.120396 0.2794)
			(stroke
				(width 0.1)
				(type default)
			)
			(layer "F.Fab")
		)
		(fp_line
			(start 0.67945 0.3048)
			(end 0.120396 0.3048)
			(stroke
				(width 0.1)
				(type default)
			)
			(layer "F.Fab")
		)
		(fp_line
			(start -0.12065 0.2794)
			(end -0.12065 0.3048)
			(stroke
				(width 0.1)
				(type default)
			)
			(layer "F.Fab")
		)
		(fp_line
			(start 0.120396 0.2794)
			(end -0.12065 0.2794)
			(stroke
				(width 0.1)
				(type default)
			)
			(layer "F.Fab")
		)
		(fp_line
			(start -0.12065 -0.2794)
			(end 0.12065 -0.2794)
			(stroke
				(width 0.1)
				(type default)
			)
			(layer "F.Fab")
		)
		(fp_line
			(start 0.12065 -0.2794)
			(end 0.12065 -0.3048)
			(stroke
				(width 0.1)
				(type default)
			)
			(layer "F.Fab")
		)
		(fp_line
			(start 0.12065 -0.3048)
			(end 0.67945 -0.3048)
			(stroke
				(width 0.1)
				(type default)
			)
			(layer "F.Fab")
		)
		(fp_line
			(start 0.67945 -0.3048)
			(end 0.67945 0.3048)
			(stroke
				(width 0.1)
				(type default)
			)
			(layer "F.Fab")
		)
		(fp_line
			(start -0.67945 -0.305054)
			(end -0.12065 -0.305054)
			(stroke
				(width 0.1)
				(type default)
			)
			(layer "F.Fab")
		)
		(fp_line
			(start -0.12065 -0.305054)
			(end -0.12065 -0.2794)
			(stroke
				(width 0.1)
				(type default)
			)
			(layer "F.Fab")
		)
		(pad "1" smd circle
			(at -0.40005 0 270)
			(size 0 0)
			(layers "F.Cu" "F.Mask" "F.Paste")
			(net "GND")
		)
		(pad "2" smd circle
			(at 0.40005 0 270)
			(size 0 0)
			(layers "F.Cu" "F.Mask" "F.Paste")
			(net "P1V8_PEX")
		)
	)
	(footprint ""
		(layer "F.Cu")
		(at 95.79229 -29.139642 180)
		(property "Reference" "C95"
			(at 0 0 180)
			(layer "F.SilkS")
			(hide yes)
			(effects
				(font
					(size 1.27 1.27)
				)
			)
		)
		(property "Value" ""
			(at 0 0 180)
			(layer "F.Fab")
			(effects
				(font
					(size 1.27 1.27)
				)
			)
		)
		(duplicate_pad_numbers_are_jumpers no)
		(fp_line
			(start 0.299974 0.150114)
			(end -0.299974 0.150114)
			(stroke
				(width 0.1)
				(type default)
			)
			(layer "F.Fab")
		)
		(fp_line
			(start 0.299974 -0.150114)
			(end 0.299974 0.150114)
			(stroke
				(width 0.1)
				(type default)
			)
			(layer "F.Fab")
		)
		(fp_line
			(start -0.299974 0.150114)
			(end -0.299974 -0.150114)
			(stroke
				(width 0.1)
				(type default)
			)
			(layer "F.Fab")
		)
		(fp_line
			(start -0.299974 -0.150114)
			(end 0.299974 -0.150114)
			(stroke
				(width 0.1)
				(type default)
			)
			(layer "F.Fab")
		)
		(pad "1" smd rect
			(at -0.2667 0 180)
			(size 0.3048 0.381)
			(layers "F.Cu" "F.Mask" "F.Paste")
			(net "P5E_PEX0_STN2_TX_DP<32>")
		)
		(pad "2" smd rect
			(at 0.2667 0 180)
			(size 0.3048 0.381)
			(layers "F.Cu" "F.Mask" "F.Paste")
			(net "P5E_PEX0_STN2_TX_C_DP<32>")
		)
	)
	(footprint ""
		(layer "F.Cu")
		(at 93.350842 -343.952322 90)
		(property "Reference" "C158"
			(at 0 0 90)
			(layer "F.SilkS")
			(hide yes)
			(effects
				(font
					(size 1.27 1.27)
				)
			)
		)
		(property "Value" ""
			(at 0 0 90)
			(layer "F.Fab")
			(effects
				(font
					(size 1.27 1.27)
				)
			)
		)
		(duplicate_pad_numbers_are_jumpers no)
		(fp_line
			(start 0.299974 -0.150114)
			(end 0.299974 0.150114)
			(stroke
				(width 0.1)
				(type default)
			)
			(layer "F.Fab")
		)
		(fp_line
			(start -0.299974 -0.150114)
			(end 0.299974 -0.150114)
			(stroke
				(width 0.1)
				(type default)
			)
			(layer "F.Fab")
		)
		(fp_line
			(start 0.299974 0.150114)
			(end -0.299974 0.150114)
			(stroke
				(width 0.1)
				(type default)
			)
			(layer "F.Fab")
		)
		(fp_line
			(start -0.299974 0.150114)
			(end -0.299974 -0.150114)
			(stroke
				(width 0.1)
				(type default)
			)
			(layer "F.Fab")
		)
		(pad "1" smd rect
			(at -0.2667 0 90)
			(size 0.3048 0.381)
			(layers "F.Cu" "F.Mask" "F.Paste")
			(net "P5E_PEX0_STN6_TX_DN<97>")
		)
		(pad "2" smd rect
			(at 0.2667 0 90)
			(size 0.3048 0.381)
			(layers "F.Cu" "F.Mask" "F.Paste")
			(net "P5E_PEX0_STN6_TX_C_DN<97>")
		)
	)
	(footprint ""
		(layer "F.Cu")
		(at 314.861448 -135.28675 180)
		(property "Reference" "C440"
			(at 0 0 180)
			(layer "F.SilkS")
			(hide yes)
			(effects
				(font
					(size 1.27 1.27)
				)
			)
		)
		(property "Value" ""
			(at 0 0 180)
			(layer "F.Fab")
			(effects
				(font
					(size 1.27 1.27)
				)
			)
		)
		(duplicate_pad_numbers_are_jumpers no)
		(fp_line
			(start 0.299974 0.150114)
			(end -0.299974 0.150114)
			(stroke
				(width 0.1)
				(type default)
			)
			(layer "F.Fab")
		)
		(fp_line
			(start 0.299974 -0.150114)
			(end 0.299974 0.150114)
			(stroke
				(width 0.1)
				(type default)
			)
			(layer "F.Fab")
		)
		(fp_line
			(start -0.299974 0.150114)
			(end -0.299974 -0.150114)
			(stroke
				(width 0.1)
				(type default)
			)
			(layer "F.Fab")
		)
		(fp_line
			(start -0.299974 -0.150114)
			(end 0.299974 -0.150114)
			(stroke
				(width 0.1)
				(type default)
			)
			(layer "F.Fab")
		)
		(pad "1" smd rect
			(at -0.2667 0 180)
			(size 0.3048 0.381)
			(layers "F.Cu" "F.Mask" "F.Paste")
			(net "P5E_PEX2_STN0_TX_DN<7>")
		)
		(pad "2" smd rect
			(at 0.2667 0 180)
			(size 0.3048 0.381)
			(layers "F.Cu" "F.Mask" "F.Paste")
			(net "P5E_PEX2_STN0_TX_C_DN<7>")
		)
	)
	(footprint ""
		(layer "F.Cu")
		(at 319.696084 -388.958836 180)
		(property "Reference" "R1851"
			(at 0 0 180)
			(layer "F.SilkS")
			(hide yes)
			(effects
				(font
					(size 1.27 1.27)
				)
			)
		)
		(property "Value" ""
			(at 0 0 180)
			(layer "F.Fab")
			(effects
				(font
					(size 1.27 1.27)
				)
			)
		)
		(duplicate_pad_numbers_are_jumpers no)
		(fp_line
			(start 0.7874 0.4064)
			(end -0.7874 0.4064)
			(stroke
				(width 0.1524)
				(type default)
			)
			(layer "F.SilkS")
		)
		(fp_line
			(start 0.7874 -0.4064)
			(end 0.7874 0.4064)
			(stroke
				(width 0.1524)
				(type default)
			)
			(layer "F.SilkS")
		)
		(fp_line
			(start -0.7874 0.4064)
			(end -0.7874 -0.4064)
			(stroke
				(width 0.1524)
				(type default)
			)
			(layer "F.SilkS")
		)
		(fp_line
			(start -0.7874 -0.4064)
			(end 0.7874 -0.4064)
			(stroke
				(width 0.1524)
				(type default)
			)
			(layer "F.SilkS")
		)
		(fp_line
			(start 0.67945 0.3048)
			(end 0.120396 0.3048)
			(stroke
				(width 0.1)
				(type default)
			)
			(layer "F.Fab")
		)
		(fp_line
			(start 0.67945 -0.3048)
			(end 0.67945 0.3048)
			(stroke
				(width 0.1)
				(type default)
			)
			(layer "F.Fab")
		)
		(fp_line
			(start 0.12065 -0.2794)
			(end 0.12065 -0.3048)
			(stroke
				(width 0.1)
				(type default)
			)
			(layer "F.Fab")
		)
		(fp_line
			(start 0.12065 -0.3048)
			(end 0.67945 -0.3048)
			(stroke
				(width 0.1)
				(type default)
			)
			(layer "F.Fab")
		)
		(fp_line
			(start 0.120396 0.3048)
			(end 0.120396 0.2794)
			(stroke
				(width 0.1)
				(type default)
			)
			(layer "F.Fab")
		)
		(fp_line
			(start 0.120396 0.2794)
			(end -0.12065 0.2794)
			(stroke
				(width 0.1)
				(type default)
			)
			(layer "F.Fab")
		)
		(fp_line
			(start -0.12065 0.3048)
			(end -0.67945 0.3048)
			(stroke
				(width 0.1)
				(type default)
			)
			(layer "F.Fab")
		)
		(fp_line
			(start -0.12065 0.2794)
			(end -0.12065 0.3048)
			(stroke
				(width 0.1)
				(type default)
			)
			(layer "F.Fab")
		)
		(fp_line
			(start -0.12065 -0.2794)
			(end 0.12065 -0.2794)
			(stroke
				(width 0.1)
				(type default)
			)
			(layer "F.Fab")
		)
		(fp_line
			(start -0.12065 -0.305054)
			(end -0.12065 -0.2794)
			(stroke
				(width 0.1)
				(type default)
			)
			(layer "F.Fab")
		)
		(fp_line
			(start -0.67945 0.3048)
			(end -0.67945 -0.305054)
			(stroke
				(width 0.1)
				(type default)
			)
			(layer "F.Fab")
		)
		(fp_line
			(start -0.67945 -0.305054)
			(end -0.12065 -0.305054)
			(stroke
				(width 0.1)
				(type default)
			)
			(layer "F.Fab")
		)
		(pad "1" smd circle
			(at -0.40005 0 180)
			(size 0 0)
			(layers "F.Cu" "F.Mask" "F.Paste")
			(net "GPU_3V3IO_RSVD5_FFU_R")
		)
		(pad "2" smd circle
			(at 0.40005 0 180)
			(size 0 0)
			(layers "F.Cu" "F.Mask" "F.Paste")
			(net "GPU_3V3IO_RSVD5_FFU")
		)
	)
	(footprint ""
		(layer "F.Cu")
		(at 396.94866 -356.244906 90)
		(property "Reference" "C737"
			(at 0 0 90)
			(layer "F.SilkS")
			(hide yes)
			(effects
				(font
					(size 1.27 1.27)
				)
			)
		)
		(property "Value" ""
			(at 0 0 90)
			(layer "F.Fab")
			(effects
				(font
					(size 1.27 1.27)
				)
			)
		)
		(duplicate_pad_numbers_are_jumpers no)
		(fp_line
			(start 0.299974 -0.150114)
			(end 0.299974 0.150114)
			(stroke
				(width 0.1)
				(type default)
			)
			(layer "F.Fab")
		)
		(fp_line
			(start -0.299974 -0.150114)
			(end 0.299974 -0.150114)
			(stroke
				(width 0.1)
				(type default)
			)
			(layer "F.Fab")
		)
		(fp_line
			(start 0.299974 0.150114)
			(end -0.299974 0.150114)
			(stroke
				(width 0.1)
				(type default)
			)
			(layer "F.Fab")
		)
		(fp_line
			(start -0.299974 0.150114)
			(end -0.299974 -0.150114)
			(stroke
				(width 0.1)
				(type default)
			)
			(layer "F.Fab")
		)
		(pad "1" smd rect
			(at -0.2667 0 90)
			(size 0.3048 0.381)
			(layers "F.Cu" "F.Mask" "F.Paste")
			(net "P5E_PEX3_STN5_TX_DN<92>")
		)
		(pad "2" smd rect
			(at 0.2667 0 90)
			(size 0.3048 0.381)
			(layers "F.Cu" "F.Mask" "F.Paste")
			(net "P5E_PEX3_STN5_TX_C_DN<92>")
		)
	)
	(footprint ""
		(layer "F.Cu")
		(at 352.920554 -87.216234)
		(property "Reference" "R1619"
			(at 0 0 0)
			(layer "F.SilkS")
			(hide yes)
			(effects
				(font
					(size 1.27 1.27)
				)
			)
		)
		(property "Value" ""
			(at 0 0 0)
			(layer "F.Fab")
			(effects
				(font
					(size 1.27 1.27)
				)
			)
		)
		(duplicate_pad_numbers_are_jumpers no)
		(fp_line
			(start -0.7874 -0.4064)
			(end 0.7874 -0.4064)
			(stroke
				(width 0.1524)
				(type default)
			)
			(layer "F.SilkS")
		)
		(fp_line
			(start -0.7874 0.4064)
			(end -0.7874 -0.4064)
			(stroke
				(width 0.1524)
				(type default)
			)
			(layer "F.SilkS")
		)
		(fp_line
			(start 0.7874 -0.4064)
			(end 0.7874 0.4064)
			(stroke
				(width 0.1524)
				(type default)
			)
			(layer "F.SilkS")
		)
		(fp_line
			(start 0.7874 0.4064)
			(end -0.7874 0.4064)
			(stroke
				(width 0.1524)
				(type default)
			)
			(layer "F.SilkS")
		)
		(fp_line
			(start -0.67945 -0.305054)
			(end -0.12065 -0.305054)
			(stroke
				(width 0.1)
				(type default)
			)
			(layer "F.Fab")
		)
		(fp_line
			(start -0.67945 0.3048)
			(end -0.67945 -0.305054)
			(stroke
				(width 0.1)
				(type default)
			)
			(layer "F.Fab")
		)
		(fp_line
			(start -0.12065 -0.305054)
			(end -0.12065 -0.2794)
			(stroke
				(width 0.1)
				(type default)
			)
			(layer "F.Fab")
		)
		(fp_line
			(start -0.12065 -0.2794)
			(end 0.12065 -0.2794)
			(stroke
				(width 0.1)
				(type default)
			)
			(layer "F.Fab")
		)
		(fp_line
			(start -0.12065 0.2794)
			(end -0.12065 0.3048)
			(stroke
				(width 0.1)
				(type default)
			)
			(layer "F.Fab")
		)
		(fp_line
			(start -0.12065 0.3048)
			(end -0.67945 0.3048)
			(stroke
				(width 0.1)
				(type default)
			)
			(layer "F.Fab")
		)
		(fp_line
			(start 0.120396 0.2794)
			(end -0.12065 0.2794)
			(stroke
				(width 0.1)
				(type default)
			)
			(layer "F.Fab")
		)
		(fp_line
			(start 0.120396 0.3048)
			(end 0.120396 0.2794)
			(stroke
				(width 0.1)
				(type default)
			)
			(layer "F.Fab")
		)
		(fp_line
			(start 0.12065 -0.3048)
			(end 0.67945 -0.3048)
			(stroke
				(width 0.1)
				(type default)
			)
			(layer "F.Fab")
		)
		(fp_line
			(start 0.12065 -0.2794)
			(end 0.12065 -0.3048)
			(stroke
				(width 0.1)
				(type default)
			)
			(layer "F.Fab")
		)
		(fp_line
			(start 0.67945 -0.3048)
			(end 0.67945 0.3048)
			(stroke
				(width 0.1)
				(type default)
			)
			(layer "F.Fab")
		)
		(fp_line
			(start 0.67945 0.3048)
			(end 0.120396 0.3048)
			(stroke
				(width 0.1)
				(type default)
			)
			(layer "F.Fab")
		)
		(pad "1" smd circle
			(at -0.40005 0)
			(size 0 0)
			(layers "F.Cu" "F.Mask" "F.Paste")
			(net "SMB_BIC_I2C9_MUX1_SSD9_R_SDA")
		)
		(pad "2" smd circle
			(at 0.40005 0)
			(size 0 0)
			(layers "F.Cu" "F.Mask" "F.Paste")
			(net "SMB_BIC_I2C9_MUX1_SSD9_SDA")
		)
	)
	(footprint ""
		(layer "F.Cu")
		(at 323.917818 -225.929698 180)
		(property "Reference" "R2978"
			(at 0 0 180)
			(layer "F.SilkS")
			(hide yes)
			(effects
				(font
					(size 1.27 1.27)
				)
			)
		)
		(property "Value" ""
			(at 0 0 180)
			(layer "F.Fab")
			(effects
				(font
					(size 1.27 1.27)
				)
			)
		)
		(duplicate_pad_numbers_are_jumpers no)
		(fp_line
			(start 0.7874 0.4064)
			(end -0.7874 0.4064)
			(stroke
				(width 0.1524)
				(type default)
			)
			(layer "F.SilkS")
		)
		(fp_line
			(start 0.7874 -0.4064)
			(end 0.7874 0.4064)
			(stroke
				(width 0.1524)
				(type default)
			)
			(layer "F.SilkS")
		)
		(fp_line
			(start -0.7874 0.4064)
			(end -0.7874 -0.4064)
			(stroke
				(width 0.1524)
				(type default)
			)
			(layer "F.SilkS")
		)
		(fp_line
			(start -0.7874 -0.4064)
			(end 0.7874 -0.4064)
			(stroke
				(width 0.1524)
				(type default)
			)
			(layer "F.SilkS")
		)
		(fp_line
			(start 0.67945 0.3048)
			(end 0.120396 0.3048)
			(stroke
				(width 0.1)
				(type default)
			)
			(layer "F.Fab")
		)
		(fp_line
			(start 0.67945 -0.3048)
			(end 0.67945 0.3048)
			(stroke
				(width 0.1)
				(type default)
			)
			(layer "F.Fab")
		)
		(fp_line
			(start 0.12065 -0.2794)
			(end 0.12065 -0.3048)
			(stroke
				(width 0.1)
				(type default)
			)
			(layer "F.Fab")
		)
		(fp_line
			(start 0.12065 -0.3048)
			(end 0.67945 -0.3048)
			(stroke
				(width 0.1)
				(type default)
			)
			(layer "F.Fab")
		)
		(fp_line
			(start 0.120396 0.3048)
			(end 0.120396 0.2794)
			(stroke
				(width 0.1)
				(type default)
			)
			(layer "F.Fab")
		)
		(fp_line
			(start 0.120396 0.2794)
			(end -0.12065 0.2794)
			(stroke
				(width 0.1)
				(type default)
			)
			(layer "F.Fab")
		)
		(fp_line
			(start -0.12065 0.3048)
			(end -0.67945 0.3048)
			(stroke
				(width 0.1)
				(type default)
			)
			(layer "F.Fab")
		)
		(fp_line
			(start -0.12065 0.2794)
			(end -0.12065 0.3048)
			(stroke
				(width 0.1)
				(type default)
			)
			(layer "F.Fab")
		)
		(fp_line
			(start -0.12065 -0.2794)
			(end 0.12065 -0.2794)
			(stroke
				(width 0.1)
				(type default)
			)
			(layer "F.Fab")
		)
		(fp_line
			(start -0.12065 -0.305054)
			(end -0.12065 -0.2794)
			(stroke
				(width 0.1)
				(type default)
			)
			(layer "F.Fab")
		)
		(fp_line
			(start -0.67945 0.3048)
			(end -0.67945 -0.305054)
			(stroke
				(width 0.1)
				(type default)
			)
			(layer "F.Fab")
		)
		(fp_line
			(start -0.67945 -0.305054)
			(end -0.12065 -0.305054)
			(stroke
				(width 0.1)
				(type default)
			)
			(layer "F.Fab")
		)
		(pad "1" smd circle
			(at -0.40005 0 180)
			(size 0 0)
			(layers "F.Cu" "F.Mask" "F.Paste")
			(net "LED_POSTCODE_0")
		)
		(pad "2" smd circle
			(at 0.40005 0 180)
			(size 0 0)
			(layers "F.Cu" "F.Mask" "F.Paste")
			(net "LED_POSTCODE_R_0")
		)
	)
	(footprint ""
		(layer "F.Cu")
		(at 31.29407 -35.264852)
		(property "Reference" "R5651"
			(at 0 0 0)
			(layer "F.SilkS")
			(hide yes)
			(effects
				(font
					(size 1.27 1.27)
				)
			)
		)
		(property "Value" ""
			(at 0 0 0)
			(layer "F.Fab")
			(effects
				(font
					(size 1.27 1.27)
				)
			)
		)
		(duplicate_pad_numbers_are_jumpers no)
		(fp_line
			(start -0.7874 -0.4064)
			(end 0.7874 -0.4064)
			(stroke
				(width 0.1524)
				(type default)
			)
			(layer "F.SilkS")
		)
		(fp_line
			(start -0.7874 0.4064)
			(end -0.7874 -0.4064)
			(stroke
				(width 0.1524)
				(type default)
			)
			(layer "F.SilkS")
		)
		(fp_line
			(start 0.7874 -0.4064)
			(end 0.7874 0.4064)
			(stroke
				(width 0.1524)
				(type default)
			)
			(layer "F.SilkS")
		)
		(fp_line
			(start 0.7874 0.4064)
			(end -0.7874 0.4064)
			(stroke
				(width 0.1524)
				(type default)
			)
			(layer "F.SilkS")
		)
		(fp_line
			(start -0.67945 -0.305054)
			(end -0.12065 -0.305054)
			(stroke
				(width 0.1)
				(type default)
			)
			(layer "F.Fab")
		)
		(fp_line
			(start -0.67945 0.3048)
			(end -0.67945 -0.305054)
			(stroke
				(width 0.1)
				(type default)
			)
			(layer "F.Fab")
		)
		(fp_line
			(start -0.12065 -0.305054)
			(end -0.12065 -0.2794)
			(stroke
				(width 0.1)
				(type default)
			)
			(layer "F.Fab")
		)
		(fp_line
			(start -0.12065 -0.2794)
			(end 0.12065 -0.2794)
			(stroke
				(width 0.1)
				(type default)
			)
			(layer "F.Fab")
		)
		(fp_line
			(start -0.12065 0.2794)
			(end -0.12065 0.3048)
			(stroke
				(width 0.1)
				(type default)
			)
			(layer "F.Fab")
		)
		(fp_line
			(start -0.12065 0.3048)
			(end -0.67945 0.3048)
			(stroke
				(width 0.1)
				(type default)
			)
			(layer "F.Fab")
		)
		(fp_line
			(start 0.120396 0.2794)
			(end -0.12065 0.2794)
			(stroke
				(width 0.1)
				(type default)
			)
			(layer "F.Fab")
		)
		(fp_line
			(start 0.120396 0.3048)
			(end 0.120396 0.2794)
			(stroke
				(width 0.1)
				(type default)
			)
			(layer "F.Fab")
		)
		(fp_line
			(start 0.12065 -0.3048)
			(end 0.67945 -0.3048)
			(stroke
				(width 0.1)
				(type default)
			)
			(layer "F.Fab")
		)
		(fp_line
			(start 0.12065 -0.2794)
			(end 0.12065 -0.3048)
			(stroke
				(width 0.1)
				(type default)
			)
			(layer "F.Fab")
		)
		(fp_line
			(start 0.67945 -0.3048)
			(end 0.67945 0.3048)
			(stroke
				(width 0.1)
				(type default)
			)
			(layer "F.Fab")
		)
		(fp_line
			(start 0.67945 0.3048)
			(end 0.120396 0.3048)
			(stroke
				(width 0.1)
				(type default)
			)
			(layer "F.Fab")
		)
		(pad "1" smd circle
			(at -0.40005 0)
			(size 0 0)
			(layers "F.Cu" "F.Mask" "F.Paste")
			(net "RST_SMB_SSD1_ISO_N")
		)
		(pad "2" smd circle
			(at 0.40005 0)
			(size 0 0)
			(layers "F.Cu" "F.Mask" "F.Paste")
			(net "GND")
		)
	)
	(footprint ""
		(layer "F.Cu")
		(at 336.042 -172.085 180)
		(property "Reference" "R4764"
			(at 0 0 180)
			(layer "F.SilkS")
			(hide yes)
			(effects
				(font
					(size 1.27 1.27)
				)
			)
		)
		(property "Value" ""
			(at 0 0 180)
			(layer "F.Fab")
			(effects
				(font
					(size 1.27 1.27)
				)
			)
		)
		(duplicate_pad_numbers_are_jumpers no)
		(fp_line
			(start 0.7874 0.4064)
			(end -0.7874 0.4064)
			(stroke
				(width 0.1524)
				(type default)
			)
			(layer "F.SilkS")
		)
		(fp_line
			(start 0.7874 -0.4064)
			(end 0.7874 0.4064)
			(stroke
				(width 0.1524)
				(type default)
			)
			(layer "F.SilkS")
		)
		(fp_line
			(start -0.7874 0.4064)
			(end -0.7874 -0.4064)
			(stroke
				(width 0.1524)
				(type default)
			)
			(layer "F.SilkS")
		)
		(fp_line
			(start -0.7874 -0.4064)
			(end 0.7874 -0.4064)
			(stroke
				(width 0.1524)
				(type default)
			)
			(layer "F.SilkS")
		)
		(fp_line
			(start 0.67945 0.3048)
			(end 0.120396 0.3048)
			(stroke
				(width 0.1)
				(type default)
			)
			(layer "F.Fab")
		)
		(fp_line
			(start 0.67945 -0.3048)
			(end 0.67945 0.3048)
			(stroke
				(width 0.1)
				(type default)
			)
			(layer "F.Fab")
		)
		(fp_line
			(start 0.12065 -0.2794)
			(end 0.12065 -0.3048)
			(stroke
				(width 0.1)
				(type default)
			)
			(layer "F.Fab")
		)
		(fp_line
			(start 0.12065 -0.3048)
			(end 0.67945 -0.3048)
			(stroke
				(width 0.1)
				(type default)
			)
			(layer "F.Fab")
		)
		(fp_line
			(start 0.120396 0.3048)
			(end 0.120396 0.2794)
			(stroke
				(width 0.1)
				(type default)
			)
			(layer "F.Fab")
		)
		(fp_line
			(start 0.120396 0.2794)
			(end -0.12065 0.2794)
			(stroke
				(width 0.1)
				(type default)
			)
			(layer "F.Fab")
		)
		(fp_line
			(start -0.12065 0.3048)
			(end -0.67945 0.3048)
			(stroke
				(width 0.1)
				(type default)
			)
			(layer "F.Fab")
		)
		(fp_line
			(start -0.12065 0.2794)
			(end -0.12065 0.3048)
			(stroke
				(width 0.1)
				(type default)
			)
			(layer "F.Fab")
		)
		(fp_line
			(start -0.12065 -0.2794)
			(end 0.12065 -0.2794)
			(stroke
				(width 0.1)
				(type default)
			)
			(layer "F.Fab")
		)
		(fp_line
			(start -0.12065 -0.305054)
			(end -0.12065 -0.2794)
			(stroke
				(width 0.1)
				(type default)
			)
			(layer "F.Fab")
		)
		(fp_line
			(start -0.67945 0.3048)
			(end -0.67945 -0.305054)
			(stroke
				(width 0.1)
				(type default)
			)
			(layer "F.Fab")
		)
		(fp_line
			(start -0.67945 -0.305054)
			(end -0.12065 -0.305054)
			(stroke
				(width 0.1)
				(type default)
			)
			(layer "F.Fab")
		)
		(pad "1" smd circle
			(at -0.40005 0 180)
			(size 0 0)
			(layers "F.Cu" "F.Mask" "F.Paste")
			(net "PCA9555_1_PEX2_A2")
		)
		(pad "2" smd circle
			(at 0.40005 0 180)
			(size 0 0)
			(layers "F.Cu" "F.Mask" "F.Paste")
			(net "P3V3_AUX")
		)
	)
	(footprint ""
		(layer "F.Cu")
		(at 200.219056 -59.574684 90)
		(property "Reference" "PC528"
			(at 0 0 90)
			(layer "F.SilkS")
			(hide yes)
			(effects
				(font
					(size 1.27 1.27)
				)
			)
		)
		(property "Value" ""
			(at 0 0 90)
			(layer "F.Fab")
			(effects
				(font
					(size 1.27 1.27)
				)
			)
		)
		(duplicate_pad_numbers_are_jumpers no)
		(fp_line
			(start 0.7874 -0.4064)
			(end 0.7874 0.4064)
			(stroke
				(width 0.1524)
				(type default)
			)
			(layer "F.SilkS")
		)
		(fp_line
			(start -0.7874 -0.4064)
			(end 0.7874 -0.4064)
			(stroke
				(width 0.1524)
				(type default)
			)
			(layer "F.SilkS")
		)
		(fp_line
			(start 0.7874 0.4064)
			(end -0.7874 0.4064)
			(stroke
				(width 0.1524)
				(type default)
			)
			(layer "F.SilkS")
		)
		(fp_line
			(start -0.7874 0.4064)
			(end -0.7874 -0.4064)
			(stroke
				(width 0.1524)
				(type default)
			)
			(layer "F.SilkS")
		)
		(fp_line
			(start -0.12065 -0.305054)
			(end -0.12065 -0.2794)
			(stroke
				(width 0.1)
				(type default)
			)
			(layer "F.Fab")
		)
		(fp_line
			(start -0.67945 -0.305054)
			(end -0.12065 -0.305054)
			(stroke
				(width 0.1)
				(type default)
			)
			(layer "F.Fab")
		)
		(fp_line
			(start 0.67945 -0.3048)
			(end 0.67945 0.3048)
			(stroke
				(width 0.1)
				(type default)
			)
			(layer "F.Fab")
		)
		(fp_line
			(start 0.12065 -0.3048)
			(end 0.67945 -0.3048)
			(stroke
				(width 0.1)
				(type default)
			)
			(layer "F.Fab")
		)
		(fp_line
			(start 0.12065 -0.2794)
			(end 0.12065 -0.3048)
			(stroke
				(width 0.1)
				(type default)
			)
			(layer "F.Fab")
		)
		(fp_line
			(start -0.12065 -0.2794)
			(end 0.12065 -0.2794)
			(stroke
				(width 0.1)
				(type default)
			)
			(layer "F.Fab")
		)
		(fp_line
			(start 0.120396 0.2794)
			(end -0.12065 0.2794)
			(stroke
				(width 0.1)
				(type default)
			)
			(layer "F.Fab")
		)
		(fp_line
			(start -0.12065 0.2794)
			(end -0.12065 0.3048)
			(stroke
				(width 0.1)
				(type default)
			)
			(layer "F.Fab")
		)
		(fp_line
			(start 0.67945 0.3048)
			(end 0.120396 0.3048)
			(stroke
				(width 0.1)
				(type default)
			)
			(layer "F.Fab")
		)
		(fp_line
			(start 0.120396 0.3048)
			(end 0.120396 0.2794)
			(stroke
				(width 0.1)
				(type default)
			)
			(layer "F.Fab")
		)
		(fp_line
			(start -0.12065 0.3048)
			(end -0.67945 0.3048)
			(stroke
				(width 0.1)
				(type default)
			)
			(layer "F.Fab")
		)
		(fp_line
			(start -0.67945 0.3048)
			(end -0.67945 -0.305054)
			(stroke
				(width 0.1)
				(type default)
			)
			(layer "F.Fab")
		)
		(pad "1" smd circle
			(at -0.40005 0 90)
			(size 0 0)
			(layers "F.Cu" "F.Mask" "F.Paste")
			(net "P5V_AUX")
		)
		(pad "2" smd circle
			(at 0.40005 0 90)
			(size 0 0)
			(layers "F.Cu" "F.Mask" "F.Paste")
			(net "GND")
		)
	)
	(footprint ""
		(layer "F.Cu")
		(at 420.573962 -72.766682 90)
		(property "Reference" "PR7093"
			(at 0 0 90)
			(layer "F.SilkS")
			(hide yes)
			(effects
				(font
					(size 1.27 1.27)
				)
			)
		)
		(property "Value" ""
			(at 0 0 90)
			(layer "F.Fab")
			(effects
				(font
					(size 1.27 1.27)
				)
			)
		)
		(duplicate_pad_numbers_are_jumpers no)
		(fp_line
			(start 0.7874 -0.4064)
			(end 0.7874 0.4064)
			(stroke
				(width 0.1524)
				(type default)
			)
			(layer "F.SilkS")
		)
		(fp_line
			(start -0.7874 -0.4064)
			(end 0.7874 -0.4064)
			(stroke
				(width 0.1524)
				(type default)
			)
			(layer "F.SilkS")
		)
		(fp_line
			(start 0.7874 0.4064)
			(end -0.7874 0.4064)
			(stroke
				(width 0.1524)
				(type default)
			)
			(layer "F.SilkS")
		)
		(fp_line
			(start -0.7874 0.4064)
			(end -0.7874 -0.4064)
			(stroke
				(width 0.1524)
				(type default)
			)
			(layer "F.SilkS")
		)
		(fp_line
			(start -0.12065 -0.305054)
			(end -0.12065 -0.2794)
			(stroke
				(width 0.1)
				(type default)
			)
			(layer "F.Fab")
		)
		(fp_line
			(start -0.67945 -0.305054)
			(end -0.12065 -0.305054)
			(stroke
				(width 0.1)
				(type default)
			)
			(layer "F.Fab")
		)
		(fp_line
			(start 0.67945 -0.3048)
			(end 0.67945 0.3048)
			(stroke
				(width 0.1)
				(type default)
			)
			(layer "F.Fab")
		)
		(fp_line
			(start 0.12065 -0.3048)
			(end 0.67945 -0.3048)
			(stroke
				(width 0.1)
				(type default)
			)
			(layer "F.Fab")
		)
		(fp_line
			(start 0.12065 -0.2794)
			(end 0.12065 -0.3048)
			(stroke
				(width 0.1)
				(type default)
			)
			(layer "F.Fab")
		)
		(fp_line
			(start -0.12065 -0.2794)
			(end 0.12065 -0.2794)
			(stroke
				(width 0.1)
				(type default)
			)
			(layer "F.Fab")
		)
		(fp_line
			(start 0.120396 0.2794)
			(end -0.12065 0.2794)
			(stroke
				(width 0.1)
				(type default)
			)
			(layer "F.Fab")
		)
		(fp_line
			(start -0.12065 0.2794)
			(end -0.12065 0.3048)
			(stroke
				(width 0.1)
				(type default)
			)
			(layer "F.Fab")
		)
		(fp_line
			(start 0.67945 0.3048)
			(end 0.120396 0.3048)
			(stroke
				(width 0.1)
				(type default)
			)
			(layer "F.Fab")
		)
		(fp_line
			(start 0.120396 0.3048)
			(end 0.120396 0.2794)
			(stroke
				(width 0.1)
				(type default)
			)
			(layer "F.Fab")
		)
		(fp_line
			(start -0.12065 0.3048)
			(end -0.67945 0.3048)
			(stroke
				(width 0.1)
				(type default)
			)
			(layer "F.Fab")
		)
		(fp_line
			(start -0.67945 0.3048)
			(end -0.67945 -0.305054)
			(stroke
				(width 0.1)
				(type default)
			)
			(layer "F.Fab")
		)
		(pad "1" smd circle
			(at -0.40005 0 90)
			(size 0 0)
			(layers "F.Cu" "F.Mask" "F.Paste")
			(net "P12V_SSD14_CO_MODE")
		)
		(pad "2" smd circle
			(at 0.40005 0 90)
			(size 0 0)
			(layers "F.Cu" "F.Mask" "F.Paste")
			(net "GND")
		)
	)
	(footprint ""
		(layer "F.Cu")
		(at 295.852342 -350.098614 90)
		(property "Reference" "C2367"
			(at 0 0 90)
			(layer "F.SilkS")
			(hide yes)
			(effects
				(font
					(size 1.27 1.27)
				)
			)
		)
		(property "Value" ""
			(at 0 0 90)
			(layer "F.Fab")
			(effects
				(font
					(size 1.27 1.27)
				)
			)
		)
		(duplicate_pad_numbers_are_jumpers no)
		(fp_line
			(start 0.299974 -0.150114)
			(end 0.299974 0.150114)
			(stroke
				(width 0.1)
				(type default)
			)
			(layer "F.Fab")
		)
		(fp_line
			(start -0.299974 -0.150114)
			(end 0.299974 -0.150114)
			(stroke
				(width 0.1)
				(type default)
			)
			(layer "F.Fab")
		)
		(fp_line
			(start 0.299974 0.150114)
			(end -0.299974 0.150114)
			(stroke
				(width 0.1)
				(type default)
			)
			(layer "F.Fab")
		)
		(fp_line
			(start -0.299974 0.150114)
			(end -0.299974 -0.150114)
			(stroke
				(width 0.1)
				(type default)
			)
			(layer "F.Fab")
		)
		(pad "1" smd rect
			(at -0.2667 0 90)
			(size 0.3048 0.381)
			(layers "F.Cu" "F.Mask" "F.Paste")
			(net "P5E_PEX2_STN4_TX_DP<66>")
		)
		(pad "2" smd rect
			(at 0.2667 0 90)
			(size 0.3048 0.381)
			(layers "F.Cu" "F.Mask" "F.Paste")
			(net "P5E_PEX2_STN4_TX_C_DP<66>")
		)
	)
	(footprint ""
		(layer "F.Cu")
		(at 127.221996 -284.834838 90)
		(property "Reference" "PC109"
			(at 0 0 90)
			(layer "F.SilkS")
			(hide yes)
			(effects
				(font
					(size 1.27 1.27)
				)
			)
		)
		(property "Value" ""
			(at 0 0 90)
			(layer "F.Fab")
			(effects
				(font
					(size 1.27 1.27)
				)
			)
		)
		(duplicate_pad_numbers_are_jumpers no)
		(fp_line
			(start 0.7874 -0.4064)
			(end 0.7874 0.4064)
			(stroke
				(width 0.1524)
				(type default)
			)
			(layer "F.SilkS")
		)
		(fp_line
			(start -0.7874 -0.4064)
			(end 0.7874 -0.4064)
			(stroke
				(width 0.1524)
				(type default)
			)
			(layer "F.SilkS")
		)
		(fp_line
			(start 0.7874 0.4064)
			(end -0.7874 0.4064)
			(stroke
				(width 0.1524)
				(type default)
			)
			(layer "F.SilkS")
		)
		(fp_line
			(start -0.7874 0.4064)
			(end -0.7874 -0.4064)
			(stroke
				(width 0.1524)
				(type default)
			)
			(layer "F.SilkS")
		)
		(fp_line
			(start -0.12065 -0.305054)
			(end -0.12065 -0.2794)
			(stroke
				(width 0.1)
				(type default)
			)
			(layer "F.Fab")
		)
		(fp_line
			(start -0.67945 -0.305054)
			(end -0.12065 -0.305054)
			(stroke
				(width 0.1)
				(type default)
			)
			(layer "F.Fab")
		)
		(fp_line
			(start 0.67945 -0.3048)
			(end 0.67945 0.3048)
			(stroke
				(width 0.1)
				(type default)
			)
			(layer "F.Fab")
		)
		(fp_line
			(start 0.12065 -0.3048)
			(end 0.67945 -0.3048)
			(stroke
				(width 0.1)
				(type default)
			)
			(layer "F.Fab")
		)
		(fp_line
			(start 0.12065 -0.2794)
			(end 0.12065 -0.3048)
			(stroke
				(width 0.1)
				(type default)
			)
			(layer "F.Fab")
		)
		(fp_line
			(start -0.12065 -0.2794)
			(end 0.12065 -0.2794)
			(stroke
				(width 0.1)
				(type default)
			)
			(layer "F.Fab")
		)
		(fp_line
			(start 0.120396 0.2794)
			(end -0.12065 0.2794)
			(stroke
				(width 0.1)
				(type default)
			)
			(layer "F.Fab")
		)
		(fp_line
			(start -0.12065 0.2794)
			(end -0.12065 0.3048)
			(stroke
				(width 0.1)
				(type default)
			)
			(layer "F.Fab")
		)
		(fp_line
			(start 0.67945 0.3048)
			(end 0.120396 0.3048)
			(stroke
				(width 0.1)
				(type default)
			)
			(layer "F.Fab")
		)
		(fp_line
			(start 0.120396 0.3048)
			(end 0.120396 0.2794)
			(stroke
				(width 0.1)
				(type default)
			)
			(layer "F.Fab")
		)
		(fp_line
			(start -0.12065 0.3048)
			(end -0.67945 0.3048)
			(stroke
				(width 0.1)
				(type default)
			)
			(layer "F.Fab")
		)
		(fp_line
			(start -0.67945 0.3048)
			(end -0.67945 -0.305054)
			(stroke
				(width 0.1)
				(type default)
			)
			(layer "F.Fab")
		)
		(pad "1" smd circle
			(at -0.40005 0 90)
			(size 0 0)
			(layers "F.Cu" "F.Mask" "F.Paste")
			(net "SW_P12V_P0V8_PEX1_FLT")
		)
		(pad "2" smd circle
			(at 0.40005 0 90)
			(size 0 0)
			(layers "F.Cu" "F.Mask" "F.Paste")
			(net "GND")
		)
	)
	(footprint ""
		(layer "F.Cu")
		(at 206.623158 -88.993472)
		(property "Reference" "R5771"
			(at 0 0 0)
			(layer "F.SilkS")
			(hide yes)
			(effects
				(font
					(size 1.27 1.27)
				)
			)
		)
		(property "Value" ""
			(at 0 0 0)
			(layer "F.Fab")
			(effects
				(font
					(size 1.27 1.27)
				)
			)
		)
		(duplicate_pad_numbers_are_jumpers no)
		(fp_line
			(start -0.7874 -0.4064)
			(end 0.7874 -0.4064)
			(stroke
				(width 0.1524)
				(type default)
			)
			(layer "F.SilkS")
		)
		(fp_line
			(start -0.7874 0.4064)
			(end -0.7874 -0.4064)
			(stroke
				(width 0.1524)
				(type default)
			)
			(layer "F.SilkS")
		)
		(fp_line
			(start 0.7874 -0.4064)
			(end 0.7874 0.4064)
			(stroke
				(width 0.1524)
				(type default)
			)
			(layer "F.SilkS")
		)
		(fp_line
			(start 0.7874 0.4064)
			(end -0.7874 0.4064)
			(stroke
				(width 0.1524)
				(type default)
			)
			(layer "F.SilkS")
		)
		(fp_line
			(start -0.67945 -0.305054)
			(end -0.12065 -0.305054)
			(stroke
				(width 0.1)
				(type default)
			)
			(layer "F.Fab")
		)
		(fp_line
			(start -0.67945 0.3048)
			(end -0.67945 -0.305054)
			(stroke
				(width 0.1)
				(type default)
			)
			(layer "F.Fab")
		)
		(fp_line
			(start -0.12065 -0.305054)
			(end -0.12065 -0.2794)
			(stroke
				(width 0.1)
				(type default)
			)
			(layer "F.Fab")
		)
		(fp_line
			(start -0.12065 -0.2794)
			(end 0.12065 -0.2794)
			(stroke
				(width 0.1)
				(type default)
			)
			(layer "F.Fab")
		)
		(fp_line
			(start -0.12065 0.2794)
			(end -0.12065 0.3048)
			(stroke
				(width 0.1)
				(type default)
			)
			(layer "F.Fab")
		)
		(fp_line
			(start -0.12065 0.3048)
			(end -0.67945 0.3048)
			(stroke
				(width 0.1)
				(type default)
			)
			(layer "F.Fab")
		)
		(fp_line
			(start 0.120396 0.2794)
			(end -0.12065 0.2794)
			(stroke
				(width 0.1)
				(type default)
			)
			(layer "F.Fab")
		)
		(fp_line
			(start 0.120396 0.3048)
			(end 0.120396 0.2794)
			(stroke
				(width 0.1)
				(type default)
			)
			(layer "F.Fab")
		)
		(fp_line
			(start 0.12065 -0.3048)
			(end 0.67945 -0.3048)
			(stroke
				(width 0.1)
				(type default)
			)
			(layer "F.Fab")
		)
		(fp_line
			(start 0.12065 -0.2794)
			(end 0.12065 -0.3048)
			(stroke
				(width 0.1)
				(type default)
			)
			(layer "F.Fab")
		)
		(fp_line
			(start 0.67945 -0.3048)
			(end 0.67945 0.3048)
			(stroke
				(width 0.1)
				(type default)
			)
			(layer "F.Fab")
		)
		(fp_line
			(start 0.67945 0.3048)
			(end 0.120396 0.3048)
			(stroke
				(width 0.1)
				(type default)
			)
			(layer "F.Fab")
		)
		(pad "1" smd circle
			(at -0.40005 0)
			(size 0 0)
			(layers "F.Cu" "F.Mask" "F.Paste")
			(net "IRQ_SSD_LED_IOEXP_R_N")
		)
		(pad "2" smd circle
			(at 0.40005 0)
			(size 0 0)
			(layers "F.Cu" "F.Mask" "F.Paste")
			(net "IRQ_SSD_LED_IOEXP_N")
		)
	)
	(footprint ""
		(layer "F.Cu")
		(at 407.295096 -97.718372 180)
		(property "Reference" "R405"
			(at 0 0 180)
			(layer "F.SilkS")
			(hide yes)
			(effects
				(font
					(size 1.27 1.27)
				)
			)
		)
		(property "Value" ""
			(at 0 0 180)
			(layer "F.Fab")
			(effects
				(font
					(size 1.27 1.27)
				)
			)
		)
		(duplicate_pad_numbers_are_jumpers no)
		(fp_line
			(start 0.7874 0.4064)
			(end -0.7874 0.4064)
			(stroke
				(width 0.1524)
				(type default)
			)
			(layer "F.SilkS")
		)
		(fp_line
			(start 0.7874 -0.4064)
			(end 0.7874 0.4064)
			(stroke
				(width 0.1524)
				(type default)
			)
			(layer "F.SilkS")
		)
		(fp_line
			(start -0.7874 0.4064)
			(end -0.7874 -0.4064)
			(stroke
				(width 0.1524)
				(type default)
			)
			(layer "F.SilkS")
		)
		(fp_line
			(start -0.7874 -0.4064)
			(end 0.7874 -0.4064)
			(stroke
				(width 0.1524)
				(type default)
			)
			(layer "F.SilkS")
		)
		(fp_line
			(start 0.67945 0.3048)
			(end 0.120396 0.3048)
			(stroke
				(width 0.1)
				(type default)
			)
			(layer "F.Fab")
		)
		(fp_line
			(start 0.67945 -0.3048)
			(end 0.67945 0.3048)
			(stroke
				(width 0.1)
				(type default)
			)
			(layer "F.Fab")
		)
		(fp_line
			(start 0.12065 -0.2794)
			(end 0.12065 -0.3048)
			(stroke
				(width 0.1)
				(type default)
			)
			(layer "F.Fab")
		)
		(fp_line
			(start 0.12065 -0.3048)
			(end 0.67945 -0.3048)
			(stroke
				(width 0.1)
				(type default)
			)
			(layer "F.Fab")
		)
		(fp_line
			(start 0.120396 0.3048)
			(end 0.120396 0.2794)
			(stroke
				(width 0.1)
				(type default)
			)
			(layer "F.Fab")
		)
		(fp_line
			(start 0.120396 0.2794)
			(end -0.12065 0.2794)
			(stroke
				(width 0.1)
				(type default)
			)
			(layer "F.Fab")
		)
		(fp_line
			(start -0.12065 0.3048)
			(end -0.67945 0.3048)
			(stroke
				(width 0.1)
				(type default)
			)
			(layer "F.Fab")
		)
		(fp_line
			(start -0.12065 0.2794)
			(end -0.12065 0.3048)
			(stroke
				(width 0.1)
				(type default)
			)
			(layer "F.Fab")
		)
		(fp_line
			(start -0.12065 -0.2794)
			(end 0.12065 -0.2794)
			(stroke
				(width 0.1)
				(type default)
			)
			(layer "F.Fab")
		)
		(fp_line
			(start -0.12065 -0.305054)
			(end -0.12065 -0.2794)
			(stroke
				(width 0.1)
				(type default)
			)
			(layer "F.Fab")
		)
		(fp_line
			(start -0.67945 0.3048)
			(end -0.67945 -0.305054)
			(stroke
				(width 0.1)
				(type default)
			)
			(layer "F.Fab")
		)
		(fp_line
			(start -0.67945 -0.305054)
			(end -0.12065 -0.305054)
			(stroke
				(width 0.1)
				(type default)
			)
			(layer "F.Fab")
		)
		(pad "1" smd circle
			(at -0.40005 0 180)
			(size 0 0)
			(layers "F.Cu" "F.Mask" "F.Paste")
			(net "RST_NIC7_PERST3_R_N")
		)
		(pad "2" smd circle
			(at 0.40005 0 180)
			(size 0 0)
			(layers "F.Cu" "F.Mask" "F.Paste")
			(net "RST_HP_NIC7_BUF_N")
		)
	)
	(footprint ""
		(layer "F.Cu")
		(at 400.759422 -22.955504 90)
		(property "Reference" "R1728"
			(at 0 0 90)
			(layer "F.SilkS")
			(hide yes)
			(effects
				(font
					(size 1.27 1.27)
				)
			)
		)
		(property "Value" ""
			(at 0 0 90)
			(layer "F.Fab")
			(effects
				(font
					(size 1.27 1.27)
				)
			)
		)
		(duplicate_pad_numbers_are_jumpers no)
		(fp_line
			(start 0.7874 -0.4064)
			(end 0.7874 0.4064)
			(stroke
				(width 0.1524)
				(type default)
			)
			(layer "F.SilkS")
		)
		(fp_line
			(start -0.7874 -0.4064)
			(end 0.7874 -0.4064)
			(stroke
				(width 0.1524)
				(type default)
			)
			(layer "F.SilkS")
		)
		(fp_line
			(start 0.7874 0.4064)
			(end -0.7874 0.4064)
			(stroke
				(width 0.1524)
				(type default)
			)
			(layer "F.SilkS")
		)
		(fp_line
			(start -0.7874 0.4064)
			(end -0.7874 -0.4064)
			(stroke
				(width 0.1524)
				(type default)
			)
			(layer "F.SilkS")
		)
		(fp_line
			(start -0.12065 -0.305054)
			(end -0.12065 -0.2794)
			(stroke
				(width 0.1)
				(type default)
			)
			(layer "F.Fab")
		)
		(fp_line
			(start -0.67945 -0.305054)
			(end -0.12065 -0.305054)
			(stroke
				(width 0.1)
				(type default)
			)
			(layer "F.Fab")
		)
		(fp_line
			(start 0.67945 -0.3048)
			(end 0.67945 0.3048)
			(stroke
				(width 0.1)
				(type default)
			)
			(layer "F.Fab")
		)
		(fp_line
			(start 0.12065 -0.3048)
			(end 0.67945 -0.3048)
			(stroke
				(width 0.1)
				(type default)
			)
			(layer "F.Fab")
		)
		(fp_line
			(start 0.12065 -0.2794)
			(end 0.12065 -0.3048)
			(stroke
				(width 0.1)
				(type default)
			)
			(layer "F.Fab")
		)
		(fp_line
			(start -0.12065 -0.2794)
			(end 0.12065 -0.2794)
			(stroke
				(width 0.1)
				(type default)
			)
			(layer "F.Fab")
		)
		(fp_line
			(start 0.120396 0.2794)
			(end -0.12065 0.2794)
			(stroke
				(width 0.1)
				(type default)
			)
			(layer "F.Fab")
		)
		(fp_line
			(start -0.12065 0.2794)
			(end -0.12065 0.3048)
			(stroke
				(width 0.1)
				(type default)
			)
			(layer "F.Fab")
		)
		(fp_line
			(start 0.67945 0.3048)
			(end 0.120396 0.3048)
			(stroke
				(width 0.1)
				(type default)
			)
			(layer "F.Fab")
		)
		(fp_line
			(start 0.120396 0.3048)
			(end 0.120396 0.2794)
			(stroke
				(width 0.1)
				(type default)
			)
			(layer "F.Fab")
		)
		(fp_line
			(start -0.12065 0.3048)
			(end -0.67945 0.3048)
			(stroke
				(width 0.1)
				(type default)
			)
			(layer "F.Fab")
		)
		(fp_line
			(start -0.67945 0.3048)
			(end -0.67945 -0.305054)
			(stroke
				(width 0.1)
				(type default)
			)
			(layer "F.Fab")
		)
		(pad "1" smd circle
			(at -0.40005 0 90)
			(size 0 0)
			(layers "F.Cu" "F.Mask" "F.Paste")
			(net "SMB_BIC_I2C9_MUX1_SSD13_R_SCL")
		)
		(pad "2" smd circle
			(at 0.40005 0 90)
			(size 0 0)
			(layers "F.Cu" "F.Mask" "F.Paste")
			(net "SMB_ISO_SSD13_SCL")
		)
	)
	(footprint ""
		(layer "F.Cu")
		(at 154.890724 -142.892018)
		(property "Reference" "R132"
			(at 0 0 0)
			(layer "F.SilkS")
			(hide yes)
			(effects
				(font
					(size 1.27 1.27)
				)
			)
		)
		(property "Value" ""
			(at 0 0 0)
			(layer "F.Fab")
			(effects
				(font
					(size 1.27 1.27)
				)
			)
		)
		(duplicate_pad_numbers_are_jumpers no)
		(fp_line
			(start -0.7874 -0.4064)
			(end 0.7874 -0.4064)
			(stroke
				(width 0.1524)
				(type default)
			)
			(layer "F.SilkS")
		)
		(fp_line
			(start -0.7874 0.4064)
			(end -0.7874 -0.4064)
			(stroke
				(width 0.1524)
				(type default)
			)
			(layer "F.SilkS")
		)
		(fp_line
			(start 0.7874 -0.4064)
			(end 0.7874 0.4064)
			(stroke
				(width 0.1524)
				(type default)
			)
			(layer "F.SilkS")
		)
		(fp_line
			(start 0.7874 0.4064)
			(end -0.7874 0.4064)
			(stroke
				(width 0.1524)
				(type default)
			)
			(layer "F.SilkS")
		)
		(fp_line
			(start -0.67945 -0.305054)
			(end -0.12065 -0.305054)
			(stroke
				(width 0.1)
				(type default)
			)
			(layer "F.Fab")
		)
		(fp_line
			(start -0.67945 0.3048)
			(end -0.67945 -0.305054)
			(stroke
				(width 0.1)
				(type default)
			)
			(layer "F.Fab")
		)
		(fp_line
			(start -0.12065 -0.305054)
			(end -0.12065 -0.2794)
			(stroke
				(width 0.1)
				(type default)
			)
			(layer "F.Fab")
		)
		(fp_line
			(start -0.12065 -0.2794)
			(end 0.12065 -0.2794)
			(stroke
				(width 0.1)
				(type default)
			)
			(layer "F.Fab")
		)
		(fp_line
			(start -0.12065 0.2794)
			(end -0.12065 0.3048)
			(stroke
				(width 0.1)
				(type default)
			)
			(layer "F.Fab")
		)
		(fp_line
			(start -0.12065 0.3048)
			(end -0.67945 0.3048)
			(stroke
				(width 0.1)
				(type default)
			)
			(layer "F.Fab")
		)
		(fp_line
			(start 0.120396 0.2794)
			(end -0.12065 0.2794)
			(stroke
				(width 0.1)
				(type default)
			)
			(layer "F.Fab")
		)
		(fp_line
			(start 0.120396 0.3048)
			(end 0.120396 0.2794)
			(stroke
				(width 0.1)
				(type default)
			)
			(layer "F.Fab")
		)
		(fp_line
			(start 0.12065 -0.3048)
			(end 0.67945 -0.3048)
			(stroke
				(width 0.1)
				(type default)
			)
			(layer "F.Fab")
		)
		(fp_line
			(start 0.12065 -0.2794)
			(end 0.12065 -0.3048)
			(stroke
				(width 0.1)
				(type default)
			)
			(layer "F.Fab")
		)
		(fp_line
			(start 0.67945 -0.3048)
			(end 0.67945 0.3048)
			(stroke
				(width 0.1)
				(type default)
			)
			(layer "F.Fab")
		)
		(fp_line
			(start 0.67945 0.3048)
			(end 0.120396 0.3048)
			(stroke
				(width 0.1)
				(type default)
			)
			(layer "F.Fab")
		)
		(pad "1" smd circle
			(at -0.40005 0)
			(size 0 0)
			(layers "F.Cu" "F.Mask" "F.Paste")
			(net "NIC2_BIF0_N")
		)
		(pad "2" smd circle
			(at 0.40005 0)
			(size 0 0)
			(layers "F.Cu" "F.Mask" "F.Paste")
			(net "GND")
		)
	)
	(footprint ""
		(layer "F.Cu")
		(at 354.875846 -36.915598 -90)
		(property "Reference" "R5568"
			(at 0 0 270)
			(layer "F.SilkS")
			(hide yes)
			(effects
				(font
					(size 1.27 1.27)
				)
			)
		)
		(property "Value" ""
			(at 0 0 270)
			(layer "F.Fab")
			(effects
				(font
					(size 1.27 1.27)
				)
			)
		)
		(duplicate_pad_numbers_are_jumpers no)
		(fp_line
			(start -0.7874 0.4064)
			(end -0.7874 -0.4064)
			(stroke
				(width 0.1524)
				(type default)
			)
			(layer "F.SilkS")
		)
		(fp_line
			(start 0.7874 0.4064)
			(end -0.7874 0.4064)
			(stroke
				(width 0.1524)
				(type default)
			)
			(layer "F.SilkS")
		)
		(fp_line
			(start -0.7874 -0.4064)
			(end 0.7874 -0.4064)
			(stroke
				(width 0.1524)
				(type default)
			)
			(layer "F.SilkS")
		)
		(fp_line
			(start 0.7874 -0.4064)
			(end 0.7874 0.4064)
			(stroke
				(width 0.1524)
				(type default)
			)
			(layer "F.SilkS")
		)
		(fp_line
			(start -0.67945 0.3048)
			(end -0.67945 -0.305054)
			(stroke
				(width 0.1)
				(type default)
			)
			(layer "F.Fab")
		)
		(fp_line
			(start -0.12065 0.3048)
			(end -0.67945 0.3048)
			(stroke
				(width 0.1)
				(type default)
			)
			(layer "F.Fab")
		)
		(fp_line
			(start 0.120396 0.3048)
			(end 0.120396 0.2794)
			(stroke
				(width 0.1)
				(type default)
			)
			(layer "F.Fab")
		)
		(fp_line
			(start 0.67945 0.3048)
			(end 0.120396 0.3048)
			(stroke
				(width 0.1)
				(type default)
			)
			(layer "F.Fab")
		)
		(fp_line
			(start -0.12065 0.2794)
			(end -0.12065 0.3048)
			(stroke
				(width 0.1)
				(type default)
			)
			(layer "F.Fab")
		)
		(fp_line
			(start 0.120396 0.2794)
			(end -0.12065 0.2794)
			(stroke
				(width 0.1)
				(type default)
			)
			(layer "F.Fab")
		)
		(fp_line
			(start -0.12065 -0.2794)
			(end 0.12065 -0.2794)
			(stroke
				(width 0.1)
				(type default)
			)
			(layer "F.Fab")
		)
		(fp_line
			(start 0.12065 -0.2794)
			(end 0.12065 -0.3048)
			(stroke
				(width 0.1)
				(type default)
			)
			(layer "F.Fab")
		)
		(fp_line
			(start 0.12065 -0.3048)
			(end 0.67945 -0.3048)
			(stroke
				(width 0.1)
				(type default)
			)
			(layer "F.Fab")
		)
		(fp_line
			(start 0.67945 -0.3048)
			(end 0.67945 0.3048)
			(stroke
				(width 0.1)
				(type default)
			)
			(layer "F.Fab")
		)
		(fp_line
			(start -0.67945 -0.305054)
			(end -0.12065 -0.305054)
			(stroke
				(width 0.1)
				(type default)
			)
			(layer "F.Fab")
		)
		(fp_line
			(start -0.12065 -0.305054)
			(end -0.12065 -0.2794)
			(stroke
				(width 0.1)
				(type default)
			)
			(layer "F.Fab")
		)
		(pad "1" smd circle
			(at -0.40005 0 270)
			(size 0 0)
			(layers "F.Cu" "F.Mask" "F.Paste")
			(net "PRSNT_SSD12_R1_N")
		)
		(pad "2" smd circle
			(at 0.40005 0 270)
			(size 0 0)
			(layers "F.Cu" "F.Mask" "F.Paste")
			(net "PRSNT_SSD12_R_N")
		)
	)
	(footprint ""
		(layer "F.Cu")
		(at 280.475182 -402.338032 -90)
		(property "Reference" "R1806"
			(at 0 0 270)
			(layer "F.SilkS")
			(hide yes)
			(effects
				(font
					(size 1.27 1.27)
				)
			)
		)
		(property "Value" ""
			(at 0 0 270)
			(layer "F.Fab")
			(effects
				(font
					(size 1.27 1.27)
				)
			)
		)
		(duplicate_pad_numbers_are_jumpers no)
		(fp_line
			(start -0.7874 0.4064)
			(end -0.7874 -0.4064)
			(stroke
				(width 0.1524)
				(type default)
			)
			(layer "F.SilkS")
		)
		(fp_line
			(start 0.7874 0.4064)
			(end -0.7874 0.4064)
			(stroke
				(width 0.1524)
				(type default)
			)
			(layer "F.SilkS")
		)
		(fp_line
			(start -0.7874 -0.4064)
			(end 0.7874 -0.4064)
			(stroke
				(width 0.1524)
				(type default)
			)
			(layer "F.SilkS")
		)
		(fp_line
			(start 0.7874 -0.4064)
			(end 0.7874 0.4064)
			(stroke
				(width 0.1524)
				(type default)
			)
			(layer "F.SilkS")
		)
		(fp_line
			(start -0.67945 0.3048)
			(end -0.67945 -0.305054)
			(stroke
				(width 0.1)
				(type default)
			)
			(layer "F.Fab")
		)
		(fp_line
			(start -0.12065 0.3048)
			(end -0.67945 0.3048)
			(stroke
				(width 0.1)
				(type default)
			)
			(layer "F.Fab")
		)
		(fp_line
			(start 0.120396 0.3048)
			(end 0.120396 0.2794)
			(stroke
				(width 0.1)
				(type default)
			)
			(layer "F.Fab")
		)
		(fp_line
			(start 0.67945 0.3048)
			(end 0.120396 0.3048)
			(stroke
				(width 0.1)
				(type default)
			)
			(layer "F.Fab")
		)
		(fp_line
			(start -0.12065 0.2794)
			(end -0.12065 0.3048)
			(stroke
				(width 0.1)
				(type default)
			)
			(layer "F.Fab")
		)
		(fp_line
			(start 0.120396 0.2794)
			(end -0.12065 0.2794)
			(stroke
				(width 0.1)
				(type default)
			)
			(layer "F.Fab")
		)
		(fp_line
			(start -0.12065 -0.2794)
			(end 0.12065 -0.2794)
			(stroke
				(width 0.1)
				(type default)
			)
			(layer "F.Fab")
		)
		(fp_line
			(start 0.12065 -0.2794)
			(end 0.12065 -0.3048)
			(stroke
				(width 0.1)
				(type default)
			)
			(layer "F.Fab")
		)
		(fp_line
			(start 0.12065 -0.3048)
			(end 0.67945 -0.3048)
			(stroke
				(width 0.1)
				(type default)
			)
			(layer "F.Fab")
		)
		(fp_line
			(start 0.67945 -0.3048)
			(end 0.67945 0.3048)
			(stroke
				(width 0.1)
				(type default)
			)
			(layer "F.Fab")
		)
		(fp_line
			(start -0.67945 -0.305054)
			(end -0.12065 -0.305054)
			(stroke
				(width 0.1)
				(type default)
			)
			(layer "F.Fab")
		)
		(fp_line
			(start -0.12065 -0.305054)
			(end -0.12065 -0.2794)
			(stroke
				(width 0.1)
				(type default)
			)
			(layer "F.Fab")
		)
		(pad "1" smd circle
			(at -0.40005 0 270)
			(size 0 0)
			(layers "F.Cu" "F.Mask" "F.Paste")
			(net "P3V3_AUX")
		)
		(pad "2" smd circle
			(at 0.40005 0 270)
			(size 0 0)
			(layers "F.Cu" "F.Mask" "F.Paste")
			(net "RST_MB_BIC_ISO_R_N")
		)
	)
	(footprint ""
		(layer "F.Cu")
		(at 321.698366 -297.46448)
		(property "Reference" "R3987"
			(at 0 0 0)
			(layer "F.SilkS")
			(hide yes)
			(effects
				(font
					(size 1.27 1.27)
				)
			)
		)
		(property "Value" ""
			(at 0 0 0)
			(layer "F.Fab")
			(effects
				(font
					(size 1.27 1.27)
				)
			)
		)
		(duplicate_pad_numbers_are_jumpers no)
		(fp_line
			(start -0.7874 -0.4064)
			(end 0.7874 -0.4064)
			(stroke
				(width 0.1524)
				(type default)
			)
			(layer "F.SilkS")
		)
		(fp_line
			(start -0.7874 0.4064)
			(end -0.7874 -0.4064)
			(stroke
				(width 0.1524)
				(type default)
			)
			(layer "F.SilkS")
		)
		(fp_line
			(start 0.7874 -0.4064)
			(end 0.7874 0.4064)
			(stroke
				(width 0.1524)
				(type default)
			)
			(layer "F.SilkS")
		)
		(fp_line
			(start 0.7874 0.4064)
			(end -0.7874 0.4064)
			(stroke
				(width 0.1524)
				(type default)
			)
			(layer "F.SilkS")
		)
		(fp_line
			(start -0.67945 -0.305054)
			(end -0.12065 -0.305054)
			(stroke
				(width 0.1)
				(type default)
			)
			(layer "F.Fab")
		)
		(fp_line
			(start -0.67945 0.3048)
			(end -0.67945 -0.305054)
			(stroke
				(width 0.1)
				(type default)
			)
			(layer "F.Fab")
		)
		(fp_line
			(start -0.12065 -0.305054)
			(end -0.12065 -0.2794)
			(stroke
				(width 0.1)
				(type default)
			)
			(layer "F.Fab")
		)
		(fp_line
			(start -0.12065 -0.2794)
			(end 0.12065 -0.2794)
			(stroke
				(width 0.1)
				(type default)
			)
			(layer "F.Fab")
		)
		(fp_line
			(start -0.12065 0.2794)
			(end -0.12065 0.3048)
			(stroke
				(width 0.1)
				(type default)
			)
			(layer "F.Fab")
		)
		(fp_line
			(start -0.12065 0.3048)
			(end -0.67945 0.3048)
			(stroke
				(width 0.1)
				(type default)
			)
			(layer "F.Fab")
		)
		(fp_line
			(start 0.120396 0.2794)
			(end -0.12065 0.2794)
			(stroke
				(width 0.1)
				(type default)
			)
			(layer "F.Fab")
		)
		(fp_line
			(start 0.120396 0.3048)
			(end 0.120396 0.2794)
			(stroke
				(width 0.1)
				(type default)
			)
			(layer "F.Fab")
		)
		(fp_line
			(start 0.12065 -0.3048)
			(end 0.67945 -0.3048)
			(stroke
				(width 0.1)
				(type default)
			)
			(layer "F.Fab")
		)
		(fp_line
			(start 0.12065 -0.2794)
			(end 0.12065 -0.3048)
			(stroke
				(width 0.1)
				(type default)
			)
			(layer "F.Fab")
		)
		(fp_line
			(start 0.67945 -0.3048)
			(end 0.67945 0.3048)
			(stroke
				(width 0.1)
				(type default)
			)
			(layer "F.Fab")
		)
		(fp_line
			(start 0.67945 0.3048)
			(end 0.120396 0.3048)
			(stroke
				(width 0.1)
				(type default)
			)
			(layer "F.Fab")
		)
		(pad "1" smd circle
			(at -0.40005 0)
			(size 0 0)
			(layers "F.Cu" "F.Mask" "F.Paste")
			(net "SMB_PEX2_HOST_LS_SDA")
		)
		(pad "2" smd circle
			(at 0.40005 0)
			(size 0 0)
			(layers "F.Cu" "F.Mask" "F.Paste")
			(net "I2C_PEX2_HOST_R_SDA")
		)
	)
	(footprint ""
		(layer "F.Cu")
		(at 232.428288 -97.258378 -90)
		(property "Reference" "R1018"
			(at 0 0 270)
			(layer "F.SilkS")
			(hide yes)
			(effects
				(font
					(size 1.27 1.27)
				)
			)
		)
		(property "Value" ""
			(at 0 0 270)
			(layer "F.Fab")
			(effects
				(font
					(size 1.27 1.27)
				)
			)
		)
		(duplicate_pad_numbers_are_jumpers no)
		(fp_line
			(start -0.7874 0.4064)
			(end -0.7874 -0.4064)
			(stroke
				(width 0.1524)
				(type default)
			)
			(layer "F.SilkS")
		)
		(fp_line
			(start 0.7874 0.4064)
			(end -0.7874 0.4064)
			(stroke
				(width 0.1524)
				(type default)
			)
			(layer "F.SilkS")
		)
		(fp_line
			(start -0.7874 -0.4064)
			(end 0.7874 -0.4064)
			(stroke
				(width 0.1524)
				(type default)
			)
			(layer "F.SilkS")
		)
		(fp_line
			(start 0.7874 -0.4064)
			(end 0.7874 0.4064)
			(stroke
				(width 0.1524)
				(type default)
			)
			(layer "F.SilkS")
		)
		(fp_line
			(start -0.67945 0.3048)
			(end -0.67945 -0.305054)
			(stroke
				(width 0.1)
				(type default)
			)
			(layer "F.Fab")
		)
		(fp_line
			(start -0.12065 0.3048)
			(end -0.67945 0.3048)
			(stroke
				(width 0.1)
				(type default)
			)
			(layer "F.Fab")
		)
		(fp_line
			(start 0.120396 0.3048)
			(end 0.120396 0.2794)
			(stroke
				(width 0.1)
				(type default)
			)
			(layer "F.Fab")
		)
		(fp_line
			(start 0.67945 0.3048)
			(end 0.120396 0.3048)
			(stroke
				(width 0.1)
				(type default)
			)
			(layer "F.Fab")
		)
		(fp_line
			(start -0.12065 0.2794)
			(end -0.12065 0.3048)
			(stroke
				(width 0.1)
				(type default)
			)
			(layer "F.Fab")
		)
		(fp_line
			(start 0.120396 0.2794)
			(end -0.12065 0.2794)
			(stroke
				(width 0.1)
				(type default)
			)
			(layer "F.Fab")
		)
		(fp_line
			(start -0.12065 -0.2794)
			(end 0.12065 -0.2794)
			(stroke
				(width 0.1)
				(type default)
			)
			(layer "F.Fab")
		)
		(fp_line
			(start 0.12065 -0.2794)
			(end 0.12065 -0.3048)
			(stroke
				(width 0.1)
				(type default)
			)
			(layer "F.Fab")
		)
		(fp_line
			(start 0.12065 -0.3048)
			(end 0.67945 -0.3048)
			(stroke
				(width 0.1)
				(type default)
			)
			(layer "F.Fab")
		)
		(fp_line
			(start 0.67945 -0.3048)
			(end 0.67945 0.3048)
			(stroke
				(width 0.1)
				(type default)
			)
			(layer "F.Fab")
		)
		(fp_line
			(start -0.67945 -0.305054)
			(end -0.12065 -0.305054)
			(stroke
				(width 0.1)
				(type default)
			)
			(layer "F.Fab")
		)
		(fp_line
			(start -0.12065 -0.305054)
			(end -0.12065 -0.2794)
			(stroke
				(width 0.1)
				(type default)
			)
			(layer "F.Fab")
		)
		(pad "1" smd circle
			(at -0.40005 0 270)
			(size 0 0)
			(layers "F.Cu" "F.Mask" "F.Paste")
			(net "P3V3_AUX")
		)
		(pad "2" smd circle
			(at 0.40005 0 270)
			(size 0 0)
			(layers "F.Cu" "F.Mask" "F.Paste")
			(net "PEX_USB_HUB_OVCUR4")
		)
	)
	(footprint ""
		(layer "F.Cu")
		(at 15.201392 -55.78475 -90)
		(property "Reference" "PD22"
			(at 1.02235 2.144522 90)
			(unlocked yes)
			(layer "F.SilkS")
			(effects
				(font
					(size 0.7874 0.5842)
					(thickness 0.1524)
				)
				(justify left)
			)
		)
		(property "Value" ""
			(at 0 0 270)
			(layer "F.Fab")
			(effects
				(font
					(size 1.27 1.27)
				)
			)
		)
		(duplicate_pad_numbers_are_jumpers no)
		(fp_line
			(start -3.400044 1.459992)
			(end -3.400044 -1.459992)
			(stroke
				(width 0.1524)
				(type default)
			)
			(layer "F.SilkS")
		)
		(fp_line
			(start 4.107942 1.459992)
			(end -3.400044 1.459992)
			(stroke
				(width 0.1524)
				(type default)
			)
			(layer "F.SilkS")
		)
		(fp_line
			(start -3.400044 -1.459992)
			(end 4.107942 -1.459992)
			(stroke
				(width 0.1524)
				(type default)
			)
			(layer "F.SilkS")
		)
		(fp_line
			(start 4.107942 -1.459992)
			(end 4.107942 1.459992)
			(stroke
				(width 0.1524)
				(type default)
			)
			(layer "F.SilkS")
		)
		(fp_poly
			(pts
				(xy 4.107942 -1.459992) (xy 4.107942 1.459992) (xy 3.308096 1.459992) (xy 3.308096 -1.459992)
			)
			(stroke
				(width 0)
				(type default)
			)
			(fill yes)
			(layer "F.SilkS")
		)
		(fp_line
			(start -2.29997 1.459992)
			(end -2.29997 -1.459992)
			(stroke
				(width 0.1)
				(type default)
			)
			(layer "F.Fab")
		)
		(fp_line
			(start 2.29997 1.459992)
			(end -2.29997 1.459992)
			(stroke
				(width 0.1)
				(type default)
			)
			(layer "F.Fab")
		)
		(fp_line
			(start -2.29997 -1.459992)
			(end 2.29997 -1.459992)
			(stroke
				(width 0.1)
				(type default)
			)
			(layer "F.Fab")
		)
		(fp_line
			(start 2.29997 -1.459992)
			(end 2.29997 1.459992)
			(stroke
				(width 0.1)
				(type default)
			)
			(layer "F.Fab")
		)
		(fp_text user "-"
			(at 5.4102 0.29845 90)
			(unlocked yes)
			(layer "F.SilkS")
			(effects
				(font
					(size 1.905 1.4224)
					(thickness 0.1524)
				)
				(justify left)
			)
		)
		(fp_text user "+"
			(at -4.7752 -0.12065 270)
			(unlocked yes)
			(layer "F.SilkS")
			(effects
				(font
					(size 1.905 1.4224)
					(thickness 0.1524)
				)
				(justify left)
			)
		)
		(fp_text user "-"
			(at 5.4102 0.29845 90)
			(unlocked yes)
			(layer "F.Fab")
			(effects
				(font
					(size 1.905 1.4224)
					(thickness 0.1524)
				)
				(justify left)
			)
		)
		(fp_text user "+"
			(at -4.7752 -0.12065 270)
			(unlocked yes)
			(layer "F.Fab")
			(effects
				(font
					(size 1.905 1.4224)
					(thickness 0.1524)
				)
				(justify left)
			)
		)
		(pad "A" smd rect
			(at -1.999996 0)
			(size 1.7018 2.5146)
			(layers "F.Cu" "F.Mask" "F.Paste")
			(net "GND")
		)
		(pad "C" smd rect
			(at 1.999996 0)
			(size 1.7018 2.5146)
			(layers "F.Cu" "F.Mask" "F.Paste")
			(net "P12V_SSD0_R")
		)
	)
	(footprint ""
		(layer "F.Cu")
		(at 207.854296 -228.833426 180)
		(property "Reference" "R5917"
			(at 0 0 180)
			(layer "F.SilkS")
			(hide yes)
			(effects
				(font
					(size 1.27 1.27)
				)
			)
		)
		(property "Value" ""
			(at 0 0 180)
			(layer "F.Fab")
			(effects
				(font
					(size 1.27 1.27)
				)
			)
		)
		(duplicate_pad_numbers_are_jumpers no)
		(fp_line
			(start 0.7874 0.4064)
			(end -0.7874 0.4064)
			(stroke
				(width 0.1524)
				(type default)
			)
			(layer "F.SilkS")
		)
		(fp_line
			(start 0.7874 -0.4064)
			(end 0.7874 0.4064)
			(stroke
				(width 0.1524)
				(type default)
			)
			(layer "F.SilkS")
		)
		(fp_line
			(start -0.7874 0.4064)
			(end -0.7874 -0.4064)
			(stroke
				(width 0.1524)
				(type default)
			)
			(layer "F.SilkS")
		)
		(fp_line
			(start -0.7874 -0.4064)
			(end 0.7874 -0.4064)
			(stroke
				(width 0.1524)
				(type default)
			)
			(layer "F.SilkS")
		)
		(fp_line
			(start 0.67945 0.3048)
			(end 0.120396 0.3048)
			(stroke
				(width 0.1)
				(type default)
			)
			(layer "F.Fab")
		)
		(fp_line
			(start 0.67945 -0.3048)
			(end 0.67945 0.3048)
			(stroke
				(width 0.1)
				(type default)
			)
			(layer "F.Fab")
		)
		(fp_line
			(start 0.12065 -0.2794)
			(end 0.12065 -0.3048)
			(stroke
				(width 0.1)
				(type default)
			)
			(layer "F.Fab")
		)
		(fp_line
			(start 0.12065 -0.3048)
			(end 0.67945 -0.3048)
			(stroke
				(width 0.1)
				(type default)
			)
			(layer "F.Fab")
		)
		(fp_line
			(start 0.120396 0.3048)
			(end 0.120396 0.2794)
			(stroke
				(width 0.1)
				(type default)
			)
			(layer "F.Fab")
		)
		(fp_line
			(start 0.120396 0.2794)
			(end -0.12065 0.2794)
			(stroke
				(width 0.1)
				(type default)
			)
			(layer "F.Fab")
		)
		(fp_line
			(start -0.12065 0.3048)
			(end -0.67945 0.3048)
			(stroke
				(width 0.1)
				(type default)
			)
			(layer "F.Fab")
		)
		(fp_line
			(start -0.12065 0.2794)
			(end -0.12065 0.3048)
			(stroke
				(width 0.1)
				(type default)
			)
			(layer "F.Fab")
		)
		(fp_line
			(start -0.12065 -0.2794)
			(end 0.12065 -0.2794)
			(stroke
				(width 0.1)
				(type default)
			)
			(layer "F.Fab")
		)
		(fp_line
			(start -0.12065 -0.305054)
			(end -0.12065 -0.2794)
			(stroke
				(width 0.1)
				(type default)
			)
			(layer "F.Fab")
		)
		(fp_line
			(start -0.67945 0.3048)
			(end -0.67945 -0.305054)
			(stroke
				(width 0.1)
				(type default)
			)
			(layer "F.Fab")
		)
		(fp_line
			(start -0.67945 -0.305054)
			(end -0.12065 -0.305054)
			(stroke
				(width 0.1)
				(type default)
			)
			(layer "F.Fab")
		)
		(pad "1" smd circle
			(at -0.40005 0 180)
			(size 0 0)
			(layers "F.Cu" "F.Mask" "F.Paste")
			(net "GND")
		)
		(pad "2" smd circle
			(at 0.40005 0 180)
			(size 0 0)
			(layers "F.Cu" "F.Mask" "F.Paste")
			(net "PD_BIC_UART_SEL")
		)
	)
	(footprint ""
		(layer "F.Cu")
		(at 266.054078 -307.415438 45)
		(property "Reference" "R1352"
			(at 0 0 45)
			(layer "F.SilkS")
			(hide yes)
			(effects
				(font
					(size 1.27 1.27)
				)
			)
		)
		(property "Value" ""
			(at 0 0 45)
			(layer "F.Fab")
			(effects
				(font
					(size 1.27 1.27)
				)
			)
		)
		(duplicate_pad_numbers_are_jumpers no)
		(fp_line
			(start -0.787389 -0.406267)
			(end 0.787389 -0.406267)
			(stroke
				(width 0.1524)
				(type default)
			)
			(layer "F.SilkS")
		)
		(fp_line
			(start -0.787389 0.406267)
			(end -0.787389 -0.406267)
			(stroke
				(width 0.1524)
				(type default)
			)
			(layer "F.SilkS")
		)
		(fp_line
			(start 0.787389 -0.406267)
			(end 0.787389 0.406267)
			(stroke
				(width 0.1524)
				(type default)
			)
			(layer "F.SilkS")
		)
		(fp_line
			(start 0.787389 0.406267)
			(end -0.787389 0.406267)
			(stroke
				(width 0.1524)
				(type default)
			)
			(layer "F.SilkS")
		)
		(fp_line
			(start -0.679446 -0.305149)
			(end -0.120695 -0.304969)
			(stroke
				(width 0.1)
				(type default)
			)
			(layer "F.Fab")
		)
		(fp_line
			(start -0.120695 -0.304969)
			(end -0.120695 -0.279466)
			(stroke
				(width 0.1)
				(type default)
			)
			(layer "F.Fab")
		)
		(fp_line
			(start -0.120695 -0.279466)
			(end 0.120695 -0.279466)
			(stroke
				(width 0.1)
				(type default)
			)
			(layer "F.Fab")
		)
		(fp_line
			(start -0.679446 0.30479)
			(end -0.679446 -0.305149)
			(stroke
				(width 0.1)
				(type default)
			)
			(layer "F.Fab")
		)
		(fp_line
			(start 0.120515 -0.30479)
			(end 0.679446 -0.30479)
			(stroke
				(width 0.1)
				(type default)
			)
			(layer "F.Fab")
		)
		(fp_line
			(start 0.120695 -0.279466)
			(end 0.120515 -0.30479)
			(stroke
				(width 0.1)
				(type default)
			)
			(layer "F.Fab")
		)
		(fp_line
			(start -0.120695 0.279466)
			(end -0.120515 0.30479)
			(stroke
				(width 0.1)
				(type default)
			)
			(layer "F.Fab")
		)
		(fp_line
			(start -0.120515 0.30479)
			(end -0.679446 0.30479)
			(stroke
				(width 0.1)
				(type default)
			)
			(layer "F.Fab")
		)
		(fp_line
			(start 0.679446 -0.30479)
			(end 0.679446 0.30479)
			(stroke
				(width 0.1)
				(type default)
			)
			(layer "F.Fab")
		)
		(fp_line
			(start 0.120335 0.279466)
			(end -0.120695 0.279466)
			(stroke
				(width 0.1)
				(type default)
			)
			(layer "F.Fab")
		)
		(fp_line
			(start 0.120515 0.30479)
			(end 0.120335 0.279466)
			(stroke
				(width 0.1)
				(type default)
			)
			(layer "F.Fab")
		)
		(fp_line
			(start 0.679446 0.30479)
			(end 0.120515 0.30479)
			(stroke
				(width 0.1)
				(type default)
			)
			(layer "F.Fab")
		)
		(pad "1" smd circle
			(at -0.40005 0 45)
			(size 0 0)
			(layers "F.Cu" "F.Mask" "F.Paste")
			(net "GND")
		)
		(pad "2" smd circle
			(at 0.40005 0 45)
			(size 0 0)
			(layers "F.Cu" "F.Mask" "F.Paste")
			(net "PEX2_DBG_MODE1")
		)
	)
	(footprint ""
		(layer "F.Cu")
		(at 29.88818 -260.84911 -90)
		(property "Reference" "C3033"
			(at 0 0 270)
			(layer "F.SilkS")
			(hide yes)
			(effects
				(font
					(size 1.27 1.27)
				)
			)
		)
		(property "Value" ""
			(at 0 0 270)
			(layer "F.Fab")
			(effects
				(font
					(size 1.27 1.27)
				)
			)
		)
		(duplicate_pad_numbers_are_jumpers no)
		(fp_line
			(start -1.2954 0.5842)
			(end -1.2954 -0.5842)
			(stroke
				(width 0.1524)
				(type default)
			)
			(layer "F.SilkS")
		)
		(fp_line
			(start 1.2954 0.5842)
			(end -1.2954 0.5842)
			(stroke
				(width 0.1524)
				(type default)
			)
			(layer "F.SilkS")
		)
		(fp_line
			(start -1.2954 -0.5842)
			(end 1.2954 -0.5842)
			(stroke
				(width 0.1524)
				(type default)
			)
			(layer "F.SilkS")
		)
		(fp_line
			(start 1.2954 -0.5842)
			(end 1.2954 0.5842)
			(stroke
				(width 0.1524)
				(type default)
			)
			(layer "F.SilkS")
		)
		(fp_line
			(start -0.8636 0.4572)
			(end -0.8636 0.4064)
			(stroke
				(width 0.1)
				(type default)
			)
			(layer "F.Fab")
		)
		(fp_line
			(start 0.8636 0.4572)
			(end -0.8636 0.4572)
			(stroke
				(width 0.1)
				(type default)
			)
			(layer "F.Fab")
		)
		(fp_line
			(start -1.1938 0.4064)
			(end -1.1938 -0.4064)
			(stroke
				(width 0.1)
				(type default)
			)
			(layer "F.Fab")
		)
		(fp_line
			(start -0.8636 0.4064)
			(end -1.1938 0.4064)
			(stroke
				(width 0.1)
				(type default)
			)
			(layer "F.Fab")
		)
		(fp_line
			(start 0.8636 0.4064)
			(end 0.8636 0.4572)
			(stroke
				(width 0.1)
				(type default)
			)
			(layer "F.Fab")
		)
		(fp_line
			(start 1.1938 0.4064)
			(end 0.8636 0.4064)
			(stroke
				(width 0.1)
				(type default)
			)
			(layer "F.Fab")
		)
		(fp_line
			(start -1.1938 -0.4064)
			(end -0.8636 -0.4064)
			(stroke
				(width 0.1)
				(type default)
			)
			(layer "F.Fab")
		)
		(fp_line
			(start -0.8636 -0.4064)
			(end -0.8636 -0.4572)
			(stroke
				(width 0.1)
				(type default)
			)
			(layer "F.Fab")
		)
		(fp_line
			(start 0.8636 -0.4064)
			(end 1.1938 -0.4064)
			(stroke
				(width 0.1)
				(type default)
			)
			(layer "F.Fab")
		)
		(fp_line
			(start 1.1938 -0.4064)
			(end 1.1938 0.4064)
			(stroke
				(width 0.1)
				(type default)
			)
			(layer "F.Fab")
		)
		(fp_line
			(start -0.8636 -0.4572)
			(end 0.8636 -0.4572)
			(stroke
				(width 0.1)
				(type default)
			)
			(layer "F.Fab")
		)
		(fp_line
			(start 0.8636 -0.4572)
			(end 0.8636 -0.4064)
			(stroke
				(width 0.1)
				(type default)
			)
			(layer "F.Fab")
		)
		(pad "1" smd rect
			(at -0.7366 0 180)
			(size 0.7112 0.8128)
			(layers "F.Cu" "F.Mask" "F.Paste")
			(net "P1V8_PLL0_PEX0")
		)
		(pad "2" smd rect
			(at 0.7366 0 180)
			(size 0.7112 0.8128)
			(layers "F.Cu" "F.Mask" "F.Paste")
			(net "GND")
		)
	)
	(footprint ""
		(layer "F.Cu")
		(at 365.506 -212.979 180)
		(property "Reference" "R4635"
			(at 0 0 180)
			(layer "F.SilkS")
			(hide yes)
			(effects
				(font
					(size 1.27 1.27)
				)
			)
		)
		(property "Value" ""
			(at 0 0 180)
			(layer "F.Fab")
			(effects
				(font
					(size 1.27 1.27)
				)
			)
		)
		(duplicate_pad_numbers_are_jumpers no)
		(fp_line
			(start 0.7874 0.4064)
			(end -0.7874 0.4064)
			(stroke
				(width 0.1524)
				(type default)
			)
			(layer "F.SilkS")
		)
		(fp_line
			(start 0.7874 -0.4064)
			(end 0.7874 0.4064)
			(stroke
				(width 0.1524)
				(type default)
			)
			(layer "F.SilkS")
		)
		(fp_line
			(start -0.7874 0.4064)
			(end -0.7874 -0.4064)
			(stroke
				(width 0.1524)
				(type default)
			)
			(layer "F.SilkS")
		)
		(fp_line
			(start -0.7874 -0.4064)
			(end 0.7874 -0.4064)
			(stroke
				(width 0.1524)
				(type default)
			)
			(layer "F.SilkS")
		)
		(fp_line
			(start 0.67945 0.3048)
			(end 0.120396 0.3048)
			(stroke
				(width 0.1)
				(type default)
			)
			(layer "F.Fab")
		)
		(fp_line
			(start 0.67945 -0.3048)
			(end 0.67945 0.3048)
			(stroke
				(width 0.1)
				(type default)
			)
			(layer "F.Fab")
		)
		(fp_line
			(start 0.12065 -0.2794)
			(end 0.12065 -0.3048)
			(stroke
				(width 0.1)
				(type default)
			)
			(layer "F.Fab")
		)
		(fp_line
			(start 0.12065 -0.3048)
			(end 0.67945 -0.3048)
			(stroke
				(width 0.1)
				(type default)
			)
			(layer "F.Fab")
		)
		(fp_line
			(start 0.120396 0.3048)
			(end 0.120396 0.2794)
			(stroke
				(width 0.1)
				(type default)
			)
			(layer "F.Fab")
		)
		(fp_line
			(start 0.120396 0.2794)
			(end -0.12065 0.2794)
			(stroke
				(width 0.1)
				(type default)
			)
			(layer "F.Fab")
		)
		(fp_line
			(start -0.12065 0.3048)
			(end -0.67945 0.3048)
			(stroke
				(width 0.1)
				(type default)
			)
			(layer "F.Fab")
		)
		(fp_line
			(start -0.12065 0.2794)
			(end -0.12065 0.3048)
			(stroke
				(width 0.1)
				(type default)
			)
			(layer "F.Fab")
		)
		(fp_line
			(start -0.12065 -0.2794)
			(end 0.12065 -0.2794)
			(stroke
				(width 0.1)
				(type default)
			)
			(layer "F.Fab")
		)
		(fp_line
			(start -0.12065 -0.305054)
			(end -0.12065 -0.2794)
			(stroke
				(width 0.1)
				(type default)
			)
			(layer "F.Fab")
		)
		(fp_line
			(start -0.67945 0.3048)
			(end -0.67945 -0.305054)
			(stroke
				(width 0.1)
				(type default)
			)
			(layer "F.Fab")
		)
		(fp_line
			(start -0.67945 -0.305054)
			(end -0.12065 -0.305054)
			(stroke
				(width 0.1)
				(type default)
			)
			(layer "F.Fab")
		)
		(pad "1" smd circle
			(at -0.40005 0 180)
			(size 0 0)
			(layers "F.Cu" "F.Mask" "F.Paste")
			(net "GND")
		)
		(pad "2" smd circle
			(at 0.40005 0 180)
			(size 0 0)
			(layers "F.Cu" "F.Mask" "F.Paste")
			(net "PCA9555_0_PEX0_A2")
		)
	)
	(footprint ""
		(layer "F.Cu")
		(at 80.623664 -87.349076 -90)
		(property "Reference" "R97"
			(at 0 0 270)
			(layer "F.SilkS")
			(hide yes)
			(effects
				(font
					(size 1.27 1.27)
				)
			)
		)
		(property "Value" ""
			(at 0 0 270)
			(layer "F.Fab")
			(effects
				(font
					(size 1.27 1.27)
				)
			)
		)
		(duplicate_pad_numbers_are_jumpers no)
		(fp_line
			(start -0.7874 0.4064)
			(end -0.7874 -0.4064)
			(stroke
				(width 0.1524)
				(type default)
			)
			(layer "F.SilkS")
		)
		(fp_line
			(start 0.7874 0.4064)
			(end -0.7874 0.4064)
			(stroke
				(width 0.1524)
				(type default)
			)
			(layer "F.SilkS")
		)
		(fp_line
			(start -0.7874 -0.4064)
			(end 0.7874 -0.4064)
			(stroke
				(width 0.1524)
				(type default)
			)
			(layer "F.SilkS")
		)
		(fp_line
			(start 0.7874 -0.4064)
			(end 0.7874 0.4064)
			(stroke
				(width 0.1524)
				(type default)
			)
			(layer "F.SilkS")
		)
		(fp_line
			(start -0.67945 0.3048)
			(end -0.67945 -0.305054)
			(stroke
				(width 0.1)
				(type default)
			)
			(layer "F.Fab")
		)
		(fp_line
			(start -0.12065 0.3048)
			(end -0.67945 0.3048)
			(stroke
				(width 0.1)
				(type default)
			)
			(layer "F.Fab")
		)
		(fp_line
			(start 0.120396 0.3048)
			(end 0.120396 0.2794)
			(stroke
				(width 0.1)
				(type default)
			)
			(layer "F.Fab")
		)
		(fp_line
			(start 0.67945 0.3048)
			(end 0.120396 0.3048)
			(stroke
				(width 0.1)
				(type default)
			)
			(layer "F.Fab")
		)
		(fp_line
			(start -0.12065 0.2794)
			(end -0.12065 0.3048)
			(stroke
				(width 0.1)
				(type default)
			)
			(layer "F.Fab")
		)
		(fp_line
			(start 0.120396 0.2794)
			(end -0.12065 0.2794)
			(stroke
				(width 0.1)
				(type default)
			)
			(layer "F.Fab")
		)
		(fp_line
			(start -0.12065 -0.2794)
			(end 0.12065 -0.2794)
			(stroke
				(width 0.1)
				(type default)
			)
			(layer "F.Fab")
		)
		(fp_line
			(start 0.12065 -0.2794)
			(end 0.12065 -0.3048)
			(stroke
				(width 0.1)
				(type default)
			)
			(layer "F.Fab")
		)
		(fp_line
			(start 0.12065 -0.3048)
			(end 0.67945 -0.3048)
			(stroke
				(width 0.1)
				(type default)
			)
			(layer "F.Fab")
		)
		(fp_line
			(start 0.67945 -0.3048)
			(end 0.67945 0.3048)
			(stroke
				(width 0.1)
				(type default)
			)
			(layer "F.Fab")
		)
		(fp_line
			(start -0.67945 -0.305054)
			(end -0.12065 -0.305054)
			(stroke
				(width 0.1)
				(type default)
			)
			(layer "F.Fab")
		)
		(fp_line
			(start -0.12065 -0.305054)
			(end -0.12065 -0.2794)
			(stroke
				(width 0.1)
				(type default)
			)
			(layer "F.Fab")
		)
		(pad "1" smd circle
			(at -0.40005 0 270)
			(size 0 0)
			(layers "F.Cu" "F.Mask" "F.Paste")
			(net "RST_NIC1_PERST1_R_N")
		)
		(pad "2" smd circle
			(at 0.40005 0 270)
			(size 0 0)
			(layers "F.Cu" "F.Mask" "F.Paste")
			(net "RST_HP_NIC1_BUF_N")
		)
	)
	(footprint ""
		(layer "F.Cu")
		(at 177.929794 -171.661328 180)
		(property "Reference" "C882"
			(at 0 0 180)
			(layer "F.SilkS")
			(hide yes)
			(effects
				(font
					(size 1.27 1.27)
				)
			)
		)
		(property "Value" ""
			(at 0 0 180)
			(layer "F.Fab")
			(effects
				(font
					(size 1.27 1.27)
				)
			)
		)
		(duplicate_pad_numbers_are_jumpers no)
		(fp_line
			(start 0.7874 0.4064)
			(end -0.7874 0.4064)
			(stroke
				(width 0.1524)
				(type default)
			)
			(layer "F.SilkS")
		)
		(fp_line
			(start 0.7874 -0.4064)
			(end 0.7874 0.4064)
			(stroke
				(width 0.1524)
				(type default)
			)
			(layer "F.SilkS")
		)
		(fp_line
			(start -0.7874 0.4064)
			(end -0.7874 -0.4064)
			(stroke
				(width 0.1524)
				(type default)
			)
			(layer "F.SilkS")
		)
		(fp_line
			(start -0.7874 -0.4064)
			(end 0.7874 -0.4064)
			(stroke
				(width 0.1524)
				(type default)
			)
			(layer "F.SilkS")
		)
		(fp_line
			(start 0.67945 0.3048)
			(end 0.120396 0.3048)
			(stroke
				(width 0.1)
				(type default)
			)
			(layer "F.Fab")
		)
		(fp_line
			(start 0.67945 -0.3048)
			(end 0.67945 0.3048)
			(stroke
				(width 0.1)
				(type default)
			)
			(layer "F.Fab")
		)
		(fp_line
			(start 0.12065 -0.2794)
			(end 0.12065 -0.3048)
			(stroke
				(width 0.1)
				(type default)
			)
			(layer "F.Fab")
		)
		(fp_line
			(start 0.12065 -0.3048)
			(end 0.67945 -0.3048)
			(stroke
				(width 0.1)
				(type default)
			)
			(layer "F.Fab")
		)
		(fp_line
			(start 0.120396 0.3048)
			(end 0.120396 0.2794)
			(stroke
				(width 0.1)
				(type default)
			)
			(layer "F.Fab")
		)
		(fp_line
			(start 0.120396 0.2794)
			(end -0.12065 0.2794)
			(stroke
				(width 0.1)
				(type default)
			)
			(layer "F.Fab")
		)
		(fp_line
			(start -0.12065 0.3048)
			(end -0.67945 0.3048)
			(stroke
				(width 0.1)
				(type default)
			)
			(layer "F.Fab")
		)
		(fp_line
			(start -0.12065 0.2794)
			(end -0.12065 0.3048)
			(stroke
				(width 0.1)
				(type default)
			)
			(layer "F.Fab")
		)
		(fp_line
			(start -0.12065 -0.2794)
			(end 0.12065 -0.2794)
			(stroke
				(width 0.1)
				(type default)
			)
			(layer "F.Fab")
		)
		(fp_line
			(start -0.12065 -0.305054)
			(end -0.12065 -0.2794)
			(stroke
				(width 0.1)
				(type default)
			)
			(layer "F.Fab")
		)
		(fp_line
			(start -0.67945 0.3048)
			(end -0.67945 -0.305054)
			(stroke
				(width 0.1)
				(type default)
			)
			(layer "F.Fab")
		)
		(fp_line
			(start -0.67945 -0.305054)
			(end -0.12065 -0.305054)
			(stroke
				(width 0.1)
				(type default)
			)
			(layer "F.Fab")
		)
		(pad "1" smd circle
			(at -0.40005 0 180)
			(size 0 0)
			(layers "F.Cu" "F.Mask" "F.Paste")
			(net "P3V3_NIC2")
		)
		(pad "2" smd circle
			(at 0.40005 0 180)
			(size 0 0)
			(layers "F.Cu" "F.Mask" "F.Paste")
			(net "GND")
		)
	)
	(footprint ""
		(layer "F.Cu")
		(at 123.67514 -94.891606)
		(property "Reference" "R1579"
			(at 0 0 0)
			(layer "F.SilkS")
			(hide yes)
			(effects
				(font
					(size 1.27 1.27)
				)
			)
		)
		(property "Value" ""
			(at 0 0 0)
			(layer "F.Fab")
			(effects
				(font
					(size 1.27 1.27)
				)
			)
		)
		(duplicate_pad_numbers_are_jumpers no)
		(fp_line
			(start -0.7874 -0.4064)
			(end 0.7874 -0.4064)
			(stroke
				(width 0.1524)
				(type default)
			)
			(layer "F.SilkS")
		)
		(fp_line
			(start -0.7874 0.4064)
			(end -0.7874 -0.4064)
			(stroke
				(width 0.1524)
				(type default)
			)
			(layer "F.SilkS")
		)
		(fp_line
			(start 0.7874 -0.4064)
			(end 0.7874 0.4064)
			(stroke
				(width 0.1524)
				(type default)
			)
			(layer "F.SilkS")
		)
		(fp_line
			(start 0.7874 0.4064)
			(end -0.7874 0.4064)
			(stroke
				(width 0.1524)
				(type default)
			)
			(layer "F.SilkS")
		)
		(fp_line
			(start -0.67945 -0.305054)
			(end -0.12065 -0.305054)
			(stroke
				(width 0.1)
				(type default)
			)
			(layer "F.Fab")
		)
		(fp_line
			(start -0.67945 0.3048)
			(end -0.67945 -0.305054)
			(stroke
				(width 0.1)
				(type default)
			)
			(layer "F.Fab")
		)
		(fp_line
			(start -0.12065 -0.305054)
			(end -0.12065 -0.2794)
			(stroke
				(width 0.1)
				(type default)
			)
			(layer "F.Fab")
		)
		(fp_line
			(start -0.12065 -0.2794)
			(end 0.12065 -0.2794)
			(stroke
				(width 0.1)
				(type default)
			)
			(layer "F.Fab")
		)
		(fp_line
			(start -0.12065 0.2794)
			(end -0.12065 0.3048)
			(stroke
				(width 0.1)
				(type default)
			)
			(layer "F.Fab")
		)
		(fp_line
			(start -0.12065 0.3048)
			(end -0.67945 0.3048)
			(stroke
				(width 0.1)
				(type default)
			)
			(layer "F.Fab")
		)
		(fp_line
			(start 0.120396 0.2794)
			(end -0.12065 0.2794)
			(stroke
				(width 0.1)
				(type default)
			)
			(layer "F.Fab")
		)
		(fp_line
			(start 0.120396 0.3048)
			(end 0.120396 0.2794)
			(stroke
				(width 0.1)
				(type default)
			)
			(layer "F.Fab")
		)
		(fp_line
			(start 0.12065 -0.3048)
			(end 0.67945 -0.3048)
			(stroke
				(width 0.1)
				(type default)
			)
			(layer "F.Fab")
		)
		(fp_line
			(start 0.12065 -0.2794)
			(end 0.12065 -0.3048)
			(stroke
				(width 0.1)
				(type default)
			)
			(layer "F.Fab")
		)
		(fp_line
			(start 0.67945 -0.3048)
			(end 0.67945 0.3048)
			(stroke
				(width 0.1)
				(type default)
			)
			(layer "F.Fab")
		)
		(fp_line
			(start 0.67945 0.3048)
			(end 0.120396 0.3048)
			(stroke
				(width 0.1)
				(type default)
			)
			(layer "F.Fab")
		)
		(pad "1" smd circle
			(at -0.40005 0)
			(size 0 0)
			(layers "F.Cu" "F.Mask" "F.Paste")
			(net "SMB_BIC_I2C9_MUX0_SSD1_R_SDA")
		)
		(pad "2" smd circle
			(at 0.40005 0)
			(size 0 0)
			(layers "F.Cu" "F.Mask" "F.Paste")
			(net "SMB_BIC_I2C9_MUX0_SSD1_SDA")
		)
	)
	(footprint ""
		(layer "F.Cu")
		(at 120.974358 -279.101804)
		(property "Reference" "PC91"
			(at 0 0 0)
			(layer "F.SilkS")
			(hide yes)
			(effects
				(font
					(size 1.27 1.27)
				)
			)
		)
		(property "Value" ""
			(at 0 0 0)
			(layer "F.Fab")
			(effects
				(font
					(size 1.27 1.27)
				)
			)
		)
		(duplicate_pad_numbers_are_jumpers no)
		(fp_line
			(start -0.7874 -0.4064)
			(end 0.7874 -0.4064)
			(stroke
				(width 0.1524)
				(type default)
			)
			(layer "F.SilkS")
		)
		(fp_line
			(start -0.7874 0.4064)
			(end -0.7874 -0.4064)
			(stroke
				(width 0.1524)
				(type default)
			)
			(layer "F.SilkS")
		)
		(fp_line
			(start 0.7874 -0.4064)
			(end 0.7874 0.4064)
			(stroke
				(width 0.1524)
				(type default)
			)
			(layer "F.SilkS")
		)
		(fp_line
			(start 0.7874 0.4064)
			(end -0.7874 0.4064)
			(stroke
				(width 0.1524)
				(type default)
			)
			(layer "F.SilkS")
		)
		(fp_line
			(start -0.67945 -0.305054)
			(end -0.12065 -0.305054)
			(stroke
				(width 0.1)
				(type default)
			)
			(layer "F.Fab")
		)
		(fp_line
			(start -0.67945 0.3048)
			(end -0.67945 -0.305054)
			(stroke
				(width 0.1)
				(type default)
			)
			(layer "F.Fab")
		)
		(fp_line
			(start -0.12065 -0.305054)
			(end -0.12065 -0.2794)
			(stroke
				(width 0.1)
				(type default)
			)
			(layer "F.Fab")
		)
		(fp_line
			(start -0.12065 -0.2794)
			(end 0.12065 -0.2794)
			(stroke
				(width 0.1)
				(type default)
			)
			(layer "F.Fab")
		)
		(fp_line
			(start -0.12065 0.2794)
			(end -0.12065 0.3048)
			(stroke
				(width 0.1)
				(type default)
			)
			(layer "F.Fab")
		)
		(fp_line
			(start -0.12065 0.3048)
			(end -0.67945 0.3048)
			(stroke
				(width 0.1)
				(type default)
			)
			(layer "F.Fab")
		)
		(fp_line
			(start 0.120396 0.2794)
			(end -0.12065 0.2794)
			(stroke
				(width 0.1)
				(type default)
			)
			(layer "F.Fab")
		)
		(fp_line
			(start 0.120396 0.3048)
			(end 0.120396 0.2794)
			(stroke
				(width 0.1)
				(type default)
			)
			(layer "F.Fab")
		)
		(fp_line
			(start 0.12065 -0.3048)
			(end 0.67945 -0.3048)
			(stroke
				(width 0.1)
				(type default)
			)
			(layer "F.Fab")
		)
		(fp_line
			(start 0.12065 -0.2794)
			(end 0.12065 -0.3048)
			(stroke
				(width 0.1)
				(type default)
			)
			(layer "F.Fab")
		)
		(fp_line
			(start 0.67945 -0.3048)
			(end 0.67945 0.3048)
			(stroke
				(width 0.1)
				(type default)
			)
			(layer "F.Fab")
		)
		(fp_line
			(start 0.67945 0.3048)
			(end 0.120396 0.3048)
			(stroke
				(width 0.1)
				(type default)
			)
			(layer "F.Fab")
		)
		(pad "1" smd circle
			(at -0.40005 0)
			(size 0 0)
			(layers "F.Cu" "F.Mask" "F.Paste")
			(net "SW_P12V_P0V8_PEX1_FLT")
		)
		(pad "2" smd circle
			(at 0.40005 0)
			(size 0 0)
			(layers "F.Cu" "F.Mask" "F.Paste")
			(net "GND")
		)
	)
	(footprint ""
		(layer "F.Cu")
		(at 313.557666 -27.006296 -90)
		(property "Reference" "PR7121"
			(at 0 0 270)
			(layer "F.SilkS")
			(hide yes)
			(effects
				(font
					(size 1.27 1.27)
				)
			)
		)
		(property "Value" ""
			(at 0 0 270)
			(layer "F.Fab")
			(effects
				(font
					(size 1.27 1.27)
				)
			)
		)
		(duplicate_pad_numbers_are_jumpers no)
		(fp_line
			(start -0.7874 0.4064)
			(end -0.7874 -0.4064)
			(stroke
				(width 0.1524)
				(type default)
			)
			(layer "F.SilkS")
		)
		(fp_line
			(start 0.7874 0.4064)
			(end -0.7874 0.4064)
			(stroke
				(width 0.1524)
				(type default)
			)
			(layer "F.SilkS")
		)
		(fp_line
			(start -0.7874 -0.4064)
			(end 0.7874 -0.4064)
			(stroke
				(width 0.1524)
				(type default)
			)
			(layer "F.SilkS")
		)
		(fp_line
			(start 0.7874 -0.4064)
			(end 0.7874 0.4064)
			(stroke
				(width 0.1524)
				(type default)
			)
			(layer "F.SilkS")
		)
		(fp_line
			(start -0.67945 0.3048)
			(end -0.67945 -0.305054)
			(stroke
				(width 0.1)
				(type default)
			)
			(layer "F.Fab")
		)
		(fp_line
			(start -0.12065 0.3048)
			(end -0.67945 0.3048)
			(stroke
				(width 0.1)
				(type default)
			)
			(layer "F.Fab")
		)
		(fp_line
			(start 0.120396 0.3048)
			(end 0.120396 0.2794)
			(stroke
				(width 0.1)
				(type default)
			)
			(layer "F.Fab")
		)
		(fp_line
			(start 0.67945 0.3048)
			(end 0.120396 0.3048)
			(stroke
				(width 0.1)
				(type default)
			)
			(layer "F.Fab")
		)
		(fp_line
			(start -0.12065 0.2794)
			(end -0.12065 0.3048)
			(stroke
				(width 0.1)
				(type default)
			)
			(layer "F.Fab")
		)
		(fp_line
			(start 0.120396 0.2794)
			(end -0.12065 0.2794)
			(stroke
				(width 0.1)
				(type default)
			)
			(layer "F.Fab")
		)
		(fp_line
			(start -0.12065 -0.2794)
			(end 0.12065 -0.2794)
			(stroke
				(width 0.1)
				(type default)
			)
			(layer "F.Fab")
		)
		(fp_line
			(start 0.12065 -0.2794)
			(end 0.12065 -0.3048)
			(stroke
				(width 0.1)
				(type default)
			)
			(layer "F.Fab")
		)
		(fp_line
			(start 0.12065 -0.3048)
			(end 0.67945 -0.3048)
			(stroke
				(width 0.1)
				(type default)
			)
			(layer "F.Fab")
		)
		(fp_line
			(start 0.67945 -0.3048)
			(end 0.67945 0.3048)
			(stroke
				(width 0.1)
				(type default)
			)
			(layer "F.Fab")
		)
		(fp_line
			(start -0.67945 -0.305054)
			(end -0.12065 -0.305054)
			(stroke
				(width 0.1)
				(type default)
			)
			(layer "F.Fab")
		)
		(fp_line
			(start -0.12065 -0.305054)
			(end -0.12065 -0.2794)
			(stroke
				(width 0.1)
				(type default)
			)
			(layer "F.Fab")
		)
		(pad "1" smd circle
			(at -0.40005 0 270)
			(size 0 0)
			(layers "F.Cu" "F.Mask" "F.Paste")
			(net "P3V3_SSD11_CO_MODE")
		)
		(pad "2" smd circle
			(at 0.40005 0 270)
			(size 0 0)
			(layers "F.Cu" "F.Mask" "F.Paste")
			(net "GND")
		)
	)
	(footprint ""
		(layer "F.Cu")
		(at 373.658384 -250.070874 -90)
		(property "Reference" "R1412"
			(at 0 0 270)
			(layer "F.SilkS")
			(hide yes)
			(effects
				(font
					(size 1.27 1.27)
				)
			)
		)
		(property "Value" ""
			(at 0 0 270)
			(layer "F.Fab")
			(effects
				(font
					(size 1.27 1.27)
				)
			)
		)
		(duplicate_pad_numbers_are_jumpers no)
		(fp_line
			(start -0.7874 0.4064)
			(end -0.7874 -0.4064)
			(stroke
				(width 0.1524)
				(type default)
			)
			(layer "F.SilkS")
		)
		(fp_line
			(start 0.7874 0.4064)
			(end -0.7874 0.4064)
			(stroke
				(width 0.1524)
				(type default)
			)
			(layer "F.SilkS")
		)
		(fp_line
			(start -0.7874 -0.4064)
			(end 0.7874 -0.4064)
			(stroke
				(width 0.1524)
				(type default)
			)
			(layer "F.SilkS")
		)
		(fp_line
			(start 0.7874 -0.4064)
			(end 0.7874 0.4064)
			(stroke
				(width 0.1524)
				(type default)
			)
			(layer "F.SilkS")
		)
		(fp_line
			(start -0.67945 0.3048)
			(end -0.67945 -0.305054)
			(stroke
				(width 0.1)
				(type default)
			)
			(layer "F.Fab")
		)
		(fp_line
			(start -0.12065 0.3048)
			(end -0.67945 0.3048)
			(stroke
				(width 0.1)
				(type default)
			)
			(layer "F.Fab")
		)
		(fp_line
			(start 0.120396 0.3048)
			(end 0.120396 0.2794)
			(stroke
				(width 0.1)
				(type default)
			)
			(layer "F.Fab")
		)
		(fp_line
			(start 0.67945 0.3048)
			(end 0.120396 0.3048)
			(stroke
				(width 0.1)
				(type default)
			)
			(layer "F.Fab")
		)
		(fp_line
			(start -0.12065 0.2794)
			(end -0.12065 0.3048)
			(stroke
				(width 0.1)
				(type default)
			)
			(layer "F.Fab")
		)
		(fp_line
			(start 0.120396 0.2794)
			(end -0.12065 0.2794)
			(stroke
				(width 0.1)
				(type default)
			)
			(layer "F.Fab")
		)
		(fp_line
			(start -0.12065 -0.2794)
			(end 0.12065 -0.2794)
			(stroke
				(width 0.1)
				(type default)
			)
			(layer "F.Fab")
		)
		(fp_line
			(start 0.12065 -0.2794)
			(end 0.12065 -0.3048)
			(stroke
				(width 0.1)
				(type default)
			)
			(layer "F.Fab")
		)
		(fp_line
			(start 0.12065 -0.3048)
			(end 0.67945 -0.3048)
			(stroke
				(width 0.1)
				(type default)
			)
			(layer "F.Fab")
		)
		(fp_line
			(start 0.67945 -0.3048)
			(end 0.67945 0.3048)
			(stroke
				(width 0.1)
				(type default)
			)
			(layer "F.Fab")
		)
		(fp_line
			(start -0.67945 -0.305054)
			(end -0.12065 -0.305054)
			(stroke
				(width 0.1)
				(type default)
			)
			(layer "F.Fab")
		)
		(fp_line
			(start -0.12065 -0.305054)
			(end -0.12065 -0.2794)
			(stroke
				(width 0.1)
				(type default)
			)
			(layer "F.Fab")
		)
		(pad "1" smd circle
			(at -0.40005 0 270)
			(size 0 0)
			(layers "F.Cu" "F.Mask" "F.Paste")
			(net "PEX3_MODE_SEL7")
		)
		(pad "2" smd circle
			(at 0.40005 0 270)
			(size 0 0)
			(layers "F.Cu" "F.Mask" "F.Paste")
			(net "P1V8_PEX")
		)
	)
	(footprint ""
		(layer "F.Cu")
		(at 376.936 -184.785 180)
		(property "Reference" "R4616"
			(at 0 0 180)
			(layer "F.SilkS")
			(hide yes)
			(effects
				(font
					(size 1.27 1.27)
				)
			)
		)
		(property "Value" ""
			(at 0 0 180)
			(layer "F.Fab")
			(effects
				(font
					(size 1.27 1.27)
				)
			)
		)
		(duplicate_pad_numbers_are_jumpers no)
		(fp_line
			(start 0.7874 0.4064)
			(end -0.7874 0.4064)
			(stroke
				(width 0.1524)
				(type default)
			)
			(layer "F.SilkS")
		)
		(fp_line
			(start 0.7874 -0.4064)
			(end 0.7874 0.4064)
			(stroke
				(width 0.1524)
				(type default)
			)
			(layer "F.SilkS")
		)
		(fp_line
			(start -0.7874 0.4064)
			(end -0.7874 -0.4064)
			(stroke
				(width 0.1524)
				(type default)
			)
			(layer "F.SilkS")
		)
		(fp_line
			(start -0.7874 -0.4064)
			(end 0.7874 -0.4064)
			(stroke
				(width 0.1524)
				(type default)
			)
			(layer "F.SilkS")
		)
		(fp_line
			(start 0.67945 0.3048)
			(end 0.120396 0.3048)
			(stroke
				(width 0.1)
				(type default)
			)
			(layer "F.Fab")
		)
		(fp_line
			(start 0.67945 -0.3048)
			(end 0.67945 0.3048)
			(stroke
				(width 0.1)
				(type default)
			)
			(layer "F.Fab")
		)
		(fp_line
			(start 0.12065 -0.2794)
			(end 0.12065 -0.3048)
			(stroke
				(width 0.1)
				(type default)
			)
			(layer "F.Fab")
		)
		(fp_line
			(start 0.12065 -0.3048)
			(end 0.67945 -0.3048)
			(stroke
				(width 0.1)
				(type default)
			)
			(layer "F.Fab")
		)
		(fp_line
			(start 0.120396 0.3048)
			(end 0.120396 0.2794)
			(stroke
				(width 0.1)
				(type default)
			)
			(layer "F.Fab")
		)
		(fp_line
			(start 0.120396 0.2794)
			(end -0.12065 0.2794)
			(stroke
				(width 0.1)
				(type default)
			)
			(layer "F.Fab")
		)
		(fp_line
			(start -0.12065 0.3048)
			(end -0.67945 0.3048)
			(stroke
				(width 0.1)
				(type default)
			)
			(layer "F.Fab")
		)
		(fp_line
			(start -0.12065 0.2794)
			(end -0.12065 0.3048)
			(stroke
				(width 0.1)
				(type default)
			)
			(layer "F.Fab")
		)
		(fp_line
			(start -0.12065 -0.2794)
			(end 0.12065 -0.2794)
			(stroke
				(width 0.1)
				(type default)
			)
			(layer "F.Fab")
		)
		(fp_line
			(start -0.12065 -0.305054)
			(end -0.12065 -0.2794)
			(stroke
				(width 0.1)
				(type default)
			)
			(layer "F.Fab")
		)
		(fp_line
			(start -0.67945 0.3048)
			(end -0.67945 -0.305054)
			(stroke
				(width 0.1)
				(type default)
			)
			(layer "F.Fab")
		)
		(fp_line
			(start -0.67945 -0.305054)
			(end -0.12065 -0.305054)
			(stroke
				(width 0.1)
				(type default)
			)
			(layer "F.Fab")
		)
		(pad "1" smd circle
			(at -0.40005 0 180)
			(size 0 0)
			(layers "F.Cu" "F.Mask" "F.Paste")
			(net "NIC1_PEX_PWR_EN_R")
		)
		(pad "2" smd circle
			(at 0.40005 0 180)
			(size 0 0)
			(layers "F.Cu" "F.Mask" "F.Paste")
			(net "GND")
		)
	)
	(footprint ""
		(layer "F.Cu")
		(at 358.013 -222.504)
		(property "Reference" "R3639"
			(at 0 0 0)
			(layer "F.SilkS")
			(hide yes)
			(effects
				(font
					(size 1.27 1.27)
				)
			)
		)
		(property "Value" ""
			(at 0 0 0)
			(layer "F.Fab")
			(effects
				(font
					(size 1.27 1.27)
				)
			)
		)
		(duplicate_pad_numbers_are_jumpers no)
		(fp_line
			(start -0.7874 -0.4064)
			(end 0.7874 -0.4064)
			(stroke
				(width 0.1524)
				(type default)
			)
			(layer "F.SilkS")
		)
		(fp_line
			(start -0.7874 0.4064)
			(end -0.7874 -0.4064)
			(stroke
				(width 0.1524)
				(type default)
			)
			(layer "F.SilkS")
		)
		(fp_line
			(start 0.7874 -0.4064)
			(end 0.7874 0.4064)
			(stroke
				(width 0.1524)
				(type default)
			)
			(layer "F.SilkS")
		)
		(fp_line
			(start 0.7874 0.4064)
			(end -0.7874 0.4064)
			(stroke
				(width 0.1524)
				(type default)
			)
			(layer "F.SilkS")
		)
		(fp_line
			(start -0.67945 -0.305054)
			(end -0.12065 -0.305054)
			(stroke
				(width 0.1)
				(type default)
			)
			(layer "F.Fab")
		)
		(fp_line
			(start -0.67945 0.3048)
			(end -0.67945 -0.305054)
			(stroke
				(width 0.1)
				(type default)
			)
			(layer "F.Fab")
		)
		(fp_line
			(start -0.12065 -0.305054)
			(end -0.12065 -0.2794)
			(stroke
				(width 0.1)
				(type default)
			)
			(layer "F.Fab")
		)
		(fp_line
			(start -0.12065 -0.2794)
			(end 0.12065 -0.2794)
			(stroke
				(width 0.1)
				(type default)
			)
			(layer "F.Fab")
		)
		(fp_line
			(start -0.12065 0.2794)
			(end -0.12065 0.3048)
			(stroke
				(width 0.1)
				(type default)
			)
			(layer "F.Fab")
		)
		(fp_line
			(start -0.12065 0.3048)
			(end -0.67945 0.3048)
			(stroke
				(width 0.1)
				(type default)
			)
			(layer "F.Fab")
		)
		(fp_line
			(start 0.120396 0.2794)
			(end -0.12065 0.2794)
			(stroke
				(width 0.1)
				(type default)
			)
			(layer "F.Fab")
		)
		(fp_line
			(start 0.120396 0.3048)
			(end 0.120396 0.2794)
			(stroke
				(width 0.1)
				(type default)
			)
			(layer "F.Fab")
		)
		(fp_line
			(start 0.12065 -0.3048)
			(end 0.67945 -0.3048)
			(stroke
				(width 0.1)
				(type default)
			)
			(layer "F.Fab")
		)
		(fp_line
			(start 0.12065 -0.2794)
			(end 0.12065 -0.3048)
			(stroke
				(width 0.1)
				(type default)
			)
			(layer "F.Fab")
		)
		(fp_line
			(start 0.67945 -0.3048)
			(end 0.67945 0.3048)
			(stroke
				(width 0.1)
				(type default)
			)
			(layer "F.Fab")
		)
		(fp_line
			(start 0.67945 0.3048)
			(end 0.120396 0.3048)
			(stroke
				(width 0.1)
				(type default)
			)
			(layer "F.Fab")
		)
		(pad "1" smd circle
			(at -0.40005 0)
			(size 0 0)
			(layers "F.Cu" "F.Mask" "F.Paste")
			(net "RST_NIC4_PERST_N")
		)
		(pad "2" smd circle
			(at 0.40005 0)
			(size 0 0)
			(layers "F.Cu" "F.Mask" "F.Paste")
			(net "RST_NIC4_PERST_R_N")
		)
	)
	(footprint ""
		(layer "F.Cu")
		(at 93.350842 -350.098614 90)
		(property "Reference" "C98"
			(at 0 0 90)
			(layer "F.SilkS")
			(hide yes)
			(effects
				(font
					(size 1.27 1.27)
				)
			)
		)
		(property "Value" ""
			(at 0 0 90)
			(layer "F.Fab")
			(effects
				(font
					(size 1.27 1.27)
				)
			)
		)
		(duplicate_pad_numbers_are_jumpers no)
		(fp_line
			(start 0.299974 -0.150114)
			(end 0.299974 0.150114)
			(stroke
				(width 0.1)
				(type default)
			)
			(layer "F.Fab")
		)
		(fp_line
			(start -0.299974 -0.150114)
			(end 0.299974 -0.150114)
			(stroke
				(width 0.1)
				(type default)
			)
			(layer "F.Fab")
		)
		(fp_line
			(start 0.299974 0.150114)
			(end -0.299974 0.150114)
			(stroke
				(width 0.1)
				(type default)
			)
			(layer "F.Fab")
		)
		(fp_line
			(start -0.299974 0.150114)
			(end -0.299974 -0.150114)
			(stroke
				(width 0.1)
				(type default)
			)
			(layer "F.Fab")
		)
		(pad "1" smd rect
			(at -0.2667 0 90)
			(size 0.3048 0.381)
			(layers "F.Cu" "F.Mask" "F.Paste")
			(net "P5E_PEX0_STN5_TX_DN<95>")
		)
		(pad "2" smd rect
			(at 0.2667 0 90)
			(size 0.3048 0.381)
			(layers "F.Cu" "F.Mask" "F.Paste")
			(net "P5E_PEX0_STN5_TX_C_DN<95>")
		)
	)
	(footprint ""
		(layer "F.Cu")
		(at 145.457926 -27.006296 -90)
		(property "Reference" "PR7109"
			(at 0 0 270)
			(layer "F.SilkS")
			(hide yes)
			(effects
				(font
					(size 1.27 1.27)
				)
			)
		)
		(property "Value" ""
			(at 0 0 270)
			(layer "F.Fab")
			(effects
				(font
					(size 1.27 1.27)
				)
			)
		)
		(duplicate_pad_numbers_are_jumpers no)
		(fp_line
			(start -0.7874 0.4064)
			(end -0.7874 -0.4064)
			(stroke
				(width 0.1524)
				(type default)
			)
			(layer "F.SilkS")
		)
		(fp_line
			(start 0.7874 0.4064)
			(end -0.7874 0.4064)
			(stroke
				(width 0.1524)
				(type default)
			)
			(layer "F.SilkS")
		)
		(fp_line
			(start -0.7874 -0.4064)
			(end 0.7874 -0.4064)
			(stroke
				(width 0.1524)
				(type default)
			)
			(layer "F.SilkS")
		)
		(fp_line
			(start 0.7874 -0.4064)
			(end 0.7874 0.4064)
			(stroke
				(width 0.1524)
				(type default)
			)
			(layer "F.SilkS")
		)
		(fp_line
			(start -0.67945 0.3048)
			(end -0.67945 -0.305054)
			(stroke
				(width 0.1)
				(type default)
			)
			(layer "F.Fab")
		)
		(fp_line
			(start -0.12065 0.3048)
			(end -0.67945 0.3048)
			(stroke
				(width 0.1)
				(type default)
			)
			(layer "F.Fab")
		)
		(fp_line
			(start 0.120396 0.3048)
			(end 0.120396 0.2794)
			(stroke
				(width 0.1)
				(type default)
			)
			(layer "F.Fab")
		)
		(fp_line
			(start 0.67945 0.3048)
			(end 0.120396 0.3048)
			(stroke
				(width 0.1)
				(type default)
			)
			(layer "F.Fab")
		)
		(fp_line
			(start -0.12065 0.2794)
			(end -0.12065 0.3048)
			(stroke
				(width 0.1)
				(type default)
			)
			(layer "F.Fab")
		)
		(fp_line
			(start 0.120396 0.2794)
			(end -0.12065 0.2794)
			(stroke
				(width 0.1)
				(type default)
			)
			(layer "F.Fab")
		)
		(fp_line
			(start -0.12065 -0.2794)
			(end 0.12065 -0.2794)
			(stroke
				(width 0.1)
				(type default)
			)
			(layer "F.Fab")
		)
		(fp_line
			(start 0.12065 -0.2794)
			(end 0.12065 -0.3048)
			(stroke
				(width 0.1)
				(type default)
			)
			(layer "F.Fab")
		)
		(fp_line
			(start 0.12065 -0.3048)
			(end 0.67945 -0.3048)
			(stroke
				(width 0.1)
				(type default)
			)
			(layer "F.Fab")
		)
		(fp_line
			(start 0.67945 -0.3048)
			(end 0.67945 0.3048)
			(stroke
				(width 0.1)
				(type default)
			)
			(layer "F.Fab")
		)
		(fp_line
			(start -0.67945 -0.305054)
			(end -0.12065 -0.305054)
			(stroke
				(width 0.1)
				(type default)
			)
			(layer "F.Fab")
		)
		(fp_line
			(start -0.12065 -0.305054)
			(end -0.12065 -0.2794)
			(stroke
				(width 0.1)
				(type default)
			)
			(layer "F.Fab")
		)
		(pad "1" smd circle
			(at -0.40005 0 270)
			(size 0 0)
			(layers "F.Cu" "F.Mask" "F.Paste")
			(net "P3V3_SSD5_CO_MODE")
		)
		(pad "2" smd circle
			(at 0.40005 0 270)
			(size 0 0)
			(layers "F.Cu" "F.Mask" "F.Paste")
			(net "GND")
		)
	)
	(footprint ""
		(layer "F.Cu")
		(at 90.639392 -293.47287 -90)
		(property "Reference" "U313"
			(at -0.535178 -4.855718 90)
			(unlocked yes)
			(layer "F.SilkS")
			(effects
				(font
					(size 0.7874 0.5842)
					(thickness 0.1524)
				)
			)
		)
		(property "Value" ""
			(at 0 0 270)
			(layer "F.Fab")
			(effects
				(font
					(size 1.27 1.27)
				)
			)
		)
		(duplicate_pad_numbers_are_jumpers no)
		(fp_line
			(start -1.463548 1.549908)
			(end -1.463548 -1.549908)
			(stroke
				(width 0.1524)
				(type default)
			)
			(layer "F.SilkS")
		)
		(fp_line
			(start 1.463548 1.549908)
			(end -1.463548 1.549908)
			(stroke
				(width 0.1524)
				(type default)
			)
			(layer "F.SilkS")
		)
		(fp_line
			(start 0 -0.762)
			(end 0.762 -1.549908)
			(stroke
				(width 0.1524)
				(type default)
			)
			(layer "F.SilkS")
		)
		(fp_line
			(start -1.463548 -1.549908)
			(end -0.787908 -1.549908)
			(stroke
				(width 0.1524)
				(type default)
			)
			(layer "F.SilkS")
		)
		(fp_line
			(start -0.787908 -1.549908)
			(end 0 -0.762)
			(stroke
				(width 0.1524)
				(type default)
			)
			(layer "F.SilkS")
		)
		(fp_line
			(start 0.762 -1.549908)
			(end 1.463548 -1.549908)
			(stroke
				(width 0.1524)
				(type default)
			)
			(layer "F.SilkS")
		)
		(fp_line
			(start 1.463548 -1.549908)
			(end 1.463548 1.549908)
			(stroke
				(width 0.1524)
				(type default)
			)
			(layer "F.SilkS")
		)
		(fp_poly
			(pts
				(xy -3.4798 -1.359916) (xy -2.86004 -1.050036) (xy -3.4798 -0.740156)
			)
			(stroke
				(width 0)
				(type default)
			)
			(fill yes)
			(layer "F.SilkS")
		)
		(fp_line
			(start -1.549908 1.549908)
			(end -1.549908 -1.549908)
			(stroke
				(width 0.1)
				(type default)
			)
			(layer "F.Fab")
		)
		(fp_line
			(start 1.549908 1.549908)
			(end -1.549908 1.549908)
			(stroke
				(width 0.1)
				(type default)
			)
			(layer "F.Fab")
		)
		(fp_line
			(start -1.549908 -1.549908)
			(end 1.549908 -1.549908)
			(stroke
				(width 0.1)
				(type default)
			)
			(layer "F.Fab")
		)
		(fp_line
			(start 1.549908 -1.549908)
			(end 1.549908 1.549908)
			(stroke
				(width 0.1)
				(type default)
			)
			(layer "F.Fab")
		)
		(fp_poly
			(pts
				(xy -3.4798 -1.359916) (xy -2.86004 -1.050036) (xy -3.4798 -0.740156)
			)
			(stroke
				(width 0)
				(type default)
			)
			(fill yes)
			(layer "F.Fab")
		)
		(pad "1" smd rect
			(at -2.175002 -1.050036)
			(size 0.6096 1.1684)
			(layers "F.Cu" "F.Mask" "F.Paste")
			(net "P1V8_PEX")
		)
		(pad "2" smd rect
			(at -2.175002 -0.32512)
			(size 0.4318 1.1684)
			(layers "F.Cu" "F.Mask" "F.Paste")
			(net "I2C_PEX0_HOST_R_SCL")
		)
		(pad "3" smd rect
			(at -2.175002 0.32512)
			(size 0.4318 1.1684)
			(layers "F.Cu" "F.Mask" "F.Paste")
			(net "I2C_PEX0_HOST_R_SDA")
		)
		(pad "4" smd rect
			(at -2.175002 1.050036)
			(size 0.6096 1.1684)
			(layers "F.Cu" "F.Mask" "F.Paste")
			(net "GND")
		)
		(pad "5" smd rect
			(at 2.175002 1.050036)
			(size 0.6096 1.1684)
			(layers "F.Cu" "F.Mask" "F.Paste")
			(net "PWRGD_P1V8_PEX0_R")
		)
		(pad "6" smd rect
			(at 2.175002 0.32512)
			(size 0.4318 1.1684)
			(layers "F.Cu" "F.Mask" "F.Paste")
			(net "SMB_PEX0_HOST_LS_SDA")
		)
		(pad "7" smd rect
			(at 2.175002 -0.32512)
			(size 0.4318 1.1684)
			(layers "F.Cu" "F.Mask" "F.Paste")
			(net "SMB_PEX0_HOST_LS_SCL")
		)
		(pad "8" smd rect
			(at 2.175002 -1.050036)
			(size 0.6096 1.1684)
			(layers "F.Cu" "F.Mask" "F.Paste")
			(net "P3V3_AUX")
		)
	)
	(footprint ""
		(layer "F.Cu")
		(at 129.690114 -253.178564 180)
		(property "Reference" "R826"
			(at 0 0 180)
			(layer "F.SilkS")
			(hide yes)
			(effects
				(font
					(size 1.27 1.27)
				)
			)
		)
		(property "Value" ""
			(at 0 0 180)
			(layer "F.Fab")
			(effects
				(font
					(size 1.27 1.27)
				)
			)
		)
		(duplicate_pad_numbers_are_jumpers no)
		(fp_line
			(start 0.7874 0.4064)
			(end -0.7874 0.4064)
			(stroke
				(width 0.1524)
				(type default)
			)
			(layer "F.SilkS")
		)
		(fp_line
			(start 0.7874 -0.4064)
			(end 0.7874 0.4064)
			(stroke
				(width 0.1524)
				(type default)
			)
			(layer "F.SilkS")
		)
		(fp_line
			(start -0.7874 0.4064)
			(end -0.7874 -0.4064)
			(stroke
				(width 0.1524)
				(type default)
			)
			(layer "F.SilkS")
		)
		(fp_line
			(start -0.7874 -0.4064)
			(end 0.7874 -0.4064)
			(stroke
				(width 0.1524)
				(type default)
			)
			(layer "F.SilkS")
		)
		(fp_line
			(start 0.67945 0.3048)
			(end 0.120396 0.3048)
			(stroke
				(width 0.1)
				(type default)
			)
			(layer "F.Fab")
		)
		(fp_line
			(start 0.67945 -0.3048)
			(end 0.67945 0.3048)
			(stroke
				(width 0.1)
				(type default)
			)
			(layer "F.Fab")
		)
		(fp_line
			(start 0.12065 -0.2794)
			(end 0.12065 -0.3048)
			(stroke
				(width 0.1)
				(type default)
			)
			(layer "F.Fab")
		)
		(fp_line
			(start 0.12065 -0.3048)
			(end 0.67945 -0.3048)
			(stroke
				(width 0.1)
				(type default)
			)
			(layer "F.Fab")
		)
		(fp_line
			(start 0.120396 0.3048)
			(end 0.120396 0.2794)
			(stroke
				(width 0.1)
				(type default)
			)
			(layer "F.Fab")
		)
		(fp_line
			(start 0.120396 0.2794)
			(end -0.12065 0.2794)
			(stroke
				(width 0.1)
				(type default)
			)
			(layer "F.Fab")
		)
		(fp_line
			(start -0.12065 0.3048)
			(end -0.67945 0.3048)
			(stroke
				(width 0.1)
				(type default)
			)
			(layer "F.Fab")
		)
		(fp_line
			(start -0.12065 0.2794)
			(end -0.12065 0.3048)
			(stroke
				(width 0.1)
				(type default)
			)
			(layer "F.Fab")
		)
		(fp_line
			(start -0.12065 -0.2794)
			(end 0.12065 -0.2794)
			(stroke
				(width 0.1)
				(type default)
			)
			(layer "F.Fab")
		)
		(fp_line
			(start -0.12065 -0.305054)
			(end -0.12065 -0.2794)
			(stroke
				(width 0.1)
				(type default)
			)
			(layer "F.Fab")
		)
		(fp_line
			(start -0.67945 0.3048)
			(end -0.67945 -0.305054)
			(stroke
				(width 0.1)
				(type default)
			)
			(layer "F.Fab")
		)
		(fp_line
			(start -0.67945 -0.305054)
			(end -0.12065 -0.305054)
			(stroke
				(width 0.1)
				(type default)
			)
			(layer "F.Fab")
		)
		(pad "1" smd circle
			(at -0.40005 0 180)
			(size 0 0)
			(layers "F.Cu" "F.Mask" "F.Paste")
			(net "PWRGD_P0V8_PEX0_R")
		)
		(pad "2" smd circle
			(at 0.40005 0 180)
			(size 0 0)
			(layers "F.Cu" "F.Mask" "F.Paste")
			(net "P0V8_PEX0_AVRRDY")
		)
	)
	(footprint ""
		(layer "F.Cu")
		(at 38.832028 -147.969224 90)
		(property "Reference" "C846"
			(at 0 0 90)
			(layer "F.SilkS")
			(hide yes)
			(effects
				(font
					(size 1.27 1.27)
				)
			)
		)
		(property "Value" ""
			(at 0 0 90)
			(layer "F.Fab")
			(effects
				(font
					(size 1.27 1.27)
				)
			)
		)
		(duplicate_pad_numbers_are_jumpers no)
		(fp_line
			(start 1.524 -0.762)
			(end 1.524 0.762)
			(stroke
				(width 0.1524)
				(type default)
			)
			(layer "F.SilkS")
		)
		(fp_line
			(start -1.524 -0.762)
			(end 1.524 -0.762)
			(stroke
				(width 0.1524)
				(type default)
			)
			(layer "F.SilkS")
		)
		(fp_line
			(start 1.524 0.762)
			(end -1.524 0.762)
			(stroke
				(width 0.1524)
				(type default)
			)
			(layer "F.SilkS")
		)
		(fp_line
			(start -1.524 0.762)
			(end -1.524 -0.762)
			(stroke
				(width 0.1524)
				(type default)
			)
			(layer "F.SilkS")
		)
		(fp_line
			(start 1.1049 -0.724916)
			(end -1.1049 -0.724916)
			(stroke
				(width 0.1)
				(type default)
			)
			(layer "F.Fab")
		)
		(fp_line
			(start -1.1049 -0.724916)
			(end -1.1049 0.724916)
			(stroke
				(width 0.1)
				(type default)
			)
			(layer "F.Fab")
		)
		(fp_line
			(start 1.1049 0.724916)
			(end 1.1049 -0.724916)
			(stroke
				(width 0.1)
				(type default)
			)
			(layer "F.Fab")
		)
		(fp_line
			(start -1.1049 0.724916)
			(end 1.1049 0.724916)
			(stroke
				(width 0.1)
				(type default)
			)
			(layer "F.Fab")
		)
		(pad "1" smd rect
			(at -0.889 0 270)
			(size 1.016 1.27)
			(layers "F.Cu" "F.Mask" "F.Paste")
			(net "P12V_NIC0")
		)
		(pad "2" smd rect
			(at 0.889 0 270)
			(size 1.016 1.27)
			(layers "F.Cu" "F.Mask" "F.Paste")
			(net "GND")
		)
	)
	(footprint ""
		(layer "F.Cu")
		(at 146.253454 -291.390832)
		(property "Reference" "L108"
			(at 0 0 0)
			(layer "F.SilkS")
			(hide yes)
			(effects
				(font
					(size 1.27 1.27)
				)
			)
		)
		(property "Value" ""
			(at 0 0 0)
			(layer "F.Fab")
			(effects
				(font
					(size 1.27 1.27)
				)
			)
		)
		(duplicate_pad_numbers_are_jumpers no)
		(fp_line
			(start -1.63576 -0.8128)
			(end -1.63576 0.8128)
			(stroke
				(width 0.1524)
				(type default)
			)
			(layer "F.SilkS")
		)
		(fp_line
			(start -1.63576 -0.8128)
			(end 1.63576 -0.8128)
			(stroke
				(width 0.1524)
				(type default)
			)
			(layer "F.SilkS")
		)
		(fp_line
			(start 1.63576 -0.8128)
			(end 1.63576 0.8128)
			(stroke
				(width 0.1524)
				(type default)
			)
			(layer "F.SilkS")
		)
		(fp_line
			(start 1.63576 0.8128)
			(end -1.63576 0.8128)
			(stroke
				(width 0.1524)
				(type default)
			)
			(layer "F.SilkS")
		)
		(fp_line
			(start -1.56083 -0.738632)
			(end -1.56083 0.7366)
			(stroke
				(width 0.1)
				(type default)
			)
			(layer "F.Fab")
		)
		(fp_line
			(start -1.56083 0.7366)
			(end -1.524 0.7366)
			(stroke
				(width 0.1)
				(type default)
			)
			(layer "F.Fab")
		)
		(fp_line
			(start -1.524 0.7366)
			(end 1.524 0.7366)
			(stroke
				(width 0.1)
				(type default)
			)
			(layer "F.Fab")
		)
		(fp_line
			(start 1.524 0.7366)
			(end 1.560576 0.7366)
			(stroke
				(width 0.1)
				(type default)
			)
			(layer "F.Fab")
		)
		(fp_line
			(start 1.560576 -0.738632)
			(end -1.56083 -0.738632)
			(stroke
				(width 0.1)
				(type default)
			)
			(layer "F.Fab")
		)
		(fp_line
			(start 1.560576 0.7366)
			(end 1.560576 -0.738632)
			(stroke
				(width 0.1)
				(type default)
			)
			(layer "F.Fab")
		)
		(pad "1" smd rect
			(at -0.94996 0 180)
			(size 1.1176 1.3716)
			(layers "F.Cu" "F.Mask" "F.Paste")
			(net "P1V8_PLL0_PEX1")
		)
		(pad "2" smd rect
			(at 0.94996 0 180)
			(size 1.1176 1.3716)
			(layers "F.Cu" "F.Mask" "F.Paste")
			(net "PCEPLL4_VDDA18_PEX1")
		)
	)
	(footprint ""
		(layer "F.Cu")
		(at 162.775138 -56.977534 180)
		(property "Reference" "PC366"
			(at 0 0 180)
			(layer "F.SilkS")
			(hide yes)
			(effects
				(font
					(size 1.27 1.27)
				)
			)
		)
		(property "Value" ""
			(at 0 0 180)
			(layer "F.Fab")
			(effects
				(font
					(size 1.27 1.27)
				)
			)
		)
		(duplicate_pad_numbers_are_jumpers no)
		(fp_line
			(start 0.7874 0.4064)
			(end -0.7874 0.4064)
			(stroke
				(width 0.1524)
				(type default)
			)
			(layer "F.SilkS")
		)
		(fp_line
			(start 0.7874 -0.4064)
			(end 0.7874 0.4064)
			(stroke
				(width 0.1524)
				(type default)
			)
			(layer "F.SilkS")
		)
		(fp_line
			(start -0.7874 0.4064)
			(end -0.7874 -0.4064)
			(stroke
				(width 0.1524)
				(type default)
			)
			(layer "F.SilkS")
		)
		(fp_line
			(start -0.7874 -0.4064)
			(end 0.7874 -0.4064)
			(stroke
				(width 0.1524)
				(type default)
			)
			(layer "F.SilkS")
		)
		(fp_line
			(start 0.67945 0.3048)
			(end 0.120396 0.3048)
			(stroke
				(width 0.1)
				(type default)
			)
			(layer "F.Fab")
		)
		(fp_line
			(start 0.67945 -0.3048)
			(end 0.67945 0.3048)
			(stroke
				(width 0.1)
				(type default)
			)
			(layer "F.Fab")
		)
		(fp_line
			(start 0.12065 -0.2794)
			(end 0.12065 -0.3048)
			(stroke
				(width 0.1)
				(type default)
			)
			(layer "F.Fab")
		)
		(fp_line
			(start 0.12065 -0.3048)
			(end 0.67945 -0.3048)
			(stroke
				(width 0.1)
				(type default)
			)
			(layer "F.Fab")
		)
		(fp_line
			(start 0.120396 0.3048)
			(end 0.120396 0.2794)
			(stroke
				(width 0.1)
				(type default)
			)
			(layer "F.Fab")
		)
		(fp_line
			(start 0.120396 0.2794)
			(end -0.12065 0.2794)
			(stroke
				(width 0.1)
				(type default)
			)
			(layer "F.Fab")
		)
		(fp_line
			(start -0.12065 0.3048)
			(end -0.67945 0.3048)
			(stroke
				(width 0.1)
				(type default)
			)
			(layer "F.Fab")
		)
		(fp_line
			(start -0.12065 0.2794)
			(end -0.12065 0.3048)
			(stroke
				(width 0.1)
				(type default)
			)
			(layer "F.Fab")
		)
		(fp_line
			(start -0.12065 -0.2794)
			(end 0.12065 -0.2794)
			(stroke
				(width 0.1)
				(type default)
			)
			(layer "F.Fab")
		)
		(fp_line
			(start -0.12065 -0.305054)
			(end -0.12065 -0.2794)
			(stroke
				(width 0.1)
				(type default)
			)
			(layer "F.Fab")
		)
		(fp_line
			(start -0.67945 0.3048)
			(end -0.67945 -0.305054)
			(stroke
				(width 0.1)
				(type default)
			)
			(layer "F.Fab")
		)
		(fp_line
			(start -0.67945 -0.305054)
			(end -0.12065 -0.305054)
			(stroke
				(width 0.1)
				(type default)
			)
			(layer "F.Fab")
		)
		(pad "1" smd circle
			(at -0.40005 0 180)
			(size 0 0)
			(layers "F.Cu" "F.Mask" "F.Paste")
			(net "P12V_AUX")
		)
		(pad "2" smd circle
			(at 0.40005 0 180)
			(size 0 0)
			(layers "F.Cu" "F.Mask" "F.Paste")
			(net "GND")
		)
	)
	(footprint ""
		(layer "F.Cu")
		(at 430.961546 -131.686808 180)
		(property "Reference" "C655"
			(at 0 0 180)
			(layer "F.SilkS")
			(hide yes)
			(effects
				(font
					(size 1.27 1.27)
				)
			)
		)
		(property "Value" ""
			(at 0 0 180)
			(layer "F.Fab")
			(effects
				(font
					(size 1.27 1.27)
				)
			)
		)
		(duplicate_pad_numbers_are_jumpers no)
		(fp_line
			(start 0.299974 0.150114)
			(end -0.299974 0.150114)
			(stroke
				(width 0.1)
				(type default)
			)
			(layer "F.Fab")
		)
		(fp_line
			(start 0.299974 -0.150114)
			(end 0.299974 0.150114)
			(stroke
				(width 0.1)
				(type default)
			)
			(layer "F.Fab")
		)
		(fp_line
			(start -0.299974 0.150114)
			(end -0.299974 -0.150114)
			(stroke
				(width 0.1)
				(type default)
			)
			(layer "F.Fab")
		)
		(fp_line
			(start -0.299974 -0.150114)
			(end 0.299974 -0.150114)
			(stroke
				(width 0.1)
				(type default)
			)
			(layer "F.Fab")
		)
		(pad "1" smd rect
			(at -0.2667 0 180)
			(size 0.3048 0.381)
			(layers "F.Cu" "F.Mask" "F.Paste")
			(net "P5E_PEX3_STN0_TX_DN<5>")
		)
		(pad "2" smd rect
			(at 0.2667 0 180)
			(size 0.3048 0.381)
			(layers "F.Cu" "F.Mask" "F.Paste")
			(net "P5E_PEX3_STN0_TX_C_DN<5>")
		)
	)
	(footprint ""
		(layer "F.Cu")
		(at 112.198404 -166.252652)
		(property "Reference" "PC27"
			(at 0 0 0)
			(layer "F.SilkS")
			(hide yes)
			(effects
				(font
					(size 1.27 1.27)
				)
			)
		)
		(property "Value" ""
			(at 0 0 0)
			(layer "F.Fab")
			(effects
				(font
					(size 1.27 1.27)
				)
			)
		)
		(duplicate_pad_numbers_are_jumpers no)
		(fp_line
			(start -1.524 -0.762)
			(end 1.524 -0.762)
			(stroke
				(width 0.1524)
				(type default)
			)
			(layer "F.SilkS")
		)
		(fp_line
			(start -1.524 0.762)
			(end -1.524 -0.762)
			(stroke
				(width 0.1524)
				(type default)
			)
			(layer "F.SilkS")
		)
		(fp_line
			(start 1.524 -0.762)
			(end 1.524 0.762)
			(stroke
				(width 0.1524)
				(type default)
			)
			(layer "F.SilkS")
		)
		(fp_line
			(start 1.524 0.762)
			(end -1.524 0.762)
			(stroke
				(width 0.1524)
				(type default)
			)
			(layer "F.SilkS")
		)
		(fp_line
			(start -1.1049 -0.724916)
			(end -1.1049 0.724916)
			(stroke
				(width 0.1)
				(type default)
			)
			(layer "F.Fab")
		)
		(fp_line
			(start -1.1049 0.724916)
			(end 1.1049 0.724916)
			(stroke
				(width 0.1)
				(type default)
			)
			(layer "F.Fab")
		)
		(fp_line
			(start 1.1049 -0.724916)
			(end -1.1049 -0.724916)
			(stroke
				(width 0.1)
				(type default)
			)
			(layer "F.Fab")
		)
		(fp_line
			(start 1.1049 0.724916)
			(end 1.1049 -0.724916)
			(stroke
				(width 0.1)
				(type default)
			)
			(layer "F.Fab")
		)
		(pad "1" smd rect
			(at -0.889 0 180)
			(size 1.016 1.27)
			(layers "F.Cu" "F.Mask" "F.Paste")
			(net "SW_P12V_P3V3_AUX_FLT")
		)
		(pad "2" smd rect
			(at 0.889 0 180)
			(size 1.016 1.27)
			(layers "F.Cu" "F.Mask" "F.Paste")
			(net "GND")
		)
	)
	(footprint ""
		(layer "F.Cu")
		(at 328.022204 -343.952322 90)
		(property "Reference" "C535"
			(at 0 0 90)
			(layer "F.SilkS")
			(hide yes)
			(effects
				(font
					(size 1.27 1.27)
				)
			)
		)
		(property "Value" ""
			(at 0 0 90)
			(layer "F.Fab")
			(effects
				(font
					(size 1.27 1.27)
				)
			)
		)
		(duplicate_pad_numbers_are_jumpers no)
		(fp_line
			(start 0.299974 -0.150114)
			(end 0.299974 0.150114)
			(stroke
				(width 0.1)
				(type default)
			)
			(layer "F.Fab")
		)
		(fp_line
			(start -0.299974 -0.150114)
			(end 0.299974 -0.150114)
			(stroke
				(width 0.1)
				(type default)
			)
			(layer "F.Fab")
		)
		(fp_line
			(start 0.299974 0.150114)
			(end -0.299974 0.150114)
			(stroke
				(width 0.1)
				(type default)
			)
			(layer "F.Fab")
		)
		(fp_line
			(start -0.299974 0.150114)
			(end -0.299974 -0.150114)
			(stroke
				(width 0.1)
				(type default)
			)
			(layer "F.Fab")
		)
		(pad "1" smd rect
			(at -0.2667 0 90)
			(size 0.3048 0.381)
			(layers "F.Cu" "F.Mask" "F.Paste")
			(net "P5E_PEX2_STN5_TX_DP<87>")
		)
		(pad "2" smd rect
			(at 0.2667 0 90)
			(size 0.3048 0.381)
			(layers "F.Cu" "F.Mask" "F.Paste")
			(net "P5E_PEX2_STN5_TX_C_DP<87>")
		)
	)
	(footprint ""
		(layer "F.Cu")
		(at 376.312684 -91.1098)
		(property "Reference" "R1749"
			(at 0 0 0)
			(layer "F.SilkS")
			(hide yes)
			(effects
				(font
					(size 1.27 1.27)
				)
			)
		)
		(property "Value" ""
			(at 0 0 0)
			(layer "F.Fab")
			(effects
				(font
					(size 1.27 1.27)
				)
			)
		)
		(duplicate_pad_numbers_are_jumpers no)
		(fp_line
			(start -0.7874 -0.4064)
			(end 0.7874 -0.4064)
			(stroke
				(width 0.1524)
				(type default)
			)
			(layer "F.SilkS")
		)
		(fp_line
			(start -0.7874 0.4064)
			(end -0.7874 -0.4064)
			(stroke
				(width 0.1524)
				(type default)
			)
			(layer "F.SilkS")
		)
		(fp_line
			(start 0.7874 -0.4064)
			(end 0.7874 0.4064)
			(stroke
				(width 0.1524)
				(type default)
			)
			(layer "F.SilkS")
		)
		(fp_line
			(start 0.7874 0.4064)
			(end -0.7874 0.4064)
			(stroke
				(width 0.1524)
				(type default)
			)
			(layer "F.SilkS")
		)
		(fp_line
			(start -0.67945 -0.305054)
			(end -0.12065 -0.305054)
			(stroke
				(width 0.1)
				(type default)
			)
			(layer "F.Fab")
		)
		(fp_line
			(start -0.67945 0.3048)
			(end -0.67945 -0.305054)
			(stroke
				(width 0.1)
				(type default)
			)
			(layer "F.Fab")
		)
		(fp_line
			(start -0.12065 -0.305054)
			(end -0.12065 -0.2794)
			(stroke
				(width 0.1)
				(type default)
			)
			(layer "F.Fab")
		)
		(fp_line
			(start -0.12065 -0.2794)
			(end 0.12065 -0.2794)
			(stroke
				(width 0.1)
				(type default)
			)
			(layer "F.Fab")
		)
		(fp_line
			(start -0.12065 0.2794)
			(end -0.12065 0.3048)
			(stroke
				(width 0.1)
				(type default)
			)
			(layer "F.Fab")
		)
		(fp_line
			(start -0.12065 0.3048)
			(end -0.67945 0.3048)
			(stroke
				(width 0.1)
				(type default)
			)
			(layer "F.Fab")
		)
		(fp_line
			(start 0.120396 0.2794)
			(end -0.12065 0.2794)
			(stroke
				(width 0.1)
				(type default)
			)
			(layer "F.Fab")
		)
		(fp_line
			(start 0.120396 0.3048)
			(end 0.120396 0.2794)
			(stroke
				(width 0.1)
				(type default)
			)
			(layer "F.Fab")
		)
		(fp_line
			(start 0.12065 -0.3048)
			(end 0.67945 -0.3048)
			(stroke
				(width 0.1)
				(type default)
			)
			(layer "F.Fab")
		)
		(fp_line
			(start 0.12065 -0.2794)
			(end 0.12065 -0.3048)
			(stroke
				(width 0.1)
				(type default)
			)
			(layer "F.Fab")
		)
		(fp_line
			(start 0.67945 -0.3048)
			(end 0.67945 0.3048)
			(stroke
				(width 0.1)
				(type default)
			)
			(layer "F.Fab")
		)
		(fp_line
			(start 0.67945 0.3048)
			(end 0.120396 0.3048)
			(stroke
				(width 0.1)
				(type default)
			)
			(layer "F.Fab")
		)
		(pad "1" smd circle
			(at -0.40005 0)
			(size 0 0)
			(layers "F.Cu" "F.Mask" "F.Paste")
			(net "P3V3_AUX")
		)
		(pad "2" smd circle
			(at 0.40005 0)
			(size 0 0)
			(layers "F.Cu" "F.Mask" "F.Paste")
			(net "BIC_I2C6_MUX_A0")
		)
	)
	(footprint ""
		(layer "F.Cu")
		(at 147.80006 -407.960068 180)
		(property "Reference" "J64"
			(at 0.590042 -11.910568 0)
			(unlocked yes)
			(layer "F.SilkS")
			(effects
				(font
					(size 0.7874 0.5842)
					(thickness 0.1524)
				)
			)
		)
		(property "Value" ""
			(at 0 0 180)
			(layer "F.Fab")
			(effects
				(font
					(size 1.27 1.27)
				)
			)
		)
		(duplicate_pad_numbers_are_jumpers no)
		(fp_line
			(start 3.525012 21.310092)
			(end 3.525012 -10.489946)
			(stroke
				(width 0.1524)
				(type default)
			)
			(layer "F.SilkS")
		)
		(fp_line
			(start 3.525012 -10.489946)
			(end -3.525012 -10.489946)
			(stroke
				(width 0.1524)
				(type default)
			)
			(layer "F.SilkS")
		)
		(fp_line
			(start -3.525012 21.310092)
			(end 3.525012 21.310092)
			(stroke
				(width 0.1524)
				(type default)
			)
			(layer "F.SilkS")
		)
		(fp_line
			(start -3.525012 10.6299)
			(end 3.525012 10.6299)
			(stroke
				(width 0.1524)
				(type default)
			)
			(layer "F.SilkS")
		)
		(fp_line
			(start -3.525012 -10.489946)
			(end -3.525012 21.310092)
			(stroke
				(width 0.1524)
				(type default)
			)
			(layer "F.SilkS")
		)
		(fp_line
			(start 3.525012 21.310092)
			(end 3.525012 -10.489946)
			(stroke
				(width 0.1)
				(type default)
			)
			(layer "F.Fab")
		)
		(fp_line
			(start 3.525012 -10.489946)
			(end -3.525012 -10.489946)
			(stroke
				(width 0.1)
				(type default)
			)
			(layer "F.Fab")
		)
		(fp_line
			(start -3.525012 21.310092)
			(end 3.525012 21.310092)
			(stroke
				(width 0.1)
				(type default)
			)
			(layer "F.Fab")
		)
		(fp_line
			(start -3.525012 -10.489946)
			(end -3.525012 21.310092)
			(stroke
				(width 0.1)
				(type default)
			)
			(layer "F.Fab")
		)
		(pad "" np_thru_hole circle
			(at 0 -6.620002 180)
			(size 3.175 3.175)
			(drill 3.175)
			(layers "*.Cu" "*.Mask")
			(clearance 0.381)
			(thermal_gap 0.381)
		)
		(pad "" np_thru_hole circle
			(at 0 0 180)
			(size 0 0)
			(drill 3.175)
			(layers "*.Cu" "*.Mask")
			(clearance 0)
		)
		(pad "" np_thru_hole circle
			(at 0 5.130038 180)
			(size 3.175 3.175)
			(drill 3.175)
			(layers "*.Cu" "*.Mask")
			(clearance 0.381)
			(thermal_gap 0.381)
		)
		(zone
			(layers "F.Cu" "B.Cu" "In1.Cu" "In2.Cu" "In3.Cu" "In4.Cu" "In5.Cu" "In6.Cu"
				"In7.Cu" "In8.Cu" "In9.Cu" "In10.Cu" "In11.Cu" "In12.Cu" "In13.Cu" "In14.Cu"
				"In15.Cu" "In16.Cu"
			)
			(hatch none 0.5)
			(connect_pads
				(clearance 0)
			)
			(min_thickness 0.25)
			(keepout
				(tracks not_allowed)
				(vias allowed)
				(pads allowed)
				(copperpour not_allowed)
				(footprints allowed)
			)
			(placement
				(enabled no)
				(sheetname "")
			)
			(fill
				(thermal_gap 0.5)
				(thermal_bridge_width 0.5)
				(island_removal_mode 0)
			)
			(polygon
				(pts
					(arc
						(start 149.89556 -413.090106)
						(mid 145.70456 -413.090106)
						(end 149.89556 -413.090106)
					)
				)
			)
		)
		(zone
			(layers "F.Cu" "B.Cu" "In1.Cu" "In2.Cu" "In3.Cu" "In4.Cu" "In5.Cu" "In6.Cu"
				"In7.Cu" "In8.Cu" "In9.Cu" "In10.Cu" "In11.Cu" "In12.Cu" "In13.Cu" "In14.Cu"
				"In15.Cu" "In16.Cu"
			)
			(hatch none 0.5)
			(connect_pads
				(clearance 0)
			)
			(min_thickness 0.25)
			(keepout
				(tracks not_allowed)
				(vias allowed)
				(pads allowed)
				(copperpour not_allowed)
				(footprints allowed)
			)
			(placement
				(enabled no)
				(sheetname "")
			)
			(fill
				(thermal_gap 0.5)
				(thermal_bridge_width 0.5)
				(island_removal_mode 0)
			)
			(polygon
				(pts
					(arc
						(start 149.89556 -401.340066)
						(mid 145.70456 -401.340066)
						(end 149.89556 -401.340066)
					)
				)
			)
		)
		(zone
			(layers "F.Cu" "B.Cu" "In1.Cu" "In2.Cu" "In3.Cu" "In4.Cu" "In5.Cu" "In6.Cu"
				"In7.Cu" "In8.Cu" "In9.Cu" "In10.Cu" "In11.Cu" "In12.Cu" "In13.Cu" "In14.Cu"
				"In15.Cu" "In16.Cu"
			)
			(hatch none 0.5)
			(connect_pads
				(clearance 0)
			)
			(min_thickness 0.25)
			(keepout
				(tracks not_allowed)
				(vias allowed)
				(pads allowed)
				(copperpour not_allowed)
				(footprints allowed)
			)
			(placement
				(enabled no)
				(sheetname "")
			)
			(fill
				(thermal_gap 0.5)
				(thermal_bridge_width 0.5)
				(island_removal_mode 0)
			)
			(polygon
				(pts
					(arc
						(start 151.41956 -407.960068)
						(mid 144.18056 -407.960068)
						(end 151.41956 -407.960068)
					)
				)
			)
		)
	)
	(footprint ""
		(layer "F.Cu")
		(at 5.65023 -50.96383 180)
		(property "Reference" "PC501"
			(at 0 0 180)
			(layer "F.SilkS")
			(hide yes)
			(effects
				(font
					(size 1.27 1.27)
				)
			)
		)
		(property "Value" ""
			(at 0 0 180)
			(layer "F.Fab")
			(effects
				(font
					(size 1.27 1.27)
				)
			)
		)
		(duplicate_pad_numbers_are_jumpers no)
		(fp_line
			(start 1.524 0.762)
			(end -1.524 0.762)
			(stroke
				(width 0.1524)
				(type default)
			)
			(layer "F.SilkS")
		)
		(fp_line
			(start 1.524 -0.762)
			(end 1.524 0.762)
			(stroke
				(width 0.1524)
				(type default)
			)
			(layer "F.SilkS")
		)
		(fp_line
			(start -1.524 0.762)
			(end -1.524 -0.762)
			(stroke
				(width 0.1524)
				(type default)
			)
			(layer "F.SilkS")
		)
		(fp_line
			(start -1.524 -0.762)
			(end 1.524 -0.762)
			(stroke
				(width 0.1524)
				(type default)
			)
			(layer "F.SilkS")
		)
		(fp_line
			(start 1.1049 0.724916)
			(end 1.1049 -0.724916)
			(stroke
				(width 0.1)
				(type default)
			)
			(layer "F.Fab")
		)
		(fp_line
			(start 1.1049 -0.724916)
			(end -1.1049 -0.724916)
			(stroke
				(width 0.1)
				(type default)
			)
			(layer "F.Fab")
		)
		(fp_line
			(start -1.1049 0.724916)
			(end 1.1049 0.724916)
			(stroke
				(width 0.1)
				(type default)
			)
			(layer "F.Fab")
		)
		(fp_line
			(start -1.1049 -0.724916)
			(end -1.1049 0.724916)
			(stroke
				(width 0.1)
				(type default)
			)
			(layer "F.Fab")
		)
		(pad "1" smd rect
			(at -0.889 0)
			(size 1.016 1.27)
			(layers "F.Cu" "F.Mask" "F.Paste")
			(net "P3V3_SSD0")
		)
		(pad "2" smd rect
			(at 0.889 0)
			(size 1.016 1.27)
			(layers "F.Cu" "F.Mask" "F.Paste")
			(net "GND")
		)
	)
	(footprint ""
		(layer "F.Cu")
		(at 124.272548 -343.952322 90)
		(property "Reference" "C350"
			(at 0 0 90)
			(layer "F.SilkS")
			(hide yes)
			(effects
				(font
					(size 1.27 1.27)
				)
			)
		)
		(property "Value" ""
			(at 0 0 90)
			(layer "F.Fab")
			(effects
				(font
					(size 1.27 1.27)
				)
			)
		)
		(duplicate_pad_numbers_are_jumpers no)
		(fp_line
			(start 0.299974 -0.150114)
			(end 0.299974 0.150114)
			(stroke
				(width 0.1)
				(type default)
			)
			(layer "F.Fab")
		)
		(fp_line
			(start -0.299974 -0.150114)
			(end 0.299974 -0.150114)
			(stroke
				(width 0.1)
				(type default)
			)
			(layer "F.Fab")
		)
		(fp_line
			(start 0.299974 0.150114)
			(end -0.299974 0.150114)
			(stroke
				(width 0.1)
				(type default)
			)
			(layer "F.Fab")
		)
		(fp_line
			(start -0.299974 0.150114)
			(end -0.299974 -0.150114)
			(stroke
				(width 0.1)
				(type default)
			)
			(layer "F.Fab")
		)
		(pad "1" smd rect
			(at -0.2667 0 90)
			(size 0.3048 0.381)
			(layers "F.Cu" "F.Mask" "F.Paste")
			(net "P5E_PEX1_STN6_TX_DP<106>")
		)
		(pad "2" smd rect
			(at 0.2667 0 90)
			(size 0.3048 0.381)
			(layers "F.Cu" "F.Mask" "F.Paste")
			(net "P5E_PEX1_STN6_TX_C_DP<106>")
		)
	)
	(footprint ""
		(layer "F.Cu")
		(at 287.4899 -412.090108)
		(property "Reference" "J7"
			(at 26.271728 5.314696 90)
			(unlocked yes)
			(layer "F.SilkS")
			(effects
				(font
					(size 2.032 1.524)
					(thickness 0.1524)
				)
				(justify left)
			)
		)
		(property "Value" ""
			(at 0 0 0)
			(layer "F.Fab")
			(effects
				(font
					(size 1.27 1.27)
				)
			)
		)
		(duplicate_pad_numbers_are_jumpers no)
		(fp_line
			(start -4.249928 -16.999966)
			(end 24.45004 -16.999966)
			(stroke
				(width 0.1524)
				(type default)
			)
			(layer "F.SilkS")
		)
		(fp_line
			(start -4.249928 50.099976)
			(end -4.249928 -16.999966)
			(stroke
				(width 0.1524)
				(type default)
			)
			(layer "F.SilkS")
		)
		(fp_line
			(start -1.249934 -13.999972)
			(end -1.249934 47.099982)
			(stroke
				(width 0.1524)
				(type default)
			)
			(layer "F.SilkS")
		)
		(fp_line
			(start -1.249934 -6.500114)
			(end 21.450046 -6.500114)
			(stroke
				(width 0.1524)
				(type default)
			)
			(layer "F.SilkS")
		)
		(fp_line
			(start -1.249934 47.099982)
			(end 21.450046 47.099982)
			(stroke
				(width 0.1524)
				(type default)
			)
			(layer "F.SilkS")
		)
		(fp_line
			(start 21.450046 -13.999972)
			(end -1.249934 -13.999972)
			(stroke
				(width 0.1524)
				(type default)
			)
			(layer "F.SilkS")
		)
		(fp_line
			(start 21.450046 47.099982)
			(end 21.450046 -13.999972)
			(stroke
				(width 0.1524)
				(type default)
			)
			(layer "F.SilkS")
		)
		(fp_line
			(start 24.45004 -16.999966)
			(end 24.45004 50.099976)
			(stroke
				(width 0.1524)
				(type default)
			)
			(layer "F.SilkS")
		)
		(fp_line
			(start 24.45004 50.099976)
			(end -4.249928 50.099976)
			(stroke
				(width 0.1524)
				(type default)
			)
			(layer "F.SilkS")
		)
		(fp_poly
			(pts
				(xy -2.413 -0.508) (xy -2.413 0.508) (xy -1.397 0)
			)
			(stroke
				(width 0)
				(type default)
			)
			(fill yes)
			(layer "F.SilkS")
		)
		(fp_line
			(start -4.249928 -16.999966)
			(end 24.45004 -16.999966)
			(stroke
				(width 0.1524)
				(type default)
			)
			(layer "B.SilkS")
		)
		(fp_line
			(start -4.249928 50.099976)
			(end -4.249928 -16.999966)
			(stroke
				(width 0.1524)
				(type default)
			)
			(layer "B.SilkS")
		)
		(fp_line
			(start 24.45004 -16.999966)
			(end 24.45004 50.099976)
			(stroke
				(width 0.1524)
				(type default)
			)
			(layer "B.SilkS")
		)
		(fp_line
			(start 24.45004 50.099976)
			(end -4.249928 50.099976)
			(stroke
				(width 0.1524)
				(type default)
			)
			(layer "B.SilkS")
		)
		(fp_line
			(start -4.249928 -16.999966)
			(end 24.45004 -16.999966)
			(stroke
				(width 0.1)
				(type default)
			)
			(layer "B.Fab")
		)
		(fp_line
			(start -4.249928 50.099976)
			(end -4.249928 -16.999966)
			(stroke
				(width 0.1)
				(type default)
			)
			(layer "B.Fab")
		)
		(fp_line
			(start 24.45004 -16.999966)
			(end 24.45004 50.099976)
			(stroke
				(width 0.1)
				(type default)
			)
			(layer "B.Fab")
		)
		(fp_line
			(start 24.45004 50.099976)
			(end -4.249928 50.099976)
			(stroke
				(width 0.1)
				(type default)
			)
			(layer "B.Fab")
		)
		(fp_line
			(start -1.249934 -13.999972)
			(end -1.249934 47.099982)
			(stroke
				(width 0.1)
				(type default)
			)
			(layer "F.Fab")
		)
		(fp_line
			(start -1.249934 47.099982)
			(end 21.450046 47.099982)
			(stroke
				(width 0.1)
				(type default)
			)
			(layer "F.Fab")
		)
		(fp_line
			(start 21.450046 -13.999972)
			(end -1.249934 -13.999972)
			(stroke
				(width 0.1)
				(type default)
			)
			(layer "F.Fab")
		)
		(fp_line
			(start 21.450046 47.099982)
			(end 21.450046 -13.999972)
			(stroke
				(width 0.1)
				(type default)
			)
			(layer "F.Fab")
		)
		(fp_poly
			(pts
				(xy -2.413 -0.508) (xy -2.413 0.508) (xy -1.397 0)
			)
			(stroke
				(width 0)
				(type default)
			)
			(fill yes)
			(layer "F.Fab")
		)
		(fp_text user "PRESS-FIT"
			(at 23.191216 43.551856 90)
			(unlocked yes)
			(layer "F.SilkS")
			(effects
				(font
					(size 1.905 1.4224)
					(thickness 0.1524)
				)
				(justify left)
			)
		)
		(fp_text user "PRESS-FIT"
			(at -5.883148 28.139898 90)
			(unlocked yes)
			(layer "B.SilkS")
			(effects
				(font
					(size 1.905 1.4224)
					(thickness 0.1524)
				)
				(justify left mirror)
			)
		)
		(fp_text user "PRESS-FIT"
			(at 18.326862 48.74895 0)
			(unlocked yes)
			(layer "B.Fab")
			(effects
				(font
					(size 1.905 1.4224)
					(thickness 0.1524)
				)
				(justify left mirror)
			)
		)
		(fp_text user "PRESS-FIT"
			(at 1.5875 48.73625 0)
			(unlocked yes)
			(layer "F.Fab")
			(effects
				(font
					(size 1.905 1.4224)
					(thickness 0.1524)
				)
				(justify left)
			)
		)
		(pad "A1" thru_hole rect
			(at 0 0 180)
			(size 0.71628 0.71628)
			(drill 0.30988)
			(layers "*.Cu" "*.Mask")
			(remove_unused_layers no)
			(net "GPU_3V3IO_RSVD3_FFU")
			(clearance 0.0508)
			(thermal_gap 0.0508)
			(padstack
				(mode front_inner_back)
				(layer "Inner"
					(shape circle)
					(size 0.71628 0.71628)
					(clearance 0.0508)
				)
				(layer "B.Cu"
					(shape rect)
					(size 0.71628 0.71628)
					(clearance 0.0508)
				)
			)
		)
		(pad "A2" thru_hole circle
			(at 2.199894 0.199898 180)
			(size 0.906272 0.906272)
			(drill 0.499872)
			(layers "*.Cu" "*.Mask")
			(remove_unused_layers no)
			(net "GND")
			(clearance 0.0508)
			(thermal_gap 0.0508)
		)
		(pad "A3" thru_hole circle
			(at 4.400042 0 180)
			(size 0.71628 0.71628)
			(drill 0.30988)
			(layers "*.Cu" "*.Mask")
			(remove_unused_layers no)
			(net "PRSNT_GPU_A2_N")
			(clearance 0.0508)
			(thermal_gap 0.0508)
		)
		(pad "A4" thru_hole circle
			(at 6.599936 0.199898 180)
			(size 0.906272 0.906272)
			(drill 0.499872)
			(layers "*.Cu" "*.Mask")
			(remove_unused_layers no)
			(net "GND")
			(clearance 0.0508)
			(thermal_gap 0.0508)
		)
		(pad "A5" thru_hole circle
			(at 8.800084 0 180)
			(size 0.71628 0.71628)
			(drill 0.30988)
			(layers "*.Cu" "*.Mask")
			(remove_unused_layers no)
			(net "GPU_3V3IO_RSVD5_FFU")
			(clearance 0.0508)
			(thermal_gap 0.0508)
		)
		(pad "A6" thru_hole circle
			(at 10.999978 0.199898 180)
			(size 0.906272 0.906272)
			(drill 0.499872)
			(layers "*.Cu" "*.Mask")
			(remove_unused_layers no)
			(net "GND")
			(clearance 0.0508)
			(thermal_gap 0.0508)
		)
		(pad "A7" thru_hole circle
			(at 13.199872 0 180)
			(size 0.71628 0.71628)
			(drill 0.30988)
			(layers "*.Cu" "*.Mask")
			(remove_unused_layers no)
			(net "GPU_FPGA_OVERT_N")
			(clearance 0.0508)
			(thermal_gap 0.0508)
		)
		(pad "A8" thru_hole circle
			(at 15.40002 0.199898 180)
			(size 0.906272 0.906272)
			(drill 0.499872)
			(layers "*.Cu" "*.Mask")
			(remove_unused_layers no)
			(net "GND")
			(clearance 0.0508)
			(thermal_gap 0.0508)
		)
		(pad "A9" thru_hole circle
			(at 17.599914 0 180)
			(size 0.71628 0.71628)
			(drill 0.30988)
			(layers "*.Cu" "*.Mask")
			(remove_unused_layers no)
			(net "Net_8815")
			(clearance 0.0508)
			(thermal_gap 0.0508)
		)
		(pad "A10" thru_hole circle
			(at 19.800062 0.199898 180)
			(size 0.906272 0.906272)
			(drill 0.499872)
			(layers "*.Cu" "*.Mask")
			(remove_unused_layers no)
			(net "GND")
			(clearance 0.0508)
			(thermal_gap 0.0508)
		)
		(pad "B1" thru_hole circle
			(at 0 1.299972 180)
			(size 0.906272 0.906272)
			(drill 0.499872)
			(layers "*.Cu" "*.Mask")
			(remove_unused_layers no)
			(net "GND")
			(clearance 0.0508)
			(thermal_gap 0.0508)
		)
		(pad "B3" thru_hole circle
			(at 4.400042 1.299972 180)
			(size 0.906272 0.906272)
			(drill 0.499872)
			(layers "*.Cu" "*.Mask")
			(remove_unused_layers no)
			(net "GND")
			(clearance 0.0508)
			(thermal_gap 0.0508)
		)
		(pad "B5" thru_hole circle
			(at 8.800084 1.299972 180)
			(size 0.906272 0.906272)
			(drill 0.499872)
			(layers "*.Cu" "*.Mask")
			(remove_unused_layers no)
			(net "GND")
			(clearance 0.0508)
			(thermal_gap 0.0508)
		)
		(pad "B7" thru_hole circle
			(at 13.199872 1.299972 180)
			(size 0.906272 0.906272)
			(drill 0.499872)
			(layers "*.Cu" "*.Mask")
			(remove_unused_layers no)
			(net "GND")
			(clearance 0.0508)
			(thermal_gap 0.0508)
		)
		(pad "B9" thru_hole circle
			(at 17.599914 1.299972 180)
			(size 0.906272 0.906272)
			(drill 0.499872)
			(layers "*.Cu" "*.Mask")
			(remove_unused_layers no)
			(net "GND")
			(clearance 0.0508)
			(thermal_gap 0.0508)
		)
		(pad "B10" thru_hole circle
			(at 19.800062 1.500124 180)
			(size 0.71628 0.71628)
			(drill 0.30988)
			(layers "*.Cu" "*.Mask")
			(remove_unused_layers no)
			(net "Net_8814")
			(clearance 0.0508)
			(thermal_gap 0.0508)
		)
		(pad "C9" thru_hole circle
			(at 17.599914 2.599944 180)
			(size 0.71628 0.71628)
			(drill 0.30988)
			(layers "*.Cu" "*.Mask")
			(remove_unused_layers no)
			(net "Net_8812")
			(clearance 0.0508)
			(thermal_gap 0.0508)
		)
		(pad "C10" thru_hole circle
			(at 19.800062 2.800096 180)
			(size 0.71628 0.71628)
			(drill 0.30988)
			(layers "*.Cu" "*.Mask")
			(remove_unused_layers no)
			(net "Net_8813")
			(clearance 0.0508)
			(thermal_gap 0.0508)
		)
		(pad "D2" thru_hole circle
			(at 2.199894 4.100068 180)
			(size 0.906272 0.906272)
			(drill 0.499872)
			(layers "*.Cu" "*.Mask")
			(remove_unused_layers no)
			(net "GND")
			(clearance 0.0508)
			(thermal_gap 0.0508)
		)
		(pad "D4" thru_hole circle
			(at 6.599936 4.100068 180)
			(size 0.906272 0.906272)
			(drill 0.499872)
			(layers "*.Cu" "*.Mask")
			(remove_unused_layers no)
			(net "GND")
			(clearance 0.0508)
			(thermal_gap 0.0508)
		)
		(pad "D6" thru_hole circle
			(at 10.999978 4.100068 180)
			(size 0.906272 0.906272)
			(drill 0.499872)
			(layers "*.Cu" "*.Mask")
			(remove_unused_layers no)
			(net "GND")
			(clearance 0.0508)
			(thermal_gap 0.0508)
		)
		(pad "D8" thru_hole circle
			(at 15.40002 4.100068 180)
			(size 0.906272 0.906272)
			(drill 0.499872)
			(layers "*.Cu" "*.Mask")
			(remove_unused_layers no)
			(net "GND")
			(clearance 0.0508)
			(thermal_gap 0.0508)
		)
		(pad "D9" thru_hole circle
			(at 17.599914 3.899916 180)
			(size 0.71628 0.71628)
			(drill 0.30988)
			(layers "*.Cu" "*.Mask")
			(remove_unused_layers no)
			(net "Net_8811")
			(clearance 0.0508)
			(thermal_gap 0.0508)
		)
		(pad "D10" thru_hole circle
			(at 19.800062 4.100068 180)
			(size 0.906272 0.906272)
			(drill 0.499872)
			(layers "*.Cu" "*.Mask")
			(remove_unused_layers no)
			(net "GND")
			(clearance 0.0508)
			(thermal_gap 0.0508)
		)
		(pad "E1" thru_hole circle
			(at 0 5.199888 180)
			(size 0.906272 0.906272)
			(drill 0.499872)
			(layers "*.Cu" "*.Mask")
			(remove_unused_layers no)
			(net "GND")
			(clearance 0.0508)
			(thermal_gap 0.0508)
		)
		(pad "E3" thru_hole circle
			(at 4.400042 5.199888 180)
			(size 0.906272 0.906272)
			(drill 0.499872)
			(layers "*.Cu" "*.Mask")
			(remove_unused_layers no)
			(net "GND")
			(clearance 0.0508)
			(thermal_gap 0.0508)
		)
		(pad "E5" thru_hole circle
			(at 8.800084 5.199888 180)
			(size 0.906272 0.906272)
			(drill 0.499872)
			(layers "*.Cu" "*.Mask")
			(remove_unused_layers no)
			(net "GND")
			(clearance 0.0508)
			(thermal_gap 0.0508)
		)
		(pad "E7" thru_hole circle
			(at 13.199872 5.199888 180)
			(size 0.906272 0.906272)
			(drill 0.499872)
			(layers "*.Cu" "*.Mask")
			(remove_unused_layers no)
			(net "GND")
			(clearance 0.0508)
			(thermal_gap 0.0508)
		)
		(pad "E9" thru_hole circle
			(at 17.599914 5.199888 180)
			(size 0.906272 0.906272)
			(drill 0.499872)
			(layers "*.Cu" "*.Mask")
			(remove_unused_layers no)
			(net "GND")
			(clearance 0.0508)
			(thermal_gap 0.0508)
		)
		(pad "E10" thru_hole circle
			(at 19.800062 5.40004 180)
			(size 0.71628 0.71628)
			(drill 0.30988)
			(layers "*.Cu" "*.Mask")
			(remove_unused_layers no)
			(net "Net_8810")
			(clearance 0.0508)
			(thermal_gap 0.0508)
		)
		(pad "F9" thru_hole circle
			(at 17.599914 6.500114 180)
			(size 0.71628 0.71628)
			(drill 0.30988)
			(layers "*.Cu" "*.Mask")
			(remove_unused_layers no)
			(net "Net_8808")
			(clearance 0.0508)
			(thermal_gap 0.0508)
		)
		(pad "F10" thru_hole circle
			(at 19.800062 6.700012 180)
			(size 0.71628 0.71628)
			(drill 0.30988)
			(layers "*.Cu" "*.Mask")
			(remove_unused_layers no)
			(net "Net_8809")
			(clearance 0.0508)
			(thermal_gap 0.0508)
		)
		(pad "G2" thru_hole circle
			(at 2.199894 7.999984 180)
			(size 0.906272 0.906272)
			(drill 0.499872)
			(layers "*.Cu" "*.Mask")
			(remove_unused_layers no)
			(net "GND")
			(clearance 0.0508)
			(thermal_gap 0.0508)
		)
		(pad "G4" thru_hole circle
			(at 6.599936 7.999984 180)
			(size 0.906272 0.906272)
			(drill 0.499872)
			(layers "*.Cu" "*.Mask")
			(remove_unused_layers no)
			(net "GND")
			(clearance 0.0508)
			(thermal_gap 0.0508)
		)
		(pad "G6" thru_hole circle
			(at 10.999978 7.999984 180)
			(size 0.906272 0.906272)
			(drill 0.499872)
			(layers "*.Cu" "*.Mask")
			(remove_unused_layers no)
			(net "GND")
			(clearance 0.0508)
			(thermal_gap 0.0508)
		)
		(pad "G8" thru_hole circle
			(at 15.40002 7.999984 180)
			(size 0.906272 0.906272)
			(drill 0.499872)
			(layers "*.Cu" "*.Mask")
			(remove_unused_layers no)
			(net "GND")
			(clearance 0.0508)
			(thermal_gap 0.0508)
		)
		(pad "G9" thru_hole circle
			(at 17.599914 7.800086 180)
			(size 0.71628 0.71628)
			(drill 0.30988)
			(layers "*.Cu" "*.Mask")
			(remove_unused_layers no)
			(net "Net_8807")
			(clearance 0.0508)
			(thermal_gap 0.0508)
		)
		(pad "G10" thru_hole circle
			(at 19.800062 7.999984 180)
			(size 0.906272 0.906272)
			(drill 0.499872)
			(layers "*.Cu" "*.Mask")
			(remove_unused_layers no)
			(net "GND")
			(clearance 0.0508)
			(thermal_gap 0.0508)
		)
		(pad "H1" thru_hole circle
			(at 0 9.100058 180)
			(size 0.906272 0.906272)
			(drill 0.499872)
			(layers "*.Cu" "*.Mask")
			(remove_unused_layers no)
			(net "GND")
			(clearance 0.0508)
			(thermal_gap 0.0508)
		)
		(pad "H3" thru_hole circle
			(at 4.400042 9.100058 180)
			(size 0.906272 0.906272)
			(drill 0.499872)
			(layers "*.Cu" "*.Mask")
			(remove_unused_layers no)
			(net "GND")
			(clearance 0.0508)
			(thermal_gap 0.0508)
		)
		(pad "H5" thru_hole circle
			(at 8.800084 9.100058 180)
			(size 0.906272 0.906272)
			(drill 0.499872)
			(layers "*.Cu" "*.Mask")
			(remove_unused_layers no)
			(net "GND")
			(clearance 0.0508)
			(thermal_gap 0.0508)
		)
		(pad "H7" thru_hole circle
			(at 13.199872 9.100058 180)
			(size 0.906272 0.906272)
			(drill 0.499872)
			(layers "*.Cu" "*.Mask")
			(remove_unused_layers no)
			(net "GND")
			(clearance 0.0508)
			(thermal_gap 0.0508)
		)
		(pad "H9" thru_hole circle
			(at 17.599914 9.100058 180)
			(size 0.906272 0.906272)
			(drill 0.499872)
			(layers "*.Cu" "*.Mask")
			(remove_unused_layers no)
			(net "GND")
			(clearance 0.0508)
			(thermal_gap 0.0508)
		)
		(pad "H10" thru_hole circle
			(at 19.800062 9.299956 180)
			(size 0.71628 0.71628)
			(drill 0.30988)
			(layers "*.Cu" "*.Mask")
			(remove_unused_layers no)
			(net "Net_8806")
			(clearance 0.0508)
			(thermal_gap 0.0508)
		)
		(pad "I9" thru_hole circle
			(at 17.599914 10.40003 180)
			(size 0.71628 0.71628)
			(drill 0.30988)
			(layers "*.Cu" "*.Mask")
			(remove_unused_layers no)
			(net "Net_8804")
			(clearance 0.0508)
			(thermal_gap 0.0508)
		)
		(pad "I10" thru_hole circle
			(at 19.800062 10.599928 180)
			(size 0.71628 0.71628)
			(drill 0.30988)
			(layers "*.Cu" "*.Mask")
			(remove_unused_layers no)
			(net "Net_8805")
			(clearance 0.0508)
			(thermal_gap 0.0508)
		)
		(pad "J2" thru_hole circle
			(at 2.199894 11.8999 180)
			(size 0.906272 0.906272)
			(drill 0.499872)
			(layers "*.Cu" "*.Mask")
			(remove_unused_layers no)
			(net "GND")
			(clearance 0.0508)
			(thermal_gap 0.0508)
		)
		(pad "J4" thru_hole circle
			(at 6.599936 11.8999 180)
			(size 0.906272 0.906272)
			(drill 0.499872)
			(layers "*.Cu" "*.Mask")
			(remove_unused_layers no)
			(net "GND")
			(clearance 0.0508)
			(thermal_gap 0.0508)
		)
		(pad "J6" thru_hole circle
			(at 10.999978 11.8999 180)
			(size 0.906272 0.906272)
			(drill 0.499872)
			(layers "*.Cu" "*.Mask")
			(remove_unused_layers no)
			(net "GND")
			(clearance 0.0508)
			(thermal_gap 0.0508)
		)
		(pad "J8" thru_hole circle
			(at 15.40002 11.8999 180)
			(size 0.906272 0.906272)
			(drill 0.499872)
			(layers "*.Cu" "*.Mask")
			(remove_unused_layers no)
			(net "GND")
			(clearance 0.0508)
			(thermal_gap 0.0508)
		)
		(pad "J9" thru_hole circle
			(at 17.599914 11.700002 180)
			(size 0.71628 0.71628)
			(drill 0.30988)
			(layers "*.Cu" "*.Mask")
			(remove_unused_layers no)
			(net "Net_8803")
			(clearance 0.0508)
			(thermal_gap 0.0508)
		)
		(pad "J10" thru_hole circle
			(at 19.800062 11.8999 180)
			(size 0.906272 0.906272)
			(drill 0.499872)
			(layers "*.Cu" "*.Mask")
			(remove_unused_layers no)
			(net "GND")
			(clearance 0.0508)
			(thermal_gap 0.0508)
		)
		(pad "K1" thru_hole circle
			(at 0 12.999974 180)
			(size 0.906272 0.906272)
			(drill 0.499872)
			(layers "*.Cu" "*.Mask")
			(remove_unused_layers no)
			(net "GND")
			(clearance 0.0508)
			(thermal_gap 0.0508)
		)
		(pad "K3" thru_hole circle
			(at 4.400042 12.999974 180)
			(size 0.906272 0.906272)
			(drill 0.499872)
			(layers "*.Cu" "*.Mask")
			(remove_unused_layers no)
			(net "GND")
			(clearance 0.0508)
			(thermal_gap 0.0508)
		)
		(pad "K5" thru_hole circle
			(at 8.800084 12.999974 180)
			(size 0.906272 0.906272)
			(drill 0.499872)
			(layers "*.Cu" "*.Mask")
			(remove_unused_layers no)
			(net "GND")
			(clearance 0.0508)
			(thermal_gap 0.0508)
		)
		(pad "K7" thru_hole circle
			(at 13.199872 12.999974 180)
			(size 0.906272 0.906272)
			(drill 0.499872)
			(layers "*.Cu" "*.Mask")
			(remove_unused_layers no)
			(net "GND")
			(clearance 0.0508)
			(thermal_gap 0.0508)
		)
		(pad "K9" thru_hole circle
			(at 17.599914 12.999974 180)
			(size 0.906272 0.906272)
			(drill 0.499872)
			(layers "*.Cu" "*.Mask")
			(remove_unused_layers no)
			(net "GND")
			(clearance 0.0508)
			(thermal_gap 0.0508)
		)
		(pad "K10" thru_hole circle
			(at 19.800062 13.199872 180)
			(size 0.71628 0.71628)
			(drill 0.30988)
			(layers "*.Cu" "*.Mask")
			(remove_unused_layers no)
			(net "Net_8802")
			(clearance 0.0508)
			(thermal_gap 0.0508)
		)
		(pad "L9" thru_hole circle
			(at 17.599914 14.299946 180)
			(size 0.71628 0.71628)
			(drill 0.30988)
			(layers "*.Cu" "*.Mask")
			(remove_unused_layers no)
			(net "Net_8800")
			(clearance 0.0508)
			(thermal_gap 0.0508)
		)
		(pad "L10" thru_hole circle
			(at 19.800062 14.500098 180)
			(size 0.71628 0.71628)
			(drill 0.30988)
			(layers "*.Cu" "*.Mask")
			(remove_unused_layers no)
			(net "Net_8801")
			(clearance 0.0508)
			(thermal_gap 0.0508)
		)
		(pad "M1_2" thru_hole circle
			(at 2.199894 15.80007 180)
			(size 0.906272 0.906272)
			(drill 0.499872)
			(layers "*.Cu" "*.Mask")
			(remove_unused_layers no)
			(net "GND")
			(clearance 0.0508)
			(thermal_gap 0.0508)
		)
		(pad "M1_4" thru_hole circle
			(at 6.599936 15.80007 180)
			(size 0.906272 0.906272)
			(drill 0.499872)
			(layers "*.Cu" "*.Mask")
			(remove_unused_layers no)
			(net "GND")
			(clearance 0.0508)
			(thermal_gap 0.0508)
		)
		(pad "M1_6" thru_hole circle
			(at 10.999978 15.80007 180)
			(size 0.906272 0.906272)
			(drill 0.499872)
			(layers "*.Cu" "*.Mask")
			(remove_unused_layers no)
			(net "GND")
			(clearance 0.0508)
			(thermal_gap 0.0508)
		)
		(pad "M1_8" thru_hole circle
			(at 15.40002 15.80007 180)
			(size 0.906272 0.906272)
			(drill 0.499872)
			(layers "*.Cu" "*.Mask")
			(remove_unused_layers no)
			(net "GND")
			(clearance 0.0508)
			(thermal_gap 0.0508)
		)
		(pad "M1_10" thru_hole circle
			(at 19.800062 15.80007 180)
			(size 0.906272 0.906272)
			(drill 0.499872)
			(layers "*.Cu" "*.Mask")
			(remove_unused_layers no)
			(net "GND")
			(clearance 0.0508)
			(thermal_gap 0.0508)
		)
		(pad "M2_2" thru_hole circle
			(at 2.199894 26.2001 180)
			(size 0.906272 0.906272)
			(drill 0.499872)
			(layers "*.Cu" "*.Mask")
			(remove_unused_layers no)
			(net "GND")
			(clearance 0.0508)
			(thermal_gap 0.0508)
		)
		(pad "M2_4" thru_hole circle
			(at 6.599936 26.2001 180)
			(size 0.906272 0.906272)
			(drill 0.499872)
			(layers "*.Cu" "*.Mask")
			(remove_unused_layers no)
			(net "GND")
			(clearance 0.0508)
			(thermal_gap 0.0508)
		)
		(pad "M2_6" thru_hole circle
			(at 10.999978 26.2001 180)
			(size 0.906272 0.906272)
			(drill 0.499872)
			(layers "*.Cu" "*.Mask")
			(remove_unused_layers no)
			(net "GND")
			(clearance 0.0508)
			(thermal_gap 0.0508)
		)
		(pad "M2_8" thru_hole circle
			(at 15.40002 26.2001 180)
			(size 0.906272 0.906272)
			(drill 0.499872)
			(layers "*.Cu" "*.Mask")
			(remove_unused_layers no)
			(net "GND")
			(clearance 0.0508)
			(thermal_gap 0.0508)
		)
		(pad "M2_10" thru_hole circle
			(at 19.800062 26.2001 180)
			(size 0.906272 0.906272)
			(drill 0.499872)
			(layers "*.Cu" "*.Mask")
			(remove_unused_layers no)
			(net "GND")
			(clearance 0.0508)
			(thermal_gap 0.0508)
		)
		(pad "M9" thru_hole circle
			(at 17.599914 15.599918 180)
			(size 0.71628 0.71628)
			(drill 0.30988)
			(layers "*.Cu" "*.Mask")
			(remove_unused_layers no)
			(net "Net_8799")
			(clearance 0.0508)
			(thermal_gap 0.0508)
		)
		(pad "N1_1" thru_hole circle
			(at 0 16.89989 180)
			(size 0.906272 0.906272)
			(drill 0.499872)
			(layers "*.Cu" "*.Mask")
			(remove_unused_layers no)
			(net "GND")
			(clearance 0.0508)
			(thermal_gap 0.0508)
		)
		(pad "N1_3" thru_hole circle
			(at 4.400042 16.89989 180)
			(size 0.906272 0.906272)
			(drill 0.499872)
			(layers "*.Cu" "*.Mask")
			(remove_unused_layers no)
			(net "GND")
			(clearance 0.0508)
			(thermal_gap 0.0508)
		)
		(pad "N1_5" thru_hole circle
			(at 8.800084 16.89989 180)
			(size 0.906272 0.906272)
			(drill 0.499872)
			(layers "*.Cu" "*.Mask")
			(remove_unused_layers no)
			(net "GND")
			(clearance 0.0508)
			(thermal_gap 0.0508)
		)
		(pad "N1_7" thru_hole circle
			(at 13.199872 16.89989 180)
			(size 0.906272 0.906272)
			(drill 0.499872)
			(layers "*.Cu" "*.Mask")
			(remove_unused_layers no)
			(net "GND")
			(clearance 0.0508)
			(thermal_gap 0.0508)
		)
		(pad "N1_9" thru_hole circle
			(at 17.599914 16.89989 180)
			(size 0.906272 0.906272)
			(drill 0.499872)
			(layers "*.Cu" "*.Mask")
			(remove_unused_layers no)
			(net "GND")
			(clearance 0.0508)
			(thermal_gap 0.0508)
		)
		(pad "N2_1" thru_hole circle
			(at 0 27.29992 180)
			(size 0.906272 0.906272)
			(drill 0.499872)
			(layers "*.Cu" "*.Mask")
			(remove_unused_layers no)
			(net "GND")
			(clearance 0.0508)
			(thermal_gap 0.0508)
		)
		(pad "N2_3" thru_hole circle
			(at 4.400042 27.29992 180)
			(size 0.906272 0.906272)
			(drill 0.499872)
			(layers "*.Cu" "*.Mask")
			(remove_unused_layers no)
			(net "GND")
			(clearance 0.0508)
			(thermal_gap 0.0508)
		)
		(pad "N2_5" thru_hole circle
			(at 8.800084 27.29992 180)
			(size 0.906272 0.906272)
			(drill 0.499872)
			(layers "*.Cu" "*.Mask")
			(remove_unused_layers no)
			(net "GND")
			(clearance 0.0508)
			(thermal_gap 0.0508)
		)
		(pad "N2_7" thru_hole circle
			(at 13.199872 27.29992 180)
			(size 0.906272 0.906272)
			(drill 0.499872)
			(layers "*.Cu" "*.Mask")
			(remove_unused_layers no)
			(net "GND")
			(clearance 0.0508)
			(thermal_gap 0.0508)
		)
		(pad "N2_9" thru_hole circle
			(at 17.599914 27.29992 180)
			(size 0.906272 0.906272)
			(drill 0.499872)
			(layers "*.Cu" "*.Mask")
			(remove_unused_layers no)
			(net "GND")
			(clearance 0.0508)
			(thermal_gap 0.0508)
		)
		(pad "N10" thru_hole circle
			(at 19.800062 27.500072 180)
			(size 0.71628 0.71628)
			(drill 0.30988)
			(layers "*.Cu" "*.Mask")
			(remove_unused_layers no)
			(net "Net_8798")
			(clearance 0.0508)
			(thermal_gap 0.0508)
		)
		(pad "O9" thru_hole circle
			(at 17.599914 28.599892 180)
			(size 0.71628 0.71628)
			(drill 0.30988)
			(layers "*.Cu" "*.Mask")
			(remove_unused_layers no)
			(net "Net_8796")
			(clearance 0.0508)
			(thermal_gap 0.0508)
		)
		(pad "O10" thru_hole circle
			(at 19.800062 28.800044 180)
			(size 0.71628 0.71628)
			(drill 0.30988)
			(layers "*.Cu" "*.Mask")
			(remove_unused_layers no)
			(net "Net_8797")
			(clearance 0.0508)
			(thermal_gap 0.0508)
		)
		(pad "P2" thru_hole circle
			(at 2.199894 30.100016 180)
			(size 0.906272 0.906272)
			(drill 0.499872)
			(layers "*.Cu" "*.Mask")
			(remove_unused_layers no)
			(net "GND")
			(clearance 0.0508)
			(thermal_gap 0.0508)
		)
		(pad "P4" thru_hole circle
			(at 6.599936 30.100016 180)
			(size 0.906272 0.906272)
			(drill 0.499872)
			(layers "*.Cu" "*.Mask")
			(remove_unused_layers no)
			(net "GND")
			(clearance 0.0508)
			(thermal_gap 0.0508)
		)
		(pad "P6" thru_hole circle
			(at 10.999978 30.100016 180)
			(size 0.906272 0.906272)
			(drill 0.499872)
			(layers "*.Cu" "*.Mask")
			(remove_unused_layers no)
			(net "GND")
			(clearance 0.0508)
			(thermal_gap 0.0508)
		)
		(pad "P8" thru_hole circle
			(at 15.40002 30.100016 180)
			(size 0.906272 0.906272)
			(drill 0.499872)
			(layers "*.Cu" "*.Mask")
			(remove_unused_layers no)
			(net "GND")
			(clearance 0.0508)
			(thermal_gap 0.0508)
		)
		(pad "P9" thru_hole circle
			(at 17.599914 29.900118 180)
			(size 0.71628 0.71628)
			(drill 0.30988)
			(layers "*.Cu" "*.Mask")
			(remove_unused_layers no)
			(net "Net_8795")
			(clearance 0.0508)
			(thermal_gap 0.0508)
		)
		(pad "P10" thru_hole circle
			(at 19.800062 30.100016 180)
			(size 0.906272 0.906272)
			(drill 0.499872)
			(layers "*.Cu" "*.Mask")
			(remove_unused_layers no)
			(net "GND")
			(clearance 0.0508)
			(thermal_gap 0.0508)
		)
		(pad "Q1" thru_hole circle
			(at 0 31.20009 180)
			(size 0.906272 0.906272)
			(drill 0.499872)
			(layers "*.Cu" "*.Mask")
			(remove_unused_layers no)
			(net "GND")
			(clearance 0.0508)
			(thermal_gap 0.0508)
		)
		(pad "Q3" thru_hole circle
			(at 4.400042 31.20009 180)
			(size 0.906272 0.906272)
			(drill 0.499872)
			(layers "*.Cu" "*.Mask")
			(remove_unused_layers no)
			(net "GND")
			(clearance 0.0508)
			(thermal_gap 0.0508)
		)
		(pad "Q5" thru_hole circle
			(at 8.800084 31.20009 180)
			(size 0.906272 0.906272)
			(drill 0.499872)
			(layers "*.Cu" "*.Mask")
			(remove_unused_layers no)
			(net "GND")
			(clearance 0.0508)
			(thermal_gap 0.0508)
		)
		(pad "Q7" thru_hole circle
			(at 13.199872 31.20009 180)
			(size 0.906272 0.906272)
			(drill 0.499872)
			(layers "*.Cu" "*.Mask")
			(remove_unused_layers no)
			(net "GND")
			(clearance 0.0508)
			(thermal_gap 0.0508)
		)
		(pad "Q9" thru_hole circle
			(at 17.599914 31.20009 180)
			(size 0.906272 0.906272)
			(drill 0.499872)
			(layers "*.Cu" "*.Mask")
			(remove_unused_layers no)
			(net "GND")
			(clearance 0.0508)
			(thermal_gap 0.0508)
		)
		(pad "Q10" thru_hole circle
			(at 19.800062 31.399988 180)
			(size 0.71628 0.71628)
			(drill 0.30988)
			(layers "*.Cu" "*.Mask")
			(remove_unused_layers no)
			(net "Net_8794")
			(clearance 0.0508)
			(thermal_gap 0.0508)
		)
		(pad "R9" thru_hole circle
			(at 17.599914 32.500062 180)
			(size 0.71628 0.71628)
			(drill 0.30988)
			(layers "*.Cu" "*.Mask")
			(remove_unused_layers no)
			(net "Net_8792")
			(clearance 0.0508)
			(thermal_gap 0.0508)
		)
		(pad "R10" thru_hole circle
			(at 19.800062 32.69996 180)
			(size 0.71628 0.71628)
			(drill 0.30988)
			(layers "*.Cu" "*.Mask")
			(remove_unused_layers no)
			(net "Net_8793")
			(clearance 0.0508)
			(thermal_gap 0.0508)
		)
		(pad "S2" thru_hole circle
			(at 2.199894 33.999932 180)
			(size 0.906272 0.906272)
			(drill 0.499872)
			(layers "*.Cu" "*.Mask")
			(remove_unused_layers no)
			(net "GND")
			(clearance 0.0508)
			(thermal_gap 0.0508)
		)
		(pad "S4" thru_hole circle
			(at 6.599936 33.999932 180)
			(size 0.906272 0.906272)
			(drill 0.499872)
			(layers "*.Cu" "*.Mask")
			(remove_unused_layers no)
			(net "GND")
			(clearance 0.0508)
			(thermal_gap 0.0508)
		)
		(pad "S6" thru_hole circle
			(at 10.999978 33.999932 180)
			(size 0.906272 0.906272)
			(drill 0.499872)
			(layers "*.Cu" "*.Mask")
			(remove_unused_layers no)
			(net "GND")
			(clearance 0.0508)
			(thermal_gap 0.0508)
		)
		(pad "S8" thru_hole circle
			(at 15.40002 33.999932 180)
			(size 0.906272 0.906272)
			(drill 0.499872)
			(layers "*.Cu" "*.Mask")
			(remove_unused_layers no)
			(net "GND")
			(clearance 0.0508)
			(thermal_gap 0.0508)
		)
		(pad "S9" thru_hole circle
			(at 17.599914 33.800034 180)
			(size 0.71628 0.71628)
			(drill 0.30988)
			(layers "*.Cu" "*.Mask")
			(remove_unused_layers no)
			(net "Net_8791")
			(clearance 0.0508)
			(thermal_gap 0.0508)
		)
		(pad "S10" thru_hole circle
			(at 19.800062 33.999932 180)
			(size 0.906272 0.906272)
			(drill 0.499872)
			(layers "*.Cu" "*.Mask")
			(remove_unused_layers no)
			(net "GND")
			(clearance 0.0508)
			(thermal_gap 0.0508)
		)
		(pad "T1" thru_hole circle
			(at 0 35.100006 180)
			(size 0.906272 0.906272)
			(drill 0.499872)
			(layers "*.Cu" "*.Mask")
			(remove_unused_layers no)
			(net "GND")
			(clearance 0.0508)
			(thermal_gap 0.0508)
		)
		(pad "T3" thru_hole circle
			(at 4.400042 35.100006 180)
			(size 0.906272 0.906272)
			(drill 0.499872)
			(layers "*.Cu" "*.Mask")
			(remove_unused_layers no)
			(net "GND")
			(clearance 0.0508)
			(thermal_gap 0.0508)
		)
		(pad "T5" thru_hole circle
			(at 8.800084 35.100006 180)
			(size 0.906272 0.906272)
			(drill 0.499872)
			(layers "*.Cu" "*.Mask")
			(remove_unused_layers no)
			(net "GND")
			(clearance 0.0508)
			(thermal_gap 0.0508)
		)
		(pad "T7" thru_hole circle
			(at 13.199872 35.100006 180)
			(size 0.906272 0.906272)
			(drill 0.499872)
			(layers "*.Cu" "*.Mask")
			(remove_unused_layers no)
			(net "GND")
			(clearance 0.0508)
			(thermal_gap 0.0508)
		)
		(pad "T9" thru_hole circle
			(at 17.599914 35.100006 180)
			(size 0.906272 0.906272)
			(drill 0.499872)
			(layers "*.Cu" "*.Mask")
			(remove_unused_layers no)
			(net "GND")
			(clearance 0.0508)
			(thermal_gap 0.0508)
		)
		(pad "T10" thru_hole circle
			(at 19.800062 35.299904 180)
			(size 0.71628 0.71628)
			(drill 0.30988)
			(layers "*.Cu" "*.Mask")
			(remove_unused_layers no)
			(net "Net_8790")
			(clearance 0.0508)
			(thermal_gap 0.0508)
		)
		(pad "U9" thru_hole circle
			(at 17.599914 36.399978 180)
			(size 0.71628 0.71628)
			(drill 0.30988)
			(layers "*.Cu" "*.Mask")
			(remove_unused_layers no)
			(net "Net_8788")
			(clearance 0.0508)
			(thermal_gap 0.0508)
		)
		(pad "U10" thru_hole circle
			(at 19.800062 36.599876 180)
			(size 0.71628 0.71628)
			(drill 0.30988)
			(layers "*.Cu" "*.Mask")
			(remove_unused_layers no)
			(net "Net_8789")
			(clearance 0.0508)
			(thermal_gap 0.0508)
		)
		(pad "V2" thru_hole circle
			(at 2.199894 37.900102 180)
			(size 0.906272 0.906272)
			(drill 0.499872)
			(layers "*.Cu" "*.Mask")
			(remove_unused_layers no)
			(net "GND")
			(clearance 0.0508)
			(thermal_gap 0.0508)
		)
		(pad "V4" thru_hole circle
			(at 6.599936 37.900102 180)
			(size 0.906272 0.906272)
			(drill 0.499872)
			(layers "*.Cu" "*.Mask")
			(remove_unused_layers no)
			(net "GND")
			(clearance 0.0508)
			(thermal_gap 0.0508)
		)
		(pad "V6" thru_hole circle
			(at 10.999978 37.900102 180)
			(size 0.906272 0.906272)
			(drill 0.499872)
			(layers "*.Cu" "*.Mask")
			(remove_unused_layers no)
			(net "GND")
			(clearance 0.0508)
			(thermal_gap 0.0508)
		)
		(pad "V8" thru_hole circle
			(at 15.40002 37.900102 180)
			(size 0.906272 0.906272)
			(drill 0.499872)
			(layers "*.Cu" "*.Mask")
			(remove_unused_layers no)
			(net "GND")
			(clearance 0.0508)
			(thermal_gap 0.0508)
		)
		(pad "V9" thru_hole circle
			(at 17.599914 37.69995 180)
			(size 0.71628 0.71628)
			(drill 0.30988)
			(layers "*.Cu" "*.Mask")
			(remove_unused_layers no)
			(net "Net_8787")
			(clearance 0.0508)
			(thermal_gap 0.0508)
		)
		(pad "V10" thru_hole circle
			(at 19.800062 37.900102 180)
			(size 0.906272 0.906272)
			(drill 0.499872)
			(layers "*.Cu" "*.Mask")
			(remove_unused_layers no)
			(net "GND")
			(clearance 0.0508)
			(thermal_gap 0.0508)
		)
		(pad "W1" thru_hole circle
			(at 0 38.999922 180)
			(size 0.906272 0.906272)
			(drill 0.499872)
			(layers "*.Cu" "*.Mask")
			(remove_unused_layers no)
			(net "GND")
			(clearance 0.0508)
			(thermal_gap 0.0508)
		)
		(pad "W3" thru_hole circle
			(at 4.400042 38.999922 180)
			(size 0.906272 0.906272)
			(drill 0.499872)
			(layers "*.Cu" "*.Mask")
			(remove_unused_layers no)
			(net "GND")
			(clearance 0.0508)
			(thermal_gap 0.0508)
		)
		(pad "W5" thru_hole circle
			(at 8.800084 38.999922 180)
			(size 0.906272 0.906272)
			(drill 0.499872)
			(layers "*.Cu" "*.Mask")
			(remove_unused_layers no)
			(net "GND")
			(clearance 0.0508)
			(thermal_gap 0.0508)
		)
		(pad "W7" thru_hole circle
			(at 13.199872 38.999922 180)
			(size 0.906272 0.906272)
			(drill 0.499872)
			(layers "*.Cu" "*.Mask")
			(remove_unused_layers no)
			(net "GND")
			(clearance 0.0508)
			(thermal_gap 0.0508)
		)
		(pad "W9" thru_hole circle
			(at 17.599914 38.999922 180)
			(size 0.906272 0.906272)
			(drill 0.499872)
			(layers "*.Cu" "*.Mask")
			(remove_unused_layers no)
			(net "GND")
			(clearance 0.0508)
			(thermal_gap 0.0508)
		)
		(pad "W10" thru_hole circle
			(at 19.800062 39.200074 180)
			(size 0.71628 0.71628)
			(drill 0.30988)
			(layers "*.Cu" "*.Mask")
			(remove_unused_layers no)
			(net "Net_8786")
			(clearance 0.0508)
			(thermal_gap 0.0508)
		)
		(pad "X9" thru_hole circle
			(at 17.599914 40.299894 180)
			(size 0.71628 0.71628)
			(drill 0.30988)
			(layers "*.Cu" "*.Mask")
			(remove_unused_layers no)
			(net "Net_8784")
			(clearance 0.0508)
			(thermal_gap 0.0508)
		)
		(pad "X10" thru_hole circle
			(at 19.800062 40.500046 180)
			(size 0.71628 0.71628)
			(drill 0.30988)
			(layers "*.Cu" "*.Mask")
			(remove_unused_layers no)
			(net "Net_8785")
			(clearance 0.0508)
			(thermal_gap 0.0508)
		)
		(pad "Y2" thru_hole circle
			(at 2.199894 41.800018 180)
			(size 0.906272 0.906272)
			(drill 0.499872)
			(layers "*.Cu" "*.Mask")
			(remove_unused_layers no)
			(net "GND")
			(clearance 0.0508)
			(thermal_gap 0.0508)
		)
		(pad "Y4" thru_hole circle
			(at 6.599936 41.800018 180)
			(size 0.906272 0.906272)
			(drill 0.499872)
			(layers "*.Cu" "*.Mask")
			(remove_unused_layers no)
			(net "GND")
			(clearance 0.0508)
			(thermal_gap 0.0508)
		)
		(pad "Y6" thru_hole circle
			(at 10.999978 41.800018 180)
			(size 0.906272 0.906272)
			(drill 0.499872)
			(layers "*.Cu" "*.Mask")
			(remove_unused_layers no)
			(net "GND")
			(clearance 0.0508)
			(thermal_gap 0.0508)
		)
		(pad "Y8" thru_hole circle
			(at 15.40002 41.800018 180)
			(size 0.906272 0.906272)
			(drill 0.499872)
			(layers "*.Cu" "*.Mask")
			(remove_unused_layers no)
			(net "GND")
			(clearance 0.0508)
			(thermal_gap 0.0508)
		)
		(pad "Y9" thru_hole circle
			(at 17.599914 41.60012 180)
			(size 0.71628 0.71628)
			(drill 0.30988)
			(layers "*.Cu" "*.Mask")
			(remove_unused_layers no)
			(net "Net_8783")
			(clearance 0.0508)
			(thermal_gap 0.0508)
		)
		(pad "Y10" thru_hole circle
			(at 19.800062 41.800018 180)
			(size 0.906272 0.906272)
			(drill 0.499872)
			(layers "*.Cu" "*.Mask")
			(remove_unused_layers no)
			(net "GND")
			(clearance 0.0508)
			(thermal_gap 0.0508)
		)
		(pad "Z1" thru_hole circle
			(at 0 42.900092 180)
			(size 0.906272 0.906272)
			(drill 0.499872)
			(layers "*.Cu" "*.Mask")
			(remove_unused_layers no)
			(net "GND")
			(clearance 0.0508)
			(thermal_gap 0.0508)
		)
		(pad "Z2" thru_hole circle
			(at 2.199894 43.09999 180)
			(size 0.71628 0.71628)
			(drill 0.30988)
			(layers "*.Cu" "*.Mask")
			(remove_unused_layers no)
			(net "Net_8819")
			(clearance 0.0508)
			(thermal_gap 0.0508)
		)
		(pad "Z3" thru_hole circle
			(at 4.400042 42.900092 180)
			(size 0.906272 0.906272)
			(drill 0.499872)
			(layers "*.Cu" "*.Mask")
			(remove_unused_layers no)
			(net "GND")
			(clearance 0.0508)
			(thermal_gap 0.0508)
		)
		(pad "Z4" thru_hole circle
			(at 6.599936 43.09999 180)
			(size 0.71628 0.71628)
			(drill 0.30988)
			(layers "*.Cu" "*.Mask")
			(remove_unused_layers no)
			(net "Net_8818")
			(clearance 0.0508)
			(thermal_gap 0.0508)
		)
		(pad "Z5" thru_hole circle
			(at 8.800084 42.900092 180)
			(size 0.906272 0.906272)
			(drill 0.499872)
			(layers "*.Cu" "*.Mask")
			(remove_unused_layers no)
			(net "GND")
			(clearance 0.0508)
			(thermal_gap 0.0508)
		)
		(pad "Z6" thru_hole circle
			(at 10.999978 43.09999 180)
			(size 0.71628 0.71628)
			(drill 0.30988)
			(layers "*.Cu" "*.Mask")
			(remove_unused_layers no)
			(net "Net_8817")
			(clearance 0.0508)
			(thermal_gap 0.0508)
		)
		(pad "Z7" thru_hole circle
			(at 13.199872 42.900092 180)
			(size 0.906272 0.906272)
			(drill 0.499872)
			(layers "*.Cu" "*.Mask")
			(remove_unused_layers no)
			(net "GND")
			(clearance 0.0508)
			(thermal_gap 0.0508)
		)
		(pad "Z8" thru_hole circle
			(at 15.40002 43.09999 180)
			(size 0.71628 0.71628)
			(drill 0.30988)
			(layers "*.Cu" "*.Mask")
			(remove_unused_layers no)
			(net "Net_8816")
			(clearance 0.0508)
			(thermal_gap 0.0508)
		)
		(pad "Z9" thru_hole circle
			(at 17.599914 42.900092 180)
			(size 0.906272 0.906272)
			(drill 0.499872)
			(layers "*.Cu" "*.Mask")
			(remove_unused_layers no)
			(net "GND")
			(clearance 0.0508)
			(thermal_gap 0.0508)
		)
		(pad "Z10" thru_hole circle
			(at 19.800062 43.09999 180)
			(size 0.71628 0.71628)
			(drill 0.30988)
			(layers "*.Cu" "*.Mask")
			(remove_unused_layers no)
			(net "Net_8782")
			(clearance 0.0508)
			(thermal_gap 0.0508)
		)
		(zone
			(layer "B.Cu")
			(hatch none 0.5)
			(connect_pads
				(clearance 0)
			)
			(min_thickness 0.25)
			(keepout
				(tracks allowed)
				(vias not_allowed)
				(pads allowed)
				(copperpour not_allowed)
				(footprints allowed)
			)
			(placement
				(enabled no)
				(sheetname "")
			)
			(fill
				(thermal_gap 0.5)
				(thermal_bridge_width 0.5)
				(island_removal_mode 0)
			)
			(polygon
				(pts
					(xy 286.972756 -394.665708) (xy 307.800756 -394.665708) (xy 307.800756 -412.50743) (xy 286.972756 -412.50743)
				)
			)
		)
		(zone
			(layer "B.Cu")
			(hatch none 0.5)
			(connect_pads
				(clearance 0)
			)
			(min_thickness 0.25)
			(keepout
				(tracks allowed)
				(vias not_allowed)
				(pads allowed)
				(copperpour not_allowed)
				(footprints allowed)
			)
			(placement
				(enabled no)
				(sheetname "")
			)
			(fill
				(thermal_gap 0.5)
				(thermal_bridge_width 0.5)
				(island_removal_mode 0)
			)
			(polygon
				(pts
					(xy 286.972756 -368.572796) (xy 307.800756 -368.572796) (xy 307.800756 -386.414518) (xy 286.972756 -386.414518)
				)
			)
		)
	)
	(footprint ""
		(layer "F.Cu")
		(at 148.511514 -296.445432 -90)
		(property "Reference" "R4568"
			(at 0 0 270)
			(layer "F.SilkS")
			(hide yes)
			(effects
				(font
					(size 1.27 1.27)
				)
			)
		)
		(property "Value" ""
			(at 0 0 270)
			(layer "F.Fab")
			(effects
				(font
					(size 1.27 1.27)
				)
			)
		)
		(duplicate_pad_numbers_are_jumpers no)
		(fp_line
			(start -0.7874 0.4064)
			(end -0.7874 -0.4064)
			(stroke
				(width 0.1524)
				(type default)
			)
			(layer "F.SilkS")
		)
		(fp_line
			(start 0.7874 0.4064)
			(end -0.7874 0.4064)
			(stroke
				(width 0.1524)
				(type default)
			)
			(layer "F.SilkS")
		)
		(fp_line
			(start -0.7874 -0.4064)
			(end 0.7874 -0.4064)
			(stroke
				(width 0.1524)
				(type default)
			)
			(layer "F.SilkS")
		)
		(fp_line
			(start 0.7874 -0.4064)
			(end 0.7874 0.4064)
			(stroke
				(width 0.1524)
				(type default)
			)
			(layer "F.SilkS")
		)
		(fp_line
			(start -0.67945 0.3048)
			(end -0.67945 -0.305054)
			(stroke
				(width 0.1)
				(type default)
			)
			(layer "F.Fab")
		)
		(fp_line
			(start -0.12065 0.3048)
			(end -0.67945 0.3048)
			(stroke
				(width 0.1)
				(type default)
			)
			(layer "F.Fab")
		)
		(fp_line
			(start 0.120396 0.3048)
			(end 0.120396 0.2794)
			(stroke
				(width 0.1)
				(type default)
			)
			(layer "F.Fab")
		)
		(fp_line
			(start 0.67945 0.3048)
			(end 0.120396 0.3048)
			(stroke
				(width 0.1)
				(type default)
			)
			(layer "F.Fab")
		)
		(fp_line
			(start -0.12065 0.2794)
			(end -0.12065 0.3048)
			(stroke
				(width 0.1)
				(type default)
			)
			(layer "F.Fab")
		)
		(fp_line
			(start 0.120396 0.2794)
			(end -0.12065 0.2794)
			(stroke
				(width 0.1)
				(type default)
			)
			(layer "F.Fab")
		)
		(fp_line
			(start -0.12065 -0.2794)
			(end 0.12065 -0.2794)
			(stroke
				(width 0.1)
				(type default)
			)
			(layer "F.Fab")
		)
		(fp_line
			(start 0.12065 -0.2794)
			(end 0.12065 -0.3048)
			(stroke
				(width 0.1)
				(type default)
			)
			(layer "F.Fab")
		)
		(fp_line
			(start 0.12065 -0.3048)
			(end 0.67945 -0.3048)
			(stroke
				(width 0.1)
				(type default)
			)
			(layer "F.Fab")
		)
		(fp_line
			(start 0.67945 -0.3048)
			(end 0.67945 0.3048)
			(stroke
				(width 0.1)
				(type default)
			)
			(layer "F.Fab")
		)
		(fp_line
			(start -0.67945 -0.305054)
			(end -0.12065 -0.305054)
			(stroke
				(width 0.1)
				(type default)
			)
			(layer "F.Fab")
		)
		(fp_line
			(start -0.12065 -0.305054)
			(end -0.12065 -0.2794)
			(stroke
				(width 0.1)
				(type default)
			)
			(layer "F.Fab")
		)
		(pad "1" smd circle
			(at -0.40005 0 270)
			(size 0 0)
			(layers "F.Cu" "F.Mask" "F.Paste")
			(net "PCEPLL0_VDDA18_PEX1")
		)
		(pad "2" smd circle
			(at 0.40005 0 270)
			(size 0 0)
			(layers "F.Cu" "F.Mask" "F.Paste")
			(net "PCEPLL0_VDDA18_PEX1_R")
		)
	)
	(footprint ""
		(layer "F.Cu")
		(at 419.771576 -25.342342 -90)
		(property "Reference" "R451"
			(at 0 0 270)
			(layer "F.SilkS")
			(hide yes)
			(effects
				(font
					(size 1.27 1.27)
				)
			)
		)
		(property "Value" ""
			(at 0 0 270)
			(layer "F.Fab")
			(effects
				(font
					(size 1.27 1.27)
				)
			)
		)
		(duplicate_pad_numbers_are_jumpers no)
		(fp_line
			(start -0.7874 0.4064)
			(end -0.7874 -0.4064)
			(stroke
				(width 0.1524)
				(type default)
			)
			(layer "F.SilkS")
		)
		(fp_line
			(start 0.7874 0.4064)
			(end -0.7874 0.4064)
			(stroke
				(width 0.1524)
				(type default)
			)
			(layer "F.SilkS")
		)
		(fp_line
			(start -0.7874 -0.4064)
			(end 0.7874 -0.4064)
			(stroke
				(width 0.1524)
				(type default)
			)
			(layer "F.SilkS")
		)
		(fp_line
			(start 0.7874 -0.4064)
			(end 0.7874 0.4064)
			(stroke
				(width 0.1524)
				(type default)
			)
			(layer "F.SilkS")
		)
		(fp_line
			(start -0.67945 0.3048)
			(end -0.67945 -0.305054)
			(stroke
				(width 0.1)
				(type default)
			)
			(layer "F.Fab")
		)
		(fp_line
			(start -0.12065 0.3048)
			(end -0.67945 0.3048)
			(stroke
				(width 0.1)
				(type default)
			)
			(layer "F.Fab")
		)
		(fp_line
			(start 0.120396 0.3048)
			(end 0.120396 0.2794)
			(stroke
				(width 0.1)
				(type default)
			)
			(layer "F.Fab")
		)
		(fp_line
			(start 0.67945 0.3048)
			(end 0.120396 0.3048)
			(stroke
				(width 0.1)
				(type default)
			)
			(layer "F.Fab")
		)
		(fp_line
			(start -0.12065 0.2794)
			(end -0.12065 0.3048)
			(stroke
				(width 0.1)
				(type default)
			)
			(layer "F.Fab")
		)
		(fp_line
			(start 0.120396 0.2794)
			(end -0.12065 0.2794)
			(stroke
				(width 0.1)
				(type default)
			)
			(layer "F.Fab")
		)
		(fp_line
			(start -0.12065 -0.2794)
			(end 0.12065 -0.2794)
			(stroke
				(width 0.1)
				(type default)
			)
			(layer "F.Fab")
		)
		(fp_line
			(start 0.12065 -0.2794)
			(end 0.12065 -0.3048)
			(stroke
				(width 0.1)
				(type default)
			)
			(layer "F.Fab")
		)
		(fp_line
			(start 0.12065 -0.3048)
			(end 0.67945 -0.3048)
			(stroke
				(width 0.1)
				(type default)
			)
			(layer "F.Fab")
		)
		(fp_line
			(start 0.67945 -0.3048)
			(end 0.67945 0.3048)
			(stroke
				(width 0.1)
				(type default)
			)
			(layer "F.Fab")
		)
		(fp_line
			(start -0.67945 -0.305054)
			(end -0.12065 -0.305054)
			(stroke
				(width 0.1)
				(type default)
			)
			(layer "F.Fab")
		)
		(fp_line
			(start -0.12065 -0.305054)
			(end -0.12065 -0.2794)
			(stroke
				(width 0.1)
				(type default)
			)
			(layer "F.Fab")
		)
		(pad "1" smd circle
			(at -0.40005 0 270)
			(size 0 0)
			(layers "F.Cu" "F.Mask" "F.Paste")
			(net "P3V3_SSD14")
		)
		(pad "2" smd circle
			(at 0.40005 0 270)
			(size 0 0)
			(layers "F.Cu" "F.Mask" "F.Paste")
			(net "DUALPORT_N_SSD14")
		)
	)
	(footprint ""
		(layer "F.Cu")
		(at 194.932808 -410.296868 -90)
		(property "Reference" "R500"
			(at 0 0 270)
			(layer "F.SilkS")
			(hide yes)
			(effects
				(font
					(size 1.27 1.27)
				)
			)
		)
		(property "Value" ""
			(at 0 0 270)
			(layer "F.Fab")
			(effects
				(font
					(size 1.27 1.27)
				)
			)
		)
		(duplicate_pad_numbers_are_jumpers no)
		(fp_line
			(start -0.7874 0.4064)
			(end -0.7874 -0.4064)
			(stroke
				(width 0.1524)
				(type default)
			)
			(layer "F.SilkS")
		)
		(fp_line
			(start 0.7874 0.4064)
			(end -0.7874 0.4064)
			(stroke
				(width 0.1524)
				(type default)
			)
			(layer "F.SilkS")
		)
		(fp_line
			(start -0.7874 -0.4064)
			(end 0.7874 -0.4064)
			(stroke
				(width 0.1524)
				(type default)
			)
			(layer "F.SilkS")
		)
		(fp_line
			(start 0.7874 -0.4064)
			(end 0.7874 0.4064)
			(stroke
				(width 0.1524)
				(type default)
			)
			(layer "F.SilkS")
		)
		(fp_line
			(start -0.67945 0.3048)
			(end -0.67945 -0.305054)
			(stroke
				(width 0.1)
				(type default)
			)
			(layer "F.Fab")
		)
		(fp_line
			(start -0.12065 0.3048)
			(end -0.67945 0.3048)
			(stroke
				(width 0.1)
				(type default)
			)
			(layer "F.Fab")
		)
		(fp_line
			(start 0.120396 0.3048)
			(end 0.120396 0.2794)
			(stroke
				(width 0.1)
				(type default)
			)
			(layer "F.Fab")
		)
		(fp_line
			(start 0.67945 0.3048)
			(end 0.120396 0.3048)
			(stroke
				(width 0.1)
				(type default)
			)
			(layer "F.Fab")
		)
		(fp_line
			(start -0.12065 0.2794)
			(end -0.12065 0.3048)
			(stroke
				(width 0.1)
				(type default)
			)
			(layer "F.Fab")
		)
		(fp_line
			(start 0.120396 0.2794)
			(end -0.12065 0.2794)
			(stroke
				(width 0.1)
				(type default)
			)
			(layer "F.Fab")
		)
		(fp_line
			(start -0.12065 -0.2794)
			(end 0.12065 -0.2794)
			(stroke
				(width 0.1)
				(type default)
			)
			(layer "F.Fab")
		)
		(fp_line
			(start 0.12065 -0.2794)
			(end 0.12065 -0.3048)
			(stroke
				(width 0.1)
				(type default)
			)
			(layer "F.Fab")
		)
		(fp_line
			(start 0.12065 -0.3048)
			(end 0.67945 -0.3048)
			(stroke
				(width 0.1)
				(type default)
			)
			(layer "F.Fab")
		)
		(fp_line
			(start 0.67945 -0.3048)
			(end 0.67945 0.3048)
			(stroke
				(width 0.1)
				(type default)
			)
			(layer "F.Fab")
		)
		(fp_line
			(start -0.67945 -0.305054)
			(end -0.12065 -0.305054)
			(stroke
				(width 0.1)
				(type default)
			)
			(layer "F.Fab")
		)
		(fp_line
			(start -0.12065 -0.305054)
			(end -0.12065 -0.2794)
			(stroke
				(width 0.1)
				(type default)
			)
			(layer "F.Fab")
		)
		(pad "1" smd circle
			(at -0.40005 0 270)
			(size 0 0)
			(layers "F.Cu" "F.Mask" "F.Paste")
			(net "SMB_ALERT_HSC_R_N")
		)
		(pad "2" smd circle
			(at 0.40005 0 270)
			(size 0 0)
			(layers "F.Cu" "F.Mask" "F.Paste")
			(net "SMB_ALERT_HSC_N")
		)
	)
	(footprint ""
		(layer "F.Cu")
		(at 196.119242 -134.394702 180)
		(property "Reference" "C230"
			(at 0 0 180)
			(layer "F.SilkS")
			(hide yes)
			(effects
				(font
					(size 1.27 1.27)
				)
			)
		)
		(property "Value" ""
			(at 0 0 180)
			(layer "F.Fab")
			(effects
				(font
					(size 1.27 1.27)
				)
			)
		)
		(duplicate_pad_numbers_are_jumpers no)
		(fp_line
			(start 0.299974 0.150114)
			(end -0.299974 0.150114)
			(stroke
				(width 0.1)
				(type default)
			)
			(layer "F.Fab")
		)
		(fp_line
			(start 0.299974 -0.150114)
			(end 0.299974 0.150114)
			(stroke
				(width 0.1)
				(type default)
			)
			(layer "F.Fab")
		)
		(fp_line
			(start -0.299974 0.150114)
			(end -0.299974 -0.150114)
			(stroke
				(width 0.1)
				(type default)
			)
			(layer "F.Fab")
		)
		(fp_line
			(start -0.299974 -0.150114)
			(end 0.299974 -0.150114)
			(stroke
				(width 0.1)
				(type default)
			)
			(layer "F.Fab")
		)
		(pad "1" smd rect
			(at -0.2667 0 180)
			(size 0.3048 0.381)
			(layers "F.Cu" "F.Mask" "F.Paste")
			(net "P5E_PEX1_STN0_TX_DP<6>")
		)
		(pad "2" smd rect
			(at 0.2667 0 180)
			(size 0.3048 0.381)
			(layers "F.Cu" "F.Mask" "F.Paste")
			(net "P5E_PEX1_STN0_TX_C_DP<6>")
		)
	)
	(footprint ""
		(layer "F.Cu")
		(at 190.920624 -70.307454 90)
		(property "Reference" "PC838"
			(at 0 0 90)
			(layer "F.SilkS")
			(hide yes)
			(effects
				(font
					(size 1.27 1.27)
				)
			)
		)
		(property "Value" ""
			(at 0 0 90)
			(layer "F.Fab")
			(effects
				(font
					(size 1.27 1.27)
				)
			)
		)
		(duplicate_pad_numbers_are_jumpers no)
		(fp_line
			(start 0.7874 -0.4064)
			(end 0.7874 0.4064)
			(stroke
				(width 0.1524)
				(type default)
			)
			(layer "F.SilkS")
		)
		(fp_line
			(start -0.7874 -0.4064)
			(end 0.7874 -0.4064)
			(stroke
				(width 0.1524)
				(type default)
			)
			(layer "F.SilkS")
		)
		(fp_line
			(start 0.7874 0.4064)
			(end -0.7874 0.4064)
			(stroke
				(width 0.1524)
				(type default)
			)
			(layer "F.SilkS")
		)
		(fp_line
			(start -0.7874 0.4064)
			(end -0.7874 -0.4064)
			(stroke
				(width 0.1524)
				(type default)
			)
			(layer "F.SilkS")
		)
		(fp_line
			(start -0.12065 -0.305054)
			(end -0.12065 -0.2794)
			(stroke
				(width 0.1)
				(type default)
			)
			(layer "F.Fab")
		)
		(fp_line
			(start -0.67945 -0.305054)
			(end -0.12065 -0.305054)
			(stroke
				(width 0.1)
				(type default)
			)
			(layer "F.Fab")
		)
		(fp_line
			(start 0.67945 -0.3048)
			(end 0.67945 0.3048)
			(stroke
				(width 0.1)
				(type default)
			)
			(layer "F.Fab")
		)
		(fp_line
			(start 0.12065 -0.3048)
			(end 0.67945 -0.3048)
			(stroke
				(width 0.1)
				(type default)
			)
			(layer "F.Fab")
		)
		(fp_line
			(start 0.12065 -0.2794)
			(end 0.12065 -0.3048)
			(stroke
				(width 0.1)
				(type default)
			)
			(layer "F.Fab")
		)
		(fp_line
			(start -0.12065 -0.2794)
			(end 0.12065 -0.2794)
			(stroke
				(width 0.1)
				(type default)
			)
			(layer "F.Fab")
		)
		(fp_line
			(start 0.120396 0.2794)
			(end -0.12065 0.2794)
			(stroke
				(width 0.1)
				(type default)
			)
			(layer "F.Fab")
		)
		(fp_line
			(start -0.12065 0.2794)
			(end -0.12065 0.3048)
			(stroke
				(width 0.1)
				(type default)
			)
			(layer "F.Fab")
		)
		(fp_line
			(start 0.67945 0.3048)
			(end 0.120396 0.3048)
			(stroke
				(width 0.1)
				(type default)
			)
			(layer "F.Fab")
		)
		(fp_line
			(start 0.120396 0.3048)
			(end 0.120396 0.2794)
			(stroke
				(width 0.1)
				(type default)
			)
			(layer "F.Fab")
		)
		(fp_line
			(start -0.12065 0.3048)
			(end -0.67945 0.3048)
			(stroke
				(width 0.1)
				(type default)
			)
			(layer "F.Fab")
		)
		(fp_line
			(start -0.67945 0.3048)
			(end -0.67945 -0.305054)
			(stroke
				(width 0.1)
				(type default)
			)
			(layer "F.Fab")
		)
		(pad "1" smd circle
			(at -0.40005 0 90)
			(size 0 0)
			(layers "F.Cu" "F.Mask" "F.Paste")
			(net "P12V_AUX")
		)
		(pad "2" smd circle
			(at 0.40005 0 90)
			(size 0 0)
			(layers "F.Cu" "F.Mask" "F.Paste")
			(net "GND")
		)
	)
	(footprint ""
		(layer "F.Cu")
		(at 284.810454 -18.61439 90)
		(property "Reference" "U135"
			(at -1.24079 2.312416 90)
			(unlocked yes)
			(layer "F.SilkS")
			(effects
				(font
					(size 0.7874 0.5842)
					(thickness 0.1524)
				)
				(justify left)
			)
		)
		(property "Value" ""
			(at 0 0 90)
			(layer "F.Fab")
			(effects
				(font
					(size 1.27 1.27)
				)
			)
		)
		(duplicate_pad_numbers_are_jumpers no)
		(fp_line
			(start 1.463548 -1.549908)
			(end 1.463548 1.549908)
			(stroke
				(width 0.1524)
				(type default)
			)
			(layer "F.SilkS")
		)
		(fp_line
			(start 0.762 -1.549908)
			(end 1.463548 -1.549908)
			(stroke
				(width 0.1524)
				(type default)
			)
			(layer "F.SilkS")
		)
		(fp_line
			(start -0.787908 -1.549908)
			(end 0 -0.762)
			(stroke
				(width 0.1524)
				(type default)
			)
			(layer "F.SilkS")
		)
		(fp_line
			(start -1.463548 -1.549908)
			(end -0.787908 -1.549908)
			(stroke
				(width 0.1524)
				(type default)
			)
			(layer "F.SilkS")
		)
		(fp_line
			(start 0 -0.762)
			(end 0.762 -1.549908)
			(stroke
				(width 0.1524)
				(type default)
			)
			(layer "F.SilkS")
		)
		(fp_line
			(start 1.463548 1.549908)
			(end -1.463548 1.549908)
			(stroke
				(width 0.1524)
				(type default)
			)
			(layer "F.SilkS")
		)
		(fp_line
			(start -1.463548 1.549908)
			(end -1.463548 -1.549908)
			(stroke
				(width 0.1524)
				(type default)
			)
			(layer "F.SilkS")
		)
		(fp_poly
			(pts
				(xy -3.46202 -1.44907) (xy -2.84226 -1.13919) (xy -3.46202 -0.82931)
			)
			(stroke
				(width 0)
				(type default)
			)
			(fill yes)
			(layer "F.SilkS")
		)
		(fp_line
			(start 1.549908 -1.549908)
			(end 1.549908 1.549908)
			(stroke
				(width 0.1)
				(type default)
			)
			(layer "F.Fab")
		)
		(fp_line
			(start -1.549908 -1.549908)
			(end 1.549908 -1.549908)
			(stroke
				(width 0.1)
				(type default)
			)
			(layer "F.Fab")
		)
		(fp_line
			(start 1.549908 1.549908)
			(end -1.549908 1.549908)
			(stroke
				(width 0.1)
				(type default)
			)
			(layer "F.Fab")
		)
		(fp_line
			(start -1.549908 1.549908)
			(end -1.549908 -1.549908)
			(stroke
				(width 0.1)
				(type default)
			)
			(layer "F.Fab")
		)
		(fp_poly
			(pts
				(xy -3.4798 -1.359916) (xy -2.86004 -1.050036) (xy -3.4798 -0.740156)
			)
			(stroke
				(width 0)
				(type default)
			)
			(fill yes)
			(layer "F.Fab")
		)
		(pad "1" smd rect
			(at -2.175002 -1.050036 180)
			(size 0.6096 1.1684)
			(layers "F.Cu" "F.Mask" "F.Paste")
			(net "P3V3_SSD9")
		)
		(pad "2" smd rect
			(at -2.175002 -0.32512 180)
			(size 0.4318 1.1684)
			(layers "F.Cu" "F.Mask" "F.Paste")
			(net "SMB_ISO_SSD9_SCL")
		)
		(pad "3" smd rect
			(at -2.175002 0.32512 180)
			(size 0.4318 1.1684)
			(layers "F.Cu" "F.Mask" "F.Paste")
			(net "SMB_ISO_SSD9_SDA")
		)
		(pad "4" smd rect
			(at -2.175002 1.050036 180)
			(size 0.6096 1.1684)
			(layers "F.Cu" "F.Mask" "F.Paste")
			(net "GND")
		)
		(pad "5" smd rect
			(at 2.175002 1.050036 180)
			(size 0.6096 1.1684)
			(layers "F.Cu" "F.Mask" "F.Paste")
			(net "SMB_SSD9_ISO_EN")
		)
		(pad "6" smd rect
			(at 2.175002 0.32512 180)
			(size 0.4318 1.1684)
			(layers "F.Cu" "F.Mask" "F.Paste")
			(net "SMB_BIC_I2C9_MUX1_SSD9_R_SDA")
		)
		(pad "7" smd rect
			(at 2.175002 -0.32512 180)
			(size 0.4318 1.1684)
			(layers "F.Cu" "F.Mask" "F.Paste")
			(net "SMB_BIC_I2C9_MUX1_SSD9_R_SCL")
		)
		(pad "8" smd rect
			(at 2.175002 -1.050036 180)
			(size 0.6096 1.1684)
			(layers "F.Cu" "F.Mask" "F.Paste")
			(net "P3V3_AUX")
		)
	)
	(footprint ""
		(layer "F.Cu")
		(at 450.195188 -415.621216 90)
		(property "Reference" "R5601"
			(at 0 0 90)
			(layer "F.SilkS")
			(hide yes)
			(effects
				(font
					(size 1.27 1.27)
				)
			)
		)
		(property "Value" ""
			(at 0 0 90)
			(layer "F.Fab")
			(effects
				(font
					(size 1.27 1.27)
				)
			)
		)
		(duplicate_pad_numbers_are_jumpers no)
		(fp_line
			(start 0.7874 -0.4064)
			(end 0.7874 0.4064)
			(stroke
				(width 0.1524)
				(type default)
			)
			(layer "F.SilkS")
		)
		(fp_line
			(start -0.7874 -0.4064)
			(end 0.7874 -0.4064)
			(stroke
				(width 0.1524)
				(type default)
			)
			(layer "F.SilkS")
		)
		(fp_line
			(start 0.7874 0.4064)
			(end -0.7874 0.4064)
			(stroke
				(width 0.1524)
				(type default)
			)
			(layer "F.SilkS")
		)
		(fp_line
			(start -0.7874 0.4064)
			(end -0.7874 -0.4064)
			(stroke
				(width 0.1524)
				(type default)
			)
			(layer "F.SilkS")
		)
		(fp_line
			(start -0.12065 -0.305054)
			(end -0.12065 -0.2794)
			(stroke
				(width 0.1)
				(type default)
			)
			(layer "F.Fab")
		)
		(fp_line
			(start -0.67945 -0.305054)
			(end -0.12065 -0.305054)
			(stroke
				(width 0.1)
				(type default)
			)
			(layer "F.Fab")
		)
		(fp_line
			(start 0.67945 -0.3048)
			(end 0.67945 0.3048)
			(stroke
				(width 0.1)
				(type default)
			)
			(layer "F.Fab")
		)
		(fp_line
			(start 0.12065 -0.3048)
			(end 0.67945 -0.3048)
			(stroke
				(width 0.1)
				(type default)
			)
			(layer "F.Fab")
		)
		(fp_line
			(start 0.12065 -0.2794)
			(end 0.12065 -0.3048)
			(stroke
				(width 0.1)
				(type default)
			)
			(layer "F.Fab")
		)
		(fp_line
			(start -0.12065 -0.2794)
			(end 0.12065 -0.2794)
			(stroke
				(width 0.1)
				(type default)
			)
			(layer "F.Fab")
		)
		(fp_line
			(start 0.120396 0.2794)
			(end -0.12065 0.2794)
			(stroke
				(width 0.1)
				(type default)
			)
			(layer "F.Fab")
		)
		(fp_line
			(start -0.12065 0.2794)
			(end -0.12065 0.3048)
			(stroke
				(width 0.1)
				(type default)
			)
			(layer "F.Fab")
		)
		(fp_line
			(start 0.67945 0.3048)
			(end 0.120396 0.3048)
			(stroke
				(width 0.1)
				(type default)
			)
			(layer "F.Fab")
		)
		(fp_line
			(start 0.120396 0.3048)
			(end 0.120396 0.2794)
			(stroke
				(width 0.1)
				(type default)
			)
			(layer "F.Fab")
		)
		(fp_line
			(start -0.12065 0.3048)
			(end -0.67945 0.3048)
			(stroke
				(width 0.1)
				(type default)
			)
			(layer "F.Fab")
		)
		(fp_line
			(start -0.67945 0.3048)
			(end -0.67945 -0.305054)
			(stroke
				(width 0.1)
				(type default)
			)
			(layer "F.Fab")
		)
		(pad "1" smd circle
			(at -0.40005 0 90)
			(size 0 0)
			(layers "F.Cu" "F.Mask" "F.Paste")
			(net "LM75_1_A2")
		)
		(pad "2" smd circle
			(at 0.40005 0 90)
			(size 0 0)
			(layers "F.Cu" "F.Mask" "F.Paste")
			(net "P3V3_AUX")
		)
	)
	(footprint ""
		(layer "F.Cu")
		(at 455.32929 -105.253536)
		(property "Reference" "PD17"
			(at 4.988052 0.267208 0)
			(unlocked yes)
			(layer "F.SilkS")
			(effects
				(font
					(size 0.7874 0.5842)
					(thickness 0.1524)
				)
				(justify left)
			)
		)
		(property "Value" ""
			(at 0 0 0)
			(layer "F.Fab")
			(effects
				(font
					(size 1.27 1.27)
				)
			)
		)
		(duplicate_pad_numbers_are_jumpers no)
		(fp_line
			(start -3.656584 -1.970024)
			(end -3.656584 1.970024)
			(stroke
				(width 0.1524)
				(type default)
			)
			(layer "F.SilkS")
		)
		(fp_line
			(start -3.656584 1.970024)
			(end 4.240784 1.970024)
			(stroke
				(width 0.1524)
				(type default)
			)
			(layer "F.SilkS")
		)
		(fp_line
			(start 4.240784 -1.970024)
			(end -3.656584 -1.970024)
			(stroke
				(width 0.1524)
				(type default)
			)
			(layer "F.SilkS")
		)
		(fp_line
			(start 4.240784 1.970024)
			(end 4.240784 -1.970024)
			(stroke
				(width 0.1524)
				(type default)
			)
			(layer "F.SilkS")
		)
		(fp_rect
			(start 3.580384 1.970024)
			(end 4.240784 -1.970024)
			(stroke
				(width 0)
				(type default)
			)
			(fill yes)
			(layer "F.SilkS")
		)
		(fp_line
			(start -2.3749 -1.970024)
			(end -2.3749 1.970024)
			(stroke
				(width 0.1)
				(type default)
			)
			(layer "F.Fab")
		)
		(fp_line
			(start -2.3749 1.970024)
			(end 2.3749 1.970024)
			(stroke
				(width 0.1)
				(type default)
			)
			(layer "F.Fab")
		)
		(fp_line
			(start 2.3749 -1.970024)
			(end -2.3749 -1.970024)
			(stroke
				(width 0.1)
				(type default)
			)
			(layer "F.Fab")
		)
		(fp_line
			(start 2.3749 1.970024)
			(end 2.3749 -1.970024)
			(stroke
				(width 0.1)
				(type default)
			)
			(layer "F.Fab")
		)
		(fp_text user "+"
			(at -4.9784 -0.23495 0)
			(unlocked yes)
			(layer "F.Fab")
			(effects
				(font
					(size 1.905 1.4224)
					(thickness 0.1524)
				)
				(justify left)
			)
		)
		(fp_text user "-"
			(at 4.1656 -0.23495 0)
			(unlocked yes)
			(layer "F.Fab")
			(effects
				(font
					(size 1.905 1.4224)
					(thickness 0.1524)
				)
				(justify left)
			)
		)
		(pad "A" smd rect
			(at -2.450084 0)
			(size 2.159 2.2606)
			(layers "F.Cu" "F.Mask" "F.Paste")
			(net "GND")
		)
		(pad "C" smd rect
			(at 2.450084 0)
			(size 2.159 2.2606)
			(layers "F.Cu" "F.Mask" "F.Paste")
			(net "P12V_AUX")
		)
	)
	(footprint ""
		(layer "F.Cu")
		(at 116.672106 -316.869318)
		(property "Reference" "C1157"
			(at 0 0 0)
			(layer "F.SilkS")
			(hide yes)
			(effects
				(font
					(size 1.27 1.27)
				)
			)
		)
		(property "Value" ""
			(at 0 0 0)
			(layer "F.Fab")
			(effects
				(font
					(size 1.27 1.27)
				)
			)
		)
		(duplicate_pad_numbers_are_jumpers no)
		(fp_line
			(start -1.2954 -0.5842)
			(end 1.2954 -0.5842)
			(stroke
				(width 0.1524)
				(type default)
			)
			(layer "F.SilkS")
		)
		(fp_line
			(start -1.2954 0.5842)
			(end -1.2954 -0.5842)
			(stroke
				(width 0.1524)
				(type default)
			)
			(layer "F.SilkS")
		)
		(fp_line
			(start 1.2954 -0.5842)
			(end 1.2954 0.5842)
			(stroke
				(width 0.1524)
				(type default)
			)
			(layer "F.SilkS")
		)
		(fp_line
			(start 1.2954 0.5842)
			(end -1.2954 0.5842)
			(stroke
				(width 0.1524)
				(type default)
			)
			(layer "F.SilkS")
		)
		(fp_line
			(start -1.1938 -0.4064)
			(end -0.8636 -0.4064)
			(stroke
				(width 0.1)
				(type default)
			)
			(layer "F.Fab")
		)
		(fp_line
			(start -1.1938 0.4064)
			(end -1.1938 -0.4064)
			(stroke
				(width 0.1)
				(type default)
			)
			(layer "F.Fab")
		)
		(fp_line
			(start -0.8636 -0.4572)
			(end 0.8636 -0.4572)
			(stroke
				(width 0.1)
				(type default)
			)
			(layer "F.Fab")
		)
		(fp_line
			(start -0.8636 -0.4064)
			(end -0.8636 -0.4572)
			(stroke
				(width 0.1)
				(type default)
			)
			(layer "F.Fab")
		)
		(fp_line
			(start -0.8636 0.4064)
			(end -1.1938 0.4064)
			(stroke
				(width 0.1)
				(type default)
			)
			(layer "F.Fab")
		)
		(fp_line
			(start -0.8636 0.4572)
			(end -0.8636 0.4064)
			(stroke
				(width 0.1)
				(type default)
			)
			(layer "F.Fab")
		)
		(fp_line
			(start 0.8636 -0.4572)
			(end 0.8636 -0.4064)
			(stroke
				(width 0.1)
				(type default)
			)
			(layer "F.Fab")
		)
		(fp_line
			(start 0.8636 -0.4064)
			(end 1.1938 -0.4064)
			(stroke
				(width 0.1)
				(type default)
			)
			(layer "F.Fab")
		)
		(fp_line
			(start 0.8636 0.4064)
			(end 0.8636 0.4572)
			(stroke
				(width 0.1)
				(type default)
			)
			(layer "F.Fab")
		)
		(fp_line
			(start 0.8636 0.4572)
			(end -0.8636 0.4572)
			(stroke
				(width 0.1)
				(type default)
			)
			(layer "F.Fab")
		)
		(fp_line
			(start 1.1938 -0.4064)
			(end 1.1938 0.4064)
			(stroke
				(width 0.1)
				(type default)
			)
			(layer "F.Fab")
		)
		(fp_line
			(start 1.1938 0.4064)
			(end 0.8636 0.4064)
			(stroke
				(width 0.1)
				(type default)
			)
			(layer "F.Fab")
		)
		(pad "1" smd rect
			(at -0.7366 0 270)
			(size 0.7112 0.8128)
			(layers "F.Cu" "F.Mask" "F.Paste")
			(net "P0V8_SERDES_VDDA_PEX0")
		)
		(pad "2" smd rect
			(at 0.7366 0 270)
			(size 0.7112 0.8128)
			(layers "F.Cu" "F.Mask" "F.Paste")
			(net "GND")
		)
	)
	(footprint ""
		(layer "F.Cu")
		(at 439.924698 -115.835176 90)
		(property "Reference" "PU122"
			(at 0.009398 -4.915154 90)
			(unlocked yes)
			(layer "F.SilkS")
			(effects
				(font
					(size 0.7874 0.5842)
					(thickness 0.1524)
				)
			)
		)
		(property "Value" ""
			(at 0 0 90)
			(layer "F.Fab")
			(effects
				(font
					(size 1.27 1.27)
				)
			)
		)
		(duplicate_pad_numbers_are_jumpers no)
		(fp_line
			(start 1.239774 -1.495298)
			(end 1.239774 1.495298)
			(stroke
				(width 0.1524)
				(type default)
			)
			(layer "F.SilkS")
		)
		(fp_line
			(start -1.239774 -1.495298)
			(end 1.239774 -1.495298)
			(stroke
				(width 0.1524)
				(type default)
			)
			(layer "F.SilkS")
		)
		(fp_line
			(start 1.239774 1.495298)
			(end -1.239774 1.495298)
			(stroke
				(width 0.1524)
				(type default)
			)
			(layer "F.SilkS")
		)
		(fp_line
			(start -1.239774 1.495298)
			(end -1.239774 -1.495298)
			(stroke
				(width 0.1524)
				(type default)
			)
			(layer "F.SilkS")
		)
		(fp_poly
			(pts
				(xy -1.809242 -1.849628) (xy -2.527808 -1.131316) (xy -1.450086 -0.77216)
			)
			(stroke
				(width 0)
				(type default)
			)
			(fill yes)
			(layer "F.SilkS")
		)
		(fp_line
			(start 0.8001 -1.050036)
			(end 0.8001 1.050036)
			(stroke
				(width 0.1)
				(type default)
			)
			(layer "F.Fab")
		)
		(fp_line
			(start -0.8001 -1.050036)
			(end 0.8001 -1.050036)
			(stroke
				(width 0.1)
				(type default)
			)
			(layer "F.Fab")
		)
		(fp_line
			(start 0.8001 1.050036)
			(end -0.8001 1.050036)
			(stroke
				(width 0.1)
				(type default)
			)
			(layer "F.Fab")
		)
		(fp_line
			(start -0.8001 1.050036)
			(end -0.8001 -1.050036)
			(stroke
				(width 0.1)
				(type default)
			)
			(layer "F.Fab")
		)
		(fp_poly
			(pts
				(xy -2.458974 -0.508) (xy -2.458974 0.508) (xy -1.442974 0)
			)
			(stroke
				(width 0)
				(type default)
			)
			(fill yes)
			(layer "F.Fab")
		)
		(pad "1_2" smd circle
			(at -0.374904 0 180)
			(size 0 0)
			(layers "F.Cu" "F.Mask" "F.Paste")
			(net "P3V3_AUX")
		)
		(pad "3" smd rect
			(at -0.499872 0.999998 90)
			(size 0.254 0.7112)
			(layers "F.Cu" "F.Mask" "F.Paste")
			(net "GND")
		)
		(pad "4" smd rect
			(at 0 0.999998 90)
			(size 0.254 0.7112)
			(layers "F.Cu" "F.Mask" "F.Paste")
			(net "P3V3_NIC7_CO_ILIMIT")
		)
		(pad "5" smd rect
			(at 0.499872 0.999998 90)
			(size 0.254 0.7112)
			(layers "F.Cu" "F.Mask" "F.Paste")
			(net "P3V3_NIC7_CO_MODE")
		)
		(pad "6_7" smd circle
			(at 0.374904 0)
			(size 0 0)
			(layers "F.Cu" "F.Mask" "F.Paste")
			(net "P3V3_NIC7")
		)
		(pad "8" smd rect
			(at 0.499872 -0.999998 90)
			(size 0.254 0.7112)
			(layers "F.Cu" "F.Mask" "F.Paste")
			(net "P3V3_NIC7_CO_GATE")
		)
		(pad "9" smd rect
			(at 0 -0.999998 90)
			(size 0.254 0.7112)
			(layers "F.Cu" "F.Mask" "F.Paste")
			(net "P3V3_NIC7_CO_EN")
		)
		(pad "10" smd rect
			(at -0.499872 -0.999998 90)
			(size 0.254 0.7112)
			(layers "F.Cu" "F.Mask" "F.Paste")
			(net "P3V3_NIC7_CO_DV_DT")
		)
	)
	(footprint ""
		(layer "F.Cu")
		(at 119.983758 -61.487812 180)
		(property "Reference" "R5974"
			(at 0 0 180)
			(layer "F.SilkS")
			(hide yes)
			(effects
				(font
					(size 1.27 1.27)
				)
			)
		)
		(property "Value" ""
			(at 0 0 180)
			(layer "F.Fab")
			(effects
				(font
					(size 1.27 1.27)
				)
			)
		)
		(duplicate_pad_numbers_are_jumpers no)
		(fp_line
			(start 0.7874 0.4064)
			(end -0.7874 0.4064)
			(stroke
				(width 0.1524)
				(type default)
			)
			(layer "F.SilkS")
		)
		(fp_line
			(start 0.7874 -0.4064)
			(end 0.7874 0.4064)
			(stroke
				(width 0.1524)
				(type default)
			)
			(layer "F.SilkS")
		)
		(fp_line
			(start -0.7874 0.4064)
			(end -0.7874 -0.4064)
			(stroke
				(width 0.1524)
				(type default)
			)
			(layer "F.SilkS")
		)
		(fp_line
			(start -0.7874 -0.4064)
			(end 0.7874 -0.4064)
			(stroke
				(width 0.1524)
				(type default)
			)
			(layer "F.SilkS")
		)
		(fp_line
			(start 0.67945 0.3048)
			(end 0.120396 0.3048)
			(stroke
				(width 0.1)
				(type default)
			)
			(layer "F.Fab")
		)
		(fp_line
			(start 0.67945 -0.3048)
			(end 0.67945 0.3048)
			(stroke
				(width 0.1)
				(type default)
			)
			(layer "F.Fab")
		)
		(fp_line
			(start 0.12065 -0.2794)
			(end 0.12065 -0.3048)
			(stroke
				(width 0.1)
				(type default)
			)
			(layer "F.Fab")
		)
		(fp_line
			(start 0.12065 -0.3048)
			(end 0.67945 -0.3048)
			(stroke
				(width 0.1)
				(type default)
			)
			(layer "F.Fab")
		)
		(fp_line
			(start 0.120396 0.3048)
			(end 0.120396 0.2794)
			(stroke
				(width 0.1)
				(type default)
			)
			(layer "F.Fab")
		)
		(fp_line
			(start 0.120396 0.2794)
			(end -0.12065 0.2794)
			(stroke
				(width 0.1)
				(type default)
			)
			(layer "F.Fab")
		)
		(fp_line
			(start -0.12065 0.3048)
			(end -0.67945 0.3048)
			(stroke
				(width 0.1)
				(type default)
			)
			(layer "F.Fab")
		)
		(fp_line
			(start -0.12065 0.2794)
			(end -0.12065 0.3048)
			(stroke
				(width 0.1)
				(type default)
			)
			(layer "F.Fab")
		)
		(fp_line
			(start -0.12065 -0.2794)
			(end 0.12065 -0.2794)
			(stroke
				(width 0.1)
				(type default)
			)
			(layer "F.Fab")
		)
		(fp_line
			(start -0.12065 -0.305054)
			(end -0.12065 -0.2794)
			(stroke
				(width 0.1)
				(type default)
			)
			(layer "F.Fab")
		)
		(fp_line
			(start -0.67945 0.3048)
			(end -0.67945 -0.305054)
			(stroke
				(width 0.1)
				(type default)
			)
			(layer "F.Fab")
		)
		(fp_line
			(start -0.67945 -0.305054)
			(end -0.12065 -0.305054)
			(stroke
				(width 0.1)
				(type default)
			)
			(layer "F.Fab")
		)
		(pad "1" smd circle
			(at -0.40005 0 180)
			(size 0 0)
			(layers "F.Cu" "F.Mask" "F.Paste")
			(net "PWRGD_P12V_SSD4_D")
		)
		(pad "2" smd circle
			(at 0.40005 0 180)
			(size 0 0)
			(layers "F.Cu" "F.Mask" "F.Paste")
			(net "PWRGD_P12V_SSD4_R")
		)
	)
	(footprint ""
		(layer "F.Cu")
		(at 245.732808 -309.555642)
		(property "Reference" "PC260"
			(at 0 0 0)
			(layer "F.SilkS")
			(hide yes)
			(effects
				(font
					(size 1.27 1.27)
				)
			)
		)
		(property "Value" ""
			(at 0 0 0)
			(layer "F.Fab")
			(effects
				(font
					(size 1.27 1.27)
				)
			)
		)
		(duplicate_pad_numbers_are_jumpers no)
		(fp_line
			(start -0.7874 -0.4064)
			(end 0.7874 -0.4064)
			(stroke
				(width 0.1524)
				(type default)
			)
			(layer "F.SilkS")
		)
		(fp_line
			(start -0.7874 0.4064)
			(end -0.7874 -0.4064)
			(stroke
				(width 0.1524)
				(type default)
			)
			(layer "F.SilkS")
		)
		(fp_line
			(start 0.7874 -0.4064)
			(end 0.7874 0.4064)
			(stroke
				(width 0.1524)
				(type default)
			)
			(layer "F.SilkS")
		)
		(fp_line
			(start 0.7874 0.4064)
			(end -0.7874 0.4064)
			(stroke
				(width 0.1524)
				(type default)
			)
			(layer "F.SilkS")
		)
		(fp_line
			(start -0.67945 -0.305054)
			(end -0.12065 -0.305054)
			(stroke
				(width 0.1)
				(type default)
			)
			(layer "F.Fab")
		)
		(fp_line
			(start -0.67945 0.3048)
			(end -0.67945 -0.305054)
			(stroke
				(width 0.1)
				(type default)
			)
			(layer "F.Fab")
		)
		(fp_line
			(start -0.12065 -0.305054)
			(end -0.12065 -0.2794)
			(stroke
				(width 0.1)
				(type default)
			)
			(layer "F.Fab")
		)
		(fp_line
			(start -0.12065 -0.2794)
			(end 0.12065 -0.2794)
			(stroke
				(width 0.1)
				(type default)
			)
			(layer "F.Fab")
		)
		(fp_line
			(start -0.12065 0.2794)
			(end -0.12065 0.3048)
			(stroke
				(width 0.1)
				(type default)
			)
			(layer "F.Fab")
		)
		(fp_line
			(start -0.12065 0.3048)
			(end -0.67945 0.3048)
			(stroke
				(width 0.1)
				(type default)
			)
			(layer "F.Fab")
		)
		(fp_line
			(start 0.120396 0.2794)
			(end -0.12065 0.2794)
			(stroke
				(width 0.1)
				(type default)
			)
			(layer "F.Fab")
		)
		(fp_line
			(start 0.120396 0.3048)
			(end 0.120396 0.2794)
			(stroke
				(width 0.1)
				(type default)
			)
			(layer "F.Fab")
		)
		(fp_line
			(start 0.12065 -0.3048)
			(end 0.67945 -0.3048)
			(stroke
				(width 0.1)
				(type default)
			)
			(layer "F.Fab")
		)
		(fp_line
			(start 0.12065 -0.2794)
			(end 0.12065 -0.3048)
			(stroke
				(width 0.1)
				(type default)
			)
			(layer "F.Fab")
		)
		(fp_line
			(start 0.67945 -0.3048)
			(end 0.67945 0.3048)
			(stroke
				(width 0.1)
				(type default)
			)
			(layer "F.Fab")
		)
		(fp_line
			(start 0.67945 0.3048)
			(end 0.120396 0.3048)
			(stroke
				(width 0.1)
				(type default)
			)
			(layer "F.Fab")
		)
		(pad "1" smd circle
			(at -0.40005 0)
			(size 0 0)
			(layers "F.Cu" "F.Mask" "F.Paste")
			(net "P1V25_PEX2_FB")
		)
		(pad "2" smd circle
			(at 0.40005 0)
			(size 0 0)
			(layers "F.Cu" "F.Mask" "F.Paste")
			(net "SH_P1V25_PEX2_FB_P")
		)
	)
	(footprint ""
		(layer "F.Cu")
		(at 173.394116 -34.248852)
		(property "Reference" "R5675"
			(at 0 0 0)
			(layer "F.SilkS")
			(hide yes)
			(effects
				(font
					(size 1.27 1.27)
				)
			)
		)
		(property "Value" ""
			(at 0 0 0)
			(layer "F.Fab")
			(effects
				(font
					(size 1.27 1.27)
				)
			)
		)
		(duplicate_pad_numbers_are_jumpers no)
		(fp_line
			(start -0.7874 -0.4064)
			(end 0.7874 -0.4064)
			(stroke
				(width 0.1524)
				(type default)
			)
			(layer "F.SilkS")
		)
		(fp_line
			(start -0.7874 0.4064)
			(end -0.7874 -0.4064)
			(stroke
				(width 0.1524)
				(type default)
			)
			(layer "F.SilkS")
		)
		(fp_line
			(start 0.7874 -0.4064)
			(end 0.7874 0.4064)
			(stroke
				(width 0.1524)
				(type default)
			)
			(layer "F.SilkS")
		)
		(fp_line
			(start 0.7874 0.4064)
			(end -0.7874 0.4064)
			(stroke
				(width 0.1524)
				(type default)
			)
			(layer "F.SilkS")
		)
		(fp_line
			(start -0.67945 -0.305054)
			(end -0.12065 -0.305054)
			(stroke
				(width 0.1)
				(type default)
			)
			(layer "F.Fab")
		)
		(fp_line
			(start -0.67945 0.3048)
			(end -0.67945 -0.305054)
			(stroke
				(width 0.1)
				(type default)
			)
			(layer "F.Fab")
		)
		(fp_line
			(start -0.12065 -0.305054)
			(end -0.12065 -0.2794)
			(stroke
				(width 0.1)
				(type default)
			)
			(layer "F.Fab")
		)
		(fp_line
			(start -0.12065 -0.2794)
			(end 0.12065 -0.2794)
			(stroke
				(width 0.1)
				(type default)
			)
			(layer "F.Fab")
		)
		(fp_line
			(start -0.12065 0.2794)
			(end -0.12065 0.3048)
			(stroke
				(width 0.1)
				(type default)
			)
			(layer "F.Fab")
		)
		(fp_line
			(start -0.12065 0.3048)
			(end -0.67945 0.3048)
			(stroke
				(width 0.1)
				(type default)
			)
			(layer "F.Fab")
		)
		(fp_line
			(start 0.120396 0.2794)
			(end -0.12065 0.2794)
			(stroke
				(width 0.1)
				(type default)
			)
			(layer "F.Fab")
		)
		(fp_line
			(start 0.120396 0.3048)
			(end 0.120396 0.2794)
			(stroke
				(width 0.1)
				(type default)
			)
			(layer "F.Fab")
		)
		(fp_line
			(start 0.12065 -0.3048)
			(end 0.67945 -0.3048)
			(stroke
				(width 0.1)
				(type default)
			)
			(layer "F.Fab")
		)
		(fp_line
			(start 0.12065 -0.2794)
			(end 0.12065 -0.3048)
			(stroke
				(width 0.1)
				(type default)
			)
			(layer "F.Fab")
		)
		(fp_line
			(start 0.67945 -0.3048)
			(end 0.67945 0.3048)
			(stroke
				(width 0.1)
				(type default)
			)
			(layer "F.Fab")
		)
		(fp_line
			(start 0.67945 0.3048)
			(end 0.120396 0.3048)
			(stroke
				(width 0.1)
				(type default)
			)
			(layer "F.Fab")
		)
		(pad "1" smd circle
			(at -0.40005 0)
			(size 0 0)
			(layers "F.Cu" "F.Mask" "F.Paste")
			(net "RST_SMB_SSD6_ISO_N")
		)
		(pad "2" smd circle
			(at 0.40005 0)
			(size 0 0)
			(layers "F.Cu" "F.Mask" "F.Paste")
			(net "P3V3_SSD6")
		)
	)
	(footprint ""
		(layer "F.Cu")
		(at 235.619544 -149.752812 180)
		(property "Reference" "R1211"
			(at 0 0 180)
			(layer "F.SilkS")
			(hide yes)
			(effects
				(font
					(size 1.27 1.27)
				)
			)
		)
		(property "Value" ""
			(at 0 0 180)
			(layer "F.Fab")
			(effects
				(font
					(size 1.27 1.27)
				)
			)
		)
		(duplicate_pad_numbers_are_jumpers no)
		(fp_line
			(start 0.7874 0.4064)
			(end -0.7874 0.4064)
			(stroke
				(width 0.1524)
				(type default)
			)
			(layer "F.SilkS")
		)
		(fp_line
			(start 0.67945 0.3048)
			(end 0.120396 0.3048)
			(stroke
				(width 0.1)
				(type default)
			)
			(layer "F.Fab")
		)
		(fp_line
			(start 0.67945 -0.3048)
			(end 0.67945 0.3048)
			(stroke
				(width 0.1)
				(type default)
			)
			(layer "F.Fab")
		)
		(fp_line
			(start 0.12065 -0.2794)
			(end 0.12065 -0.3048)
			(stroke
				(width 0.1)
				(type default)
			)
			(layer "F.Fab")
		)
		(fp_line
			(start 0.12065 -0.3048)
			(end 0.67945 -0.3048)
			(stroke
				(width 0.1)
				(type default)
			)
			(layer "F.Fab")
		)
		(fp_line
			(start 0.120396 0.3048)
			(end 0.120396 0.2794)
			(stroke
				(width 0.1)
				(type default)
			)
			(layer "F.Fab")
		)
		(fp_line
			(start 0.120396 0.2794)
			(end -0.12065 0.2794)
			(stroke
				(width 0.1)
				(type default)
			)
			(layer "F.Fab")
		)
		(fp_line
			(start -0.12065 0.3048)
			(end -0.67945 0.3048)
			(stroke
				(width 0.1)
				(type default)
			)
			(layer "F.Fab")
		)
		(fp_line
			(start -0.12065 0.2794)
			(end -0.12065 0.3048)
			(stroke
				(width 0.1)
				(type default)
			)
			(layer "F.Fab")
		)
		(fp_line
			(start -0.12065 -0.2794)
			(end 0.12065 -0.2794)
			(stroke
				(width 0.1)
				(type default)
			)
			(layer "F.Fab")
		)
		(fp_line
			(start -0.12065 -0.305054)
			(end -0.12065 -0.2794)
			(stroke
				(width 0.1)
				(type default)
			)
			(layer "F.Fab")
		)
		(fp_line
			(start -0.67945 0.3048)
			(end -0.67945 -0.305054)
			(stroke
				(width 0.1)
				(type default)
			)
			(layer "F.Fab")
		)
		(fp_line
			(start -0.67945 -0.305054)
			(end -0.12065 -0.305054)
			(stroke
				(width 0.1)
				(type default)
			)
			(layer "F.Fab")
		)
		(pad "1" smd circle
			(at -0.40005 0 180)
			(size 0 0)
			(layers "F.Cu" "F.Mask" "F.Paste")
			(net "CLK_100M_PEX3_REF_R_DP")
		)
		(pad "2" smd circle
			(at 0.40005 0 180)
			(size 0 0)
			(layers "F.Cu" "F.Mask" "F.Paste")
			(net "CLK_100M_PEX3_REF_DP")
		)
	)
	(footprint ""
		(layer "F.Cu")
		(at 230.153718 -273.063716 90)
		(property "Reference" "C4294"
			(at 0 0 90)
			(layer "F.SilkS")
			(hide yes)
			(effects
				(font
					(size 1.27 1.27)
				)
			)
		)
		(property "Value" ""
			(at 0 0 90)
			(layer "F.Fab")
			(effects
				(font
					(size 1.27 1.27)
				)
			)
		)
		(duplicate_pad_numbers_are_jumpers no)
		(fp_line
			(start 0.299974 -0.150114)
			(end 0.299974 0.150114)
			(stroke
				(width 0.1)
				(type default)
			)
			(layer "F.Fab")
		)
		(fp_line
			(start -0.299974 -0.150114)
			(end 0.299974 -0.150114)
			(stroke
				(width 0.1)
				(type default)
			)
			(layer "F.Fab")
		)
		(fp_line
			(start 0.299974 0.150114)
			(end -0.299974 0.150114)
			(stroke
				(width 0.1)
				(type default)
			)
			(layer "F.Fab")
		)
		(fp_line
			(start -0.299974 0.150114)
			(end -0.299974 -0.150114)
			(stroke
				(width 0.1)
				(type default)
			)
			(layer "F.Fab")
		)
		(pad "1" smd rect
			(at -0.2667 0 90)
			(size 0.3048 0.381)
			(layers "F.Cu" "F.Mask" "F.Paste")
			(net "P1V25_SERDES_VDDPLL_PEX1")
		)
		(pad "2" smd rect
			(at 0.2667 0 90)
			(size 0.3048 0.381)
			(layers "F.Cu" "F.Mask" "F.Paste")
			(net "GND")
		)
	)
	(footprint ""
		(layer "F.Cu")
		(at 80.019398 -146.190208 180)
		(property "Reference" "C12"
			(at 0 0 180)
			(layer "F.SilkS")
			(hide yes)
			(effects
				(font
					(size 1.27 1.27)
				)
			)
		)
		(property "Value" ""
			(at 0 0 180)
			(layer "F.Fab")
			(effects
				(font
					(size 1.27 1.27)
				)
			)
		)
		(duplicate_pad_numbers_are_jumpers no)
		(fp_line
			(start 0.299974 0.150114)
			(end -0.299974 0.150114)
			(stroke
				(width 0.1)
				(type default)
			)
			(layer "F.Fab")
		)
		(fp_line
			(start 0.299974 -0.150114)
			(end 0.299974 0.150114)
			(stroke
				(width 0.1)
				(type default)
			)
			(layer "F.Fab")
		)
		(fp_line
			(start -0.299974 0.150114)
			(end -0.299974 -0.150114)
			(stroke
				(width 0.1)
				(type default)
			)
			(layer "F.Fab")
		)
		(fp_line
			(start -0.299974 -0.150114)
			(end 0.299974 -0.150114)
			(stroke
				(width 0.1)
				(type default)
			)
			(layer "F.Fab")
		)
		(pad "1" smd rect
			(at -0.2667 0 180)
			(size 0.3048 0.381)
			(layers "F.Cu" "F.Mask" "F.Paste")
			(net "P5E_PEX0_STN0_TX_DN<10>")
		)
		(pad "2" smd rect
			(at 0.2667 0 180)
			(size 0.3048 0.381)
			(layers "F.Cu" "F.Mask" "F.Paste")
			(net "P5E_PEX0_STN0_TX_C_DN<10>")
		)
	)
	(footprint ""
		(layer "F.Cu")
		(at 137.047478 -21.37156)
		(property "Reference" "C3901"
			(at 0 0 0)
			(layer "F.SilkS")
			(hide yes)
			(effects
				(font
					(size 1.27 1.27)
				)
			)
		)
		(property "Value" ""
			(at 0 0 0)
			(layer "F.Fab")
			(effects
				(font
					(size 1.27 1.27)
				)
			)
		)
		(duplicate_pad_numbers_are_jumpers no)
		(fp_line
			(start -0.7874 -0.4064)
			(end 0.7874 -0.4064)
			(stroke
				(width 0.1524)
				(type default)
			)
			(layer "F.SilkS")
		)
		(fp_line
			(start -0.7874 0.4064)
			(end -0.7874 -0.4064)
			(stroke
				(width 0.1524)
				(type default)
			)
			(layer "F.SilkS")
		)
		(fp_line
			(start 0.7874 -0.4064)
			(end 0.7874 0.4064)
			(stroke
				(width 0.1524)
				(type default)
			)
			(layer "F.SilkS")
		)
		(fp_line
			(start 0.7874 0.4064)
			(end -0.7874 0.4064)
			(stroke
				(width 0.1524)
				(type default)
			)
			(layer "F.SilkS")
		)
		(fp_line
			(start -0.67945 -0.305054)
			(end -0.12065 -0.305054)
			(stroke
				(width 0.1)
				(type default)
			)
			(layer "F.Fab")
		)
		(fp_line
			(start -0.67945 0.3048)
			(end -0.67945 -0.305054)
			(stroke
				(width 0.1)
				(type default)
			)
			(layer "F.Fab")
		)
		(fp_line
			(start -0.12065 -0.305054)
			(end -0.12065 -0.2794)
			(stroke
				(width 0.1)
				(type default)
			)
			(layer "F.Fab")
		)
		(fp_line
			(start -0.12065 -0.2794)
			(end 0.12065 -0.2794)
			(stroke
				(width 0.1)
				(type default)
			)
			(layer "F.Fab")
		)
		(fp_line
			(start -0.12065 0.2794)
			(end -0.12065 0.3048)
			(stroke
				(width 0.1)
				(type default)
			)
			(layer "F.Fab")
		)
		(fp_line
			(start -0.12065 0.3048)
			(end -0.67945 0.3048)
			(stroke
				(width 0.1)
				(type default)
			)
			(layer "F.Fab")
		)
		(fp_line
			(start 0.120396 0.2794)
			(end -0.12065 0.2794)
			(stroke
				(width 0.1)
				(type default)
			)
			(layer "F.Fab")
		)
		(fp_line
			(start 0.120396 0.3048)
			(end 0.120396 0.2794)
			(stroke
				(width 0.1)
				(type default)
			)
			(layer "F.Fab")
		)
		(fp_line
			(start 0.12065 -0.3048)
			(end 0.67945 -0.3048)
			(stroke
				(width 0.1)
				(type default)
			)
			(layer "F.Fab")
		)
		(fp_line
			(start 0.12065 -0.2794)
			(end 0.12065 -0.3048)
			(stroke
				(width 0.1)
				(type default)
			)
			(layer "F.Fab")
		)
		(fp_line
			(start 0.67945 -0.3048)
			(end 0.67945 0.3048)
			(stroke
				(width 0.1)
				(type default)
			)
			(layer "F.Fab")
		)
		(fp_line
			(start 0.67945 0.3048)
			(end 0.120396 0.3048)
			(stroke
				(width 0.1)
				(type default)
			)
			(layer "F.Fab")
		)
		(pad "1" smd circle
			(at -0.40005 0)
			(size 0 0)
			(layers "F.Cu" "F.Mask" "F.Paste")
			(net "P12V_SSD4")
		)
		(pad "2" smd circle
			(at 0.40005 0)
			(size 0 0)
			(layers "F.Cu" "F.Mask" "F.Paste")
			(net "GND")
		)
	)
	(footprint ""
		(layer "F.Cu")
		(at 317.830708 -304.90795 90)
		(property "Reference" "R6720"
			(at 0 0 90)
			(layer "F.SilkS")
			(hide yes)
			(effects
				(font
					(size 1.27 1.27)
				)
			)
		)
		(property "Value" ""
			(at 0 0 90)
			(layer "F.Fab")
			(effects
				(font
					(size 1.27 1.27)
				)
			)
		)
		(duplicate_pad_numbers_are_jumpers no)
		(fp_line
			(start 0.7874 -0.4064)
			(end 0.7874 0.4064)
			(stroke
				(width 0.1524)
				(type default)
			)
			(layer "F.SilkS")
		)
		(fp_line
			(start -0.7874 -0.4064)
			(end 0.7874 -0.4064)
			(stroke
				(width 0.1524)
				(type default)
			)
			(layer "F.SilkS")
		)
		(fp_line
			(start 0.7874 0.4064)
			(end -0.7874 0.4064)
			(stroke
				(width 0.1524)
				(type default)
			)
			(layer "F.SilkS")
		)
		(fp_line
			(start -0.7874 0.4064)
			(end -0.7874 -0.4064)
			(stroke
				(width 0.1524)
				(type default)
			)
			(layer "F.SilkS")
		)
		(fp_line
			(start -0.12065 -0.305054)
			(end -0.12065 -0.2794)
			(stroke
				(width 0.1)
				(type default)
			)
			(layer "F.Fab")
		)
		(fp_line
			(start -0.67945 -0.305054)
			(end -0.12065 -0.305054)
			(stroke
				(width 0.1)
				(type default)
			)
			(layer "F.Fab")
		)
		(fp_line
			(start 0.67945 -0.3048)
			(end 0.67945 0.3048)
			(stroke
				(width 0.1)
				(type default)
			)
			(layer "F.Fab")
		)
		(fp_line
			(start 0.12065 -0.3048)
			(end 0.67945 -0.3048)
			(stroke
				(width 0.1)
				(type default)
			)
			(layer "F.Fab")
		)
		(fp_line
			(start 0.12065 -0.2794)
			(end 0.12065 -0.3048)
			(stroke
				(width 0.1)
				(type default)
			)
			(layer "F.Fab")
		)
		(fp_line
			(start -0.12065 -0.2794)
			(end 0.12065 -0.2794)
			(stroke
				(width 0.1)
				(type default)
			)
			(layer "F.Fab")
		)
		(fp_line
			(start 0.120396 0.2794)
			(end -0.12065 0.2794)
			(stroke
				(width 0.1)
				(type default)
			)
			(layer "F.Fab")
		)
		(fp_line
			(start -0.12065 0.2794)
			(end -0.12065 0.3048)
			(stroke
				(width 0.1)
				(type default)
			)
			(layer "F.Fab")
		)
		(fp_line
			(start 0.67945 0.3048)
			(end 0.120396 0.3048)
			(stroke
				(width 0.1)
				(type default)
			)
			(layer "F.Fab")
		)
		(fp_line
			(start 0.120396 0.3048)
			(end 0.120396 0.2794)
			(stroke
				(width 0.1)
				(type default)
			)
			(layer "F.Fab")
		)
		(fp_line
			(start -0.12065 0.3048)
			(end -0.67945 0.3048)
			(stroke
				(width 0.1)
				(type default)
			)
			(layer "F.Fab")
		)
		(fp_line
			(start -0.67945 0.3048)
			(end -0.67945 -0.305054)
			(stroke
				(width 0.1)
				(type default)
			)
			(layer "F.Fab")
		)
		(pad "1" smd circle
			(at -0.40005 0 90)
			(size 0 0)
			(layers "F.Cu" "F.Mask" "F.Paste")
			(net "SMB_PEX2_SLAVE1_SCL")
		)
		(pad "2" smd circle
			(at 0.40005 0 90)
			(size 0 0)
			(layers "F.Cu" "F.Mask" "F.Paste")
			(net "SMB_PEX2_R_SCL")
		)
	)
	(footprint ""
		(layer "F.Cu")
		(at 275.26869 -407.720292 90)
		(property "Reference" "R1813"
			(at 0 0 90)
			(layer "F.SilkS")
			(hide yes)
			(effects
				(font
					(size 1.27 1.27)
				)
			)
		)
		(property "Value" ""
			(at 0 0 90)
			(layer "F.Fab")
			(effects
				(font
					(size 1.27 1.27)
				)
			)
		)
		(duplicate_pad_numbers_are_jumpers no)
		(fp_line
			(start 0.7874 -0.4064)
			(end 0.7874 0.4064)
			(stroke
				(width 0.1524)
				(type default)
			)
			(layer "F.SilkS")
		)
		(fp_line
			(start -0.7874 -0.4064)
			(end 0.7874 -0.4064)
			(stroke
				(width 0.1524)
				(type default)
			)
			(layer "F.SilkS")
		)
		(fp_line
			(start 0.7874 0.4064)
			(end -0.7874 0.4064)
			(stroke
				(width 0.1524)
				(type default)
			)
			(layer "F.SilkS")
		)
		(fp_line
			(start -0.7874 0.4064)
			(end -0.7874 -0.4064)
			(stroke
				(width 0.1524)
				(type default)
			)
			(layer "F.SilkS")
		)
		(fp_line
			(start -0.12065 -0.305054)
			(end -0.12065 -0.2794)
			(stroke
				(width 0.1)
				(type default)
			)
			(layer "F.Fab")
		)
		(fp_line
			(start -0.67945 -0.305054)
			(end -0.12065 -0.305054)
			(stroke
				(width 0.1)
				(type default)
			)
			(layer "F.Fab")
		)
		(fp_line
			(start 0.67945 -0.3048)
			(end 0.67945 0.3048)
			(stroke
				(width 0.1)
				(type default)
			)
			(layer "F.Fab")
		)
		(fp_line
			(start 0.12065 -0.3048)
			(end 0.67945 -0.3048)
			(stroke
				(width 0.1)
				(type default)
			)
			(layer "F.Fab")
		)
		(fp_line
			(start 0.12065 -0.2794)
			(end 0.12065 -0.3048)
			(stroke
				(width 0.1)
				(type default)
			)
			(layer "F.Fab")
		)
		(fp_line
			(start -0.12065 -0.2794)
			(end 0.12065 -0.2794)
			(stroke
				(width 0.1)
				(type default)
			)
			(layer "F.Fab")
		)
		(fp_line
			(start 0.120396 0.2794)
			(end -0.12065 0.2794)
			(stroke
				(width 0.1)
				(type default)
			)
			(layer "F.Fab")
		)
		(fp_line
			(start -0.12065 0.2794)
			(end -0.12065 0.3048)
			(stroke
				(width 0.1)
				(type default)
			)
			(layer "F.Fab")
		)
		(fp_line
			(start 0.67945 0.3048)
			(end 0.120396 0.3048)
			(stroke
				(width 0.1)
				(type default)
			)
			(layer "F.Fab")
		)
		(fp_line
			(start 0.120396 0.3048)
			(end 0.120396 0.2794)
			(stroke
				(width 0.1)
				(type default)
			)
			(layer "F.Fab")
		)
		(fp_line
			(start -0.12065 0.3048)
			(end -0.67945 0.3048)
			(stroke
				(width 0.1)
				(type default)
			)
			(layer "F.Fab")
		)
		(fp_line
			(start -0.67945 0.3048)
			(end -0.67945 -0.305054)
			(stroke
				(width 0.1)
				(type default)
			)
			(layer "F.Fab")
		)
		(pad "1" smd circle
			(at -0.40005 0 90)
			(size 0 0)
			(layers "F.Cu" "F.Mask" "F.Paste")
			(net "P3V3_AUX")
		)
		(pad "2" smd circle
			(at 0.40005 0 90)
			(size 0 0)
			(layers "F.Cu" "F.Mask" "F.Paste")
			(net "RST_MB_BMC_BUF_N")
		)
	)
	(footprint ""
		(layer "F.Cu")
		(at 140.731748 -356.244906 90)
		(property "Reference" "C2262"
			(at 0 0 90)
			(layer "F.SilkS")
			(hide yes)
			(effects
				(font
					(size 1.27 1.27)
				)
			)
		)
		(property "Value" ""
			(at 0 0 90)
			(layer "F.Fab")
			(effects
				(font
					(size 1.27 1.27)
				)
			)
		)
		(duplicate_pad_numbers_are_jumpers no)
		(fp_line
			(start 0.299974 -0.150114)
			(end 0.299974 0.150114)
			(stroke
				(width 0.1)
				(type default)
			)
			(layer "F.Fab")
		)
		(fp_line
			(start -0.299974 -0.150114)
			(end 0.299974 -0.150114)
			(stroke
				(width 0.1)
				(type default)
			)
			(layer "F.Fab")
		)
		(fp_line
			(start 0.299974 0.150114)
			(end -0.299974 0.150114)
			(stroke
				(width 0.1)
				(type default)
			)
			(layer "F.Fab")
		)
		(fp_line
			(start -0.299974 0.150114)
			(end -0.299974 -0.150114)
			(stroke
				(width 0.1)
				(type default)
			)
			(layer "F.Fab")
		)
		(pad "1" smd rect
			(at -0.2667 0 90)
			(size 0.3048 0.381)
			(layers "F.Cu" "F.Mask" "F.Paste")
			(net "P5E_PEX1_STN5_TX_DN<86>")
		)
		(pad "2" smd rect
			(at 0.2667 0 90)
			(size 0.3048 0.381)
			(layers "F.Cu" "F.Mask" "F.Paste")
			(net "P5E_PEX1_STN5_TX_C_DN<86>")
		)
	)
	(footprint ""
		(layer "F.Cu")
		(at 242.587018 -275.602192 135)
		(property "Reference" "C633"
			(at 0 0 135)
			(layer "F.SilkS")
			(hide yes)
			(effects
				(font
					(size 1.27 1.27)
				)
			)
		)
		(property "Value" ""
			(at 0 0 135)
			(layer "F.Fab")
			(effects
				(font
					(size 1.27 1.27)
				)
			)
		)
		(duplicate_pad_numbers_are_jumpers no)
		(fp_line
			(start 0.787389 -0.406267)
			(end 0.787389 0.406267)
			(stroke
				(width 0.1524)
				(type default)
			)
			(layer "F.SilkS")
		)
		(fp_line
			(start 0.787389 0.406267)
			(end -0.787389 0.406267)
			(stroke
				(width 0.1524)
				(type default)
			)
			(layer "F.SilkS")
		)
		(fp_line
			(start -0.787389 -0.406267)
			(end 0.787389 -0.406267)
			(stroke
				(width 0.1524)
				(type default)
			)
			(layer "F.SilkS")
		)
		(fp_line
			(start -0.787389 0.406267)
			(end -0.787389 -0.406267)
			(stroke
				(width 0.1524)
				(type default)
			)
			(layer "F.SilkS")
		)
		(fp_line
			(start 0.679446 -0.30479)
			(end 0.679446 0.30479)
			(stroke
				(width 0.1)
				(type default)
			)
			(layer "F.Fab")
		)
		(fp_line
			(start 0.120515 -0.30479)
			(end 0.679446 -0.30479)
			(stroke
				(width 0.1)
				(type default)
			)
			(layer "F.Fab")
		)
		(fp_line
			(start 0.120695 -0.279466)
			(end 0.120515 -0.30479)
			(stroke
				(width 0.1)
				(type default)
			)
			(layer "F.Fab")
		)
		(fp_line
			(start 0.679446 0.30479)
			(end 0.120515 0.30479)
			(stroke
				(width 0.1)
				(type default)
			)
			(layer "F.Fab")
		)
		(fp_line
			(start -0.120695 -0.304969)
			(end -0.120695 -0.279466)
			(stroke
				(width 0.1)
				(type default)
			)
			(layer "F.Fab")
		)
		(fp_line
			(start -0.120695 -0.279466)
			(end 0.120695 -0.279466)
			(stroke
				(width 0.1)
				(type default)
			)
			(layer "F.Fab")
		)
		(fp_line
			(start 0.120335 0.279466)
			(end -0.120695 0.279466)
			(stroke
				(width 0.1)
				(type default)
			)
			(layer "F.Fab")
		)
		(fp_line
			(start 0.120515 0.30479)
			(end 0.120335 0.279466)
			(stroke
				(width 0.1)
				(type default)
			)
			(layer "F.Fab")
		)
		(fp_line
			(start -0.679446 -0.305149)
			(end -0.120695 -0.304969)
			(stroke
				(width 0.1)
				(type default)
			)
			(layer "F.Fab")
		)
		(fp_line
			(start -0.120695 0.279466)
			(end -0.120515 0.30479)
			(stroke
				(width 0.1)
				(type default)
			)
			(layer "F.Fab")
		)
		(fp_line
			(start -0.120515 0.30479)
			(end -0.679446 0.30479)
			(stroke
				(width 0.1)
				(type default)
			)
			(layer "F.Fab")
		)
		(fp_line
			(start -0.679446 0.30479)
			(end -0.679446 -0.305149)
			(stroke
				(width 0.1)
				(type default)
			)
			(layer "F.Fab")
		)
		(pad "1" smd circle
			(at -0.40005 0 135)
			(size 0 0)
			(layers "F.Cu" "F.Mask" "F.Paste")
			(net "P12V_PEX2_P1V25_VIN_P")
		)
		(pad "2" smd circle
			(at 0.40005 0 135)
			(size 0 0)
			(layers "F.Cu" "F.Mask" "F.Paste")
			(net "P12V_PEX2_P1V25_VIN_N")
		)
	)
	(footprint ""
		(layer "F.Cu")
		(at 343.902792 -240.691162 90)
		(property "Reference" "R3598"
			(at 0 0 90)
			(layer "F.SilkS")
			(hide yes)
			(effects
				(font
					(size 1.27 1.27)
				)
			)
		)
		(property "Value" ""
			(at 0 0 90)
			(layer "F.Fab")
			(effects
				(font
					(size 1.27 1.27)
				)
			)
		)
		(duplicate_pad_numbers_are_jumpers no)
		(fp_line
			(start 0.7874 -0.4064)
			(end 0.7874 0.4064)
			(stroke
				(width 0.1524)
				(type default)
			)
			(layer "F.SilkS")
		)
		(fp_line
			(start -0.7874 -0.4064)
			(end 0.7874 -0.4064)
			(stroke
				(width 0.1524)
				(type default)
			)
			(layer "F.SilkS")
		)
		(fp_line
			(start 0.7874 0.4064)
			(end -0.7874 0.4064)
			(stroke
				(width 0.1524)
				(type default)
			)
			(layer "F.SilkS")
		)
		(fp_line
			(start -0.7874 0.4064)
			(end -0.7874 -0.4064)
			(stroke
				(width 0.1524)
				(type default)
			)
			(layer "F.SilkS")
		)
		(fp_line
			(start -0.12065 -0.305054)
			(end -0.12065 -0.2794)
			(stroke
				(width 0.1)
				(type default)
			)
			(layer "F.Fab")
		)
		(fp_line
			(start -0.67945 -0.305054)
			(end -0.12065 -0.305054)
			(stroke
				(width 0.1)
				(type default)
			)
			(layer "F.Fab")
		)
		(fp_line
			(start 0.67945 -0.3048)
			(end 0.67945 0.3048)
			(stroke
				(width 0.1)
				(type default)
			)
			(layer "F.Fab")
		)
		(fp_line
			(start 0.12065 -0.3048)
			(end 0.67945 -0.3048)
			(stroke
				(width 0.1)
				(type default)
			)
			(layer "F.Fab")
		)
		(fp_line
			(start 0.12065 -0.2794)
			(end 0.12065 -0.3048)
			(stroke
				(width 0.1)
				(type default)
			)
			(layer "F.Fab")
		)
		(fp_line
			(start -0.12065 -0.2794)
			(end 0.12065 -0.2794)
			(stroke
				(width 0.1)
				(type default)
			)
			(layer "F.Fab")
		)
		(fp_line
			(start 0.120396 0.2794)
			(end -0.12065 0.2794)
			(stroke
				(width 0.1)
				(type default)
			)
			(layer "F.Fab")
		)
		(fp_line
			(start -0.12065 0.2794)
			(end -0.12065 0.3048)
			(stroke
				(width 0.1)
				(type default)
			)
			(layer "F.Fab")
		)
		(fp_line
			(start 0.67945 0.3048)
			(end 0.120396 0.3048)
			(stroke
				(width 0.1)
				(type default)
			)
			(layer "F.Fab")
		)
		(fp_line
			(start 0.120396 0.3048)
			(end 0.120396 0.2794)
			(stroke
				(width 0.1)
				(type default)
			)
			(layer "F.Fab")
		)
		(fp_line
			(start -0.12065 0.3048)
			(end -0.67945 0.3048)
			(stroke
				(width 0.1)
				(type default)
			)
			(layer "F.Fab")
		)
		(fp_line
			(start -0.67945 0.3048)
			(end -0.67945 -0.305054)
			(stroke
				(width 0.1)
				(type default)
			)
			(layer "F.Fab")
		)
		(pad "1" smd circle
			(at -0.40005 0 90)
			(size 0 0)
			(layers "F.Cu" "F.Mask" "F.Paste")
			(net "RST_SSD1_PERST_N")
		)
		(pad "2" smd circle
			(at 0.40005 0 90)
			(size 0 0)
			(layers "F.Cu" "F.Mask" "F.Paste")
			(net "RST_SSD1_PERST_R_N")
		)
	)
	(footprint ""
		(layer "F.Cu")
		(at 137.047478 -19.33956)
		(property "Reference" "C3905"
			(at 0 0 0)
			(layer "F.SilkS")
			(hide yes)
			(effects
				(font
					(size 1.27 1.27)
				)
			)
		)
		(property "Value" ""
			(at 0 0 0)
			(layer "F.Fab")
			(effects
				(font
					(size 1.27 1.27)
				)
			)
		)
		(duplicate_pad_numbers_are_jumpers no)
		(fp_line
			(start -0.7874 -0.4064)
			(end 0.7874 -0.4064)
			(stroke
				(width 0.1524)
				(type default)
			)
			(layer "F.SilkS")
		)
		(fp_line
			(start -0.7874 0.4064)
			(end -0.7874 -0.4064)
			(stroke
				(width 0.1524)
				(type default)
			)
			(layer "F.SilkS")
		)
		(fp_line
			(start 0.7874 -0.4064)
			(end 0.7874 0.4064)
			(stroke
				(width 0.1524)
				(type default)
			)
			(layer "F.SilkS")
		)
		(fp_line
			(start 0.7874 0.4064)
			(end -0.7874 0.4064)
			(stroke
				(width 0.1524)
				(type default)
			)
			(layer "F.SilkS")
		)
		(fp_line
			(start -0.67945 -0.305054)
			(end -0.12065 -0.305054)
			(stroke
				(width 0.1)
				(type default)
			)
			(layer "F.Fab")
		)
		(fp_line
			(start -0.67945 0.3048)
			(end -0.67945 -0.305054)
			(stroke
				(width 0.1)
				(type default)
			)
			(layer "F.Fab")
		)
		(fp_line
			(start -0.12065 -0.305054)
			(end -0.12065 -0.2794)
			(stroke
				(width 0.1)
				(type default)
			)
			(layer "F.Fab")
		)
		(fp_line
			(start -0.12065 -0.2794)
			(end 0.12065 -0.2794)
			(stroke
				(width 0.1)
				(type default)
			)
			(layer "F.Fab")
		)
		(fp_line
			(start -0.12065 0.2794)
			(end -0.12065 0.3048)
			(stroke
				(width 0.1)
				(type default)
			)
			(layer "F.Fab")
		)
		(fp_line
			(start -0.12065 0.3048)
			(end -0.67945 0.3048)
			(stroke
				(width 0.1)
				(type default)
			)
			(layer "F.Fab")
		)
		(fp_line
			(start 0.120396 0.2794)
			(end -0.12065 0.2794)
			(stroke
				(width 0.1)
				(type default)
			)
			(layer "F.Fab")
		)
		(fp_line
			(start 0.120396 0.3048)
			(end 0.120396 0.2794)
			(stroke
				(width 0.1)
				(type default)
			)
			(layer "F.Fab")
		)
		(fp_line
			(start 0.12065 -0.3048)
			(end 0.67945 -0.3048)
			(stroke
				(width 0.1)
				(type default)
			)
			(layer "F.Fab")
		)
		(fp_line
			(start 0.12065 -0.2794)
			(end 0.12065 -0.3048)
			(stroke
				(width 0.1)
				(type default)
			)
			(layer "F.Fab")
		)
		(fp_line
			(start 0.67945 -0.3048)
			(end 0.67945 0.3048)
			(stroke
				(width 0.1)
				(type default)
			)
			(layer "F.Fab")
		)
		(fp_line
			(start 0.67945 0.3048)
			(end 0.120396 0.3048)
			(stroke
				(width 0.1)
				(type default)
			)
			(layer "F.Fab")
		)
		(pad "1" smd circle
			(at -0.40005 0)
			(size 0 0)
			(layers "F.Cu" "F.Mask" "F.Paste")
			(net "P12V_SSD4")
		)
		(pad "2" smd circle
			(at 0.40005 0)
			(size 0 0)
			(layers "F.Cu" "F.Mask" "F.Paste")
			(net "GND")
		)
	)
	(footprint ""
		(layer "F.Cu")
		(at 215.985598 -27.092148 -90)
		(property "Reference" "R5745"
			(at 0 0 270)
			(layer "F.SilkS")
			(hide yes)
			(effects
				(font
					(size 1.27 1.27)
				)
			)
		)
		(property "Value" ""
			(at 0 0 270)
			(layer "F.Fab")
			(effects
				(font
					(size 1.27 1.27)
				)
			)
		)
		(duplicate_pad_numbers_are_jumpers no)
		(fp_line
			(start -0.7874 0.4064)
			(end -0.7874 -0.4064)
			(stroke
				(width 0.1524)
				(type default)
			)
			(layer "F.SilkS")
		)
		(fp_line
			(start 0.7874 0.4064)
			(end -0.7874 0.4064)
			(stroke
				(width 0.1524)
				(type default)
			)
			(layer "F.SilkS")
		)
		(fp_line
			(start -0.7874 -0.4064)
			(end 0.7874 -0.4064)
			(stroke
				(width 0.1524)
				(type default)
			)
			(layer "F.SilkS")
		)
		(fp_line
			(start 0.7874 -0.4064)
			(end 0.7874 0.4064)
			(stroke
				(width 0.1524)
				(type default)
			)
			(layer "F.SilkS")
		)
		(fp_line
			(start -0.67945 0.3048)
			(end -0.67945 -0.305054)
			(stroke
				(width 0.1)
				(type default)
			)
			(layer "F.Fab")
		)
		(fp_line
			(start -0.12065 0.3048)
			(end -0.67945 0.3048)
			(stroke
				(width 0.1)
				(type default)
			)
			(layer "F.Fab")
		)
		(fp_line
			(start 0.120396 0.3048)
			(end 0.120396 0.2794)
			(stroke
				(width 0.1)
				(type default)
			)
			(layer "F.Fab")
		)
		(fp_line
			(start 0.67945 0.3048)
			(end 0.120396 0.3048)
			(stroke
				(width 0.1)
				(type default)
			)
			(layer "F.Fab")
		)
		(fp_line
			(start -0.12065 0.2794)
			(end -0.12065 0.3048)
			(stroke
				(width 0.1)
				(type default)
			)
			(layer "F.Fab")
		)
		(fp_line
			(start 0.120396 0.2794)
			(end -0.12065 0.2794)
			(stroke
				(width 0.1)
				(type default)
			)
			(layer "F.Fab")
		)
		(fp_line
			(start -0.12065 -0.2794)
			(end 0.12065 -0.2794)
			(stroke
				(width 0.1)
				(type default)
			)
			(layer "F.Fab")
		)
		(fp_line
			(start 0.12065 -0.2794)
			(end 0.12065 -0.3048)
			(stroke
				(width 0.1)
				(type default)
			)
			(layer "F.Fab")
		)
		(fp_line
			(start 0.12065 -0.3048)
			(end 0.67945 -0.3048)
			(stroke
				(width 0.1)
				(type default)
			)
			(layer "F.Fab")
		)
		(fp_line
			(start 0.67945 -0.3048)
			(end 0.67945 0.3048)
			(stroke
				(width 0.1)
				(type default)
			)
			(layer "F.Fab")
		)
		(fp_line
			(start -0.67945 -0.305054)
			(end -0.12065 -0.305054)
			(stroke
				(width 0.1)
				(type default)
			)
			(layer "F.Fab")
		)
		(fp_line
			(start -0.12065 -0.305054)
			(end -0.12065 -0.2794)
			(stroke
				(width 0.1)
				(type default)
			)
			(layer "F.Fab")
		)
		(pad "1" smd circle
			(at -0.40005 0 270)
			(size 0 0)
			(layers "F.Cu" "F.Mask" "F.Paste")
			(net "P3V3_SSD7")
		)
		(pad "2" smd circle
			(at 0.40005 0 270)
			(size 0 0)
			(layers "F.Cu" "F.Mask" "F.Paste")
			(net "SSD7_LED_ISO_N")
		)
	)
	(footprint ""
		(layer "F.Cu")
		(at 55.8292 -116.5352 180)
		(property "Reference" "R40"
			(at 0 0 180)
			(layer "F.SilkS")
			(hide yes)
			(effects
				(font
					(size 1.27 1.27)
				)
			)
		)
		(property "Value" ""
			(at 0 0 180)
			(layer "F.Fab")
			(effects
				(font
					(size 1.27 1.27)
				)
			)
		)
		(duplicate_pad_numbers_are_jumpers no)
		(fp_line
			(start 0.7874 0.4064)
			(end -0.7874 0.4064)
			(stroke
				(width 0.1524)
				(type default)
			)
			(layer "F.SilkS")
		)
		(fp_line
			(start 0.7874 -0.4064)
			(end 0.7874 0.4064)
			(stroke
				(width 0.1524)
				(type default)
			)
			(layer "F.SilkS")
		)
		(fp_line
			(start -0.7874 0.4064)
			(end -0.7874 -0.4064)
			(stroke
				(width 0.1524)
				(type default)
			)
			(layer "F.SilkS")
		)
		(fp_line
			(start -0.7874 -0.4064)
			(end 0.7874 -0.4064)
			(stroke
				(width 0.1524)
				(type default)
			)
			(layer "F.SilkS")
		)
		(fp_line
			(start 0.67945 0.3048)
			(end 0.120396 0.3048)
			(stroke
				(width 0.1)
				(type default)
			)
			(layer "F.Fab")
		)
		(fp_line
			(start 0.67945 -0.3048)
			(end 0.67945 0.3048)
			(stroke
				(width 0.1)
				(type default)
			)
			(layer "F.Fab")
		)
		(fp_line
			(start 0.12065 -0.2794)
			(end 0.12065 -0.3048)
			(stroke
				(width 0.1)
				(type default)
			)
			(layer "F.Fab")
		)
		(fp_line
			(start 0.12065 -0.3048)
			(end 0.67945 -0.3048)
			(stroke
				(width 0.1)
				(type default)
			)
			(layer "F.Fab")
		)
		(fp_line
			(start 0.120396 0.3048)
			(end 0.120396 0.2794)
			(stroke
				(width 0.1)
				(type default)
			)
			(layer "F.Fab")
		)
		(fp_line
			(start 0.120396 0.2794)
			(end -0.12065 0.2794)
			(stroke
				(width 0.1)
				(type default)
			)
			(layer "F.Fab")
		)
		(fp_line
			(start -0.12065 0.3048)
			(end -0.67945 0.3048)
			(stroke
				(width 0.1)
				(type default)
			)
			(layer "F.Fab")
		)
		(fp_line
			(start -0.12065 0.2794)
			(end -0.12065 0.3048)
			(stroke
				(width 0.1)
				(type default)
			)
			(layer "F.Fab")
		)
		(fp_line
			(start -0.12065 -0.2794)
			(end 0.12065 -0.2794)
			(stroke
				(width 0.1)
				(type default)
			)
			(layer "F.Fab")
		)
		(fp_line
			(start -0.12065 -0.305054)
			(end -0.12065 -0.2794)
			(stroke
				(width 0.1)
				(type default)
			)
			(layer "F.Fab")
		)
		(fp_line
			(start -0.67945 0.3048)
			(end -0.67945 -0.305054)
			(stroke
				(width 0.1)
				(type default)
			)
			(layer "F.Fab")
		)
		(fp_line
			(start -0.67945 -0.305054)
			(end -0.12065 -0.305054)
			(stroke
				(width 0.1)
				(type default)
			)
			(layer "F.Fab")
		)
		(pad "1" smd circle
			(at -0.40005 0 180)
			(size 0 0)
			(layers "F.Cu" "F.Mask" "F.Paste")
			(net "PRSNT_NIC0_N")
		)
		(pad "2" smd circle
			(at 0.40005 0 180)
			(size 0 0)
			(layers "F.Cu" "F.Mask" "F.Paste")
			(net "PRSNTB1_NIC0_N")
		)
	)
	(footprint ""
		(layer "F.Cu")
		(at 341.746586 -282.421584 -90)
		(property "Reference" "PC145"
			(at 0 0 270)
			(layer "F.SilkS")
			(hide yes)
			(effects
				(font
					(size 1.27 1.27)
				)
			)
		)
		(property "Value" ""
			(at 0 0 270)
			(layer "F.Fab")
			(effects
				(font
					(size 1.27 1.27)
				)
			)
		)
		(duplicate_pad_numbers_are_jumpers no)
		(fp_line
			(start -0.7874 0.4064)
			(end -0.7874 -0.4064)
			(stroke
				(width 0.1524)
				(type default)
			)
			(layer "F.SilkS")
		)
		(fp_line
			(start 0.7874 0.4064)
			(end -0.7874 0.4064)
			(stroke
				(width 0.1524)
				(type default)
			)
			(layer "F.SilkS")
		)
		(fp_line
			(start -0.7874 -0.4064)
			(end 0.7874 -0.4064)
			(stroke
				(width 0.1524)
				(type default)
			)
			(layer "F.SilkS")
		)
		(fp_line
			(start 0.7874 -0.4064)
			(end 0.7874 0.4064)
			(stroke
				(width 0.1524)
				(type default)
			)
			(layer "F.SilkS")
		)
		(fp_line
			(start -0.67945 0.3048)
			(end -0.67945 -0.305054)
			(stroke
				(width 0.1)
				(type default)
			)
			(layer "F.Fab")
		)
		(fp_line
			(start -0.12065 0.3048)
			(end -0.67945 0.3048)
			(stroke
				(width 0.1)
				(type default)
			)
			(layer "F.Fab")
		)
		(fp_line
			(start 0.120396 0.3048)
			(end 0.120396 0.2794)
			(stroke
				(width 0.1)
				(type default)
			)
			(layer "F.Fab")
		)
		(fp_line
			(start 0.67945 0.3048)
			(end 0.120396 0.3048)
			(stroke
				(width 0.1)
				(type default)
			)
			(layer "F.Fab")
		)
		(fp_line
			(start -0.12065 0.2794)
			(end -0.12065 0.3048)
			(stroke
				(width 0.1)
				(type default)
			)
			(layer "F.Fab")
		)
		(fp_line
			(start 0.120396 0.2794)
			(end -0.12065 0.2794)
			(stroke
				(width 0.1)
				(type default)
			)
			(layer "F.Fab")
		)
		(fp_line
			(start -0.12065 -0.2794)
			(end 0.12065 -0.2794)
			(stroke
				(width 0.1)
				(type default)
			)
			(layer "F.Fab")
		)
		(fp_line
			(start 0.12065 -0.2794)
			(end 0.12065 -0.3048)
			(stroke
				(width 0.1)
				(type default)
			)
			(layer "F.Fab")
		)
		(fp_line
			(start 0.12065 -0.3048)
			(end 0.67945 -0.3048)
			(stroke
				(width 0.1)
				(type default)
			)
			(layer "F.Fab")
		)
		(fp_line
			(start 0.67945 -0.3048)
			(end 0.67945 0.3048)
			(stroke
				(width 0.1)
				(type default)
			)
			(layer "F.Fab")
		)
		(fp_line
			(start -0.67945 -0.305054)
			(end -0.12065 -0.305054)
			(stroke
				(width 0.1)
				(type default)
			)
			(layer "F.Fab")
		)
		(fp_line
			(start -0.12065 -0.305054)
			(end -0.12065 -0.2794)
			(stroke
				(width 0.1)
				(type default)
			)
			(layer "F.Fab")
		)
		(pad "1" smd circle
			(at -0.40005 0 270)
			(size 0 0)
			(layers "F.Cu" "F.Mask" "F.Paste")
			(net "P0V8_PEX2_VCC1")
		)
		(pad "2" smd circle
			(at 0.40005 0 270)
			(size 0 0)
			(layers "F.Cu" "F.Mask" "F.Paste")
			(net "GND")
		)
	)
	(footprint ""
		(layer "F.Cu")
		(at 187.598558 -66.32194 -90)
		(property "Reference" "PC853"
			(at 0 0 270)
			(layer "F.SilkS")
			(hide yes)
			(effects
				(font
					(size 1.27 1.27)
				)
			)
		)
		(property "Value" ""
			(at 0 0 270)
			(layer "F.Fab")
			(effects
				(font
					(size 1.27 1.27)
				)
			)
		)
		(duplicate_pad_numbers_are_jumpers no)
		(fp_line
			(start -0.7874 0.4064)
			(end -0.7874 -0.4064)
			(stroke
				(width 0.1524)
				(type default)
			)
			(layer "F.SilkS")
		)
		(fp_line
			(start 0.7874 0.4064)
			(end -0.7874 0.4064)
			(stroke
				(width 0.1524)
				(type default)
			)
			(layer "F.SilkS")
		)
		(fp_line
			(start -0.7874 -0.4064)
			(end 0.7874 -0.4064)
			(stroke
				(width 0.1524)
				(type default)
			)
			(layer "F.SilkS")
		)
		(fp_line
			(start 0.7874 -0.4064)
			(end 0.7874 0.4064)
			(stroke
				(width 0.1524)
				(type default)
			)
			(layer "F.SilkS")
		)
		(fp_line
			(start -0.67945 0.3048)
			(end -0.67945 -0.305054)
			(stroke
				(width 0.1)
				(type default)
			)
			(layer "F.Fab")
		)
		(fp_line
			(start -0.12065 0.3048)
			(end -0.67945 0.3048)
			(stroke
				(width 0.1)
				(type default)
			)
			(layer "F.Fab")
		)
		(fp_line
			(start 0.120396 0.3048)
			(end 0.120396 0.2794)
			(stroke
				(width 0.1)
				(type default)
			)
			(layer "F.Fab")
		)
		(fp_line
			(start 0.67945 0.3048)
			(end 0.120396 0.3048)
			(stroke
				(width 0.1)
				(type default)
			)
			(layer "F.Fab")
		)
		(fp_line
			(start -0.12065 0.2794)
			(end -0.12065 0.3048)
			(stroke
				(width 0.1)
				(type default)
			)
			(layer "F.Fab")
		)
		(fp_line
			(start 0.120396 0.2794)
			(end -0.12065 0.2794)
			(stroke
				(width 0.1)
				(type default)
			)
			(layer "F.Fab")
		)
		(fp_line
			(start -0.12065 -0.2794)
			(end 0.12065 -0.2794)
			(stroke
				(width 0.1)
				(type default)
			)
			(layer "F.Fab")
		)
		(fp_line
			(start 0.12065 -0.2794)
			(end 0.12065 -0.3048)
			(stroke
				(width 0.1)
				(type default)
			)
			(layer "F.Fab")
		)
		(fp_line
			(start 0.12065 -0.3048)
			(end 0.67945 -0.3048)
			(stroke
				(width 0.1)
				(type default)
			)
			(layer "F.Fab")
		)
		(fp_line
			(start 0.67945 -0.3048)
			(end 0.67945 0.3048)
			(stroke
				(width 0.1)
				(type default)
			)
			(layer "F.Fab")
		)
		(fp_line
			(start -0.67945 -0.305054)
			(end -0.12065 -0.305054)
			(stroke
				(width 0.1)
				(type default)
			)
			(layer "F.Fab")
		)
		(fp_line
			(start -0.12065 -0.305054)
			(end -0.12065 -0.2794)
			(stroke
				(width 0.1)
				(type default)
			)
			(layer "F.Fab")
		)
		(pad "1" smd circle
			(at -0.40005 0 270)
			(size 0 0)
			(layers "F.Cu" "F.Mask" "F.Paste")
			(net "P12V_SSD6_CO_GATE")
		)
		(pad "2" smd circle
			(at 0.40005 0 270)
			(size 0 0)
			(layers "F.Cu" "F.Mask" "F.Paste")
			(net "GND")
		)
	)
	(footprint ""
		(layer "F.Cu")
		(at 452.694802 -246.92864 -90)
		(property "Reference" "C4430"
			(at 0 0 270)
			(layer "F.SilkS")
			(hide yes)
			(effects
				(font
					(size 1.27 1.27)
				)
			)
		)
		(property "Value" ""
			(at 0 0 270)
			(layer "F.Fab")
			(effects
				(font
					(size 1.27 1.27)
				)
			)
		)
		(duplicate_pad_numbers_are_jumpers no)
		(fp_line
			(start -1.524 0.762)
			(end -1.524 -0.762)
			(stroke
				(width 0.1524)
				(type default)
			)
			(layer "F.SilkS")
		)
		(fp_line
			(start 1.524 0.762)
			(end -1.524 0.762)
			(stroke
				(width 0.1524)
				(type default)
			)
			(layer "F.SilkS")
		)
		(fp_line
			(start -1.524 -0.762)
			(end 1.524 -0.762)
			(stroke
				(width 0.1524)
				(type default)
			)
			(layer "F.SilkS")
		)
		(fp_line
			(start 1.524 -0.762)
			(end 1.524 0.762)
			(stroke
				(width 0.1524)
				(type default)
			)
			(layer "F.SilkS")
		)
		(fp_line
			(start -1.1049 0.724916)
			(end 1.1049 0.724916)
			(stroke
				(width 0.1)
				(type default)
			)
			(layer "F.Fab")
		)
		(fp_line
			(start 1.1049 0.724916)
			(end 1.1049 -0.724916)
			(stroke
				(width 0.1)
				(type default)
			)
			(layer "F.Fab")
		)
		(fp_line
			(start -1.1049 -0.724916)
			(end -1.1049 0.724916)
			(stroke
				(width 0.1)
				(type default)
			)
			(layer "F.Fab")
		)
		(fp_line
			(start 1.1049 -0.724916)
			(end -1.1049 -0.724916)
			(stroke
				(width 0.1)
				(type default)
			)
			(layer "F.Fab")
		)
		(pad "1" smd rect
			(at -0.889 0 90)
			(size 1.016 1.27)
			(layers "F.Cu" "F.Mask" "F.Paste")
			(net "P3V3_AUX")
		)
		(pad "2" smd rect
			(at 0.889 0 90)
			(size 1.016 1.27)
			(layers "F.Cu" "F.Mask" "F.Paste")
			(net "GND")
		)
	)
	(footprint ""
		(layer "F.Cu")
		(at 198.564246 -362.567728 180)
		(property "Reference" "PC6"
			(at 0 0 180)
			(layer "F.SilkS")
			(hide yes)
			(effects
				(font
					(size 1.27 1.27)
				)
			)
		)
		(property "Value" ""
			(at 0 0 180)
			(layer "F.Fab")
			(effects
				(font
					(size 1.27 1.27)
				)
			)
		)
		(duplicate_pad_numbers_are_jumpers no)
		(fp_line
			(start 0.7874 0.4064)
			(end -0.7874 0.4064)
			(stroke
				(width 0.1524)
				(type default)
			)
			(layer "F.SilkS")
		)
		(fp_line
			(start 0.7874 -0.4064)
			(end 0.7874 0.4064)
			(stroke
				(width 0.1524)
				(type default)
			)
			(layer "F.SilkS")
		)
		(fp_line
			(start -0.7874 0.4064)
			(end -0.7874 -0.4064)
			(stroke
				(width 0.1524)
				(type default)
			)
			(layer "F.SilkS")
		)
		(fp_line
			(start -0.7874 -0.4064)
			(end 0.7874 -0.4064)
			(stroke
				(width 0.1524)
				(type default)
			)
			(layer "F.SilkS")
		)
		(fp_line
			(start 0.67945 0.3048)
			(end 0.120396 0.3048)
			(stroke
				(width 0.1)
				(type default)
			)
			(layer "F.Fab")
		)
		(fp_line
			(start 0.67945 -0.3048)
			(end 0.67945 0.3048)
			(stroke
				(width 0.1)
				(type default)
			)
			(layer "F.Fab")
		)
		(fp_line
			(start 0.12065 -0.2794)
			(end 0.12065 -0.3048)
			(stroke
				(width 0.1)
				(type default)
			)
			(layer "F.Fab")
		)
		(fp_line
			(start 0.12065 -0.3048)
			(end 0.67945 -0.3048)
			(stroke
				(width 0.1)
				(type default)
			)
			(layer "F.Fab")
		)
		(fp_line
			(start 0.120396 0.3048)
			(end 0.120396 0.2794)
			(stroke
				(width 0.1)
				(type default)
			)
			(layer "F.Fab")
		)
		(fp_line
			(start 0.120396 0.2794)
			(end -0.12065 0.2794)
			(stroke
				(width 0.1)
				(type default)
			)
			(layer "F.Fab")
		)
		(fp_line
			(start -0.12065 0.3048)
			(end -0.67945 0.3048)
			(stroke
				(width 0.1)
				(type default)
			)
			(layer "F.Fab")
		)
		(fp_line
			(start -0.12065 0.2794)
			(end -0.12065 0.3048)
			(stroke
				(width 0.1)
				(type default)
			)
			(layer "F.Fab")
		)
		(fp_line
			(start -0.12065 -0.2794)
			(end 0.12065 -0.2794)
			(stroke
				(width 0.1)
				(type default)
			)
			(layer "F.Fab")
		)
		(fp_line
			(start -0.12065 -0.305054)
			(end -0.12065 -0.2794)
			(stroke
				(width 0.1)
				(type default)
			)
			(layer "F.Fab")
		)
		(fp_line
			(start -0.67945 0.3048)
			(end -0.67945 -0.305054)
			(stroke
				(width 0.1)
				(type default)
			)
			(layer "F.Fab")
		)
		(fp_line
			(start -0.67945 -0.305054)
			(end -0.12065 -0.305054)
			(stroke
				(width 0.1)
				(type default)
			)
			(layer "F.Fab")
		)
		(pad "1" smd circle
			(at -0.40005 0 180)
			(size 0 0)
			(layers "F.Cu" "F.Mask" "F.Paste")
			(net "HSC_IMON")
		)
		(pad "2" smd circle
			(at 0.40005 0 180)
			(size 0 0)
			(layers "F.Cu" "F.Mask" "F.Paste")
			(net "AGND_HSC")
		)
	)
	(footprint ""
		(layer "F.Cu")
		(at 461.748886 -267.009626)
		(property "Reference" "C4393"
			(at 0 0 0)
			(layer "F.SilkS")
			(hide yes)
			(effects
				(font
					(size 1.27 1.27)
				)
			)
		)
		(property "Value" ""
			(at 0 0 0)
			(layer "F.Fab")
			(effects
				(font
					(size 1.27 1.27)
				)
			)
		)
		(duplicate_pad_numbers_are_jumpers no)
		(fp_line
			(start -0.299974 -0.150114)
			(end 0.299974 -0.150114)
			(stroke
				(width 0.1)
				(type default)
			)
			(layer "F.Fab")
		)
		(fp_line
			(start -0.299974 0.150114)
			(end -0.299974 -0.150114)
			(stroke
				(width 0.1)
				(type default)
			)
			(layer "F.Fab")
		)
		(fp_line
			(start 0.299974 -0.150114)
			(end 0.299974 0.150114)
			(stroke
				(width 0.1)
				(type default)
			)
			(layer "F.Fab")
		)
		(fp_line
			(start 0.299974 0.150114)
			(end -0.299974 0.150114)
			(stroke
				(width 0.1)
				(type default)
			)
			(layer "F.Fab")
		)
		(pad "1" smd rect
			(at -0.2667 0)
			(size 0.3048 0.381)
			(layers "F.Cu" "F.Mask" "F.Paste")
			(net "P1V25_SERDES_VDDPLL_PEX3")
		)
		(pad "2" smd rect
			(at 0.2667 0)
			(size 0.3048 0.381)
			(layers "F.Cu" "F.Mask" "F.Paste")
			(net "GND")
		)
	)
	(footprint ""
		(layer "F.Cu")
		(at 451.669658 -366.295432 90)
		(property "Reference" "R6691"
			(at 0 0 90)
			(layer "F.SilkS")
			(hide yes)
			(effects
				(font
					(size 1.27 1.27)
				)
			)
		)
		(property "Value" ""
			(at 0 0 90)
			(layer "F.Fab")
			(effects
				(font
					(size 1.27 1.27)
				)
			)
		)
		(duplicate_pad_numbers_are_jumpers no)
		(fp_line
			(start 0.7874 -0.4064)
			(end 0.7874 0.4064)
			(stroke
				(width 0.1524)
				(type default)
			)
			(layer "F.SilkS")
		)
		(fp_line
			(start -0.7874 -0.4064)
			(end 0.7874 -0.4064)
			(stroke
				(width 0.1524)
				(type default)
			)
			(layer "F.SilkS")
		)
		(fp_line
			(start 0.7874 0.4064)
			(end -0.7874 0.4064)
			(stroke
				(width 0.1524)
				(type default)
			)
			(layer "F.SilkS")
		)
		(fp_line
			(start -0.7874 0.4064)
			(end -0.7874 -0.4064)
			(stroke
				(width 0.1524)
				(type default)
			)
			(layer "F.SilkS")
		)
		(fp_line
			(start -0.12065 -0.305054)
			(end -0.12065 -0.2794)
			(stroke
				(width 0.1)
				(type default)
			)
			(layer "F.Fab")
		)
		(fp_line
			(start -0.67945 -0.305054)
			(end -0.12065 -0.305054)
			(stroke
				(width 0.1)
				(type default)
			)
			(layer "F.Fab")
		)
		(fp_line
			(start 0.67945 -0.3048)
			(end 0.67945 0.3048)
			(stroke
				(width 0.1)
				(type default)
			)
			(layer "F.Fab")
		)
		(fp_line
			(start 0.12065 -0.3048)
			(end 0.67945 -0.3048)
			(stroke
				(width 0.1)
				(type default)
			)
			(layer "F.Fab")
		)
		(fp_line
			(start 0.12065 -0.2794)
			(end 0.12065 -0.3048)
			(stroke
				(width 0.1)
				(type default)
			)
			(layer "F.Fab")
		)
		(fp_line
			(start -0.12065 -0.2794)
			(end 0.12065 -0.2794)
			(stroke
				(width 0.1)
				(type default)
			)
			(layer "F.Fab")
		)
		(fp_line
			(start 0.120396 0.2794)
			(end -0.12065 0.2794)
			(stroke
				(width 0.1)
				(type default)
			)
			(layer "F.Fab")
		)
		(fp_line
			(start -0.12065 0.2794)
			(end -0.12065 0.3048)
			(stroke
				(width 0.1)
				(type default)
			)
			(layer "F.Fab")
		)
		(fp_line
			(start 0.67945 0.3048)
			(end 0.120396 0.3048)
			(stroke
				(width 0.1)
				(type default)
			)
			(layer "F.Fab")
		)
		(fp_line
			(start 0.120396 0.3048)
			(end 0.120396 0.2794)
			(stroke
				(width 0.1)
				(type default)
			)
			(layer "F.Fab")
		)
		(fp_line
			(start -0.12065 0.3048)
			(end -0.67945 0.3048)
			(stroke
				(width 0.1)
				(type default)
			)
			(layer "F.Fab")
		)
		(fp_line
			(start -0.67945 0.3048)
			(end -0.67945 -0.305054)
			(stroke
				(width 0.1)
				(type default)
			)
			(layer "F.Fab")
		)
		(pad "1" smd circle
			(at -0.40005 0 90)
			(size 0 0)
			(layers "F.Cu" "F.Mask" "F.Paste")
			(net "P3V3_AUX")
		)
		(pad "2" smd circle
			(at 0.40005 0 90)
			(size 0 0)
			(layers "F.Cu" "F.Mask" "F.Paste")
			(net "GPU_3V3IO_RSVD4")
		)
	)
	(footprint ""
		(layer "F.Cu")
		(at 228.596952 -147.140422 90)
		(property "Reference" "U117"
			(at 4.851908 -5.381752 0)
			(unlocked yes)
			(layer "F.SilkS")
			(effects
				(font
					(size 0.7874 0.5842)
					(thickness 0.1524)
				)
				(justify left)
			)
		)
		(property "Value" ""
			(at 0 0 90)
			(layer "F.Fab")
			(effects
				(font
					(size 1.27 1.27)
				)
			)
		)
		(duplicate_pad_numbers_are_jumpers no)
		(fp_line
			(start 3.999992 -3.999992)
			(end 3.4798 -3.999992)
			(stroke
				(width 0.1524)
				(type default)
			)
			(layer "F.SilkS")
		)
		(fp_line
			(start -3.4798 -3.999992)
			(end -3.999992 -3.999992)
			(stroke
				(width 0.1524)
				(type default)
			)
			(layer "F.SilkS")
		)
		(fp_line
			(start -3.999992 -3.999992)
			(end -3.999992 -3.4798)
			(stroke
				(width 0.1524)
				(type default)
			)
			(layer "F.SilkS")
		)
		(fp_line
			(start 3.999992 -3.4798)
			(end 3.999992 -3.999992)
			(stroke
				(width 0.1524)
				(type default)
			)
			(layer "F.SilkS")
		)
		(fp_line
			(start -3.999992 3.4798)
			(end -3.999992 3.999992)
			(stroke
				(width 0.1524)
				(type default)
			)
			(layer "F.SilkS")
		)
		(fp_line
			(start 3.999992 3.999992)
			(end 3.999992 3.4798)
			(stroke
				(width 0.1524)
				(type default)
			)
			(layer "F.SilkS")
		)
		(fp_line
			(start 3.4798 3.999992)
			(end 3.999992 3.999992)
			(stroke
				(width 0.1524)
				(type default)
			)
			(layer "F.SilkS")
		)
		(fp_line
			(start -3.999992 3.999992)
			(end -3.4798 3.999992)
			(stroke
				(width 0.1524)
				(type default)
			)
			(layer "F.SilkS")
		)
		(fp_poly
			(pts
				(xy -4.682236 -4.609338) (xy -5.400548 -3.890772) (xy -4.322826 -3.531616)
			)
			(stroke
				(width 0)
				(type default)
			)
			(fill yes)
			(layer "F.SilkS")
		)
		(fp_line
			(start 3.999992 -3.999992)
			(end -3.999992 -3.999992)
			(stroke
				(width 0.1)
				(type default)
			)
			(layer "F.Fab")
		)
		(fp_line
			(start -3.999992 -3.999992)
			(end -3.999992 3.999992)
			(stroke
				(width 0.1)
				(type default)
			)
			(layer "F.Fab")
		)
		(fp_line
			(start 3.999992 3.999992)
			(end 3.999992 -3.999992)
			(stroke
				(width 0.1)
				(type default)
			)
			(layer "F.Fab")
		)
		(fp_line
			(start -3.999992 3.999992)
			(end 3.999992 3.999992)
			(stroke
				(width 0.1)
				(type default)
			)
			(layer "F.Fab")
		)
		(fp_poly
			(pts
				(xy -5.4102 -3.75793) (xy -5.4102 -2.74193) (xy -4.3942 -3.24993)
			)
			(stroke
				(width 0)
				(type default)
			)
			(fill yes)
			(layer "F.Fab")
		)
		(pad "A1" smd rect
			(at -3.875024 -3.24993 180)
			(size 0.1778 0.5588)
			(layers "F.Cu" "F.Mask" "F.Paste")
			(net "FM_CK440_PEX_DEV_25M_EN")
		)
		(pad "A2" smd rect
			(at -3.875024 -2.750058 180)
			(size 0.1778 0.5588)
			(layers "F.Cu" "F.Mask" "F.Paste")
			(net "Net_9065")
		)
		(pad "A3" smd rect
			(at -3.875024 -2.249932 180)
			(size 0.1778 0.5588)
			(layers "F.Cu" "F.Mask" "F.Paste")
			(net "Net_9066")
		)
		(pad "A4" smd rect
			(at -3.875024 -1.75006 180)
			(size 0.1778 0.5588)
			(layers "F.Cu" "F.Mask" "F.Paste")
			(net "Net_9067")
		)
		(pad "A5" smd rect
			(at -3.875024 -1.249934 180)
			(size 0.1778 0.5588)
			(layers "F.Cu" "F.Mask" "F.Paste")
			(net "Net_9068")
		)
		(pad "A6" smd rect
			(at -3.875024 -0.750062 180)
			(size 0.1778 0.5588)
			(layers "F.Cu" "F.Mask" "F.Paste")
			(net "TP_CLK_CK440_PEX_PFT_OUT_DP")
		)
		(pad "A7" smd rect
			(at -3.875024 -0.249936 180)
			(size 0.1778 0.5588)
			(layers "F.Cu" "F.Mask" "F.Paste")
			(net "TP_CLK_CK440_PEX_PFT_OUT_DN")
		)
		(pad "A8" smd rect
			(at -3.875024 0.249936 180)
			(size 0.1778 0.5588)
			(layers "F.Cu" "F.Mask" "F.Paste")
			(net "TP_CK440_PEX_PFT_IN_DP")
		)
		(pad "A9" smd rect
			(at -3.875024 0.750062 180)
			(size 0.1778 0.5588)
			(layers "F.Cu" "F.Mask" "F.Paste")
			(net "TP_CK440_PEX_PFT_IN_DN")
		)
		(pad "A10" smd rect
			(at -3.875024 1.249934 180)
			(size 0.1778 0.5588)
			(layers "F.Cu" "F.Mask" "F.Paste")
			(net "SMB_CK440_PEX_CLK_SCL")
		)
		(pad "A11" smd rect
			(at -3.875024 1.75006 180)
			(size 0.1778 0.5588)
			(layers "F.Cu" "F.Mask" "F.Paste")
			(net "CLK_CK440_PEX_SMB_ADDR0")
		)
		(pad "A12" smd rect
			(at -3.875024 2.249932 180)
			(size 0.1778 0.5588)
			(layers "F.Cu" "F.Mask" "F.Paste")
			(net "P3V3_CLK_GEN_VDDXTAL_CK440_PEX")
		)
		(pad "A13" smd rect
			(at -3.875024 2.750058 180)
			(size 0.1778 0.5588)
			(layers "F.Cu" "F.Mask" "F.Paste")
			(net "XTAL_CK440_PEX_25M_XIN")
		)
		(pad "A14" smd rect
			(at -3.875024 3.24993 180)
			(size 0.1778 0.5588)
			(layers "F.Cu" "F.Mask" "F.Paste")
			(net "GND")
		)
		(pad "A15" smd rect
			(at -3.24993 3.875024 90)
			(size 0.1778 0.5588)
			(layers "F.Cu" "F.Mask" "F.Paste")
			(net "Net_9044")
		)
		(pad "A16" smd rect
			(at -2.750058 3.875024 90)
			(size 0.1778 0.5588)
			(layers "F.Cu" "F.Mask" "F.Paste")
			(net "CK440_PEX_SS_EN")
		)
		(pad "A17" smd rect
			(at -2.249932 3.875024 90)
			(size 0.1778 0.5588)
			(layers "F.Cu" "F.Mask" "F.Paste")
			(net "FM_CLK_EN_R")
		)
		(pad "A18" smd rect
			(at -1.75006 3.875024 90)
			(size 0.1778 0.5588)
			(layers "F.Cu" "F.Mask" "F.Paste")
			(net "Net_9069")
		)
		(pad "A19" smd rect
			(at -1.249934 3.875024 90)
			(size 0.1778 0.5588)
			(layers "F.Cu" "F.Mask" "F.Paste")
			(net "Net_9070")
		)
		(pad "A20" smd rect
			(at -0.750062 3.875024 90)
			(size 0.1778 0.5588)
			(layers "F.Cu" "F.Mask" "F.Paste")
			(net "Net_9071")
		)
		(pad "A21" smd rect
			(at -0.249936 3.875024 90)
			(size 0.1778 0.5588)
			(layers "F.Cu" "F.Mask" "F.Paste")
			(net "Net_9072")
		)
		(pad "A22" smd rect
			(at 0.249936 3.875024 90)
			(size 0.1778 0.5588)
			(layers "F.Cu" "F.Mask" "F.Paste")
			(net "Net_9073")
		)
		(pad "A23" smd rect
			(at 0.750062 3.875024 90)
			(size 0.1778 0.5588)
			(layers "F.Cu" "F.Mask" "F.Paste")
			(net "Net_9074")
		)
		(pad "A24" smd rect
			(at 1.249934 3.875024 90)
			(size 0.1778 0.5588)
			(layers "F.Cu" "F.Mask" "F.Paste")
			(net "CLK_100M_PEX3_REF_DN")
		)
		(pad "A25" smd rect
			(at 1.75006 3.875024 90)
			(size 0.1778 0.5588)
			(layers "F.Cu" "F.Mask" "F.Paste")
			(net "CLK_100M_PEX3_REF_DP")
		)
		(pad "A26" smd rect
			(at 2.249932 3.875024 90)
			(size 0.1778 0.5588)
			(layers "F.Cu" "F.Mask" "F.Paste")
			(net "PEX_REF_CLK_GEN_EN_N")
		)
		(pad "A27" smd rect
			(at 2.750058 3.875024 90)
			(size 0.1778 0.5588)
			(layers "F.Cu" "F.Mask" "F.Paste")
			(net "CLK_100M_PEX2_REF_DN")
		)
		(pad "A28" smd rect
			(at 3.24993 3.875024 90)
			(size 0.1778 0.5588)
			(layers "F.Cu" "F.Mask" "F.Paste")
			(net "CLK_100M_PEX2_REF_DP")
		)
		(pad "A29" smd rect
			(at 3.875024 3.24993)
			(size 0.1778 0.5588)
			(layers "F.Cu" "F.Mask" "F.Paste")
			(net "PEX_REF_CLK_GEN_EN_N")
		)
		(pad "A30" smd rect
			(at 3.875024 2.750058)
			(size 0.1778 0.5588)
			(layers "F.Cu" "F.Mask" "F.Paste")
			(net "PEX_REF_CLK_GEN_EN_N")
		)
		(pad "A31" smd rect
			(at 3.875024 2.249932)
			(size 0.1778 0.5588)
			(layers "F.Cu" "F.Mask" "F.Paste")
			(net "CLK_100M_PEX1_REF_DN")
		)
		(pad "A32" smd rect
			(at 3.875024 1.75006)
			(size 0.1778 0.5588)
			(layers "F.Cu" "F.Mask" "F.Paste")
			(net "CLK_100M_PEX1_REF_DP")
		)
		(pad "A33" smd rect
			(at 3.875024 1.249934)
			(size 0.1778 0.5588)
			(layers "F.Cu" "F.Mask" "F.Paste")
			(net "CLK_100M_PEX0_REF_DN")
		)
		(pad "A34" smd rect
			(at 3.875024 0.750062)
			(size 0.1778 0.5588)
			(layers "F.Cu" "F.Mask" "F.Paste")
			(net "CLK_100M_PEX0_REF_DP")
		)
		(pad "A35" smd rect
			(at 3.875024 0.249936)
			(size 0.1778 0.5588)
			(layers "F.Cu" "F.Mask" "F.Paste")
			(net "Net_9045")
		)
		(pad "A36" smd rect
			(at 3.875024 -0.249936)
			(size 0.1778 0.5588)
			(layers "F.Cu" "F.Mask" "F.Paste")
			(net "Net_9046")
		)
		(pad "A37" smd rect
			(at 3.875024 -0.750062)
			(size 0.1778 0.5588)
			(layers "F.Cu" "F.Mask" "F.Paste")
			(net "Net_9047")
		)
		(pad "A38" smd rect
			(at 3.875024 -1.249934)
			(size 0.1778 0.5588)
			(layers "F.Cu" "F.Mask" "F.Paste")
			(net "Net_9048")
		)
		(pad "A39" smd rect
			(at 3.875024 -1.75006)
			(size 0.1778 0.5588)
			(layers "F.Cu" "F.Mask" "F.Paste")
			(net "Net_9049")
		)
		(pad "A40" smd rect
			(at 3.875024 -2.249932)
			(size 0.1778 0.5588)
			(layers "F.Cu" "F.Mask" "F.Paste")
			(net "Net_9050")
		)
		(pad "A41" smd rect
			(at 3.875024 -2.750058)
			(size 0.1778 0.5588)
			(layers "F.Cu" "F.Mask" "F.Paste")
			(net "Net_9051")
		)
		(pad "A42" smd rect
			(at 3.875024 -3.24993)
			(size 0.1778 0.5588)
			(layers "F.Cu" "F.Mask" "F.Paste")
			(net "Net_9052")
		)
		(pad "A43" smd rect
			(at 3.24993 -3.875024 90)
			(size 0.1778 0.5588)
			(layers "F.Cu" "F.Mask" "F.Paste")
			(net "Net_9053")
		)
		(pad "A44" smd rect
			(at 2.750058 -3.875024 90)
			(size 0.1778 0.5588)
			(layers "F.Cu" "F.Mask" "F.Paste")
			(net "Net_9054")
		)
		(pad "A45" smd rect
			(at 2.249932 -3.875024 90)
			(size 0.1778 0.5588)
			(layers "F.Cu" "F.Mask" "F.Paste")
			(net "Net_9055")
		)
		(pad "A46" smd rect
			(at 1.75006 -3.875024 90)
			(size 0.1778 0.5588)
			(layers "F.Cu" "F.Mask" "F.Paste")
			(net "Net_9056")
		)
		(pad "A47" smd rect
			(at 1.249934 -3.875024 90)
			(size 0.1778 0.5588)
			(layers "F.Cu" "F.Mask" "F.Paste")
			(net "Net_9057")
		)
		(pad "A48" smd rect
			(at 0.750062 -3.875024 90)
			(size 0.1778 0.5588)
			(layers "F.Cu" "F.Mask" "F.Paste")
			(net "Net_9058")
		)
		(pad "A49" smd rect
			(at 0.249936 -3.875024 90)
			(size 0.1778 0.5588)
			(layers "F.Cu" "F.Mask" "F.Paste")
			(net "Net_9059")
		)
		(pad "A50" smd rect
			(at -0.249936 -3.875024 90)
			(size 0.1778 0.5588)
			(layers "F.Cu" "F.Mask" "F.Paste")
			(net "Net_9060")
		)
		(pad "A51" smd rect
			(at -0.750062 -3.875024 90)
			(size 0.1778 0.5588)
			(layers "F.Cu" "F.Mask" "F.Paste")
			(net "Net_9061")
		)
		(pad "A52" smd rect
			(at -1.249934 -3.875024 90)
			(size 0.1778 0.5588)
			(layers "F.Cu" "F.Mask" "F.Paste")
			(net "Net_9062")
		)
		(pad "A53" smd rect
			(at -1.75006 -3.875024 90)
			(size 0.1778 0.5588)
			(layers "F.Cu" "F.Mask" "F.Paste")
			(net "TP_CK440_PEX_SBI_DATA_OUT")
		)
		(pad "A54" smd rect
			(at -2.249932 -3.875024 90)
			(size 0.1778 0.5588)
			(layers "F.Cu" "F.Mask" "F.Paste")
			(net "PD_CK440_PEX_SBI_CLK")
		)
		(pad "A55" smd rect
			(at -2.750058 -3.875024 90)
			(size 0.1778 0.5588)
			(layers "F.Cu" "F.Mask" "F.Paste")
			(net "Net_9063")
		)
		(pad "A56" smd rect
			(at -3.24993 -3.875024 90)
			(size 0.1778 0.5588)
			(layers "F.Cu" "F.Mask" "F.Paste")
			(net "Net_9064")
		)
		(pad "B1" smd rect
			(at -3.124962 -2.500122 180)
			(size 0.2794 0.4572)
			(layers "F.Cu" "F.Mask" "F.Paste")
			(net "P3V3_CLK_GEN_VDDA25M_CK440_PEX")
		)
		(pad "B2" smd rect
			(at -3.124962 -1.999996 180)
			(size 0.2794 0.4572)
			(layers "F.Cu" "F.Mask" "F.Paste")
			(net "Net_9040")
		)
		(pad "B3" smd rect
			(at -3.124962 -1.500124 180)
			(size 0.2794 0.4572)
			(layers "F.Cu" "F.Mask" "F.Paste")
			(net "Net_9033")
		)
		(pad "B4" smd rect
			(at -3.124962 -0.999998 180)
			(size 0.2794 0.4572)
			(layers "F.Cu" "F.Mask" "F.Paste")
			(net "PU_CK440_PEX_PFT_LOST_N")
		)
		(pad "B5" smd rect
			(at -3.124962 -0.499872 180)
			(size 0.2794 0.4572)
			(layers "F.Cu" "F.Mask" "F.Paste")
			(net "Net_9023")
		)
		(pad "B6" smd rect
			(at -3.124962 0 180)
			(size 0.2794 0.4572)
			(layers "F.Cu" "F.Mask" "F.Paste")
			(net "P3V3_CLK_GEN_VDDPT_CK440_PEX")
		)
		(pad "B7" smd rect
			(at -3.124962 0.499872 180)
			(size 0.2794 0.4572)
			(layers "F.Cu" "F.Mask" "F.Paste")
			(net "Net_9022")
		)
		(pad "B8" smd rect
			(at -3.124962 0.999998 180)
			(size 0.2794 0.4572)
			(layers "F.Cu" "F.Mask" "F.Paste")
			(net "SMB_CK440_PEX_CLK_SDA")
		)
		(pad "B9" smd rect
			(at -3.124962 1.500124 180)
			(size 0.2794 0.4572)
			(layers "F.Cu" "F.Mask" "F.Paste")
			(net "CLK_CK440_PEX_SMB_ADDR1")
		)
		(pad "B10" smd rect
			(at -3.124962 1.999996 180)
			(size 0.2794 0.4572)
			(layers "F.Cu" "F.Mask" "F.Paste")
			(net "GND")
		)
		(pad "B11" smd rect
			(at -3.124962 2.500122 180)
			(size 0.2794 0.4572)
			(layers "F.Cu" "F.Mask" "F.Paste")
			(net "XTAL_CK440_PEX_25M_XOUT")
		)
		(pad "B12" smd rect
			(at -2.500122 3.124962 90)
			(size 0.2794 0.4572)
			(layers "F.Cu" "F.Mask" "F.Paste")
			(net "GND")
		)
		(pad "B13" smd rect
			(at -1.999996 3.124962 90)
			(size 0.2794 0.4572)
			(layers "F.Cu" "F.Mask" "F.Paste")
			(net "Net_9043")
		)
		(pad "B14" smd rect
			(at -1.500124 3.124962 90)
			(size 0.2794 0.4572)
			(layers "F.Cu" "F.Mask" "F.Paste")
			(net "CLK_GEN_CK440_PEX_OE6_N")
		)
		(pad "B15" smd rect
			(at -0.999998 3.124962 90)
			(size 0.2794 0.4572)
			(layers "F.Cu" "F.Mask" "F.Paste")
			(net "CLK_GEN_CK440_PEX_OE5_N")
		)
		(pad "B16" smd rect
			(at -0.499872 3.124962 90)
			(size 0.2794 0.4572)
			(layers "F.Cu" "F.Mask" "F.Paste")
			(net "Net_9042")
		)
		(pad "B17" smd rect
			(at 0 3.124962 90)
			(size 0.2794 0.4572)
			(layers "F.Cu" "F.Mask" "F.Paste")
			(net "P3V3_CLK_GEN_VDDA100M_CK440_PEX")
		)
		(pad "B18" smd rect
			(at 0.499872 3.124962 90)
			(size 0.2794 0.4572)
			(layers "F.Cu" "F.Mask" "F.Paste")
			(net "Net_9041")
		)
		(pad "B19" smd rect
			(at 0.999998 3.124962 90)
			(size 0.2794 0.4572)
			(layers "F.Cu" "F.Mask" "F.Paste")
			(net "CLK_GEN_CK440_PEX_OE4_N")
		)
		(pad "B20" smd rect
			(at 1.500124 3.124962 90)
			(size 0.2794 0.4572)
			(layers "F.Cu" "F.Mask" "F.Paste")
			(net "Net_9039")
		)
		(pad "B21" smd rect
			(at 1.999996 3.124962 90)
			(size 0.2794 0.4572)
			(layers "F.Cu" "F.Mask" "F.Paste")
			(net "P3V3_CLK_GEN_VDD_CK440_PEX")
		)
		(pad "B22" smd rect
			(at 2.500122 3.124962 90)
			(size 0.2794 0.4572)
			(layers "F.Cu" "F.Mask" "F.Paste")
			(net "Net_9038")
		)
		(pad "B23" smd rect
			(at 3.124962 2.500122)
			(size 0.2794 0.4572)
			(layers "F.Cu" "F.Mask" "F.Paste")
			(net "P3V3_CLK_GEN_VDD_CK440_PEX")
		)
		(pad "B24" smd rect
			(at 3.124962 1.999996)
			(size 0.2794 0.4572)
			(layers "F.Cu" "F.Mask" "F.Paste")
			(net "Net_9037")
		)
		(pad "B25" smd rect
			(at 3.124962 1.500124)
			(size 0.2794 0.4572)
			(layers "F.Cu" "F.Mask" "F.Paste")
			(net "Net_9036")
		)
		(pad "B26" smd rect
			(at 3.124962 0.999998)
			(size 0.2794 0.4572)
			(layers "F.Cu" "F.Mask" "F.Paste")
			(net "Net_9035")
		)
		(pad "B27" smd rect
			(at 3.124962 0.499872)
			(size 0.2794 0.4572)
			(layers "F.Cu" "F.Mask" "F.Paste")
			(net "PEX_REF_CLK_GEN_EN_N")
		)
		(pad "B28" smd rect
			(at 3.124962 0)
			(size 0.2794 0.4572)
			(layers "F.Cu" "F.Mask" "F.Paste")
			(net "Net_9034")
		)
		(pad "B29" smd rect
			(at 3.124962 -0.499872)
			(size 0.2794 0.4572)
			(layers "F.Cu" "F.Mask" "F.Paste")
			(net "P3V3_CLK_GEN_VDDMXCK_CK440_PEX")
		)
		(pad "B30" smd rect
			(at 3.124962 -0.999998)
			(size 0.2794 0.4572)
			(layers "F.Cu" "F.Mask" "F.Paste")
			(net "Net_9032")
		)
		(pad "B31" smd rect
			(at 3.124962 -1.500124)
			(size 0.2794 0.4572)
			(layers "F.Cu" "F.Mask" "F.Paste")
			(net "Net_9031")
		)
		(pad "B32" smd rect
			(at 3.124962 -1.999996)
			(size 0.2794 0.4572)
			(layers "F.Cu" "F.Mask" "F.Paste")
			(net "P3V3_CLK_GEN_VDDMXCK_CK440_PEX")
		)
		(pad "B33" smd rect
			(at 3.124962 -2.500122)
			(size 0.2794 0.4572)
			(layers "F.Cu" "F.Mask" "F.Paste")
			(net "Net_9030")
		)
		(pad "B34" smd rect
			(at 2.500122 -3.124962 90)
			(size 0.2794 0.4572)
			(layers "F.Cu" "F.Mask" "F.Paste")
			(net "Net_9029")
		)
		(pad "B35" smd rect
			(at 1.999996 -3.124962 90)
			(size 0.2794 0.4572)
			(layers "F.Cu" "F.Mask" "F.Paste")
			(net "P3V3_CLK_GEN_VDDMXCK_CK440_PEX")
		)
		(pad "B36" smd rect
			(at 1.500124 -3.124962 90)
			(size 0.2794 0.4572)
			(layers "F.Cu" "F.Mask" "F.Paste")
			(net "Net_9028")
		)
		(pad "B37" smd rect
			(at 0.999998 -3.124962 90)
			(size 0.2794 0.4572)
			(layers "F.Cu" "F.Mask" "F.Paste")
			(net "Net_9027")
		)
		(pad "B38" smd rect
			(at 0.499872 -3.124962 90)
			(size 0.2794 0.4572)
			(layers "F.Cu" "F.Mask" "F.Paste")
			(net "FM_CK440_PEX_MXCK_25M_100M")
		)
		(pad "B39" smd rect
			(at 0 -3.124962 90)
			(size 0.2794 0.4572)
			(layers "F.Cu" "F.Mask" "F.Paste")
			(net "Net_9026")
		)
		(pad "B40" smd rect
			(at -0.499872 -3.124962 90)
			(size 0.2794 0.4572)
			(layers "F.Cu" "F.Mask" "F.Paste")
			(net "P3V3_CLK_GEN_VDDMXCK_CK440_PEX")
		)
		(pad "B41" smd rect
			(at -0.999998 -3.124962 90)
			(size 0.2794 0.4572)
			(layers "F.Cu" "F.Mask" "F.Paste")
			(net "Net_9025")
		)
		(pad "B42" smd rect
			(at -1.500124 -3.124962 90)
			(size 0.2794 0.4572)
			(layers "F.Cu" "F.Mask" "F.Paste")
			(net "PU_CK440_PEX_SHFT_LD_N")
		)
		(pad "B43" smd rect
			(at -1.999996 -3.124962 90)
			(size 0.2794 0.4572)
			(layers "F.Cu" "F.Mask" "F.Paste")
			(net "PD_CK440_PEX_SBI_DATA_IN")
		)
		(pad "B44" smd rect
			(at -2.500122 -3.124962 90)
			(size 0.2794 0.4572)
			(layers "F.Cu" "F.Mask" "F.Paste")
			(net "Net_9024")
		)
		(pad "C1" smd circle
			(at 0 0 90)
			(size 0 0)
			(layers "F.Cu" "F.Mask" "F.Paste")
			(net "GND")
		)
		(zone
			(layer "F.Cu")
			(hatch none 0.5)
			(connect_pads
				(clearance 0)
			)
			(min_thickness 0.25)
			(keepout
				(tracks not_allowed)
				(vias allowed)
				(pads allowed)
				(copperpour not_allowed)
				(footprints allowed)
			)
			(placement
				(enabled no)
				(sheetname "")
			)
			(fill
				(thermal_gap 0.5)
				(thermal_bridge_width 0.5)
				(island_removal_mode 0)
			)
			(polygon
				(pts
					(xy 226.818952 -144.29486) (xy 226.818952 -144.536922) (xy 226.310952 -144.536922) (xy 225.993452 -144.854422)
					(xy 225.993452 -149.743922) (xy 231.200452 -149.743922) (xy 231.200452 -144.536922) (xy 226.844352 -144.536922)
					(xy 226.844352 -144.29486) (xy 231.442514 -144.29486) (xy 231.442514 -149.985984) (xy 225.75139 -149.985984)
					(xy 225.75139 -144.29486)
				)
			)
		)
	)
	(footprint ""
		(layer "F.Cu")
		(at 136.445244 -90.099642 180)
		(property "Reference" "R1580"
			(at 0 0 180)
			(layer "F.SilkS")
			(hide yes)
			(effects
				(font
					(size 1.27 1.27)
				)
			)
		)
		(property "Value" ""
			(at 0 0 180)
			(layer "F.Fab")
			(effects
				(font
					(size 1.27 1.27)
				)
			)
		)
		(duplicate_pad_numbers_are_jumpers no)
		(fp_line
			(start 0.7874 0.4064)
			(end -0.7874 0.4064)
			(stroke
				(width 0.1524)
				(type default)
			)
			(layer "F.SilkS")
		)
		(fp_line
			(start 0.7874 -0.4064)
			(end 0.7874 0.4064)
			(stroke
				(width 0.1524)
				(type default)
			)
			(layer "F.SilkS")
		)
		(fp_line
			(start -0.7874 0.4064)
			(end -0.7874 -0.4064)
			(stroke
				(width 0.1524)
				(type default)
			)
			(layer "F.SilkS")
		)
		(fp_line
			(start -0.7874 -0.4064)
			(end 0.7874 -0.4064)
			(stroke
				(width 0.1524)
				(type default)
			)
			(layer "F.SilkS")
		)
		(fp_line
			(start 0.67945 0.3048)
			(end 0.120396 0.3048)
			(stroke
				(width 0.1)
				(type default)
			)
			(layer "F.Fab")
		)
		(fp_line
			(start 0.67945 -0.3048)
			(end 0.67945 0.3048)
			(stroke
				(width 0.1)
				(type default)
			)
			(layer "F.Fab")
		)
		(fp_line
			(start 0.12065 -0.2794)
			(end 0.12065 -0.3048)
			(stroke
				(width 0.1)
				(type default)
			)
			(layer "F.Fab")
		)
		(fp_line
			(start 0.12065 -0.3048)
			(end 0.67945 -0.3048)
			(stroke
				(width 0.1)
				(type default)
			)
			(layer "F.Fab")
		)
		(fp_line
			(start 0.120396 0.3048)
			(end 0.120396 0.2794)
			(stroke
				(width 0.1)
				(type default)
			)
			(layer "F.Fab")
		)
		(fp_line
			(start 0.120396 0.2794)
			(end -0.12065 0.2794)
			(stroke
				(width 0.1)
				(type default)
			)
			(layer "F.Fab")
		)
		(fp_line
			(start -0.12065 0.3048)
			(end -0.67945 0.3048)
			(stroke
				(width 0.1)
				(type default)
			)
			(layer "F.Fab")
		)
		(fp_line
			(start -0.12065 0.2794)
			(end -0.12065 0.3048)
			(stroke
				(width 0.1)
				(type default)
			)
			(layer "F.Fab")
		)
		(fp_line
			(start -0.12065 -0.2794)
			(end 0.12065 -0.2794)
			(stroke
				(width 0.1)
				(type default)
			)
			(layer "F.Fab")
		)
		(fp_line
			(start -0.12065 -0.305054)
			(end -0.12065 -0.2794)
			(stroke
				(width 0.1)
				(type default)
			)
			(layer "F.Fab")
		)
		(fp_line
			(start -0.67945 0.3048)
			(end -0.67945 -0.305054)
			(stroke
				(width 0.1)
				(type default)
			)
			(layer "F.Fab")
		)
		(fp_line
			(start -0.67945 -0.305054)
			(end -0.12065 -0.305054)
			(stroke
				(width 0.1)
				(type default)
			)
			(layer "F.Fab")
		)
		(pad "1" smd circle
			(at -0.40005 0 180)
			(size 0 0)
			(layers "F.Cu" "F.Mask" "F.Paste")
			(net "SMB_BIC_I2C9_MUX0_SSD5_R_SDA")
		)
		(pad "2" smd circle
			(at 0.40005 0 180)
			(size 0 0)
			(layers "F.Cu" "F.Mask" "F.Paste")
			(net "SMB_BIC_I2C9_MUX0_SSD5_SDA")
		)
	)
	(footprint ""
		(layer "F.Cu")
		(at 30.153356 -291.390832)
		(property "Reference" "L92"
			(at 0 0 0)
			(layer "F.SilkS")
			(hide yes)
			(effects
				(font
					(size 1.27 1.27)
				)
			)
		)
		(property "Value" ""
			(at 0 0 0)
			(layer "F.Fab")
			(effects
				(font
					(size 1.27 1.27)
				)
			)
		)
		(duplicate_pad_numbers_are_jumpers no)
		(fp_line
			(start -1.63576 -0.8128)
			(end -1.63576 0.8128)
			(stroke
				(width 0.1524)
				(type default)
			)
			(layer "F.SilkS")
		)
		(fp_line
			(start -1.63576 -0.8128)
			(end 1.63576 -0.8128)
			(stroke
				(width 0.1524)
				(type default)
			)
			(layer "F.SilkS")
		)
		(fp_line
			(start 1.63576 -0.8128)
			(end 1.63576 0.8128)
			(stroke
				(width 0.1524)
				(type default)
			)
			(layer "F.SilkS")
		)
		(fp_line
			(start 1.63576 0.8128)
			(end -1.63576 0.8128)
			(stroke
				(width 0.1524)
				(type default)
			)
			(layer "F.SilkS")
		)
		(fp_line
			(start -1.56083 -0.738632)
			(end -1.56083 0.7366)
			(stroke
				(width 0.1)
				(type default)
			)
			(layer "F.Fab")
		)
		(fp_line
			(start -1.56083 0.7366)
			(end -1.524 0.7366)
			(stroke
				(width 0.1)
				(type default)
			)
			(layer "F.Fab")
		)
		(fp_line
			(start -1.524 0.7366)
			(end 1.524 0.7366)
			(stroke
				(width 0.1)
				(type default)
			)
			(layer "F.Fab")
		)
		(fp_line
			(start 1.524 0.7366)
			(end 1.560576 0.7366)
			(stroke
				(width 0.1)
				(type default)
			)
			(layer "F.Fab")
		)
		(fp_line
			(start 1.560576 -0.738632)
			(end -1.56083 -0.738632)
			(stroke
				(width 0.1)
				(type default)
			)
			(layer "F.Fab")
		)
		(fp_line
			(start 1.560576 0.7366)
			(end 1.560576 -0.738632)
			(stroke
				(width 0.1)
				(type default)
			)
			(layer "F.Fab")
		)
		(pad "1" smd rect
			(at -0.94996 0 180)
			(size 1.1176 1.3716)
			(layers "F.Cu" "F.Mask" "F.Paste")
			(net "P1V8_PLL0_PEX0")
		)
		(pad "2" smd rect
			(at 0.94996 0 180)
			(size 1.1176 1.3716)
			(layers "F.Cu" "F.Mask" "F.Paste")
			(net "PCEPLL4_VDDA18_PEX0")
		)
	)
	(footprint ""
		(layer "F.Cu")
		(at 21.255736 -152.71115 90)
		(property "Reference" "R685"
			(at 0 0 90)
			(layer "F.SilkS")
			(hide yes)
			(effects
				(font
					(size 1.27 1.27)
				)
			)
		)
		(property "Value" ""
			(at 0 0 90)
			(layer "F.Fab")
			(effects
				(font
					(size 1.27 1.27)
				)
			)
		)
		(duplicate_pad_numbers_are_jumpers no)
		(fp_line
			(start 0.7874 -0.4064)
			(end 0.7874 0.4064)
			(stroke
				(width 0.1524)
				(type default)
			)
			(layer "F.SilkS")
		)
		(fp_line
			(start -0.7874 -0.4064)
			(end 0.7874 -0.4064)
			(stroke
				(width 0.1524)
				(type default)
			)
			(layer "F.SilkS")
		)
		(fp_line
			(start 0.7874 0.4064)
			(end -0.7874 0.4064)
			(stroke
				(width 0.1524)
				(type default)
			)
			(layer "F.SilkS")
		)
		(fp_line
			(start -0.7874 0.4064)
			(end -0.7874 -0.4064)
			(stroke
				(width 0.1524)
				(type default)
			)
			(layer "F.SilkS")
		)
		(fp_line
			(start -0.12065 -0.305054)
			(end -0.12065 -0.2794)
			(stroke
				(width 0.1)
				(type default)
			)
			(layer "F.Fab")
		)
		(fp_line
			(start -0.67945 -0.305054)
			(end -0.12065 -0.305054)
			(stroke
				(width 0.1)
				(type default)
			)
			(layer "F.Fab")
		)
		(fp_line
			(start 0.67945 -0.3048)
			(end 0.67945 0.3048)
			(stroke
				(width 0.1)
				(type default)
			)
			(layer "F.Fab")
		)
		(fp_line
			(start 0.12065 -0.3048)
			(end 0.67945 -0.3048)
			(stroke
				(width 0.1)
				(type default)
			)
			(layer "F.Fab")
		)
		(fp_line
			(start 0.12065 -0.2794)
			(end 0.12065 -0.3048)
			(stroke
				(width 0.1)
				(type default)
			)
			(layer "F.Fab")
		)
		(fp_line
			(start -0.12065 -0.2794)
			(end 0.12065 -0.2794)
			(stroke
				(width 0.1)
				(type default)
			)
			(layer "F.Fab")
		)
		(fp_line
			(start 0.120396 0.2794)
			(end -0.12065 0.2794)
			(stroke
				(width 0.1)
				(type default)
			)
			(layer "F.Fab")
		)
		(fp_line
			(start -0.12065 0.2794)
			(end -0.12065 0.3048)
			(stroke
				(width 0.1)
				(type default)
			)
			(layer "F.Fab")
		)
		(fp_line
			(start 0.67945 0.3048)
			(end 0.120396 0.3048)
			(stroke
				(width 0.1)
				(type default)
			)
			(layer "F.Fab")
		)
		(fp_line
			(start 0.120396 0.3048)
			(end 0.120396 0.2794)
			(stroke
				(width 0.1)
				(type default)
			)
			(layer "F.Fab")
		)
		(fp_line
			(start -0.12065 0.3048)
			(end -0.67945 0.3048)
			(stroke
				(width 0.1)
				(type default)
			)
			(layer "F.Fab")
		)
		(fp_line
			(start -0.67945 0.3048)
			(end -0.67945 -0.305054)
			(stroke
				(width 0.1)
				(type default)
			)
			(layer "F.Fab")
		)
		(pad "1" smd circle
			(at -0.40005 0 90)
			(size 0 0)
			(layers "F.Cu" "F.Mask" "F.Paste")
			(net "NIC0_ADC_A1")
		)
		(pad "2" smd circle
			(at 0.40005 0 90)
			(size 0 0)
			(layers "F.Cu" "F.Mask" "F.Paste")
			(net "GND")
		)
	)
	(footprint ""
		(layer "F.Cu")
		(at 334.518 -205.232 -90)
		(property "Reference" "R4117"
			(at 0 0 270)
			(layer "F.SilkS")
			(hide yes)
			(effects
				(font
					(size 1.27 1.27)
				)
			)
		)
		(property "Value" ""
			(at 0 0 270)
			(layer "F.Fab")
			(effects
				(font
					(size 1.27 1.27)
				)
			)
		)
		(duplicate_pad_numbers_are_jumpers no)
		(fp_line
			(start -0.7874 0.4064)
			(end -0.7874 -0.4064)
			(stroke
				(width 0.1524)
				(type default)
			)
			(layer "F.SilkS")
		)
		(fp_line
			(start 0.7874 0.4064)
			(end -0.7874 0.4064)
			(stroke
				(width 0.1524)
				(type default)
			)
			(layer "F.SilkS")
		)
		(fp_line
			(start -0.7874 -0.4064)
			(end 0.7874 -0.4064)
			(stroke
				(width 0.1524)
				(type default)
			)
			(layer "F.SilkS")
		)
		(fp_line
			(start 0.7874 -0.4064)
			(end 0.7874 0.4064)
			(stroke
				(width 0.1524)
				(type default)
			)
			(layer "F.SilkS")
		)
		(fp_line
			(start -0.67945 0.3048)
			(end -0.67945 -0.305054)
			(stroke
				(width 0.1)
				(type default)
			)
			(layer "F.Fab")
		)
		(fp_line
			(start -0.12065 0.3048)
			(end -0.67945 0.3048)
			(stroke
				(width 0.1)
				(type default)
			)
			(layer "F.Fab")
		)
		(fp_line
			(start 0.120396 0.3048)
			(end 0.120396 0.2794)
			(stroke
				(width 0.1)
				(type default)
			)
			(layer "F.Fab")
		)
		(fp_line
			(start 0.67945 0.3048)
			(end 0.120396 0.3048)
			(stroke
				(width 0.1)
				(type default)
			)
			(layer "F.Fab")
		)
		(fp_line
			(start -0.12065 0.2794)
			(end -0.12065 0.3048)
			(stroke
				(width 0.1)
				(type default)
			)
			(layer "F.Fab")
		)
		(fp_line
			(start 0.120396 0.2794)
			(end -0.12065 0.2794)
			(stroke
				(width 0.1)
				(type default)
			)
			(layer "F.Fab")
		)
		(fp_line
			(start -0.12065 -0.2794)
			(end 0.12065 -0.2794)
			(stroke
				(width 0.1)
				(type default)
			)
			(layer "F.Fab")
		)
		(fp_line
			(start 0.12065 -0.2794)
			(end 0.12065 -0.3048)
			(stroke
				(width 0.1)
				(type default)
			)
			(layer "F.Fab")
		)
		(fp_line
			(start 0.12065 -0.3048)
			(end 0.67945 -0.3048)
			(stroke
				(width 0.1)
				(type default)
			)
			(layer "F.Fab")
		)
		(fp_line
			(start 0.67945 -0.3048)
			(end 0.67945 0.3048)
			(stroke
				(width 0.1)
				(type default)
			)
			(layer "F.Fab")
		)
		(fp_line
			(start -0.67945 -0.305054)
			(end -0.12065 -0.305054)
			(stroke
				(width 0.1)
				(type default)
			)
			(layer "F.Fab")
		)
		(fp_line
			(start -0.12065 -0.305054)
			(end -0.12065 -0.2794)
			(stroke
				(width 0.1)
				(type default)
			)
			(layer "F.Fab")
		)
		(pad "1" smd circle
			(at -0.40005 0 270)
			(size 0 0)
			(layers "F.Cu" "F.Mask" "F.Paste")
			(net "RST_SSD8_PERST_N")
		)
		(pad "2" smd circle
			(at 0.40005 0 270)
			(size 0 0)
			(layers "F.Cu" "F.Mask" "F.Paste")
			(net "RST_SSD8_PERST_R_N")
		)
	)
	(footprint ""
		(layer "F.Cu")
		(at 109.347 -37.47516)
		(property "Reference" "R6062"
			(at 0 0 0)
			(layer "F.SilkS")
			(hide yes)
			(effects
				(font
					(size 1.27 1.27)
				)
			)
		)
		(property "Value" ""
			(at 0 0 0)
			(layer "F.Fab")
			(effects
				(font
					(size 1.27 1.27)
				)
			)
		)
		(duplicate_pad_numbers_are_jumpers no)
		(fp_line
			(start -0.7874 -0.4064)
			(end 0.7874 -0.4064)
			(stroke
				(width 0.1524)
				(type default)
			)
			(layer "F.SilkS")
		)
		(fp_line
			(start -0.7874 0.4064)
			(end -0.7874 -0.4064)
			(stroke
				(width 0.1524)
				(type default)
			)
			(layer "F.SilkS")
		)
		(fp_line
			(start 0.7874 -0.4064)
			(end 0.7874 0.4064)
			(stroke
				(width 0.1524)
				(type default)
			)
			(layer "F.SilkS")
		)
		(fp_line
			(start 0.7874 0.4064)
			(end -0.7874 0.4064)
			(stroke
				(width 0.1524)
				(type default)
			)
			(layer "F.SilkS")
		)
		(fp_line
			(start -0.67945 -0.305054)
			(end -0.12065 -0.305054)
			(stroke
				(width 0.1)
				(type default)
			)
			(layer "F.Fab")
		)
		(fp_line
			(start -0.67945 0.3048)
			(end -0.67945 -0.305054)
			(stroke
				(width 0.1)
				(type default)
			)
			(layer "F.Fab")
		)
		(fp_line
			(start -0.12065 -0.305054)
			(end -0.12065 -0.2794)
			(stroke
				(width 0.1)
				(type default)
			)
			(layer "F.Fab")
		)
		(fp_line
			(start -0.12065 -0.2794)
			(end 0.12065 -0.2794)
			(stroke
				(width 0.1)
				(type default)
			)
			(layer "F.Fab")
		)
		(fp_line
			(start -0.12065 0.2794)
			(end -0.12065 0.3048)
			(stroke
				(width 0.1)
				(type default)
			)
			(layer "F.Fab")
		)
		(fp_line
			(start -0.12065 0.3048)
			(end -0.67945 0.3048)
			(stroke
				(width 0.1)
				(type default)
			)
			(layer "F.Fab")
		)
		(fp_line
			(start 0.120396 0.2794)
			(end -0.12065 0.2794)
			(stroke
				(width 0.1)
				(type default)
			)
			(layer "F.Fab")
		)
		(fp_line
			(start 0.120396 0.3048)
			(end 0.120396 0.2794)
			(stroke
				(width 0.1)
				(type default)
			)
			(layer "F.Fab")
		)
		(fp_line
			(start 0.12065 -0.3048)
			(end 0.67945 -0.3048)
			(stroke
				(width 0.1)
				(type default)
			)
			(layer "F.Fab")
		)
		(fp_line
			(start 0.12065 -0.2794)
			(end 0.12065 -0.3048)
			(stroke
				(width 0.1)
				(type default)
			)
			(layer "F.Fab")
		)
		(fp_line
			(start 0.67945 -0.3048)
			(end 0.67945 0.3048)
			(stroke
				(width 0.1)
				(type default)
			)
			(layer "F.Fab")
		)
		(fp_line
			(start 0.67945 0.3048)
			(end 0.120396 0.3048)
			(stroke
				(width 0.1)
				(type default)
			)
			(layer "F.Fab")
		)
		(pad "1" smd circle
			(at -0.40005 0)
			(size 0 0)
			(layers "F.Cu" "F.Mask" "F.Paste")
			(net "P3V3_SSD4")
		)
		(pad "2" smd circle
			(at 0.40005 0)
			(size 0 0)
			(layers "F.Cu" "F.Mask" "F.Paste")
			(net "P3V3_SSD4_PG_G1")
		)
	)
	(footprint ""
		(layer "F.Cu")
		(at 376.809 -179.451)
		(property "Reference" "R4719"
			(at 0 0 0)
			(layer "F.SilkS")
			(hide yes)
			(effects
				(font
					(size 1.27 1.27)
				)
			)
		)
		(property "Value" ""
			(at 0 0 0)
			(layer "F.Fab")
			(effects
				(font
					(size 1.27 1.27)
				)
			)
		)
		(duplicate_pad_numbers_are_jumpers no)
		(fp_line
			(start -0.7874 -0.4064)
			(end 0.7874 -0.4064)
			(stroke
				(width 0.1524)
				(type default)
			)
			(layer "F.SilkS")
		)
		(fp_line
			(start -0.7874 0.4064)
			(end -0.7874 -0.4064)
			(stroke
				(width 0.1524)
				(type default)
			)
			(layer "F.SilkS")
		)
		(fp_line
			(start 0.7874 -0.4064)
			(end 0.7874 0.4064)
			(stroke
				(width 0.1524)
				(type default)
			)
			(layer "F.SilkS")
		)
		(fp_line
			(start 0.7874 0.4064)
			(end -0.7874 0.4064)
			(stroke
				(width 0.1524)
				(type default)
			)
			(layer "F.SilkS")
		)
		(fp_line
			(start -0.67945 -0.305054)
			(end -0.12065 -0.305054)
			(stroke
				(width 0.1)
				(type default)
			)
			(layer "F.Fab")
		)
		(fp_line
			(start -0.67945 0.3048)
			(end -0.67945 -0.305054)
			(stroke
				(width 0.1)
				(type default)
			)
			(layer "F.Fab")
		)
		(fp_line
			(start -0.12065 -0.305054)
			(end -0.12065 -0.2794)
			(stroke
				(width 0.1)
				(type default)
			)
			(layer "F.Fab")
		)
		(fp_line
			(start -0.12065 -0.2794)
			(end 0.12065 -0.2794)
			(stroke
				(width 0.1)
				(type default)
			)
			(layer "F.Fab")
		)
		(fp_line
			(start -0.12065 0.2794)
			(end -0.12065 0.3048)
			(stroke
				(width 0.1)
				(type default)
			)
			(layer "F.Fab")
		)
		(fp_line
			(start -0.12065 0.3048)
			(end -0.67945 0.3048)
			(stroke
				(width 0.1)
				(type default)
			)
			(layer "F.Fab")
		)
		(fp_line
			(start 0.120396 0.2794)
			(end -0.12065 0.2794)
			(stroke
				(width 0.1)
				(type default)
			)
			(layer "F.Fab")
		)
		(fp_line
			(start 0.120396 0.3048)
			(end 0.120396 0.2794)
			(stroke
				(width 0.1)
				(type default)
			)
			(layer "F.Fab")
		)
		(fp_line
			(start 0.12065 -0.3048)
			(end 0.67945 -0.3048)
			(stroke
				(width 0.1)
				(type default)
			)
			(layer "F.Fab")
		)
		(fp_line
			(start 0.12065 -0.2794)
			(end 0.12065 -0.3048)
			(stroke
				(width 0.1)
				(type default)
			)
			(layer "F.Fab")
		)
		(fp_line
			(start 0.67945 -0.3048)
			(end 0.67945 0.3048)
			(stroke
				(width 0.1)
				(type default)
			)
			(layer "F.Fab")
		)
		(fp_line
			(start 0.67945 0.3048)
			(end 0.120396 0.3048)
			(stroke
				(width 0.1)
				(type default)
			)
			(layer "F.Fab")
		)
		(pad "1" smd circle
			(at -0.40005 0)
			(size 0 0)
			(layers "F.Cu" "F.Mask" "F.Paste")
			(net "GND")
		)
		(pad "2" smd circle
			(at 0.40005 0)
			(size 0 0)
			(layers "F.Cu" "F.Mask" "F.Paste")
			(net "PCA9555_1_PEX1_A0")
		)
	)
	(footprint ""
		(layer "F.Cu")
		(at 224.022158 -87.716868)
		(property "Reference" "R4263"
			(at 0 0 0)
			(layer "F.SilkS")
			(hide yes)
			(effects
				(font
					(size 1.27 1.27)
				)
			)
		)
		(property "Value" ""
			(at 0 0 0)
			(layer "F.Fab")
			(effects
				(font
					(size 1.27 1.27)
				)
			)
		)
		(duplicate_pad_numbers_are_jumpers no)
		(fp_line
			(start -0.7874 -0.4064)
			(end 0.7874 -0.4064)
			(stroke
				(width 0.1524)
				(type default)
			)
			(layer "F.SilkS")
		)
		(fp_line
			(start -0.7874 0.4064)
			(end -0.7874 -0.4064)
			(stroke
				(width 0.1524)
				(type default)
			)
			(layer "F.SilkS")
		)
		(fp_line
			(start 0.7874 -0.4064)
			(end 0.7874 0.4064)
			(stroke
				(width 0.1524)
				(type default)
			)
			(layer "F.SilkS")
		)
		(fp_line
			(start 0.7874 0.4064)
			(end -0.7874 0.4064)
			(stroke
				(width 0.1524)
				(type default)
			)
			(layer "F.SilkS")
		)
		(fp_line
			(start -0.67945 -0.305054)
			(end -0.12065 -0.305054)
			(stroke
				(width 0.1)
				(type default)
			)
			(layer "F.Fab")
		)
		(fp_line
			(start -0.67945 0.3048)
			(end -0.67945 -0.305054)
			(stroke
				(width 0.1)
				(type default)
			)
			(layer "F.Fab")
		)
		(fp_line
			(start -0.12065 -0.305054)
			(end -0.12065 -0.2794)
			(stroke
				(width 0.1)
				(type default)
			)
			(layer "F.Fab")
		)
		(fp_line
			(start -0.12065 -0.2794)
			(end 0.12065 -0.2794)
			(stroke
				(width 0.1)
				(type default)
			)
			(layer "F.Fab")
		)
		(fp_line
			(start -0.12065 0.2794)
			(end -0.12065 0.3048)
			(stroke
				(width 0.1)
				(type default)
			)
			(layer "F.Fab")
		)
		(fp_line
			(start -0.12065 0.3048)
			(end -0.67945 0.3048)
			(stroke
				(width 0.1)
				(type default)
			)
			(layer "F.Fab")
		)
		(fp_line
			(start 0.120396 0.2794)
			(end -0.12065 0.2794)
			(stroke
				(width 0.1)
				(type default)
			)
			(layer "F.Fab")
		)
		(fp_line
			(start 0.120396 0.3048)
			(end 0.120396 0.2794)
			(stroke
				(width 0.1)
				(type default)
			)
			(layer "F.Fab")
		)
		(fp_line
			(start 0.12065 -0.3048)
			(end 0.67945 -0.3048)
			(stroke
				(width 0.1)
				(type default)
			)
			(layer "F.Fab")
		)
		(fp_line
			(start 0.12065 -0.2794)
			(end 0.12065 -0.3048)
			(stroke
				(width 0.1)
				(type default)
			)
			(layer "F.Fab")
		)
		(fp_line
			(start 0.67945 -0.3048)
			(end 0.67945 0.3048)
			(stroke
				(width 0.1)
				(type default)
			)
			(layer "F.Fab")
		)
		(fp_line
			(start 0.67945 0.3048)
			(end 0.120396 0.3048)
			(stroke
				(width 0.1)
				(type default)
			)
			(layer "F.Fab")
		)
		(pad "1" smd circle
			(at -0.40005 0)
			(size 0 0)
			(layers "F.Cu" "F.Mask" "F.Paste")
			(net "SMB_SSD_LED_IOEXP_SDA")
		)
		(pad "2" smd circle
			(at 0.40005 0)
			(size 0 0)
			(layers "F.Cu" "F.Mask" "F.Paste")
			(net "SMB_BIC_I2C6_R_SDA")
		)
	)
	(footprint ""
		(layer "F.Cu")
		(at 139.817348 -356.244906 90)
		(property "Reference" "C2261"
			(at 0 0 90)
			(layer "F.SilkS")
			(hide yes)
			(effects
				(font
					(size 1.27 1.27)
				)
			)
		)
		(property "Value" ""
			(at 0 0 90)
			(layer "F.Fab")
			(effects
				(font
					(size 1.27 1.27)
				)
			)
		)
		(duplicate_pad_numbers_are_jumpers no)
		(fp_line
			(start 0.299974 -0.150114)
			(end 0.299974 0.150114)
			(stroke
				(width 0.1)
				(type default)
			)
			(layer "F.Fab")
		)
		(fp_line
			(start -0.299974 -0.150114)
			(end 0.299974 -0.150114)
			(stroke
				(width 0.1)
				(type default)
			)
			(layer "F.Fab")
		)
		(fp_line
			(start 0.299974 0.150114)
			(end -0.299974 0.150114)
			(stroke
				(width 0.1)
				(type default)
			)
			(layer "F.Fab")
		)
		(fp_line
			(start -0.299974 0.150114)
			(end -0.299974 -0.150114)
			(stroke
				(width 0.1)
				(type default)
			)
			(layer "F.Fab")
		)
		(pad "1" smd rect
			(at -0.2667 0 90)
			(size 0.3048 0.381)
			(layers "F.Cu" "F.Mask" "F.Paste")
			(net "P5E_PEX1_STN5_TX_DP<86>")
		)
		(pad "2" smd rect
			(at 0.2667 0 90)
			(size 0.3048 0.381)
			(layers "F.Cu" "F.Mask" "F.Paste")
			(net "P5E_PEX1_STN5_TX_C_DP<86>")
		)
	)
	(footprint ""
		(layer "F.Cu")
		(at 379.998732 -309.570628 45)
		(property "Reference" "R1420"
			(at 0 0 45)
			(layer "F.SilkS")
			(hide yes)
			(effects
				(font
					(size 1.27 1.27)
				)
			)
		)
		(property "Value" ""
			(at 0 0 45)
			(layer "F.Fab")
			(effects
				(font
					(size 1.27 1.27)
				)
			)
		)
		(duplicate_pad_numbers_are_jumpers no)
		(fp_line
			(start -0.787389 -0.406267)
			(end 0.787389 -0.406267)
			(stroke
				(width 0.1524)
				(type default)
			)
			(layer "F.SilkS")
		)
		(fp_line
			(start -0.787389 0.406267)
			(end -0.787389 -0.406267)
			(stroke
				(width 0.1524)
				(type default)
			)
			(layer "F.SilkS")
		)
		(fp_line
			(start 0.787389 -0.406267)
			(end 0.787389 0.406267)
			(stroke
				(width 0.1524)
				(type default)
			)
			(layer "F.SilkS")
		)
		(fp_line
			(start 0.787389 0.406267)
			(end -0.787389 0.406267)
			(stroke
				(width 0.1524)
				(type default)
			)
			(layer "F.SilkS")
		)
		(fp_line
			(start -0.679446 -0.305149)
			(end -0.120695 -0.304969)
			(stroke
				(width 0.1)
				(type default)
			)
			(layer "F.Fab")
		)
		(fp_line
			(start -0.120695 -0.304969)
			(end -0.120695 -0.279466)
			(stroke
				(width 0.1)
				(type default)
			)
			(layer "F.Fab")
		)
		(fp_line
			(start -0.120695 -0.279466)
			(end 0.120695 -0.279466)
			(stroke
				(width 0.1)
				(type default)
			)
			(layer "F.Fab")
		)
		(fp_line
			(start -0.679446 0.30479)
			(end -0.679446 -0.305149)
			(stroke
				(width 0.1)
				(type default)
			)
			(layer "F.Fab")
		)
		(fp_line
			(start 0.120515 -0.30479)
			(end 0.679446 -0.30479)
			(stroke
				(width 0.1)
				(type default)
			)
			(layer "F.Fab")
		)
		(fp_line
			(start 0.120695 -0.279466)
			(end 0.120515 -0.30479)
			(stroke
				(width 0.1)
				(type default)
			)
			(layer "F.Fab")
		)
		(fp_line
			(start -0.120695 0.279466)
			(end -0.120515 0.30479)
			(stroke
				(width 0.1)
				(type default)
			)
			(layer "F.Fab")
		)
		(fp_line
			(start -0.120515 0.30479)
			(end -0.679446 0.30479)
			(stroke
				(width 0.1)
				(type default)
			)
			(layer "F.Fab")
		)
		(fp_line
			(start 0.679446 -0.30479)
			(end 0.679446 0.30479)
			(stroke
				(width 0.1)
				(type default)
			)
			(layer "F.Fab")
		)
		(fp_line
			(start 0.120335 0.279466)
			(end -0.120695 0.279466)
			(stroke
				(width 0.1)
				(type default)
			)
			(layer "F.Fab")
		)
		(fp_line
			(start 0.120515 0.30479)
			(end 0.120335 0.279466)
			(stroke
				(width 0.1)
				(type default)
			)
			(layer "F.Fab")
		)
		(fp_line
			(start 0.679446 0.30479)
			(end 0.120515 0.30479)
			(stroke
				(width 0.1)
				(type default)
			)
			(layer "F.Fab")
		)
		(pad "1" smd circle
			(at -0.40005 0 45)
			(size 0 0)
			(layers "F.Cu" "F.Mask" "F.Paste")
			(net "GND")
		)
		(pad "2" smd circle
			(at 0.40005 0 45)
			(size 0 0)
			(layers "F.Cu" "F.Mask" "F.Paste")
			(net "PEX3_DBG_MODE0")
		)
	)
	(footprint ""
		(layer "F.Cu")
		(at 175.0949 -100.766372 180)
		(property "Reference" "R180"
			(at 0 0 180)
			(layer "F.SilkS")
			(hide yes)
			(effects
				(font
					(size 1.27 1.27)
				)
			)
		)
		(property "Value" ""
			(at 0 0 180)
			(layer "F.Fab")
			(effects
				(font
					(size 1.27 1.27)
				)
			)
		)
		(duplicate_pad_numbers_are_jumpers no)
		(fp_line
			(start 0.7874 0.4064)
			(end -0.7874 0.4064)
			(stroke
				(width 0.1524)
				(type default)
			)
			(layer "F.SilkS")
		)
		(fp_line
			(start 0.7874 -0.4064)
			(end 0.7874 0.4064)
			(stroke
				(width 0.1524)
				(type default)
			)
			(layer "F.SilkS")
		)
		(fp_line
			(start -0.7874 0.4064)
			(end -0.7874 -0.4064)
			(stroke
				(width 0.1524)
				(type default)
			)
			(layer "F.SilkS")
		)
		(fp_line
			(start -0.7874 -0.4064)
			(end 0.7874 -0.4064)
			(stroke
				(width 0.1524)
				(type default)
			)
			(layer "F.SilkS")
		)
		(fp_line
			(start 0.67945 0.3048)
			(end 0.120396 0.3048)
			(stroke
				(width 0.1)
				(type default)
			)
			(layer "F.Fab")
		)
		(fp_line
			(start 0.67945 -0.3048)
			(end 0.67945 0.3048)
			(stroke
				(width 0.1)
				(type default)
			)
			(layer "F.Fab")
		)
		(fp_line
			(start 0.12065 -0.2794)
			(end 0.12065 -0.3048)
			(stroke
				(width 0.1)
				(type default)
			)
			(layer "F.Fab")
		)
		(fp_line
			(start 0.12065 -0.3048)
			(end 0.67945 -0.3048)
			(stroke
				(width 0.1)
				(type default)
			)
			(layer "F.Fab")
		)
		(fp_line
			(start 0.120396 0.3048)
			(end 0.120396 0.2794)
			(stroke
				(width 0.1)
				(type default)
			)
			(layer "F.Fab")
		)
		(fp_line
			(start 0.120396 0.2794)
			(end -0.12065 0.2794)
			(stroke
				(width 0.1)
				(type default)
			)
			(layer "F.Fab")
		)
		(fp_line
			(start -0.12065 0.3048)
			(end -0.67945 0.3048)
			(stroke
				(width 0.1)
				(type default)
			)
			(layer "F.Fab")
		)
		(fp_line
			(start -0.12065 0.2794)
			(end -0.12065 0.3048)
			(stroke
				(width 0.1)
				(type default)
			)
			(layer "F.Fab")
		)
		(fp_line
			(start -0.12065 -0.2794)
			(end 0.12065 -0.2794)
			(stroke
				(width 0.1)
				(type default)
			)
			(layer "F.Fab")
		)
		(fp_line
			(start -0.12065 -0.305054)
			(end -0.12065 -0.2794)
			(stroke
				(width 0.1)
				(type default)
			)
			(layer "F.Fab")
		)
		(fp_line
			(start -0.67945 0.3048)
			(end -0.67945 -0.305054)
			(stroke
				(width 0.1)
				(type default)
			)
			(layer "F.Fab")
		)
		(fp_line
			(start -0.67945 -0.305054)
			(end -0.12065 -0.305054)
			(stroke
				(width 0.1)
				(type default)
			)
			(layer "F.Fab")
		)
		(pad "1" smd circle
			(at -0.40005 0 180)
			(size 0 0)
			(layers "F.Cu" "F.Mask" "F.Paste")
			(net "NIC3_SLOT_ID1")
		)
		(pad "2" smd circle
			(at 0.40005 0 180)
			(size 0 0)
			(layers "F.Cu" "F.Mask" "F.Paste")
			(net "P3V3_NIC3")
		)
	)
	(footprint ""
		(layer "F.Cu")
		(at 284.443678 -49.95291 180)
		(property "Reference" "R610"
			(at 0 0 180)
			(layer "F.SilkS")
			(hide yes)
			(effects
				(font
					(size 1.27 1.27)
				)
			)
		)
		(property "Value" ""
			(at 0 0 180)
			(layer "F.Fab")
			(effects
				(font
					(size 1.27 1.27)
				)
			)
		)
		(duplicate_pad_numbers_are_jumpers no)
		(fp_line
			(start 0.7874 0.4064)
			(end -0.7874 0.4064)
			(stroke
				(width 0.1524)
				(type default)
			)
			(layer "F.SilkS")
		)
		(fp_line
			(start 0.7874 -0.4064)
			(end 0.7874 0.4064)
			(stroke
				(width 0.1524)
				(type default)
			)
			(layer "F.SilkS")
		)
		(fp_line
			(start -0.7874 0.4064)
			(end -0.7874 -0.4064)
			(stroke
				(width 0.1524)
				(type default)
			)
			(layer "F.SilkS")
		)
		(fp_line
			(start -0.7874 -0.4064)
			(end 0.7874 -0.4064)
			(stroke
				(width 0.1524)
				(type default)
			)
			(layer "F.SilkS")
		)
		(fp_line
			(start 0.67945 0.3048)
			(end 0.120396 0.3048)
			(stroke
				(width 0.1)
				(type default)
			)
			(layer "F.Fab")
		)
		(fp_line
			(start 0.67945 -0.3048)
			(end 0.67945 0.3048)
			(stroke
				(width 0.1)
				(type default)
			)
			(layer "F.Fab")
		)
		(fp_line
			(start 0.12065 -0.2794)
			(end 0.12065 -0.3048)
			(stroke
				(width 0.1)
				(type default)
			)
			(layer "F.Fab")
		)
		(fp_line
			(start 0.12065 -0.3048)
			(end 0.67945 -0.3048)
			(stroke
				(width 0.1)
				(type default)
			)
			(layer "F.Fab")
		)
		(fp_line
			(start 0.120396 0.3048)
			(end 0.120396 0.2794)
			(stroke
				(width 0.1)
				(type default)
			)
			(layer "F.Fab")
		)
		(fp_line
			(start 0.120396 0.2794)
			(end -0.12065 0.2794)
			(stroke
				(width 0.1)
				(type default)
			)
			(layer "F.Fab")
		)
		(fp_line
			(start -0.12065 0.3048)
			(end -0.67945 0.3048)
			(stroke
				(width 0.1)
				(type default)
			)
			(layer "F.Fab")
		)
		(fp_line
			(start -0.12065 0.2794)
			(end -0.12065 0.3048)
			(stroke
				(width 0.1)
				(type default)
			)
			(layer "F.Fab")
		)
		(fp_line
			(start -0.12065 -0.2794)
			(end 0.12065 -0.2794)
			(stroke
				(width 0.1)
				(type default)
			)
			(layer "F.Fab")
		)
		(fp_line
			(start -0.12065 -0.305054)
			(end -0.12065 -0.2794)
			(stroke
				(width 0.1)
				(type default)
			)
			(layer "F.Fab")
		)
		(fp_line
			(start -0.67945 0.3048)
			(end -0.67945 -0.305054)
			(stroke
				(width 0.1)
				(type default)
			)
			(layer "F.Fab")
		)
		(fp_line
			(start -0.67945 -0.305054)
			(end -0.12065 -0.305054)
			(stroke
				(width 0.1)
				(type default)
			)
			(layer "F.Fab")
		)
		(pad "1" smd circle
			(at -0.40005 0 180)
			(size 0 0)
			(layers "F.Cu" "F.Mask" "F.Paste")
			(net "SMB_BIC_I2C6_MUX_SSD_8_15_ADC_R_SCL")
		)
		(pad "2" smd circle
			(at 0.40005 0 180)
			(size 0 0)
			(layers "F.Cu" "F.Mask" "F.Paste")
			(net "SMB_SSD9_ADC_SCL")
		)
	)
	(footprint ""
		(layer "F.Cu")
		(at 361.048808 -162.003994 90)
		(property "Reference" "PR7056"
			(at 0 0 90)
			(layer "F.SilkS")
			(hide yes)
			(effects
				(font
					(size 1.27 1.27)
				)
			)
		)
		(property "Value" ""
			(at 0 0 90)
			(layer "F.Fab")
			(effects
				(font
					(size 1.27 1.27)
				)
			)
		)
		(duplicate_pad_numbers_are_jumpers no)
		(fp_line
			(start 0.7874 -0.4064)
			(end 0.7874 0.4064)
			(stroke
				(width 0.1524)
				(type default)
			)
			(layer "F.SilkS")
		)
		(fp_line
			(start -0.7874 -0.4064)
			(end 0.7874 -0.4064)
			(stroke
				(width 0.1524)
				(type default)
			)
			(layer "F.SilkS")
		)
		(fp_line
			(start 0.7874 0.4064)
			(end -0.7874 0.4064)
			(stroke
				(width 0.1524)
				(type default)
			)
			(layer "F.SilkS")
		)
		(fp_line
			(start -0.7874 0.4064)
			(end -0.7874 -0.4064)
			(stroke
				(width 0.1524)
				(type default)
			)
			(layer "F.SilkS")
		)
		(fp_line
			(start -0.12065 -0.305054)
			(end -0.12065 -0.2794)
			(stroke
				(width 0.1)
				(type default)
			)
			(layer "F.Fab")
		)
		(fp_line
			(start -0.67945 -0.305054)
			(end -0.12065 -0.305054)
			(stroke
				(width 0.1)
				(type default)
			)
			(layer "F.Fab")
		)
		(fp_line
			(start 0.67945 -0.3048)
			(end 0.67945 0.3048)
			(stroke
				(width 0.1)
				(type default)
			)
			(layer "F.Fab")
		)
		(fp_line
			(start 0.12065 -0.3048)
			(end 0.67945 -0.3048)
			(stroke
				(width 0.1)
				(type default)
			)
			(layer "F.Fab")
		)
		(fp_line
			(start 0.12065 -0.2794)
			(end 0.12065 -0.3048)
			(stroke
				(width 0.1)
				(type default)
			)
			(layer "F.Fab")
		)
		(fp_line
			(start -0.12065 -0.2794)
			(end 0.12065 -0.2794)
			(stroke
				(width 0.1)
				(type default)
			)
			(layer "F.Fab")
		)
		(fp_line
			(start 0.120396 0.2794)
			(end -0.12065 0.2794)
			(stroke
				(width 0.1)
				(type default)
			)
			(layer "F.Fab")
		)
		(fp_line
			(start -0.12065 0.2794)
			(end -0.12065 0.3048)
			(stroke
				(width 0.1)
				(type default)
			)
			(layer "F.Fab")
		)
		(fp_line
			(start 0.67945 0.3048)
			(end 0.120396 0.3048)
			(stroke
				(width 0.1)
				(type default)
			)
			(layer "F.Fab")
		)
		(fp_line
			(start 0.120396 0.3048)
			(end 0.120396 0.2794)
			(stroke
				(width 0.1)
				(type default)
			)
			(layer "F.Fab")
		)
		(fp_line
			(start -0.12065 0.3048)
			(end -0.67945 0.3048)
			(stroke
				(width 0.1)
				(type default)
			)
			(layer "F.Fab")
		)
		(fp_line
			(start -0.67945 0.3048)
			(end -0.67945 -0.305054)
			(stroke
				(width 0.1)
				(type default)
			)
			(layer "F.Fab")
		)
		(pad "1" smd circle
			(at -0.40005 0 90)
			(size 0 0)
			(layers "F.Cu" "F.Mask" "F.Paste")
			(net "P12V_NIC6_CO_ISET")
		)
		(pad "2" smd circle
			(at 0.40005 0 90)
			(size 0 0)
			(layers "F.Cu" "F.Mask" "F.Paste")
			(net "GND")
		)
	)
	(footprint ""
		(layer "F.Cu")
		(at 134.738872 -22.867366 90)
		(property "Reference" "C3903"
			(at 0 0 90)
			(layer "F.SilkS")
			(hide yes)
			(effects
				(font
					(size 1.27 1.27)
				)
			)
		)
		(property "Value" ""
			(at 0 0 90)
			(layer "F.Fab")
			(effects
				(font
					(size 1.27 1.27)
				)
			)
		)
		(duplicate_pad_numbers_are_jumpers no)
		(fp_line
			(start 0.7874 -0.4064)
			(end 0.7874 0.4064)
			(stroke
				(width 0.1524)
				(type default)
			)
			(layer "F.SilkS")
		)
		(fp_line
			(start -0.7874 -0.4064)
			(end 0.7874 -0.4064)
			(stroke
				(width 0.1524)
				(type default)
			)
			(layer "F.SilkS")
		)
		(fp_line
			(start 0.7874 0.4064)
			(end -0.7874 0.4064)
			(stroke
				(width 0.1524)
				(type default)
			)
			(layer "F.SilkS")
		)
		(fp_line
			(start -0.7874 0.4064)
			(end -0.7874 -0.4064)
			(stroke
				(width 0.1524)
				(type default)
			)
			(layer "F.SilkS")
		)
		(fp_line
			(start -0.12065 -0.305054)
			(end -0.12065 -0.2794)
			(stroke
				(width 0.1)
				(type default)
			)
			(layer "F.Fab")
		)
		(fp_line
			(start -0.67945 -0.305054)
			(end -0.12065 -0.305054)
			(stroke
				(width 0.1)
				(type default)
			)
			(layer "F.Fab")
		)
		(fp_line
			(start 0.67945 -0.3048)
			(end 0.67945 0.3048)
			(stroke
				(width 0.1)
				(type default)
			)
			(layer "F.Fab")
		)
		(fp_line
			(start 0.12065 -0.3048)
			(end 0.67945 -0.3048)
			(stroke
				(width 0.1)
				(type default)
			)
			(layer "F.Fab")
		)
		(fp_line
			(start 0.12065 -0.2794)
			(end 0.12065 -0.3048)
			(stroke
				(width 0.1)
				(type default)
			)
			(layer "F.Fab")
		)
		(fp_line
			(start -0.12065 -0.2794)
			(end 0.12065 -0.2794)
			(stroke
				(width 0.1)
				(type default)
			)
			(layer "F.Fab")
		)
		(fp_line
			(start 0.120396 0.2794)
			(end -0.12065 0.2794)
			(stroke
				(width 0.1)
				(type default)
			)
			(layer "F.Fab")
		)
		(fp_line
			(start -0.12065 0.2794)
			(end -0.12065 0.3048)
			(stroke
				(width 0.1)
				(type default)
			)
			(layer "F.Fab")
		)
		(fp_line
			(start 0.67945 0.3048)
			(end 0.120396 0.3048)
			(stroke
				(width 0.1)
				(type default)
			)
			(layer "F.Fab")
		)
		(fp_line
			(start 0.120396 0.3048)
			(end 0.120396 0.2794)
			(stroke
				(width 0.1)
				(type default)
			)
			(layer "F.Fab")
		)
		(fp_line
			(start -0.12065 0.3048)
			(end -0.67945 0.3048)
			(stroke
				(width 0.1)
				(type default)
			)
			(layer "F.Fab")
		)
		(fp_line
			(start -0.67945 0.3048)
			(end -0.67945 -0.305054)
			(stroke
				(width 0.1)
				(type default)
			)
			(layer "F.Fab")
		)
		(pad "1" smd circle
			(at -0.40005 0 90)
			(size 0 0)
			(layers "F.Cu" "F.Mask" "F.Paste")
			(net "P12V_SSD4")
		)
		(pad "2" smd circle
			(at 0.40005 0 90)
			(size 0 0)
			(layers "F.Cu" "F.Mask" "F.Paste")
			(net "GND")
		)
	)
	(footprint ""
		(layer "F.Cu")
		(at 244.811042 -257.99796 -90)
		(property "Reference" "R6530"
			(at 0 0 270)
			(layer "F.SilkS")
			(hide yes)
			(effects
				(font
					(size 1.27 1.27)
				)
			)
		)
		(property "Value" ""
			(at 0 0 270)
			(layer "F.Fab")
			(effects
				(font
					(size 1.27 1.27)
				)
			)
		)
		(duplicate_pad_numbers_are_jumpers no)
		(fp_line
			(start -0.7874 0.4064)
			(end -0.7874 -0.4064)
			(stroke
				(width 0.1524)
				(type default)
			)
			(layer "F.SilkS")
		)
		(fp_line
			(start 0.7874 0.4064)
			(end -0.7874 0.4064)
			(stroke
				(width 0.1524)
				(type default)
			)
			(layer "F.SilkS")
		)
		(fp_line
			(start -0.7874 -0.4064)
			(end 0.7874 -0.4064)
			(stroke
				(width 0.1524)
				(type default)
			)
			(layer "F.SilkS")
		)
		(fp_line
			(start 0.7874 -0.4064)
			(end 0.7874 0.4064)
			(stroke
				(width 0.1524)
				(type default)
			)
			(layer "F.SilkS")
		)
		(fp_line
			(start -0.67945 0.3048)
			(end -0.67945 -0.305054)
			(stroke
				(width 0.1)
				(type default)
			)
			(layer "F.Fab")
		)
		(fp_line
			(start -0.12065 0.3048)
			(end -0.67945 0.3048)
			(stroke
				(width 0.1)
				(type default)
			)
			(layer "F.Fab")
		)
		(fp_line
			(start 0.120396 0.3048)
			(end 0.120396 0.2794)
			(stroke
				(width 0.1)
				(type default)
			)
			(layer "F.Fab")
		)
		(fp_line
			(start 0.67945 0.3048)
			(end 0.120396 0.3048)
			(stroke
				(width 0.1)
				(type default)
			)
			(layer "F.Fab")
		)
		(fp_line
			(start -0.12065 0.2794)
			(end -0.12065 0.3048)
			(stroke
				(width 0.1)
				(type default)
			)
			(layer "F.Fab")
		)
		(fp_line
			(start 0.120396 0.2794)
			(end -0.12065 0.2794)
			(stroke
				(width 0.1)
				(type default)
			)
			(layer "F.Fab")
		)
		(fp_line
			(start -0.12065 -0.2794)
			(end 0.12065 -0.2794)
			(stroke
				(width 0.1)
				(type default)
			)
			(layer "F.Fab")
		)
		(fp_line
			(start 0.12065 -0.2794)
			(end 0.12065 -0.3048)
			(stroke
				(width 0.1)
				(type default)
			)
			(layer "F.Fab")
		)
		(fp_line
			(start 0.12065 -0.3048)
			(end 0.67945 -0.3048)
			(stroke
				(width 0.1)
				(type default)
			)
			(layer "F.Fab")
		)
		(fp_line
			(start 0.67945 -0.3048)
			(end 0.67945 0.3048)
			(stroke
				(width 0.1)
				(type default)
			)
			(layer "F.Fab")
		)
		(fp_line
			(start -0.67945 -0.305054)
			(end -0.12065 -0.305054)
			(stroke
				(width 0.1)
				(type default)
			)
			(layer "F.Fab")
		)
		(fp_line
			(start -0.12065 -0.305054)
			(end -0.12065 -0.2794)
			(stroke
				(width 0.1)
				(type default)
			)
			(layer "F.Fab")
		)
		(pad "1" smd circle
			(at -0.40005 0 270)
			(size 0 0)
			(layers "F.Cu" "F.Mask" "F.Paste")
			(net "P1V25_SERDES_VDDPLL_PEX2")
		)
		(pad "2" smd circle
			(at 0.40005 0 270)
			(size 0 0)
			(layers "F.Cu" "F.Mask" "F.Paste")
			(net "P1V25_SERDES_VDDPLL_PEX2_C7")
		)
	)
	(footprint ""
		(layer "F.Cu")
		(at 393.022582 -44.341542 90)
		(property "Reference" "R657"
			(at 0 0 90)
			(layer "F.SilkS")
			(hide yes)
			(effects
				(font
					(size 1.27 1.27)
				)
			)
		)
		(property "Value" ""
			(at 0 0 90)
			(layer "F.Fab")
			(effects
				(font
					(size 1.27 1.27)
				)
			)
		)
		(duplicate_pad_numbers_are_jumpers no)
		(fp_line
			(start 0.7874 -0.4064)
			(end 0.7874 0.4064)
			(stroke
				(width 0.1524)
				(type default)
			)
			(layer "F.SilkS")
		)
		(fp_line
			(start -0.7874 -0.4064)
			(end 0.7874 -0.4064)
			(stroke
				(width 0.1524)
				(type default)
			)
			(layer "F.SilkS")
		)
		(fp_line
			(start 0.7874 0.4064)
			(end -0.7874 0.4064)
			(stroke
				(width 0.1524)
				(type default)
			)
			(layer "F.SilkS")
		)
		(fp_line
			(start -0.7874 0.4064)
			(end -0.7874 -0.4064)
			(stroke
				(width 0.1524)
				(type default)
			)
			(layer "F.SilkS")
		)
		(fp_line
			(start -0.12065 -0.305054)
			(end -0.12065 -0.2794)
			(stroke
				(width 0.1)
				(type default)
			)
			(layer "F.Fab")
		)
		(fp_line
			(start -0.67945 -0.305054)
			(end -0.12065 -0.305054)
			(stroke
				(width 0.1)
				(type default)
			)
			(layer "F.Fab")
		)
		(fp_line
			(start 0.67945 -0.3048)
			(end 0.67945 0.3048)
			(stroke
				(width 0.1)
				(type default)
			)
			(layer "F.Fab")
		)
		(fp_line
			(start 0.12065 -0.3048)
			(end 0.67945 -0.3048)
			(stroke
				(width 0.1)
				(type default)
			)
			(layer "F.Fab")
		)
		(fp_line
			(start 0.12065 -0.2794)
			(end 0.12065 -0.3048)
			(stroke
				(width 0.1)
				(type default)
			)
			(layer "F.Fab")
		)
		(fp_line
			(start -0.12065 -0.2794)
			(end 0.12065 -0.2794)
			(stroke
				(width 0.1)
				(type default)
			)
			(layer "F.Fab")
		)
		(fp_line
			(start 0.120396 0.2794)
			(end -0.12065 0.2794)
			(stroke
				(width 0.1)
				(type default)
			)
			(layer "F.Fab")
		)
		(fp_line
			(start -0.12065 0.2794)
			(end -0.12065 0.3048)
			(stroke
				(width 0.1)
				(type default)
			)
			(layer "F.Fab")
		)
		(fp_line
			(start 0.67945 0.3048)
			(end 0.120396 0.3048)
			(stroke
				(width 0.1)
				(type default)
			)
			(layer "F.Fab")
		)
		(fp_line
			(start 0.120396 0.3048)
			(end 0.120396 0.2794)
			(stroke
				(width 0.1)
				(type default)
			)
			(layer "F.Fab")
		)
		(fp_line
			(start -0.12065 0.3048)
			(end -0.67945 0.3048)
			(stroke
				(width 0.1)
				(type default)
			)
			(layer "F.Fab")
		)
		(fp_line
			(start -0.67945 0.3048)
			(end -0.67945 -0.305054)
			(stroke
				(width 0.1)
				(type default)
			)
			(layer "F.Fab")
		)
		(pad "1" smd circle
			(at -0.40005 0 90)
			(size 0 0)
			(layers "F.Cu" "F.Mask" "F.Paste")
			(net "P12V_SSD13")
		)
		(pad "2" smd circle
			(at 0.40005 0 90)
			(size 0 0)
			(layers "F.Cu" "F.Mask" "F.Paste")
			(net "P12V_SSD13_VIN_N")
		)
	)
	(footprint ""
		(layer "F.Cu")
		(at 424.573954 -26.31186 -90)
		(property "Reference" "U406"
			(at 0.20066 -2.401316 90)
			(unlocked yes)
			(layer "F.SilkS")
			(effects
				(font
					(size 0.7874 0.5842)
					(thickness 0.1524)
				)
			)
		)
		(property "Value" ""
			(at 0 0 270)
			(layer "F.Fab")
			(effects
				(font
					(size 1.27 1.27)
				)
			)
		)
		(duplicate_pad_numbers_are_jumpers no)
		(fp_line
			(start -1.949958 1.610106)
			(end -1.949958 -1.610106)
			(stroke
				(width 0.1524)
				(type default)
			)
			(layer "F.SilkS")
		)
		(fp_line
			(start 1.949958 1.610106)
			(end -1.949958 1.610106)
			(stroke
				(width 0.1524)
				(type default)
			)
			(layer "F.SilkS")
		)
		(fp_line
			(start 1.949958 -1.560068)
			(end 1.949958 1.610106)
			(stroke
				(width 0.1524)
				(type default)
			)
			(layer "F.SilkS")
		)
		(fp_line
			(start -1.949958 -1.610106)
			(end 1.949958 -1.610106)
			(stroke
				(width 0.1524)
				(type default)
			)
			(layer "F.SilkS")
		)
		(fp_line
			(start -0.750062 1.560068)
			(end -0.750062 -1.560068)
			(stroke
				(width 0.1)
				(type default)
			)
			(layer "F.Fab")
		)
		(fp_line
			(start 0.750062 1.560068)
			(end -0.750062 1.560068)
			(stroke
				(width 0.1)
				(type default)
			)
			(layer "F.Fab")
		)
		(fp_line
			(start -0.750062 -1.560068)
			(end 0.750062 -1.560068)
			(stroke
				(width 0.1)
				(type default)
			)
			(layer "F.Fab")
		)
		(fp_line
			(start 0.750062 -1.560068)
			(end 0.750062 1.560068)
			(stroke
				(width 0.1)
				(type default)
			)
			(layer "F.Fab")
		)
		(pad "D" smd rect
			(at 1.100074 0 180)
			(size 1.016 1.4224)
			(layers "F.Cu" "F.Mask" "F.Paste")
			(net "SSD14_LED_ISO_N")
		)
		(pad "G" smd rect
			(at -1.100074 -0.94996 180)
			(size 1.016 1.4224)
			(layers "F.Cu" "F.Mask" "F.Paste")
			(net "SSD14_LED_R")
		)
		(pad "S" smd rect
			(at -1.100074 0.94996 180)
			(size 1.016 1.4224)
			(layers "F.Cu" "F.Mask" "F.Paste")
			(net "GND")
		)
	)
	(footprint ""
		(layer "F.Cu")
		(at 355.913436 -138.360404 180)
		(property "Reference" "R4451"
			(at 0 0 180)
			(layer "F.SilkS")
			(hide yes)
			(effects
				(font
					(size 1.27 1.27)
				)
			)
		)
		(property "Value" ""
			(at 0 0 180)
			(layer "F.Fab")
			(effects
				(font
					(size 1.27 1.27)
				)
			)
		)
		(duplicate_pad_numbers_are_jumpers no)
		(fp_line
			(start 0.7874 0.4064)
			(end -0.7874 0.4064)
			(stroke
				(width 0.1524)
				(type default)
			)
			(layer "F.SilkS")
		)
		(fp_line
			(start 0.7874 -0.4064)
			(end 0.7874 0.4064)
			(stroke
				(width 0.1524)
				(type default)
			)
			(layer "F.SilkS")
		)
		(fp_line
			(start -0.7874 0.4064)
			(end -0.7874 -0.4064)
			(stroke
				(width 0.1524)
				(type default)
			)
			(layer "F.SilkS")
		)
		(fp_line
			(start -0.7874 -0.4064)
			(end 0.7874 -0.4064)
			(stroke
				(width 0.1524)
				(type default)
			)
			(layer "F.SilkS")
		)
		(fp_line
			(start 0.67945 0.3048)
			(end 0.120396 0.3048)
			(stroke
				(width 0.1)
				(type default)
			)
			(layer "F.Fab")
		)
		(fp_line
			(start 0.67945 -0.3048)
			(end 0.67945 0.3048)
			(stroke
				(width 0.1)
				(type default)
			)
			(layer "F.Fab")
		)
		(fp_line
			(start 0.12065 -0.2794)
			(end 0.12065 -0.3048)
			(stroke
				(width 0.1)
				(type default)
			)
			(layer "F.Fab")
		)
		(fp_line
			(start 0.12065 -0.3048)
			(end 0.67945 -0.3048)
			(stroke
				(width 0.1)
				(type default)
			)
			(layer "F.Fab")
		)
		(fp_line
			(start 0.120396 0.3048)
			(end 0.120396 0.2794)
			(stroke
				(width 0.1)
				(type default)
			)
			(layer "F.Fab")
		)
		(fp_line
			(start 0.120396 0.2794)
			(end -0.12065 0.2794)
			(stroke
				(width 0.1)
				(type default)
			)
			(layer "F.Fab")
		)
		(fp_line
			(start -0.12065 0.3048)
			(end -0.67945 0.3048)
			(stroke
				(width 0.1)
				(type default)
			)
			(layer "F.Fab")
		)
		(fp_line
			(start -0.12065 0.2794)
			(end -0.12065 0.3048)
			(stroke
				(width 0.1)
				(type default)
			)
			(layer "F.Fab")
		)
		(fp_line
			(start -0.12065 -0.2794)
			(end 0.12065 -0.2794)
			(stroke
				(width 0.1)
				(type default)
			)
			(layer "F.Fab")
		)
		(fp_line
			(start -0.12065 -0.305054)
			(end -0.12065 -0.2794)
			(stroke
				(width 0.1)
				(type default)
			)
			(layer "F.Fab")
		)
		(fp_line
			(start -0.67945 0.3048)
			(end -0.67945 -0.305054)
			(stroke
				(width 0.1)
				(type default)
			)
			(layer "F.Fab")
		)
		(fp_line
			(start -0.67945 -0.305054)
			(end -0.12065 -0.305054)
			(stroke
				(width 0.1)
				(type default)
			)
			(layer "F.Fab")
		)
		(pad "1" smd circle
			(at -0.40005 0 180)
			(size 0 0)
			(layers "F.Cu" "F.Mask" "F.Paste")
			(net "PWRGD_P12V_NIC6")
		)
		(pad "2" smd circle
			(at 0.40005 0 180)
			(size 0 0)
			(layers "F.Cu" "F.Mask" "F.Paste")
			(net "PWRGD_P12V_NIC6_R")
		)
	)
	(footprint ""
		(layer "F.Cu")
		(at 372.574058 -26.31186 -90)
		(property "Reference" "U408"
			(at 0.09906 -2.331212 90)
			(unlocked yes)
			(layer "F.SilkS")
			(effects
				(font
					(size 0.7874 0.5842)
					(thickness 0.1524)
				)
			)
		)
		(property "Value" ""
			(at 0 0 270)
			(layer "F.Fab")
			(effects
				(font
					(size 1.27 1.27)
				)
			)
		)
		(duplicate_pad_numbers_are_jumpers no)
		(fp_line
			(start -1.949958 1.610106)
			(end -1.949958 -1.610106)
			(stroke
				(width 0.1524)
				(type default)
			)
			(layer "F.SilkS")
		)
		(fp_line
			(start 1.949958 1.610106)
			(end -1.949958 1.610106)
			(stroke
				(width 0.1524)
				(type default)
			)
			(layer "F.SilkS")
		)
		(fp_line
			(start 1.949958 -1.560068)
			(end 1.949958 1.610106)
			(stroke
				(width 0.1524)
				(type default)
			)
			(layer "F.SilkS")
		)
		(fp_line
			(start -1.949958 -1.610106)
			(end 1.949958 -1.610106)
			(stroke
				(width 0.1524)
				(type default)
			)
			(layer "F.SilkS")
		)
		(fp_line
			(start -0.750062 1.560068)
			(end -0.750062 -1.560068)
			(stroke
				(width 0.1)
				(type default)
			)
			(layer "F.Fab")
		)
		(fp_line
			(start 0.750062 1.560068)
			(end -0.750062 1.560068)
			(stroke
				(width 0.1)
				(type default)
			)
			(layer "F.Fab")
		)
		(fp_line
			(start -0.750062 -1.560068)
			(end 0.750062 -1.560068)
			(stroke
				(width 0.1)
				(type default)
			)
			(layer "F.Fab")
		)
		(fp_line
			(start 0.750062 -1.560068)
			(end 0.750062 1.560068)
			(stroke
				(width 0.1)
				(type default)
			)
			(layer "F.Fab")
		)
		(pad "D" smd rect
			(at 1.100074 0 180)
			(size 1.016 1.4224)
			(layers "F.Cu" "F.Mask" "F.Paste")
			(net "SSD12_LED_ISO_N")
		)
		(pad "G" smd rect
			(at -1.100074 -0.94996 180)
			(size 1.016 1.4224)
			(layers "F.Cu" "F.Mask" "F.Paste")
			(net "SSD12_LED_R")
		)
		(pad "S" smd rect
			(at -1.100074 0.94996 180)
			(size 1.016 1.4224)
			(layers "F.Cu" "F.Mask" "F.Paste")
			(net "GND")
		)
	)
	(footprint ""
		(layer "F.Cu")
		(at 261.622286 -252.356874 -90)
		(property "Reference" "R1359"
			(at 0 0 270)
			(layer "F.SilkS")
			(hide yes)
			(effects
				(font
					(size 1.27 1.27)
				)
			)
		)
		(property "Value" ""
			(at 0 0 270)
			(layer "F.Fab")
			(effects
				(font
					(size 1.27 1.27)
				)
			)
		)
		(duplicate_pad_numbers_are_jumpers no)
		(fp_line
			(start -0.7874 0.4064)
			(end -0.7874 -0.4064)
			(stroke
				(width 0.1524)
				(type default)
			)
			(layer "F.SilkS")
		)
		(fp_line
			(start 0.7874 0.4064)
			(end -0.7874 0.4064)
			(stroke
				(width 0.1524)
				(type default)
			)
			(layer "F.SilkS")
		)
		(fp_line
			(start -0.7874 -0.4064)
			(end 0.7874 -0.4064)
			(stroke
				(width 0.1524)
				(type default)
			)
			(layer "F.SilkS")
		)
		(fp_line
			(start 0.7874 -0.4064)
			(end 0.7874 0.4064)
			(stroke
				(width 0.1524)
				(type default)
			)
			(layer "F.SilkS")
		)
		(fp_line
			(start -0.67945 0.3048)
			(end -0.67945 -0.305054)
			(stroke
				(width 0.1)
				(type default)
			)
			(layer "F.Fab")
		)
		(fp_line
			(start -0.12065 0.3048)
			(end -0.67945 0.3048)
			(stroke
				(width 0.1)
				(type default)
			)
			(layer "F.Fab")
		)
		(fp_line
			(start 0.120396 0.3048)
			(end 0.120396 0.2794)
			(stroke
				(width 0.1)
				(type default)
			)
			(layer "F.Fab")
		)
		(fp_line
			(start 0.67945 0.3048)
			(end 0.120396 0.3048)
			(stroke
				(width 0.1)
				(type default)
			)
			(layer "F.Fab")
		)
		(fp_line
			(start -0.12065 0.2794)
			(end -0.12065 0.3048)
			(stroke
				(width 0.1)
				(type default)
			)
			(layer "F.Fab")
		)
		(fp_line
			(start 0.120396 0.2794)
			(end -0.12065 0.2794)
			(stroke
				(width 0.1)
				(type default)
			)
			(layer "F.Fab")
		)
		(fp_line
			(start -0.12065 -0.2794)
			(end 0.12065 -0.2794)
			(stroke
				(width 0.1)
				(type default)
			)
			(layer "F.Fab")
		)
		(fp_line
			(start 0.12065 -0.2794)
			(end 0.12065 -0.3048)
			(stroke
				(width 0.1)
				(type default)
			)
			(layer "F.Fab")
		)
		(fp_line
			(start 0.12065 -0.3048)
			(end 0.67945 -0.3048)
			(stroke
				(width 0.1)
				(type default)
			)
			(layer "F.Fab")
		)
		(fp_line
			(start 0.67945 -0.3048)
			(end 0.67945 0.3048)
			(stroke
				(width 0.1)
				(type default)
			)
			(layer "F.Fab")
		)
		(fp_line
			(start -0.67945 -0.305054)
			(end -0.12065 -0.305054)
			(stroke
				(width 0.1)
				(type default)
			)
			(layer "F.Fab")
		)
		(fp_line
			(start -0.12065 -0.305054)
			(end -0.12065 -0.2794)
			(stroke
				(width 0.1)
				(type default)
			)
			(layer "F.Fab")
		)
		(pad "1" smd circle
			(at -0.40005 0 270)
			(size 0 0)
			(layers "F.Cu" "F.Mask" "F.Paste")
			(net "GND")
		)
		(pad "2" smd circle
			(at 0.40005 0 270)
			(size 0 0)
			(layers "F.Cu" "F.Mask" "F.Paste")
			(net "PEX2_MODE_SEL3")
		)
	)
	(footprint ""
		(layer "F.Cu")
		(at 2.87528 -69.182234)
		(property "Reference" "R5874"
			(at 0 0 0)
			(layer "F.SilkS")
			(hide yes)
			(effects
				(font
					(size 1.27 1.27)
				)
			)
		)
		(property "Value" ""
			(at 0 0 0)
			(layer "F.Fab")
			(effects
				(font
					(size 1.27 1.27)
				)
			)
		)
		(duplicate_pad_numbers_are_jumpers no)
		(fp_line
			(start -0.7874 -0.4064)
			(end 0.7874 -0.4064)
			(stroke
				(width 0.1524)
				(type default)
			)
			(layer "F.SilkS")
		)
		(fp_line
			(start -0.7874 0.4064)
			(end -0.7874 -0.4064)
			(stroke
				(width 0.1524)
				(type default)
			)
			(layer "F.SilkS")
		)
		(fp_line
			(start 0.7874 -0.4064)
			(end 0.7874 0.4064)
			(stroke
				(width 0.1524)
				(type default)
			)
			(layer "F.SilkS")
		)
		(fp_line
			(start 0.7874 0.4064)
			(end -0.7874 0.4064)
			(stroke
				(width 0.1524)
				(type default)
			)
			(layer "F.SilkS")
		)
		(fp_line
			(start -0.67945 -0.305054)
			(end -0.12065 -0.305054)
			(stroke
				(width 0.1)
				(type default)
			)
			(layer "F.Fab")
		)
		(fp_line
			(start -0.67945 0.3048)
			(end -0.67945 -0.305054)
			(stroke
				(width 0.1)
				(type default)
			)
			(layer "F.Fab")
		)
		(fp_line
			(start -0.12065 -0.305054)
			(end -0.12065 -0.2794)
			(stroke
				(width 0.1)
				(type default)
			)
			(layer "F.Fab")
		)
		(fp_line
			(start -0.12065 -0.2794)
			(end 0.12065 -0.2794)
			(stroke
				(width 0.1)
				(type default)
			)
			(layer "F.Fab")
		)
		(fp_line
			(start -0.12065 0.2794)
			(end -0.12065 0.3048)
			(stroke
				(width 0.1)
				(type default)
			)
			(layer "F.Fab")
		)
		(fp_line
			(start -0.12065 0.3048)
			(end -0.67945 0.3048)
			(stroke
				(width 0.1)
				(type default)
			)
			(layer "F.Fab")
		)
		(fp_line
			(start 0.120396 0.2794)
			(end -0.12065 0.2794)
			(stroke
				(width 0.1)
				(type default)
			)
			(layer "F.Fab")
		)
		(fp_line
			(start 0.120396 0.3048)
			(end 0.120396 0.2794)
			(stroke
				(width 0.1)
				(type default)
			)
			(layer "F.Fab")
		)
		(fp_line
			(start 0.12065 -0.3048)
			(end 0.67945 -0.3048)
			(stroke
				(width 0.1)
				(type default)
			)
			(layer "F.Fab")
		)
		(fp_line
			(start 0.12065 -0.2794)
			(end 0.12065 -0.3048)
			(stroke
				(width 0.1)
				(type default)
			)
			(layer "F.Fab")
		)
		(fp_line
			(start 0.67945 -0.3048)
			(end 0.67945 0.3048)
			(stroke
				(width 0.1)
				(type default)
			)
			(layer "F.Fab")
		)
		(fp_line
			(start 0.67945 0.3048)
			(end 0.120396 0.3048)
			(stroke
				(width 0.1)
				(type default)
			)
			(layer "F.Fab")
		)
		(pad "1" smd circle
			(at -0.40005 0)
			(size 0 0)
			(layers "F.Cu" "F.Mask" "F.Paste")
			(net "P3V3_SSD0")
		)
		(pad "2" smd circle
			(at 0.40005 0)
			(size 0 0)
			(layers "F.Cu" "F.Mask" "F.Paste")
			(net "P3V3_SSD0_PG_G1")
		)
	)
	(footprint ""
		(layer "F.Cu")
		(at 375.122694 -311.156604 -90)
		(property "Reference" "R1461"
			(at 0 0 270)
			(layer "F.SilkS")
			(hide yes)
			(effects
				(font
					(size 1.27 1.27)
				)
			)
		)
		(property "Value" ""
			(at 0 0 270)
			(layer "F.Fab")
			(effects
				(font
					(size 1.27 1.27)
				)
			)
		)
		(duplicate_pad_numbers_are_jumpers no)
		(fp_line
			(start -0.7874 0.4064)
			(end -0.7874 -0.4064)
			(stroke
				(width 0.1524)
				(type default)
			)
			(layer "F.SilkS")
		)
		(fp_line
			(start 0.7874 0.4064)
			(end -0.7874 0.4064)
			(stroke
				(width 0.1524)
				(type default)
			)
			(layer "F.SilkS")
		)
		(fp_line
			(start -0.7874 -0.4064)
			(end 0.7874 -0.4064)
			(stroke
				(width 0.1524)
				(type default)
			)
			(layer "F.SilkS")
		)
		(fp_line
			(start 0.7874 -0.4064)
			(end 0.7874 0.4064)
			(stroke
				(width 0.1524)
				(type default)
			)
			(layer "F.SilkS")
		)
		(fp_line
			(start -0.67945 0.3048)
			(end -0.67945 -0.305054)
			(stroke
				(width 0.1)
				(type default)
			)
			(layer "F.Fab")
		)
		(fp_line
			(start -0.12065 0.3048)
			(end -0.67945 0.3048)
			(stroke
				(width 0.1)
				(type default)
			)
			(layer "F.Fab")
		)
		(fp_line
			(start 0.120396 0.3048)
			(end 0.120396 0.2794)
			(stroke
				(width 0.1)
				(type default)
			)
			(layer "F.Fab")
		)
		(fp_line
			(start 0.67945 0.3048)
			(end 0.120396 0.3048)
			(stroke
				(width 0.1)
				(type default)
			)
			(layer "F.Fab")
		)
		(fp_line
			(start -0.12065 0.2794)
			(end -0.12065 0.3048)
			(stroke
				(width 0.1)
				(type default)
			)
			(layer "F.Fab")
		)
		(fp_line
			(start 0.120396 0.2794)
			(end -0.12065 0.2794)
			(stroke
				(width 0.1)
				(type default)
			)
			(layer "F.Fab")
		)
		(fp_line
			(start -0.12065 -0.2794)
			(end 0.12065 -0.2794)
			(stroke
				(width 0.1)
				(type default)
			)
			(layer "F.Fab")
		)
		(fp_line
			(start 0.12065 -0.2794)
			(end 0.12065 -0.3048)
			(stroke
				(width 0.1)
				(type default)
			)
			(layer "F.Fab")
		)
		(fp_line
			(start 0.12065 -0.3048)
			(end 0.67945 -0.3048)
			(stroke
				(width 0.1)
				(type default)
			)
			(layer "F.Fab")
		)
		(fp_line
			(start 0.67945 -0.3048)
			(end 0.67945 0.3048)
			(stroke
				(width 0.1)
				(type default)
			)
			(layer "F.Fab")
		)
		(fp_line
			(start -0.67945 -0.305054)
			(end -0.12065 -0.305054)
			(stroke
				(width 0.1)
				(type default)
			)
			(layer "F.Fab")
		)
		(fp_line
			(start -0.12065 -0.305054)
			(end -0.12065 -0.2794)
			(stroke
				(width 0.1)
				(type default)
			)
			(layer "F.Fab")
		)
		(pad "1" smd circle
			(at -0.40005 0 270)
			(size 0 0)
			(layers "F.Cu" "F.Mask" "F.Paste")
			(net "PU_PEX3_TR_TCK")
		)
		(pad "2" smd circle
			(at 0.40005 0 270)
			(size 0 0)
			(layers "F.Cu" "F.Mask" "F.Paste")
			(net "P1V8_PEX")
		)
	)
	(footprint ""
		(layer "F.Cu")
		(at 78.243684 -43.85691)
		(property "Reference" "R531"
			(at 0 0 0)
			(layer "F.SilkS")
			(hide yes)
			(effects
				(font
					(size 1.27 1.27)
				)
			)
		)
		(property "Value" ""
			(at 0 0 0)
			(layer "F.Fab")
			(effects
				(font
					(size 1.27 1.27)
				)
			)
		)
		(duplicate_pad_numbers_are_jumpers no)
		(fp_line
			(start -0.7874 -0.4064)
			(end 0.7874 -0.4064)
			(stroke
				(width 0.1524)
				(type default)
			)
			(layer "F.SilkS")
		)
		(fp_line
			(start -0.7874 0.4064)
			(end -0.7874 -0.4064)
			(stroke
				(width 0.1524)
				(type default)
			)
			(layer "F.SilkS")
		)
		(fp_line
			(start 0.7874 -0.4064)
			(end 0.7874 0.4064)
			(stroke
				(width 0.1524)
				(type default)
			)
			(layer "F.SilkS")
		)
		(fp_line
			(start 0.7874 0.4064)
			(end -0.7874 0.4064)
			(stroke
				(width 0.1524)
				(type default)
			)
			(layer "F.SilkS")
		)
		(fp_line
			(start -0.67945 -0.305054)
			(end -0.12065 -0.305054)
			(stroke
				(width 0.1)
				(type default)
			)
			(layer "F.Fab")
		)
		(fp_line
			(start -0.67945 0.3048)
			(end -0.67945 -0.305054)
			(stroke
				(width 0.1)
				(type default)
			)
			(layer "F.Fab")
		)
		(fp_line
			(start -0.12065 -0.305054)
			(end -0.12065 -0.2794)
			(stroke
				(width 0.1)
				(type default)
			)
			(layer "F.Fab")
		)
		(fp_line
			(start -0.12065 -0.2794)
			(end 0.12065 -0.2794)
			(stroke
				(width 0.1)
				(type default)
			)
			(layer "F.Fab")
		)
		(fp_line
			(start -0.12065 0.2794)
			(end -0.12065 0.3048)
			(stroke
				(width 0.1)
				(type default)
			)
			(layer "F.Fab")
		)
		(fp_line
			(start -0.12065 0.3048)
			(end -0.67945 0.3048)
			(stroke
				(width 0.1)
				(type default)
			)
			(layer "F.Fab")
		)
		(fp_line
			(start 0.120396 0.2794)
			(end -0.12065 0.2794)
			(stroke
				(width 0.1)
				(type default)
			)
			(layer "F.Fab")
		)
		(fp_line
			(start 0.120396 0.3048)
			(end 0.120396 0.2794)
			(stroke
				(width 0.1)
				(type default)
			)
			(layer "F.Fab")
		)
		(fp_line
			(start 0.12065 -0.3048)
			(end 0.67945 -0.3048)
			(stroke
				(width 0.1)
				(type default)
			)
			(layer "F.Fab")
		)
		(fp_line
			(start 0.12065 -0.2794)
			(end 0.12065 -0.3048)
			(stroke
				(width 0.1)
				(type default)
			)
			(layer "F.Fab")
		)
		(fp_line
			(start 0.67945 -0.3048)
			(end 0.67945 0.3048)
			(stroke
				(width 0.1)
				(type default)
			)
			(layer "F.Fab")
		)
		(fp_line
			(start 0.67945 0.3048)
			(end 0.120396 0.3048)
			(stroke
				(width 0.1)
				(type default)
			)
			(layer "F.Fab")
		)
		(pad "1" smd circle
			(at -0.40005 0)
			(size 0 0)
			(layers "F.Cu" "F.Mask" "F.Paste")
			(net "SSD2_ADC_A1")
		)
		(pad "2" smd circle
			(at 0.40005 0)
			(size 0 0)
			(layers "F.Cu" "F.Mask" "F.Paste")
			(net "GND")
		)
	)
	(footprint ""
		(layer "F.Cu")
		(at 112.311942 -109.626654 180)
		(property "Reference" "R944"
			(at 0 0 180)
			(layer "F.SilkS")
			(hide yes)
			(effects
				(font
					(size 1.27 1.27)
				)
			)
		)
		(property "Value" ""
			(at 0 0 180)
			(layer "F.Fab")
			(effects
				(font
					(size 1.27 1.27)
				)
			)
		)
		(duplicate_pad_numbers_are_jumpers no)
		(fp_line
			(start 0.7874 0.4064)
			(end -0.7874 0.4064)
			(stroke
				(width 0.1524)
				(type default)
			)
			(layer "F.SilkS")
		)
		(fp_line
			(start 0.7874 -0.4064)
			(end 0.7874 0.4064)
			(stroke
				(width 0.1524)
				(type default)
			)
			(layer "F.SilkS")
		)
		(fp_line
			(start -0.7874 0.4064)
			(end -0.7874 -0.4064)
			(stroke
				(width 0.1524)
				(type default)
			)
			(layer "F.SilkS")
		)
		(fp_line
			(start -0.7874 -0.4064)
			(end 0.7874 -0.4064)
			(stroke
				(width 0.1524)
				(type default)
			)
			(layer "F.SilkS")
		)
		(fp_line
			(start 0.67945 0.3048)
			(end 0.120396 0.3048)
			(stroke
				(width 0.1)
				(type default)
			)
			(layer "F.Fab")
		)
		(fp_line
			(start 0.67945 -0.3048)
			(end 0.67945 0.3048)
			(stroke
				(width 0.1)
				(type default)
			)
			(layer "F.Fab")
		)
		(fp_line
			(start 0.12065 -0.2794)
			(end 0.12065 -0.3048)
			(stroke
				(width 0.1)
				(type default)
			)
			(layer "F.Fab")
		)
		(fp_line
			(start 0.12065 -0.3048)
			(end 0.67945 -0.3048)
			(stroke
				(width 0.1)
				(type default)
			)
			(layer "F.Fab")
		)
		(fp_line
			(start 0.120396 0.3048)
			(end 0.120396 0.2794)
			(stroke
				(width 0.1)
				(type default)
			)
			(layer "F.Fab")
		)
		(fp_line
			(start 0.120396 0.2794)
			(end -0.12065 0.2794)
			(stroke
				(width 0.1)
				(type default)
			)
			(layer "F.Fab")
		)
		(fp_line
			(start -0.12065 0.3048)
			(end -0.67945 0.3048)
			(stroke
				(width 0.1)
				(type default)
			)
			(layer "F.Fab")
		)
		(fp_line
			(start -0.12065 0.2794)
			(end -0.12065 0.3048)
			(stroke
				(width 0.1)
				(type default)
			)
			(layer "F.Fab")
		)
		(fp_line
			(start -0.12065 -0.2794)
			(end 0.12065 -0.2794)
			(stroke
				(width 0.1)
				(type default)
			)
			(layer "F.Fab")
		)
		(fp_line
			(start -0.12065 -0.305054)
			(end -0.12065 -0.2794)
			(stroke
				(width 0.1)
				(type default)
			)
			(layer "F.Fab")
		)
		(fp_line
			(start -0.67945 0.3048)
			(end -0.67945 -0.305054)
			(stroke
				(width 0.1)
				(type default)
			)
			(layer "F.Fab")
		)
		(fp_line
			(start -0.67945 -0.305054)
			(end -0.12065 -0.305054)
			(stroke
				(width 0.1)
				(type default)
			)
			(layer "F.Fab")
		)
		(pad "1" smd circle
			(at -0.40005 0 180)
			(size 0 0)
			(layers "F.Cu" "F.Mask" "F.Paste")
			(net "GND")
		)
		(pad "2" smd circle
			(at 0.40005 0 180)
			(size 0 0)
			(layers "F.Cu" "F.Mask" "F.Paste")
			(net "P12V_NIC1_CO_EN")
		)
	)
	(footprint ""
		(layer "F.Cu")
		(at 268.232382 -334.16367)
		(property "Reference" "R6797"
			(at 0 0 0)
			(layer "F.SilkS")
			(hide yes)
			(effects
				(font
					(size 1.27 1.27)
				)
			)
		)
		(property "Value" ""
			(at 0 0 0)
			(layer "F.Fab")
			(effects
				(font
					(size 1.27 1.27)
				)
			)
		)
		(duplicate_pad_numbers_are_jumpers no)
		(fp_line
			(start -0.7874 -0.4064)
			(end 0.7874 -0.4064)
			(stroke
				(width 0.1524)
				(type default)
			)
			(layer "F.SilkS")
		)
		(fp_line
			(start -0.7874 0.4064)
			(end -0.7874 -0.4064)
			(stroke
				(width 0.1524)
				(type default)
			)
			(layer "F.SilkS")
		)
		(fp_line
			(start 0.7874 -0.4064)
			(end 0.7874 0.4064)
			(stroke
				(width 0.1524)
				(type default)
			)
			(layer "F.SilkS")
		)
		(fp_line
			(start 0.7874 0.4064)
			(end -0.7874 0.4064)
			(stroke
				(width 0.1524)
				(type default)
			)
			(layer "F.SilkS")
		)
		(fp_line
			(start -0.67945 -0.305054)
			(end -0.12065 -0.305054)
			(stroke
				(width 0.1)
				(type default)
			)
			(layer "F.Fab")
		)
		(fp_line
			(start -0.67945 0.3048)
			(end -0.67945 -0.305054)
			(stroke
				(width 0.1)
				(type default)
			)
			(layer "F.Fab")
		)
		(fp_line
			(start -0.12065 -0.305054)
			(end -0.12065 -0.2794)
			(stroke
				(width 0.1)
				(type default)
			)
			(layer "F.Fab")
		)
		(fp_line
			(start -0.12065 -0.2794)
			(end 0.12065 -0.2794)
			(stroke
				(width 0.1)
				(type default)
			)
			(layer "F.Fab")
		)
		(fp_line
			(start -0.12065 0.2794)
			(end -0.12065 0.3048)
			(stroke
				(width 0.1)
				(type default)
			)
			(layer "F.Fab")
		)
		(fp_line
			(start -0.12065 0.3048)
			(end -0.67945 0.3048)
			(stroke
				(width 0.1)
				(type default)
			)
			(layer "F.Fab")
		)
		(fp_line
			(start 0.120396 0.2794)
			(end -0.12065 0.2794)
			(stroke
				(width 0.1)
				(type default)
			)
			(layer "F.Fab")
		)
		(fp_line
			(start 0.120396 0.3048)
			(end 0.120396 0.2794)
			(stroke
				(width 0.1)
				(type default)
			)
			(layer "F.Fab")
		)
		(fp_line
			(start 0.12065 -0.3048)
			(end 0.67945 -0.3048)
			(stroke
				(width 0.1)
				(type default)
			)
			(layer "F.Fab")
		)
		(fp_line
			(start 0.12065 -0.2794)
			(end 0.12065 -0.3048)
			(stroke
				(width 0.1)
				(type default)
			)
			(layer "F.Fab")
		)
		(fp_line
			(start 0.67945 -0.3048)
			(end 0.67945 0.3048)
			(stroke
				(width 0.1)
				(type default)
			)
			(layer "F.Fab")
		)
		(fp_line
			(start 0.67945 0.3048)
			(end 0.120396 0.3048)
			(stroke
				(width 0.1)
				(type default)
			)
			(layer "F.Fab")
		)
		(pad "1" smd circle
			(at -0.40005 0)
			(size 0 0)
			(layers "F.Cu" "F.Mask" "F.Paste")
			(net "HSC_D_OC_R2")
		)
		(pad "2" smd circle
			(at 0.40005 0)
			(size 0 0)
			(layers "F.Cu" "F.Mask" "F.Paste")
			(net "A_HSC_LOW_GATE")
		)
	)
	(footprint ""
		(layer "F.Cu")
		(at 80.019398 -149.79015 180)
		(property "Reference" "C8"
			(at 0 0 180)
			(layer "F.SilkS")
			(hide yes)
			(effects
				(font
					(size 1.27 1.27)
				)
			)
		)
		(property "Value" ""
			(at 0 0 180)
			(layer "F.Fab")
			(effects
				(font
					(size 1.27 1.27)
				)
			)
		)
		(duplicate_pad_numbers_are_jumpers no)
		(fp_line
			(start 0.299974 0.150114)
			(end -0.299974 0.150114)
			(stroke
				(width 0.1)
				(type default)
			)
			(layer "F.Fab")
		)
		(fp_line
			(start 0.299974 -0.150114)
			(end 0.299974 0.150114)
			(stroke
				(width 0.1)
				(type default)
			)
			(layer "F.Fab")
		)
		(fp_line
			(start -0.299974 0.150114)
			(end -0.299974 -0.150114)
			(stroke
				(width 0.1)
				(type default)
			)
			(layer "F.Fab")
		)
		(fp_line
			(start -0.299974 -0.150114)
			(end 0.299974 -0.150114)
			(stroke
				(width 0.1)
				(type default)
			)
			(layer "F.Fab")
		)
		(pad "1" smd rect
			(at -0.2667 0 180)
			(size 0.3048 0.381)
			(layers "F.Cu" "F.Mask" "F.Paste")
			(net "P5E_PEX0_STN0_TX_DP<12>")
		)
		(pad "2" smd rect
			(at 0.2667 0 180)
			(size 0.3048 0.381)
			(layers "F.Cu" "F.Mask" "F.Paste")
			(net "P5E_PEX0_STN0_TX_C_DP<12>")
		)
	)
	(footprint ""
		(layer "F.Cu")
		(at 71.247 -220.297756 90)
		(property "Reference" "R6634"
			(at 0 0 90)
			(layer "F.SilkS")
			(hide yes)
			(effects
				(font
					(size 1.27 1.27)
				)
			)
		)
		(property "Value" ""
			(at 0 0 90)
			(layer "F.Fab")
			(effects
				(font
					(size 1.27 1.27)
				)
			)
		)
		(duplicate_pad_numbers_are_jumpers no)
		(fp_line
			(start 0.7874 -0.4064)
			(end 0.7874 0.4064)
			(stroke
				(width 0.1524)
				(type default)
			)
			(layer "F.SilkS")
		)
		(fp_line
			(start -0.7874 -0.4064)
			(end 0.7874 -0.4064)
			(stroke
				(width 0.1524)
				(type default)
			)
			(layer "F.SilkS")
		)
		(fp_line
			(start 0.7874 0.4064)
			(end -0.7874 0.4064)
			(stroke
				(width 0.1524)
				(type default)
			)
			(layer "F.SilkS")
		)
		(fp_line
			(start -0.7874 0.4064)
			(end -0.7874 -0.4064)
			(stroke
				(width 0.1524)
				(type default)
			)
			(layer "F.SilkS")
		)
		(fp_line
			(start -0.12065 -0.305054)
			(end -0.12065 -0.2794)
			(stroke
				(width 0.1)
				(type default)
			)
			(layer "F.Fab")
		)
		(fp_line
			(start -0.67945 -0.305054)
			(end -0.12065 -0.305054)
			(stroke
				(width 0.1)
				(type default)
			)
			(layer "F.Fab")
		)
		(fp_line
			(start 0.67945 -0.3048)
			(end 0.67945 0.3048)
			(stroke
				(width 0.1)
				(type default)
			)
			(layer "F.Fab")
		)
		(fp_line
			(start 0.12065 -0.3048)
			(end 0.67945 -0.3048)
			(stroke
				(width 0.1)
				(type default)
			)
			(layer "F.Fab")
		)
		(fp_line
			(start 0.12065 -0.2794)
			(end 0.12065 -0.3048)
			(stroke
				(width 0.1)
				(type default)
			)
			(layer "F.Fab")
		)
		(fp_line
			(start -0.12065 -0.2794)
			(end 0.12065 -0.2794)
			(stroke
				(width 0.1)
				(type default)
			)
			(layer "F.Fab")
		)
		(fp_line
			(start 0.120396 0.2794)
			(end -0.12065 0.2794)
			(stroke
				(width 0.1)
				(type default)
			)
			(layer "F.Fab")
		)
		(fp_line
			(start -0.12065 0.2794)
			(end -0.12065 0.3048)
			(stroke
				(width 0.1)
				(type default)
			)
			(layer "F.Fab")
		)
		(fp_line
			(start 0.67945 0.3048)
			(end 0.120396 0.3048)
			(stroke
				(width 0.1)
				(type default)
			)
			(layer "F.Fab")
		)
		(fp_line
			(start 0.120396 0.3048)
			(end 0.120396 0.2794)
			(stroke
				(width 0.1)
				(type default)
			)
			(layer "F.Fab")
		)
		(fp_line
			(start -0.12065 0.3048)
			(end -0.67945 0.3048)
			(stroke
				(width 0.1)
				(type default)
			)
			(layer "F.Fab")
		)
		(fp_line
			(start -0.67945 0.3048)
			(end -0.67945 -0.305054)
			(stroke
				(width 0.1)
				(type default)
			)
			(layer "F.Fab")
		)
		(pad "1" smd circle
			(at -0.40005 0 90)
			(size 0 0)
			(layers "F.Cu" "F.Mask" "F.Paste")
			(net "UART_PEX3_CLI_BUF_R_TX")
		)
		(pad "2" smd circle
			(at 0.40005 0 90)
			(size 0 0)
			(layers "F.Cu" "F.Mask" "F.Paste")
			(net "UART_PEX3_CLI_BUF_R1_TX")
		)
	)
	(footprint ""
		(layer "F.Cu")
		(at 112.061244 -37.951156)
		(property "Reference" "Q220"
			(at 0.003556 -1.874774 0)
			(unlocked yes)
			(layer "F.SilkS")
			(effects
				(font
					(size 0.7874 0.5842)
					(thickness 0.1524)
				)
			)
		)
		(property "Value" ""
			(at 0 0 0)
			(layer "F.Fab")
			(effects
				(font
					(size 1.27 1.27)
				)
			)
		)
		(duplicate_pad_numbers_are_jumpers no)
		(fp_line
			(start -1.376172 -1.199896)
			(end -0.508 -1.199896)
			(stroke
				(width 0.1524)
				(type default)
			)
			(layer "F.SilkS")
		)
		(fp_line
			(start -1.376172 1.199896)
			(end -1.376172 -1.199896)
			(stroke
				(width 0.1524)
				(type default)
			)
			(layer "F.SilkS")
		)
		(fp_line
			(start -0.508 -1.199896)
			(end 0 -0.762)
			(stroke
				(width 0.1524)
				(type default)
			)
			(layer "F.SilkS")
		)
		(fp_line
			(start 0 -0.762)
			(end 0.508 -1.199896)
			(stroke
				(width 0.1524)
				(type default)
			)
			(layer "F.SilkS")
		)
		(fp_line
			(start 0.508 -1.199896)
			(end 1.376172 -1.199896)
			(stroke
				(width 0.1524)
				(type default)
			)
			(layer "F.SilkS")
		)
		(fp_line
			(start 1.376172 -1.199896)
			(end 1.376172 1.199896)
			(stroke
				(width 0.1524)
				(type default)
			)
			(layer "F.SilkS")
		)
		(fp_line
			(start 1.376172 1.199896)
			(end -1.376172 1.199896)
			(stroke
				(width 0.1524)
				(type default)
			)
			(layer "F.SilkS")
		)
		(fp_poly
			(pts
				(xy -1.63576 -1.119378) (xy -1.905254 -1.927606) (xy -2.443988 -1.388872)
			)
			(stroke
				(width 0)
				(type default)
			)
			(fill yes)
			(layer "F.SilkS")
		)
		(fp_line
			(start -0.674878 -1.100074)
			(end 0.674878 -1.100074)
			(stroke
				(width 0.1)
				(type default)
			)
			(layer "F.Fab")
		)
		(fp_line
			(start -0.674878 1.100074)
			(end -0.674878 -1.100074)
			(stroke
				(width 0.1)
				(type default)
			)
			(layer "F.Fab")
		)
		(fp_line
			(start 0.674878 -1.100074)
			(end 0.674878 1.100074)
			(stroke
				(width 0.1)
				(type default)
			)
			(layer "F.Fab")
		)
		(fp_line
			(start 0.674878 1.100074)
			(end -0.674878 1.100074)
			(stroke
				(width 0.1)
				(type default)
			)
			(layer "F.Fab")
		)
		(fp_poly
			(pts
				(xy -1.4605 -0.7493) (xy -2.2225 -1.1303) (xy -2.2225 -0.3683)
			)
			(stroke
				(width 0)
				(type default)
			)
			(fill yes)
			(layer "F.Fab")
		)
		(pad "1" smd rect
			(at -0.899922 -0.750062 270)
			(size 0.6096 0.6096)
			(layers "F.Cu" "F.Mask" "F.Paste")
			(net "GND")
		)
		(pad "2" smd rect
			(at -0.899922 0 270)
			(size 0.4064 0.6096)
			(layers "F.Cu" "F.Mask" "F.Paste")
			(net "P3V3_SSD4_PG_G1")
		)
		(pad "3" smd rect
			(at -0.899922 0.750062 270)
			(size 0.6096 0.6096)
			(layers "F.Cu" "F.Mask" "F.Paste")
			(net "PWRGD_P3V3_SSD4_D")
		)
		(pad "4" smd rect
			(at 0.899922 0.750062 270)
			(size 0.6096 0.6096)
			(layers "F.Cu" "F.Mask" "F.Paste")
			(net "GND")
		)
		(pad "5" smd rect
			(at 0.899922 0 270)
			(size 0.4064 0.6096)
			(layers "F.Cu" "F.Mask" "F.Paste")
			(net "P3V3_SSD4_PG_G2")
		)
		(pad "6" smd rect
			(at 0.899922 -0.750062 270)
			(size 0.6096 0.6096)
			(layers "F.Cu" "F.Mask" "F.Paste")
			(net "P3V3_SSD4_PG_G2")
		)
	)
	(footprint ""
		(layer "F.Cu")
		(at 5.999988 -407.599896)
		(property "Reference" "H53"
			(at -3.804412 -5.609336 0)
			(unlocked yes)
			(layer "F.SilkS")
			(effects
				(font
					(size 0.7874 0.5842)
					(thickness 0.1524)
				)
				(justify left)
			)
		)
		(property "Value" ""
			(at 0 0 0)
			(layer "F.Fab")
			(effects
				(font
					(size 1.27 1.27)
				)
			)
		)
		(duplicate_pad_numbers_are_jumpers no)
		(pad "1" thru_hole circle
			(at 0 0)
			(size 10.0076 10.0076)
			(drill 5.6134)
			(layers "*.Cu" "*.Mask")
			(remove_unused_layers no)
			(net "GND")
			(clearance -1.9431)
		)
	)
	(footprint ""
		(layer "F.Cu")
		(at 74.027792 -35.876738)
		(property "Reference" "R5883"
			(at 0 0 0)
			(layer "F.SilkS")
			(hide yes)
			(effects
				(font
					(size 1.27 1.27)
				)
			)
		)
		(property "Value" ""
			(at 0 0 0)
			(layer "F.Fab")
			(effects
				(font
					(size 1.27 1.27)
				)
			)
		)
		(duplicate_pad_numbers_are_jumpers no)
		(fp_line
			(start -0.7874 -0.4064)
			(end 0.7874 -0.4064)
			(stroke
				(width 0.1524)
				(type default)
			)
			(layer "F.SilkS")
		)
		(fp_line
			(start -0.7874 0.4064)
			(end -0.7874 -0.4064)
			(stroke
				(width 0.1524)
				(type default)
			)
			(layer "F.SilkS")
		)
		(fp_line
			(start 0.7874 -0.4064)
			(end 0.7874 0.4064)
			(stroke
				(width 0.1524)
				(type default)
			)
			(layer "F.SilkS")
		)
		(fp_line
			(start 0.7874 0.4064)
			(end -0.7874 0.4064)
			(stroke
				(width 0.1524)
				(type default)
			)
			(layer "F.SilkS")
		)
		(fp_line
			(start -0.67945 -0.305054)
			(end -0.12065 -0.305054)
			(stroke
				(width 0.1)
				(type default)
			)
			(layer "F.Fab")
		)
		(fp_line
			(start -0.67945 0.3048)
			(end -0.67945 -0.305054)
			(stroke
				(width 0.1)
				(type default)
			)
			(layer "F.Fab")
		)
		(fp_line
			(start -0.12065 -0.305054)
			(end -0.12065 -0.2794)
			(stroke
				(width 0.1)
				(type default)
			)
			(layer "F.Fab")
		)
		(fp_line
			(start -0.12065 -0.2794)
			(end 0.12065 -0.2794)
			(stroke
				(width 0.1)
				(type default)
			)
			(layer "F.Fab")
		)
		(fp_line
			(start -0.12065 0.2794)
			(end -0.12065 0.3048)
			(stroke
				(width 0.1)
				(type default)
			)
			(layer "F.Fab")
		)
		(fp_line
			(start -0.12065 0.3048)
			(end -0.67945 0.3048)
			(stroke
				(width 0.1)
				(type default)
			)
			(layer "F.Fab")
		)
		(fp_line
			(start 0.120396 0.2794)
			(end -0.12065 0.2794)
			(stroke
				(width 0.1)
				(type default)
			)
			(layer "F.Fab")
		)
		(fp_line
			(start 0.120396 0.3048)
			(end 0.120396 0.2794)
			(stroke
				(width 0.1)
				(type default)
			)
			(layer "F.Fab")
		)
		(fp_line
			(start 0.12065 -0.3048)
			(end 0.67945 -0.3048)
			(stroke
				(width 0.1)
				(type default)
			)
			(layer "F.Fab")
		)
		(fp_line
			(start 0.12065 -0.2794)
			(end 0.12065 -0.3048)
			(stroke
				(width 0.1)
				(type default)
			)
			(layer "F.Fab")
		)
		(fp_line
			(start 0.67945 -0.3048)
			(end 0.67945 0.3048)
			(stroke
				(width 0.1)
				(type default)
			)
			(layer "F.Fab")
		)
		(fp_line
			(start 0.67945 0.3048)
			(end 0.120396 0.3048)
			(stroke
				(width 0.1)
				(type default)
			)
			(layer "F.Fab")
		)
		(pad "1" smd circle
			(at -0.40005 0)
			(size 0 0)
			(layers "F.Cu" "F.Mask" "F.Paste")
			(net "PWRGD_P3V3_SSD3_D")
		)
		(pad "2" smd circle
			(at 0.40005 0)
			(size 0 0)
			(layers "F.Cu" "F.Mask" "F.Paste")
			(net "PWRGD_P3V3_SSD3_R")
		)
	)
	(footprint ""
		(layer "F.Cu")
		(at 52.267866 -52.035456 180)
		(property "Reference" "R863"
			(at 0 0 180)
			(layer "F.SilkS")
			(hide yes)
			(effects
				(font
					(size 1.27 1.27)
				)
			)
		)
		(property "Value" ""
			(at 0 0 180)
			(layer "F.Fab")
			(effects
				(font
					(size 1.27 1.27)
				)
			)
		)
		(duplicate_pad_numbers_are_jumpers no)
		(fp_line
			(start 0.7874 0.4064)
			(end -0.7874 0.4064)
			(stroke
				(width 0.1524)
				(type default)
			)
			(layer "F.SilkS")
		)
		(fp_line
			(start 0.7874 -0.4064)
			(end 0.7874 0.4064)
			(stroke
				(width 0.1524)
				(type default)
			)
			(layer "F.SilkS")
		)
		(fp_line
			(start -0.7874 0.4064)
			(end -0.7874 -0.4064)
			(stroke
				(width 0.1524)
				(type default)
			)
			(layer "F.SilkS")
		)
		(fp_line
			(start -0.7874 -0.4064)
			(end 0.7874 -0.4064)
			(stroke
				(width 0.1524)
				(type default)
			)
			(layer "F.SilkS")
		)
		(fp_line
			(start 0.67945 0.3048)
			(end 0.120396 0.3048)
			(stroke
				(width 0.1)
				(type default)
			)
			(layer "F.Fab")
		)
		(fp_line
			(start 0.67945 -0.3048)
			(end 0.67945 0.3048)
			(stroke
				(width 0.1)
				(type default)
			)
			(layer "F.Fab")
		)
		(fp_line
			(start 0.12065 -0.2794)
			(end 0.12065 -0.3048)
			(stroke
				(width 0.1)
				(type default)
			)
			(layer "F.Fab")
		)
		(fp_line
			(start 0.12065 -0.3048)
			(end 0.67945 -0.3048)
			(stroke
				(width 0.1)
				(type default)
			)
			(layer "F.Fab")
		)
		(fp_line
			(start 0.120396 0.3048)
			(end 0.120396 0.2794)
			(stroke
				(width 0.1)
				(type default)
			)
			(layer "F.Fab")
		)
		(fp_line
			(start 0.120396 0.2794)
			(end -0.12065 0.2794)
			(stroke
				(width 0.1)
				(type default)
			)
			(layer "F.Fab")
		)
		(fp_line
			(start -0.12065 0.3048)
			(end -0.67945 0.3048)
			(stroke
				(width 0.1)
				(type default)
			)
			(layer "F.Fab")
		)
		(fp_line
			(start -0.12065 0.2794)
			(end -0.12065 0.3048)
			(stroke
				(width 0.1)
				(type default)
			)
			(layer "F.Fab")
		)
		(fp_line
			(start -0.12065 -0.2794)
			(end 0.12065 -0.2794)
			(stroke
				(width 0.1)
				(type default)
			)
			(layer "F.Fab")
		)
		(fp_line
			(start -0.12065 -0.305054)
			(end -0.12065 -0.2794)
			(stroke
				(width 0.1)
				(type default)
			)
			(layer "F.Fab")
		)
		(fp_line
			(start -0.67945 0.3048)
			(end -0.67945 -0.305054)
			(stroke
				(width 0.1)
				(type default)
			)
			(layer "F.Fab")
		)
		(fp_line
			(start -0.67945 -0.305054)
			(end -0.12065 -0.305054)
			(stroke
				(width 0.1)
				(type default)
			)
			(layer "F.Fab")
		)
		(pad "1" smd circle
			(at -0.40005 0 180)
			(size 0 0)
			(layers "F.Cu" "F.Mask" "F.Paste")
			(net "P3V3_AUX")
		)
		(pad "2" smd circle
			(at 0.40005 0 180)
			(size 0 0)
			(layers "F.Cu" "F.Mask" "F.Paste")
			(net "PWRGD_P12V_SSD1")
		)
	)
	(footprint ""
		(layer "F.Cu")
		(at 59.007756 -229.6668)
		(property "Reference" "J72"
			(at -1.458976 -4.433824 0)
			(unlocked yes)
			(layer "F.SilkS")
			(effects
				(font
					(size 0.7874 0.5842)
					(thickness 0.1524)
				)
				(justify left)
			)
		)
		(property "Value" ""
			(at 0 0 0)
			(layer "F.Fab")
			(effects
				(font
					(size 1.27 1.27)
				)
			)
		)
		(duplicate_pad_numbers_are_jumpers no)
		(fp_line
			(start -1.27 -3.81)
			(end 1.27 -3.81)
			(stroke
				(width 0.1524)
				(type default)
			)
			(layer "F.SilkS")
		)
		(fp_line
			(start -1.27 -0.7747)
			(end -1.27 -3.81)
			(stroke
				(width 0.1524)
				(type default)
			)
			(layer "F.SilkS")
		)
		(fp_line
			(start -1.27 3.81)
			(end -1.27 0.7747)
			(stroke
				(width 0.1524)
				(type default)
			)
			(layer "F.SilkS")
		)
		(fp_line
			(start 1.27 -3.81)
			(end 1.27 -3.3147)
			(stroke
				(width 0.1524)
				(type default)
			)
			(layer "F.SilkS")
		)
		(fp_line
			(start 1.27 -1.7653)
			(end 1.27 1.7653)
			(stroke
				(width 0.1524)
				(type default)
			)
			(layer "F.SilkS")
		)
		(fp_line
			(start 1.27 3.3147)
			(end 1.27 3.81)
			(stroke
				(width 0.1524)
				(type default)
			)
			(layer "F.SilkS")
		)
		(fp_line
			(start 1.27 3.81)
			(end -1.27 3.81)
			(stroke
				(width 0.1524)
				(type default)
			)
			(layer "F.SilkS")
		)
		(fp_poly
			(pts
				(xy 4.3942 -3.048) (xy 4.3942 -2.032) (xy 3.3782 -2.54)
			)
			(stroke
				(width 0)
				(type default)
			)
			(fill yes)
			(layer "F.SilkS")
		)
		(fp_line
			(start -1.27 -3.81)
			(end -1.27 3.81)
			(stroke
				(width 0.1)
				(type default)
			)
			(layer "F.Fab")
		)
		(fp_line
			(start -1.27 3.81)
			(end 1.27 3.81)
			(stroke
				(width 0.1)
				(type default)
			)
			(layer "F.Fab")
		)
		(fp_line
			(start 1.27 -3.81)
			(end -1.27 -3.81)
			(stroke
				(width 0.1)
				(type default)
			)
			(layer "F.Fab")
		)
		(fp_line
			(start 1.27 3.81)
			(end 1.27 -3.81)
			(stroke
				(width 0.1)
				(type default)
			)
			(layer "F.Fab")
		)
		(fp_poly
			(pts
				(xy 4.3942 -3.048) (xy 4.3942 -2.032) (xy 3.3782 -2.54)
			)
			(stroke
				(width 0)
				(type default)
			)
			(fill yes)
			(layer "F.Fab")
		)
		(fp_text user "3"
			(at 3.921252 2.54 90)
			(unlocked yes)
			(layer "F.SilkS")
			(effects
				(font
					(size 0.7874 0.5842)
					(thickness 0.1524)
				)
			)
		)
		(fp_text user "3"
			(at 3.921252 2.54 90)
			(unlocked yes)
			(layer "F.Fab")
			(effects
				(font
					(size 0.7874 0.5842)
					(thickness 0.1524)
				)
			)
		)
		(pad "1" smd rect
			(at 1.459992 -2.54 90)
			(size 1.27 3.429)
			(layers "F.Cu" "F.Mask" "F.Paste")
			(net "GND")
		)
		(pad "2" smd rect
			(at -1.459992 0 90)
			(size 1.27 3.429)
			(layers "F.Cu" "F.Mask" "F.Paste")
			(net "UART_PEX1_CLI_BUF_R1_TX")
		)
		(pad "3" smd rect
			(at 1.459992 2.54 90)
			(size 1.27 3.429)
			(layers "F.Cu" "F.Mask" "F.Paste")
			(net "UART_PEX1_CLI_R1_RX")
		)
	)
	(footprint ""
		(layer "F.Cu")
		(at 188.37402 -72.766682 90)
		(property "Reference" "PR7070"
			(at 0 0 90)
			(layer "F.SilkS")
			(hide yes)
			(effects
				(font
					(size 1.27 1.27)
				)
			)
		)
		(property "Value" ""
			(at 0 0 90)
			(layer "F.Fab")
			(effects
				(font
					(size 1.27 1.27)
				)
			)
		)
		(duplicate_pad_numbers_are_jumpers no)
		(fp_line
			(start 0.7874 -0.4064)
			(end 0.7874 0.4064)
			(stroke
				(width 0.1524)
				(type default)
			)
			(layer "F.SilkS")
		)
		(fp_line
			(start -0.7874 -0.4064)
			(end 0.7874 -0.4064)
			(stroke
				(width 0.1524)
				(type default)
			)
			(layer "F.SilkS")
		)
		(fp_line
			(start 0.7874 0.4064)
			(end -0.7874 0.4064)
			(stroke
				(width 0.1524)
				(type default)
			)
			(layer "F.SilkS")
		)
		(fp_line
			(start -0.7874 0.4064)
			(end -0.7874 -0.4064)
			(stroke
				(width 0.1524)
				(type default)
			)
			(layer "F.SilkS")
		)
		(fp_line
			(start -0.12065 -0.305054)
			(end -0.12065 -0.2794)
			(stroke
				(width 0.1)
				(type default)
			)
			(layer "F.Fab")
		)
		(fp_line
			(start -0.67945 -0.305054)
			(end -0.12065 -0.305054)
			(stroke
				(width 0.1)
				(type default)
			)
			(layer "F.Fab")
		)
		(fp_line
			(start 0.67945 -0.3048)
			(end 0.67945 0.3048)
			(stroke
				(width 0.1)
				(type default)
			)
			(layer "F.Fab")
		)
		(fp_line
			(start 0.12065 -0.3048)
			(end 0.67945 -0.3048)
			(stroke
				(width 0.1)
				(type default)
			)
			(layer "F.Fab")
		)
		(fp_line
			(start 0.12065 -0.2794)
			(end 0.12065 -0.3048)
			(stroke
				(width 0.1)
				(type default)
			)
			(layer "F.Fab")
		)
		(fp_line
			(start -0.12065 -0.2794)
			(end 0.12065 -0.2794)
			(stroke
				(width 0.1)
				(type default)
			)
			(layer "F.Fab")
		)
		(fp_line
			(start 0.120396 0.2794)
			(end -0.12065 0.2794)
			(stroke
				(width 0.1)
				(type default)
			)
			(layer "F.Fab")
		)
		(fp_line
			(start -0.12065 0.2794)
			(end -0.12065 0.3048)
			(stroke
				(width 0.1)
				(type default)
			)
			(layer "F.Fab")
		)
		(fp_line
			(start 0.67945 0.3048)
			(end 0.120396 0.3048)
			(stroke
				(width 0.1)
				(type default)
			)
			(layer "F.Fab")
		)
		(fp_line
			(start 0.120396 0.3048)
			(end 0.120396 0.2794)
			(stroke
				(width 0.1)
				(type default)
			)
			(layer "F.Fab")
		)
		(fp_line
			(start -0.12065 0.3048)
			(end -0.67945 0.3048)
			(stroke
				(width 0.1)
				(type default)
			)
			(layer "F.Fab")
		)
		(fp_line
			(start -0.67945 0.3048)
			(end -0.67945 -0.305054)
			(stroke
				(width 0.1)
				(type default)
			)
			(layer "F.Fab")
		)
		(pad "1" smd circle
			(at -0.40005 0 90)
			(size 0 0)
			(layers "F.Cu" "F.Mask" "F.Paste")
			(net "P12V_SSD6_CO_MODE")
		)
		(pad "2" smd circle
			(at 0.40005 0 90)
			(size 0 0)
			(layers "F.Cu" "F.Mask" "F.Paste")
			(net "GND")
		)
	)
	(footprint ""
		(layer "F.Cu")
		(at 259.662422 -22.937216 90)
		(property "Reference" "R1697"
			(at 0 0 90)
			(layer "F.SilkS")
			(hide yes)
			(effects
				(font
					(size 1.27 1.27)
				)
			)
		)
		(property "Value" ""
			(at 0 0 90)
			(layer "F.Fab")
			(effects
				(font
					(size 1.27 1.27)
				)
			)
		)
		(duplicate_pad_numbers_are_jumpers no)
		(fp_line
			(start 0.7874 -0.4064)
			(end 0.7874 0.4064)
			(stroke
				(width 0.1524)
				(type default)
			)
			(layer "F.SilkS")
		)
		(fp_line
			(start -0.7874 -0.4064)
			(end 0.7874 -0.4064)
			(stroke
				(width 0.1524)
				(type default)
			)
			(layer "F.SilkS")
		)
		(fp_line
			(start 0.7874 0.4064)
			(end -0.7874 0.4064)
			(stroke
				(width 0.1524)
				(type default)
			)
			(layer "F.SilkS")
		)
		(fp_line
			(start -0.7874 0.4064)
			(end -0.7874 -0.4064)
			(stroke
				(width 0.1524)
				(type default)
			)
			(layer "F.SilkS")
		)
		(fp_line
			(start -0.12065 -0.305054)
			(end -0.12065 -0.2794)
			(stroke
				(width 0.1)
				(type default)
			)
			(layer "F.Fab")
		)
		(fp_line
			(start -0.67945 -0.305054)
			(end -0.12065 -0.305054)
			(stroke
				(width 0.1)
				(type default)
			)
			(layer "F.Fab")
		)
		(fp_line
			(start 0.67945 -0.3048)
			(end 0.67945 0.3048)
			(stroke
				(width 0.1)
				(type default)
			)
			(layer "F.Fab")
		)
		(fp_line
			(start 0.12065 -0.3048)
			(end 0.67945 -0.3048)
			(stroke
				(width 0.1)
				(type default)
			)
			(layer "F.Fab")
		)
		(fp_line
			(start 0.12065 -0.2794)
			(end 0.12065 -0.3048)
			(stroke
				(width 0.1)
				(type default)
			)
			(layer "F.Fab")
		)
		(fp_line
			(start -0.12065 -0.2794)
			(end 0.12065 -0.2794)
			(stroke
				(width 0.1)
				(type default)
			)
			(layer "F.Fab")
		)
		(fp_line
			(start 0.120396 0.2794)
			(end -0.12065 0.2794)
			(stroke
				(width 0.1)
				(type default)
			)
			(layer "F.Fab")
		)
		(fp_line
			(start -0.12065 0.2794)
			(end -0.12065 0.3048)
			(stroke
				(width 0.1)
				(type default)
			)
			(layer "F.Fab")
		)
		(fp_line
			(start 0.67945 0.3048)
			(end 0.120396 0.3048)
			(stroke
				(width 0.1)
				(type default)
			)
			(layer "F.Fab")
		)
		(fp_line
			(start 0.120396 0.3048)
			(end 0.120396 0.2794)
			(stroke
				(width 0.1)
				(type default)
			)
			(layer "F.Fab")
		)
		(fp_line
			(start -0.12065 0.3048)
			(end -0.67945 0.3048)
			(stroke
				(width 0.1)
				(type default)
			)
			(layer "F.Fab")
		)
		(fp_line
			(start -0.67945 0.3048)
			(end -0.67945 -0.305054)
			(stroke
				(width 0.1)
				(type default)
			)
			(layer "F.Fab")
		)
		(pad "1" smd circle
			(at -0.40005 0 90)
			(size 0 0)
			(layers "F.Cu" "F.Mask" "F.Paste")
			(net "SMB_BIC_I2C9_MUX1_SSD8_R_SDA")
		)
		(pad "2" smd circle
			(at 0.40005 0 90)
			(size 0 0)
			(layers "F.Cu" "F.Mask" "F.Paste")
			(net "SMB_ISO_SSD8_SDA")
		)
	)
	(footprint ""
		(layer "F.Cu")
		(at 239.971834 -24.807418)
		(property "Reference" "R435"
			(at 0 0 0)
			(layer "F.SilkS")
			(hide yes)
			(effects
				(font
					(size 1.27 1.27)
				)
			)
		)
		(property "Value" ""
			(at 0 0 0)
			(layer "F.Fab")
			(effects
				(font
					(size 1.27 1.27)
				)
			)
		)
		(duplicate_pad_numbers_are_jumpers no)
		(fp_line
			(start -0.7874 -0.4064)
			(end 0.7874 -0.4064)
			(stroke
				(width 0.1524)
				(type default)
			)
			(layer "F.SilkS")
		)
		(fp_line
			(start -0.7874 0.4064)
			(end -0.7874 -0.4064)
			(stroke
				(width 0.1524)
				(type default)
			)
			(layer "F.SilkS")
		)
		(fp_line
			(start 0.7874 -0.4064)
			(end 0.7874 0.4064)
			(stroke
				(width 0.1524)
				(type default)
			)
			(layer "F.SilkS")
		)
		(fp_line
			(start 0.7874 0.4064)
			(end -0.7874 0.4064)
			(stroke
				(width 0.1524)
				(type default)
			)
			(layer "F.SilkS")
		)
		(fp_line
			(start -0.67945 -0.305054)
			(end -0.12065 -0.305054)
			(stroke
				(width 0.1)
				(type default)
			)
			(layer "F.Fab")
		)
		(fp_line
			(start -0.67945 0.3048)
			(end -0.67945 -0.305054)
			(stroke
				(width 0.1)
				(type default)
			)
			(layer "F.Fab")
		)
		(fp_line
			(start -0.12065 -0.305054)
			(end -0.12065 -0.2794)
			(stroke
				(width 0.1)
				(type default)
			)
			(layer "F.Fab")
		)
		(fp_line
			(start -0.12065 -0.2794)
			(end 0.12065 -0.2794)
			(stroke
				(width 0.1)
				(type default)
			)
			(layer "F.Fab")
		)
		(fp_line
			(start -0.12065 0.2794)
			(end -0.12065 0.3048)
			(stroke
				(width 0.1)
				(type default)
			)
			(layer "F.Fab")
		)
		(fp_line
			(start -0.12065 0.3048)
			(end -0.67945 0.3048)
			(stroke
				(width 0.1)
				(type default)
			)
			(layer "F.Fab")
		)
		(fp_line
			(start 0.120396 0.2794)
			(end -0.12065 0.2794)
			(stroke
				(width 0.1)
				(type default)
			)
			(layer "F.Fab")
		)
		(fp_line
			(start 0.120396 0.3048)
			(end 0.120396 0.2794)
			(stroke
				(width 0.1)
				(type default)
			)
			(layer "F.Fab")
		)
		(fp_line
			(start 0.12065 -0.3048)
			(end 0.67945 -0.3048)
			(stroke
				(width 0.1)
				(type default)
			)
			(layer "F.Fab")
		)
		(fp_line
			(start 0.12065 -0.2794)
			(end 0.12065 -0.3048)
			(stroke
				(width 0.1)
				(type default)
			)
			(layer "F.Fab")
		)
		(fp_line
			(start 0.67945 -0.3048)
			(end 0.67945 0.3048)
			(stroke
				(width 0.1)
				(type default)
			)
			(layer "F.Fab")
		)
		(fp_line
			(start 0.67945 0.3048)
			(end 0.120396 0.3048)
			(stroke
				(width 0.1)
				(type default)
			)
			(layer "F.Fab")
		)
		(pad "1" smd circle
			(at -0.40005 0)
			(size 0 0)
			(layers "F.Cu" "F.Mask" "F.Paste")
			(net "P3V3_SSD8")
		)
		(pad "2" smd circle
			(at 0.40005 0)
			(size 0 0)
			(layers "F.Cu" "F.Mask" "F.Paste")
			(net "PU_CLKREQ8")
		)
	)
	(footprint ""
		(layer "F.Cu")
		(at 317.957708 -299.04055 -90)
		(property "Reference" "C4187"
			(at 0 0 270)
			(layer "F.SilkS")
			(hide yes)
			(effects
				(font
					(size 1.27 1.27)
				)
			)
		)
		(property "Value" ""
			(at 0 0 270)
			(layer "F.Fab")
			(effects
				(font
					(size 1.27 1.27)
				)
			)
		)
		(duplicate_pad_numbers_are_jumpers no)
		(fp_line
			(start -0.7874 0.4064)
			(end -0.7874 -0.4064)
			(stroke
				(width 0.1524)
				(type default)
			)
			(layer "F.SilkS")
		)
		(fp_line
			(start 0.7874 0.4064)
			(end -0.7874 0.4064)
			(stroke
				(width 0.1524)
				(type default)
			)
			(layer "F.SilkS")
		)
		(fp_line
			(start -0.7874 -0.4064)
			(end 0.7874 -0.4064)
			(stroke
				(width 0.1524)
				(type default)
			)
			(layer "F.SilkS")
		)
		(fp_line
			(start 0.7874 -0.4064)
			(end 0.7874 0.4064)
			(stroke
				(width 0.1524)
				(type default)
			)
			(layer "F.SilkS")
		)
		(fp_line
			(start -0.67945 0.3048)
			(end -0.67945 -0.305054)
			(stroke
				(width 0.1)
				(type default)
			)
			(layer "F.Fab")
		)
		(fp_line
			(start -0.12065 0.3048)
			(end -0.67945 0.3048)
			(stroke
				(width 0.1)
				(type default)
			)
			(layer "F.Fab")
		)
		(fp_line
			(start 0.120396 0.3048)
			(end 0.120396 0.2794)
			(stroke
				(width 0.1)
				(type default)
			)
			(layer "F.Fab")
		)
		(fp_line
			(start 0.67945 0.3048)
			(end 0.120396 0.3048)
			(stroke
				(width 0.1)
				(type default)
			)
			(layer "F.Fab")
		)
		(fp_line
			(start -0.12065 0.2794)
			(end -0.12065 0.3048)
			(stroke
				(width 0.1)
				(type default)
			)
			(layer "F.Fab")
		)
		(fp_line
			(start 0.120396 0.2794)
			(end -0.12065 0.2794)
			(stroke
				(width 0.1)
				(type default)
			)
			(layer "F.Fab")
		)
		(fp_line
			(start -0.12065 -0.2794)
			(end 0.12065 -0.2794)
			(stroke
				(width 0.1)
				(type default)
			)
			(layer "F.Fab")
		)
		(fp_line
			(start 0.12065 -0.2794)
			(end 0.12065 -0.3048)
			(stroke
				(width 0.1)
				(type default)
			)
			(layer "F.Fab")
		)
		(fp_line
			(start 0.12065 -0.3048)
			(end 0.67945 -0.3048)
			(stroke
				(width 0.1)
				(type default)
			)
			(layer "F.Fab")
		)
		(fp_line
			(start 0.67945 -0.3048)
			(end 0.67945 0.3048)
			(stroke
				(width 0.1)
				(type default)
			)
			(layer "F.Fab")
		)
		(fp_line
			(start -0.67945 -0.305054)
			(end -0.12065 -0.305054)
			(stroke
				(width 0.1)
				(type default)
			)
			(layer "F.Fab")
		)
		(fp_line
			(start -0.12065 -0.305054)
			(end -0.12065 -0.2794)
			(stroke
				(width 0.1)
				(type default)
			)
			(layer "F.Fab")
		)
		(pad "1" smd circle
			(at -0.40005 0 270)
			(size 0 0)
			(layers "F.Cu" "F.Mask" "F.Paste")
			(net "GND")
		)
		(pad "2" smd circle
			(at 0.40005 0 270)
			(size 0 0)
			(layers "F.Cu" "F.Mask" "F.Paste")
			(net "P1V8_PEX")
		)
	)
	(footprint ""
		(layer "F.Cu")
		(at 8.549386 -255.046734 -90)
		(property "Reference" "R6462"
			(at 0 0 270)
			(layer "F.SilkS")
			(hide yes)
			(effects
				(font
					(size 1.27 1.27)
				)
			)
		)
		(property "Value" ""
			(at 0 0 270)
			(layer "F.Fab")
			(effects
				(font
					(size 1.27 1.27)
				)
			)
		)
		(duplicate_pad_numbers_are_jumpers no)
		(fp_line
			(start -0.7874 0.4064)
			(end -0.7874 -0.4064)
			(stroke
				(width 0.1524)
				(type default)
			)
			(layer "F.SilkS")
		)
		(fp_line
			(start 0.7874 0.4064)
			(end -0.7874 0.4064)
			(stroke
				(width 0.1524)
				(type default)
			)
			(layer "F.SilkS")
		)
		(fp_line
			(start -0.7874 -0.4064)
			(end 0.7874 -0.4064)
			(stroke
				(width 0.1524)
				(type default)
			)
			(layer "F.SilkS")
		)
		(fp_line
			(start 0.7874 -0.4064)
			(end 0.7874 0.4064)
			(stroke
				(width 0.1524)
				(type default)
			)
			(layer "F.SilkS")
		)
		(fp_line
			(start -0.67945 0.3048)
			(end -0.67945 -0.305054)
			(stroke
				(width 0.1)
				(type default)
			)
			(layer "F.Fab")
		)
		(fp_line
			(start -0.12065 0.3048)
			(end -0.67945 0.3048)
			(stroke
				(width 0.1)
				(type default)
			)
			(layer "F.Fab")
		)
		(fp_line
			(start 0.120396 0.3048)
			(end 0.120396 0.2794)
			(stroke
				(width 0.1)
				(type default)
			)
			(layer "F.Fab")
		)
		(fp_line
			(start 0.67945 0.3048)
			(end 0.120396 0.3048)
			(stroke
				(width 0.1)
				(type default)
			)
			(layer "F.Fab")
		)
		(fp_line
			(start -0.12065 0.2794)
			(end -0.12065 0.3048)
			(stroke
				(width 0.1)
				(type default)
			)
			(layer "F.Fab")
		)
		(fp_line
			(start 0.120396 0.2794)
			(end -0.12065 0.2794)
			(stroke
				(width 0.1)
				(type default)
			)
			(layer "F.Fab")
		)
		(fp_line
			(start -0.12065 -0.2794)
			(end 0.12065 -0.2794)
			(stroke
				(width 0.1)
				(type default)
			)
			(layer "F.Fab")
		)
		(fp_line
			(start 0.12065 -0.2794)
			(end 0.12065 -0.3048)
			(stroke
				(width 0.1)
				(type default)
			)
			(layer "F.Fab")
		)
		(fp_line
			(start 0.12065 -0.3048)
			(end 0.67945 -0.3048)
			(stroke
				(width 0.1)
				(type default)
			)
			(layer "F.Fab")
		)
		(fp_line
			(start 0.67945 -0.3048)
			(end 0.67945 0.3048)
			(stroke
				(width 0.1)
				(type default)
			)
			(layer "F.Fab")
		)
		(fp_line
			(start -0.67945 -0.305054)
			(end -0.12065 -0.305054)
			(stroke
				(width 0.1)
				(type default)
			)
			(layer "F.Fab")
		)
		(fp_line
			(start -0.12065 -0.305054)
			(end -0.12065 -0.2794)
			(stroke
				(width 0.1)
				(type default)
			)
			(layer "F.Fab")
		)
		(pad "1" smd circle
			(at -0.40005 0 270)
			(size 0 0)
			(layers "F.Cu" "F.Mask" "F.Paste")
			(net "P1V25_SERDES_VDDPLL_PEX0")
		)
		(pad "2" smd circle
			(at 0.40005 0 270)
			(size 0 0)
			(layers "F.Cu" "F.Mask" "F.Paste")
			(net "P1V25_SERDES_VDDPLL_PEX0_C1")
		)
	)
	(footprint ""
		(layer "F.Cu")
		(at 19.307048 -343.952322 90)
		(property "Reference" "C2152"
			(at 0 0 90)
			(layer "F.SilkS")
			(hide yes)
			(effects
				(font
					(size 1.27 1.27)
				)
			)
		)
		(property "Value" ""
			(at 0 0 90)
			(layer "F.Fab")
			(effects
				(font
					(size 1.27 1.27)
				)
			)
		)
		(duplicate_pad_numbers_are_jumpers no)
		(fp_line
			(start 0.299974 -0.150114)
			(end 0.299974 0.150114)
			(stroke
				(width 0.1)
				(type default)
			)
			(layer "F.Fab")
		)
		(fp_line
			(start -0.299974 -0.150114)
			(end 0.299974 -0.150114)
			(stroke
				(width 0.1)
				(type default)
			)
			(layer "F.Fab")
		)
		(fp_line
			(start 0.299974 0.150114)
			(end -0.299974 0.150114)
			(stroke
				(width 0.1)
				(type default)
			)
			(layer "F.Fab")
		)
		(fp_line
			(start -0.299974 0.150114)
			(end -0.299974 -0.150114)
			(stroke
				(width 0.1)
				(type default)
			)
			(layer "F.Fab")
		)
		(pad "1" smd rect
			(at -0.2667 0 90)
			(size 0.3048 0.381)
			(layers "F.Cu" "F.Mask" "F.Paste")
			(net "P5E_PEX0_STN4_TX_DP<79>")
		)
		(pad "2" smd rect
			(at 0.2667 0 90)
			(size 0.3048 0.381)
			(layers "F.Cu" "F.Mask" "F.Paste")
			(net "P5E_PEX0_STN4_TX_C_DP<79>")
		)
	)
	(footprint ""
		(layer "F.Cu")
		(at 75.65644 -20.467574 180)
		(property "Reference" "R1647"
			(at 0 0 180)
			(layer "F.SilkS")
			(hide yes)
			(effects
				(font
					(size 1.27 1.27)
				)
			)
		)
		(property "Value" ""
			(at 0 0 180)
			(layer "F.Fab")
			(effects
				(font
					(size 1.27 1.27)
				)
			)
		)
		(duplicate_pad_numbers_are_jumpers no)
		(fp_line
			(start 0.7874 0.4064)
			(end -0.7874 0.4064)
			(stroke
				(width 0.1524)
				(type default)
			)
			(layer "F.SilkS")
		)
		(fp_line
			(start 0.7874 -0.4064)
			(end 0.7874 0.4064)
			(stroke
				(width 0.1524)
				(type default)
			)
			(layer "F.SilkS")
		)
		(fp_line
			(start -0.7874 0.4064)
			(end -0.7874 -0.4064)
			(stroke
				(width 0.1524)
				(type default)
			)
			(layer "F.SilkS")
		)
		(fp_line
			(start -0.7874 -0.4064)
			(end 0.7874 -0.4064)
			(stroke
				(width 0.1524)
				(type default)
			)
			(layer "F.SilkS")
		)
		(fp_line
			(start 0.67945 0.3048)
			(end 0.120396 0.3048)
			(stroke
				(width 0.1)
				(type default)
			)
			(layer "F.Fab")
		)
		(fp_line
			(start 0.67945 -0.3048)
			(end 0.67945 0.3048)
			(stroke
				(width 0.1)
				(type default)
			)
			(layer "F.Fab")
		)
		(fp_line
			(start 0.12065 -0.2794)
			(end 0.12065 -0.3048)
			(stroke
				(width 0.1)
				(type default)
			)
			(layer "F.Fab")
		)
		(fp_line
			(start 0.12065 -0.3048)
			(end 0.67945 -0.3048)
			(stroke
				(width 0.1)
				(type default)
			)
			(layer "F.Fab")
		)
		(fp_line
			(start 0.120396 0.3048)
			(end 0.120396 0.2794)
			(stroke
				(width 0.1)
				(type default)
			)
			(layer "F.Fab")
		)
		(fp_line
			(start 0.120396 0.2794)
			(end -0.12065 0.2794)
			(stroke
				(width 0.1)
				(type default)
			)
			(layer "F.Fab")
		)
		(fp_line
			(start -0.12065 0.3048)
			(end -0.67945 0.3048)
			(stroke
				(width 0.1)
				(type default)
			)
			(layer "F.Fab")
		)
		(fp_line
			(start -0.12065 0.2794)
			(end -0.12065 0.3048)
			(stroke
				(width 0.1)
				(type default)
			)
			(layer "F.Fab")
		)
		(fp_line
			(start -0.12065 -0.2794)
			(end 0.12065 -0.2794)
			(stroke
				(width 0.1)
				(type default)
			)
			(layer "F.Fab")
		)
		(fp_line
			(start -0.12065 -0.305054)
			(end -0.12065 -0.2794)
			(stroke
				(width 0.1)
				(type default)
			)
			(layer "F.Fab")
		)
		(fp_line
			(start -0.67945 0.3048)
			(end -0.67945 -0.305054)
			(stroke
				(width 0.1)
				(type default)
			)
			(layer "F.Fab")
		)
		(fp_line
			(start -0.67945 -0.305054)
			(end -0.12065 -0.305054)
			(stroke
				(width 0.1)
				(type default)
			)
			(layer "F.Fab")
		)
		(pad "1" smd circle
			(at -0.40005 0 180)
			(size 0 0)
			(layers "F.Cu" "F.Mask" "F.Paste")
			(net "P3V3_SSD2")
		)
		(pad "2" smd circle
			(at 0.40005 0 180)
			(size 0 0)
			(layers "F.Cu" "F.Mask" "F.Paste")
			(net "SMB_ISO_SSD2_SDA")
		)
	)
	(footprint ""
		(layer "F.Cu")
		(at 358.013 -228.6 180)
		(property "Reference" "R3640"
			(at 0 0 180)
			(layer "F.SilkS")
			(hide yes)
			(effects
				(font
					(size 1.27 1.27)
				)
			)
		)
		(property "Value" ""
			(at 0 0 180)
			(layer "F.Fab")
			(effects
				(font
					(size 1.27 1.27)
				)
			)
		)
		(duplicate_pad_numbers_are_jumpers no)
		(fp_line
			(start 0.7874 0.4064)
			(end -0.7874 0.4064)
			(stroke
				(width 0.1524)
				(type default)
			)
			(layer "F.SilkS")
		)
		(fp_line
			(start 0.7874 -0.4064)
			(end 0.7874 0.4064)
			(stroke
				(width 0.1524)
				(type default)
			)
			(layer "F.SilkS")
		)
		(fp_line
			(start -0.7874 0.4064)
			(end -0.7874 -0.4064)
			(stroke
				(width 0.1524)
				(type default)
			)
			(layer "F.SilkS")
		)
		(fp_line
			(start -0.7874 -0.4064)
			(end 0.7874 -0.4064)
			(stroke
				(width 0.1524)
				(type default)
			)
			(layer "F.SilkS")
		)
		(fp_line
			(start 0.67945 0.3048)
			(end 0.120396 0.3048)
			(stroke
				(width 0.1)
				(type default)
			)
			(layer "F.Fab")
		)
		(fp_line
			(start 0.67945 -0.3048)
			(end 0.67945 0.3048)
			(stroke
				(width 0.1)
				(type default)
			)
			(layer "F.Fab")
		)
		(fp_line
			(start 0.12065 -0.2794)
			(end 0.12065 -0.3048)
			(stroke
				(width 0.1)
				(type default)
			)
			(layer "F.Fab")
		)
		(fp_line
			(start 0.12065 -0.3048)
			(end 0.67945 -0.3048)
			(stroke
				(width 0.1)
				(type default)
			)
			(layer "F.Fab")
		)
		(fp_line
			(start 0.120396 0.3048)
			(end 0.120396 0.2794)
			(stroke
				(width 0.1)
				(type default)
			)
			(layer "F.Fab")
		)
		(fp_line
			(start 0.120396 0.2794)
			(end -0.12065 0.2794)
			(stroke
				(width 0.1)
				(type default)
			)
			(layer "F.Fab")
		)
		(fp_line
			(start -0.12065 0.3048)
			(end -0.67945 0.3048)
			(stroke
				(width 0.1)
				(type default)
			)
			(layer "F.Fab")
		)
		(fp_line
			(start -0.12065 0.2794)
			(end -0.12065 0.3048)
			(stroke
				(width 0.1)
				(type default)
			)
			(layer "F.Fab")
		)
		(fp_line
			(start -0.12065 -0.2794)
			(end 0.12065 -0.2794)
			(stroke
				(width 0.1)
				(type default)
			)
			(layer "F.Fab")
		)
		(fp_line
			(start -0.12065 -0.305054)
			(end -0.12065 -0.2794)
			(stroke
				(width 0.1)
				(type default)
			)
			(layer "F.Fab")
		)
		(fp_line
			(start -0.67945 0.3048)
			(end -0.67945 -0.305054)
			(stroke
				(width 0.1)
				(type default)
			)
			(layer "F.Fab")
		)
		(fp_line
			(start -0.67945 -0.305054)
			(end -0.12065 -0.305054)
			(stroke
				(width 0.1)
				(type default)
			)
			(layer "F.Fab")
		)
		(pad "1" smd circle
			(at -0.40005 0 180)
			(size 0 0)
			(layers "F.Cu" "F.Mask" "F.Paste")
			(net "NIC4_CLK_EN_R_N")
		)
		(pad "2" smd circle
			(at 0.40005 0 180)
			(size 0 0)
			(layers "F.Cu" "F.Mask" "F.Paste")
			(net "NIC4_CLK_EN_N")
		)
	)
	(footprint ""
		(layer "F.Cu")
		(at 249.992388 -29.139642 180)
		(property "Reference" "C493"
			(at 0 0 180)
			(layer "F.SilkS")
			(hide yes)
			(effects
				(font
					(size 1.27 1.27)
				)
			)
		)
		(property "Value" ""
			(at 0 0 180)
			(layer "F.Fab")
			(effects
				(font
					(size 1.27 1.27)
				)
			)
		)
		(duplicate_pad_numbers_are_jumpers no)
		(fp_line
			(start 0.299974 0.150114)
			(end -0.299974 0.150114)
			(stroke
				(width 0.1)
				(type default)
			)
			(layer "F.Fab")
		)
		(fp_line
			(start 0.299974 -0.150114)
			(end 0.299974 0.150114)
			(stroke
				(width 0.1)
				(type default)
			)
			(layer "F.Fab")
		)
		(fp_line
			(start -0.299974 0.150114)
			(end -0.299974 -0.150114)
			(stroke
				(width 0.1)
				(type default)
			)
			(layer "F.Fab")
		)
		(fp_line
			(start -0.299974 -0.150114)
			(end 0.299974 -0.150114)
			(stroke
				(width 0.1)
				(type default)
			)
			(layer "F.Fab")
		)
		(pad "1" smd rect
			(at -0.2667 0 180)
			(size 0.3048 0.381)
			(layers "F.Cu" "F.Mask" "F.Paste")
			(net "P5E_PEX2_STN2_TX_DP<44>")
		)
		(pad "2" smd rect
			(at 0.2667 0 180)
			(size 0.3048 0.381)
			(layers "F.Cu" "F.Mask" "F.Paste")
			(net "P5E_PEX2_STN2_TX_C_DP<44>")
		)
	)
	(footprint ""
		(layer "F.Cu")
		(at 355.009196 -26.03373)
		(property "Reference" "R4076"
			(at 0 0 0)
			(layer "F.SilkS")
			(hide yes)
			(effects
				(font
					(size 1.27 1.27)
				)
			)
		)
		(property "Value" ""
			(at 0 0 0)
			(layer "F.Fab")
			(effects
				(font
					(size 1.27 1.27)
				)
			)
		)
		(duplicate_pad_numbers_are_jumpers no)
		(fp_line
			(start -0.7874 -0.4064)
			(end 0.7874 -0.4064)
			(stroke
				(width 0.1524)
				(type default)
			)
			(layer "F.SilkS")
		)
		(fp_line
			(start -0.7874 0.4064)
			(end -0.7874 -0.4064)
			(stroke
				(width 0.1524)
				(type default)
			)
			(layer "F.SilkS")
		)
		(fp_line
			(start 0.7874 -0.4064)
			(end 0.7874 0.4064)
			(stroke
				(width 0.1524)
				(type default)
			)
			(layer "F.SilkS")
		)
		(fp_line
			(start 0.7874 0.4064)
			(end -0.7874 0.4064)
			(stroke
				(width 0.1524)
				(type default)
			)
			(layer "F.SilkS")
		)
		(fp_line
			(start -0.67945 -0.305054)
			(end -0.12065 -0.305054)
			(stroke
				(width 0.1)
				(type default)
			)
			(layer "F.Fab")
		)
		(fp_line
			(start -0.67945 0.3048)
			(end -0.67945 -0.305054)
			(stroke
				(width 0.1)
				(type default)
			)
			(layer "F.Fab")
		)
		(fp_line
			(start -0.12065 -0.305054)
			(end -0.12065 -0.2794)
			(stroke
				(width 0.1)
				(type default)
			)
			(layer "F.Fab")
		)
		(fp_line
			(start -0.12065 -0.2794)
			(end 0.12065 -0.2794)
			(stroke
				(width 0.1)
				(type default)
			)
			(layer "F.Fab")
		)
		(fp_line
			(start -0.12065 0.2794)
			(end -0.12065 0.3048)
			(stroke
				(width 0.1)
				(type default)
			)
			(layer "F.Fab")
		)
		(fp_line
			(start -0.12065 0.3048)
			(end -0.67945 0.3048)
			(stroke
				(width 0.1)
				(type default)
			)
			(layer "F.Fab")
		)
		(fp_line
			(start 0.120396 0.2794)
			(end -0.12065 0.2794)
			(stroke
				(width 0.1)
				(type default)
			)
			(layer "F.Fab")
		)
		(fp_line
			(start 0.120396 0.3048)
			(end 0.120396 0.2794)
			(stroke
				(width 0.1)
				(type default)
			)
			(layer "F.Fab")
		)
		(fp_line
			(start 0.12065 -0.3048)
			(end 0.67945 -0.3048)
			(stroke
				(width 0.1)
				(type default)
			)
			(layer "F.Fab")
		)
		(fp_line
			(start 0.12065 -0.2794)
			(end 0.12065 -0.3048)
			(stroke
				(width 0.1)
				(type default)
			)
			(layer "F.Fab")
		)
		(fp_line
			(start 0.67945 -0.3048)
			(end 0.67945 0.3048)
			(stroke
				(width 0.1)
				(type default)
			)
			(layer "F.Fab")
		)
		(fp_line
			(start 0.67945 0.3048)
			(end 0.120396 0.3048)
			(stroke
				(width 0.1)
				(type default)
			)
			(layer "F.Fab")
		)
		(pad "1" smd circle
			(at -0.40005 0)
			(size 0 0)
			(layers "F.Cu" "F.Mask" "F.Paste")
			(net "P3V3_AUX")
		)
		(pad "2" smd circle
			(at 0.40005 0)
			(size 0 0)
			(layers "F.Cu" "F.Mask" "F.Paste")
			(net "PRSNT_SSD12_R_N")
		)
	)
	(footprint ""
		(layer "F.Cu")
		(at 440.495944 -103.259128)
		(property "Reference" "C623"
			(at 0 0 0)
			(layer "F.SilkS")
			(hide yes)
			(effects
				(font
					(size 1.27 1.27)
				)
			)
		)
		(property "Value" ""
			(at 0 0 0)
			(layer "F.Fab")
			(effects
				(font
					(size 1.27 1.27)
				)
			)
		)
		(duplicate_pad_numbers_are_jumpers no)
		(fp_line
			(start -0.7874 -0.4064)
			(end 0.7874 -0.4064)
			(stroke
				(width 0.1524)
				(type default)
			)
			(layer "F.SilkS")
		)
		(fp_line
			(start -0.7874 0.4064)
			(end -0.7874 -0.4064)
			(stroke
				(width 0.1524)
				(type default)
			)
			(layer "F.SilkS")
		)
		(fp_line
			(start 0.7874 -0.4064)
			(end 0.7874 0.4064)
			(stroke
				(width 0.1524)
				(type default)
			)
			(layer "F.SilkS")
		)
		(fp_line
			(start 0.7874 0.4064)
			(end -0.7874 0.4064)
			(stroke
				(width 0.1524)
				(type default)
			)
			(layer "F.SilkS")
		)
		(fp_line
			(start -0.67945 -0.305054)
			(end -0.12065 -0.305054)
			(stroke
				(width 0.1)
				(type default)
			)
			(layer "F.Fab")
		)
		(fp_line
			(start -0.67945 0.3048)
			(end -0.67945 -0.305054)
			(stroke
				(width 0.1)
				(type default)
			)
			(layer "F.Fab")
		)
		(fp_line
			(start -0.12065 -0.305054)
			(end -0.12065 -0.2794)
			(stroke
				(width 0.1)
				(type default)
			)
			(layer "F.Fab")
		)
		(fp_line
			(start -0.12065 -0.2794)
			(end 0.12065 -0.2794)
			(stroke
				(width 0.1)
				(type default)
			)
			(layer "F.Fab")
		)
		(fp_line
			(start -0.12065 0.2794)
			(end -0.12065 0.3048)
			(stroke
				(width 0.1)
				(type default)
			)
			(layer "F.Fab")
		)
		(fp_line
			(start -0.12065 0.3048)
			(end -0.67945 0.3048)
			(stroke
				(width 0.1)
				(type default)
			)
			(layer "F.Fab")
		)
		(fp_line
			(start 0.120396 0.2794)
			(end -0.12065 0.2794)
			(stroke
				(width 0.1)
				(type default)
			)
			(layer "F.Fab")
		)
		(fp_line
			(start 0.120396 0.3048)
			(end 0.120396 0.2794)
			(stroke
				(width 0.1)
				(type default)
			)
			(layer "F.Fab")
		)
		(fp_line
			(start 0.12065 -0.3048)
			(end 0.67945 -0.3048)
			(stroke
				(width 0.1)
				(type default)
			)
			(layer "F.Fab")
		)
		(fp_line
			(start 0.12065 -0.2794)
			(end 0.12065 -0.3048)
			(stroke
				(width 0.1)
				(type default)
			)
			(layer "F.Fab")
		)
		(fp_line
			(start 0.67945 -0.3048)
			(end 0.67945 0.3048)
			(stroke
				(width 0.1)
				(type default)
			)
			(layer "F.Fab")
		)
		(fp_line
			(start 0.67945 0.3048)
			(end 0.120396 0.3048)
			(stroke
				(width 0.1)
				(type default)
			)
			(layer "F.Fab")
		)
		(pad "1" smd circle
			(at -0.40005 0)
			(size 0 0)
			(layers "F.Cu" "F.Mask" "F.Paste")
			(net "P12V_NIC7_R")
		)
		(pad "2" smd circle
			(at 0.40005 0)
			(size 0 0)
			(layers "F.Cu" "F.Mask" "F.Paste")
			(net "GND")
		)
	)
	(footprint ""
		(layer "F.Cu")
		(at 238.919512 -231.416606 90)
		(property "Reference" "R4514"
			(at 0 0 90)
			(layer "F.SilkS")
			(hide yes)
			(effects
				(font
					(size 1.27 1.27)
				)
			)
		)
		(property "Value" ""
			(at 0 0 90)
			(layer "F.Fab")
			(effects
				(font
					(size 1.27 1.27)
				)
			)
		)
		(duplicate_pad_numbers_are_jumpers no)
		(fp_line
			(start 0.7874 -0.4064)
			(end 0.7874 0.4064)
			(stroke
				(width 0.1524)
				(type default)
			)
			(layer "F.SilkS")
		)
		(fp_line
			(start -0.7874 -0.4064)
			(end 0.7874 -0.4064)
			(stroke
				(width 0.1524)
				(type default)
			)
			(layer "F.SilkS")
		)
		(fp_line
			(start 0.7874 0.4064)
			(end -0.7874 0.4064)
			(stroke
				(width 0.1524)
				(type default)
			)
			(layer "F.SilkS")
		)
		(fp_line
			(start -0.7874 0.4064)
			(end -0.7874 -0.4064)
			(stroke
				(width 0.1524)
				(type default)
			)
			(layer "F.SilkS")
		)
		(fp_line
			(start -0.12065 -0.305054)
			(end -0.12065 -0.2794)
			(stroke
				(width 0.1)
				(type default)
			)
			(layer "F.Fab")
		)
		(fp_line
			(start -0.67945 -0.305054)
			(end -0.12065 -0.305054)
			(stroke
				(width 0.1)
				(type default)
			)
			(layer "F.Fab")
		)
		(fp_line
			(start 0.67945 -0.3048)
			(end 0.67945 0.3048)
			(stroke
				(width 0.1)
				(type default)
			)
			(layer "F.Fab")
		)
		(fp_line
			(start 0.12065 -0.3048)
			(end 0.67945 -0.3048)
			(stroke
				(width 0.1)
				(type default)
			)
			(layer "F.Fab")
		)
		(fp_line
			(start 0.12065 -0.2794)
			(end 0.12065 -0.3048)
			(stroke
				(width 0.1)
				(type default)
			)
			(layer "F.Fab")
		)
		(fp_line
			(start -0.12065 -0.2794)
			(end 0.12065 -0.2794)
			(stroke
				(width 0.1)
				(type default)
			)
			(layer "F.Fab")
		)
		(fp_line
			(start 0.120396 0.2794)
			(end -0.12065 0.2794)
			(stroke
				(width 0.1)
				(type default)
			)
			(layer "F.Fab")
		)
		(fp_line
			(start -0.12065 0.2794)
			(end -0.12065 0.3048)
			(stroke
				(width 0.1)
				(type default)
			)
			(layer "F.Fab")
		)
		(fp_line
			(start 0.67945 0.3048)
			(end 0.120396 0.3048)
			(stroke
				(width 0.1)
				(type default)
			)
			(layer "F.Fab")
		)
		(fp_line
			(start 0.120396 0.3048)
			(end 0.120396 0.2794)
			(stroke
				(width 0.1)
				(type default)
			)
			(layer "F.Fab")
		)
		(fp_line
			(start -0.12065 0.3048)
			(end -0.67945 0.3048)
			(stroke
				(width 0.1)
				(type default)
			)
			(layer "F.Fab")
		)
		(fp_line
			(start -0.67945 0.3048)
			(end -0.67945 -0.305054)
			(stroke
				(width 0.1)
				(type default)
			)
			(layer "F.Fab")
		)
		(pad "1" smd circle
			(at -0.40005 0 90)
			(size 0 0)
			(layers "F.Cu" "F.Mask" "F.Paste")
			(net "SSD0_PWRDIS_BIC")
		)
		(pad "2" smd circle
			(at 0.40005 0 90)
			(size 0 0)
			(layers "F.Cu" "F.Mask" "F.Paste")
			(net "SSD0_PWRDIS_BIC_R")
		)
	)
	(footprint ""
		(layer "F.Cu")
		(at 143.030194 -284.404308 -90)
		(property "Reference" "C3189"
			(at 0 0 270)
			(layer "F.SilkS")
			(hide yes)
			(effects
				(font
					(size 1.27 1.27)
				)
			)
		)
		(property "Value" ""
			(at 0 0 270)
			(layer "F.Fab")
			(effects
				(font
					(size 1.27 1.27)
				)
			)
		)
		(duplicate_pad_numbers_are_jumpers no)
		(fp_line
			(start -1.2954 0.5842)
			(end -1.2954 -0.5842)
			(stroke
				(width 0.1524)
				(type default)
			)
			(layer "F.SilkS")
		)
		(fp_line
			(start 1.2954 0.5842)
			(end -1.2954 0.5842)
			(stroke
				(width 0.1524)
				(type default)
			)
			(layer "F.SilkS")
		)
		(fp_line
			(start -1.2954 -0.5842)
			(end 1.2954 -0.5842)
			(stroke
				(width 0.1524)
				(type default)
			)
			(layer "F.SilkS")
		)
		(fp_line
			(start 1.2954 -0.5842)
			(end 1.2954 0.5842)
			(stroke
				(width 0.1524)
				(type default)
			)
			(layer "F.SilkS")
		)
		(fp_line
			(start -0.8636 0.4572)
			(end -0.8636 0.4064)
			(stroke
				(width 0.1)
				(type default)
			)
			(layer "F.Fab")
		)
		(fp_line
			(start 0.8636 0.4572)
			(end -0.8636 0.4572)
			(stroke
				(width 0.1)
				(type default)
			)
			(layer "F.Fab")
		)
		(fp_line
			(start -1.1938 0.4064)
			(end -1.1938 -0.4064)
			(stroke
				(width 0.1)
				(type default)
			)
			(layer "F.Fab")
		)
		(fp_line
			(start -0.8636 0.4064)
			(end -1.1938 0.4064)
			(stroke
				(width 0.1)
				(type default)
			)
			(layer "F.Fab")
		)
		(fp_line
			(start 0.8636 0.4064)
			(end 0.8636 0.4572)
			(stroke
				(width 0.1)
				(type default)
			)
			(layer "F.Fab")
		)
		(fp_line
			(start 1.1938 0.4064)
			(end 0.8636 0.4064)
			(stroke
				(width 0.1)
				(type default)
			)
			(layer "F.Fab")
		)
		(fp_line
			(start -1.1938 -0.4064)
			(end -0.8636 -0.4064)
			(stroke
				(width 0.1)
				(type default)
			)
			(layer "F.Fab")
		)
		(fp_line
			(start -0.8636 -0.4064)
			(end -0.8636 -0.4572)
			(stroke
				(width 0.1)
				(type default)
			)
			(layer "F.Fab")
		)
		(fp_line
			(start 0.8636 -0.4064)
			(end 1.1938 -0.4064)
			(stroke
				(width 0.1)
				(type default)
			)
			(layer "F.Fab")
		)
		(fp_line
			(start 1.1938 -0.4064)
			(end 1.1938 0.4064)
			(stroke
				(width 0.1)
				(type default)
			)
			(layer "F.Fab")
		)
		(fp_line
			(start -0.8636 -0.4572)
			(end 0.8636 -0.4572)
			(stroke
				(width 0.1)
				(type default)
			)
			(layer "F.Fab")
		)
		(fp_line
			(start 0.8636 -0.4572)
			(end 0.8636 -0.4064)
			(stroke
				(width 0.1)
				(type default)
			)
			(layer "F.Fab")
		)
		(pad "1" smd rect
			(at -0.7366 0 180)
			(size 0.7112 0.8128)
			(layers "F.Cu" "F.Mask" "F.Paste")
			(net "P1V8_PLL0_PEX1")
		)
		(pad "2" smd rect
			(at 0.7366 0 180)
			(size 0.7112 0.8128)
			(layers "F.Cu" "F.Mask" "F.Paste")
			(net "GND")
		)
	)
	(footprint ""
		(layer "F.Cu")
		(at 326.694038 -115.394486)
		(property "Reference" "PR7102"
			(at 0 0 0)
			(layer "F.SilkS")
			(hide yes)
			(effects
				(font
					(size 1.27 1.27)
				)
			)
		)
		(property "Value" ""
			(at 0 0 0)
			(layer "F.Fab")
			(effects
				(font
					(size 1.27 1.27)
				)
			)
		)
		(duplicate_pad_numbers_are_jumpers no)
		(fp_line
			(start -0.7874 -0.4064)
			(end 0.7874 -0.4064)
			(stroke
				(width 0.1524)
				(type default)
			)
			(layer "F.SilkS")
		)
		(fp_line
			(start -0.7874 0.4064)
			(end -0.7874 -0.4064)
			(stroke
				(width 0.1524)
				(type default)
			)
			(layer "F.SilkS")
		)
		(fp_line
			(start 0.7874 -0.4064)
			(end 0.7874 0.4064)
			(stroke
				(width 0.1524)
				(type default)
			)
			(layer "F.SilkS")
		)
		(fp_line
			(start 0.7874 0.4064)
			(end -0.7874 0.4064)
			(stroke
				(width 0.1524)
				(type default)
			)
			(layer "F.SilkS")
		)
		(fp_line
			(start -0.67945 -0.305054)
			(end -0.12065 -0.305054)
			(stroke
				(width 0.1)
				(type default)
			)
			(layer "F.Fab")
		)
		(fp_line
			(start -0.67945 0.3048)
			(end -0.67945 -0.305054)
			(stroke
				(width 0.1)
				(type default)
			)
			(layer "F.Fab")
		)
		(fp_line
			(start -0.12065 -0.305054)
			(end -0.12065 -0.2794)
			(stroke
				(width 0.1)
				(type default)
			)
			(layer "F.Fab")
		)
		(fp_line
			(start -0.12065 -0.2794)
			(end 0.12065 -0.2794)
			(stroke
				(width 0.1)
				(type default)
			)
			(layer "F.Fab")
		)
		(fp_line
			(start -0.12065 0.2794)
			(end -0.12065 0.3048)
			(stroke
				(width 0.1)
				(type default)
			)
			(layer "F.Fab")
		)
		(fp_line
			(start -0.12065 0.3048)
			(end -0.67945 0.3048)
			(stroke
				(width 0.1)
				(type default)
			)
			(layer "F.Fab")
		)
		(fp_line
			(start 0.120396 0.2794)
			(end -0.12065 0.2794)
			(stroke
				(width 0.1)
				(type default)
			)
			(layer "F.Fab")
		)
		(fp_line
			(start 0.120396 0.3048)
			(end 0.120396 0.2794)
			(stroke
				(width 0.1)
				(type default)
			)
			(layer "F.Fab")
		)
		(fp_line
			(start 0.12065 -0.3048)
			(end 0.67945 -0.3048)
			(stroke
				(width 0.1)
				(type default)
			)
			(layer "F.Fab")
		)
		(fp_line
			(start 0.12065 -0.2794)
			(end 0.12065 -0.3048)
			(stroke
				(width 0.1)
				(type default)
			)
			(layer "F.Fab")
		)
		(fp_line
			(start 0.67945 -0.3048)
			(end 0.67945 0.3048)
			(stroke
				(width 0.1)
				(type default)
			)
			(layer "F.Fab")
		)
		(fp_line
			(start 0.67945 0.3048)
			(end 0.120396 0.3048)
			(stroke
				(width 0.1)
				(type default)
			)
			(layer "F.Fab")
		)
		(pad "1" smd circle
			(at -0.40005 0)
			(size 0 0)
			(layers "F.Cu" "F.Mask" "F.Paste")
			(net "P3V3_NIC5_CO_ILIMIT")
		)
		(pad "2" smd circle
			(at 0.40005 0)
			(size 0 0)
			(layers "F.Cu" "F.Mask" "F.Paste")
			(net "GND")
		)
	)
	(footprint ""
		(layer "F.Cu")
		(at 258.242562 -211.749386)
		(property "Reference" "C2491"
			(at 0 0 0)
			(layer "F.SilkS")
			(hide yes)
			(effects
				(font
					(size 1.27 1.27)
				)
			)
		)
		(property "Value" ""
			(at 0 0 0)
			(layer "F.Fab")
			(effects
				(font
					(size 1.27 1.27)
				)
			)
		)
		(duplicate_pad_numbers_are_jumpers no)
		(fp_line
			(start -0.7874 -0.4064)
			(end 0.7874 -0.4064)
			(stroke
				(width 0.1524)
				(type default)
			)
			(layer "F.SilkS")
		)
		(fp_line
			(start -0.7874 0.4064)
			(end -0.7874 -0.4064)
			(stroke
				(width 0.1524)
				(type default)
			)
			(layer "F.SilkS")
		)
		(fp_line
			(start 0.7874 -0.4064)
			(end 0.7874 0.4064)
			(stroke
				(width 0.1524)
				(type default)
			)
			(layer "F.SilkS")
		)
		(fp_line
			(start 0.7874 0.4064)
			(end -0.7874 0.4064)
			(stroke
				(width 0.1524)
				(type default)
			)
			(layer "F.SilkS")
		)
		(fp_line
			(start -0.67945 -0.305054)
			(end -0.12065 -0.305054)
			(stroke
				(width 0.1)
				(type default)
			)
			(layer "F.Fab")
		)
		(fp_line
			(start -0.67945 0.3048)
			(end -0.67945 -0.305054)
			(stroke
				(width 0.1)
				(type default)
			)
			(layer "F.Fab")
		)
		(fp_line
			(start -0.12065 -0.305054)
			(end -0.12065 -0.2794)
			(stroke
				(width 0.1)
				(type default)
			)
			(layer "F.Fab")
		)
		(fp_line
			(start -0.12065 -0.2794)
			(end 0.12065 -0.2794)
			(stroke
				(width 0.1)
				(type default)
			)
			(layer "F.Fab")
		)
		(fp_line
			(start -0.12065 0.2794)
			(end -0.12065 0.3048)
			(stroke
				(width 0.1)
				(type default)
			)
			(layer "F.Fab")
		)
		(fp_line
			(start -0.12065 0.3048)
			(end -0.67945 0.3048)
			(stroke
				(width 0.1)
				(type default)
			)
			(layer "F.Fab")
		)
		(fp_line
			(start 0.120396 0.2794)
			(end -0.12065 0.2794)
			(stroke
				(width 0.1)
				(type default)
			)
			(layer "F.Fab")
		)
		(fp_line
			(start 0.120396 0.3048)
			(end 0.120396 0.2794)
			(stroke
				(width 0.1)
				(type default)
			)
			(layer "F.Fab")
		)
		(fp_line
			(start 0.12065 -0.3048)
			(end 0.67945 -0.3048)
			(stroke
				(width 0.1)
				(type default)
			)
			(layer "F.Fab")
		)
		(fp_line
			(start 0.12065 -0.2794)
			(end 0.12065 -0.3048)
			(stroke
				(width 0.1)
				(type default)
			)
			(layer "F.Fab")
		)
		(fp_line
			(start 0.67945 -0.3048)
			(end 0.67945 0.3048)
			(stroke
				(width 0.1)
				(type default)
			)
			(layer "F.Fab")
		)
		(fp_line
			(start 0.67945 0.3048)
			(end 0.120396 0.3048)
			(stroke
				(width 0.1)
				(type default)
			)
			(layer "F.Fab")
		)
		(pad "1" smd circle
			(at -0.40005 0)
			(size 0 0)
			(layers "F.Cu" "F.Mask" "F.Paste")
			(net "PWR_EN_P1V2_AUX_R")
		)
		(pad "2" smd circle
			(at 0.40005 0)
			(size 0 0)
			(layers "F.Cu" "F.Mask" "F.Paste")
			(net "GND")
		)
	)
	(footprint ""
		(layer "F.Cu")
		(at 58.357262 -390.07161 90)
		(property "Reference" "R1827"
			(at 0 0 90)
			(layer "F.SilkS")
			(hide yes)
			(effects
				(font
					(size 1.27 1.27)
				)
			)
		)
		(property "Value" ""
			(at 0 0 90)
			(layer "F.Fab")
			(effects
				(font
					(size 1.27 1.27)
				)
			)
		)
		(duplicate_pad_numbers_are_jumpers no)
		(fp_line
			(start 0.7874 -0.4064)
			(end 0.7874 0.4064)
			(stroke
				(width 0.1524)
				(type default)
			)
			(layer "F.SilkS")
		)
		(fp_line
			(start -0.7874 -0.4064)
			(end 0.7874 -0.4064)
			(stroke
				(width 0.1524)
				(type default)
			)
			(layer "F.SilkS")
		)
		(fp_line
			(start 0.7874 0.4064)
			(end -0.7874 0.4064)
			(stroke
				(width 0.1524)
				(type default)
			)
			(layer "F.SilkS")
		)
		(fp_line
			(start -0.7874 0.4064)
			(end -0.7874 -0.4064)
			(stroke
				(width 0.1524)
				(type default)
			)
			(layer "F.SilkS")
		)
		(fp_line
			(start -0.12065 -0.305054)
			(end -0.12065 -0.2794)
			(stroke
				(width 0.1)
				(type default)
			)
			(layer "F.Fab")
		)
		(fp_line
			(start -0.67945 -0.305054)
			(end -0.12065 -0.305054)
			(stroke
				(width 0.1)
				(type default)
			)
			(layer "F.Fab")
		)
		(fp_line
			(start 0.67945 -0.3048)
			(end 0.67945 0.3048)
			(stroke
				(width 0.1)
				(type default)
			)
			(layer "F.Fab")
		)
		(fp_line
			(start 0.12065 -0.3048)
			(end 0.67945 -0.3048)
			(stroke
				(width 0.1)
				(type default)
			)
			(layer "F.Fab")
		)
		(fp_line
			(start 0.12065 -0.2794)
			(end 0.12065 -0.3048)
			(stroke
				(width 0.1)
				(type default)
			)
			(layer "F.Fab")
		)
		(fp_line
			(start -0.12065 -0.2794)
			(end 0.12065 -0.2794)
			(stroke
				(width 0.1)
				(type default)
			)
			(layer "F.Fab")
		)
		(fp_line
			(start 0.120396 0.2794)
			(end -0.12065 0.2794)
			(stroke
				(width 0.1)
				(type default)
			)
			(layer "F.Fab")
		)
		(fp_line
			(start -0.12065 0.2794)
			(end -0.12065 0.3048)
			(stroke
				(width 0.1)
				(type default)
			)
			(layer "F.Fab")
		)
		(fp_line
			(start 0.67945 0.3048)
			(end 0.120396 0.3048)
			(stroke
				(width 0.1)
				(type default)
			)
			(layer "F.Fab")
		)
		(fp_line
			(start 0.120396 0.3048)
			(end 0.120396 0.2794)
			(stroke
				(width 0.1)
				(type default)
			)
			(layer "F.Fab")
		)
		(fp_line
			(start -0.12065 0.3048)
			(end -0.67945 0.3048)
			(stroke
				(width 0.1)
				(type default)
			)
			(layer "F.Fab")
		)
		(fp_line
			(start -0.67945 0.3048)
			(end -0.67945 -0.305054)
			(stroke
				(width 0.1)
				(type default)
			)
			(layer "F.Fab")
		)
		(pad "1" smd circle
			(at -0.40005 0 90)
			(size 0 0)
			(layers "F.Cu" "F.Mask" "F.Paste")
			(net "GPU_THERM_OVERT_R_N")
		)
		(pad "2" smd circle
			(at 0.40005 0 90)
			(size 0 0)
			(layers "F.Cu" "F.Mask" "F.Paste")
			(net "GPU_THERM_OVERT_N")
		)
	)
	(footprint ""
		(layer "F.Cu")
		(at 148.570442 -250.070874 -90)
		(property "Reference" "R1277"
			(at 0 0 270)
			(layer "F.SilkS")
			(hide yes)
			(effects
				(font
					(size 1.27 1.27)
				)
			)
		)
		(property "Value" ""
			(at 0 0 270)
			(layer "F.Fab")
			(effects
				(font
					(size 1.27 1.27)
				)
			)
		)
		(duplicate_pad_numbers_are_jumpers no)
		(fp_line
			(start -0.7874 0.4064)
			(end -0.7874 -0.4064)
			(stroke
				(width 0.1524)
				(type default)
			)
			(layer "F.SilkS")
		)
		(fp_line
			(start 0.7874 0.4064)
			(end -0.7874 0.4064)
			(stroke
				(width 0.1524)
				(type default)
			)
			(layer "F.SilkS")
		)
		(fp_line
			(start -0.7874 -0.4064)
			(end 0.7874 -0.4064)
			(stroke
				(width 0.1524)
				(type default)
			)
			(layer "F.SilkS")
		)
		(fp_line
			(start 0.7874 -0.4064)
			(end 0.7874 0.4064)
			(stroke
				(width 0.1524)
				(type default)
			)
			(layer "F.SilkS")
		)
		(fp_line
			(start -0.67945 0.3048)
			(end -0.67945 -0.305054)
			(stroke
				(width 0.1)
				(type default)
			)
			(layer "F.Fab")
		)
		(fp_line
			(start -0.12065 0.3048)
			(end -0.67945 0.3048)
			(stroke
				(width 0.1)
				(type default)
			)
			(layer "F.Fab")
		)
		(fp_line
			(start 0.120396 0.3048)
			(end 0.120396 0.2794)
			(stroke
				(width 0.1)
				(type default)
			)
			(layer "F.Fab")
		)
		(fp_line
			(start 0.67945 0.3048)
			(end 0.120396 0.3048)
			(stroke
				(width 0.1)
				(type default)
			)
			(layer "F.Fab")
		)
		(fp_line
			(start -0.12065 0.2794)
			(end -0.12065 0.3048)
			(stroke
				(width 0.1)
				(type default)
			)
			(layer "F.Fab")
		)
		(fp_line
			(start 0.120396 0.2794)
			(end -0.12065 0.2794)
			(stroke
				(width 0.1)
				(type default)
			)
			(layer "F.Fab")
		)
		(fp_line
			(start -0.12065 -0.2794)
			(end 0.12065 -0.2794)
			(stroke
				(width 0.1)
				(type default)
			)
			(layer "F.Fab")
		)
		(fp_line
			(start 0.12065 -0.2794)
			(end 0.12065 -0.3048)
			(stroke
				(width 0.1)
				(type default)
			)
			(layer "F.Fab")
		)
		(fp_line
			(start 0.12065 -0.3048)
			(end 0.67945 -0.3048)
			(stroke
				(width 0.1)
				(type default)
			)
			(layer "F.Fab")
		)
		(fp_line
			(start 0.67945 -0.3048)
			(end 0.67945 0.3048)
			(stroke
				(width 0.1)
				(type default)
			)
			(layer "F.Fab")
		)
		(fp_line
			(start -0.67945 -0.305054)
			(end -0.12065 -0.305054)
			(stroke
				(width 0.1)
				(type default)
			)
			(layer "F.Fab")
		)
		(fp_line
			(start -0.12065 -0.305054)
			(end -0.12065 -0.2794)
			(stroke
				(width 0.1)
				(type default)
			)
			(layer "F.Fab")
		)
		(pad "1" smd circle
			(at -0.40005 0 270)
			(size 0 0)
			(layers "F.Cu" "F.Mask" "F.Paste")
			(net "PEX1_MODE_SEL8")
		)
		(pad "2" smd circle
			(at 0.40005 0 270)
			(size 0 0)
			(layers "F.Cu" "F.Mask" "F.Paste")
			(net "P1V8_PEX")
		)
	)
	(footprint ""
		(layer "F.Cu")
		(at 376.34926 -280.994612 -90)
		(property "Reference" "C3586"
			(at 0 0 270)
			(layer "F.SilkS")
			(hide yes)
			(effects
				(font
					(size 1.27 1.27)
				)
			)
		)
		(property "Value" ""
			(at 0 0 270)
			(layer "F.Fab")
			(effects
				(font
					(size 1.27 1.27)
				)
			)
		)
		(duplicate_pad_numbers_are_jumpers no)
		(fp_line
			(start -0.299974 0.150114)
			(end -0.299974 -0.150114)
			(stroke
				(width 0.1)
				(type default)
			)
			(layer "F.Fab")
		)
		(fp_line
			(start 0.299974 0.150114)
			(end -0.299974 0.150114)
			(stroke
				(width 0.1)
				(type default)
			)
			(layer "F.Fab")
		)
		(fp_line
			(start -0.299974 -0.150114)
			(end 0.299974 -0.150114)
			(stroke
				(width 0.1)
				(type default)
			)
			(layer "F.Fab")
		)
		(fp_line
			(start 0.299974 -0.150114)
			(end 0.299974 0.150114)
			(stroke
				(width 0.1)
				(type default)
			)
			(layer "F.Fab")
		)
		(pad "1" smd rect
			(at -0.2667 0 270)
			(size 0.3048 0.381)
			(layers "F.Cu" "F.Mask" "F.Paste")
			(net "P1V8_PLL0_PEX3")
		)
		(pad "2" smd rect
			(at 0.2667 0 270)
			(size 0.3048 0.381)
			(layers "F.Cu" "F.Mask" "F.Paste")
			(net "GND")
		)
	)
	(footprint ""
		(layer "F.Cu")
		(at 104.839008 -231.191562 90)
		(property "Reference" "PL26"
			(at -3.556762 -4.152138 90)
			(unlocked yes)
			(layer "F.SilkS")
			(effects
				(font
					(size 0.7874 0.5842)
					(thickness 0.1524)
				)
				(justify left)
			)
		)
		(property "Value" ""
			(at 0 0 90)
			(layer "F.Fab")
			(effects
				(font
					(size 1.27 1.27)
				)
			)
		)
		(duplicate_pad_numbers_are_jumpers no)
		(fp_line
			(start 3.64998 -3.350006)
			(end 3.64998 -1.8034)
			(stroke
				(width 0.1524)
				(type default)
			)
			(layer "F.SilkS")
		)
		(fp_line
			(start -3.6576 -3.350006)
			(end 3.64998 -3.350006)
			(stroke
				(width 0.1524)
				(type default)
			)
			(layer "F.SilkS")
		)
		(fp_line
			(start -3.64998 -1.8034)
			(end -3.64998 -3.350006)
			(stroke
				(width 0.1524)
				(type default)
			)
			(layer "F.SilkS")
		)
		(fp_line
			(start 3.64998 1.8034)
			(end 3.64998 3.350006)
			(stroke
				(width 0.1524)
				(type default)
			)
			(layer "F.SilkS")
		)
		(fp_line
			(start 3.64998 3.350006)
			(end -3.64998 3.350006)
			(stroke
				(width 0.1524)
				(type default)
			)
			(layer "F.SilkS")
		)
		(fp_line
			(start -3.64998 3.350006)
			(end -3.64998 1.8288)
			(stroke
				(width 0.1524)
				(type default)
			)
			(layer "F.SilkS")
		)
		(fp_line
			(start 3.64998 -3.350006)
			(end 3.64998 3.350006)
			(stroke
				(width 0.1)
				(type default)
			)
			(layer "F.Fab")
		)
		(fp_line
			(start -3.64998 -3.350006)
			(end 3.64998 -3.350006)
			(stroke
				(width 0.1)
				(type default)
			)
			(layer "F.Fab")
		)
		(fp_line
			(start 3.64998 3.350006)
			(end -3.64998 3.350006)
			(stroke
				(width 0.1)
				(type default)
			)
			(layer "F.Fab")
		)
		(fp_line
			(start -3.64998 3.350006)
			(end -3.64998 -3.350006)
			(stroke
				(width 0.1)
				(type default)
			)
			(layer "F.Fab")
		)
		(pad "1" smd rect
			(at -2.92481 0 90)
			(size 2.15392 3.302)
			(layers "F.Cu" "F.Mask" "F.Paste")
			(net "SW_P1V8_PEX_PH")
		)
		(pad "2" smd rect
			(at 2.92481 0 90)
			(size 2.15392 3.302)
			(layers "F.Cu" "F.Mask" "F.Paste")
			(net "P1V8_PEX_R")
		)
	)
	(footprint ""
		(layer "F.Cu")
		(at 137.622788 -350.098614 90)
		(property "Reference" "C2266"
			(at 0 0 90)
			(layer "F.SilkS")
			(hide yes)
			(effects
				(font
					(size 1.27 1.27)
				)
			)
		)
		(property "Value" ""
			(at 0 0 90)
			(layer "F.Fab")
			(effects
				(font
					(size 1.27 1.27)
				)
			)
		)
		(duplicate_pad_numbers_are_jumpers no)
		(fp_line
			(start 0.299974 -0.150114)
			(end 0.299974 0.150114)
			(stroke
				(width 0.1)
				(type default)
			)
			(layer "F.Fab")
		)
		(fp_line
			(start -0.299974 -0.150114)
			(end 0.299974 -0.150114)
			(stroke
				(width 0.1)
				(type default)
			)
			(layer "F.Fab")
		)
		(fp_line
			(start 0.299974 0.150114)
			(end -0.299974 0.150114)
			(stroke
				(width 0.1)
				(type default)
			)
			(layer "F.Fab")
		)
		(fp_line
			(start -0.299974 0.150114)
			(end -0.299974 -0.150114)
			(stroke
				(width 0.1)
				(type default)
			)
			(layer "F.Fab")
		)
		(pad "1" smd rect
			(at -0.2667 0 90)
			(size 0.3048 0.381)
			(layers "F.Cu" "F.Mask" "F.Paste")
			(net "P5E_PEX1_STN5_TX_DN<84>")
		)
		(pad "2" smd rect
			(at 0.2667 0 90)
			(size 0.3048 0.381)
			(layers "F.Cu" "F.Mask" "F.Paste")
			(net "P5E_PEX1_STN5_TX_C_DN<84>")
		)
	)
	(footprint ""
		(layer "F.Cu")
		(at 319.140332 -143.182848 90)
		(property "Reference" "C4003"
			(at 0 0 90)
			(layer "F.SilkS")
			(hide yes)
			(effects
				(font
					(size 1.27 1.27)
				)
			)
		)
		(property "Value" ""
			(at 0 0 90)
			(layer "F.Fab")
			(effects
				(font
					(size 1.27 1.27)
				)
			)
		)
		(duplicate_pad_numbers_are_jumpers no)
		(fp_line
			(start 0.7874 -0.4064)
			(end 0.7874 0.4064)
			(stroke
				(width 0.1524)
				(type default)
			)
			(layer "F.SilkS")
		)
		(fp_line
			(start -0.7874 -0.4064)
			(end 0.7874 -0.4064)
			(stroke
				(width 0.1524)
				(type default)
			)
			(layer "F.SilkS")
		)
		(fp_line
			(start 0.7874 0.4064)
			(end -0.7874 0.4064)
			(stroke
				(width 0.1524)
				(type default)
			)
			(layer "F.SilkS")
		)
		(fp_line
			(start -0.7874 0.4064)
			(end -0.7874 -0.4064)
			(stroke
				(width 0.1524)
				(type default)
			)
			(layer "F.SilkS")
		)
		(fp_line
			(start -0.12065 -0.305054)
			(end -0.12065 -0.2794)
			(stroke
				(width 0.1)
				(type default)
			)
			(layer "F.Fab")
		)
		(fp_line
			(start -0.67945 -0.305054)
			(end -0.12065 -0.305054)
			(stroke
				(width 0.1)
				(type default)
			)
			(layer "F.Fab")
		)
		(fp_line
			(start 0.67945 -0.3048)
			(end 0.67945 0.3048)
			(stroke
				(width 0.1)
				(type default)
			)
			(layer "F.Fab")
		)
		(fp_line
			(start 0.12065 -0.3048)
			(end 0.67945 -0.3048)
			(stroke
				(width 0.1)
				(type default)
			)
			(layer "F.Fab")
		)
		(fp_line
			(start 0.12065 -0.2794)
			(end 0.12065 -0.3048)
			(stroke
				(width 0.1)
				(type default)
			)
			(layer "F.Fab")
		)
		(fp_line
			(start -0.12065 -0.2794)
			(end 0.12065 -0.2794)
			(stroke
				(width 0.1)
				(type default)
			)
			(layer "F.Fab")
		)
		(fp_line
			(start 0.120396 0.2794)
			(end -0.12065 0.2794)
			(stroke
				(width 0.1)
				(type default)
			)
			(layer "F.Fab")
		)
		(fp_line
			(start -0.12065 0.2794)
			(end -0.12065 0.3048)
			(stroke
				(width 0.1)
				(type default)
			)
			(layer "F.Fab")
		)
		(fp_line
			(start 0.67945 0.3048)
			(end 0.120396 0.3048)
			(stroke
				(width 0.1)
				(type default)
			)
			(layer "F.Fab")
		)
		(fp_line
			(start 0.120396 0.3048)
			(end 0.120396 0.2794)
			(stroke
				(width 0.1)
				(type default)
			)
			(layer "F.Fab")
		)
		(fp_line
			(start -0.12065 0.3048)
			(end -0.67945 0.3048)
			(stroke
				(width 0.1)
				(type default)
			)
			(layer "F.Fab")
		)
		(fp_line
			(start -0.67945 0.3048)
			(end -0.67945 -0.305054)
			(stroke
				(width 0.1)
				(type default)
			)
			(layer "F.Fab")
		)
		(pad "1" smd circle
			(at -0.40005 0 90)
			(size 0 0)
			(layers "F.Cu" "F.Mask" "F.Paste")
			(net "PRSNT_NIC5_R_N")
		)
		(pad "2" smd circle
			(at 0.40005 0 90)
			(size 0 0)
			(layers "F.Cu" "F.Mask" "F.Paste")
			(net "GND")
		)
	)
	(footprint ""
		(layer "F.Cu")
		(at 202.774296 -303.938686 -90)
		(property "Reference" "R6808"
			(at 0 0 270)
			(layer "F.SilkS")
			(hide yes)
			(effects
				(font
					(size 1.27 1.27)
				)
			)
		)
		(property "Value" ""
			(at 0 0 270)
			(layer "F.Fab")
			(effects
				(font
					(size 1.27 1.27)
				)
			)
		)
		(duplicate_pad_numbers_are_jumpers no)
		(fp_line
			(start -0.7874 0.4064)
			(end -0.7874 -0.4064)
			(stroke
				(width 0.1524)
				(type default)
			)
			(layer "F.SilkS")
		)
		(fp_line
			(start 0.7874 0.4064)
			(end -0.7874 0.4064)
			(stroke
				(width 0.1524)
				(type default)
			)
			(layer "F.SilkS")
		)
		(fp_line
			(start -0.7874 -0.4064)
			(end 0.7874 -0.4064)
			(stroke
				(width 0.1524)
				(type default)
			)
			(layer "F.SilkS")
		)
		(fp_line
			(start 0.7874 -0.4064)
			(end 0.7874 0.4064)
			(stroke
				(width 0.1524)
				(type default)
			)
			(layer "F.SilkS")
		)
		(fp_line
			(start -0.67945 0.3048)
			(end -0.67945 -0.305054)
			(stroke
				(width 0.1)
				(type default)
			)
			(layer "F.Fab")
		)
		(fp_line
			(start -0.12065 0.3048)
			(end -0.67945 0.3048)
			(stroke
				(width 0.1)
				(type default)
			)
			(layer "F.Fab")
		)
		(fp_line
			(start 0.120396 0.3048)
			(end 0.120396 0.2794)
			(stroke
				(width 0.1)
				(type default)
			)
			(layer "F.Fab")
		)
		(fp_line
			(start 0.67945 0.3048)
			(end 0.120396 0.3048)
			(stroke
				(width 0.1)
				(type default)
			)
			(layer "F.Fab")
		)
		(fp_line
			(start -0.12065 0.2794)
			(end -0.12065 0.3048)
			(stroke
				(width 0.1)
				(type default)
			)
			(layer "F.Fab")
		)
		(fp_line
			(start 0.120396 0.2794)
			(end -0.12065 0.2794)
			(stroke
				(width 0.1)
				(type default)
			)
			(layer "F.Fab")
		)
		(fp_line
			(start -0.12065 -0.2794)
			(end 0.12065 -0.2794)
			(stroke
				(width 0.1)
				(type default)
			)
			(layer "F.Fab")
		)
		(fp_line
			(start 0.12065 -0.2794)
			(end 0.12065 -0.3048)
			(stroke
				(width 0.1)
				(type default)
			)
			(layer "F.Fab")
		)
		(fp_line
			(start 0.12065 -0.3048)
			(end 0.67945 -0.3048)
			(stroke
				(width 0.1)
				(type default)
			)
			(layer "F.Fab")
		)
		(fp_line
			(start 0.67945 -0.3048)
			(end 0.67945 0.3048)
			(stroke
				(width 0.1)
				(type default)
			)
			(layer "F.Fab")
		)
		(fp_line
			(start -0.67945 -0.305054)
			(end -0.12065 -0.305054)
			(stroke
				(width 0.1)
				(type default)
			)
			(layer "F.Fab")
		)
		(fp_line
			(start -0.12065 -0.305054)
			(end -0.12065 -0.2794)
			(stroke
				(width 0.1)
				(type default)
			)
			(layer "F.Fab")
		)
		(pad "1" smd circle
			(at -0.40005 0 270)
			(size 0 0)
			(layers "F.Cu" "F.Mask" "F.Paste")
			(net "SMB_PEX1_R_SCL")
		)
		(pad "2" smd circle
			(at 0.40005 0 270)
			(size 0 0)
			(layers "F.Cu" "F.Mask" "F.Paste")
			(net "SMB_PEX1_SCL")
		)
	)
	(footprint ""
		(layer "F.Cu")
		(at 379.633988 -4.836922)
		(property "Reference" "R5817"
			(at 0 0 0)
			(layer "F.SilkS")
			(hide yes)
			(effects
				(font
					(size 1.27 1.27)
				)
			)
		)
		(property "Value" ""
			(at 0 0 0)
			(layer "F.Fab")
			(effects
				(font
					(size 1.27 1.27)
				)
			)
		)
		(duplicate_pad_numbers_are_jumpers no)
		(fp_line
			(start -0.7874 -0.4064)
			(end 0.7874 -0.4064)
			(stroke
				(width 0.1524)
				(type default)
			)
			(layer "F.SilkS")
		)
		(fp_line
			(start -0.7874 0.4064)
			(end -0.7874 -0.4064)
			(stroke
				(width 0.1524)
				(type default)
			)
			(layer "F.SilkS")
		)
		(fp_line
			(start 0.7874 -0.4064)
			(end 0.7874 0.4064)
			(stroke
				(width 0.1524)
				(type default)
			)
			(layer "F.SilkS")
		)
		(fp_line
			(start 0.7874 0.4064)
			(end -0.7874 0.4064)
			(stroke
				(width 0.1524)
				(type default)
			)
			(layer "F.SilkS")
		)
		(fp_line
			(start -0.67945 -0.305054)
			(end -0.12065 -0.305054)
			(stroke
				(width 0.1)
				(type default)
			)
			(layer "F.Fab")
		)
		(fp_line
			(start -0.67945 0.3048)
			(end -0.67945 -0.305054)
			(stroke
				(width 0.1)
				(type default)
			)
			(layer "F.Fab")
		)
		(fp_line
			(start -0.12065 -0.305054)
			(end -0.12065 -0.2794)
			(stroke
				(width 0.1)
				(type default)
			)
			(layer "F.Fab")
		)
		(fp_line
			(start -0.12065 -0.2794)
			(end 0.12065 -0.2794)
			(stroke
				(width 0.1)
				(type default)
			)
			(layer "F.Fab")
		)
		(fp_line
			(start -0.12065 0.2794)
			(end -0.12065 0.3048)
			(stroke
				(width 0.1)
				(type default)
			)
			(layer "F.Fab")
		)
		(fp_line
			(start -0.12065 0.3048)
			(end -0.67945 0.3048)
			(stroke
				(width 0.1)
				(type default)
			)
			(layer "F.Fab")
		)
		(fp_line
			(start 0.120396 0.2794)
			(end -0.12065 0.2794)
			(stroke
				(width 0.1)
				(type default)
			)
			(layer "F.Fab")
		)
		(fp_line
			(start 0.120396 0.3048)
			(end 0.120396 0.2794)
			(stroke
				(width 0.1)
				(type default)
			)
			(layer "F.Fab")
		)
		(fp_line
			(start 0.12065 -0.3048)
			(end 0.67945 -0.3048)
			(stroke
				(width 0.1)
				(type default)
			)
			(layer "F.Fab")
		)
		(fp_line
			(start 0.12065 -0.2794)
			(end 0.12065 -0.3048)
			(stroke
				(width 0.1)
				(type default)
			)
			(layer "F.Fab")
		)
		(fp_line
			(start 0.67945 -0.3048)
			(end 0.67945 0.3048)
			(stroke
				(width 0.1)
				(type default)
			)
			(layer "F.Fab")
		)
		(fp_line
			(start 0.67945 0.3048)
			(end 0.120396 0.3048)
			(stroke
				(width 0.1)
				(type default)
			)
			(layer "F.Fab")
		)
		(pad "1" smd circle
			(at -0.40005 0)
			(size 0 0)
			(layers "F.Cu" "F.Mask" "F.Paste")
			(net "LM75_3_A2")
		)
		(pad "2" smd circle
			(at 0.40005 0)
			(size 0 0)
			(layers "F.Cu" "F.Mask" "F.Paste")
			(net "P3V3_AUX")
		)
	)
	(footprint ""
		(layer "F.Cu")
		(at 104.267762 -54.067456)
		(property "Reference" "PR221"
			(at 0 0 0)
			(layer "F.SilkS")
			(hide yes)
			(effects
				(font
					(size 1.27 1.27)
				)
			)
		)
		(property "Value" ""
			(at 0 0 0)
			(layer "F.Fab")
			(effects
				(font
					(size 1.27 1.27)
				)
			)
		)
		(duplicate_pad_numbers_are_jumpers no)
		(fp_line
			(start -0.7874 -0.4064)
			(end 0.7874 -0.4064)
			(stroke
				(width 0.1524)
				(type default)
			)
			(layer "F.SilkS")
		)
		(fp_line
			(start -0.7874 0.4064)
			(end -0.7874 -0.4064)
			(stroke
				(width 0.1524)
				(type default)
			)
			(layer "F.SilkS")
		)
		(fp_line
			(start 0.7874 -0.4064)
			(end 0.7874 0.4064)
			(stroke
				(width 0.1524)
				(type default)
			)
			(layer "F.SilkS")
		)
		(fp_line
			(start 0.7874 0.4064)
			(end -0.7874 0.4064)
			(stroke
				(width 0.1524)
				(type default)
			)
			(layer "F.SilkS")
		)
		(fp_line
			(start -0.67945 -0.305054)
			(end -0.12065 -0.305054)
			(stroke
				(width 0.1)
				(type default)
			)
			(layer "F.Fab")
		)
		(fp_line
			(start -0.67945 0.3048)
			(end -0.67945 -0.305054)
			(stroke
				(width 0.1)
				(type default)
			)
			(layer "F.Fab")
		)
		(fp_line
			(start -0.12065 -0.305054)
			(end -0.12065 -0.2794)
			(stroke
				(width 0.1)
				(type default)
			)
			(layer "F.Fab")
		)
		(fp_line
			(start -0.12065 -0.2794)
			(end 0.12065 -0.2794)
			(stroke
				(width 0.1)
				(type default)
			)
			(layer "F.Fab")
		)
		(fp_line
			(start -0.12065 0.2794)
			(end -0.12065 0.3048)
			(stroke
				(width 0.1)
				(type default)
			)
			(layer "F.Fab")
		)
		(fp_line
			(start -0.12065 0.3048)
			(end -0.67945 0.3048)
			(stroke
				(width 0.1)
				(type default)
			)
			(layer "F.Fab")
		)
		(fp_line
			(start 0.120396 0.2794)
			(end -0.12065 0.2794)
			(stroke
				(width 0.1)
				(type default)
			)
			(layer "F.Fab")
		)
		(fp_line
			(start 0.120396 0.3048)
			(end 0.120396 0.2794)
			(stroke
				(width 0.1)
				(type default)
			)
			(layer "F.Fab")
		)
		(fp_line
			(start 0.12065 -0.3048)
			(end 0.67945 -0.3048)
			(stroke
				(width 0.1)
				(type default)
			)
			(layer "F.Fab")
		)
		(fp_line
			(start 0.12065 -0.2794)
			(end 0.12065 -0.3048)
			(stroke
				(width 0.1)
				(type default)
			)
			(layer "F.Fab")
		)
		(fp_line
			(start 0.67945 -0.3048)
			(end 0.67945 0.3048)
			(stroke
				(width 0.1)
				(type default)
			)
			(layer "F.Fab")
		)
		(fp_line
			(start 0.67945 0.3048)
			(end 0.120396 0.3048)
			(stroke
				(width 0.1)
				(type default)
			)
			(layer "F.Fab")
		)
		(pad "1" smd circle
			(at -0.40005 0)
			(size 0 0)
			(layers "F.Cu" "F.Mask" "F.Paste")
			(net "P12V_SSD3_OCP")
		)
		(pad "2" smd circle
			(at 0.40005 0)
			(size 0 0)
			(layers "F.Cu" "F.Mask" "F.Paste")
			(net "GND")
		)
	)
	(footprint ""
		(layer "F.Cu")
		(at 312.695082 -35.48253)
		(property "Reference" "U392"
			(at -2.559812 1.09093 90)
			(unlocked yes)
			(layer "F.SilkS")
			(effects
				(font
					(size 0.7874 0.5842)
					(thickness 0.1524)
				)
				(justify left)
			)
		)
		(property "Value" ""
			(at 0 0 0)
			(layer "F.Fab")
			(effects
				(font
					(size 1.27 1.27)
				)
			)
		)
		(duplicate_pad_numbers_are_jumpers no)
		(fp_line
			(start -1.3462 -1.1938)
			(end -1.3462 1.1684)
			(stroke
				(width 0.1524)
				(type default)
			)
			(layer "F.SilkS")
		)
		(fp_line
			(start -1.3462 1.1938)
			(end 1.3462 1.1938)
			(stroke
				(width 0.1524)
				(type default)
			)
			(layer "F.SilkS")
		)
		(fp_line
			(start 1.3462 -1.1938)
			(end -1.3462 -1.1938)
			(stroke
				(width 0.1524)
				(type default)
			)
			(layer "F.SilkS")
		)
		(fp_line
			(start 1.3462 1.1938)
			(end 1.3462 -1.1938)
			(stroke
				(width 0.1524)
				(type default)
			)
			(layer "F.SilkS")
		)
		(fp_poly
			(pts
				(xy -1.447038 -0.760476) (xy -2.052066 -0.457962) (xy -2.052066 -1.06299)
			)
			(stroke
				(width 0)
				(type default)
			)
			(fill yes)
			(layer "F.SilkS")
		)
		(fp_line
			(start -0.674878 -1.124966)
			(end -0.674878 1.124966)
			(stroke
				(width 0.1)
				(type default)
			)
			(layer "F.Fab")
		)
		(fp_line
			(start -0.674878 1.124966)
			(end 0.674878 1.124966)
			(stroke
				(width 0.1)
				(type default)
			)
			(layer "F.Fab")
		)
		(fp_line
			(start 0.674878 -1.124966)
			(end -0.674878 -1.124966)
			(stroke
				(width 0.1)
				(type default)
			)
			(layer "F.Fab")
		)
		(fp_line
			(start 0.674878 1.124966)
			(end 0.674878 -1.124966)
			(stroke
				(width 0.1)
				(type default)
			)
			(layer "F.Fab")
		)
		(fp_poly
			(pts
				(xy -1.447038 -0.760476) (xy -2.052066 -0.457962) (xy -2.052066 -1.06299)
			)
			(stroke
				(width 0)
				(type default)
			)
			(fill yes)
			(layer "F.Fab")
		)
		(pad "1" smd rect
			(at -0.899922 -0.750062)
			(size 0.6096 0.6096)
			(layers "F.Cu" "F.Mask" "F.Paste")
			(net "PWRGD_P3V3_SSD11_R")
		)
		(pad "2" smd rect
			(at -0.899922 0 90)
			(size 0.4064 0.6096)
			(layers "F.Cu" "F.Mask" "F.Paste")
			(net "RST_SMB_SSD11_N")
		)
		(pad "3" smd rect
			(at -0.899922 0.750062)
			(size 0.6096 0.6096)
			(layers "F.Cu" "F.Mask" "F.Paste")
			(net "GND")
		)
		(pad "4" smd rect
			(at 0.899922 0.750062)
			(size 0.6096 0.6096)
			(layers "F.Cu" "F.Mask" "F.Paste")
			(net "RST_SMB_SSD11_ISO_N")
		)
		(pad "5" smd rect
			(at 0.899922 -0.750062)
			(size 0.6096 0.6096)
			(layers "F.Cu" "F.Mask" "F.Paste")
			(net "P3V3_AUX")
		)
	)
	(footprint ""
		(layer "F.Cu")
		(at 72.947276 -20.35556)
		(property "Reference" "C3891"
			(at 0 0 0)
			(layer "F.SilkS")
			(hide yes)
			(effects
				(font
					(size 1.27 1.27)
				)
			)
		)
		(property "Value" ""
			(at 0 0 0)
			(layer "F.Fab")
			(effects
				(font
					(size 1.27 1.27)
				)
			)
		)
		(duplicate_pad_numbers_are_jumpers no)
		(fp_line
			(start -0.7874 -0.4064)
			(end 0.7874 -0.4064)
			(stroke
				(width 0.1524)
				(type default)
			)
			(layer "F.SilkS")
		)
		(fp_line
			(start -0.7874 0.4064)
			(end -0.7874 -0.4064)
			(stroke
				(width 0.1524)
				(type default)
			)
			(layer "F.SilkS")
		)
		(fp_line
			(start 0.7874 -0.4064)
			(end 0.7874 0.4064)
			(stroke
				(width 0.1524)
				(type default)
			)
			(layer "F.SilkS")
		)
		(fp_line
			(start 0.7874 0.4064)
			(end -0.7874 0.4064)
			(stroke
				(width 0.1524)
				(type default)
			)
			(layer "F.SilkS")
		)
		(fp_line
			(start -0.67945 -0.305054)
			(end -0.12065 -0.305054)
			(stroke
				(width 0.1)
				(type default)
			)
			(layer "F.Fab")
		)
		(fp_line
			(start -0.67945 0.3048)
			(end -0.67945 -0.305054)
			(stroke
				(width 0.1)
				(type default)
			)
			(layer "F.Fab")
		)
		(fp_line
			(start -0.12065 -0.305054)
			(end -0.12065 -0.2794)
			(stroke
				(width 0.1)
				(type default)
			)
			(layer "F.Fab")
		)
		(fp_line
			(start -0.12065 -0.2794)
			(end 0.12065 -0.2794)
			(stroke
				(width 0.1)
				(type default)
			)
			(layer "F.Fab")
		)
		(fp_line
			(start -0.12065 0.2794)
			(end -0.12065 0.3048)
			(stroke
				(width 0.1)
				(type default)
			)
			(layer "F.Fab")
		)
		(fp_line
			(start -0.12065 0.3048)
			(end -0.67945 0.3048)
			(stroke
				(width 0.1)
				(type default)
			)
			(layer "F.Fab")
		)
		(fp_line
			(start 0.120396 0.2794)
			(end -0.12065 0.2794)
			(stroke
				(width 0.1)
				(type default)
			)
			(layer "F.Fab")
		)
		(fp_line
			(start 0.120396 0.3048)
			(end 0.120396 0.2794)
			(stroke
				(width 0.1)
				(type default)
			)
			(layer "F.Fab")
		)
		(fp_line
			(start 0.12065 -0.3048)
			(end 0.67945 -0.3048)
			(stroke
				(width 0.1)
				(type default)
			)
			(layer "F.Fab")
		)
		(fp_line
			(start 0.12065 -0.2794)
			(end 0.12065 -0.3048)
			(stroke
				(width 0.1)
				(type default)
			)
			(layer "F.Fab")
		)
		(fp_line
			(start 0.67945 -0.3048)
			(end 0.67945 0.3048)
			(stroke
				(width 0.1)
				(type default)
			)
			(layer "F.Fab")
		)
		(fp_line
			(start 0.67945 0.3048)
			(end 0.120396 0.3048)
			(stroke
				(width 0.1)
				(type default)
			)
			(layer "F.Fab")
		)
		(pad "1" smd circle
			(at -0.40005 0)
			(size 0 0)
			(layers "F.Cu" "F.Mask" "F.Paste")
			(net "P12V_SSD2")
		)
		(pad "2" smd circle
			(at 0.40005 0)
			(size 0 0)
			(layers "F.Cu" "F.Mask" "F.Paste")
			(net "GND")
		)
	)
	(footprint ""
		(layer "F.Cu")
		(at 365.976916 -280.344118)
		(property "Reference" "PC202"
			(at 0 0 0)
			(layer "F.SilkS")
			(hide yes)
			(effects
				(font
					(size 1.27 1.27)
				)
			)
		)
		(property "Value" ""
			(at 0 0 0)
			(layer "F.Fab")
			(effects
				(font
					(size 1.27 1.27)
				)
			)
		)
		(duplicate_pad_numbers_are_jumpers no)
		(fp_line
			(start -0.7874 -0.4064)
			(end 0.7874 -0.4064)
			(stroke
				(width 0.1524)
				(type default)
			)
			(layer "F.SilkS")
		)
		(fp_line
			(start -0.7874 0.4064)
			(end -0.7874 -0.4064)
			(stroke
				(width 0.1524)
				(type default)
			)
			(layer "F.SilkS")
		)
		(fp_line
			(start 0.7874 -0.4064)
			(end 0.7874 0.4064)
			(stroke
				(width 0.1524)
				(type default)
			)
			(layer "F.SilkS")
		)
		(fp_line
			(start 0.7874 0.4064)
			(end -0.7874 0.4064)
			(stroke
				(width 0.1524)
				(type default)
			)
			(layer "F.SilkS")
		)
		(fp_line
			(start -0.67945 -0.305054)
			(end -0.12065 -0.305054)
			(stroke
				(width 0.1)
				(type default)
			)
			(layer "F.Fab")
		)
		(fp_line
			(start -0.67945 0.3048)
			(end -0.67945 -0.305054)
			(stroke
				(width 0.1)
				(type default)
			)
			(layer "F.Fab")
		)
		(fp_line
			(start -0.12065 -0.305054)
			(end -0.12065 -0.2794)
			(stroke
				(width 0.1)
				(type default)
			)
			(layer "F.Fab")
		)
		(fp_line
			(start -0.12065 -0.2794)
			(end 0.12065 -0.2794)
			(stroke
				(width 0.1)
				(type default)
			)
			(layer "F.Fab")
		)
		(fp_line
			(start -0.12065 0.2794)
			(end -0.12065 0.3048)
			(stroke
				(width 0.1)
				(type default)
			)
			(layer "F.Fab")
		)
		(fp_line
			(start -0.12065 0.3048)
			(end -0.67945 0.3048)
			(stroke
				(width 0.1)
				(type default)
			)
			(layer "F.Fab")
		)
		(fp_line
			(start 0.120396 0.2794)
			(end -0.12065 0.2794)
			(stroke
				(width 0.1)
				(type default)
			)
			(layer "F.Fab")
		)
		(fp_line
			(start 0.120396 0.3048)
			(end 0.120396 0.2794)
			(stroke
				(width 0.1)
				(type default)
			)
			(layer "F.Fab")
		)
		(fp_line
			(start 0.12065 -0.3048)
			(end 0.67945 -0.3048)
			(stroke
				(width 0.1)
				(type default)
			)
			(layer "F.Fab")
		)
		(fp_line
			(start 0.12065 -0.2794)
			(end 0.12065 -0.3048)
			(stroke
				(width 0.1)
				(type default)
			)
			(layer "F.Fab")
		)
		(fp_line
			(start 0.67945 -0.3048)
			(end 0.67945 0.3048)
			(stroke
				(width 0.1)
				(type default)
			)
			(layer "F.Fab")
		)
		(fp_line
			(start 0.67945 0.3048)
			(end 0.120396 0.3048)
			(stroke
				(width 0.1)
				(type default)
			)
			(layer "F.Fab")
		)
		(pad "1" smd circle
			(at -0.40005 0)
			(size 0 0)
			(layers "F.Cu" "F.Mask" "F.Paste")
			(net "P0V8_PEX2_VREF")
		)
		(pad "2" smd circle
			(at 0.40005 0)
			(size 0 0)
			(layers "F.Cu" "F.Mask" "F.Paste")
			(net "GND")
		)
	)
	(footprint ""
		(layer "F.Cu")
		(at 84.023962 -356.244906 90)
		(property "Reference" "C106"
			(at 0 0 90)
			(layer "F.SilkS")
			(hide yes)
			(effects
				(font
					(size 1.27 1.27)
				)
			)
		)
		(property "Value" ""
			(at 0 0 90)
			(layer "F.Fab")
			(effects
				(font
					(size 1.27 1.27)
				)
			)
		)
		(duplicate_pad_numbers_are_jumpers no)
		(fp_line
			(start 0.299974 -0.150114)
			(end 0.299974 0.150114)
			(stroke
				(width 0.1)
				(type default)
			)
			(layer "F.Fab")
		)
		(fp_line
			(start -0.299974 -0.150114)
			(end 0.299974 -0.150114)
			(stroke
				(width 0.1)
				(type default)
			)
			(layer "F.Fab")
		)
		(fp_line
			(start 0.299974 0.150114)
			(end -0.299974 0.150114)
			(stroke
				(width 0.1)
				(type default)
			)
			(layer "F.Fab")
		)
		(fp_line
			(start -0.299974 0.150114)
			(end -0.299974 -0.150114)
			(stroke
				(width 0.1)
				(type default)
			)
			(layer "F.Fab")
		)
		(pad "1" smd rect
			(at -0.2667 0 90)
			(size 0.3048 0.381)
			(layers "F.Cu" "F.Mask" "F.Paste")
			(net "P5E_PEX0_STN5_TX_DN<91>")
		)
		(pad "2" smd rect
			(at 0.2667 0 90)
			(size 0.3048 0.381)
			(layers "F.Cu" "F.Mask" "F.Paste")
			(net "P5E_PEX0_STN5_TX_C_DN<91>")
		)
	)
	(footprint ""
		(layer "F.Cu")
		(at 449.956428 -17.419574 180)
		(property "Reference" "R1733"
			(at 0 0 180)
			(layer "F.SilkS")
			(hide yes)
			(effects
				(font
					(size 1.27 1.27)
				)
			)
		)
		(property "Value" ""
			(at 0 0 180)
			(layer "F.Fab")
			(effects
				(font
					(size 1.27 1.27)
				)
			)
		)
		(duplicate_pad_numbers_are_jumpers no)
		(fp_line
			(start 0.7874 0.4064)
			(end -0.7874 0.4064)
			(stroke
				(width 0.1524)
				(type default)
			)
			(layer "F.SilkS")
		)
		(fp_line
			(start 0.7874 -0.4064)
			(end 0.7874 0.4064)
			(stroke
				(width 0.1524)
				(type default)
			)
			(layer "F.SilkS")
		)
		(fp_line
			(start -0.7874 0.4064)
			(end -0.7874 -0.4064)
			(stroke
				(width 0.1524)
				(type default)
			)
			(layer "F.SilkS")
		)
		(fp_line
			(start -0.7874 -0.4064)
			(end 0.7874 -0.4064)
			(stroke
				(width 0.1524)
				(type default)
			)
			(layer "F.SilkS")
		)
		(fp_line
			(start 0.67945 0.3048)
			(end 0.120396 0.3048)
			(stroke
				(width 0.1)
				(type default)
			)
			(layer "F.Fab")
		)
		(fp_line
			(start 0.67945 -0.3048)
			(end 0.67945 0.3048)
			(stroke
				(width 0.1)
				(type default)
			)
			(layer "F.Fab")
		)
		(fp_line
			(start 0.12065 -0.2794)
			(end 0.12065 -0.3048)
			(stroke
				(width 0.1)
				(type default)
			)
			(layer "F.Fab")
		)
		(fp_line
			(start 0.12065 -0.3048)
			(end 0.67945 -0.3048)
			(stroke
				(width 0.1)
				(type default)
			)
			(layer "F.Fab")
		)
		(fp_line
			(start 0.120396 0.3048)
			(end 0.120396 0.2794)
			(stroke
				(width 0.1)
				(type default)
			)
			(layer "F.Fab")
		)
		(fp_line
			(start 0.120396 0.2794)
			(end -0.12065 0.2794)
			(stroke
				(width 0.1)
				(type default)
			)
			(layer "F.Fab")
		)
		(fp_line
			(start -0.12065 0.3048)
			(end -0.67945 0.3048)
			(stroke
				(width 0.1)
				(type default)
			)
			(layer "F.Fab")
		)
		(fp_line
			(start -0.12065 0.2794)
			(end -0.12065 0.3048)
			(stroke
				(width 0.1)
				(type default)
			)
			(layer "F.Fab")
		)
		(fp_line
			(start -0.12065 -0.2794)
			(end 0.12065 -0.2794)
			(stroke
				(width 0.1)
				(type default)
			)
			(layer "F.Fab")
		)
		(fp_line
			(start -0.12065 -0.305054)
			(end -0.12065 -0.2794)
			(stroke
				(width 0.1)
				(type default)
			)
			(layer "F.Fab")
		)
		(fp_line
			(start -0.67945 0.3048)
			(end -0.67945 -0.305054)
			(stroke
				(width 0.1)
				(type default)
			)
			(layer "F.Fab")
		)
		(fp_line
			(start -0.67945 -0.305054)
			(end -0.12065 -0.305054)
			(stroke
				(width 0.1)
				(type default)
			)
			(layer "F.Fab")
		)
		(pad "1" smd circle
			(at -0.40005 0 180)
			(size 0 0)
			(layers "F.Cu" "F.Mask" "F.Paste")
			(net "P3V3_SSD15")
		)
		(pad "2" smd circle
			(at 0.40005 0 180)
			(size 0 0)
			(layers "F.Cu" "F.Mask" "F.Paste")
			(net "SMB_ISO_SSD15_SCL")
		)
	)
	(footprint ""
		(layer "F.Cu")
		(at 399.723864 -167.742108)
		(property "Reference" "C619"
			(at 0 0 0)
			(layer "F.SilkS")
			(hide yes)
			(effects
				(font
					(size 1.27 1.27)
				)
			)
		)
		(property "Value" ""
			(at 0 0 0)
			(layer "F.Fab")
			(effects
				(font
					(size 1.27 1.27)
				)
			)
		)
		(duplicate_pad_numbers_are_jumpers no)
		(fp_line
			(start -0.7874 -0.4064)
			(end 0.7874 -0.4064)
			(stroke
				(width 0.1524)
				(type default)
			)
			(layer "F.SilkS")
		)
		(fp_line
			(start -0.7874 0.4064)
			(end -0.7874 -0.4064)
			(stroke
				(width 0.1524)
				(type default)
			)
			(layer "F.SilkS")
		)
		(fp_line
			(start 0.7874 -0.4064)
			(end 0.7874 0.4064)
			(stroke
				(width 0.1524)
				(type default)
			)
			(layer "F.SilkS")
		)
		(fp_line
			(start 0.7874 0.4064)
			(end -0.7874 0.4064)
			(stroke
				(width 0.1524)
				(type default)
			)
			(layer "F.SilkS")
		)
		(fp_line
			(start -0.67945 -0.305054)
			(end -0.12065 -0.305054)
			(stroke
				(width 0.1)
				(type default)
			)
			(layer "F.Fab")
		)
		(fp_line
			(start -0.67945 0.3048)
			(end -0.67945 -0.305054)
			(stroke
				(width 0.1)
				(type default)
			)
			(layer "F.Fab")
		)
		(fp_line
			(start -0.12065 -0.305054)
			(end -0.12065 -0.2794)
			(stroke
				(width 0.1)
				(type default)
			)
			(layer "F.Fab")
		)
		(fp_line
			(start -0.12065 -0.2794)
			(end 0.12065 -0.2794)
			(stroke
				(width 0.1)
				(type default)
			)
			(layer "F.Fab")
		)
		(fp_line
			(start -0.12065 0.2794)
			(end -0.12065 0.3048)
			(stroke
				(width 0.1)
				(type default)
			)
			(layer "F.Fab")
		)
		(fp_line
			(start -0.12065 0.3048)
			(end -0.67945 0.3048)
			(stroke
				(width 0.1)
				(type default)
			)
			(layer "F.Fab")
		)
		(fp_line
			(start 0.120396 0.2794)
			(end -0.12065 0.2794)
			(stroke
				(width 0.1)
				(type default)
			)
			(layer "F.Fab")
		)
		(fp_line
			(start 0.120396 0.3048)
			(end 0.120396 0.2794)
			(stroke
				(width 0.1)
				(type default)
			)
			(layer "F.Fab")
		)
		(fp_line
			(start 0.12065 -0.3048)
			(end 0.67945 -0.3048)
			(stroke
				(width 0.1)
				(type default)
			)
			(layer "F.Fab")
		)
		(fp_line
			(start 0.12065 -0.2794)
			(end 0.12065 -0.3048)
			(stroke
				(width 0.1)
				(type default)
			)
			(layer "F.Fab")
		)
		(fp_line
			(start 0.67945 -0.3048)
			(end 0.67945 0.3048)
			(stroke
				(width 0.1)
				(type default)
			)
			(layer "F.Fab")
		)
		(fp_line
			(start 0.67945 0.3048)
			(end 0.120396 0.3048)
			(stroke
				(width 0.1)
				(type default)
			)
			(layer "F.Fab")
		)
		(pad "1" smd circle
			(at -0.40005 0)
			(size 0 0)
			(layers "F.Cu" "F.Mask" "F.Paste")
			(net "P3V3_AUX")
		)
		(pad "2" smd circle
			(at 0.40005 0)
			(size 0 0)
			(layers "F.Cu" "F.Mask" "F.Paste")
			(net "GND")
		)
	)
	(footprint ""
		(layer "F.Cu")
		(at 168.367964 -53.051456)
		(property "Reference" "R4461"
			(at 0 0 0)
			(layer "F.SilkS")
			(hide yes)
			(effects
				(font
					(size 1.27 1.27)
				)
			)
		)
		(property "Value" ""
			(at 0 0 0)
			(layer "F.Fab")
			(effects
				(font
					(size 1.27 1.27)
				)
			)
		)
		(duplicate_pad_numbers_are_jumpers no)
		(fp_line
			(start -0.7874 -0.4064)
			(end 0.7874 -0.4064)
			(stroke
				(width 0.1524)
				(type default)
			)
			(layer "F.SilkS")
		)
		(fp_line
			(start -0.7874 0.4064)
			(end -0.7874 -0.4064)
			(stroke
				(width 0.1524)
				(type default)
			)
			(layer "F.SilkS")
		)
		(fp_line
			(start 0.7874 -0.4064)
			(end 0.7874 0.4064)
			(stroke
				(width 0.1524)
				(type default)
			)
			(layer "F.SilkS")
		)
		(fp_line
			(start 0.7874 0.4064)
			(end -0.7874 0.4064)
			(stroke
				(width 0.1524)
				(type default)
			)
			(layer "F.SilkS")
		)
		(fp_line
			(start -0.67945 -0.305054)
			(end -0.12065 -0.305054)
			(stroke
				(width 0.1)
				(type default)
			)
			(layer "F.Fab")
		)
		(fp_line
			(start -0.67945 0.3048)
			(end -0.67945 -0.305054)
			(stroke
				(width 0.1)
				(type default)
			)
			(layer "F.Fab")
		)
		(fp_line
			(start -0.12065 -0.305054)
			(end -0.12065 -0.2794)
			(stroke
				(width 0.1)
				(type default)
			)
			(layer "F.Fab")
		)
		(fp_line
			(start -0.12065 -0.2794)
			(end 0.12065 -0.2794)
			(stroke
				(width 0.1)
				(type default)
			)
			(layer "F.Fab")
		)
		(fp_line
			(start -0.12065 0.2794)
			(end -0.12065 0.3048)
			(stroke
				(width 0.1)
				(type default)
			)
			(layer "F.Fab")
		)
		(fp_line
			(start -0.12065 0.3048)
			(end -0.67945 0.3048)
			(stroke
				(width 0.1)
				(type default)
			)
			(layer "F.Fab")
		)
		(fp_line
			(start 0.120396 0.2794)
			(end -0.12065 0.2794)
			(stroke
				(width 0.1)
				(type default)
			)
			(layer "F.Fab")
		)
		(fp_line
			(start 0.120396 0.3048)
			(end 0.120396 0.2794)
			(stroke
				(width 0.1)
				(type default)
			)
			(layer "F.Fab")
		)
		(fp_line
			(start 0.12065 -0.3048)
			(end 0.67945 -0.3048)
			(stroke
				(width 0.1)
				(type default)
			)
			(layer "F.Fab")
		)
		(fp_line
			(start 0.12065 -0.2794)
			(end 0.12065 -0.3048)
			(stroke
				(width 0.1)
				(type default)
			)
			(layer "F.Fab")
		)
		(fp_line
			(start 0.67945 -0.3048)
			(end 0.67945 0.3048)
			(stroke
				(width 0.1)
				(type default)
			)
			(layer "F.Fab")
		)
		(fp_line
			(start 0.67945 0.3048)
			(end 0.120396 0.3048)
			(stroke
				(width 0.1)
				(type default)
			)
			(layer "F.Fab")
		)
		(pad "1" smd circle
			(at -0.40005 0)
			(size 0 0)
			(layers "F.Cu" "F.Mask" "F.Paste")
			(net "PWRGD_P12V_SSD5")
		)
		(pad "2" smd circle
			(at 0.40005 0)
			(size 0 0)
			(layers "F.Cu" "F.Mask" "F.Paste")
			(net "PWRGD_P12V_SSD5_R")
		)
	)
	(footprint ""
		(layer "F.Cu")
		(at 213.17966 -181.608476 -90)
		(property "Reference" "R5299"
			(at 0 0 270)
			(layer "F.SilkS")
			(hide yes)
			(effects
				(font
					(size 1.27 1.27)
				)
			)
		)
		(property "Value" ""
			(at 0 0 270)
			(layer "F.Fab")
			(effects
				(font
					(size 1.27 1.27)
				)
			)
		)
		(duplicate_pad_numbers_are_jumpers no)
		(fp_line
			(start -0.7874 0.4064)
			(end -0.7874 -0.4064)
			(stroke
				(width 0.1524)
				(type default)
			)
			(layer "F.SilkS")
		)
		(fp_line
			(start 0.7874 0.4064)
			(end -0.7874 0.4064)
			(stroke
				(width 0.1524)
				(type default)
			)
			(layer "F.SilkS")
		)
		(fp_line
			(start -0.7874 -0.4064)
			(end 0.7874 -0.4064)
			(stroke
				(width 0.1524)
				(type default)
			)
			(layer "F.SilkS")
		)
		(fp_line
			(start 0.7874 -0.4064)
			(end 0.7874 0.4064)
			(stroke
				(width 0.1524)
				(type default)
			)
			(layer "F.SilkS")
		)
		(fp_line
			(start -0.67945 0.3048)
			(end -0.67945 -0.305054)
			(stroke
				(width 0.1)
				(type default)
			)
			(layer "F.Fab")
		)
		(fp_line
			(start -0.12065 0.3048)
			(end -0.67945 0.3048)
			(stroke
				(width 0.1)
				(type default)
			)
			(layer "F.Fab")
		)
		(fp_line
			(start 0.120396 0.3048)
			(end 0.120396 0.2794)
			(stroke
				(width 0.1)
				(type default)
			)
			(layer "F.Fab")
		)
		(fp_line
			(start 0.67945 0.3048)
			(end 0.120396 0.3048)
			(stroke
				(width 0.1)
				(type default)
			)
			(layer "F.Fab")
		)
		(fp_line
			(start -0.12065 0.2794)
			(end -0.12065 0.3048)
			(stroke
				(width 0.1)
				(type default)
			)
			(layer "F.Fab")
		)
		(fp_line
			(start 0.120396 0.2794)
			(end -0.12065 0.2794)
			(stroke
				(width 0.1)
				(type default)
			)
			(layer "F.Fab")
		)
		(fp_line
			(start -0.12065 -0.2794)
			(end 0.12065 -0.2794)
			(stroke
				(width 0.1)
				(type default)
			)
			(layer "F.Fab")
		)
		(fp_line
			(start 0.12065 -0.2794)
			(end 0.12065 -0.3048)
			(stroke
				(width 0.1)
				(type default)
			)
			(layer "F.Fab")
		)
		(fp_line
			(start 0.12065 -0.3048)
			(end 0.67945 -0.3048)
			(stroke
				(width 0.1)
				(type default)
			)
			(layer "F.Fab")
		)
		(fp_line
			(start 0.67945 -0.3048)
			(end 0.67945 0.3048)
			(stroke
				(width 0.1)
				(type default)
			)
			(layer "F.Fab")
		)
		(fp_line
			(start -0.67945 -0.305054)
			(end -0.12065 -0.305054)
			(stroke
				(width 0.1)
				(type default)
			)
			(layer "F.Fab")
		)
		(fp_line
			(start -0.12065 -0.305054)
			(end -0.12065 -0.2794)
			(stroke
				(width 0.1)
				(type default)
			)
			(layer "F.Fab")
		)
		(pad "1" smd circle
			(at -0.40005 0 270)
			(size 0 0)
			(layers "F.Cu" "F.Mask" "F.Paste")
			(net "SEL_FLASH_PEX2_BUF")
		)
		(pad "2" smd circle
			(at 0.40005 0 270)
			(size 0 0)
			(layers "F.Cu" "F.Mask" "F.Paste")
			(net "SEL_FLASH_PEX2_BUF_R")
		)
	)
	(footprint ""
		(layer "F.Cu")
		(at 238.124746 -112.888268 180)
		(property "Reference" "C842"
			(at 0 0 180)
			(layer "F.SilkS")
			(hide yes)
			(effects
				(font
					(size 1.27 1.27)
				)
			)
		)
		(property "Value" ""
			(at 0 0 180)
			(layer "F.Fab")
			(effects
				(font
					(size 1.27 1.27)
				)
			)
		)
		(duplicate_pad_numbers_are_jumpers no)
		(fp_line
			(start 0.7874 0.4064)
			(end -0.7874 0.4064)
			(stroke
				(width 0.1524)
				(type default)
			)
			(layer "F.SilkS")
		)
		(fp_line
			(start 0.7874 -0.4064)
			(end 0.7874 0.4064)
			(stroke
				(width 0.1524)
				(type default)
			)
			(layer "F.SilkS")
		)
		(fp_line
			(start -0.7874 0.4064)
			(end -0.7874 -0.4064)
			(stroke
				(width 0.1524)
				(type default)
			)
			(layer "F.SilkS")
		)
		(fp_line
			(start -0.7874 -0.4064)
			(end 0.7874 -0.4064)
			(stroke
				(width 0.1524)
				(type default)
			)
			(layer "F.SilkS")
		)
		(fp_line
			(start 0.67945 0.3048)
			(end 0.120396 0.3048)
			(stroke
				(width 0.1)
				(type default)
			)
			(layer "F.Fab")
		)
		(fp_line
			(start 0.67945 -0.3048)
			(end 0.67945 0.3048)
			(stroke
				(width 0.1)
				(type default)
			)
			(layer "F.Fab")
		)
		(fp_line
			(start 0.12065 -0.2794)
			(end 0.12065 -0.3048)
			(stroke
				(width 0.1)
				(type default)
			)
			(layer "F.Fab")
		)
		(fp_line
			(start 0.12065 -0.3048)
			(end 0.67945 -0.3048)
			(stroke
				(width 0.1)
				(type default)
			)
			(layer "F.Fab")
		)
		(fp_line
			(start 0.120396 0.3048)
			(end 0.120396 0.2794)
			(stroke
				(width 0.1)
				(type default)
			)
			(layer "F.Fab")
		)
		(fp_line
			(start 0.120396 0.2794)
			(end -0.12065 0.2794)
			(stroke
				(width 0.1)
				(type default)
			)
			(layer "F.Fab")
		)
		(fp_line
			(start -0.12065 0.3048)
			(end -0.67945 0.3048)
			(stroke
				(width 0.1)
				(type default)
			)
			(layer "F.Fab")
		)
		(fp_line
			(start -0.12065 0.2794)
			(end -0.12065 0.3048)
			(stroke
				(width 0.1)
				(type default)
			)
			(layer "F.Fab")
		)
		(fp_line
			(start -0.12065 -0.2794)
			(end 0.12065 -0.2794)
			(stroke
				(width 0.1)
				(type default)
			)
			(layer "F.Fab")
		)
		(fp_line
			(start -0.12065 -0.305054)
			(end -0.12065 -0.2794)
			(stroke
				(width 0.1)
				(type default)
			)
			(layer "F.Fab")
		)
		(fp_line
			(start -0.67945 0.3048)
			(end -0.67945 -0.305054)
			(stroke
				(width 0.1)
				(type default)
			)
			(layer "F.Fab")
		)
		(fp_line
			(start -0.67945 -0.305054)
			(end -0.12065 -0.305054)
			(stroke
				(width 0.1)
				(type default)
			)
			(layer "F.Fab")
		)
		(pad "1" smd circle
			(at -0.40005 0 180)
			(size 0 0)
			(layers "F.Cu" "F.Mask" "F.Paste")
			(net "GND")
		)
		(pad "2" smd circle
			(at 0.40005 0 180)
			(size 0 0)
			(layers "F.Cu" "F.Mask" "F.Paste")
			(net "P12V_NIC3_CO_EN")
		)
	)
	(footprint ""
		(layer "F.Cu")
		(at 411.428692 -207.945482)
		(property "Reference" "Q238"
			(at -3.236214 -1.629156 0)
			(unlocked yes)
			(layer "F.SilkS")
			(effects
				(font
					(size 0.7874 0.5842)
					(thickness 0.1524)
				)
			)
		)
		(property "Value" ""
			(at 0 0 0)
			(layer "F.Fab")
			(effects
				(font
					(size 1.27 1.27)
				)
			)
		)
		(duplicate_pad_numbers_are_jumpers no)
		(fp_line
			(start -1.376172 -1.199896)
			(end -0.508 -1.199896)
			(stroke
				(width 0.1524)
				(type default)
			)
			(layer "F.SilkS")
		)
		(fp_line
			(start -1.376172 1.199896)
			(end -1.376172 -1.199896)
			(stroke
				(width 0.1524)
				(type default)
			)
			(layer "F.SilkS")
		)
		(fp_line
			(start -0.508 -1.199896)
			(end 0 -0.762)
			(stroke
				(width 0.1524)
				(type default)
			)
			(layer "F.SilkS")
		)
		(fp_line
			(start 0 -0.762)
			(end 0.508 -1.199896)
			(stroke
				(width 0.1524)
				(type default)
			)
			(layer "F.SilkS")
		)
		(fp_line
			(start 0.508 -1.199896)
			(end 1.376172 -1.199896)
			(stroke
				(width 0.1524)
				(type default)
			)
			(layer "F.SilkS")
		)
		(fp_line
			(start 1.376172 -1.199896)
			(end 1.376172 1.199896)
			(stroke
				(width 0.1524)
				(type default)
			)
			(layer "F.SilkS")
		)
		(fp_line
			(start 1.376172 1.199896)
			(end -1.376172 1.199896)
			(stroke
				(width 0.1524)
				(type default)
			)
			(layer "F.SilkS")
		)
		(fp_poly
			(pts
				(xy -1.4605 -0.7493) (xy -2.2225 -1.1303) (xy -2.2225 -0.3683)
			)
			(stroke
				(width 0)
				(type default)
			)
			(fill yes)
			(layer "F.SilkS")
		)
		(fp_line
			(start -0.674878 -1.100074)
			(end 0.674878 -1.100074)
			(stroke
				(width 0.1)
				(type default)
			)
			(layer "F.Fab")
		)
		(fp_line
			(start -0.674878 1.100074)
			(end -0.674878 -1.100074)
			(stroke
				(width 0.1)
				(type default)
			)
			(layer "F.Fab")
		)
		(fp_line
			(start 0.674878 -1.100074)
			(end 0.674878 1.100074)
			(stroke
				(width 0.1)
				(type default)
			)
			(layer "F.Fab")
		)
		(fp_line
			(start 0.674878 1.100074)
			(end -0.674878 1.100074)
			(stroke
				(width 0.1)
				(type default)
			)
			(layer "F.Fab")
		)
		(fp_poly
			(pts
				(xy -1.4605 -0.7493) (xy -2.2225 -1.1303) (xy -2.2225 -0.3683)
			)
			(stroke
				(width 0)
				(type default)
			)
			(fill yes)
			(layer "F.Fab")
		)
		(pad "1" smd rect
			(at -0.899922 -0.750062 270)
			(size 0.6096 0.6096)
			(layers "F.Cu" "F.Mask" "F.Paste")
			(net "GND")
		)
		(pad "2" smd rect
			(at -0.899922 0 270)
			(size 0.4064 0.6096)
			(layers "F.Cu" "F.Mask" "F.Paste")
			(net "FPGA_PEX3_MODE_SEL1_R")
		)
		(pad "3" smd rect
			(at -0.899922 0.750062 270)
			(size 0.6096 0.6096)
			(layers "F.Cu" "F.Mask" "F.Paste")
			(net "FPGA_PEX3_MODE_SEL1_ISO")
		)
		(pad "4" smd rect
			(at 0.899922 0.750062 270)
			(size 0.6096 0.6096)
			(layers "F.Cu" "F.Mask" "F.Paste")
			(net "GND")
		)
		(pad "5" smd rect
			(at 0.899922 0 270)
			(size 0.4064 0.6096)
			(layers "F.Cu" "F.Mask" "F.Paste")
			(net "FPGA_PEX3_MODE_SEL1_D_N")
		)
		(pad "6" smd rect
			(at 0.899922 -0.750062 270)
			(size 0.6096 0.6096)
			(layers "F.Cu" "F.Mask" "F.Paste")
			(net "FPGA_PEX3_MODE_SEL1_D_N")
		)
	)
	(footprint ""
		(layer "F.Cu")
		(at 40.598344 -252.356874 -90)
		(property "Reference" "R1191"
			(at 0 0 270)
			(layer "F.SilkS")
			(hide yes)
			(effects
				(font
					(size 1.27 1.27)
				)
			)
		)
		(property "Value" ""
			(at 0 0 270)
			(layer "F.Fab")
			(effects
				(font
					(size 1.27 1.27)
				)
			)
		)
		(duplicate_pad_numbers_are_jumpers no)
		(fp_line
			(start -0.7874 0.4064)
			(end -0.7874 -0.4064)
			(stroke
				(width 0.1524)
				(type default)
			)
			(layer "F.SilkS")
		)
		(fp_line
			(start 0.7874 0.4064)
			(end -0.7874 0.4064)
			(stroke
				(width 0.1524)
				(type default)
			)
			(layer "F.SilkS")
		)
		(fp_line
			(start -0.7874 -0.4064)
			(end 0.7874 -0.4064)
			(stroke
				(width 0.1524)
				(type default)
			)
			(layer "F.SilkS")
		)
		(fp_line
			(start 0.7874 -0.4064)
			(end 0.7874 0.4064)
			(stroke
				(width 0.1524)
				(type default)
			)
			(layer "F.SilkS")
		)
		(fp_line
			(start -0.67945 0.3048)
			(end -0.67945 -0.305054)
			(stroke
				(width 0.1)
				(type default)
			)
			(layer "F.Fab")
		)
		(fp_line
			(start -0.12065 0.3048)
			(end -0.67945 0.3048)
			(stroke
				(width 0.1)
				(type default)
			)
			(layer "F.Fab")
		)
		(fp_line
			(start 0.120396 0.3048)
			(end 0.120396 0.2794)
			(stroke
				(width 0.1)
				(type default)
			)
			(layer "F.Fab")
		)
		(fp_line
			(start 0.67945 0.3048)
			(end 0.120396 0.3048)
			(stroke
				(width 0.1)
				(type default)
			)
			(layer "F.Fab")
		)
		(fp_line
			(start -0.12065 0.2794)
			(end -0.12065 0.3048)
			(stroke
				(width 0.1)
				(type default)
			)
			(layer "F.Fab")
		)
		(fp_line
			(start 0.120396 0.2794)
			(end -0.12065 0.2794)
			(stroke
				(width 0.1)
				(type default)
			)
			(layer "F.Fab")
		)
		(fp_line
			(start -0.12065 -0.2794)
			(end 0.12065 -0.2794)
			(stroke
				(width 0.1)
				(type default)
			)
			(layer "F.Fab")
		)
		(fp_line
			(start 0.12065 -0.2794)
			(end 0.12065 -0.3048)
			(stroke
				(width 0.1)
				(type default)
			)
			(layer "F.Fab")
		)
		(fp_line
			(start 0.12065 -0.3048)
			(end 0.67945 -0.3048)
			(stroke
				(width 0.1)
				(type default)
			)
			(layer "F.Fab")
		)
		(fp_line
			(start 0.67945 -0.3048)
			(end 0.67945 0.3048)
			(stroke
				(width 0.1)
				(type default)
			)
			(layer "F.Fab")
		)
		(fp_line
			(start -0.67945 -0.305054)
			(end -0.12065 -0.305054)
			(stroke
				(width 0.1)
				(type default)
			)
			(layer "F.Fab")
		)
		(fp_line
			(start -0.12065 -0.305054)
			(end -0.12065 -0.2794)
			(stroke
				(width 0.1)
				(type default)
			)
			(layer "F.Fab")
		)
		(pad "1" smd circle
			(at -0.40005 0 270)
			(size 0 0)
			(layers "F.Cu" "F.Mask" "F.Paste")
			(net "GND")
		)
		(pad "2" smd circle
			(at 0.40005 0 270)
			(size 0 0)
			(layers "F.Cu" "F.Mask" "F.Paste")
			(net "PEX0_MODE_SEL1")
		)
	)
	(footprint ""
		(layer "F.Cu")
		(at 175.510952 -350.098614 90)
		(property "Reference" "C2525"
			(at 0 0 90)
			(layer "F.SilkS")
			(hide yes)
			(effects
				(font
					(size 1.27 1.27)
				)
			)
		)
		(property "Value" ""
			(at 0 0 90)
			(layer "F.Fab")
			(effects
				(font
					(size 1.27 1.27)
				)
			)
		)
		(duplicate_pad_numbers_are_jumpers no)
		(fp_line
			(start 0.299974 -0.150114)
			(end 0.299974 0.150114)
			(stroke
				(width 0.1)
				(type default)
			)
			(layer "F.Fab")
		)
		(fp_line
			(start -0.299974 -0.150114)
			(end 0.299974 -0.150114)
			(stroke
				(width 0.1)
				(type default)
			)
			(layer "F.Fab")
		)
		(fp_line
			(start 0.299974 0.150114)
			(end -0.299974 0.150114)
			(stroke
				(width 0.1)
				(type default)
			)
			(layer "F.Fab")
		)
		(fp_line
			(start -0.299974 0.150114)
			(end -0.299974 -0.150114)
			(stroke
				(width 0.1)
				(type default)
			)
			(layer "F.Fab")
		)
		(pad "1" smd rect
			(at -0.2667 0 90)
			(size 0.3048 0.381)
			(layers "F.Cu" "F.Mask" "F.Paste")
			(net "P5E_PEX1_STN4_TX_DN<73>")
		)
		(pad "2" smd rect
			(at 0.2667 0 90)
			(size 0.3048 0.381)
			(layers "F.Cu" "F.Mask" "F.Paste")
			(net "P5E_PEX1_STN4_TX_C_DN<73>")
		)
	)
	(footprint ""
		(layer "F.Cu")
		(at 271.480534 -121.919746)
		(property "Reference" "C468"
			(at 0 0 0)
			(layer "F.SilkS")
			(hide yes)
			(effects
				(font
					(size 1.27 1.27)
				)
			)
		)
		(property "Value" ""
			(at 0 0 0)
			(layer "F.Fab")
			(effects
				(font
					(size 1.27 1.27)
				)
			)
		)
		(duplicate_pad_numbers_are_jumpers no)
		(fp_line
			(start -0.299974 -0.150114)
			(end 0.299974 -0.150114)
			(stroke
				(width 0.1)
				(type default)
			)
			(layer "F.Fab")
		)
		(fp_line
			(start -0.299974 0.150114)
			(end -0.299974 -0.150114)
			(stroke
				(width 0.1)
				(type default)
			)
			(layer "F.Fab")
		)
		(fp_line
			(start 0.299974 -0.150114)
			(end 0.299974 0.150114)
			(stroke
				(width 0.1)
				(type default)
			)
			(layer "F.Fab")
		)
		(fp_line
			(start 0.299974 0.150114)
			(end -0.299974 0.150114)
			(stroke
				(width 0.1)
				(type default)
			)
			(layer "F.Fab")
		)
		(pad "1" smd rect
			(at -0.2667 0)
			(size 0.3048 0.381)
			(layers "F.Cu" "F.Mask" "F.Paste")
			(net "P5E_PEX2_STN1_TX_DP<25>")
		)
		(pad "2" smd rect
			(at 0.2667 0)
			(size 0.3048 0.381)
			(layers "F.Cu" "F.Mask" "F.Paste")
			(net "P5E_PEX2_STN1_TX_C_DP<25>")
		)
	)
	(footprint ""
		(layer "F.Cu")
		(at 375.230136 -290.805108 -90)
		(property "Reference" "C3557"
			(at 0 0 270)
			(layer "F.SilkS")
			(hide yes)
			(effects
				(font
					(size 1.27 1.27)
				)
			)
		)
		(property "Value" ""
			(at 0 0 270)
			(layer "F.Fab")
			(effects
				(font
					(size 1.27 1.27)
				)
			)
		)
		(duplicate_pad_numbers_are_jumpers no)
		(fp_line
			(start -1.2954 0.5842)
			(end -1.2954 -0.5842)
			(stroke
				(width 0.1524)
				(type default)
			)
			(layer "F.SilkS")
		)
		(fp_line
			(start 1.2954 0.5842)
			(end -1.2954 0.5842)
			(stroke
				(width 0.1524)
				(type default)
			)
			(layer "F.SilkS")
		)
		(fp_line
			(start -1.2954 -0.5842)
			(end 1.2954 -0.5842)
			(stroke
				(width 0.1524)
				(type default)
			)
			(layer "F.SilkS")
		)
		(fp_line
			(start 1.2954 -0.5842)
			(end 1.2954 0.5842)
			(stroke
				(width 0.1524)
				(type default)
			)
			(layer "F.SilkS")
		)
		(fp_line
			(start -0.8636 0.4572)
			(end -0.8636 0.4064)
			(stroke
				(width 0.1)
				(type default)
			)
			(layer "F.Fab")
		)
		(fp_line
			(start 0.8636 0.4572)
			(end -0.8636 0.4572)
			(stroke
				(width 0.1)
				(type default)
			)
			(layer "F.Fab")
		)
		(fp_line
			(start -1.1938 0.4064)
			(end -1.1938 -0.4064)
			(stroke
				(width 0.1)
				(type default)
			)
			(layer "F.Fab")
		)
		(fp_line
			(start -0.8636 0.4064)
			(end -1.1938 0.4064)
			(stroke
				(width 0.1)
				(type default)
			)
			(layer "F.Fab")
		)
		(fp_line
			(start 0.8636 0.4064)
			(end 0.8636 0.4572)
			(stroke
				(width 0.1)
				(type default)
			)
			(layer "F.Fab")
		)
		(fp_line
			(start 1.1938 0.4064)
			(end 0.8636 0.4064)
			(stroke
				(width 0.1)
				(type default)
			)
			(layer "F.Fab")
		)
		(fp_line
			(start -1.1938 -0.4064)
			(end -0.8636 -0.4064)
			(stroke
				(width 0.1)
				(type default)
			)
			(layer "F.Fab")
		)
		(fp_line
			(start -0.8636 -0.4064)
			(end -0.8636 -0.4572)
			(stroke
				(width 0.1)
				(type default)
			)
			(layer "F.Fab")
		)
		(fp_line
			(start 0.8636 -0.4064)
			(end 1.1938 -0.4064)
			(stroke
				(width 0.1)
				(type default)
			)
			(layer "F.Fab")
		)
		(fp_line
			(start 1.1938 -0.4064)
			(end 1.1938 0.4064)
			(stroke
				(width 0.1)
				(type default)
			)
			(layer "F.Fab")
		)
		(fp_line
			(start -0.8636 -0.4572)
			(end 0.8636 -0.4572)
			(stroke
				(width 0.1)
				(type default)
			)
			(layer "F.Fab")
		)
		(fp_line
			(start 0.8636 -0.4572)
			(end 0.8636 -0.4064)
			(stroke
				(width 0.1)
				(type default)
			)
			(layer "F.Fab")
		)
		(pad "1" smd rect
			(at -0.7366 0 180)
			(size 0.7112 0.8128)
			(layers "F.Cu" "F.Mask" "F.Paste")
			(net "P1V8_PLL0_PEX3")
		)
		(pad "2" smd rect
			(at 0.7366 0 180)
			(size 0.7112 0.8128)
			(layers "F.Cu" "F.Mask" "F.Paste")
			(net "GND")
		)
	)
	(footprint ""
		(layer "F.Cu")
		(at 214.466678 -213.180168 180)
		(property "Reference" "R5772"
			(at 0 0 180)
			(layer "F.SilkS")
			(hide yes)
			(effects
				(font
					(size 1.27 1.27)
				)
			)
		)
		(property "Value" ""
			(at 0 0 180)
			(layer "F.Fab")
			(effects
				(font
					(size 1.27 1.27)
				)
			)
		)
		(duplicate_pad_numbers_are_jumpers no)
		(fp_line
			(start 0.7874 0.4064)
			(end -0.7874 0.4064)
			(stroke
				(width 0.1524)
				(type default)
			)
			(layer "F.SilkS")
		)
		(fp_line
			(start 0.7874 -0.4064)
			(end 0.7874 0.4064)
			(stroke
				(width 0.1524)
				(type default)
			)
			(layer "F.SilkS")
		)
		(fp_line
			(start -0.7874 0.4064)
			(end -0.7874 -0.4064)
			(stroke
				(width 0.1524)
				(type default)
			)
			(layer "F.SilkS")
		)
		(fp_line
			(start -0.7874 -0.4064)
			(end 0.7874 -0.4064)
			(stroke
				(width 0.1524)
				(type default)
			)
			(layer "F.SilkS")
		)
		(fp_line
			(start 0.67945 0.3048)
			(end 0.120396 0.3048)
			(stroke
				(width 0.1)
				(type default)
			)
			(layer "F.Fab")
		)
		(fp_line
			(start 0.67945 -0.3048)
			(end 0.67945 0.3048)
			(stroke
				(width 0.1)
				(type default)
			)
			(layer "F.Fab")
		)
		(fp_line
			(start 0.12065 -0.2794)
			(end 0.12065 -0.3048)
			(stroke
				(width 0.1)
				(type default)
			)
			(layer "F.Fab")
		)
		(fp_line
			(start 0.12065 -0.3048)
			(end 0.67945 -0.3048)
			(stroke
				(width 0.1)
				(type default)
			)
			(layer "F.Fab")
		)
		(fp_line
			(start 0.120396 0.3048)
			(end 0.120396 0.2794)
			(stroke
				(width 0.1)
				(type default)
			)
			(layer "F.Fab")
		)
		(fp_line
			(start 0.120396 0.2794)
			(end -0.12065 0.2794)
			(stroke
				(width 0.1)
				(type default)
			)
			(layer "F.Fab")
		)
		(fp_line
			(start -0.12065 0.3048)
			(end -0.67945 0.3048)
			(stroke
				(width 0.1)
				(type default)
			)
			(layer "F.Fab")
		)
		(fp_line
			(start -0.12065 0.2794)
			(end -0.12065 0.3048)
			(stroke
				(width 0.1)
				(type default)
			)
			(layer "F.Fab")
		)
		(fp_line
			(start -0.12065 -0.2794)
			(end 0.12065 -0.2794)
			(stroke
				(width 0.1)
				(type default)
			)
			(layer "F.Fab")
		)
		(fp_line
			(start -0.12065 -0.305054)
			(end -0.12065 -0.2794)
			(stroke
				(width 0.1)
				(type default)
			)
			(layer "F.Fab")
		)
		(fp_line
			(start -0.67945 0.3048)
			(end -0.67945 -0.305054)
			(stroke
				(width 0.1)
				(type default)
			)
			(layer "F.Fab")
		)
		(fp_line
			(start -0.67945 -0.305054)
			(end -0.12065 -0.305054)
			(stroke
				(width 0.1)
				(type default)
			)
			(layer "F.Fab")
		)
		(pad "1" smd circle
			(at -0.40005 0 180)
			(size 0 0)
			(layers "F.Cu" "F.Mask" "F.Paste")
			(net "SMB_ALERT_PMBUS_R_N")
		)
		(pad "2" smd circle
			(at 0.40005 0 180)
			(size 0 0)
			(layers "F.Cu" "F.Mask" "F.Paste")
			(net "P0V8_PEX0_SMBALERT")
		)
	)
	(footprint ""
		(layer "F.Cu")
		(at 230.749094 -176.72558 180)
		(property "Reference" "C3647"
			(at 0 0 180)
			(layer "F.SilkS")
			(hide yes)
			(effects
				(font
					(size 1.27 1.27)
				)
			)
		)
		(property "Value" ""
			(at 0 0 180)
			(layer "F.Fab")
			(effects
				(font
					(size 1.27 1.27)
				)
			)
		)
		(duplicate_pad_numbers_are_jumpers no)
		(fp_line
			(start 0.7874 0.4064)
			(end -0.7874 0.4064)
			(stroke
				(width 0.1524)
				(type default)
			)
			(layer "F.SilkS")
		)
		(fp_line
			(start 0.7874 -0.4064)
			(end 0.7874 0.4064)
			(stroke
				(width 0.1524)
				(type default)
			)
			(layer "F.SilkS")
		)
		(fp_line
			(start -0.7874 0.4064)
			(end -0.7874 -0.4064)
			(stroke
				(width 0.1524)
				(type default)
			)
			(layer "F.SilkS")
		)
		(fp_line
			(start -0.7874 -0.4064)
			(end 0.7874 -0.4064)
			(stroke
				(width 0.1524)
				(type default)
			)
			(layer "F.SilkS")
		)
		(fp_line
			(start 0.67945 0.3048)
			(end 0.120396 0.3048)
			(stroke
				(width 0.1)
				(type default)
			)
			(layer "F.Fab")
		)
		(fp_line
			(start 0.67945 -0.3048)
			(end 0.67945 0.3048)
			(stroke
				(width 0.1)
				(type default)
			)
			(layer "F.Fab")
		)
		(fp_line
			(start 0.12065 -0.2794)
			(end 0.12065 -0.3048)
			(stroke
				(width 0.1)
				(type default)
			)
			(layer "F.Fab")
		)
		(fp_line
			(start 0.12065 -0.3048)
			(end 0.67945 -0.3048)
			(stroke
				(width 0.1)
				(type default)
			)
			(layer "F.Fab")
		)
		(fp_line
			(start 0.120396 0.3048)
			(end 0.120396 0.2794)
			(stroke
				(width 0.1)
				(type default)
			)
			(layer "F.Fab")
		)
		(fp_line
			(start 0.120396 0.2794)
			(end -0.12065 0.2794)
			(stroke
				(width 0.1)
				(type default)
			)
			(layer "F.Fab")
		)
		(fp_line
			(start -0.12065 0.3048)
			(end -0.67945 0.3048)
			(stroke
				(width 0.1)
				(type default)
			)
			(layer "F.Fab")
		)
		(fp_line
			(start -0.12065 0.2794)
			(end -0.12065 0.3048)
			(stroke
				(width 0.1)
				(type default)
			)
			(layer "F.Fab")
		)
		(fp_line
			(start -0.12065 -0.2794)
			(end 0.12065 -0.2794)
			(stroke
				(width 0.1)
				(type default)
			)
			(layer "F.Fab")
		)
		(fp_line
			(start -0.12065 -0.305054)
			(end -0.12065 -0.2794)
			(stroke
				(width 0.1)
				(type default)
			)
			(layer "F.Fab")
		)
		(fp_line
			(start -0.67945 0.3048)
			(end -0.67945 -0.305054)
			(stroke
				(width 0.1)
				(type default)
			)
			(layer "F.Fab")
		)
		(fp_line
			(start -0.67945 -0.305054)
			(end -0.12065 -0.305054)
			(stroke
				(width 0.1)
				(type default)
			)
			(layer "F.Fab")
		)
		(pad "1" smd circle
			(at -0.40005 0 180)
			(size 0 0)
			(layers "F.Cu" "F.Mask" "F.Paste")
			(net "GND")
		)
		(pad "2" smd circle
			(at 0.40005 0 180)
			(size 0 0)
			(layers "F.Cu" "F.Mask" "F.Paste")
			(net "THRESHOLD")
		)
	)
	(footprint ""
		(layer "F.Cu")
		(at 331.147166 -20.35556)
		(property "Reference" "C3955"
			(at 0 0 0)
			(layer "F.SilkS")
			(hide yes)
			(effects
				(font
					(size 1.27 1.27)
				)
			)
		)
		(property "Value" ""
			(at 0 0 0)
			(layer "F.Fab")
			(effects
				(font
					(size 1.27 1.27)
				)
			)
		)
		(duplicate_pad_numbers_are_jumpers no)
		(fp_line
			(start -0.7874 -0.4064)
			(end 0.7874 -0.4064)
			(stroke
				(width 0.1524)
				(type default)
			)
			(layer "F.SilkS")
		)
		(fp_line
			(start -0.7874 0.4064)
			(end -0.7874 -0.4064)
			(stroke
				(width 0.1524)
				(type default)
			)
			(layer "F.SilkS")
		)
		(fp_line
			(start 0.7874 -0.4064)
			(end 0.7874 0.4064)
			(stroke
				(width 0.1524)
				(type default)
			)
			(layer "F.SilkS")
		)
		(fp_line
			(start 0.7874 0.4064)
			(end -0.7874 0.4064)
			(stroke
				(width 0.1524)
				(type default)
			)
			(layer "F.SilkS")
		)
		(fp_line
			(start -0.67945 -0.305054)
			(end -0.12065 -0.305054)
			(stroke
				(width 0.1)
				(type default)
			)
			(layer "F.Fab")
		)
		(fp_line
			(start -0.67945 0.3048)
			(end -0.67945 -0.305054)
			(stroke
				(width 0.1)
				(type default)
			)
			(layer "F.Fab")
		)
		(fp_line
			(start -0.12065 -0.305054)
			(end -0.12065 -0.2794)
			(stroke
				(width 0.1)
				(type default)
			)
			(layer "F.Fab")
		)
		(fp_line
			(start -0.12065 -0.2794)
			(end 0.12065 -0.2794)
			(stroke
				(width 0.1)
				(type default)
			)
			(layer "F.Fab")
		)
		(fp_line
			(start -0.12065 0.2794)
			(end -0.12065 0.3048)
			(stroke
				(width 0.1)
				(type default)
			)
			(layer "F.Fab")
		)
		(fp_line
			(start -0.12065 0.3048)
			(end -0.67945 0.3048)
			(stroke
				(width 0.1)
				(type default)
			)
			(layer "F.Fab")
		)
		(fp_line
			(start 0.120396 0.2794)
			(end -0.12065 0.2794)
			(stroke
				(width 0.1)
				(type default)
			)
			(layer "F.Fab")
		)
		(fp_line
			(start 0.120396 0.3048)
			(end 0.120396 0.2794)
			(stroke
				(width 0.1)
				(type default)
			)
			(layer "F.Fab")
		)
		(fp_line
			(start 0.12065 -0.3048)
			(end 0.67945 -0.3048)
			(stroke
				(width 0.1)
				(type default)
			)
			(layer "F.Fab")
		)
		(fp_line
			(start 0.12065 -0.2794)
			(end 0.12065 -0.3048)
			(stroke
				(width 0.1)
				(type default)
			)
			(layer "F.Fab")
		)
		(fp_line
			(start 0.67945 -0.3048)
			(end 0.67945 0.3048)
			(stroke
				(width 0.1)
				(type default)
			)
			(layer "F.Fab")
		)
		(fp_line
			(start 0.67945 0.3048)
			(end 0.120396 0.3048)
			(stroke
				(width 0.1)
				(type default)
			)
			(layer "F.Fab")
		)
		(pad "1" smd circle
			(at -0.40005 0)
			(size 0 0)
			(layers "F.Cu" "F.Mask" "F.Paste")
			(net "P12V_SSD11")
		)
		(pad "2" smd circle
			(at 0.40005 0)
			(size 0 0)
			(layers "F.Cu" "F.Mask" "F.Paste")
			(net "GND")
		)
	)
	(footprint ""
		(layer "F.Cu")
		(at 451.638416 -374.471692 90)
		(property "Reference" "R6685"
			(at 0 0 90)
			(layer "F.SilkS")
			(hide yes)
			(effects
				(font
					(size 1.27 1.27)
				)
			)
		)
		(property "Value" ""
			(at 0 0 90)
			(layer "F.Fab")
			(effects
				(font
					(size 1.27 1.27)
				)
			)
		)
		(duplicate_pad_numbers_are_jumpers no)
		(fp_line
			(start 0.7874 -0.4064)
			(end 0.7874 0.4064)
			(stroke
				(width 0.1524)
				(type default)
			)
			(layer "F.SilkS")
		)
		(fp_line
			(start -0.7874 -0.4064)
			(end 0.7874 -0.4064)
			(stroke
				(width 0.1524)
				(type default)
			)
			(layer "F.SilkS")
		)
		(fp_line
			(start 0.7874 0.4064)
			(end -0.7874 0.4064)
			(stroke
				(width 0.1524)
				(type default)
			)
			(layer "F.SilkS")
		)
		(fp_line
			(start -0.7874 0.4064)
			(end -0.7874 -0.4064)
			(stroke
				(width 0.1524)
				(type default)
			)
			(layer "F.SilkS")
		)
		(fp_line
			(start -0.12065 -0.305054)
			(end -0.12065 -0.2794)
			(stroke
				(width 0.1)
				(type default)
			)
			(layer "F.Fab")
		)
		(fp_line
			(start -0.67945 -0.305054)
			(end -0.12065 -0.305054)
			(stroke
				(width 0.1)
				(type default)
			)
			(layer "F.Fab")
		)
		(fp_line
			(start 0.67945 -0.3048)
			(end 0.67945 0.3048)
			(stroke
				(width 0.1)
				(type default)
			)
			(layer "F.Fab")
		)
		(fp_line
			(start 0.12065 -0.3048)
			(end 0.67945 -0.3048)
			(stroke
				(width 0.1)
				(type default)
			)
			(layer "F.Fab")
		)
		(fp_line
			(start 0.12065 -0.2794)
			(end 0.12065 -0.3048)
			(stroke
				(width 0.1)
				(type default)
			)
			(layer "F.Fab")
		)
		(fp_line
			(start -0.12065 -0.2794)
			(end 0.12065 -0.2794)
			(stroke
				(width 0.1)
				(type default)
			)
			(layer "F.Fab")
		)
		(fp_line
			(start 0.120396 0.2794)
			(end -0.12065 0.2794)
			(stroke
				(width 0.1)
				(type default)
			)
			(layer "F.Fab")
		)
		(fp_line
			(start -0.12065 0.2794)
			(end -0.12065 0.3048)
			(stroke
				(width 0.1)
				(type default)
			)
			(layer "F.Fab")
		)
		(fp_line
			(start 0.67945 0.3048)
			(end 0.120396 0.3048)
			(stroke
				(width 0.1)
				(type default)
			)
			(layer "F.Fab")
		)
		(fp_line
			(start 0.120396 0.3048)
			(end 0.120396 0.2794)
			(stroke
				(width 0.1)
				(type default)
			)
			(layer "F.Fab")
		)
		(fp_line
			(start -0.12065 0.3048)
			(end -0.67945 0.3048)
			(stroke
				(width 0.1)
				(type default)
			)
			(layer "F.Fab")
		)
		(fp_line
			(start -0.67945 0.3048)
			(end -0.67945 -0.305054)
			(stroke
				(width 0.1)
				(type default)
			)
			(layer "F.Fab")
		)
		(pad "1" smd circle
			(at -0.40005 0 90)
			(size 0 0)
			(layers "F.Cu" "F.Mask" "F.Paste")
			(net "P3V3_AUX")
		)
		(pad "2" smd circle
			(at 0.40005 0 90)
			(size 0 0)
			(layers "F.Cu" "F.Mask" "F.Paste")
			(net "GPU_3V3IO_RSVD3")
		)
	)
	(footprint ""
		(layer "F.Cu")
		(at 310.443626 -45.88891)
		(property "Reference" "R620"
			(at 0 0 0)
			(layer "F.SilkS")
			(hide yes)
			(effects
				(font
					(size 1.27 1.27)
				)
			)
		)
		(property "Value" ""
			(at 0 0 0)
			(layer "F.Fab")
			(effects
				(font
					(size 1.27 1.27)
				)
			)
		)
		(duplicate_pad_numbers_are_jumpers no)
		(fp_line
			(start -0.7874 -0.4064)
			(end 0.7874 -0.4064)
			(stroke
				(width 0.1524)
				(type default)
			)
			(layer "F.SilkS")
		)
		(fp_line
			(start -0.7874 0.4064)
			(end -0.7874 -0.4064)
			(stroke
				(width 0.1524)
				(type default)
			)
			(layer "F.SilkS")
		)
		(fp_line
			(start 0.7874 -0.4064)
			(end 0.7874 0.4064)
			(stroke
				(width 0.1524)
				(type default)
			)
			(layer "F.SilkS")
		)
		(fp_line
			(start 0.7874 0.4064)
			(end -0.7874 0.4064)
			(stroke
				(width 0.1524)
				(type default)
			)
			(layer "F.SilkS")
		)
		(fp_line
			(start -0.67945 -0.305054)
			(end -0.12065 -0.305054)
			(stroke
				(width 0.1)
				(type default)
			)
			(layer "F.Fab")
		)
		(fp_line
			(start -0.67945 0.3048)
			(end -0.67945 -0.305054)
			(stroke
				(width 0.1)
				(type default)
			)
			(layer "F.Fab")
		)
		(fp_line
			(start -0.12065 -0.305054)
			(end -0.12065 -0.2794)
			(stroke
				(width 0.1)
				(type default)
			)
			(layer "F.Fab")
		)
		(fp_line
			(start -0.12065 -0.2794)
			(end 0.12065 -0.2794)
			(stroke
				(width 0.1)
				(type default)
			)
			(layer "F.Fab")
		)
		(fp_line
			(start -0.12065 0.2794)
			(end -0.12065 0.3048)
			(stroke
				(width 0.1)
				(type default)
			)
			(layer "F.Fab")
		)
		(fp_line
			(start -0.12065 0.3048)
			(end -0.67945 0.3048)
			(stroke
				(width 0.1)
				(type default)
			)
			(layer "F.Fab")
		)
		(fp_line
			(start 0.120396 0.2794)
			(end -0.12065 0.2794)
			(stroke
				(width 0.1)
				(type default)
			)
			(layer "F.Fab")
		)
		(fp_line
			(start 0.120396 0.3048)
			(end 0.120396 0.2794)
			(stroke
				(width 0.1)
				(type default)
			)
			(layer "F.Fab")
		)
		(fp_line
			(start 0.12065 -0.3048)
			(end 0.67945 -0.3048)
			(stroke
				(width 0.1)
				(type default)
			)
			(layer "F.Fab")
		)
		(fp_line
			(start 0.12065 -0.2794)
			(end 0.12065 -0.3048)
			(stroke
				(width 0.1)
				(type default)
			)
			(layer "F.Fab")
		)
		(fp_line
			(start 0.67945 -0.3048)
			(end 0.67945 0.3048)
			(stroke
				(width 0.1)
				(type default)
			)
			(layer "F.Fab")
		)
		(fp_line
			(start 0.67945 0.3048)
			(end 0.120396 0.3048)
			(stroke
				(width 0.1)
				(type default)
			)
			(layer "F.Fab")
		)
		(pad "1" smd circle
			(at -0.40005 0)
			(size 0 0)
			(layers "F.Cu" "F.Mask" "F.Paste")
			(net "SSD10_ADC_A0")
		)
		(pad "2" smd circle
			(at 0.40005 0)
			(size 0 0)
			(layers "F.Cu" "F.Mask" "F.Paste")
			(net "GND")
		)
	)
	(footprint ""
		(layer "F.Cu")
		(at 28.341828 -27.006296 -90)
		(property "Reference" "PR6922"
			(at 0 0 270)
			(layer "F.SilkS")
			(hide yes)
			(effects
				(font
					(size 1.27 1.27)
				)
			)
		)
		(property "Value" ""
			(at 0 0 270)
			(layer "F.Fab")
			(effects
				(font
					(size 1.27 1.27)
				)
			)
		)
		(duplicate_pad_numbers_are_jumpers no)
		(fp_line
			(start -0.7874 0.4064)
			(end -0.7874 -0.4064)
			(stroke
				(width 0.1524)
				(type default)
			)
			(layer "F.SilkS")
		)
		(fp_line
			(start 0.7874 0.4064)
			(end -0.7874 0.4064)
			(stroke
				(width 0.1524)
				(type default)
			)
			(layer "F.SilkS")
		)
		(fp_line
			(start -0.7874 -0.4064)
			(end 0.7874 -0.4064)
			(stroke
				(width 0.1524)
				(type default)
			)
			(layer "F.SilkS")
		)
		(fp_line
			(start 0.7874 -0.4064)
			(end 0.7874 0.4064)
			(stroke
				(width 0.1524)
				(type default)
			)
			(layer "F.SilkS")
		)
		(fp_line
			(start -0.67945 0.3048)
			(end -0.67945 -0.305054)
			(stroke
				(width 0.1)
				(type default)
			)
			(layer "F.Fab")
		)
		(fp_line
			(start -0.12065 0.3048)
			(end -0.67945 0.3048)
			(stroke
				(width 0.1)
				(type default)
			)
			(layer "F.Fab")
		)
		(fp_line
			(start 0.120396 0.3048)
			(end 0.120396 0.2794)
			(stroke
				(width 0.1)
				(type default)
			)
			(layer "F.Fab")
		)
		(fp_line
			(start 0.67945 0.3048)
			(end 0.120396 0.3048)
			(stroke
				(width 0.1)
				(type default)
			)
			(layer "F.Fab")
		)
		(fp_line
			(start -0.12065 0.2794)
			(end -0.12065 0.3048)
			(stroke
				(width 0.1)
				(type default)
			)
			(layer "F.Fab")
		)
		(fp_line
			(start 0.120396 0.2794)
			(end -0.12065 0.2794)
			(stroke
				(width 0.1)
				(type default)
			)
			(layer "F.Fab")
		)
		(fp_line
			(start -0.12065 -0.2794)
			(end 0.12065 -0.2794)
			(stroke
				(width 0.1)
				(type default)
			)
			(layer "F.Fab")
		)
		(fp_line
			(start 0.12065 -0.2794)
			(end 0.12065 -0.3048)
			(stroke
				(width 0.1)
				(type default)
			)
			(layer "F.Fab")
		)
		(fp_line
			(start 0.12065 -0.3048)
			(end 0.67945 -0.3048)
			(stroke
				(width 0.1)
				(type default)
			)
			(layer "F.Fab")
		)
		(fp_line
			(start 0.67945 -0.3048)
			(end 0.67945 0.3048)
			(stroke
				(width 0.1)
				(type default)
			)
			(layer "F.Fab")
		)
		(fp_line
			(start -0.67945 -0.305054)
			(end -0.12065 -0.305054)
			(stroke
				(width 0.1)
				(type default)
			)
			(layer "F.Fab")
		)
		(fp_line
			(start -0.12065 -0.305054)
			(end -0.12065 -0.2794)
			(stroke
				(width 0.1)
				(type default)
			)
			(layer "F.Fab")
		)
		(pad "1" smd circle
			(at -0.40005 0 270)
			(size 0 0)
			(layers "F.Cu" "F.Mask" "F.Paste")
			(net "P3V3_SSD1_CO_ILIMIT")
		)
		(pad "2" smd circle
			(at 0.40005 0 270)
			(size 0 0)
			(layers "F.Cu" "F.Mask" "F.Paste")
			(net "GND")
		)
	)
	(footprint ""
		(layer "F.Cu")
		(at 317.27521 -388.960868)
		(property "Reference" "C4112"
			(at 0 0 0)
			(layer "F.SilkS")
			(hide yes)
			(effects
				(font
					(size 1.27 1.27)
				)
			)
		)
		(property "Value" ""
			(at 0 0 0)
			(layer "F.Fab")
			(effects
				(font
					(size 1.27 1.27)
				)
			)
		)
		(duplicate_pad_numbers_are_jumpers no)
		(fp_line
			(start -0.7874 -0.4064)
			(end 0.7874 -0.4064)
			(stroke
				(width 0.1524)
				(type default)
			)
			(layer "F.SilkS")
		)
		(fp_line
			(start -0.7874 0.4064)
			(end -0.7874 -0.4064)
			(stroke
				(width 0.1524)
				(type default)
			)
			(layer "F.SilkS")
		)
		(fp_line
			(start 0.7874 -0.4064)
			(end 0.7874 0.4064)
			(stroke
				(width 0.1524)
				(type default)
			)
			(layer "F.SilkS")
		)
		(fp_line
			(start 0.7874 0.4064)
			(end -0.7874 0.4064)
			(stroke
				(width 0.1524)
				(type default)
			)
			(layer "F.SilkS")
		)
		(fp_line
			(start -0.67945 -0.305054)
			(end -0.12065 -0.305054)
			(stroke
				(width 0.1)
				(type default)
			)
			(layer "F.Fab")
		)
		(fp_line
			(start -0.67945 0.3048)
			(end -0.67945 -0.305054)
			(stroke
				(width 0.1)
				(type default)
			)
			(layer "F.Fab")
		)
		(fp_line
			(start -0.12065 -0.305054)
			(end -0.12065 -0.2794)
			(stroke
				(width 0.1)
				(type default)
			)
			(layer "F.Fab")
		)
		(fp_line
			(start -0.12065 -0.2794)
			(end 0.12065 -0.2794)
			(stroke
				(width 0.1)
				(type default)
			)
			(layer "F.Fab")
		)
		(fp_line
			(start -0.12065 0.2794)
			(end -0.12065 0.3048)
			(stroke
				(width 0.1)
				(type default)
			)
			(layer "F.Fab")
		)
		(fp_line
			(start -0.12065 0.3048)
			(end -0.67945 0.3048)
			(stroke
				(width 0.1)
				(type default)
			)
			(layer "F.Fab")
		)
		(fp_line
			(start 0.120396 0.2794)
			(end -0.12065 0.2794)
			(stroke
				(width 0.1)
				(type default)
			)
			(layer "F.Fab")
		)
		(fp_line
			(start 0.120396 0.3048)
			(end 0.120396 0.2794)
			(stroke
				(width 0.1)
				(type default)
			)
			(layer "F.Fab")
		)
		(fp_line
			(start 0.12065 -0.3048)
			(end 0.67945 -0.3048)
			(stroke
				(width 0.1)
				(type default)
			)
			(layer "F.Fab")
		)
		(fp_line
			(start 0.12065 -0.2794)
			(end 0.12065 -0.3048)
			(stroke
				(width 0.1)
				(type default)
			)
			(layer "F.Fab")
		)
		(fp_line
			(start 0.67945 -0.3048)
			(end 0.67945 0.3048)
			(stroke
				(width 0.1)
				(type default)
			)
			(layer "F.Fab")
		)
		(fp_line
			(start 0.67945 0.3048)
			(end 0.120396 0.3048)
			(stroke
				(width 0.1)
				(type default)
			)
			(layer "F.Fab")
		)
		(pad "1" smd circle
			(at -0.40005 0)
			(size 0 0)
			(layers "F.Cu" "F.Mask" "F.Paste")
			(net "GND")
		)
		(pad "2" smd circle
			(at 0.40005 0)
			(size 0 0)
			(layers "F.Cu" "F.Mask" "F.Paste")
			(net "GPU_3V3IO_RSVD5_FFU")
		)
	)
	(footprint ""
		(layer "F.Cu")
		(at 367.523776 -152.71115 90)
		(property "Reference" "R752"
			(at 0 0 90)
			(layer "F.SilkS")
			(hide yes)
			(effects
				(font
					(size 1.27 1.27)
				)
			)
		)
		(property "Value" ""
			(at 0 0 90)
			(layer "F.Fab")
			(effects
				(font
					(size 1.27 1.27)
				)
			)
		)
		(duplicate_pad_numbers_are_jumpers no)
		(fp_line
			(start 0.7874 -0.4064)
			(end 0.7874 0.4064)
			(stroke
				(width 0.1524)
				(type default)
			)
			(layer "F.SilkS")
		)
		(fp_line
			(start -0.7874 -0.4064)
			(end 0.7874 -0.4064)
			(stroke
				(width 0.1524)
				(type default)
			)
			(layer "F.SilkS")
		)
		(fp_line
			(start 0.7874 0.4064)
			(end -0.7874 0.4064)
			(stroke
				(width 0.1524)
				(type default)
			)
			(layer "F.SilkS")
		)
		(fp_line
			(start -0.7874 0.4064)
			(end -0.7874 -0.4064)
			(stroke
				(width 0.1524)
				(type default)
			)
			(layer "F.SilkS")
		)
		(fp_line
			(start -0.12065 -0.305054)
			(end -0.12065 -0.2794)
			(stroke
				(width 0.1)
				(type default)
			)
			(layer "F.Fab")
		)
		(fp_line
			(start -0.67945 -0.305054)
			(end -0.12065 -0.305054)
			(stroke
				(width 0.1)
				(type default)
			)
			(layer "F.Fab")
		)
		(fp_line
			(start 0.67945 -0.3048)
			(end 0.67945 0.3048)
			(stroke
				(width 0.1)
				(type default)
			)
			(layer "F.Fab")
		)
		(fp_line
			(start 0.12065 -0.3048)
			(end 0.67945 -0.3048)
			(stroke
				(width 0.1)
				(type default)
			)
			(layer "F.Fab")
		)
		(fp_line
			(start 0.12065 -0.2794)
			(end 0.12065 -0.3048)
			(stroke
				(width 0.1)
				(type default)
			)
			(layer "F.Fab")
		)
		(fp_line
			(start -0.12065 -0.2794)
			(end 0.12065 -0.2794)
			(stroke
				(width 0.1)
				(type default)
			)
			(layer "F.Fab")
		)
		(fp_line
			(start 0.120396 0.2794)
			(end -0.12065 0.2794)
			(stroke
				(width 0.1)
				(type default)
			)
			(layer "F.Fab")
		)
		(fp_line
			(start -0.12065 0.2794)
			(end -0.12065 0.3048)
			(stroke
				(width 0.1)
				(type default)
			)
			(layer "F.Fab")
		)
		(fp_line
			(start 0.67945 0.3048)
			(end 0.120396 0.3048)
			(stroke
				(width 0.1)
				(type default)
			)
			(layer "F.Fab")
		)
		(fp_line
			(start 0.120396 0.3048)
			(end 0.120396 0.2794)
			(stroke
				(width 0.1)
				(type default)
			)
			(layer "F.Fab")
		)
		(fp_line
			(start -0.12065 0.3048)
			(end -0.67945 0.3048)
			(stroke
				(width 0.1)
				(type default)
			)
			(layer "F.Fab")
		)
		(fp_line
			(start -0.67945 0.3048)
			(end -0.67945 -0.305054)
			(stroke
				(width 0.1)
				(type default)
			)
			(layer "F.Fab")
		)
		(pad "1" smd circle
			(at -0.40005 0 90)
			(size 0 0)
			(layers "F.Cu" "F.Mask" "F.Paste")
			(net "NIC6_ADC_A0")
		)
		(pad "2" smd circle
			(at 0.40005 0 90)
			(size 0 0)
			(layers "F.Cu" "F.Mask" "F.Paste")
			(net "GND")
		)
	)
	(footprint ""
		(layer "F.Cu")
		(at 450.230494 -120.79224)
		(property "Reference" "R6051"
			(at 0 0 0)
			(layer "F.SilkS")
			(hide yes)
			(effects
				(font
					(size 1.27 1.27)
				)
			)
		)
		(property "Value" ""
			(at 0 0 0)
			(layer "F.Fab")
			(effects
				(font
					(size 1.27 1.27)
				)
			)
		)
		(duplicate_pad_numbers_are_jumpers no)
		(fp_line
			(start -0.7874 -0.4064)
			(end 0.7874 -0.4064)
			(stroke
				(width 0.1524)
				(type default)
			)
			(layer "F.SilkS")
		)
		(fp_line
			(start -0.7874 0.4064)
			(end -0.7874 -0.4064)
			(stroke
				(width 0.1524)
				(type default)
			)
			(layer "F.SilkS")
		)
		(fp_line
			(start 0.7874 -0.4064)
			(end 0.7874 0.4064)
			(stroke
				(width 0.1524)
				(type default)
			)
			(layer "F.SilkS")
		)
		(fp_line
			(start 0.7874 0.4064)
			(end -0.7874 0.4064)
			(stroke
				(width 0.1524)
				(type default)
			)
			(layer "F.SilkS")
		)
		(fp_line
			(start -0.67945 -0.305054)
			(end -0.12065 -0.305054)
			(stroke
				(width 0.1)
				(type default)
			)
			(layer "F.Fab")
		)
		(fp_line
			(start -0.67945 0.3048)
			(end -0.67945 -0.305054)
			(stroke
				(width 0.1)
				(type default)
			)
			(layer "F.Fab")
		)
		(fp_line
			(start -0.12065 -0.305054)
			(end -0.12065 -0.2794)
			(stroke
				(width 0.1)
				(type default)
			)
			(layer "F.Fab")
		)
		(fp_line
			(start -0.12065 -0.2794)
			(end 0.12065 -0.2794)
			(stroke
				(width 0.1)
				(type default)
			)
			(layer "F.Fab")
		)
		(fp_line
			(start -0.12065 0.2794)
			(end -0.12065 0.3048)
			(stroke
				(width 0.1)
				(type default)
			)
			(layer "F.Fab")
		)
		(fp_line
			(start -0.12065 0.3048)
			(end -0.67945 0.3048)
			(stroke
				(width 0.1)
				(type default)
			)
			(layer "F.Fab")
		)
		(fp_line
			(start 0.120396 0.2794)
			(end -0.12065 0.2794)
			(stroke
				(width 0.1)
				(type default)
			)
			(layer "F.Fab")
		)
		(fp_line
			(start 0.120396 0.3048)
			(end 0.120396 0.2794)
			(stroke
				(width 0.1)
				(type default)
			)
			(layer "F.Fab")
		)
		(fp_line
			(start 0.12065 -0.3048)
			(end 0.67945 -0.3048)
			(stroke
				(width 0.1)
				(type default)
			)
			(layer "F.Fab")
		)
		(fp_line
			(start 0.12065 -0.2794)
			(end 0.12065 -0.3048)
			(stroke
				(width 0.1)
				(type default)
			)
			(layer "F.Fab")
		)
		(fp_line
			(start 0.67945 -0.3048)
			(end 0.67945 0.3048)
			(stroke
				(width 0.1)
				(type default)
			)
			(layer "F.Fab")
		)
		(fp_line
			(start 0.67945 0.3048)
			(end 0.120396 0.3048)
			(stroke
				(width 0.1)
				(type default)
			)
			(layer "F.Fab")
		)
		(pad "1" smd circle
			(at -0.40005 0)
			(size 0 0)
			(layers "F.Cu" "F.Mask" "F.Paste")
			(net "P3V3_NIC7")
		)
		(pad "2" smd circle
			(at 0.40005 0)
			(size 0 0)
			(layers "F.Cu" "F.Mask" "F.Paste")
			(net "P3V3_NIC7_PG_G1")
		)
	)
	(footprint ""
		(layer "F.Cu")
		(at 336.042 -160.782 180)
		(property "Reference" "R4811"
			(at 0 0 180)
			(layer "F.SilkS")
			(hide yes)
			(effects
				(font
					(size 1.27 1.27)
				)
			)
		)
		(property "Value" ""
			(at 0 0 180)
			(layer "F.Fab")
			(effects
				(font
					(size 1.27 1.27)
				)
			)
		)
		(duplicate_pad_numbers_are_jumpers no)
		(fp_line
			(start 0.7874 0.4064)
			(end -0.7874 0.4064)
			(stroke
				(width 0.1524)
				(type default)
			)
			(layer "F.SilkS")
		)
		(fp_line
			(start 0.7874 -0.4064)
			(end 0.7874 0.4064)
			(stroke
				(width 0.1524)
				(type default)
			)
			(layer "F.SilkS")
		)
		(fp_line
			(start -0.7874 0.4064)
			(end -0.7874 -0.4064)
			(stroke
				(width 0.1524)
				(type default)
			)
			(layer "F.SilkS")
		)
		(fp_line
			(start -0.7874 -0.4064)
			(end 0.7874 -0.4064)
			(stroke
				(width 0.1524)
				(type default)
			)
			(layer "F.SilkS")
		)
		(fp_line
			(start 0.67945 0.3048)
			(end 0.120396 0.3048)
			(stroke
				(width 0.1)
				(type default)
			)
			(layer "F.Fab")
		)
		(fp_line
			(start 0.67945 -0.3048)
			(end 0.67945 0.3048)
			(stroke
				(width 0.1)
				(type default)
			)
			(layer "F.Fab")
		)
		(fp_line
			(start 0.12065 -0.2794)
			(end 0.12065 -0.3048)
			(stroke
				(width 0.1)
				(type default)
			)
			(layer "F.Fab")
		)
		(fp_line
			(start 0.12065 -0.3048)
			(end 0.67945 -0.3048)
			(stroke
				(width 0.1)
				(type default)
			)
			(layer "F.Fab")
		)
		(fp_line
			(start 0.120396 0.3048)
			(end 0.120396 0.2794)
			(stroke
				(width 0.1)
				(type default)
			)
			(layer "F.Fab")
		)
		(fp_line
			(start 0.120396 0.2794)
			(end -0.12065 0.2794)
			(stroke
				(width 0.1)
				(type default)
			)
			(layer "F.Fab")
		)
		(fp_line
			(start -0.12065 0.3048)
			(end -0.67945 0.3048)
			(stroke
				(width 0.1)
				(type default)
			)
			(layer "F.Fab")
		)
		(fp_line
			(start -0.12065 0.2794)
			(end -0.12065 0.3048)
			(stroke
				(width 0.1)
				(type default)
			)
			(layer "F.Fab")
		)
		(fp_line
			(start -0.12065 -0.2794)
			(end 0.12065 -0.2794)
			(stroke
				(width 0.1)
				(type default)
			)
			(layer "F.Fab")
		)
		(fp_line
			(start -0.12065 -0.305054)
			(end -0.12065 -0.2794)
			(stroke
				(width 0.1)
				(type default)
			)
			(layer "F.Fab")
		)
		(fp_line
			(start -0.67945 0.3048)
			(end -0.67945 -0.305054)
			(stroke
				(width 0.1)
				(type default)
			)
			(layer "F.Fab")
		)
		(fp_line
			(start -0.67945 -0.305054)
			(end -0.12065 -0.305054)
			(stroke
				(width 0.1)
				(type default)
			)
			(layer "F.Fab")
		)
		(pad "1" smd circle
			(at -0.40005 0 180)
			(size 0 0)
			(layers "F.Cu" "F.Mask" "F.Paste")
			(net "PCA9555_0_PEX3_A2")
		)
		(pad "2" smd circle
			(at 0.40005 0 180)
			(size 0 0)
			(layers "F.Cu" "F.Mask" "F.Paste")
			(net "P3V3_AUX")
		)
	)
	(footprint ""
		(layer "F.Cu")
		(at 328.936604 -343.952322 90)
		(property "Reference" "C536"
			(at 0 0 90)
			(layer "F.SilkS")
			(hide yes)
			(effects
				(font
					(size 1.27 1.27)
				)
			)
		)
		(property "Value" ""
			(at 0 0 90)
			(layer "F.Fab")
			(effects
				(font
					(size 1.27 1.27)
				)
			)
		)
		(duplicate_pad_numbers_are_jumpers no)
		(fp_line
			(start 0.299974 -0.150114)
			(end 0.299974 0.150114)
			(stroke
				(width 0.1)
				(type default)
			)
			(layer "F.Fab")
		)
		(fp_line
			(start -0.299974 -0.150114)
			(end 0.299974 -0.150114)
			(stroke
				(width 0.1)
				(type default)
			)
			(layer "F.Fab")
		)
		(fp_line
			(start 0.299974 0.150114)
			(end -0.299974 0.150114)
			(stroke
				(width 0.1)
				(type default)
			)
			(layer "F.Fab")
		)
		(fp_line
			(start -0.299974 0.150114)
			(end -0.299974 -0.150114)
			(stroke
				(width 0.1)
				(type default)
			)
			(layer "F.Fab")
		)
		(pad "1" smd rect
			(at -0.2667 0 90)
			(size 0.3048 0.381)
			(layers "F.Cu" "F.Mask" "F.Paste")
			(net "P5E_PEX2_STN5_TX_DN<87>")
		)
		(pad "2" smd rect
			(at 0.2667 0 90)
			(size 0.3048 0.381)
			(layers "F.Cu" "F.Mask" "F.Paste")
			(net "P5E_PEX2_STN5_TX_C_DN<87>")
		)
	)
	(footprint ""
		(layer "F.Cu")
		(at 142.343886 -46.90491)
		(property "Reference" "R552"
			(at 0 0 0)
			(layer "F.SilkS")
			(hide yes)
			(effects
				(font
					(size 1.27 1.27)
				)
			)
		)
		(property "Value" ""
			(at 0 0 0)
			(layer "F.Fab")
			(effects
				(font
					(size 1.27 1.27)
				)
			)
		)
		(duplicate_pad_numbers_are_jumpers no)
		(fp_line
			(start -0.7874 -0.4064)
			(end 0.7874 -0.4064)
			(stroke
				(width 0.1524)
				(type default)
			)
			(layer "F.SilkS")
		)
		(fp_line
			(start -0.7874 0.4064)
			(end -0.7874 -0.4064)
			(stroke
				(width 0.1524)
				(type default)
			)
			(layer "F.SilkS")
		)
		(fp_line
			(start 0.7874 -0.4064)
			(end 0.7874 0.4064)
			(stroke
				(width 0.1524)
				(type default)
			)
			(layer "F.SilkS")
		)
		(fp_line
			(start 0.7874 0.4064)
			(end -0.7874 0.4064)
			(stroke
				(width 0.1524)
				(type default)
			)
			(layer "F.SilkS")
		)
		(fp_line
			(start -0.67945 -0.305054)
			(end -0.12065 -0.305054)
			(stroke
				(width 0.1)
				(type default)
			)
			(layer "F.Fab")
		)
		(fp_line
			(start -0.67945 0.3048)
			(end -0.67945 -0.305054)
			(stroke
				(width 0.1)
				(type default)
			)
			(layer "F.Fab")
		)
		(fp_line
			(start -0.12065 -0.305054)
			(end -0.12065 -0.2794)
			(stroke
				(width 0.1)
				(type default)
			)
			(layer "F.Fab")
		)
		(fp_line
			(start -0.12065 -0.2794)
			(end 0.12065 -0.2794)
			(stroke
				(width 0.1)
				(type default)
			)
			(layer "F.Fab")
		)
		(fp_line
			(start -0.12065 0.2794)
			(end -0.12065 0.3048)
			(stroke
				(width 0.1)
				(type default)
			)
			(layer "F.Fab")
		)
		(fp_line
			(start -0.12065 0.3048)
			(end -0.67945 0.3048)
			(stroke
				(width 0.1)
				(type default)
			)
			(layer "F.Fab")
		)
		(fp_line
			(start 0.120396 0.2794)
			(end -0.12065 0.2794)
			(stroke
				(width 0.1)
				(type default)
			)
			(layer "F.Fab")
		)
		(fp_line
			(start 0.120396 0.3048)
			(end 0.120396 0.2794)
			(stroke
				(width 0.1)
				(type default)
			)
			(layer "F.Fab")
		)
		(fp_line
			(start 0.12065 -0.3048)
			(end 0.67945 -0.3048)
			(stroke
				(width 0.1)
				(type default)
			)
			(layer "F.Fab")
		)
		(fp_line
			(start 0.12065 -0.2794)
			(end 0.12065 -0.3048)
			(stroke
				(width 0.1)
				(type default)
			)
			(layer "F.Fab")
		)
		(fp_line
			(start 0.67945 -0.3048)
			(end 0.67945 0.3048)
			(stroke
				(width 0.1)
				(type default)
			)
			(layer "F.Fab")
		)
		(fp_line
			(start 0.67945 0.3048)
			(end 0.120396 0.3048)
			(stroke
				(width 0.1)
				(type default)
			)
			(layer "F.Fab")
		)
		(pad "1" smd circle
			(at -0.40005 0)
			(size 0 0)
			(layers "F.Cu" "F.Mask" "F.Paste")
			(net "SSD4_ADC_ALERT_N")
		)
		(pad "2" smd circle
			(at 0.40005 0)
			(size 0 0)
			(layers "F.Cu" "F.Mask" "F.Paste")
			(net "SSD_0_7_ADC_ALERT_N")
		)
	)
	(footprint ""
		(layer "F.Cu")
		(at 345.76131 -261.687564 180)
		(property "Reference" "PR133"
			(at 0 0 180)
			(layer "F.SilkS")
			(hide yes)
			(effects
				(font
					(size 1.27 1.27)
				)
			)
		)
		(property "Value" ""
			(at 0 0 180)
			(layer "F.Fab")
			(effects
				(font
					(size 1.27 1.27)
				)
			)
		)
		(duplicate_pad_numbers_are_jumpers no)
		(fp_line
			(start 0.7874 0.4064)
			(end -0.7874 0.4064)
			(stroke
				(width 0.1524)
				(type default)
			)
			(layer "F.SilkS")
		)
		(fp_line
			(start 0.7874 -0.4064)
			(end 0.7874 0.4064)
			(stroke
				(width 0.1524)
				(type default)
			)
			(layer "F.SilkS")
		)
		(fp_line
			(start -0.7874 0.4064)
			(end -0.7874 -0.4064)
			(stroke
				(width 0.1524)
				(type default)
			)
			(layer "F.SilkS")
		)
		(fp_line
			(start -0.7874 -0.4064)
			(end 0.7874 -0.4064)
			(stroke
				(width 0.1524)
				(type default)
			)
			(layer "F.SilkS")
		)
		(fp_line
			(start 0.67945 0.3048)
			(end 0.120396 0.3048)
			(stroke
				(width 0.1)
				(type default)
			)
			(layer "F.Fab")
		)
		(fp_line
			(start 0.67945 -0.3048)
			(end 0.67945 0.3048)
			(stroke
				(width 0.1)
				(type default)
			)
			(layer "F.Fab")
		)
		(fp_line
			(start 0.12065 -0.2794)
			(end 0.12065 -0.3048)
			(stroke
				(width 0.1)
				(type default)
			)
			(layer "F.Fab")
		)
		(fp_line
			(start 0.12065 -0.3048)
			(end 0.67945 -0.3048)
			(stroke
				(width 0.1)
				(type default)
			)
			(layer "F.Fab")
		)
		(fp_line
			(start 0.120396 0.3048)
			(end 0.120396 0.2794)
			(stroke
				(width 0.1)
				(type default)
			)
			(layer "F.Fab")
		)
		(fp_line
			(start 0.120396 0.2794)
			(end -0.12065 0.2794)
			(stroke
				(width 0.1)
				(type default)
			)
			(layer "F.Fab")
		)
		(fp_line
			(start -0.12065 0.3048)
			(end -0.67945 0.3048)
			(stroke
				(width 0.1)
				(type default)
			)
			(layer "F.Fab")
		)
		(fp_line
			(start -0.12065 0.2794)
			(end -0.12065 0.3048)
			(stroke
				(width 0.1)
				(type default)
			)
			(layer "F.Fab")
		)
		(fp_line
			(start -0.12065 -0.2794)
			(end 0.12065 -0.2794)
			(stroke
				(width 0.1)
				(type default)
			)
			(layer "F.Fab")
		)
		(fp_line
			(start -0.12065 -0.305054)
			(end -0.12065 -0.2794)
			(stroke
				(width 0.1)
				(type default)
			)
			(layer "F.Fab")
		)
		(fp_line
			(start -0.67945 0.3048)
			(end -0.67945 -0.305054)
			(stroke
				(width 0.1)
				(type default)
			)
			(layer "F.Fab")
		)
		(fp_line
			(start -0.67945 -0.305054)
			(end -0.12065 -0.305054)
			(stroke
				(width 0.1)
				(type default)
			)
			(layer "F.Fab")
		)
		(pad "1" smd circle
			(at -0.40005 0 180)
			(size 0 0)
			(layers "F.Cu" "F.Mask" "F.Paste")
			(net "P0V8_PEX2_VR_CONFIG")
		)
		(pad "2" smd circle
			(at 0.40005 0 180)
			(size 0 0)
			(layers "F.Cu" "F.Mask" "F.Paste")
			(net "GND")
		)
	)
	(footprint ""
		(layer "F.Cu")
		(at 254.84709 -54.3941)
		(property "Reference" "PU38"
			(at -2.074418 3.195574 0)
			(unlocked yes)
			(layer "F.SilkS")
			(effects
				(font
					(size 0.7874 0.5842)
					(thickness 0.1524)
				)
				(justify left)
			)
		)
		(property "Value" ""
			(at 0 0 0)
			(layer "F.Fab")
			(effects
				(font
					(size 1.27 1.27)
				)
			)
		)
		(duplicate_pad_numbers_are_jumpers no)
		(fp_line
			(start -1.943608 -1.549908)
			(end 1.943608 -1.549908)
			(stroke
				(width 0.1524)
				(type default)
			)
			(layer "F.SilkS")
		)
		(fp_line
			(start -1.943608 1.549908)
			(end -1.943608 -1.549908)
			(stroke
				(width 0.1524)
				(type default)
			)
			(layer "F.SilkS")
		)
		(fp_line
			(start 1.943608 -1.549908)
			(end 1.943608 1.549908)
			(stroke
				(width 0.1524)
				(type default)
			)
			(layer "F.SilkS")
		)
		(fp_line
			(start 1.943608 1.549908)
			(end -1.943608 1.549908)
			(stroke
				(width 0.1524)
				(type default)
			)
			(layer "F.SilkS")
		)
		(fp_poly
			(pts
				(xy -2.019808 -1.549908) (xy -1.257808 -1.549908) (xy -1.257808 -1.880108) (xy -2.019808 -1.880108)
			)
			(stroke
				(width 0)
				(type default)
			)
			(fill yes)
			(layer "F.SilkS")
		)
		(fp_line
			(start -1.549908 -1.549908)
			(end 1.549908 -1.549908)
			(stroke
				(width 0.1)
				(type default)
			)
			(layer "F.Fab")
		)
		(fp_line
			(start -1.549908 1.549908)
			(end -1.549908 -1.549908)
			(stroke
				(width 0.1)
				(type default)
			)
			(layer "F.Fab")
		)
		(fp_line
			(start 1.549908 -1.549908)
			(end 1.549908 1.549908)
			(stroke
				(width 0.1)
				(type default)
			)
			(layer "F.Fab")
		)
		(fp_line
			(start 1.549908 1.549908)
			(end -1.549908 1.549908)
			(stroke
				(width 0.1)
				(type default)
			)
			(layer "F.Fab")
		)
		(fp_poly
			(pts
				(xy -2.019808 -1.549908) (xy -1.257808 -1.549908) (xy -1.257808 -1.880108) (xy -2.019808 -1.880108)
			)
			(stroke
				(width 0)
				(type default)
			)
			(fill yes)
			(layer "F.Fab")
		)
		(pad "1" smd rect
			(at -1.500124 -1.249934 270)
			(size 0.2794 0.6096)
			(layers "F.Cu" "F.Mask" "F.Paste")
			(net "P12V_SSD8_R")
		)
		(pad "2" smd rect
			(at -1.500124 -0.750062 270)
			(size 0.2794 0.6096)
			(layers "F.Cu" "F.Mask" "F.Paste")
			(net "P12V_SSD8_R")
		)
		(pad "3" smd rect
			(at -1.500124 -0.249936 270)
			(size 0.2794 0.6096)
			(layers "F.Cu" "F.Mask" "F.Paste")
			(net "P12V_SSD8_R")
		)
		(pad "4" smd rect
			(at -1.500124 0.249936 270)
			(size 0.2794 0.6096)
			(layers "F.Cu" "F.Mask" "F.Paste")
			(net "P12V_SSD8_R")
		)
		(pad "5" smd rect
			(at -1.500124 0.750062 270)
			(size 0.2794 0.6096)
			(layers "F.Cu" "F.Mask" "F.Paste")
			(net "P12V_SSD8_R")
		)
		(pad "6" smd rect
			(at -1.500124 1.249934 270)
			(size 0.2794 0.6096)
			(layers "F.Cu" "F.Mask" "F.Paste")
			(net "GND")
		)
		(pad "7" smd rect
			(at 1.500124 1.249934 270)
			(size 0.2794 0.6096)
			(layers "F.Cu" "F.Mask" "F.Paste")
			(net "P12V_SSD8_SS")
		)
		(pad "8" smd rect
			(at 1.500124 0.750062 270)
			(size 0.2794 0.6096)
			(layers "F.Cu" "F.Mask" "F.Paste")
			(net "PWRGD_P12V_SSD8")
		)
		(pad "9" smd rect
			(at 1.500124 0.249936 270)
			(size 0.2794 0.6096)
			(layers "F.Cu" "F.Mask" "F.Paste")
			(net "P12V_SSD8_OCP")
		)
		(pad "10" smd rect
			(at 1.500124 -0.249936 270)
			(size 0.2794 0.6096)
			(layers "F.Cu" "F.Mask" "F.Paste")
			(net "P5V_AUX")
		)
		(pad "11" smd rect
			(at 1.500124 -0.750062 270)
			(size 0.2794 0.6096)
			(layers "F.Cu" "F.Mask" "F.Paste")
			(net "SSD8_PWR_EN_R")
		)
		(pad "12" smd rect
			(at 1.500124 -1.249934 270)
			(size 0.2794 0.6096)
			(layers "F.Cu" "F.Mask" "F.Paste")
			(net "P12V_AUX")
		)
		(pad "13" smd rect
			(at 0 0)
			(size 1.9812 2.7178)
			(layers "F.Cu" "F.Mask" "F.Paste")
			(net "P12V_AUX")
		)
		(zone
			(layer "F.Cu")
			(hatch none 0.5)
			(connect_pads
				(clearance 0)
			)
			(min_thickness 0.25)
			(keepout
				(tracks not_allowed)
				(vias allowed)
				(pads allowed)
				(copperpour not_allowed)
				(footprints allowed)
			)
			(placement
				(enabled no)
				(sheetname "")
			)
			(fill
				(thermal_gap 0.5)
				(thermal_bridge_width 0.5)
				(island_removal_mode 0)
			)
			(polygon
				(pts
					(xy 255.99009 -55.9435) (xy 255.99009 -55.8165) (xy 255.99009 -52.8447) (xy 255.99009 -52.844192)
					(xy 253.70409 -52.844192) (xy 253.70409 -52.8447) (xy 253.70409 -52.9717) (xy 253.70409 -54.3941)
					(xy 253.80569 -54.3941) (xy 253.80569 -52.9717) (xy 255.88849 -52.9717) (xy 255.88849 -55.8165)
					(xy 253.80569 -55.8165) (xy 253.80569 -54.4195) (xy 253.70409 -54.4195) (xy 253.70409 -55.8165)
					(xy 253.70409 -55.9435) (xy 253.70409 -55.944008) (xy 255.99009 -55.944008)
				)
			)
		)
	)
	(footprint ""
		(layer "F.Cu")
		(at 83.394042 -29.507688 -90)
		(property "Reference" "PC683"
			(at 0 0 270)
			(layer "F.SilkS")
			(hide yes)
			(effects
				(font
					(size 1.27 1.27)
				)
			)
		)
		(property "Value" ""
			(at 0 0 270)
			(layer "F.Fab")
			(effects
				(font
					(size 1.27 1.27)
				)
			)
		)
		(duplicate_pad_numbers_are_jumpers no)
		(fp_line
			(start -1.524 0.762)
			(end -1.524 -0.762)
			(stroke
				(width 0.1524)
				(type default)
			)
			(layer "F.SilkS")
		)
		(fp_line
			(start 1.524 0.762)
			(end -1.524 0.762)
			(stroke
				(width 0.1524)
				(type default)
			)
			(layer "F.SilkS")
		)
		(fp_line
			(start -1.524 -0.762)
			(end 1.524 -0.762)
			(stroke
				(width 0.1524)
				(type default)
			)
			(layer "F.SilkS")
		)
		(fp_line
			(start 1.524 -0.762)
			(end 1.524 0.762)
			(stroke
				(width 0.1524)
				(type default)
			)
			(layer "F.SilkS")
		)
		(fp_line
			(start -1.1049 0.724916)
			(end 1.1049 0.724916)
			(stroke
				(width 0.1)
				(type default)
			)
			(layer "F.Fab")
		)
		(fp_line
			(start 1.1049 0.724916)
			(end 1.1049 -0.724916)
			(stroke
				(width 0.1)
				(type default)
			)
			(layer "F.Fab")
		)
		(fp_line
			(start -1.1049 -0.724916)
			(end -1.1049 0.724916)
			(stroke
				(width 0.1)
				(type default)
			)
			(layer "F.Fab")
		)
		(fp_line
			(start 1.1049 -0.724916)
			(end -1.1049 -0.724916)
			(stroke
				(width 0.1)
				(type default)
			)
			(layer "F.Fab")
		)
		(pad "1" smd rect
			(at -0.889 0 90)
			(size 1.016 1.27)
			(layers "F.Cu" "F.Mask" "F.Paste")
			(net "P3V3_SSD3")
		)
		(pad "2" smd rect
			(at 0.889 0 90)
			(size 1.016 1.27)
			(layers "F.Cu" "F.Mask" "F.Paste")
			(net "GND")
		)
	)
	(footprint ""
		(layer "F.Cu")
		(at 336.004662 -10.545572 90)
		(property "Reference" "R1706"
			(at 0 0 90)
			(layer "F.SilkS")
			(hide yes)
			(effects
				(font
					(size 1.27 1.27)
				)
			)
		)
		(property "Value" ""
			(at 0 0 90)
			(layer "F.Fab")
			(effects
				(font
					(size 1.27 1.27)
				)
			)
		)
		(duplicate_pad_numbers_are_jumpers no)
		(fp_line
			(start 0.7874 -0.4064)
			(end 0.7874 0.4064)
			(stroke
				(width 0.1524)
				(type default)
			)
			(layer "F.SilkS")
		)
		(fp_line
			(start -0.7874 -0.4064)
			(end 0.7874 -0.4064)
			(stroke
				(width 0.1524)
				(type default)
			)
			(layer "F.SilkS")
		)
		(fp_line
			(start 0.7874 0.4064)
			(end -0.7874 0.4064)
			(stroke
				(width 0.1524)
				(type default)
			)
			(layer "F.SilkS")
		)
		(fp_line
			(start -0.7874 0.4064)
			(end -0.7874 -0.4064)
			(stroke
				(width 0.1524)
				(type default)
			)
			(layer "F.SilkS")
		)
		(fp_line
			(start -0.12065 -0.305054)
			(end -0.12065 -0.2794)
			(stroke
				(width 0.1)
				(type default)
			)
			(layer "F.Fab")
		)
		(fp_line
			(start -0.67945 -0.305054)
			(end -0.12065 -0.305054)
			(stroke
				(width 0.1)
				(type default)
			)
			(layer "F.Fab")
		)
		(fp_line
			(start 0.67945 -0.3048)
			(end 0.67945 0.3048)
			(stroke
				(width 0.1)
				(type default)
			)
			(layer "F.Fab")
		)
		(fp_line
			(start 0.12065 -0.3048)
			(end 0.67945 -0.3048)
			(stroke
				(width 0.1)
				(type default)
			)
			(layer "F.Fab")
		)
		(fp_line
			(start 0.12065 -0.2794)
			(end 0.12065 -0.3048)
			(stroke
				(width 0.1)
				(type default)
			)
			(layer "F.Fab")
		)
		(fp_line
			(start -0.12065 -0.2794)
			(end 0.12065 -0.2794)
			(stroke
				(width 0.1)
				(type default)
			)
			(layer "F.Fab")
		)
		(fp_line
			(start 0.120396 0.2794)
			(end -0.12065 0.2794)
			(stroke
				(width 0.1)
				(type default)
			)
			(layer "F.Fab")
		)
		(fp_line
			(start -0.12065 0.2794)
			(end -0.12065 0.3048)
			(stroke
				(width 0.1)
				(type default)
			)
			(layer "F.Fab")
		)
		(fp_line
			(start 0.67945 0.3048)
			(end 0.120396 0.3048)
			(stroke
				(width 0.1)
				(type default)
			)
			(layer "F.Fab")
		)
		(fp_line
			(start 0.120396 0.3048)
			(end 0.120396 0.2794)
			(stroke
				(width 0.1)
				(type default)
			)
			(layer "F.Fab")
		)
		(fp_line
			(start -0.12065 0.3048)
			(end -0.67945 0.3048)
			(stroke
				(width 0.1)
				(type default)
			)
			(layer "F.Fab")
		)
		(fp_line
			(start -0.67945 0.3048)
			(end -0.67945 -0.305054)
			(stroke
				(width 0.1)
				(type default)
			)
			(layer "F.Fab")
		)
		(pad "1" smd circle
			(at -0.40005 0 90)
			(size 0 0)
			(layers "F.Cu" "F.Mask" "F.Paste")
			(net "P3V3_SSD11")
		)
		(pad "2" smd circle
			(at 0.40005 0 90)
			(size 0 0)
			(layers "F.Cu" "F.Mask" "F.Paste")
			(net "SMB_ISO_SSD11_SDA")
		)
	)
	(footprint ""
		(layer "F.Cu")
		(at 115.356386 -84.469986 180)
		(property "Reference" "R1144"
			(at 0 0 180)
			(layer "F.SilkS")
			(hide yes)
			(effects
				(font
					(size 1.27 1.27)
				)
			)
		)
		(property "Value" ""
			(at 0 0 180)
			(layer "F.Fab")
			(effects
				(font
					(size 1.27 1.27)
				)
			)
		)
		(duplicate_pad_numbers_are_jumpers no)
		(fp_line
			(start -0.7874 -0.4064)
			(end 0.7874 -0.4064)
			(stroke
				(width 0.1524)
				(type default)
			)
			(layer "F.SilkS")
		)
		(fp_line
			(start 0.67945 0.3048)
			(end 0.120396 0.3048)
			(stroke
				(width 0.1)
				(type default)
			)
			(layer "F.Fab")
		)
		(fp_line
			(start 0.67945 -0.3048)
			(end 0.67945 0.3048)
			(stroke
				(width 0.1)
				(type default)
			)
			(layer "F.Fab")
		)
		(fp_line
			(start 0.12065 -0.2794)
			(end 0.12065 -0.3048)
			(stroke
				(width 0.1)
				(type default)
			)
			(layer "F.Fab")
		)
		(fp_line
			(start 0.12065 -0.3048)
			(end 0.67945 -0.3048)
			(stroke
				(width 0.1)
				(type default)
			)
			(layer "F.Fab")
		)
		(fp_line
			(start 0.120396 0.3048)
			(end 0.120396 0.2794)
			(stroke
				(width 0.1)
				(type default)
			)
			(layer "F.Fab")
		)
		(fp_line
			(start 0.120396 0.2794)
			(end -0.12065 0.2794)
			(stroke
				(width 0.1)
				(type default)
			)
			(layer "F.Fab")
		)
		(fp_line
			(start -0.12065 0.3048)
			(end -0.67945 0.3048)
			(stroke
				(width 0.1)
				(type default)
			)
			(layer "F.Fab")
		)
		(fp_line
			(start -0.12065 0.2794)
			(end -0.12065 0.3048)
			(stroke
				(width 0.1)
				(type default)
			)
			(layer "F.Fab")
		)
		(fp_line
			(start -0.12065 -0.2794)
			(end 0.12065 -0.2794)
			(stroke
				(width 0.1)
				(type default)
			)
			(layer "F.Fab")
		)
		(fp_line
			(start -0.12065 -0.305054)
			(end -0.12065 -0.2794)
			(stroke
				(width 0.1)
				(type default)
			)
			(layer "F.Fab")
		)
		(fp_line
			(start -0.67945 0.3048)
			(end -0.67945 -0.305054)
			(stroke
				(width 0.1)
				(type default)
			)
			(layer "F.Fab")
		)
		(fp_line
			(start -0.67945 -0.305054)
			(end -0.12065 -0.305054)
			(stroke
				(width 0.1)
				(type default)
			)
			(layer "F.Fab")
		)
		(pad "1" smd circle
			(at -0.40005 0 180)
			(size 0 0)
			(layers "F.Cu" "F.Mask" "F.Paste")
			(net "CLK_100M_DB800ZL_SSD4_R_DP")
		)
		(pad "2" smd circle
			(at 0.40005 0 180)
			(size 0 0)
			(layers "F.Cu" "F.Mask" "F.Paste")
			(net "CLK_100M_DB800ZL_SSD4_DP")
		)
	)
	(footprint ""
		(layer "F.Cu")
		(at 118.956328 -32.848042 -90)
		(property "Reference" "R6054"
			(at 0 0 270)
			(layer "F.SilkS")
			(hide yes)
			(effects
				(font
					(size 1.27 1.27)
				)
			)
		)
		(property "Value" ""
			(at 0 0 270)
			(layer "F.Fab")
			(effects
				(font
					(size 1.27 1.27)
				)
			)
		)
		(duplicate_pad_numbers_are_jumpers no)
		(fp_line
			(start -0.7874 0.4064)
			(end -0.7874 -0.4064)
			(stroke
				(width 0.1524)
				(type default)
			)
			(layer "F.SilkS")
		)
		(fp_line
			(start 0.7874 0.4064)
			(end -0.7874 0.4064)
			(stroke
				(width 0.1524)
				(type default)
			)
			(layer "F.SilkS")
		)
		(fp_line
			(start -0.7874 -0.4064)
			(end 0.7874 -0.4064)
			(stroke
				(width 0.1524)
				(type default)
			)
			(layer "F.SilkS")
		)
		(fp_line
			(start 0.7874 -0.4064)
			(end 0.7874 0.4064)
			(stroke
				(width 0.1524)
				(type default)
			)
			(layer "F.SilkS")
		)
		(fp_line
			(start -0.67945 0.3048)
			(end -0.67945 -0.305054)
			(stroke
				(width 0.1)
				(type default)
			)
			(layer "F.Fab")
		)
		(fp_line
			(start -0.12065 0.3048)
			(end -0.67945 0.3048)
			(stroke
				(width 0.1)
				(type default)
			)
			(layer "F.Fab")
		)
		(fp_line
			(start 0.120396 0.3048)
			(end 0.120396 0.2794)
			(stroke
				(width 0.1)
				(type default)
			)
			(layer "F.Fab")
		)
		(fp_line
			(start 0.67945 0.3048)
			(end 0.120396 0.3048)
			(stroke
				(width 0.1)
				(type default)
			)
			(layer "F.Fab")
		)
		(fp_line
			(start -0.12065 0.2794)
			(end -0.12065 0.3048)
			(stroke
				(width 0.1)
				(type default)
			)
			(layer "F.Fab")
		)
		(fp_line
			(start 0.120396 0.2794)
			(end -0.12065 0.2794)
			(stroke
				(width 0.1)
				(type default)
			)
			(layer "F.Fab")
		)
		(fp_line
			(start -0.12065 -0.2794)
			(end 0.12065 -0.2794)
			(stroke
				(width 0.1)
				(type default)
			)
			(layer "F.Fab")
		)
		(fp_line
			(start 0.12065 -0.2794)
			(end 0.12065 -0.3048)
			(stroke
				(width 0.1)
				(type default)
			)
			(layer "F.Fab")
		)
		(fp_line
			(start 0.12065 -0.3048)
			(end 0.67945 -0.3048)
			(stroke
				(width 0.1)
				(type default)
			)
			(layer "F.Fab")
		)
		(fp_line
			(start 0.67945 -0.3048)
			(end 0.67945 0.3048)
			(stroke
				(width 0.1)
				(type default)
			)
			(layer "F.Fab")
		)
		(fp_line
			(start -0.67945 -0.305054)
			(end -0.12065 -0.305054)
			(stroke
				(width 0.1)
				(type default)
			)
			(layer "F.Fab")
		)
		(fp_line
			(start -0.12065 -0.305054)
			(end -0.12065 -0.2794)
			(stroke
				(width 0.1)
				(type default)
			)
			(layer "F.Fab")
		)
		(pad "1" smd circle
			(at -0.40005 0 270)
			(size 0 0)
			(layers "F.Cu" "F.Mask" "F.Paste")
			(net "SSD4_AUX_P3V3_EN_R")
		)
		(pad "2" smd circle
			(at 0.40005 0 270)
			(size 0 0)
			(layers "F.Cu" "F.Mask" "F.Paste")
			(net "P3V3_SSD4_CO_EN")
		)
	)
	(footprint ""
		(layer "F.Cu")
		(at 231.844596 -279.567386 180)
		(property "Reference" "R787"
			(at 0 0 180)
			(layer "F.SilkS")
			(hide yes)
			(effects
				(font
					(size 1.27 1.27)
				)
			)
		)
		(property "Value" ""
			(at 0 0 180)
			(layer "F.Fab")
			(effects
				(font
					(size 1.27 1.27)
				)
			)
		)
		(duplicate_pad_numbers_are_jumpers no)
		(fp_line
			(start 0.7874 0.4064)
			(end -0.7874 0.4064)
			(stroke
				(width 0.1524)
				(type default)
			)
			(layer "F.SilkS")
		)
		(fp_line
			(start 0.7874 -0.4064)
			(end 0.7874 0.4064)
			(stroke
				(width 0.1524)
				(type default)
			)
			(layer "F.SilkS")
		)
		(fp_line
			(start -0.7874 0.4064)
			(end -0.7874 -0.4064)
			(stroke
				(width 0.1524)
				(type default)
			)
			(layer "F.SilkS")
		)
		(fp_line
			(start -0.7874 -0.4064)
			(end 0.7874 -0.4064)
			(stroke
				(width 0.1524)
				(type default)
			)
			(layer "F.SilkS")
		)
		(fp_line
			(start 0.67945 0.3048)
			(end 0.120396 0.3048)
			(stroke
				(width 0.1)
				(type default)
			)
			(layer "F.Fab")
		)
		(fp_line
			(start 0.67945 -0.3048)
			(end 0.67945 0.3048)
			(stroke
				(width 0.1)
				(type default)
			)
			(layer "F.Fab")
		)
		(fp_line
			(start 0.12065 -0.2794)
			(end 0.12065 -0.3048)
			(stroke
				(width 0.1)
				(type default)
			)
			(layer "F.Fab")
		)
		(fp_line
			(start 0.12065 -0.3048)
			(end 0.67945 -0.3048)
			(stroke
				(width 0.1)
				(type default)
			)
			(layer "F.Fab")
		)
		(fp_line
			(start 0.120396 0.3048)
			(end 0.120396 0.2794)
			(stroke
				(width 0.1)
				(type default)
			)
			(layer "F.Fab")
		)
		(fp_line
			(start 0.120396 0.2794)
			(end -0.12065 0.2794)
			(stroke
				(width 0.1)
				(type default)
			)
			(layer "F.Fab")
		)
		(fp_line
			(start -0.12065 0.3048)
			(end -0.67945 0.3048)
			(stroke
				(width 0.1)
				(type default)
			)
			(layer "F.Fab")
		)
		(fp_line
			(start -0.12065 0.2794)
			(end -0.12065 0.3048)
			(stroke
				(width 0.1)
				(type default)
			)
			(layer "F.Fab")
		)
		(fp_line
			(start -0.12065 -0.2794)
			(end 0.12065 -0.2794)
			(stroke
				(width 0.1)
				(type default)
			)
			(layer "F.Fab")
		)
		(fp_line
			(start -0.12065 -0.305054)
			(end -0.12065 -0.2794)
			(stroke
				(width 0.1)
				(type default)
			)
			(layer "F.Fab")
		)
		(fp_line
			(start -0.67945 0.3048)
			(end -0.67945 -0.305054)
			(stroke
				(width 0.1)
				(type default)
			)
			(layer "F.Fab")
		)
		(fp_line
			(start -0.67945 -0.305054)
			(end -0.12065 -0.305054)
			(stroke
				(width 0.1)
				(type default)
			)
			(layer "F.Fab")
		)
		(pad "1" smd circle
			(at -0.40005 0 180)
			(size 0 0)
			(layers "F.Cu" "F.Mask" "F.Paste")
			(net "SMB_BIC_I2C6_MUX_PEX_ADC_R_SDA")
		)
		(pad "2" smd circle
			(at 0.40005 0 180)
			(size 0 0)
			(layers "F.Cu" "F.Mask" "F.Paste")
			(net "SMB_PEX1_P1V25_ADC_SDA")
		)
	)
	(footprint ""
		(layer "F.Cu")
		(at 113.716816 -137.43686 -90)
		(property "Reference" "PC38"
			(at 0 0 270)
			(layer "F.SilkS")
			(hide yes)
			(effects
				(font
					(size 1.27 1.27)
				)
			)
		)
		(property "Value" ""
			(at 0 0 270)
			(layer "F.Fab")
			(effects
				(font
					(size 1.27 1.27)
				)
			)
		)
		(duplicate_pad_numbers_are_jumpers no)
		(fp_line
			(start -1.988058 2.750058)
			(end 2.750058 2.750058)
			(stroke
				(width 0.1524)
				(type default)
			)
			(layer "F.SilkS")
		)
		(fp_line
			(start 2.750058 2.750058)
			(end 2.750058 0.9398)
			(stroke
				(width 0.1524)
				(type default)
			)
			(layer "F.SilkS")
		)
		(fp_line
			(start -2.750058 1.988058)
			(end -1.988058 2.750058)
			(stroke
				(width 0.1524)
				(type default)
			)
			(layer "F.SilkS")
		)
		(fp_line
			(start -2.750058 0.9398)
			(end -2.750058 1.988058)
			(stroke
				(width 0.1524)
				(type default)
			)
			(layer "F.SilkS")
		)
		(fp_line
			(start 2.750058 -0.9398)
			(end 2.750058 -2.750058)
			(stroke
				(width 0.1524)
				(type default)
			)
			(layer "F.SilkS")
		)
		(fp_line
			(start -2.750058 -1.988058)
			(end -2.750058 -0.9398)
			(stroke
				(width 0.1524)
				(type default)
			)
			(layer "F.SilkS")
		)
		(fp_line
			(start -1.988058 -2.750058)
			(end -2.750058 -1.988058)
			(stroke
				(width 0.1524)
				(type default)
			)
			(layer "F.SilkS")
		)
		(fp_line
			(start 2.750058 -2.750058)
			(end -1.988058 -2.750058)
			(stroke
				(width 0.1524)
				(type default)
			)
			(layer "F.SilkS")
		)
		(fp_line
			(start -2.750058 2.750058)
			(end 2.750058 2.750058)
			(stroke
				(width 0.1)
				(type default)
			)
			(layer "F.Fab")
		)
		(fp_line
			(start 2.750058 2.750058)
			(end 2.750058 -2.750058)
			(stroke
				(width 0.1)
				(type default)
			)
			(layer "F.Fab")
		)
		(fp_line
			(start -2.750058 -2.750058)
			(end -2.750058 2.750058)
			(stroke
				(width 0.1)
				(type default)
			)
			(layer "F.Fab")
		)
		(fp_line
			(start 2.750058 -2.750058)
			(end -2.750058 -2.750058)
			(stroke
				(width 0.1)
				(type default)
			)
			(layer "F.Fab")
		)
		(pad "1" smd rect
			(at -2.199894 0)
			(size 1.6002 3.0226)
			(layers "F.Cu" "F.Mask" "F.Paste")
			(net "P3V3_AUX")
		)
		(pad "2" smd rect
			(at 2.199894 0)
			(size 1.6002 3.0226)
			(layers "F.Cu" "F.Mask" "F.Paste")
			(net "GND")
		)
	)
	(footprint ""
		(layer "F.Cu")
		(at 148.511514 -299.645832 -90)
		(property "Reference" "R4569"
			(at 0 0 270)
			(layer "F.SilkS")
			(hide yes)
			(effects
				(font
					(size 1.27 1.27)
				)
			)
		)
		(property "Value" ""
			(at 0 0 270)
			(layer "F.Fab")
			(effects
				(font
					(size 1.27 1.27)
				)
			)
		)
		(duplicate_pad_numbers_are_jumpers no)
		(fp_line
			(start -0.7874 0.4064)
			(end -0.7874 -0.4064)
			(stroke
				(width 0.1524)
				(type default)
			)
			(layer "F.SilkS")
		)
		(fp_line
			(start 0.7874 0.4064)
			(end -0.7874 0.4064)
			(stroke
				(width 0.1524)
				(type default)
			)
			(layer "F.SilkS")
		)
		(fp_line
			(start -0.7874 -0.4064)
			(end 0.7874 -0.4064)
			(stroke
				(width 0.1524)
				(type default)
			)
			(layer "F.SilkS")
		)
		(fp_line
			(start 0.7874 -0.4064)
			(end 0.7874 0.4064)
			(stroke
				(width 0.1524)
				(type default)
			)
			(layer "F.SilkS")
		)
		(fp_line
			(start -0.67945 0.3048)
			(end -0.67945 -0.305054)
			(stroke
				(width 0.1)
				(type default)
			)
			(layer "F.Fab")
		)
		(fp_line
			(start -0.12065 0.3048)
			(end -0.67945 0.3048)
			(stroke
				(width 0.1)
				(type default)
			)
			(layer "F.Fab")
		)
		(fp_line
			(start 0.120396 0.3048)
			(end 0.120396 0.2794)
			(stroke
				(width 0.1)
				(type default)
			)
			(layer "F.Fab")
		)
		(fp_line
			(start 0.67945 0.3048)
			(end 0.120396 0.3048)
			(stroke
				(width 0.1)
				(type default)
			)
			(layer "F.Fab")
		)
		(fp_line
			(start -0.12065 0.2794)
			(end -0.12065 0.3048)
			(stroke
				(width 0.1)
				(type default)
			)
			(layer "F.Fab")
		)
		(fp_line
			(start 0.120396 0.2794)
			(end -0.12065 0.2794)
			(stroke
				(width 0.1)
				(type default)
			)
			(layer "F.Fab")
		)
		(fp_line
			(start -0.12065 -0.2794)
			(end 0.12065 -0.2794)
			(stroke
				(width 0.1)
				(type default)
			)
			(layer "F.Fab")
		)
		(fp_line
			(start 0.12065 -0.2794)
			(end 0.12065 -0.3048)
			(stroke
				(width 0.1)
				(type default)
			)
			(layer "F.Fab")
		)
		(fp_line
			(start 0.12065 -0.3048)
			(end 0.67945 -0.3048)
			(stroke
				(width 0.1)
				(type default)
			)
			(layer "F.Fab")
		)
		(fp_line
			(start 0.67945 -0.3048)
			(end 0.67945 0.3048)
			(stroke
				(width 0.1)
				(type default)
			)
			(layer "F.Fab")
		)
		(fp_line
			(start -0.67945 -0.305054)
			(end -0.12065 -0.305054)
			(stroke
				(width 0.1)
				(type default)
			)
			(layer "F.Fab")
		)
		(fp_line
			(start -0.12065 -0.305054)
			(end -0.12065 -0.2794)
			(stroke
				(width 0.1)
				(type default)
			)
			(layer "F.Fab")
		)
		(pad "1" smd circle
			(at -0.40005 0 270)
			(size 0 0)
			(layers "F.Cu" "F.Mask" "F.Paste")
			(net "PCEPLL1_VDDA18_PEX1")
		)
		(pad "2" smd circle
			(at 0.40005 0 270)
			(size 0 0)
			(layers "F.Cu" "F.Mask" "F.Paste")
			(net "PCEPLL1_VDDA18_PEX1_R")
		)
	)
	(footprint ""
		(layer "F.Cu")
		(at 30.081982 -296.191432 180)
		(property "Reference" "C3030"
			(at 0 0 180)
			(layer "F.SilkS")
			(hide yes)
			(effects
				(font
					(size 1.27 1.27)
				)
			)
		)
		(property "Value" ""
			(at 0 0 180)
			(layer "F.Fab")
			(effects
				(font
					(size 1.27 1.27)
				)
			)
		)
		(duplicate_pad_numbers_are_jumpers no)
		(fp_line
			(start 1.2954 0.5842)
			(end -1.2954 0.5842)
			(stroke
				(width 0.1524)
				(type default)
			)
			(layer "F.SilkS")
		)
		(fp_line
			(start 1.2954 -0.5842)
			(end 1.2954 0.5842)
			(stroke
				(width 0.1524)
				(type default)
			)
			(layer "F.SilkS")
		)
		(fp_line
			(start -1.2954 0.5842)
			(end -1.2954 -0.5842)
			(stroke
				(width 0.1524)
				(type default)
			)
			(layer "F.SilkS")
		)
		(fp_line
			(start -1.2954 -0.5842)
			(end 1.2954 -0.5842)
			(stroke
				(width 0.1524)
				(type default)
			)
			(layer "F.SilkS")
		)
		(fp_line
			(start 1.1938 0.4064)
			(end 0.8636 0.4064)
			(stroke
				(width 0.1)
				(type default)
			)
			(layer "F.Fab")
		)
		(fp_line
			(start 1.1938 -0.4064)
			(end 1.1938 0.4064)
			(stroke
				(width 0.1)
				(type default)
			)
			(layer "F.Fab")
		)
		(fp_line
			(start 0.8636 0.4572)
			(end -0.8636 0.4572)
			(stroke
				(width 0.1)
				(type default)
			)
			(layer "F.Fab")
		)
		(fp_line
			(start 0.8636 0.4064)
			(end 0.8636 0.4572)
			(stroke
				(width 0.1)
				(type default)
			)
			(layer "F.Fab")
		)
		(fp_line
			(start 0.8636 -0.4064)
			(end 1.1938 -0.4064)
			(stroke
				(width 0.1)
				(type default)
			)
			(layer "F.Fab")
		)
		(fp_line
			(start 0.8636 -0.4572)
			(end 0.8636 -0.4064)
			(stroke
				(width 0.1)
				(type default)
			)
			(layer "F.Fab")
		)
		(fp_line
			(start -0.8636 0.4572)
			(end -0.8636 0.4064)
			(stroke
				(width 0.1)
				(type default)
			)
			(layer "F.Fab")
		)
		(fp_line
			(start -0.8636 0.4064)
			(end -1.1938 0.4064)
			(stroke
				(width 0.1)
				(type default)
			)
			(layer "F.Fab")
		)
		(fp_line
			(start -0.8636 -0.4064)
			(end -0.8636 -0.4572)
			(stroke
				(width 0.1)
				(type default)
			)
			(layer "F.Fab")
		)
		(fp_line
			(start -0.8636 -0.4572)
			(end 0.8636 -0.4572)
			(stroke
				(width 0.1)
				(type default)
			)
			(layer "F.Fab")
		)
		(fp_line
			(start -1.1938 0.4064)
			(end -1.1938 -0.4064)
			(stroke
				(width 0.1)
				(type default)
			)
			(layer "F.Fab")
		)
		(fp_line
			(start -1.1938 -0.4064)
			(end -0.8636 -0.4064)
			(stroke
				(width 0.1)
				(type default)
			)
			(layer "F.Fab")
		)
		(pad "1" smd rect
			(at -0.7366 0 90)
			(size 0.7112 0.8128)
			(layers "F.Cu" "F.Mask" "F.Paste")
			(net "PCEPLL0_VDDA18_PEX0_R")
		)
		(pad "2" smd rect
			(at 0.7366 0 90)
			(size 0.7112 0.8128)
			(layers "F.Cu" "F.Mask" "F.Paste")
			(net "GND")
		)
	)
	(footprint ""
		(layer "F.Cu")
		(at 240.316258 -219.674948)
		(property "Reference" "R4852"
			(at 0 0 0)
			(layer "F.SilkS")
			(hide yes)
			(effects
				(font
					(size 1.27 1.27)
				)
			)
		)
		(property "Value" ""
			(at 0 0 0)
			(layer "F.Fab")
			(effects
				(font
					(size 1.27 1.27)
				)
			)
		)
		(duplicate_pad_numbers_are_jumpers no)
		(fp_line
			(start -0.7874 -0.4064)
			(end 0.7874 -0.4064)
			(stroke
				(width 0.1524)
				(type default)
			)
			(layer "F.SilkS")
		)
		(fp_line
			(start -0.7874 0.4064)
			(end -0.7874 -0.4064)
			(stroke
				(width 0.1524)
				(type default)
			)
			(layer "F.SilkS")
		)
		(fp_line
			(start 0.7874 -0.4064)
			(end 0.7874 0.4064)
			(stroke
				(width 0.1524)
				(type default)
			)
			(layer "F.SilkS")
		)
		(fp_line
			(start 0.7874 0.4064)
			(end -0.7874 0.4064)
			(stroke
				(width 0.1524)
				(type default)
			)
			(layer "F.SilkS")
		)
		(fp_line
			(start -0.67945 -0.305054)
			(end -0.12065 -0.305054)
			(stroke
				(width 0.1)
				(type default)
			)
			(layer "F.Fab")
		)
		(fp_line
			(start -0.67945 0.3048)
			(end -0.67945 -0.305054)
			(stroke
				(width 0.1)
				(type default)
			)
			(layer "F.Fab")
		)
		(fp_line
			(start -0.12065 -0.305054)
			(end -0.12065 -0.2794)
			(stroke
				(width 0.1)
				(type default)
			)
			(layer "F.Fab")
		)
		(fp_line
			(start -0.12065 -0.2794)
			(end 0.12065 -0.2794)
			(stroke
				(width 0.1)
				(type default)
			)
			(layer "F.Fab")
		)
		(fp_line
			(start -0.12065 0.2794)
			(end -0.12065 0.3048)
			(stroke
				(width 0.1)
				(type default)
			)
			(layer "F.Fab")
		)
		(fp_line
			(start -0.12065 0.3048)
			(end -0.67945 0.3048)
			(stroke
				(width 0.1)
				(type default)
			)
			(layer "F.Fab")
		)
		(fp_line
			(start 0.120396 0.2794)
			(end -0.12065 0.2794)
			(stroke
				(width 0.1)
				(type default)
			)
			(layer "F.Fab")
		)
		(fp_line
			(start 0.120396 0.3048)
			(end 0.120396 0.2794)
			(stroke
				(width 0.1)
				(type default)
			)
			(layer "F.Fab")
		)
		(fp_line
			(start 0.12065 -0.3048)
			(end 0.67945 -0.3048)
			(stroke
				(width 0.1)
				(type default)
			)
			(layer "F.Fab")
		)
		(fp_line
			(start 0.12065 -0.2794)
			(end 0.12065 -0.3048)
			(stroke
				(width 0.1)
				(type default)
			)
			(layer "F.Fab")
		)
		(fp_line
			(start 0.67945 -0.3048)
			(end 0.67945 0.3048)
			(stroke
				(width 0.1)
				(type default)
			)
			(layer "F.Fab")
		)
		(fp_line
			(start 0.67945 0.3048)
			(end 0.120396 0.3048)
			(stroke
				(width 0.1)
				(type default)
			)
			(layer "F.Fab")
		)
		(pad "1" smd circle
			(at -0.40005 0)
			(size 0 0)
			(layers "F.Cu" "F.Mask" "F.Paste")
			(net "PD_BIC_ADCREXT0")
		)
		(pad "2" smd circle
			(at 0.40005 0)
			(size 0 0)
			(layers "F.Cu" "F.Mask" "F.Paste")
			(net "GND")
		)
	)
	(footprint ""
		(layer "F.Cu")
		(at 318.31026 -63.652146 180)
		(property "Reference" "R6007"
			(at 0 0 180)
			(layer "F.SilkS")
			(hide yes)
			(effects
				(font
					(size 1.27 1.27)
				)
			)
		)
		(property "Value" ""
			(at 0 0 180)
			(layer "F.Fab")
			(effects
				(font
					(size 1.27 1.27)
				)
			)
		)
		(duplicate_pad_numbers_are_jumpers no)
		(fp_line
			(start 0.7874 0.4064)
			(end -0.7874 0.4064)
			(stroke
				(width 0.1524)
				(type default)
			)
			(layer "F.SilkS")
		)
		(fp_line
			(start 0.7874 -0.4064)
			(end 0.7874 0.4064)
			(stroke
				(width 0.1524)
				(type default)
			)
			(layer "F.SilkS")
		)
		(fp_line
			(start -0.7874 0.4064)
			(end -0.7874 -0.4064)
			(stroke
				(width 0.1524)
				(type default)
			)
			(layer "F.SilkS")
		)
		(fp_line
			(start -0.7874 -0.4064)
			(end 0.7874 -0.4064)
			(stroke
				(width 0.1524)
				(type default)
			)
			(layer "F.SilkS")
		)
		(fp_line
			(start 0.67945 0.3048)
			(end 0.120396 0.3048)
			(stroke
				(width 0.1)
				(type default)
			)
			(layer "F.Fab")
		)
		(fp_line
			(start 0.67945 -0.3048)
			(end 0.67945 0.3048)
			(stroke
				(width 0.1)
				(type default)
			)
			(layer "F.Fab")
		)
		(fp_line
			(start 0.12065 -0.2794)
			(end 0.12065 -0.3048)
			(stroke
				(width 0.1)
				(type default)
			)
			(layer "F.Fab")
		)
		(fp_line
			(start 0.12065 -0.3048)
			(end 0.67945 -0.3048)
			(stroke
				(width 0.1)
				(type default)
			)
			(layer "F.Fab")
		)
		(fp_line
			(start 0.120396 0.3048)
			(end 0.120396 0.2794)
			(stroke
				(width 0.1)
				(type default)
			)
			(layer "F.Fab")
		)
		(fp_line
			(start 0.120396 0.2794)
			(end -0.12065 0.2794)
			(stroke
				(width 0.1)
				(type default)
			)
			(layer "F.Fab")
		)
		(fp_line
			(start -0.12065 0.3048)
			(end -0.67945 0.3048)
			(stroke
				(width 0.1)
				(type default)
			)
			(layer "F.Fab")
		)
		(fp_line
			(start -0.12065 0.2794)
			(end -0.12065 0.3048)
			(stroke
				(width 0.1)
				(type default)
			)
			(layer "F.Fab")
		)
		(fp_line
			(start -0.12065 -0.2794)
			(end 0.12065 -0.2794)
			(stroke
				(width 0.1)
				(type default)
			)
			(layer "F.Fab")
		)
		(fp_line
			(start -0.12065 -0.305054)
			(end -0.12065 -0.2794)
			(stroke
				(width 0.1)
				(type default)
			)
			(layer "F.Fab")
		)
		(fp_line
			(start -0.67945 0.3048)
			(end -0.67945 -0.305054)
			(stroke
				(width 0.1)
				(type default)
			)
			(layer "F.Fab")
		)
		(fp_line
			(start -0.67945 -0.305054)
			(end -0.12065 -0.305054)
			(stroke
				(width 0.1)
				(type default)
			)
			(layer "F.Fab")
		)
		(pad "1" smd circle
			(at -0.40005 0 180)
			(size 0 0)
			(layers "F.Cu" "F.Mask" "F.Paste")
			(net "P5V_AUX")
		)
		(pad "2" smd circle
			(at 0.40005 0 180)
			(size 0 0)
			(layers "F.Cu" "F.Mask" "F.Paste")
			(net "P12V_SSD11_PG_G2")
		)
	)
	(footprint ""
		(layer "F.Cu")
		(at 240.320576 -26.666444 -90)
		(property "Reference" "R4069"
			(at 0 0 270)
			(layer "F.SilkS")
			(hide yes)
			(effects
				(font
					(size 1.27 1.27)
				)
			)
		)
		(property "Value" ""
			(at 0 0 270)
			(layer "F.Fab")
			(effects
				(font
					(size 1.27 1.27)
				)
			)
		)
		(duplicate_pad_numbers_are_jumpers no)
		(fp_line
			(start -0.7874 0.4064)
			(end -0.7874 -0.4064)
			(stroke
				(width 0.1524)
				(type default)
			)
			(layer "F.SilkS")
		)
		(fp_line
			(start 0.7874 0.4064)
			(end -0.7874 0.4064)
			(stroke
				(width 0.1524)
				(type default)
			)
			(layer "F.SilkS")
		)
		(fp_line
			(start -0.7874 -0.4064)
			(end 0.7874 -0.4064)
			(stroke
				(width 0.1524)
				(type default)
			)
			(layer "F.SilkS")
		)
		(fp_line
			(start 0.7874 -0.4064)
			(end 0.7874 0.4064)
			(stroke
				(width 0.1524)
				(type default)
			)
			(layer "F.SilkS")
		)
		(fp_line
			(start -0.67945 0.3048)
			(end -0.67945 -0.305054)
			(stroke
				(width 0.1)
				(type default)
			)
			(layer "F.Fab")
		)
		(fp_line
			(start -0.12065 0.3048)
			(end -0.67945 0.3048)
			(stroke
				(width 0.1)
				(type default)
			)
			(layer "F.Fab")
		)
		(fp_line
			(start 0.120396 0.3048)
			(end 0.120396 0.2794)
			(stroke
				(width 0.1)
				(type default)
			)
			(layer "F.Fab")
		)
		(fp_line
			(start 0.67945 0.3048)
			(end 0.120396 0.3048)
			(stroke
				(width 0.1)
				(type default)
			)
			(layer "F.Fab")
		)
		(fp_line
			(start -0.12065 0.2794)
			(end -0.12065 0.3048)
			(stroke
				(width 0.1)
				(type default)
			)
			(layer "F.Fab")
		)
		(fp_line
			(start 0.120396 0.2794)
			(end -0.12065 0.2794)
			(stroke
				(width 0.1)
				(type default)
			)
			(layer "F.Fab")
		)
		(fp_line
			(start -0.12065 -0.2794)
			(end 0.12065 -0.2794)
			(stroke
				(width 0.1)
				(type default)
			)
			(layer "F.Fab")
		)
		(fp_line
			(start 0.12065 -0.2794)
			(end 0.12065 -0.3048)
			(stroke
				(width 0.1)
				(type default)
			)
			(layer "F.Fab")
		)
		(fp_line
			(start 0.12065 -0.3048)
			(end 0.67945 -0.3048)
			(stroke
				(width 0.1)
				(type default)
			)
			(layer "F.Fab")
		)
		(fp_line
			(start 0.67945 -0.3048)
			(end 0.67945 0.3048)
			(stroke
				(width 0.1)
				(type default)
			)
			(layer "F.Fab")
		)
		(fp_line
			(start -0.67945 -0.305054)
			(end -0.12065 -0.305054)
			(stroke
				(width 0.1)
				(type default)
			)
			(layer "F.Fab")
		)
		(fp_line
			(start -0.12065 -0.305054)
			(end -0.12065 -0.2794)
			(stroke
				(width 0.1)
				(type default)
			)
			(layer "F.Fab")
		)
		(pad "1" smd circle
			(at -0.40005 0 270)
			(size 0 0)
			(layers "F.Cu" "F.Mask" "F.Paste")
			(net "PRSNT_SSD8_R_N")
		)
		(pad "2" smd circle
			(at 0.40005 0 270)
			(size 0 0)
			(layers "F.Cu" "F.Mask" "F.Paste")
			(net "PRSNT_SSD8_N")
		)
	)
	(footprint ""
		(layer "F.Cu")
		(at 216.945972 -46.4439 180)
		(property "Reference" "U62"
			(at 0.080772 -2.45237 0)
			(unlocked yes)
			(layer "F.SilkS")
			(effects
				(font
					(size 0.7874 0.5842)
					(thickness 0.1524)
				)
			)
		)
		(property "Value" ""
			(at 0 0 180)
			(layer "F.Fab")
			(effects
				(font
					(size 1.27 1.27)
				)
			)
		)
		(duplicate_pad_numbers_are_jumpers no)
		(fp_line
			(start 1.500124 1.500124)
			(end 1.004062 1.500124)
			(stroke
				(width 0.1524)
				(type default)
			)
			(layer "F.SilkS")
		)
		(fp_line
			(start 1.500124 1.004062)
			(end 1.500124 1.500124)
			(stroke
				(width 0.1524)
				(type default)
			)
			(layer "F.SilkS")
		)
		(fp_line
			(start 1.500124 -1.500124)
			(end 1.500124 -1.004062)
			(stroke
				(width 0.1524)
				(type default)
			)
			(layer "F.SilkS")
		)
		(fp_line
			(start 1.004062 -1.500124)
			(end 1.500124 -1.500124)
			(stroke
				(width 0.1524)
				(type default)
			)
			(layer "F.SilkS")
		)
		(fp_line
			(start -1.004062 1.500124)
			(end -1.500124 1.500124)
			(stroke
				(width 0.1524)
				(type default)
			)
			(layer "F.SilkS")
		)
		(fp_line
			(start -1.500124 1.500124)
			(end -1.500124 1.004062)
			(stroke
				(width 0.1524)
				(type default)
			)
			(layer "F.SilkS")
		)
		(fp_line
			(start -1.500124 -1.004062)
			(end -1.500124 -1.500124)
			(stroke
				(width 0.1524)
				(type default)
			)
			(layer "F.SilkS")
		)
		(fp_line
			(start -1.500124 -1.500124)
			(end -1.004062 -1.500124)
			(stroke
				(width 0.1524)
				(type default)
			)
			(layer "F.SilkS")
		)
		(fp_poly
			(pts
				(xy -1.697482 -2.477516) (xy -2.416048 -1.759204) (xy -1.338326 -1.400048)
			)
			(stroke
				(width 0)
				(type default)
			)
			(fill yes)
			(layer "F.SilkS")
		)
		(fp_line
			(start 1.500124 1.500124)
			(end -1.500124 1.500124)
			(stroke
				(width 0.1)
				(type default)
			)
			(layer "F.Fab")
		)
		(fp_line
			(start 1.500124 -1.500124)
			(end 1.500124 1.500124)
			(stroke
				(width 0.1)
				(type default)
			)
			(layer "F.Fab")
		)
		(fp_line
			(start -1.500124 1.500124)
			(end -1.500124 -1.500124)
			(stroke
				(width 0.1)
				(type default)
			)
			(layer "F.Fab")
		)
		(fp_line
			(start -1.500124 -1.500124)
			(end 1.500124 -1.500124)
			(stroke
				(width 0.1)
				(type default)
			)
			(layer "F.Fab")
		)
		(fp_poly
			(pts
				(xy -2.847848 -1.258062) (xy -2.847848 -0.242062) (xy -1.831848 -0.750062)
			)
			(stroke
				(width 0)
				(type default)
			)
			(fill yes)
			(layer "F.Fab")
		)
		(pad "1" smd rect
			(at -1.400048 -0.750062 90)
			(size 0.2286 0.6096)
			(layers "F.Cu" "F.Mask" "F.Paste")
			(net "SSD7_ADC_A1")
		)
		(pad "2" smd rect
			(at -1.400048 -0.249936 90)
			(size 0.2286 0.6096)
			(layers "F.Cu" "F.Mask" "F.Paste")
			(net "SSD7_ADC_A0")
		)
		(pad "3" smd rect
			(at -1.400048 0.249936 90)
			(size 0.2286 0.6096)
			(layers "F.Cu" "F.Mask" "F.Paste")
			(net "SSD7_ADC_ALERT_N")
		)
		(pad "4" smd rect
			(at -1.400048 0.750062 90)
			(size 0.2286 0.6096)
			(layers "F.Cu" "F.Mask" "F.Paste")
			(net "SMB_SSD7_ADC_SDA")
		)
		(pad "5" smd rect
			(at -0.750062 1.400048 180)
			(size 0.2286 0.6096)
			(layers "F.Cu" "F.Mask" "F.Paste")
			(net "SMB_SSD7_ADC_SCL")
		)
		(pad "6" smd rect
			(at -0.249936 1.400048 180)
			(size 0.2286 0.6096)
			(layers "F.Cu" "F.Mask" "F.Paste")
			(net "Net_8720")
		)
		(pad "7" smd rect
			(at 0.249936 1.400048 180)
			(size 0.2286 0.6096)
			(layers "F.Cu" "F.Mask" "F.Paste")
			(net "Net_8719")
		)
		(pad "8" smd rect
			(at 0.750062 1.400048 180)
			(size 0.2286 0.6096)
			(layers "F.Cu" "F.Mask" "F.Paste")
			(net "Net_8718")
		)
		(pad "9" smd rect
			(at 1.400048 0.750062 90)
			(size 0.2286 0.6096)
			(layers "F.Cu" "F.Mask" "F.Paste")
			(net "P3V3_AUX")
		)
		(pad "10" smd rect
			(at 1.400048 0.249936 90)
			(size 0.2286 0.6096)
			(layers "F.Cu" "F.Mask" "F.Paste")
			(net "GND")
		)
		(pad "11" smd rect
			(at 1.400048 -0.249936 90)
			(size 0.2286 0.6096)
			(layers "F.Cu" "F.Mask" "F.Paste")
			(net "P12V_SSD7_R")
		)
		(pad "12" smd rect
			(at 1.400048 -0.750062 90)
			(size 0.2286 0.6096)
			(layers "F.Cu" "F.Mask" "F.Paste")
			(net "P12V_SSD7_VIN_N")
		)
		(pad "13" smd rect
			(at 0.750062 -1.400048 180)
			(size 0.2286 0.6096)
			(layers "F.Cu" "F.Mask" "F.Paste")
			(net "P12V_SSD7_VIN_P")
		)
		(pad "14" smd rect
			(at 0.249936 -1.400048 180)
			(size 0.2286 0.6096)
			(layers "F.Cu" "F.Mask" "F.Paste")
			(net "Net_8717")
		)
		(pad "15" smd rect
			(at -0.249936 -1.400048 180)
			(size 0.2286 0.6096)
			(layers "F.Cu" "F.Mask" "F.Paste")
			(net "Net_8716")
		)
		(pad "16" smd rect
			(at -0.750062 -1.400048 180)
			(size 0.2286 0.6096)
			(layers "F.Cu" "F.Mask" "F.Paste")
			(net "Net_8715")
		)
		(pad "TH" smd rect
			(at 0 0 180)
			(size 1.7018 1.7018)
			(layers "F.Cu" "F.Mask" "F.Paste")
			(net "GND")
		)
		(zone
			(layer "F.Cu")
			(hatch none 0.5)
			(connect_pads
				(clearance 0)
			)
			(min_thickness 0.25)
			(keepout
				(tracks not_allowed)
				(vias allowed)
				(pads allowed)
				(copperpour not_allowed)
				(footprints allowed)
			)
			(placement
				(enabled no)
				(sheetname "")
			)
			(fill
				(thermal_gap 0.5)
				(thermal_bridge_width 0.5)
				(island_removal_mode 0)
			)
			(polygon
				(pts
					(xy 217.99042 -46.4185) (xy 217.99042 -45.399452) (xy 215.901524 -45.399452) (xy 215.901524 -47.488348)
					(xy 217.99042 -47.488348) (xy 217.99042 -46.4439) (xy 217.847672 -46.4439) (xy 217.847672 -47.3456)
					(xy 216.044272 -47.3456) (xy 216.044272 -45.5422) (xy 217.847672 -45.5422) (xy 217.847672 -46.4185)
				)
			)
		)
	)
	(footprint ""
		(layer "F.Cu")
		(at 339.718396 -120.53824 180)
		(property "Reference" "R6037"
			(at 0 0 180)
			(layer "F.SilkS")
			(hide yes)
			(effects
				(font
					(size 1.27 1.27)
				)
			)
		)
		(property "Value" ""
			(at 0 0 180)
			(layer "F.Fab")
			(effects
				(font
					(size 1.27 1.27)
				)
			)
		)
		(duplicate_pad_numbers_are_jumpers no)
		(fp_line
			(start 0.7874 0.4064)
			(end -0.7874 0.4064)
			(stroke
				(width 0.1524)
				(type default)
			)
			(layer "F.SilkS")
		)
		(fp_line
			(start 0.7874 -0.4064)
			(end 0.7874 0.4064)
			(stroke
				(width 0.1524)
				(type default)
			)
			(layer "F.SilkS")
		)
		(fp_line
			(start -0.7874 0.4064)
			(end -0.7874 -0.4064)
			(stroke
				(width 0.1524)
				(type default)
			)
			(layer "F.SilkS")
		)
		(fp_line
			(start -0.7874 -0.4064)
			(end 0.7874 -0.4064)
			(stroke
				(width 0.1524)
				(type default)
			)
			(layer "F.SilkS")
		)
		(fp_line
			(start 0.67945 0.3048)
			(end 0.120396 0.3048)
			(stroke
				(width 0.1)
				(type default)
			)
			(layer "F.Fab")
		)
		(fp_line
			(start 0.67945 -0.3048)
			(end 0.67945 0.3048)
			(stroke
				(width 0.1)
				(type default)
			)
			(layer "F.Fab")
		)
		(fp_line
			(start 0.12065 -0.2794)
			(end 0.12065 -0.3048)
			(stroke
				(width 0.1)
				(type default)
			)
			(layer "F.Fab")
		)
		(fp_line
			(start 0.12065 -0.3048)
			(end 0.67945 -0.3048)
			(stroke
				(width 0.1)
				(type default)
			)
			(layer "F.Fab")
		)
		(fp_line
			(start 0.120396 0.3048)
			(end 0.120396 0.2794)
			(stroke
				(width 0.1)
				(type default)
			)
			(layer "F.Fab")
		)
		(fp_line
			(start 0.120396 0.2794)
			(end -0.12065 0.2794)
			(stroke
				(width 0.1)
				(type default)
			)
			(layer "F.Fab")
		)
		(fp_line
			(start -0.12065 0.3048)
			(end -0.67945 0.3048)
			(stroke
				(width 0.1)
				(type default)
			)
			(layer "F.Fab")
		)
		(fp_line
			(start -0.12065 0.2794)
			(end -0.12065 0.3048)
			(stroke
				(width 0.1)
				(type default)
			)
			(layer "F.Fab")
		)
		(fp_line
			(start -0.12065 -0.2794)
			(end 0.12065 -0.2794)
			(stroke
				(width 0.1)
				(type default)
			)
			(layer "F.Fab")
		)
		(fp_line
			(start -0.12065 -0.305054)
			(end -0.12065 -0.2794)
			(stroke
				(width 0.1)
				(type default)
			)
			(layer "F.Fab")
		)
		(fp_line
			(start -0.67945 0.3048)
			(end -0.67945 -0.305054)
			(stroke
				(width 0.1)
				(type default)
			)
			(layer "F.Fab")
		)
		(fp_line
			(start -0.67945 -0.305054)
			(end -0.12065 -0.305054)
			(stroke
				(width 0.1)
				(type default)
			)
			(layer "F.Fab")
		)
		(pad "1" smd circle
			(at -0.40005 0 180)
			(size 0 0)
			(layers "F.Cu" "F.Mask" "F.Paste")
			(net "P5V_AUX")
		)
		(pad "2" smd circle
			(at 0.40005 0 180)
			(size 0 0)
			(layers "F.Cu" "F.Mask" "F.Paste")
			(net "P3V3_NIC5_PG_G2")
		)
	)
	(footprint ""
		(layer "F.Cu")
		(at 117.958362 -131.218686 180)
		(property "Reference" "R2774"
			(at 0 0 180)
			(layer "F.SilkS")
			(hide yes)
			(effects
				(font
					(size 1.27 1.27)
				)
			)
		)
		(property "Value" ""
			(at 0 0 180)
			(layer "F.Fab")
			(effects
				(font
					(size 1.27 1.27)
				)
			)
		)
		(duplicate_pad_numbers_are_jumpers no)
		(fp_line
			(start 0.7874 0.4064)
			(end -0.7874 0.4064)
			(stroke
				(width 0.1524)
				(type default)
			)
			(layer "F.SilkS")
		)
		(fp_line
			(start 0.7874 -0.4064)
			(end 0.7874 0.4064)
			(stroke
				(width 0.1524)
				(type default)
			)
			(layer "F.SilkS")
		)
		(fp_line
			(start -0.7874 0.4064)
			(end -0.7874 -0.4064)
			(stroke
				(width 0.1524)
				(type default)
			)
			(layer "F.SilkS")
		)
		(fp_line
			(start -0.7874 -0.4064)
			(end 0.7874 -0.4064)
			(stroke
				(width 0.1524)
				(type default)
			)
			(layer "F.SilkS")
		)
		(fp_line
			(start 0.67945 0.3048)
			(end 0.120396 0.3048)
			(stroke
				(width 0.1)
				(type default)
			)
			(layer "F.Fab")
		)
		(fp_line
			(start 0.67945 -0.3048)
			(end 0.67945 0.3048)
			(stroke
				(width 0.1)
				(type default)
			)
			(layer "F.Fab")
		)
		(fp_line
			(start 0.12065 -0.2794)
			(end 0.12065 -0.3048)
			(stroke
				(width 0.1)
				(type default)
			)
			(layer "F.Fab")
		)
		(fp_line
			(start 0.12065 -0.3048)
			(end 0.67945 -0.3048)
			(stroke
				(width 0.1)
				(type default)
			)
			(layer "F.Fab")
		)
		(fp_line
			(start 0.120396 0.3048)
			(end 0.120396 0.2794)
			(stroke
				(width 0.1)
				(type default)
			)
			(layer "F.Fab")
		)
		(fp_line
			(start 0.120396 0.2794)
			(end -0.12065 0.2794)
			(stroke
				(width 0.1)
				(type default)
			)
			(layer "F.Fab")
		)
		(fp_line
			(start -0.12065 0.3048)
			(end -0.67945 0.3048)
			(stroke
				(width 0.1)
				(type default)
			)
			(layer "F.Fab")
		)
		(fp_line
			(start -0.12065 0.2794)
			(end -0.12065 0.3048)
			(stroke
				(width 0.1)
				(type default)
			)
			(layer "F.Fab")
		)
		(fp_line
			(start -0.12065 -0.2794)
			(end 0.12065 -0.2794)
			(stroke
				(width 0.1)
				(type default)
			)
			(layer "F.Fab")
		)
		(fp_line
			(start -0.12065 -0.305054)
			(end -0.12065 -0.2794)
			(stroke
				(width 0.1)
				(type default)
			)
			(layer "F.Fab")
		)
		(fp_line
			(start -0.67945 0.3048)
			(end -0.67945 -0.305054)
			(stroke
				(width 0.1)
				(type default)
			)
			(layer "F.Fab")
		)
		(fp_line
			(start -0.67945 -0.305054)
			(end -0.12065 -0.305054)
			(stroke
				(width 0.1)
				(type default)
			)
			(layer "F.Fab")
		)
		(pad "1" smd circle
			(at -0.40005 0 180)
			(size 0 0)
			(layers "F.Cu" "F.Mask" "F.Paste")
			(net "P3V3_AUX")
		)
		(pad "2" smd circle
			(at 0.40005 0 180)
			(size 0 0)
			(layers "F.Cu" "F.Mask" "F.Paste")
			(net "PWR_EN_P3V3_R")
		)
	)
	(footprint ""
		(layer "F.Cu")
		(at 360.050588 -398.649444)
		(property "Reference" "R6706"
			(at 0 0 0)
			(layer "F.SilkS")
			(hide yes)
			(effects
				(font
					(size 1.27 1.27)
				)
			)
		)
		(property "Value" ""
			(at 0 0 0)
			(layer "F.Fab")
			(effects
				(font
					(size 1.27 1.27)
				)
			)
		)
		(duplicate_pad_numbers_are_jumpers no)
		(fp_line
			(start -0.7874 -0.4064)
			(end 0.7874 -0.4064)
			(stroke
				(width 0.1524)
				(type default)
			)
			(layer "F.SilkS")
		)
		(fp_line
			(start -0.7874 0.4064)
			(end -0.7874 -0.4064)
			(stroke
				(width 0.1524)
				(type default)
			)
			(layer "F.SilkS")
		)
		(fp_line
			(start 0.7874 -0.4064)
			(end 0.7874 0.4064)
			(stroke
				(width 0.1524)
				(type default)
			)
			(layer "F.SilkS")
		)
		(fp_line
			(start 0.7874 0.4064)
			(end -0.7874 0.4064)
			(stroke
				(width 0.1524)
				(type default)
			)
			(layer "F.SilkS")
		)
		(fp_line
			(start -0.67945 -0.305054)
			(end -0.12065 -0.305054)
			(stroke
				(width 0.1)
				(type default)
			)
			(layer "F.Fab")
		)
		(fp_line
			(start -0.67945 0.3048)
			(end -0.67945 -0.305054)
			(stroke
				(width 0.1)
				(type default)
			)
			(layer "F.Fab")
		)
		(fp_line
			(start -0.12065 -0.305054)
			(end -0.12065 -0.2794)
			(stroke
				(width 0.1)
				(type default)
			)
			(layer "F.Fab")
		)
		(fp_line
			(start -0.12065 -0.2794)
			(end 0.12065 -0.2794)
			(stroke
				(width 0.1)
				(type default)
			)
			(layer "F.Fab")
		)
		(fp_line
			(start -0.12065 0.2794)
			(end -0.12065 0.3048)
			(stroke
				(width 0.1)
				(type default)
			)
			(layer "F.Fab")
		)
		(fp_line
			(start -0.12065 0.3048)
			(end -0.67945 0.3048)
			(stroke
				(width 0.1)
				(type default)
			)
			(layer "F.Fab")
		)
		(fp_line
			(start 0.120396 0.2794)
			(end -0.12065 0.2794)
			(stroke
				(width 0.1)
				(type default)
			)
			(layer "F.Fab")
		)
		(fp_line
			(start 0.120396 0.3048)
			(end 0.120396 0.2794)
			(stroke
				(width 0.1)
				(type default)
			)
			(layer "F.Fab")
		)
		(fp_line
			(start 0.12065 -0.3048)
			(end 0.67945 -0.3048)
			(stroke
				(width 0.1)
				(type default)
			)
			(layer "F.Fab")
		)
		(fp_line
			(start 0.12065 -0.2794)
			(end 0.12065 -0.3048)
			(stroke
				(width 0.1)
				(type default)
			)
			(layer "F.Fab")
		)
		(fp_line
			(start 0.67945 -0.3048)
			(end 0.67945 0.3048)
			(stroke
				(width 0.1)
				(type default)
			)
			(layer "F.Fab")
		)
		(fp_line
			(start 0.67945 0.3048)
			(end 0.120396 0.3048)
			(stroke
				(width 0.1)
				(type default)
			)
			(layer "F.Fab")
		)
		(pad "1" smd circle
			(at -0.40005 0)
			(size 0 0)
			(layers "F.Cu" "F.Mask" "F.Paste")
			(net "MB_3V3IO_RSVD3_ISO")
		)
		(pad "2" smd circle
			(at 0.40005 0)
			(size 0 0)
			(layers "F.Cu" "F.Mask" "F.Paste")
			(net "MB_3V3IO_RSVD3")
		)
	)
	(footprint ""
		(layer "F.Cu")
		(at 378.852684 -88.8238)
		(property "Reference" "R1765"
			(at 0 0 0)
			(layer "F.SilkS")
			(hide yes)
			(effects
				(font
					(size 1.27 1.27)
				)
			)
		)
		(property "Value" ""
			(at 0 0 0)
			(layer "F.Fab")
			(effects
				(font
					(size 1.27 1.27)
				)
			)
		)
		(duplicate_pad_numbers_are_jumpers no)
		(fp_line
			(start -0.7874 -0.4064)
			(end 0.7874 -0.4064)
			(stroke
				(width 0.1524)
				(type default)
			)
			(layer "F.SilkS")
		)
		(fp_line
			(start -0.7874 0.4064)
			(end -0.7874 -0.4064)
			(stroke
				(width 0.1524)
				(type default)
			)
			(layer "F.SilkS")
		)
		(fp_line
			(start 0.7874 -0.4064)
			(end 0.7874 0.4064)
			(stroke
				(width 0.1524)
				(type default)
			)
			(layer "F.SilkS")
		)
		(fp_line
			(start 0.7874 0.4064)
			(end -0.7874 0.4064)
			(stroke
				(width 0.1524)
				(type default)
			)
			(layer "F.SilkS")
		)
		(fp_line
			(start -0.67945 -0.305054)
			(end -0.12065 -0.305054)
			(stroke
				(width 0.1)
				(type default)
			)
			(layer "F.Fab")
		)
		(fp_line
			(start -0.67945 0.3048)
			(end -0.67945 -0.305054)
			(stroke
				(width 0.1)
				(type default)
			)
			(layer "F.Fab")
		)
		(fp_line
			(start -0.12065 -0.305054)
			(end -0.12065 -0.2794)
			(stroke
				(width 0.1)
				(type default)
			)
			(layer "F.Fab")
		)
		(fp_line
			(start -0.12065 -0.2794)
			(end 0.12065 -0.2794)
			(stroke
				(width 0.1)
				(type default)
			)
			(layer "F.Fab")
		)
		(fp_line
			(start -0.12065 0.2794)
			(end -0.12065 0.3048)
			(stroke
				(width 0.1)
				(type default)
			)
			(layer "F.Fab")
		)
		(fp_line
			(start -0.12065 0.3048)
			(end -0.67945 0.3048)
			(stroke
				(width 0.1)
				(type default)
			)
			(layer "F.Fab")
		)
		(fp_line
			(start 0.120396 0.2794)
			(end -0.12065 0.2794)
			(stroke
				(width 0.1)
				(type default)
			)
			(layer "F.Fab")
		)
		(fp_line
			(start 0.120396 0.3048)
			(end 0.120396 0.2794)
			(stroke
				(width 0.1)
				(type default)
			)
			(layer "F.Fab")
		)
		(fp_line
			(start 0.12065 -0.3048)
			(end 0.67945 -0.3048)
			(stroke
				(width 0.1)
				(type default)
			)
			(layer "F.Fab")
		)
		(fp_line
			(start 0.12065 -0.2794)
			(end 0.12065 -0.3048)
			(stroke
				(width 0.1)
				(type default)
			)
			(layer "F.Fab")
		)
		(fp_line
			(start 0.67945 -0.3048)
			(end 0.67945 0.3048)
			(stroke
				(width 0.1)
				(type default)
			)
			(layer "F.Fab")
		)
		(fp_line
			(start 0.67945 0.3048)
			(end 0.120396 0.3048)
			(stroke
				(width 0.1)
				(type default)
			)
			(layer "F.Fab")
		)
		(pad "1" smd circle
			(at -0.40005 0)
			(size 0 0)
			(layers "F.Cu" "F.Mask" "F.Paste")
			(net "SMB_BIC_I2C6_MUX_NIC_ADC_R_SDA")
		)
		(pad "2" smd circle
			(at 0.40005 0)
			(size 0 0)
			(layers "F.Cu" "F.Mask" "F.Paste")
			(net "SMB_BIC_I2C6_MUX_NIC_ADC_SDA")
		)
	)
	(footprint ""
		(layer "F.Cu")
		(at 25.358344 -252.356874 -90)
		(property "Reference" "R1203"
			(at 0 0 270)
			(layer "F.SilkS")
			(hide yes)
			(effects
				(font
					(size 1.27 1.27)
				)
			)
		)
		(property "Value" ""
			(at 0 0 270)
			(layer "F.Fab")
			(effects
				(font
					(size 1.27 1.27)
				)
			)
		)
		(duplicate_pad_numbers_are_jumpers no)
		(fp_line
			(start -0.7874 0.4064)
			(end -0.7874 -0.4064)
			(stroke
				(width 0.1524)
				(type default)
			)
			(layer "F.SilkS")
		)
		(fp_line
			(start 0.7874 0.4064)
			(end -0.7874 0.4064)
			(stroke
				(width 0.1524)
				(type default)
			)
			(layer "F.SilkS")
		)
		(fp_line
			(start -0.7874 -0.4064)
			(end 0.7874 -0.4064)
			(stroke
				(width 0.1524)
				(type default)
			)
			(layer "F.SilkS")
		)
		(fp_line
			(start 0.7874 -0.4064)
			(end 0.7874 0.4064)
			(stroke
				(width 0.1524)
				(type default)
			)
			(layer "F.SilkS")
		)
		(fp_line
			(start -0.67945 0.3048)
			(end -0.67945 -0.305054)
			(stroke
				(width 0.1)
				(type default)
			)
			(layer "F.Fab")
		)
		(fp_line
			(start -0.12065 0.3048)
			(end -0.67945 0.3048)
			(stroke
				(width 0.1)
				(type default)
			)
			(layer "F.Fab")
		)
		(fp_line
			(start 0.120396 0.3048)
			(end 0.120396 0.2794)
			(stroke
				(width 0.1)
				(type default)
			)
			(layer "F.Fab")
		)
		(fp_line
			(start 0.67945 0.3048)
			(end 0.120396 0.3048)
			(stroke
				(width 0.1)
				(type default)
			)
			(layer "F.Fab")
		)
		(fp_line
			(start -0.12065 0.2794)
			(end -0.12065 0.3048)
			(stroke
				(width 0.1)
				(type default)
			)
			(layer "F.Fab")
		)
		(fp_line
			(start 0.120396 0.2794)
			(end -0.12065 0.2794)
			(stroke
				(width 0.1)
				(type default)
			)
			(layer "F.Fab")
		)
		(fp_line
			(start -0.12065 -0.2794)
			(end 0.12065 -0.2794)
			(stroke
				(width 0.1)
				(type default)
			)
			(layer "F.Fab")
		)
		(fp_line
			(start 0.12065 -0.2794)
			(end 0.12065 -0.3048)
			(stroke
				(width 0.1)
				(type default)
			)
			(layer "F.Fab")
		)
		(fp_line
			(start 0.12065 -0.3048)
			(end 0.67945 -0.3048)
			(stroke
				(width 0.1)
				(type default)
			)
			(layer "F.Fab")
		)
		(fp_line
			(start 0.67945 -0.3048)
			(end 0.67945 0.3048)
			(stroke
				(width 0.1)
				(type default)
			)
			(layer "F.Fab")
		)
		(fp_line
			(start -0.67945 -0.305054)
			(end -0.12065 -0.305054)
			(stroke
				(width 0.1)
				(type default)
			)
			(layer "F.Fab")
		)
		(fp_line
			(start -0.12065 -0.305054)
			(end -0.12065 -0.2794)
			(stroke
				(width 0.1)
				(type default)
			)
			(layer "F.Fab")
		)
		(pad "1" smd circle
			(at -0.40005 0 270)
			(size 0 0)
			(layers "F.Cu" "F.Mask" "F.Paste")
			(net "GND")
		)
		(pad "2" smd circle
			(at 0.40005 0 270)
			(size 0 0)
			(layers "F.Cu" "F.Mask" "F.Paste")
			(net "PEX0_MODE_SEL7")
		)
	)
	(footprint ""
		(layer "F.Cu")
		(at 376.312684 -81.9658)
		(property "Reference" "R1752"
			(at 0 0 0)
			(layer "F.SilkS")
			(hide yes)
			(effects
				(font
					(size 1.27 1.27)
				)
			)
		)
		(property "Value" ""
			(at 0 0 0)
			(layer "F.Fab")
			(effects
				(font
					(size 1.27 1.27)
				)
			)
		)
		(duplicate_pad_numbers_are_jumpers no)
		(fp_line
			(start -0.7874 -0.4064)
			(end 0.7874 -0.4064)
			(stroke
				(width 0.1524)
				(type default)
			)
			(layer "F.SilkS")
		)
		(fp_line
			(start -0.7874 0.4064)
			(end -0.7874 -0.4064)
			(stroke
				(width 0.1524)
				(type default)
			)
			(layer "F.SilkS")
		)
		(fp_line
			(start 0.7874 -0.4064)
			(end 0.7874 0.4064)
			(stroke
				(width 0.1524)
				(type default)
			)
			(layer "F.SilkS")
		)
		(fp_line
			(start 0.7874 0.4064)
			(end -0.7874 0.4064)
			(stroke
				(width 0.1524)
				(type default)
			)
			(layer "F.SilkS")
		)
		(fp_line
			(start -0.67945 -0.305054)
			(end -0.12065 -0.305054)
			(stroke
				(width 0.1)
				(type default)
			)
			(layer "F.Fab")
		)
		(fp_line
			(start -0.67945 0.3048)
			(end -0.67945 -0.305054)
			(stroke
				(width 0.1)
				(type default)
			)
			(layer "F.Fab")
		)
		(fp_line
			(start -0.12065 -0.305054)
			(end -0.12065 -0.2794)
			(stroke
				(width 0.1)
				(type default)
			)
			(layer "F.Fab")
		)
		(fp_line
			(start -0.12065 -0.2794)
			(end 0.12065 -0.2794)
			(stroke
				(width 0.1)
				(type default)
			)
			(layer "F.Fab")
		)
		(fp_line
			(start -0.12065 0.2794)
			(end -0.12065 0.3048)
			(stroke
				(width 0.1)
				(type default)
			)
			(layer "F.Fab")
		)
		(fp_line
			(start -0.12065 0.3048)
			(end -0.67945 0.3048)
			(stroke
				(width 0.1)
				(type default)
			)
			(layer "F.Fab")
		)
		(fp_line
			(start 0.120396 0.2794)
			(end -0.12065 0.2794)
			(stroke
				(width 0.1)
				(type default)
			)
			(layer "F.Fab")
		)
		(fp_line
			(start 0.120396 0.3048)
			(end 0.120396 0.2794)
			(stroke
				(width 0.1)
				(type default)
			)
			(layer "F.Fab")
		)
		(fp_line
			(start 0.12065 -0.3048)
			(end 0.67945 -0.3048)
			(stroke
				(width 0.1)
				(type default)
			)
			(layer "F.Fab")
		)
		(fp_line
			(start 0.12065 -0.2794)
			(end 0.12065 -0.3048)
			(stroke
				(width 0.1)
				(type default)
			)
			(layer "F.Fab")
		)
		(fp_line
			(start 0.67945 -0.3048)
			(end 0.67945 0.3048)
			(stroke
				(width 0.1)
				(type default)
			)
			(layer "F.Fab")
		)
		(fp_line
			(start 0.67945 0.3048)
			(end 0.120396 0.3048)
			(stroke
				(width 0.1)
				(type default)
			)
			(layer "F.Fab")
		)
		(pad "1" smd circle
			(at -0.40005 0)
			(size 0 0)
			(layers "F.Cu" "F.Mask" "F.Paste")
			(net "P3V3_AUX")
		)
		(pad "2" smd circle
			(at 0.40005 0)
			(size 0 0)
			(layers "F.Cu" "F.Mask" "F.Paste")
			(net "SMB_BIC_I2C6_MUX_SSD_0_7_ADC_R_SDA")
		)
	)
	(footprint ""
		(layer "F.Cu")
		(at 25.524968 -343.952322 90)
		(property "Reference" "C2156"
			(at 0 0 90)
			(layer "F.SilkS")
			(hide yes)
			(effects
				(font
					(size 1.27 1.27)
				)
			)
		)
		(property "Value" ""
			(at 0 0 90)
			(layer "F.Fab")
			(effects
				(font
					(size 1.27 1.27)
				)
			)
		)
		(duplicate_pad_numbers_are_jumpers no)
		(fp_line
			(start 0.299974 -0.150114)
			(end 0.299974 0.150114)
			(stroke
				(width 0.1)
				(type default)
			)
			(layer "F.Fab")
		)
		(fp_line
			(start -0.299974 -0.150114)
			(end 0.299974 -0.150114)
			(stroke
				(width 0.1)
				(type default)
			)
			(layer "F.Fab")
		)
		(fp_line
			(start 0.299974 0.150114)
			(end -0.299974 0.150114)
			(stroke
				(width 0.1)
				(type default)
			)
			(layer "F.Fab")
		)
		(fp_line
			(start -0.299974 0.150114)
			(end -0.299974 -0.150114)
			(stroke
				(width 0.1)
				(type default)
			)
			(layer "F.Fab")
		)
		(pad "1" smd rect
			(at -0.2667 0 90)
			(size 0.3048 0.381)
			(layers "F.Cu" "F.Mask" "F.Paste")
			(net "P5E_PEX0_STN4_TX_DP<77>")
		)
		(pad "2" smd rect
			(at 0.2667 0 90)
			(size 0.3048 0.381)
			(layers "F.Cu" "F.Mask" "F.Paste")
			(net "P5E_PEX0_STN4_TX_C_DP<77>")
		)
	)
	(footprint ""
		(layer "F.Cu")
		(at 215.985598 -25.1587 -90)
		(property "Reference" "R5746"
			(at 0 0 270)
			(layer "F.SilkS")
			(hide yes)
			(effects
				(font
					(size 1.27 1.27)
				)
			)
		)
		(property "Value" ""
			(at 0 0 270)
			(layer "F.Fab")
			(effects
				(font
					(size 1.27 1.27)
				)
			)
		)
		(duplicate_pad_numbers_are_jumpers no)
		(fp_line
			(start -0.7874 0.4064)
			(end -0.7874 -0.4064)
			(stroke
				(width 0.1524)
				(type default)
			)
			(layer "F.SilkS")
		)
		(fp_line
			(start 0.7874 0.4064)
			(end -0.7874 0.4064)
			(stroke
				(width 0.1524)
				(type default)
			)
			(layer "F.SilkS")
		)
		(fp_line
			(start -0.7874 -0.4064)
			(end 0.7874 -0.4064)
			(stroke
				(width 0.1524)
				(type default)
			)
			(layer "F.SilkS")
		)
		(fp_line
			(start 0.7874 -0.4064)
			(end 0.7874 0.4064)
			(stroke
				(width 0.1524)
				(type default)
			)
			(layer "F.SilkS")
		)
		(fp_line
			(start -0.67945 0.3048)
			(end -0.67945 -0.305054)
			(stroke
				(width 0.1)
				(type default)
			)
			(layer "F.Fab")
		)
		(fp_line
			(start -0.12065 0.3048)
			(end -0.67945 0.3048)
			(stroke
				(width 0.1)
				(type default)
			)
			(layer "F.Fab")
		)
		(fp_line
			(start 0.120396 0.3048)
			(end 0.120396 0.2794)
			(stroke
				(width 0.1)
				(type default)
			)
			(layer "F.Fab")
		)
		(fp_line
			(start 0.67945 0.3048)
			(end 0.120396 0.3048)
			(stroke
				(width 0.1)
				(type default)
			)
			(layer "F.Fab")
		)
		(fp_line
			(start -0.12065 0.2794)
			(end -0.12065 0.3048)
			(stroke
				(width 0.1)
				(type default)
			)
			(layer "F.Fab")
		)
		(fp_line
			(start 0.120396 0.2794)
			(end -0.12065 0.2794)
			(stroke
				(width 0.1)
				(type default)
			)
			(layer "F.Fab")
		)
		(fp_line
			(start -0.12065 -0.2794)
			(end 0.12065 -0.2794)
			(stroke
				(width 0.1)
				(type default)
			)
			(layer "F.Fab")
		)
		(fp_line
			(start 0.12065 -0.2794)
			(end 0.12065 -0.3048)
			(stroke
				(width 0.1)
				(type default)
			)
			(layer "F.Fab")
		)
		(fp_line
			(start 0.12065 -0.3048)
			(end 0.67945 -0.3048)
			(stroke
				(width 0.1)
				(type default)
			)
			(layer "F.Fab")
		)
		(fp_line
			(start 0.67945 -0.3048)
			(end 0.67945 0.3048)
			(stroke
				(width 0.1)
				(type default)
			)
			(layer "F.Fab")
		)
		(fp_line
			(start -0.67945 -0.305054)
			(end -0.12065 -0.305054)
			(stroke
				(width 0.1)
				(type default)
			)
			(layer "F.Fab")
		)
		(fp_line
			(start -0.12065 -0.305054)
			(end -0.12065 -0.2794)
			(stroke
				(width 0.1)
				(type default)
			)
			(layer "F.Fab")
		)
		(pad "1" smd circle
			(at -0.40005 0 270)
			(size 0 0)
			(layers "F.Cu" "F.Mask" "F.Paste")
			(net "SSD7_LED_ISO_N")
		)
		(pad "2" smd circle
			(at 0.40005 0 270)
			(size 0 0)
			(layers "F.Cu" "F.Mask" "F.Paste")
			(net "SSD7_LED_ISO_R_N")
		)
	)
	(footprint ""
		(layer "F.Cu")
		(at 145.642076 -305.648106 -135)
		(property "Reference" "R1308"
			(at 0 0 225)
			(layer "F.SilkS")
			(hide yes)
			(effects
				(font
					(size 1.27 1.27)
				)
			)
		)
		(property "Value" ""
			(at 0 0 225)
			(layer "F.Fab")
			(effects
				(font
					(size 1.27 1.27)
				)
			)
		)
		(duplicate_pad_numbers_are_jumpers no)
		(fp_line
			(start 0.787389 0.406267)
			(end -0.787389 0.406267)
			(stroke
				(width 0.1524)
				(type default)
			)
			(layer "F.SilkS")
		)
		(fp_line
			(start 0.787389 -0.406267)
			(end 0.787389 0.406267)
			(stroke
				(width 0.1524)
				(type default)
			)
			(layer "F.SilkS")
		)
		(fp_line
			(start -0.787389 0.406267)
			(end -0.787389 -0.406267)
			(stroke
				(width 0.1524)
				(type default)
			)
			(layer "F.SilkS")
		)
		(fp_line
			(start -0.787389 -0.406267)
			(end 0.787389 -0.406267)
			(stroke
				(width 0.1524)
				(type default)
			)
			(layer "F.SilkS")
		)
		(fp_line
			(start 0.679446 0.30479)
			(end 0.120515 0.30479)
			(stroke
				(width 0.1)
				(type default)
			)
			(layer "F.Fab")
		)
		(fp_line
			(start 0.120515 0.30479)
			(end 0.120335 0.279466)
			(stroke
				(width 0.1)
				(type default)
			)
			(layer "F.Fab")
		)
		(fp_line
			(start 0.120335 0.279466)
			(end -0.120695 0.279466)
			(stroke
				(width 0.1)
				(type default)
			)
			(layer "F.Fab")
		)
		(fp_line
			(start 0.679446 -0.30479)
			(end 0.679446 0.30479)
			(stroke
				(width 0.1)
				(type default)
			)
			(layer "F.Fab")
		)
		(fp_line
			(start -0.120515 0.30479)
			(end -0.679446 0.30479)
			(stroke
				(width 0.1)
				(type default)
			)
			(layer "F.Fab")
		)
		(fp_line
			(start -0.120695 0.279466)
			(end -0.120515 0.30479)
			(stroke
				(width 0.1)
				(type default)
			)
			(layer "F.Fab")
		)
		(fp_line
			(start 0.120695 -0.279466)
			(end 0.120515 -0.30479)
			(stroke
				(width 0.1)
				(type default)
			)
			(layer "F.Fab")
		)
		(fp_line
			(start 0.120515 -0.30479)
			(end 0.679446 -0.30479)
			(stroke
				(width 0.1)
				(type default)
			)
			(layer "F.Fab")
		)
		(fp_line
			(start -0.679446 0.30479)
			(end -0.679446 -0.305149)
			(stroke
				(width 0.1)
				(type default)
			)
			(layer "F.Fab")
		)
		(fp_line
			(start -0.120695 -0.279466)
			(end 0.120695 -0.279466)
			(stroke
				(width 0.1)
				(type default)
			)
			(layer "F.Fab")
		)
		(fp_line
			(start -0.120695 -0.304969)
			(end -0.120695 -0.279466)
			(stroke
				(width 0.1)
				(type default)
			)
			(layer "F.Fab")
		)
		(fp_line
			(start -0.679446 -0.305149)
			(end -0.120695 -0.304969)
			(stroke
				(width 0.1)
				(type default)
			)
			(layer "F.Fab")
		)
		(pad "1" smd circle
			(at -0.40005 0 225)
			(size 0 0)
			(layers "F.Cu" "F.Mask" "F.Paste")
			(net "PEX1_DFT_IDDT")
		)
		(pad "2" smd circle
			(at 0.40005 0 225)
			(size 0 0)
			(layers "F.Cu" "F.Mask" "F.Paste")
			(net "P1V8_PEX")
		)
	)
	(footprint ""
		(layer "F.Cu")
		(at 291.194998 -102.798372 180)
		(property "Reference" "R274"
			(at 0 0 180)
			(layer "F.SilkS")
			(hide yes)
			(effects
				(font
					(size 1.27 1.27)
				)
			)
		)
		(property "Value" ""
			(at 0 0 180)
			(layer "F.Fab")
			(effects
				(font
					(size 1.27 1.27)
				)
			)
		)
		(duplicate_pad_numbers_are_jumpers no)
		(fp_line
			(start 0.7874 0.4064)
			(end -0.7874 0.4064)
			(stroke
				(width 0.1524)
				(type default)
			)
			(layer "F.SilkS")
		)
		(fp_line
			(start 0.7874 -0.4064)
			(end 0.7874 0.4064)
			(stroke
				(width 0.1524)
				(type default)
			)
			(layer "F.SilkS")
		)
		(fp_line
			(start -0.7874 0.4064)
			(end -0.7874 -0.4064)
			(stroke
				(width 0.1524)
				(type default)
			)
			(layer "F.SilkS")
		)
		(fp_line
			(start -0.7874 -0.4064)
			(end 0.7874 -0.4064)
			(stroke
				(width 0.1524)
				(type default)
			)
			(layer "F.SilkS")
		)
		(fp_line
			(start 0.67945 0.3048)
			(end 0.120396 0.3048)
			(stroke
				(width 0.1)
				(type default)
			)
			(layer "F.Fab")
		)
		(fp_line
			(start 0.67945 -0.3048)
			(end 0.67945 0.3048)
			(stroke
				(width 0.1)
				(type default)
			)
			(layer "F.Fab")
		)
		(fp_line
			(start 0.12065 -0.2794)
			(end 0.12065 -0.3048)
			(stroke
				(width 0.1)
				(type default)
			)
			(layer "F.Fab")
		)
		(fp_line
			(start 0.12065 -0.3048)
			(end 0.67945 -0.3048)
			(stroke
				(width 0.1)
				(type default)
			)
			(layer "F.Fab")
		)
		(fp_line
			(start 0.120396 0.3048)
			(end 0.120396 0.2794)
			(stroke
				(width 0.1)
				(type default)
			)
			(layer "F.Fab")
		)
		(fp_line
			(start 0.120396 0.2794)
			(end -0.12065 0.2794)
			(stroke
				(width 0.1)
				(type default)
			)
			(layer "F.Fab")
		)
		(fp_line
			(start -0.12065 0.3048)
			(end -0.67945 0.3048)
			(stroke
				(width 0.1)
				(type default)
			)
			(layer "F.Fab")
		)
		(fp_line
			(start -0.12065 0.2794)
			(end -0.12065 0.3048)
			(stroke
				(width 0.1)
				(type default)
			)
			(layer "F.Fab")
		)
		(fp_line
			(start -0.12065 -0.2794)
			(end 0.12065 -0.2794)
			(stroke
				(width 0.1)
				(type default)
			)
			(layer "F.Fab")
		)
		(fp_line
			(start -0.12065 -0.305054)
			(end -0.12065 -0.2794)
			(stroke
				(width 0.1)
				(type default)
			)
			(layer "F.Fab")
		)
		(fp_line
			(start -0.67945 0.3048)
			(end -0.67945 -0.305054)
			(stroke
				(width 0.1)
				(type default)
			)
			(layer "F.Fab")
		)
		(fp_line
			(start -0.67945 -0.305054)
			(end -0.12065 -0.305054)
			(stroke
				(width 0.1)
				(type default)
			)
			(layer "F.Fab")
		)
		(pad "1" smd circle
			(at -0.40005 0 180)
			(size 0 0)
			(layers "F.Cu" "F.Mask" "F.Paste")
			(net "NCSI_NIC5_TXD1")
		)
		(pad "2" smd circle
			(at 0.40005 0 180)
			(size 0 0)
			(layers "F.Cu" "F.Mask" "F.Paste")
			(net "GND")
		)
	)
	(footprint ""
		(layer "F.Cu")
		(at 240.968276 -319.392554 180)
		(property "Reference" "PC243"
			(at 0 0 180)
			(layer "F.SilkS")
			(hide yes)
			(effects
				(font
					(size 1.27 1.27)
				)
			)
		)
		(property "Value" ""
			(at 0 0 180)
			(layer "F.Fab")
			(effects
				(font
					(size 1.27 1.27)
				)
			)
		)
		(duplicate_pad_numbers_are_jumpers no)
		(fp_line
			(start 0.7874 0.4064)
			(end -0.7874 0.4064)
			(stroke
				(width 0.1524)
				(type default)
			)
			(layer "F.SilkS")
		)
		(fp_line
			(start 0.7874 -0.4064)
			(end 0.7874 0.4064)
			(stroke
				(width 0.1524)
				(type default)
			)
			(layer "F.SilkS")
		)
		(fp_line
			(start -0.7874 0.4064)
			(end -0.7874 -0.4064)
			(stroke
				(width 0.1524)
				(type default)
			)
			(layer "F.SilkS")
		)
		(fp_line
			(start -0.7874 -0.4064)
			(end 0.7874 -0.4064)
			(stroke
				(width 0.1524)
				(type default)
			)
			(layer "F.SilkS")
		)
		(fp_line
			(start 0.67945 0.3048)
			(end 0.120396 0.3048)
			(stroke
				(width 0.1)
				(type default)
			)
			(layer "F.Fab")
		)
		(fp_line
			(start 0.67945 -0.3048)
			(end 0.67945 0.3048)
			(stroke
				(width 0.1)
				(type default)
			)
			(layer "F.Fab")
		)
		(fp_line
			(start 0.12065 -0.2794)
			(end 0.12065 -0.3048)
			(stroke
				(width 0.1)
				(type default)
			)
			(layer "F.Fab")
		)
		(fp_line
			(start 0.12065 -0.3048)
			(end 0.67945 -0.3048)
			(stroke
				(width 0.1)
				(type default)
			)
			(layer "F.Fab")
		)
		(fp_line
			(start 0.120396 0.3048)
			(end 0.120396 0.2794)
			(stroke
				(width 0.1)
				(type default)
			)
			(layer "F.Fab")
		)
		(fp_line
			(start 0.120396 0.2794)
			(end -0.12065 0.2794)
			(stroke
				(width 0.1)
				(type default)
			)
			(layer "F.Fab")
		)
		(fp_line
			(start -0.12065 0.3048)
			(end -0.67945 0.3048)
			(stroke
				(width 0.1)
				(type default)
			)
			(layer "F.Fab")
		)
		(fp_line
			(start -0.12065 0.2794)
			(end -0.12065 0.3048)
			(stroke
				(width 0.1)
				(type default)
			)
			(layer "F.Fab")
		)
		(fp_line
			(start -0.12065 -0.2794)
			(end 0.12065 -0.2794)
			(stroke
				(width 0.1)
				(type default)
			)
			(layer "F.Fab")
		)
		(fp_line
			(start -0.12065 -0.305054)
			(end -0.12065 -0.2794)
			(stroke
				(width 0.1)
				(type default)
			)
			(layer "F.Fab")
		)
		(fp_line
			(start -0.67945 0.3048)
			(end -0.67945 -0.305054)
			(stroke
				(width 0.1)
				(type default)
			)
			(layer "F.Fab")
		)
		(fp_line
			(start -0.67945 -0.305054)
			(end -0.12065 -0.305054)
			(stroke
				(width 0.1)
				(type default)
			)
			(layer "F.Fab")
		)
		(pad "1" smd circle
			(at -0.40005 0 180)
			(size 0 0)
			(layers "F.Cu" "F.Mask" "F.Paste")
			(net "P12V_AUX")
		)
		(pad "2" smd circle
			(at 0.40005 0 180)
			(size 0 0)
			(layers "F.Cu" "F.Mask" "F.Paste")
			(net "GND")
		)
	)
	(footprint ""
		(layer "F.Cu")
		(at 255.824736 -259.378958)
		(property "Reference" "R1397"
			(at 0 0 0)
			(layer "F.SilkS")
			(hide yes)
			(effects
				(font
					(size 1.27 1.27)
				)
			)
		)
		(property "Value" ""
			(at 0 0 0)
			(layer "F.Fab")
			(effects
				(font
					(size 1.27 1.27)
				)
			)
		)
		(duplicate_pad_numbers_are_jumpers no)
		(fp_line
			(start -0.7874 -0.4064)
			(end 0.7874 -0.4064)
			(stroke
				(width 0.1524)
				(type default)
			)
			(layer "F.SilkS")
		)
		(fp_line
			(start -0.7874 0.4064)
			(end -0.7874 -0.4064)
			(stroke
				(width 0.1524)
				(type default)
			)
			(layer "F.SilkS")
		)
		(fp_line
			(start 0.7874 -0.4064)
			(end 0.7874 0.4064)
			(stroke
				(width 0.1524)
				(type default)
			)
			(layer "F.SilkS")
		)
		(fp_line
			(start 0.7874 0.4064)
			(end -0.7874 0.4064)
			(stroke
				(width 0.1524)
				(type default)
			)
			(layer "F.SilkS")
		)
		(fp_line
			(start -0.67945 -0.305054)
			(end -0.12065 -0.305054)
			(stroke
				(width 0.1)
				(type default)
			)
			(layer "F.Fab")
		)
		(fp_line
			(start -0.67945 0.3048)
			(end -0.67945 -0.305054)
			(stroke
				(width 0.1)
				(type default)
			)
			(layer "F.Fab")
		)
		(fp_line
			(start -0.12065 -0.305054)
			(end -0.12065 -0.2794)
			(stroke
				(width 0.1)
				(type default)
			)
			(layer "F.Fab")
		)
		(fp_line
			(start -0.12065 -0.2794)
			(end 0.12065 -0.2794)
			(stroke
				(width 0.1)
				(type default)
			)
			(layer "F.Fab")
		)
		(fp_line
			(start -0.12065 0.2794)
			(end -0.12065 0.3048)
			(stroke
				(width 0.1)
				(type default)
			)
			(layer "F.Fab")
		)
		(fp_line
			(start -0.12065 0.3048)
			(end -0.67945 0.3048)
			(stroke
				(width 0.1)
				(type default)
			)
			(layer "F.Fab")
		)
		(fp_line
			(start 0.120396 0.2794)
			(end -0.12065 0.2794)
			(stroke
				(width 0.1)
				(type default)
			)
			(layer "F.Fab")
		)
		(fp_line
			(start 0.120396 0.3048)
			(end 0.120396 0.2794)
			(stroke
				(width 0.1)
				(type default)
			)
			(layer "F.Fab")
		)
		(fp_line
			(start 0.12065 -0.3048)
			(end 0.67945 -0.3048)
			(stroke
				(width 0.1)
				(type default)
			)
			(layer "F.Fab")
		)
		(fp_line
			(start 0.12065 -0.2794)
			(end 0.12065 -0.3048)
			(stroke
				(width 0.1)
				(type default)
			)
			(layer "F.Fab")
		)
		(fp_line
			(start 0.67945 -0.3048)
			(end 0.67945 0.3048)
			(stroke
				(width 0.1)
				(type default)
			)
			(layer "F.Fab")
		)
		(fp_line
			(start 0.67945 0.3048)
			(end 0.120396 0.3048)
			(stroke
				(width 0.1)
				(type default)
			)
			(layer "F.Fab")
		)
		(pad "1" smd circle
			(at -0.40005 0)
			(size 0 0)
			(layers "F.Cu" "F.Mask" "F.Paste")
			(net "PEX2_SYS_ERR_N_G")
		)
		(pad "2" smd circle
			(at 0.40005 0)
			(size 0 0)
			(layers "F.Cu" "F.Mask" "F.Paste")
			(net "P3V3_AUX")
		)
	)
	(footprint ""
		(layer "F.Cu")
		(at 28.782518 -29.875734)
		(property "Reference" "PU82"
			(at -3.360674 -1.147826 90)
			(unlocked yes)
			(layer "F.SilkS")
			(effects
				(font
					(size 0.7874 0.5842)
					(thickness 0.1524)
				)
			)
		)
		(property "Value" ""
			(at 0 0 0)
			(layer "F.Fab")
			(effects
				(font
					(size 1.27 1.27)
				)
			)
		)
		(duplicate_pad_numbers_are_jumpers no)
		(fp_line
			(start -1.239774 -1.495298)
			(end 1.239774 -1.495298)
			(stroke
				(width 0.1524)
				(type default)
			)
			(layer "F.SilkS")
		)
		(fp_line
			(start -1.239774 1.495298)
			(end -1.239774 -1.495298)
			(stroke
				(width 0.1524)
				(type default)
			)
			(layer "F.SilkS")
		)
		(fp_line
			(start 1.239774 -1.495298)
			(end 1.239774 1.495298)
			(stroke
				(width 0.1524)
				(type default)
			)
			(layer "F.SilkS")
		)
		(fp_line
			(start 1.239774 1.495298)
			(end -1.239774 1.495298)
			(stroke
				(width 0.1524)
				(type default)
			)
			(layer "F.SilkS")
		)
		(fp_poly
			(pts
				(xy -2.181352 -1.59639) (xy -2.899664 -0.878078) (xy -1.822196 -0.518922)
			)
			(stroke
				(width 0)
				(type default)
			)
			(fill yes)
			(layer "F.SilkS")
		)
		(fp_line
			(start -0.8001 -1.050036)
			(end 0.8001 -1.050036)
			(stroke
				(width 0.1)
				(type default)
			)
			(layer "F.Fab")
		)
		(fp_line
			(start -0.8001 1.050036)
			(end -0.8001 -1.050036)
			(stroke
				(width 0.1)
				(type default)
			)
			(layer "F.Fab")
		)
		(fp_line
			(start 0.8001 -1.050036)
			(end 0.8001 1.050036)
			(stroke
				(width 0.1)
				(type default)
			)
			(layer "F.Fab")
		)
		(fp_line
			(start 0.8001 1.050036)
			(end -0.8001 1.050036)
			(stroke
				(width 0.1)
				(type default)
			)
			(layer "F.Fab")
		)
		(fp_poly
			(pts
				(xy -2.458974 -0.508) (xy -2.458974 0.508) (xy -1.442974 0)
			)
			(stroke
				(width 0)
				(type default)
			)
			(fill yes)
			(layer "F.Fab")
		)
		(pad "1_2" smd circle
			(at -0.374904 0 90)
			(size 0 0)
			(layers "F.Cu" "F.Mask" "F.Paste")
			(net "P3V3_AUX")
		)
		(pad "3" smd rect
			(at -0.499872 0.999998)
			(size 0.254 0.7112)
			(layers "F.Cu" "F.Mask" "F.Paste")
			(net "GND")
		)
		(pad "4" smd rect
			(at 0 0.999998)
			(size 0.254 0.7112)
			(layers "F.Cu" "F.Mask" "F.Paste")
			(net "P3V3_SSD1_CO_ILIMIT")
		)
		(pad "5" smd rect
			(at 0.499872 0.999998)
			(size 0.254 0.7112)
			(layers "F.Cu" "F.Mask" "F.Paste")
			(net "P3V3_SSD1_CO_MODE")
		)
		(pad "6_7" smd circle
			(at 0.374904 0 270)
			(size 0 0)
			(layers "F.Cu" "F.Mask" "F.Paste")
			(net "P3V3_SSD1")
		)
		(pad "8" smd rect
			(at 0.499872 -0.999998)
			(size 0.254 0.7112)
			(layers "F.Cu" "F.Mask" "F.Paste")
			(net "P3V3_SSD1_CO_GATE")
		)
		(pad "9" smd rect
			(at 0 -0.999998)
			(size 0.254 0.7112)
			(layers "F.Cu" "F.Mask" "F.Paste")
			(net "P3V3_SSD1_CO_EN")
		)
		(pad "10" smd rect
			(at -0.499872 -0.999998)
			(size 0.254 0.7112)
			(layers "F.Cu" "F.Mask" "F.Paste")
			(net "P3V3_SSD1_CO_DV_DT")
		)
	)
	(footprint ""
		(layer "F.Cu")
		(at 16.431768 -162.003994 -90)
		(property "Reference" "R903"
			(at 0 0 270)
			(layer "F.SilkS")
			(hide yes)
			(effects
				(font
					(size 1.27 1.27)
				)
			)
		)
		(property "Value" ""
			(at 0 0 270)
			(layer "F.Fab")
			(effects
				(font
					(size 1.27 1.27)
				)
			)
		)
		(duplicate_pad_numbers_are_jumpers no)
		(fp_line
			(start -0.7874 0.4064)
			(end -0.7874 -0.4064)
			(stroke
				(width 0.1524)
				(type default)
			)
			(layer "F.SilkS")
		)
		(fp_line
			(start 0.7874 0.4064)
			(end -0.7874 0.4064)
			(stroke
				(width 0.1524)
				(type default)
			)
			(layer "F.SilkS")
		)
		(fp_line
			(start -0.7874 -0.4064)
			(end 0.7874 -0.4064)
			(stroke
				(width 0.1524)
				(type default)
			)
			(layer "F.SilkS")
		)
		(fp_line
			(start 0.7874 -0.4064)
			(end 0.7874 0.4064)
			(stroke
				(width 0.1524)
				(type default)
			)
			(layer "F.SilkS")
		)
		(fp_line
			(start -0.67945 0.3048)
			(end -0.67945 -0.305054)
			(stroke
				(width 0.1)
				(type default)
			)
			(layer "F.Fab")
		)
		(fp_line
			(start -0.12065 0.3048)
			(end -0.67945 0.3048)
			(stroke
				(width 0.1)
				(type default)
			)
			(layer "F.Fab")
		)
		(fp_line
			(start 0.120396 0.3048)
			(end 0.120396 0.2794)
			(stroke
				(width 0.1)
				(type default)
			)
			(layer "F.Fab")
		)
		(fp_line
			(start 0.67945 0.3048)
			(end 0.120396 0.3048)
			(stroke
				(width 0.1)
				(type default)
			)
			(layer "F.Fab")
		)
		(fp_line
			(start -0.12065 0.2794)
			(end -0.12065 0.3048)
			(stroke
				(width 0.1)
				(type default)
			)
			(layer "F.Fab")
		)
		(fp_line
			(start 0.120396 0.2794)
			(end -0.12065 0.2794)
			(stroke
				(width 0.1)
				(type default)
			)
			(layer "F.Fab")
		)
		(fp_line
			(start -0.12065 -0.2794)
			(end 0.12065 -0.2794)
			(stroke
				(width 0.1)
				(type default)
			)
			(layer "F.Fab")
		)
		(fp_line
			(start 0.12065 -0.2794)
			(end 0.12065 -0.3048)
			(stroke
				(width 0.1)
				(type default)
			)
			(layer "F.Fab")
		)
		(fp_line
			(start 0.12065 -0.3048)
			(end 0.67945 -0.3048)
			(stroke
				(width 0.1)
				(type default)
			)
			(layer "F.Fab")
		)
		(fp_line
			(start 0.67945 -0.3048)
			(end 0.67945 0.3048)
			(stroke
				(width 0.1)
				(type default)
			)
			(layer "F.Fab")
		)
		(fp_line
			(start -0.67945 -0.305054)
			(end -0.12065 -0.305054)
			(stroke
				(width 0.1)
				(type default)
			)
			(layer "F.Fab")
		)
		(fp_line
			(start -0.12065 -0.305054)
			(end -0.12065 -0.2794)
			(stroke
				(width 0.1)
				(type default)
			)
			(layer "F.Fab")
		)
		(pad "1" smd circle
			(at -0.40005 0 270)
			(size 0 0)
			(layers "F.Cu" "F.Mask" "F.Paste")
			(net "HP_NIC0_EN")
		)
		(pad "2" smd circle
			(at 0.40005 0 270)
			(size 0 0)
			(layers "F.Cu" "F.Mask" "F.Paste")
			(net "P12V_NIC0_CO_EN")
		)
	)
	(footprint ""
		(layer "F.Cu")
		(at 336.042 -148.971 180)
		(property "Reference" "R4827"
			(at 0 0 180)
			(layer "F.SilkS")
			(hide yes)
			(effects
				(font
					(size 1.27 1.27)
				)
			)
		)
		(property "Value" ""
			(at 0 0 180)
			(layer "F.Fab")
			(effects
				(font
					(size 1.27 1.27)
				)
			)
		)
		(duplicate_pad_numbers_are_jumpers no)
		(fp_line
			(start 0.7874 0.4064)
			(end -0.7874 0.4064)
			(stroke
				(width 0.1524)
				(type default)
			)
			(layer "F.SilkS")
		)
		(fp_line
			(start 0.7874 -0.4064)
			(end 0.7874 0.4064)
			(stroke
				(width 0.1524)
				(type default)
			)
			(layer "F.SilkS")
		)
		(fp_line
			(start -0.7874 0.4064)
			(end -0.7874 -0.4064)
			(stroke
				(width 0.1524)
				(type default)
			)
			(layer "F.SilkS")
		)
		(fp_line
			(start -0.7874 -0.4064)
			(end 0.7874 -0.4064)
			(stroke
				(width 0.1524)
				(type default)
			)
			(layer "F.SilkS")
		)
		(fp_line
			(start 0.67945 0.3048)
			(end 0.120396 0.3048)
			(stroke
				(width 0.1)
				(type default)
			)
			(layer "F.Fab")
		)
		(fp_line
			(start 0.67945 -0.3048)
			(end 0.67945 0.3048)
			(stroke
				(width 0.1)
				(type default)
			)
			(layer "F.Fab")
		)
		(fp_line
			(start 0.12065 -0.2794)
			(end 0.12065 -0.3048)
			(stroke
				(width 0.1)
				(type default)
			)
			(layer "F.Fab")
		)
		(fp_line
			(start 0.12065 -0.3048)
			(end 0.67945 -0.3048)
			(stroke
				(width 0.1)
				(type default)
			)
			(layer "F.Fab")
		)
		(fp_line
			(start 0.120396 0.3048)
			(end 0.120396 0.2794)
			(stroke
				(width 0.1)
				(type default)
			)
			(layer "F.Fab")
		)
		(fp_line
			(start 0.120396 0.2794)
			(end -0.12065 0.2794)
			(stroke
				(width 0.1)
				(type default)
			)
			(layer "F.Fab")
		)
		(fp_line
			(start -0.12065 0.3048)
			(end -0.67945 0.3048)
			(stroke
				(width 0.1)
				(type default)
			)
			(layer "F.Fab")
		)
		(fp_line
			(start -0.12065 0.2794)
			(end -0.12065 0.3048)
			(stroke
				(width 0.1)
				(type default)
			)
			(layer "F.Fab")
		)
		(fp_line
			(start -0.12065 -0.2794)
			(end 0.12065 -0.2794)
			(stroke
				(width 0.1)
				(type default)
			)
			(layer "F.Fab")
		)
		(fp_line
			(start -0.12065 -0.305054)
			(end -0.12065 -0.2794)
			(stroke
				(width 0.1)
				(type default)
			)
			(layer "F.Fab")
		)
		(fp_line
			(start -0.67945 0.3048)
			(end -0.67945 -0.305054)
			(stroke
				(width 0.1)
				(type default)
			)
			(layer "F.Fab")
		)
		(fp_line
			(start -0.67945 -0.305054)
			(end -0.12065 -0.305054)
			(stroke
				(width 0.1)
				(type default)
			)
			(layer "F.Fab")
		)
		(pad "1" smd circle
			(at -0.40005 0 180)
			(size 0 0)
			(layers "F.Cu" "F.Mask" "F.Paste")
			(net "PCA9555_1_PEX3_A2")
		)
		(pad "2" smd circle
			(at 0.40005 0 180)
			(size 0 0)
			(layers "F.Cu" "F.Mask" "F.Paste")
			(net "P3V3_AUX")
		)
	)
	(footprint ""
		(layer "F.Cu")
		(at 433.83581 -289.230816 -90)
		(property "Reference" "R6401"
			(at 0 0 270)
			(layer "F.SilkS")
			(hide yes)
			(effects
				(font
					(size 1.27 1.27)
				)
			)
		)
		(property "Value" ""
			(at 0 0 270)
			(layer "F.Fab")
			(effects
				(font
					(size 1.27 1.27)
				)
			)
		)
		(duplicate_pad_numbers_are_jumpers no)
		(fp_line
			(start -0.7874 0.4064)
			(end -0.7874 -0.4064)
			(stroke
				(width 0.1524)
				(type default)
			)
			(layer "F.SilkS")
		)
		(fp_line
			(start 0.7874 0.4064)
			(end -0.7874 0.4064)
			(stroke
				(width 0.1524)
				(type default)
			)
			(layer "F.SilkS")
		)
		(fp_line
			(start -0.7874 -0.4064)
			(end 0.7874 -0.4064)
			(stroke
				(width 0.1524)
				(type default)
			)
			(layer "F.SilkS")
		)
		(fp_line
			(start 0.7874 -0.4064)
			(end 0.7874 0.4064)
			(stroke
				(width 0.1524)
				(type default)
			)
			(layer "F.SilkS")
		)
		(fp_line
			(start -0.67945 0.3048)
			(end -0.67945 -0.305054)
			(stroke
				(width 0.1)
				(type default)
			)
			(layer "F.Fab")
		)
		(fp_line
			(start -0.12065 0.3048)
			(end -0.67945 0.3048)
			(stroke
				(width 0.1)
				(type default)
			)
			(layer "F.Fab")
		)
		(fp_line
			(start 0.120396 0.3048)
			(end 0.120396 0.2794)
			(stroke
				(width 0.1)
				(type default)
			)
			(layer "F.Fab")
		)
		(fp_line
			(start 0.67945 0.3048)
			(end 0.120396 0.3048)
			(stroke
				(width 0.1)
				(type default)
			)
			(layer "F.Fab")
		)
		(fp_line
			(start -0.12065 0.2794)
			(end -0.12065 0.3048)
			(stroke
				(width 0.1)
				(type default)
			)
			(layer "F.Fab")
		)
		(fp_line
			(start 0.120396 0.2794)
			(end -0.12065 0.2794)
			(stroke
				(width 0.1)
				(type default)
			)
			(layer "F.Fab")
		)
		(fp_line
			(start -0.12065 -0.2794)
			(end 0.12065 -0.2794)
			(stroke
				(width 0.1)
				(type default)
			)
			(layer "F.Fab")
		)
		(fp_line
			(start 0.12065 -0.2794)
			(end 0.12065 -0.3048)
			(stroke
				(width 0.1)
				(type default)
			)
			(layer "F.Fab")
		)
		(fp_line
			(start 0.12065 -0.3048)
			(end 0.67945 -0.3048)
			(stroke
				(width 0.1)
				(type default)
			)
			(layer "F.Fab")
		)
		(fp_line
			(start 0.67945 -0.3048)
			(end 0.67945 0.3048)
			(stroke
				(width 0.1)
				(type default)
			)
			(layer "F.Fab")
		)
		(fp_line
			(start -0.67945 -0.305054)
			(end -0.12065 -0.305054)
			(stroke
				(width 0.1)
				(type default)
			)
			(layer "F.Fab")
		)
		(fp_line
			(start -0.12065 -0.305054)
			(end -0.12065 -0.2794)
			(stroke
				(width 0.1)
				(type default)
			)
			(layer "F.Fab")
		)
		(pad "1" smd circle
			(at -0.40005 0 270)
			(size 0 0)
			(layers "F.Cu" "F.Mask" "F.Paste")
			(net "RST_PEX3_S0_PERST_N")
		)
		(pad "2" smd circle
			(at 0.40005 0 270)
			(size 0 0)
			(layers "F.Cu" "F.Mask" "F.Paste")
			(net "RST_PEX3_S0_PERST_R_N")
		)
	)
	(footprint ""
		(layer "F.Cu")
		(at 101.22408 -246.83212)
		(property "Reference" "R821"
			(at 0 0 0)
			(layer "F.SilkS")
			(hide yes)
			(effects
				(font
					(size 1.27 1.27)
				)
			)
		)
		(property "Value" ""
			(at 0 0 0)
			(layer "F.Fab")
			(effects
				(font
					(size 1.27 1.27)
				)
			)
		)
		(duplicate_pad_numbers_are_jumpers no)
		(fp_line
			(start -0.7874 -0.4064)
			(end 0.7874 -0.4064)
			(stroke
				(width 0.1524)
				(type default)
			)
			(layer "F.SilkS")
		)
		(fp_line
			(start -0.7874 0.4064)
			(end -0.7874 -0.4064)
			(stroke
				(width 0.1524)
				(type default)
			)
			(layer "F.SilkS")
		)
		(fp_line
			(start 0.7874 -0.4064)
			(end 0.7874 0.4064)
			(stroke
				(width 0.1524)
				(type default)
			)
			(layer "F.SilkS")
		)
		(fp_line
			(start 0.7874 0.4064)
			(end -0.7874 0.4064)
			(stroke
				(width 0.1524)
				(type default)
			)
			(layer "F.SilkS")
		)
		(fp_line
			(start -0.67945 -0.305054)
			(end -0.12065 -0.305054)
			(stroke
				(width 0.1)
				(type default)
			)
			(layer "F.Fab")
		)
		(fp_line
			(start -0.67945 0.3048)
			(end -0.67945 -0.305054)
			(stroke
				(width 0.1)
				(type default)
			)
			(layer "F.Fab")
		)
		(fp_line
			(start -0.12065 -0.305054)
			(end -0.12065 -0.2794)
			(stroke
				(width 0.1)
				(type default)
			)
			(layer "F.Fab")
		)
		(fp_line
			(start -0.12065 -0.2794)
			(end 0.12065 -0.2794)
			(stroke
				(width 0.1)
				(type default)
			)
			(layer "F.Fab")
		)
		(fp_line
			(start -0.12065 0.2794)
			(end -0.12065 0.3048)
			(stroke
				(width 0.1)
				(type default)
			)
			(layer "F.Fab")
		)
		(fp_line
			(start -0.12065 0.3048)
			(end -0.67945 0.3048)
			(stroke
				(width 0.1)
				(type default)
			)
			(layer "F.Fab")
		)
		(fp_line
			(start 0.120396 0.2794)
			(end -0.12065 0.2794)
			(stroke
				(width 0.1)
				(type default)
			)
			(layer "F.Fab")
		)
		(fp_line
			(start 0.120396 0.3048)
			(end 0.120396 0.2794)
			(stroke
				(width 0.1)
				(type default)
			)
			(layer "F.Fab")
		)
		(fp_line
			(start 0.12065 -0.3048)
			(end 0.67945 -0.3048)
			(stroke
				(width 0.1)
				(type default)
			)
			(layer "F.Fab")
		)
		(fp_line
			(start 0.12065 -0.2794)
			(end 0.12065 -0.3048)
			(stroke
				(width 0.1)
				(type default)
			)
			(layer "F.Fab")
		)
		(fp_line
			(start 0.67945 -0.3048)
			(end 0.67945 0.3048)
			(stroke
				(width 0.1)
				(type default)
			)
			(layer "F.Fab")
		)
		(fp_line
			(start 0.67945 0.3048)
			(end 0.120396 0.3048)
			(stroke
				(width 0.1)
				(type default)
			)
			(layer "F.Fab")
		)
		(pad "1" smd circle
			(at -0.40005 0)
			(size 0 0)
			(layers "F.Cu" "F.Mask" "F.Paste")
			(net "P1V8_PEX_R")
		)
		(pad "2" smd circle
			(at 0.40005 0)
			(size 0 0)
			(layers "F.Cu" "F.Mask" "F.Paste")
			(net "P12V_PEX_P1V8_VIN_P")
		)
	)
	(footprint ""
		(layer "F.Cu")
		(at 239.47247 -55.80507 90)
		(property "Reference" "PR273"
			(at 0 0 90)
			(layer "F.SilkS")
			(hide yes)
			(effects
				(font
					(size 1.27 1.27)
				)
			)
		)
		(property "Value" ""
			(at 0 0 90)
			(layer "F.Fab")
			(effects
				(font
					(size 1.27 1.27)
				)
			)
		)
		(duplicate_pad_numbers_are_jumpers no)
		(fp_line
			(start 0.7874 -0.4064)
			(end 0.7874 0.4064)
			(stroke
				(width 0.1524)
				(type default)
			)
			(layer "F.SilkS")
		)
		(fp_line
			(start -0.7874 -0.4064)
			(end 0.7874 -0.4064)
			(stroke
				(width 0.1524)
				(type default)
			)
			(layer "F.SilkS")
		)
		(fp_line
			(start 0.7874 0.4064)
			(end -0.7874 0.4064)
			(stroke
				(width 0.1524)
				(type default)
			)
			(layer "F.SilkS")
		)
		(fp_line
			(start -0.7874 0.4064)
			(end -0.7874 -0.4064)
			(stroke
				(width 0.1524)
				(type default)
			)
			(layer "F.SilkS")
		)
		(fp_line
			(start -0.12065 -0.305054)
			(end -0.12065 -0.2794)
			(stroke
				(width 0.1)
				(type default)
			)
			(layer "F.Fab")
		)
		(fp_line
			(start -0.67945 -0.305054)
			(end -0.12065 -0.305054)
			(stroke
				(width 0.1)
				(type default)
			)
			(layer "F.Fab")
		)
		(fp_line
			(start 0.67945 -0.3048)
			(end 0.67945 0.3048)
			(stroke
				(width 0.1)
				(type default)
			)
			(layer "F.Fab")
		)
		(fp_line
			(start 0.12065 -0.3048)
			(end 0.67945 -0.3048)
			(stroke
				(width 0.1)
				(type default)
			)
			(layer "F.Fab")
		)
		(fp_line
			(start 0.12065 -0.2794)
			(end 0.12065 -0.3048)
			(stroke
				(width 0.1)
				(type default)
			)
			(layer "F.Fab")
		)
		(fp_line
			(start -0.12065 -0.2794)
			(end 0.12065 -0.2794)
			(stroke
				(width 0.1)
				(type default)
			)
			(layer "F.Fab")
		)
		(fp_line
			(start 0.120396 0.2794)
			(end -0.12065 0.2794)
			(stroke
				(width 0.1)
				(type default)
			)
			(layer "F.Fab")
		)
		(fp_line
			(start -0.12065 0.2794)
			(end -0.12065 0.3048)
			(stroke
				(width 0.1)
				(type default)
			)
			(layer "F.Fab")
		)
		(fp_line
			(start 0.67945 0.3048)
			(end 0.120396 0.3048)
			(stroke
				(width 0.1)
				(type default)
			)
			(layer "F.Fab")
		)
		(fp_line
			(start 0.120396 0.3048)
			(end 0.120396 0.2794)
			(stroke
				(width 0.1)
				(type default)
			)
			(layer "F.Fab")
		)
		(fp_line
			(start -0.12065 0.3048)
			(end -0.67945 0.3048)
			(stroke
				(width 0.1)
				(type default)
			)
			(layer "F.Fab")
		)
		(fp_line
			(start -0.67945 0.3048)
			(end -0.67945 -0.305054)
			(stroke
				(width 0.1)
				(type default)
			)
			(layer "F.Fab")
		)
		(pad "1" smd circle
			(at -0.40005 0 90)
			(size 0 0)
			(layers "F.Cu" "F.Mask" "F.Paste")
			(net "P3V3_SSD8_OCP")
		)
		(pad "2" smd circle
			(at 0.40005 0 90)
			(size 0 0)
			(layers "F.Cu" "F.Mask" "F.Paste")
			(net "GND")
		)
	)
	(footprint ""
		(layer "F.Cu")
		(at 400.567144 -57.332626)
		(property "Reference" "R6828"
			(at 0 0 0)
			(layer "F.SilkS")
			(hide yes)
			(effects
				(font
					(size 1.27 1.27)
				)
			)
		)
		(property "Value" ""
			(at 0 0 0)
			(layer "F.Fab")
			(effects
				(font
					(size 1.27 1.27)
				)
			)
		)
		(duplicate_pad_numbers_are_jumpers no)
		(fp_line
			(start -0.7874 -0.4064)
			(end 0.7874 -0.4064)
			(stroke
				(width 0.1524)
				(type default)
			)
			(layer "F.SilkS")
		)
		(fp_line
			(start -0.7874 0.4064)
			(end -0.7874 -0.4064)
			(stroke
				(width 0.1524)
				(type default)
			)
			(layer "F.SilkS")
		)
		(fp_line
			(start 0.7874 -0.4064)
			(end 0.7874 0.4064)
			(stroke
				(width 0.1524)
				(type default)
			)
			(layer "F.SilkS")
		)
		(fp_line
			(start 0.7874 0.4064)
			(end -0.7874 0.4064)
			(stroke
				(width 0.1524)
				(type default)
			)
			(layer "F.SilkS")
		)
		(fp_line
			(start -0.67945 -0.305054)
			(end -0.12065 -0.305054)
			(stroke
				(width 0.1)
				(type default)
			)
			(layer "F.Fab")
		)
		(fp_line
			(start -0.67945 0.3048)
			(end -0.67945 -0.305054)
			(stroke
				(width 0.1)
				(type default)
			)
			(layer "F.Fab")
		)
		(fp_line
			(start -0.12065 -0.305054)
			(end -0.12065 -0.2794)
			(stroke
				(width 0.1)
				(type default)
			)
			(layer "F.Fab")
		)
		(fp_line
			(start -0.12065 -0.2794)
			(end 0.12065 -0.2794)
			(stroke
				(width 0.1)
				(type default)
			)
			(layer "F.Fab")
		)
		(fp_line
			(start -0.12065 0.2794)
			(end -0.12065 0.3048)
			(stroke
				(width 0.1)
				(type default)
			)
			(layer "F.Fab")
		)
		(fp_line
			(start -0.12065 0.3048)
			(end -0.67945 0.3048)
			(stroke
				(width 0.1)
				(type default)
			)
			(layer "F.Fab")
		)
		(fp_line
			(start 0.120396 0.2794)
			(end -0.12065 0.2794)
			(stroke
				(width 0.1)
				(type default)
			)
			(layer "F.Fab")
		)
		(fp_line
			(start 0.120396 0.3048)
			(end 0.120396 0.2794)
			(stroke
				(width 0.1)
				(type default)
			)
			(layer "F.Fab")
		)
		(fp_line
			(start 0.12065 -0.3048)
			(end 0.67945 -0.3048)
			(stroke
				(width 0.1)
				(type default)
			)
			(layer "F.Fab")
		)
		(fp_line
			(start 0.12065 -0.2794)
			(end 0.12065 -0.3048)
			(stroke
				(width 0.1)
				(type default)
			)
			(layer "F.Fab")
		)
		(fp_line
			(start 0.67945 -0.3048)
			(end 0.67945 0.3048)
			(stroke
				(width 0.1)
				(type default)
			)
			(layer "F.Fab")
		)
		(fp_line
			(start 0.67945 0.3048)
			(end 0.120396 0.3048)
			(stroke
				(width 0.1)
				(type default)
			)
			(layer "F.Fab")
		)
		(pad "1" smd circle
			(at -0.40005 0)
			(size 0 0)
			(layers "F.Cu" "F.Mask" "F.Paste")
			(net "SSD13_PWR_EN_R")
		)
		(pad "2" smd circle
			(at 0.40005 0)
			(size 0 0)
			(layers "F.Cu" "F.Mask" "F.Paste")
			(net "GND")
		)
	)
	(footprint ""
		(layer "F.Cu")
		(at 397.146018 -46.4439 180)
		(property "Reference" "U76"
			(at 0.550418 -2.40157 0)
			(unlocked yes)
			(layer "F.SilkS")
			(effects
				(font
					(size 0.7874 0.5842)
					(thickness 0.1524)
				)
			)
		)
		(property "Value" ""
			(at 0 0 180)
			(layer "F.Fab")
			(effects
				(font
					(size 1.27 1.27)
				)
			)
		)
		(duplicate_pad_numbers_are_jumpers no)
		(fp_line
			(start 1.500124 1.500124)
			(end 1.004062 1.500124)
			(stroke
				(width 0.1524)
				(type default)
			)
			(layer "F.SilkS")
		)
		(fp_line
			(start 1.500124 1.004062)
			(end 1.500124 1.500124)
			(stroke
				(width 0.1524)
				(type default)
			)
			(layer "F.SilkS")
		)
		(fp_line
			(start 1.500124 -1.500124)
			(end 1.500124 -1.004062)
			(stroke
				(width 0.1524)
				(type default)
			)
			(layer "F.SilkS")
		)
		(fp_line
			(start 1.004062 -1.500124)
			(end 1.500124 -1.500124)
			(stroke
				(width 0.1524)
				(type default)
			)
			(layer "F.SilkS")
		)
		(fp_line
			(start -1.004062 1.500124)
			(end -1.500124 1.500124)
			(stroke
				(width 0.1524)
				(type default)
			)
			(layer "F.SilkS")
		)
		(fp_line
			(start -1.500124 1.500124)
			(end -1.500124 1.004062)
			(stroke
				(width 0.1524)
				(type default)
			)
			(layer "F.SilkS")
		)
		(fp_line
			(start -1.500124 -1.004062)
			(end -1.500124 -1.500124)
			(stroke
				(width 0.1524)
				(type default)
			)
			(layer "F.SilkS")
		)
		(fp_line
			(start -1.500124 -1.500124)
			(end -1.004062 -1.500124)
			(stroke
				(width 0.1524)
				(type default)
			)
			(layer "F.SilkS")
		)
		(fp_poly
			(pts
				(xy -1.945894 -2.155952) (xy -2.664206 -1.43764) (xy -1.586738 -1.078484)
			)
			(stroke
				(width 0)
				(type default)
			)
			(fill yes)
			(layer "F.SilkS")
		)
		(fp_line
			(start 1.500124 1.500124)
			(end -1.500124 1.500124)
			(stroke
				(width 0.1)
				(type default)
			)
			(layer "F.Fab")
		)
		(fp_line
			(start 1.500124 -1.500124)
			(end 1.500124 1.500124)
			(stroke
				(width 0.1)
				(type default)
			)
			(layer "F.Fab")
		)
		(fp_line
			(start -1.500124 1.500124)
			(end -1.500124 -1.500124)
			(stroke
				(width 0.1)
				(type default)
			)
			(layer "F.Fab")
		)
		(fp_line
			(start -1.500124 -1.500124)
			(end 1.500124 -1.500124)
			(stroke
				(width 0.1)
				(type default)
			)
			(layer "F.Fab")
		)
		(fp_poly
			(pts
				(xy -2.847848 -1.258062) (xy -2.847848 -0.242062) (xy -1.831848 -0.750062)
			)
			(stroke
				(width 0)
				(type default)
			)
			(fill yes)
			(layer "F.Fab")
		)
		(pad "1" smd rect
			(at -1.400048 -0.750062 90)
			(size 0.2286 0.6096)
			(layers "F.Cu" "F.Mask" "F.Paste")
			(net "SSD13_ADC_A1")
		)
		(pad "2" smd rect
			(at -1.400048 -0.249936 90)
			(size 0.2286 0.6096)
			(layers "F.Cu" "F.Mask" "F.Paste")
			(net "SSD13_ADC_A0")
		)
		(pad "3" smd rect
			(at -1.400048 0.249936 90)
			(size 0.2286 0.6096)
			(layers "F.Cu" "F.Mask" "F.Paste")
			(net "SSD13_ADC_ALERT_N")
		)
		(pad "4" smd rect
			(at -1.400048 0.750062 90)
			(size 0.2286 0.6096)
			(layers "F.Cu" "F.Mask" "F.Paste")
			(net "SMB_SSD13_ADC_SDA")
		)
		(pad "5" smd rect
			(at -0.750062 1.400048 180)
			(size 0.2286 0.6096)
			(layers "F.Cu" "F.Mask" "F.Paste")
			(net "SMB_SSD13_ADC_SCL")
		)
		(pad "6" smd rect
			(at -0.249936 1.400048 180)
			(size 0.2286 0.6096)
			(layers "F.Cu" "F.Mask" "F.Paste")
			(net "Net_8684")
		)
		(pad "7" smd rect
			(at 0.249936 1.400048 180)
			(size 0.2286 0.6096)
			(layers "F.Cu" "F.Mask" "F.Paste")
			(net "Net_8683")
		)
		(pad "8" smd rect
			(at 0.750062 1.400048 180)
			(size 0.2286 0.6096)
			(layers "F.Cu" "F.Mask" "F.Paste")
			(net "Net_8682")
		)
		(pad "9" smd rect
			(at 1.400048 0.750062 90)
			(size 0.2286 0.6096)
			(layers "F.Cu" "F.Mask" "F.Paste")
			(net "P3V3_AUX")
		)
		(pad "10" smd rect
			(at 1.400048 0.249936 90)
			(size 0.2286 0.6096)
			(layers "F.Cu" "F.Mask" "F.Paste")
			(net "GND")
		)
		(pad "11" smd rect
			(at 1.400048 -0.249936 90)
			(size 0.2286 0.6096)
			(layers "F.Cu" "F.Mask" "F.Paste")
			(net "P12V_SSD13_R")
		)
		(pad "12" smd rect
			(at 1.400048 -0.750062 90)
			(size 0.2286 0.6096)
			(layers "F.Cu" "F.Mask" "F.Paste")
			(net "P12V_SSD13_VIN_N")
		)
		(pad "13" smd rect
			(at 0.750062 -1.400048 180)
			(size 0.2286 0.6096)
			(layers "F.Cu" "F.Mask" "F.Paste")
			(net "P12V_SSD13_VIN_P")
		)
		(pad "14" smd rect
			(at 0.249936 -1.400048 180)
			(size 0.2286 0.6096)
			(layers "F.Cu" "F.Mask" "F.Paste")
			(net "Net_8681")
		)
		(pad "15" smd rect
			(at -0.249936 -1.400048 180)
			(size 0.2286 0.6096)
			(layers "F.Cu" "F.Mask" "F.Paste")
			(net "Net_8680")
		)
		(pad "16" smd rect
			(at -0.750062 -1.400048 180)
			(size 0.2286 0.6096)
			(layers "F.Cu" "F.Mask" "F.Paste")
			(net "Net_8679")
		)
		(pad "TH" smd rect
			(at 0 0 180)
			(size 1.7018 1.7018)
			(layers "F.Cu" "F.Mask" "F.Paste")
			(net "GND")
		)
		(zone
			(layer "F.Cu")
			(hatch none 0.5)
			(connect_pads
				(clearance 0)
			)
			(min_thickness 0.25)
			(keepout
				(tracks not_allowed)
				(vias allowed)
				(pads allowed)
				(copperpour not_allowed)
				(footprints allowed)
			)
			(placement
				(enabled no)
				(sheetname "")
			)
			(fill
				(thermal_gap 0.5)
				(thermal_bridge_width 0.5)
				(island_removal_mode 0)
			)
			(polygon
				(pts
					(xy 398.190466 -46.4185) (xy 398.190466 -45.399452) (xy 396.10157 -45.399452) (xy 396.10157 -47.488348)
					(xy 398.190466 -47.488348) (xy 398.190466 -46.4439) (xy 398.047718 -46.4439) (xy 398.047718 -47.3456)
					(xy 396.244318 -47.3456) (xy 396.244318 -45.5422) (xy 398.047718 -45.5422) (xy 398.047718 -46.4185)
				)
			)
		)
	)
	(footprint ""
		(layer "F.Cu")
		(at 122.809254 -27.04973 180)
		(property "Reference" "C2767"
			(at 0 0 180)
			(layer "F.SilkS")
			(hide yes)
			(effects
				(font
					(size 1.27 1.27)
				)
			)
		)
		(property "Value" ""
			(at 0 0 180)
			(layer "F.Fab")
			(effects
				(font
					(size 1.27 1.27)
				)
			)
		)
		(duplicate_pad_numbers_are_jumpers no)
		(fp_line
			(start 0.7874 0.4064)
			(end -0.7874 0.4064)
			(stroke
				(width 0.1524)
				(type default)
			)
			(layer "F.SilkS")
		)
		(fp_line
			(start 0.7874 -0.4064)
			(end 0.7874 0.4064)
			(stroke
				(width 0.1524)
				(type default)
			)
			(layer "F.SilkS")
		)
		(fp_line
			(start -0.7874 0.4064)
			(end -0.7874 -0.4064)
			(stroke
				(width 0.1524)
				(type default)
			)
			(layer "F.SilkS")
		)
		(fp_line
			(start -0.7874 -0.4064)
			(end 0.7874 -0.4064)
			(stroke
				(width 0.1524)
				(type default)
			)
			(layer "F.SilkS")
		)
		(fp_line
			(start 0.67945 0.3048)
			(end 0.120396 0.3048)
			(stroke
				(width 0.1)
				(type default)
			)
			(layer "F.Fab")
		)
		(fp_line
			(start 0.67945 -0.3048)
			(end 0.67945 0.3048)
			(stroke
				(width 0.1)
				(type default)
			)
			(layer "F.Fab")
		)
		(fp_line
			(start 0.12065 -0.2794)
			(end 0.12065 -0.3048)
			(stroke
				(width 0.1)
				(type default)
			)
			(layer "F.Fab")
		)
		(fp_line
			(start 0.12065 -0.3048)
			(end 0.67945 -0.3048)
			(stroke
				(width 0.1)
				(type default)
			)
			(layer "F.Fab")
		)
		(fp_line
			(start 0.120396 0.3048)
			(end 0.120396 0.2794)
			(stroke
				(width 0.1)
				(type default)
			)
			(layer "F.Fab")
		)
		(fp_line
			(start 0.120396 0.2794)
			(end -0.12065 0.2794)
			(stroke
				(width 0.1)
				(type default)
			)
			(layer "F.Fab")
		)
		(fp_line
			(start -0.12065 0.3048)
			(end -0.67945 0.3048)
			(stroke
				(width 0.1)
				(type default)
			)
			(layer "F.Fab")
		)
		(fp_line
			(start -0.12065 0.2794)
			(end -0.12065 0.3048)
			(stroke
				(width 0.1)
				(type default)
			)
			(layer "F.Fab")
		)
		(fp_line
			(start -0.12065 -0.2794)
			(end 0.12065 -0.2794)
			(stroke
				(width 0.1)
				(type default)
			)
			(layer "F.Fab")
		)
		(fp_line
			(start -0.12065 -0.305054)
			(end -0.12065 -0.2794)
			(stroke
				(width 0.1)
				(type default)
			)
			(layer "F.Fab")
		)
		(fp_line
			(start -0.67945 0.3048)
			(end -0.67945 -0.305054)
			(stroke
				(width 0.1)
				(type default)
			)
			(layer "F.Fab")
		)
		(fp_line
			(start -0.67945 -0.305054)
			(end -0.12065 -0.305054)
			(stroke
				(width 0.1)
				(type default)
			)
			(layer "F.Fab")
		)
		(pad "1" smd circle
			(at -0.40005 0 180)
			(size 0 0)
			(layers "F.Cu" "F.Mask" "F.Paste")
			(net "PRSNT_SSD4_R_N")
		)
		(pad "2" smd circle
			(at 0.40005 0 180)
			(size 0 0)
			(layers "F.Cu" "F.Mask" "F.Paste")
			(net "GND")
		)
	)
	(footprint ""
		(layer "F.Cu")
		(at 252.714506 -66.32194 90)
		(property "Reference" "R5990"
			(at 0 0 90)
			(layer "F.SilkS")
			(hide yes)
			(effects
				(font
					(size 1.27 1.27)
				)
			)
		)
		(property "Value" ""
			(at 0 0 90)
			(layer "F.Fab")
			(effects
				(font
					(size 1.27 1.27)
				)
			)
		)
		(duplicate_pad_numbers_are_jumpers no)
		(fp_line
			(start 0.7874 -0.4064)
			(end 0.7874 0.4064)
			(stroke
				(width 0.1524)
				(type default)
			)
			(layer "F.SilkS")
		)
		(fp_line
			(start -0.7874 -0.4064)
			(end 0.7874 -0.4064)
			(stroke
				(width 0.1524)
				(type default)
			)
			(layer "F.SilkS")
		)
		(fp_line
			(start 0.7874 0.4064)
			(end -0.7874 0.4064)
			(stroke
				(width 0.1524)
				(type default)
			)
			(layer "F.SilkS")
		)
		(fp_line
			(start -0.7874 0.4064)
			(end -0.7874 -0.4064)
			(stroke
				(width 0.1524)
				(type default)
			)
			(layer "F.SilkS")
		)
		(fp_line
			(start -0.12065 -0.305054)
			(end -0.12065 -0.2794)
			(stroke
				(width 0.1)
				(type default)
			)
			(layer "F.Fab")
		)
		(fp_line
			(start -0.67945 -0.305054)
			(end -0.12065 -0.305054)
			(stroke
				(width 0.1)
				(type default)
			)
			(layer "F.Fab")
		)
		(fp_line
			(start 0.67945 -0.3048)
			(end 0.67945 0.3048)
			(stroke
				(width 0.1)
				(type default)
			)
			(layer "F.Fab")
		)
		(fp_line
			(start 0.12065 -0.3048)
			(end 0.67945 -0.3048)
			(stroke
				(width 0.1)
				(type default)
			)
			(layer "F.Fab")
		)
		(fp_line
			(start 0.12065 -0.2794)
			(end 0.12065 -0.3048)
			(stroke
				(width 0.1)
				(type default)
			)
			(layer "F.Fab")
		)
		(fp_line
			(start -0.12065 -0.2794)
			(end 0.12065 -0.2794)
			(stroke
				(width 0.1)
				(type default)
			)
			(layer "F.Fab")
		)
		(fp_line
			(start 0.120396 0.2794)
			(end -0.12065 0.2794)
			(stroke
				(width 0.1)
				(type default)
			)
			(layer "F.Fab")
		)
		(fp_line
			(start -0.12065 0.2794)
			(end -0.12065 0.3048)
			(stroke
				(width 0.1)
				(type default)
			)
			(layer "F.Fab")
		)
		(fp_line
			(start 0.67945 0.3048)
			(end 0.120396 0.3048)
			(stroke
				(width 0.1)
				(type default)
			)
			(layer "F.Fab")
		)
		(fp_line
			(start 0.120396 0.3048)
			(end 0.120396 0.2794)
			(stroke
				(width 0.1)
				(type default)
			)
			(layer "F.Fab")
		)
		(fp_line
			(start -0.12065 0.3048)
			(end -0.67945 0.3048)
			(stroke
				(width 0.1)
				(type default)
			)
			(layer "F.Fab")
		)
		(fp_line
			(start -0.67945 0.3048)
			(end -0.67945 -0.305054)
			(stroke
				(width 0.1)
				(type default)
			)
			(layer "F.Fab")
		)
		(pad "1" smd circle
			(at -0.40005 0 90)
			(size 0 0)
			(layers "F.Cu" "F.Mask" "F.Paste")
			(net "SSD8_PWR_EN_R")
		)
		(pad "2" smd circle
			(at 0.40005 0 90)
			(size 0 0)
			(layers "F.Cu" "F.Mask" "F.Paste")
			(net "P12V_SSD8_CO_EN")
		)
	)
	(footprint ""
		(layer "F.Cu")
		(at 202.036172 -306.049172 90)
		(property "Reference" "R3930"
			(at 0 0 90)
			(layer "F.SilkS")
			(hide yes)
			(effects
				(font
					(size 1.27 1.27)
				)
			)
		)
		(property "Value" ""
			(at 0 0 90)
			(layer "F.Fab")
			(effects
				(font
					(size 1.27 1.27)
				)
			)
		)
		(duplicate_pad_numbers_are_jumpers no)
		(fp_line
			(start 0.7874 -0.4064)
			(end 0.7874 0.4064)
			(stroke
				(width 0.1524)
				(type default)
			)
			(layer "F.SilkS")
		)
		(fp_line
			(start -0.7874 -0.4064)
			(end 0.7874 -0.4064)
			(stroke
				(width 0.1524)
				(type default)
			)
			(layer "F.SilkS")
		)
		(fp_line
			(start 0.7874 0.4064)
			(end -0.7874 0.4064)
			(stroke
				(width 0.1524)
				(type default)
			)
			(layer "F.SilkS")
		)
		(fp_line
			(start -0.7874 0.4064)
			(end -0.7874 -0.4064)
			(stroke
				(width 0.1524)
				(type default)
			)
			(layer "F.SilkS")
		)
		(fp_line
			(start -0.12065 -0.305054)
			(end -0.12065 -0.2794)
			(stroke
				(width 0.1)
				(type default)
			)
			(layer "F.Fab")
		)
		(fp_line
			(start -0.67945 -0.305054)
			(end -0.12065 -0.305054)
			(stroke
				(width 0.1)
				(type default)
			)
			(layer "F.Fab")
		)
		(fp_line
			(start 0.67945 -0.3048)
			(end 0.67945 0.3048)
			(stroke
				(width 0.1)
				(type default)
			)
			(layer "F.Fab")
		)
		(fp_line
			(start 0.12065 -0.3048)
			(end 0.67945 -0.3048)
			(stroke
				(width 0.1)
				(type default)
			)
			(layer "F.Fab")
		)
		(fp_line
			(start 0.12065 -0.2794)
			(end 0.12065 -0.3048)
			(stroke
				(width 0.1)
				(type default)
			)
			(layer "F.Fab")
		)
		(fp_line
			(start -0.12065 -0.2794)
			(end 0.12065 -0.2794)
			(stroke
				(width 0.1)
				(type default)
			)
			(layer "F.Fab")
		)
		(fp_line
			(start 0.120396 0.2794)
			(end -0.12065 0.2794)
			(stroke
				(width 0.1)
				(type default)
			)
			(layer "F.Fab")
		)
		(fp_line
			(start -0.12065 0.2794)
			(end -0.12065 0.3048)
			(stroke
				(width 0.1)
				(type default)
			)
			(layer "F.Fab")
		)
		(fp_line
			(start 0.67945 0.3048)
			(end 0.120396 0.3048)
			(stroke
				(width 0.1)
				(type default)
			)
			(layer "F.Fab")
		)
		(fp_line
			(start 0.120396 0.3048)
			(end 0.120396 0.2794)
			(stroke
				(width 0.1)
				(type default)
			)
			(layer "F.Fab")
		)
		(fp_line
			(start -0.12065 0.3048)
			(end -0.67945 0.3048)
			(stroke
				(width 0.1)
				(type default)
			)
			(layer "F.Fab")
		)
		(fp_line
			(start -0.67945 0.3048)
			(end -0.67945 -0.305054)
			(stroke
				(width 0.1)
				(type default)
			)
			(layer "F.Fab")
		)
		(pad "1" smd circle
			(at -0.40005 0 90)
			(size 0 0)
			(layers "F.Cu" "F.Mask" "F.Paste")
			(net "SMB_PEX1_SLAVE_SCL")
		)
		(pad "2" smd circle
			(at 0.40005 0 90)
			(size 0 0)
			(layers "F.Cu" "F.Mask" "F.Paste")
			(net "SMB_PEX1_R_SCL")
		)
	)
	(footprint ""
		(layer "F.Cu")
		(at 202.652376 -364.885986 180)
		(property "Reference" "PC3"
			(at 0 0 180)
			(layer "F.SilkS")
			(hide yes)
			(effects
				(font
					(size 1.27 1.27)
				)
			)
		)
		(property "Value" ""
			(at 0 0 180)
			(layer "F.Fab")
			(effects
				(font
					(size 1.27 1.27)
				)
			)
		)
		(duplicate_pad_numbers_are_jumpers no)
		(fp_line
			(start 0.7874 0.4064)
			(end -0.7874 0.4064)
			(stroke
				(width 0.1524)
				(type default)
			)
			(layer "F.SilkS")
		)
		(fp_line
			(start 0.7874 -0.4064)
			(end 0.7874 0.4064)
			(stroke
				(width 0.1524)
				(type default)
			)
			(layer "F.SilkS")
		)
		(fp_line
			(start -0.7874 0.4064)
			(end -0.7874 -0.4064)
			(stroke
				(width 0.1524)
				(type default)
			)
			(layer "F.SilkS")
		)
		(fp_line
			(start -0.7874 -0.4064)
			(end 0.7874 -0.4064)
			(stroke
				(width 0.1524)
				(type default)
			)
			(layer "F.SilkS")
		)
		(fp_line
			(start 0.67945 0.3048)
			(end 0.120396 0.3048)
			(stroke
				(width 0.1)
				(type default)
			)
			(layer "F.Fab")
		)
		(fp_line
			(start 0.67945 -0.3048)
			(end 0.67945 0.3048)
			(stroke
				(width 0.1)
				(type default)
			)
			(layer "F.Fab")
		)
		(fp_line
			(start 0.12065 -0.2794)
			(end 0.12065 -0.3048)
			(stroke
				(width 0.1)
				(type default)
			)
			(layer "F.Fab")
		)
		(fp_line
			(start 0.12065 -0.3048)
			(end 0.67945 -0.3048)
			(stroke
				(width 0.1)
				(type default)
			)
			(layer "F.Fab")
		)
		(fp_line
			(start 0.120396 0.3048)
			(end 0.120396 0.2794)
			(stroke
				(width 0.1)
				(type default)
			)
			(layer "F.Fab")
		)
		(fp_line
			(start 0.120396 0.2794)
			(end -0.12065 0.2794)
			(stroke
				(width 0.1)
				(type default)
			)
			(layer "F.Fab")
		)
		(fp_line
			(start -0.12065 0.3048)
			(end -0.67945 0.3048)
			(stroke
				(width 0.1)
				(type default)
			)
			(layer "F.Fab")
		)
		(fp_line
			(start -0.12065 0.2794)
			(end -0.12065 0.3048)
			(stroke
				(width 0.1)
				(type default)
			)
			(layer "F.Fab")
		)
		(fp_line
			(start -0.12065 -0.2794)
			(end 0.12065 -0.2794)
			(stroke
				(width 0.1)
				(type default)
			)
			(layer "F.Fab")
		)
		(fp_line
			(start -0.12065 -0.305054)
			(end -0.12065 -0.2794)
			(stroke
				(width 0.1)
				(type default)
			)
			(layer "F.Fab")
		)
		(fp_line
			(start -0.67945 0.3048)
			(end -0.67945 -0.305054)
			(stroke
				(width 0.1)
				(type default)
			)
			(layer "F.Fab")
		)
		(fp_line
			(start -0.67945 -0.305054)
			(end -0.12065 -0.305054)
			(stroke
				(width 0.1)
				(type default)
			)
			(layer "F.Fab")
		)
		(pad "1" smd circle
			(at -0.40005 0 180)
			(size 0 0)
			(layers "F.Cu" "F.Mask" "F.Paste")
			(net "HSC_VOSEN")
		)
		(pad "2" smd circle
			(at 0.40005 0 180)
			(size 0 0)
			(layers "F.Cu" "F.Mask" "F.Paste")
			(net "AGND_HSC")
		)
	)
	(footprint ""
		(layer "F.Cu")
		(at 229.594664 -204.44206 -90)
		(property "Reference" "R458"
			(at 0 0 270)
			(layer "F.SilkS")
			(hide yes)
			(effects
				(font
					(size 1.27 1.27)
				)
			)
		)
		(property "Value" ""
			(at 0 0 270)
			(layer "F.Fab")
			(effects
				(font
					(size 1.27 1.27)
				)
			)
		)
		(duplicate_pad_numbers_are_jumpers no)
		(fp_line
			(start -0.7874 0.4064)
			(end -0.7874 -0.4064)
			(stroke
				(width 0.1524)
				(type default)
			)
			(layer "F.SilkS")
		)
		(fp_line
			(start 0.7874 0.4064)
			(end -0.7874 0.4064)
			(stroke
				(width 0.1524)
				(type default)
			)
			(layer "F.SilkS")
		)
		(fp_line
			(start -0.7874 -0.4064)
			(end 0.7874 -0.4064)
			(stroke
				(width 0.1524)
				(type default)
			)
			(layer "F.SilkS")
		)
		(fp_line
			(start 0.7874 -0.4064)
			(end 0.7874 0.4064)
			(stroke
				(width 0.1524)
				(type default)
			)
			(layer "F.SilkS")
		)
		(fp_line
			(start -0.67945 0.3048)
			(end -0.67945 -0.305054)
			(stroke
				(width 0.1)
				(type default)
			)
			(layer "F.Fab")
		)
		(fp_line
			(start -0.12065 0.3048)
			(end -0.67945 0.3048)
			(stroke
				(width 0.1)
				(type default)
			)
			(layer "F.Fab")
		)
		(fp_line
			(start 0.120396 0.3048)
			(end 0.120396 0.2794)
			(stroke
				(width 0.1)
				(type default)
			)
			(layer "F.Fab")
		)
		(fp_line
			(start 0.67945 0.3048)
			(end 0.120396 0.3048)
			(stroke
				(width 0.1)
				(type default)
			)
			(layer "F.Fab")
		)
		(fp_line
			(start -0.12065 0.2794)
			(end -0.12065 0.3048)
			(stroke
				(width 0.1)
				(type default)
			)
			(layer "F.Fab")
		)
		(fp_line
			(start 0.120396 0.2794)
			(end -0.12065 0.2794)
			(stroke
				(width 0.1)
				(type default)
			)
			(layer "F.Fab")
		)
		(fp_line
			(start -0.12065 -0.2794)
			(end 0.12065 -0.2794)
			(stroke
				(width 0.1)
				(type default)
			)
			(layer "F.Fab")
		)
		(fp_line
			(start 0.12065 -0.2794)
			(end 0.12065 -0.3048)
			(stroke
				(width 0.1)
				(type default)
			)
			(layer "F.Fab")
		)
		(fp_line
			(start 0.12065 -0.3048)
			(end 0.67945 -0.3048)
			(stroke
				(width 0.1)
				(type default)
			)
			(layer "F.Fab")
		)
		(fp_line
			(start 0.67945 -0.3048)
			(end 0.67945 0.3048)
			(stroke
				(width 0.1)
				(type default)
			)
			(layer "F.Fab")
		)
		(fp_line
			(start -0.67945 -0.305054)
			(end -0.12065 -0.305054)
			(stroke
				(width 0.1)
				(type default)
			)
			(layer "F.Fab")
		)
		(fp_line
			(start -0.12065 -0.305054)
			(end -0.12065 -0.2794)
			(stroke
				(width 0.1)
				(type default)
			)
			(layer "F.Fab")
		)
		(pad "1" smd circle
			(at -0.40005 0 270)
			(size 0 0)
			(layers "F.Cu" "F.Mask" "F.Paste")
			(net "SPI_BIC1_CS0_N")
		)
		(pad "2" smd circle
			(at 0.40005 0 270)
			(size 0 0)
			(layers "F.Cu" "F.Mask" "F.Paste")
			(net "SPI_BIC1_CS0_R_N")
		)
	)
	(footprint ""
		(layer "F.Cu")
		(at 419.089586 -239.302544 180)
		(property "Reference" "R6619"
			(at 0 0 180)
			(layer "F.SilkS")
			(hide yes)
			(effects
				(font
					(size 1.27 1.27)
				)
			)
		)
		(property "Value" ""
			(at 0 0 180)
			(layer "F.Fab")
			(effects
				(font
					(size 1.27 1.27)
				)
			)
		)
		(duplicate_pad_numbers_are_jumpers no)
		(fp_line
			(start 0.7874 0.4064)
			(end -0.7874 0.4064)
			(stroke
				(width 0.1524)
				(type default)
			)
			(layer "F.SilkS")
		)
		(fp_line
			(start 0.7874 -0.4064)
			(end 0.7874 0.4064)
			(stroke
				(width 0.1524)
				(type default)
			)
			(layer "F.SilkS")
		)
		(fp_line
			(start -0.7874 0.4064)
			(end -0.7874 -0.4064)
			(stroke
				(width 0.1524)
				(type default)
			)
			(layer "F.SilkS")
		)
		(fp_line
			(start -0.7874 -0.4064)
			(end 0.7874 -0.4064)
			(stroke
				(width 0.1524)
				(type default)
			)
			(layer "F.SilkS")
		)
		(fp_line
			(start 0.67945 0.3048)
			(end 0.120396 0.3048)
			(stroke
				(width 0.1)
				(type default)
			)
			(layer "F.Fab")
		)
		(fp_line
			(start 0.67945 -0.3048)
			(end 0.67945 0.3048)
			(stroke
				(width 0.1)
				(type default)
			)
			(layer "F.Fab")
		)
		(fp_line
			(start 0.12065 -0.2794)
			(end 0.12065 -0.3048)
			(stroke
				(width 0.1)
				(type default)
			)
			(layer "F.Fab")
		)
		(fp_line
			(start 0.12065 -0.3048)
			(end 0.67945 -0.3048)
			(stroke
				(width 0.1)
				(type default)
			)
			(layer "F.Fab")
		)
		(fp_line
			(start 0.120396 0.3048)
			(end 0.120396 0.2794)
			(stroke
				(width 0.1)
				(type default)
			)
			(layer "F.Fab")
		)
		(fp_line
			(start 0.120396 0.2794)
			(end -0.12065 0.2794)
			(stroke
				(width 0.1)
				(type default)
			)
			(layer "F.Fab")
		)
		(fp_line
			(start -0.12065 0.3048)
			(end -0.67945 0.3048)
			(stroke
				(width 0.1)
				(type default)
			)
			(layer "F.Fab")
		)
		(fp_line
			(start -0.12065 0.2794)
			(end -0.12065 0.3048)
			(stroke
				(width 0.1)
				(type default)
			)
			(layer "F.Fab")
		)
		(fp_line
			(start -0.12065 -0.2794)
			(end 0.12065 -0.2794)
			(stroke
				(width 0.1)
				(type default)
			)
			(layer "F.Fab")
		)
		(fp_line
			(start -0.12065 -0.305054)
			(end -0.12065 -0.2794)
			(stroke
				(width 0.1)
				(type default)
			)
			(layer "F.Fab")
		)
		(fp_line
			(start -0.67945 0.3048)
			(end -0.67945 -0.305054)
			(stroke
				(width 0.1)
				(type default)
			)
			(layer "F.Fab")
		)
		(fp_line
			(start -0.67945 -0.305054)
			(end -0.12065 -0.305054)
			(stroke
				(width 0.1)
				(type default)
			)
			(layer "F.Fab")
		)
		(pad "1" smd circle
			(at -0.40005 0 180)
			(size 0 0)
			(layers "F.Cu" "F.Mask" "F.Paste")
			(net "UART_PEX2_SDB_R_RX")
		)
		(pad "2" smd circle
			(at 0.40005 0 180)
			(size 0 0)
			(layers "F.Cu" "F.Mask" "F.Paste")
			(net "UART_PEX2_SDB_R1_RX")
		)
	)
	(footprint ""
		(layer "F.Cu")
		(at 58.686192 -384.702812)
		(property "Reference" "R1834"
			(at 0 0 0)
			(layer "F.SilkS")
			(hide yes)
			(effects
				(font
					(size 1.27 1.27)
				)
			)
		)
		(property "Value" ""
			(at 0 0 0)
			(layer "F.Fab")
			(effects
				(font
					(size 1.27 1.27)
				)
			)
		)
		(duplicate_pad_numbers_are_jumpers no)
		(fp_line
			(start -0.7874 -0.4064)
			(end 0.7874 -0.4064)
			(stroke
				(width 0.1524)
				(type default)
			)
			(layer "F.SilkS")
		)
		(fp_line
			(start -0.7874 0.4064)
			(end -0.7874 -0.4064)
			(stroke
				(width 0.1524)
				(type default)
			)
			(layer "F.SilkS")
		)
		(fp_line
			(start 0.7874 -0.4064)
			(end 0.7874 0.4064)
			(stroke
				(width 0.1524)
				(type default)
			)
			(layer "F.SilkS")
		)
		(fp_line
			(start 0.7874 0.4064)
			(end -0.7874 0.4064)
			(stroke
				(width 0.1524)
				(type default)
			)
			(layer "F.SilkS")
		)
		(fp_line
			(start -0.67945 -0.305054)
			(end -0.12065 -0.305054)
			(stroke
				(width 0.1)
				(type default)
			)
			(layer "F.Fab")
		)
		(fp_line
			(start -0.67945 0.3048)
			(end -0.67945 -0.305054)
			(stroke
				(width 0.1)
				(type default)
			)
			(layer "F.Fab")
		)
		(fp_line
			(start -0.12065 -0.305054)
			(end -0.12065 -0.2794)
			(stroke
				(width 0.1)
				(type default)
			)
			(layer "F.Fab")
		)
		(fp_line
			(start -0.12065 -0.2794)
			(end 0.12065 -0.2794)
			(stroke
				(width 0.1)
				(type default)
			)
			(layer "F.Fab")
		)
		(fp_line
			(start -0.12065 0.2794)
			(end -0.12065 0.3048)
			(stroke
				(width 0.1)
				(type default)
			)
			(layer "F.Fab")
		)
		(fp_line
			(start -0.12065 0.3048)
			(end -0.67945 0.3048)
			(stroke
				(width 0.1)
				(type default)
			)
			(layer "F.Fab")
		)
		(fp_line
			(start 0.120396 0.2794)
			(end -0.12065 0.2794)
			(stroke
				(width 0.1)
				(type default)
			)
			(layer "F.Fab")
		)
		(fp_line
			(start 0.120396 0.3048)
			(end 0.120396 0.2794)
			(stroke
				(width 0.1)
				(type default)
			)
			(layer "F.Fab")
		)
		(fp_line
			(start 0.12065 -0.3048)
			(end 0.67945 -0.3048)
			(stroke
				(width 0.1)
				(type default)
			)
			(layer "F.Fab")
		)
		(fp_line
			(start 0.12065 -0.2794)
			(end 0.12065 -0.3048)
			(stroke
				(width 0.1)
				(type default)
			)
			(layer "F.Fab")
		)
		(fp_line
			(start 0.67945 -0.3048)
			(end 0.67945 0.3048)
			(stroke
				(width 0.1)
				(type default)
			)
			(layer "F.Fab")
		)
		(fp_line
			(start 0.67945 0.3048)
			(end 0.120396 0.3048)
			(stroke
				(width 0.1)
				(type default)
			)
			(layer "F.Fab")
		)
		(pad "1" smd circle
			(at -0.40005 0)
			(size 0 0)
			(layers "F.Cu" "F.Mask" "F.Paste")
			(net "GPU_PEX_STRAP1_R")
		)
		(pad "2" smd circle
			(at 0.40005 0)
			(size 0 0)
			(layers "F.Cu" "F.Mask" "F.Paste")
			(net "GPU_PEX_STRAP1")
		)
	)
	(footprint ""
		(layer "F.Cu")
		(at 131.39674 -118.378986 -90)
		(property "Reference" "R5954"
			(at 0 0 270)
			(layer "F.SilkS")
			(hide yes)
			(effects
				(font
					(size 1.27 1.27)
				)
			)
		)
		(property "Value" ""
			(at 0 0 270)
			(layer "F.Fab")
			(effects
				(font
					(size 1.27 1.27)
				)
			)
		)
		(duplicate_pad_numbers_are_jumpers no)
		(fp_line
			(start -0.7874 0.4064)
			(end -0.7874 -0.4064)
			(stroke
				(width 0.1524)
				(type default)
			)
			(layer "F.SilkS")
		)
		(fp_line
			(start 0.7874 0.4064)
			(end -0.7874 0.4064)
			(stroke
				(width 0.1524)
				(type default)
			)
			(layer "F.SilkS")
		)
		(fp_line
			(start -0.7874 -0.4064)
			(end 0.7874 -0.4064)
			(stroke
				(width 0.1524)
				(type default)
			)
			(layer "F.SilkS")
		)
		(fp_line
			(start 0.7874 -0.4064)
			(end 0.7874 0.4064)
			(stroke
				(width 0.1524)
				(type default)
			)
			(layer "F.SilkS")
		)
		(fp_line
			(start -0.67945 0.3048)
			(end -0.67945 -0.305054)
			(stroke
				(width 0.1)
				(type default)
			)
			(layer "F.Fab")
		)
		(fp_line
			(start -0.12065 0.3048)
			(end -0.67945 0.3048)
			(stroke
				(width 0.1)
				(type default)
			)
			(layer "F.Fab")
		)
		(fp_line
			(start 0.120396 0.3048)
			(end 0.120396 0.2794)
			(stroke
				(width 0.1)
				(type default)
			)
			(layer "F.Fab")
		)
		(fp_line
			(start 0.67945 0.3048)
			(end 0.120396 0.3048)
			(stroke
				(width 0.1)
				(type default)
			)
			(layer "F.Fab")
		)
		(fp_line
			(start -0.12065 0.2794)
			(end -0.12065 0.3048)
			(stroke
				(width 0.1)
				(type default)
			)
			(layer "F.Fab")
		)
		(fp_line
			(start 0.120396 0.2794)
			(end -0.12065 0.2794)
			(stroke
				(width 0.1)
				(type default)
			)
			(layer "F.Fab")
		)
		(fp_line
			(start -0.12065 -0.2794)
			(end 0.12065 -0.2794)
			(stroke
				(width 0.1)
				(type default)
			)
			(layer "F.Fab")
		)
		(fp_line
			(start 0.12065 -0.2794)
			(end 0.12065 -0.3048)
			(stroke
				(width 0.1)
				(type default)
			)
			(layer "F.Fab")
		)
		(fp_line
			(start 0.12065 -0.3048)
			(end 0.67945 -0.3048)
			(stroke
				(width 0.1)
				(type default)
			)
			(layer "F.Fab")
		)
		(fp_line
			(start 0.67945 -0.3048)
			(end 0.67945 0.3048)
			(stroke
				(width 0.1)
				(type default)
			)
			(layer "F.Fab")
		)
		(fp_line
			(start -0.67945 -0.305054)
			(end -0.12065 -0.305054)
			(stroke
				(width 0.1)
				(type default)
			)
			(layer "F.Fab")
		)
		(fp_line
			(start -0.12065 -0.305054)
			(end -0.12065 -0.2794)
			(stroke
				(width 0.1)
				(type default)
			)
			(layer "F.Fab")
		)
		(pad "1" smd circle
			(at -0.40005 0 270)
			(size 0 0)
			(layers "F.Cu" "F.Mask" "F.Paste")
			(net "HP_NIC2_EN")
		)
		(pad "2" smd circle
			(at 0.40005 0 270)
			(size 0 0)
			(layers "F.Cu" "F.Mask" "F.Paste")
			(net "P3V3_NIC2_CO_EN")
		)
	)
	(footprint ""
		(layer "F.Cu")
		(at 135.526018 -100.154486)
		(property "Reference" "C2709"
			(at 0 0 0)
			(layer "F.SilkS")
			(hide yes)
			(effects
				(font
					(size 1.27 1.27)
				)
			)
		)
		(property "Value" ""
			(at 0 0 0)
			(layer "F.Fab")
			(effects
				(font
					(size 1.27 1.27)
				)
			)
		)
		(duplicate_pad_numbers_are_jumpers no)
		(fp_line
			(start -0.7874 -0.4064)
			(end 0.7874 -0.4064)
			(stroke
				(width 0.1524)
				(type default)
			)
			(layer "F.SilkS")
		)
		(fp_line
			(start -0.7874 0.4064)
			(end -0.7874 -0.4064)
			(stroke
				(width 0.1524)
				(type default)
			)
			(layer "F.SilkS")
		)
		(fp_line
			(start 0.7874 -0.4064)
			(end 0.7874 0.4064)
			(stroke
				(width 0.1524)
				(type default)
			)
			(layer "F.SilkS")
		)
		(fp_line
			(start 0.7874 0.4064)
			(end -0.7874 0.4064)
			(stroke
				(width 0.1524)
				(type default)
			)
			(layer "F.SilkS")
		)
		(fp_line
			(start -0.67945 -0.305054)
			(end -0.12065 -0.305054)
			(stroke
				(width 0.1)
				(type default)
			)
			(layer "F.Fab")
		)
		(fp_line
			(start -0.67945 0.3048)
			(end -0.67945 -0.305054)
			(stroke
				(width 0.1)
				(type default)
			)
			(layer "F.Fab")
		)
		(fp_line
			(start -0.12065 -0.305054)
			(end -0.12065 -0.2794)
			(stroke
				(width 0.1)
				(type default)
			)
			(layer "F.Fab")
		)
		(fp_line
			(start -0.12065 -0.2794)
			(end 0.12065 -0.2794)
			(stroke
				(width 0.1)
				(type default)
			)
			(layer "F.Fab")
		)
		(fp_line
			(start -0.12065 0.2794)
			(end -0.12065 0.3048)
			(stroke
				(width 0.1)
				(type default)
			)
			(layer "F.Fab")
		)
		(fp_line
			(start -0.12065 0.3048)
			(end -0.67945 0.3048)
			(stroke
				(width 0.1)
				(type default)
			)
			(layer "F.Fab")
		)
		(fp_line
			(start 0.120396 0.2794)
			(end -0.12065 0.2794)
			(stroke
				(width 0.1)
				(type default)
			)
			(layer "F.Fab")
		)
		(fp_line
			(start 0.120396 0.3048)
			(end 0.120396 0.2794)
			(stroke
				(width 0.1)
				(type default)
			)
			(layer "F.Fab")
		)
		(fp_line
			(start 0.12065 -0.3048)
			(end 0.67945 -0.3048)
			(stroke
				(width 0.1)
				(type default)
			)
			(layer "F.Fab")
		)
		(fp_line
			(start 0.12065 -0.2794)
			(end 0.12065 -0.3048)
			(stroke
				(width 0.1)
				(type default)
			)
			(layer "F.Fab")
		)
		(fp_line
			(start 0.67945 -0.3048)
			(end 0.67945 0.3048)
			(stroke
				(width 0.1)
				(type default)
			)
			(layer "F.Fab")
		)
		(fp_line
			(start 0.67945 0.3048)
			(end 0.120396 0.3048)
			(stroke
				(width 0.1)
				(type default)
			)
			(layer "F.Fab")
		)
		(pad "1" smd circle
			(at -0.40005 0)
			(size 0 0)
			(layers "F.Cu" "F.Mask" "F.Paste")
			(net "P3V3_AUX")
		)
		(pad "2" smd circle
			(at 0.40005 0)
			(size 0 0)
			(layers "F.Cu" "F.Mask" "F.Paste")
			(net "GND")
		)
	)
	(footprint ""
		(layer "F.Cu")
		(at 224.851976 -373.090186)
		(property "Reference" "PR30"
			(at 0 0 0)
			(layer "F.SilkS")
			(hide yes)
			(effects
				(font
					(size 1.27 1.27)
				)
			)
		)
		(property "Value" ""
			(at 0 0 0)
			(layer "F.Fab")
			(effects
				(font
					(size 1.27 1.27)
				)
			)
		)
		(duplicate_pad_numbers_are_jumpers no)
		(fp_line
			(start -0.7874 -0.4064)
			(end 0.7874 -0.4064)
			(stroke
				(width 0.1524)
				(type default)
			)
			(layer "F.SilkS")
		)
		(fp_line
			(start -0.7874 0.4064)
			(end -0.7874 -0.4064)
			(stroke
				(width 0.1524)
				(type default)
			)
			(layer "F.SilkS")
		)
		(fp_line
			(start 0.7874 -0.4064)
			(end 0.7874 0.4064)
			(stroke
				(width 0.1524)
				(type default)
			)
			(layer "F.SilkS")
		)
		(fp_line
			(start 0.7874 0.4064)
			(end -0.7874 0.4064)
			(stroke
				(width 0.1524)
				(type default)
			)
			(layer "F.SilkS")
		)
		(fp_line
			(start -0.67945 -0.305054)
			(end -0.12065 -0.305054)
			(stroke
				(width 0.1)
				(type default)
			)
			(layer "F.Fab")
		)
		(fp_line
			(start -0.67945 0.3048)
			(end -0.67945 -0.305054)
			(stroke
				(width 0.1)
				(type default)
			)
			(layer "F.Fab")
		)
		(fp_line
			(start -0.12065 -0.305054)
			(end -0.12065 -0.2794)
			(stroke
				(width 0.1)
				(type default)
			)
			(layer "F.Fab")
		)
		(fp_line
			(start -0.12065 -0.2794)
			(end 0.12065 -0.2794)
			(stroke
				(width 0.1)
				(type default)
			)
			(layer "F.Fab")
		)
		(fp_line
			(start -0.12065 0.2794)
			(end -0.12065 0.3048)
			(stroke
				(width 0.1)
				(type default)
			)
			(layer "F.Fab")
		)
		(fp_line
			(start -0.12065 0.3048)
			(end -0.67945 0.3048)
			(stroke
				(width 0.1)
				(type default)
			)
			(layer "F.Fab")
		)
		(fp_line
			(start 0.120396 0.2794)
			(end -0.12065 0.2794)
			(stroke
				(width 0.1)
				(type default)
			)
			(layer "F.Fab")
		)
		(fp_line
			(start 0.120396 0.3048)
			(end 0.120396 0.2794)
			(stroke
				(width 0.1)
				(type default)
			)
			(layer "F.Fab")
		)
		(fp_line
			(start 0.12065 -0.3048)
			(end 0.67945 -0.3048)
			(stroke
				(width 0.1)
				(type default)
			)
			(layer "F.Fab")
		)
		(fp_line
			(start 0.12065 -0.2794)
			(end 0.12065 -0.3048)
			(stroke
				(width 0.1)
				(type default)
			)
			(layer "F.Fab")
		)
		(fp_line
			(start 0.67945 -0.3048)
			(end 0.67945 0.3048)
			(stroke
				(width 0.1)
				(type default)
			)
			(layer "F.Fab")
		)
		(fp_line
			(start 0.67945 0.3048)
			(end 0.120396 0.3048)
			(stroke
				(width 0.1)
				(type default)
			)
			(layer "F.Fab")
		)
		(pad "1" smd circle
			(at -0.40005 0)
			(size 0 0)
			(layers "F.Cu" "F.Mask" "F.Paste")
			(net "HSC_FLT_TYPE_1")
		)
		(pad "2" smd circle
			(at 0.40005 0)
			(size 0 0)
			(layers "F.Cu" "F.Mask" "F.Paste")
			(net "HSC_FLT_TYPE_R")
		)
	)
	(footprint ""
		(layer "F.Cu")
		(at 18.619978 -15.649956 180)
		(property "Reference" "H128"
			(at 1.35636 2.69621 0)
			(unlocked yes)
			(layer "B.SilkS")
			(effects
				(font
					(size 0.7874 0.5842)
					(thickness 0.1524)
				)
				(justify left mirror)
			)
		)
		(property "Value" ""
			(at 0 0 180)
			(layer "F.Fab")
			(effects
				(font
					(size 1.27 1.27)
				)
			)
		)
		(duplicate_pad_numbers_are_jumpers no)
		(pad "1" thru_hole rect
			(at 0 0 180)
			(size 4.2164 5.0038)
			(drill 2.0066
				(offset 0.099822 0)
			)
			(layers "*.Cu" "*.Mask")
			(remove_unused_layers no)
			(net "Net_8535")
			(clearance -0.8509)
			(padstack
				(mode front_inner_back)
				(layer "Inner"
					(shape circle)
					(size 4.0132 4.0132)
					(clearance -0.7493)
				)
				(layer "B.Cu"
					(shape circle)
					(size 4.0132 4.0132)
					(clearance -0.7493)
				)
			)
		)
	)
	(footprint ""
		(layer "F.Cu")
		(at 198.76135 -124.076714 180)
		(property "Reference" "C237"
			(at 0 0 180)
			(layer "F.SilkS")
			(hide yes)
			(effects
				(font
					(size 1.27 1.27)
				)
			)
		)
		(property "Value" ""
			(at 0 0 180)
			(layer "F.Fab")
			(effects
				(font
					(size 1.27 1.27)
				)
			)
		)
		(duplicate_pad_numbers_are_jumpers no)
		(fp_line
			(start 0.299974 0.150114)
			(end -0.299974 0.150114)
			(stroke
				(width 0.1)
				(type default)
			)
			(layer "F.Fab")
		)
		(fp_line
			(start 0.299974 -0.150114)
			(end 0.299974 0.150114)
			(stroke
				(width 0.1)
				(type default)
			)
			(layer "F.Fab")
		)
		(fp_line
			(start -0.299974 0.150114)
			(end -0.299974 -0.150114)
			(stroke
				(width 0.1)
				(type default)
			)
			(layer "F.Fab")
		)
		(fp_line
			(start -0.299974 -0.150114)
			(end 0.299974 -0.150114)
			(stroke
				(width 0.1)
				(type default)
			)
			(layer "F.Fab")
		)
		(pad "1" smd rect
			(at -0.2667 0 180)
			(size 0.3048 0.381)
			(layers "F.Cu" "F.Mask" "F.Paste")
			(net "P5E_PEX1_STN0_TX_DN<3>")
		)
		(pad "2" smd rect
			(at 0.2667 0 180)
			(size 0.3048 0.381)
			(layers "F.Cu" "F.Mask" "F.Paste")
			(net "P5E_PEX1_STN0_TX_C_DN<3>")
		)
	)
	(footprint ""
		(layer "F.Cu")
		(at 267.718286 -252.356874 -90)
		(property "Reference" "R1368"
			(at 0 0 270)
			(layer "F.SilkS")
			(hide yes)
			(effects
				(font
					(size 1.27 1.27)
				)
			)
		)
		(property "Value" ""
			(at 0 0 270)
			(layer "F.Fab")
			(effects
				(font
					(size 1.27 1.27)
				)
			)
		)
		(duplicate_pad_numbers_are_jumpers no)
		(fp_line
			(start -0.7874 0.4064)
			(end -0.7874 -0.4064)
			(stroke
				(width 0.1524)
				(type default)
			)
			(layer "F.SilkS")
		)
		(fp_line
			(start 0.7874 0.4064)
			(end -0.7874 0.4064)
			(stroke
				(width 0.1524)
				(type default)
			)
			(layer "F.SilkS")
		)
		(fp_line
			(start -0.7874 -0.4064)
			(end 0.7874 -0.4064)
			(stroke
				(width 0.1524)
				(type default)
			)
			(layer "F.SilkS")
		)
		(fp_line
			(start 0.7874 -0.4064)
			(end 0.7874 0.4064)
			(stroke
				(width 0.1524)
				(type default)
			)
			(layer "F.SilkS")
		)
		(fp_line
			(start -0.67945 0.3048)
			(end -0.67945 -0.305054)
			(stroke
				(width 0.1)
				(type default)
			)
			(layer "F.Fab")
		)
		(fp_line
			(start -0.12065 0.3048)
			(end -0.67945 0.3048)
			(stroke
				(width 0.1)
				(type default)
			)
			(layer "F.Fab")
		)
		(fp_line
			(start 0.120396 0.3048)
			(end 0.120396 0.2794)
			(stroke
				(width 0.1)
				(type default)
			)
			(layer "F.Fab")
		)
		(fp_line
			(start 0.67945 0.3048)
			(end 0.120396 0.3048)
			(stroke
				(width 0.1)
				(type default)
			)
			(layer "F.Fab")
		)
		(fp_line
			(start -0.12065 0.2794)
			(end -0.12065 0.3048)
			(stroke
				(width 0.1)
				(type default)
			)
			(layer "F.Fab")
		)
		(fp_line
			(start 0.120396 0.2794)
			(end -0.12065 0.2794)
			(stroke
				(width 0.1)
				(type default)
			)
			(layer "F.Fab")
		)
		(fp_line
			(start -0.12065 -0.2794)
			(end 0.12065 -0.2794)
			(stroke
				(width 0.1)
				(type default)
			)
			(layer "F.Fab")
		)
		(fp_line
			(start 0.12065 -0.2794)
			(end 0.12065 -0.3048)
			(stroke
				(width 0.1)
				(type default)
			)
			(layer "F.Fab")
		)
		(fp_line
			(start 0.12065 -0.3048)
			(end 0.67945 -0.3048)
			(stroke
				(width 0.1)
				(type default)
			)
			(layer "F.Fab")
		)
		(fp_line
			(start 0.67945 -0.3048)
			(end 0.67945 0.3048)
			(stroke
				(width 0.1)
				(type default)
			)
			(layer "F.Fab")
		)
		(fp_line
			(start -0.67945 -0.305054)
			(end -0.12065 -0.305054)
			(stroke
				(width 0.1)
				(type default)
			)
			(layer "F.Fab")
		)
		(fp_line
			(start -0.12065 -0.305054)
			(end -0.12065 -0.2794)
			(stroke
				(width 0.1)
				(type default)
			)
			(layer "F.Fab")
		)
		(pad "1" smd circle
			(at -0.40005 0 270)
			(size 0 0)
			(layers "F.Cu" "F.Mask" "F.Paste")
			(net "GND")
		)
		(pad "2" smd circle
			(at 0.40005 0 270)
			(size 0 0)
			(layers "F.Cu" "F.Mask" "F.Paste")
			(net "PEX2_MODE_SEL12")
		)
	)
	(footprint ""
		(layer "F.Cu")
		(at 133.599428 -343.952322 90)
		(property "Reference" "C2269"
			(at 0 0 90)
			(layer "F.SilkS")
			(hide yes)
			(effects
				(font
					(size 1.27 1.27)
				)
			)
		)
		(property "Value" ""
			(at 0 0 90)
			(layer "F.Fab")
			(effects
				(font
					(size 1.27 1.27)
				)
			)
		)
		(duplicate_pad_numbers_are_jumpers no)
		(fp_line
			(start 0.299974 -0.150114)
			(end 0.299974 0.150114)
			(stroke
				(width 0.1)
				(type default)
			)
			(layer "F.Fab")
		)
		(fp_line
			(start -0.299974 -0.150114)
			(end 0.299974 -0.150114)
			(stroke
				(width 0.1)
				(type default)
			)
			(layer "F.Fab")
		)
		(fp_line
			(start 0.299974 0.150114)
			(end -0.299974 0.150114)
			(stroke
				(width 0.1)
				(type default)
			)
			(layer "F.Fab")
		)
		(fp_line
			(start -0.299974 0.150114)
			(end -0.299974 -0.150114)
			(stroke
				(width 0.1)
				(type default)
			)
			(layer "F.Fab")
		)
		(pad "1" smd rect
			(at -0.2667 0 90)
			(size 0.3048 0.381)
			(layers "F.Cu" "F.Mask" "F.Paste")
			(net "P5E_PEX1_STN5_TX_DP<82>")
		)
		(pad "2" smd rect
			(at 0.2667 0 90)
			(size 0.3048 0.381)
			(layers "F.Cu" "F.Mask" "F.Paste")
			(net "P5E_PEX1_STN5_TX_C_DP<82>")
		)
	)
	(footprint ""
		(layer "F.Cu")
		(at 131.242816 -70.844918 -90)
		(property "Reference" "PD102"
			(at 3.839718 2.158746 90)
			(unlocked yes)
			(layer "F.SilkS")
			(effects
				(font
					(size 0.7874 0.5842)
					(thickness 0.1524)
				)
				(justify left)
			)
		)
		(property "Value" ""
			(at 0 0 270)
			(layer "F.Fab")
			(effects
				(font
					(size 1.27 1.27)
				)
			)
		)
		(duplicate_pad_numbers_are_jumpers no)
		(fp_line
			(start -3.400044 1.459992)
			(end -3.400044 -1.459992)
			(stroke
				(width 0.1524)
				(type default)
			)
			(layer "F.SilkS")
		)
		(fp_line
			(start 4.107942 1.459992)
			(end -3.400044 1.459992)
			(stroke
				(width 0.1524)
				(type default)
			)
			(layer "F.SilkS")
		)
		(fp_line
			(start -3.400044 -1.459992)
			(end 4.107942 -1.459992)
			(stroke
				(width 0.1524)
				(type default)
			)
			(layer "F.SilkS")
		)
		(fp_line
			(start 4.107942 -1.459992)
			(end 4.107942 1.459992)
			(stroke
				(width 0.1524)
				(type default)
			)
			(layer "F.SilkS")
		)
		(fp_poly
			(pts
				(xy 4.107942 -1.459992) (xy 4.107942 1.459992) (xy 3.308096 1.459992) (xy 3.308096 -1.459992)
			)
			(stroke
				(width 0)
				(type default)
			)
			(fill yes)
			(layer "F.SilkS")
		)
		(fp_line
			(start -2.29997 1.459992)
			(end -2.29997 -1.459992)
			(stroke
				(width 0.1)
				(type default)
			)
			(layer "F.Fab")
		)
		(fp_line
			(start 2.29997 1.459992)
			(end -2.29997 1.459992)
			(stroke
				(width 0.1)
				(type default)
			)
			(layer "F.Fab")
		)
		(fp_line
			(start -2.29997 -1.459992)
			(end 2.29997 -1.459992)
			(stroke
				(width 0.1)
				(type default)
			)
			(layer "F.Fab")
		)
		(fp_line
			(start 2.29997 -1.459992)
			(end 2.29997 1.459992)
			(stroke
				(width 0.1)
				(type default)
			)
			(layer "F.Fab")
		)
		(fp_text user "-"
			(at 5.4102 0.29845 90)
			(unlocked yes)
			(layer "F.SilkS")
			(effects
				(font
					(size 1.905 1.4224)
					(thickness 0.1524)
				)
				(justify left)
			)
		)
		(fp_text user "+"
			(at -5.375656 -0.180848 270)
			(unlocked yes)
			(layer "F.SilkS")
			(effects
				(font
					(size 1.905 1.4224)
					(thickness 0.1524)
				)
				(justify left)
			)
		)
		(fp_text user "-"
			(at 5.4102 0.29845 90)
			(unlocked yes)
			(layer "F.Fab")
			(effects
				(font
					(size 1.905 1.4224)
					(thickness 0.1524)
				)
				(justify left)
			)
		)
		(fp_text user "+"
			(at -4.7752 -0.12065 270)
			(unlocked yes)
			(layer "F.Fab")
			(effects
				(font
					(size 1.905 1.4224)
					(thickness 0.1524)
				)
				(justify left)
			)
		)
		(pad "A" smd rect
			(at -1.999996 0)
			(size 1.7018 2.5146)
			(layers "F.Cu" "F.Mask" "F.Paste")
			(net "GND")
		)
		(pad "C" smd rect
			(at 1.999996 0)
			(size 1.7018 2.5146)
			(layers "F.Cu" "F.Mask" "F.Paste")
			(net "P12V_SSD4_R")
		)
	)
	(footprint ""
		(layer "F.Cu")
		(at 234.3023 -178.844194 180)
		(property "Reference" "R4257"
			(at 0 0 180)
			(layer "F.SilkS")
			(hide yes)
			(effects
				(font
					(size 1.27 1.27)
				)
			)
		)
		(property "Value" ""
			(at 0 0 180)
			(layer "F.Fab")
			(effects
				(font
					(size 1.27 1.27)
				)
			)
		)
		(duplicate_pad_numbers_are_jumpers no)
		(fp_line
			(start 0.7874 0.4064)
			(end -0.7874 0.4064)
			(stroke
				(width 0.1524)
				(type default)
			)
			(layer "F.SilkS")
		)
		(fp_line
			(start 0.7874 -0.4064)
			(end 0.7874 0.4064)
			(stroke
				(width 0.1524)
				(type default)
			)
			(layer "F.SilkS")
		)
		(fp_line
			(start -0.7874 0.4064)
			(end -0.7874 -0.4064)
			(stroke
				(width 0.1524)
				(type default)
			)
			(layer "F.SilkS")
		)
		(fp_line
			(start -0.7874 -0.4064)
			(end 0.7874 -0.4064)
			(stroke
				(width 0.1524)
				(type default)
			)
			(layer "F.SilkS")
		)
		(fp_line
			(start 0.67945 0.3048)
			(end 0.120396 0.3048)
			(stroke
				(width 0.1)
				(type default)
			)
			(layer "F.Fab")
		)
		(fp_line
			(start 0.67945 -0.3048)
			(end 0.67945 0.3048)
			(stroke
				(width 0.1)
				(type default)
			)
			(layer "F.Fab")
		)
		(fp_line
			(start 0.12065 -0.2794)
			(end 0.12065 -0.3048)
			(stroke
				(width 0.1)
				(type default)
			)
			(layer "F.Fab")
		)
		(fp_line
			(start 0.12065 -0.3048)
			(end 0.67945 -0.3048)
			(stroke
				(width 0.1)
				(type default)
			)
			(layer "F.Fab")
		)
		(fp_line
			(start 0.120396 0.3048)
			(end 0.120396 0.2794)
			(stroke
				(width 0.1)
				(type default)
			)
			(layer "F.Fab")
		)
		(fp_line
			(start 0.120396 0.2794)
			(end -0.12065 0.2794)
			(stroke
				(width 0.1)
				(type default)
			)
			(layer "F.Fab")
		)
		(fp_line
			(start -0.12065 0.3048)
			(end -0.67945 0.3048)
			(stroke
				(width 0.1)
				(type default)
			)
			(layer "F.Fab")
		)
		(fp_line
			(start -0.12065 0.2794)
			(end -0.12065 0.3048)
			(stroke
				(width 0.1)
				(type default)
			)
			(layer "F.Fab")
		)
		(fp_line
			(start -0.12065 -0.2794)
			(end 0.12065 -0.2794)
			(stroke
				(width 0.1)
				(type default)
			)
			(layer "F.Fab")
		)
		(fp_line
			(start -0.12065 -0.305054)
			(end -0.12065 -0.2794)
			(stroke
				(width 0.1)
				(type default)
			)
			(layer "F.Fab")
		)
		(fp_line
			(start -0.67945 0.3048)
			(end -0.67945 -0.305054)
			(stroke
				(width 0.1)
				(type default)
			)
			(layer "F.Fab")
		)
		(fp_line
			(start -0.67945 -0.305054)
			(end -0.12065 -0.305054)
			(stroke
				(width 0.1)
				(type default)
			)
			(layer "F.Fab")
		)
		(pad "1" smd circle
			(at -0.40005 0 180)
			(size 0 0)
			(layers "F.Cu" "F.Mask" "F.Paste")
			(net "RST_FPGA_BIC_R1_N")
		)
		(pad "2" smd circle
			(at 0.40005 0 180)
			(size 0 0)
			(layers "F.Cu" "F.Mask" "F.Paste")
			(net "RST_FPGA_BIC_R_N")
		)
	)
	(footprint ""
		(layer "F.Cu")
		(at 216.989914 -311.179972)
		(property "Reference" "H132"
			(at -2.095754 -4.7879 0)
			(unlocked yes)
			(layer "F.SilkS")
			(effects
				(font
					(size 0.7874 0.5842)
					(thickness 0.1524)
				)
				(justify left)
			)
		)
		(property "Value" ""
			(at 0 0 0)
			(layer "F.Fab")
			(effects
				(font
					(size 1.27 1.27)
				)
			)
		)
		(duplicate_pad_numbers_are_jumpers no)
		(pad "1" thru_hole circle
			(at 0 0)
			(size 6.5024 6.5024)
			(drill 3.2004)
			(layers "*.Cu" "*.Mask")
			(remove_unused_layers no)
			(net "GND")
			(clearance -1.397)
		)
	)
	(footprint ""
		(layer "F.Cu")
		(at 137.73785 -194.088512 90)
		(property "Reference" "Y4"
			(at -2.421382 -0.01905 0)
			(unlocked yes)
			(layer "F.SilkS")
			(effects
				(font
					(size 0.7874 0.5842)
					(thickness 0.1524)
				)
				(justify left)
			)
		)
		(property "Value" ""
			(at 0 0 90)
			(layer "F.Fab")
			(effects
				(font
					(size 1.27 1.27)
				)
			)
		)
		(duplicate_pad_numbers_are_jumpers no)
		(fp_line
			(start 1.6002 -1.9558)
			(end 1.6002 1.9558)
			(stroke
				(width 0.1524)
				(type default)
			)
			(layer "F.SilkS")
		)
		(fp_line
			(start -1.6002 -1.9558)
			(end 1.6002 -1.9558)
			(stroke
				(width 0.1524)
				(type default)
			)
			(layer "F.SilkS")
		)
		(fp_line
			(start 1.6002 1.9558)
			(end -1.6002 1.9558)
			(stroke
				(width 0.1524)
				(type default)
			)
			(layer "F.SilkS")
		)
		(fp_line
			(start -1.6002 1.9558)
			(end -1.6002 -1.9558)
			(stroke
				(width 0.1524)
				(type default)
			)
			(layer "F.SilkS")
		)
		(fp_poly
			(pts
				(xy -1.7145 -1.0668) (xy -2.8067 -1.651) (xy -2.8067 -0.5842)
			)
			(stroke
				(width 0)
				(type default)
			)
			(fill yes)
			(layer "F.SilkS")
		)
		(fp_line
			(start 1.299972 -1.649984)
			(end 1.299972 1.649984)
			(stroke
				(width 0.1)
				(type default)
			)
			(layer "F.Fab")
		)
		(fp_line
			(start -1.299972 -1.649984)
			(end 1.299972 -1.649984)
			(stroke
				(width 0.1)
				(type default)
			)
			(layer "F.Fab")
		)
		(fp_line
			(start 1.299972 1.649984)
			(end -1.299972 1.649984)
			(stroke
				(width 0.1)
				(type default)
			)
			(layer "F.Fab")
		)
		(fp_line
			(start -1.299972 1.649984)
			(end -1.299972 -1.649984)
			(stroke
				(width 0.1)
				(type default)
			)
			(layer "F.Fab")
		)
		(fp_poly
			(pts
				(xy -1.7145 -1.0668) (xy -2.8067 -1.651) (xy -2.8067 -0.5842)
			)
			(stroke
				(width 0)
				(type default)
			)
			(fill yes)
			(layer "F.Fab")
		)
		(pad "1" smd rect
			(at -0.849884 -1.100074 90)
			(size 1.2192 1.4224)
			(layers "F.Cu" "F.Mask" "F.Paste")
			(net "OSC_CLI_IN")
		)
		(pad "2" smd rect
			(at -0.849884 1.100074 90)
			(size 1.2192 1.4224)
			(layers "F.Cu" "F.Mask" "F.Paste")
			(net "GND")
		)
		(pad "3" smd rect
			(at 0.849884 1.100074 90)
			(size 1.2192 1.4224)
			(layers "F.Cu" "F.Mask" "F.Paste")
			(net "OSC_CLI_OUT")
		)
		(pad "4" smd rect
			(at 0.849884 -1.100074 90)
			(size 1.2192 1.4224)
			(layers "F.Cu" "F.Mask" "F.Paste")
			(net "GND")
		)
	)
	(footprint ""
		(layer "F.Cu")
		(at 310.810402 -18.61439 90)
		(property "Reference" "U136"
			(at -1.34239 2.372868 90)
			(unlocked yes)
			(layer "F.SilkS")
			(effects
				(font
					(size 0.7874 0.5842)
					(thickness 0.1524)
				)
				(justify left)
			)
		)
		(property "Value" ""
			(at 0 0 90)
			(layer "F.Fab")
			(effects
				(font
					(size 1.27 1.27)
				)
			)
		)
		(duplicate_pad_numbers_are_jumpers no)
		(fp_line
			(start 1.463548 -1.549908)
			(end 1.463548 1.549908)
			(stroke
				(width 0.1524)
				(type default)
			)
			(layer "F.SilkS")
		)
		(fp_line
			(start 0.762 -1.549908)
			(end 1.463548 -1.549908)
			(stroke
				(width 0.1524)
				(type default)
			)
			(layer "F.SilkS")
		)
		(fp_line
			(start -0.787908 -1.549908)
			(end 0 -0.762)
			(stroke
				(width 0.1524)
				(type default)
			)
			(layer "F.SilkS")
		)
		(fp_line
			(start -1.463548 -1.549908)
			(end -0.787908 -1.549908)
			(stroke
				(width 0.1524)
				(type default)
			)
			(layer "F.SilkS")
		)
		(fp_line
			(start 0 -0.762)
			(end 0.762 -1.549908)
			(stroke
				(width 0.1524)
				(type default)
			)
			(layer "F.SilkS")
		)
		(fp_line
			(start 1.463548 1.549908)
			(end -1.463548 1.549908)
			(stroke
				(width 0.1524)
				(type default)
			)
			(layer "F.SilkS")
		)
		(fp_line
			(start -1.463548 1.549908)
			(end -1.463548 -1.549908)
			(stroke
				(width 0.1524)
				(type default)
			)
			(layer "F.SilkS")
		)
		(fp_poly
			(pts
				(xy -3.4798 -1.359916) (xy -2.86004 -1.050036) (xy -3.4798 -0.740156)
			)
			(stroke
				(width 0)
				(type default)
			)
			(fill yes)
			(layer "F.SilkS")
		)
		(fp_line
			(start 1.549908 -1.549908)
			(end 1.549908 1.549908)
			(stroke
				(width 0.1)
				(type default)
			)
			(layer "F.Fab")
		)
		(fp_line
			(start -1.549908 -1.549908)
			(end 1.549908 -1.549908)
			(stroke
				(width 0.1)
				(type default)
			)
			(layer "F.Fab")
		)
		(fp_line
			(start 1.549908 1.549908)
			(end -1.549908 1.549908)
			(stroke
				(width 0.1)
				(type default)
			)
			(layer "F.Fab")
		)
		(fp_line
			(start -1.549908 1.549908)
			(end -1.549908 -1.549908)
			(stroke
				(width 0.1)
				(type default)
			)
			(layer "F.Fab")
		)
		(fp_poly
			(pts
				(xy -3.4798 -1.359916) (xy -2.86004 -1.050036) (xy -3.4798 -0.740156)
			)
			(stroke
				(width 0)
				(type default)
			)
			(fill yes)
			(layer "F.Fab")
		)
		(pad "1" smd rect
			(at -2.175002 -1.050036 180)
			(size 0.6096 1.1684)
			(layers "F.Cu" "F.Mask" "F.Paste")
			(net "P3V3_SSD10")
		)
		(pad "2" smd rect
			(at -2.175002 -0.32512 180)
			(size 0.4318 1.1684)
			(layers "F.Cu" "F.Mask" "F.Paste")
			(net "SMB_ISO_SSD10_SCL")
		)
		(pad "3" smd rect
			(at -2.175002 0.32512 180)
			(size 0.4318 1.1684)
			(layers "F.Cu" "F.Mask" "F.Paste")
			(net "SMB_ISO_SSD10_SDA")
		)
		(pad "4" smd rect
			(at -2.175002 1.050036 180)
			(size 0.6096 1.1684)
			(layers "F.Cu" "F.Mask" "F.Paste")
			(net "GND")
		)
		(pad "5" smd rect
			(at 2.175002 1.050036 180)
			(size 0.6096 1.1684)
			(layers "F.Cu" "F.Mask" "F.Paste")
			(net "SMB_SSD10_ISO_EN")
		)
		(pad "6" smd rect
			(at 2.175002 0.32512 180)
			(size 0.4318 1.1684)
			(layers "F.Cu" "F.Mask" "F.Paste")
			(net "SMB_BIC_I2C9_MUX1_SSD10_R_SDA")
		)
		(pad "7" smd rect
			(at 2.175002 -0.32512 180)
			(size 0.4318 1.1684)
			(layers "F.Cu" "F.Mask" "F.Paste")
			(net "SMB_BIC_I2C9_MUX1_SSD10_R_SCL")
		)
		(pad "8" smd rect
			(at 2.175002 -1.050036 180)
			(size 0.6096 1.1684)
			(layers "F.Cu" "F.Mask" "F.Paste")
			(net "P3V3_AUX")
		)
	)
	(footprint ""
		(layer "F.Cu")
		(at 393.669266 -80.356202 180)
		(property "Reference" "R1766"
			(at 0 0 180)
			(layer "F.SilkS")
			(hide yes)
			(effects
				(font
					(size 1.27 1.27)
				)
			)
		)
		(property "Value" ""
			(at 0 0 180)
			(layer "F.Fab")
			(effects
				(font
					(size 1.27 1.27)
				)
			)
		)
		(duplicate_pad_numbers_are_jumpers no)
		(fp_line
			(start 0.7874 0.4064)
			(end -0.7874 0.4064)
			(stroke
				(width 0.1524)
				(type default)
			)
			(layer "F.SilkS")
		)
		(fp_line
			(start 0.7874 -0.4064)
			(end 0.7874 0.4064)
			(stroke
				(width 0.1524)
				(type default)
			)
			(layer "F.SilkS")
		)
		(fp_line
			(start -0.7874 0.4064)
			(end -0.7874 -0.4064)
			(stroke
				(width 0.1524)
				(type default)
			)
			(layer "F.SilkS")
		)
		(fp_line
			(start -0.7874 -0.4064)
			(end 0.7874 -0.4064)
			(stroke
				(width 0.1524)
				(type default)
			)
			(layer "F.SilkS")
		)
		(fp_line
			(start 0.67945 0.3048)
			(end 0.120396 0.3048)
			(stroke
				(width 0.1)
				(type default)
			)
			(layer "F.Fab")
		)
		(fp_line
			(start 0.67945 -0.3048)
			(end 0.67945 0.3048)
			(stroke
				(width 0.1)
				(type default)
			)
			(layer "F.Fab")
		)
		(fp_line
			(start 0.12065 -0.2794)
			(end 0.12065 -0.3048)
			(stroke
				(width 0.1)
				(type default)
			)
			(layer "F.Fab")
		)
		(fp_line
			(start 0.12065 -0.3048)
			(end 0.67945 -0.3048)
			(stroke
				(width 0.1)
				(type default)
			)
			(layer "F.Fab")
		)
		(fp_line
			(start 0.120396 0.3048)
			(end 0.120396 0.2794)
			(stroke
				(width 0.1)
				(type default)
			)
			(layer "F.Fab")
		)
		(fp_line
			(start 0.120396 0.2794)
			(end -0.12065 0.2794)
			(stroke
				(width 0.1)
				(type default)
			)
			(layer "F.Fab")
		)
		(fp_line
			(start -0.12065 0.3048)
			(end -0.67945 0.3048)
			(stroke
				(width 0.1)
				(type default)
			)
			(layer "F.Fab")
		)
		(fp_line
			(start -0.12065 0.2794)
			(end -0.12065 0.3048)
			(stroke
				(width 0.1)
				(type default)
			)
			(layer "F.Fab")
		)
		(fp_line
			(start -0.12065 -0.2794)
			(end 0.12065 -0.2794)
			(stroke
				(width 0.1)
				(type default)
			)
			(layer "F.Fab")
		)
		(fp_line
			(start -0.12065 -0.305054)
			(end -0.12065 -0.2794)
			(stroke
				(width 0.1)
				(type default)
			)
			(layer "F.Fab")
		)
		(fp_line
			(start -0.67945 0.3048)
			(end -0.67945 -0.305054)
			(stroke
				(width 0.1)
				(type default)
			)
			(layer "F.Fab")
		)
		(fp_line
			(start -0.67945 -0.305054)
			(end -0.12065 -0.305054)
			(stroke
				(width 0.1)
				(type default)
			)
			(layer "F.Fab")
		)
		(pad "1" smd circle
			(at -0.40005 0 180)
			(size 0 0)
			(layers "F.Cu" "F.Mask" "F.Paste")
			(net "SMB_BIC_I2C6_MUX_SSD_8_15_ADC_R_SDA")
		)
		(pad "2" smd circle
			(at 0.40005 0 180)
			(size 0 0)
			(layers "F.Cu" "F.Mask" "F.Paste")
			(net "SMB_BIC_I2C6_MUX_SSD_8_15_ADC_SDA")
		)
	)
	(footprint ""
		(layer "F.Cu")
		(at 125.454156 -172.44949 90)
		(property "Reference" "C4501"
			(at 0 0 90)
			(layer "F.SilkS")
			(hide yes)
			(effects
				(font
					(size 1.27 1.27)
				)
			)
		)
		(property "Value" ""
			(at 0 0 90)
			(layer "F.Fab")
			(effects
				(font
					(size 1.27 1.27)
				)
			)
		)
		(duplicate_pad_numbers_are_jumpers no)
		(fp_line
			(start 0.7874 -0.4064)
			(end 0.7874 0.4064)
			(stroke
				(width 0.1524)
				(type default)
			)
			(layer "F.SilkS")
		)
		(fp_line
			(start -0.7874 -0.4064)
			(end 0.7874 -0.4064)
			(stroke
				(width 0.1524)
				(type default)
			)
			(layer "F.SilkS")
		)
		(fp_line
			(start 0.7874 0.4064)
			(end -0.7874 0.4064)
			(stroke
				(width 0.1524)
				(type default)
			)
			(layer "F.SilkS")
		)
		(fp_line
			(start -0.7874 0.4064)
			(end -0.7874 -0.4064)
			(stroke
				(width 0.1524)
				(type default)
			)
			(layer "F.SilkS")
		)
		(fp_line
			(start -0.12065 -0.305054)
			(end -0.12065 -0.2794)
			(stroke
				(width 0.1)
				(type default)
			)
			(layer "F.Fab")
		)
		(fp_line
			(start -0.67945 -0.305054)
			(end -0.12065 -0.305054)
			(stroke
				(width 0.1)
				(type default)
			)
			(layer "F.Fab")
		)
		(fp_line
			(start 0.67945 -0.3048)
			(end 0.67945 0.3048)
			(stroke
				(width 0.1)
				(type default)
			)
			(layer "F.Fab")
		)
		(fp_line
			(start 0.12065 -0.3048)
			(end 0.67945 -0.3048)
			(stroke
				(width 0.1)
				(type default)
			)
			(layer "F.Fab")
		)
		(fp_line
			(start 0.12065 -0.2794)
			(end 0.12065 -0.3048)
			(stroke
				(width 0.1)
				(type default)
			)
			(layer "F.Fab")
		)
		(fp_line
			(start -0.12065 -0.2794)
			(end 0.12065 -0.2794)
			(stroke
				(width 0.1)
				(type default)
			)
			(layer "F.Fab")
		)
		(fp_line
			(start 0.120396 0.2794)
			(end -0.12065 0.2794)
			(stroke
				(width 0.1)
				(type default)
			)
			(layer "F.Fab")
		)
		(fp_line
			(start -0.12065 0.2794)
			(end -0.12065 0.3048)
			(stroke
				(width 0.1)
				(type default)
			)
			(layer "F.Fab")
		)
		(fp_line
			(start 0.67945 0.3048)
			(end 0.120396 0.3048)
			(stroke
				(width 0.1)
				(type default)
			)
			(layer "F.Fab")
		)
		(fp_line
			(start 0.120396 0.3048)
			(end 0.120396 0.2794)
			(stroke
				(width 0.1)
				(type default)
			)
			(layer "F.Fab")
		)
		(fp_line
			(start -0.12065 0.3048)
			(end -0.67945 0.3048)
			(stroke
				(width 0.1)
				(type default)
			)
			(layer "F.Fab")
		)
		(fp_line
			(start -0.67945 0.3048)
			(end -0.67945 -0.305054)
			(stroke
				(width 0.1)
				(type default)
			)
			(layer "F.Fab")
		)
		(pad "1" smd circle
			(at -0.40005 0 90)
			(size 0 0)
			(layers "F.Cu" "F.Mask" "F.Paste")
			(net "NIC0_CLK_EN_R_N")
		)
		(pad "2" smd circle
			(at 0.40005 0 90)
			(size 0 0)
			(layers "F.Cu" "F.Mask" "F.Paste")
			(net "GND")
		)
	)
	(footprint ""
		(layer "F.Cu")
		(at 430.961546 -151.596852 180)
		(property "Reference" "C639"
			(at 0 0 180)
			(layer "F.SilkS")
			(hide yes)
			(effects
				(font
					(size 1.27 1.27)
				)
			)
		)
		(property "Value" ""
			(at 0 0 180)
			(layer "F.Fab")
			(effects
				(font
					(size 1.27 1.27)
				)
			)
		)
		(duplicate_pad_numbers_are_jumpers no)
		(fp_line
			(start 0.299974 0.150114)
			(end -0.299974 0.150114)
			(stroke
				(width 0.1)
				(type default)
			)
			(layer "F.Fab")
		)
		(fp_line
			(start 0.299974 -0.150114)
			(end 0.299974 0.150114)
			(stroke
				(width 0.1)
				(type default)
			)
			(layer "F.Fab")
		)
		(fp_line
			(start -0.299974 0.150114)
			(end -0.299974 -0.150114)
			(stroke
				(width 0.1)
				(type default)
			)
			(layer "F.Fab")
		)
		(fp_line
			(start -0.299974 -0.150114)
			(end 0.299974 -0.150114)
			(stroke
				(width 0.1)
				(type default)
			)
			(layer "F.Fab")
		)
		(pad "1" smd rect
			(at -0.2667 0 180)
			(size 0.3048 0.381)
			(layers "F.Cu" "F.Mask" "F.Paste")
			(net "P5E_PEX3_STN0_TX_DN<13>")
		)
		(pad "2" smd rect
			(at 0.2667 0 180)
			(size 0.3048 0.381)
			(layers "F.Cu" "F.Mask" "F.Paste")
			(net "P5E_PEX3_STN0_TX_C_DN<13>")
		)
	)
	(footprint ""
		(layer "F.Cu")
		(at 260.431026 -237.165388 180)
		(property "Reference" "C4426"
			(at 0 0 180)
			(layer "F.SilkS")
			(hide yes)
			(effects
				(font
					(size 1.27 1.27)
				)
			)
		)
		(property "Value" ""
			(at 0 0 180)
			(layer "F.Fab")
			(effects
				(font
					(size 1.27 1.27)
				)
			)
		)
		(duplicate_pad_numbers_are_jumpers no)
		(fp_line
			(start 1.524 0.762)
			(end -1.524 0.762)
			(stroke
				(width 0.1524)
				(type default)
			)
			(layer "F.SilkS")
		)
		(fp_line
			(start 1.524 -0.762)
			(end 1.524 0.762)
			(stroke
				(width 0.1524)
				(type default)
			)
			(layer "F.SilkS")
		)
		(fp_line
			(start -1.524 0.762)
			(end -1.524 -0.762)
			(stroke
				(width 0.1524)
				(type default)
			)
			(layer "F.SilkS")
		)
		(fp_line
			(start -1.524 -0.762)
			(end 1.524 -0.762)
			(stroke
				(width 0.1524)
				(type default)
			)
			(layer "F.SilkS")
		)
		(fp_line
			(start 1.1049 0.724916)
			(end 1.1049 -0.724916)
			(stroke
				(width 0.1)
				(type default)
			)
			(layer "F.Fab")
		)
		(fp_line
			(start 1.1049 -0.724916)
			(end -1.1049 -0.724916)
			(stroke
				(width 0.1)
				(type default)
			)
			(layer "F.Fab")
		)
		(fp_line
			(start -1.1049 0.724916)
			(end 1.1049 0.724916)
			(stroke
				(width 0.1)
				(type default)
			)
			(layer "F.Fab")
		)
		(fp_line
			(start -1.1049 -0.724916)
			(end -1.1049 0.724916)
			(stroke
				(width 0.1)
				(type default)
			)
			(layer "F.Fab")
		)
		(pad "1" smd rect
			(at -0.889 0)
			(size 1.016 1.27)
			(layers "F.Cu" "F.Mask" "F.Paste")
			(net "P1V8_PLL0_PEX2")
		)
		(pad "2" smd rect
			(at 0.889 0)
			(size 1.016 1.27)
			(layers "F.Cu" "F.Mask" "F.Paste")
			(net "GND")
		)
	)
	(footprint ""
		(layer "F.Cu")
		(at 227.904294 -182.61838)
		(property "Reference" "Q57"
			(at -0.726694 -2.13995 0)
			(unlocked yes)
			(layer "F.SilkS")
			(effects
				(font
					(size 0.7874 0.5842)
					(thickness 0.1524)
				)
				(justify left)
			)
		)
		(property "Value" ""
			(at 0 0 0)
			(layer "F.Fab")
			(effects
				(font
					(size 1.27 1.27)
				)
			)
		)
		(duplicate_pad_numbers_are_jumpers no)
		(fp_line
			(start -1.584198 -1.53416)
			(end 1.584198 -1.53416)
			(stroke
				(width 0.1524)
				(type default)
			)
			(layer "F.SilkS")
		)
		(fp_line
			(start -1.584198 1.53416)
			(end -1.584198 -1.53416)
			(stroke
				(width 0.1524)
				(type default)
			)
			(layer "F.SilkS")
		)
		(fp_line
			(start 1.584198 -1.53416)
			(end 1.584198 1.53416)
			(stroke
				(width 0.1524)
				(type default)
			)
			(layer "F.SilkS")
		)
		(fp_line
			(start 1.584198 1.53416)
			(end -1.584198 1.53416)
			(stroke
				(width 0.1524)
				(type default)
			)
			(layer "F.SilkS")
		)
		(fp_line
			(start -0.700024 -1.500124)
			(end 0.700024 -1.500124)
			(stroke
				(width 0.1)
				(type default)
			)
			(layer "F.Fab")
		)
		(fp_line
			(start -0.700024 1.500124)
			(end -0.700024 -1.500124)
			(stroke
				(width 0.1)
				(type default)
			)
			(layer "F.Fab")
		)
		(fp_line
			(start 0.700024 -1.500124)
			(end 0.700024 1.500124)
			(stroke
				(width 0.1)
				(type default)
			)
			(layer "F.Fab")
		)
		(fp_line
			(start 0.700024 1.500124)
			(end -0.700024 1.500124)
			(stroke
				(width 0.1)
				(type default)
			)
			(layer "F.Fab")
		)
		(pad "B" smd rect
			(at -0.999998 -0.94996 90)
			(size 0.8128 0.9144)
			(layers "F.Cu" "F.Mask" "F.Paste")
			(net "RST_BJT_Q15_B")
		)
		(pad "C" smd rect
			(at 0.999998 0 90)
			(size 0.8128 0.9144)
			(layers "F.Cu" "F.Mask" "F.Paste")
			(net "RST_BJT_Q15_C")
		)
		(pad "E" smd rect
			(at -0.999998 0.94996 90)
			(size 0.8128 0.9144)
			(layers "F.Cu" "F.Mask" "F.Paste")
			(net "GND")
		)
	)
	(footprint ""
		(layer "F.Cu")
		(at 458.357732 -310.692292)
		(property "Reference" "R848"
			(at 0 0 0)
			(layer "F.SilkS")
			(hide yes)
			(effects
				(font
					(size 1.27 1.27)
				)
			)
		)
		(property "Value" ""
			(at 0 0 0)
			(layer "F.Fab")
			(effects
				(font
					(size 1.27 1.27)
				)
			)
		)
		(duplicate_pad_numbers_are_jumpers no)
		(fp_line
			(start -0.7874 -0.4064)
			(end 0.7874 -0.4064)
			(stroke
				(width 0.1524)
				(type default)
			)
			(layer "F.SilkS")
		)
		(fp_line
			(start -0.7874 0.4064)
			(end -0.7874 -0.4064)
			(stroke
				(width 0.1524)
				(type default)
			)
			(layer "F.SilkS")
		)
		(fp_line
			(start 0.7874 -0.4064)
			(end 0.7874 0.4064)
			(stroke
				(width 0.1524)
				(type default)
			)
			(layer "F.SilkS")
		)
		(fp_line
			(start 0.7874 0.4064)
			(end -0.7874 0.4064)
			(stroke
				(width 0.1524)
				(type default)
			)
			(layer "F.SilkS")
		)
		(fp_line
			(start -0.67945 -0.305054)
			(end -0.12065 -0.305054)
			(stroke
				(width 0.1)
				(type default)
			)
			(layer "F.Fab")
		)
		(fp_line
			(start -0.67945 0.3048)
			(end -0.67945 -0.305054)
			(stroke
				(width 0.1)
				(type default)
			)
			(layer "F.Fab")
		)
		(fp_line
			(start -0.12065 -0.305054)
			(end -0.12065 -0.2794)
			(stroke
				(width 0.1)
				(type default)
			)
			(layer "F.Fab")
		)
		(fp_line
			(start -0.12065 -0.2794)
			(end 0.12065 -0.2794)
			(stroke
				(width 0.1)
				(type default)
			)
			(layer "F.Fab")
		)
		(fp_line
			(start -0.12065 0.2794)
			(end -0.12065 0.3048)
			(stroke
				(width 0.1)
				(type default)
			)
			(layer "F.Fab")
		)
		(fp_line
			(start -0.12065 0.3048)
			(end -0.67945 0.3048)
			(stroke
				(width 0.1)
				(type default)
			)
			(layer "F.Fab")
		)
		(fp_line
			(start 0.120396 0.2794)
			(end -0.12065 0.2794)
			(stroke
				(width 0.1)
				(type default)
			)
			(layer "F.Fab")
		)
		(fp_line
			(start 0.120396 0.3048)
			(end 0.120396 0.2794)
			(stroke
				(width 0.1)
				(type default)
			)
			(layer "F.Fab")
		)
		(fp_line
			(start 0.12065 -0.3048)
			(end 0.67945 -0.3048)
			(stroke
				(width 0.1)
				(type default)
			)
			(layer "F.Fab")
		)
		(fp_line
			(start 0.12065 -0.2794)
			(end 0.12065 -0.3048)
			(stroke
				(width 0.1)
				(type default)
			)
			(layer "F.Fab")
		)
		(fp_line
			(start 0.67945 -0.3048)
			(end 0.67945 0.3048)
			(stroke
				(width 0.1)
				(type default)
			)
			(layer "F.Fab")
		)
		(fp_line
			(start 0.67945 0.3048)
			(end 0.120396 0.3048)
			(stroke
				(width 0.1)
				(type default)
			)
			(layer "F.Fab")
		)
		(pad "1" smd circle
			(at -0.40005 0)
			(size 0 0)
			(layers "F.Cu" "F.Mask" "F.Paste")
			(net "P1V25_PEX3_EN")
		)
		(pad "2" smd circle
			(at 0.40005 0)
			(size 0 0)
			(layers "F.Cu" "F.Mask" "F.Paste")
			(net "PWR_EN_PEX_R")
		)
	)
	(footprint ""
		(layer "F.Cu")
		(at 488.15117 -551.726608 180)
		(property "Reference" "SCREW_SSD0_2"
			(at -5.207 -1.402334 0)
			(unlocked yes)
			(layer "B.SilkS")
			(effects
				(font
					(size 0.7874 0.5842)
					(thickness 0.1524)
				)
				(justify mirror)
			)
		)
		(property "Value" ""
			(at 0 0 180)
			(layer "F.Fab")
			(effects
				(font
					(size 1.27 1.27)
				)
			)
		)
		(duplicate_pad_numbers_are_jumpers no)
		(pad "1" thru_hole circle
			(at 0 0 180)
			(size 0.4572 0.4572)
			(drill 0.2032)
			(layers "*.Cu" "*.Mask")
			(remove_unused_layers no)
			(net "Net_9155")
			(clearance 0.127)
			(thermal_gap 0.127)
			(padstack
				(mode front_inner_back)
				(layer "Inner"
					(shape circle)
					(size 0.4572 0.4572)
					(clearance 0.127)
				)
				(layer "B.Cu"
					(shape circle)
					(size 0.508 0.508)
					(clearance 0.1016)
				)
			)
		)
	)
	(footprint ""
		(layer "F.Cu")
		(at 82.661506 -124.076714 180)
		(property "Reference" "C26"
			(at 0 0 180)
			(layer "F.SilkS")
			(hide yes)
			(effects
				(font
					(size 1.27 1.27)
				)
			)
		)
		(property "Value" ""
			(at 0 0 180)
			(layer "F.Fab")
			(effects
				(font
					(size 1.27 1.27)
				)
			)
		)
		(duplicate_pad_numbers_are_jumpers no)
		(fp_line
			(start 0.299974 0.150114)
			(end -0.299974 0.150114)
			(stroke
				(width 0.1)
				(type default)
			)
			(layer "F.Fab")
		)
		(fp_line
			(start 0.299974 -0.150114)
			(end 0.299974 0.150114)
			(stroke
				(width 0.1)
				(type default)
			)
			(layer "F.Fab")
		)
		(fp_line
			(start -0.299974 0.150114)
			(end -0.299974 -0.150114)
			(stroke
				(width 0.1)
				(type default)
			)
			(layer "F.Fab")
		)
		(fp_line
			(start -0.299974 -0.150114)
			(end 0.299974 -0.150114)
			(stroke
				(width 0.1)
				(type default)
			)
			(layer "F.Fab")
		)
		(pad "1" smd rect
			(at -0.2667 0 180)
			(size 0.3048 0.381)
			(layers "F.Cu" "F.Mask" "F.Paste")
			(net "P5E_PEX0_STN0_TX_DN<3>")
		)
		(pad "2" smd rect
			(at 0.2667 0 180)
			(size 0.3048 0.381)
			(layers "F.Cu" "F.Mask" "F.Paste")
			(net "P5E_PEX0_STN0_TX_C_DN<3>")
		)
	)
	(footprint ""
		(layer "F.Cu")
		(at 220.188028 -117.90045 90)
		(property "Reference" "PC345"
			(at 0 0 90)
			(layer "F.SilkS")
			(hide yes)
			(effects
				(font
					(size 1.27 1.27)
				)
			)
		)
		(property "Value" ""
			(at 0 0 90)
			(layer "F.Fab")
			(effects
				(font
					(size 1.27 1.27)
				)
			)
		)
		(duplicate_pad_numbers_are_jumpers no)
		(fp_line
			(start 1.524 -0.762)
			(end 1.524 0.762)
			(stroke
				(width 0.1524)
				(type default)
			)
			(layer "F.SilkS")
		)
		(fp_line
			(start -1.524 -0.762)
			(end 1.524 -0.762)
			(stroke
				(width 0.1524)
				(type default)
			)
			(layer "F.SilkS")
		)
		(fp_line
			(start 1.524 0.762)
			(end -1.524 0.762)
			(stroke
				(width 0.1524)
				(type default)
			)
			(layer "F.SilkS")
		)
		(fp_line
			(start -1.524 0.762)
			(end -1.524 -0.762)
			(stroke
				(width 0.1524)
				(type default)
			)
			(layer "F.SilkS")
		)
		(fp_line
			(start 1.1049 -0.724916)
			(end -1.1049 -0.724916)
			(stroke
				(width 0.1)
				(type default)
			)
			(layer "F.Fab")
		)
		(fp_line
			(start -1.1049 -0.724916)
			(end -1.1049 0.724916)
			(stroke
				(width 0.1)
				(type default)
			)
			(layer "F.Fab")
		)
		(fp_line
			(start 1.1049 0.724916)
			(end 1.1049 -0.724916)
			(stroke
				(width 0.1)
				(type default)
			)
			(layer "F.Fab")
		)
		(fp_line
			(start -1.1049 0.724916)
			(end 1.1049 0.724916)
			(stroke
				(width 0.1)
				(type default)
			)
			(layer "F.Fab")
		)
		(pad "1" smd rect
			(at -0.889 0 270)
			(size 1.016 1.27)
			(layers "F.Cu" "F.Mask" "F.Paste")
			(net "P12V_NIC3_R")
		)
		(pad "2" smd rect
			(at 0.889 0 270)
			(size 1.016 1.27)
			(layers "F.Cu" "F.Mask" "F.Paste")
			(net "GND")
		)
	)
	(footprint ""
		(layer "F.Cu")
		(at 254.46355 -146.592798 -90)
		(property "Reference" "R733"
			(at 0 0 270)
			(layer "F.SilkS")
			(hide yes)
			(effects
				(font
					(size 1.27 1.27)
				)
			)
		)
		(property "Value" ""
			(at 0 0 270)
			(layer "F.Fab")
			(effects
				(font
					(size 1.27 1.27)
				)
			)
		)
		(duplicate_pad_numbers_are_jumpers no)
		(fp_line
			(start -0.7874 0.4064)
			(end -0.7874 -0.4064)
			(stroke
				(width 0.1524)
				(type default)
			)
			(layer "F.SilkS")
		)
		(fp_line
			(start 0.7874 0.4064)
			(end -0.7874 0.4064)
			(stroke
				(width 0.1524)
				(type default)
			)
			(layer "F.SilkS")
		)
		(fp_line
			(start -0.7874 -0.4064)
			(end 0.7874 -0.4064)
			(stroke
				(width 0.1524)
				(type default)
			)
			(layer "F.SilkS")
		)
		(fp_line
			(start 0.7874 -0.4064)
			(end 0.7874 0.4064)
			(stroke
				(width 0.1524)
				(type default)
			)
			(layer "F.SilkS")
		)
		(fp_line
			(start -0.67945 0.3048)
			(end -0.67945 -0.305054)
			(stroke
				(width 0.1)
				(type default)
			)
			(layer "F.Fab")
		)
		(fp_line
			(start -0.12065 0.3048)
			(end -0.67945 0.3048)
			(stroke
				(width 0.1)
				(type default)
			)
			(layer "F.Fab")
		)
		(fp_line
			(start 0.120396 0.3048)
			(end 0.120396 0.2794)
			(stroke
				(width 0.1)
				(type default)
			)
			(layer "F.Fab")
		)
		(fp_line
			(start 0.67945 0.3048)
			(end 0.120396 0.3048)
			(stroke
				(width 0.1)
				(type default)
			)
			(layer "F.Fab")
		)
		(fp_line
			(start -0.12065 0.2794)
			(end -0.12065 0.3048)
			(stroke
				(width 0.1)
				(type default)
			)
			(layer "F.Fab")
		)
		(fp_line
			(start 0.120396 0.2794)
			(end -0.12065 0.2794)
			(stroke
				(width 0.1)
				(type default)
			)
			(layer "F.Fab")
		)
		(fp_line
			(start -0.12065 -0.2794)
			(end 0.12065 -0.2794)
			(stroke
				(width 0.1)
				(type default)
			)
			(layer "F.Fab")
		)
		(fp_line
			(start 0.12065 -0.2794)
			(end 0.12065 -0.3048)
			(stroke
				(width 0.1)
				(type default)
			)
			(layer "F.Fab")
		)
		(fp_line
			(start 0.12065 -0.3048)
			(end 0.67945 -0.3048)
			(stroke
				(width 0.1)
				(type default)
			)
			(layer "F.Fab")
		)
		(fp_line
			(start 0.67945 -0.3048)
			(end 0.67945 0.3048)
			(stroke
				(width 0.1)
				(type default)
			)
			(layer "F.Fab")
		)
		(fp_line
			(start -0.67945 -0.305054)
			(end -0.12065 -0.305054)
			(stroke
				(width 0.1)
				(type default)
			)
			(layer "F.Fab")
		)
		(fp_line
			(start -0.12065 -0.305054)
			(end -0.12065 -0.2794)
			(stroke
				(width 0.1)
				(type default)
			)
			(layer "F.Fab")
		)
		(pad "1" smd circle
			(at -0.40005 0 270)
			(size 0 0)
			(layers "F.Cu" "F.Mask" "F.Paste")
			(net "P12V_NIC4_R")
		)
		(pad "2" smd circle
			(at 0.40005 0 270)
			(size 0 0)
			(layers "F.Cu" "F.Mask" "F.Paste")
			(net "P12V_NIC4_VIN_P")
		)
	)
	(footprint ""
		(layer "F.Cu")
		(at 242.893088 -151.737822 180)
		(property "Reference" "PR7020"
			(at 0 0 180)
			(layer "F.SilkS")
			(hide yes)
			(effects
				(font
					(size 1.27 1.27)
				)
			)
		)
		(property "Value" ""
			(at 0 0 180)
			(layer "F.Fab")
			(effects
				(font
					(size 1.27 1.27)
				)
			)
		)
		(duplicate_pad_numbers_are_jumpers no)
		(fp_line
			(start 0.7874 0.4064)
			(end -0.7874 0.4064)
			(stroke
				(width 0.1524)
				(type default)
			)
			(layer "F.SilkS")
		)
		(fp_line
			(start 0.7874 -0.4064)
			(end 0.7874 0.4064)
			(stroke
				(width 0.1524)
				(type default)
			)
			(layer "F.SilkS")
		)
		(fp_line
			(start -0.7874 0.4064)
			(end -0.7874 -0.4064)
			(stroke
				(width 0.1524)
				(type default)
			)
			(layer "F.SilkS")
		)
		(fp_line
			(start -0.7874 -0.4064)
			(end 0.7874 -0.4064)
			(stroke
				(width 0.1524)
				(type default)
			)
			(layer "F.SilkS")
		)
		(fp_line
			(start 0.67945 0.3048)
			(end 0.120396 0.3048)
			(stroke
				(width 0.1)
				(type default)
			)
			(layer "F.Fab")
		)
		(fp_line
			(start 0.67945 -0.3048)
			(end 0.67945 0.3048)
			(stroke
				(width 0.1)
				(type default)
			)
			(layer "F.Fab")
		)
		(fp_line
			(start 0.12065 -0.2794)
			(end 0.12065 -0.3048)
			(stroke
				(width 0.1)
				(type default)
			)
			(layer "F.Fab")
		)
		(fp_line
			(start 0.12065 -0.3048)
			(end 0.67945 -0.3048)
			(stroke
				(width 0.1)
				(type default)
			)
			(layer "F.Fab")
		)
		(fp_line
			(start 0.120396 0.3048)
			(end 0.120396 0.2794)
			(stroke
				(width 0.1)
				(type default)
			)
			(layer "F.Fab")
		)
		(fp_line
			(start 0.120396 0.2794)
			(end -0.12065 0.2794)
			(stroke
				(width 0.1)
				(type default)
			)
			(layer "F.Fab")
		)
		(fp_line
			(start -0.12065 0.3048)
			(end -0.67945 0.3048)
			(stroke
				(width 0.1)
				(type default)
			)
			(layer "F.Fab")
		)
		(fp_line
			(start -0.12065 0.2794)
			(end -0.12065 0.3048)
			(stroke
				(width 0.1)
				(type default)
			)
			(layer "F.Fab")
		)
		(fp_line
			(start -0.12065 -0.2794)
			(end 0.12065 -0.2794)
			(stroke
				(width 0.1)
				(type default)
			)
			(layer "F.Fab")
		)
		(fp_line
			(start -0.12065 -0.305054)
			(end -0.12065 -0.2794)
			(stroke
				(width 0.1)
				(type default)
			)
			(layer "F.Fab")
		)
		(fp_line
			(start -0.67945 0.3048)
			(end -0.67945 -0.305054)
			(stroke
				(width 0.1)
				(type default)
			)
			(layer "F.Fab")
		)
		(fp_line
			(start -0.67945 -0.305054)
			(end -0.12065 -0.305054)
			(stroke
				(width 0.1)
				(type default)
			)
			(layer "F.Fab")
		)
		(pad "1" smd circle
			(at -0.40005 0 180)
			(size 0 0)
			(layers "F.Cu" "F.Mask" "F.Paste")
			(net "P12V_NIC4_R")
		)
		(pad "2" smd circle
			(at 0.40005 0 180)
			(size 0 0)
			(layers "F.Cu" "F.Mask" "F.Paste")
			(net "P12V_NIC4_CO_AVIN_PD")
		)
	)
	(footprint ""
		(layer "F.Cu")
		(at 77.806042 -356.244906 90)
		(property "Reference" "C112"
			(at 0 0 90)
			(layer "F.SilkS")
			(hide yes)
			(effects
				(font
					(size 1.27 1.27)
				)
			)
		)
		(property "Value" ""
			(at 0 0 90)
			(layer "F.Fab")
			(effects
				(font
					(size 1.27 1.27)
				)
			)
		)
		(duplicate_pad_numbers_are_jumpers no)
		(fp_line
			(start 0.299974 -0.150114)
			(end 0.299974 0.150114)
			(stroke
				(width 0.1)
				(type default)
			)
			(layer "F.Fab")
		)
		(fp_line
			(start -0.299974 -0.150114)
			(end 0.299974 -0.150114)
			(stroke
				(width 0.1)
				(type default)
			)
			(layer "F.Fab")
		)
		(fp_line
			(start 0.299974 0.150114)
			(end -0.299974 0.150114)
			(stroke
				(width 0.1)
				(type default)
			)
			(layer "F.Fab")
		)
		(fp_line
			(start -0.299974 0.150114)
			(end -0.299974 -0.150114)
			(stroke
				(width 0.1)
				(type default)
			)
			(layer "F.Fab")
		)
		(pad "1" smd rect
			(at -0.2667 0 90)
			(size 0.3048 0.381)
			(layers "F.Cu" "F.Mask" "F.Paste")
			(net "P5E_PEX0_STN5_TX_DN<88>")
		)
		(pad "2" smd rect
			(at 0.2667 0 90)
			(size 0.3048 0.381)
			(layers "F.Cu" "F.Mask" "F.Paste")
			(net "P5E_PEX0_STN5_TX_C_DN<88>")
		)
	)
	(footprint ""
		(layer "F.Cu")
		(at 130.490468 -356.244906 90)
		(property "Reference" "C2255"
			(at 0 0 90)
			(layer "F.SilkS")
			(hide yes)
			(effects
				(font
					(size 1.27 1.27)
				)
			)
		)
		(property "Value" ""
			(at 0 0 90)
			(layer "F.Fab")
			(effects
				(font
					(size 1.27 1.27)
				)
			)
		)
		(duplicate_pad_numbers_are_jumpers no)
		(fp_line
			(start 0.299974 -0.150114)
			(end 0.299974 0.150114)
			(stroke
				(width 0.1)
				(type default)
			)
			(layer "F.Fab")
		)
		(fp_line
			(start -0.299974 -0.150114)
			(end 0.299974 -0.150114)
			(stroke
				(width 0.1)
				(type default)
			)
			(layer "F.Fab")
		)
		(fp_line
			(start 0.299974 0.150114)
			(end -0.299974 0.150114)
			(stroke
				(width 0.1)
				(type default)
			)
			(layer "F.Fab")
		)
		(fp_line
			(start -0.299974 0.150114)
			(end -0.299974 -0.150114)
			(stroke
				(width 0.1)
				(type default)
			)
			(layer "F.Fab")
		)
		(pad "1" smd rect
			(at -0.2667 0 90)
			(size 0.3048 0.381)
			(layers "F.Cu" "F.Mask" "F.Paste")
			(net "P5E_PEX1_STN5_TX_DP<89>")
		)
		(pad "2" smd rect
			(at 0.2667 0 90)
			(size 0.3048 0.381)
			(layers "F.Cu" "F.Mask" "F.Paste")
			(net "P5E_PEX1_STN5_TX_C_DP<89>")
		)
	)
	(footprint ""
		(layer "F.Cu")
		(at 315.954156 -48.21809)
		(property "Reference" "PD75"
			(at -3.432556 2.29616 0)
			(unlocked yes)
			(layer "F.SilkS")
			(effects
				(font
					(size 0.7874 0.5842)
					(thickness 0.1524)
				)
				(justify left)
			)
		)
		(property "Value" ""
			(at 0 0 0)
			(layer "F.Fab")
			(effects
				(font
					(size 1.27 1.27)
				)
			)
		)
		(duplicate_pad_numbers_are_jumpers no)
		(fp_line
			(start -3.400044 -1.459992)
			(end 4.107942 -1.459992)
			(stroke
				(width 0.1524)
				(type default)
			)
			(layer "F.SilkS")
		)
		(fp_line
			(start -3.400044 1.459992)
			(end -3.400044 -1.459992)
			(stroke
				(width 0.1524)
				(type default)
			)
			(layer "F.SilkS")
		)
		(fp_line
			(start 4.107942 -1.459992)
			(end 4.107942 1.459992)
			(stroke
				(width 0.1524)
				(type default)
			)
			(layer "F.SilkS")
		)
		(fp_line
			(start 4.107942 1.459992)
			(end -3.400044 1.459992)
			(stroke
				(width 0.1524)
				(type default)
			)
			(layer "F.SilkS")
		)
		(fp_poly
			(pts
				(xy 4.107942 -1.459992) (xy 4.107942 1.459992) (xy 3.308096 1.459992) (xy 3.308096 -1.459992)
			)
			(stroke
				(width 0)
				(type default)
			)
			(fill yes)
			(layer "F.SilkS")
		)
		(fp_line
			(start -2.29997 -1.459992)
			(end 2.29997 -1.459992)
			(stroke
				(width 0.1)
				(type default)
			)
			(layer "F.Fab")
		)
		(fp_line
			(start -2.29997 1.459992)
			(end -2.29997 -1.459992)
			(stroke
				(width 0.1)
				(type default)
			)
			(layer "F.Fab")
		)
		(fp_line
			(start 2.29997 -1.459992)
			(end 2.29997 1.459992)
			(stroke
				(width 0.1)
				(type default)
			)
			(layer "F.Fab")
		)
		(fp_line
			(start 2.29997 1.459992)
			(end -2.29997 1.459992)
			(stroke
				(width 0.1)
				(type default)
			)
			(layer "F.Fab")
		)
		(fp_text user "+"
			(at -4.7752 -0.12065 0)
			(unlocked yes)
			(layer "F.SilkS")
			(effects
				(font
					(size 1.905 1.4224)
					(thickness 0.1524)
				)
				(justify left)
			)
		)
		(fp_text user "-"
			(at 5.4102 0.29845 180)
			(unlocked yes)
			(layer "F.SilkS")
			(effects
				(font
					(size 1.905 1.4224)
					(thickness 0.1524)
				)
				(justify left)
			)
		)
		(fp_text user "+"
			(at -4.7752 -0.12065 0)
			(unlocked yes)
			(layer "F.Fab")
			(effects
				(font
					(size 1.905 1.4224)
					(thickness 0.1524)
				)
				(justify left)
			)
		)
		(fp_text user "-"
			(at 5.4102 0.29845 180)
			(unlocked yes)
			(layer "F.Fab")
			(effects
				(font
					(size 1.905 1.4224)
					(thickness 0.1524)
				)
				(justify left)
			)
		)
		(pad "A" smd rect
			(at -1.999996 0 90)
			(size 1.7018 2.5146)
			(layers "F.Cu" "F.Mask" "F.Paste")
			(net "GND")
		)
		(pad "C" smd rect
			(at 1.999996 0 90)
			(size 1.7018 2.5146)
			(layers "F.Cu" "F.Mask" "F.Paste")
			(net "P3V3_SSD11")
		)
	)
	(footprint ""
		(layer "F.Cu")
		(at 202.220576 -26.666444 -90)
		(property "Reference" "R4067"
			(at 0 0 270)
			(layer "F.SilkS")
			(hide yes)
			(effects
				(font
					(size 1.27 1.27)
				)
			)
		)
		(property "Value" ""
			(at 0 0 270)
			(layer "F.Fab")
			(effects
				(font
					(size 1.27 1.27)
				)
			)
		)
		(duplicate_pad_numbers_are_jumpers no)
		(fp_line
			(start -0.7874 0.4064)
			(end -0.7874 -0.4064)
			(stroke
				(width 0.1524)
				(type default)
			)
			(layer "F.SilkS")
		)
		(fp_line
			(start 0.7874 0.4064)
			(end -0.7874 0.4064)
			(stroke
				(width 0.1524)
				(type default)
			)
			(layer "F.SilkS")
		)
		(fp_line
			(start -0.7874 -0.4064)
			(end 0.7874 -0.4064)
			(stroke
				(width 0.1524)
				(type default)
			)
			(layer "F.SilkS")
		)
		(fp_line
			(start 0.7874 -0.4064)
			(end 0.7874 0.4064)
			(stroke
				(width 0.1524)
				(type default)
			)
			(layer "F.SilkS")
		)
		(fp_line
			(start -0.67945 0.3048)
			(end -0.67945 -0.305054)
			(stroke
				(width 0.1)
				(type default)
			)
			(layer "F.Fab")
		)
		(fp_line
			(start -0.12065 0.3048)
			(end -0.67945 0.3048)
			(stroke
				(width 0.1)
				(type default)
			)
			(layer "F.Fab")
		)
		(fp_line
			(start 0.120396 0.3048)
			(end 0.120396 0.2794)
			(stroke
				(width 0.1)
				(type default)
			)
			(layer "F.Fab")
		)
		(fp_line
			(start 0.67945 0.3048)
			(end 0.120396 0.3048)
			(stroke
				(width 0.1)
				(type default)
			)
			(layer "F.Fab")
		)
		(fp_line
			(start -0.12065 0.2794)
			(end -0.12065 0.3048)
			(stroke
				(width 0.1)
				(type default)
			)
			(layer "F.Fab")
		)
		(fp_line
			(start 0.120396 0.2794)
			(end -0.12065 0.2794)
			(stroke
				(width 0.1)
				(type default)
			)
			(layer "F.Fab")
		)
		(fp_line
			(start -0.12065 -0.2794)
			(end 0.12065 -0.2794)
			(stroke
				(width 0.1)
				(type default)
			)
			(layer "F.Fab")
		)
		(fp_line
			(start 0.12065 -0.2794)
			(end 0.12065 -0.3048)
			(stroke
				(width 0.1)
				(type default)
			)
			(layer "F.Fab")
		)
		(fp_line
			(start 0.12065 -0.3048)
			(end 0.67945 -0.3048)
			(stroke
				(width 0.1)
				(type default)
			)
			(layer "F.Fab")
		)
		(fp_line
			(start 0.67945 -0.3048)
			(end 0.67945 0.3048)
			(stroke
				(width 0.1)
				(type default)
			)
			(layer "F.Fab")
		)
		(fp_line
			(start -0.67945 -0.305054)
			(end -0.12065 -0.305054)
			(stroke
				(width 0.1)
				(type default)
			)
			(layer "F.Fab")
		)
		(fp_line
			(start -0.12065 -0.305054)
			(end -0.12065 -0.2794)
			(stroke
				(width 0.1)
				(type default)
			)
			(layer "F.Fab")
		)
		(pad "1" smd circle
			(at -0.40005 0 270)
			(size 0 0)
			(layers "F.Cu" "F.Mask" "F.Paste")
			(net "PRSNT_SSD7_R_N")
		)
		(pad "2" smd circle
			(at 0.40005 0 270)
			(size 0 0)
			(layers "F.Cu" "F.Mask" "F.Paste")
			(net "PRSNT_SSD7_N")
		)
	)
	(footprint ""
		(layer "F.Cu")
		(at 411.97784 -117.566186)
		(property "Reference" "R398"
			(at 0 0 0)
			(layer "F.SilkS")
			(hide yes)
			(effects
				(font
					(size 1.27 1.27)
				)
			)
		)
		(property "Value" ""
			(at 0 0 0)
			(layer "F.Fab")
			(effects
				(font
					(size 1.27 1.27)
				)
			)
		)
		(duplicate_pad_numbers_are_jumpers no)
		(fp_line
			(start -0.7874 -0.4064)
			(end 0.7874 -0.4064)
			(stroke
				(width 0.1524)
				(type default)
			)
			(layer "F.SilkS")
		)
		(fp_line
			(start -0.7874 0.4064)
			(end -0.7874 -0.4064)
			(stroke
				(width 0.1524)
				(type default)
			)
			(layer "F.SilkS")
		)
		(fp_line
			(start 0.7874 -0.4064)
			(end 0.7874 0.4064)
			(stroke
				(width 0.1524)
				(type default)
			)
			(layer "F.SilkS")
		)
		(fp_line
			(start 0.7874 0.4064)
			(end -0.7874 0.4064)
			(stroke
				(width 0.1524)
				(type default)
			)
			(layer "F.SilkS")
		)
		(fp_line
			(start -0.67945 -0.305054)
			(end -0.12065 -0.305054)
			(stroke
				(width 0.1)
				(type default)
			)
			(layer "F.Fab")
		)
		(fp_line
			(start -0.67945 0.3048)
			(end -0.67945 -0.305054)
			(stroke
				(width 0.1)
				(type default)
			)
			(layer "F.Fab")
		)
		(fp_line
			(start -0.12065 -0.305054)
			(end -0.12065 -0.2794)
			(stroke
				(width 0.1)
				(type default)
			)
			(layer "F.Fab")
		)
		(fp_line
			(start -0.12065 -0.2794)
			(end 0.12065 -0.2794)
			(stroke
				(width 0.1)
				(type default)
			)
			(layer "F.Fab")
		)
		(fp_line
			(start -0.12065 0.2794)
			(end -0.12065 0.3048)
			(stroke
				(width 0.1)
				(type default)
			)
			(layer "F.Fab")
		)
		(fp_line
			(start -0.12065 0.3048)
			(end -0.67945 0.3048)
			(stroke
				(width 0.1)
				(type default)
			)
			(layer "F.Fab")
		)
		(fp_line
			(start 0.120396 0.2794)
			(end -0.12065 0.2794)
			(stroke
				(width 0.1)
				(type default)
			)
			(layer "F.Fab")
		)
		(fp_line
			(start 0.120396 0.3048)
			(end 0.120396 0.2794)
			(stroke
				(width 0.1)
				(type default)
			)
			(layer "F.Fab")
		)
		(fp_line
			(start 0.12065 -0.3048)
			(end 0.67945 -0.3048)
			(stroke
				(width 0.1)
				(type default)
			)
			(layer "F.Fab")
		)
		(fp_line
			(start 0.12065 -0.2794)
			(end 0.12065 -0.3048)
			(stroke
				(width 0.1)
				(type default)
			)
			(layer "F.Fab")
		)
		(fp_line
			(start 0.67945 -0.3048)
			(end 0.67945 0.3048)
			(stroke
				(width 0.1)
				(type default)
			)
			(layer "F.Fab")
		)
		(fp_line
			(start 0.67945 0.3048)
			(end 0.120396 0.3048)
			(stroke
				(width 0.1)
				(type default)
			)
			(layer "F.Fab")
		)
		(pad "1" smd circle
			(at -0.40005 0)
			(size 0 0)
			(layers "F.Cu" "F.Mask" "F.Paste")
			(net "PRSNT_NIC7_N")
		)
		(pad "2" smd circle
			(at 0.40005 0)
			(size 0 0)
			(layers "F.Cu" "F.Mask" "F.Paste")
			(net "PRSNTB2_NIC7_N")
		)
	)
	(footprint ""
		(layer "F.Cu")
		(at 334.628998 -293.816786 -90)
		(property "Reference" "PC147"
			(at 0 0 270)
			(layer "F.SilkS")
			(hide yes)
			(effects
				(font
					(size 1.27 1.27)
				)
			)
		)
		(property "Value" ""
			(at 0 0 270)
			(layer "F.Fab")
			(effects
				(font
					(size 1.27 1.27)
				)
			)
		)
		(duplicate_pad_numbers_are_jumpers no)
		(fp_line
			(start -0.7874 0.4064)
			(end -0.7874 -0.4064)
			(stroke
				(width 0.1524)
				(type default)
			)
			(layer "F.SilkS")
		)
		(fp_line
			(start 0.7874 0.4064)
			(end -0.7874 0.4064)
			(stroke
				(width 0.1524)
				(type default)
			)
			(layer "F.SilkS")
		)
		(fp_line
			(start -0.7874 -0.4064)
			(end 0.7874 -0.4064)
			(stroke
				(width 0.1524)
				(type default)
			)
			(layer "F.SilkS")
		)
		(fp_line
			(start 0.7874 -0.4064)
			(end 0.7874 0.4064)
			(stroke
				(width 0.1524)
				(type default)
			)
			(layer "F.SilkS")
		)
		(fp_line
			(start -0.67945 0.3048)
			(end -0.67945 -0.305054)
			(stroke
				(width 0.1)
				(type default)
			)
			(layer "F.Fab")
		)
		(fp_line
			(start -0.12065 0.3048)
			(end -0.67945 0.3048)
			(stroke
				(width 0.1)
				(type default)
			)
			(layer "F.Fab")
		)
		(fp_line
			(start 0.120396 0.3048)
			(end 0.120396 0.2794)
			(stroke
				(width 0.1)
				(type default)
			)
			(layer "F.Fab")
		)
		(fp_line
			(start 0.67945 0.3048)
			(end 0.120396 0.3048)
			(stroke
				(width 0.1)
				(type default)
			)
			(layer "F.Fab")
		)
		(fp_line
			(start -0.12065 0.2794)
			(end -0.12065 0.3048)
			(stroke
				(width 0.1)
				(type default)
			)
			(layer "F.Fab")
		)
		(fp_line
			(start 0.120396 0.2794)
			(end -0.12065 0.2794)
			(stroke
				(width 0.1)
				(type default)
			)
			(layer "F.Fab")
		)
		(fp_line
			(start -0.12065 -0.2794)
			(end 0.12065 -0.2794)
			(stroke
				(width 0.1)
				(type default)
			)
			(layer "F.Fab")
		)
		(fp_line
			(start 0.12065 -0.2794)
			(end 0.12065 -0.3048)
			(stroke
				(width 0.1)
				(type default)
			)
			(layer "F.Fab")
		)
		(fp_line
			(start 0.12065 -0.3048)
			(end 0.67945 -0.3048)
			(stroke
				(width 0.1)
				(type default)
			)
			(layer "F.Fab")
		)
		(fp_line
			(start 0.67945 -0.3048)
			(end 0.67945 0.3048)
			(stroke
				(width 0.1)
				(type default)
			)
			(layer "F.Fab")
		)
		(fp_line
			(start -0.67945 -0.305054)
			(end -0.12065 -0.305054)
			(stroke
				(width 0.1)
				(type default)
			)
			(layer "F.Fab")
		)
		(fp_line
			(start -0.12065 -0.305054)
			(end -0.12065 -0.2794)
			(stroke
				(width 0.1)
				(type default)
			)
			(layer "F.Fab")
		)
		(pad "1" smd circle
			(at -0.40005 0 270)
			(size 0 0)
			(layers "F.Cu" "F.Mask" "F.Paste")
			(net "P0V8_PEX2")
		)
		(pad "2" smd circle
			(at 0.40005 0 270)
			(size 0 0)
			(layers "F.Cu" "F.Mask" "F.Paste")
			(net "GND")
		)
	)
	(footprint ""
		(layer "F.Cu")
		(at 52.267866 -56.353456)
		(property "Reference" "C2863"
			(at 0 0 0)
			(layer "F.SilkS")
			(hide yes)
			(effects
				(font
					(size 1.27 1.27)
				)
			)
		)
		(property "Value" ""
			(at 0 0 0)
			(layer "F.Fab")
			(effects
				(font
					(size 1.27 1.27)
				)
			)
		)
		(duplicate_pad_numbers_are_jumpers no)
		(fp_line
			(start -0.7874 -0.4064)
			(end 0.7874 -0.4064)
			(stroke
				(width 0.1524)
				(type default)
			)
			(layer "F.SilkS")
		)
		(fp_line
			(start -0.7874 0.4064)
			(end -0.7874 -0.4064)
			(stroke
				(width 0.1524)
				(type default)
			)
			(layer "F.SilkS")
		)
		(fp_line
			(start 0.7874 -0.4064)
			(end 0.7874 0.4064)
			(stroke
				(width 0.1524)
				(type default)
			)
			(layer "F.SilkS")
		)
		(fp_line
			(start 0.7874 0.4064)
			(end -0.7874 0.4064)
			(stroke
				(width 0.1524)
				(type default)
			)
			(layer "F.SilkS")
		)
		(fp_line
			(start -0.67945 -0.305054)
			(end -0.12065 -0.305054)
			(stroke
				(width 0.1)
				(type default)
			)
			(layer "F.Fab")
		)
		(fp_line
			(start -0.67945 0.3048)
			(end -0.67945 -0.305054)
			(stroke
				(width 0.1)
				(type default)
			)
			(layer "F.Fab")
		)
		(fp_line
			(start -0.12065 -0.305054)
			(end -0.12065 -0.2794)
			(stroke
				(width 0.1)
				(type default)
			)
			(layer "F.Fab")
		)
		(fp_line
			(start -0.12065 -0.2794)
			(end 0.12065 -0.2794)
			(stroke
				(width 0.1)
				(type default)
			)
			(layer "F.Fab")
		)
		(fp_line
			(start -0.12065 0.2794)
			(end -0.12065 0.3048)
			(stroke
				(width 0.1)
				(type default)
			)
			(layer "F.Fab")
		)
		(fp_line
			(start -0.12065 0.3048)
			(end -0.67945 0.3048)
			(stroke
				(width 0.1)
				(type default)
			)
			(layer "F.Fab")
		)
		(fp_line
			(start 0.120396 0.2794)
			(end -0.12065 0.2794)
			(stroke
				(width 0.1)
				(type default)
			)
			(layer "F.Fab")
		)
		(fp_line
			(start 0.120396 0.3048)
			(end 0.120396 0.2794)
			(stroke
				(width 0.1)
				(type default)
			)
			(layer "F.Fab")
		)
		(fp_line
			(start 0.12065 -0.3048)
			(end 0.67945 -0.3048)
			(stroke
				(width 0.1)
				(type default)
			)
			(layer "F.Fab")
		)
		(fp_line
			(start 0.12065 -0.2794)
			(end 0.12065 -0.3048)
			(stroke
				(width 0.1)
				(type default)
			)
			(layer "F.Fab")
		)
		(fp_line
			(start 0.67945 -0.3048)
			(end 0.67945 0.3048)
			(stroke
				(width 0.1)
				(type default)
			)
			(layer "F.Fab")
		)
		(fp_line
			(start 0.67945 0.3048)
			(end 0.120396 0.3048)
			(stroke
				(width 0.1)
				(type default)
			)
			(layer "F.Fab")
		)
		(pad "1" smd circle
			(at -0.40005 0)
			(size 0 0)
			(layers "F.Cu" "F.Mask" "F.Paste")
			(net "SSD1_PWR_EN_R")
		)
		(pad "2" smd circle
			(at 0.40005 0)
			(size 0 0)
			(layers "F.Cu" "F.Mask" "F.Paste")
			(net "GND")
		)
	)
	(footprint ""
		(layer "F.Cu")
		(at 383.59842 -343.952322 90)
		(property "Reference" "C772"
			(at 0 0 90)
			(layer "F.SilkS")
			(hide yes)
			(effects
				(font
					(size 1.27 1.27)
				)
			)
		)
		(property "Value" ""
			(at 0 0 90)
			(layer "F.Fab")
			(effects
				(font
					(size 1.27 1.27)
				)
			)
		)
		(duplicate_pad_numbers_are_jumpers no)
		(fp_line
			(start 0.299974 -0.150114)
			(end 0.299974 0.150114)
			(stroke
				(width 0.1)
				(type default)
			)
			(layer "F.Fab")
		)
		(fp_line
			(start -0.299974 -0.150114)
			(end 0.299974 -0.150114)
			(stroke
				(width 0.1)
				(type default)
			)
			(layer "F.Fab")
		)
		(fp_line
			(start 0.299974 0.150114)
			(end -0.299974 0.150114)
			(stroke
				(width 0.1)
				(type default)
			)
			(layer "F.Fab")
		)
		(fp_line
			(start -0.299974 0.150114)
			(end -0.299974 -0.150114)
			(stroke
				(width 0.1)
				(type default)
			)
			(layer "F.Fab")
		)
		(pad "1" smd rect
			(at -0.2667 0 90)
			(size 0.3048 0.381)
			(layers "F.Cu" "F.Mask" "F.Paste")
			(net "P5E_PEX3_STN6_TX_DP<106>")
		)
		(pad "2" smd rect
			(at 0.2667 0 90)
			(size 0.3048 0.381)
			(layers "F.Cu" "F.Mask" "F.Paste")
			(net "P5E_PEX3_STN6_TX_C_DP<106>")
		)
	)
	(footprint ""
		(layer "F.Cu")
		(at 293.69385 -165.670484 -90)
		(property "Reference" "R2467"
			(at 0 0 270)
			(layer "F.SilkS")
			(hide yes)
			(effects
				(font
					(size 1.27 1.27)
				)
			)
		)
		(property "Value" ""
			(at 0 0 270)
			(layer "F.Fab")
			(effects
				(font
					(size 1.27 1.27)
				)
			)
		)
		(duplicate_pad_numbers_are_jumpers no)
		(fp_line
			(start -0.7874 0.4064)
			(end -0.7874 -0.4064)
			(stroke
				(width 0.1524)
				(type default)
			)
			(layer "F.SilkS")
		)
		(fp_line
			(start 0.7874 0.4064)
			(end -0.7874 0.4064)
			(stroke
				(width 0.1524)
				(type default)
			)
			(layer "F.SilkS")
		)
		(fp_line
			(start -0.7874 -0.4064)
			(end 0.7874 -0.4064)
			(stroke
				(width 0.1524)
				(type default)
			)
			(layer "F.SilkS")
		)
		(fp_line
			(start 0.7874 -0.4064)
			(end 0.7874 0.4064)
			(stroke
				(width 0.1524)
				(type default)
			)
			(layer "F.SilkS")
		)
		(fp_line
			(start -0.67945 0.3048)
			(end -0.67945 -0.305054)
			(stroke
				(width 0.1)
				(type default)
			)
			(layer "F.Fab")
		)
		(fp_line
			(start -0.12065 0.3048)
			(end -0.67945 0.3048)
			(stroke
				(width 0.1)
				(type default)
			)
			(layer "F.Fab")
		)
		(fp_line
			(start 0.120396 0.3048)
			(end 0.120396 0.2794)
			(stroke
				(width 0.1)
				(type default)
			)
			(layer "F.Fab")
		)
		(fp_line
			(start 0.67945 0.3048)
			(end 0.120396 0.3048)
			(stroke
				(width 0.1)
				(type default)
			)
			(layer "F.Fab")
		)
		(fp_line
			(start -0.12065 0.2794)
			(end -0.12065 0.3048)
			(stroke
				(width 0.1)
				(type default)
			)
			(layer "F.Fab")
		)
		(fp_line
			(start 0.120396 0.2794)
			(end -0.12065 0.2794)
			(stroke
				(width 0.1)
				(type default)
			)
			(layer "F.Fab")
		)
		(fp_line
			(start -0.12065 -0.2794)
			(end 0.12065 -0.2794)
			(stroke
				(width 0.1)
				(type default)
			)
			(layer "F.Fab")
		)
		(fp_line
			(start 0.12065 -0.2794)
			(end 0.12065 -0.3048)
			(stroke
				(width 0.1)
				(type default)
			)
			(layer "F.Fab")
		)
		(fp_line
			(start 0.12065 -0.3048)
			(end 0.67945 -0.3048)
			(stroke
				(width 0.1)
				(type default)
			)
			(layer "F.Fab")
		)
		(fp_line
			(start 0.67945 -0.3048)
			(end 0.67945 0.3048)
			(stroke
				(width 0.1)
				(type default)
			)
			(layer "F.Fab")
		)
		(fp_line
			(start -0.67945 -0.305054)
			(end -0.12065 -0.305054)
			(stroke
				(width 0.1)
				(type default)
			)
			(layer "F.Fab")
		)
		(fp_line
			(start -0.12065 -0.305054)
			(end -0.12065 -0.2794)
			(stroke
				(width 0.1)
				(type default)
			)
			(layer "F.Fab")
		)
		(pad "1" smd circle
			(at -0.40005 0 270)
			(size 0 0)
			(layers "F.Cu" "F.Mask" "F.Paste")
			(net "P3V3_NIC4")
		)
		(pad "2" smd circle
			(at 0.40005 0 270)
			(size 0 0)
			(layers "F.Cu" "F.Mask" "F.Paste")
			(net "NIC4_PWRBRK_N")
		)
	)
	(footprint ""
		(layer "F.Cu")
		(at 442.794136 -116.410486)
		(property "Reference" "PR7105"
			(at 0 0 0)
			(layer "F.SilkS")
			(hide yes)
			(effects
				(font
					(size 1.27 1.27)
				)
			)
		)
		(property "Value" ""
			(at 0 0 0)
			(layer "F.Fab")
			(effects
				(font
					(size 1.27 1.27)
				)
			)
		)
		(duplicate_pad_numbers_are_jumpers no)
		(fp_line
			(start -0.7874 -0.4064)
			(end 0.7874 -0.4064)
			(stroke
				(width 0.1524)
				(type default)
			)
			(layer "F.SilkS")
		)
		(fp_line
			(start -0.7874 0.4064)
			(end -0.7874 -0.4064)
			(stroke
				(width 0.1524)
				(type default)
			)
			(layer "F.SilkS")
		)
		(fp_line
			(start 0.7874 -0.4064)
			(end 0.7874 0.4064)
			(stroke
				(width 0.1524)
				(type default)
			)
			(layer "F.SilkS")
		)
		(fp_line
			(start 0.7874 0.4064)
			(end -0.7874 0.4064)
			(stroke
				(width 0.1524)
				(type default)
			)
			(layer "F.SilkS")
		)
		(fp_line
			(start -0.67945 -0.305054)
			(end -0.12065 -0.305054)
			(stroke
				(width 0.1)
				(type default)
			)
			(layer "F.Fab")
		)
		(fp_line
			(start -0.67945 0.3048)
			(end -0.67945 -0.305054)
			(stroke
				(width 0.1)
				(type default)
			)
			(layer "F.Fab")
		)
		(fp_line
			(start -0.12065 -0.305054)
			(end -0.12065 -0.2794)
			(stroke
				(width 0.1)
				(type default)
			)
			(layer "F.Fab")
		)
		(fp_line
			(start -0.12065 -0.2794)
			(end 0.12065 -0.2794)
			(stroke
				(width 0.1)
				(type default)
			)
			(layer "F.Fab")
		)
		(fp_line
			(start -0.12065 0.2794)
			(end -0.12065 0.3048)
			(stroke
				(width 0.1)
				(type default)
			)
			(layer "F.Fab")
		)
		(fp_line
			(start -0.12065 0.3048)
			(end -0.67945 0.3048)
			(stroke
				(width 0.1)
				(type default)
			)
			(layer "F.Fab")
		)
		(fp_line
			(start 0.120396 0.2794)
			(end -0.12065 0.2794)
			(stroke
				(width 0.1)
				(type default)
			)
			(layer "F.Fab")
		)
		(fp_line
			(start 0.120396 0.3048)
			(end 0.120396 0.2794)
			(stroke
				(width 0.1)
				(type default)
			)
			(layer "F.Fab")
		)
		(fp_line
			(start 0.12065 -0.3048)
			(end 0.67945 -0.3048)
			(stroke
				(width 0.1)
				(type default)
			)
			(layer "F.Fab")
		)
		(fp_line
			(start 0.12065 -0.2794)
			(end 0.12065 -0.3048)
			(stroke
				(width 0.1)
				(type default)
			)
			(layer "F.Fab")
		)
		(fp_line
			(start 0.67945 -0.3048)
			(end 0.67945 0.3048)
			(stroke
				(width 0.1)
				(type default)
			)
			(layer "F.Fab")
		)
		(fp_line
			(start 0.67945 0.3048)
			(end 0.120396 0.3048)
			(stroke
				(width 0.1)
				(type default)
			)
			(layer "F.Fab")
		)
		(pad "1" smd circle
			(at -0.40005 0)
			(size 0 0)
			(layers "F.Cu" "F.Mask" "F.Paste")
			(net "P3V3_NIC7_CO_MODE")
		)
		(pad "2" smd circle
			(at 0.40005 0)
			(size 0 0)
			(layers "F.Cu" "F.Mask" "F.Paste")
			(net "GND")
		)
	)
	(footprint ""
		(layer "F.Cu")
		(at 365.24692 -261.606538 90)
		(property "Reference" "C3657"
			(at 0 0 90)
			(layer "F.SilkS")
			(hide yes)
			(effects
				(font
					(size 1.27 1.27)
				)
			)
		)
		(property "Value" ""
			(at 0 0 90)
			(layer "F.Fab")
			(effects
				(font
					(size 1.27 1.27)
				)
			)
		)
		(duplicate_pad_numbers_are_jumpers no)
		(fp_line
			(start 0.7874 -0.4064)
			(end 0.7874 0.4064)
			(stroke
				(width 0.1524)
				(type default)
			)
			(layer "F.SilkS")
		)
		(fp_line
			(start -0.7874 -0.4064)
			(end 0.7874 -0.4064)
			(stroke
				(width 0.1524)
				(type default)
			)
			(layer "F.SilkS")
		)
		(fp_line
			(start 0.7874 0.4064)
			(end -0.7874 0.4064)
			(stroke
				(width 0.1524)
				(type default)
			)
			(layer "F.SilkS")
		)
		(fp_line
			(start -0.7874 0.4064)
			(end -0.7874 -0.4064)
			(stroke
				(width 0.1524)
				(type default)
			)
			(layer "F.SilkS")
		)
		(fp_line
			(start -0.12065 -0.305054)
			(end -0.12065 -0.2794)
			(stroke
				(width 0.1)
				(type default)
			)
			(layer "F.Fab")
		)
		(fp_line
			(start -0.67945 -0.305054)
			(end -0.12065 -0.305054)
			(stroke
				(width 0.1)
				(type default)
			)
			(layer "F.Fab")
		)
		(fp_line
			(start 0.67945 -0.3048)
			(end 0.67945 0.3048)
			(stroke
				(width 0.1)
				(type default)
			)
			(layer "F.Fab")
		)
		(fp_line
			(start 0.12065 -0.3048)
			(end 0.67945 -0.3048)
			(stroke
				(width 0.1)
				(type default)
			)
			(layer "F.Fab")
		)
		(fp_line
			(start 0.12065 -0.2794)
			(end 0.12065 -0.3048)
			(stroke
				(width 0.1)
				(type default)
			)
			(layer "F.Fab")
		)
		(fp_line
			(start -0.12065 -0.2794)
			(end 0.12065 -0.2794)
			(stroke
				(width 0.1)
				(type default)
			)
			(layer "F.Fab")
		)
		(fp_line
			(start 0.120396 0.2794)
			(end -0.12065 0.2794)
			(stroke
				(width 0.1)
				(type default)
			)
			(layer "F.Fab")
		)
		(fp_line
			(start -0.12065 0.2794)
			(end -0.12065 0.3048)
			(stroke
				(width 0.1)
				(type default)
			)
			(layer "F.Fab")
		)
		(fp_line
			(start 0.67945 0.3048)
			(end 0.120396 0.3048)
			(stroke
				(width 0.1)
				(type default)
			)
			(layer "F.Fab")
		)
		(fp_line
			(start 0.120396 0.3048)
			(end 0.120396 0.2794)
			(stroke
				(width 0.1)
				(type default)
			)
			(layer "F.Fab")
		)
		(fp_line
			(start -0.12065 0.3048)
			(end -0.67945 0.3048)
			(stroke
				(width 0.1)
				(type default)
			)
			(layer "F.Fab")
		)
		(fp_line
			(start -0.67945 0.3048)
			(end -0.67945 -0.305054)
			(stroke
				(width 0.1)
				(type default)
			)
			(layer "F.Fab")
		)
		(pad "1" smd circle
			(at -0.40005 0 90)
			(size 0 0)
			(layers "F.Cu" "F.Mask" "F.Paste")
			(net "P3V3_AUX")
		)
		(pad "2" smd circle
			(at 0.40005 0 90)
			(size 0 0)
			(layers "F.Cu" "F.Mask" "F.Paste")
			(net "GND")
		)
	)
	(footprint ""
		(layer "F.Cu")
		(at 345.934792 -240.691162 -90)
		(property "Reference" "R3540"
			(at 0 0 270)
			(layer "F.SilkS")
			(hide yes)
			(effects
				(font
					(size 1.27 1.27)
				)
			)
		)
		(property "Value" ""
			(at 0 0 270)
			(layer "F.Fab")
			(effects
				(font
					(size 1.27 1.27)
				)
			)
		)
		(duplicate_pad_numbers_are_jumpers no)
		(fp_line
			(start -0.7874 0.4064)
			(end -0.7874 -0.4064)
			(stroke
				(width 0.1524)
				(type default)
			)
			(layer "F.SilkS")
		)
		(fp_line
			(start 0.7874 0.4064)
			(end -0.7874 0.4064)
			(stroke
				(width 0.1524)
				(type default)
			)
			(layer "F.SilkS")
		)
		(fp_line
			(start -0.7874 -0.4064)
			(end 0.7874 -0.4064)
			(stroke
				(width 0.1524)
				(type default)
			)
			(layer "F.SilkS")
		)
		(fp_line
			(start 0.7874 -0.4064)
			(end 0.7874 0.4064)
			(stroke
				(width 0.1524)
				(type default)
			)
			(layer "F.SilkS")
		)
		(fp_line
			(start -0.67945 0.3048)
			(end -0.67945 -0.305054)
			(stroke
				(width 0.1)
				(type default)
			)
			(layer "F.Fab")
		)
		(fp_line
			(start -0.12065 0.3048)
			(end -0.67945 0.3048)
			(stroke
				(width 0.1)
				(type default)
			)
			(layer "F.Fab")
		)
		(fp_line
			(start 0.120396 0.3048)
			(end 0.120396 0.2794)
			(stroke
				(width 0.1)
				(type default)
			)
			(layer "F.Fab")
		)
		(fp_line
			(start 0.67945 0.3048)
			(end 0.120396 0.3048)
			(stroke
				(width 0.1)
				(type default)
			)
			(layer "F.Fab")
		)
		(fp_line
			(start -0.12065 0.2794)
			(end -0.12065 0.3048)
			(stroke
				(width 0.1)
				(type default)
			)
			(layer "F.Fab")
		)
		(fp_line
			(start 0.120396 0.2794)
			(end -0.12065 0.2794)
			(stroke
				(width 0.1)
				(type default)
			)
			(layer "F.Fab")
		)
		(fp_line
			(start -0.12065 -0.2794)
			(end 0.12065 -0.2794)
			(stroke
				(width 0.1)
				(type default)
			)
			(layer "F.Fab")
		)
		(fp_line
			(start 0.12065 -0.2794)
			(end 0.12065 -0.3048)
			(stroke
				(width 0.1)
				(type default)
			)
			(layer "F.Fab")
		)
		(fp_line
			(start 0.12065 -0.3048)
			(end 0.67945 -0.3048)
			(stroke
				(width 0.1)
				(type default)
			)
			(layer "F.Fab")
		)
		(fp_line
			(start 0.67945 -0.3048)
			(end 0.67945 0.3048)
			(stroke
				(width 0.1)
				(type default)
			)
			(layer "F.Fab")
		)
		(fp_line
			(start -0.67945 -0.305054)
			(end -0.12065 -0.305054)
			(stroke
				(width 0.1)
				(type default)
			)
			(layer "F.Fab")
		)
		(fp_line
			(start -0.12065 -0.305054)
			(end -0.12065 -0.2794)
			(stroke
				(width 0.1)
				(type default)
			)
			(layer "F.Fab")
		)
		(pad "1" smd circle
			(at -0.40005 0 270)
			(size 0 0)
			(layers "F.Cu" "F.Mask" "F.Paste")
			(net "SMB_FPGA_ALERT_R_N")
		)
		(pad "2" smd circle
			(at 0.40005 0 270)
			(size 0 0)
			(layers "F.Cu" "F.Mask" "F.Paste")
			(net "SMB_FPGA_ALERT_N")
		)
	)
	(footprint ""
		(layer "F.Cu")
		(at 88.835992 -289.230816 90)
		(property "Reference" "R3892"
			(at 0 0 90)
			(layer "F.SilkS")
			(hide yes)
			(effects
				(font
					(size 1.27 1.27)
				)
			)
		)
		(property "Value" ""
			(at 0 0 90)
			(layer "F.Fab")
			(effects
				(font
					(size 1.27 1.27)
				)
			)
		)
		(duplicate_pad_numbers_are_jumpers no)
		(fp_line
			(start 0.7874 -0.4064)
			(end 0.7874 0.4064)
			(stroke
				(width 0.1524)
				(type default)
			)
			(layer "F.SilkS")
		)
		(fp_line
			(start -0.7874 -0.4064)
			(end 0.7874 -0.4064)
			(stroke
				(width 0.1524)
				(type default)
			)
			(layer "F.SilkS")
		)
		(fp_line
			(start 0.7874 0.4064)
			(end -0.7874 0.4064)
			(stroke
				(width 0.1524)
				(type default)
			)
			(layer "F.SilkS")
		)
		(fp_line
			(start -0.7874 0.4064)
			(end -0.7874 -0.4064)
			(stroke
				(width 0.1524)
				(type default)
			)
			(layer "F.SilkS")
		)
		(fp_line
			(start -0.12065 -0.305054)
			(end -0.12065 -0.2794)
			(stroke
				(width 0.1)
				(type default)
			)
			(layer "F.Fab")
		)
		(fp_line
			(start -0.67945 -0.305054)
			(end -0.12065 -0.305054)
			(stroke
				(width 0.1)
				(type default)
			)
			(layer "F.Fab")
		)
		(fp_line
			(start 0.67945 -0.3048)
			(end 0.67945 0.3048)
			(stroke
				(width 0.1)
				(type default)
			)
			(layer "F.Fab")
		)
		(fp_line
			(start 0.12065 -0.3048)
			(end 0.67945 -0.3048)
			(stroke
				(width 0.1)
				(type default)
			)
			(layer "F.Fab")
		)
		(fp_line
			(start 0.12065 -0.2794)
			(end 0.12065 -0.3048)
			(stroke
				(width 0.1)
				(type default)
			)
			(layer "F.Fab")
		)
		(fp_line
			(start -0.12065 -0.2794)
			(end 0.12065 -0.2794)
			(stroke
				(width 0.1)
				(type default)
			)
			(layer "F.Fab")
		)
		(fp_line
			(start 0.120396 0.2794)
			(end -0.12065 0.2794)
			(stroke
				(width 0.1)
				(type default)
			)
			(layer "F.Fab")
		)
		(fp_line
			(start -0.12065 0.2794)
			(end -0.12065 0.3048)
			(stroke
				(width 0.1)
				(type default)
			)
			(layer "F.Fab")
		)
		(fp_line
			(start 0.67945 0.3048)
			(end 0.120396 0.3048)
			(stroke
				(width 0.1)
				(type default)
			)
			(layer "F.Fab")
		)
		(fp_line
			(start 0.120396 0.3048)
			(end 0.120396 0.2794)
			(stroke
				(width 0.1)
				(type default)
			)
			(layer "F.Fab")
		)
		(fp_line
			(start -0.12065 0.3048)
			(end -0.67945 0.3048)
			(stroke
				(width 0.1)
				(type default)
			)
			(layer "F.Fab")
		)
		(fp_line
			(start -0.67945 0.3048)
			(end -0.67945 -0.305054)
			(stroke
				(width 0.1)
				(type default)
			)
			(layer "F.Fab")
		)
		(pad "1" smd circle
			(at -0.40005 0 90)
			(size 0 0)
			(layers "F.Cu" "F.Mask" "F.Paste")
			(net "SMB_PEX0_FPGA_SDA")
		)
		(pad "2" smd circle
			(at 0.40005 0 90)
			(size 0 0)
			(layers "F.Cu" "F.Mask" "F.Paste")
			(net "SMB_PEX0_HOST_LS_SDA")
		)
	)
	(footprint ""
		(layer "F.Cu")
		(at 265.487658 -285.218632)
		(property "Reference" "C3406"
			(at 0 0 0)
			(layer "F.SilkS")
			(hide yes)
			(effects
				(font
					(size 1.27 1.27)
				)
			)
		)
		(property "Value" ""
			(at 0 0 0)
			(layer "F.Fab")
			(effects
				(font
					(size 1.27 1.27)
				)
			)
		)
		(duplicate_pad_numbers_are_jumpers no)
		(fp_line
			(start -1.2954 -0.5842)
			(end 1.2954 -0.5842)
			(stroke
				(width 0.1524)
				(type default)
			)
			(layer "F.SilkS")
		)
		(fp_line
			(start -1.2954 0.5842)
			(end -1.2954 -0.5842)
			(stroke
				(width 0.1524)
				(type default)
			)
			(layer "F.SilkS")
		)
		(fp_line
			(start 1.2954 -0.5842)
			(end 1.2954 0.5842)
			(stroke
				(width 0.1524)
				(type default)
			)
			(layer "F.SilkS")
		)
		(fp_line
			(start 1.2954 0.5842)
			(end -1.2954 0.5842)
			(stroke
				(width 0.1524)
				(type default)
			)
			(layer "F.SilkS")
		)
		(fp_line
			(start -1.1938 -0.4064)
			(end -0.8636 -0.4064)
			(stroke
				(width 0.1)
				(type default)
			)
			(layer "F.Fab")
		)
		(fp_line
			(start -1.1938 0.4064)
			(end -1.1938 -0.4064)
			(stroke
				(width 0.1)
				(type default)
			)
			(layer "F.Fab")
		)
		(fp_line
			(start -0.8636 -0.4572)
			(end 0.8636 -0.4572)
			(stroke
				(width 0.1)
				(type default)
			)
			(layer "F.Fab")
		)
		(fp_line
			(start -0.8636 -0.4064)
			(end -0.8636 -0.4572)
			(stroke
				(width 0.1)
				(type default)
			)
			(layer "F.Fab")
		)
		(fp_line
			(start -0.8636 0.4064)
			(end -1.1938 0.4064)
			(stroke
				(width 0.1)
				(type default)
			)
			(layer "F.Fab")
		)
		(fp_line
			(start -0.8636 0.4572)
			(end -0.8636 0.4064)
			(stroke
				(width 0.1)
				(type default)
			)
			(layer "F.Fab")
		)
		(fp_line
			(start 0.8636 -0.4572)
			(end 0.8636 -0.4064)
			(stroke
				(width 0.1)
				(type default)
			)
			(layer "F.Fab")
		)
		(fp_line
			(start 0.8636 -0.4064)
			(end 1.1938 -0.4064)
			(stroke
				(width 0.1)
				(type default)
			)
			(layer "F.Fab")
		)
		(fp_line
			(start 0.8636 0.4064)
			(end 0.8636 0.4572)
			(stroke
				(width 0.1)
				(type default)
			)
			(layer "F.Fab")
		)
		(fp_line
			(start 0.8636 0.4572)
			(end -0.8636 0.4572)
			(stroke
				(width 0.1)
				(type default)
			)
			(layer "F.Fab")
		)
		(fp_line
			(start 1.1938 -0.4064)
			(end 1.1938 0.4064)
			(stroke
				(width 0.1)
				(type default)
			)
			(layer "F.Fab")
		)
		(fp_line
			(start 1.1938 0.4064)
			(end 0.8636 0.4064)
			(stroke
				(width 0.1)
				(type default)
			)
			(layer "F.Fab")
		)
		(pad "1" smd rect
			(at -0.7366 0 270)
			(size 0.7112 0.8128)
			(layers "F.Cu" "F.Mask" "F.Paste")
			(net "PCEPLL7_VDDA18_PEX2")
		)
		(pad "2" smd rect
			(at 0.7366 0 270)
			(size 0.7112 0.8128)
			(layers "F.Cu" "F.Mask" "F.Paste")
			(net "GND")
		)
	)
	(footprint ""
		(layer "F.Cu")
		(at 439.469022 -123.067318 90)
		(property "Reference" "PC491"
			(at 0 0 90)
			(layer "F.SilkS")
			(hide yes)
			(effects
				(font
					(size 1.27 1.27)
				)
			)
		)
		(property "Value" ""
			(at 0 0 90)
			(layer "F.Fab")
			(effects
				(font
					(size 1.27 1.27)
				)
			)
		)
		(duplicate_pad_numbers_are_jumpers no)
		(fp_line
			(start 1.524 -0.762)
			(end 1.524 0.762)
			(stroke
				(width 0.1524)
				(type default)
			)
			(layer "F.SilkS")
		)
		(fp_line
			(start -1.524 -0.762)
			(end 1.524 -0.762)
			(stroke
				(width 0.1524)
				(type default)
			)
			(layer "F.SilkS")
		)
		(fp_line
			(start 1.524 0.762)
			(end -1.524 0.762)
			(stroke
				(width 0.1524)
				(type default)
			)
			(layer "F.SilkS")
		)
		(fp_line
			(start -1.524 0.762)
			(end -1.524 -0.762)
			(stroke
				(width 0.1524)
				(type default)
			)
			(layer "F.SilkS")
		)
		(fp_line
			(start 1.1049 -0.724916)
			(end -1.1049 -0.724916)
			(stroke
				(width 0.1)
				(type default)
			)
			(layer "F.Fab")
		)
		(fp_line
			(start -1.1049 -0.724916)
			(end -1.1049 0.724916)
			(stroke
				(width 0.1)
				(type default)
			)
			(layer "F.Fab")
		)
		(fp_line
			(start 1.1049 0.724916)
			(end 1.1049 -0.724916)
			(stroke
				(width 0.1)
				(type default)
			)
			(layer "F.Fab")
		)
		(fp_line
			(start -1.1049 0.724916)
			(end 1.1049 0.724916)
			(stroke
				(width 0.1)
				(type default)
			)
			(layer "F.Fab")
		)
		(pad "1" smd rect
			(at -0.889 0 270)
			(size 1.016 1.27)
			(layers "F.Cu" "F.Mask" "F.Paste")
			(net "P3V3_NIC7")
		)
		(pad "2" smd rect
			(at 0.889 0 270)
			(size 1.016 1.27)
			(layers "F.Cu" "F.Mask" "F.Paste")
			(net "GND")
		)
	)
	(footprint ""
		(layer "F.Cu")
		(at 35.3695 -256.888234 -90)
		(property "Reference" "R4563"
			(at 0 0 270)
			(layer "F.SilkS")
			(hide yes)
			(effects
				(font
					(size 1.27 1.27)
				)
			)
		)
		(property "Value" ""
			(at 0 0 270)
			(layer "F.Fab")
			(effects
				(font
					(size 1.27 1.27)
				)
			)
		)
		(duplicate_pad_numbers_are_jumpers no)
		(fp_line
			(start -0.7874 0.4064)
			(end -0.7874 -0.4064)
			(stroke
				(width 0.1524)
				(type default)
			)
			(layer "F.SilkS")
		)
		(fp_line
			(start 0.7874 0.4064)
			(end -0.7874 0.4064)
			(stroke
				(width 0.1524)
				(type default)
			)
			(layer "F.SilkS")
		)
		(fp_line
			(start -0.7874 -0.4064)
			(end 0.7874 -0.4064)
			(stroke
				(width 0.1524)
				(type default)
			)
			(layer "F.SilkS")
		)
		(fp_line
			(start 0.7874 -0.4064)
			(end 0.7874 0.4064)
			(stroke
				(width 0.1524)
				(type default)
			)
			(layer "F.SilkS")
		)
		(fp_line
			(start -0.67945 0.3048)
			(end -0.67945 -0.305054)
			(stroke
				(width 0.1)
				(type default)
			)
			(layer "F.Fab")
		)
		(fp_line
			(start -0.12065 0.3048)
			(end -0.67945 0.3048)
			(stroke
				(width 0.1)
				(type default)
			)
			(layer "F.Fab")
		)
		(fp_line
			(start 0.120396 0.3048)
			(end 0.120396 0.2794)
			(stroke
				(width 0.1)
				(type default)
			)
			(layer "F.Fab")
		)
		(fp_line
			(start 0.67945 0.3048)
			(end 0.120396 0.3048)
			(stroke
				(width 0.1)
				(type default)
			)
			(layer "F.Fab")
		)
		(fp_line
			(start -0.12065 0.2794)
			(end -0.12065 0.3048)
			(stroke
				(width 0.1)
				(type default)
			)
			(layer "F.Fab")
		)
		(fp_line
			(start 0.120396 0.2794)
			(end -0.12065 0.2794)
			(stroke
				(width 0.1)
				(type default)
			)
			(layer "F.Fab")
		)
		(fp_line
			(start -0.12065 -0.2794)
			(end 0.12065 -0.2794)
			(stroke
				(width 0.1)
				(type default)
			)
			(layer "F.Fab")
		)
		(fp_line
			(start 0.12065 -0.2794)
			(end 0.12065 -0.3048)
			(stroke
				(width 0.1)
				(type default)
			)
			(layer "F.Fab")
		)
		(fp_line
			(start 0.12065 -0.3048)
			(end 0.67945 -0.3048)
			(stroke
				(width 0.1)
				(type default)
			)
			(layer "F.Fab")
		)
		(fp_line
			(start 0.67945 -0.3048)
			(end 0.67945 0.3048)
			(stroke
				(width 0.1)
				(type default)
			)
			(layer "F.Fab")
		)
		(fp_line
			(start -0.67945 -0.305054)
			(end -0.12065 -0.305054)
			(stroke
				(width 0.1)
				(type default)
			)
			(layer "F.Fab")
		)
		(fp_line
			(start -0.12065 -0.305054)
			(end -0.12065 -0.2794)
			(stroke
				(width 0.1)
				(type default)
			)
			(layer "F.Fab")
		)
		(pad "1" smd circle
			(at -0.40005 0 270)
			(size 0 0)
			(layers "F.Cu" "F.Mask" "F.Paste")
			(net "PCEPLL5_VDDA18_PEX0")
		)
		(pad "2" smd circle
			(at 0.40005 0 270)
			(size 0 0)
			(layers "F.Cu" "F.Mask" "F.Paste")
			(net "PCEPLL5_VDDA18_PEX0_R")
		)
	)
	(footprint ""
		(layer "F.Cu")
		(at 98.27387 -72.766682 90)
		(property "Reference" "PR6911"
			(at 0 0 90)
			(layer "F.SilkS")
			(hide yes)
			(effects
				(font
					(size 1.27 1.27)
				)
			)
		)
		(property "Value" ""
			(at 0 0 90)
			(layer "F.Fab")
			(effects
				(font
					(size 1.27 1.27)
				)
			)
		)
		(duplicate_pad_numbers_are_jumpers no)
		(fp_line
			(start 0.7874 -0.4064)
			(end 0.7874 0.4064)
			(stroke
				(width 0.1524)
				(type default)
			)
			(layer "F.SilkS")
		)
		(fp_line
			(start -0.7874 -0.4064)
			(end 0.7874 -0.4064)
			(stroke
				(width 0.1524)
				(type default)
			)
			(layer "F.SilkS")
		)
		(fp_line
			(start 0.7874 0.4064)
			(end -0.7874 0.4064)
			(stroke
				(width 0.1524)
				(type default)
			)
			(layer "F.SilkS")
		)
		(fp_line
			(start -0.7874 0.4064)
			(end -0.7874 -0.4064)
			(stroke
				(width 0.1524)
				(type default)
			)
			(layer "F.SilkS")
		)
		(fp_line
			(start -0.12065 -0.305054)
			(end -0.12065 -0.2794)
			(stroke
				(width 0.1)
				(type default)
			)
			(layer "F.Fab")
		)
		(fp_line
			(start -0.67945 -0.305054)
			(end -0.12065 -0.305054)
			(stroke
				(width 0.1)
				(type default)
			)
			(layer "F.Fab")
		)
		(fp_line
			(start 0.67945 -0.3048)
			(end 0.67945 0.3048)
			(stroke
				(width 0.1)
				(type default)
			)
			(layer "F.Fab")
		)
		(fp_line
			(start 0.12065 -0.3048)
			(end 0.67945 -0.3048)
			(stroke
				(width 0.1)
				(type default)
			)
			(layer "F.Fab")
		)
		(fp_line
			(start 0.12065 -0.2794)
			(end 0.12065 -0.3048)
			(stroke
				(width 0.1)
				(type default)
			)
			(layer "F.Fab")
		)
		(fp_line
			(start -0.12065 -0.2794)
			(end 0.12065 -0.2794)
			(stroke
				(width 0.1)
				(type default)
			)
			(layer "F.Fab")
		)
		(fp_line
			(start 0.120396 0.2794)
			(end -0.12065 0.2794)
			(stroke
				(width 0.1)
				(type default)
			)
			(layer "F.Fab")
		)
		(fp_line
			(start -0.12065 0.2794)
			(end -0.12065 0.3048)
			(stroke
				(width 0.1)
				(type default)
			)
			(layer "F.Fab")
		)
		(fp_line
			(start 0.67945 0.3048)
			(end 0.120396 0.3048)
			(stroke
				(width 0.1)
				(type default)
			)
			(layer "F.Fab")
		)
		(fp_line
			(start 0.120396 0.3048)
			(end 0.120396 0.2794)
			(stroke
				(width 0.1)
				(type default)
			)
			(layer "F.Fab")
		)
		(fp_line
			(start -0.12065 0.3048)
			(end -0.67945 0.3048)
			(stroke
				(width 0.1)
				(type default)
			)
			(layer "F.Fab")
		)
		(fp_line
			(start -0.67945 0.3048)
			(end -0.67945 -0.305054)
			(stroke
				(width 0.1)
				(type default)
			)
			(layer "F.Fab")
		)
		(pad "1" smd circle
			(at -0.40005 0 90)
			(size 0 0)
			(layers "F.Cu" "F.Mask" "F.Paste")
			(net "P12V_SSD3_CO_MODE")
		)
		(pad "2" smd circle
			(at 0.40005 0 90)
			(size 0 0)
			(layers "F.Cu" "F.Mask" "F.Paste")
			(net "GND")
		)
	)
	(footprint ""
		(layer "F.Cu")
		(at 52.267866 -55.083456)
		(property "Reference" "PC421"
			(at 0 0 0)
			(layer "F.SilkS")
			(hide yes)
			(effects
				(font
					(size 1.27 1.27)
				)
			)
		)
		(property "Value" ""
			(at 0 0 0)
			(layer "F.Fab")
			(effects
				(font
					(size 1.27 1.27)
				)
			)
		)
		(duplicate_pad_numbers_are_jumpers no)
		(fp_line
			(start -0.7874 -0.4064)
			(end 0.7874 -0.4064)
			(stroke
				(width 0.1524)
				(type default)
			)
			(layer "F.SilkS")
		)
		(fp_line
			(start -0.7874 0.4064)
			(end -0.7874 -0.4064)
			(stroke
				(width 0.1524)
				(type default)
			)
			(layer "F.SilkS")
		)
		(fp_line
			(start 0.7874 -0.4064)
			(end 0.7874 0.4064)
			(stroke
				(width 0.1524)
				(type default)
			)
			(layer "F.SilkS")
		)
		(fp_line
			(start 0.7874 0.4064)
			(end -0.7874 0.4064)
			(stroke
				(width 0.1524)
				(type default)
			)
			(layer "F.SilkS")
		)
		(fp_line
			(start -0.67945 -0.305054)
			(end -0.12065 -0.305054)
			(stroke
				(width 0.1)
				(type default)
			)
			(layer "F.Fab")
		)
		(fp_line
			(start -0.67945 0.3048)
			(end -0.67945 -0.305054)
			(stroke
				(width 0.1)
				(type default)
			)
			(layer "F.Fab")
		)
		(fp_line
			(start -0.12065 -0.305054)
			(end -0.12065 -0.2794)
			(stroke
				(width 0.1)
				(type default)
			)
			(layer "F.Fab")
		)
		(fp_line
			(start -0.12065 -0.2794)
			(end 0.12065 -0.2794)
			(stroke
				(width 0.1)
				(type default)
			)
			(layer "F.Fab")
		)
		(fp_line
			(start -0.12065 0.2794)
			(end -0.12065 0.3048)
			(stroke
				(width 0.1)
				(type default)
			)
			(layer "F.Fab")
		)
		(fp_line
			(start -0.12065 0.3048)
			(end -0.67945 0.3048)
			(stroke
				(width 0.1)
				(type default)
			)
			(layer "F.Fab")
		)
		(fp_line
			(start 0.120396 0.2794)
			(end -0.12065 0.2794)
			(stroke
				(width 0.1)
				(type default)
			)
			(layer "F.Fab")
		)
		(fp_line
			(start 0.120396 0.3048)
			(end 0.120396 0.2794)
			(stroke
				(width 0.1)
				(type default)
			)
			(layer "F.Fab")
		)
		(fp_line
			(start 0.12065 -0.3048)
			(end 0.67945 -0.3048)
			(stroke
				(width 0.1)
				(type default)
			)
			(layer "F.Fab")
		)
		(fp_line
			(start 0.12065 -0.2794)
			(end 0.12065 -0.3048)
			(stroke
				(width 0.1)
				(type default)
			)
			(layer "F.Fab")
		)
		(fp_line
			(start 0.67945 -0.3048)
			(end 0.67945 0.3048)
			(stroke
				(width 0.1)
				(type default)
			)
			(layer "F.Fab")
		)
		(fp_line
			(start 0.67945 0.3048)
			(end 0.120396 0.3048)
			(stroke
				(width 0.1)
				(type default)
			)
			(layer "F.Fab")
		)
		(pad "1" smd circle
			(at -0.40005 0)
			(size 0 0)
			(layers "F.Cu" "F.Mask" "F.Paste")
			(net "P5V_AUX")
		)
		(pad "2" smd circle
			(at 0.40005 0)
			(size 0 0)
			(layers "F.Cu" "F.Mask" "F.Paste")
			(net "GND")
		)
	)
	(footprint ""
		(layer "F.Cu")
		(at 152.738328 -120.113298)
		(property "Reference" "C259"
			(at 0 0 0)
			(layer "F.SilkS")
			(hide yes)
			(effects
				(font
					(size 1.27 1.27)
				)
			)
		)
		(property "Value" ""
			(at 0 0 0)
			(layer "F.Fab")
			(effects
				(font
					(size 1.27 1.27)
				)
			)
		)
		(duplicate_pad_numbers_are_jumpers no)
		(fp_line
			(start -0.299974 -0.150114)
			(end 0.299974 -0.150114)
			(stroke
				(width 0.1)
				(type default)
			)
			(layer "F.Fab")
		)
		(fp_line
			(start -0.299974 0.150114)
			(end -0.299974 -0.150114)
			(stroke
				(width 0.1)
				(type default)
			)
			(layer "F.Fab")
		)
		(fp_line
			(start 0.299974 -0.150114)
			(end 0.299974 0.150114)
			(stroke
				(width 0.1)
				(type default)
			)
			(layer "F.Fab")
		)
		(fp_line
			(start 0.299974 0.150114)
			(end -0.299974 0.150114)
			(stroke
				(width 0.1)
				(type default)
			)
			(layer "F.Fab")
		)
		(pad "1" smd rect
			(at -0.2667 0)
			(size 0.3048 0.381)
			(layers "F.Cu" "F.Mask" "F.Paste")
			(net "P5E_PEX1_STN1_TX_DN<24>")
		)
		(pad "2" smd rect
			(at 0.2667 0)
			(size 0.3048 0.381)
			(layers "F.Cu" "F.Mask" "F.Paste")
			(net "P5E_PEX1_STN1_TX_C_DN<24>")
		)
	)
	(footprint ""
		(layer "F.Cu")
		(at 411.77083 -138.864848)
		(property "Reference" "R397"
			(at 0 0 0)
			(layer "F.SilkS")
			(hide yes)
			(effects
				(font
					(size 1.27 1.27)
				)
			)
		)
		(property "Value" ""
			(at 0 0 0)
			(layer "F.Fab")
			(effects
				(font
					(size 1.27 1.27)
				)
			)
		)
		(duplicate_pad_numbers_are_jumpers no)
		(fp_line
			(start -0.7874 -0.4064)
			(end 0.7874 -0.4064)
			(stroke
				(width 0.1524)
				(type default)
			)
			(layer "F.SilkS")
		)
		(fp_line
			(start -0.7874 0.4064)
			(end -0.7874 -0.4064)
			(stroke
				(width 0.1524)
				(type default)
			)
			(layer "F.SilkS")
		)
		(fp_line
			(start 0.7874 -0.4064)
			(end 0.7874 0.4064)
			(stroke
				(width 0.1524)
				(type default)
			)
			(layer "F.SilkS")
		)
		(fp_line
			(start 0.7874 0.4064)
			(end -0.7874 0.4064)
			(stroke
				(width 0.1524)
				(type default)
			)
			(layer "F.SilkS")
		)
		(fp_line
			(start -0.67945 -0.305054)
			(end -0.12065 -0.305054)
			(stroke
				(width 0.1)
				(type default)
			)
			(layer "F.Fab")
		)
		(fp_line
			(start -0.67945 0.3048)
			(end -0.67945 -0.305054)
			(stroke
				(width 0.1)
				(type default)
			)
			(layer "F.Fab")
		)
		(fp_line
			(start -0.12065 -0.305054)
			(end -0.12065 -0.2794)
			(stroke
				(width 0.1)
				(type default)
			)
			(layer "F.Fab")
		)
		(fp_line
			(start -0.12065 -0.2794)
			(end 0.12065 -0.2794)
			(stroke
				(width 0.1)
				(type default)
			)
			(layer "F.Fab")
		)
		(fp_line
			(start -0.12065 0.2794)
			(end -0.12065 0.3048)
			(stroke
				(width 0.1)
				(type default)
			)
			(layer "F.Fab")
		)
		(fp_line
			(start -0.12065 0.3048)
			(end -0.67945 0.3048)
			(stroke
				(width 0.1)
				(type default)
			)
			(layer "F.Fab")
		)
		(fp_line
			(start 0.120396 0.2794)
			(end -0.12065 0.2794)
			(stroke
				(width 0.1)
				(type default)
			)
			(layer "F.Fab")
		)
		(fp_line
			(start 0.120396 0.3048)
			(end 0.120396 0.2794)
			(stroke
				(width 0.1)
				(type default)
			)
			(layer "F.Fab")
		)
		(fp_line
			(start 0.12065 -0.3048)
			(end 0.67945 -0.3048)
			(stroke
				(width 0.1)
				(type default)
			)
			(layer "F.Fab")
		)
		(fp_line
			(start 0.12065 -0.2794)
			(end 0.12065 -0.3048)
			(stroke
				(width 0.1)
				(type default)
			)
			(layer "F.Fab")
		)
		(fp_line
			(start 0.67945 -0.3048)
			(end 0.67945 0.3048)
			(stroke
				(width 0.1)
				(type default)
			)
			(layer "F.Fab")
		)
		(fp_line
			(start 0.67945 0.3048)
			(end 0.120396 0.3048)
			(stroke
				(width 0.1)
				(type default)
			)
			(layer "F.Fab")
		)
		(pad "1" smd circle
			(at -0.40005 0)
			(size 0 0)
			(layers "F.Cu" "F.Mask" "F.Paste")
			(net "PRSNT_NIC7_N")
		)
		(pad "2" smd circle
			(at 0.40005 0)
			(size 0 0)
			(layers "F.Cu" "F.Mask" "F.Paste")
			(net "PRSNTB1_NIC7_N")
		)
	)
	(footprint ""
		(layer "F.Cu")
		(at 312.21934 -150.70455 180)
		(property "Reference" "C429"
			(at 0 0 180)
			(layer "F.SilkS")
			(hide yes)
			(effects
				(font
					(size 1.27 1.27)
				)
			)
		)
		(property "Value" ""
			(at 0 0 180)
			(layer "F.Fab")
			(effects
				(font
					(size 1.27 1.27)
				)
			)
		)
		(duplicate_pad_numbers_are_jumpers no)
		(fp_line
			(start 0.299974 0.150114)
			(end -0.299974 0.150114)
			(stroke
				(width 0.1)
				(type default)
			)
			(layer "F.Fab")
		)
		(fp_line
			(start 0.299974 -0.150114)
			(end 0.299974 0.150114)
			(stroke
				(width 0.1)
				(type default)
			)
			(layer "F.Fab")
		)
		(fp_line
			(start -0.299974 0.150114)
			(end -0.299974 -0.150114)
			(stroke
				(width 0.1)
				(type default)
			)
			(layer "F.Fab")
		)
		(fp_line
			(start -0.299974 -0.150114)
			(end 0.299974 -0.150114)
			(stroke
				(width 0.1)
				(type default)
			)
			(layer "F.Fab")
		)
		(pad "1" smd rect
			(at -0.2667 0 180)
			(size 0.3048 0.381)
			(layers "F.Cu" "F.Mask" "F.Paste")
			(net "P5E_PEX2_STN0_TX_DN<12>")
		)
		(pad "2" smd rect
			(at 0.2667 0 180)
			(size 0.3048 0.381)
			(layers "F.Cu" "F.Mask" "F.Paste")
			(net "P5E_PEX2_STN0_TX_C_DN<12>")
		)
	)
	(footprint ""
		(layer "F.Cu")
		(at 189.047374 -20.35556)
		(property "Reference" "C3919"
			(at 0 0 0)
			(layer "F.SilkS")
			(hide yes)
			(effects
				(font
					(size 1.27 1.27)
				)
			)
		)
		(property "Value" ""
			(at 0 0 0)
			(layer "F.Fab")
			(effects
				(font
					(size 1.27 1.27)
				)
			)
		)
		(duplicate_pad_numbers_are_jumpers no)
		(fp_line
			(start -0.7874 -0.4064)
			(end 0.7874 -0.4064)
			(stroke
				(width 0.1524)
				(type default)
			)
			(layer "F.SilkS")
		)
		(fp_line
			(start -0.7874 0.4064)
			(end -0.7874 -0.4064)
			(stroke
				(width 0.1524)
				(type default)
			)
			(layer "F.SilkS")
		)
		(fp_line
			(start 0.7874 -0.4064)
			(end 0.7874 0.4064)
			(stroke
				(width 0.1524)
				(type default)
			)
			(layer "F.SilkS")
		)
		(fp_line
			(start 0.7874 0.4064)
			(end -0.7874 0.4064)
			(stroke
				(width 0.1524)
				(type default)
			)
			(layer "F.SilkS")
		)
		(fp_line
			(start -0.67945 -0.305054)
			(end -0.12065 -0.305054)
			(stroke
				(width 0.1)
				(type default)
			)
			(layer "F.Fab")
		)
		(fp_line
			(start -0.67945 0.3048)
			(end -0.67945 -0.305054)
			(stroke
				(width 0.1)
				(type default)
			)
			(layer "F.Fab")
		)
		(fp_line
			(start -0.12065 -0.305054)
			(end -0.12065 -0.2794)
			(stroke
				(width 0.1)
				(type default)
			)
			(layer "F.Fab")
		)
		(fp_line
			(start -0.12065 -0.2794)
			(end 0.12065 -0.2794)
			(stroke
				(width 0.1)
				(type default)
			)
			(layer "F.Fab")
		)
		(fp_line
			(start -0.12065 0.2794)
			(end -0.12065 0.3048)
			(stroke
				(width 0.1)
				(type default)
			)
			(layer "F.Fab")
		)
		(fp_line
			(start -0.12065 0.3048)
			(end -0.67945 0.3048)
			(stroke
				(width 0.1)
				(type default)
			)
			(layer "F.Fab")
		)
		(fp_line
			(start 0.120396 0.2794)
			(end -0.12065 0.2794)
			(stroke
				(width 0.1)
				(type default)
			)
			(layer "F.Fab")
		)
		(fp_line
			(start 0.120396 0.3048)
			(end 0.120396 0.2794)
			(stroke
				(width 0.1)
				(type default)
			)
			(layer "F.Fab")
		)
		(fp_line
			(start 0.12065 -0.3048)
			(end 0.67945 -0.3048)
			(stroke
				(width 0.1)
				(type default)
			)
			(layer "F.Fab")
		)
		(fp_line
			(start 0.12065 -0.2794)
			(end 0.12065 -0.3048)
			(stroke
				(width 0.1)
				(type default)
			)
			(layer "F.Fab")
		)
		(fp_line
			(start 0.67945 -0.3048)
			(end 0.67945 0.3048)
			(stroke
				(width 0.1)
				(type default)
			)
			(layer "F.Fab")
		)
		(fp_line
			(start 0.67945 0.3048)
			(end 0.120396 0.3048)
			(stroke
				(width 0.1)
				(type default)
			)
			(layer "F.Fab")
		)
		(pad "1" smd circle
			(at -0.40005 0)
			(size 0 0)
			(layers "F.Cu" "F.Mask" "F.Paste")
			(net "P12V_SSD6")
		)
		(pad "2" smd circle
			(at 0.40005 0)
			(size 0 0)
			(layers "F.Cu" "F.Mask" "F.Paste")
			(net "GND")
		)
	)
	(footprint ""
		(layer "F.Cu")
		(at 407.696162 -387.942836 180)
		(property "Reference" "R1856"
			(at 0 0 180)
			(layer "F.SilkS")
			(hide yes)
			(effects
				(font
					(size 1.27 1.27)
				)
			)
		)
		(property "Value" ""
			(at 0 0 180)
			(layer "F.Fab")
			(effects
				(font
					(size 1.27 1.27)
				)
			)
		)
		(duplicate_pad_numbers_are_jumpers no)
		(fp_line
			(start 0.7874 0.4064)
			(end -0.7874 0.4064)
			(stroke
				(width 0.1524)
				(type default)
			)
			(layer "F.SilkS")
		)
		(fp_line
			(start 0.7874 -0.4064)
			(end 0.7874 0.4064)
			(stroke
				(width 0.1524)
				(type default)
			)
			(layer "F.SilkS")
		)
		(fp_line
			(start -0.7874 0.4064)
			(end -0.7874 -0.4064)
			(stroke
				(width 0.1524)
				(type default)
			)
			(layer "F.SilkS")
		)
		(fp_line
			(start -0.7874 -0.4064)
			(end 0.7874 -0.4064)
			(stroke
				(width 0.1524)
				(type default)
			)
			(layer "F.SilkS")
		)
		(fp_line
			(start 0.67945 0.3048)
			(end 0.120396 0.3048)
			(stroke
				(width 0.1)
				(type default)
			)
			(layer "F.Fab")
		)
		(fp_line
			(start 0.67945 -0.3048)
			(end 0.67945 0.3048)
			(stroke
				(width 0.1)
				(type default)
			)
			(layer "F.Fab")
		)
		(fp_line
			(start 0.12065 -0.2794)
			(end 0.12065 -0.3048)
			(stroke
				(width 0.1)
				(type default)
			)
			(layer "F.Fab")
		)
		(fp_line
			(start 0.12065 -0.3048)
			(end 0.67945 -0.3048)
			(stroke
				(width 0.1)
				(type default)
			)
			(layer "F.Fab")
		)
		(fp_line
			(start 0.120396 0.3048)
			(end 0.120396 0.2794)
			(stroke
				(width 0.1)
				(type default)
			)
			(layer "F.Fab")
		)
		(fp_line
			(start 0.120396 0.2794)
			(end -0.12065 0.2794)
			(stroke
				(width 0.1)
				(type default)
			)
			(layer "F.Fab")
		)
		(fp_line
			(start -0.12065 0.3048)
			(end -0.67945 0.3048)
			(stroke
				(width 0.1)
				(type default)
			)
			(layer "F.Fab")
		)
		(fp_line
			(start -0.12065 0.2794)
			(end -0.12065 0.3048)
			(stroke
				(width 0.1)
				(type default)
			)
			(layer "F.Fab")
		)
		(fp_line
			(start -0.12065 -0.2794)
			(end 0.12065 -0.2794)
			(stroke
				(width 0.1)
				(type default)
			)
			(layer "F.Fab")
		)
		(fp_line
			(start -0.12065 -0.305054)
			(end -0.12065 -0.2794)
			(stroke
				(width 0.1)
				(type default)
			)
			(layer "F.Fab")
		)
		(fp_line
			(start -0.67945 0.3048)
			(end -0.67945 -0.305054)
			(stroke
				(width 0.1)
				(type default)
			)
			(layer "F.Fab")
		)
		(fp_line
			(start -0.67945 -0.305054)
			(end -0.12065 -0.305054)
			(stroke
				(width 0.1)
				(type default)
			)
			(layer "F.Fab")
		)
		(pad "1" smd circle
			(at -0.40005 0 180)
			(size 0 0)
			(layers "F.Cu" "F.Mask" "F.Paste")
			(net "GPU_WP_HW_CTRL_R_N")
		)
		(pad "2" smd circle
			(at 0.40005 0 180)
			(size 0 0)
			(layers "F.Cu" "F.Mask" "F.Paste")
			(net "GPU_WP_HW_CTRL_N")
		)
	)
	(footprint ""
		(layer "F.Cu")
		(at 463.658458 -534.632662 180)
		(property "Reference" "SCREW_SSD10_2"
			(at -5.6007 -1.402334 0)
			(unlocked yes)
			(layer "B.SilkS")
			(effects
				(font
					(size 0.7874 0.5842)
					(thickness 0.1524)
				)
				(justify mirror)
			)
		)
		(property "Value" ""
			(at 0 0 180)
			(layer "F.Fab")
			(effects
				(font
					(size 1.27 1.27)
				)
			)
		)
		(duplicate_pad_numbers_are_jumpers no)
		(pad "1" thru_hole circle
			(at 0 0 180)
			(size 0.4572 0.4572)
			(drill 0.2032)
			(layers "*.Cu" "*.Mask")
			(remove_unused_layers no)
			(net "Net_9153")
			(clearance 0.127)
			(thermal_gap 0.127)
			(padstack
				(mode front_inner_back)
				(layer "Inner"
					(shape circle)
					(size 0.4572 0.4572)
					(clearance 0.127)
				)
				(layer "B.Cu"
					(shape circle)
					(size 0.508 0.508)
					(clearance 0.1016)
				)
			)
		)
	)
	(footprint ""
		(layer "F.Cu")
		(at 38.599872 -152.295352 180)
		(property "Reference" "R17"
			(at 0 0 180)
			(layer "F.SilkS")
			(hide yes)
			(effects
				(font
					(size 1.27 1.27)
				)
			)
		)
		(property "Value" ""
			(at 0 0 180)
			(layer "F.Fab")
			(effects
				(font
					(size 1.27 1.27)
				)
			)
		)
		(duplicate_pad_numbers_are_jumpers no)
		(fp_line
			(start 0.7874 0.4064)
			(end -0.7874 0.4064)
			(stroke
				(width 0.1524)
				(type default)
			)
			(layer "F.SilkS")
		)
		(fp_line
			(start 0.7874 -0.4064)
			(end 0.7874 0.4064)
			(stroke
				(width 0.1524)
				(type default)
			)
			(layer "F.SilkS")
		)
		(fp_line
			(start -0.7874 0.4064)
			(end -0.7874 -0.4064)
			(stroke
				(width 0.1524)
				(type default)
			)
			(layer "F.SilkS")
		)
		(fp_line
			(start -0.7874 -0.4064)
			(end 0.7874 -0.4064)
			(stroke
				(width 0.1524)
				(type default)
			)
			(layer "F.SilkS")
		)
		(fp_line
			(start 0.67945 0.3048)
			(end 0.120396 0.3048)
			(stroke
				(width 0.1)
				(type default)
			)
			(layer "F.Fab")
		)
		(fp_line
			(start 0.67945 -0.3048)
			(end 0.67945 0.3048)
			(stroke
				(width 0.1)
				(type default)
			)
			(layer "F.Fab")
		)
		(fp_line
			(start 0.12065 -0.2794)
			(end 0.12065 -0.3048)
			(stroke
				(width 0.1)
				(type default)
			)
			(layer "F.Fab")
		)
		(fp_line
			(start 0.12065 -0.3048)
			(end 0.67945 -0.3048)
			(stroke
				(width 0.1)
				(type default)
			)
			(layer "F.Fab")
		)
		(fp_line
			(start 0.120396 0.3048)
			(end 0.120396 0.2794)
			(stroke
				(width 0.1)
				(type default)
			)
			(layer "F.Fab")
		)
		(fp_line
			(start 0.120396 0.2794)
			(end -0.12065 0.2794)
			(stroke
				(width 0.1)
				(type default)
			)
			(layer "F.Fab")
		)
		(fp_line
			(start -0.12065 0.3048)
			(end -0.67945 0.3048)
			(stroke
				(width 0.1)
				(type default)
			)
			(layer "F.Fab")
		)
		(fp_line
			(start -0.12065 0.2794)
			(end -0.12065 0.3048)
			(stroke
				(width 0.1)
				(type default)
			)
			(layer "F.Fab")
		)
		(fp_line
			(start -0.12065 -0.2794)
			(end 0.12065 -0.2794)
			(stroke
				(width 0.1)
				(type default)
			)
			(layer "F.Fab")
		)
		(fp_line
			(start -0.12065 -0.305054)
			(end -0.12065 -0.2794)
			(stroke
				(width 0.1)
				(type default)
			)
			(layer "F.Fab")
		)
		(fp_line
			(start -0.67945 0.3048)
			(end -0.67945 -0.305054)
			(stroke
				(width 0.1)
				(type default)
			)
			(layer "F.Fab")
		)
		(fp_line
			(start -0.67945 -0.305054)
			(end -0.12065 -0.305054)
			(stroke
				(width 0.1)
				(type default)
			)
			(layer "F.Fab")
		)
		(pad "1" smd circle
			(at -0.40005 0 180)
			(size 0 0)
			(layers "F.Cu" "F.Mask" "F.Paste")
			(net "NCSI_NIC0_RXD1")
		)
		(pad "2" smd circle
			(at 0.40005 0 180)
			(size 0 0)
			(layers "F.Cu" "F.Mask" "F.Paste")
			(net "GND")
		)
	)
	(footprint ""
		(layer "F.Cu")
		(at 36.638484 -119.198898)
		(property "Reference" "C47"
			(at 0 0 0)
			(layer "F.SilkS")
			(hide yes)
			(effects
				(font
					(size 1.27 1.27)
				)
			)
		)
		(property "Value" ""
			(at 0 0 0)
			(layer "F.Fab")
			(effects
				(font
					(size 1.27 1.27)
				)
			)
		)
		(duplicate_pad_numbers_are_jumpers no)
		(fp_line
			(start -0.299974 -0.150114)
			(end 0.299974 -0.150114)
			(stroke
				(width 0.1)
				(type default)
			)
			(layer "F.Fab")
		)
		(fp_line
			(start -0.299974 0.150114)
			(end -0.299974 -0.150114)
			(stroke
				(width 0.1)
				(type default)
			)
			(layer "F.Fab")
		)
		(fp_line
			(start 0.299974 -0.150114)
			(end 0.299974 0.150114)
			(stroke
				(width 0.1)
				(type default)
			)
			(layer "F.Fab")
		)
		(fp_line
			(start 0.299974 0.150114)
			(end -0.299974 0.150114)
			(stroke
				(width 0.1)
				(type default)
			)
			(layer "F.Fab")
		)
		(pad "1" smd rect
			(at -0.2667 0)
			(size 0.3048 0.381)
			(layers "F.Cu" "F.Mask" "F.Paste")
			(net "P5E_PEX0_STN1_TX_DP<24>")
		)
		(pad "2" smd rect
			(at 0.2667 0)
			(size 0.3048 0.381)
			(layers "F.Cu" "F.Mask" "F.Paste")
			(net "P5E_PEX0_STN1_TX_C_DP<24>")
		)
	)
	(footprint ""
		(layer "F.Cu")
		(at 82.661506 -144.396714 180)
		(property "Reference" "C14"
			(at 0 0 180)
			(layer "F.SilkS")
			(hide yes)
			(effects
				(font
					(size 1.27 1.27)
				)
			)
		)
		(property "Value" ""
			(at 0 0 180)
			(layer "F.Fab")
			(effects
				(font
					(size 1.27 1.27)
				)
			)
		)
		(duplicate_pad_numbers_are_jumpers no)
		(fp_line
			(start 0.299974 0.150114)
			(end -0.299974 0.150114)
			(stroke
				(width 0.1)
				(type default)
			)
			(layer "F.Fab")
		)
		(fp_line
			(start 0.299974 -0.150114)
			(end 0.299974 0.150114)
			(stroke
				(width 0.1)
				(type default)
			)
			(layer "F.Fab")
		)
		(fp_line
			(start -0.299974 0.150114)
			(end -0.299974 -0.150114)
			(stroke
				(width 0.1)
				(type default)
			)
			(layer "F.Fab")
		)
		(fp_line
			(start -0.299974 -0.150114)
			(end 0.299974 -0.150114)
			(stroke
				(width 0.1)
				(type default)
			)
			(layer "F.Fab")
		)
		(pad "1" smd rect
			(at -0.2667 0 180)
			(size 0.3048 0.381)
			(layers "F.Cu" "F.Mask" "F.Paste")
			(net "P5E_PEX0_STN0_TX_DN<9>")
		)
		(pad "2" smd rect
			(at 0.2667 0 180)
			(size 0.3048 0.381)
			(layers "F.Cu" "F.Mask" "F.Paste")
			(net "P5E_PEX0_STN0_TX_C_DN<9>")
		)
	)
	(footprint ""
		(layer "F.Cu")
		(at 136.675622 -69.47916 180)
		(property "Reference" "PU107"
			(at -1.908048 4.07924 90)
			(unlocked yes)
			(layer "F.SilkS")
			(effects
				(font
					(size 0.7874 0.5842)
					(thickness 0.1524)
				)
			)
		)
		(property "Value" ""
			(at 0 0 180)
			(layer "F.Fab")
			(effects
				(font
					(size 1.27 1.27)
				)
			)
		)
		(duplicate_pad_numbers_are_jumpers no)
		(fp_line
			(start 1.239774 1.495298)
			(end -1.239774 1.495298)
			(stroke
				(width 0.1524)
				(type default)
			)
			(layer "F.SilkS")
		)
		(fp_line
			(start 1.239774 -1.495298)
			(end 1.239774 1.495298)
			(stroke
				(width 0.1524)
				(type default)
			)
			(layer "F.SilkS")
		)
		(fp_line
			(start -1.239774 1.495298)
			(end -1.239774 -1.495298)
			(stroke
				(width 0.1524)
				(type default)
			)
			(layer "F.SilkS")
		)
		(fp_line
			(start -1.239774 -1.495298)
			(end 1.239774 -1.495298)
			(stroke
				(width 0.1524)
				(type default)
			)
			(layer "F.SilkS")
		)
		(fp_poly
			(pts
				(xy -1.562608 -0.953516) (xy -2.28092 -0.235204) (xy -1.203452 0.124206)
			)
			(stroke
				(width 0)
				(type default)
			)
			(fill yes)
			(layer "F.SilkS")
		)
		(fp_line
			(start 0.8001 1.050036)
			(end -0.8001 1.050036)
			(stroke
				(width 0.1)
				(type default)
			)
			(layer "F.Fab")
		)
		(fp_line
			(start 0.8001 -1.050036)
			(end 0.8001 1.050036)
			(stroke
				(width 0.1)
				(type default)
			)
			(layer "F.Fab")
		)
		(fp_line
			(start -0.8001 1.050036)
			(end -0.8001 -1.050036)
			(stroke
				(width 0.1)
				(type default)
			)
			(layer "F.Fab")
		)
		(fp_line
			(start -0.8001 -1.050036)
			(end 0.8001 -1.050036)
			(stroke
				(width 0.1)
				(type default)
			)
			(layer "F.Fab")
		)
		(fp_poly
			(pts
				(xy -2.458974 -0.508) (xy -2.458974 0.508) (xy -1.442974 0)
			)
			(stroke
				(width 0)
				(type default)
			)
			(fill yes)
			(layer "F.Fab")
		)
		(pad "1_2" smd circle
			(at -0.374904 0 270)
			(size 0 0)
			(layers "F.Cu" "F.Mask" "F.Paste")
			(net "P12V_AUX")
		)
		(pad "3" smd rect
			(at -0.499872 0.999998 180)
			(size 0.254 0.7112)
			(layers "F.Cu" "F.Mask" "F.Paste")
			(net "GND")
		)
		(pad "4" smd rect
			(at 0 0.999998 180)
			(size 0.254 0.7112)
			(layers "F.Cu" "F.Mask" "F.Paste")
			(net "P12V_SSD4_CO_ILIMIT")
		)
		(pad "5" smd rect
			(at 0.499872 0.999998 180)
			(size 0.254 0.7112)
			(layers "F.Cu" "F.Mask" "F.Paste")
			(net "P12V_SSD4_CO_MODE")
		)
		(pad "6_7" smd circle
			(at 0.374904 0 90)
			(size 0 0)
			(layers "F.Cu" "F.Mask" "F.Paste")
			(net "P12V_SSD4_R")
		)
		(pad "8" smd rect
			(at 0.499872 -0.999998 180)
			(size 0.254 0.7112)
			(layers "F.Cu" "F.Mask" "F.Paste")
			(net "P12V_SSD4_CO_GATE")
		)
		(pad "9" smd rect
			(at 0 -0.999998 180)
			(size 0.254 0.7112)
			(layers "F.Cu" "F.Mask" "F.Paste")
			(net "P12V_SSD4_CO_EN")
		)
		(pad "10" smd rect
			(at -0.499872 -0.999998 180)
			(size 0.254 0.7112)
			(layers "F.Cu" "F.Mask" "F.Paste")
			(net "P12V_SSD4_CO_DV_DT")
		)
	)
	(footprint ""
		(layer "F.Cu")
		(at 328.440034 -253.907036)
		(property "Reference" "J56"
			(at -1.4224 -4.562348 0)
			(unlocked yes)
			(layer "F.SilkS")
			(effects
				(font
					(size 0.7874 0.5842)
					(thickness 0.1524)
				)
				(justify left)
			)
		)
		(property "Value" ""
			(at 0 0 0)
			(layer "F.Fab")
			(effects
				(font
					(size 1.27 1.27)
				)
			)
		)
		(duplicate_pad_numbers_are_jumpers no)
		(fp_line
			(start -1.27 -3.81)
			(end 1.27 -3.81)
			(stroke
				(width 0.1524)
				(type default)
			)
			(layer "F.SilkS")
		)
		(fp_line
			(start -1.27 -0.7747)
			(end -1.27 -3.81)
			(stroke
				(width 0.1524)
				(type default)
			)
			(layer "F.SilkS")
		)
		(fp_line
			(start -1.27 3.81)
			(end -1.27 0.7747)
			(stroke
				(width 0.1524)
				(type default)
			)
			(layer "F.SilkS")
		)
		(fp_line
			(start 1.27 -3.81)
			(end 1.27 -3.3147)
			(stroke
				(width 0.1524)
				(type default)
			)
			(layer "F.SilkS")
		)
		(fp_line
			(start 1.27 -1.7653)
			(end 1.27 1.7653)
			(stroke
				(width 0.1524)
				(type default)
			)
			(layer "F.SilkS")
		)
		(fp_line
			(start 1.27 3.3147)
			(end 1.27 3.81)
			(stroke
				(width 0.1524)
				(type default)
			)
			(layer "F.SilkS")
		)
		(fp_line
			(start 1.27 3.81)
			(end -1.27 3.81)
			(stroke
				(width 0.1524)
				(type default)
			)
			(layer "F.SilkS")
		)
		(fp_poly
			(pts
				(xy 4.3942 -3.048) (xy 4.3942 -2.032) (xy 3.3782 -2.54)
			)
			(stroke
				(width 0)
				(type default)
			)
			(fill yes)
			(layer "F.SilkS")
		)
		(fp_line
			(start -1.27 -3.81)
			(end -1.27 3.81)
			(stroke
				(width 0.1)
				(type default)
			)
			(layer "F.Fab")
		)
		(fp_line
			(start -1.27 3.81)
			(end 1.27 3.81)
			(stroke
				(width 0.1)
				(type default)
			)
			(layer "F.Fab")
		)
		(fp_line
			(start 1.27 -3.81)
			(end -1.27 -3.81)
			(stroke
				(width 0.1)
				(type default)
			)
			(layer "F.Fab")
		)
		(fp_line
			(start 1.27 3.81)
			(end 1.27 -3.81)
			(stroke
				(width 0.1)
				(type default)
			)
			(layer "F.Fab")
		)
		(fp_poly
			(pts
				(xy 4.3942 -3.048) (xy 4.3942 -2.032) (xy 3.3782 -2.54)
			)
			(stroke
				(width 0)
				(type default)
			)
			(fill yes)
			(layer "F.Fab")
		)
		(fp_text user "3"
			(at 4.430014 2.728468 90)
			(unlocked yes)
			(layer "F.SilkS")
			(effects
				(font
					(size 0.7874 0.5842)
					(thickness 0.1524)
				)
			)
		)
		(fp_text user "3"
			(at 3.921252 2.54 90)
			(unlocked yes)
			(layer "F.Fab")
			(effects
				(font
					(size 0.7874 0.5842)
					(thickness 0.1524)
				)
			)
		)
		(pad "1" smd rect
			(at 1.459992 -2.54 90)
			(size 1.27 3.429)
			(layers "F.Cu" "F.Mask" "F.Paste")
			(net "Net_2677")
		)
		(pad "2" smd rect
			(at -1.459992 0 90)
			(size 1.27 3.429)
			(layers "F.Cu" "F.Mask" "F.Paste")
			(net "JP_FPGA_FRC_PWRON_N")
		)
		(pad "3" smd rect
			(at 1.459992 2.54 90)
			(size 1.27 3.429)
			(layers "F.Cu" "F.Mask" "F.Paste")
			(net "GND")
		)
	)
	(footprint ""
		(layer "F.Cu")
		(at 27.386788 -307.803296 -135)
		(property "Reference" "R1086"
			(at 0 0 225)
			(layer "F.SilkS")
			(hide yes)
			(effects
				(font
					(size 1.27 1.27)
				)
			)
		)
		(property "Value" ""
			(at 0 0 225)
			(layer "F.Fab")
			(effects
				(font
					(size 1.27 1.27)
				)
			)
		)
		(duplicate_pad_numbers_are_jumpers no)
		(fp_line
			(start 0.787389 0.406267)
			(end -0.787389 0.406267)
			(stroke
				(width 0.1524)
				(type default)
			)
			(layer "F.SilkS")
		)
		(fp_line
			(start 0.787389 -0.406267)
			(end 0.787389 0.406267)
			(stroke
				(width 0.1524)
				(type default)
			)
			(layer "F.SilkS")
		)
		(fp_line
			(start -0.787389 0.406267)
			(end -0.787389 -0.406267)
			(stroke
				(width 0.1524)
				(type default)
			)
			(layer "F.SilkS")
		)
		(fp_line
			(start -0.787389 -0.406267)
			(end 0.787389 -0.406267)
			(stroke
				(width 0.1524)
				(type default)
			)
			(layer "F.SilkS")
		)
		(fp_line
			(start 0.679446 0.30479)
			(end 0.120515 0.30479)
			(stroke
				(width 0.1)
				(type default)
			)
			(layer "F.Fab")
		)
		(fp_line
			(start 0.120515 0.30479)
			(end 0.120335 0.279466)
			(stroke
				(width 0.1)
				(type default)
			)
			(layer "F.Fab")
		)
		(fp_line
			(start 0.120335 0.279466)
			(end -0.120695 0.279466)
			(stroke
				(width 0.1)
				(type default)
			)
			(layer "F.Fab")
		)
		(fp_line
			(start 0.679446 -0.30479)
			(end 0.679446 0.30479)
			(stroke
				(width 0.1)
				(type default)
			)
			(layer "F.Fab")
		)
		(fp_line
			(start -0.120515 0.30479)
			(end -0.679446 0.30479)
			(stroke
				(width 0.1)
				(type default)
			)
			(layer "F.Fab")
		)
		(fp_line
			(start -0.120695 0.279466)
			(end -0.120515 0.30479)
			(stroke
				(width 0.1)
				(type default)
			)
			(layer "F.Fab")
		)
		(fp_line
			(start 0.120695 -0.279466)
			(end 0.120515 -0.30479)
			(stroke
				(width 0.1)
				(type default)
			)
			(layer "F.Fab")
		)
		(fp_line
			(start 0.120515 -0.30479)
			(end 0.679446 -0.30479)
			(stroke
				(width 0.1)
				(type default)
			)
			(layer "F.Fab")
		)
		(fp_line
			(start -0.679446 0.30479)
			(end -0.679446 -0.305149)
			(stroke
				(width 0.1)
				(type default)
			)
			(layer "F.Fab")
		)
		(fp_line
			(start -0.120695 -0.279466)
			(end 0.120695 -0.279466)
			(stroke
				(width 0.1)
				(type default)
			)
			(layer "F.Fab")
		)
		(fp_line
			(start -0.120695 -0.304969)
			(end -0.120695 -0.279466)
			(stroke
				(width 0.1)
				(type default)
			)
			(layer "F.Fab")
		)
		(fp_line
			(start -0.679446 -0.305149)
			(end -0.120695 -0.304969)
			(stroke
				(width 0.1)
				(type default)
			)
			(layer "F.Fab")
		)
		(pad "1" smd circle
			(at -0.40005 0 225)
			(size 0 0)
			(layers "F.Cu" "F.Mask" "F.Paste")
			(net "PEX0_DBG_SEL0")
		)
		(pad "2" smd circle
			(at 0.40005 0 225)
			(size 0 0)
			(layers "F.Cu" "F.Mask" "F.Paste")
			(net "P1V8_PEX")
		)
	)
	(footprint ""
		(layer "F.Cu")
		(at 97.850198 -95.263716 -90)
		(property "Reference" "PR197"
			(at 0 0 270)
			(layer "F.SilkS")
			(hide yes)
			(effects
				(font
					(size 1.27 1.27)
				)
			)
		)
		(property "Value" ""
			(at 0 0 270)
			(layer "F.Fab")
			(effects
				(font
					(size 1.27 1.27)
				)
			)
		)
		(duplicate_pad_numbers_are_jumpers no)
		(fp_line
			(start -0.7874 0.4064)
			(end -0.7874 -0.4064)
			(stroke
				(width 0.1524)
				(type default)
			)
			(layer "F.SilkS")
		)
		(fp_line
			(start 0.7874 0.4064)
			(end -0.7874 0.4064)
			(stroke
				(width 0.1524)
				(type default)
			)
			(layer "F.SilkS")
		)
		(fp_line
			(start -0.7874 -0.4064)
			(end 0.7874 -0.4064)
			(stroke
				(width 0.1524)
				(type default)
			)
			(layer "F.SilkS")
		)
		(fp_line
			(start 0.7874 -0.4064)
			(end 0.7874 0.4064)
			(stroke
				(width 0.1524)
				(type default)
			)
			(layer "F.SilkS")
		)
		(fp_line
			(start -0.67945 0.3048)
			(end -0.67945 -0.305054)
			(stroke
				(width 0.1)
				(type default)
			)
			(layer "F.Fab")
		)
		(fp_line
			(start -0.12065 0.3048)
			(end -0.67945 0.3048)
			(stroke
				(width 0.1)
				(type default)
			)
			(layer "F.Fab")
		)
		(fp_line
			(start 0.120396 0.3048)
			(end 0.120396 0.2794)
			(stroke
				(width 0.1)
				(type default)
			)
			(layer "F.Fab")
		)
		(fp_line
			(start 0.67945 0.3048)
			(end 0.120396 0.3048)
			(stroke
				(width 0.1)
				(type default)
			)
			(layer "F.Fab")
		)
		(fp_line
			(start -0.12065 0.2794)
			(end -0.12065 0.3048)
			(stroke
				(width 0.1)
				(type default)
			)
			(layer "F.Fab")
		)
		(fp_line
			(start 0.120396 0.2794)
			(end -0.12065 0.2794)
			(stroke
				(width 0.1)
				(type default)
			)
			(layer "F.Fab")
		)
		(fp_line
			(start -0.12065 -0.2794)
			(end 0.12065 -0.2794)
			(stroke
				(width 0.1)
				(type default)
			)
			(layer "F.Fab")
		)
		(fp_line
			(start 0.12065 -0.2794)
			(end 0.12065 -0.3048)
			(stroke
				(width 0.1)
				(type default)
			)
			(layer "F.Fab")
		)
		(fp_line
			(start 0.12065 -0.3048)
			(end 0.67945 -0.3048)
			(stroke
				(width 0.1)
				(type default)
			)
			(layer "F.Fab")
		)
		(fp_line
			(start 0.67945 -0.3048)
			(end 0.67945 0.3048)
			(stroke
				(width 0.1)
				(type default)
			)
			(layer "F.Fab")
		)
		(fp_line
			(start -0.67945 -0.305054)
			(end -0.12065 -0.305054)
			(stroke
				(width 0.1)
				(type default)
			)
			(layer "F.Fab")
		)
		(fp_line
			(start -0.12065 -0.305054)
			(end -0.12065 -0.2794)
			(stroke
				(width 0.1)
				(type default)
			)
			(layer "F.Fab")
		)
		(pad "1" smd circle
			(at -0.40005 0 270)
			(size 0 0)
			(layers "F.Cu" "F.Mask" "F.Paste")
			(net "P12V_NIC1_OCP")
		)
		(pad "2" smd circle
			(at 0.40005 0 270)
			(size 0 0)
			(layers "F.Cu" "F.Mask" "F.Paste")
			(net "GND")
		)
	)
	(footprint ""
		(layer "F.Cu")
		(at 407.190448 -373.881142)
		(property "Reference" "R6682"
			(at 0 0 0)
			(layer "F.SilkS")
			(hide yes)
			(effects
				(font
					(size 1.27 1.27)
				)
			)
		)
		(property "Value" ""
			(at 0 0 0)
			(layer "F.Fab")
			(effects
				(font
					(size 1.27 1.27)
				)
			)
		)
		(duplicate_pad_numbers_are_jumpers no)
		(fp_line
			(start -0.7874 -0.4064)
			(end 0.7874 -0.4064)
			(stroke
				(width 0.1524)
				(type default)
			)
			(layer "F.SilkS")
		)
		(fp_line
			(start -0.7874 0.4064)
			(end -0.7874 -0.4064)
			(stroke
				(width 0.1524)
				(type default)
			)
			(layer "F.SilkS")
		)
		(fp_line
			(start 0.7874 -0.4064)
			(end 0.7874 0.4064)
			(stroke
				(width 0.1524)
				(type default)
			)
			(layer "F.SilkS")
		)
		(fp_line
			(start 0.7874 0.4064)
			(end -0.7874 0.4064)
			(stroke
				(width 0.1524)
				(type default)
			)
			(layer "F.SilkS")
		)
		(fp_line
			(start -0.67945 -0.305054)
			(end -0.12065 -0.305054)
			(stroke
				(width 0.1)
				(type default)
			)
			(layer "F.Fab")
		)
		(fp_line
			(start -0.67945 0.3048)
			(end -0.67945 -0.305054)
			(stroke
				(width 0.1)
				(type default)
			)
			(layer "F.Fab")
		)
		(fp_line
			(start -0.12065 -0.305054)
			(end -0.12065 -0.2794)
			(stroke
				(width 0.1)
				(type default)
			)
			(layer "F.Fab")
		)
		(fp_line
			(start -0.12065 -0.2794)
			(end 0.12065 -0.2794)
			(stroke
				(width 0.1)
				(type default)
			)
			(layer "F.Fab")
		)
		(fp_line
			(start -0.12065 0.2794)
			(end -0.12065 0.3048)
			(stroke
				(width 0.1)
				(type default)
			)
			(layer "F.Fab")
		)
		(fp_line
			(start -0.12065 0.3048)
			(end -0.67945 0.3048)
			(stroke
				(width 0.1)
				(type default)
			)
			(layer "F.Fab")
		)
		(fp_line
			(start 0.120396 0.2794)
			(end -0.12065 0.2794)
			(stroke
				(width 0.1)
				(type default)
			)
			(layer "F.Fab")
		)
		(fp_line
			(start 0.120396 0.3048)
			(end 0.120396 0.2794)
			(stroke
				(width 0.1)
				(type default)
			)
			(layer "F.Fab")
		)
		(fp_line
			(start 0.12065 -0.3048)
			(end 0.67945 -0.3048)
			(stroke
				(width 0.1)
				(type default)
			)
			(layer "F.Fab")
		)
		(fp_line
			(start 0.12065 -0.2794)
			(end 0.12065 -0.3048)
			(stroke
				(width 0.1)
				(type default)
			)
			(layer "F.Fab")
		)
		(fp_line
			(start 0.67945 -0.3048)
			(end 0.67945 0.3048)
			(stroke
				(width 0.1)
				(type default)
			)
			(layer "F.Fab")
		)
		(fp_line
			(start 0.67945 0.3048)
			(end 0.120396 0.3048)
			(stroke
				(width 0.1)
				(type default)
			)
			(layer "F.Fab")
		)
		(pad "1" smd circle
			(at -0.40005 0)
			(size 0 0)
			(layers "F.Cu" "F.Mask" "F.Paste")
			(net "GPU_3V3IO_RSVD1")
		)
		(pad "2" smd circle
			(at 0.40005 0)
			(size 0 0)
			(layers "F.Cu" "F.Mask" "F.Paste")
			(net "GND")
		)
	)
	(footprint ""
		(layer "F.Cu")
		(at 78.267814 -56.353456)
		(property "Reference" "C2865"
			(at 0 0 0)
			(layer "F.SilkS")
			(hide yes)
			(effects
				(font
					(size 1.27 1.27)
				)
			)
		)
		(property "Value" ""
			(at 0 0 0)
			(layer "F.Fab")
			(effects
				(font
					(size 1.27 1.27)
				)
			)
		)
		(duplicate_pad_numbers_are_jumpers no)
		(fp_line
			(start -0.7874 -0.4064)
			(end 0.7874 -0.4064)
			(stroke
				(width 0.1524)
				(type default)
			)
			(layer "F.SilkS")
		)
		(fp_line
			(start -0.7874 0.4064)
			(end -0.7874 -0.4064)
			(stroke
				(width 0.1524)
				(type default)
			)
			(layer "F.SilkS")
		)
		(fp_line
			(start 0.7874 -0.4064)
			(end 0.7874 0.4064)
			(stroke
				(width 0.1524)
				(type default)
			)
			(layer "F.SilkS")
		)
		(fp_line
			(start 0.7874 0.4064)
			(end -0.7874 0.4064)
			(stroke
				(width 0.1524)
				(type default)
			)
			(layer "F.SilkS")
		)
		(fp_line
			(start -0.67945 -0.305054)
			(end -0.12065 -0.305054)
			(stroke
				(width 0.1)
				(type default)
			)
			(layer "F.Fab")
		)
		(fp_line
			(start -0.67945 0.3048)
			(end -0.67945 -0.305054)
			(stroke
				(width 0.1)
				(type default)
			)
			(layer "F.Fab")
		)
		(fp_line
			(start -0.12065 -0.305054)
			(end -0.12065 -0.2794)
			(stroke
				(width 0.1)
				(type default)
			)
			(layer "F.Fab")
		)
		(fp_line
			(start -0.12065 -0.2794)
			(end 0.12065 -0.2794)
			(stroke
				(width 0.1)
				(type default)
			)
			(layer "F.Fab")
		)
		(fp_line
			(start -0.12065 0.2794)
			(end -0.12065 0.3048)
			(stroke
				(width 0.1)
				(type default)
			)
			(layer "F.Fab")
		)
		(fp_line
			(start -0.12065 0.3048)
			(end -0.67945 0.3048)
			(stroke
				(width 0.1)
				(type default)
			)
			(layer "F.Fab")
		)
		(fp_line
			(start 0.120396 0.2794)
			(end -0.12065 0.2794)
			(stroke
				(width 0.1)
				(type default)
			)
			(layer "F.Fab")
		)
		(fp_line
			(start 0.120396 0.3048)
			(end 0.120396 0.2794)
			(stroke
				(width 0.1)
				(type default)
			)
			(layer "F.Fab")
		)
		(fp_line
			(start 0.12065 -0.3048)
			(end 0.67945 -0.3048)
			(stroke
				(width 0.1)
				(type default)
			)
			(layer "F.Fab")
		)
		(fp_line
			(start 0.12065 -0.2794)
			(end 0.12065 -0.3048)
			(stroke
				(width 0.1)
				(type default)
			)
			(layer "F.Fab")
		)
		(fp_line
			(start 0.67945 -0.3048)
			(end 0.67945 0.3048)
			(stroke
				(width 0.1)
				(type default)
			)
			(layer "F.Fab")
		)
		(fp_line
			(start 0.67945 0.3048)
			(end 0.120396 0.3048)
			(stroke
				(width 0.1)
				(type default)
			)
			(layer "F.Fab")
		)
		(pad "1" smd circle
			(at -0.40005 0)
			(size 0 0)
			(layers "F.Cu" "F.Mask" "F.Paste")
			(net "SSD2_PWR_EN_R")
		)
		(pad "2" smd circle
			(at 0.40005 0)
			(size 0 0)
			(layers "F.Cu" "F.Mask" "F.Paste")
			(net "GND")
		)
	)
	(footprint ""
		(layer "F.Cu")
		(at 379.754384 -250.070874 -90)
		(property "Reference" "R1409"
			(at 0 0 270)
			(layer "F.SilkS")
			(hide yes)
			(effects
				(font
					(size 1.27 1.27)
				)
			)
		)
		(property "Value" ""
			(at 0 0 270)
			(layer "F.Fab")
			(effects
				(font
					(size 1.27 1.27)
				)
			)
		)
		(duplicate_pad_numbers_are_jumpers no)
		(fp_line
			(start -0.7874 0.4064)
			(end -0.7874 -0.4064)
			(stroke
				(width 0.1524)
				(type default)
			)
			(layer "F.SilkS")
		)
		(fp_line
			(start 0.7874 0.4064)
			(end -0.7874 0.4064)
			(stroke
				(width 0.1524)
				(type default)
			)
			(layer "F.SilkS")
		)
		(fp_line
			(start -0.7874 -0.4064)
			(end 0.7874 -0.4064)
			(stroke
				(width 0.1524)
				(type default)
			)
			(layer "F.SilkS")
		)
		(fp_line
			(start 0.7874 -0.4064)
			(end 0.7874 0.4064)
			(stroke
				(width 0.1524)
				(type default)
			)
			(layer "F.SilkS")
		)
		(fp_line
			(start -0.67945 0.3048)
			(end -0.67945 -0.305054)
			(stroke
				(width 0.1)
				(type default)
			)
			(layer "F.Fab")
		)
		(fp_line
			(start -0.12065 0.3048)
			(end -0.67945 0.3048)
			(stroke
				(width 0.1)
				(type default)
			)
			(layer "F.Fab")
		)
		(fp_line
			(start 0.120396 0.3048)
			(end 0.120396 0.2794)
			(stroke
				(width 0.1)
				(type default)
			)
			(layer "F.Fab")
		)
		(fp_line
			(start 0.67945 0.3048)
			(end 0.120396 0.3048)
			(stroke
				(width 0.1)
				(type default)
			)
			(layer "F.Fab")
		)
		(fp_line
			(start -0.12065 0.2794)
			(end -0.12065 0.3048)
			(stroke
				(width 0.1)
				(type default)
			)
			(layer "F.Fab")
		)
		(fp_line
			(start 0.120396 0.2794)
			(end -0.12065 0.2794)
			(stroke
				(width 0.1)
				(type default)
			)
			(layer "F.Fab")
		)
		(fp_line
			(start -0.12065 -0.2794)
			(end 0.12065 -0.2794)
			(stroke
				(width 0.1)
				(type default)
			)
			(layer "F.Fab")
		)
		(fp_line
			(start 0.12065 -0.2794)
			(end 0.12065 -0.3048)
			(stroke
				(width 0.1)
				(type default)
			)
			(layer "F.Fab")
		)
		(fp_line
			(start 0.12065 -0.3048)
			(end 0.67945 -0.3048)
			(stroke
				(width 0.1)
				(type default)
			)
			(layer "F.Fab")
		)
		(fp_line
			(start 0.67945 -0.3048)
			(end 0.67945 0.3048)
			(stroke
				(width 0.1)
				(type default)
			)
			(layer "F.Fab")
		)
		(fp_line
			(start -0.67945 -0.305054)
			(end -0.12065 -0.305054)
			(stroke
				(width 0.1)
				(type default)
			)
			(layer "F.Fab")
		)
		(fp_line
			(start -0.12065 -0.305054)
			(end -0.12065 -0.2794)
			(stroke
				(width 0.1)
				(type default)
			)
			(layer "F.Fab")
		)
		(pad "1" smd circle
			(at -0.40005 0 270)
			(size 0 0)
			(layers "F.Cu" "F.Mask" "F.Paste")
			(net "PEX3_MODE_SEL4")
		)
		(pad "2" smd circle
			(at 0.40005 0 270)
			(size 0 0)
			(layers "F.Cu" "F.Mask" "F.Paste")
			(net "P1V8_PEX")
		)
	)
	(footprint ""
		(layer "F.Cu")
		(at 167.523668 -167.742108)
		(property "Reference" "C415"
			(at 0 0 0)
			(layer "F.SilkS")
			(hide yes)
			(effects
				(font
					(size 1.27 1.27)
				)
			)
		)
		(property "Value" ""
			(at 0 0 0)
			(layer "F.Fab")
			(effects
				(font
					(size 1.27 1.27)
				)
			)
		)
		(duplicate_pad_numbers_are_jumpers no)
		(fp_line
			(start -0.7874 -0.4064)
			(end 0.7874 -0.4064)
			(stroke
				(width 0.1524)
				(type default)
			)
			(layer "F.SilkS")
		)
		(fp_line
			(start -0.7874 0.4064)
			(end -0.7874 -0.4064)
			(stroke
				(width 0.1524)
				(type default)
			)
			(layer "F.SilkS")
		)
		(fp_line
			(start 0.7874 -0.4064)
			(end 0.7874 0.4064)
			(stroke
				(width 0.1524)
				(type default)
			)
			(layer "F.SilkS")
		)
		(fp_line
			(start 0.7874 0.4064)
			(end -0.7874 0.4064)
			(stroke
				(width 0.1524)
				(type default)
			)
			(layer "F.SilkS")
		)
		(fp_line
			(start -0.67945 -0.305054)
			(end -0.12065 -0.305054)
			(stroke
				(width 0.1)
				(type default)
			)
			(layer "F.Fab")
		)
		(fp_line
			(start -0.67945 0.3048)
			(end -0.67945 -0.305054)
			(stroke
				(width 0.1)
				(type default)
			)
			(layer "F.Fab")
		)
		(fp_line
			(start -0.12065 -0.305054)
			(end -0.12065 -0.2794)
			(stroke
				(width 0.1)
				(type default)
			)
			(layer "F.Fab")
		)
		(fp_line
			(start -0.12065 -0.2794)
			(end 0.12065 -0.2794)
			(stroke
				(width 0.1)
				(type default)
			)
			(layer "F.Fab")
		)
		(fp_line
			(start -0.12065 0.2794)
			(end -0.12065 0.3048)
			(stroke
				(width 0.1)
				(type default)
			)
			(layer "F.Fab")
		)
		(fp_line
			(start -0.12065 0.3048)
			(end -0.67945 0.3048)
			(stroke
				(width 0.1)
				(type default)
			)
			(layer "F.Fab")
		)
		(fp_line
			(start 0.120396 0.2794)
			(end -0.12065 0.2794)
			(stroke
				(width 0.1)
				(type default)
			)
			(layer "F.Fab")
		)
		(fp_line
			(start 0.120396 0.3048)
			(end 0.120396 0.2794)
			(stroke
				(width 0.1)
				(type default)
			)
			(layer "F.Fab")
		)
		(fp_line
			(start 0.12065 -0.3048)
			(end 0.67945 -0.3048)
			(stroke
				(width 0.1)
				(type default)
			)
			(layer "F.Fab")
		)
		(fp_line
			(start 0.12065 -0.2794)
			(end 0.12065 -0.3048)
			(stroke
				(width 0.1)
				(type default)
			)
			(layer "F.Fab")
		)
		(fp_line
			(start 0.67945 -0.3048)
			(end 0.67945 0.3048)
			(stroke
				(width 0.1)
				(type default)
			)
			(layer "F.Fab")
		)
		(fp_line
			(start 0.67945 0.3048)
			(end 0.120396 0.3048)
			(stroke
				(width 0.1)
				(type default)
			)
			(layer "F.Fab")
		)
		(pad "1" smd circle
			(at -0.40005 0)
			(size 0 0)
			(layers "F.Cu" "F.Mask" "F.Paste")
			(net "P3V3_AUX")
		)
		(pad "2" smd circle
			(at 0.40005 0)
			(size 0 0)
			(layers "F.Cu" "F.Mask" "F.Paste")
			(net "GND")
		)
	)
	(footprint ""
		(layer "F.Cu")
		(at 338.796884 -117.627654 180)
		(property "Reference" "PR7026"
			(at 0 0 180)
			(layer "F.SilkS")
			(hide yes)
			(effects
				(font
					(size 1.27 1.27)
				)
			)
		)
		(property "Value" ""
			(at 0 0 180)
			(layer "F.Fab")
			(effects
				(font
					(size 1.27 1.27)
				)
			)
		)
		(duplicate_pad_numbers_are_jumpers no)
		(fp_line
			(start 0.7874 0.4064)
			(end -0.7874 0.4064)
			(stroke
				(width 0.1524)
				(type default)
			)
			(layer "F.SilkS")
		)
		(fp_line
			(start 0.7874 -0.4064)
			(end 0.7874 0.4064)
			(stroke
				(width 0.1524)
				(type default)
			)
			(layer "F.SilkS")
		)
		(fp_line
			(start -0.7874 0.4064)
			(end -0.7874 -0.4064)
			(stroke
				(width 0.1524)
				(type default)
			)
			(layer "F.SilkS")
		)
		(fp_line
			(start -0.7874 -0.4064)
			(end 0.7874 -0.4064)
			(stroke
				(width 0.1524)
				(type default)
			)
			(layer "F.SilkS")
		)
		(fp_line
			(start 0.67945 0.3048)
			(end 0.120396 0.3048)
			(stroke
				(width 0.1)
				(type default)
			)
			(layer "F.Fab")
		)
		(fp_line
			(start 0.67945 -0.3048)
			(end 0.67945 0.3048)
			(stroke
				(width 0.1)
				(type default)
			)
			(layer "F.Fab")
		)
		(fp_line
			(start 0.12065 -0.2794)
			(end 0.12065 -0.3048)
			(stroke
				(width 0.1)
				(type default)
			)
			(layer "F.Fab")
		)
		(fp_line
			(start 0.12065 -0.3048)
			(end 0.67945 -0.3048)
			(stroke
				(width 0.1)
				(type default)
			)
			(layer "F.Fab")
		)
		(fp_line
			(start 0.120396 0.3048)
			(end 0.120396 0.2794)
			(stroke
				(width 0.1)
				(type default)
			)
			(layer "F.Fab")
		)
		(fp_line
			(start 0.120396 0.2794)
			(end -0.12065 0.2794)
			(stroke
				(width 0.1)
				(type default)
			)
			(layer "F.Fab")
		)
		(fp_line
			(start -0.12065 0.3048)
			(end -0.67945 0.3048)
			(stroke
				(width 0.1)
				(type default)
			)
			(layer "F.Fab")
		)
		(fp_line
			(start -0.12065 0.2794)
			(end -0.12065 0.3048)
			(stroke
				(width 0.1)
				(type default)
			)
			(layer "F.Fab")
		)
		(fp_line
			(start -0.12065 -0.2794)
			(end 0.12065 -0.2794)
			(stroke
				(width 0.1)
				(type default)
			)
			(layer "F.Fab")
		)
		(fp_line
			(start -0.12065 -0.305054)
			(end -0.12065 -0.2794)
			(stroke
				(width 0.1)
				(type default)
			)
			(layer "F.Fab")
		)
		(fp_line
			(start -0.67945 0.3048)
			(end -0.67945 -0.305054)
			(stroke
				(width 0.1)
				(type default)
			)
			(layer "F.Fab")
		)
		(fp_line
			(start -0.67945 -0.305054)
			(end -0.12065 -0.305054)
			(stroke
				(width 0.1)
				(type default)
			)
			(layer "F.Fab")
		)
		(pad "1" smd circle
			(at -0.40005 0 180)
			(size 0 0)
			(layers "F.Cu" "F.Mask" "F.Paste")
			(net "P12V_NIC5_CO_OV_FB")
		)
		(pad "2" smd circle
			(at 0.40005 0 180)
			(size 0 0)
			(layers "F.Cu" "F.Mask" "F.Paste")
			(net "P12V_NIC5_R")
		)
	)
	(footprint ""
		(layer "F.Cu")
		(at 58.176922 -378.572268)
		(property "Reference" "R1825"
			(at 0 0 0)
			(layer "F.SilkS")
			(hide yes)
			(effects
				(font
					(size 1.27 1.27)
				)
			)
		)
		(property "Value" ""
			(at 0 0 0)
			(layer "F.Fab")
			(effects
				(font
					(size 1.27 1.27)
				)
			)
		)
		(duplicate_pad_numbers_are_jumpers no)
		(fp_line
			(start -0.7874 -0.4064)
			(end 0.7874 -0.4064)
			(stroke
				(width 0.1524)
				(type default)
			)
			(layer "F.SilkS")
		)
		(fp_line
			(start -0.7874 0.4064)
			(end -0.7874 -0.4064)
			(stroke
				(width 0.1524)
				(type default)
			)
			(layer "F.SilkS")
		)
		(fp_line
			(start 0.7874 -0.4064)
			(end 0.7874 0.4064)
			(stroke
				(width 0.1524)
				(type default)
			)
			(layer "F.SilkS")
		)
		(fp_line
			(start 0.7874 0.4064)
			(end -0.7874 0.4064)
			(stroke
				(width 0.1524)
				(type default)
			)
			(layer "F.SilkS")
		)
		(fp_line
			(start -0.67945 -0.305054)
			(end -0.12065 -0.305054)
			(stroke
				(width 0.1)
				(type default)
			)
			(layer "F.Fab")
		)
		(fp_line
			(start -0.67945 0.3048)
			(end -0.67945 -0.305054)
			(stroke
				(width 0.1)
				(type default)
			)
			(layer "F.Fab")
		)
		(fp_line
			(start -0.12065 -0.305054)
			(end -0.12065 -0.2794)
			(stroke
				(width 0.1)
				(type default)
			)
			(layer "F.Fab")
		)
		(fp_line
			(start -0.12065 -0.2794)
			(end 0.12065 -0.2794)
			(stroke
				(width 0.1)
				(type default)
			)
			(layer "F.Fab")
		)
		(fp_line
			(start -0.12065 0.2794)
			(end -0.12065 0.3048)
			(stroke
				(width 0.1)
				(type default)
			)
			(layer "F.Fab")
		)
		(fp_line
			(start -0.12065 0.3048)
			(end -0.67945 0.3048)
			(stroke
				(width 0.1)
				(type default)
			)
			(layer "F.Fab")
		)
		(fp_line
			(start 0.120396 0.2794)
			(end -0.12065 0.2794)
			(stroke
				(width 0.1)
				(type default)
			)
			(layer "F.Fab")
		)
		(fp_line
			(start 0.120396 0.3048)
			(end 0.120396 0.2794)
			(stroke
				(width 0.1)
				(type default)
			)
			(layer "F.Fab")
		)
		(fp_line
			(start 0.12065 -0.3048)
			(end 0.67945 -0.3048)
			(stroke
				(width 0.1)
				(type default)
			)
			(layer "F.Fab")
		)
		(fp_line
			(start 0.12065 -0.2794)
			(end 0.12065 -0.3048)
			(stroke
				(width 0.1)
				(type default)
			)
			(layer "F.Fab")
		)
		(fp_line
			(start 0.67945 -0.3048)
			(end 0.67945 0.3048)
			(stroke
				(width 0.1)
				(type default)
			)
			(layer "F.Fab")
		)
		(fp_line
			(start 0.67945 0.3048)
			(end 0.120396 0.3048)
			(stroke
				(width 0.1)
				(type default)
			)
			(layer "F.Fab")
		)
		(pad "1" smd circle
			(at -0.40005 0)
			(size 0 0)
			(layers "F.Cu" "F.Mask" "F.Paste")
			(net "GPU_BASE_ID1_R")
		)
		(pad "2" smd circle
			(at 0.40005 0)
			(size 0 0)
			(layers "F.Cu" "F.Mask" "F.Paste")
			(net "GPU_BASE_ID1")
		)
	)
	(footprint ""
		(layer "F.Cu")
		(at 41.984168 -343.952322 90)
		(property "Reference" "C171"
			(at 0 0 90)
			(layer "F.SilkS")
			(hide yes)
			(effects
				(font
					(size 1.27 1.27)
				)
			)
		)
		(property "Value" ""
			(at 0 0 90)
			(layer "F.Fab")
			(effects
				(font
					(size 1.27 1.27)
				)
			)
		)
		(duplicate_pad_numbers_are_jumpers no)
		(fp_line
			(start 0.299974 -0.150114)
			(end 0.299974 0.150114)
			(stroke
				(width 0.1)
				(type default)
			)
			(layer "F.Fab")
		)
		(fp_line
			(start -0.299974 -0.150114)
			(end 0.299974 -0.150114)
			(stroke
				(width 0.1)
				(type default)
			)
			(layer "F.Fab")
		)
		(fp_line
			(start 0.299974 0.150114)
			(end -0.299974 0.150114)
			(stroke
				(width 0.1)
				(type default)
			)
			(layer "F.Fab")
		)
		(fp_line
			(start -0.299974 0.150114)
			(end -0.299974 -0.150114)
			(stroke
				(width 0.1)
				(type default)
			)
			(layer "F.Fab")
		)
		(pad "1" smd rect
			(at -0.2667 0 90)
			(size 0.3048 0.381)
			(layers "F.Cu" "F.Mask" "F.Paste")
			(net "P5E_PEX0_STN7_TX_DP<122>")
		)
		(pad "2" smd rect
			(at 0.2667 0 90)
			(size 0.3048 0.381)
			(layers "F.Cu" "F.Mask" "F.Paste")
			(net "P5E_PEX0_STN7_TX_C_DP<122>")
		)
	)
	(footprint ""
		(layer "F.Cu")
		(at 115.83035 -309.749952 -90)
		(property "Reference" "R6453"
			(at 0 0 270)
			(layer "F.SilkS")
			(hide yes)
			(effects
				(font
					(size 1.27 1.27)
				)
			)
		)
		(property "Value" ""
			(at 0 0 270)
			(layer "F.Fab")
			(effects
				(font
					(size 1.27 1.27)
				)
			)
		)
		(duplicate_pad_numbers_are_jumpers no)
		(fp_line
			(start -0.7874 0.4064)
			(end -0.7874 -0.4064)
			(stroke
				(width 0.1524)
				(type default)
			)
			(layer "F.SilkS")
		)
		(fp_line
			(start 0.7874 0.4064)
			(end -0.7874 0.4064)
			(stroke
				(width 0.1524)
				(type default)
			)
			(layer "F.SilkS")
		)
		(fp_line
			(start -0.7874 -0.4064)
			(end 0.7874 -0.4064)
			(stroke
				(width 0.1524)
				(type default)
			)
			(layer "F.SilkS")
		)
		(fp_line
			(start 0.7874 -0.4064)
			(end 0.7874 0.4064)
			(stroke
				(width 0.1524)
				(type default)
			)
			(layer "F.SilkS")
		)
		(fp_line
			(start -0.67945 0.3048)
			(end -0.67945 -0.305054)
			(stroke
				(width 0.1)
				(type default)
			)
			(layer "F.Fab")
		)
		(fp_line
			(start -0.12065 0.3048)
			(end -0.67945 0.3048)
			(stroke
				(width 0.1)
				(type default)
			)
			(layer "F.Fab")
		)
		(fp_line
			(start 0.120396 0.3048)
			(end 0.120396 0.2794)
			(stroke
				(width 0.1)
				(type default)
			)
			(layer "F.Fab")
		)
		(fp_line
			(start 0.67945 0.3048)
			(end 0.120396 0.3048)
			(stroke
				(width 0.1)
				(type default)
			)
			(layer "F.Fab")
		)
		(fp_line
			(start -0.12065 0.2794)
			(end -0.12065 0.3048)
			(stroke
				(width 0.1)
				(type default)
			)
			(layer "F.Fab")
		)
		(fp_line
			(start 0.120396 0.2794)
			(end -0.12065 0.2794)
			(stroke
				(width 0.1)
				(type default)
			)
			(layer "F.Fab")
		)
		(fp_line
			(start -0.12065 -0.2794)
			(end 0.12065 -0.2794)
			(stroke
				(width 0.1)
				(type default)
			)
			(layer "F.Fab")
		)
		(fp_line
			(start 0.12065 -0.2794)
			(end 0.12065 -0.3048)
			(stroke
				(width 0.1)
				(type default)
			)
			(layer "F.Fab")
		)
		(fp_line
			(start 0.12065 -0.3048)
			(end 0.67945 -0.3048)
			(stroke
				(width 0.1)
				(type default)
			)
			(layer "F.Fab")
		)
		(fp_line
			(start 0.67945 -0.3048)
			(end 0.67945 0.3048)
			(stroke
				(width 0.1)
				(type default)
			)
			(layer "F.Fab")
		)
		(fp_line
			(start -0.67945 -0.305054)
			(end -0.12065 -0.305054)
			(stroke
				(width 0.1)
				(type default)
			)
			(layer "F.Fab")
		)
		(fp_line
			(start -0.12065 -0.305054)
			(end -0.12065 -0.2794)
			(stroke
				(width 0.1)
				(type default)
			)
			(layer "F.Fab")
		)
		(pad "1" smd circle
			(at -0.40005 0 270)
			(size 0 0)
			(layers "F.Cu" "F.Mask" "F.Paste")
			(net "P0V8_SERDES_VDDA_PEX0")
		)
		(pad "2" smd circle
			(at 0.40005 0 270)
			(size 0 0)
			(layers "F.Cu" "F.Mask" "F.Paste")
			(net "P0V8_SERDES_VDDA_PEX0_C4")
		)
	)
	(footprint ""
		(layer "F.Cu")
		(at 244.12194 -254.097282 -90)
		(property "Reference" "C4353"
			(at 0 0 270)
			(layer "F.SilkS")
			(hide yes)
			(effects
				(font
					(size 1.27 1.27)
				)
			)
		)
		(property "Value" ""
			(at 0 0 270)
			(layer "F.Fab")
			(effects
				(font
					(size 1.27 1.27)
				)
			)
		)
		(duplicate_pad_numbers_are_jumpers no)
		(fp_line
			(start -1.2954 0.5842)
			(end -1.2954 -0.5842)
			(stroke
				(width 0.1524)
				(type default)
			)
			(layer "F.SilkS")
		)
		(fp_line
			(start 1.2954 0.5842)
			(end -1.2954 0.5842)
			(stroke
				(width 0.1524)
				(type default)
			)
			(layer "F.SilkS")
		)
		(fp_line
			(start -1.2954 -0.5842)
			(end 1.2954 -0.5842)
			(stroke
				(width 0.1524)
				(type default)
			)
			(layer "F.SilkS")
		)
		(fp_line
			(start 1.2954 -0.5842)
			(end 1.2954 0.5842)
			(stroke
				(width 0.1524)
				(type default)
			)
			(layer "F.SilkS")
		)
		(fp_line
			(start -0.8636 0.4572)
			(end -0.8636 0.4064)
			(stroke
				(width 0.1)
				(type default)
			)
			(layer "F.Fab")
		)
		(fp_line
			(start 0.8636 0.4572)
			(end -0.8636 0.4572)
			(stroke
				(width 0.1)
				(type default)
			)
			(layer "F.Fab")
		)
		(fp_line
			(start -1.1938 0.4064)
			(end -1.1938 -0.4064)
			(stroke
				(width 0.1)
				(type default)
			)
			(layer "F.Fab")
		)
		(fp_line
			(start -0.8636 0.4064)
			(end -1.1938 0.4064)
			(stroke
				(width 0.1)
				(type default)
			)
			(layer "F.Fab")
		)
		(fp_line
			(start 0.8636 0.4064)
			(end 0.8636 0.4572)
			(stroke
				(width 0.1)
				(type default)
			)
			(layer "F.Fab")
		)
		(fp_line
			(start 1.1938 0.4064)
			(end 0.8636 0.4064)
			(stroke
				(width 0.1)
				(type default)
			)
			(layer "F.Fab")
		)
		(fp_line
			(start -1.1938 -0.4064)
			(end -0.8636 -0.4064)
			(stroke
				(width 0.1)
				(type default)
			)
			(layer "F.Fab")
		)
		(fp_line
			(start -0.8636 -0.4064)
			(end -0.8636 -0.4572)
			(stroke
				(width 0.1)
				(type default)
			)
			(layer "F.Fab")
		)
		(fp_line
			(start 0.8636 -0.4064)
			(end 1.1938 -0.4064)
			(stroke
				(width 0.1)
				(type default)
			)
			(layer "F.Fab")
		)
		(fp_line
			(start 1.1938 -0.4064)
			(end 1.1938 0.4064)
			(stroke
				(width 0.1)
				(type default)
			)
			(layer "F.Fab")
		)
		(fp_line
			(start -0.8636 -0.4572)
			(end 0.8636 -0.4572)
			(stroke
				(width 0.1)
				(type default)
			)
			(layer "F.Fab")
		)
		(fp_line
			(start 0.8636 -0.4572)
			(end 0.8636 -0.4064)
			(stroke
				(width 0.1)
				(type default)
			)
			(layer "F.Fab")
		)
		(pad "1" smd rect
			(at -0.7366 0 180)
			(size 0.7112 0.8128)
			(layers "F.Cu" "F.Mask" "F.Paste")
			(net "P1V25_SERDES_VDDPLL_PEX2_C7")
		)
		(pad "2" smd rect
			(at 0.7366 0 180)
			(size 0.7112 0.8128)
			(layers "F.Cu" "F.Mask" "F.Paste")
			(net "GND")
		)
	)
	(footprint ""
		(layer "F.Cu")
		(at 143.226282 -39.73576 -90)
		(property "Reference" "R5554"
			(at 0 0 270)
			(layer "F.SilkS")
			(hide yes)
			(effects
				(font
					(size 1.27 1.27)
				)
			)
		)
		(property "Value" ""
			(at 0 0 270)
			(layer "F.Fab")
			(effects
				(font
					(size 1.27 1.27)
				)
			)
		)
		(duplicate_pad_numbers_are_jumpers no)
		(fp_line
			(start -0.7874 0.4064)
			(end -0.7874 -0.4064)
			(stroke
				(width 0.1524)
				(type default)
			)
			(layer "F.SilkS")
		)
		(fp_line
			(start 0.7874 0.4064)
			(end -0.7874 0.4064)
			(stroke
				(width 0.1524)
				(type default)
			)
			(layer "F.SilkS")
		)
		(fp_line
			(start -0.7874 -0.4064)
			(end 0.7874 -0.4064)
			(stroke
				(width 0.1524)
				(type default)
			)
			(layer "F.SilkS")
		)
		(fp_line
			(start 0.7874 -0.4064)
			(end 0.7874 0.4064)
			(stroke
				(width 0.1524)
				(type default)
			)
			(layer "F.SilkS")
		)
		(fp_line
			(start -0.67945 0.3048)
			(end -0.67945 -0.305054)
			(stroke
				(width 0.1)
				(type default)
			)
			(layer "F.Fab")
		)
		(fp_line
			(start -0.12065 0.3048)
			(end -0.67945 0.3048)
			(stroke
				(width 0.1)
				(type default)
			)
			(layer "F.Fab")
		)
		(fp_line
			(start 0.120396 0.3048)
			(end 0.120396 0.2794)
			(stroke
				(width 0.1)
				(type default)
			)
			(layer "F.Fab")
		)
		(fp_line
			(start 0.67945 0.3048)
			(end 0.120396 0.3048)
			(stroke
				(width 0.1)
				(type default)
			)
			(layer "F.Fab")
		)
		(fp_line
			(start -0.12065 0.2794)
			(end -0.12065 0.3048)
			(stroke
				(width 0.1)
				(type default)
			)
			(layer "F.Fab")
		)
		(fp_line
			(start 0.120396 0.2794)
			(end -0.12065 0.2794)
			(stroke
				(width 0.1)
				(type default)
			)
			(layer "F.Fab")
		)
		(fp_line
			(start -0.12065 -0.2794)
			(end 0.12065 -0.2794)
			(stroke
				(width 0.1)
				(type default)
			)
			(layer "F.Fab")
		)
		(fp_line
			(start 0.12065 -0.2794)
			(end 0.12065 -0.3048)
			(stroke
				(width 0.1)
				(type default)
			)
			(layer "F.Fab")
		)
		(fp_line
			(start 0.12065 -0.3048)
			(end 0.67945 -0.3048)
			(stroke
				(width 0.1)
				(type default)
			)
			(layer "F.Fab")
		)
		(fp_line
			(start 0.67945 -0.3048)
			(end 0.67945 0.3048)
			(stroke
				(width 0.1)
				(type default)
			)
			(layer "F.Fab")
		)
		(fp_line
			(start -0.67945 -0.305054)
			(end -0.12065 -0.305054)
			(stroke
				(width 0.1)
				(type default)
			)
			(layer "F.Fab")
		)
		(fp_line
			(start -0.12065 -0.305054)
			(end -0.12065 -0.2794)
			(stroke
				(width 0.1)
				(type default)
			)
			(layer "F.Fab")
		)
		(pad "1" smd circle
			(at -0.40005 0 270)
			(size 0 0)
			(layers "F.Cu" "F.Mask" "F.Paste")
			(net "P3V3_AUX")
		)
		(pad "2" smd circle
			(at 0.40005 0 270)
			(size 0 0)
			(layers "F.Cu" "F.Mask" "F.Paste")
			(net "SSD5_AUX_P3V3_EN")
		)
	)
	(footprint ""
		(layer "F.Cu")
		(at 142.559532 -22.955504 90)
		(property "Reference" "R1671"
			(at 0 0 90)
			(layer "F.SilkS")
			(hide yes)
			(effects
				(font
					(size 1.27 1.27)
				)
			)
		)
		(property "Value" ""
			(at 0 0 90)
			(layer "F.Fab")
			(effects
				(font
					(size 1.27 1.27)
				)
			)
		)
		(duplicate_pad_numbers_are_jumpers no)
		(fp_line
			(start 0.7874 -0.4064)
			(end 0.7874 0.4064)
			(stroke
				(width 0.1524)
				(type default)
			)
			(layer "F.SilkS")
		)
		(fp_line
			(start -0.7874 -0.4064)
			(end 0.7874 -0.4064)
			(stroke
				(width 0.1524)
				(type default)
			)
			(layer "F.SilkS")
		)
		(fp_line
			(start 0.7874 0.4064)
			(end -0.7874 0.4064)
			(stroke
				(width 0.1524)
				(type default)
			)
			(layer "F.SilkS")
		)
		(fp_line
			(start -0.7874 0.4064)
			(end -0.7874 -0.4064)
			(stroke
				(width 0.1524)
				(type default)
			)
			(layer "F.SilkS")
		)
		(fp_line
			(start -0.12065 -0.305054)
			(end -0.12065 -0.2794)
			(stroke
				(width 0.1)
				(type default)
			)
			(layer "F.Fab")
		)
		(fp_line
			(start -0.67945 -0.305054)
			(end -0.12065 -0.305054)
			(stroke
				(width 0.1)
				(type default)
			)
			(layer "F.Fab")
		)
		(fp_line
			(start 0.67945 -0.3048)
			(end 0.67945 0.3048)
			(stroke
				(width 0.1)
				(type default)
			)
			(layer "F.Fab")
		)
		(fp_line
			(start 0.12065 -0.3048)
			(end 0.67945 -0.3048)
			(stroke
				(width 0.1)
				(type default)
			)
			(layer "F.Fab")
		)
		(fp_line
			(start 0.12065 -0.2794)
			(end 0.12065 -0.3048)
			(stroke
				(width 0.1)
				(type default)
			)
			(layer "F.Fab")
		)
		(fp_line
			(start -0.12065 -0.2794)
			(end 0.12065 -0.2794)
			(stroke
				(width 0.1)
				(type default)
			)
			(layer "F.Fab")
		)
		(fp_line
			(start 0.120396 0.2794)
			(end -0.12065 0.2794)
			(stroke
				(width 0.1)
				(type default)
			)
			(layer "F.Fab")
		)
		(fp_line
			(start -0.12065 0.2794)
			(end -0.12065 0.3048)
			(stroke
				(width 0.1)
				(type default)
			)
			(layer "F.Fab")
		)
		(fp_line
			(start 0.67945 0.3048)
			(end 0.120396 0.3048)
			(stroke
				(width 0.1)
				(type default)
			)
			(layer "F.Fab")
		)
		(fp_line
			(start 0.120396 0.3048)
			(end 0.120396 0.2794)
			(stroke
				(width 0.1)
				(type default)
			)
			(layer "F.Fab")
		)
		(fp_line
			(start -0.12065 0.3048)
			(end -0.67945 0.3048)
			(stroke
				(width 0.1)
				(type default)
			)
			(layer "F.Fab")
		)
		(fp_line
			(start -0.67945 0.3048)
			(end -0.67945 -0.305054)
			(stroke
				(width 0.1)
				(type default)
			)
			(layer "F.Fab")
		)
		(pad "1" smd circle
			(at -0.40005 0 90)
			(size 0 0)
			(layers "F.Cu" "F.Mask" "F.Paste")
			(net "SMB_BIC_I2C9_MUX0_SSD4_R_SCL")
		)
		(pad "2" smd circle
			(at 0.40005 0 90)
			(size 0 0)
			(layers "F.Cu" "F.Mask" "F.Paste")
			(net "SMB_ISO_SSD4_SCL")
		)
	)
	(footprint ""
		(layer "F.Cu")
		(at 144.923764 -306.366418 45)
		(property "Reference" "R1319"
			(at 0 0 45)
			(layer "F.SilkS")
			(hide yes)
			(effects
				(font
					(size 1.27 1.27)
				)
			)
		)
		(property "Value" ""
			(at 0 0 45)
			(layer "F.Fab")
			(effects
				(font
					(size 1.27 1.27)
				)
			)
		)
		(duplicate_pad_numbers_are_jumpers no)
		(fp_line
			(start -0.787389 -0.406267)
			(end 0.787389 -0.406267)
			(stroke
				(width 0.1524)
				(type default)
			)
			(layer "F.SilkS")
		)
		(fp_line
			(start -0.787389 0.406267)
			(end -0.787389 -0.406267)
			(stroke
				(width 0.1524)
				(type default)
			)
			(layer "F.SilkS")
		)
		(fp_line
			(start 0.787389 -0.406267)
			(end 0.787389 0.406267)
			(stroke
				(width 0.1524)
				(type default)
			)
			(layer "F.SilkS")
		)
		(fp_line
			(start 0.787389 0.406267)
			(end -0.787389 0.406267)
			(stroke
				(width 0.1524)
				(type default)
			)
			(layer "F.SilkS")
		)
		(fp_line
			(start -0.679446 -0.305149)
			(end -0.120695 -0.304969)
			(stroke
				(width 0.1)
				(type default)
			)
			(layer "F.Fab")
		)
		(fp_line
			(start -0.120695 -0.304969)
			(end -0.120695 -0.279466)
			(stroke
				(width 0.1)
				(type default)
			)
			(layer "F.Fab")
		)
		(fp_line
			(start -0.120695 -0.279466)
			(end 0.120695 -0.279466)
			(stroke
				(width 0.1)
				(type default)
			)
			(layer "F.Fab")
		)
		(fp_line
			(start -0.679446 0.30479)
			(end -0.679446 -0.305149)
			(stroke
				(width 0.1)
				(type default)
			)
			(layer "F.Fab")
		)
		(fp_line
			(start 0.120515 -0.30479)
			(end 0.679446 -0.30479)
			(stroke
				(width 0.1)
				(type default)
			)
			(layer "F.Fab")
		)
		(fp_line
			(start 0.120695 -0.279466)
			(end 0.120515 -0.30479)
			(stroke
				(width 0.1)
				(type default)
			)
			(layer "F.Fab")
		)
		(fp_line
			(start -0.120695 0.279466)
			(end -0.120515 0.30479)
			(stroke
				(width 0.1)
				(type default)
			)
			(layer "F.Fab")
		)
		(fp_line
			(start -0.120515 0.30479)
			(end -0.679446 0.30479)
			(stroke
				(width 0.1)
				(type default)
			)
			(layer "F.Fab")
		)
		(fp_line
			(start 0.679446 -0.30479)
			(end 0.679446 0.30479)
			(stroke
				(width 0.1)
				(type default)
			)
			(layer "F.Fab")
		)
		(fp_line
			(start 0.120335 0.279466)
			(end -0.120695 0.279466)
			(stroke
				(width 0.1)
				(type default)
			)
			(layer "F.Fab")
		)
		(fp_line
			(start 0.120515 0.30479)
			(end 0.120335 0.279466)
			(stroke
				(width 0.1)
				(type default)
			)
			(layer "F.Fab")
		)
		(fp_line
			(start 0.679446 0.30479)
			(end 0.120515 0.30479)
			(stroke
				(width 0.1)
				(type default)
			)
			(layer "F.Fab")
		)
		(pad "1" smd circle
			(at -0.40005 0 45)
			(size 0 0)
			(layers "F.Cu" "F.Mask" "F.Paste")
			(net "GND")
		)
		(pad "2" smd circle
			(at 0.40005 0 45)
			(size 0 0)
			(layers "F.Cu" "F.Mask" "F.Paste")
			(net "PEX1_DFT_IDDT")
		)
	)
	(footprint ""
		(layer "F.Cu")
		(at 113.21923 -159.27324 -90)
		(property "Reference" "PR62"
			(at 0 0 270)
			(layer "F.SilkS")
			(hide yes)
			(effects
				(font
					(size 1.27 1.27)
				)
			)
		)
		(property "Value" ""
			(at 0 0 270)
			(layer "F.Fab")
			(effects
				(font
					(size 1.27 1.27)
				)
			)
		)
		(duplicate_pad_numbers_are_jumpers no)
		(fp_line
			(start -0.7874 0.4064)
			(end -0.7874 -0.4064)
			(stroke
				(width 0.1524)
				(type default)
			)
			(layer "F.SilkS")
		)
		(fp_line
			(start 0.7874 0.4064)
			(end -0.7874 0.4064)
			(stroke
				(width 0.1524)
				(type default)
			)
			(layer "F.SilkS")
		)
		(fp_line
			(start -0.7874 -0.4064)
			(end 0.7874 -0.4064)
			(stroke
				(width 0.1524)
				(type default)
			)
			(layer "F.SilkS")
		)
		(fp_line
			(start 0.7874 -0.4064)
			(end 0.7874 0.4064)
			(stroke
				(width 0.1524)
				(type default)
			)
			(layer "F.SilkS")
		)
		(fp_line
			(start -0.67945 0.3048)
			(end -0.67945 -0.305054)
			(stroke
				(width 0.1)
				(type default)
			)
			(layer "F.Fab")
		)
		(fp_line
			(start -0.12065 0.3048)
			(end -0.67945 0.3048)
			(stroke
				(width 0.1)
				(type default)
			)
			(layer "F.Fab")
		)
		(fp_line
			(start 0.120396 0.3048)
			(end 0.120396 0.2794)
			(stroke
				(width 0.1)
				(type default)
			)
			(layer "F.Fab")
		)
		(fp_line
			(start 0.67945 0.3048)
			(end 0.120396 0.3048)
			(stroke
				(width 0.1)
				(type default)
			)
			(layer "F.Fab")
		)
		(fp_line
			(start -0.12065 0.2794)
			(end -0.12065 0.3048)
			(stroke
				(width 0.1)
				(type default)
			)
			(layer "F.Fab")
		)
		(fp_line
			(start 0.120396 0.2794)
			(end -0.12065 0.2794)
			(stroke
				(width 0.1)
				(type default)
			)
			(layer "F.Fab")
		)
		(fp_line
			(start -0.12065 -0.2794)
			(end 0.12065 -0.2794)
			(stroke
				(width 0.1)
				(type default)
			)
			(layer "F.Fab")
		)
		(fp_line
			(start 0.12065 -0.2794)
			(end 0.12065 -0.3048)
			(stroke
				(width 0.1)
				(type default)
			)
			(layer "F.Fab")
		)
		(fp_line
			(start 0.12065 -0.3048)
			(end 0.67945 -0.3048)
			(stroke
				(width 0.1)
				(type default)
			)
			(layer "F.Fab")
		)
		(fp_line
			(start 0.67945 -0.3048)
			(end 0.67945 0.3048)
			(stroke
				(width 0.1)
				(type default)
			)
			(layer "F.Fab")
		)
		(fp_line
			(start -0.67945 -0.305054)
			(end -0.12065 -0.305054)
			(stroke
				(width 0.1)
				(type default)
			)
			(layer "F.Fab")
		)
		(fp_line
			(start -0.12065 -0.305054)
			(end -0.12065 -0.2794)
			(stroke
				(width 0.1)
				(type default)
			)
			(layer "F.Fab")
		)
		(pad "1" smd circle
			(at -0.40005 0 270)
			(size 0 0)
			(layers "F.Cu" "F.Mask" "F.Paste")
			(net "P3V3_AUX_CS")
		)
		(pad "2" smd circle
			(at 0.40005 0 270)
			(size 0 0)
			(layers "F.Cu" "F.Mask" "F.Paste")
			(net "GND")
		)
	)
	(footprint ""
		(layer "F.Cu")
		(at 362.064808 -162.003994 90)
		(property "Reference" "PC833"
			(at 0 0 90)
			(layer "F.SilkS")
			(hide yes)
			(effects
				(font
					(size 1.27 1.27)
				)
			)
		)
		(property "Value" ""
			(at 0 0 90)
			(layer "F.Fab")
			(effects
				(font
					(size 1.27 1.27)
				)
			)
		)
		(duplicate_pad_numbers_are_jumpers no)
		(fp_line
			(start 0.7874 -0.4064)
			(end 0.7874 0.4064)
			(stroke
				(width 0.1524)
				(type default)
			)
			(layer "F.SilkS")
		)
		(fp_line
			(start -0.7874 -0.4064)
			(end 0.7874 -0.4064)
			(stroke
				(width 0.1524)
				(type default)
			)
			(layer "F.SilkS")
		)
		(fp_line
			(start 0.7874 0.4064)
			(end -0.7874 0.4064)
			(stroke
				(width 0.1524)
				(type default)
			)
			(layer "F.SilkS")
		)
		(fp_line
			(start -0.7874 0.4064)
			(end -0.7874 -0.4064)
			(stroke
				(width 0.1524)
				(type default)
			)
			(layer "F.SilkS")
		)
		(fp_line
			(start -0.12065 -0.305054)
			(end -0.12065 -0.2794)
			(stroke
				(width 0.1)
				(type default)
			)
			(layer "F.Fab")
		)
		(fp_line
			(start -0.67945 -0.305054)
			(end -0.12065 -0.305054)
			(stroke
				(width 0.1)
				(type default)
			)
			(layer "F.Fab")
		)
		(fp_line
			(start 0.67945 -0.3048)
			(end 0.67945 0.3048)
			(stroke
				(width 0.1)
				(type default)
			)
			(layer "F.Fab")
		)
		(fp_line
			(start 0.12065 -0.3048)
			(end 0.67945 -0.3048)
			(stroke
				(width 0.1)
				(type default)
			)
			(layer "F.Fab")
		)
		(fp_line
			(start 0.12065 -0.2794)
			(end 0.12065 -0.3048)
			(stroke
				(width 0.1)
				(type default)
			)
			(layer "F.Fab")
		)
		(fp_line
			(start -0.12065 -0.2794)
			(end 0.12065 -0.2794)
			(stroke
				(width 0.1)
				(type default)
			)
			(layer "F.Fab")
		)
		(fp_line
			(start 0.120396 0.2794)
			(end -0.12065 0.2794)
			(stroke
				(width 0.1)
				(type default)
			)
			(layer "F.Fab")
		)
		(fp_line
			(start -0.12065 0.2794)
			(end -0.12065 0.3048)
			(stroke
				(width 0.1)
				(type default)
			)
			(layer "F.Fab")
		)
		(fp_line
			(start 0.67945 0.3048)
			(end 0.120396 0.3048)
			(stroke
				(width 0.1)
				(type default)
			)
			(layer "F.Fab")
		)
		(fp_line
			(start 0.120396 0.3048)
			(end 0.120396 0.2794)
			(stroke
				(width 0.1)
				(type default)
			)
			(layer "F.Fab")
		)
		(fp_line
			(start -0.12065 0.3048)
			(end -0.67945 0.3048)
			(stroke
				(width 0.1)
				(type default)
			)
			(layer "F.Fab")
		)
		(fp_line
			(start -0.67945 0.3048)
			(end -0.67945 -0.305054)
			(stroke
				(width 0.1)
				(type default)
			)
			(layer "F.Fab")
		)
		(pad "1" smd circle
			(at -0.40005 0 90)
			(size 0 0)
			(layers "F.Cu" "F.Mask" "F.Paste")
			(net "P12V_NIC6_CO_TIMER")
		)
		(pad "2" smd circle
			(at 0.40005 0 90)
			(size 0 0)
			(layers "F.Cu" "F.Mask" "F.Paste")
			(net "GND")
		)
	)
	(footprint ""
		(layer "F.Cu")
		(at 177.295048 -59.577986 90)
		(property "Reference" "PC531"
			(at 0 0 90)
			(layer "F.SilkS")
			(hide yes)
			(effects
				(font
					(size 1.27 1.27)
				)
			)
		)
		(property "Value" ""
			(at 0 0 90)
			(layer "F.Fab")
			(effects
				(font
					(size 1.27 1.27)
				)
			)
		)
		(duplicate_pad_numbers_are_jumpers no)
		(fp_line
			(start 0.7874 -0.4064)
			(end 0.7874 0.4064)
			(stroke
				(width 0.1524)
				(type default)
			)
			(layer "F.SilkS")
		)
		(fp_line
			(start -0.7874 -0.4064)
			(end 0.7874 -0.4064)
			(stroke
				(width 0.1524)
				(type default)
			)
			(layer "F.SilkS")
		)
		(fp_line
			(start 0.7874 0.4064)
			(end -0.7874 0.4064)
			(stroke
				(width 0.1524)
				(type default)
			)
			(layer "F.SilkS")
		)
		(fp_line
			(start -0.7874 0.4064)
			(end -0.7874 -0.4064)
			(stroke
				(width 0.1524)
				(type default)
			)
			(layer "F.SilkS")
		)
		(fp_line
			(start -0.12065 -0.305054)
			(end -0.12065 -0.2794)
			(stroke
				(width 0.1)
				(type default)
			)
			(layer "F.Fab")
		)
		(fp_line
			(start -0.67945 -0.305054)
			(end -0.12065 -0.305054)
			(stroke
				(width 0.1)
				(type default)
			)
			(layer "F.Fab")
		)
		(fp_line
			(start 0.67945 -0.3048)
			(end 0.67945 0.3048)
			(stroke
				(width 0.1)
				(type default)
			)
			(layer "F.Fab")
		)
		(fp_line
			(start 0.12065 -0.3048)
			(end 0.67945 -0.3048)
			(stroke
				(width 0.1)
				(type default)
			)
			(layer "F.Fab")
		)
		(fp_line
			(start 0.12065 -0.2794)
			(end 0.12065 -0.3048)
			(stroke
				(width 0.1)
				(type default)
			)
			(layer "F.Fab")
		)
		(fp_line
			(start -0.12065 -0.2794)
			(end 0.12065 -0.2794)
			(stroke
				(width 0.1)
				(type default)
			)
			(layer "F.Fab")
		)
		(fp_line
			(start 0.120396 0.2794)
			(end -0.12065 0.2794)
			(stroke
				(width 0.1)
				(type default)
			)
			(layer "F.Fab")
		)
		(fp_line
			(start -0.12065 0.2794)
			(end -0.12065 0.3048)
			(stroke
				(width 0.1)
				(type default)
			)
			(layer "F.Fab")
		)
		(fp_line
			(start 0.67945 0.3048)
			(end 0.120396 0.3048)
			(stroke
				(width 0.1)
				(type default)
			)
			(layer "F.Fab")
		)
		(fp_line
			(start 0.120396 0.3048)
			(end 0.120396 0.2794)
			(stroke
				(width 0.1)
				(type default)
			)
			(layer "F.Fab")
		)
		(fp_line
			(start -0.12065 0.3048)
			(end -0.67945 0.3048)
			(stroke
				(width 0.1)
				(type default)
			)
			(layer "F.Fab")
		)
		(fp_line
			(start -0.67945 0.3048)
			(end -0.67945 -0.305054)
			(stroke
				(width 0.1)
				(type default)
			)
			(layer "F.Fab")
		)
		(pad "1" smd circle
			(at -0.40005 0 90)
			(size 0 0)
			(layers "F.Cu" "F.Mask" "F.Paste")
			(net "P3V3_SSD6_SS")
		)
		(pad "2" smd circle
			(at 0.40005 0 90)
			(size 0 0)
			(layers "F.Cu" "F.Mask" "F.Paste")
			(net "GND")
		)
	)
	(footprint ""
		(layer "F.Cu")
		(at 487.0577 -548.246554 180)
		(property "Reference" "SCREW_SSD3_1"
			(at -5.207 -1.402334 0)
			(unlocked yes)
			(layer "B.SilkS")
			(effects
				(font
					(size 0.7874 0.5842)
					(thickness 0.1524)
				)
				(justify mirror)
			)
		)
		(property "Value" ""
			(at 0 0 180)
			(layer "F.Fab")
			(effects
				(font
					(size 1.27 1.27)
				)
			)
		)
		(duplicate_pad_numbers_are_jumpers no)
		(pad "1" thru_hole circle
			(at 0 0 180)
			(size 0.4572 0.4572)
			(drill 0.2032)
			(layers "*.Cu" "*.Mask")
			(remove_unused_layers no)
			(net "Net_9138")
			(clearance 0.127)
			(thermal_gap 0.127)
			(padstack
				(mode front_inner_back)
				(layer "Inner"
					(shape circle)
					(size 0.4572 0.4572)
					(clearance 0.127)
				)
				(layer "B.Cu"
					(shape circle)
					(size 0.508 0.508)
					(clearance 0.1016)
				)
			)
		)
	)
	(footprint ""
		(layer "F.Cu")
		(at 37.004752 -140.85697 180)
		(property "Reference" "R33"
			(at 0 0 180)
			(layer "F.SilkS")
			(hide yes)
			(effects
				(font
					(size 1.27 1.27)
				)
			)
		)
		(property "Value" ""
			(at 0 0 180)
			(layer "F.Fab")
			(effects
				(font
					(size 1.27 1.27)
				)
			)
		)
		(duplicate_pad_numbers_are_jumpers no)
		(fp_line
			(start 0.7874 0.4064)
			(end -0.7874 0.4064)
			(stroke
				(width 0.1524)
				(type default)
			)
			(layer "F.SilkS")
		)
		(fp_line
			(start 0.7874 -0.4064)
			(end 0.7874 0.4064)
			(stroke
				(width 0.1524)
				(type default)
			)
			(layer "F.SilkS")
		)
		(fp_line
			(start -0.7874 0.4064)
			(end -0.7874 -0.4064)
			(stroke
				(width 0.1524)
				(type default)
			)
			(layer "F.SilkS")
		)
		(fp_line
			(start -0.7874 -0.4064)
			(end 0.7874 -0.4064)
			(stroke
				(width 0.1524)
				(type default)
			)
			(layer "F.SilkS")
		)
		(fp_line
			(start 0.67945 0.3048)
			(end 0.120396 0.3048)
			(stroke
				(width 0.1)
				(type default)
			)
			(layer "F.Fab")
		)
		(fp_line
			(start 0.67945 -0.3048)
			(end 0.67945 0.3048)
			(stroke
				(width 0.1)
				(type default)
			)
			(layer "F.Fab")
		)
		(fp_line
			(start 0.12065 -0.2794)
			(end 0.12065 -0.3048)
			(stroke
				(width 0.1)
				(type default)
			)
			(layer "F.Fab")
		)
		(fp_line
			(start 0.12065 -0.3048)
			(end 0.67945 -0.3048)
			(stroke
				(width 0.1)
				(type default)
			)
			(layer "F.Fab")
		)
		(fp_line
			(start 0.120396 0.3048)
			(end 0.120396 0.2794)
			(stroke
				(width 0.1)
				(type default)
			)
			(layer "F.Fab")
		)
		(fp_line
			(start 0.120396 0.2794)
			(end -0.12065 0.2794)
			(stroke
				(width 0.1)
				(type default)
			)
			(layer "F.Fab")
		)
		(fp_line
			(start -0.12065 0.3048)
			(end -0.67945 0.3048)
			(stroke
				(width 0.1)
				(type default)
			)
			(layer "F.Fab")
		)
		(fp_line
			(start -0.12065 0.2794)
			(end -0.12065 0.3048)
			(stroke
				(width 0.1)
				(type default)
			)
			(layer "F.Fab")
		)
		(fp_line
			(start -0.12065 -0.2794)
			(end 0.12065 -0.2794)
			(stroke
				(width 0.1)
				(type default)
			)
			(layer "F.Fab")
		)
		(fp_line
			(start -0.12065 -0.305054)
			(end -0.12065 -0.2794)
			(stroke
				(width 0.1)
				(type default)
			)
			(layer "F.Fab")
		)
		(fp_line
			(start -0.67945 0.3048)
			(end -0.67945 -0.305054)
			(stroke
				(width 0.1)
				(type default)
			)
			(layer "F.Fab")
		)
		(fp_line
			(start -0.67945 -0.305054)
			(end -0.12065 -0.305054)
			(stroke
				(width 0.1)
				(type default)
			)
			(layer "F.Fab")
		)
		(pad "1" smd circle
			(at -0.40005 0 180)
			(size 0 0)
			(layers "F.Cu" "F.Mask" "F.Paste")
			(net "NIC0_BIF2_N")
		)
		(pad "2" smd circle
			(at 0.40005 0 180)
			(size 0 0)
			(layers "F.Cu" "F.Mask" "F.Paste")
			(net "P3V3_AUX")
		)
	)
	(footprint ""
		(layer "F.Cu")
		(at 166.961058 -169.23385 180)
		(property "Reference" "C886"
			(at 0 0 180)
			(layer "F.SilkS")
			(hide yes)
			(effects
				(font
					(size 1.27 1.27)
				)
			)
		)
		(property "Value" ""
			(at 0 0 180)
			(layer "F.Fab")
			(effects
				(font
					(size 1.27 1.27)
				)
			)
		)
		(duplicate_pad_numbers_are_jumpers no)
		(fp_line
			(start 0.7874 0.4064)
			(end -0.7874 0.4064)
			(stroke
				(width 0.1524)
				(type default)
			)
			(layer "F.SilkS")
		)
		(fp_line
			(start 0.7874 -0.4064)
			(end 0.7874 0.4064)
			(stroke
				(width 0.1524)
				(type default)
			)
			(layer "F.SilkS")
		)
		(fp_line
			(start -0.7874 0.4064)
			(end -0.7874 -0.4064)
			(stroke
				(width 0.1524)
				(type default)
			)
			(layer "F.SilkS")
		)
		(fp_line
			(start -0.7874 -0.4064)
			(end 0.7874 -0.4064)
			(stroke
				(width 0.1524)
				(type default)
			)
			(layer "F.SilkS")
		)
		(fp_line
			(start 0.67945 0.3048)
			(end 0.120396 0.3048)
			(stroke
				(width 0.1)
				(type default)
			)
			(layer "F.Fab")
		)
		(fp_line
			(start 0.67945 -0.3048)
			(end 0.67945 0.3048)
			(stroke
				(width 0.1)
				(type default)
			)
			(layer "F.Fab")
		)
		(fp_line
			(start 0.12065 -0.2794)
			(end 0.12065 -0.3048)
			(stroke
				(width 0.1)
				(type default)
			)
			(layer "F.Fab")
		)
		(fp_line
			(start 0.12065 -0.3048)
			(end 0.67945 -0.3048)
			(stroke
				(width 0.1)
				(type default)
			)
			(layer "F.Fab")
		)
		(fp_line
			(start 0.120396 0.3048)
			(end 0.120396 0.2794)
			(stroke
				(width 0.1)
				(type default)
			)
			(layer "F.Fab")
		)
		(fp_line
			(start 0.120396 0.2794)
			(end -0.12065 0.2794)
			(stroke
				(width 0.1)
				(type default)
			)
			(layer "F.Fab")
		)
		(fp_line
			(start -0.12065 0.3048)
			(end -0.67945 0.3048)
			(stroke
				(width 0.1)
				(type default)
			)
			(layer "F.Fab")
		)
		(fp_line
			(start -0.12065 0.2794)
			(end -0.12065 0.3048)
			(stroke
				(width 0.1)
				(type default)
			)
			(layer "F.Fab")
		)
		(fp_line
			(start -0.12065 -0.2794)
			(end 0.12065 -0.2794)
			(stroke
				(width 0.1)
				(type default)
			)
			(layer "F.Fab")
		)
		(fp_line
			(start -0.12065 -0.305054)
			(end -0.12065 -0.2794)
			(stroke
				(width 0.1)
				(type default)
			)
			(layer "F.Fab")
		)
		(fp_line
			(start -0.67945 0.3048)
			(end -0.67945 -0.305054)
			(stroke
				(width 0.1)
				(type default)
			)
			(layer "F.Fab")
		)
		(fp_line
			(start -0.67945 -0.305054)
			(end -0.12065 -0.305054)
			(stroke
				(width 0.1)
				(type default)
			)
			(layer "F.Fab")
		)
		(pad "1" smd circle
			(at -0.40005 0 180)
			(size 0 0)
			(layers "F.Cu" "F.Mask" "F.Paste")
			(net "P3V3_AUX")
		)
		(pad "2" smd circle
			(at 0.40005 0 180)
			(size 0 0)
			(layers "F.Cu" "F.Mask" "F.Paste")
			(net "GND")
		)
	)
	(footprint ""
		(layer "F.Cu")
		(at 238.124746 -116.698268)
		(property "Reference" "PC637"
			(at 0 0 0)
			(layer "F.SilkS")
			(hide yes)
			(effects
				(font
					(size 1.27 1.27)
				)
			)
		)
		(property "Value" ""
			(at 0 0 0)
			(layer "F.Fab")
			(effects
				(font
					(size 1.27 1.27)
				)
			)
		)
		(duplicate_pad_numbers_are_jumpers no)
		(fp_line
			(start -0.7874 -0.4064)
			(end 0.7874 -0.4064)
			(stroke
				(width 0.1524)
				(type default)
			)
			(layer "F.SilkS")
		)
		(fp_line
			(start -0.7874 0.4064)
			(end -0.7874 -0.4064)
			(stroke
				(width 0.1524)
				(type default)
			)
			(layer "F.SilkS")
		)
		(fp_line
			(start 0.7874 -0.4064)
			(end 0.7874 0.4064)
			(stroke
				(width 0.1524)
				(type default)
			)
			(layer "F.SilkS")
		)
		(fp_line
			(start 0.7874 0.4064)
			(end -0.7874 0.4064)
			(stroke
				(width 0.1524)
				(type default)
			)
			(layer "F.SilkS")
		)
		(fp_line
			(start -0.67945 -0.305054)
			(end -0.12065 -0.305054)
			(stroke
				(width 0.1)
				(type default)
			)
			(layer "F.Fab")
		)
		(fp_line
			(start -0.67945 0.3048)
			(end -0.67945 -0.305054)
			(stroke
				(width 0.1)
				(type default)
			)
			(layer "F.Fab")
		)
		(fp_line
			(start -0.12065 -0.305054)
			(end -0.12065 -0.2794)
			(stroke
				(width 0.1)
				(type default)
			)
			(layer "F.Fab")
		)
		(fp_line
			(start -0.12065 -0.2794)
			(end 0.12065 -0.2794)
			(stroke
				(width 0.1)
				(type default)
			)
			(layer "F.Fab")
		)
		(fp_line
			(start -0.12065 0.2794)
			(end -0.12065 0.3048)
			(stroke
				(width 0.1)
				(type default)
			)
			(layer "F.Fab")
		)
		(fp_line
			(start -0.12065 0.3048)
			(end -0.67945 0.3048)
			(stroke
				(width 0.1)
				(type default)
			)
			(layer "F.Fab")
		)
		(fp_line
			(start 0.120396 0.2794)
			(end -0.12065 0.2794)
			(stroke
				(width 0.1)
				(type default)
			)
			(layer "F.Fab")
		)
		(fp_line
			(start 0.120396 0.3048)
			(end 0.120396 0.2794)
			(stroke
				(width 0.1)
				(type default)
			)
			(layer "F.Fab")
		)
		(fp_line
			(start 0.12065 -0.3048)
			(end 0.67945 -0.3048)
			(stroke
				(width 0.1)
				(type default)
			)
			(layer "F.Fab")
		)
		(fp_line
			(start 0.12065 -0.2794)
			(end 0.12065 -0.3048)
			(stroke
				(width 0.1)
				(type default)
			)
			(layer "F.Fab")
		)
		(fp_line
			(start 0.67945 -0.3048)
			(end 0.67945 0.3048)
			(stroke
				(width 0.1)
				(type default)
			)
			(layer "F.Fab")
		)
		(fp_line
			(start 0.67945 0.3048)
			(end 0.120396 0.3048)
			(stroke
				(width 0.1)
				(type default)
			)
			(layer "F.Fab")
		)
		(pad "1" smd circle
			(at -0.40005 0)
			(size 0 0)
			(layers "F.Cu" "F.Mask" "F.Paste")
			(net "P12V_NIC3_CO_ISET_R")
		)
		(pad "2" smd circle
			(at 0.40005 0)
			(size 0 0)
			(layers "F.Cu" "F.Mask" "F.Paste")
			(net "GND")
		)
	)
	(footprint ""
		(layer "F.Cu")
		(at 375.690384 -250.070874 -90)
		(property "Reference" "R1410"
			(at 0 0 270)
			(layer "F.SilkS")
			(hide yes)
			(effects
				(font
					(size 1.27 1.27)
				)
			)
		)
		(property "Value" ""
			(at 0 0 270)
			(layer "F.Fab")
			(effects
				(font
					(size 1.27 1.27)
				)
			)
		)
		(duplicate_pad_numbers_are_jumpers no)
		(fp_line
			(start -0.7874 0.4064)
			(end -0.7874 -0.4064)
			(stroke
				(width 0.1524)
				(type default)
			)
			(layer "F.SilkS")
		)
		(fp_line
			(start 0.7874 0.4064)
			(end -0.7874 0.4064)
			(stroke
				(width 0.1524)
				(type default)
			)
			(layer "F.SilkS")
		)
		(fp_line
			(start -0.7874 -0.4064)
			(end 0.7874 -0.4064)
			(stroke
				(width 0.1524)
				(type default)
			)
			(layer "F.SilkS")
		)
		(fp_line
			(start 0.7874 -0.4064)
			(end 0.7874 0.4064)
			(stroke
				(width 0.1524)
				(type default)
			)
			(layer "F.SilkS")
		)
		(fp_line
			(start -0.67945 0.3048)
			(end -0.67945 -0.305054)
			(stroke
				(width 0.1)
				(type default)
			)
			(layer "F.Fab")
		)
		(fp_line
			(start -0.12065 0.3048)
			(end -0.67945 0.3048)
			(stroke
				(width 0.1)
				(type default)
			)
			(layer "F.Fab")
		)
		(fp_line
			(start 0.120396 0.3048)
			(end 0.120396 0.2794)
			(stroke
				(width 0.1)
				(type default)
			)
			(layer "F.Fab")
		)
		(fp_line
			(start 0.67945 0.3048)
			(end 0.120396 0.3048)
			(stroke
				(width 0.1)
				(type default)
			)
			(layer "F.Fab")
		)
		(fp_line
			(start -0.12065 0.2794)
			(end -0.12065 0.3048)
			(stroke
				(width 0.1)
				(type default)
			)
			(layer "F.Fab")
		)
		(fp_line
			(start 0.120396 0.2794)
			(end -0.12065 0.2794)
			(stroke
				(width 0.1)
				(type default)
			)
			(layer "F.Fab")
		)
		(fp_line
			(start -0.12065 -0.2794)
			(end 0.12065 -0.2794)
			(stroke
				(width 0.1)
				(type default)
			)
			(layer "F.Fab")
		)
		(fp_line
			(start 0.12065 -0.2794)
			(end 0.12065 -0.3048)
			(stroke
				(width 0.1)
				(type default)
			)
			(layer "F.Fab")
		)
		(fp_line
			(start 0.12065 -0.3048)
			(end 0.67945 -0.3048)
			(stroke
				(width 0.1)
				(type default)
			)
			(layer "F.Fab")
		)
		(fp_line
			(start 0.67945 -0.3048)
			(end 0.67945 0.3048)
			(stroke
				(width 0.1)
				(type default)
			)
			(layer "F.Fab")
		)
		(fp_line
			(start -0.67945 -0.305054)
			(end -0.12065 -0.305054)
			(stroke
				(width 0.1)
				(type default)
			)
			(layer "F.Fab")
		)
		(fp_line
			(start -0.12065 -0.305054)
			(end -0.12065 -0.2794)
			(stroke
				(width 0.1)
				(type default)
			)
			(layer "F.Fab")
		)
		(pad "1" smd circle
			(at -0.40005 0 270)
			(size 0 0)
			(layers "F.Cu" "F.Mask" "F.Paste")
			(net "PEX3_MODE_SEL5")
		)
		(pad "2" smd circle
			(at 0.40005 0 270)
			(size 0 0)
			(layers "F.Cu" "F.Mask" "F.Paste")
			(net "P1V8_PEX")
		)
	)
	(footprint ""
		(layer "F.Cu")
		(at 433.403248 -59.571636 90)
		(property "Reference" "PR285"
			(at 0 0 90)
			(layer "F.SilkS")
			(hide yes)
			(effects
				(font
					(size 1.27 1.27)
				)
			)
		)
		(property "Value" ""
			(at 0 0 90)
			(layer "F.Fab")
			(effects
				(font
					(size 1.27 1.27)
				)
			)
		)
		(duplicate_pad_numbers_are_jumpers no)
		(fp_line
			(start 0.7874 -0.4064)
			(end 0.7874 0.4064)
			(stroke
				(width 0.1524)
				(type default)
			)
			(layer "F.SilkS")
		)
		(fp_line
			(start -0.7874 -0.4064)
			(end 0.7874 -0.4064)
			(stroke
				(width 0.1524)
				(type default)
			)
			(layer "F.SilkS")
		)
		(fp_line
			(start 0.7874 0.4064)
			(end -0.7874 0.4064)
			(stroke
				(width 0.1524)
				(type default)
			)
			(layer "F.SilkS")
		)
		(fp_line
			(start -0.7874 0.4064)
			(end -0.7874 -0.4064)
			(stroke
				(width 0.1524)
				(type default)
			)
			(layer "F.SilkS")
		)
		(fp_line
			(start -0.12065 -0.305054)
			(end -0.12065 -0.2794)
			(stroke
				(width 0.1)
				(type default)
			)
			(layer "F.Fab")
		)
		(fp_line
			(start -0.67945 -0.305054)
			(end -0.12065 -0.305054)
			(stroke
				(width 0.1)
				(type default)
			)
			(layer "F.Fab")
		)
		(fp_line
			(start 0.67945 -0.3048)
			(end 0.67945 0.3048)
			(stroke
				(width 0.1)
				(type default)
			)
			(layer "F.Fab")
		)
		(fp_line
			(start 0.12065 -0.3048)
			(end 0.67945 -0.3048)
			(stroke
				(width 0.1)
				(type default)
			)
			(layer "F.Fab")
		)
		(fp_line
			(start 0.12065 -0.2794)
			(end 0.12065 -0.3048)
			(stroke
				(width 0.1)
				(type default)
			)
			(layer "F.Fab")
		)
		(fp_line
			(start -0.12065 -0.2794)
			(end 0.12065 -0.2794)
			(stroke
				(width 0.1)
				(type default)
			)
			(layer "F.Fab")
		)
		(fp_line
			(start 0.120396 0.2794)
			(end -0.12065 0.2794)
			(stroke
				(width 0.1)
				(type default)
			)
			(layer "F.Fab")
		)
		(fp_line
			(start -0.12065 0.2794)
			(end -0.12065 0.3048)
			(stroke
				(width 0.1)
				(type default)
			)
			(layer "F.Fab")
		)
		(fp_line
			(start 0.67945 0.3048)
			(end 0.120396 0.3048)
			(stroke
				(width 0.1)
				(type default)
			)
			(layer "F.Fab")
		)
		(fp_line
			(start 0.120396 0.3048)
			(end 0.120396 0.2794)
			(stroke
				(width 0.1)
				(type default)
			)
			(layer "F.Fab")
		)
		(fp_line
			(start -0.12065 0.3048)
			(end -0.67945 0.3048)
			(stroke
				(width 0.1)
				(type default)
			)
			(layer "F.Fab")
		)
		(fp_line
			(start -0.67945 0.3048)
			(end -0.67945 -0.305054)
			(stroke
				(width 0.1)
				(type default)
			)
			(layer "F.Fab")
		)
		(pad "1" smd circle
			(at -0.40005 0 90)
			(size 0 0)
			(layers "F.Cu" "F.Mask" "F.Paste")
			(net "P3V3_SSD15_OCP")
		)
		(pad "2" smd circle
			(at 0.40005 0 90)
			(size 0 0)
			(layers "F.Cu" "F.Mask" "F.Paste")
			(net "GND")
		)
	)
	(footprint ""
		(layer "F.Cu")
		(at 410.092652 -158.080202 90)
		(property "Reference" "R3310"
			(at 0 0 90)
			(layer "F.SilkS")
			(hide yes)
			(effects
				(font
					(size 1.27 1.27)
				)
			)
		)
		(property "Value" ""
			(at 0 0 90)
			(layer "F.Fab")
			(effects
				(font
					(size 1.27 1.27)
				)
			)
		)
		(duplicate_pad_numbers_are_jumpers no)
		(fp_line
			(start 0.7874 -0.4064)
			(end 0.7874 0.4064)
			(stroke
				(width 0.1524)
				(type default)
			)
			(layer "F.SilkS")
		)
		(fp_line
			(start -0.7874 -0.4064)
			(end 0.7874 -0.4064)
			(stroke
				(width 0.1524)
				(type default)
			)
			(layer "F.SilkS")
		)
		(fp_line
			(start 0.7874 0.4064)
			(end -0.7874 0.4064)
			(stroke
				(width 0.1524)
				(type default)
			)
			(layer "F.SilkS")
		)
		(fp_line
			(start -0.7874 0.4064)
			(end -0.7874 -0.4064)
			(stroke
				(width 0.1524)
				(type default)
			)
			(layer "F.SilkS")
		)
		(fp_line
			(start -0.12065 -0.305054)
			(end -0.12065 -0.2794)
			(stroke
				(width 0.1)
				(type default)
			)
			(layer "F.Fab")
		)
		(fp_line
			(start -0.67945 -0.305054)
			(end -0.12065 -0.305054)
			(stroke
				(width 0.1)
				(type default)
			)
			(layer "F.Fab")
		)
		(fp_line
			(start 0.67945 -0.3048)
			(end 0.67945 0.3048)
			(stroke
				(width 0.1)
				(type default)
			)
			(layer "F.Fab")
		)
		(fp_line
			(start 0.12065 -0.3048)
			(end 0.67945 -0.3048)
			(stroke
				(width 0.1)
				(type default)
			)
			(layer "F.Fab")
		)
		(fp_line
			(start 0.12065 -0.2794)
			(end 0.12065 -0.3048)
			(stroke
				(width 0.1)
				(type default)
			)
			(layer "F.Fab")
		)
		(fp_line
			(start -0.12065 -0.2794)
			(end 0.12065 -0.2794)
			(stroke
				(width 0.1)
				(type default)
			)
			(layer "F.Fab")
		)
		(fp_line
			(start 0.120396 0.2794)
			(end -0.12065 0.2794)
			(stroke
				(width 0.1)
				(type default)
			)
			(layer "F.Fab")
		)
		(fp_line
			(start -0.12065 0.2794)
			(end -0.12065 0.3048)
			(stroke
				(width 0.1)
				(type default)
			)
			(layer "F.Fab")
		)
		(fp_line
			(start 0.67945 0.3048)
			(end 0.120396 0.3048)
			(stroke
				(width 0.1)
				(type default)
			)
			(layer "F.Fab")
		)
		(fp_line
			(start 0.120396 0.3048)
			(end 0.120396 0.2794)
			(stroke
				(width 0.1)
				(type default)
			)
			(layer "F.Fab")
		)
		(fp_line
			(start -0.12065 0.3048)
			(end -0.67945 0.3048)
			(stroke
				(width 0.1)
				(type default)
			)
			(layer "F.Fab")
		)
		(fp_line
			(start -0.67945 0.3048)
			(end -0.67945 -0.305054)
			(stroke
				(width 0.1)
				(type default)
			)
			(layer "F.Fab")
		)
		(pad "1" smd circle
			(at -0.40005 0 90)
			(size 0 0)
			(layers "F.Cu" "F.Mask" "F.Paste")
			(net "FM_SYS_THROTTLE_R")
		)
		(pad "2" smd circle
			(at 0.40005 0 90)
			(size 0 0)
			(layers "F.Cu" "F.Mask" "F.Paste")
			(net "FM_SYS_THROTTLE_NIC6")
		)
	)
	(footprint ""
		(layer "F.Cu")
		(at 118.054628 -356.244906 90)
		(property "Reference" "C346"
			(at 0 0 90)
			(layer "F.SilkS")
			(hide yes)
			(effects
				(font
					(size 1.27 1.27)
				)
			)
		)
		(property "Value" ""
			(at 0 0 90)
			(layer "F.Fab")
			(effects
				(font
					(size 1.27 1.27)
				)
			)
		)
		(duplicate_pad_numbers_are_jumpers no)
		(fp_line
			(start 0.299974 -0.150114)
			(end 0.299974 0.150114)
			(stroke
				(width 0.1)
				(type default)
			)
			(layer "F.Fab")
		)
		(fp_line
			(start -0.299974 -0.150114)
			(end 0.299974 -0.150114)
			(stroke
				(width 0.1)
				(type default)
			)
			(layer "F.Fab")
		)
		(fp_line
			(start 0.299974 0.150114)
			(end -0.299974 0.150114)
			(stroke
				(width 0.1)
				(type default)
			)
			(layer "F.Fab")
		)
		(fp_line
			(start -0.299974 0.150114)
			(end -0.299974 -0.150114)
			(stroke
				(width 0.1)
				(type default)
			)
			(layer "F.Fab")
		)
		(pad "1" smd rect
			(at -0.2667 0 90)
			(size 0.3048 0.381)
			(layers "F.Cu" "F.Mask" "F.Paste")
			(net "P5E_PEX1_STN6_TX_DP<108>")
		)
		(pad "2" smd rect
			(at 0.2667 0 90)
			(size 0.3048 0.381)
			(layers "F.Cu" "F.Mask" "F.Paste")
			(net "P5E_PEX1_STN6_TX_C_DP<108>")
		)
	)
	(footprint ""
		(layer "F.Cu")
		(at 393.8397 -350.098614 90)
		(property "Reference" "C741"
			(at 0 0 90)
			(layer "F.SilkS")
			(hide yes)
			(effects
				(font
					(size 1.27 1.27)
				)
			)
		)
		(property "Value" ""
			(at 0 0 90)
			(layer "F.Fab")
			(effects
				(font
					(size 1.27 1.27)
				)
			)
		)
		(duplicate_pad_numbers_are_jumpers no)
		(fp_line
			(start 0.299974 -0.150114)
			(end 0.299974 0.150114)
			(stroke
				(width 0.1)
				(type default)
			)
			(layer "F.Fab")
		)
		(fp_line
			(start -0.299974 -0.150114)
			(end 0.299974 -0.150114)
			(stroke
				(width 0.1)
				(type default)
			)
			(layer "F.Fab")
		)
		(fp_line
			(start 0.299974 0.150114)
			(end -0.299974 0.150114)
			(stroke
				(width 0.1)
				(type default)
			)
			(layer "F.Fab")
		)
		(fp_line
			(start -0.299974 0.150114)
			(end -0.299974 -0.150114)
			(stroke
				(width 0.1)
				(type default)
			)
			(layer "F.Fab")
		)
		(pad "1" smd rect
			(at -0.2667 0 90)
			(size 0.3048 0.381)
			(layers "F.Cu" "F.Mask" "F.Paste")
			(net "P5E_PEX3_STN5_TX_DN<90>")
		)
		(pad "2" smd rect
			(at 0.2667 0 90)
			(size 0.3048 0.381)
			(layers "F.Cu" "F.Mask" "F.Paste")
			(net "P5E_PEX3_STN5_TX_C_DN<90>")
		)
	)
	(footprint ""
		(layer "F.Cu")
		(at 271.480534 -100.203254)
		(property "Reference" "C486"
			(at 0 0 0)
			(layer "F.SilkS")
			(hide yes)
			(effects
				(font
					(size 1.27 1.27)
				)
			)
		)
		(property "Value" ""
			(at 0 0 0)
			(layer "F.Fab")
			(effects
				(font
					(size 1.27 1.27)
				)
			)
		)
		(duplicate_pad_numbers_are_jumpers no)
		(fp_line
			(start -0.299974 -0.150114)
			(end 0.299974 -0.150114)
			(stroke
				(width 0.1)
				(type default)
			)
			(layer "F.Fab")
		)
		(fp_line
			(start -0.299974 0.150114)
			(end -0.299974 -0.150114)
			(stroke
				(width 0.1)
				(type default)
			)
			(layer "F.Fab")
		)
		(fp_line
			(start 0.299974 -0.150114)
			(end 0.299974 0.150114)
			(stroke
				(width 0.1)
				(type default)
			)
			(layer "F.Fab")
		)
		(fp_line
			(start 0.299974 0.150114)
			(end -0.299974 0.150114)
			(stroke
				(width 0.1)
				(type default)
			)
			(layer "F.Fab")
		)
		(pad "1" smd rect
			(at -0.2667 0)
			(size 0.3048 0.381)
			(layers "F.Cu" "F.Mask" "F.Paste")
			(net "P5E_PEX2_STN1_TX_DN<16>")
		)
		(pad "2" smd rect
			(at 0.2667 0)
			(size 0.3048 0.381)
			(layers "F.Cu" "F.Mask" "F.Paste")
			(net "P5E_PEX2_STN1_TX_C_DN<16>")
		)
	)
	(footprint ""
		(layer "F.Cu")
		(at 123.71324 -135.058404 180)
		(property "Reference" "C2857"
			(at 0 0 180)
			(layer "F.SilkS")
			(hide yes)
			(effects
				(font
					(size 1.27 1.27)
				)
			)
		)
		(property "Value" ""
			(at 0 0 180)
			(layer "F.Fab")
			(effects
				(font
					(size 1.27 1.27)
				)
			)
		)
		(duplicate_pad_numbers_are_jumpers no)
		(fp_line
			(start 0.7874 0.4064)
			(end -0.7874 0.4064)
			(stroke
				(width 0.1524)
				(type default)
			)
			(layer "F.SilkS")
		)
		(fp_line
			(start 0.7874 -0.4064)
			(end 0.7874 0.4064)
			(stroke
				(width 0.1524)
				(type default)
			)
			(layer "F.SilkS")
		)
		(fp_line
			(start -0.7874 0.4064)
			(end -0.7874 -0.4064)
			(stroke
				(width 0.1524)
				(type default)
			)
			(layer "F.SilkS")
		)
		(fp_line
			(start -0.7874 -0.4064)
			(end 0.7874 -0.4064)
			(stroke
				(width 0.1524)
				(type default)
			)
			(layer "F.SilkS")
		)
		(fp_line
			(start 0.67945 0.3048)
			(end 0.120396 0.3048)
			(stroke
				(width 0.1)
				(type default)
			)
			(layer "F.Fab")
		)
		(fp_line
			(start 0.67945 -0.3048)
			(end 0.67945 0.3048)
			(stroke
				(width 0.1)
				(type default)
			)
			(layer "F.Fab")
		)
		(fp_line
			(start 0.12065 -0.2794)
			(end 0.12065 -0.3048)
			(stroke
				(width 0.1)
				(type default)
			)
			(layer "F.Fab")
		)
		(fp_line
			(start 0.12065 -0.3048)
			(end 0.67945 -0.3048)
			(stroke
				(width 0.1)
				(type default)
			)
			(layer "F.Fab")
		)
		(fp_line
			(start 0.120396 0.3048)
			(end 0.120396 0.2794)
			(stroke
				(width 0.1)
				(type default)
			)
			(layer "F.Fab")
		)
		(fp_line
			(start 0.120396 0.2794)
			(end -0.12065 0.2794)
			(stroke
				(width 0.1)
				(type default)
			)
			(layer "F.Fab")
		)
		(fp_line
			(start -0.12065 0.3048)
			(end -0.67945 0.3048)
			(stroke
				(width 0.1)
				(type default)
			)
			(layer "F.Fab")
		)
		(fp_line
			(start -0.12065 0.2794)
			(end -0.12065 0.3048)
			(stroke
				(width 0.1)
				(type default)
			)
			(layer "F.Fab")
		)
		(fp_line
			(start -0.12065 -0.2794)
			(end 0.12065 -0.2794)
			(stroke
				(width 0.1)
				(type default)
			)
			(layer "F.Fab")
		)
		(fp_line
			(start -0.12065 -0.305054)
			(end -0.12065 -0.2794)
			(stroke
				(width 0.1)
				(type default)
			)
			(layer "F.Fab")
		)
		(fp_line
			(start -0.67945 0.3048)
			(end -0.67945 -0.305054)
			(stroke
				(width 0.1)
				(type default)
			)
			(layer "F.Fab")
		)
		(fp_line
			(start -0.67945 -0.305054)
			(end -0.12065 -0.305054)
			(stroke
				(width 0.1)
				(type default)
			)
			(layer "F.Fab")
		)
		(pad "1" smd circle
			(at -0.40005 0 180)
			(size 0 0)
			(layers "F.Cu" "F.Mask" "F.Paste")
			(net "P12V_NIC2_EN_R")
		)
		(pad "2" smd circle
			(at 0.40005 0 180)
			(size 0 0)
			(layers "F.Cu" "F.Mask" "F.Paste")
			(net "GND")
		)
	)
	(footprint ""
		(layer "F.Cu")
		(at 230.664258 -103.328216 -90)
		(property "Reference" "PD8"
			(at 4.217416 -2.712212 90)
			(unlocked yes)
			(layer "F.SilkS")
			(effects
				(font
					(size 0.7874 0.5842)
					(thickness 0.1524)
				)
				(justify left)
			)
		)
		(property "Value" ""
			(at 0 0 270)
			(layer "F.Fab")
			(effects
				(font
					(size 1.27 1.27)
				)
			)
		)
		(duplicate_pad_numbers_are_jumpers no)
		(fp_line
			(start -3.656584 1.970024)
			(end 4.240784 1.970024)
			(stroke
				(width 0.1524)
				(type default)
			)
			(layer "F.SilkS")
		)
		(fp_line
			(start 4.240784 1.970024)
			(end 4.240784 -1.970024)
			(stroke
				(width 0.1524)
				(type default)
			)
			(layer "F.SilkS")
		)
		(fp_line
			(start -3.656584 -1.970024)
			(end -3.656584 1.970024)
			(stroke
				(width 0.1524)
				(type default)
			)
			(layer "F.SilkS")
		)
		(fp_line
			(start 4.240784 -1.970024)
			(end -3.656584 -1.970024)
			(stroke
				(width 0.1524)
				(type default)
			)
			(layer "F.SilkS")
		)
		(fp_poly
			(pts
				(xy 3.580384 1.970024) (xy 3.580384 -1.970024) (xy 4.240784 -1.970024) (xy 4.240784 1.970024)
			)
			(stroke
				(width 0)
				(type default)
			)
			(fill yes)
			(layer "F.SilkS")
		)
		(fp_line
			(start -2.3749 1.970024)
			(end 2.3749 1.970024)
			(stroke
				(width 0.1)
				(type default)
			)
			(layer "F.Fab")
		)
		(fp_line
			(start 2.3749 1.970024)
			(end 2.3749 -1.970024)
			(stroke
				(width 0.1)
				(type default)
			)
			(layer "F.Fab")
		)
		(fp_line
			(start -2.3749 -1.970024)
			(end -2.3749 1.970024)
			(stroke
				(width 0.1)
				(type default)
			)
			(layer "F.Fab")
		)
		(fp_line
			(start 2.3749 -1.970024)
			(end -2.3749 -1.970024)
			(stroke
				(width 0.1)
				(type default)
			)
			(layer "F.Fab")
		)
		(fp_text user "+"
			(at -4.9784 -0.23495 270)
			(unlocked yes)
			(layer "F.Fab")
			(effects
				(font
					(size 1.905 1.4224)
					(thickness 0.1524)
				)
				(justify left)
			)
		)
		(fp_text user "-"
			(at 4.1656 -0.23495 270)
			(unlocked yes)
			(layer "F.Fab")
			(effects
				(font
					(size 1.905 1.4224)
					(thickness 0.1524)
				)
				(justify left)
			)
		)
		(pad "A" smd rect
			(at -2.450084 0 270)
			(size 2.159 2.2606)
			(layers "F.Cu" "F.Mask" "F.Paste")
			(net "GND")
		)
		(pad "C" smd rect
			(at 2.450084 0 270)
			(size 2.159 2.2606)
			(layers "F.Cu" "F.Mask" "F.Paste")
			(net "P12V_AUX")
		)
	)
	(footprint ""
		(layer "F.Cu")
		(at 351.455228 -53.468524 90)
		(property "Reference" "PC581"
			(at 0 0 90)
			(layer "F.SilkS")
			(hide yes)
			(effects
				(font
					(size 1.27 1.27)
				)
			)
		)
		(property "Value" ""
			(at 0 0 90)
			(layer "F.Fab")
			(effects
				(font
					(size 1.27 1.27)
				)
			)
		)
		(duplicate_pad_numbers_are_jumpers no)
		(fp_line
			(start 1.524 -0.762)
			(end 1.524 0.762)
			(stroke
				(width 0.1524)
				(type default)
			)
			(layer "F.SilkS")
		)
		(fp_line
			(start -1.524 -0.762)
			(end 1.524 -0.762)
			(stroke
				(width 0.1524)
				(type default)
			)
			(layer "F.SilkS")
		)
		(fp_line
			(start 1.524 0.762)
			(end -1.524 0.762)
			(stroke
				(width 0.1524)
				(type default)
			)
			(layer "F.SilkS")
		)
		(fp_line
			(start -1.524 0.762)
			(end -1.524 -0.762)
			(stroke
				(width 0.1524)
				(type default)
			)
			(layer "F.SilkS")
		)
		(fp_line
			(start 1.1049 -0.724916)
			(end -1.1049 -0.724916)
			(stroke
				(width 0.1)
				(type default)
			)
			(layer "F.Fab")
		)
		(fp_line
			(start -1.1049 -0.724916)
			(end -1.1049 0.724916)
			(stroke
				(width 0.1)
				(type default)
			)
			(layer "F.Fab")
		)
		(fp_line
			(start 1.1049 0.724916)
			(end 1.1049 -0.724916)
			(stroke
				(width 0.1)
				(type default)
			)
			(layer "F.Fab")
		)
		(fp_line
			(start -1.1049 0.724916)
			(end 1.1049 0.724916)
			(stroke
				(width 0.1)
				(type default)
			)
			(layer "F.Fab")
		)
		(pad "1" smd rect
			(at -0.889 0 270)
			(size 1.016 1.27)
			(layers "F.Cu" "F.Mask" "F.Paste")
			(net "GND")
		)
		(pad "2" smd rect
			(at 0.889 0 270)
			(size 1.016 1.27)
			(layers "F.Cu" "F.Mask" "F.Paste")
			(net "P3V3_AUX")
		)
	)
	(footprint ""
		(layer "F.Cu")
		(at 328.92238 -44.341542 90)
		(property "Reference" "R635"
			(at 0 0 90)
			(layer "F.SilkS")
			(hide yes)
			(effects
				(font
					(size 1.27 1.27)
				)
			)
		)
		(property "Value" ""
			(at 0 0 90)
			(layer "F.Fab")
			(effects
				(font
					(size 1.27 1.27)
				)
			)
		)
		(duplicate_pad_numbers_are_jumpers no)
		(fp_line
			(start 0.7874 -0.4064)
			(end 0.7874 0.4064)
			(stroke
				(width 0.1524)
				(type default)
			)
			(layer "F.SilkS")
		)
		(fp_line
			(start -0.7874 -0.4064)
			(end 0.7874 -0.4064)
			(stroke
				(width 0.1524)
				(type default)
			)
			(layer "F.SilkS")
		)
		(fp_line
			(start 0.7874 0.4064)
			(end -0.7874 0.4064)
			(stroke
				(width 0.1524)
				(type default)
			)
			(layer "F.SilkS")
		)
		(fp_line
			(start -0.7874 0.4064)
			(end -0.7874 -0.4064)
			(stroke
				(width 0.1524)
				(type default)
			)
			(layer "F.SilkS")
		)
		(fp_line
			(start -0.12065 -0.305054)
			(end -0.12065 -0.2794)
			(stroke
				(width 0.1)
				(type default)
			)
			(layer "F.Fab")
		)
		(fp_line
			(start -0.67945 -0.305054)
			(end -0.12065 -0.305054)
			(stroke
				(width 0.1)
				(type default)
			)
			(layer "F.Fab")
		)
		(fp_line
			(start 0.67945 -0.3048)
			(end 0.67945 0.3048)
			(stroke
				(width 0.1)
				(type default)
			)
			(layer "F.Fab")
		)
		(fp_line
			(start 0.12065 -0.3048)
			(end 0.67945 -0.3048)
			(stroke
				(width 0.1)
				(type default)
			)
			(layer "F.Fab")
		)
		(fp_line
			(start 0.12065 -0.2794)
			(end 0.12065 -0.3048)
			(stroke
				(width 0.1)
				(type default)
			)
			(layer "F.Fab")
		)
		(fp_line
			(start -0.12065 -0.2794)
			(end 0.12065 -0.2794)
			(stroke
				(width 0.1)
				(type default)
			)
			(layer "F.Fab")
		)
		(fp_line
			(start 0.120396 0.2794)
			(end -0.12065 0.2794)
			(stroke
				(width 0.1)
				(type default)
			)
			(layer "F.Fab")
		)
		(fp_line
			(start -0.12065 0.2794)
			(end -0.12065 0.3048)
			(stroke
				(width 0.1)
				(type default)
			)
			(layer "F.Fab")
		)
		(fp_line
			(start 0.67945 0.3048)
			(end 0.120396 0.3048)
			(stroke
				(width 0.1)
				(type default)
			)
			(layer "F.Fab")
		)
		(fp_line
			(start 0.120396 0.3048)
			(end 0.120396 0.2794)
			(stroke
				(width 0.1)
				(type default)
			)
			(layer "F.Fab")
		)
		(fp_line
			(start -0.12065 0.3048)
			(end -0.67945 0.3048)
			(stroke
				(width 0.1)
				(type default)
			)
			(layer "F.Fab")
		)
		(fp_line
			(start -0.67945 0.3048)
			(end -0.67945 -0.305054)
			(stroke
				(width 0.1)
				(type default)
			)
			(layer "F.Fab")
		)
		(pad "1" smd circle
			(at -0.40005 0 90)
			(size 0 0)
			(layers "F.Cu" "F.Mask" "F.Paste")
			(net "P12V_SSD11")
		)
		(pad "2" smd circle
			(at 0.40005 0 90)
			(size 0 0)
			(layers "F.Cu" "F.Mask" "F.Paste")
			(net "P12V_SSD11_VIN_N")
		)
	)
	(footprint ""
		(layer "F.Cu")
		(at 175.749966 -295.89984)
		(property "Reference" "PEX1"
			(at -3.353562 35.593274 0)
			(unlocked yes)
			(layer "F.SilkS")
			(effects
				(font
					(size 2.032 1.524)
					(thickness 0.1524)
				)
				(justify left)
			)
		)
		(property "Value" ""
			(at 0 0 0)
			(layer "F.Fab")
			(effects
				(font
					(size 1.27 1.27)
				)
			)
		)
		(duplicate_pad_numbers_are_jumpers no)
		(fp_line
			(start -23.750016 -23.750016)
			(end -23.750016 23.750016)
			(stroke
				(width 0.1524)
				(type default)
			)
			(layer "F.SilkS")
		)
		(fp_line
			(start -23.750016 23.750016)
			(end 23.750016 23.750016)
			(stroke
				(width 0.1524)
				(type default)
			)
			(layer "F.SilkS")
		)
		(fp_line
			(start 23.750016 -23.750016)
			(end -23.750016 -23.750016)
			(stroke
				(width 0.1524)
				(type default)
			)
			(layer "F.SilkS")
		)
		(fp_line
			(start 23.750016 23.750016)
			(end 23.750016 -23.750016)
			(stroke
				(width 0.1524)
				(type default)
			)
			(layer "F.SilkS")
		)
		(fp_poly
			(pts
				(xy -21.850096 -23.750016) (xy -21.850096 -24.512016) (xy -24.512016 -24.512016) (xy -24.512016 -21.850096)
				(xy -23.750016 -21.850096) (xy -23.750016 -23.750016)
			)
			(stroke
				(width 0)
				(type default)
			)
			(fill yes)
			(layer "F.SilkS")
		)
		(fp_line
			(start -23.750016 -23.750016)
			(end -23.750016 23.750016)
			(stroke
				(width 0.1)
				(type default)
			)
			(layer "F.Fab")
		)
		(fp_line
			(start -23.750016 23.750016)
			(end 23.750016 23.750016)
			(stroke
				(width 0.1)
				(type default)
			)
			(layer "F.Fab")
		)
		(fp_line
			(start 23.750016 -23.750016)
			(end -23.750016 -23.750016)
			(stroke
				(width 0.1)
				(type default)
			)
			(layer "F.Fab")
		)
		(fp_line
			(start 23.750016 23.750016)
			(end 23.750016 -23.750016)
			(stroke
				(width 0.1)
				(type default)
			)
			(layer "F.Fab")
		)
		(fp_poly
			(pts
				(xy -21.850096 -23.750016) (xy -21.850096 -24.512016) (xy -24.512016 -24.512016) (xy -24.512016 -21.850096)
				(xy -23.750016 -21.850096) (xy -23.750016 -23.750016)
			)
			(stroke
				(width 0)
				(type default)
			)
			(fill yes)
			(layer "F.Fab")
		)
		(pad "A2" smd circle
			(at -21.850096 -22.800056)
			(size 0.4572 0.4572)
			(layers "F.Cu" "F.Mask" "F.Paste")
			(net "GND")
		)
		(pad "A3" smd circle
			(at -20.899882 -22.800056)
			(size 0.4572 0.4572)
			(layers "F.Cu" "F.Mask" "F.Paste")
			(net "P5E_PEX1_STN7_RX_DN<123>")
		)
		(pad "A4" smd circle
			(at -19.949922 -22.800056)
			(size 0.4572 0.4572)
			(layers "F.Cu" "F.Mask" "F.Paste")
			(net "GND")
		)
		(pad "A5" smd circle
			(at -18.999962 -22.800056)
			(size 0.4572 0.4572)
			(layers "F.Cu" "F.Mask" "F.Paste")
			(net "P5E_PEX1_STN7_RX_DN<125>")
		)
		(pad "A6" smd circle
			(at -18.050002 -22.800056)
			(size 0.4572 0.4572)
			(layers "F.Cu" "F.Mask" "F.Paste")
			(net "GND")
		)
		(pad "A7" smd circle
			(at -17.100042 -22.800056)
			(size 0.4572 0.4572)
			(layers "F.Cu" "F.Mask" "F.Paste")
			(net "P5E_PEX1_STN7_RX_DN<127>")
		)
		(pad "A8" smd circle
			(at -16.150082 -22.800056)
			(size 0.4572 0.4572)
			(layers "F.Cu" "F.Mask" "F.Paste")
			(net "GND")
		)
		(pad "A9" smd circle
			(at -15.200122 -22.800056)
			(size 0.4572 0.4572)
			(layers "F.Cu" "F.Mask" "F.Paste")
			(net "P5E_PEX1_STN6_RX_DN<110>")
		)
		(pad "A10" smd circle
			(at -14.249908 -22.800056)
			(size 0.4572 0.4572)
			(layers "F.Cu" "F.Mask" "F.Paste")
			(net "GND")
		)
		(pad "A11" smd circle
			(at -13.299948 -22.800056)
			(size 0.4572 0.4572)
			(layers "F.Cu" "F.Mask" "F.Paste")
			(net "P5E_PEX1_STN6_RX_DN<108>")
		)
		(pad "A12" smd circle
			(at -12.349988 -22.800056)
			(size 0.4572 0.4572)
			(layers "F.Cu" "F.Mask" "F.Paste")
			(net "GND")
		)
		(pad "A13" smd circle
			(at -11.400028 -22.800056)
			(size 0.4572 0.4572)
			(layers "F.Cu" "F.Mask" "F.Paste")
			(net "P5E_PEX1_STN6_RX_DN<106>")
		)
		(pad "A14" smd circle
			(at -10.450068 -22.800056)
			(size 0.4572 0.4572)
			(layers "F.Cu" "F.Mask" "F.Paste")
			(net "GND")
		)
		(pad "A15" smd circle
			(at -9.500108 -22.800056)
			(size 0.4572 0.4572)
			(layers "F.Cu" "F.Mask" "F.Paste")
			(net "P5E_PEX1_STN6_RX_DN<104>")
		)
		(pad "A16" smd circle
			(at -8.549894 -22.800056)
			(size 0.4572 0.4572)
			(layers "F.Cu" "F.Mask" "F.Paste")
			(net "GND")
		)
		(pad "A17" smd circle
			(at -7.599934 -22.800056)
			(size 0.4572 0.4572)
			(layers "F.Cu" "F.Mask" "F.Paste")
			(net "P5E_PEX1_STN6_RX_DN<102>")
		)
		(pad "A18" smd circle
			(at -6.649974 -22.800056)
			(size 0.4572 0.4572)
			(layers "F.Cu" "F.Mask" "F.Paste")
			(net "GND")
		)
		(pad "A19" smd circle
			(at -5.700014 -22.800056)
			(size 0.4572 0.4572)
			(layers "F.Cu" "F.Mask" "F.Paste")
			(net "P5E_PEX1_STN6_RX_DN<100>")
		)
		(pad "A20" smd circle
			(at -4.750054 -22.800056)
			(size 0.4572 0.4572)
			(layers "F.Cu" "F.Mask" "F.Paste")
			(net "GND")
		)
		(pad "A21" smd circle
			(at -3.800094 -22.800056)
			(size 0.4572 0.4572)
			(layers "F.Cu" "F.Mask" "F.Paste")
			(net "P5E_PEX1_STN6_RX_DN<98>")
		)
		(pad "A22" smd circle
			(at -2.84988 -22.800056)
			(size 0.4572 0.4572)
			(layers "F.Cu" "F.Mask" "F.Paste")
			(net "GND")
		)
		(pad "A23" smd circle
			(at -1.89992 -22.800056)
			(size 0.4572 0.4572)
			(layers "F.Cu" "F.Mask" "F.Paste")
			(net "P5E_PEX1_STN6_RX_DN<96>")
		)
		(pad "A24" smd circle
			(at -0.94996 -22.800056)
			(size 0.4572 0.4572)
			(layers "F.Cu" "F.Mask" "F.Paste")
			(net "GND")
		)
		(pad "A25" smd circle
			(at 0 -22.800056)
			(size 0.4572 0.4572)
			(layers "F.Cu" "F.Mask" "F.Paste")
			(net "P5E_PEX1_STN5_RX_DN<81>")
		)
		(pad "A26" smd circle
			(at 0.94996 -22.800056)
			(size 0.4572 0.4572)
			(layers "F.Cu" "F.Mask" "F.Paste")
			(net "GND")
		)
		(pad "A27" smd circle
			(at 1.89992 -22.800056)
			(size 0.4572 0.4572)
			(layers "F.Cu" "F.Mask" "F.Paste")
			(net "P5E_PEX1_STN5_RX_DN<83>")
		)
		(pad "A28" smd circle
			(at 2.84988 -22.800056)
			(size 0.4572 0.4572)
			(layers "F.Cu" "F.Mask" "F.Paste")
			(net "GND")
		)
		(pad "A29" smd circle
			(at 3.800094 -22.800056)
			(size 0.4572 0.4572)
			(layers "F.Cu" "F.Mask" "F.Paste")
			(net "P5E_PEX1_STN5_RX_DN<85>")
		)
		(pad "A30" smd circle
			(at 4.750054 -22.800056)
			(size 0.4572 0.4572)
			(layers "F.Cu" "F.Mask" "F.Paste")
			(net "GND")
		)
		(pad "A31" smd circle
			(at 5.700014 -22.800056)
			(size 0.4572 0.4572)
			(layers "F.Cu" "F.Mask" "F.Paste")
			(net "P5E_PEX1_STN5_RX_DN<87>")
		)
		(pad "A32" smd circle
			(at 6.649974 -22.800056)
			(size 0.4572 0.4572)
			(layers "F.Cu" "F.Mask" "F.Paste")
			(net "GND")
		)
		(pad "A33" smd circle
			(at 7.599934 -22.800056)
			(size 0.4572 0.4572)
			(layers "F.Cu" "F.Mask" "F.Paste")
			(net "P5E_PEX1_STN5_RX_DN<89>")
		)
		(pad "A34" smd circle
			(at 8.549894 -22.800056)
			(size 0.4572 0.4572)
			(layers "F.Cu" "F.Mask" "F.Paste")
			(net "GND")
		)
		(pad "A35" smd circle
			(at 9.500108 -22.800056)
			(size 0.4572 0.4572)
			(layers "F.Cu" "F.Mask" "F.Paste")
			(net "P5E_PEX1_STN5_RX_DN<91>")
		)
		(pad "A36" smd circle
			(at 10.450068 -22.800056)
			(size 0.4572 0.4572)
			(layers "F.Cu" "F.Mask" "F.Paste")
			(net "GND")
		)
		(pad "A37" smd circle
			(at 11.400028 -22.800056)
			(size 0.4572 0.4572)
			(layers "F.Cu" "F.Mask" "F.Paste")
			(net "P5E_PEX1_STN5_RX_DN<93>")
		)
		(pad "A38" smd circle
			(at 12.349988 -22.800056)
			(size 0.4572 0.4572)
			(layers "F.Cu" "F.Mask" "F.Paste")
			(net "GND")
		)
		(pad "A39" smd circle
			(at 13.299948 -22.800056)
			(size 0.4572 0.4572)
			(layers "F.Cu" "F.Mask" "F.Paste")
			(net "P5E_PEX1_STN5_RX_DN<95>")
		)
		(pad "A40" smd circle
			(at 14.249908 -22.800056)
			(size 0.4572 0.4572)
			(layers "F.Cu" "F.Mask" "F.Paste")
			(net "GND")
		)
		(pad "A41" smd circle
			(at 15.200122 -22.800056)
			(size 0.4572 0.4572)
			(layers "F.Cu" "F.Mask" "F.Paste")
			(net "P5E_PEX1_STN4_RX_DN<78>")
		)
		(pad "A42" smd circle
			(at 16.150082 -22.800056)
			(size 0.4572 0.4572)
			(layers "F.Cu" "F.Mask" "F.Paste")
			(net "GND")
		)
		(pad "A43" smd circle
			(at 17.100042 -22.800056)
			(size 0.4572 0.4572)
			(layers "F.Cu" "F.Mask" "F.Paste")
			(net "P5E_PEX1_STN4_RX_DN<76>")
		)
		(pad "A44" smd circle
			(at 18.050002 -22.800056)
			(size 0.4572 0.4572)
			(layers "F.Cu" "F.Mask" "F.Paste")
			(net "GND")
		)
		(pad "A45" smd circle
			(at 18.999962 -22.800056)
			(size 0.4572 0.4572)
			(layers "F.Cu" "F.Mask" "F.Paste")
			(net "P5E_PEX1_STN4_RX_DN<74>")
		)
		(pad "A46" smd circle
			(at 19.949922 -22.800056)
			(size 0.4572 0.4572)
			(layers "F.Cu" "F.Mask" "F.Paste")
			(net "GND")
		)
		(pad "A47" smd circle
			(at 20.899882 -22.800056)
			(size 0.4572 0.4572)
			(layers "F.Cu" "F.Mask" "F.Paste")
			(net "P5E_PEX1_STN4_RX_DN<72>")
		)
		(pad "A48" smd circle
			(at 21.850096 -22.800056)
			(size 0.4572 0.4572)
			(layers "F.Cu" "F.Mask" "F.Paste")
			(net "GND")
		)
		(pad "AA1" smd circle
			(at -22.800056 -3.800094)
			(size 0.4572 0.4572)
			(layers "F.Cu" "F.Mask" "F.Paste")
			(net "CLK_100M_PEX1_REF_R_DN")
		)
		(pad "AA2" smd circle
			(at -21.850096 -3.800094)
			(size 0.4572 0.4572)
			(layers "F.Cu" "F.Mask" "F.Paste")
			(net "CLK_100M_PEX1_REF_R_DP")
		)
		(pad "AA3" smd circle
			(at -20.899882 -3.800094)
			(size 0.4572 0.4572)
			(layers "F.Cu" "F.Mask" "F.Paste")
			(net "GND")
		)
		(pad "AA4" smd circle
			(at -19.949922 -3.800094)
			(size 0.4572 0.4572)
			(layers "F.Cu" "F.Mask" "F.Paste")
			(net "GND")
		)
		(pad "AA5" smd circle
			(at -18.999962 -3.800094)
			(size 0.4572 0.4572)
			(layers "F.Cu" "F.Mask" "F.Paste")
			(net "GND")
		)
		(pad "AA6" smd circle
			(at -18.050002 -3.800094)
			(size 0.4572 0.4572)
			(layers "F.Cu" "F.Mask" "F.Paste")
			(net "GND")
		)
		(pad "AA7" smd circle
			(at -17.100042 -3.800094)
			(size 0.4572 0.4572)
			(layers "F.Cu" "F.Mask" "F.Paste")
			(net "GND")
		)
		(pad "AA8" smd circle
			(at -16.150082 -3.800094)
			(size 0.4572 0.4572)
			(layers "F.Cu" "F.Mask" "F.Paste")
			(net "GND")
		)
		(pad "AA9" smd circle
			(at -15.200122 -3.800094)
			(size 0.4572 0.4572)
			(layers "F.Cu" "F.Mask" "F.Paste")
			(net "GND")
		)
		(pad "AA10" smd circle
			(at -14.249908 -3.800094)
			(size 0.4572 0.4572)
			(layers "F.Cu" "F.Mask" "F.Paste")
			(net "P1V8_VDDA_PEX1")
		)
		(pad "AA11" smd circle
			(at -13.299948 -3.800094)
			(size 0.4572 0.4572)
			(layers "F.Cu" "F.Mask" "F.Paste")
			(net "GND")
		)
		(pad "AA12" smd circle
			(at -12.349988 -3.800094)
			(size 0.4572 0.4572)
			(layers "F.Cu" "F.Mask" "F.Paste")
			(net "GND")
		)
		(pad "AA13" smd circle
			(at -11.400028 -3.800094)
			(size 0.4572 0.4572)
			(layers "F.Cu" "F.Mask" "F.Paste")
			(net "PCEPLL0_VDDA18_PEX1")
		)
		(pad "AA14" smd circle
			(at -10.450068 -3.800094)
			(size 0.4572 0.4572)
			(layers "F.Cu" "F.Mask" "F.Paste")
			(net "GND")
		)
		(pad "AA15" smd circle
			(at -9.500108 -3.800094)
			(size 0.4572 0.4572)
			(layers "F.Cu" "F.Mask" "F.Paste")
			(net "P0V8_PEX1")
		)
		(pad "AA16" smd circle
			(at -8.549894 -3.800094)
			(size 0.4572 0.4572)
			(layers "F.Cu" "F.Mask" "F.Paste")
			(net "GND")
		)
		(pad "AA17" smd circle
			(at -7.599934 -3.800094)
			(size 0.4572 0.4572)
			(layers "F.Cu" "F.Mask" "F.Paste")
			(net "GND")
		)
		(pad "AA18" smd circle
			(at -6.649974 -3.800094)
			(size 0.4572 0.4572)
			(layers "F.Cu" "F.Mask" "F.Paste")
			(net "GND")
		)
		(pad "AA19" smd circle
			(at -5.700014 -3.800094)
			(size 0.4572 0.4572)
			(layers "F.Cu" "F.Mask" "F.Paste")
			(net "GND")
		)
		(pad "AA20" smd circle
			(at -4.750054 -3.800094)
			(size 0.4572 0.4572)
			(layers "F.Cu" "F.Mask" "F.Paste")
			(net "GND")
		)
		(pad "AA21" smd circle
			(at -3.800094 -3.800094)
			(size 0.4572 0.4572)
			(layers "F.Cu" "F.Mask" "F.Paste")
			(net "GND")
		)
		(pad "AA22" smd circle
			(at -2.84988 -3.800094)
			(size 0.4572 0.4572)
			(layers "F.Cu" "F.Mask" "F.Paste")
			(net "GND")
		)
		(pad "AA23" smd circle
			(at -1.89992 -3.800094)
			(size 0.4572 0.4572)
			(layers "F.Cu" "F.Mask" "F.Paste")
			(net "GND")
		)
		(pad "AA24" smd circle
			(at -0.94996 -3.800094)
			(size 0.4572 0.4572)
			(layers "F.Cu" "F.Mask" "F.Paste")
			(net "GND")
		)
		(pad "AA25" smd circle
			(at 0 -3.800094)
			(size 0.4572 0.4572)
			(layers "F.Cu" "F.Mask" "F.Paste")
			(net "GND")
		)
		(pad "AA26" smd circle
			(at 0.94996 -3.800094)
			(size 0.4572 0.4572)
			(layers "F.Cu" "F.Mask" "F.Paste")
			(net "GND")
		)
		(pad "AA27" smd circle
			(at 1.89992 -3.800094)
			(size 0.4572 0.4572)
			(layers "F.Cu" "F.Mask" "F.Paste")
			(net "GND")
		)
		(pad "AA28" smd circle
			(at 2.84988 -3.800094)
			(size 0.4572 0.4572)
			(layers "F.Cu" "F.Mask" "F.Paste")
			(net "GND")
		)
		(pad "AA29" smd circle
			(at 3.800094 -3.800094)
			(size 0.4572 0.4572)
			(layers "F.Cu" "F.Mask" "F.Paste")
			(net "GND")
		)
		(pad "AA30" smd circle
			(at 4.750054 -3.800094)
			(size 0.4572 0.4572)
			(layers "F.Cu" "F.Mask" "F.Paste")
			(net "GND")
		)
		(pad "AA31" smd circle
			(at 5.700014 -3.800094)
			(size 0.4572 0.4572)
			(layers "F.Cu" "F.Mask" "F.Paste")
			(net "GND")
		)
		(pad "AA32" smd circle
			(at 6.649974 -3.800094)
			(size 0.4572 0.4572)
			(layers "F.Cu" "F.Mask" "F.Paste")
			(net "GND")
		)
		(pad "AA33" smd circle
			(at 7.599934 -3.800094)
			(size 0.4572 0.4572)
			(layers "F.Cu" "F.Mask" "F.Paste")
			(net "GND")
		)
		(pad "AA34" smd circle
			(at 8.549894 -3.800094)
			(size 0.4572 0.4572)
			(layers "F.Cu" "F.Mask" "F.Paste")
			(net "P1V8_VDDA_PEX1")
		)
		(pad "AA35" smd circle
			(at 9.500108 -3.800094)
			(size 0.4572 0.4572)
			(layers "F.Cu" "F.Mask" "F.Paste")
			(net "Net_506")
		)
		(pad "AA36" smd circle
			(at 10.450068 -3.800094)
			(size 0.4572 0.4572)
			(layers "F.Cu" "F.Mask" "F.Paste")
			(net "GND")
		)
		(pad "AA37" smd circle
			(at 11.400028 -3.800094)
			(size 0.4572 0.4572)
			(layers "F.Cu" "F.Mask" "F.Paste")
			(net "P1V8_VDDA_PEX1")
		)
		(pad "AA38" smd circle
			(at 12.349988 -3.800094)
			(size 0.4572 0.4572)
			(layers "F.Cu" "F.Mask" "F.Paste")
			(net "GND")
		)
		(pad "AA39" smd circle
			(at 13.299948 -3.800094)
			(size 0.4572 0.4572)
			(layers "F.Cu" "F.Mask" "F.Paste")
			(net "PEX1_ADCTEMP_VINP1")
		)
		(pad "AA40" smd circle
			(at 14.249908 -3.800094)
			(size 0.4572 0.4572)
			(layers "F.Cu" "F.Mask" "F.Paste")
			(net "GND")
		)
		(pad "AA41" smd circle
			(at 15.200122 -3.800094)
			(size 0.4572 0.4572)
			(layers "F.Cu" "F.Mask" "F.Paste")
			(net "GND")
		)
		(pad "AA42" smd circle
			(at 16.150082 -3.800094)
			(size 0.4572 0.4572)
			(layers "F.Cu" "F.Mask" "F.Paste")
			(net "GND")
		)
		(pad "AA43" smd circle
			(at 17.100042 -3.800094)
			(size 0.4572 0.4572)
			(layers "F.Cu" "F.Mask" "F.Paste")
			(net "Net_1384")
		)
		(pad "AA44" smd circle
			(at 18.050002 -3.800094)
			(size 0.4572 0.4572)
			(layers "F.Cu" "F.Mask" "F.Paste")
			(net "Net_1377")
		)
		(pad "AA45" smd circle
			(at 18.999962 -3.800094)
			(size 0.4572 0.4572)
			(layers "F.Cu" "F.Mask" "F.Paste")
			(net "GND")
		)
		(pad "AA46" smd circle
			(at 19.949922 -3.800094)
			(size 0.4572 0.4572)
			(layers "F.Cu" "F.Mask" "F.Paste")
			(net "Net_1543")
		)
		(pad "AA47" smd circle
			(at 20.899882 -3.800094)
			(size 0.4572 0.4572)
			(layers "F.Cu" "F.Mask" "F.Paste")
			(net "Net_1628")
		)
		(pad "AA48" smd circle
			(at 21.850096 -3.800094)
			(size 0.4572 0.4572)
			(layers "F.Cu" "F.Mask" "F.Paste")
			(net "GND")
		)
		(pad "AA49" smd circle
			(at 22.800056 -3.800094)
			(size 0.4572 0.4572)
			(layers "F.Cu" "F.Mask" "F.Paste")
			(net "GND")
		)
		(pad "AB1" smd circle
			(at -22.800056 -2.84988)
			(size 0.4572 0.4572)
			(layers "F.Cu" "F.Mask" "F.Paste")
			(net "GND")
		)
		(pad "AB2" smd circle
			(at -21.850096 -2.84988)
			(size 0.4572 0.4572)
			(layers "F.Cu" "F.Mask" "F.Paste")
			(net "GND")
		)
		(pad "AB3" smd circle
			(at -20.899882 -2.84988)
			(size 0.4572 0.4572)
			(layers "F.Cu" "F.Mask" "F.Paste")
			(net "GND")
		)
		(pad "AB4" smd circle
			(at -19.949922 -2.84988)
			(size 0.4572 0.4572)
			(layers "F.Cu" "F.Mask" "F.Paste")
			(net "CLK_100M_DB800ZL_PEX1_S0_R_DN")
		)
		(pad "AB5" smd circle
			(at -18.999962 -2.84988)
			(size 0.4572 0.4572)
			(layers "F.Cu" "F.Mask" "F.Paste")
			(net "CLK_100M_DB800ZL_PEX1_S0_R_DP")
		)
		(pad "AB6" smd circle
			(at -18.050002 -2.84988)
			(size 0.4572 0.4572)
			(layers "F.Cu" "F.Mask" "F.Paste")
			(net "GND")
		)
		(pad "AB7" smd circle
			(at -17.100042 -2.84988)
			(size 0.4572 0.4572)
			(layers "F.Cu" "F.Mask" "F.Paste")
			(net "Net_5306")
		)
		(pad "AB8" smd circle
			(at -16.150082 -2.84988)
			(size 0.4572 0.4572)
			(layers "F.Cu" "F.Mask" "F.Paste")
			(net "Net_5305")
		)
		(pad "AB9" smd circle
			(at -15.200122 -2.84988)
			(size 0.4572 0.4572)
			(layers "F.Cu" "F.Mask" "F.Paste")
			(net "GND")
		)
		(pad "AB10" smd circle
			(at -14.249908 -2.84988)
			(size 0.4572 0.4572)
			(layers "F.Cu" "F.Mask" "F.Paste")
			(net "P1V8_VDDA_PEX1")
		)
		(pad "AB11" smd circle
			(at -13.299948 -2.84988)
			(size 0.4572 0.4572)
			(layers "F.Cu" "F.Mask" "F.Paste")
			(net "GND")
		)
		(pad "AB12" smd circle
			(at -12.349988 -2.84988)
			(size 0.4572 0.4572)
			(layers "F.Cu" "F.Mask" "F.Paste")
			(net "PCEPLL1_VDDA18_PEX1")
		)
		(pad "AB13" smd circle
			(at -11.400028 -2.84988)
			(size 0.4572 0.4572)
			(layers "F.Cu" "F.Mask" "F.Paste")
			(net "GND")
		)
		(pad "AB14" smd circle
			(at -10.450068 -2.84988)
			(size 0.4572 0.4572)
			(layers "F.Cu" "F.Mask" "F.Paste")
			(net "P0V8_PEX1")
		)
		(pad "AB15" smd circle
			(at -9.500108 -2.84988)
			(size 0.4572 0.4572)
			(layers "F.Cu" "F.Mask" "F.Paste")
			(net "GND")
		)
		(pad "AB16" smd circle
			(at -8.549894 -2.84988)
			(size 0.4572 0.4572)
			(layers "F.Cu" "F.Mask" "F.Paste")
			(net "P0V8_SERDES_VDDA_PEX1")
		)
		(pad "AB17" smd circle
			(at -7.599934 -2.84988)
			(size 0.4572 0.4572)
			(layers "F.Cu" "F.Mask" "F.Paste")
			(net "P0V8_SERDES_VDDA_PEX1")
		)
		(pad "AB18" smd circle
			(at -6.649974 -2.84988)
			(size 0.4572 0.4572)
			(layers "F.Cu" "F.Mask" "F.Paste")
			(net "P0V8_SERDES_VDDA_PEX1")
		)
		(pad "AB19" smd circle
			(at -5.700014 -2.84988)
			(size 0.4572 0.4572)
			(layers "F.Cu" "F.Mask" "F.Paste")
			(net "P0V8_SERDES_VDDA_PEX1")
		)
		(pad "AB20" smd circle
			(at -4.750054 -2.84988)
			(size 0.4572 0.4572)
			(layers "F.Cu" "F.Mask" "F.Paste")
			(net "P0V8_SERDES_VDDA_PEX1")
		)
		(pad "AB21" smd circle
			(at -3.800094 -2.84988)
			(size 0.4572 0.4572)
			(layers "F.Cu" "F.Mask" "F.Paste")
			(net "P0V8_SERDES_VDDA_PEX1")
		)
		(pad "AB22" smd circle
			(at -2.84988 -2.84988)
			(size 0.4572 0.4572)
			(layers "F.Cu" "F.Mask" "F.Paste")
			(net "P0V8_SERDES_VDDA_PEX1")
		)
		(pad "AB23" smd circle
			(at -1.89992 -2.84988)
			(size 0.4572 0.4572)
			(layers "F.Cu" "F.Mask" "F.Paste")
			(net "P0V8_SERDES_VDDA_PEX1")
		)
		(pad "AB24" smd circle
			(at -0.94996 -2.84988)
			(size 0.4572 0.4572)
			(layers "F.Cu" "F.Mask" "F.Paste")
			(net "P0V8_SERDES_VDDA_PEX1")
		)
		(pad "AB25" smd circle
			(at 0 -2.84988)
			(size 0.4572 0.4572)
			(layers "F.Cu" "F.Mask" "F.Paste")
			(net "P0V8_SERDES_VDDA_PEX1")
		)
		(pad "AB26" smd circle
			(at 0.94996 -2.84988)
			(size 0.4572 0.4572)
			(layers "F.Cu" "F.Mask" "F.Paste")
			(net "P0V8_SERDES_VDDA_PEX1")
		)
		(pad "AB27" smd circle
			(at 1.89992 -2.84988)
			(size 0.4572 0.4572)
			(layers "F.Cu" "F.Mask" "F.Paste")
			(net "P0V8_SERDES_VDDA_PEX1")
		)
		(pad "AB28" smd circle
			(at 2.84988 -2.84988)
			(size 0.4572 0.4572)
			(layers "F.Cu" "F.Mask" "F.Paste")
			(net "P0V8_SERDES_VDDA_PEX1")
		)
		(pad "AB29" smd circle
			(at 3.800094 -2.84988)
			(size 0.4572 0.4572)
			(layers "F.Cu" "F.Mask" "F.Paste")
			(net "P0V8_SERDES_VDDA_PEX1")
		)
		(pad "AB30" smd circle
			(at 4.750054 -2.84988)
			(size 0.4572 0.4572)
			(layers "F.Cu" "F.Mask" "F.Paste")
			(net "P0V8_SERDES_VDDA_PEX1")
		)
		(pad "AB31" smd circle
			(at 5.700014 -2.84988)
			(size 0.4572 0.4572)
			(layers "F.Cu" "F.Mask" "F.Paste")
			(net "P0V8_SERDES_VDDA_PEX1")
		)
		(pad "AB32" smd circle
			(at 6.649974 -2.84988)
			(size 0.4572 0.4572)
			(layers "F.Cu" "F.Mask" "F.Paste")
			(net "P0V8_SERDES_VDDA_PEX1")
		)
		(pad "AB33" smd circle
			(at 7.599934 -2.84988)
			(size 0.4572 0.4572)
			(layers "F.Cu" "F.Mask" "F.Paste")
			(net "P0V8_SERDES_VDDA_PEX1")
		)
		(pad "AB34" smd circle
			(at 8.549894 -2.84988)
			(size 0.4572 0.4572)
			(layers "F.Cu" "F.Mask" "F.Paste")
			(net "GND")
		)
		(pad "AB35" smd circle
			(at 9.500108 -2.84988)
			(size 0.4572 0.4572)
			(layers "F.Cu" "F.Mask" "F.Paste")
			(net "Net_509")
		)
		(pad "AB36" smd circle
			(at 10.450068 -2.84988)
			(size 0.4572 0.4572)
			(layers "F.Cu" "F.Mask" "F.Paste")
			(net "GND")
		)
		(pad "AB37" smd circle
			(at 11.400028 -2.84988)
			(size 0.4572 0.4572)
			(layers "F.Cu" "F.Mask" "F.Paste")
			(net "GND")
		)
		(pad "AB38" smd circle
			(at 12.349988 -2.84988)
			(size 0.4572 0.4572)
			(layers "F.Cu" "F.Mask" "F.Paste")
			(net "GND")
		)
		(pad "AB39" smd circle
			(at 13.299948 -2.84988)
			(size 0.4572 0.4572)
			(layers "F.Cu" "F.Mask" "F.Paste")
			(net "GND")
		)
		(pad "AB40" smd circle
			(at 14.249908 -2.84988)
			(size 0.4572 0.4572)
			(layers "F.Cu" "F.Mask" "F.Paste")
			(net "GND")
		)
		(pad "AB41" smd circle
			(at 15.200122 -2.84988)
			(size 0.4572 0.4572)
			(layers "F.Cu" "F.Mask" "F.Paste")
			(net "Net_1392")
		)
		(pad "AB42" smd circle
			(at 16.150082 -2.84988)
			(size 0.4572 0.4572)
			(layers "F.Cu" "F.Mask" "F.Paste")
			(net "Net_1379")
		)
		(pad "AB43" smd circle
			(at 17.100042 -2.84988)
			(size 0.4572 0.4572)
			(layers "F.Cu" "F.Mask" "F.Paste")
			(net "GND")
		)
		(pad "AB44" smd circle
			(at 18.050002 -2.84988)
			(size 0.4572 0.4572)
			(layers "F.Cu" "F.Mask" "F.Paste")
			(net "GND")
		)
		(pad "AB45" smd circle
			(at 18.999962 -2.84988)
			(size 0.4572 0.4572)
			(layers "F.Cu" "F.Mask" "F.Paste")
			(net "GND")
		)
		(pad "AB46" smd circle
			(at 19.949922 -2.84988)
			(size 0.4572 0.4572)
			(layers "F.Cu" "F.Mask" "F.Paste")
			(net "GND")
		)
		(pad "AB47" smd circle
			(at 20.899882 -2.84988)
			(size 0.4572 0.4572)
			(layers "F.Cu" "F.Mask" "F.Paste")
			(net "GND")
		)
		(pad "AB48" smd circle
			(at 21.850096 -2.84988)
			(size 0.4572 0.4572)
			(layers "F.Cu" "F.Mask" "F.Paste")
			(net "Net_1584")
		)
		(pad "AB49" smd circle
			(at 22.800056 -2.84988)
			(size 0.4572 0.4572)
			(layers "F.Cu" "F.Mask" "F.Paste")
			(net "Net_1610")
		)
		(pad "AC1" smd circle
			(at -22.800056 -1.89992)
			(size 0.4572 0.4572)
			(layers "F.Cu" "F.Mask" "F.Paste")
			(net "CLK_100M_DB2000QL_PEX1_S1_R_DN")
		)
		(pad "AC2" smd circle
			(at -21.850096 -1.89992)
			(size 0.4572 0.4572)
			(layers "F.Cu" "F.Mask" "F.Paste")
			(net "CLK_100M_DB2000QL_PEX1_S1_R_DP")
		)
		(pad "AC3" smd circle
			(at -20.899882 -1.89992)
			(size 0.4572 0.4572)
			(layers "F.Cu" "F.Mask" "F.Paste")
			(net "GND")
		)
		(pad "AC4" smd circle
			(at -19.949922 -1.89992)
			(size 0.4572 0.4572)
			(layers "F.Cu" "F.Mask" "F.Paste")
			(net "GND")
		)
		(pad "AC5" smd circle
			(at -18.999962 -1.89992)
			(size 0.4572 0.4572)
			(layers "F.Cu" "F.Mask" "F.Paste")
			(net "GND")
		)
		(pad "AC6" smd circle
			(at -18.050002 -1.89992)
			(size 0.4572 0.4572)
			(layers "F.Cu" "F.Mask" "F.Paste")
			(net "GND")
		)
		(pad "AC7" smd circle
			(at -17.100042 -1.89992)
			(size 0.4572 0.4572)
			(layers "F.Cu" "F.Mask" "F.Paste")
			(net "Net_5308")
		)
		(pad "AC8" smd circle
			(at -16.150082 -1.89992)
			(size 0.4572 0.4572)
			(layers "F.Cu" "F.Mask" "F.Paste")
			(net "Net_5310")
		)
		(pad "AC9" smd circle
			(at -15.200122 -1.89992)
			(size 0.4572 0.4572)
			(layers "F.Cu" "F.Mask" "F.Paste")
			(net "GND")
		)
		(pad "AC10" smd circle
			(at -14.249908 -1.89992)
			(size 0.4572 0.4572)
			(layers "F.Cu" "F.Mask" "F.Paste")
			(net "P1V8_VDDA_PEX1")
		)
		(pad "AC11" smd circle
			(at -13.299948 -1.89992)
			(size 0.4572 0.4572)
			(layers "F.Cu" "F.Mask" "F.Paste")
			(net "GND")
		)
		(pad "AC12" smd circle
			(at -12.349988 -1.89992)
			(size 0.4572 0.4572)
			(layers "F.Cu" "F.Mask" "F.Paste")
			(net "GND")
		)
		(pad "AC13" smd circle
			(at -11.400028 -1.89992)
			(size 0.4572 0.4572)
			(layers "F.Cu" "F.Mask" "F.Paste")
			(net "SYSPLL_VDDA18_PEX1")
		)
		(pad "AC14" smd circle
			(at -10.450068 -1.89992)
			(size 0.4572 0.4572)
			(layers "F.Cu" "F.Mask" "F.Paste")
			(net "GND")
		)
		(pad "AC15" smd circle
			(at -9.500108 -1.89992)
			(size 0.4572 0.4572)
			(layers "F.Cu" "F.Mask" "F.Paste")
			(net "P0V8_PEX1")
		)
		(pad "AC16" smd circle
			(at -8.549894 -1.89992)
			(size 0.4572 0.4572)
			(layers "F.Cu" "F.Mask" "F.Paste")
			(net "GND")
		)
		(pad "AC17" smd circle
			(at -7.599934 -1.89992)
			(size 0.4572 0.4572)
			(layers "F.Cu" "F.Mask" "F.Paste")
			(net "P0V8_PEX1")
		)
		(pad "AC18" smd circle
			(at -6.649974 -1.89992)
			(size 0.4572 0.4572)
			(layers "F.Cu" "F.Mask" "F.Paste")
			(net "GND")
		)
		(pad "AC19" smd circle
			(at -5.700014 -1.89992)
			(size 0.4572 0.4572)
			(layers "F.Cu" "F.Mask" "F.Paste")
			(net "P0V8_PEX1")
		)
		(pad "AC20" smd circle
			(at -4.750054 -1.89992)
			(size 0.4572 0.4572)
			(layers "F.Cu" "F.Mask" "F.Paste")
			(net "GND")
		)
		(pad "AC21" smd circle
			(at -3.800094 -1.89992)
			(size 0.4572 0.4572)
			(layers "F.Cu" "F.Mask" "F.Paste")
			(net "P0V8_PEX1")
		)
		(pad "AC22" smd circle
			(at -2.84988 -1.89992)
			(size 0.4572 0.4572)
			(layers "F.Cu" "F.Mask" "F.Paste")
			(net "GND")
		)
		(pad "AC23" smd circle
			(at -1.89992 -1.89992)
			(size 0.4572 0.4572)
			(layers "F.Cu" "F.Mask" "F.Paste")
			(net "P0V8_PEX1")
		)
		(pad "AC24" smd circle
			(at -0.94996 -1.89992)
			(size 0.4572 0.4572)
			(layers "F.Cu" "F.Mask" "F.Paste")
			(net "GND")
		)
		(pad "AC25" smd circle
			(at 0 -1.89992)
			(size 0.4572 0.4572)
			(layers "F.Cu" "F.Mask" "F.Paste")
			(net "P0V8_PEX1")
		)
		(pad "AC26" smd circle
			(at 0.94996 -1.89992)
			(size 0.4572 0.4572)
			(layers "F.Cu" "F.Mask" "F.Paste")
			(net "GND")
		)
		(pad "AC27" smd circle
			(at 1.89992 -1.89992)
			(size 0.4572 0.4572)
			(layers "F.Cu" "F.Mask" "F.Paste")
			(net "P0V8_PEX1")
		)
		(pad "AC28" smd circle
			(at 2.84988 -1.89992)
			(size 0.4572 0.4572)
			(layers "F.Cu" "F.Mask" "F.Paste")
			(net "GND")
		)
		(pad "AC29" smd circle
			(at 3.800094 -1.89992)
			(size 0.4572 0.4572)
			(layers "F.Cu" "F.Mask" "F.Paste")
			(net "P0V8_PEX1")
		)
		(pad "AC30" smd circle
			(at 4.750054 -1.89992)
			(size 0.4572 0.4572)
			(layers "F.Cu" "F.Mask" "F.Paste")
			(net "GND")
		)
		(pad "AC31" smd circle
			(at 5.700014 -1.89992)
			(size 0.4572 0.4572)
			(layers "F.Cu" "F.Mask" "F.Paste")
			(net "P0V8_PEX1")
		)
		(pad "AC32" smd circle
			(at 6.649974 -1.89992)
			(size 0.4572 0.4572)
			(layers "F.Cu" "F.Mask" "F.Paste")
			(net "GND")
		)
		(pad "AC33" smd circle
			(at 7.599934 -1.89992)
			(size 0.4572 0.4572)
			(layers "F.Cu" "F.Mask" "F.Paste")
			(net "P0V8_PEX1")
		)
		(pad "AC34" smd circle
			(at 8.549894 -1.89992)
			(size 0.4572 0.4572)
			(layers "F.Cu" "F.Mask" "F.Paste")
			(net "GND")
		)
		(pad "AC35" smd circle
			(at 9.500108 -1.89992)
			(size 0.4572 0.4572)
			(layers "F.Cu" "F.Mask" "F.Paste")
			(net "GND")
		)
		(pad "AC36" smd circle
			(at 10.450068 -1.89992)
			(size 0.4572 0.4572)
			(layers "F.Cu" "F.Mask" "F.Paste")
			(net "P1V25_PEX1")
		)
		(pad "AC37" smd circle
			(at 11.400028 -1.89992)
			(size 0.4572 0.4572)
			(layers "F.Cu" "F.Mask" "F.Paste")
			(net "GND")
		)
		(pad "AC38" smd circle
			(at 12.349988 -1.89992)
			(size 0.4572 0.4572)
			(layers "F.Cu" "F.Mask" "F.Paste")
			(net "P1V25_SERDES_VDDPLL_PEX1")
		)
		(pad "AC39" smd circle
			(at 13.299948 -1.89992)
			(size 0.4572 0.4572)
			(layers "F.Cu" "F.Mask" "F.Paste")
			(net "GND")
		)
		(pad "AC40" smd circle
			(at 14.249908 -1.89992)
			(size 0.4572 0.4572)
			(layers "F.Cu" "F.Mask" "F.Paste")
			(net "GND")
		)
		(pad "AC41" smd circle
			(at 15.200122 -1.89992)
			(size 0.4572 0.4572)
			(layers "F.Cu" "F.Mask" "F.Paste")
			(net "GND")
		)
		(pad "AC42" smd circle
			(at 16.150082 -1.89992)
			(size 0.4572 0.4572)
			(layers "F.Cu" "F.Mask" "F.Paste")
			(net "GND")
		)
		(pad "AC43" smd circle
			(at 17.100042 -1.89992)
			(size 0.4572 0.4572)
			(layers "F.Cu" "F.Mask" "F.Paste")
			(net "Net_1358")
		)
		(pad "AC44" smd circle
			(at 18.050002 -1.89992)
			(size 0.4572 0.4572)
			(layers "F.Cu" "F.Mask" "F.Paste")
			(net "Net_1417")
		)
		(pad "AC45" smd circle
			(at 18.999962 -1.89992)
			(size 0.4572 0.4572)
			(layers "F.Cu" "F.Mask" "F.Paste")
			(net "GND")
		)
		(pad "AC46" smd circle
			(at 19.949922 -1.89992)
			(size 0.4572 0.4572)
			(layers "F.Cu" "F.Mask" "F.Paste")
			(net "Net_1567")
		)
		(pad "AC47" smd circle
			(at 20.899882 -1.89992)
			(size 0.4572 0.4572)
			(layers "F.Cu" "F.Mask" "F.Paste")
			(net "Net_1579")
		)
		(pad "AC48" smd circle
			(at 21.850096 -1.89992)
			(size 0.4572 0.4572)
			(layers "F.Cu" "F.Mask" "F.Paste")
			(net "GND")
		)
		(pad "AC49" smd circle
			(at 22.800056 -1.89992)
			(size 0.4572 0.4572)
			(layers "F.Cu" "F.Mask" "F.Paste")
			(net "GND")
		)
		(pad "AD1" smd circle
			(at -22.800056 -0.94996)
			(size 0.4572 0.4572)
			(layers "F.Cu" "F.Mask" "F.Paste")
			(net "GND")
		)
		(pad "AD2" smd circle
			(at -21.850096 -0.94996)
			(size 0.4572 0.4572)
			(layers "F.Cu" "F.Mask" "F.Paste")
			(net "GND")
		)
		(pad "AD3" smd circle
			(at -20.899882 -0.94996)
			(size 0.4572 0.4572)
			(layers "F.Cu" "F.Mask" "F.Paste")
			(net "GND")
		)
		(pad "AD4" smd circle
			(at -19.949922 -0.94996)
			(size 0.4572 0.4572)
			(layers "F.Cu" "F.Mask" "F.Paste")
			(net "Net_386")
		)
		(pad "AD5" smd circle
			(at -18.999962 -0.94996)
			(size 0.4572 0.4572)
			(layers "F.Cu" "F.Mask" "F.Paste")
			(net "Net_385")
		)
		(pad "AD6" smd circle
			(at -18.050002 -0.94996)
			(size 0.4572 0.4572)
			(layers "F.Cu" "F.Mask" "F.Paste")
			(net "GND")
		)
		(pad "AD7" smd circle
			(at -17.100042 -0.94996)
			(size 0.4572 0.4572)
			(layers "F.Cu" "F.Mask" "F.Paste")
			(net "Net_5307")
		)
		(pad "AD8" smd circle
			(at -16.150082 -0.94996)
			(size 0.4572 0.4572)
			(layers "F.Cu" "F.Mask" "F.Paste")
			(net "Net_5309")
		)
		(pad "AD9" smd circle
			(at -15.200122 -0.94996)
			(size 0.4572 0.4572)
			(layers "F.Cu" "F.Mask" "F.Paste")
			(net "GND")
		)
		(pad "AD10" smd circle
			(at -14.249908 -0.94996)
			(size 0.4572 0.4572)
			(layers "F.Cu" "F.Mask" "F.Paste")
			(net "GND")
		)
		(pad "AD11" smd circle
			(at -13.299948 -0.94996)
			(size 0.4572 0.4572)
			(layers "F.Cu" "F.Mask" "F.Paste")
			(net "GND")
		)
		(pad "AD12" smd circle
			(at -12.349988 -0.94996)
			(size 0.4572 0.4572)
			(layers "F.Cu" "F.Mask" "F.Paste")
			(net "PCEPLL2_VDDA18_PEX1")
		)
		(pad "AD13" smd circle
			(at -11.400028 -0.94996)
			(size 0.4572 0.4572)
			(layers "F.Cu" "F.Mask" "F.Paste")
			(net "GND")
		)
		(pad "AD14" smd circle
			(at -10.450068 -0.94996)
			(size 0.4572 0.4572)
			(layers "F.Cu" "F.Mask" "F.Paste")
			(net "P0V8_PEX1")
		)
		(pad "AD15" smd circle
			(at -9.500108 -0.94996)
			(size 0.4572 0.4572)
			(layers "F.Cu" "F.Mask" "F.Paste")
			(net "GND")
		)
		(pad "AD16" smd circle
			(at -8.549894 -0.94996)
			(size 0.4572 0.4572)
			(layers "F.Cu" "F.Mask" "F.Paste")
			(net "P0V8_PEX1")
		)
		(pad "AD17" smd circle
			(at -7.599934 -0.94996)
			(size 0.4572 0.4572)
			(layers "F.Cu" "F.Mask" "F.Paste")
			(net "GND")
		)
		(pad "AD18" smd circle
			(at -6.649974 -0.94996)
			(size 0.4572 0.4572)
			(layers "F.Cu" "F.Mask" "F.Paste")
			(net "P0V8_PEX1")
		)
		(pad "AD19" smd circle
			(at -5.700014 -0.94996)
			(size 0.4572 0.4572)
			(layers "F.Cu" "F.Mask" "F.Paste")
			(net "GND")
		)
		(pad "AD20" smd circle
			(at -4.750054 -0.94996)
			(size 0.4572 0.4572)
			(layers "F.Cu" "F.Mask" "F.Paste")
			(net "P0V8_PEX1")
		)
		(pad "AD21" smd circle
			(at -3.800094 -0.94996)
			(size 0.4572 0.4572)
			(layers "F.Cu" "F.Mask" "F.Paste")
			(net "GND")
		)
		(pad "AD22" smd circle
			(at -2.84988 -0.94996)
			(size 0.4572 0.4572)
			(layers "F.Cu" "F.Mask" "F.Paste")
			(net "P0V8_PEX1")
		)
		(pad "AD23" smd circle
			(at -1.89992 -0.94996)
			(size 0.4572 0.4572)
			(layers "F.Cu" "F.Mask" "F.Paste")
			(net "GND")
		)
		(pad "AD24" smd circle
			(at -0.94996 -0.94996)
			(size 0.4572 0.4572)
			(layers "F.Cu" "F.Mask" "F.Paste")
			(net "P0V8_PEX1")
		)
		(pad "AD25" smd circle
			(at 0 -0.94996)
			(size 0.4572 0.4572)
			(layers "F.Cu" "F.Mask" "F.Paste")
			(net "GND")
		)
		(pad "AD26" smd circle
			(at 0.94996 -0.94996)
			(size 0.4572 0.4572)
			(layers "F.Cu" "F.Mask" "F.Paste")
			(net "P0V8_PEX1")
		)
		(pad "AD27" smd circle
			(at 1.89992 -0.94996)
			(size 0.4572 0.4572)
			(layers "F.Cu" "F.Mask" "F.Paste")
			(net "GND")
		)
		(pad "AD28" smd circle
			(at 2.84988 -0.94996)
			(size 0.4572 0.4572)
			(layers "F.Cu" "F.Mask" "F.Paste")
			(net "P0V8_PEX1")
		)
		(pad "AD29" smd circle
			(at 3.800094 -0.94996)
			(size 0.4572 0.4572)
			(layers "F.Cu" "F.Mask" "F.Paste")
			(net "GND")
		)
		(pad "AD30" smd circle
			(at 4.750054 -0.94996)
			(size 0.4572 0.4572)
			(layers "F.Cu" "F.Mask" "F.Paste")
			(net "P0V8_PEX1")
		)
		(pad "AD31" smd circle
			(at 5.700014 -0.94996)
			(size 0.4572 0.4572)
			(layers "F.Cu" "F.Mask" "F.Paste")
			(net "GND")
		)
		(pad "AD32" smd circle
			(at 6.649974 -0.94996)
			(size 0.4572 0.4572)
			(layers "F.Cu" "F.Mask" "F.Paste")
			(net "P0V8_SERDES_VDDA_PEX1")
		)
		(pad "AD33" smd circle
			(at 7.599934 -0.94996)
			(size 0.4572 0.4572)
			(layers "F.Cu" "F.Mask" "F.Paste")
			(net "P0V8_SERDES_VDDA_PEX1")
		)
		(pad "AD34" smd circle
			(at 8.549894 -0.94996)
			(size 0.4572 0.4572)
			(layers "F.Cu" "F.Mask" "F.Paste")
			(net "P0V8_SERDES_VDDA_PEX1")
		)
		(pad "AD35" smd circle
			(at 9.500108 -0.94996)
			(size 0.4572 0.4572)
			(layers "F.Cu" "F.Mask" "F.Paste")
			(net "GND")
		)
		(pad "AD36" smd circle
			(at 10.450068 -0.94996)
			(size 0.4572 0.4572)
			(layers "F.Cu" "F.Mask" "F.Paste")
			(net "P1V25_PEX1")
		)
		(pad "AD37" smd circle
			(at 11.400028 -0.94996)
			(size 0.4572 0.4572)
			(layers "F.Cu" "F.Mask" "F.Paste")
			(net "GND")
		)
		(pad "AD38" smd circle
			(at 12.349988 -0.94996)
			(size 0.4572 0.4572)
			(layers "F.Cu" "F.Mask" "F.Paste")
			(net "P1V25_SERDES_VDDPLL_PEX1")
		)
		(pad "AD39" smd circle
			(at 13.299948 -0.94996)
			(size 0.4572 0.4572)
			(layers "F.Cu" "F.Mask" "F.Paste")
			(net "GND")
		)
		(pad "AD40" smd circle
			(at 14.249908 -0.94996)
			(size 0.4572 0.4572)
			(layers "F.Cu" "F.Mask" "F.Paste")
			(net "GND")
		)
		(pad "AD41" smd circle
			(at 15.200122 -0.94996)
			(size 0.4572 0.4572)
			(layers "F.Cu" "F.Mask" "F.Paste")
			(net "Net_1421")
		)
		(pad "AD42" smd circle
			(at 16.150082 -0.94996)
			(size 0.4572 0.4572)
			(layers "F.Cu" "F.Mask" "F.Paste")
			(net "Net_1403")
		)
		(pad "AD43" smd circle
			(at 17.100042 -0.94996)
			(size 0.4572 0.4572)
			(layers "F.Cu" "F.Mask" "F.Paste")
			(net "GND")
		)
		(pad "AD44" smd circle
			(at 18.050002 -0.94996)
			(size 0.4572 0.4572)
			(layers "F.Cu" "F.Mask" "F.Paste")
			(net "GND")
		)
		(pad "AD45" smd circle
			(at 18.999962 -0.94996)
			(size 0.4572 0.4572)
			(layers "F.Cu" "F.Mask" "F.Paste")
			(net "GND")
		)
		(pad "AD46" smd circle
			(at 19.949922 -0.94996)
			(size 0.4572 0.4572)
			(layers "F.Cu" "F.Mask" "F.Paste")
			(net "GND")
		)
		(pad "AD47" smd circle
			(at 20.899882 -0.94996)
			(size 0.4572 0.4572)
			(layers "F.Cu" "F.Mask" "F.Paste")
			(net "GND")
		)
		(pad "AD48" smd circle
			(at 21.850096 -0.94996)
			(size 0.4572 0.4572)
			(layers "F.Cu" "F.Mask" "F.Paste")
			(net "Net_1580")
		)
		(pad "AD49" smd circle
			(at 22.800056 -0.94996)
			(size 0.4572 0.4572)
			(layers "F.Cu" "F.Mask" "F.Paste")
			(net "Net_1624")
		)
		(pad "AE1" smd circle
			(at -22.800056 0)
			(size 0.4572 0.4572)
			(layers "F.Cu" "F.Mask" "F.Paste")
			(net "CLK_100M_DB800ZL_PEX1_S3_R_DN")
		)
		(pad "AE2" smd circle
			(at -21.850096 0)
			(size 0.4572 0.4572)
			(layers "F.Cu" "F.Mask" "F.Paste")
			(net "CLK_100M_DB800ZL_PEX1_S3_R_DP")
		)
		(pad "AE3" smd circle
			(at -20.899882 0)
			(size 0.4572 0.4572)
			(layers "F.Cu" "F.Mask" "F.Paste")
			(net "GND")
		)
		(pad "AE4" smd circle
			(at -19.949922 0)
			(size 0.4572 0.4572)
			(layers "F.Cu" "F.Mask" "F.Paste")
			(net "GND")
		)
		(pad "AE5" smd circle
			(at -18.999962 0)
			(size 0.4572 0.4572)
			(layers "F.Cu" "F.Mask" "F.Paste")
			(net "GND")
		)
		(pad "AE6" smd circle
			(at -18.050002 0)
			(size 0.4572 0.4572)
			(layers "F.Cu" "F.Mask" "F.Paste")
			(net "GND")
		)
		(pad "AE7" smd circle
			(at -17.100042 0)
			(size 0.4572 0.4572)
			(layers "F.Cu" "F.Mask" "F.Paste")
			(net "Net_5304")
		)
		(pad "AE8" smd circle
			(at -16.150082 0)
			(size 0.4572 0.4572)
			(layers "F.Cu" "F.Mask" "F.Paste")
			(net "Net_5311")
		)
		(pad "AE9" smd circle
			(at -15.200122 0)
			(size 0.4572 0.4572)
			(layers "F.Cu" "F.Mask" "F.Paste")
			(net "GND")
		)
		(pad "AE10" smd circle
			(at -14.249908 0)
			(size 0.4572 0.4572)
			(layers "F.Cu" "F.Mask" "F.Paste")
			(net "P1V8_PEX")
		)
		(pad "AE11" smd circle
			(at -13.299948 0)
			(size 0.4572 0.4572)
			(layers "F.Cu" "F.Mask" "F.Paste")
			(net "GND")
		)
		(pad "AE12" smd circle
			(at -12.349988 0)
			(size 0.4572 0.4572)
			(layers "F.Cu" "F.Mask" "F.Paste")
			(net "GND")
		)
		(pad "AE13" smd circle
			(at -11.400028 0)
			(size 0.4572 0.4572)
			(layers "F.Cu" "F.Mask" "F.Paste")
			(net "PCEPLL3_VDDA18_PEX1")
		)
		(pad "AE14" smd circle
			(at -10.450068 0)
			(size 0.4572 0.4572)
			(layers "F.Cu" "F.Mask" "F.Paste")
			(net "GND")
		)
		(pad "AE15" smd circle
			(at -9.500108 0)
			(size 0.4572 0.4572)
			(layers "F.Cu" "F.Mask" "F.Paste")
			(net "P0V8_PEX1")
		)
		(pad "AE16" smd circle
			(at -8.549894 0)
			(size 0.4572 0.4572)
			(layers "F.Cu" "F.Mask" "F.Paste")
			(net "GND")
		)
		(pad "AE17" smd circle
			(at -7.599934 0)
			(size 0.4572 0.4572)
			(layers "F.Cu" "F.Mask" "F.Paste")
			(net "P0V8_PEX1")
		)
		(pad "AE18" smd circle
			(at -6.649974 0)
			(size 0.4572 0.4572)
			(layers "F.Cu" "F.Mask" "F.Paste")
			(net "GND")
		)
		(pad "AE19" smd circle
			(at -5.700014 0)
			(size 0.4572 0.4572)
			(layers "F.Cu" "F.Mask" "F.Paste")
			(net "P0V8_PEX1")
		)
		(pad "AE20" smd circle
			(at -4.750054 0)
			(size 0.4572 0.4572)
			(layers "F.Cu" "F.Mask" "F.Paste")
			(net "GND")
		)
		(pad "AE21" smd circle
			(at -3.800094 0)
			(size 0.4572 0.4572)
			(layers "F.Cu" "F.Mask" "F.Paste")
			(net "P0V8_PEX1")
		)
		(pad "AE22" smd circle
			(at -2.84988 0)
			(size 0.4572 0.4572)
			(layers "F.Cu" "F.Mask" "F.Paste")
			(net "GND")
		)
		(pad "AE23" smd circle
			(at -1.89992 0)
			(size 0.4572 0.4572)
			(layers "F.Cu" "F.Mask" "F.Paste")
			(net "P0V8_PEX1")
		)
		(pad "AE24" smd circle
			(at -0.94996 0)
			(size 0.4572 0.4572)
			(layers "F.Cu" "F.Mask" "F.Paste")
			(net "GND")
		)
		(pad "AE25" smd circle
			(at 0 0)
			(size 0.4572 0.4572)
			(layers "F.Cu" "F.Mask" "F.Paste")
			(net "P0V8_PEX1")
		)
		(pad "AE26" smd circle
			(at 0.94996 0)
			(size 0.4572 0.4572)
			(layers "F.Cu" "F.Mask" "F.Paste")
			(net "GND")
		)
		(pad "AE27" smd circle
			(at 1.89992 0)
			(size 0.4572 0.4572)
			(layers "F.Cu" "F.Mask" "F.Paste")
			(net "P0V8_PEX1")
		)
		(pad "AE28" smd circle
			(at 2.84988 0)
			(size 0.4572 0.4572)
			(layers "F.Cu" "F.Mask" "F.Paste")
			(net "GND")
		)
		(pad "AE29" smd circle
			(at 3.800094 0)
			(size 0.4572 0.4572)
			(layers "F.Cu" "F.Mask" "F.Paste")
			(net "P0V8_PEX1")
		)
		(pad "AE30" smd circle
			(at 4.750054 0)
			(size 0.4572 0.4572)
			(layers "F.Cu" "F.Mask" "F.Paste")
			(net "GND")
		)
		(pad "AE31" smd circle
			(at 5.700014 0)
			(size 0.4572 0.4572)
			(layers "F.Cu" "F.Mask" "F.Paste")
			(net "P0V8_PEX1")
		)
		(pad "AE32" smd circle
			(at 6.649974 0)
			(size 0.4572 0.4572)
			(layers "F.Cu" "F.Mask" "F.Paste")
			(net "GND")
		)
		(pad "AE33" smd circle
			(at 7.599934 0)
			(size 0.4572 0.4572)
			(layers "F.Cu" "F.Mask" "F.Paste")
			(net "P0V8_SERDES_VDDA_PEX1")
		)
		(pad "AE34" smd circle
			(at 8.549894 0)
			(size 0.4572 0.4572)
			(layers "F.Cu" "F.Mask" "F.Paste")
			(net "P0V8_SERDES_VDDA_PEX1")
		)
		(pad "AE35" smd circle
			(at 9.500108 0)
			(size 0.4572 0.4572)
			(layers "F.Cu" "F.Mask" "F.Paste")
			(net "GND")
		)
		(pad "AE36" smd circle
			(at 10.450068 0)
			(size 0.4572 0.4572)
			(layers "F.Cu" "F.Mask" "F.Paste")
			(net "P1V25_PEX1")
		)
		(pad "AE37" smd circle
			(at 11.400028 0)
			(size 0.4572 0.4572)
			(layers "F.Cu" "F.Mask" "F.Paste")
			(net "GND")
		)
		(pad "AE38" smd circle
			(at 12.349988 0)
			(size 0.4572 0.4572)
			(layers "F.Cu" "F.Mask" "F.Paste")
			(net "P1V25_SERDES_VDDPLL_PEX1")
		)
		(pad "AE39" smd circle
			(at 13.299948 0)
			(size 0.4572 0.4572)
			(layers "F.Cu" "F.Mask" "F.Paste")
			(net "GND")
		)
		(pad "AE40" smd circle
			(at 14.249908 0)
			(size 0.4572 0.4572)
			(layers "F.Cu" "F.Mask" "F.Paste")
			(net "GND")
		)
		(pad "AE41" smd circle
			(at 15.200122 0)
			(size 0.4572 0.4572)
			(layers "F.Cu" "F.Mask" "F.Paste")
			(net "GND")
		)
		(pad "AE42" smd circle
			(at 16.150082 0)
			(size 0.4572 0.4572)
			(layers "F.Cu" "F.Mask" "F.Paste")
			(net "GND")
		)
		(pad "AE43" smd circle
			(at 17.100042 0)
			(size 0.4572 0.4572)
			(layers "F.Cu" "F.Mask" "F.Paste")
			(net "Net_1381")
		)
		(pad "AE44" smd circle
			(at 18.050002 0)
			(size 0.4572 0.4572)
			(layers "F.Cu" "F.Mask" "F.Paste")
			(net "Net_1415")
		)
		(pad "AE45" smd circle
			(at 18.999962 0)
			(size 0.4572 0.4572)
			(layers "F.Cu" "F.Mask" "F.Paste")
			(net "GND")
		)
		(pad "AE46" smd circle
			(at 19.949922 0)
			(size 0.4572 0.4572)
			(layers "F.Cu" "F.Mask" "F.Paste")
			(net "Net_1615")
		)
		(pad "AE47" smd circle
			(at 20.899882 0)
			(size 0.4572 0.4572)
			(layers "F.Cu" "F.Mask" "F.Paste")
			(net "Net_1612")
		)
		(pad "AE48" smd circle
			(at 21.850096 0)
			(size 0.4572 0.4572)
			(layers "F.Cu" "F.Mask" "F.Paste")
			(net "GND")
		)
		(pad "AE49" smd circle
			(at 22.800056 0)
			(size 0.4572 0.4572)
			(layers "F.Cu" "F.Mask" "F.Paste")
			(net "GND")
		)
		(pad "AF1" smd circle
			(at -22.800056 0.94996)
			(size 0.4572 0.4572)
			(layers "F.Cu" "F.Mask" "F.Paste")
			(net "GND")
		)
		(pad "AF2" smd circle
			(at -21.850096 0.94996)
			(size 0.4572 0.4572)
			(layers "F.Cu" "F.Mask" "F.Paste")
			(net "GND")
		)
		(pad "AF3" smd circle
			(at -20.899882 0.94996)
			(size 0.4572 0.4572)
			(layers "F.Cu" "F.Mask" "F.Paste")
			(net "GND")
		)
		(pad "AF4" smd circle
			(at -19.949922 0.94996)
			(size 0.4572 0.4572)
			(layers "F.Cu" "F.Mask" "F.Paste")
			(net "Net_5223")
		)
		(pad "AF5" smd circle
			(at -18.999962 0.94996)
			(size 0.4572 0.4572)
			(layers "F.Cu" "F.Mask" "F.Paste")
			(net "Net_5224")
		)
		(pad "AF6" smd circle
			(at -18.050002 0.94996)
			(size 0.4572 0.4572)
			(layers "F.Cu" "F.Mask" "F.Paste")
			(net "GND")
		)
		(pad "AF7" smd circle
			(at -17.100042 0.94996)
			(size 0.4572 0.4572)
			(layers "F.Cu" "F.Mask" "F.Paste")
			(net "SPI_PEX1_SDIO0")
		)
		(pad "AF8" smd circle
			(at -16.150082 0.94996)
			(size 0.4572 0.4572)
			(layers "F.Cu" "F.Mask" "F.Paste")
			(net "SPI_PEX1_SDIO1")
		)
		(pad "AF9" smd circle
			(at -15.200122 0.94996)
			(size 0.4572 0.4572)
			(layers "F.Cu" "F.Mask" "F.Paste")
			(net "GND")
		)
		(pad "AF10" smd circle
			(at -14.249908 0.94996)
			(size 0.4572 0.4572)
			(layers "F.Cu" "F.Mask" "F.Paste")
			(net "P1V8_PEX")
		)
		(pad "AF11" smd circle
			(at -13.299948 0.94996)
			(size 0.4572 0.4572)
			(layers "F.Cu" "F.Mask" "F.Paste")
			(net "GND")
		)
		(pad "AF12" smd circle
			(at -12.349988 0.94996)
			(size 0.4572 0.4572)
			(layers "F.Cu" "F.Mask" "F.Paste")
			(net "PCEPLL4_VDDA18_PEX1")
		)
		(pad "AF13" smd circle
			(at -11.400028 0.94996)
			(size 0.4572 0.4572)
			(layers "F.Cu" "F.Mask" "F.Paste")
			(net "GND")
		)
		(pad "AF14" smd circle
			(at -10.450068 0.94996)
			(size 0.4572 0.4572)
			(layers "F.Cu" "F.Mask" "F.Paste")
			(net "P0V8_PEX1")
		)
		(pad "AF15" smd circle
			(at -9.500108 0.94996)
			(size 0.4572 0.4572)
			(layers "F.Cu" "F.Mask" "F.Paste")
			(net "GND")
		)
		(pad "AF16" smd circle
			(at -8.549894 0.94996)
			(size 0.4572 0.4572)
			(layers "F.Cu" "F.Mask" "F.Paste")
			(net "P0V8_PEX1")
		)
		(pad "AF17" smd circle
			(at -7.599934 0.94996)
			(size 0.4572 0.4572)
			(layers "F.Cu" "F.Mask" "F.Paste")
			(net "GND")
		)
		(pad "AF18" smd circle
			(at -6.649974 0.94996)
			(size 0.4572 0.4572)
			(layers "F.Cu" "F.Mask" "F.Paste")
			(net "P0V8_PEX1")
		)
		(pad "AF19" smd circle
			(at -5.700014 0.94996)
			(size 0.4572 0.4572)
			(layers "F.Cu" "F.Mask" "F.Paste")
			(net "GND")
		)
		(pad "AF20" smd circle
			(at -4.750054 0.94996)
			(size 0.4572 0.4572)
			(layers "F.Cu" "F.Mask" "F.Paste")
			(net "P0V8_PEX1")
		)
		(pad "AF21" smd circle
			(at -3.800094 0.94996)
			(size 0.4572 0.4572)
			(layers "F.Cu" "F.Mask" "F.Paste")
			(net "GND")
		)
		(pad "AF22" smd circle
			(at -2.84988 0.94996)
			(size 0.4572 0.4572)
			(layers "F.Cu" "F.Mask" "F.Paste")
			(net "P0V8_PEX1")
		)
		(pad "AF23" smd circle
			(at -1.89992 0.94996)
			(size 0.4572 0.4572)
			(layers "F.Cu" "F.Mask" "F.Paste")
			(net "GND")
		)
		(pad "AF24" smd circle
			(at -0.94996 0.94996)
			(size 0.4572 0.4572)
			(layers "F.Cu" "F.Mask" "F.Paste")
			(net "P0V8_PEX1")
		)
		(pad "AF25" smd circle
			(at 0 0.94996)
			(size 0.4572 0.4572)
			(layers "F.Cu" "F.Mask" "F.Paste")
			(net "GND")
		)
		(pad "AF26" smd circle
			(at 0.94996 0.94996)
			(size 0.4572 0.4572)
			(layers "F.Cu" "F.Mask" "F.Paste")
			(net "P0V8_PEX1")
		)
		(pad "AF27" smd circle
			(at 1.89992 0.94996)
			(size 0.4572 0.4572)
			(layers "F.Cu" "F.Mask" "F.Paste")
			(net "GND")
		)
		(pad "AF28" smd circle
			(at 2.84988 0.94996)
			(size 0.4572 0.4572)
			(layers "F.Cu" "F.Mask" "F.Paste")
			(net "P0V8_PEX1")
		)
		(pad "AF29" smd circle
			(at 3.800094 0.94996)
			(size 0.4572 0.4572)
			(layers "F.Cu" "F.Mask" "F.Paste")
			(net "GND")
		)
		(pad "AF30" smd circle
			(at 4.750054 0.94996)
			(size 0.4572 0.4572)
			(layers "F.Cu" "F.Mask" "F.Paste")
			(net "P0V8_PEX1")
		)
		(pad "AF31" smd circle
			(at 5.700014 0.94996)
			(size 0.4572 0.4572)
			(layers "F.Cu" "F.Mask" "F.Paste")
			(net "GND")
		)
		(pad "AF32" smd circle
			(at 6.649974 0.94996)
			(size 0.4572 0.4572)
			(layers "F.Cu" "F.Mask" "F.Paste")
			(net "P0V8_SERDES_VDDA_PEX1")
		)
		(pad "AF33" smd circle
			(at 7.599934 0.94996)
			(size 0.4572 0.4572)
			(layers "F.Cu" "F.Mask" "F.Paste")
			(net "P0V8_SERDES_VDDA_PEX1")
		)
		(pad "AF34" smd circle
			(at 8.549894 0.94996)
			(size 0.4572 0.4572)
			(layers "F.Cu" "F.Mask" "F.Paste")
			(net "P0V8_SERDES_VDDA_PEX1")
		)
		(pad "AF35" smd circle
			(at 9.500108 0.94996)
			(size 0.4572 0.4572)
			(layers "F.Cu" "F.Mask" "F.Paste")
			(net "GND")
		)
		(pad "AF36" smd circle
			(at 10.450068 0.94996)
			(size 0.4572 0.4572)
			(layers "F.Cu" "F.Mask" "F.Paste")
			(net "P1V25_PEX1")
		)
		(pad "AF37" smd circle
			(at 11.400028 0.94996)
			(size 0.4572 0.4572)
			(layers "F.Cu" "F.Mask" "F.Paste")
			(net "GND")
		)
		(pad "AF38" smd circle
			(at 12.349988 0.94996)
			(size 0.4572 0.4572)
			(layers "F.Cu" "F.Mask" "F.Paste")
			(net "P1V25_SERDES_VDDPLL_PEX1")
		)
		(pad "AF39" smd circle
			(at 13.299948 0.94996)
			(size 0.4572 0.4572)
			(layers "F.Cu" "F.Mask" "F.Paste")
			(net "GND")
		)
		(pad "AF40" smd circle
			(at 14.249908 0.94996)
			(size 0.4572 0.4572)
			(layers "F.Cu" "F.Mask" "F.Paste")
			(net "GND")
		)
		(pad "AF41" smd circle
			(at 15.200122 0.94996)
			(size 0.4572 0.4572)
			(layers "F.Cu" "F.Mask" "F.Paste")
			(net "Net_1372")
		)
		(pad "AF42" smd circle
			(at 16.150082 0.94996)
			(size 0.4572 0.4572)
			(layers "F.Cu" "F.Mask" "F.Paste")
			(net "Net_1369")
		)
		(pad "AF43" smd circle
			(at 17.100042 0.94996)
			(size 0.4572 0.4572)
			(layers "F.Cu" "F.Mask" "F.Paste")
			(net "GND")
		)
		(pad "AF44" smd circle
			(at 18.050002 0.94996)
			(size 0.4572 0.4572)
			(layers "F.Cu" "F.Mask" "F.Paste")
			(net "GND")
		)
		(pad "AF45" smd circle
			(at 18.999962 0.94996)
			(size 0.4572 0.4572)
			(layers "F.Cu" "F.Mask" "F.Paste")
			(net "GND")
		)
		(pad "AF46" smd circle
			(at 19.949922 0.94996)
			(size 0.4572 0.4572)
			(layers "F.Cu" "F.Mask" "F.Paste")
			(net "GND")
		)
		(pad "AF47" smd circle
			(at 20.899882 0.94996)
			(size 0.4572 0.4572)
			(layers "F.Cu" "F.Mask" "F.Paste")
			(net "GND")
		)
		(pad "AF48" smd circle
			(at 21.850096 0.94996)
			(size 0.4572 0.4572)
			(layers "F.Cu" "F.Mask" "F.Paste")
			(net "Net_1627")
		)
		(pad "AF49" smd circle
			(at 22.800056 0.94996)
			(size 0.4572 0.4572)
			(layers "F.Cu" "F.Mask" "F.Paste")
			(net "Net_1529")
		)
		(pad "AG1" smd circle
			(at -22.800056 1.89992)
			(size 0.4572 0.4572)
			(layers "F.Cu" "F.Mask" "F.Paste")
			(net "Net_5226")
		)
		(pad "AG2" smd circle
			(at -21.850096 1.89992)
			(size 0.4572 0.4572)
			(layers "F.Cu" "F.Mask" "F.Paste")
			(net "Net_5227")
		)
		(pad "AG3" smd circle
			(at -20.899882 1.89992)
			(size 0.4572 0.4572)
			(layers "F.Cu" "F.Mask" "F.Paste")
			(net "GND")
		)
		(pad "AG4" smd circle
			(at -19.949922 1.89992)
			(size 0.4572 0.4572)
			(layers "F.Cu" "F.Mask" "F.Paste")
			(net "GND")
		)
		(pad "AG5" smd circle
			(at -18.999962 1.89992)
			(size 0.4572 0.4572)
			(layers "F.Cu" "F.Mask" "F.Paste")
			(net "GND")
		)
		(pad "AG6" smd circle
			(at -18.050002 1.89992)
			(size 0.4572 0.4572)
			(layers "F.Cu" "F.Mask" "F.Paste")
			(net "GND")
		)
		(pad "AG7" smd circle
			(at -17.100042 1.89992)
			(size 0.4572 0.4572)
			(layers "F.Cu" "F.Mask" "F.Paste")
			(net "SPI_PEX1_RST_N")
		)
		(pad "AG8" smd circle
			(at -16.150082 1.89992)
			(size 0.4572 0.4572)
			(layers "F.Cu" "F.Mask" "F.Paste")
			(net "SPI_PEX1_SDIO2")
		)
		(pad "AG9" smd circle
			(at -15.200122 1.89992)
			(size 0.4572 0.4572)
			(layers "F.Cu" "F.Mask" "F.Paste")
			(net "GND")
		)
		(pad "AG10" smd circle
			(at -14.249908 1.89992)
			(size 0.4572 0.4572)
			(layers "F.Cu" "F.Mask" "F.Paste")
			(net "GND")
		)
		(pad "AG11" smd circle
			(at -13.299948 1.89992)
			(size 0.4572 0.4572)
			(layers "F.Cu" "F.Mask" "F.Paste")
			(net "GND")
		)
		(pad "AG12" smd circle
			(at -12.349988 1.89992)
			(size 0.4572 0.4572)
			(layers "F.Cu" "F.Mask" "F.Paste")
			(net "GND")
		)
		(pad "AG13" smd circle
			(at -11.400028 1.89992)
			(size 0.4572 0.4572)
			(layers "F.Cu" "F.Mask" "F.Paste")
			(net "PCEPLL5_VDDA18_PEX1")
		)
		(pad "AG14" smd circle
			(at -10.450068 1.89992)
			(size 0.4572 0.4572)
			(layers "F.Cu" "F.Mask" "F.Paste")
			(net "GND")
		)
		(pad "AG15" smd circle
			(at -9.500108 1.89992)
			(size 0.4572 0.4572)
			(layers "F.Cu" "F.Mask" "F.Paste")
			(net "P0V8_PEX1")
		)
		(pad "AG16" smd circle
			(at -8.549894 1.89992)
			(size 0.4572 0.4572)
			(layers "F.Cu" "F.Mask" "F.Paste")
			(net "GND")
		)
		(pad "AG17" smd circle
			(at -7.599934 1.89992)
			(size 0.4572 0.4572)
			(layers "F.Cu" "F.Mask" "F.Paste")
			(net "P0V8_PEX1")
		)
		(pad "AG18" smd circle
			(at -6.649974 1.89992)
			(size 0.4572 0.4572)
			(layers "F.Cu" "F.Mask" "F.Paste")
			(net "GND")
		)
		(pad "AG19" smd circle
			(at -5.700014 1.89992)
			(size 0.4572 0.4572)
			(layers "F.Cu" "F.Mask" "F.Paste")
			(net "P0V8_PEX1")
		)
		(pad "AG20" smd circle
			(at -4.750054 1.89992)
			(size 0.4572 0.4572)
			(layers "F.Cu" "F.Mask" "F.Paste")
			(net "GND")
		)
		(pad "AG21" smd circle
			(at -3.800094 1.89992)
			(size 0.4572 0.4572)
			(layers "F.Cu" "F.Mask" "F.Paste")
			(net "P0V8_PEX1")
		)
		(pad "AG22" smd circle
			(at -2.84988 1.89992)
			(size 0.4572 0.4572)
			(layers "F.Cu" "F.Mask" "F.Paste")
			(net "GND")
		)
		(pad "AG23" smd circle
			(at -1.89992 1.89992)
			(size 0.4572 0.4572)
			(layers "F.Cu" "F.Mask" "F.Paste")
			(net "P0V8_PEX1")
		)
		(pad "AG24" smd circle
			(at -0.94996 1.89992)
			(size 0.4572 0.4572)
			(layers "F.Cu" "F.Mask" "F.Paste")
			(net "GND")
		)
		(pad "AG25" smd circle
			(at 0 1.89992)
			(size 0.4572 0.4572)
			(layers "F.Cu" "F.Mask" "F.Paste")
			(net "P0V8_PEX1")
		)
		(pad "AG26" smd circle
			(at 0.94996 1.89992)
			(size 0.4572 0.4572)
			(layers "F.Cu" "F.Mask" "F.Paste")
			(net "GND")
		)
		(pad "AG27" smd circle
			(at 1.89992 1.89992)
			(size 0.4572 0.4572)
			(layers "F.Cu" "F.Mask" "F.Paste")
			(net "P0V8_PEX1")
		)
		(pad "AG28" smd circle
			(at 2.84988 1.89992)
			(size 0.4572 0.4572)
			(layers "F.Cu" "F.Mask" "F.Paste")
			(net "GND")
		)
		(pad "AG29" smd circle
			(at 3.800094 1.89992)
			(size 0.4572 0.4572)
			(layers "F.Cu" "F.Mask" "F.Paste")
			(net "P0V8_PEX1")
		)
		(pad "AG30" smd circle
			(at 4.750054 1.89992)
			(size 0.4572 0.4572)
			(layers "F.Cu" "F.Mask" "F.Paste")
			(net "GND")
		)
		(pad "AG31" smd circle
			(at 5.700014 1.89992)
			(size 0.4572 0.4572)
			(layers "F.Cu" "F.Mask" "F.Paste")
			(net "P0V8_PEX1")
		)
		(pad "AG32" smd circle
			(at 6.649974 1.89992)
			(size 0.4572 0.4572)
			(layers "F.Cu" "F.Mask" "F.Paste")
			(net "GND")
		)
		(pad "AG33" smd circle
			(at 7.599934 1.89992)
			(size 0.4572 0.4572)
			(layers "F.Cu" "F.Mask" "F.Paste")
			(net "P0V8_PEX1")
		)
		(pad "AG34" smd circle
			(at 8.549894 1.89992)
			(size 0.4572 0.4572)
			(layers "F.Cu" "F.Mask" "F.Paste")
			(net "GND")
		)
		(pad "AG35" smd circle
			(at 9.500108 1.89992)
			(size 0.4572 0.4572)
			(layers "F.Cu" "F.Mask" "F.Paste")
			(net "GND")
		)
		(pad "AG36" smd circle
			(at 10.450068 1.89992)
			(size 0.4572 0.4572)
			(layers "F.Cu" "F.Mask" "F.Paste")
			(net "P1V25_PEX1")
		)
		(pad "AG37" smd circle
			(at 11.400028 1.89992)
			(size 0.4572 0.4572)
			(layers "F.Cu" "F.Mask" "F.Paste")
			(net "GND")
		)
		(pad "AG38" smd circle
			(at 12.349988 1.89992)
			(size 0.4572 0.4572)
			(layers "F.Cu" "F.Mask" "F.Paste")
			(net "P1V25_SERDES_VDDPLL_PEX1")
		)
		(pad "AG39" smd circle
			(at 13.299948 1.89992)
			(size 0.4572 0.4572)
			(layers "F.Cu" "F.Mask" "F.Paste")
			(net "GND")
		)
		(pad "AG40" smd circle
			(at 14.249908 1.89992)
			(size 0.4572 0.4572)
			(layers "F.Cu" "F.Mask" "F.Paste")
			(net "GND")
		)
		(pad "AG41" smd circle
			(at 15.200122 1.89992)
			(size 0.4572 0.4572)
			(layers "F.Cu" "F.Mask" "F.Paste")
			(net "GND")
		)
		(pad "AG42" smd circle
			(at 16.150082 1.89992)
			(size 0.4572 0.4572)
			(layers "F.Cu" "F.Mask" "F.Paste")
			(net "GND")
		)
		(pad "AG43" smd circle
			(at 17.100042 1.89992)
			(size 0.4572 0.4572)
			(layers "F.Cu" "F.Mask" "F.Paste")
			(net "Net_1360")
		)
		(pad "AG44" smd circle
			(at 18.050002 1.89992)
			(size 0.4572 0.4572)
			(layers "F.Cu" "F.Mask" "F.Paste")
			(net "Net_1433")
		)
		(pad "AG45" smd circle
			(at 18.999962 1.89992)
			(size 0.4572 0.4572)
			(layers "F.Cu" "F.Mask" "F.Paste")
			(net "GND")
		)
		(pad "AG46" smd circle
			(at 19.949922 1.89992)
			(size 0.4572 0.4572)
			(layers "F.Cu" "F.Mask" "F.Paste")
			(net "Net_1557")
		)
		(pad "AG47" smd circle
			(at 20.899882 1.89992)
			(size 0.4572 0.4572)
			(layers "F.Cu" "F.Mask" "F.Paste")
			(net "Net_1603")
		)
		(pad "AG48" smd circle
			(at 21.850096 1.89992)
			(size 0.4572 0.4572)
			(layers "F.Cu" "F.Mask" "F.Paste")
			(net "GND")
		)
		(pad "AG49" smd circle
			(at 22.800056 1.89992)
			(size 0.4572 0.4572)
			(layers "F.Cu" "F.Mask" "F.Paste")
			(net "GND")
		)
		(pad "AH1" smd circle
			(at -22.800056 2.84988)
			(size 0.4572 0.4572)
			(layers "F.Cu" "F.Mask" "F.Paste")
			(net "GND")
		)
		(pad "AH2" smd circle
			(at -21.850096 2.84988)
			(size 0.4572 0.4572)
			(layers "F.Cu" "F.Mask" "F.Paste")
			(net "GND")
		)
		(pad "AH3" smd circle
			(at -20.899882 2.84988)
			(size 0.4572 0.4572)
			(layers "F.Cu" "F.Mask" "F.Paste")
			(net "GND")
		)
		(pad "AH4" smd circle
			(at -19.949922 2.84988)
			(size 0.4572 0.4572)
			(layers "F.Cu" "F.Mask" "F.Paste")
			(net "Net_5229")
		)
		(pad "AH5" smd circle
			(at -18.999962 2.84988)
			(size 0.4572 0.4572)
			(layers "F.Cu" "F.Mask" "F.Paste")
			(net "Net_5230")
		)
		(pad "AH6" smd circle
			(at -18.050002 2.84988)
			(size 0.4572 0.4572)
			(layers "F.Cu" "F.Mask" "F.Paste")
			(net "GND")
		)
		(pad "AH7" smd circle
			(at -17.100042 2.84988)
			(size 0.4572 0.4572)
			(layers "F.Cu" "F.Mask" "F.Paste")
			(net "SPI_PEX1_CLK")
		)
		(pad "AH8" smd circle
			(at -16.150082 2.84988)
			(size 0.4572 0.4572)
			(layers "F.Cu" "F.Mask" "F.Paste")
			(net "SPI_PEX1_SDIO3")
		)
		(pad "AH9" smd circle
			(at -15.200122 2.84988)
			(size 0.4572 0.4572)
			(layers "F.Cu" "F.Mask" "F.Paste")
			(net "GND")
		)
		(pad "AH10" smd circle
			(at -14.249908 2.84988)
			(size 0.4572 0.4572)
			(layers "F.Cu" "F.Mask" "F.Paste")
			(net "P1V8_PEX")
		)
		(pad "AH11" smd circle
			(at -13.299948 2.84988)
			(size 0.4572 0.4572)
			(layers "F.Cu" "F.Mask" "F.Paste")
			(net "GND")
		)
		(pad "AH12" smd circle
			(at -12.349988 2.84988)
			(size 0.4572 0.4572)
			(layers "F.Cu" "F.Mask" "F.Paste")
			(net "PCEPLL6_VDDA18_PEX1")
		)
		(pad "AH13" smd circle
			(at -11.400028 2.84988)
			(size 0.4572 0.4572)
			(layers "F.Cu" "F.Mask" "F.Paste")
			(net "GND")
		)
		(pad "AH14" smd circle
			(at -10.450068 2.84988)
			(size 0.4572 0.4572)
			(layers "F.Cu" "F.Mask" "F.Paste")
			(net "P0V8_PEX1")
		)
		(pad "AH15" smd circle
			(at -9.500108 2.84988)
			(size 0.4572 0.4572)
			(layers "F.Cu" "F.Mask" "F.Paste")
			(net "GND")
		)
		(pad "AH16" smd circle
			(at -8.549894 2.84988)
			(size 0.4572 0.4572)
			(layers "F.Cu" "F.Mask" "F.Paste")
			(net "P0V8_SERDES_VDDA_PEX1")
		)
		(pad "AH17" smd circle
			(at -7.599934 2.84988)
			(size 0.4572 0.4572)
			(layers "F.Cu" "F.Mask" "F.Paste")
			(net "P0V8_SERDES_VDDA_PEX1")
		)
		(pad "AH18" smd circle
			(at -6.649974 2.84988)
			(size 0.4572 0.4572)
			(layers "F.Cu" "F.Mask" "F.Paste")
			(net "P0V8_SERDES_VDDA_PEX1")
		)
		(pad "AH19" smd circle
			(at -5.700014 2.84988)
			(size 0.4572 0.4572)
			(layers "F.Cu" "F.Mask" "F.Paste")
			(net "P0V8_SERDES_VDDA_PEX1")
		)
		(pad "AH20" smd circle
			(at -4.750054 2.84988)
			(size 0.4572 0.4572)
			(layers "F.Cu" "F.Mask" "F.Paste")
			(net "P0V8_SERDES_VDDA_PEX1")
		)
		(pad "AH21" smd circle
			(at -3.800094 2.84988)
			(size 0.4572 0.4572)
			(layers "F.Cu" "F.Mask" "F.Paste")
			(net "P0V8_SERDES_VDDA_PEX1")
		)
		(pad "AH22" smd circle
			(at -2.84988 2.84988)
			(size 0.4572 0.4572)
			(layers "F.Cu" "F.Mask" "F.Paste")
			(net "P0V8_SERDES_VDDA_PEX1")
		)
		(pad "AH23" smd circle
			(at -1.89992 2.84988)
			(size 0.4572 0.4572)
			(layers "F.Cu" "F.Mask" "F.Paste")
			(net "P0V8_SERDES_VDDA_PEX1")
		)
		(pad "AH24" smd circle
			(at -0.94996 2.84988)
			(size 0.4572 0.4572)
			(layers "F.Cu" "F.Mask" "F.Paste")
			(net "P0V8_SERDES_VDDA_PEX1")
		)
		(pad "AH25" smd circle
			(at 0 2.84988)
			(size 0.4572 0.4572)
			(layers "F.Cu" "F.Mask" "F.Paste")
			(net "P0V8_SERDES_VDDA_PEX1")
		)
		(pad "AH26" smd circle
			(at 0.94996 2.84988)
			(size 0.4572 0.4572)
			(layers "F.Cu" "F.Mask" "F.Paste")
			(net "P0V8_SERDES_VDDA_PEX1")
		)
		(pad "AH27" smd circle
			(at 1.89992 2.84988)
			(size 0.4572 0.4572)
			(layers "F.Cu" "F.Mask" "F.Paste")
			(net "P0V8_SERDES_VDDA_PEX1")
		)
		(pad "AH28" smd circle
			(at 2.84988 2.84988)
			(size 0.4572 0.4572)
			(layers "F.Cu" "F.Mask" "F.Paste")
			(net "P0V8_SERDES_VDDA_PEX1")
		)
		(pad "AH29" smd circle
			(at 3.800094 2.84988)
			(size 0.4572 0.4572)
			(layers "F.Cu" "F.Mask" "F.Paste")
			(net "P0V8_SERDES_VDDA_PEX1")
		)
		(pad "AH30" smd circle
			(at 4.750054 2.84988)
			(size 0.4572 0.4572)
			(layers "F.Cu" "F.Mask" "F.Paste")
			(net "P0V8_SERDES_VDDA_PEX1")
		)
		(pad "AH31" smd circle
			(at 5.700014 2.84988)
			(size 0.4572 0.4572)
			(layers "F.Cu" "F.Mask" "F.Paste")
			(net "P0V8_SERDES_VDDA_PEX1")
		)
		(pad "AH32" smd circle
			(at 6.649974 2.84988)
			(size 0.4572 0.4572)
			(layers "F.Cu" "F.Mask" "F.Paste")
			(net "P0V8_SERDES_VDDA_PEX1")
		)
		(pad "AH33" smd circle
			(at 7.599934 2.84988)
			(size 0.4572 0.4572)
			(layers "F.Cu" "F.Mask" "F.Paste")
			(net "P0V8_SERDES_VDDA_PEX1")
		)
		(pad "AH34" smd circle
			(at 8.549894 2.84988)
			(size 0.4572 0.4572)
			(layers "F.Cu" "F.Mask" "F.Paste")
			(net "GND")
		)
		(pad "AH35" smd circle
			(at 9.500108 2.84988)
			(size 0.4572 0.4572)
			(layers "F.Cu" "F.Mask" "F.Paste")
			(net "GND")
		)
		(pad "AH36" smd circle
			(at 10.450068 2.84988)
			(size 0.4572 0.4572)
			(layers "F.Cu" "F.Mask" "F.Paste")
			(net "GND")
		)
		(pad "AH37" smd circle
			(at 11.400028 2.84988)
			(size 0.4572 0.4572)
			(layers "F.Cu" "F.Mask" "F.Paste")
			(net "GND")
		)
		(pad "AH38" smd circle
			(at 12.349988 2.84988)
			(size 0.4572 0.4572)
			(layers "F.Cu" "F.Mask" "F.Paste")
			(net "GND")
		)
		(pad "AH39" smd circle
			(at 13.299948 2.84988)
			(size 0.4572 0.4572)
			(layers "F.Cu" "F.Mask" "F.Paste")
			(net "GND")
		)
		(pad "AH40" smd circle
			(at 14.249908 2.84988)
			(size 0.4572 0.4572)
			(layers "F.Cu" "F.Mask" "F.Paste")
			(net "GND")
		)
		(pad "AH41" smd circle
			(at 15.200122 2.84988)
			(size 0.4572 0.4572)
			(layers "F.Cu" "F.Mask" "F.Paste")
			(net "Net_1374")
		)
		(pad "AH42" smd circle
			(at 16.150082 2.84988)
			(size 0.4572 0.4572)
			(layers "F.Cu" "F.Mask" "F.Paste")
			(net "Net_1397")
		)
		(pad "AH43" smd circle
			(at 17.100042 2.84988)
			(size 0.4572 0.4572)
			(layers "F.Cu" "F.Mask" "F.Paste")
			(net "GND")
		)
		(pad "AH44" smd circle
			(at 18.050002 2.84988)
			(size 0.4572 0.4572)
			(layers "F.Cu" "F.Mask" "F.Paste")
			(net "GND")
		)
		(pad "AH45" smd circle
			(at 18.999962 2.84988)
			(size 0.4572 0.4572)
			(layers "F.Cu" "F.Mask" "F.Paste")
			(net "GND")
		)
		(pad "AH46" smd circle
			(at 19.949922 2.84988)
			(size 0.4572 0.4572)
			(layers "F.Cu" "F.Mask" "F.Paste")
			(net "GND")
		)
		(pad "AH47" smd circle
			(at 20.899882 2.84988)
			(size 0.4572 0.4572)
			(layers "F.Cu" "F.Mask" "F.Paste")
			(net "GND")
		)
		(pad "AH48" smd circle
			(at 21.850096 2.84988)
			(size 0.4572 0.4572)
			(layers "F.Cu" "F.Mask" "F.Paste")
			(net "Net_1587")
		)
		(pad "AH49" smd circle
			(at 22.800056 2.84988)
			(size 0.4572 0.4572)
			(layers "F.Cu" "F.Mask" "F.Paste")
			(net "Net_1591")
		)
		(pad "AJ1" smd circle
			(at -22.800056 3.800094)
			(size 0.4572 0.4572)
			(layers "F.Cu" "F.Mask" "F.Paste")
			(net "Net_5232")
		)
		(pad "AJ2" smd circle
			(at -21.850096 3.800094)
			(size 0.4572 0.4572)
			(layers "F.Cu" "F.Mask" "F.Paste")
			(net "Net_5233")
		)
		(pad "AJ3" smd circle
			(at -20.899882 3.800094)
			(size 0.4572 0.4572)
			(layers "F.Cu" "F.Mask" "F.Paste")
			(net "GND")
		)
		(pad "AJ4" smd circle
			(at -19.949922 3.800094)
			(size 0.4572 0.4572)
			(layers "F.Cu" "F.Mask" "F.Paste")
			(net "GND")
		)
		(pad "AJ5" smd circle
			(at -18.999962 3.800094)
			(size 0.4572 0.4572)
			(layers "F.Cu" "F.Mask" "F.Paste")
			(net "GND")
		)
		(pad "AJ6" smd circle
			(at -18.050002 3.800094)
			(size 0.4572 0.4572)
			(layers "F.Cu" "F.Mask" "F.Paste")
			(net "GND")
		)
		(pad "AJ7" smd circle
			(at -17.100042 3.800094)
			(size 0.4572 0.4572)
			(layers "F.Cu" "F.Mask" "F.Paste")
			(net "SPI_PEX1_CS_N")
		)
		(pad "AJ8" smd circle
			(at -16.150082 3.800094)
			(size 0.4572 0.4572)
			(layers "F.Cu" "F.Mask" "F.Paste")
			(net "Net_5303")
		)
		(pad "AJ9" smd circle
			(at -15.200122 3.800094)
			(size 0.4572 0.4572)
			(layers "F.Cu" "F.Mask" "F.Paste")
			(net "GND")
		)
		(pad "AJ10" smd circle
			(at -14.249908 3.800094)
			(size 0.4572 0.4572)
			(layers "F.Cu" "F.Mask" "F.Paste")
			(net "P1V8_PEX")
		)
		(pad "AJ11" smd circle
			(at -13.299948 3.800094)
			(size 0.4572 0.4572)
			(layers "F.Cu" "F.Mask" "F.Paste")
			(net "GND")
		)
		(pad "AJ12" smd circle
			(at -12.349988 3.800094)
			(size 0.4572 0.4572)
			(layers "F.Cu" "F.Mask" "F.Paste")
			(net "GND")
		)
		(pad "AJ13" smd circle
			(at -11.400028 3.800094)
			(size 0.4572 0.4572)
			(layers "F.Cu" "F.Mask" "F.Paste")
			(net "PCEPLL7_VDDA18_PEX1")
		)
		(pad "AJ14" smd circle
			(at -10.450068 3.800094)
			(size 0.4572 0.4572)
			(layers "F.Cu" "F.Mask" "F.Paste")
			(net "GND")
		)
		(pad "AJ15" smd circle
			(at -9.500108 3.800094)
			(size 0.4572 0.4572)
			(layers "F.Cu" "F.Mask" "F.Paste")
			(net "P0V8_PEX1")
		)
		(pad "AJ16" smd circle
			(at -8.549894 3.800094)
			(size 0.4572 0.4572)
			(layers "F.Cu" "F.Mask" "F.Paste")
			(net "GND")
		)
		(pad "AJ17" smd circle
			(at -7.599934 3.800094)
			(size 0.4572 0.4572)
			(layers "F.Cu" "F.Mask" "F.Paste")
			(net "GND")
		)
		(pad "AJ18" smd circle
			(at -6.649974 3.800094)
			(size 0.4572 0.4572)
			(layers "F.Cu" "F.Mask" "F.Paste")
			(net "GND")
		)
		(pad "AJ19" smd circle
			(at -5.700014 3.800094)
			(size 0.4572 0.4572)
			(layers "F.Cu" "F.Mask" "F.Paste")
			(net "GND")
		)
		(pad "AJ20" smd circle
			(at -4.750054 3.800094)
			(size 0.4572 0.4572)
			(layers "F.Cu" "F.Mask" "F.Paste")
			(net "GND")
		)
		(pad "AJ21" smd circle
			(at -3.800094 3.800094)
			(size 0.4572 0.4572)
			(layers "F.Cu" "F.Mask" "F.Paste")
			(net "GND")
		)
		(pad "AJ22" smd circle
			(at -2.84988 3.800094)
			(size 0.4572 0.4572)
			(layers "F.Cu" "F.Mask" "F.Paste")
			(net "GND")
		)
		(pad "AJ23" smd circle
			(at -1.89992 3.800094)
			(size 0.4572 0.4572)
			(layers "F.Cu" "F.Mask" "F.Paste")
			(net "GND")
		)
		(pad "AJ24" smd circle
			(at -0.94996 3.800094)
			(size 0.4572 0.4572)
			(layers "F.Cu" "F.Mask" "F.Paste")
			(net "GND")
		)
		(pad "AJ25" smd circle
			(at 0 3.800094)
			(size 0.4572 0.4572)
			(layers "F.Cu" "F.Mask" "F.Paste")
			(net "GND")
		)
		(pad "AJ26" smd circle
			(at 0.94996 3.800094)
			(size 0.4572 0.4572)
			(layers "F.Cu" "F.Mask" "F.Paste")
			(net "GND")
		)
		(pad "AJ27" smd circle
			(at 1.89992 3.800094)
			(size 0.4572 0.4572)
			(layers "F.Cu" "F.Mask" "F.Paste")
			(net "GND")
		)
		(pad "AJ28" smd circle
			(at 2.84988 3.800094)
			(size 0.4572 0.4572)
			(layers "F.Cu" "F.Mask" "F.Paste")
			(net "GND")
		)
		(pad "AJ29" smd circle
			(at 3.800094 3.800094)
			(size 0.4572 0.4572)
			(layers "F.Cu" "F.Mask" "F.Paste")
			(net "GND")
		)
		(pad "AJ30" smd circle
			(at 4.750054 3.800094)
			(size 0.4572 0.4572)
			(layers "F.Cu" "F.Mask" "F.Paste")
			(net "GND")
		)
		(pad "AJ31" smd circle
			(at 5.700014 3.800094)
			(size 0.4572 0.4572)
			(layers "F.Cu" "F.Mask" "F.Paste")
			(net "GND")
		)
		(pad "AJ32" smd circle
			(at 6.649974 3.800094)
			(size 0.4572 0.4572)
			(layers "F.Cu" "F.Mask" "F.Paste")
			(net "GND")
		)
		(pad "AJ33" smd circle
			(at 7.599934 3.800094)
			(size 0.4572 0.4572)
			(layers "F.Cu" "F.Mask" "F.Paste")
			(net "GND")
		)
		(pad "AJ34" smd circle
			(at 8.549894 3.800094)
			(size 0.4572 0.4572)
			(layers "F.Cu" "F.Mask" "F.Paste")
			(net "GND")
		)
		(pad "AJ35" smd circle
			(at 9.500108 3.800094)
			(size 0.4572 0.4572)
			(layers "F.Cu" "F.Mask" "F.Paste")
			(net "GND")
		)
		(pad "AJ36" smd circle
			(at 10.450068 3.800094)
			(size 0.4572 0.4572)
			(layers "F.Cu" "F.Mask" "F.Paste")
			(net "GND")
		)
		(pad "AJ37" smd circle
			(at 11.400028 3.800094)
			(size 0.4572 0.4572)
			(layers "F.Cu" "F.Mask" "F.Paste")
			(net "GND")
		)
		(pad "AJ38" smd circle
			(at 12.349988 3.800094)
			(size 0.4572 0.4572)
			(layers "F.Cu" "F.Mask" "F.Paste")
			(net "UART_PEX1_CLI_TX")
		)
		(pad "AJ39" smd circle
			(at 13.299948 3.800094)
			(size 0.4572 0.4572)
			(layers "F.Cu" "F.Mask" "F.Paste")
			(net "Net_5238")
		)
		(pad "AJ40" smd circle
			(at 14.249908 3.800094)
			(size 0.4572 0.4572)
			(layers "F.Cu" "F.Mask" "F.Paste")
			(net "GND")
		)
		(pad "AJ41" smd circle
			(at 15.200122 3.800094)
			(size 0.4572 0.4572)
			(layers "F.Cu" "F.Mask" "F.Paste")
			(net "GND")
		)
		(pad "AJ42" smd circle
			(at 16.150082 3.800094)
			(size 0.4572 0.4572)
			(layers "F.Cu" "F.Mask" "F.Paste")
			(net "GND")
		)
		(pad "AJ43" smd circle
			(at 17.100042 3.800094)
			(size 0.4572 0.4572)
			(layers "F.Cu" "F.Mask" "F.Paste")
			(net "Net_1399")
		)
		(pad "AJ44" smd circle
			(at 18.050002 3.800094)
			(size 0.4572 0.4572)
			(layers "F.Cu" "F.Mask" "F.Paste")
			(net "Net_1388")
		)
		(pad "AJ45" smd circle
			(at 18.999962 3.800094)
			(size 0.4572 0.4572)
			(layers "F.Cu" "F.Mask" "F.Paste")
			(net "GND")
		)
		(pad "AJ46" smd circle
			(at 19.949922 3.800094)
			(size 0.4572 0.4572)
			(layers "F.Cu" "F.Mask" "F.Paste")
			(net "Net_1531")
		)
		(pad "AJ47" smd circle
			(at 20.899882 3.800094)
			(size 0.4572 0.4572)
			(layers "F.Cu" "F.Mask" "F.Paste")
			(net "Net_1613")
		)
		(pad "AJ48" smd circle
			(at 21.850096 3.800094)
			(size 0.4572 0.4572)
			(layers "F.Cu" "F.Mask" "F.Paste")
			(net "GND")
		)
		(pad "AJ49" smd circle
			(at 22.800056 3.800094)
			(size 0.4572 0.4572)
			(layers "F.Cu" "F.Mask" "F.Paste")
			(net "GND")
		)
		(pad "AK1" smd circle
			(at -22.800056 4.750054)
			(size 0.4572 0.4572)
			(layers "F.Cu" "F.Mask" "F.Paste")
			(net "GND")
		)
		(pad "AK2" smd circle
			(at -21.850096 4.750054)
			(size 0.4572 0.4572)
			(layers "F.Cu" "F.Mask" "F.Paste")
			(net "GND")
		)
		(pad "AK3" smd circle
			(at -20.899882 4.750054)
			(size 0.4572 0.4572)
			(layers "F.Cu" "F.Mask" "F.Paste")
			(net "GND")
		)
		(pad "AK4" smd circle
			(at -19.949922 4.750054)
			(size 0.4572 0.4572)
			(layers "F.Cu" "F.Mask" "F.Paste")
			(net "Net_501")
		)
		(pad "AK5" smd circle
			(at -18.999962 4.750054)
			(size 0.4572 0.4572)
			(layers "F.Cu" "F.Mask" "F.Paste")
			(net "Net_502")
		)
		(pad "AK6" smd circle
			(at -18.050002 4.750054)
			(size 0.4572 0.4572)
			(layers "F.Cu" "F.Mask" "F.Paste")
			(net "GND")
		)
		(pad "AK7" smd circle
			(at -17.100042 4.750054)
			(size 0.4572 0.4572)
			(layers "F.Cu" "F.Mask" "F.Paste")
			(net "Net_5302")
		)
		(pad "AK8" smd circle
			(at -16.150082 4.750054)
			(size 0.4572 0.4572)
			(layers "F.Cu" "F.Mask" "F.Paste")
			(net "GND")
		)
		(pad "AK9" smd circle
			(at -15.200122 4.750054)
			(size 0.4572 0.4572)
			(layers "F.Cu" "F.Mask" "F.Paste")
			(net "GND")
		)
		(pad "AK10" smd circle
			(at -14.249908 4.750054)
			(size 0.4572 0.4572)
			(layers "F.Cu" "F.Mask" "F.Paste")
			(net "P1V8_PEX")
		)
		(pad "AK11" smd circle
			(at -13.299948 4.750054)
			(size 0.4572 0.4572)
			(layers "F.Cu" "F.Mask" "F.Paste")
			(net "GND")
		)
		(pad "AK12" smd circle
			(at -12.349988 4.750054)
			(size 0.4572 0.4572)
			(layers "F.Cu" "F.Mask" "F.Paste")
			(net "P1V8_PEX")
		)
		(pad "AK13" smd circle
			(at -11.400028 4.750054)
			(size 0.4572 0.4572)
			(layers "F.Cu" "F.Mask" "F.Paste")
			(net "GND")
		)
		(pad "AK14" smd circle
			(at -10.450068 4.750054)
			(size 0.4572 0.4572)
			(layers "F.Cu" "F.Mask" "F.Paste")
			(net "P0V8_PEX1")
		)
		(pad "AK15" smd circle
			(at -9.500108 4.750054)
			(size 0.4572 0.4572)
			(layers "F.Cu" "F.Mask" "F.Paste")
			(net "GND")
		)
		(pad "AK16" smd circle
			(at -8.549894 4.750054)
			(size 0.4572 0.4572)
			(layers "F.Cu" "F.Mask" "F.Paste")
			(net "P0V8_SERDES_VDDA_PEX1")
		)
		(pad "AK17" smd circle
			(at -7.599934 4.750054)
			(size 0.4572 0.4572)
			(layers "F.Cu" "F.Mask" "F.Paste")
			(net "P0V8_SERDES_VDDA_PEX1")
		)
		(pad "AK18" smd circle
			(at -6.649974 4.750054)
			(size 0.4572 0.4572)
			(layers "F.Cu" "F.Mask" "F.Paste")
			(net "P0V8_SERDES_VDDA_PEX1")
		)
		(pad "AK19" smd circle
			(at -5.700014 4.750054)
			(size 0.4572 0.4572)
			(layers "F.Cu" "F.Mask" "F.Paste")
			(net "P0V8_SERDES_VDDA_PEX1")
		)
		(pad "AK20" smd circle
			(at -4.750054 4.750054)
			(size 0.4572 0.4572)
			(layers "F.Cu" "F.Mask" "F.Paste")
			(net "P0V8_SERDES_VDDA_PEX1")
		)
		(pad "AK21" smd circle
			(at -3.800094 4.750054)
			(size 0.4572 0.4572)
			(layers "F.Cu" "F.Mask" "F.Paste")
			(net "P0V8_SERDES_VDDA_PEX1")
		)
		(pad "AK22" smd circle
			(at -2.84988 4.750054)
			(size 0.4572 0.4572)
			(layers "F.Cu" "F.Mask" "F.Paste")
			(net "P0V8_SERDES_VDDA_PEX1")
		)
		(pad "AK23" smd circle
			(at -1.89992 4.750054)
			(size 0.4572 0.4572)
			(layers "F.Cu" "F.Mask" "F.Paste")
			(net "P0V8_SERDES_VDDA_PEX1")
		)
		(pad "AK24" smd circle
			(at -0.94996 4.750054)
			(size 0.4572 0.4572)
			(layers "F.Cu" "F.Mask" "F.Paste")
			(net "P0V8_SERDES_VDDA_PEX1")
		)
		(pad "AK25" smd circle
			(at 0 4.750054)
			(size 0.4572 0.4572)
			(layers "F.Cu" "F.Mask" "F.Paste")
			(net "P0V8_SERDES_VDDA_PEX1")
		)
		(pad "AK26" smd circle
			(at 0.94996 4.750054)
			(size 0.4572 0.4572)
			(layers "F.Cu" "F.Mask" "F.Paste")
			(net "P0V8_SERDES_VDDA_PEX1")
		)
		(pad "AK27" smd circle
			(at 1.89992 4.750054)
			(size 0.4572 0.4572)
			(layers "F.Cu" "F.Mask" "F.Paste")
			(net "P0V8_SERDES_VDDA_PEX1")
		)
		(pad "AK28" smd circle
			(at 2.84988 4.750054)
			(size 0.4572 0.4572)
			(layers "F.Cu" "F.Mask" "F.Paste")
			(net "P0V8_SERDES_VDDA_PEX1")
		)
		(pad "AK29" smd circle
			(at 3.800094 4.750054)
			(size 0.4572 0.4572)
			(layers "F.Cu" "F.Mask" "F.Paste")
			(net "P0V8_SERDES_VDDA_PEX1")
		)
		(pad "AK30" smd circle
			(at 4.750054 4.750054)
			(size 0.4572 0.4572)
			(layers "F.Cu" "F.Mask" "F.Paste")
			(net "P0V8_SERDES_VDDA_PEX1")
		)
		(pad "AK31" smd circle
			(at 5.700014 4.750054)
			(size 0.4572 0.4572)
			(layers "F.Cu" "F.Mask" "F.Paste")
			(net "P0V8_SERDES_VDDA_PEX1")
		)
		(pad "AK32" smd circle
			(at 6.649974 4.750054)
			(size 0.4572 0.4572)
			(layers "F.Cu" "F.Mask" "F.Paste")
			(net "P0V8_SERDES_VDDA_PEX1")
		)
		(pad "AK33" smd circle
			(at 7.599934 4.750054)
			(size 0.4572 0.4572)
			(layers "F.Cu" "F.Mask" "F.Paste")
			(net "P0V8_SERDES_VDDA_PEX1")
		)
		(pad "AK34" smd circle
			(at 8.549894 4.750054)
			(size 0.4572 0.4572)
			(layers "F.Cu" "F.Mask" "F.Paste")
			(net "GND")
		)
		(pad "AK35" smd circle
			(at 9.500108 4.750054)
			(size 0.4572 0.4572)
			(layers "F.Cu" "F.Mask" "F.Paste")
			(net "P1V8_PEX")
		)
		(pad "AK36" smd circle
			(at 10.450068 4.750054)
			(size 0.4572 0.4572)
			(layers "F.Cu" "F.Mask" "F.Paste")
			(net "GND")
		)
		(pad "AK37" smd circle
			(at 11.400028 4.750054)
			(size 0.4572 0.4572)
			(layers "F.Cu" "F.Mask" "F.Paste")
			(net "GND")
		)
		(pad "AK38" smd circle
			(at 12.349988 4.750054)
			(size 0.4572 0.4572)
			(layers "F.Cu" "F.Mask" "F.Paste")
			(net "UART_PEX1_CLI_BUF_RX")
		)
		(pad "AK39" smd circle
			(at 13.299948 4.750054)
			(size 0.4572 0.4572)
			(layers "F.Cu" "F.Mask" "F.Paste")
			(net "UART_PEX1_SDB_BUF_RX")
		)
		(pad "AK40" smd circle
			(at 14.249908 4.750054)
			(size 0.4572 0.4572)
			(layers "F.Cu" "F.Mask" "F.Paste")
			(net "GND")
		)
		(pad "AK41" smd circle
			(at 15.200122 4.750054)
			(size 0.4572 0.4572)
			(layers "F.Cu" "F.Mask" "F.Paste")
			(net "Net_1364")
		)
		(pad "AK42" smd circle
			(at 16.150082 4.750054)
			(size 0.4572 0.4572)
			(layers "F.Cu" "F.Mask" "F.Paste")
			(net "Net_1425")
		)
		(pad "AK43" smd circle
			(at 17.100042 4.750054)
			(size 0.4572 0.4572)
			(layers "F.Cu" "F.Mask" "F.Paste")
			(net "GND")
		)
		(pad "AK44" smd circle
			(at 18.050002 4.750054)
			(size 0.4572 0.4572)
			(layers "F.Cu" "F.Mask" "F.Paste")
			(net "GND")
		)
		(pad "AK45" smd circle
			(at 18.999962 4.750054)
			(size 0.4572 0.4572)
			(layers "F.Cu" "F.Mask" "F.Paste")
			(net "GND")
		)
		(pad "AK46" smd circle
			(at 19.949922 4.750054)
			(size 0.4572 0.4572)
			(layers "F.Cu" "F.Mask" "F.Paste")
			(net "GND")
		)
		(pad "AK47" smd circle
			(at 20.899882 4.750054)
			(size 0.4572 0.4572)
			(layers "F.Cu" "F.Mask" "F.Paste")
			(net "GND")
		)
		(pad "AK48" smd circle
			(at 21.850096 4.750054)
			(size 0.4572 0.4572)
			(layers "F.Cu" "F.Mask" "F.Paste")
			(net "Net_1586")
		)
		(pad "AK49" smd circle
			(at 22.800056 4.750054)
			(size 0.4572 0.4572)
			(layers "F.Cu" "F.Mask" "F.Paste")
			(net "Net_1573")
		)
		(pad "AL1" smd circle
			(at -22.800056 5.700014)
			(size 0.4572 0.4572)
			(layers "F.Cu" "F.Mask" "F.Paste")
			(net "GND")
		)
		(pad "AL2" smd circle
			(at -21.850096 5.700014)
			(size 0.4572 0.4572)
			(layers "F.Cu" "F.Mask" "F.Paste")
			(net "GND")
		)
		(pad "AL3" smd circle
			(at -20.899882 5.700014)
			(size 0.4572 0.4572)
			(layers "F.Cu" "F.Mask" "F.Paste")
			(net "GND")
		)
		(pad "AL4" smd circle
			(at -19.949922 5.700014)
			(size 0.4572 0.4572)
			(layers "F.Cu" "F.Mask" "F.Paste")
			(net "GND")
		)
		(pad "AL5" smd circle
			(at -18.999962 5.700014)
			(size 0.4572 0.4572)
			(layers "F.Cu" "F.Mask" "F.Paste")
			(net "GND")
		)
		(pad "AL6" smd circle
			(at -18.050002 5.700014)
			(size 0.4572 0.4572)
			(layers "F.Cu" "F.Mask" "F.Paste")
			(net "GND")
		)
		(pad "AL7" smd circle
			(at -17.100042 5.700014)
			(size 0.4572 0.4572)
			(layers "F.Cu" "F.Mask" "F.Paste")
			(net "GND")
		)
		(pad "AL8" smd circle
			(at -16.150082 5.700014)
			(size 0.4572 0.4572)
			(layers "F.Cu" "F.Mask" "F.Paste")
			(net "GND")
		)
		(pad "AL9" smd circle
			(at -15.200122 5.700014)
			(size 0.4572 0.4572)
			(layers "F.Cu" "F.Mask" "F.Paste")
			(net "GND")
		)
		(pad "AL10" smd circle
			(at -14.249908 5.700014)
			(size 0.4572 0.4572)
			(layers "F.Cu" "F.Mask" "F.Paste")
			(net "GND")
		)
		(pad "AL11" smd circle
			(at -13.299948 5.700014)
			(size 0.4572 0.4572)
			(layers "F.Cu" "F.Mask" "F.Paste")
			(net "GND")
		)
		(pad "AL12" smd circle
			(at -12.349988 5.700014)
			(size 0.4572 0.4572)
			(layers "F.Cu" "F.Mask" "F.Paste")
			(net "GND")
		)
		(pad "AL13" smd circle
			(at -11.400028 5.700014)
			(size 0.4572 0.4572)
			(layers "F.Cu" "F.Mask" "F.Paste")
			(net "GND")
		)
		(pad "AL14" smd circle
			(at -10.450068 5.700014)
			(size 0.4572 0.4572)
			(layers "F.Cu" "F.Mask" "F.Paste")
			(net "VSSA_SENSE")
		)
		(pad "AL15" smd circle
			(at -9.500108 5.700014)
			(size 0.4572 0.4572)
			(layers "F.Cu" "F.Mask" "F.Paste")
			(net "VDDA_SENSE")
		)
		(pad "AL16" smd circle
			(at -8.549894 5.700014)
			(size 0.4572 0.4572)
			(layers "F.Cu" "F.Mask" "F.Paste")
			(net "GND")
		)
		(pad "AL17" smd circle
			(at -7.599934 5.700014)
			(size 0.4572 0.4572)
			(layers "F.Cu" "F.Mask" "F.Paste")
			(net "GND")
		)
		(pad "AL18" smd circle
			(at -6.649974 5.700014)
			(size 0.4572 0.4572)
			(layers "F.Cu" "F.Mask" "F.Paste")
			(net "GND")
		)
		(pad "AL19" smd circle
			(at -5.700014 5.700014)
			(size 0.4572 0.4572)
			(layers "F.Cu" "F.Mask" "F.Paste")
			(net "GND")
		)
		(pad "AL20" smd circle
			(at -4.750054 5.700014)
			(size 0.4572 0.4572)
			(layers "F.Cu" "F.Mask" "F.Paste")
			(net "GND")
		)
		(pad "AL21" smd circle
			(at -3.800094 5.700014)
			(size 0.4572 0.4572)
			(layers "F.Cu" "F.Mask" "F.Paste")
			(net "GND")
		)
		(pad "AL22" smd circle
			(at -2.84988 5.700014)
			(size 0.4572 0.4572)
			(layers "F.Cu" "F.Mask" "F.Paste")
			(net "GND")
		)
		(pad "AL23" smd circle
			(at -1.89992 5.700014)
			(size 0.4572 0.4572)
			(layers "F.Cu" "F.Mask" "F.Paste")
			(net "GND")
		)
		(pad "AL24" smd circle
			(at -0.94996 5.700014)
			(size 0.4572 0.4572)
			(layers "F.Cu" "F.Mask" "F.Paste")
			(net "GND")
		)
		(pad "AL25" smd circle
			(at 0 5.700014)
			(size 0.4572 0.4572)
			(layers "F.Cu" "F.Mask" "F.Paste")
			(net "GND")
		)
		(pad "AL26" smd circle
			(at 0.94996 5.700014)
			(size 0.4572 0.4572)
			(layers "F.Cu" "F.Mask" "F.Paste")
			(net "GND")
		)
		(pad "AL27" smd circle
			(at 1.89992 5.700014)
			(size 0.4572 0.4572)
			(layers "F.Cu" "F.Mask" "F.Paste")
			(net "GND")
		)
		(pad "AL28" smd circle
			(at 2.84988 5.700014)
			(size 0.4572 0.4572)
			(layers "F.Cu" "F.Mask" "F.Paste")
			(net "GND")
		)
		(pad "AL29" smd circle
			(at 3.800094 5.700014)
			(size 0.4572 0.4572)
			(layers "F.Cu" "F.Mask" "F.Paste")
			(net "GND")
		)
		(pad "AL30" smd circle
			(at 4.750054 5.700014)
			(size 0.4572 0.4572)
			(layers "F.Cu" "F.Mask" "F.Paste")
			(net "GND")
		)
		(pad "AL31" smd circle
			(at 5.700014 5.700014)
			(size 0.4572 0.4572)
			(layers "F.Cu" "F.Mask" "F.Paste")
			(net "GND")
		)
		(pad "AL32" smd circle
			(at 6.649974 5.700014)
			(size 0.4572 0.4572)
			(layers "F.Cu" "F.Mask" "F.Paste")
			(net "GND")
		)
		(pad "AL33" smd circle
			(at 7.599934 5.700014)
			(size 0.4572 0.4572)
			(layers "F.Cu" "F.Mask" "F.Paste")
			(net "GND")
		)
		(pad "AL34" smd circle
			(at 8.549894 5.700014)
			(size 0.4572 0.4572)
			(layers "F.Cu" "F.Mask" "F.Paste")
			(net "GND")
		)
		(pad "AL35" smd circle
			(at 9.500108 5.700014)
			(size 0.4572 0.4572)
			(layers "F.Cu" "F.Mask" "F.Paste")
			(net "P1V8_PEX")
		)
		(pad "AL36" smd circle
			(at 10.450068 5.700014)
			(size 0.4572 0.4572)
			(layers "F.Cu" "F.Mask" "F.Paste")
			(net "GND")
		)
		(pad "AL37" smd circle
			(at 11.400028 5.700014)
			(size 0.4572 0.4572)
			(layers "F.Cu" "F.Mask" "F.Paste")
			(net "GND")
		)
		(pad "AL38" smd circle
			(at 12.349988 5.700014)
			(size 0.4572 0.4572)
			(layers "F.Cu" "F.Mask" "F.Paste")
			(net "Net_5269")
		)
		(pad "AL39" smd circle
			(at 13.299948 5.700014)
			(size 0.4572 0.4572)
			(layers "F.Cu" "F.Mask" "F.Paste")
			(net "UART_PEX1_SDB_TX")
		)
		(pad "AL40" smd circle
			(at 14.249908 5.700014)
			(size 0.4572 0.4572)
			(layers "F.Cu" "F.Mask" "F.Paste")
			(net "GND")
		)
		(pad "AL41" smd circle
			(at 15.200122 5.700014)
			(size 0.4572 0.4572)
			(layers "F.Cu" "F.Mask" "F.Paste")
			(net "GND")
		)
		(pad "AL42" smd circle
			(at 16.150082 5.700014)
			(size 0.4572 0.4572)
			(layers "F.Cu" "F.Mask" "F.Paste")
			(net "GND")
		)
		(pad "AL43" smd circle
			(at 17.100042 5.700014)
			(size 0.4572 0.4572)
			(layers "F.Cu" "F.Mask" "F.Paste")
			(net "Net_1432")
		)
		(pad "AL44" smd circle
			(at 18.050002 5.700014)
			(size 0.4572 0.4572)
			(layers "F.Cu" "F.Mask" "F.Paste")
			(net "Net_1385")
		)
		(pad "AL45" smd circle
			(at 18.999962 5.700014)
			(size 0.4572 0.4572)
			(layers "F.Cu" "F.Mask" "F.Paste")
			(net "GND")
		)
		(pad "AL46" smd circle
			(at 19.949922 5.700014)
			(size 0.4572 0.4572)
			(layers "F.Cu" "F.Mask" "F.Paste")
			(net "Net_1553")
		)
		(pad "AL47" smd circle
			(at 20.899882 5.700014)
			(size 0.4572 0.4572)
			(layers "F.Cu" "F.Mask" "F.Paste")
			(net "Net_1550")
		)
		(pad "AL48" smd circle
			(at 21.850096 5.700014)
			(size 0.4572 0.4572)
			(layers "F.Cu" "F.Mask" "F.Paste")
			(net "GND")
		)
		(pad "AL49" smd circle
			(at 22.800056 5.700014)
			(size 0.4572 0.4572)
			(layers "F.Cu" "F.Mask" "F.Paste")
			(net "GND")
		)
		(pad "AM1" smd circle
			(at -22.800056 6.649974)
			(size 0.4572 0.4572)
			(layers "F.Cu" "F.Mask" "F.Paste")
			(net "Net_1710")
		)
		(pad "AM2" smd circle
			(at -21.850096 6.649974)
			(size 0.4572 0.4572)
			(layers "F.Cu" "F.Mask" "F.Paste")
			(net "Net_1386")
		)
		(pad "AM3" smd circle
			(at -20.899882 6.649974)
			(size 0.4572 0.4572)
			(layers "F.Cu" "F.Mask" "F.Paste")
			(net "GND")
		)
		(pad "AM4" smd circle
			(at -19.949922 6.649974)
			(size 0.4572 0.4572)
			(layers "F.Cu" "F.Mask" "F.Paste")
			(net "GND")
		)
		(pad "AM5" smd circle
			(at -18.999962 6.649974)
			(size 0.4572 0.4572)
			(layers "F.Cu" "F.Mask" "F.Paste")
			(net "GND")
		)
		(pad "AM6" smd circle
			(at -18.050002 6.649974)
			(size 0.4572 0.4572)
			(layers "F.Cu" "F.Mask" "F.Paste")
			(net "GND")
		)
		(pad "AM7" smd circle
			(at -17.100042 6.649974)
			(size 0.4572 0.4572)
			(layers "F.Cu" "F.Mask" "F.Paste")
			(net "GND")
		)
		(pad "AM8" smd circle
			(at -16.150082 6.649974)
			(size 0.4572 0.4572)
			(layers "F.Cu" "F.Mask" "F.Paste")
			(net "Net_1658")
		)
		(pad "AM9" smd circle
			(at -15.200122 6.649974)
			(size 0.4572 0.4572)
			(layers "F.Cu" "F.Mask" "F.Paste")
			(net "Net_1640")
		)
		(pad "AM10" smd circle
			(at -14.249908 6.649974)
			(size 0.4572 0.4572)
			(layers "F.Cu" "F.Mask" "F.Paste")
			(net "GND")
		)
		(pad "AM11" smd circle
			(at -13.299948 6.649974)
			(size 0.4572 0.4572)
			(layers "F.Cu" "F.Mask" "F.Paste")
			(net "GND")
		)
		(pad "AM12" smd circle
			(at -12.349988 6.649974)
			(size 0.4572 0.4572)
			(layers "F.Cu" "F.Mask" "F.Paste")
			(net "TP_PEX1_VDDQ_EFUSE")
		)
		(pad "AM13" smd circle
			(at -11.400028 6.649974)
			(size 0.4572 0.4572)
			(layers "F.Cu" "F.Mask" "F.Paste")
			(net "GND")
		)
		(pad "AM14" smd circle
			(at -10.450068 6.649974)
			(size 0.4572 0.4572)
			(layers "F.Cu" "F.Mask" "F.Paste")
			(net "P1V8_VDDA_PEX1")
		)
		(pad "AM15" smd circle
			(at -9.500108 6.649974)
			(size 0.4572 0.4572)
			(layers "F.Cu" "F.Mask" "F.Paste")
			(net "GND")
		)
		(pad "AM16" smd circle
			(at -8.549894 6.649974)
			(size 0.4572 0.4572)
			(layers "F.Cu" "F.Mask" "F.Paste")
			(net "P1V25_PEX1")
		)
		(pad "AM17" smd circle
			(at -7.599934 6.649974)
			(size 0.4572 0.4572)
			(layers "F.Cu" "F.Mask" "F.Paste")
			(net "P1V25_PEX1")
		)
		(pad "AM18" smd circle
			(at -6.649974 6.649974)
			(size 0.4572 0.4572)
			(layers "F.Cu" "F.Mask" "F.Paste")
			(net "P1V25_PEX1")
		)
		(pad "AM19" smd circle
			(at -5.700014 6.649974)
			(size 0.4572 0.4572)
			(layers "F.Cu" "F.Mask" "F.Paste")
			(net "P1V25_PEX1")
		)
		(pad "AM20" smd circle
			(at -4.750054 6.649974)
			(size 0.4572 0.4572)
			(layers "F.Cu" "F.Mask" "F.Paste")
			(net "P1V25_PEX1")
		)
		(pad "AM21" smd circle
			(at -3.800094 6.649974)
			(size 0.4572 0.4572)
			(layers "F.Cu" "F.Mask" "F.Paste")
			(net "P1V25_PEX1")
		)
		(pad "AM22" smd circle
			(at -2.84988 6.649974)
			(size 0.4572 0.4572)
			(layers "F.Cu" "F.Mask" "F.Paste")
			(net "P1V25_PEX1")
		)
		(pad "AM23" smd circle
			(at -1.89992 6.649974)
			(size 0.4572 0.4572)
			(layers "F.Cu" "F.Mask" "F.Paste")
			(net "P1V25_PEX1")
		)
		(pad "AM24" smd circle
			(at -0.94996 6.649974)
			(size 0.4572 0.4572)
			(layers "F.Cu" "F.Mask" "F.Paste")
			(net "P1V25_PEX1")
		)
		(pad "AM25" smd circle
			(at 0 6.649974)
			(size 0.4572 0.4572)
			(layers "F.Cu" "F.Mask" "F.Paste")
			(net "P1V25_PEX1")
		)
		(pad "AM26" smd circle
			(at 0.94996 6.649974)
			(size 0.4572 0.4572)
			(layers "F.Cu" "F.Mask" "F.Paste")
			(net "P1V25_PEX1")
		)
		(pad "AM27" smd circle
			(at 1.89992 6.649974)
			(size 0.4572 0.4572)
			(layers "F.Cu" "F.Mask" "F.Paste")
			(net "P1V25_PEX1")
		)
		(pad "AM28" smd circle
			(at 2.84988 6.649974)
			(size 0.4572 0.4572)
			(layers "F.Cu" "F.Mask" "F.Paste")
			(net "P1V25_PEX1")
		)
		(pad "AM29" smd circle
			(at 3.800094 6.649974)
			(size 0.4572 0.4572)
			(layers "F.Cu" "F.Mask" "F.Paste")
			(net "P1V25_PEX1")
		)
		(pad "AM30" smd circle
			(at 4.750054 6.649974)
			(size 0.4572 0.4572)
			(layers "F.Cu" "F.Mask" "F.Paste")
			(net "P1V25_PEX1")
		)
		(pad "AM31" smd circle
			(at 5.700014 6.649974)
			(size 0.4572 0.4572)
			(layers "F.Cu" "F.Mask" "F.Paste")
			(net "P1V25_PEX1")
		)
		(pad "AM32" smd circle
			(at 6.649974 6.649974)
			(size 0.4572 0.4572)
			(layers "F.Cu" "F.Mask" "F.Paste")
			(net "P1V25_PEX1")
		)
		(pad "AM33" smd circle
			(at 7.599934 6.649974)
			(size 0.4572 0.4572)
			(layers "F.Cu" "F.Mask" "F.Paste")
			(net "P1V25_PEX1")
		)
		(pad "AM34" smd circle
			(at 8.549894 6.649974)
			(size 0.4572 0.4572)
			(layers "F.Cu" "F.Mask" "F.Paste")
			(net "GND")
		)
		(pad "AM35" smd circle
			(at 9.500108 6.649974)
			(size 0.4572 0.4572)
			(layers "F.Cu" "F.Mask" "F.Paste")
			(net "P1V8_PEX")
		)
		(pad "AM36" smd circle
			(at 10.450068 6.649974)
			(size 0.4572 0.4572)
			(layers "F.Cu" "F.Mask" "F.Paste")
			(net "GND")
		)
		(pad "AM37" smd circle
			(at 11.400028 6.649974)
			(size 0.4572 0.4572)
			(layers "F.Cu" "F.Mask" "F.Paste")
			(net "GND")
		)
		(pad "AM38" smd circle
			(at 12.349988 6.649974)
			(size 0.4572 0.4572)
			(layers "F.Cu" "F.Mask" "F.Paste")
			(net "Net_5236")
		)
		(pad "AM39" smd circle
			(at 13.299948 6.649974)
			(size 0.4572 0.4572)
			(layers "F.Cu" "F.Mask" "F.Paste")
			(net "Net_5279")
		)
		(pad "AM40" smd circle
			(at 14.249908 6.649974)
			(size 0.4572 0.4572)
			(layers "F.Cu" "F.Mask" "F.Paste")
			(net "GND")
		)
		(pad "AM41" smd circle
			(at 15.200122 6.649974)
			(size 0.4572 0.4572)
			(layers "F.Cu" "F.Mask" "F.Paste")
			(net "Net_1406")
		)
		(pad "AM42" smd circle
			(at 16.150082 6.649974)
			(size 0.4572 0.4572)
			(layers "F.Cu" "F.Mask" "F.Paste")
			(net "Net_1429")
		)
		(pad "AM43" smd circle
			(at 17.100042 6.649974)
			(size 0.4572 0.4572)
			(layers "F.Cu" "F.Mask" "F.Paste")
			(net "GND")
		)
		(pad "AM44" smd circle
			(at 18.050002 6.649974)
			(size 0.4572 0.4572)
			(layers "F.Cu" "F.Mask" "F.Paste")
			(net "GND")
		)
		(pad "AM45" smd circle
			(at 18.999962 6.649974)
			(size 0.4572 0.4572)
			(layers "F.Cu" "F.Mask" "F.Paste")
			(net "GND")
		)
		(pad "AM46" smd circle
			(at 19.949922 6.649974)
			(size 0.4572 0.4572)
			(layers "F.Cu" "F.Mask" "F.Paste")
			(net "GND")
		)
		(pad "AM47" smd circle
			(at 20.899882 6.649974)
			(size 0.4572 0.4572)
			(layers "F.Cu" "F.Mask" "F.Paste")
			(net "GND")
		)
		(pad "AM48" smd circle
			(at 21.850096 6.649974)
			(size 0.4572 0.4572)
			(layers "F.Cu" "F.Mask" "F.Paste")
			(net "Net_1596")
		)
		(pad "AM49" smd circle
			(at 22.800056 6.649974)
			(size 0.4572 0.4572)
			(layers "F.Cu" "F.Mask" "F.Paste")
			(net "Net_1560")
		)
		(pad "AN1" smd circle
			(at -22.800056 7.599934)
			(size 0.4572 0.4572)
			(layers "F.Cu" "F.Mask" "F.Paste")
			(net "GND")
		)
		(pad "AN2" smd circle
			(at -21.850096 7.599934)
			(size 0.4572 0.4572)
			(layers "F.Cu" "F.Mask" "F.Paste")
			(net "GND")
		)
		(pad "AN3" smd circle
			(at -20.899882 7.599934)
			(size 0.4572 0.4572)
			(layers "F.Cu" "F.Mask" "F.Paste")
			(net "Net_1357")
		)
		(pad "AN4" smd circle
			(at -19.949922 7.599934)
			(size 0.4572 0.4572)
			(layers "F.Cu" "F.Mask" "F.Paste")
			(net "Net_1375")
		)
		(pad "AN5" smd circle
			(at -18.999962 7.599934)
			(size 0.4572 0.4572)
			(layers "F.Cu" "F.Mask" "F.Paste")
			(net "GND")
		)
		(pad "AN6" smd circle
			(at -18.050002 7.599934)
			(size 0.4572 0.4572)
			(layers "F.Cu" "F.Mask" "F.Paste")
			(net "Net_1654")
		)
		(pad "AN7" smd circle
			(at -17.100042 7.599934)
			(size 0.4572 0.4572)
			(layers "F.Cu" "F.Mask" "F.Paste")
			(net "Net_1652")
		)
		(pad "AN8" smd circle
			(at -16.150082 7.599934)
			(size 0.4572 0.4572)
			(layers "F.Cu" "F.Mask" "F.Paste")
			(net "GND")
		)
		(pad "AN9" smd circle
			(at -15.200122 7.599934)
			(size 0.4572 0.4572)
			(layers "F.Cu" "F.Mask" "F.Paste")
			(net "GND")
		)
		(pad "AN10" smd circle
			(at -14.249908 7.599934)
			(size 0.4572 0.4572)
			(layers "F.Cu" "F.Mask" "F.Paste")
			(net "GND")
		)
		(pad "AN11" smd circle
			(at -13.299948 7.599934)
			(size 0.4572 0.4572)
			(layers "F.Cu" "F.Mask" "F.Paste")
			(net "GND")
		)
		(pad "AN12" smd circle
			(at -12.349988 7.599934)
			(size 0.4572 0.4572)
			(layers "F.Cu" "F.Mask" "F.Paste")
			(net "GND")
		)
		(pad "AN13" smd circle
			(at -11.400028 7.599934)
			(size 0.4572 0.4572)
			(layers "F.Cu" "F.Mask" "F.Paste")
			(net "GND")
		)
		(pad "AN14" smd circle
			(at -10.450068 7.599934)
			(size 0.4572 0.4572)
			(layers "F.Cu" "F.Mask" "F.Paste")
			(net "Net_505")
		)
		(pad "AN15" smd circle
			(at -9.500108 7.599934)
			(size 0.4572 0.4572)
			(layers "F.Cu" "F.Mask" "F.Paste")
			(net "GND")
		)
		(pad "AN16" smd circle
			(at -8.549894 7.599934)
			(size 0.4572 0.4572)
			(layers "F.Cu" "F.Mask" "F.Paste")
			(net "GND")
		)
		(pad "AN17" smd circle
			(at -7.599934 7.599934)
			(size 0.4572 0.4572)
			(layers "F.Cu" "F.Mask" "F.Paste")
			(net "GND")
		)
		(pad "AN18" smd circle
			(at -6.649974 7.599934)
			(size 0.4572 0.4572)
			(layers "F.Cu" "F.Mask" "F.Paste")
			(net "GND")
		)
		(pad "AN19" smd circle
			(at -5.700014 7.599934)
			(size 0.4572 0.4572)
			(layers "F.Cu" "F.Mask" "F.Paste")
			(net "GND")
		)
		(pad "AN20" smd circle
			(at -4.750054 7.599934)
			(size 0.4572 0.4572)
			(layers "F.Cu" "F.Mask" "F.Paste")
			(net "GND")
		)
		(pad "AN21" smd circle
			(at -3.800094 7.599934)
			(size 0.4572 0.4572)
			(layers "F.Cu" "F.Mask" "F.Paste")
			(net "GND")
		)
		(pad "AN22" smd circle
			(at -2.84988 7.599934)
			(size 0.4572 0.4572)
			(layers "F.Cu" "F.Mask" "F.Paste")
			(net "GND")
		)
		(pad "AN23" smd circle
			(at -1.89992 7.599934)
			(size 0.4572 0.4572)
			(layers "F.Cu" "F.Mask" "F.Paste")
			(net "GND")
		)
		(pad "AN24" smd circle
			(at -0.94996 7.599934)
			(size 0.4572 0.4572)
			(layers "F.Cu" "F.Mask" "F.Paste")
			(net "GND")
		)
		(pad "AN25" smd circle
			(at 0 7.599934)
			(size 0.4572 0.4572)
			(layers "F.Cu" "F.Mask" "F.Paste")
			(net "GND")
		)
		(pad "AN26" smd circle
			(at 0.94996 7.599934)
			(size 0.4572 0.4572)
			(layers "F.Cu" "F.Mask" "F.Paste")
			(net "GND")
		)
		(pad "AN27" smd circle
			(at 1.89992 7.599934)
			(size 0.4572 0.4572)
			(layers "F.Cu" "F.Mask" "F.Paste")
			(net "GND")
		)
		(pad "AN28" smd circle
			(at 2.84988 7.599934)
			(size 0.4572 0.4572)
			(layers "F.Cu" "F.Mask" "F.Paste")
			(net "GND")
		)
		(pad "AN29" smd circle
			(at 3.800094 7.599934)
			(size 0.4572 0.4572)
			(layers "F.Cu" "F.Mask" "F.Paste")
			(net "GND")
		)
		(pad "AN30" smd circle
			(at 4.750054 7.599934)
			(size 0.4572 0.4572)
			(layers "F.Cu" "F.Mask" "F.Paste")
			(net "GND")
		)
		(pad "AN31" smd circle
			(at 5.700014 7.599934)
			(size 0.4572 0.4572)
			(layers "F.Cu" "F.Mask" "F.Paste")
			(net "GND")
		)
		(pad "AN32" smd circle
			(at 6.649974 7.599934)
			(size 0.4572 0.4572)
			(layers "F.Cu" "F.Mask" "F.Paste")
			(net "GND")
		)
		(pad "AN33" smd circle
			(at 7.599934 7.599934)
			(size 0.4572 0.4572)
			(layers "F.Cu" "F.Mask" "F.Paste")
			(net "GND")
		)
		(pad "AN34" smd circle
			(at 8.549894 7.599934)
			(size 0.4572 0.4572)
			(layers "F.Cu" "F.Mask" "F.Paste")
			(net "GND")
		)
		(pad "AN35" smd circle
			(at 9.500108 7.599934)
			(size 0.4572 0.4572)
			(layers "F.Cu" "F.Mask" "F.Paste")
			(net "GND")
		)
		(pad "AN36" smd circle
			(at 10.450068 7.599934)
			(size 0.4572 0.4572)
			(layers "F.Cu" "F.Mask" "F.Paste")
			(net "Net_507")
		)
		(pad "AN37" smd circle
			(at 11.400028 7.599934)
			(size 0.4572 0.4572)
			(layers "F.Cu" "F.Mask" "F.Paste")
			(net "GND")
		)
		(pad "AN38" smd circle
			(at 12.349988 7.599934)
			(size 0.4572 0.4572)
			(layers "F.Cu" "F.Mask" "F.Paste")
			(net "Net_5270")
		)
		(pad "AN39" smd circle
			(at 13.299948 7.599934)
			(size 0.4572 0.4572)
			(layers "F.Cu" "F.Mask" "F.Paste")
			(net "Net_5237")
		)
		(pad "AN40" smd circle
			(at 14.249908 7.599934)
			(size 0.4572 0.4572)
			(layers "F.Cu" "F.Mask" "F.Paste")
			(net "GND")
		)
		(pad "AN41" smd circle
			(at 15.200122 7.599934)
			(size 0.4572 0.4572)
			(layers "F.Cu" "F.Mask" "F.Paste")
			(net "GND")
		)
		(pad "AN42" smd circle
			(at 16.150082 7.599934)
			(size 0.4572 0.4572)
			(layers "F.Cu" "F.Mask" "F.Paste")
			(net "GND")
		)
		(pad "AN43" smd circle
			(at 17.100042 7.599934)
			(size 0.4572 0.4572)
			(layers "F.Cu" "F.Mask" "F.Paste")
			(net "P5E_PEX1_STN0_TX_DP<0>")
		)
		(pad "AN44" smd circle
			(at 18.050002 7.599934)
			(size 0.4572 0.4572)
			(layers "F.Cu" "F.Mask" "F.Paste")
			(net "P5E_PEX1_STN0_TX_DN<0>")
		)
		(pad "AN45" smd circle
			(at 18.999962 7.599934)
			(size 0.4572 0.4572)
			(layers "F.Cu" "F.Mask" "F.Paste")
			(net "GND")
		)
		(pad "AN46" smd circle
			(at 19.949922 7.599934)
			(size 0.4572 0.4572)
			(layers "F.Cu" "F.Mask" "F.Paste")
			(net "P5E_PEX1_STN0_RX_DP<0>")
		)
		(pad "AN47" smd circle
			(at 20.899882 7.599934)
			(size 0.4572 0.4572)
			(layers "F.Cu" "F.Mask" "F.Paste")
			(net "P5E_PEX1_STN0_RX_DN<0>")
		)
		(pad "AN48" smd circle
			(at 21.850096 7.599934)
			(size 0.4572 0.4572)
			(layers "F.Cu" "F.Mask" "F.Paste")
			(net "GND")
		)
		(pad "AN49" smd circle
			(at 22.800056 7.599934)
			(size 0.4572 0.4572)
			(layers "F.Cu" "F.Mask" "F.Paste")
			(net "GND")
		)
		(pad "AP1" smd circle
			(at -22.800056 8.549894)
			(size 0.4572 0.4572)
			(layers "F.Cu" "F.Mask" "F.Paste")
			(net "Net_1382")
		)
		(pad "AP2" smd circle
			(at -21.850096 8.549894)
			(size 0.4572 0.4572)
			(layers "F.Cu" "F.Mask" "F.Paste")
			(net "Net_1370")
		)
		(pad "AP3" smd circle
			(at -20.899882 8.549894)
			(size 0.4572 0.4572)
			(layers "F.Cu" "F.Mask" "F.Paste")
			(net "GND")
		)
		(pad "AP4" smd circle
			(at -19.949922 8.549894)
			(size 0.4572 0.4572)
			(layers "F.Cu" "F.Mask" "F.Paste")
			(net "GND")
		)
		(pad "AP5" smd circle
			(at -18.999962 8.549894)
			(size 0.4572 0.4572)
			(layers "F.Cu" "F.Mask" "F.Paste")
			(net "GND")
		)
		(pad "AP6" smd circle
			(at -18.050002 8.549894)
			(size 0.4572 0.4572)
			(layers "F.Cu" "F.Mask" "F.Paste")
			(net "GND")
		)
		(pad "AP7" smd circle
			(at -17.100042 8.549894)
			(size 0.4572 0.4572)
			(layers "F.Cu" "F.Mask" "F.Paste")
			(net "GND")
		)
		(pad "AP8" smd circle
			(at -16.150082 8.549894)
			(size 0.4572 0.4572)
			(layers "F.Cu" "F.Mask" "F.Paste")
			(net "Net_1638")
		)
		(pad "AP9" smd circle
			(at -15.200122 8.549894)
			(size 0.4572 0.4572)
			(layers "F.Cu" "F.Mask" "F.Paste")
			(net "Net_1670")
		)
		(pad "AP10" smd circle
			(at -14.249908 8.549894)
			(size 0.4572 0.4572)
			(layers "F.Cu" "F.Mask" "F.Paste")
			(net "GND")
		)
		(pad "AP11" smd circle
			(at -13.299948 8.549894)
			(size 0.4572 0.4572)
			(layers "F.Cu" "F.Mask" "F.Paste")
			(net "GND")
		)
		(pad "AP12" smd circle
			(at -12.349988 8.549894)
			(size 0.4572 0.4572)
			(layers "F.Cu" "F.Mask" "F.Paste")
			(net "GND")
		)
		(pad "AP13" smd circle
			(at -11.400028 8.549894)
			(size 0.4572 0.4572)
			(layers "F.Cu" "F.Mask" "F.Paste")
			(net "GND")
		)
		(pad "AP14" smd circle
			(at -10.450068 8.549894)
			(size 0.4572 0.4572)
			(layers "F.Cu" "F.Mask" "F.Paste")
			(net "Net_510")
		)
		(pad "AP15" smd circle
			(at -9.500108 8.549894)
			(size 0.4572 0.4572)
			(layers "F.Cu" "F.Mask" "F.Paste")
			(net "GND")
		)
		(pad "AP16" smd circle
			(at -8.549894 8.549894)
			(size 0.4572 0.4572)
			(layers "F.Cu" "F.Mask" "F.Paste")
			(net "P1V25_SERDES_VDDPLL_PEX1")
		)
		(pad "AP17" smd circle
			(at -7.599934 8.549894)
			(size 0.4572 0.4572)
			(layers "F.Cu" "F.Mask" "F.Paste")
			(net "P1V25_SERDES_VDDPLL_PEX1")
		)
		(pad "AP18" smd circle
			(at -6.649974 8.549894)
			(size 0.4572 0.4572)
			(layers "F.Cu" "F.Mask" "F.Paste")
			(net "P1V25_SERDES_VDDPLL_PEX1")
		)
		(pad "AP19" smd circle
			(at -5.700014 8.549894)
			(size 0.4572 0.4572)
			(layers "F.Cu" "F.Mask" "F.Paste")
			(net "P1V25_SERDES_VDDPLL_PEX1")
		)
		(pad "AP20" smd circle
			(at -4.750054 8.549894)
			(size 0.4572 0.4572)
			(layers "F.Cu" "F.Mask" "F.Paste")
			(net "P1V25_SERDES_VDDPLL_PEX1")
		)
		(pad "AP21" smd circle
			(at -3.800094 8.549894)
			(size 0.4572 0.4572)
			(layers "F.Cu" "F.Mask" "F.Paste")
			(net "P1V25_SERDES_VDDPLL_PEX1")
		)
		(pad "AP22" smd circle
			(at -2.84988 8.549894)
			(size 0.4572 0.4572)
			(layers "F.Cu" "F.Mask" "F.Paste")
			(net "P1V25_SERDES_VDDPLL_PEX1")
		)
		(pad "AP23" smd circle
			(at -1.89992 8.549894)
			(size 0.4572 0.4572)
			(layers "F.Cu" "F.Mask" "F.Paste")
			(net "P1V25_SERDES_VDDPLL_PEX1")
		)
		(pad "AP24" smd circle
			(at -0.94996 8.549894)
			(size 0.4572 0.4572)
			(layers "F.Cu" "F.Mask" "F.Paste")
			(net "P1V25_SERDES_VDDPLL_PEX1")
		)
		(pad "AP25" smd circle
			(at 0 8.549894)
			(size 0.4572 0.4572)
			(layers "F.Cu" "F.Mask" "F.Paste")
			(net "P1V25_SERDES_VDDPLL_PEX1")
		)
		(pad "AP26" smd circle
			(at 0.94996 8.549894)
			(size 0.4572 0.4572)
			(layers "F.Cu" "F.Mask" "F.Paste")
			(net "P1V25_SERDES_VDDPLL_PEX1")
		)
		(pad "AP27" smd circle
			(at 1.89992 8.549894)
			(size 0.4572 0.4572)
			(layers "F.Cu" "F.Mask" "F.Paste")
			(net "P1V25_SERDES_VDDPLL_PEX1")
		)
		(pad "AP28" smd circle
			(at 2.84988 8.549894)
			(size 0.4572 0.4572)
			(layers "F.Cu" "F.Mask" "F.Paste")
			(net "P1V25_SERDES_VDDPLL_PEX1")
		)
		(pad "AP29" smd circle
			(at 3.800094 8.549894)
			(size 0.4572 0.4572)
			(layers "F.Cu" "F.Mask" "F.Paste")
			(net "P1V25_SERDES_VDDPLL_PEX1")
		)
		(pad "AP30" smd circle
			(at 4.750054 8.549894)
			(size 0.4572 0.4572)
			(layers "F.Cu" "F.Mask" "F.Paste")
			(net "P1V25_SERDES_VDDPLL_PEX1")
		)
		(pad "AP31" smd circle
			(at 5.700014 8.549894)
			(size 0.4572 0.4572)
			(layers "F.Cu" "F.Mask" "F.Paste")
			(net "P1V25_SERDES_VDDPLL_PEX1")
		)
		(pad "AP32" smd circle
			(at 6.649974 8.549894)
			(size 0.4572 0.4572)
			(layers "F.Cu" "F.Mask" "F.Paste")
			(net "P1V25_SERDES_VDDPLL_PEX1")
		)
		(pad "AP33" smd circle
			(at 7.599934 8.549894)
			(size 0.4572 0.4572)
			(layers "F.Cu" "F.Mask" "F.Paste")
			(net "P1V25_SERDES_VDDPLL_PEX1")
		)
		(pad "AP34" smd circle
			(at 8.549894 8.549894)
			(size 0.4572 0.4572)
			(layers "F.Cu" "F.Mask" "F.Paste")
			(net "GND")
		)
		(pad "AP35" smd circle
			(at 9.500108 8.549894)
			(size 0.4572 0.4572)
			(layers "F.Cu" "F.Mask" "F.Paste")
			(net "P1V8_VDDA_PEX1")
		)
		(pad "AP36" smd circle
			(at 10.450068 8.549894)
			(size 0.4572 0.4572)
			(layers "F.Cu" "F.Mask" "F.Paste")
			(net "Net_498")
		)
		(pad "AP37" smd circle
			(at 11.400028 8.549894)
			(size 0.4572 0.4572)
			(layers "F.Cu" "F.Mask" "F.Paste")
			(net "GND")
		)
		(pad "AP38" smd circle
			(at 12.349988 8.549894)
			(size 0.4572 0.4572)
			(layers "F.Cu" "F.Mask" "F.Paste")
			(net "Net_5290")
		)
		(pad "AP39" smd circle
			(at 13.299948 8.549894)
			(size 0.4572 0.4572)
			(layers "F.Cu" "F.Mask" "F.Paste")
			(net "Net_5296")
		)
		(pad "AP40" smd circle
			(at 14.249908 8.549894)
			(size 0.4572 0.4572)
			(layers "F.Cu" "F.Mask" "F.Paste")
			(net "GND")
		)
		(pad "AP41" smd circle
			(at 15.200122 8.549894)
			(size 0.4572 0.4572)
			(layers "F.Cu" "F.Mask" "F.Paste")
			(net "P5E_PEX1_STN0_TX_DP<1>")
		)
		(pad "AP42" smd circle
			(at 16.150082 8.549894)
			(size 0.4572 0.4572)
			(layers "F.Cu" "F.Mask" "F.Paste")
			(net "P5E_PEX1_STN0_TX_DN<1>")
		)
		(pad "AP43" smd circle
			(at 17.100042 8.549894)
			(size 0.4572 0.4572)
			(layers "F.Cu" "F.Mask" "F.Paste")
			(net "GND")
		)
		(pad "AP44" smd circle
			(at 18.050002 8.549894)
			(size 0.4572 0.4572)
			(layers "F.Cu" "F.Mask" "F.Paste")
			(net "GND")
		)
		(pad "AP45" smd circle
			(at 18.999962 8.549894)
			(size 0.4572 0.4572)
			(layers "F.Cu" "F.Mask" "F.Paste")
			(net "GND")
		)
		(pad "AP46" smd circle
			(at 19.949922 8.549894)
			(size 0.4572 0.4572)
			(layers "F.Cu" "F.Mask" "F.Paste")
			(net "GND")
		)
		(pad "AP47" smd circle
			(at 20.899882 8.549894)
			(size 0.4572 0.4572)
			(layers "F.Cu" "F.Mask" "F.Paste")
			(net "GND")
		)
		(pad "AP48" smd circle
			(at 21.850096 8.549894)
			(size 0.4572 0.4572)
			(layers "F.Cu" "F.Mask" "F.Paste")
			(net "P5E_PEX1_STN0_RX_DP<1>")
		)
		(pad "AP49" smd circle
			(at 22.800056 8.549894)
			(size 0.4572 0.4572)
			(layers "F.Cu" "F.Mask" "F.Paste")
			(net "P5E_PEX1_STN0_RX_DN<1>")
		)
		(pad "AR1" smd circle
			(at -22.800056 9.500108)
			(size 0.4572 0.4572)
			(layers "F.Cu" "F.Mask" "F.Paste")
			(net "GND")
		)
		(pad "AR2" smd circle
			(at -21.850096 9.500108)
			(size 0.4572 0.4572)
			(layers "F.Cu" "F.Mask" "F.Paste")
			(net "GND")
		)
		(pad "AR3" smd circle
			(at -20.899882 9.500108)
			(size 0.4572 0.4572)
			(layers "F.Cu" "F.Mask" "F.Paste")
			(net "Net_1709")
		)
		(pad "AR4" smd circle
			(at -19.949922 9.500108)
			(size 0.4572 0.4572)
			(layers "F.Cu" "F.Mask" "F.Paste")
			(net "Net_1712")
		)
		(pad "AR5" smd circle
			(at -18.999962 9.500108)
			(size 0.4572 0.4572)
			(layers "F.Cu" "F.Mask" "F.Paste")
			(net "GND")
		)
		(pad "AR6" smd circle
			(at -18.050002 9.500108)
			(size 0.4572 0.4572)
			(layers "F.Cu" "F.Mask" "F.Paste")
			(net "Net_1649")
		)
		(pad "AR7" smd circle
			(at -17.100042 9.500108)
			(size 0.4572 0.4572)
			(layers "F.Cu" "F.Mask" "F.Paste")
			(net "Net_1674")
		)
		(pad "AR8" smd circle
			(at -16.150082 9.500108)
			(size 0.4572 0.4572)
			(layers "F.Cu" "F.Mask" "F.Paste")
			(net "GND")
		)
		(pad "AR9" smd circle
			(at -15.200122 9.500108)
			(size 0.4572 0.4572)
			(layers "F.Cu" "F.Mask" "F.Paste")
			(net "GND")
		)
		(pad "AR10" smd circle
			(at -14.249908 9.500108)
			(size 0.4572 0.4572)
			(layers "F.Cu" "F.Mask" "F.Paste")
			(net "GND")
		)
		(pad "AR11" smd circle
			(at -13.299948 9.500108)
			(size 0.4572 0.4572)
			(layers "F.Cu" "F.Mask" "F.Paste")
			(net "GND")
		)
		(pad "AR12" smd circle
			(at -12.349988 9.500108)
			(size 0.4572 0.4572)
			(layers "F.Cu" "F.Mask" "F.Paste")
			(net "GND")
		)
		(pad "AR13" smd circle
			(at -11.400028 9.500108)
			(size 0.4572 0.4572)
			(layers "F.Cu" "F.Mask" "F.Paste")
			(net "GND")
		)
		(pad "AR14" smd circle
			(at -10.450068 9.500108)
			(size 0.4572 0.4572)
			(layers "F.Cu" "F.Mask" "F.Paste")
			(net "GND")
		)
		(pad "AR15" smd circle
			(at -9.500108 9.500108)
			(size 0.4572 0.4572)
			(layers "F.Cu" "F.Mask" "F.Paste")
			(net "GND")
		)
		(pad "AR16" smd circle
			(at -8.549894 9.500108)
			(size 0.4572 0.4572)
			(layers "F.Cu" "F.Mask" "F.Paste")
			(net "GND")
		)
		(pad "AR17" smd circle
			(at -7.599934 9.500108)
			(size 0.4572 0.4572)
			(layers "F.Cu" "F.Mask" "F.Paste")
			(net "GND")
		)
		(pad "AR18" smd circle
			(at -6.649974 9.500108)
			(size 0.4572 0.4572)
			(layers "F.Cu" "F.Mask" "F.Paste")
			(net "GND")
		)
		(pad "AR19" smd circle
			(at -5.700014 9.500108)
			(size 0.4572 0.4572)
			(layers "F.Cu" "F.Mask" "F.Paste")
			(net "GND")
		)
		(pad "AR20" smd circle
			(at -4.750054 9.500108)
			(size 0.4572 0.4572)
			(layers "F.Cu" "F.Mask" "F.Paste")
			(net "GND")
		)
		(pad "AR21" smd circle
			(at -3.800094 9.500108)
			(size 0.4572 0.4572)
			(layers "F.Cu" "F.Mask" "F.Paste")
			(net "GND")
		)
		(pad "AR22" smd circle
			(at -2.84988 9.500108)
			(size 0.4572 0.4572)
			(layers "F.Cu" "F.Mask" "F.Paste")
			(net "GND")
		)
		(pad "AR23" smd circle
			(at -1.89992 9.500108)
			(size 0.4572 0.4572)
			(layers "F.Cu" "F.Mask" "F.Paste")
			(net "GND")
		)
		(pad "AR24" smd circle
			(at -0.94996 9.500108)
			(size 0.4572 0.4572)
			(layers "F.Cu" "F.Mask" "F.Paste")
			(net "GND")
		)
		(pad "AR25" smd circle
			(at 0 9.500108)
			(size 0.4572 0.4572)
			(layers "F.Cu" "F.Mask" "F.Paste")
			(net "GND")
		)
		(pad "AR26" smd circle
			(at 0.94996 9.500108)
			(size 0.4572 0.4572)
			(layers "F.Cu" "F.Mask" "F.Paste")
			(net "GND")
		)
		(pad "AR27" smd circle
			(at 1.89992 9.500108)
			(size 0.4572 0.4572)
			(layers "F.Cu" "F.Mask" "F.Paste")
			(net "GND")
		)
		(pad "AR28" smd circle
			(at 2.84988 9.500108)
			(size 0.4572 0.4572)
			(layers "F.Cu" "F.Mask" "F.Paste")
			(net "GND")
		)
		(pad "AR29" smd circle
			(at 3.800094 9.500108)
			(size 0.4572 0.4572)
			(layers "F.Cu" "F.Mask" "F.Paste")
			(net "GND")
		)
		(pad "AR30" smd circle
			(at 4.750054 9.500108)
			(size 0.4572 0.4572)
			(layers "F.Cu" "F.Mask" "F.Paste")
			(net "GND")
		)
		(pad "AR31" smd circle
			(at 5.700014 9.500108)
			(size 0.4572 0.4572)
			(layers "F.Cu" "F.Mask" "F.Paste")
			(net "GND")
		)
		(pad "AR32" smd circle
			(at 6.649974 9.500108)
			(size 0.4572 0.4572)
			(layers "F.Cu" "F.Mask" "F.Paste")
			(net "GND")
		)
		(pad "AR33" smd circle
			(at 7.599934 9.500108)
			(size 0.4572 0.4572)
			(layers "F.Cu" "F.Mask" "F.Paste")
			(net "GND")
		)
		(pad "AR34" smd circle
			(at 8.549894 9.500108)
			(size 0.4572 0.4572)
			(layers "F.Cu" "F.Mask" "F.Paste")
			(net "GND")
		)
		(pad "AR35" smd circle
			(at 9.500108 9.500108)
			(size 0.4572 0.4572)
			(layers "F.Cu" "F.Mask" "F.Paste")
			(net "GND")
		)
		(pad "AR36" smd circle
			(at 10.450068 9.500108)
			(size 0.4572 0.4572)
			(layers "F.Cu" "F.Mask" "F.Paste")
			(net "Net_500")
		)
		(pad "AR37" smd circle
			(at 11.400028 9.500108)
			(size 0.4572 0.4572)
			(layers "F.Cu" "F.Mask" "F.Paste")
			(net "GND")
		)
		(pad "AR38" smd circle
			(at 12.349988 9.500108)
			(size 0.4572 0.4572)
			(layers "F.Cu" "F.Mask" "F.Paste")
			(net "Net_5295")
		)
		(pad "AR39" smd circle
			(at 13.299948 9.500108)
			(size 0.4572 0.4572)
			(layers "F.Cu" "F.Mask" "F.Paste")
			(net "Net_5297")
		)
		(pad "AR40" smd circle
			(at 14.249908 9.500108)
			(size 0.4572 0.4572)
			(layers "F.Cu" "F.Mask" "F.Paste")
			(net "GND")
		)
		(pad "AR41" smd circle
			(at 15.200122 9.500108)
			(size 0.4572 0.4572)
			(layers "F.Cu" "F.Mask" "F.Paste")
			(net "GND")
		)
		(pad "AR42" smd circle
			(at 16.150082 9.500108)
			(size 0.4572 0.4572)
			(layers "F.Cu" "F.Mask" "F.Paste")
			(net "GND")
		)
		(pad "AR43" smd circle
			(at 17.100042 9.500108)
			(size 0.4572 0.4572)
			(layers "F.Cu" "F.Mask" "F.Paste")
			(net "P5E_PEX1_STN0_TX_DP<2>")
		)
		(pad "AR44" smd circle
			(at 18.050002 9.500108)
			(size 0.4572 0.4572)
			(layers "F.Cu" "F.Mask" "F.Paste")
			(net "P5E_PEX1_STN0_TX_DN<2>")
		)
		(pad "AR45" smd circle
			(at 18.999962 9.500108)
			(size 0.4572 0.4572)
			(layers "F.Cu" "F.Mask" "F.Paste")
			(net "GND")
		)
		(pad "AR46" smd circle
			(at 19.949922 9.500108)
			(size 0.4572 0.4572)
			(layers "F.Cu" "F.Mask" "F.Paste")
			(net "P5E_PEX1_STN0_RX_DP<2>")
		)
		(pad "AR47" smd circle
			(at 20.899882 9.500108)
			(size 0.4572 0.4572)
			(layers "F.Cu" "F.Mask" "F.Paste")
			(net "P5E_PEX1_STN0_RX_DN<2>")
		)
		(pad "AR48" smd circle
			(at 21.850096 9.500108)
			(size 0.4572 0.4572)
			(layers "F.Cu" "F.Mask" "F.Paste")
			(net "GND")
		)
		(pad "AR49" smd circle
			(at 22.800056 9.500108)
			(size 0.4572 0.4572)
			(layers "F.Cu" "F.Mask" "F.Paste")
			(net "GND")
		)
		(pad "AT1" smd circle
			(at -22.800056 10.450068)
			(size 0.4572 0.4572)
			(layers "F.Cu" "F.Mask" "F.Paste")
			(net "Net_1422")
		)
		(pad "AT2" smd circle
			(at -21.850096 10.450068)
			(size 0.4572 0.4572)
			(layers "F.Cu" "F.Mask" "F.Paste")
			(net "Net_1711")
		)
		(pad "AT3" smd circle
			(at -20.899882 10.450068)
			(size 0.4572 0.4572)
			(layers "F.Cu" "F.Mask" "F.Paste")
			(net "GND")
		)
		(pad "AT4" smd circle
			(at -19.949922 10.450068)
			(size 0.4572 0.4572)
			(layers "F.Cu" "F.Mask" "F.Paste")
			(net "GND")
		)
		(pad "AT5" smd circle
			(at -18.999962 10.450068)
			(size 0.4572 0.4572)
			(layers "F.Cu" "F.Mask" "F.Paste")
			(net "GND")
		)
		(pad "AT6" smd circle
			(at -18.050002 10.450068)
			(size 0.4572 0.4572)
			(layers "F.Cu" "F.Mask" "F.Paste")
			(net "GND")
		)
		(pad "AT7" smd circle
			(at -17.100042 10.450068)
			(size 0.4572 0.4572)
			(layers "F.Cu" "F.Mask" "F.Paste")
			(net "GND")
		)
		(pad "AT8" smd circle
			(at -16.150082 10.450068)
			(size 0.4572 0.4572)
			(layers "F.Cu" "F.Mask" "F.Paste")
			(net "Net_1660")
		)
		(pad "AT9" smd circle
			(at -15.200122 10.450068)
			(size 0.4572 0.4572)
			(layers "F.Cu" "F.Mask" "F.Paste")
			(net "Net_1655")
		)
		(pad "AT10" smd circle
			(at -14.249908 10.450068)
			(size 0.4572 0.4572)
			(layers "F.Cu" "F.Mask" "F.Paste")
			(net "GND")
		)
		(pad "AT11" smd circle
			(at -13.299948 10.450068)
			(size 0.4572 0.4572)
			(layers "F.Cu" "F.Mask" "F.Paste")
			(net "GND")
		)
		(pad "AT12" smd circle
			(at -12.349988 10.450068)
			(size 0.4572 0.4572)
			(layers "F.Cu" "F.Mask" "F.Paste")
			(net "GND")
		)
		(pad "AT13" smd circle
			(at -11.400028 10.450068)
			(size 0.4572 0.4572)
			(layers "F.Cu" "F.Mask" "F.Paste")
			(net "GND")
		)
		(pad "AT14" smd circle
			(at -10.450068 10.450068)
			(size 0.4572 0.4572)
			(layers "F.Cu" "F.Mask" "F.Paste")
			(net "GND")
		)
		(pad "AT15" smd circle
			(at -9.500108 10.450068)
			(size 0.4572 0.4572)
			(layers "F.Cu" "F.Mask" "F.Paste")
			(net "GND")
		)
		(pad "AT16" smd circle
			(at -8.549894 10.450068)
			(size 0.4572 0.4572)
			(layers "F.Cu" "F.Mask" "F.Paste")
			(net "GND")
		)
		(pad "AT17" smd circle
			(at -7.599934 10.450068)
			(size 0.4572 0.4572)
			(layers "F.Cu" "F.Mask" "F.Paste")
			(net "GND")
		)
		(pad "AT18" smd circle
			(at -6.649974 10.450068)
			(size 0.4572 0.4572)
			(layers "F.Cu" "F.Mask" "F.Paste")
			(net "GND")
		)
		(pad "AT19" smd circle
			(at -5.700014 10.450068)
			(size 0.4572 0.4572)
			(layers "F.Cu" "F.Mask" "F.Paste")
			(net "GND")
		)
		(pad "AT20" smd circle
			(at -4.750054 10.450068)
			(size 0.4572 0.4572)
			(layers "F.Cu" "F.Mask" "F.Paste")
			(net "GND")
		)
		(pad "AT21" smd circle
			(at -3.800094 10.450068)
			(size 0.4572 0.4572)
			(layers "F.Cu" "F.Mask" "F.Paste")
			(net "GND")
		)
		(pad "AT22" smd circle
			(at -2.84988 10.450068)
			(size 0.4572 0.4572)
			(layers "F.Cu" "F.Mask" "F.Paste")
			(net "GND")
		)
		(pad "AT23" smd circle
			(at -1.89992 10.450068)
			(size 0.4572 0.4572)
			(layers "F.Cu" "F.Mask" "F.Paste")
			(net "GND")
		)
		(pad "AT24" smd circle
			(at -0.94996 10.450068)
			(size 0.4572 0.4572)
			(layers "F.Cu" "F.Mask" "F.Paste")
			(net "GND")
		)
		(pad "AT25" smd circle
			(at 0 10.450068)
			(size 0.4572 0.4572)
			(layers "F.Cu" "F.Mask" "F.Paste")
			(net "GND")
		)
		(pad "AT26" smd circle
			(at 0.94996 10.450068)
			(size 0.4572 0.4572)
			(layers "F.Cu" "F.Mask" "F.Paste")
			(net "GND")
		)
		(pad "AT27" smd circle
			(at 1.89992 10.450068)
			(size 0.4572 0.4572)
			(layers "F.Cu" "F.Mask" "F.Paste")
			(net "GND")
		)
		(pad "AT28" smd circle
			(at 2.84988 10.450068)
			(size 0.4572 0.4572)
			(layers "F.Cu" "F.Mask" "F.Paste")
			(net "GND")
		)
		(pad "AT29" smd circle
			(at 3.800094 10.450068)
			(size 0.4572 0.4572)
			(layers "F.Cu" "F.Mask" "F.Paste")
			(net "GND")
		)
		(pad "AT30" smd circle
			(at 4.750054 10.450068)
			(size 0.4572 0.4572)
			(layers "F.Cu" "F.Mask" "F.Paste")
			(net "GND")
		)
		(pad "AT31" smd circle
			(at 5.700014 10.450068)
			(size 0.4572 0.4572)
			(layers "F.Cu" "F.Mask" "F.Paste")
			(net "GND")
		)
		(pad "AT32" smd circle
			(at 6.649974 10.450068)
			(size 0.4572 0.4572)
			(layers "F.Cu" "F.Mask" "F.Paste")
			(net "GND")
		)
		(pad "AT33" smd circle
			(at 7.599934 10.450068)
			(size 0.4572 0.4572)
			(layers "F.Cu" "F.Mask" "F.Paste")
			(net "GND")
		)
		(pad "AT34" smd circle
			(at 8.549894 10.450068)
			(size 0.4572 0.4572)
			(layers "F.Cu" "F.Mask" "F.Paste")
			(net "GND")
		)
		(pad "AT35" smd circle
			(at 9.500108 10.450068)
			(size 0.4572 0.4572)
			(layers "F.Cu" "F.Mask" "F.Paste")
			(net "GND")
		)
		(pad "AT36" smd circle
			(at 10.450068 10.450068)
			(size 0.4572 0.4572)
			(layers "F.Cu" "F.Mask" "F.Paste")
			(net "Net_503")
		)
		(pad "AT37" smd circle
			(at 11.400028 10.450068)
			(size 0.4572 0.4572)
			(layers "F.Cu" "F.Mask" "F.Paste")
			(net "GND")
		)
		(pad "AT38" smd circle
			(at 12.349988 10.450068)
			(size 0.4572 0.4572)
			(layers "F.Cu" "F.Mask" "F.Paste")
			(net "Net_5261")
		)
		(pad "AT39" smd circle
			(at 13.299948 10.450068)
			(size 0.4572 0.4572)
			(layers "F.Cu" "F.Mask" "F.Paste")
			(net "Net_5246")
		)
		(pad "AT40" smd circle
			(at 14.249908 10.450068)
			(size 0.4572 0.4572)
			(layers "F.Cu" "F.Mask" "F.Paste")
			(net "GND")
		)
		(pad "AT41" smd circle
			(at 15.200122 10.450068)
			(size 0.4572 0.4572)
			(layers "F.Cu" "F.Mask" "F.Paste")
			(net "P5E_PEX1_STN0_TX_DP<3>")
		)
		(pad "AT42" smd circle
			(at 16.150082 10.450068)
			(size 0.4572 0.4572)
			(layers "F.Cu" "F.Mask" "F.Paste")
			(net "P5E_PEX1_STN0_TX_DN<3>")
		)
		(pad "AT43" smd circle
			(at 17.100042 10.450068)
			(size 0.4572 0.4572)
			(layers "F.Cu" "F.Mask" "F.Paste")
			(net "GND")
		)
		(pad "AT44" smd circle
			(at 18.050002 10.450068)
			(size 0.4572 0.4572)
			(layers "F.Cu" "F.Mask" "F.Paste")
			(net "GND")
		)
		(pad "AT45" smd circle
			(at 18.999962 10.450068)
			(size 0.4572 0.4572)
			(layers "F.Cu" "F.Mask" "F.Paste")
			(net "GND")
		)
		(pad "AT46" smd circle
			(at 19.949922 10.450068)
			(size 0.4572 0.4572)
			(layers "F.Cu" "F.Mask" "F.Paste")
			(net "GND")
		)
		(pad "AT47" smd circle
			(at 20.899882 10.450068)
			(size 0.4572 0.4572)
			(layers "F.Cu" "F.Mask" "F.Paste")
			(net "GND")
		)
		(pad "AT48" smd circle
			(at 21.850096 10.450068)
			(size 0.4572 0.4572)
			(layers "F.Cu" "F.Mask" "F.Paste")
			(net "P5E_PEX1_STN0_RX_DP<3>")
		)
		(pad "AT49" smd circle
			(at 22.800056 10.450068)
			(size 0.4572 0.4572)
			(layers "F.Cu" "F.Mask" "F.Paste")
			(net "P5E_PEX1_STN0_RX_DN<3>")
		)
		(pad "AU1" smd circle
			(at -22.800056 11.400028)
			(size 0.4572 0.4572)
			(layers "F.Cu" "F.Mask" "F.Paste")
			(net "GND")
		)
		(pad "AU2" smd circle
			(at -21.850096 11.400028)
			(size 0.4572 0.4572)
			(layers "F.Cu" "F.Mask" "F.Paste")
			(net "GND")
		)
		(pad "AU3" smd circle
			(at -20.899882 11.400028)
			(size 0.4572 0.4572)
			(layers "F.Cu" "F.Mask" "F.Paste")
			(net "Net_1734")
		)
		(pad "AU4" smd circle
			(at -19.949922 11.400028)
			(size 0.4572 0.4572)
			(layers "F.Cu" "F.Mask" "F.Paste")
			(net "Net_1737")
		)
		(pad "AU5" smd circle
			(at -18.999962 11.400028)
			(size 0.4572 0.4572)
			(layers "F.Cu" "F.Mask" "F.Paste")
			(net "GND")
		)
		(pad "AU6" smd circle
			(at -18.050002 11.400028)
			(size 0.4572 0.4572)
			(layers "F.Cu" "F.Mask" "F.Paste")
			(net "Net_1678")
		)
		(pad "AU7" smd circle
			(at -17.100042 11.400028)
			(size 0.4572 0.4572)
			(layers "F.Cu" "F.Mask" "F.Paste")
			(net "Net_1643")
		)
		(pad "AU8" smd circle
			(at -16.150082 11.400028)
			(size 0.4572 0.4572)
			(layers "F.Cu" "F.Mask" "F.Paste")
			(net "GND")
		)
		(pad "AU9" smd circle
			(at -15.200122 11.400028)
			(size 0.4572 0.4572)
			(layers "F.Cu" "F.Mask" "F.Paste")
			(net "GND")
		)
		(pad "AU10" smd circle
			(at -14.249908 11.400028)
			(size 0.4572 0.4572)
			(layers "F.Cu" "F.Mask" "F.Paste")
			(net "GND")
		)
		(pad "AU11" smd circle
			(at -13.299948 11.400028)
			(size 0.4572 0.4572)
			(layers "F.Cu" "F.Mask" "F.Paste")
			(net "GND")
		)
		(pad "AU12" smd circle
			(at -12.349988 11.400028)
			(size 0.4572 0.4572)
			(layers "F.Cu" "F.Mask" "F.Paste")
			(net "GND")
		)
		(pad "AU13" smd circle
			(at -11.400028 11.400028)
			(size 0.4572 0.4572)
			(layers "F.Cu" "F.Mask" "F.Paste")
			(net "GND")
		)
		(pad "AU14" smd circle
			(at -10.450068 11.400028)
			(size 0.4572 0.4572)
			(layers "F.Cu" "F.Mask" "F.Paste")
			(net "GND")
		)
		(pad "AU15" smd circle
			(at -9.500108 11.400028)
			(size 0.4572 0.4572)
			(layers "F.Cu" "F.Mask" "F.Paste")
			(net "GND")
		)
		(pad "AU16" smd circle
			(at -8.549894 11.400028)
			(size 0.4572 0.4572)
			(layers "F.Cu" "F.Mask" "F.Paste")
			(net "GND")
		)
		(pad "AU17" smd circle
			(at -7.599934 11.400028)
			(size 0.4572 0.4572)
			(layers "F.Cu" "F.Mask" "F.Paste")
			(net "GND")
		)
		(pad "AU18" smd circle
			(at -6.649974 11.400028)
			(size 0.4572 0.4572)
			(layers "F.Cu" "F.Mask" "F.Paste")
			(net "GND")
		)
		(pad "AU19" smd circle
			(at -5.700014 11.400028)
			(size 0.4572 0.4572)
			(layers "F.Cu" "F.Mask" "F.Paste")
			(net "GND")
		)
		(pad "AU20" smd circle
			(at -4.750054 11.400028)
			(size 0.4572 0.4572)
			(layers "F.Cu" "F.Mask" "F.Paste")
			(net "GND")
		)
		(pad "AU21" smd circle
			(at -3.800094 11.400028)
			(size 0.4572 0.4572)
			(layers "F.Cu" "F.Mask" "F.Paste")
			(net "GND")
		)
		(pad "AU22" smd circle
			(at -2.84988 11.400028)
			(size 0.4572 0.4572)
			(layers "F.Cu" "F.Mask" "F.Paste")
			(net "GND")
		)
		(pad "AU23" smd circle
			(at -1.89992 11.400028)
			(size 0.4572 0.4572)
			(layers "F.Cu" "F.Mask" "F.Paste")
			(net "GND")
		)
		(pad "AU24" smd circle
			(at -0.94996 11.400028)
			(size 0.4572 0.4572)
			(layers "F.Cu" "F.Mask" "F.Paste")
			(net "GND")
		)
		(pad "AU25" smd circle
			(at 0 11.400028)
			(size 0.4572 0.4572)
			(layers "F.Cu" "F.Mask" "F.Paste")
			(net "GND")
		)
		(pad "AU26" smd circle
			(at 0.94996 11.400028)
			(size 0.4572 0.4572)
			(layers "F.Cu" "F.Mask" "F.Paste")
			(net "GND")
		)
		(pad "AU27" smd circle
			(at 1.89992 11.400028)
			(size 0.4572 0.4572)
			(layers "F.Cu" "F.Mask" "F.Paste")
			(net "GND")
		)
		(pad "AU28" smd circle
			(at 2.84988 11.400028)
			(size 0.4572 0.4572)
			(layers "F.Cu" "F.Mask" "F.Paste")
			(net "GND")
		)
		(pad "AU29" smd circle
			(at 3.800094 11.400028)
			(size 0.4572 0.4572)
			(layers "F.Cu" "F.Mask" "F.Paste")
			(net "GND")
		)
		(pad "AU30" smd circle
			(at 4.750054 11.400028)
			(size 0.4572 0.4572)
			(layers "F.Cu" "F.Mask" "F.Paste")
			(net "GND")
		)
		(pad "AU31" smd circle
			(at 5.700014 11.400028)
			(size 0.4572 0.4572)
			(layers "F.Cu" "F.Mask" "F.Paste")
			(net "GND")
		)
		(pad "AU32" smd circle
			(at 6.649974 11.400028)
			(size 0.4572 0.4572)
			(layers "F.Cu" "F.Mask" "F.Paste")
			(net "GND")
		)
		(pad "AU33" smd circle
			(at 7.599934 11.400028)
			(size 0.4572 0.4572)
			(layers "F.Cu" "F.Mask" "F.Paste")
			(net "GND")
		)
		(pad "AU34" smd circle
			(at 8.549894 11.400028)
			(size 0.4572 0.4572)
			(layers "F.Cu" "F.Mask" "F.Paste")
			(net "GND")
		)
		(pad "AU35" smd circle
			(at 9.500108 11.400028)
			(size 0.4572 0.4572)
			(layers "F.Cu" "F.Mask" "F.Paste")
			(net "GND")
		)
		(pad "AU36" smd circle
			(at 10.450068 11.400028)
			(size 0.4572 0.4572)
			(layers "F.Cu" "F.Mask" "F.Paste")
			(net "GND")
		)
		(pad "AU37" smd circle
			(at 11.400028 11.400028)
			(size 0.4572 0.4572)
			(layers "F.Cu" "F.Mask" "F.Paste")
			(net "GND")
		)
		(pad "AU38" smd circle
			(at 12.349988 11.400028)
			(size 0.4572 0.4572)
			(layers "F.Cu" "F.Mask" "F.Paste")
			(net "Net_5268")
		)
		(pad "AU39" smd circle
			(at 13.299948 11.400028)
			(size 0.4572 0.4572)
			(layers "F.Cu" "F.Mask" "F.Paste")
			(net "Net_5240")
		)
		(pad "AU40" smd circle
			(at 14.249908 11.400028)
			(size 0.4572 0.4572)
			(layers "F.Cu" "F.Mask" "F.Paste")
			(net "GND")
		)
		(pad "AU41" smd circle
			(at 15.200122 11.400028)
			(size 0.4572 0.4572)
			(layers "F.Cu" "F.Mask" "F.Paste")
			(net "GND")
		)
		(pad "AU42" smd circle
			(at 16.150082 11.400028)
			(size 0.4572 0.4572)
			(layers "F.Cu" "F.Mask" "F.Paste")
			(net "GND")
		)
		(pad "AU43" smd circle
			(at 17.100042 11.400028)
			(size 0.4572 0.4572)
			(layers "F.Cu" "F.Mask" "F.Paste")
			(net "P5E_PEX1_STN0_TX_DP<4>")
		)
		(pad "AU44" smd circle
			(at 18.050002 11.400028)
			(size 0.4572 0.4572)
			(layers "F.Cu" "F.Mask" "F.Paste")
			(net "P5E_PEX1_STN0_TX_DN<4>")
		)
		(pad "AU45" smd circle
			(at 18.999962 11.400028)
			(size 0.4572 0.4572)
			(layers "F.Cu" "F.Mask" "F.Paste")
			(net "GND")
		)
		(pad "AU46" smd circle
			(at 19.949922 11.400028)
			(size 0.4572 0.4572)
			(layers "F.Cu" "F.Mask" "F.Paste")
			(net "P5E_PEX1_STN0_RX_DP<4>")
		)
		(pad "AU47" smd circle
			(at 20.899882 11.400028)
			(size 0.4572 0.4572)
			(layers "F.Cu" "F.Mask" "F.Paste")
			(net "P5E_PEX1_STN0_RX_DN<4>")
		)
		(pad "AU48" smd circle
			(at 21.850096 11.400028)
			(size 0.4572 0.4572)
			(layers "F.Cu" "F.Mask" "F.Paste")
			(net "GND")
		)
		(pad "AU49" smd circle
			(at 22.800056 11.400028)
			(size 0.4572 0.4572)
			(layers "F.Cu" "F.Mask" "F.Paste")
			(net "GND")
		)
		(pad "AV1" smd circle
			(at -22.800056 12.349988)
			(size 0.4572 0.4572)
			(layers "F.Cu" "F.Mask" "F.Paste")
			(net "Net_1411")
		)
		(pad "AV2" smd circle
			(at -21.850096 12.349988)
			(size 0.4572 0.4572)
			(layers "F.Cu" "F.Mask" "F.Paste")
			(net "Net_1398")
		)
		(pad "AV3" smd circle
			(at -20.899882 12.349988)
			(size 0.4572 0.4572)
			(layers "F.Cu" "F.Mask" "F.Paste")
			(net "GND")
		)
		(pad "AV4" smd circle
			(at -19.949922 12.349988)
			(size 0.4572 0.4572)
			(layers "F.Cu" "F.Mask" "F.Paste")
			(net "GND")
		)
		(pad "AV5" smd circle
			(at -18.999962 12.349988)
			(size 0.4572 0.4572)
			(layers "F.Cu" "F.Mask" "F.Paste")
			(net "GND")
		)
		(pad "AV6" smd circle
			(at -18.050002 12.349988)
			(size 0.4572 0.4572)
			(layers "F.Cu" "F.Mask" "F.Paste")
			(net "GND")
		)
		(pad "AV7" smd circle
			(at -17.100042 12.349988)
			(size 0.4572 0.4572)
			(layers "F.Cu" "F.Mask" "F.Paste")
			(net "GND")
		)
		(pad "AV8" smd circle
			(at -16.150082 12.349988)
			(size 0.4572 0.4572)
			(layers "F.Cu" "F.Mask" "F.Paste")
			(net "Net_1690")
		)
		(pad "AV9" smd circle
			(at -15.200122 12.349988)
			(size 0.4572 0.4572)
			(layers "F.Cu" "F.Mask" "F.Paste")
			(net "Net_1666")
		)
		(pad "AV10" smd circle
			(at -14.249908 12.349988)
			(size 0.4572 0.4572)
			(layers "F.Cu" "F.Mask" "F.Paste")
			(net "GND")
		)
		(pad "AV11" smd circle
			(at -13.299948 12.349988)
			(size 0.4572 0.4572)
			(layers "F.Cu" "F.Mask" "F.Paste")
			(net "GND")
		)
		(pad "AV12" smd circle
			(at -12.349988 12.349988)
			(size 0.4572 0.4572)
			(layers "F.Cu" "F.Mask" "F.Paste")
			(net "Net_5258")
		)
		(pad "AV13" smd circle
			(at -11.400028 12.349988)
			(size 0.4572 0.4572)
			(layers "F.Cu" "F.Mask" "F.Paste")
			(net "Net_5259")
		)
		(pad "AV14" smd circle
			(at -10.450068 12.349988)
			(size 0.4572 0.4572)
			(layers "F.Cu" "F.Mask" "F.Paste")
			(net "Net_5250")
		)
		(pad "AV15" smd circle
			(at -9.500108 12.349988)
			(size 0.4572 0.4572)
			(layers "F.Cu" "F.Mask" "F.Paste")
			(net "Net_5244")
		)
		(pad "AV16" smd circle
			(at -8.549894 12.349988)
			(size 0.4572 0.4572)
			(layers "F.Cu" "F.Mask" "F.Paste")
			(net "Net_5253")
		)
		(pad "AV17" smd circle
			(at -7.599934 12.349988)
			(size 0.4572 0.4572)
			(layers "F.Cu" "F.Mask" "F.Paste")
			(net "Net_5254")
		)
		(pad "AV18" smd circle
			(at -6.649974 12.349988)
			(size 0.4572 0.4572)
			(layers "F.Cu" "F.Mask" "F.Paste")
			(net "Net_5249")
		)
		(pad "AV19" smd circle
			(at -5.700014 12.349988)
			(size 0.4572 0.4572)
			(layers "F.Cu" "F.Mask" "F.Paste")
			(net "Net_5245")
		)
		(pad "AV20" smd circle
			(at -4.750054 12.349988)
			(size 0.4572 0.4572)
			(layers "F.Cu" "F.Mask" "F.Paste")
			(net "GND")
		)
		(pad "AV21" smd circle
			(at -3.800094 12.349988)
			(size 0.4572 0.4572)
			(layers "F.Cu" "F.Mask" "F.Paste")
			(net "Net_5284")
		)
		(pad "AV22" smd circle
			(at -2.84988 12.349988)
			(size 0.4572 0.4572)
			(layers "F.Cu" "F.Mask" "F.Paste")
			(net "Net_5285")
		)
		(pad "AV23" smd circle
			(at -1.89992 12.349988)
			(size 0.4572 0.4572)
			(layers "F.Cu" "F.Mask" "F.Paste")
			(net "Net_5287")
		)
		(pad "AV24" smd circle
			(at -0.94996 12.349988)
			(size 0.4572 0.4572)
			(layers "F.Cu" "F.Mask" "F.Paste")
			(net "GND")
		)
		(pad "AV25" smd circle
			(at 0 12.349988)
			(size 0.4572 0.4572)
			(layers "F.Cu" "F.Mask" "F.Paste")
			(net "PEX1_MODE_SEL2")
		)
		(pad "AV26" smd circle
			(at 0.94996 12.349988)
			(size 0.4572 0.4572)
			(layers "F.Cu" "F.Mask" "F.Paste")
			(net "PEX1_MODE_SEL7")
		)
		(pad "AV27" smd circle
			(at 1.89992 12.349988)
			(size 0.4572 0.4572)
			(layers "F.Cu" "F.Mask" "F.Paste")
			(net "PEX1_MODE_SEL3")
		)
		(pad "AV28" smd circle
			(at 2.84988 12.349988)
			(size 0.4572 0.4572)
			(layers "F.Cu" "F.Mask" "F.Paste")
			(net "PEX1_MODE_SEL9")
		)
		(pad "AV29" smd circle
			(at 3.800094 12.349988)
			(size 0.4572 0.4572)
			(layers "F.Cu" "F.Mask" "F.Paste")
			(net "PEX1_PCA9555_INT_R_N")
		)
		(pad "AV30" smd circle
			(at 4.750054 12.349988)
			(size 0.4572 0.4572)
			(layers "F.Cu" "F.Mask" "F.Paste")
			(net "PEX1_SYS_ERR_N")
		)
		(pad "AV31" smd circle
			(at 5.700014 12.349988)
			(size 0.4572 0.4572)
			(layers "F.Cu" "F.Mask" "F.Paste")
			(net "PEX1_MODE_SEL6")
		)
		(pad "AV32" smd circle
			(at 6.649974 12.349988)
			(size 0.4572 0.4572)
			(layers "F.Cu" "F.Mask" "F.Paste")
			(net "PEX1_MODE_SEL10")
		)
		(pad "AV33" smd circle
			(at 7.599934 12.349988)
			(size 0.4572 0.4572)
			(layers "F.Cu" "F.Mask" "F.Paste")
			(net "Net_5262")
		)
		(pad "AV34" smd circle
			(at 8.549894 12.349988)
			(size 0.4572 0.4572)
			(layers "F.Cu" "F.Mask" "F.Paste")
			(net "Net_5235")
		)
		(pad "AV35" smd circle
			(at 9.500108 12.349988)
			(size 0.4572 0.4572)
			(layers "F.Cu" "F.Mask" "F.Paste")
			(net "Net_5264")
		)
		(pad "AV36" smd circle
			(at 10.450068 12.349988)
			(size 0.4572 0.4572)
			(layers "F.Cu" "F.Mask" "F.Paste")
			(net "Net_5241")
		)
		(pad "AV37" smd circle
			(at 11.400028 12.349988)
			(size 0.4572 0.4572)
			(layers "F.Cu" "F.Mask" "F.Paste")
			(net "Net_5266")
		)
		(pad "AV38" smd circle
			(at 12.349988 12.349988)
			(size 0.4572 0.4572)
			(layers "F.Cu" "F.Mask" "F.Paste")
			(net "Net_5265")
		)
		(pad "AV39" smd circle
			(at 13.299948 12.349988)
			(size 0.4572 0.4572)
			(layers "F.Cu" "F.Mask" "F.Paste")
			(net "Net_5257")
		)
		(pad "AV40" smd circle
			(at 14.249908 12.349988)
			(size 0.4572 0.4572)
			(layers "F.Cu" "F.Mask" "F.Paste")
			(net "GND")
		)
		(pad "AV41" smd circle
			(at 15.200122 12.349988)
			(size 0.4572 0.4572)
			(layers "F.Cu" "F.Mask" "F.Paste")
			(net "P5E_PEX1_STN0_TX_DP<5>")
		)
		(pad "AV42" smd circle
			(at 16.150082 12.349988)
			(size 0.4572 0.4572)
			(layers "F.Cu" "F.Mask" "F.Paste")
			(net "P5E_PEX1_STN0_TX_DN<5>")
		)
		(pad "AV43" smd circle
			(at 17.100042 12.349988)
			(size 0.4572 0.4572)
			(layers "F.Cu" "F.Mask" "F.Paste")
			(net "GND")
		)
		(pad "AV44" smd circle
			(at 18.050002 12.349988)
			(size 0.4572 0.4572)
			(layers "F.Cu" "F.Mask" "F.Paste")
			(net "GND")
		)
		(pad "AV45" smd circle
			(at 18.999962 12.349988)
			(size 0.4572 0.4572)
			(layers "F.Cu" "F.Mask" "F.Paste")
			(net "GND")
		)
		(pad "AV46" smd circle
			(at 19.949922 12.349988)
			(size 0.4572 0.4572)
			(layers "F.Cu" "F.Mask" "F.Paste")
			(net "GND")
		)
		(pad "AV47" smd circle
			(at 20.899882 12.349988)
			(size 0.4572 0.4572)
			(layers "F.Cu" "F.Mask" "F.Paste")
			(net "GND")
		)
		(pad "AV48" smd circle
			(at 21.850096 12.349988)
			(size 0.4572 0.4572)
			(layers "F.Cu" "F.Mask" "F.Paste")
			(net "P5E_PEX1_STN0_RX_DP<5>")
		)
		(pad "AV49" smd circle
			(at 22.800056 12.349988)
			(size 0.4572 0.4572)
			(layers "F.Cu" "F.Mask" "F.Paste")
			(net "P5E_PEX1_STN0_RX_DN<5>")
		)
		(pad "AW1" smd circle
			(at -22.800056 13.299948)
			(size 0.4572 0.4572)
			(layers "F.Cu" "F.Mask" "F.Paste")
			(net "GND")
		)
		(pad "AW2" smd circle
			(at -21.850096 13.299948)
			(size 0.4572 0.4572)
			(layers "F.Cu" "F.Mask" "F.Paste")
			(net "GND")
		)
		(pad "AW3" smd circle
			(at -20.899882 13.299948)
			(size 0.4572 0.4572)
			(layers "F.Cu" "F.Mask" "F.Paste")
			(net "Net_1363")
		)
		(pad "AW4" smd circle
			(at -19.949922 13.299948)
			(size 0.4572 0.4572)
			(layers "F.Cu" "F.Mask" "F.Paste")
			(net "Net_1706")
		)
		(pad "AW5" smd circle
			(at -18.999962 13.299948)
			(size 0.4572 0.4572)
			(layers "F.Cu" "F.Mask" "F.Paste")
			(net "GND")
		)
		(pad "AW6" smd circle
			(at -18.050002 13.299948)
			(size 0.4572 0.4572)
			(layers "F.Cu" "F.Mask" "F.Paste")
			(net "Net_1668")
		)
		(pad "AW7" smd circle
			(at -17.100042 13.299948)
			(size 0.4572 0.4572)
			(layers "F.Cu" "F.Mask" "F.Paste")
			(net "Net_1688")
		)
		(pad "AW8" smd circle
			(at -16.150082 13.299948)
			(size 0.4572 0.4572)
			(layers "F.Cu" "F.Mask" "F.Paste")
			(net "GND")
		)
		(pad "AW9" smd circle
			(at -15.200122 13.299948)
			(size 0.4572 0.4572)
			(layers "F.Cu" "F.Mask" "F.Paste")
			(net "GND")
		)
		(pad "AW10" smd circle
			(at -14.249908 13.299948)
			(size 0.4572 0.4572)
			(layers "F.Cu" "F.Mask" "F.Paste")
			(net "GND")
		)
		(pad "AW11" smd circle
			(at -13.299948 13.299948)
			(size 0.4572 0.4572)
			(layers "F.Cu" "F.Mask" "F.Paste")
			(net "GND")
		)
		(pad "AW12" smd circle
			(at -12.349988 13.299948)
			(size 0.4572 0.4572)
			(layers "F.Cu" "F.Mask" "F.Paste")
			(net "Net_5256")
		)
		(pad "AW13" smd circle
			(at -11.400028 13.299948)
			(size 0.4572 0.4572)
			(layers "F.Cu" "F.Mask" "F.Paste")
			(net "Net_5252")
		)
		(pad "AW14" smd circle
			(at -10.450068 13.299948)
			(size 0.4572 0.4572)
			(layers "F.Cu" "F.Mask" "F.Paste")
			(net "Net_5248")
		)
		(pad "AW15" smd circle
			(at -9.500108 13.299948)
			(size 0.4572 0.4572)
			(layers "F.Cu" "F.Mask" "F.Paste")
			(net "Net_5243")
		)
		(pad "AW16" smd circle
			(at -8.549894 13.299948)
			(size 0.4572 0.4572)
			(layers "F.Cu" "F.Mask" "F.Paste")
			(net "Net_5255")
		)
		(pad "AW17" smd circle
			(at -7.599934 13.299948)
			(size 0.4572 0.4572)
			(layers "F.Cu" "F.Mask" "F.Paste")
			(net "Net_5251")
		)
		(pad "AW18" smd circle
			(at -6.649974 13.299948)
			(size 0.4572 0.4572)
			(layers "F.Cu" "F.Mask" "F.Paste")
			(net "Net_5247")
		)
		(pad "AW19" smd circle
			(at -5.700014 13.299948)
			(size 0.4572 0.4572)
			(layers "F.Cu" "F.Mask" "F.Paste")
			(net "Net_5242")
		)
		(pad "AW20" smd circle
			(at -4.750054 13.299948)
			(size 0.4572 0.4572)
			(layers "F.Cu" "F.Mask" "F.Paste")
			(net "GND")
		)
		(pad "AW21" smd circle
			(at -3.800094 13.299948)
			(size 0.4572 0.4572)
			(layers "F.Cu" "F.Mask" "F.Paste")
			(net "Net_5276")
		)
		(pad "AW22" smd circle
			(at -2.84988 13.299948)
			(size 0.4572 0.4572)
			(layers "F.Cu" "F.Mask" "F.Paste")
			(net "Net_5286")
		)
		(pad "AW23" smd circle
			(at -1.89992 13.299948)
			(size 0.4572 0.4572)
			(layers "F.Cu" "F.Mask" "F.Paste")
			(net "Net_5275")
		)
		(pad "AW24" smd circle
			(at -0.94996 13.299948)
			(size 0.4572 0.4572)
			(layers "F.Cu" "F.Mask" "F.Paste")
			(net "GND")
		)
		(pad "AW25" smd circle
			(at 0 13.299948)
			(size 0.4572 0.4572)
			(layers "F.Cu" "F.Mask" "F.Paste")
			(net "PEX1_MODE_SEL5")
		)
		(pad "AW26" smd circle
			(at 0.94996 13.299948)
			(size 0.4572 0.4572)
			(layers "F.Cu" "F.Mask" "F.Paste")
			(net "PEX1_DBG_MODE3")
		)
		(pad "AW27" smd circle
			(at 1.89992 13.299948)
			(size 0.4572 0.4572)
			(layers "F.Cu" "F.Mask" "F.Paste")
			(net "PEX1_MODE_SEL0")
		)
		(pad "AW28" smd circle
			(at 2.84988 13.299948)
			(size 0.4572 0.4572)
			(layers "F.Cu" "F.Mask" "F.Paste")
			(net "PEX1_MODE_SEL4")
		)
		(pad "AW29" smd circle
			(at 3.800094 13.299948)
			(size 0.4572 0.4572)
			(layers "F.Cu" "F.Mask" "F.Paste")
			(net "PEX1_MODE_SEL8")
		)
		(pad "AW30" smd circle
			(at 4.750054 13.299948)
			(size 0.4572 0.4572)
			(layers "F.Cu" "F.Mask" "F.Paste")
			(net "PEX1_DBG_MODE2")
		)
		(pad "AW31" smd circle
			(at 5.700014 13.299948)
			(size 0.4572 0.4572)
			(layers "F.Cu" "F.Mask" "F.Paste")
			(net "PEX1_MODE_SEL11")
		)
		(pad "AW32" smd circle
			(at 6.649974 13.299948)
			(size 0.4572 0.4572)
			(layers "F.Cu" "F.Mask" "F.Paste")
			(net "PEX1_MODE_SEL12")
		)
		(pad "AW33" smd circle
			(at 7.599934 13.299948)
			(size 0.4572 0.4572)
			(layers "F.Cu" "F.Mask" "F.Paste")
			(net "Net_5260")
		)
		(pad "AW34" smd circle
			(at 8.549894 13.299948)
			(size 0.4572 0.4572)
			(layers "F.Cu" "F.Mask" "F.Paste")
			(net "PEX1_DBG_MODE4")
		)
		(pad "AW35" smd circle
			(at 9.500108 13.299948)
			(size 0.4572 0.4572)
			(layers "F.Cu" "F.Mask" "F.Paste")
			(net "Net_5239")
		)
		(pad "AW36" smd circle
			(at 10.450068 13.299948)
			(size 0.4572 0.4572)
			(layers "F.Cu" "F.Mask" "F.Paste")
			(net "Net_5263")
		)
		(pad "AW37" smd circle
			(at 11.400028 13.299948)
			(size 0.4572 0.4572)
			(layers "F.Cu" "F.Mask" "F.Paste")
			(net "Net_5267")
		)
		(pad "AW38" smd circle
			(at 12.349988 13.299948)
			(size 0.4572 0.4572)
			(layers "F.Cu" "F.Mask" "F.Paste")
			(net "PEX1_MODE_SEL1")
		)
		(pad "AW39" smd circle
			(at 13.299948 13.299948)
			(size 0.4572 0.4572)
			(layers "F.Cu" "F.Mask" "F.Paste")
			(net "Net_5234")
		)
		(pad "AW40" smd circle
			(at 14.249908 13.299948)
			(size 0.4572 0.4572)
			(layers "F.Cu" "F.Mask" "F.Paste")
			(net "GND")
		)
		(pad "AW41" smd circle
			(at 15.200122 13.299948)
			(size 0.4572 0.4572)
			(layers "F.Cu" "F.Mask" "F.Paste")
			(net "GND")
		)
		(pad "AW42" smd circle
			(at 16.150082 13.299948)
			(size 0.4572 0.4572)
			(layers "F.Cu" "F.Mask" "F.Paste")
			(net "GND")
		)
		(pad "AW43" smd circle
			(at 17.100042 13.299948)
			(size 0.4572 0.4572)
			(layers "F.Cu" "F.Mask" "F.Paste")
			(net "P5E_PEX1_STN0_TX_DP<6>")
		)
		(pad "AW44" smd circle
			(at 18.050002 13.299948)
			(size 0.4572 0.4572)
			(layers "F.Cu" "F.Mask" "F.Paste")
			(net "P5E_PEX1_STN0_TX_DN<6>")
		)
		(pad "AW45" smd circle
			(at 18.999962 13.299948)
			(size 0.4572 0.4572)
			(layers "F.Cu" "F.Mask" "F.Paste")
			(net "GND")
		)
		(pad "AW46" smd circle
			(at 19.949922 13.299948)
			(size 0.4572 0.4572)
			(layers "F.Cu" "F.Mask" "F.Paste")
			(net "P5E_PEX1_STN0_RX_DP<6>")
		)
		(pad "AW47" smd circle
			(at 20.899882 13.299948)
			(size 0.4572 0.4572)
			(layers "F.Cu" "F.Mask" "F.Paste")
			(net "P5E_PEX1_STN0_RX_DN<6>")
		)
		(pad "AW48" smd circle
			(at 21.850096 13.299948)
			(size 0.4572 0.4572)
			(layers "F.Cu" "F.Mask" "F.Paste")
			(net "GND")
		)
		(pad "AW49" smd circle
			(at 22.800056 13.299948)
			(size 0.4572 0.4572)
			(layers "F.Cu" "F.Mask" "F.Paste")
			(net "GND")
		)
		(pad "AY1" smd circle
			(at -22.800056 14.249908)
			(size 0.4572 0.4572)
			(layers "F.Cu" "F.Mask" "F.Paste")
			(net "Net_1426")
		)
		(pad "AY2" smd circle
			(at -21.850096 14.249908)
			(size 0.4572 0.4572)
			(layers "F.Cu" "F.Mask" "F.Paste")
			(net "Net_1389")
		)
		(pad "AY3" smd circle
			(at -20.899882 14.249908)
			(size 0.4572 0.4572)
			(layers "F.Cu" "F.Mask" "F.Paste")
			(net "GND")
		)
		(pad "AY4" smd circle
			(at -19.949922 14.249908)
			(size 0.4572 0.4572)
			(layers "F.Cu" "F.Mask" "F.Paste")
			(net "GND")
		)
		(pad "AY5" smd circle
			(at -18.999962 14.249908)
			(size 0.4572 0.4572)
			(layers "F.Cu" "F.Mask" "F.Paste")
			(net "GND")
		)
		(pad "AY6" smd circle
			(at -18.050002 14.249908)
			(size 0.4572 0.4572)
			(layers "F.Cu" "F.Mask" "F.Paste")
			(net "GND")
		)
		(pad "AY7" smd circle
			(at -17.100042 14.249908)
			(size 0.4572 0.4572)
			(layers "F.Cu" "F.Mask" "F.Paste")
			(net "GND")
		)
		(pad "AY8" smd circle
			(at -16.150082 14.249908)
			(size 0.4572 0.4572)
			(layers "F.Cu" "F.Mask" "F.Paste")
			(net "GND")
		)
		(pad "AY9" smd circle
			(at -15.200122 14.249908)
			(size 0.4572 0.4572)
			(layers "F.Cu" "F.Mask" "F.Paste")
			(net "GND")
		)
		(pad "AY10" smd circle
			(at -14.249908 14.249908)
			(size 0.4572 0.4572)
			(layers "F.Cu" "F.Mask" "F.Paste")
			(net "GND")
		)
		(pad "AY11" smd circle
			(at -13.299948 14.249908)
			(size 0.4572 0.4572)
			(layers "F.Cu" "F.Mask" "F.Paste")
			(net "GND")
		)
		(pad "AY12" smd circle
			(at -12.349988 14.249908)
			(size 0.4572 0.4572)
			(layers "F.Cu" "F.Mask" "F.Paste")
			(net "GND")
		)
		(pad "AY13" smd circle
			(at -11.400028 14.249908)
			(size 0.4572 0.4572)
			(layers "F.Cu" "F.Mask" "F.Paste")
			(net "GND")
		)
		(pad "AY14" smd circle
			(at -10.450068 14.249908)
			(size 0.4572 0.4572)
			(layers "F.Cu" "F.Mask" "F.Paste")
			(net "GND")
		)
		(pad "AY15" smd circle
			(at -9.500108 14.249908)
			(size 0.4572 0.4572)
			(layers "F.Cu" "F.Mask" "F.Paste")
			(net "GND")
		)
		(pad "AY16" smd circle
			(at -8.549894 14.249908)
			(size 0.4572 0.4572)
			(layers "F.Cu" "F.Mask" "F.Paste")
			(net "GND")
		)
		(pad "AY17" smd circle
			(at -7.599934 14.249908)
			(size 0.4572 0.4572)
			(layers "F.Cu" "F.Mask" "F.Paste")
			(net "GND")
		)
		(pad "AY18" smd circle
			(at -6.649974 14.249908)
			(size 0.4572 0.4572)
			(layers "F.Cu" "F.Mask" "F.Paste")
			(net "GND")
		)
		(pad "AY19" smd circle
			(at -5.700014 14.249908)
			(size 0.4572 0.4572)
			(layers "F.Cu" "F.Mask" "F.Paste")
			(net "GND")
		)
		(pad "AY20" smd circle
			(at -4.750054 14.249908)
			(size 0.4572 0.4572)
			(layers "F.Cu" "F.Mask" "F.Paste")
			(net "GND")
		)
		(pad "AY21" smd circle
			(at -3.800094 14.249908)
			(size 0.4572 0.4572)
			(layers "F.Cu" "F.Mask" "F.Paste")
			(net "GND")
		)
		(pad "AY22" smd circle
			(at -2.84988 14.249908)
			(size 0.4572 0.4572)
			(layers "F.Cu" "F.Mask" "F.Paste")
			(net "GND")
		)
		(pad "AY23" smd circle
			(at -1.89992 14.249908)
			(size 0.4572 0.4572)
			(layers "F.Cu" "F.Mask" "F.Paste")
			(net "GND")
		)
		(pad "AY24" smd circle
			(at -0.94996 14.249908)
			(size 0.4572 0.4572)
			(layers "F.Cu" "F.Mask" "F.Paste")
			(net "GND")
		)
		(pad "AY25" smd circle
			(at 0 14.249908)
			(size 0.4572 0.4572)
			(layers "F.Cu" "F.Mask" "F.Paste")
			(net "GND")
		)
		(pad "AY26" smd circle
			(at 0.94996 14.249908)
			(size 0.4572 0.4572)
			(layers "F.Cu" "F.Mask" "F.Paste")
			(net "GND")
		)
		(pad "AY27" smd circle
			(at 1.89992 14.249908)
			(size 0.4572 0.4572)
			(layers "F.Cu" "F.Mask" "F.Paste")
			(net "GND")
		)
		(pad "AY28" smd circle
			(at 2.84988 14.249908)
			(size 0.4572 0.4572)
			(layers "F.Cu" "F.Mask" "F.Paste")
			(net "GND")
		)
		(pad "AY29" smd circle
			(at 3.800094 14.249908)
			(size 0.4572 0.4572)
			(layers "F.Cu" "F.Mask" "F.Paste")
			(net "GND")
		)
		(pad "AY30" smd circle
			(at 4.750054 14.249908)
			(size 0.4572 0.4572)
			(layers "F.Cu" "F.Mask" "F.Paste")
			(net "GND")
		)
		(pad "AY31" smd circle
			(at 5.700014 14.249908)
			(size 0.4572 0.4572)
			(layers "F.Cu" "F.Mask" "F.Paste")
			(net "GND")
		)
		(pad "AY32" smd circle
			(at 6.649974 14.249908)
			(size 0.4572 0.4572)
			(layers "F.Cu" "F.Mask" "F.Paste")
			(net "GND")
		)
		(pad "AY33" smd circle
			(at 7.599934 14.249908)
			(size 0.4572 0.4572)
			(layers "F.Cu" "F.Mask" "F.Paste")
			(net "GND")
		)
		(pad "AY34" smd circle
			(at 8.549894 14.249908)
			(size 0.4572 0.4572)
			(layers "F.Cu" "F.Mask" "F.Paste")
			(net "GND")
		)
		(pad "AY35" smd circle
			(at 9.500108 14.249908)
			(size 0.4572 0.4572)
			(layers "F.Cu" "F.Mask" "F.Paste")
			(net "GND")
		)
		(pad "AY36" smd circle
			(at 10.450068 14.249908)
			(size 0.4572 0.4572)
			(layers "F.Cu" "F.Mask" "F.Paste")
			(net "GND")
		)
		(pad "AY37" smd circle
			(at 11.400028 14.249908)
			(size 0.4572 0.4572)
			(layers "F.Cu" "F.Mask" "F.Paste")
			(net "GND")
		)
		(pad "AY38" smd circle
			(at 12.349988 14.249908)
			(size 0.4572 0.4572)
			(layers "F.Cu" "F.Mask" "F.Paste")
			(net "GND")
		)
		(pad "AY39" smd circle
			(at 13.299948 14.249908)
			(size 0.4572 0.4572)
			(layers "F.Cu" "F.Mask" "F.Paste")
			(net "GND")
		)
		(pad "AY40" smd circle
			(at 14.249908 14.249908)
			(size 0.4572 0.4572)
			(layers "F.Cu" "F.Mask" "F.Paste")
			(net "GND")
		)
		(pad "AY41" smd circle
			(at 15.200122 14.249908)
			(size 0.4572 0.4572)
			(layers "F.Cu" "F.Mask" "F.Paste")
			(net "GND")
		)
		(pad "AY42" smd circle
			(at 16.150082 14.249908)
			(size 0.4572 0.4572)
			(layers "F.Cu" "F.Mask" "F.Paste")
			(net "GND")
		)
		(pad "AY43" smd circle
			(at 17.100042 14.249908)
			(size 0.4572 0.4572)
			(layers "F.Cu" "F.Mask" "F.Paste")
			(net "GND")
		)
		(pad "AY44" smd circle
			(at 18.050002 14.249908)
			(size 0.4572 0.4572)
			(layers "F.Cu" "F.Mask" "F.Paste")
			(net "GND")
		)
		(pad "AY45" smd circle
			(at 18.999962 14.249908)
			(size 0.4572 0.4572)
			(layers "F.Cu" "F.Mask" "F.Paste")
			(net "GND")
		)
		(pad "AY46" smd circle
			(at 19.949922 14.249908)
			(size 0.4572 0.4572)
			(layers "F.Cu" "F.Mask" "F.Paste")
			(net "GND")
		)
		(pad "AY47" smd circle
			(at 20.899882 14.249908)
			(size 0.4572 0.4572)
			(layers "F.Cu" "F.Mask" "F.Paste")
			(net "GND")
		)
		(pad "AY48" smd circle
			(at 21.850096 14.249908)
			(size 0.4572 0.4572)
			(layers "F.Cu" "F.Mask" "F.Paste")
			(net "P5E_PEX1_STN0_RX_DP<7>")
		)
		(pad "AY49" smd circle
			(at 22.800056 14.249908)
			(size 0.4572 0.4572)
			(layers "F.Cu" "F.Mask" "F.Paste")
			(net "P5E_PEX1_STN0_RX_DN<7>")
		)
		(pad "B1" smd circle
			(at -22.800056 -21.850096)
			(size 0.4572 0.4572)
			(layers "F.Cu" "F.Mask" "F.Paste")
			(net "GND")
		)
		(pad "B2" smd circle
			(at -21.850096 -21.850096)
			(size 0.4572 0.4572)
			(layers "F.Cu" "F.Mask" "F.Paste")
			(net "GND")
		)
		(pad "B3" smd circle
			(at -20.899882 -21.850096)
			(size 0.4572 0.4572)
			(layers "F.Cu" "F.Mask" "F.Paste")
			(net "P5E_PEX1_STN7_RX_DP<123>")
		)
		(pad "B4" smd circle
			(at -19.949922 -21.850096)
			(size 0.4572 0.4572)
			(layers "F.Cu" "F.Mask" "F.Paste")
			(net "GND")
		)
		(pad "B5" smd circle
			(at -18.999962 -21.850096)
			(size 0.4572 0.4572)
			(layers "F.Cu" "F.Mask" "F.Paste")
			(net "P5E_PEX1_STN7_RX_DP<125>")
		)
		(pad "B6" smd circle
			(at -18.050002 -21.850096)
			(size 0.4572 0.4572)
			(layers "F.Cu" "F.Mask" "F.Paste")
			(net "GND")
		)
		(pad "B7" smd circle
			(at -17.100042 -21.850096)
			(size 0.4572 0.4572)
			(layers "F.Cu" "F.Mask" "F.Paste")
			(net "P5E_PEX1_STN7_RX_DP<127>")
		)
		(pad "B8" smd circle
			(at -16.150082 -21.850096)
			(size 0.4572 0.4572)
			(layers "F.Cu" "F.Mask" "F.Paste")
			(net "GND")
		)
		(pad "B9" smd circle
			(at -15.200122 -21.850096)
			(size 0.4572 0.4572)
			(layers "F.Cu" "F.Mask" "F.Paste")
			(net "P5E_PEX1_STN6_RX_DP<110>")
		)
		(pad "B10" smd circle
			(at -14.249908 -21.850096)
			(size 0.4572 0.4572)
			(layers "F.Cu" "F.Mask" "F.Paste")
			(net "GND")
		)
		(pad "B11" smd circle
			(at -13.299948 -21.850096)
			(size 0.4572 0.4572)
			(layers "F.Cu" "F.Mask" "F.Paste")
			(net "P5E_PEX1_STN6_RX_DP<108>")
		)
		(pad "B12" smd circle
			(at -12.349988 -21.850096)
			(size 0.4572 0.4572)
			(layers "F.Cu" "F.Mask" "F.Paste")
			(net "GND")
		)
		(pad "B13" smd circle
			(at -11.400028 -21.850096)
			(size 0.4572 0.4572)
			(layers "F.Cu" "F.Mask" "F.Paste")
			(net "P5E_PEX1_STN6_RX_DP<106>")
		)
		(pad "B14" smd circle
			(at -10.450068 -21.850096)
			(size 0.4572 0.4572)
			(layers "F.Cu" "F.Mask" "F.Paste")
			(net "GND")
		)
		(pad "B15" smd circle
			(at -9.500108 -21.850096)
			(size 0.4572 0.4572)
			(layers "F.Cu" "F.Mask" "F.Paste")
			(net "P5E_PEX1_STN6_RX_DP<104>")
		)
		(pad "B16" smd circle
			(at -8.549894 -21.850096)
			(size 0.4572 0.4572)
			(layers "F.Cu" "F.Mask" "F.Paste")
			(net "GND")
		)
		(pad "B17" smd circle
			(at -7.599934 -21.850096)
			(size 0.4572 0.4572)
			(layers "F.Cu" "F.Mask" "F.Paste")
			(net "P5E_PEX1_STN6_RX_DP<102>")
		)
		(pad "B18" smd circle
			(at -6.649974 -21.850096)
			(size 0.4572 0.4572)
			(layers "F.Cu" "F.Mask" "F.Paste")
			(net "GND")
		)
		(pad "B19" smd circle
			(at -5.700014 -21.850096)
			(size 0.4572 0.4572)
			(layers "F.Cu" "F.Mask" "F.Paste")
			(net "P5E_PEX1_STN6_RX_DP<100>")
		)
		(pad "B20" smd circle
			(at -4.750054 -21.850096)
			(size 0.4572 0.4572)
			(layers "F.Cu" "F.Mask" "F.Paste")
			(net "GND")
		)
		(pad "B21" smd circle
			(at -3.800094 -21.850096)
			(size 0.4572 0.4572)
			(layers "F.Cu" "F.Mask" "F.Paste")
			(net "P5E_PEX1_STN6_RX_DP<98>")
		)
		(pad "B22" smd circle
			(at -2.84988 -21.850096)
			(size 0.4572 0.4572)
			(layers "F.Cu" "F.Mask" "F.Paste")
			(net "GND")
		)
		(pad "B23" smd circle
			(at -1.89992 -21.850096)
			(size 0.4572 0.4572)
			(layers "F.Cu" "F.Mask" "F.Paste")
			(net "P5E_PEX1_STN6_RX_DP<96>")
		)
		(pad "B24" smd circle
			(at -0.94996 -21.850096)
			(size 0.4572 0.4572)
			(layers "F.Cu" "F.Mask" "F.Paste")
			(net "GND")
		)
		(pad "B25" smd circle
			(at 0 -21.850096)
			(size 0.4572 0.4572)
			(layers "F.Cu" "F.Mask" "F.Paste")
			(net "P5E_PEX1_STN5_RX_DP<81>")
		)
		(pad "B26" smd circle
			(at 0.94996 -21.850096)
			(size 0.4572 0.4572)
			(layers "F.Cu" "F.Mask" "F.Paste")
			(net "GND")
		)
		(pad "B27" smd circle
			(at 1.89992 -21.850096)
			(size 0.4572 0.4572)
			(layers "F.Cu" "F.Mask" "F.Paste")
			(net "P5E_PEX1_STN5_RX_DP<83>")
		)
		(pad "B28" smd circle
			(at 2.84988 -21.850096)
			(size 0.4572 0.4572)
			(layers "F.Cu" "F.Mask" "F.Paste")
			(net "GND")
		)
		(pad "B29" smd circle
			(at 3.800094 -21.850096)
			(size 0.4572 0.4572)
			(layers "F.Cu" "F.Mask" "F.Paste")
			(net "P5E_PEX1_STN5_RX_DP<85>")
		)
		(pad "B30" smd circle
			(at 4.750054 -21.850096)
			(size 0.4572 0.4572)
			(layers "F.Cu" "F.Mask" "F.Paste")
			(net "GND")
		)
		(pad "B31" smd circle
			(at 5.700014 -21.850096)
			(size 0.4572 0.4572)
			(layers "F.Cu" "F.Mask" "F.Paste")
			(net "P5E_PEX1_STN5_RX_DP<87>")
		)
		(pad "B32" smd circle
			(at 6.649974 -21.850096)
			(size 0.4572 0.4572)
			(layers "F.Cu" "F.Mask" "F.Paste")
			(net "GND")
		)
		(pad "B33" smd circle
			(at 7.599934 -21.850096)
			(size 0.4572 0.4572)
			(layers "F.Cu" "F.Mask" "F.Paste")
			(net "P5E_PEX1_STN5_RX_DP<89>")
		)
		(pad "B34" smd circle
			(at 8.549894 -21.850096)
			(size 0.4572 0.4572)
			(layers "F.Cu" "F.Mask" "F.Paste")
			(net "GND")
		)
		(pad "B35" smd circle
			(at 9.500108 -21.850096)
			(size 0.4572 0.4572)
			(layers "F.Cu" "F.Mask" "F.Paste")
			(net "P5E_PEX1_STN5_RX_DP<91>")
		)
		(pad "B36" smd circle
			(at 10.450068 -21.850096)
			(size 0.4572 0.4572)
			(layers "F.Cu" "F.Mask" "F.Paste")
			(net "GND")
		)
		(pad "B37" smd circle
			(at 11.400028 -21.850096)
			(size 0.4572 0.4572)
			(layers "F.Cu" "F.Mask" "F.Paste")
			(net "P5E_PEX1_STN5_RX_DP<93>")
		)
		(pad "B38" smd circle
			(at 12.349988 -21.850096)
			(size 0.4572 0.4572)
			(layers "F.Cu" "F.Mask" "F.Paste")
			(net "GND")
		)
		(pad "B39" smd circle
			(at 13.299948 -21.850096)
			(size 0.4572 0.4572)
			(layers "F.Cu" "F.Mask" "F.Paste")
			(net "P5E_PEX1_STN5_RX_DP<95>")
		)
		(pad "B40" smd circle
			(at 14.249908 -21.850096)
			(size 0.4572 0.4572)
			(layers "F.Cu" "F.Mask" "F.Paste")
			(net "GND")
		)
		(pad "B41" smd circle
			(at 15.200122 -21.850096)
			(size 0.4572 0.4572)
			(layers "F.Cu" "F.Mask" "F.Paste")
			(net "P5E_PEX1_STN4_RX_DP<78>")
		)
		(pad "B42" smd circle
			(at 16.150082 -21.850096)
			(size 0.4572 0.4572)
			(layers "F.Cu" "F.Mask" "F.Paste")
			(net "GND")
		)
		(pad "B43" smd circle
			(at 17.100042 -21.850096)
			(size 0.4572 0.4572)
			(layers "F.Cu" "F.Mask" "F.Paste")
			(net "P5E_PEX1_STN4_RX_DP<76>")
		)
		(pad "B44" smd circle
			(at 18.050002 -21.850096)
			(size 0.4572 0.4572)
			(layers "F.Cu" "F.Mask" "F.Paste")
			(net "GND")
		)
		(pad "B45" smd circle
			(at 18.999962 -21.850096)
			(size 0.4572 0.4572)
			(layers "F.Cu" "F.Mask" "F.Paste")
			(net "P5E_PEX1_STN4_RX_DP<74>")
		)
		(pad "B46" smd circle
			(at 19.949922 -21.850096)
			(size 0.4572 0.4572)
			(layers "F.Cu" "F.Mask" "F.Paste")
			(net "GND")
		)
		(pad "B47" smd circle
			(at 20.899882 -21.850096)
			(size 0.4572 0.4572)
			(layers "F.Cu" "F.Mask" "F.Paste")
			(net "P5E_PEX1_STN4_RX_DP<72>")
		)
		(pad "B48" smd circle
			(at 21.850096 -21.850096)
			(size 0.4572 0.4572)
			(layers "F.Cu" "F.Mask" "F.Paste")
			(net "GND")
		)
		(pad "B49" smd circle
			(at 22.800056 -21.850096)
			(size 0.4572 0.4572)
			(layers "F.Cu" "F.Mask" "F.Paste")
			(net "GND")
		)
		(pad "BA1" smd circle
			(at -22.800056 15.200122)
			(size 0.4572 0.4572)
			(layers "F.Cu" "F.Mask" "F.Paste")
			(net "GND")
		)
		(pad "BA2" smd circle
			(at -21.850096 15.200122)
			(size 0.4572 0.4572)
			(layers "F.Cu" "F.Mask" "F.Paste")
			(net "GND")
		)
		(pad "BA3" smd circle
			(at -20.899882 15.200122)
			(size 0.4572 0.4572)
			(layers "F.Cu" "F.Mask" "F.Paste")
			(net "GND")
		)
		(pad "BA4" smd circle
			(at -19.949922 15.200122)
			(size 0.4572 0.4572)
			(layers "F.Cu" "F.Mask" "F.Paste")
			(net "Net_1664")
		)
		(pad "BA5" smd circle
			(at -18.999962 15.200122)
			(size 0.4572 0.4572)
			(layers "F.Cu" "F.Mask" "F.Paste")
			(net "GND")
		)
		(pad "BA6" smd circle
			(at -18.050002 15.200122)
			(size 0.4572 0.4572)
			(layers "F.Cu" "F.Mask" "F.Paste")
			(net "Net_1680")
		)
		(pad "BA7" smd circle
			(at -17.100042 15.200122)
			(size 0.4572 0.4572)
			(layers "F.Cu" "F.Mask" "F.Paste")
			(net "GND")
		)
		(pad "BA8" smd circle
			(at -16.150082 15.200122)
			(size 0.4572 0.4572)
			(layers "F.Cu" "F.Mask" "F.Paste")
			(net "Net_1641")
		)
		(pad "BA9" smd circle
			(at -15.200122 15.200122)
			(size 0.4572 0.4572)
			(layers "F.Cu" "F.Mask" "F.Paste")
			(net "GND")
		)
		(pad "BA10" smd circle
			(at -14.249908 15.200122)
			(size 0.4572 0.4572)
			(layers "F.Cu" "F.Mask" "F.Paste")
			(net "P5E_PEX1_STN2_TX_DP<46>")
		)
		(pad "BA11" smd circle
			(at -13.299948 15.200122)
			(size 0.4572 0.4572)
			(layers "F.Cu" "F.Mask" "F.Paste")
			(net "GND")
		)
		(pad "BA12" smd circle
			(at -12.349988 15.200122)
			(size 0.4572 0.4572)
			(layers "F.Cu" "F.Mask" "F.Paste")
			(net "P5E_PEX1_STN2_TX_DP<44>")
		)
		(pad "BA13" smd circle
			(at -11.400028 15.200122)
			(size 0.4572 0.4572)
			(layers "F.Cu" "F.Mask" "F.Paste")
			(net "GND")
		)
		(pad "BA14" smd circle
			(at -10.450068 15.200122)
			(size 0.4572 0.4572)
			(layers "F.Cu" "F.Mask" "F.Paste")
			(net "P5E_PEX1_STN2_TX_DP<42>")
		)
		(pad "BA15" smd circle
			(at -9.500108 15.200122)
			(size 0.4572 0.4572)
			(layers "F.Cu" "F.Mask" "F.Paste")
			(net "GND")
		)
		(pad "BA16" smd circle
			(at -8.549894 15.200122)
			(size 0.4572 0.4572)
			(layers "F.Cu" "F.Mask" "F.Paste")
			(net "P5E_PEX1_STN2_TX_DP<40>")
		)
		(pad "BA17" smd circle
			(at -7.599934 15.200122)
			(size 0.4572 0.4572)
			(layers "F.Cu" "F.Mask" "F.Paste")
			(net "GND")
		)
		(pad "BA18" smd circle
			(at -6.649974 15.200122)
			(size 0.4572 0.4572)
			(layers "F.Cu" "F.Mask" "F.Paste")
			(net "P5E_PEX1_STN2_TX_DP<38>")
		)
		(pad "BA19" smd circle
			(at -5.700014 15.200122)
			(size 0.4572 0.4572)
			(layers "F.Cu" "F.Mask" "F.Paste")
			(net "GND")
		)
		(pad "BA20" smd circle
			(at -4.750054 15.200122)
			(size 0.4572 0.4572)
			(layers "F.Cu" "F.Mask" "F.Paste")
			(net "P5E_PEX1_STN2_TX_DP<36>")
		)
		(pad "BA21" smd circle
			(at -3.800094 15.200122)
			(size 0.4572 0.4572)
			(layers "F.Cu" "F.Mask" "F.Paste")
			(net "GND")
		)
		(pad "BA22" smd circle
			(at -2.84988 15.200122)
			(size 0.4572 0.4572)
			(layers "F.Cu" "F.Mask" "F.Paste")
			(net "P5E_PEX1_STN2_TX_DP<34>")
		)
		(pad "BA23" smd circle
			(at -1.89992 15.200122)
			(size 0.4572 0.4572)
			(layers "F.Cu" "F.Mask" "F.Paste")
			(net "GND")
		)
		(pad "BA24" smd circle
			(at -0.94996 15.200122)
			(size 0.4572 0.4572)
			(layers "F.Cu" "F.Mask" "F.Paste")
			(net "P5E_PEX1_STN2_TX_DP<32>")
		)
		(pad "BA25" smd circle
			(at 0 15.200122)
			(size 0.4572 0.4572)
			(layers "F.Cu" "F.Mask" "F.Paste")
			(net "GND")
		)
		(pad "BA26" smd circle
			(at 0.94996 15.200122)
			(size 0.4572 0.4572)
			(layers "F.Cu" "F.Mask" "F.Paste")
			(net "P5E_PEX1_STN1_TX_DN<17>")
		)
		(pad "BA27" smd circle
			(at 1.89992 15.200122)
			(size 0.4572 0.4572)
			(layers "F.Cu" "F.Mask" "F.Paste")
			(net "GND")
		)
		(pad "BA28" smd circle
			(at 2.84988 15.200122)
			(size 0.4572 0.4572)
			(layers "F.Cu" "F.Mask" "F.Paste")
			(net "P5E_PEX1_STN1_TX_DN<19>")
		)
		(pad "BA29" smd circle
			(at 3.800094 15.200122)
			(size 0.4572 0.4572)
			(layers "F.Cu" "F.Mask" "F.Paste")
			(net "GND")
		)
		(pad "BA30" smd circle
			(at 4.750054 15.200122)
			(size 0.4572 0.4572)
			(layers "F.Cu" "F.Mask" "F.Paste")
			(net "P5E_PEX1_STN1_TX_DN<21>")
		)
		(pad "BA31" smd circle
			(at 5.700014 15.200122)
			(size 0.4572 0.4572)
			(layers "F.Cu" "F.Mask" "F.Paste")
			(net "GND")
		)
		(pad "BA32" smd circle
			(at 6.649974 15.200122)
			(size 0.4572 0.4572)
			(layers "F.Cu" "F.Mask" "F.Paste")
			(net "P5E_PEX1_STN1_TX_DN<23>")
		)
		(pad "BA33" smd circle
			(at 7.599934 15.200122)
			(size 0.4572 0.4572)
			(layers "F.Cu" "F.Mask" "F.Paste")
			(net "GND")
		)
		(pad "BA34" smd circle
			(at 8.549894 15.200122)
			(size 0.4572 0.4572)
			(layers "F.Cu" "F.Mask" "F.Paste")
			(net "P5E_PEX1_STN1_TX_DN<25>")
		)
		(pad "BA35" smd circle
			(at 9.500108 15.200122)
			(size 0.4572 0.4572)
			(layers "F.Cu" "F.Mask" "F.Paste")
			(net "GND")
		)
		(pad "BA36" smd circle
			(at 10.450068 15.200122)
			(size 0.4572 0.4572)
			(layers "F.Cu" "F.Mask" "F.Paste")
			(net "P5E_PEX1_STN1_TX_DN<27>")
		)
		(pad "BA37" smd circle
			(at 11.400028 15.200122)
			(size 0.4572 0.4572)
			(layers "F.Cu" "F.Mask" "F.Paste")
			(net "GND")
		)
		(pad "BA38" smd circle
			(at 12.349988 15.200122)
			(size 0.4572 0.4572)
			(layers "F.Cu" "F.Mask" "F.Paste")
			(net "P5E_PEX1_STN1_TX_DN<29>")
		)
		(pad "BA39" smd circle
			(at 13.299948 15.200122)
			(size 0.4572 0.4572)
			(layers "F.Cu" "F.Mask" "F.Paste")
			(net "GND")
		)
		(pad "BA40" smd circle
			(at 14.249908 15.200122)
			(size 0.4572 0.4572)
			(layers "F.Cu" "F.Mask" "F.Paste")
			(net "P5E_PEX1_STN1_TX_DN<31>")
		)
		(pad "BA41" smd circle
			(at 15.200122 15.200122)
			(size 0.4572 0.4572)
			(layers "F.Cu" "F.Mask" "F.Paste")
			(net "GND")
		)
		(pad "BA42" smd circle
			(at 16.150082 15.200122)
			(size 0.4572 0.4572)
			(layers "F.Cu" "F.Mask" "F.Paste")
			(net "P5E_PEX1_STN0_TX_DN<14>")
		)
		(pad "BA43" smd circle
			(at 17.100042 15.200122)
			(size 0.4572 0.4572)
			(layers "F.Cu" "F.Mask" "F.Paste")
			(net "GND")
		)
		(pad "BA44" smd circle
			(at 18.050002 15.200122)
			(size 0.4572 0.4572)
			(layers "F.Cu" "F.Mask" "F.Paste")
			(net "P5E_PEX1_STN0_TX_DN<12>")
		)
		(pad "BA45" smd circle
			(at 18.999962 15.200122)
			(size 0.4572 0.4572)
			(layers "F.Cu" "F.Mask" "F.Paste")
			(net "GND")
		)
		(pad "BA46" smd circle
			(at 19.949922 15.200122)
			(size 0.4572 0.4572)
			(layers "F.Cu" "F.Mask" "F.Paste")
			(net "P5E_PEX1_STN0_TX_DP<10>")
		)
		(pad "BA47" smd circle
			(at 20.899882 15.200122)
			(size 0.4572 0.4572)
			(layers "F.Cu" "F.Mask" "F.Paste")
			(net "GND")
		)
		(pad "BA48" smd circle
			(at 21.850096 15.200122)
			(size 0.4572 0.4572)
			(layers "F.Cu" "F.Mask" "F.Paste")
			(net "GND")
		)
		(pad "BA49" smd circle
			(at 22.800056 15.200122)
			(size 0.4572 0.4572)
			(layers "F.Cu" "F.Mask" "F.Paste")
			(net "GND")
		)
		(pad "BB1" smd circle
			(at -22.800056 16.150082)
			(size 0.4572 0.4572)
			(layers "F.Cu" "F.Mask" "F.Paste")
			(net "Net_1676")
		)
		(pad "BB2" smd circle
			(at -21.850096 16.150082)
			(size 0.4572 0.4572)
			(layers "F.Cu" "F.Mask" "F.Paste")
			(net "Net_1653")
		)
		(pad "BB3" smd circle
			(at -20.899882 16.150082)
			(size 0.4572 0.4572)
			(layers "F.Cu" "F.Mask" "F.Paste")
			(net "GND")
		)
		(pad "BB4" smd circle
			(at -19.949922 16.150082)
			(size 0.4572 0.4572)
			(layers "F.Cu" "F.Mask" "F.Paste")
			(net "Net_1647")
		)
		(pad "BB5" smd circle
			(at -18.999962 16.150082)
			(size 0.4572 0.4572)
			(layers "F.Cu" "F.Mask" "F.Paste")
			(net "GND")
		)
		(pad "BB6" smd circle
			(at -18.050002 16.150082)
			(size 0.4572 0.4572)
			(layers "F.Cu" "F.Mask" "F.Paste")
			(net "Net_1656")
		)
		(pad "BB7" smd circle
			(at -17.100042 16.150082)
			(size 0.4572 0.4572)
			(layers "F.Cu" "F.Mask" "F.Paste")
			(net "GND")
		)
		(pad "BB8" smd circle
			(at -16.150082 16.150082)
			(size 0.4572 0.4572)
			(layers "F.Cu" "F.Mask" "F.Paste")
			(net "Net_1662")
		)
		(pad "BB9" smd circle
			(at -15.200122 16.150082)
			(size 0.4572 0.4572)
			(layers "F.Cu" "F.Mask" "F.Paste")
			(net "GND")
		)
		(pad "BB10" smd circle
			(at -14.249908 16.150082)
			(size 0.4572 0.4572)
			(layers "F.Cu" "F.Mask" "F.Paste")
			(net "P5E_PEX1_STN2_TX_DN<46>")
		)
		(pad "BB11" smd circle
			(at -13.299948 16.150082)
			(size 0.4572 0.4572)
			(layers "F.Cu" "F.Mask" "F.Paste")
			(net "GND")
		)
		(pad "BB12" smd circle
			(at -12.349988 16.150082)
			(size 0.4572 0.4572)
			(layers "F.Cu" "F.Mask" "F.Paste")
			(net "P5E_PEX1_STN2_TX_DN<44>")
		)
		(pad "BB13" smd circle
			(at -11.400028 16.150082)
			(size 0.4572 0.4572)
			(layers "F.Cu" "F.Mask" "F.Paste")
			(net "GND")
		)
		(pad "BB14" smd circle
			(at -10.450068 16.150082)
			(size 0.4572 0.4572)
			(layers "F.Cu" "F.Mask" "F.Paste")
			(net "P5E_PEX1_STN2_TX_DN<42>")
		)
		(pad "BB15" smd circle
			(at -9.500108 16.150082)
			(size 0.4572 0.4572)
			(layers "F.Cu" "F.Mask" "F.Paste")
			(net "GND")
		)
		(pad "BB16" smd circle
			(at -8.549894 16.150082)
			(size 0.4572 0.4572)
			(layers "F.Cu" "F.Mask" "F.Paste")
			(net "P5E_PEX1_STN2_TX_DN<40>")
		)
		(pad "BB17" smd circle
			(at -7.599934 16.150082)
			(size 0.4572 0.4572)
			(layers "F.Cu" "F.Mask" "F.Paste")
			(net "GND")
		)
		(pad "BB18" smd circle
			(at -6.649974 16.150082)
			(size 0.4572 0.4572)
			(layers "F.Cu" "F.Mask" "F.Paste")
			(net "P5E_PEX1_STN2_TX_DN<38>")
		)
		(pad "BB19" smd circle
			(at -5.700014 16.150082)
			(size 0.4572 0.4572)
			(layers "F.Cu" "F.Mask" "F.Paste")
			(net "GND")
		)
		(pad "BB20" smd circle
			(at -4.750054 16.150082)
			(size 0.4572 0.4572)
			(layers "F.Cu" "F.Mask" "F.Paste")
			(net "P5E_PEX1_STN2_TX_DN<36>")
		)
		(pad "BB21" smd circle
			(at -3.800094 16.150082)
			(size 0.4572 0.4572)
			(layers "F.Cu" "F.Mask" "F.Paste")
			(net "GND")
		)
		(pad "BB22" smd circle
			(at -2.84988 16.150082)
			(size 0.4572 0.4572)
			(layers "F.Cu" "F.Mask" "F.Paste")
			(net "P5E_PEX1_STN2_TX_DN<34>")
		)
		(pad "BB23" smd circle
			(at -1.89992 16.150082)
			(size 0.4572 0.4572)
			(layers "F.Cu" "F.Mask" "F.Paste")
			(net "GND")
		)
		(pad "BB24" smd circle
			(at -0.94996 16.150082)
			(size 0.4572 0.4572)
			(layers "F.Cu" "F.Mask" "F.Paste")
			(net "P5E_PEX1_STN2_TX_DN<32>")
		)
		(pad "BB25" smd circle
			(at 0 16.150082)
			(size 0.4572 0.4572)
			(layers "F.Cu" "F.Mask" "F.Paste")
			(net "GND")
		)
		(pad "BB26" smd circle
			(at 0.94996 16.150082)
			(size 0.4572 0.4572)
			(layers "F.Cu" "F.Mask" "F.Paste")
			(net "P5E_PEX1_STN1_TX_DP<17>")
		)
		(pad "BB27" smd circle
			(at 1.89992 16.150082)
			(size 0.4572 0.4572)
			(layers "F.Cu" "F.Mask" "F.Paste")
			(net "GND")
		)
		(pad "BB28" smd circle
			(at 2.84988 16.150082)
			(size 0.4572 0.4572)
			(layers "F.Cu" "F.Mask" "F.Paste")
			(net "P5E_PEX1_STN1_TX_DP<19>")
		)
		(pad "BB29" smd circle
			(at 3.800094 16.150082)
			(size 0.4572 0.4572)
			(layers "F.Cu" "F.Mask" "F.Paste")
			(net "GND")
		)
		(pad "BB30" smd circle
			(at 4.750054 16.150082)
			(size 0.4572 0.4572)
			(layers "F.Cu" "F.Mask" "F.Paste")
			(net "P5E_PEX1_STN1_TX_DP<21>")
		)
		(pad "BB31" smd circle
			(at 5.700014 16.150082)
			(size 0.4572 0.4572)
			(layers "F.Cu" "F.Mask" "F.Paste")
			(net "GND")
		)
		(pad "BB32" smd circle
			(at 6.649974 16.150082)
			(size 0.4572 0.4572)
			(layers "F.Cu" "F.Mask" "F.Paste")
			(net "P5E_PEX1_STN1_TX_DP<23>")
		)
		(pad "BB33" smd circle
			(at 7.599934 16.150082)
			(size 0.4572 0.4572)
			(layers "F.Cu" "F.Mask" "F.Paste")
			(net "GND")
		)
		(pad "BB34" smd circle
			(at 8.549894 16.150082)
			(size 0.4572 0.4572)
			(layers "F.Cu" "F.Mask" "F.Paste")
			(net "P5E_PEX1_STN1_TX_DP<25>")
		)
		(pad "BB35" smd circle
			(at 9.500108 16.150082)
			(size 0.4572 0.4572)
			(layers "F.Cu" "F.Mask" "F.Paste")
			(net "GND")
		)
		(pad "BB36" smd circle
			(at 10.450068 16.150082)
			(size 0.4572 0.4572)
			(layers "F.Cu" "F.Mask" "F.Paste")
			(net "P5E_PEX1_STN1_TX_DP<27>")
		)
		(pad "BB37" smd circle
			(at 11.400028 16.150082)
			(size 0.4572 0.4572)
			(layers "F.Cu" "F.Mask" "F.Paste")
			(net "GND")
		)
		(pad "BB38" smd circle
			(at 12.349988 16.150082)
			(size 0.4572 0.4572)
			(layers "F.Cu" "F.Mask" "F.Paste")
			(net "P5E_PEX1_STN1_TX_DP<29>")
		)
		(pad "BB39" smd circle
			(at 13.299948 16.150082)
			(size 0.4572 0.4572)
			(layers "F.Cu" "F.Mask" "F.Paste")
			(net "GND")
		)
		(pad "BB40" smd circle
			(at 14.249908 16.150082)
			(size 0.4572 0.4572)
			(layers "F.Cu" "F.Mask" "F.Paste")
			(net "P5E_PEX1_STN1_TX_DP<31>")
		)
		(pad "BB41" smd circle
			(at 15.200122 16.150082)
			(size 0.4572 0.4572)
			(layers "F.Cu" "F.Mask" "F.Paste")
			(net "GND")
		)
		(pad "BB42" smd circle
			(at 16.150082 16.150082)
			(size 0.4572 0.4572)
			(layers "F.Cu" "F.Mask" "F.Paste")
			(net "P5E_PEX1_STN0_TX_DP<14>")
		)
		(pad "BB43" smd circle
			(at 17.100042 16.150082)
			(size 0.4572 0.4572)
			(layers "F.Cu" "F.Mask" "F.Paste")
			(net "GND")
		)
		(pad "BB44" smd circle
			(at 18.050002 16.150082)
			(size 0.4572 0.4572)
			(layers "F.Cu" "F.Mask" "F.Paste")
			(net "P5E_PEX1_STN0_TX_DP<12>")
		)
		(pad "BB45" smd circle
			(at 18.999962 16.150082)
			(size 0.4572 0.4572)
			(layers "F.Cu" "F.Mask" "F.Paste")
			(net "GND")
		)
		(pad "BB46" smd circle
			(at 19.949922 16.150082)
			(size 0.4572 0.4572)
			(layers "F.Cu" "F.Mask" "F.Paste")
			(net "P5E_PEX1_STN0_TX_DN<10>")
		)
		(pad "BB47" smd circle
			(at 20.899882 16.150082)
			(size 0.4572 0.4572)
			(layers "F.Cu" "F.Mask" "F.Paste")
			(net "GND")
		)
		(pad "BB48" smd circle
			(at 21.850096 16.150082)
			(size 0.4572 0.4572)
			(layers "F.Cu" "F.Mask" "F.Paste")
			(net "P5E_PEX1_STN0_TX_DP<7>")
		)
		(pad "BB49" smd circle
			(at 22.800056 16.150082)
			(size 0.4572 0.4572)
			(layers "F.Cu" "F.Mask" "F.Paste")
			(net "P5E_PEX1_STN0_TX_DN<7>")
		)
		(pad "BC1" smd circle
			(at -22.800056 17.100042)
			(size 0.4572 0.4572)
			(layers "F.Cu" "F.Mask" "F.Paste")
			(net "GND")
		)
		(pad "BC2" smd circle
			(at -21.850096 17.100042)
			(size 0.4572 0.4572)
			(layers "F.Cu" "F.Mask" "F.Paste")
			(net "GND")
		)
		(pad "BC3" smd circle
			(at -20.899882 17.100042)
			(size 0.4572 0.4572)
			(layers "F.Cu" "F.Mask" "F.Paste")
			(net "Net_1684")
		)
		(pad "BC4" smd circle
			(at -19.949922 17.100042)
			(size 0.4572 0.4572)
			(layers "F.Cu" "F.Mask" "F.Paste")
			(net "GND")
		)
		(pad "BC5" smd circle
			(at -18.999962 17.100042)
			(size 0.4572 0.4572)
			(layers "F.Cu" "F.Mask" "F.Paste")
			(net "Net_1682")
		)
		(pad "BC6" smd circle
			(at -18.050002 17.100042)
			(size 0.4572 0.4572)
			(layers "F.Cu" "F.Mask" "F.Paste")
			(net "GND")
		)
		(pad "BC7" smd circle
			(at -17.100042 17.100042)
			(size 0.4572 0.4572)
			(layers "F.Cu" "F.Mask" "F.Paste")
			(net "Net_1646")
		)
		(pad "BC8" smd circle
			(at -16.150082 17.100042)
			(size 0.4572 0.4572)
			(layers "F.Cu" "F.Mask" "F.Paste")
			(net "GND")
		)
		(pad "BC9" smd circle
			(at -15.200122 17.100042)
			(size 0.4572 0.4572)
			(layers "F.Cu" "F.Mask" "F.Paste")
			(net "P5E_PEX1_STN2_TX_DP<47>")
		)
		(pad "BC10" smd circle
			(at -14.249908 17.100042)
			(size 0.4572 0.4572)
			(layers "F.Cu" "F.Mask" "F.Paste")
			(net "GND")
		)
		(pad "BC11" smd circle
			(at -13.299948 17.100042)
			(size 0.4572 0.4572)
			(layers "F.Cu" "F.Mask" "F.Paste")
			(net "P5E_PEX1_STN2_TX_DP<45>")
		)
		(pad "BC12" smd circle
			(at -12.349988 17.100042)
			(size 0.4572 0.4572)
			(layers "F.Cu" "F.Mask" "F.Paste")
			(net "GND")
		)
		(pad "BC13" smd circle
			(at -11.400028 17.100042)
			(size 0.4572 0.4572)
			(layers "F.Cu" "F.Mask" "F.Paste")
			(net "P5E_PEX1_STN2_TX_DP<43>")
		)
		(pad "BC14" smd circle
			(at -10.450068 17.100042)
			(size 0.4572 0.4572)
			(layers "F.Cu" "F.Mask" "F.Paste")
			(net "GND")
		)
		(pad "BC15" smd circle
			(at -9.500108 17.100042)
			(size 0.4572 0.4572)
			(layers "F.Cu" "F.Mask" "F.Paste")
			(net "P5E_PEX1_STN2_TX_DP<41>")
		)
		(pad "BC16" smd circle
			(at -8.549894 17.100042)
			(size 0.4572 0.4572)
			(layers "F.Cu" "F.Mask" "F.Paste")
			(net "GND")
		)
		(pad "BC17" smd circle
			(at -7.599934 17.100042)
			(size 0.4572 0.4572)
			(layers "F.Cu" "F.Mask" "F.Paste")
			(net "P5E_PEX1_STN2_TX_DP<39>")
		)
		(pad "BC18" smd circle
			(at -6.649974 17.100042)
			(size 0.4572 0.4572)
			(layers "F.Cu" "F.Mask" "F.Paste")
			(net "GND")
		)
		(pad "BC19" smd circle
			(at -5.700014 17.100042)
			(size 0.4572 0.4572)
			(layers "F.Cu" "F.Mask" "F.Paste")
			(net "P5E_PEX1_STN2_TX_DP<37>")
		)
		(pad "BC20" smd circle
			(at -4.750054 17.100042)
			(size 0.4572 0.4572)
			(layers "F.Cu" "F.Mask" "F.Paste")
			(net "GND")
		)
		(pad "BC21" smd circle
			(at -3.800094 17.100042)
			(size 0.4572 0.4572)
			(layers "F.Cu" "F.Mask" "F.Paste")
			(net "P5E_PEX1_STN2_TX_DP<35>")
		)
		(pad "BC22" smd circle
			(at -2.84988 17.100042)
			(size 0.4572 0.4572)
			(layers "F.Cu" "F.Mask" "F.Paste")
			(net "GND")
		)
		(pad "BC23" smd circle
			(at -1.89992 17.100042)
			(size 0.4572 0.4572)
			(layers "F.Cu" "F.Mask" "F.Paste")
			(net "P5E_PEX1_STN2_TX_DP<33>")
		)
		(pad "BC24" smd circle
			(at -0.94996 17.100042)
			(size 0.4572 0.4572)
			(layers "F.Cu" "F.Mask" "F.Paste")
			(net "GND")
		)
		(pad "BC25" smd circle
			(at 0 17.100042)
			(size 0.4572 0.4572)
			(layers "F.Cu" "F.Mask" "F.Paste")
			(net "P5E_PEX1_STN1_TX_DP<16>")
		)
		(pad "BC26" smd circle
			(at 0.94996 17.100042)
			(size 0.4572 0.4572)
			(layers "F.Cu" "F.Mask" "F.Paste")
			(net "GND")
		)
		(pad "BC27" smd circle
			(at 1.89992 17.100042)
			(size 0.4572 0.4572)
			(layers "F.Cu" "F.Mask" "F.Paste")
			(net "P5E_PEX1_STN1_TX_DP<18>")
		)
		(pad "BC28" smd circle
			(at 2.84988 17.100042)
			(size 0.4572 0.4572)
			(layers "F.Cu" "F.Mask" "F.Paste")
			(net "GND")
		)
		(pad "BC29" smd circle
			(at 3.800094 17.100042)
			(size 0.4572 0.4572)
			(layers "F.Cu" "F.Mask" "F.Paste")
			(net "P5E_PEX1_STN1_TX_DP<20>")
		)
		(pad "BC30" smd circle
			(at 4.750054 17.100042)
			(size 0.4572 0.4572)
			(layers "F.Cu" "F.Mask" "F.Paste")
			(net "GND")
		)
		(pad "BC31" smd circle
			(at 5.700014 17.100042)
			(size 0.4572 0.4572)
			(layers "F.Cu" "F.Mask" "F.Paste")
			(net "P5E_PEX1_STN1_TX_DP<22>")
		)
		(pad "BC32" smd circle
			(at 6.649974 17.100042)
			(size 0.4572 0.4572)
			(layers "F.Cu" "F.Mask" "F.Paste")
			(net "GND")
		)
		(pad "BC33" smd circle
			(at 7.599934 17.100042)
			(size 0.4572 0.4572)
			(layers "F.Cu" "F.Mask" "F.Paste")
			(net "P5E_PEX1_STN1_TX_DP<24>")
		)
		(pad "BC34" smd circle
			(at 8.549894 17.100042)
			(size 0.4572 0.4572)
			(layers "F.Cu" "F.Mask" "F.Paste")
			(net "GND")
		)
		(pad "BC35" smd circle
			(at 9.500108 17.100042)
			(size 0.4572 0.4572)
			(layers "F.Cu" "F.Mask" "F.Paste")
			(net "P5E_PEX1_STN1_TX_DP<26>")
		)
		(pad "BC36" smd circle
			(at 10.450068 17.100042)
			(size 0.4572 0.4572)
			(layers "F.Cu" "F.Mask" "F.Paste")
			(net "GND")
		)
		(pad "BC37" smd circle
			(at 11.400028 17.100042)
			(size 0.4572 0.4572)
			(layers "F.Cu" "F.Mask" "F.Paste")
			(net "P5E_PEX1_STN1_TX_DP<28>")
		)
		(pad "BC38" smd circle
			(at 12.349988 17.100042)
			(size 0.4572 0.4572)
			(layers "F.Cu" "F.Mask" "F.Paste")
			(net "GND")
		)
		(pad "BC39" smd circle
			(at 13.299948 17.100042)
			(size 0.4572 0.4572)
			(layers "F.Cu" "F.Mask" "F.Paste")
			(net "P5E_PEX1_STN1_TX_DP<30>")
		)
		(pad "BC40" smd circle
			(at 14.249908 17.100042)
			(size 0.4572 0.4572)
			(layers "F.Cu" "F.Mask" "F.Paste")
			(net "GND")
		)
		(pad "BC41" smd circle
			(at 15.200122 17.100042)
			(size 0.4572 0.4572)
			(layers "F.Cu" "F.Mask" "F.Paste")
			(net "P5E_PEX1_STN0_TX_DP<15>")
		)
		(pad "BC42" smd circle
			(at 16.150082 17.100042)
			(size 0.4572 0.4572)
			(layers "F.Cu" "F.Mask" "F.Paste")
			(net "GND")
		)
		(pad "BC43" smd circle
			(at 17.100042 17.100042)
			(size 0.4572 0.4572)
			(layers "F.Cu" "F.Mask" "F.Paste")
			(net "P5E_PEX1_STN0_TX_DP<13>")
		)
		(pad "BC44" smd circle
			(at 18.050002 17.100042)
			(size 0.4572 0.4572)
			(layers "F.Cu" "F.Mask" "F.Paste")
			(net "GND")
		)
		(pad "BC45" smd circle
			(at 18.999962 17.100042)
			(size 0.4572 0.4572)
			(layers "F.Cu" "F.Mask" "F.Paste")
			(net "P5E_PEX1_STN0_TX_DP<11>")
		)
		(pad "BC46" smd circle
			(at 19.949922 17.100042)
			(size 0.4572 0.4572)
			(layers "F.Cu" "F.Mask" "F.Paste")
			(net "GND")
		)
		(pad "BC47" smd circle
			(at 20.899882 17.100042)
			(size 0.4572 0.4572)
			(layers "F.Cu" "F.Mask" "F.Paste")
			(net "P5E_PEX1_STN0_TX_DP<9>")
		)
		(pad "BC48" smd circle
			(at 21.850096 17.100042)
			(size 0.4572 0.4572)
			(layers "F.Cu" "F.Mask" "F.Paste")
			(net "GND")
		)
		(pad "BC49" smd circle
			(at 22.800056 17.100042)
			(size 0.4572 0.4572)
			(layers "F.Cu" "F.Mask" "F.Paste")
			(net "GND")
		)
		(pad "BD1" smd circle
			(at -22.800056 18.050002)
			(size 0.4572 0.4572)
			(layers "F.Cu" "F.Mask" "F.Paste")
			(net "GND")
		)
		(pad "BD2" smd circle
			(at -21.850096 18.050002)
			(size 0.4572 0.4572)
			(layers "F.Cu" "F.Mask" "F.Paste")
			(net "GND")
		)
		(pad "BD3" smd circle
			(at -20.899882 18.050002)
			(size 0.4572 0.4572)
			(layers "F.Cu" "F.Mask" "F.Paste")
			(net "Net_1686")
		)
		(pad "BD4" smd circle
			(at -19.949922 18.050002)
			(size 0.4572 0.4572)
			(layers "F.Cu" "F.Mask" "F.Paste")
			(net "GND")
		)
		(pad "BD5" smd circle
			(at -18.999962 18.050002)
			(size 0.4572 0.4572)
			(layers "F.Cu" "F.Mask" "F.Paste")
			(net "Net_1672")
		)
		(pad "BD6" smd circle
			(at -18.050002 18.050002)
			(size 0.4572 0.4572)
			(layers "F.Cu" "F.Mask" "F.Paste")
			(net "GND")
		)
		(pad "BD7" smd circle
			(at -17.100042 18.050002)
			(size 0.4572 0.4572)
			(layers "F.Cu" "F.Mask" "F.Paste")
			(net "Net_1651")
		)
		(pad "BD8" smd circle
			(at -16.150082 18.050002)
			(size 0.4572 0.4572)
			(layers "F.Cu" "F.Mask" "F.Paste")
			(net "GND")
		)
		(pad "BD9" smd circle
			(at -15.200122 18.050002)
			(size 0.4572 0.4572)
			(layers "F.Cu" "F.Mask" "F.Paste")
			(net "P5E_PEX1_STN2_TX_DN<47>")
		)
		(pad "BD10" smd circle
			(at -14.249908 18.050002)
			(size 0.4572 0.4572)
			(layers "F.Cu" "F.Mask" "F.Paste")
			(net "GND")
		)
		(pad "BD11" smd circle
			(at -13.299948 18.050002)
			(size 0.4572 0.4572)
			(layers "F.Cu" "F.Mask" "F.Paste")
			(net "P5E_PEX1_STN2_TX_DN<45>")
		)
		(pad "BD12" smd circle
			(at -12.349988 18.050002)
			(size 0.4572 0.4572)
			(layers "F.Cu" "F.Mask" "F.Paste")
			(net "GND")
		)
		(pad "BD13" smd circle
			(at -11.400028 18.050002)
			(size 0.4572 0.4572)
			(layers "F.Cu" "F.Mask" "F.Paste")
			(net "P5E_PEX1_STN2_TX_DN<43>")
		)
		(pad "BD14" smd circle
			(at -10.450068 18.050002)
			(size 0.4572 0.4572)
			(layers "F.Cu" "F.Mask" "F.Paste")
			(net "GND")
		)
		(pad "BD15" smd circle
			(at -9.500108 18.050002)
			(size 0.4572 0.4572)
			(layers "F.Cu" "F.Mask" "F.Paste")
			(net "P5E_PEX1_STN2_TX_DN<41>")
		)
		(pad "BD16" smd circle
			(at -8.549894 18.050002)
			(size 0.4572 0.4572)
			(layers "F.Cu" "F.Mask" "F.Paste")
			(net "GND")
		)
		(pad "BD17" smd circle
			(at -7.599934 18.050002)
			(size 0.4572 0.4572)
			(layers "F.Cu" "F.Mask" "F.Paste")
			(net "P5E_PEX1_STN2_TX_DN<39>")
		)
		(pad "BD18" smd circle
			(at -6.649974 18.050002)
			(size 0.4572 0.4572)
			(layers "F.Cu" "F.Mask" "F.Paste")
			(net "GND")
		)
		(pad "BD19" smd circle
			(at -5.700014 18.050002)
			(size 0.4572 0.4572)
			(layers "F.Cu" "F.Mask" "F.Paste")
			(net "P5E_PEX1_STN2_TX_DN<37>")
		)
		(pad "BD20" smd circle
			(at -4.750054 18.050002)
			(size 0.4572 0.4572)
			(layers "F.Cu" "F.Mask" "F.Paste")
			(net "GND")
		)
		(pad "BD21" smd circle
			(at -3.800094 18.050002)
			(size 0.4572 0.4572)
			(layers "F.Cu" "F.Mask" "F.Paste")
			(net "P5E_PEX1_STN2_TX_DN<35>")
		)
		(pad "BD22" smd circle
			(at -2.84988 18.050002)
			(size 0.4572 0.4572)
			(layers "F.Cu" "F.Mask" "F.Paste")
			(net "GND")
		)
		(pad "BD23" smd circle
			(at -1.89992 18.050002)
			(size 0.4572 0.4572)
			(layers "F.Cu" "F.Mask" "F.Paste")
			(net "P5E_PEX1_STN2_TX_DN<33>")
		)
		(pad "BD24" smd circle
			(at -0.94996 18.050002)
			(size 0.4572 0.4572)
			(layers "F.Cu" "F.Mask" "F.Paste")
			(net "GND")
		)
		(pad "BD25" smd circle
			(at 0 18.050002)
			(size 0.4572 0.4572)
			(layers "F.Cu" "F.Mask" "F.Paste")
			(net "P5E_PEX1_STN1_TX_DN<16>")
		)
		(pad "BD26" smd circle
			(at 0.94996 18.050002)
			(size 0.4572 0.4572)
			(layers "F.Cu" "F.Mask" "F.Paste")
			(net "GND")
		)
		(pad "BD27" smd circle
			(at 1.89992 18.050002)
			(size 0.4572 0.4572)
			(layers "F.Cu" "F.Mask" "F.Paste")
			(net "P5E_PEX1_STN1_TX_DN<18>")
		)
		(pad "BD28" smd circle
			(at 2.84988 18.050002)
			(size 0.4572 0.4572)
			(layers "F.Cu" "F.Mask" "F.Paste")
			(net "GND")
		)
		(pad "BD29" smd circle
			(at 3.800094 18.050002)
			(size 0.4572 0.4572)
			(layers "F.Cu" "F.Mask" "F.Paste")
			(net "P5E_PEX1_STN1_TX_DN<20>")
		)
		(pad "BD30" smd circle
			(at 4.750054 18.050002)
			(size 0.4572 0.4572)
			(layers "F.Cu" "F.Mask" "F.Paste")
			(net "GND")
		)
		(pad "BD31" smd circle
			(at 5.700014 18.050002)
			(size 0.4572 0.4572)
			(layers "F.Cu" "F.Mask" "F.Paste")
			(net "P5E_PEX1_STN1_TX_DN<22>")
		)
		(pad "BD32" smd circle
			(at 6.649974 18.050002)
			(size 0.4572 0.4572)
			(layers "F.Cu" "F.Mask" "F.Paste")
			(net "GND")
		)
		(pad "BD33" smd circle
			(at 7.599934 18.050002)
			(size 0.4572 0.4572)
			(layers "F.Cu" "F.Mask" "F.Paste")
			(net "P5E_PEX1_STN1_TX_DN<24>")
		)
		(pad "BD34" smd circle
			(at 8.549894 18.050002)
			(size 0.4572 0.4572)
			(layers "F.Cu" "F.Mask" "F.Paste")
			(net "GND")
		)
		(pad "BD35" smd circle
			(at 9.500108 18.050002)
			(size 0.4572 0.4572)
			(layers "F.Cu" "F.Mask" "F.Paste")
			(net "P5E_PEX1_STN1_TX_DN<26>")
		)
		(pad "BD36" smd circle
			(at 10.450068 18.050002)
			(size 0.4572 0.4572)
			(layers "F.Cu" "F.Mask" "F.Paste")
			(net "GND")
		)
		(pad "BD37" smd circle
			(at 11.400028 18.050002)
			(size 0.4572 0.4572)
			(layers "F.Cu" "F.Mask" "F.Paste")
			(net "P5E_PEX1_STN1_TX_DN<28>")
		)
		(pad "BD38" smd circle
			(at 12.349988 18.050002)
			(size 0.4572 0.4572)
			(layers "F.Cu" "F.Mask" "F.Paste")
			(net "GND")
		)
		(pad "BD39" smd circle
			(at 13.299948 18.050002)
			(size 0.4572 0.4572)
			(layers "F.Cu" "F.Mask" "F.Paste")
			(net "P5E_PEX1_STN1_TX_DN<30>")
		)
		(pad "BD40" smd circle
			(at 14.249908 18.050002)
			(size 0.4572 0.4572)
			(layers "F.Cu" "F.Mask" "F.Paste")
			(net "GND")
		)
		(pad "BD41" smd circle
			(at 15.200122 18.050002)
			(size 0.4572 0.4572)
			(layers "F.Cu" "F.Mask" "F.Paste")
			(net "P5E_PEX1_STN0_TX_DN<15>")
		)
		(pad "BD42" smd circle
			(at 16.150082 18.050002)
			(size 0.4572 0.4572)
			(layers "F.Cu" "F.Mask" "F.Paste")
			(net "GND")
		)
		(pad "BD43" smd circle
			(at 17.100042 18.050002)
			(size 0.4572 0.4572)
			(layers "F.Cu" "F.Mask" "F.Paste")
			(net "P5E_PEX1_STN0_TX_DN<13>")
		)
		(pad "BD44" smd circle
			(at 18.050002 18.050002)
			(size 0.4572 0.4572)
			(layers "F.Cu" "F.Mask" "F.Paste")
			(net "GND")
		)
		(pad "BD45" smd circle
			(at 18.999962 18.050002)
			(size 0.4572 0.4572)
			(layers "F.Cu" "F.Mask" "F.Paste")
			(net "P5E_PEX1_STN0_TX_DN<11>")
		)
		(pad "BD46" smd circle
			(at 19.949922 18.050002)
			(size 0.4572 0.4572)
			(layers "F.Cu" "F.Mask" "F.Paste")
			(net "GND")
		)
		(pad "BD47" smd circle
			(at 20.899882 18.050002)
			(size 0.4572 0.4572)
			(layers "F.Cu" "F.Mask" "F.Paste")
			(net "P5E_PEX1_STN0_TX_DN<9>")
		)
		(pad "BD48" smd circle
			(at 21.850096 18.050002)
			(size 0.4572 0.4572)
			(layers "F.Cu" "F.Mask" "F.Paste")
			(net "GND")
		)
		(pad "BD49" smd circle
			(at 22.800056 18.050002)
			(size 0.4572 0.4572)
			(layers "F.Cu" "F.Mask" "F.Paste")
			(net "GND")
		)
		(pad "BE1" smd circle
			(at -22.800056 18.999962)
			(size 0.4572 0.4572)
			(layers "F.Cu" "F.Mask" "F.Paste")
			(net "Net_1648")
		)
		(pad "BE2" smd circle
			(at -21.850096 18.999962)
			(size 0.4572 0.4572)
			(layers "F.Cu" "F.Mask" "F.Paste")
			(net "Net_1645")
		)
		(pad "BE3" smd circle
			(at -20.899882 18.999962)
			(size 0.4572 0.4572)
			(layers "F.Cu" "F.Mask" "F.Paste")
			(net "GND")
		)
		(pad "BE4" smd circle
			(at -19.949922 18.999962)
			(size 0.4572 0.4572)
			(layers "F.Cu" "F.Mask" "F.Paste")
			(net "GND")
		)
		(pad "BE5" smd circle
			(at -18.999962 18.999962)
			(size 0.4572 0.4572)
			(layers "F.Cu" "F.Mask" "F.Paste")
			(net "GND")
		)
		(pad "BE6" smd circle
			(at -18.050002 18.999962)
			(size 0.4572 0.4572)
			(layers "F.Cu" "F.Mask" "F.Paste")
			(net "GND")
		)
		(pad "BE7" smd circle
			(at -17.100042 18.999962)
			(size 0.4572 0.4572)
			(layers "F.Cu" "F.Mask" "F.Paste")
			(net "GND")
		)
		(pad "BE8" smd circle
			(at -16.150082 18.999962)
			(size 0.4572 0.4572)
			(layers "F.Cu" "F.Mask" "F.Paste")
			(net "GND")
		)
		(pad "BE9" smd circle
			(at -15.200122 18.999962)
			(size 0.4572 0.4572)
			(layers "F.Cu" "F.Mask" "F.Paste")
			(net "GND")
		)
		(pad "BE10" smd circle
			(at -14.249908 18.999962)
			(size 0.4572 0.4572)
			(layers "F.Cu" "F.Mask" "F.Paste")
			(net "GND")
		)
		(pad "BE11" smd circle
			(at -13.299948 18.999962)
			(size 0.4572 0.4572)
			(layers "F.Cu" "F.Mask" "F.Paste")
			(net "GND")
		)
		(pad "BE12" smd circle
			(at -12.349988 18.999962)
			(size 0.4572 0.4572)
			(layers "F.Cu" "F.Mask" "F.Paste")
			(net "GND")
		)
		(pad "BE13" smd circle
			(at -11.400028 18.999962)
			(size 0.4572 0.4572)
			(layers "F.Cu" "F.Mask" "F.Paste")
			(net "GND")
		)
		(pad "BE14" smd circle
			(at -10.450068 18.999962)
			(size 0.4572 0.4572)
			(layers "F.Cu" "F.Mask" "F.Paste")
			(net "GND")
		)
		(pad "BE15" smd circle
			(at -9.500108 18.999962)
			(size 0.4572 0.4572)
			(layers "F.Cu" "F.Mask" "F.Paste")
			(net "GND")
		)
		(pad "BE16" smd circle
			(at -8.549894 18.999962)
			(size 0.4572 0.4572)
			(layers "F.Cu" "F.Mask" "F.Paste")
			(net "GND")
		)
		(pad "BE17" smd circle
			(at -7.599934 18.999962)
			(size 0.4572 0.4572)
			(layers "F.Cu" "F.Mask" "F.Paste")
			(net "GND")
		)
		(pad "BE18" smd circle
			(at -6.649974 18.999962)
			(size 0.4572 0.4572)
			(layers "F.Cu" "F.Mask" "F.Paste")
			(net "GND")
		)
		(pad "BE19" smd circle
			(at -5.700014 18.999962)
			(size 0.4572 0.4572)
			(layers "F.Cu" "F.Mask" "F.Paste")
			(net "GND")
		)
		(pad "BE20" smd circle
			(at -4.750054 18.999962)
			(size 0.4572 0.4572)
			(layers "F.Cu" "F.Mask" "F.Paste")
			(net "GND")
		)
		(pad "BE21" smd circle
			(at -3.800094 18.999962)
			(size 0.4572 0.4572)
			(layers "F.Cu" "F.Mask" "F.Paste")
			(net "GND")
		)
		(pad "BE22" smd circle
			(at -2.84988 18.999962)
			(size 0.4572 0.4572)
			(layers "F.Cu" "F.Mask" "F.Paste")
			(net "GND")
		)
		(pad "BE23" smd circle
			(at -1.89992 18.999962)
			(size 0.4572 0.4572)
			(layers "F.Cu" "F.Mask" "F.Paste")
			(net "GND")
		)
		(pad "BE24" smd circle
			(at -0.94996 18.999962)
			(size 0.4572 0.4572)
			(layers "F.Cu" "F.Mask" "F.Paste")
			(net "GND")
		)
		(pad "BE25" smd circle
			(at 0 18.999962)
			(size 0.4572 0.4572)
			(layers "F.Cu" "F.Mask" "F.Paste")
			(net "GND")
		)
		(pad "BE26" smd circle
			(at 0.94996 18.999962)
			(size 0.4572 0.4572)
			(layers "F.Cu" "F.Mask" "F.Paste")
			(net "GND")
		)
		(pad "BE27" smd circle
			(at 1.89992 18.999962)
			(size 0.4572 0.4572)
			(layers "F.Cu" "F.Mask" "F.Paste")
			(net "GND")
		)
		(pad "BE28" smd circle
			(at 2.84988 18.999962)
			(size 0.4572 0.4572)
			(layers "F.Cu" "F.Mask" "F.Paste")
			(net "GND")
		)
		(pad "BE29" smd circle
			(at 3.800094 18.999962)
			(size 0.4572 0.4572)
			(layers "F.Cu" "F.Mask" "F.Paste")
			(net "GND")
		)
		(pad "BE30" smd circle
			(at 4.750054 18.999962)
			(size 0.4572 0.4572)
			(layers "F.Cu" "F.Mask" "F.Paste")
			(net "GND")
		)
		(pad "BE31" smd circle
			(at 5.700014 18.999962)
			(size 0.4572 0.4572)
			(layers "F.Cu" "F.Mask" "F.Paste")
			(net "GND")
		)
		(pad "BE32" smd circle
			(at 6.649974 18.999962)
			(size 0.4572 0.4572)
			(layers "F.Cu" "F.Mask" "F.Paste")
			(net "GND")
		)
		(pad "BE33" smd circle
			(at 7.599934 18.999962)
			(size 0.4572 0.4572)
			(layers "F.Cu" "F.Mask" "F.Paste")
			(net "GND")
		)
		(pad "BE34" smd circle
			(at 8.549894 18.999962)
			(size 0.4572 0.4572)
			(layers "F.Cu" "F.Mask" "F.Paste")
			(net "GND")
		)
		(pad "BE35" smd circle
			(at 9.500108 18.999962)
			(size 0.4572 0.4572)
			(layers "F.Cu" "F.Mask" "F.Paste")
			(net "GND")
		)
		(pad "BE36" smd circle
			(at 10.450068 18.999962)
			(size 0.4572 0.4572)
			(layers "F.Cu" "F.Mask" "F.Paste")
			(net "GND")
		)
		(pad "BE37" smd circle
			(at 11.400028 18.999962)
			(size 0.4572 0.4572)
			(layers "F.Cu" "F.Mask" "F.Paste")
			(net "GND")
		)
		(pad "BE38" smd circle
			(at 12.349988 18.999962)
			(size 0.4572 0.4572)
			(layers "F.Cu" "F.Mask" "F.Paste")
			(net "GND")
		)
		(pad "BE39" smd circle
			(at 13.299948 18.999962)
			(size 0.4572 0.4572)
			(layers "F.Cu" "F.Mask" "F.Paste")
			(net "GND")
		)
		(pad "BE40" smd circle
			(at 14.249908 18.999962)
			(size 0.4572 0.4572)
			(layers "F.Cu" "F.Mask" "F.Paste")
			(net "GND")
		)
		(pad "BE41" smd circle
			(at 15.200122 18.999962)
			(size 0.4572 0.4572)
			(layers "F.Cu" "F.Mask" "F.Paste")
			(net "GND")
		)
		(pad "BE42" smd circle
			(at 16.150082 18.999962)
			(size 0.4572 0.4572)
			(layers "F.Cu" "F.Mask" "F.Paste")
			(net "GND")
		)
		(pad "BE43" smd circle
			(at 17.100042 18.999962)
			(size 0.4572 0.4572)
			(layers "F.Cu" "F.Mask" "F.Paste")
			(net "GND")
		)
		(pad "BE44" smd circle
			(at 18.050002 18.999962)
			(size 0.4572 0.4572)
			(layers "F.Cu" "F.Mask" "F.Paste")
			(net "GND")
		)
		(pad "BE45" smd circle
			(at 18.999962 18.999962)
			(size 0.4572 0.4572)
			(layers "F.Cu" "F.Mask" "F.Paste")
			(net "GND")
		)
		(pad "BE46" smd circle
			(at 19.949922 18.999962)
			(size 0.4572 0.4572)
			(layers "F.Cu" "F.Mask" "F.Paste")
			(net "GND")
		)
		(pad "BE47" smd circle
			(at 20.899882 18.999962)
			(size 0.4572 0.4572)
			(layers "F.Cu" "F.Mask" "F.Paste")
			(net "GND")
		)
		(pad "BE48" smd circle
			(at 21.850096 18.999962)
			(size 0.4572 0.4572)
			(layers "F.Cu" "F.Mask" "F.Paste")
			(net "P5E_PEX1_STN0_TX_DP<8>")
		)
		(pad "BE49" smd circle
			(at 22.800056 18.999962)
			(size 0.4572 0.4572)
			(layers "F.Cu" "F.Mask" "F.Paste")
			(net "P5E_PEX1_STN0_TX_DN<8>")
		)
		(pad "BF1" smd circle
			(at -22.800056 19.949922)
			(size 0.4572 0.4572)
			(layers "F.Cu" "F.Mask" "F.Paste")
			(net "GND")
		)
		(pad "BF2" smd circle
			(at -21.850096 19.949922)
			(size 0.4572 0.4572)
			(layers "F.Cu" "F.Mask" "F.Paste")
			(net "GND")
		)
		(pad "BF3" smd circle
			(at -20.899882 19.949922)
			(size 0.4572 0.4572)
			(layers "F.Cu" "F.Mask" "F.Paste")
			(net "GND")
		)
		(pad "BF4" smd circle
			(at -19.949922 19.949922)
			(size 0.4572 0.4572)
			(layers "F.Cu" "F.Mask" "F.Paste")
			(net "Net_1707")
		)
		(pad "BF5" smd circle
			(at -18.999962 19.949922)
			(size 0.4572 0.4572)
			(layers "F.Cu" "F.Mask" "F.Paste")
			(net "GND")
		)
		(pad "BF6" smd circle
			(at -18.050002 19.949922)
			(size 0.4572 0.4572)
			(layers "F.Cu" "F.Mask" "F.Paste")
			(net "Net_1725")
		)
		(pad "BF7" smd circle
			(at -17.100042 19.949922)
			(size 0.4572 0.4572)
			(layers "F.Cu" "F.Mask" "F.Paste")
			(net "GND")
		)
		(pad "BF8" smd circle
			(at -16.150082 19.949922)
			(size 0.4572 0.4572)
			(layers "F.Cu" "F.Mask" "F.Paste")
			(net "Net_1713")
		)
		(pad "BF9" smd circle
			(at -15.200122 19.949922)
			(size 0.4572 0.4572)
			(layers "F.Cu" "F.Mask" "F.Paste")
			(net "GND")
		)
		(pad "BF10" smd circle
			(at -14.249908 19.949922)
			(size 0.4572 0.4572)
			(layers "F.Cu" "F.Mask" "F.Paste")
			(net "P5E_PEX1_STN2_RX_DP<46>")
		)
		(pad "BF11" smd circle
			(at -13.299948 19.949922)
			(size 0.4572 0.4572)
			(layers "F.Cu" "F.Mask" "F.Paste")
			(net "GND")
		)
		(pad "BF12" smd circle
			(at -12.349988 19.949922)
			(size 0.4572 0.4572)
			(layers "F.Cu" "F.Mask" "F.Paste")
			(net "P5E_PEX1_STN2_RX_DP<44>")
		)
		(pad "BF13" smd circle
			(at -11.400028 19.949922)
			(size 0.4572 0.4572)
			(layers "F.Cu" "F.Mask" "F.Paste")
			(net "GND")
		)
		(pad "BF14" smd circle
			(at -10.450068 19.949922)
			(size 0.4572 0.4572)
			(layers "F.Cu" "F.Mask" "F.Paste")
			(net "P5E_PEX1_STN2_RX_DP<42>")
		)
		(pad "BF15" smd circle
			(at -9.500108 19.949922)
			(size 0.4572 0.4572)
			(layers "F.Cu" "F.Mask" "F.Paste")
			(net "GND")
		)
		(pad "BF16" smd circle
			(at -8.549894 19.949922)
			(size 0.4572 0.4572)
			(layers "F.Cu" "F.Mask" "F.Paste")
			(net "P5E_PEX1_STN2_RX_DP<40>")
		)
		(pad "BF17" smd circle
			(at -7.599934 19.949922)
			(size 0.4572 0.4572)
			(layers "F.Cu" "F.Mask" "F.Paste")
			(net "GND")
		)
		(pad "BF18" smd circle
			(at -6.649974 19.949922)
			(size 0.4572 0.4572)
			(layers "F.Cu" "F.Mask" "F.Paste")
			(net "P5E_PEX1_STN2_RX_DP<38>")
		)
		(pad "BF19" smd circle
			(at -5.700014 19.949922)
			(size 0.4572 0.4572)
			(layers "F.Cu" "F.Mask" "F.Paste")
			(net "GND")
		)
		(pad "BF20" smd circle
			(at -4.750054 19.949922)
			(size 0.4572 0.4572)
			(layers "F.Cu" "F.Mask" "F.Paste")
			(net "P5E_PEX1_STN2_RX_DP<36>")
		)
		(pad "BF21" smd circle
			(at -3.800094 19.949922)
			(size 0.4572 0.4572)
			(layers "F.Cu" "F.Mask" "F.Paste")
			(net "GND")
		)
		(pad "BF22" smd circle
			(at -2.84988 19.949922)
			(size 0.4572 0.4572)
			(layers "F.Cu" "F.Mask" "F.Paste")
			(net "P5E_PEX1_STN2_RX_DP<34>")
		)
		(pad "BF23" smd circle
			(at -1.89992 19.949922)
			(size 0.4572 0.4572)
			(layers "F.Cu" "F.Mask" "F.Paste")
			(net "GND")
		)
		(pad "BF24" smd circle
			(at -0.94996 19.949922)
			(size 0.4572 0.4572)
			(layers "F.Cu" "F.Mask" "F.Paste")
			(net "P5E_PEX1_STN2_RX_DP<32>")
		)
		(pad "BF25" smd circle
			(at 0 19.949922)
			(size 0.4572 0.4572)
			(layers "F.Cu" "F.Mask" "F.Paste")
			(net "GND")
		)
		(pad "BF26" smd circle
			(at 0.94996 19.949922)
			(size 0.4572 0.4572)
			(layers "F.Cu" "F.Mask" "F.Paste")
			(net "P5E_PEX1_STN1_RX_DP<17>")
		)
		(pad "BF27" smd circle
			(at 1.89992 19.949922)
			(size 0.4572 0.4572)
			(layers "F.Cu" "F.Mask" "F.Paste")
			(net "GND")
		)
		(pad "BF28" smd circle
			(at 2.84988 19.949922)
			(size 0.4572 0.4572)
			(layers "F.Cu" "F.Mask" "F.Paste")
			(net "P5E_PEX1_STN1_RX_DP<19>")
		)
		(pad "BF29" smd circle
			(at 3.800094 19.949922)
			(size 0.4572 0.4572)
			(layers "F.Cu" "F.Mask" "F.Paste")
			(net "GND")
		)
		(pad "BF30" smd circle
			(at 4.750054 19.949922)
			(size 0.4572 0.4572)
			(layers "F.Cu" "F.Mask" "F.Paste")
			(net "P5E_PEX1_STN1_RX_DP<21>")
		)
		(pad "BF31" smd circle
			(at 5.700014 19.949922)
			(size 0.4572 0.4572)
			(layers "F.Cu" "F.Mask" "F.Paste")
			(net "GND")
		)
		(pad "BF32" smd circle
			(at 6.649974 19.949922)
			(size 0.4572 0.4572)
			(layers "F.Cu" "F.Mask" "F.Paste")
			(net "P5E_PEX1_STN1_RX_DP<23>")
		)
		(pad "BF33" smd circle
			(at 7.599934 19.949922)
			(size 0.4572 0.4572)
			(layers "F.Cu" "F.Mask" "F.Paste")
			(net "GND")
		)
		(pad "BF34" smd circle
			(at 8.549894 19.949922)
			(size 0.4572 0.4572)
			(layers "F.Cu" "F.Mask" "F.Paste")
			(net "P5E_PEX1_STN1_RX_DP<25>")
		)
		(pad "BF35" smd circle
			(at 9.500108 19.949922)
			(size 0.4572 0.4572)
			(layers "F.Cu" "F.Mask" "F.Paste")
			(net "GND")
		)
		(pad "BF36" smd circle
			(at 10.450068 19.949922)
			(size 0.4572 0.4572)
			(layers "F.Cu" "F.Mask" "F.Paste")
			(net "P5E_PEX1_STN1_RX_DP<27>")
		)
		(pad "BF37" smd circle
			(at 11.400028 19.949922)
			(size 0.4572 0.4572)
			(layers "F.Cu" "F.Mask" "F.Paste")
			(net "GND")
		)
		(pad "BF38" smd circle
			(at 12.349988 19.949922)
			(size 0.4572 0.4572)
			(layers "F.Cu" "F.Mask" "F.Paste")
			(net "P5E_PEX1_STN1_RX_DP<29>")
		)
		(pad "BF39" smd circle
			(at 13.299948 19.949922)
			(size 0.4572 0.4572)
			(layers "F.Cu" "F.Mask" "F.Paste")
			(net "GND")
		)
		(pad "BF40" smd circle
			(at 14.249908 19.949922)
			(size 0.4572 0.4572)
			(layers "F.Cu" "F.Mask" "F.Paste")
			(net "P5E_PEX1_STN1_RX_DP<31>")
		)
		(pad "BF41" smd circle
			(at 15.200122 19.949922)
			(size 0.4572 0.4572)
			(layers "F.Cu" "F.Mask" "F.Paste")
			(net "GND")
		)
		(pad "BF42" smd circle
			(at 16.150082 19.949922)
			(size 0.4572 0.4572)
			(layers "F.Cu" "F.Mask" "F.Paste")
			(net "P5E_PEX1_STN0_RX_DP<14>")
		)
		(pad "BF43" smd circle
			(at 17.100042 19.949922)
			(size 0.4572 0.4572)
			(layers "F.Cu" "F.Mask" "F.Paste")
			(net "GND")
		)
		(pad "BF44" smd circle
			(at 18.050002 19.949922)
			(size 0.4572 0.4572)
			(layers "F.Cu" "F.Mask" "F.Paste")
			(net "P5E_PEX1_STN0_RX_DP<12>")
		)
		(pad "BF45" smd circle
			(at 18.999962 19.949922)
			(size 0.4572 0.4572)
			(layers "F.Cu" "F.Mask" "F.Paste")
			(net "GND")
		)
		(pad "BF46" smd circle
			(at 19.949922 19.949922)
			(size 0.4572 0.4572)
			(layers "F.Cu" "F.Mask" "F.Paste")
			(net "P5E_PEX1_STN0_RX_DP<10>")
		)
		(pad "BF47" smd circle
			(at 20.899882 19.949922)
			(size 0.4572 0.4572)
			(layers "F.Cu" "F.Mask" "F.Paste")
			(net "GND")
		)
		(pad "BF48" smd circle
			(at 21.850096 19.949922)
			(size 0.4572 0.4572)
			(layers "F.Cu" "F.Mask" "F.Paste")
			(net "GND")
		)
		(pad "BF49" smd circle
			(at 22.800056 19.949922)
			(size 0.4572 0.4572)
			(layers "F.Cu" "F.Mask" "F.Paste")
			(net "GND")
		)
		(pad "BG1" smd circle
			(at -22.800056 20.899882)
			(size 0.4572 0.4572)
			(layers "F.Cu" "F.Mask" "F.Paste")
			(net "Net_1727")
		)
		(pad "BG2" smd circle
			(at -21.850096 20.899882)
			(size 0.4572 0.4572)
			(layers "F.Cu" "F.Mask" "F.Paste")
			(net "Net_1715")
		)
		(pad "BG3" smd circle
			(at -20.899882 20.899882)
			(size 0.4572 0.4572)
			(layers "F.Cu" "F.Mask" "F.Paste")
			(net "GND")
		)
		(pad "BG4" smd circle
			(at -19.949922 20.899882)
			(size 0.4572 0.4572)
			(layers "F.Cu" "F.Mask" "F.Paste")
			(net "Net_1708")
		)
		(pad "BG5" smd circle
			(at -18.999962 20.899882)
			(size 0.4572 0.4572)
			(layers "F.Cu" "F.Mask" "F.Paste")
			(net "GND")
		)
		(pad "BG6" smd circle
			(at -18.050002 20.899882)
			(size 0.4572 0.4572)
			(layers "F.Cu" "F.Mask" "F.Paste")
			(net "Net_1721")
		)
		(pad "BG7" smd circle
			(at -17.100042 20.899882)
			(size 0.4572 0.4572)
			(layers "F.Cu" "F.Mask" "F.Paste")
			(net "GND")
		)
		(pad "BG8" smd circle
			(at -16.150082 20.899882)
			(size 0.4572 0.4572)
			(layers "F.Cu" "F.Mask" "F.Paste")
			(net "Net_1400")
		)
		(pad "BG9" smd circle
			(at -15.200122 20.899882)
			(size 0.4572 0.4572)
			(layers "F.Cu" "F.Mask" "F.Paste")
			(net "GND")
		)
		(pad "BG10" smd circle
			(at -14.249908 20.899882)
			(size 0.4572 0.4572)
			(layers "F.Cu" "F.Mask" "F.Paste")
			(net "P5E_PEX1_STN2_RX_DN<46>")
		)
		(pad "BG11" smd circle
			(at -13.299948 20.899882)
			(size 0.4572 0.4572)
			(layers "F.Cu" "F.Mask" "F.Paste")
			(net "GND")
		)
		(pad "BG12" smd circle
			(at -12.349988 20.899882)
			(size 0.4572 0.4572)
			(layers "F.Cu" "F.Mask" "F.Paste")
			(net "P5E_PEX1_STN2_RX_DN<44>")
		)
		(pad "BG13" smd circle
			(at -11.400028 20.899882)
			(size 0.4572 0.4572)
			(layers "F.Cu" "F.Mask" "F.Paste")
			(net "GND")
		)
		(pad "BG14" smd circle
			(at -10.450068 20.899882)
			(size 0.4572 0.4572)
			(layers "F.Cu" "F.Mask" "F.Paste")
			(net "P5E_PEX1_STN2_RX_DN<42>")
		)
		(pad "BG15" smd circle
			(at -9.500108 20.899882)
			(size 0.4572 0.4572)
			(layers "F.Cu" "F.Mask" "F.Paste")
			(net "GND")
		)
		(pad "BG16" smd circle
			(at -8.549894 20.899882)
			(size 0.4572 0.4572)
			(layers "F.Cu" "F.Mask" "F.Paste")
			(net "P5E_PEX1_STN2_RX_DN<40>")
		)
		(pad "BG17" smd circle
			(at -7.599934 20.899882)
			(size 0.4572 0.4572)
			(layers "F.Cu" "F.Mask" "F.Paste")
			(net "GND")
		)
		(pad "BG18" smd circle
			(at -6.649974 20.899882)
			(size 0.4572 0.4572)
			(layers "F.Cu" "F.Mask" "F.Paste")
			(net "P5E_PEX1_STN2_RX_DN<38>")
		)
		(pad "BG19" smd circle
			(at -5.700014 20.899882)
			(size 0.4572 0.4572)
			(layers "F.Cu" "F.Mask" "F.Paste")
			(net "GND")
		)
		(pad "BG20" smd circle
			(at -4.750054 20.899882)
			(size 0.4572 0.4572)
			(layers "F.Cu" "F.Mask" "F.Paste")
			(net "P5E_PEX1_STN2_RX_DN<36>")
		)
		(pad "BG21" smd circle
			(at -3.800094 20.899882)
			(size 0.4572 0.4572)
			(layers "F.Cu" "F.Mask" "F.Paste")
			(net "GND")
		)
		(pad "BG22" smd circle
			(at -2.84988 20.899882)
			(size 0.4572 0.4572)
			(layers "F.Cu" "F.Mask" "F.Paste")
			(net "P5E_PEX1_STN2_RX_DN<34>")
		)
		(pad "BG23" smd circle
			(at -1.89992 20.899882)
			(size 0.4572 0.4572)
			(layers "F.Cu" "F.Mask" "F.Paste")
			(net "GND")
		)
		(pad "BG24" smd circle
			(at -0.94996 20.899882)
			(size 0.4572 0.4572)
			(layers "F.Cu" "F.Mask" "F.Paste")
			(net "P5E_PEX1_STN2_RX_DN<32>")
		)
		(pad "BG25" smd circle
			(at 0 20.899882)
			(size 0.4572 0.4572)
			(layers "F.Cu" "F.Mask" "F.Paste")
			(net "GND")
		)
		(pad "BG26" smd circle
			(at 0.94996 20.899882)
			(size 0.4572 0.4572)
			(layers "F.Cu" "F.Mask" "F.Paste")
			(net "P5E_PEX1_STN1_RX_DN<17>")
		)
		(pad "BG27" smd circle
			(at 1.89992 20.899882)
			(size 0.4572 0.4572)
			(layers "F.Cu" "F.Mask" "F.Paste")
			(net "GND")
		)
		(pad "BG28" smd circle
			(at 2.84988 20.899882)
			(size 0.4572 0.4572)
			(layers "F.Cu" "F.Mask" "F.Paste")
			(net "P5E_PEX1_STN1_RX_DN<19>")
		)
		(pad "BG29" smd circle
			(at 3.800094 20.899882)
			(size 0.4572 0.4572)
			(layers "F.Cu" "F.Mask" "F.Paste")
			(net "GND")
		)
		(pad "BG30" smd circle
			(at 4.750054 20.899882)
			(size 0.4572 0.4572)
			(layers "F.Cu" "F.Mask" "F.Paste")
			(net "P5E_PEX1_STN1_RX_DN<21>")
		)
		(pad "BG31" smd circle
			(at 5.700014 20.899882)
			(size 0.4572 0.4572)
			(layers "F.Cu" "F.Mask" "F.Paste")
			(net "GND")
		)
		(pad "BG32" smd circle
			(at 6.649974 20.899882)
			(size 0.4572 0.4572)
			(layers "F.Cu" "F.Mask" "F.Paste")
			(net "P5E_PEX1_STN1_RX_DN<23>")
		)
		(pad "BG33" smd circle
			(at 7.599934 20.899882)
			(size 0.4572 0.4572)
			(layers "F.Cu" "F.Mask" "F.Paste")
			(net "GND")
		)
		(pad "BG34" smd circle
			(at 8.549894 20.899882)
			(size 0.4572 0.4572)
			(layers "F.Cu" "F.Mask" "F.Paste")
			(net "P5E_PEX1_STN1_RX_DN<25>")
		)
		(pad "BG35" smd circle
			(at 9.500108 20.899882)
			(size 0.4572 0.4572)
			(layers "F.Cu" "F.Mask" "F.Paste")
			(net "GND")
		)
		(pad "BG36" smd circle
			(at 10.450068 20.899882)
			(size 0.4572 0.4572)
			(layers "F.Cu" "F.Mask" "F.Paste")
			(net "P5E_PEX1_STN1_RX_DN<27>")
		)
		(pad "BG37" smd circle
			(at 11.400028 20.899882)
			(size 0.4572 0.4572)
			(layers "F.Cu" "F.Mask" "F.Paste")
			(net "GND")
		)
		(pad "BG38" smd circle
			(at 12.349988 20.899882)
			(size 0.4572 0.4572)
			(layers "F.Cu" "F.Mask" "F.Paste")
			(net "P5E_PEX1_STN1_RX_DN<29>")
		)
		(pad "BG39" smd circle
			(at 13.299948 20.899882)
			(size 0.4572 0.4572)
			(layers "F.Cu" "F.Mask" "F.Paste")
			(net "GND")
		)
		(pad "BG40" smd circle
			(at 14.249908 20.899882)
			(size 0.4572 0.4572)
			(layers "F.Cu" "F.Mask" "F.Paste")
			(net "P5E_PEX1_STN1_RX_DN<31>")
		)
		(pad "BG41" smd circle
			(at 15.200122 20.899882)
			(size 0.4572 0.4572)
			(layers "F.Cu" "F.Mask" "F.Paste")
			(net "GND")
		)
		(pad "BG42" smd circle
			(at 16.150082 20.899882)
			(size 0.4572 0.4572)
			(layers "F.Cu" "F.Mask" "F.Paste")
			(net "P5E_PEX1_STN0_RX_DN<14>")
		)
		(pad "BG43" smd circle
			(at 17.100042 20.899882)
			(size 0.4572 0.4572)
			(layers "F.Cu" "F.Mask" "F.Paste")
			(net "GND")
		)
		(pad "BG44" smd circle
			(at 18.050002 20.899882)
			(size 0.4572 0.4572)
			(layers "F.Cu" "F.Mask" "F.Paste")
			(net "P5E_PEX1_STN0_RX_DN<12>")
		)
		(pad "BG45" smd circle
			(at 18.999962 20.899882)
			(size 0.4572 0.4572)
			(layers "F.Cu" "F.Mask" "F.Paste")
			(net "GND")
		)
		(pad "BG46" smd circle
			(at 19.949922 20.899882)
			(size 0.4572 0.4572)
			(layers "F.Cu" "F.Mask" "F.Paste")
			(net "P5E_PEX1_STN0_RX_DN<10>")
		)
		(pad "BG47" smd circle
			(at 20.899882 20.899882)
			(size 0.4572 0.4572)
			(layers "F.Cu" "F.Mask" "F.Paste")
			(net "GND")
		)
		(pad "BG48" smd circle
			(at 21.850096 20.899882)
			(size 0.4572 0.4572)
			(layers "F.Cu" "F.Mask" "F.Paste")
			(net "P5E_PEX1_STN0_RX_DP<8>")
		)
		(pad "BG49" smd circle
			(at 22.800056 20.899882)
			(size 0.4572 0.4572)
			(layers "F.Cu" "F.Mask" "F.Paste")
			(net "P5E_PEX1_STN0_RX_DN<8>")
		)
		(pad "BH1" smd circle
			(at -22.800056 21.850096)
			(size 0.4572 0.4572)
			(layers "F.Cu" "F.Mask" "F.Paste")
			(net "GND")
		)
		(pad "BH2" smd circle
			(at -21.850096 21.850096)
			(size 0.4572 0.4572)
			(layers "F.Cu" "F.Mask" "F.Paste")
			(net "GND")
		)
		(pad "BH3" smd circle
			(at -20.899882 21.850096)
			(size 0.4572 0.4572)
			(layers "F.Cu" "F.Mask" "F.Paste")
			(net "Net_1730")
		)
		(pad "BH4" smd circle
			(at -19.949922 21.850096)
			(size 0.4572 0.4572)
			(layers "F.Cu" "F.Mask" "F.Paste")
			(net "GND")
		)
		(pad "BH5" smd circle
			(at -18.999962 21.850096)
			(size 0.4572 0.4572)
			(layers "F.Cu" "F.Mask" "F.Paste")
			(net "Net_1719")
		)
		(pad "BH6" smd circle
			(at -18.050002 21.850096)
			(size 0.4572 0.4572)
			(layers "F.Cu" "F.Mask" "F.Paste")
			(net "GND")
		)
		(pad "BH7" smd circle
			(at -17.100042 21.850096)
			(size 0.4572 0.4572)
			(layers "F.Cu" "F.Mask" "F.Paste")
			(net "Net_1717")
		)
		(pad "BH8" smd circle
			(at -16.150082 21.850096)
			(size 0.4572 0.4572)
			(layers "F.Cu" "F.Mask" "F.Paste")
			(net "GND")
		)
		(pad "BH9" smd circle
			(at -15.200122 21.850096)
			(size 0.4572 0.4572)
			(layers "F.Cu" "F.Mask" "F.Paste")
			(net "P5E_PEX1_STN2_RX_DP<47>")
		)
		(pad "BH10" smd circle
			(at -14.249908 21.850096)
			(size 0.4572 0.4572)
			(layers "F.Cu" "F.Mask" "F.Paste")
			(net "GND")
		)
		(pad "BH11" smd circle
			(at -13.299948 21.850096)
			(size 0.4572 0.4572)
			(layers "F.Cu" "F.Mask" "F.Paste")
			(net "P5E_PEX1_STN2_RX_DP<45>")
		)
		(pad "BH12" smd circle
			(at -12.349988 21.850096)
			(size 0.4572 0.4572)
			(layers "F.Cu" "F.Mask" "F.Paste")
			(net "GND")
		)
		(pad "BH13" smd circle
			(at -11.400028 21.850096)
			(size 0.4572 0.4572)
			(layers "F.Cu" "F.Mask" "F.Paste")
			(net "P5E_PEX1_STN2_RX_DP<43>")
		)
		(pad "BH14" smd circle
			(at -10.450068 21.850096)
			(size 0.4572 0.4572)
			(layers "F.Cu" "F.Mask" "F.Paste")
			(net "GND")
		)
		(pad "BH15" smd circle
			(at -9.500108 21.850096)
			(size 0.4572 0.4572)
			(layers "F.Cu" "F.Mask" "F.Paste")
			(net "P5E_PEX1_STN2_RX_DP<41>")
		)
		(pad "BH16" smd circle
			(at -8.549894 21.850096)
			(size 0.4572 0.4572)
			(layers "F.Cu" "F.Mask" "F.Paste")
			(net "GND")
		)
		(pad "BH17" smd circle
			(at -7.599934 21.850096)
			(size 0.4572 0.4572)
			(layers "F.Cu" "F.Mask" "F.Paste")
			(net "P5E_PEX1_STN2_RX_DP<39>")
		)
		(pad "BH18" smd circle
			(at -6.649974 21.850096)
			(size 0.4572 0.4572)
			(layers "F.Cu" "F.Mask" "F.Paste")
			(net "GND")
		)
		(pad "BH19" smd circle
			(at -5.700014 21.850096)
			(size 0.4572 0.4572)
			(layers "F.Cu" "F.Mask" "F.Paste")
			(net "P5E_PEX1_STN2_RX_DP<37>")
		)
		(pad "BH20" smd circle
			(at -4.750054 21.850096)
			(size 0.4572 0.4572)
			(layers "F.Cu" "F.Mask" "F.Paste")
			(net "GND")
		)
		(pad "BH21" smd circle
			(at -3.800094 21.850096)
			(size 0.4572 0.4572)
			(layers "F.Cu" "F.Mask" "F.Paste")
			(net "P5E_PEX1_STN2_RX_DP<35>")
		)
		(pad "BH22" smd circle
			(at -2.84988 21.850096)
			(size 0.4572 0.4572)
			(layers "F.Cu" "F.Mask" "F.Paste")
			(net "GND")
		)
		(pad "BH23" smd circle
			(at -1.89992 21.850096)
			(size 0.4572 0.4572)
			(layers "F.Cu" "F.Mask" "F.Paste")
			(net "P5E_PEX1_STN2_RX_DP<33>")
		)
		(pad "BH24" smd circle
			(at -0.94996 21.850096)
			(size 0.4572 0.4572)
			(layers "F.Cu" "F.Mask" "F.Paste")
			(net "GND")
		)
		(pad "BH25" smd circle
			(at 0 21.850096)
			(size 0.4572 0.4572)
			(layers "F.Cu" "F.Mask" "F.Paste")
			(net "P5E_PEX1_STN1_RX_DP<16>")
		)
		(pad "BH26" smd circle
			(at 0.94996 21.850096)
			(size 0.4572 0.4572)
			(layers "F.Cu" "F.Mask" "F.Paste")
			(net "GND")
		)
		(pad "BH27" smd circle
			(at 1.89992 21.850096)
			(size 0.4572 0.4572)
			(layers "F.Cu" "F.Mask" "F.Paste")
			(net "P5E_PEX1_STN1_RX_DP<18>")
		)
		(pad "BH28" smd circle
			(at 2.84988 21.850096)
			(size 0.4572 0.4572)
			(layers "F.Cu" "F.Mask" "F.Paste")
			(net "GND")
		)
		(pad "BH29" smd circle
			(at 3.800094 21.850096)
			(size 0.4572 0.4572)
			(layers "F.Cu" "F.Mask" "F.Paste")
			(net "P5E_PEX1_STN1_RX_DP<20>")
		)
		(pad "BH30" smd circle
			(at 4.750054 21.850096)
			(size 0.4572 0.4572)
			(layers "F.Cu" "F.Mask" "F.Paste")
			(net "GND")
		)
		(pad "BH31" smd circle
			(at 5.700014 21.850096)
			(size 0.4572 0.4572)
			(layers "F.Cu" "F.Mask" "F.Paste")
			(net "P5E_PEX1_STN1_RX_DP<22>")
		)
		(pad "BH32" smd circle
			(at 6.649974 21.850096)
			(size 0.4572 0.4572)
			(layers "F.Cu" "F.Mask" "F.Paste")
			(net "GND")
		)
		(pad "BH33" smd circle
			(at 7.599934 21.850096)
			(size 0.4572 0.4572)
			(layers "F.Cu" "F.Mask" "F.Paste")
			(net "P5E_PEX1_STN1_RX_DP<24>")
		)
		(pad "BH34" smd circle
			(at 8.549894 21.850096)
			(size 0.4572 0.4572)
			(layers "F.Cu" "F.Mask" "F.Paste")
			(net "GND")
		)
		(pad "BH35" smd circle
			(at 9.500108 21.850096)
			(size 0.4572 0.4572)
			(layers "F.Cu" "F.Mask" "F.Paste")
			(net "P5E_PEX1_STN1_RX_DP<26>")
		)
		(pad "BH36" smd circle
			(at 10.450068 21.850096)
			(size 0.4572 0.4572)
			(layers "F.Cu" "F.Mask" "F.Paste")
			(net "GND")
		)
		(pad "BH37" smd circle
			(at 11.400028 21.850096)
			(size 0.4572 0.4572)
			(layers "F.Cu" "F.Mask" "F.Paste")
			(net "P5E_PEX1_STN1_RX_DP<28>")
		)
		(pad "BH38" smd circle
			(at 12.349988 21.850096)
			(size 0.4572 0.4572)
			(layers "F.Cu" "F.Mask" "F.Paste")
			(net "GND")
		)
		(pad "BH39" smd circle
			(at 13.299948 21.850096)
			(size 0.4572 0.4572)
			(layers "F.Cu" "F.Mask" "F.Paste")
			(net "P5E_PEX1_STN1_RX_DP<30>")
		)
		(pad "BH40" smd circle
			(at 14.249908 21.850096)
			(size 0.4572 0.4572)
			(layers "F.Cu" "F.Mask" "F.Paste")
			(net "GND")
		)
		(pad "BH41" smd circle
			(at 15.200122 21.850096)
			(size 0.4572 0.4572)
			(layers "F.Cu" "F.Mask" "F.Paste")
			(net "P5E_PEX1_STN0_RX_DP<15>")
		)
		(pad "BH42" smd circle
			(at 16.150082 21.850096)
			(size 0.4572 0.4572)
			(layers "F.Cu" "F.Mask" "F.Paste")
			(net "GND")
		)
		(pad "BH43" smd circle
			(at 17.100042 21.850096)
			(size 0.4572 0.4572)
			(layers "F.Cu" "F.Mask" "F.Paste")
			(net "P5E_PEX1_STN0_RX_DP<13>")
		)
		(pad "BH44" smd circle
			(at 18.050002 21.850096)
			(size 0.4572 0.4572)
			(layers "F.Cu" "F.Mask" "F.Paste")
			(net "GND")
		)
		(pad "BH45" smd circle
			(at 18.999962 21.850096)
			(size 0.4572 0.4572)
			(layers "F.Cu" "F.Mask" "F.Paste")
			(net "P5E_PEX1_STN0_RX_DP<11>")
		)
		(pad "BH46" smd circle
			(at 19.949922 21.850096)
			(size 0.4572 0.4572)
			(layers "F.Cu" "F.Mask" "F.Paste")
			(net "GND")
		)
		(pad "BH47" smd circle
			(at 20.899882 21.850096)
			(size 0.4572 0.4572)
			(layers "F.Cu" "F.Mask" "F.Paste")
			(net "P5E_PEX1_STN0_RX_DP<9>")
		)
		(pad "BH48" smd circle
			(at 21.850096 21.850096)
			(size 0.4572 0.4572)
			(layers "F.Cu" "F.Mask" "F.Paste")
			(net "GND")
		)
		(pad "BH49" smd circle
			(at 22.800056 21.850096)
			(size 0.4572 0.4572)
			(layers "F.Cu" "F.Mask" "F.Paste")
			(net "GND")
		)
		(pad "BJ2" smd circle
			(at -21.850096 22.800056)
			(size 0.4572 0.4572)
			(layers "F.Cu" "F.Mask" "F.Paste")
			(net "GND")
		)
		(pad "BJ3" smd circle
			(at -20.899882 22.800056)
			(size 0.4572 0.4572)
			(layers "F.Cu" "F.Mask" "F.Paste")
			(net "Net_1380")
		)
		(pad "BJ4" smd circle
			(at -19.949922 22.800056)
			(size 0.4572 0.4572)
			(layers "F.Cu" "F.Mask" "F.Paste")
			(net "GND")
		)
		(pad "BJ5" smd circle
			(at -18.999962 22.800056)
			(size 0.4572 0.4572)
			(layers "F.Cu" "F.Mask" "F.Paste")
			(net "Net_1723")
		)
		(pad "BJ6" smd circle
			(at -18.050002 22.800056)
			(size 0.4572 0.4572)
			(layers "F.Cu" "F.Mask" "F.Paste")
			(net "GND")
		)
		(pad "BJ7" smd circle
			(at -17.100042 22.800056)
			(size 0.4572 0.4572)
			(layers "F.Cu" "F.Mask" "F.Paste")
			(net "Net_1418")
		)
		(pad "BJ8" smd circle
			(at -16.150082 22.800056)
			(size 0.4572 0.4572)
			(layers "F.Cu" "F.Mask" "F.Paste")
			(net "GND")
		)
		(pad "BJ9" smd circle
			(at -15.200122 22.800056)
			(size 0.4572 0.4572)
			(layers "F.Cu" "F.Mask" "F.Paste")
			(net "P5E_PEX1_STN2_RX_DN<47>")
		)
		(pad "BJ10" smd circle
			(at -14.249908 22.800056)
			(size 0.4572 0.4572)
			(layers "F.Cu" "F.Mask" "F.Paste")
			(net "GND")
		)
		(pad "BJ11" smd circle
			(at -13.299948 22.800056)
			(size 0.4572 0.4572)
			(layers "F.Cu" "F.Mask" "F.Paste")
			(net "P5E_PEX1_STN2_RX_DN<45>")
		)
		(pad "BJ12" smd circle
			(at -12.349988 22.800056)
			(size 0.4572 0.4572)
			(layers "F.Cu" "F.Mask" "F.Paste")
			(net "GND")
		)
		(pad "BJ13" smd circle
			(at -11.400028 22.800056)
			(size 0.4572 0.4572)
			(layers "F.Cu" "F.Mask" "F.Paste")
			(net "P5E_PEX1_STN2_RX_DN<43>")
		)
		(pad "BJ14" smd circle
			(at -10.450068 22.800056)
			(size 0.4572 0.4572)
			(layers "F.Cu" "F.Mask" "F.Paste")
			(net "GND")
		)
		(pad "BJ15" smd circle
			(at -9.500108 22.800056)
			(size 0.4572 0.4572)
			(layers "F.Cu" "F.Mask" "F.Paste")
			(net "P5E_PEX1_STN2_RX_DN<41>")
		)
		(pad "BJ16" smd circle
			(at -8.549894 22.800056)
			(size 0.4572 0.4572)
			(layers "F.Cu" "F.Mask" "F.Paste")
			(net "GND")
		)
		(pad "BJ17" smd circle
			(at -7.599934 22.800056)
			(size 0.4572 0.4572)
			(layers "F.Cu" "F.Mask" "F.Paste")
			(net "P5E_PEX1_STN2_RX_DN<39>")
		)
		(pad "BJ18" smd circle
			(at -6.649974 22.800056)
			(size 0.4572 0.4572)
			(layers "F.Cu" "F.Mask" "F.Paste")
			(net "GND")
		)
		(pad "BJ19" smd circle
			(at -5.700014 22.800056)
			(size 0.4572 0.4572)
			(layers "F.Cu" "F.Mask" "F.Paste")
			(net "P5E_PEX1_STN2_RX_DN<37>")
		)
		(pad "BJ20" smd circle
			(at -4.750054 22.800056)
			(size 0.4572 0.4572)
			(layers "F.Cu" "F.Mask" "F.Paste")
			(net "GND")
		)
		(pad "BJ21" smd circle
			(at -3.800094 22.800056)
			(size 0.4572 0.4572)
			(layers "F.Cu" "F.Mask" "F.Paste")
			(net "P5E_PEX1_STN2_RX_DN<35>")
		)
		(pad "BJ22" smd circle
			(at -2.84988 22.800056)
			(size 0.4572 0.4572)
			(layers "F.Cu" "F.Mask" "F.Paste")
			(net "GND")
		)
		(pad "BJ23" smd circle
			(at -1.89992 22.800056)
			(size 0.4572 0.4572)
			(layers "F.Cu" "F.Mask" "F.Paste")
			(net "P5E_PEX1_STN2_RX_DN<33>")
		)
		(pad "BJ24" smd circle
			(at -0.94996 22.800056)
			(size 0.4572 0.4572)
			(layers "F.Cu" "F.Mask" "F.Paste")
			(net "GND")
		)
		(pad "BJ25" smd circle
			(at 0 22.800056)
			(size 0.4572 0.4572)
			(layers "F.Cu" "F.Mask" "F.Paste")
			(net "P5E_PEX1_STN1_RX_DN<16>")
		)
		(pad "BJ26" smd circle
			(at 0.94996 22.800056)
			(size 0.4572 0.4572)
			(layers "F.Cu" "F.Mask" "F.Paste")
			(net "GND")
		)
		(pad "BJ27" smd circle
			(at 1.89992 22.800056)
			(size 0.4572 0.4572)
			(layers "F.Cu" "F.Mask" "F.Paste")
			(net "P5E_PEX1_STN1_RX_DN<18>")
		)
		(pad "BJ28" smd circle
			(at 2.84988 22.800056)
			(size 0.4572 0.4572)
			(layers "F.Cu" "F.Mask" "F.Paste")
			(net "GND")
		)
		(pad "BJ29" smd circle
			(at 3.800094 22.800056)
			(size 0.4572 0.4572)
			(layers "F.Cu" "F.Mask" "F.Paste")
			(net "P5E_PEX1_STN1_RX_DN<20>")
		)
		(pad "BJ30" smd circle
			(at 4.750054 22.800056)
			(size 0.4572 0.4572)
			(layers "F.Cu" "F.Mask" "F.Paste")
			(net "GND")
		)
		(pad "BJ31" smd circle
			(at 5.700014 22.800056)
			(size 0.4572 0.4572)
			(layers "F.Cu" "F.Mask" "F.Paste")
			(net "P5E_PEX1_STN1_RX_DN<22>")
		)
		(pad "BJ32" smd circle
			(at 6.649974 22.800056)
			(size 0.4572 0.4572)
			(layers "F.Cu" "F.Mask" "F.Paste")
			(net "GND")
		)
		(pad "BJ33" smd circle
			(at 7.599934 22.800056)
			(size 0.4572 0.4572)
			(layers "F.Cu" "F.Mask" "F.Paste")
			(net "P5E_PEX1_STN1_RX_DN<24>")
		)
		(pad "BJ34" smd circle
			(at 8.549894 22.800056)
			(size 0.4572 0.4572)
			(layers "F.Cu" "F.Mask" "F.Paste")
			(net "GND")
		)
		(pad "BJ35" smd circle
			(at 9.500108 22.800056)
			(size 0.4572 0.4572)
			(layers "F.Cu" "F.Mask" "F.Paste")
			(net "P5E_PEX1_STN1_RX_DN<26>")
		)
		(pad "BJ36" smd circle
			(at 10.450068 22.800056)
			(size 0.4572 0.4572)
			(layers "F.Cu" "F.Mask" "F.Paste")
			(net "GND")
		)
		(pad "BJ37" smd circle
			(at 11.400028 22.800056)
			(size 0.4572 0.4572)
			(layers "F.Cu" "F.Mask" "F.Paste")
			(net "P5E_PEX1_STN1_RX_DN<28>")
		)
		(pad "BJ38" smd circle
			(at 12.349988 22.800056)
			(size 0.4572 0.4572)
			(layers "F.Cu" "F.Mask" "F.Paste")
			(net "GND")
		)
		(pad "BJ39" smd circle
			(at 13.299948 22.800056)
			(size 0.4572 0.4572)
			(layers "F.Cu" "F.Mask" "F.Paste")
			(net "P5E_PEX1_STN1_RX_DN<30>")
		)
		(pad "BJ40" smd circle
			(at 14.249908 22.800056)
			(size 0.4572 0.4572)
			(layers "F.Cu" "F.Mask" "F.Paste")
			(net "GND")
		)
		(pad "BJ41" smd circle
			(at 15.200122 22.800056)
			(size 0.4572 0.4572)
			(layers "F.Cu" "F.Mask" "F.Paste")
			(net "P5E_PEX1_STN0_RX_DN<15>")
		)
		(pad "BJ42" smd circle
			(at 16.150082 22.800056)
			(size 0.4572 0.4572)
			(layers "F.Cu" "F.Mask" "F.Paste")
			(net "GND")
		)
		(pad "BJ43" smd circle
			(at 17.100042 22.800056)
			(size 0.4572 0.4572)
			(layers "F.Cu" "F.Mask" "F.Paste")
			(net "P5E_PEX1_STN0_RX_DN<13>")
		)
		(pad "BJ44" smd circle
			(at 18.050002 22.800056)
			(size 0.4572 0.4572)
			(layers "F.Cu" "F.Mask" "F.Paste")
			(net "GND")
		)
		(pad "BJ45" smd circle
			(at 18.999962 22.800056)
			(size 0.4572 0.4572)
			(layers "F.Cu" "F.Mask" "F.Paste")
			(net "P5E_PEX1_STN0_RX_DN<11>")
		)
		(pad "BJ46" smd circle
			(at 19.949922 22.800056)
			(size 0.4572 0.4572)
			(layers "F.Cu" "F.Mask" "F.Paste")
			(net "GND")
		)
		(pad "BJ47" smd circle
			(at 20.899882 22.800056)
			(size 0.4572 0.4572)
			(layers "F.Cu" "F.Mask" "F.Paste")
			(net "P5E_PEX1_STN0_RX_DN<9>")
		)
		(pad "BJ48" smd circle
			(at 21.850096 22.800056)
			(size 0.4572 0.4572)
			(layers "F.Cu" "F.Mask" "F.Paste")
			(net "GND")
		)
		(pad "C1" smd circle
			(at -22.800056 -20.899882)
			(size 0.4572 0.4572)
			(layers "F.Cu" "F.Mask" "F.Paste")
			(net "P5E_PEX1_STN7_RX_DN<122>")
		)
		(pad "C2" smd circle
			(at -21.850096 -20.899882)
			(size 0.4572 0.4572)
			(layers "F.Cu" "F.Mask" "F.Paste")
			(net "P5E_PEX1_STN7_RX_DP<122>")
		)
		(pad "C3" smd circle
			(at -20.899882 -20.899882)
			(size 0.4572 0.4572)
			(layers "F.Cu" "F.Mask" "F.Paste")
			(net "GND")
		)
		(pad "C4" smd circle
			(at -19.949922 -20.899882)
			(size 0.4572 0.4572)
			(layers "F.Cu" "F.Mask" "F.Paste")
			(net "P5E_PEX1_STN7_RX_DN<124>")
		)
		(pad "C5" smd circle
			(at -18.999962 -20.899882)
			(size 0.4572 0.4572)
			(layers "F.Cu" "F.Mask" "F.Paste")
			(net "GND")
		)
		(pad "C6" smd circle
			(at -18.050002 -20.899882)
			(size 0.4572 0.4572)
			(layers "F.Cu" "F.Mask" "F.Paste")
			(net "P5E_PEX1_STN7_RX_DN<126>")
		)
		(pad "C7" smd circle
			(at -17.100042 -20.899882)
			(size 0.4572 0.4572)
			(layers "F.Cu" "F.Mask" "F.Paste")
			(net "GND")
		)
		(pad "C8" smd circle
			(at -16.150082 -20.899882)
			(size 0.4572 0.4572)
			(layers "F.Cu" "F.Mask" "F.Paste")
			(net "P5E_PEX1_STN6_RX_DN<111>")
		)
		(pad "C9" smd circle
			(at -15.200122 -20.899882)
			(size 0.4572 0.4572)
			(layers "F.Cu" "F.Mask" "F.Paste")
			(net "GND")
		)
		(pad "C10" smd circle
			(at -14.249908 -20.899882)
			(size 0.4572 0.4572)
			(layers "F.Cu" "F.Mask" "F.Paste")
			(net "P5E_PEX1_STN6_RX_DN<109>")
		)
		(pad "C11" smd circle
			(at -13.299948 -20.899882)
			(size 0.4572 0.4572)
			(layers "F.Cu" "F.Mask" "F.Paste")
			(net "GND")
		)
		(pad "C12" smd circle
			(at -12.349988 -20.899882)
			(size 0.4572 0.4572)
			(layers "F.Cu" "F.Mask" "F.Paste")
			(net "P5E_PEX1_STN6_RX_DN<107>")
		)
		(pad "C13" smd circle
			(at -11.400028 -20.899882)
			(size 0.4572 0.4572)
			(layers "F.Cu" "F.Mask" "F.Paste")
			(net "GND")
		)
		(pad "C14" smd circle
			(at -10.450068 -20.899882)
			(size 0.4572 0.4572)
			(layers "F.Cu" "F.Mask" "F.Paste")
			(net "P5E_PEX1_STN6_RX_DN<105>")
		)
		(pad "C15" smd circle
			(at -9.500108 -20.899882)
			(size 0.4572 0.4572)
			(layers "F.Cu" "F.Mask" "F.Paste")
			(net "GND")
		)
		(pad "C16" smd circle
			(at -8.549894 -20.899882)
			(size 0.4572 0.4572)
			(layers "F.Cu" "F.Mask" "F.Paste")
			(net "P5E_PEX1_STN6_RX_DN<103>")
		)
		(pad "C17" smd circle
			(at -7.599934 -20.899882)
			(size 0.4572 0.4572)
			(layers "F.Cu" "F.Mask" "F.Paste")
			(net "GND")
		)
		(pad "C18" smd circle
			(at -6.649974 -20.899882)
			(size 0.4572 0.4572)
			(layers "F.Cu" "F.Mask" "F.Paste")
			(net "P5E_PEX1_STN6_RX_DN<101>")
		)
		(pad "C19" smd circle
			(at -5.700014 -20.899882)
			(size 0.4572 0.4572)
			(layers "F.Cu" "F.Mask" "F.Paste")
			(net "GND")
		)
		(pad "C20" smd circle
			(at -4.750054 -20.899882)
			(size 0.4572 0.4572)
			(layers "F.Cu" "F.Mask" "F.Paste")
			(net "P5E_PEX1_STN6_RX_DN<99>")
		)
		(pad "C21" smd circle
			(at -3.800094 -20.899882)
			(size 0.4572 0.4572)
			(layers "F.Cu" "F.Mask" "F.Paste")
			(net "GND")
		)
		(pad "C22" smd circle
			(at -2.84988 -20.899882)
			(size 0.4572 0.4572)
			(layers "F.Cu" "F.Mask" "F.Paste")
			(net "P5E_PEX1_STN6_RX_DN<97>")
		)
		(pad "C23" smd circle
			(at -1.89992 -20.899882)
			(size 0.4572 0.4572)
			(layers "F.Cu" "F.Mask" "F.Paste")
			(net "GND")
		)
		(pad "C24" smd circle
			(at -0.94996 -20.899882)
			(size 0.4572 0.4572)
			(layers "F.Cu" "F.Mask" "F.Paste")
			(net "P5E_PEX1_STN5_RX_DN<80>")
		)
		(pad "C25" smd circle
			(at 0 -20.899882)
			(size 0.4572 0.4572)
			(layers "F.Cu" "F.Mask" "F.Paste")
			(net "GND")
		)
		(pad "C26" smd circle
			(at 0.94996 -20.899882)
			(size 0.4572 0.4572)
			(layers "F.Cu" "F.Mask" "F.Paste")
			(net "P5E_PEX1_STN5_RX_DN<82>")
		)
		(pad "C27" smd circle
			(at 1.89992 -20.899882)
			(size 0.4572 0.4572)
			(layers "F.Cu" "F.Mask" "F.Paste")
			(net "GND")
		)
		(pad "C28" smd circle
			(at 2.84988 -20.899882)
			(size 0.4572 0.4572)
			(layers "F.Cu" "F.Mask" "F.Paste")
			(net "P5E_PEX1_STN5_RX_DN<84>")
		)
		(pad "C29" smd circle
			(at 3.800094 -20.899882)
			(size 0.4572 0.4572)
			(layers "F.Cu" "F.Mask" "F.Paste")
			(net "GND")
		)
		(pad "C30" smd circle
			(at 4.750054 -20.899882)
			(size 0.4572 0.4572)
			(layers "F.Cu" "F.Mask" "F.Paste")
			(net "P5E_PEX1_STN5_RX_DN<86>")
		)
		(pad "C31" smd circle
			(at 5.700014 -20.899882)
			(size 0.4572 0.4572)
			(layers "F.Cu" "F.Mask" "F.Paste")
			(net "GND")
		)
		(pad "C32" smd circle
			(at 6.649974 -20.899882)
			(size 0.4572 0.4572)
			(layers "F.Cu" "F.Mask" "F.Paste")
			(net "P5E_PEX1_STN5_RX_DN<88>")
		)
		(pad "C33" smd circle
			(at 7.599934 -20.899882)
			(size 0.4572 0.4572)
			(layers "F.Cu" "F.Mask" "F.Paste")
			(net "GND")
		)
		(pad "C34" smd circle
			(at 8.549894 -20.899882)
			(size 0.4572 0.4572)
			(layers "F.Cu" "F.Mask" "F.Paste")
			(net "P5E_PEX1_STN5_RX_DN<90>")
		)
		(pad "C35" smd circle
			(at 9.500108 -20.899882)
			(size 0.4572 0.4572)
			(layers "F.Cu" "F.Mask" "F.Paste")
			(net "GND")
		)
		(pad "C36" smd circle
			(at 10.450068 -20.899882)
			(size 0.4572 0.4572)
			(layers "F.Cu" "F.Mask" "F.Paste")
			(net "P5E_PEX1_STN5_RX_DN<92>")
		)
		(pad "C37" smd circle
			(at 11.400028 -20.899882)
			(size 0.4572 0.4572)
			(layers "F.Cu" "F.Mask" "F.Paste")
			(net "GND")
		)
		(pad "C38" smd circle
			(at 12.349988 -20.899882)
			(size 0.4572 0.4572)
			(layers "F.Cu" "F.Mask" "F.Paste")
			(net "P5E_PEX1_STN5_RX_DN<94>")
		)
		(pad "C39" smd circle
			(at 13.299948 -20.899882)
			(size 0.4572 0.4572)
			(layers "F.Cu" "F.Mask" "F.Paste")
			(net "GND")
		)
		(pad "C40" smd circle
			(at 14.249908 -20.899882)
			(size 0.4572 0.4572)
			(layers "F.Cu" "F.Mask" "F.Paste")
			(net "P5E_PEX1_STN4_RX_DN<79>")
		)
		(pad "C41" smd circle
			(at 15.200122 -20.899882)
			(size 0.4572 0.4572)
			(layers "F.Cu" "F.Mask" "F.Paste")
			(net "GND")
		)
		(pad "C42" smd circle
			(at 16.150082 -20.899882)
			(size 0.4572 0.4572)
			(layers "F.Cu" "F.Mask" "F.Paste")
			(net "P5E_PEX1_STN4_RX_DN<77>")
		)
		(pad "C43" smd circle
			(at 17.100042 -20.899882)
			(size 0.4572 0.4572)
			(layers "F.Cu" "F.Mask" "F.Paste")
			(net "GND")
		)
		(pad "C44" smd circle
			(at 18.050002 -20.899882)
			(size 0.4572 0.4572)
			(layers "F.Cu" "F.Mask" "F.Paste")
			(net "P5E_PEX1_STN4_RX_DN<75>")
		)
		(pad "C45" smd circle
			(at 18.999962 -20.899882)
			(size 0.4572 0.4572)
			(layers "F.Cu" "F.Mask" "F.Paste")
			(net "GND")
		)
		(pad "C46" smd circle
			(at 19.949922 -20.899882)
			(size 0.4572 0.4572)
			(layers "F.Cu" "F.Mask" "F.Paste")
			(net "P5E_PEX1_STN4_RX_DN<73>")
		)
		(pad "C47" smd circle
			(at 20.899882 -20.899882)
			(size 0.4572 0.4572)
			(layers "F.Cu" "F.Mask" "F.Paste")
			(net "GND")
		)
		(pad "C48" smd circle
			(at 21.850096 -20.899882)
			(size 0.4572 0.4572)
			(layers "F.Cu" "F.Mask" "F.Paste")
			(net "P5E_PEX1_STN4_RX_DP<71>")
		)
		(pad "C49" smd circle
			(at 22.800056 -20.899882)
			(size 0.4572 0.4572)
			(layers "F.Cu" "F.Mask" "F.Paste")
			(net "P5E_PEX1_STN4_RX_DN<71>")
		)
		(pad "D1" smd circle
			(at -22.800056 -19.949922)
			(size 0.4572 0.4572)
			(layers "F.Cu" "F.Mask" "F.Paste")
			(net "GND")
		)
		(pad "D2" smd circle
			(at -21.850096 -19.949922)
			(size 0.4572 0.4572)
			(layers "F.Cu" "F.Mask" "F.Paste")
			(net "GND")
		)
		(pad "D3" smd circle
			(at -20.899882 -19.949922)
			(size 0.4572 0.4572)
			(layers "F.Cu" "F.Mask" "F.Paste")
			(net "GND")
		)
		(pad "D4" smd circle
			(at -19.949922 -19.949922)
			(size 0.4572 0.4572)
			(layers "F.Cu" "F.Mask" "F.Paste")
			(net "P5E_PEX1_STN7_RX_DP<124>")
		)
		(pad "D5" smd circle
			(at -18.999962 -19.949922)
			(size 0.4572 0.4572)
			(layers "F.Cu" "F.Mask" "F.Paste")
			(net "GND")
		)
		(pad "D6" smd circle
			(at -18.050002 -19.949922)
			(size 0.4572 0.4572)
			(layers "F.Cu" "F.Mask" "F.Paste")
			(net "P5E_PEX1_STN7_RX_DP<126>")
		)
		(pad "D7" smd circle
			(at -17.100042 -19.949922)
			(size 0.4572 0.4572)
			(layers "F.Cu" "F.Mask" "F.Paste")
			(net "GND")
		)
		(pad "D8" smd circle
			(at -16.150082 -19.949922)
			(size 0.4572 0.4572)
			(layers "F.Cu" "F.Mask" "F.Paste")
			(net "P5E_PEX1_STN6_RX_DP<111>")
		)
		(pad "D9" smd circle
			(at -15.200122 -19.949922)
			(size 0.4572 0.4572)
			(layers "F.Cu" "F.Mask" "F.Paste")
			(net "GND")
		)
		(pad "D10" smd circle
			(at -14.249908 -19.949922)
			(size 0.4572 0.4572)
			(layers "F.Cu" "F.Mask" "F.Paste")
			(net "P5E_PEX1_STN6_RX_DP<109>")
		)
		(pad "D11" smd circle
			(at -13.299948 -19.949922)
			(size 0.4572 0.4572)
			(layers "F.Cu" "F.Mask" "F.Paste")
			(net "GND")
		)
		(pad "D12" smd circle
			(at -12.349988 -19.949922)
			(size 0.4572 0.4572)
			(layers "F.Cu" "F.Mask" "F.Paste")
			(net "P5E_PEX1_STN6_RX_DP<107>")
		)
		(pad "D13" smd circle
			(at -11.400028 -19.949922)
			(size 0.4572 0.4572)
			(layers "F.Cu" "F.Mask" "F.Paste")
			(net "GND")
		)
		(pad "D14" smd circle
			(at -10.450068 -19.949922)
			(size 0.4572 0.4572)
			(layers "F.Cu" "F.Mask" "F.Paste")
			(net "P5E_PEX1_STN6_RX_DP<105>")
		)
		(pad "D15" smd circle
			(at -9.500108 -19.949922)
			(size 0.4572 0.4572)
			(layers "F.Cu" "F.Mask" "F.Paste")
			(net "GND")
		)
		(pad "D16" smd circle
			(at -8.549894 -19.949922)
			(size 0.4572 0.4572)
			(layers "F.Cu" "F.Mask" "F.Paste")
			(net "P5E_PEX1_STN6_RX_DP<103>")
		)
		(pad "D17" smd circle
			(at -7.599934 -19.949922)
			(size 0.4572 0.4572)
			(layers "F.Cu" "F.Mask" "F.Paste")
			(net "GND")
		)
		(pad "D18" smd circle
			(at -6.649974 -19.949922)
			(size 0.4572 0.4572)
			(layers "F.Cu" "F.Mask" "F.Paste")
			(net "P5E_PEX1_STN6_RX_DP<101>")
		)
		(pad "D19" smd circle
			(at -5.700014 -19.949922)
			(size 0.4572 0.4572)
			(layers "F.Cu" "F.Mask" "F.Paste")
			(net "GND")
		)
		(pad "D20" smd circle
			(at -4.750054 -19.949922)
			(size 0.4572 0.4572)
			(layers "F.Cu" "F.Mask" "F.Paste")
			(net "P5E_PEX1_STN6_RX_DP<99>")
		)
		(pad "D21" smd circle
			(at -3.800094 -19.949922)
			(size 0.4572 0.4572)
			(layers "F.Cu" "F.Mask" "F.Paste")
			(net "GND")
		)
		(pad "D22" smd circle
			(at -2.84988 -19.949922)
			(size 0.4572 0.4572)
			(layers "F.Cu" "F.Mask" "F.Paste")
			(net "P5E_PEX1_STN6_RX_DP<97>")
		)
		(pad "D23" smd circle
			(at -1.89992 -19.949922)
			(size 0.4572 0.4572)
			(layers "F.Cu" "F.Mask" "F.Paste")
			(net "GND")
		)
		(pad "D24" smd circle
			(at -0.94996 -19.949922)
			(size 0.4572 0.4572)
			(layers "F.Cu" "F.Mask" "F.Paste")
			(net "P5E_PEX1_STN5_RX_DP<80>")
		)
		(pad "D25" smd circle
			(at 0 -19.949922)
			(size 0.4572 0.4572)
			(layers "F.Cu" "F.Mask" "F.Paste")
			(net "GND")
		)
		(pad "D26" smd circle
			(at 0.94996 -19.949922)
			(size 0.4572 0.4572)
			(layers "F.Cu" "F.Mask" "F.Paste")
			(net "P5E_PEX1_STN5_RX_DP<82>")
		)
		(pad "D27" smd circle
			(at 1.89992 -19.949922)
			(size 0.4572 0.4572)
			(layers "F.Cu" "F.Mask" "F.Paste")
			(net "GND")
		)
		(pad "D28" smd circle
			(at 2.84988 -19.949922)
			(size 0.4572 0.4572)
			(layers "F.Cu" "F.Mask" "F.Paste")
			(net "P5E_PEX1_STN5_RX_DP<84>")
		)
		(pad "D29" smd circle
			(at 3.800094 -19.949922)
			(size 0.4572 0.4572)
			(layers "F.Cu" "F.Mask" "F.Paste")
			(net "GND")
		)
		(pad "D30" smd circle
			(at 4.750054 -19.949922)
			(size 0.4572 0.4572)
			(layers "F.Cu" "F.Mask" "F.Paste")
			(net "P5E_PEX1_STN5_RX_DP<86>")
		)
		(pad "D31" smd circle
			(at 5.700014 -19.949922)
			(size 0.4572 0.4572)
			(layers "F.Cu" "F.Mask" "F.Paste")
			(net "GND")
		)
		(pad "D32" smd circle
			(at 6.649974 -19.949922)
			(size 0.4572 0.4572)
			(layers "F.Cu" "F.Mask" "F.Paste")
			(net "P5E_PEX1_STN5_RX_DP<88>")
		)
		(pad "D33" smd circle
			(at 7.599934 -19.949922)
			(size 0.4572 0.4572)
			(layers "F.Cu" "F.Mask" "F.Paste")
			(net "GND")
		)
		(pad "D34" smd circle
			(at 8.549894 -19.949922)
			(size 0.4572 0.4572)
			(layers "F.Cu" "F.Mask" "F.Paste")
			(net "P5E_PEX1_STN5_RX_DP<90>")
		)
		(pad "D35" smd circle
			(at 9.500108 -19.949922)
			(size 0.4572 0.4572)
			(layers "F.Cu" "F.Mask" "F.Paste")
			(net "GND")
		)
		(pad "D36" smd circle
			(at 10.450068 -19.949922)
			(size 0.4572 0.4572)
			(layers "F.Cu" "F.Mask" "F.Paste")
			(net "P5E_PEX1_STN5_RX_DP<92>")
		)
		(pad "D37" smd circle
			(at 11.400028 -19.949922)
			(size 0.4572 0.4572)
			(layers "F.Cu" "F.Mask" "F.Paste")
			(net "GND")
		)
		(pad "D38" smd circle
			(at 12.349988 -19.949922)
			(size 0.4572 0.4572)
			(layers "F.Cu" "F.Mask" "F.Paste")
			(net "P5E_PEX1_STN5_RX_DP<94>")
		)
		(pad "D39" smd circle
			(at 13.299948 -19.949922)
			(size 0.4572 0.4572)
			(layers "F.Cu" "F.Mask" "F.Paste")
			(net "GND")
		)
		(pad "D40" smd circle
			(at 14.249908 -19.949922)
			(size 0.4572 0.4572)
			(layers "F.Cu" "F.Mask" "F.Paste")
			(net "P5E_PEX1_STN4_RX_DP<79>")
		)
		(pad "D41" smd circle
			(at 15.200122 -19.949922)
			(size 0.4572 0.4572)
			(layers "F.Cu" "F.Mask" "F.Paste")
			(net "GND")
		)
		(pad "D42" smd circle
			(at 16.150082 -19.949922)
			(size 0.4572 0.4572)
			(layers "F.Cu" "F.Mask" "F.Paste")
			(net "P5E_PEX1_STN4_RX_DP<77>")
		)
		(pad "D43" smd circle
			(at 17.100042 -19.949922)
			(size 0.4572 0.4572)
			(layers "F.Cu" "F.Mask" "F.Paste")
			(net "GND")
		)
		(pad "D44" smd circle
			(at 18.050002 -19.949922)
			(size 0.4572 0.4572)
			(layers "F.Cu" "F.Mask" "F.Paste")
			(net "P5E_PEX1_STN4_RX_DP<75>")
		)
		(pad "D45" smd circle
			(at 18.999962 -19.949922)
			(size 0.4572 0.4572)
			(layers "F.Cu" "F.Mask" "F.Paste")
			(net "GND")
		)
		(pad "D46" smd circle
			(at 19.949922 -19.949922)
			(size 0.4572 0.4572)
			(layers "F.Cu" "F.Mask" "F.Paste")
			(net "P5E_PEX1_STN4_RX_DP<73>")
		)
		(pad "D47" smd circle
			(at 20.899882 -19.949922)
			(size 0.4572 0.4572)
			(layers "F.Cu" "F.Mask" "F.Paste")
			(net "GND")
		)
		(pad "D48" smd circle
			(at 21.850096 -19.949922)
			(size 0.4572 0.4572)
			(layers "F.Cu" "F.Mask" "F.Paste")
			(net "GND")
		)
		(pad "D49" smd circle
			(at 22.800056 -19.949922)
			(size 0.4572 0.4572)
			(layers "F.Cu" "F.Mask" "F.Paste")
			(net "GND")
		)
		(pad "E1" smd circle
			(at -22.800056 -18.999962)
			(size 0.4572 0.4572)
			(layers "F.Cu" "F.Mask" "F.Paste")
			(net "P5E_PEX1_STN7_TX_DN<122>")
		)
		(pad "E2" smd circle
			(at -21.850096 -18.999962)
			(size 0.4572 0.4572)
			(layers "F.Cu" "F.Mask" "F.Paste")
			(net "P5E_PEX1_STN7_TX_DP<122>")
		)
		(pad "E3" smd circle
			(at -20.899882 -18.999962)
			(size 0.4572 0.4572)
			(layers "F.Cu" "F.Mask" "F.Paste")
			(net "GND")
		)
		(pad "E4" smd circle
			(at -19.949922 -18.999962)
			(size 0.4572 0.4572)
			(layers "F.Cu" "F.Mask" "F.Paste")
			(net "GND")
		)
		(pad "E5" smd circle
			(at -18.999962 -18.999962)
			(size 0.4572 0.4572)
			(layers "F.Cu" "F.Mask" "F.Paste")
			(net "GND")
		)
		(pad "E6" smd circle
			(at -18.050002 -18.999962)
			(size 0.4572 0.4572)
			(layers "F.Cu" "F.Mask" "F.Paste")
			(net "GND")
		)
		(pad "E7" smd circle
			(at -17.100042 -18.999962)
			(size 0.4572 0.4572)
			(layers "F.Cu" "F.Mask" "F.Paste")
			(net "GND")
		)
		(pad "E8" smd circle
			(at -16.150082 -18.999962)
			(size 0.4572 0.4572)
			(layers "F.Cu" "F.Mask" "F.Paste")
			(net "GND")
		)
		(pad "E9" smd circle
			(at -15.200122 -18.999962)
			(size 0.4572 0.4572)
			(layers "F.Cu" "F.Mask" "F.Paste")
			(net "GND")
		)
		(pad "E10" smd circle
			(at -14.249908 -18.999962)
			(size 0.4572 0.4572)
			(layers "F.Cu" "F.Mask" "F.Paste")
			(net "GND")
		)
		(pad "E11" smd circle
			(at -13.299948 -18.999962)
			(size 0.4572 0.4572)
			(layers "F.Cu" "F.Mask" "F.Paste")
			(net "GND")
		)
		(pad "E12" smd circle
			(at -12.349988 -18.999962)
			(size 0.4572 0.4572)
			(layers "F.Cu" "F.Mask" "F.Paste")
			(net "GND")
		)
		(pad "E13" smd circle
			(at -11.400028 -18.999962)
			(size 0.4572 0.4572)
			(layers "F.Cu" "F.Mask" "F.Paste")
			(net "GND")
		)
		(pad "E14" smd circle
			(at -10.450068 -18.999962)
			(size 0.4572 0.4572)
			(layers "F.Cu" "F.Mask" "F.Paste")
			(net "GND")
		)
		(pad "E15" smd circle
			(at -9.500108 -18.999962)
			(size 0.4572 0.4572)
			(layers "F.Cu" "F.Mask" "F.Paste")
			(net "GND")
		)
		(pad "E16" smd circle
			(at -8.549894 -18.999962)
			(size 0.4572 0.4572)
			(layers "F.Cu" "F.Mask" "F.Paste")
			(net "GND")
		)
		(pad "E17" smd circle
			(at -7.599934 -18.999962)
			(size 0.4572 0.4572)
			(layers "F.Cu" "F.Mask" "F.Paste")
			(net "GND")
		)
		(pad "E18" smd circle
			(at -6.649974 -18.999962)
			(size 0.4572 0.4572)
			(layers "F.Cu" "F.Mask" "F.Paste")
			(net "GND")
		)
		(pad "E19" smd circle
			(at -5.700014 -18.999962)
			(size 0.4572 0.4572)
			(layers "F.Cu" "F.Mask" "F.Paste")
			(net "GND")
		)
		(pad "E20" smd circle
			(at -4.750054 -18.999962)
			(size 0.4572 0.4572)
			(layers "F.Cu" "F.Mask" "F.Paste")
			(net "GND")
		)
		(pad "E21" smd circle
			(at -3.800094 -18.999962)
			(size 0.4572 0.4572)
			(layers "F.Cu" "F.Mask" "F.Paste")
			(net "GND")
		)
		(pad "E22" smd circle
			(at -2.84988 -18.999962)
			(size 0.4572 0.4572)
			(layers "F.Cu" "F.Mask" "F.Paste")
			(net "GND")
		)
		(pad "E23" smd circle
			(at -1.89992 -18.999962)
			(size 0.4572 0.4572)
			(layers "F.Cu" "F.Mask" "F.Paste")
			(net "GND")
		)
		(pad "E24" smd circle
			(at -0.94996 -18.999962)
			(size 0.4572 0.4572)
			(layers "F.Cu" "F.Mask" "F.Paste")
			(net "GND")
		)
		(pad "E25" smd circle
			(at 0 -18.999962)
			(size 0.4572 0.4572)
			(layers "F.Cu" "F.Mask" "F.Paste")
			(net "GND")
		)
		(pad "E26" smd circle
			(at 0.94996 -18.999962)
			(size 0.4572 0.4572)
			(layers "F.Cu" "F.Mask" "F.Paste")
			(net "GND")
		)
		(pad "E27" smd circle
			(at 1.89992 -18.999962)
			(size 0.4572 0.4572)
			(layers "F.Cu" "F.Mask" "F.Paste")
			(net "GND")
		)
		(pad "E28" smd circle
			(at 2.84988 -18.999962)
			(size 0.4572 0.4572)
			(layers "F.Cu" "F.Mask" "F.Paste")
			(net "GND")
		)
		(pad "E29" smd circle
			(at 3.800094 -18.999962)
			(size 0.4572 0.4572)
			(layers "F.Cu" "F.Mask" "F.Paste")
			(net "GND")
		)
		(pad "E30" smd circle
			(at 4.750054 -18.999962)
			(size 0.4572 0.4572)
			(layers "F.Cu" "F.Mask" "F.Paste")
			(net "GND")
		)
		(pad "E31" smd circle
			(at 5.700014 -18.999962)
			(size 0.4572 0.4572)
			(layers "F.Cu" "F.Mask" "F.Paste")
			(net "GND")
		)
		(pad "E32" smd circle
			(at 6.649974 -18.999962)
			(size 0.4572 0.4572)
			(layers "F.Cu" "F.Mask" "F.Paste")
			(net "GND")
		)
		(pad "E33" smd circle
			(at 7.599934 -18.999962)
			(size 0.4572 0.4572)
			(layers "F.Cu" "F.Mask" "F.Paste")
			(net "GND")
		)
		(pad "E34" smd circle
			(at 8.549894 -18.999962)
			(size 0.4572 0.4572)
			(layers "F.Cu" "F.Mask" "F.Paste")
			(net "GND")
		)
		(pad "E35" smd circle
			(at 9.500108 -18.999962)
			(size 0.4572 0.4572)
			(layers "F.Cu" "F.Mask" "F.Paste")
			(net "GND")
		)
		(pad "E36" smd circle
			(at 10.450068 -18.999962)
			(size 0.4572 0.4572)
			(layers "F.Cu" "F.Mask" "F.Paste")
			(net "GND")
		)
		(pad "E37" smd circle
			(at 11.400028 -18.999962)
			(size 0.4572 0.4572)
			(layers "F.Cu" "F.Mask" "F.Paste")
			(net "GND")
		)
		(pad "E38" smd circle
			(at 12.349988 -18.999962)
			(size 0.4572 0.4572)
			(layers "F.Cu" "F.Mask" "F.Paste")
			(net "GND")
		)
		(pad "E39" smd circle
			(at 13.299948 -18.999962)
			(size 0.4572 0.4572)
			(layers "F.Cu" "F.Mask" "F.Paste")
			(net "GND")
		)
		(pad "E40" smd circle
			(at 14.249908 -18.999962)
			(size 0.4572 0.4572)
			(layers "F.Cu" "F.Mask" "F.Paste")
			(net "GND")
		)
		(pad "E41" smd circle
			(at 15.200122 -18.999962)
			(size 0.4572 0.4572)
			(layers "F.Cu" "F.Mask" "F.Paste")
			(net "GND")
		)
		(pad "E42" smd circle
			(at 16.150082 -18.999962)
			(size 0.4572 0.4572)
			(layers "F.Cu" "F.Mask" "F.Paste")
			(net "GND")
		)
		(pad "E43" smd circle
			(at 17.100042 -18.999962)
			(size 0.4572 0.4572)
			(layers "F.Cu" "F.Mask" "F.Paste")
			(net "GND")
		)
		(pad "E44" smd circle
			(at 18.050002 -18.999962)
			(size 0.4572 0.4572)
			(layers "F.Cu" "F.Mask" "F.Paste")
			(net "GND")
		)
		(pad "E45" smd circle
			(at 18.999962 -18.999962)
			(size 0.4572 0.4572)
			(layers "F.Cu" "F.Mask" "F.Paste")
			(net "GND")
		)
		(pad "E46" smd circle
			(at 19.949922 -18.999962)
			(size 0.4572 0.4572)
			(layers "F.Cu" "F.Mask" "F.Paste")
			(net "GND")
		)
		(pad "E47" smd circle
			(at 20.899882 -18.999962)
			(size 0.4572 0.4572)
			(layers "F.Cu" "F.Mask" "F.Paste")
			(net "GND")
		)
		(pad "E48" smd circle
			(at 21.850096 -18.999962)
			(size 0.4572 0.4572)
			(layers "F.Cu" "F.Mask" "F.Paste")
			(net "P5E_PEX1_STN4_TX_DP<71>")
		)
		(pad "E49" smd circle
			(at 22.800056 -18.999962)
			(size 0.4572 0.4572)
			(layers "F.Cu" "F.Mask" "F.Paste")
			(net "P5E_PEX1_STN4_TX_DN<71>")
		)
		(pad "F1" smd circle
			(at -22.800056 -18.050002)
			(size 0.4572 0.4572)
			(layers "F.Cu" "F.Mask" "F.Paste")
			(net "GND")
		)
		(pad "F2" smd circle
			(at -21.850096 -18.050002)
			(size 0.4572 0.4572)
			(layers "F.Cu" "F.Mask" "F.Paste")
			(net "GND")
		)
		(pad "F3" smd circle
			(at -20.899882 -18.050002)
			(size 0.4572 0.4572)
			(layers "F.Cu" "F.Mask" "F.Paste")
			(net "P5E_PEX1_STN7_TX_DN<123>")
		)
		(pad "F4" smd circle
			(at -19.949922 -18.050002)
			(size 0.4572 0.4572)
			(layers "F.Cu" "F.Mask" "F.Paste")
			(net "GND")
		)
		(pad "F5" smd circle
			(at -18.999962 -18.050002)
			(size 0.4572 0.4572)
			(layers "F.Cu" "F.Mask" "F.Paste")
			(net "P5E_PEX1_STN7_TX_DN<125>")
		)
		(pad "F6" smd circle
			(at -18.050002 -18.050002)
			(size 0.4572 0.4572)
			(layers "F.Cu" "F.Mask" "F.Paste")
			(net "GND")
		)
		(pad "F7" smd circle
			(at -17.100042 -18.050002)
			(size 0.4572 0.4572)
			(layers "F.Cu" "F.Mask" "F.Paste")
			(net "P5E_PEX1_STN7_TX_DN<127>")
		)
		(pad "F8" smd circle
			(at -16.150082 -18.050002)
			(size 0.4572 0.4572)
			(layers "F.Cu" "F.Mask" "F.Paste")
			(net "GND")
		)
		(pad "F9" smd circle
			(at -15.200122 -18.050002)
			(size 0.4572 0.4572)
			(layers "F.Cu" "F.Mask" "F.Paste")
			(net "P5E_PEX1_STN6_TX_DN<110>")
		)
		(pad "F10" smd circle
			(at -14.249908 -18.050002)
			(size 0.4572 0.4572)
			(layers "F.Cu" "F.Mask" "F.Paste")
			(net "GND")
		)
		(pad "F11" smd circle
			(at -13.299948 -18.050002)
			(size 0.4572 0.4572)
			(layers "F.Cu" "F.Mask" "F.Paste")
			(net "P5E_PEX1_STN6_TX_DN<108>")
		)
		(pad "F12" smd circle
			(at -12.349988 -18.050002)
			(size 0.4572 0.4572)
			(layers "F.Cu" "F.Mask" "F.Paste")
			(net "GND")
		)
		(pad "F13" smd circle
			(at -11.400028 -18.050002)
			(size 0.4572 0.4572)
			(layers "F.Cu" "F.Mask" "F.Paste")
			(net "P5E_PEX1_STN6_TX_DN<106>")
		)
		(pad "F14" smd circle
			(at -10.450068 -18.050002)
			(size 0.4572 0.4572)
			(layers "F.Cu" "F.Mask" "F.Paste")
			(net "GND")
		)
		(pad "F15" smd circle
			(at -9.500108 -18.050002)
			(size 0.4572 0.4572)
			(layers "F.Cu" "F.Mask" "F.Paste")
			(net "P5E_PEX1_STN6_TX_DN<104>")
		)
		(pad "F16" smd circle
			(at -8.549894 -18.050002)
			(size 0.4572 0.4572)
			(layers "F.Cu" "F.Mask" "F.Paste")
			(net "GND")
		)
		(pad "F17" smd circle
			(at -7.599934 -18.050002)
			(size 0.4572 0.4572)
			(layers "F.Cu" "F.Mask" "F.Paste")
			(net "P5E_PEX1_STN6_TX_DN<102>")
		)
		(pad "F18" smd circle
			(at -6.649974 -18.050002)
			(size 0.4572 0.4572)
			(layers "F.Cu" "F.Mask" "F.Paste")
			(net "GND")
		)
		(pad "F19" smd circle
			(at -5.700014 -18.050002)
			(size 0.4572 0.4572)
			(layers "F.Cu" "F.Mask" "F.Paste")
			(net "P5E_PEX1_STN6_TX_DN<100>")
		)
		(pad "F20" smd circle
			(at -4.750054 -18.050002)
			(size 0.4572 0.4572)
			(layers "F.Cu" "F.Mask" "F.Paste")
			(net "GND")
		)
		(pad "F21" smd circle
			(at -3.800094 -18.050002)
			(size 0.4572 0.4572)
			(layers "F.Cu" "F.Mask" "F.Paste")
			(net "P5E_PEX1_STN6_TX_DN<98>")
		)
		(pad "F22" smd circle
			(at -2.84988 -18.050002)
			(size 0.4572 0.4572)
			(layers "F.Cu" "F.Mask" "F.Paste")
			(net "GND")
		)
		(pad "F23" smd circle
			(at -1.89992 -18.050002)
			(size 0.4572 0.4572)
			(layers "F.Cu" "F.Mask" "F.Paste")
			(net "P5E_PEX1_STN6_TX_DN<96>")
		)
		(pad "F24" smd circle
			(at -0.94996 -18.050002)
			(size 0.4572 0.4572)
			(layers "F.Cu" "F.Mask" "F.Paste")
			(net "GND")
		)
		(pad "F25" smd circle
			(at 0 -18.050002)
			(size 0.4572 0.4572)
			(layers "F.Cu" "F.Mask" "F.Paste")
			(net "P5E_PEX1_STN5_TX_DN<81>")
		)
		(pad "F26" smd circle
			(at 0.94996 -18.050002)
			(size 0.4572 0.4572)
			(layers "F.Cu" "F.Mask" "F.Paste")
			(net "GND")
		)
		(pad "F27" smd circle
			(at 1.89992 -18.050002)
			(size 0.4572 0.4572)
			(layers "F.Cu" "F.Mask" "F.Paste")
			(net "P5E_PEX1_STN5_TX_DN<83>")
		)
		(pad "F28" smd circle
			(at 2.84988 -18.050002)
			(size 0.4572 0.4572)
			(layers "F.Cu" "F.Mask" "F.Paste")
			(net "GND")
		)
		(pad "F29" smd circle
			(at 3.800094 -18.050002)
			(size 0.4572 0.4572)
			(layers "F.Cu" "F.Mask" "F.Paste")
			(net "P5E_PEX1_STN5_TX_DN<85>")
		)
		(pad "F30" smd circle
			(at 4.750054 -18.050002)
			(size 0.4572 0.4572)
			(layers "F.Cu" "F.Mask" "F.Paste")
			(net "GND")
		)
		(pad "F31" smd circle
			(at 5.700014 -18.050002)
			(size 0.4572 0.4572)
			(layers "F.Cu" "F.Mask" "F.Paste")
			(net "P5E_PEX1_STN5_TX_DN<87>")
		)
		(pad "F32" smd circle
			(at 6.649974 -18.050002)
			(size 0.4572 0.4572)
			(layers "F.Cu" "F.Mask" "F.Paste")
			(net "GND")
		)
		(pad "F33" smd circle
			(at 7.599934 -18.050002)
			(size 0.4572 0.4572)
			(layers "F.Cu" "F.Mask" "F.Paste")
			(net "P5E_PEX1_STN5_TX_DN<89>")
		)
		(pad "F34" smd circle
			(at 8.549894 -18.050002)
			(size 0.4572 0.4572)
			(layers "F.Cu" "F.Mask" "F.Paste")
			(net "GND")
		)
		(pad "F35" smd circle
			(at 9.500108 -18.050002)
			(size 0.4572 0.4572)
			(layers "F.Cu" "F.Mask" "F.Paste")
			(net "P5E_PEX1_STN5_TX_DN<91>")
		)
		(pad "F36" smd circle
			(at 10.450068 -18.050002)
			(size 0.4572 0.4572)
			(layers "F.Cu" "F.Mask" "F.Paste")
			(net "GND")
		)
		(pad "F37" smd circle
			(at 11.400028 -18.050002)
			(size 0.4572 0.4572)
			(layers "F.Cu" "F.Mask" "F.Paste")
			(net "P5E_PEX1_STN5_TX_DN<93>")
		)
		(pad "F38" smd circle
			(at 12.349988 -18.050002)
			(size 0.4572 0.4572)
			(layers "F.Cu" "F.Mask" "F.Paste")
			(net "GND")
		)
		(pad "F39" smd circle
			(at 13.299948 -18.050002)
			(size 0.4572 0.4572)
			(layers "F.Cu" "F.Mask" "F.Paste")
			(net "P5E_PEX1_STN5_TX_DN<95>")
		)
		(pad "F40" smd circle
			(at 14.249908 -18.050002)
			(size 0.4572 0.4572)
			(layers "F.Cu" "F.Mask" "F.Paste")
			(net "GND")
		)
		(pad "F41" smd circle
			(at 15.200122 -18.050002)
			(size 0.4572 0.4572)
			(layers "F.Cu" "F.Mask" "F.Paste")
			(net "P5E_PEX1_STN4_TX_DN<78>")
		)
		(pad "F42" smd circle
			(at 16.150082 -18.050002)
			(size 0.4572 0.4572)
			(layers "F.Cu" "F.Mask" "F.Paste")
			(net "GND")
		)
		(pad "F43" smd circle
			(at 17.100042 -18.050002)
			(size 0.4572 0.4572)
			(layers "F.Cu" "F.Mask" "F.Paste")
			(net "P5E_PEX1_STN4_TX_DN<76>")
		)
		(pad "F44" smd circle
			(at 18.050002 -18.050002)
			(size 0.4572 0.4572)
			(layers "F.Cu" "F.Mask" "F.Paste")
			(net "GND")
		)
		(pad "F45" smd circle
			(at 18.999962 -18.050002)
			(size 0.4572 0.4572)
			(layers "F.Cu" "F.Mask" "F.Paste")
			(net "P5E_PEX1_STN4_TX_DN<74>")
		)
		(pad "F46" smd circle
			(at 19.949922 -18.050002)
			(size 0.4572 0.4572)
			(layers "F.Cu" "F.Mask" "F.Paste")
			(net "GND")
		)
		(pad "F47" smd circle
			(at 20.899882 -18.050002)
			(size 0.4572 0.4572)
			(layers "F.Cu" "F.Mask" "F.Paste")
			(net "P5E_PEX1_STN4_TX_DN<72>")
		)
		(pad "F48" smd circle
			(at 21.850096 -18.050002)
			(size 0.4572 0.4572)
			(layers "F.Cu" "F.Mask" "F.Paste")
			(net "GND")
		)
		(pad "F49" smd circle
			(at 22.800056 -18.050002)
			(size 0.4572 0.4572)
			(layers "F.Cu" "F.Mask" "F.Paste")
			(net "GND")
		)
		(pad "G1" smd circle
			(at -22.800056 -17.100042)
			(size 0.4572 0.4572)
			(layers "F.Cu" "F.Mask" "F.Paste")
			(net "GND")
		)
		(pad "G2" smd circle
			(at -21.850096 -17.100042)
			(size 0.4572 0.4572)
			(layers "F.Cu" "F.Mask" "F.Paste")
			(net "GND")
		)
		(pad "G3" smd circle
			(at -20.899882 -17.100042)
			(size 0.4572 0.4572)
			(layers "F.Cu" "F.Mask" "F.Paste")
			(net "P5E_PEX1_STN7_TX_DP<123>")
		)
		(pad "G4" smd circle
			(at -19.949922 -17.100042)
			(size 0.4572 0.4572)
			(layers "F.Cu" "F.Mask" "F.Paste")
			(net "GND")
		)
		(pad "G5" smd circle
			(at -18.999962 -17.100042)
			(size 0.4572 0.4572)
			(layers "F.Cu" "F.Mask" "F.Paste")
			(net "P5E_PEX1_STN7_TX_DP<125>")
		)
		(pad "G6" smd circle
			(at -18.050002 -17.100042)
			(size 0.4572 0.4572)
			(layers "F.Cu" "F.Mask" "F.Paste")
			(net "GND")
		)
		(pad "G7" smd circle
			(at -17.100042 -17.100042)
			(size 0.4572 0.4572)
			(layers "F.Cu" "F.Mask" "F.Paste")
			(net "P5E_PEX1_STN7_TX_DP<127>")
		)
		(pad "G8" smd circle
			(at -16.150082 -17.100042)
			(size 0.4572 0.4572)
			(layers "F.Cu" "F.Mask" "F.Paste")
			(net "GND")
		)
		(pad "G9" smd circle
			(at -15.200122 -17.100042)
			(size 0.4572 0.4572)
			(layers "F.Cu" "F.Mask" "F.Paste")
			(net "P5E_PEX1_STN6_TX_DP<110>")
		)
		(pad "G10" smd circle
			(at -14.249908 -17.100042)
			(size 0.4572 0.4572)
			(layers "F.Cu" "F.Mask" "F.Paste")
			(net "GND")
		)
		(pad "G11" smd circle
			(at -13.299948 -17.100042)
			(size 0.4572 0.4572)
			(layers "F.Cu" "F.Mask" "F.Paste")
			(net "P5E_PEX1_STN6_TX_DP<108>")
		)
		(pad "G12" smd circle
			(at -12.349988 -17.100042)
			(size 0.4572 0.4572)
			(layers "F.Cu" "F.Mask" "F.Paste")
			(net "GND")
		)
		(pad "G13" smd circle
			(at -11.400028 -17.100042)
			(size 0.4572 0.4572)
			(layers "F.Cu" "F.Mask" "F.Paste")
			(net "P5E_PEX1_STN6_TX_DP<106>")
		)
		(pad "G14" smd circle
			(at -10.450068 -17.100042)
			(size 0.4572 0.4572)
			(layers "F.Cu" "F.Mask" "F.Paste")
			(net "GND")
		)
		(pad "G15" smd circle
			(at -9.500108 -17.100042)
			(size 0.4572 0.4572)
			(layers "F.Cu" "F.Mask" "F.Paste")
			(net "P5E_PEX1_STN6_TX_DP<104>")
		)
		(pad "G16" smd circle
			(at -8.549894 -17.100042)
			(size 0.4572 0.4572)
			(layers "F.Cu" "F.Mask" "F.Paste")
			(net "GND")
		)
		(pad "G17" smd circle
			(at -7.599934 -17.100042)
			(size 0.4572 0.4572)
			(layers "F.Cu" "F.Mask" "F.Paste")
			(net "P5E_PEX1_STN6_TX_DP<102>")
		)
		(pad "G18" smd circle
			(at -6.649974 -17.100042)
			(size 0.4572 0.4572)
			(layers "F.Cu" "F.Mask" "F.Paste")
			(net "GND")
		)
		(pad "G19" smd circle
			(at -5.700014 -17.100042)
			(size 0.4572 0.4572)
			(layers "F.Cu" "F.Mask" "F.Paste")
			(net "P5E_PEX1_STN6_TX_DP<100>")
		)
		(pad "G20" smd circle
			(at -4.750054 -17.100042)
			(size 0.4572 0.4572)
			(layers "F.Cu" "F.Mask" "F.Paste")
			(net "GND")
		)
		(pad "G21" smd circle
			(at -3.800094 -17.100042)
			(size 0.4572 0.4572)
			(layers "F.Cu" "F.Mask" "F.Paste")
			(net "P5E_PEX1_STN6_TX_DP<98>")
		)
		(pad "G22" smd circle
			(at -2.84988 -17.100042)
			(size 0.4572 0.4572)
			(layers "F.Cu" "F.Mask" "F.Paste")
			(net "GND")
		)
		(pad "G23" smd circle
			(at -1.89992 -17.100042)
			(size 0.4572 0.4572)
			(layers "F.Cu" "F.Mask" "F.Paste")
			(net "P5E_PEX1_STN6_TX_DP<96>")
		)
		(pad "G24" smd circle
			(at -0.94996 -17.100042)
			(size 0.4572 0.4572)
			(layers "F.Cu" "F.Mask" "F.Paste")
			(net "GND")
		)
		(pad "G25" smd circle
			(at 0 -17.100042)
			(size 0.4572 0.4572)
			(layers "F.Cu" "F.Mask" "F.Paste")
			(net "P5E_PEX1_STN5_TX_DP<81>")
		)
		(pad "G26" smd circle
			(at 0.94996 -17.100042)
			(size 0.4572 0.4572)
			(layers "F.Cu" "F.Mask" "F.Paste")
			(net "GND")
		)
		(pad "G27" smd circle
			(at 1.89992 -17.100042)
			(size 0.4572 0.4572)
			(layers "F.Cu" "F.Mask" "F.Paste")
			(net "P5E_PEX1_STN5_TX_DP<83>")
		)
		(pad "G28" smd circle
			(at 2.84988 -17.100042)
			(size 0.4572 0.4572)
			(layers "F.Cu" "F.Mask" "F.Paste")
			(net "GND")
		)
		(pad "G29" smd circle
			(at 3.800094 -17.100042)
			(size 0.4572 0.4572)
			(layers "F.Cu" "F.Mask" "F.Paste")
			(net "P5E_PEX1_STN5_TX_DP<85>")
		)
		(pad "G30" smd circle
			(at 4.750054 -17.100042)
			(size 0.4572 0.4572)
			(layers "F.Cu" "F.Mask" "F.Paste")
			(net "GND")
		)
		(pad "G31" smd circle
			(at 5.700014 -17.100042)
			(size 0.4572 0.4572)
			(layers "F.Cu" "F.Mask" "F.Paste")
			(net "P5E_PEX1_STN5_TX_DP<87>")
		)
		(pad "G32" smd circle
			(at 6.649974 -17.100042)
			(size 0.4572 0.4572)
			(layers "F.Cu" "F.Mask" "F.Paste")
			(net "GND")
		)
		(pad "G33" smd circle
			(at 7.599934 -17.100042)
			(size 0.4572 0.4572)
			(layers "F.Cu" "F.Mask" "F.Paste")
			(net "P5E_PEX1_STN5_TX_DP<89>")
		)
		(pad "G34" smd circle
			(at 8.549894 -17.100042)
			(size 0.4572 0.4572)
			(layers "F.Cu" "F.Mask" "F.Paste")
			(net "GND")
		)
		(pad "G35" smd circle
			(at 9.500108 -17.100042)
			(size 0.4572 0.4572)
			(layers "F.Cu" "F.Mask" "F.Paste")
			(net "P5E_PEX1_STN5_TX_DP<91>")
		)
		(pad "G36" smd circle
			(at 10.450068 -17.100042)
			(size 0.4572 0.4572)
			(layers "F.Cu" "F.Mask" "F.Paste")
			(net "GND")
		)
		(pad "G37" smd circle
			(at 11.400028 -17.100042)
			(size 0.4572 0.4572)
			(layers "F.Cu" "F.Mask" "F.Paste")
			(net "P5E_PEX1_STN5_TX_DP<93>")
		)
		(pad "G38" smd circle
			(at 12.349988 -17.100042)
			(size 0.4572 0.4572)
			(layers "F.Cu" "F.Mask" "F.Paste")
			(net "GND")
		)
		(pad "G39" smd circle
			(at 13.299948 -17.100042)
			(size 0.4572 0.4572)
			(layers "F.Cu" "F.Mask" "F.Paste")
			(net "P5E_PEX1_STN5_TX_DP<95>")
		)
		(pad "G40" smd circle
			(at 14.249908 -17.100042)
			(size 0.4572 0.4572)
			(layers "F.Cu" "F.Mask" "F.Paste")
			(net "GND")
		)
		(pad "G41" smd circle
			(at 15.200122 -17.100042)
			(size 0.4572 0.4572)
			(layers "F.Cu" "F.Mask" "F.Paste")
			(net "P5E_PEX1_STN4_TX_DP<78>")
		)
		(pad "G42" smd circle
			(at 16.150082 -17.100042)
			(size 0.4572 0.4572)
			(layers "F.Cu" "F.Mask" "F.Paste")
			(net "GND")
		)
		(pad "G43" smd circle
			(at 17.100042 -17.100042)
			(size 0.4572 0.4572)
			(layers "F.Cu" "F.Mask" "F.Paste")
			(net "P5E_PEX1_STN4_TX_DP<76>")
		)
		(pad "G44" smd circle
			(at 18.050002 -17.100042)
			(size 0.4572 0.4572)
			(layers "F.Cu" "F.Mask" "F.Paste")
			(net "GND")
		)
		(pad "G45" smd circle
			(at 18.999962 -17.100042)
			(size 0.4572 0.4572)
			(layers "F.Cu" "F.Mask" "F.Paste")
			(net "P5E_PEX1_STN4_TX_DP<74>")
		)
		(pad "G46" smd circle
			(at 19.949922 -17.100042)
			(size 0.4572 0.4572)
			(layers "F.Cu" "F.Mask" "F.Paste")
			(net "GND")
		)
		(pad "G47" smd circle
			(at 20.899882 -17.100042)
			(size 0.4572 0.4572)
			(layers "F.Cu" "F.Mask" "F.Paste")
			(net "P5E_PEX1_STN4_TX_DP<72>")
		)
		(pad "G48" smd circle
			(at 21.850096 -17.100042)
			(size 0.4572 0.4572)
			(layers "F.Cu" "F.Mask" "F.Paste")
			(net "GND")
		)
		(pad "G49" smd circle
			(at 22.800056 -17.100042)
			(size 0.4572 0.4572)
			(layers "F.Cu" "F.Mask" "F.Paste")
			(net "GND")
		)
		(pad "H1" smd circle
			(at -22.800056 -16.150082)
			(size 0.4572 0.4572)
			(layers "F.Cu" "F.Mask" "F.Paste")
			(net "P5E_PEX1_STN7_TX_DN<121>")
		)
		(pad "H2" smd circle
			(at -21.850096 -16.150082)
			(size 0.4572 0.4572)
			(layers "F.Cu" "F.Mask" "F.Paste")
			(net "P5E_PEX1_STN7_TX_DP<121>")
		)
		(pad "H3" smd circle
			(at -20.899882 -16.150082)
			(size 0.4572 0.4572)
			(layers "F.Cu" "F.Mask" "F.Paste")
			(net "GND")
		)
		(pad "H4" smd circle
			(at -19.949922 -16.150082)
			(size 0.4572 0.4572)
			(layers "F.Cu" "F.Mask" "F.Paste")
			(net "P5E_PEX1_STN7_TX_DN<124>")
		)
		(pad "H5" smd circle
			(at -18.999962 -16.150082)
			(size 0.4572 0.4572)
			(layers "F.Cu" "F.Mask" "F.Paste")
			(net "GND")
		)
		(pad "H6" smd circle
			(at -18.050002 -16.150082)
			(size 0.4572 0.4572)
			(layers "F.Cu" "F.Mask" "F.Paste")
			(net "P5E_PEX1_STN7_TX_DN<126>")
		)
		(pad "H7" smd circle
			(at -17.100042 -16.150082)
			(size 0.4572 0.4572)
			(layers "F.Cu" "F.Mask" "F.Paste")
			(net "GND")
		)
		(pad "H8" smd circle
			(at -16.150082 -16.150082)
			(size 0.4572 0.4572)
			(layers "F.Cu" "F.Mask" "F.Paste")
			(net "P5E_PEX1_STN6_TX_DN<111>")
		)
		(pad "H9" smd circle
			(at -15.200122 -16.150082)
			(size 0.4572 0.4572)
			(layers "F.Cu" "F.Mask" "F.Paste")
			(net "GND")
		)
		(pad "H10" smd circle
			(at -14.249908 -16.150082)
			(size 0.4572 0.4572)
			(layers "F.Cu" "F.Mask" "F.Paste")
			(net "P5E_PEX1_STN6_TX_DN<109>")
		)
		(pad "H11" smd circle
			(at -13.299948 -16.150082)
			(size 0.4572 0.4572)
			(layers "F.Cu" "F.Mask" "F.Paste")
			(net "GND")
		)
		(pad "H12" smd circle
			(at -12.349988 -16.150082)
			(size 0.4572 0.4572)
			(layers "F.Cu" "F.Mask" "F.Paste")
			(net "P5E_PEX1_STN6_TX_DN<107>")
		)
		(pad "H13" smd circle
			(at -11.400028 -16.150082)
			(size 0.4572 0.4572)
			(layers "F.Cu" "F.Mask" "F.Paste")
			(net "GND")
		)
		(pad "H14" smd circle
			(at -10.450068 -16.150082)
			(size 0.4572 0.4572)
			(layers "F.Cu" "F.Mask" "F.Paste")
			(net "P5E_PEX1_STN6_TX_DN<105>")
		)
		(pad "H15" smd circle
			(at -9.500108 -16.150082)
			(size 0.4572 0.4572)
			(layers "F.Cu" "F.Mask" "F.Paste")
			(net "GND")
		)
		(pad "H16" smd circle
			(at -8.549894 -16.150082)
			(size 0.4572 0.4572)
			(layers "F.Cu" "F.Mask" "F.Paste")
			(net "P5E_PEX1_STN6_TX_DN<103>")
		)
		(pad "H17" smd circle
			(at -7.599934 -16.150082)
			(size 0.4572 0.4572)
			(layers "F.Cu" "F.Mask" "F.Paste")
			(net "GND")
		)
		(pad "H18" smd circle
			(at -6.649974 -16.150082)
			(size 0.4572 0.4572)
			(layers "F.Cu" "F.Mask" "F.Paste")
			(net "P5E_PEX1_STN6_TX_DN<101>")
		)
		(pad "H19" smd circle
			(at -5.700014 -16.150082)
			(size 0.4572 0.4572)
			(layers "F.Cu" "F.Mask" "F.Paste")
			(net "GND")
		)
		(pad "H20" smd circle
			(at -4.750054 -16.150082)
			(size 0.4572 0.4572)
			(layers "F.Cu" "F.Mask" "F.Paste")
			(net "P5E_PEX1_STN6_TX_DN<99>")
		)
		(pad "H21" smd circle
			(at -3.800094 -16.150082)
			(size 0.4572 0.4572)
			(layers "F.Cu" "F.Mask" "F.Paste")
			(net "GND")
		)
		(pad "H22" smd circle
			(at -2.84988 -16.150082)
			(size 0.4572 0.4572)
			(layers "F.Cu" "F.Mask" "F.Paste")
			(net "P5E_PEX1_STN6_TX_DN<97>")
		)
		(pad "H23" smd circle
			(at -1.89992 -16.150082)
			(size 0.4572 0.4572)
			(layers "F.Cu" "F.Mask" "F.Paste")
			(net "GND")
		)
		(pad "H24" smd circle
			(at -0.94996 -16.150082)
			(size 0.4572 0.4572)
			(layers "F.Cu" "F.Mask" "F.Paste")
			(net "P5E_PEX1_STN5_TX_DN<80>")
		)
		(pad "H25" smd circle
			(at 0 -16.150082)
			(size 0.4572 0.4572)
			(layers "F.Cu" "F.Mask" "F.Paste")
			(net "GND")
		)
		(pad "H26" smd circle
			(at 0.94996 -16.150082)
			(size 0.4572 0.4572)
			(layers "F.Cu" "F.Mask" "F.Paste")
			(net "P5E_PEX1_STN5_TX_DN<82>")
		)
		(pad "H27" smd circle
			(at 1.89992 -16.150082)
			(size 0.4572 0.4572)
			(layers "F.Cu" "F.Mask" "F.Paste")
			(net "GND")
		)
		(pad "H28" smd circle
			(at 2.84988 -16.150082)
			(size 0.4572 0.4572)
			(layers "F.Cu" "F.Mask" "F.Paste")
			(net "P5E_PEX1_STN5_TX_DN<84>")
		)
		(pad "H29" smd circle
			(at 3.800094 -16.150082)
			(size 0.4572 0.4572)
			(layers "F.Cu" "F.Mask" "F.Paste")
			(net "GND")
		)
		(pad "H30" smd circle
			(at 4.750054 -16.150082)
			(size 0.4572 0.4572)
			(layers "F.Cu" "F.Mask" "F.Paste")
			(net "P5E_PEX1_STN5_TX_DN<86>")
		)
		(pad "H31" smd circle
			(at 5.700014 -16.150082)
			(size 0.4572 0.4572)
			(layers "F.Cu" "F.Mask" "F.Paste")
			(net "GND")
		)
		(pad "H32" smd circle
			(at 6.649974 -16.150082)
			(size 0.4572 0.4572)
			(layers "F.Cu" "F.Mask" "F.Paste")
			(net "P5E_PEX1_STN5_TX_DN<88>")
		)
		(pad "H33" smd circle
			(at 7.599934 -16.150082)
			(size 0.4572 0.4572)
			(layers "F.Cu" "F.Mask" "F.Paste")
			(net "GND")
		)
		(pad "H34" smd circle
			(at 8.549894 -16.150082)
			(size 0.4572 0.4572)
			(layers "F.Cu" "F.Mask" "F.Paste")
			(net "P5E_PEX1_STN5_TX_DN<90>")
		)
		(pad "H35" smd circle
			(at 9.500108 -16.150082)
			(size 0.4572 0.4572)
			(layers "F.Cu" "F.Mask" "F.Paste")
			(net "GND")
		)
		(pad "H36" smd circle
			(at 10.450068 -16.150082)
			(size 0.4572 0.4572)
			(layers "F.Cu" "F.Mask" "F.Paste")
			(net "P5E_PEX1_STN5_TX_DN<92>")
		)
		(pad "H37" smd circle
			(at 11.400028 -16.150082)
			(size 0.4572 0.4572)
			(layers "F.Cu" "F.Mask" "F.Paste")
			(net "GND")
		)
		(pad "H38" smd circle
			(at 12.349988 -16.150082)
			(size 0.4572 0.4572)
			(layers "F.Cu" "F.Mask" "F.Paste")
			(net "P5E_PEX1_STN5_TX_DN<94>")
		)
		(pad "H39" smd circle
			(at 13.299948 -16.150082)
			(size 0.4572 0.4572)
			(layers "F.Cu" "F.Mask" "F.Paste")
			(net "GND")
		)
		(pad "H40" smd circle
			(at 14.249908 -16.150082)
			(size 0.4572 0.4572)
			(layers "F.Cu" "F.Mask" "F.Paste")
			(net "P5E_PEX1_STN4_TX_DN<79>")
		)
		(pad "H41" smd circle
			(at 15.200122 -16.150082)
			(size 0.4572 0.4572)
			(layers "F.Cu" "F.Mask" "F.Paste")
			(net "GND")
		)
		(pad "H42" smd circle
			(at 16.150082 -16.150082)
			(size 0.4572 0.4572)
			(layers "F.Cu" "F.Mask" "F.Paste")
			(net "P5E_PEX1_STN4_TX_DN<77>")
		)
		(pad "H43" smd circle
			(at 17.100042 -16.150082)
			(size 0.4572 0.4572)
			(layers "F.Cu" "F.Mask" "F.Paste")
			(net "GND")
		)
		(pad "H44" smd circle
			(at 18.050002 -16.150082)
			(size 0.4572 0.4572)
			(layers "F.Cu" "F.Mask" "F.Paste")
			(net "P5E_PEX1_STN4_TX_DN<75>")
		)
		(pad "H45" smd circle
			(at 18.999962 -16.150082)
			(size 0.4572 0.4572)
			(layers "F.Cu" "F.Mask" "F.Paste")
			(net "GND")
		)
		(pad "H46" smd circle
			(at 19.949922 -16.150082)
			(size 0.4572 0.4572)
			(layers "F.Cu" "F.Mask" "F.Paste")
			(net "P5E_PEX1_STN4_TX_DN<73>")
		)
		(pad "H47" smd circle
			(at 20.899882 -16.150082)
			(size 0.4572 0.4572)
			(layers "F.Cu" "F.Mask" "F.Paste")
			(net "GND")
		)
		(pad "H48" smd circle
			(at 21.850096 -16.150082)
			(size 0.4572 0.4572)
			(layers "F.Cu" "F.Mask" "F.Paste")
			(net "P5E_PEX1_STN4_TX_DP<70>")
		)
		(pad "H49" smd circle
			(at 22.800056 -16.150082)
			(size 0.4572 0.4572)
			(layers "F.Cu" "F.Mask" "F.Paste")
			(net "P5E_PEX1_STN4_TX_DN<70>")
		)
		(pad "J1" smd circle
			(at -22.800056 -15.200122)
			(size 0.4572 0.4572)
			(layers "F.Cu" "F.Mask" "F.Paste")
			(net "GND")
		)
		(pad "J2" smd circle
			(at -21.850096 -15.200122)
			(size 0.4572 0.4572)
			(layers "F.Cu" "F.Mask" "F.Paste")
			(net "GND")
		)
		(pad "J3" smd circle
			(at -20.899882 -15.200122)
			(size 0.4572 0.4572)
			(layers "F.Cu" "F.Mask" "F.Paste")
			(net "GND")
		)
		(pad "J4" smd circle
			(at -19.949922 -15.200122)
			(size 0.4572 0.4572)
			(layers "F.Cu" "F.Mask" "F.Paste")
			(net "P5E_PEX1_STN7_TX_DP<124>")
		)
		(pad "J5" smd circle
			(at -18.999962 -15.200122)
			(size 0.4572 0.4572)
			(layers "F.Cu" "F.Mask" "F.Paste")
			(net "GND")
		)
		(pad "J6" smd circle
			(at -18.050002 -15.200122)
			(size 0.4572 0.4572)
			(layers "F.Cu" "F.Mask" "F.Paste")
			(net "P5E_PEX1_STN7_TX_DP<126>")
		)
		(pad "J7" smd circle
			(at -17.100042 -15.200122)
			(size 0.4572 0.4572)
			(layers "F.Cu" "F.Mask" "F.Paste")
			(net "GND")
		)
		(pad "J8" smd circle
			(at -16.150082 -15.200122)
			(size 0.4572 0.4572)
			(layers "F.Cu" "F.Mask" "F.Paste")
			(net "P5E_PEX1_STN6_TX_DP<111>")
		)
		(pad "J9" smd circle
			(at -15.200122 -15.200122)
			(size 0.4572 0.4572)
			(layers "F.Cu" "F.Mask" "F.Paste")
			(net "GND")
		)
		(pad "J10" smd circle
			(at -14.249908 -15.200122)
			(size 0.4572 0.4572)
			(layers "F.Cu" "F.Mask" "F.Paste")
			(net "P5E_PEX1_STN6_TX_DP<109>")
		)
		(pad "J11" smd circle
			(at -13.299948 -15.200122)
			(size 0.4572 0.4572)
			(layers "F.Cu" "F.Mask" "F.Paste")
			(net "GND")
		)
		(pad "J12" smd circle
			(at -12.349988 -15.200122)
			(size 0.4572 0.4572)
			(layers "F.Cu" "F.Mask" "F.Paste")
			(net "P5E_PEX1_STN6_TX_DP<107>")
		)
		(pad "J13" smd circle
			(at -11.400028 -15.200122)
			(size 0.4572 0.4572)
			(layers "F.Cu" "F.Mask" "F.Paste")
			(net "GND")
		)
		(pad "J14" smd circle
			(at -10.450068 -15.200122)
			(size 0.4572 0.4572)
			(layers "F.Cu" "F.Mask" "F.Paste")
			(net "P5E_PEX1_STN6_TX_DP<105>")
		)
		(pad "J15" smd circle
			(at -9.500108 -15.200122)
			(size 0.4572 0.4572)
			(layers "F.Cu" "F.Mask" "F.Paste")
			(net "GND")
		)
		(pad "J16" smd circle
			(at -8.549894 -15.200122)
			(size 0.4572 0.4572)
			(layers "F.Cu" "F.Mask" "F.Paste")
			(net "P5E_PEX1_STN6_TX_DP<103>")
		)
		(pad "J17" smd circle
			(at -7.599934 -15.200122)
			(size 0.4572 0.4572)
			(layers "F.Cu" "F.Mask" "F.Paste")
			(net "GND")
		)
		(pad "J18" smd circle
			(at -6.649974 -15.200122)
			(size 0.4572 0.4572)
			(layers "F.Cu" "F.Mask" "F.Paste")
			(net "P5E_PEX1_STN6_TX_DP<101>")
		)
		(pad "J19" smd circle
			(at -5.700014 -15.200122)
			(size 0.4572 0.4572)
			(layers "F.Cu" "F.Mask" "F.Paste")
			(net "GND")
		)
		(pad "J20" smd circle
			(at -4.750054 -15.200122)
			(size 0.4572 0.4572)
			(layers "F.Cu" "F.Mask" "F.Paste")
			(net "P5E_PEX1_STN6_TX_DP<99>")
		)
		(pad "J21" smd circle
			(at -3.800094 -15.200122)
			(size 0.4572 0.4572)
			(layers "F.Cu" "F.Mask" "F.Paste")
			(net "GND")
		)
		(pad "J22" smd circle
			(at -2.84988 -15.200122)
			(size 0.4572 0.4572)
			(layers "F.Cu" "F.Mask" "F.Paste")
			(net "P5E_PEX1_STN6_TX_DP<97>")
		)
		(pad "J23" smd circle
			(at -1.89992 -15.200122)
			(size 0.4572 0.4572)
			(layers "F.Cu" "F.Mask" "F.Paste")
			(net "GND")
		)
		(pad "J24" smd circle
			(at -0.94996 -15.200122)
			(size 0.4572 0.4572)
			(layers "F.Cu" "F.Mask" "F.Paste")
			(net "P5E_PEX1_STN5_TX_DP<80>")
		)
		(pad "J25" smd circle
			(at 0 -15.200122)
			(size 0.4572 0.4572)
			(layers "F.Cu" "F.Mask" "F.Paste")
			(net "GND")
		)
		(pad "J26" smd circle
			(at 0.94996 -15.200122)
			(size 0.4572 0.4572)
			(layers "F.Cu" "F.Mask" "F.Paste")
			(net "P5E_PEX1_STN5_TX_DP<82>")
		)
		(pad "J27" smd circle
			(at 1.89992 -15.200122)
			(size 0.4572 0.4572)
			(layers "F.Cu" "F.Mask" "F.Paste")
			(net "GND")
		)
		(pad "J28" smd circle
			(at 2.84988 -15.200122)
			(size 0.4572 0.4572)
			(layers "F.Cu" "F.Mask" "F.Paste")
			(net "P5E_PEX1_STN5_TX_DP<84>")
		)
		(pad "J29" smd circle
			(at 3.800094 -15.200122)
			(size 0.4572 0.4572)
			(layers "F.Cu" "F.Mask" "F.Paste")
			(net "GND")
		)
		(pad "J30" smd circle
			(at 4.750054 -15.200122)
			(size 0.4572 0.4572)
			(layers "F.Cu" "F.Mask" "F.Paste")
			(net "P5E_PEX1_STN5_TX_DP<86>")
		)
		(pad "J31" smd circle
			(at 5.700014 -15.200122)
			(size 0.4572 0.4572)
			(layers "F.Cu" "F.Mask" "F.Paste")
			(net "GND")
		)
		(pad "J32" smd circle
			(at 6.649974 -15.200122)
			(size 0.4572 0.4572)
			(layers "F.Cu" "F.Mask" "F.Paste")
			(net "P5E_PEX1_STN5_TX_DP<88>")
		)
		(pad "J33" smd circle
			(at 7.599934 -15.200122)
			(size 0.4572 0.4572)
			(layers "F.Cu" "F.Mask" "F.Paste")
			(net "GND")
		)
		(pad "J34" smd circle
			(at 8.549894 -15.200122)
			(size 0.4572 0.4572)
			(layers "F.Cu" "F.Mask" "F.Paste")
			(net "P5E_PEX1_STN5_TX_DP<90>")
		)
		(pad "J35" smd circle
			(at 9.500108 -15.200122)
			(size 0.4572 0.4572)
			(layers "F.Cu" "F.Mask" "F.Paste")
			(net "GND")
		)
		(pad "J36" smd circle
			(at 10.450068 -15.200122)
			(size 0.4572 0.4572)
			(layers "F.Cu" "F.Mask" "F.Paste")
			(net "P5E_PEX1_STN5_TX_DP<92>")
		)
		(pad "J37" smd circle
			(at 11.400028 -15.200122)
			(size 0.4572 0.4572)
			(layers "F.Cu" "F.Mask" "F.Paste")
			(net "GND")
		)
		(pad "J38" smd circle
			(at 12.349988 -15.200122)
			(size 0.4572 0.4572)
			(layers "F.Cu" "F.Mask" "F.Paste")
			(net "P5E_PEX1_STN5_TX_DP<94>")
		)
		(pad "J39" smd circle
			(at 13.299948 -15.200122)
			(size 0.4572 0.4572)
			(layers "F.Cu" "F.Mask" "F.Paste")
			(net "GND")
		)
		(pad "J40" smd circle
			(at 14.249908 -15.200122)
			(size 0.4572 0.4572)
			(layers "F.Cu" "F.Mask" "F.Paste")
			(net "P5E_PEX1_STN4_TX_DP<79>")
		)
		(pad "J41" smd circle
			(at 15.200122 -15.200122)
			(size 0.4572 0.4572)
			(layers "F.Cu" "F.Mask" "F.Paste")
			(net "GND")
		)
		(pad "J42" smd circle
			(at 16.150082 -15.200122)
			(size 0.4572 0.4572)
			(layers "F.Cu" "F.Mask" "F.Paste")
			(net "P5E_PEX1_STN4_TX_DP<77>")
		)
		(pad "J43" smd circle
			(at 17.100042 -15.200122)
			(size 0.4572 0.4572)
			(layers "F.Cu" "F.Mask" "F.Paste")
			(net "GND")
		)
		(pad "J44" smd circle
			(at 18.050002 -15.200122)
			(size 0.4572 0.4572)
			(layers "F.Cu" "F.Mask" "F.Paste")
			(net "P5E_PEX1_STN4_TX_DP<75>")
		)
		(pad "J45" smd circle
			(at 18.999962 -15.200122)
			(size 0.4572 0.4572)
			(layers "F.Cu" "F.Mask" "F.Paste")
			(net "GND")
		)
		(pad "J46" smd circle
			(at 19.949922 -15.200122)
			(size 0.4572 0.4572)
			(layers "F.Cu" "F.Mask" "F.Paste")
			(net "P5E_PEX1_STN4_TX_DP<73>")
		)
		(pad "J47" smd circle
			(at 20.899882 -15.200122)
			(size 0.4572 0.4572)
			(layers "F.Cu" "F.Mask" "F.Paste")
			(net "GND")
		)
		(pad "J48" smd circle
			(at 21.850096 -15.200122)
			(size 0.4572 0.4572)
			(layers "F.Cu" "F.Mask" "F.Paste")
			(net "GND")
		)
		(pad "J49" smd circle
			(at 22.800056 -15.200122)
			(size 0.4572 0.4572)
			(layers "F.Cu" "F.Mask" "F.Paste")
			(net "GND")
		)
		(pad "K1" smd circle
			(at -22.800056 -14.249908)
			(size 0.4572 0.4572)
			(layers "F.Cu" "F.Mask" "F.Paste")
			(net "P5E_PEX1_STN7_RX_DN<121>")
		)
		(pad "K2" smd circle
			(at -21.850096 -14.249908)
			(size 0.4572 0.4572)
			(layers "F.Cu" "F.Mask" "F.Paste")
			(net "P5E_PEX1_STN7_RX_DP<121>")
		)
		(pad "K3" smd circle
			(at -20.899882 -14.249908)
			(size 0.4572 0.4572)
			(layers "F.Cu" "F.Mask" "F.Paste")
			(net "GND")
		)
		(pad "K4" smd circle
			(at -19.949922 -14.249908)
			(size 0.4572 0.4572)
			(layers "F.Cu" "F.Mask" "F.Paste")
			(net "GND")
		)
		(pad "K5" smd circle
			(at -18.999962 -14.249908)
			(size 0.4572 0.4572)
			(layers "F.Cu" "F.Mask" "F.Paste")
			(net "GND")
		)
		(pad "K6" smd circle
			(at -18.050002 -14.249908)
			(size 0.4572 0.4572)
			(layers "F.Cu" "F.Mask" "F.Paste")
			(net "GND")
		)
		(pad "K7" smd circle
			(at -17.100042 -14.249908)
			(size 0.4572 0.4572)
			(layers "F.Cu" "F.Mask" "F.Paste")
			(net "GND")
		)
		(pad "K8" smd circle
			(at -16.150082 -14.249908)
			(size 0.4572 0.4572)
			(layers "F.Cu" "F.Mask" "F.Paste")
			(net "GND")
		)
		(pad "K9" smd circle
			(at -15.200122 -14.249908)
			(size 0.4572 0.4572)
			(layers "F.Cu" "F.Mask" "F.Paste")
			(net "GND")
		)
		(pad "K10" smd circle
			(at -14.249908 -14.249908)
			(size 0.4572 0.4572)
			(layers "F.Cu" "F.Mask" "F.Paste")
			(net "GND")
		)
		(pad "K11" smd circle
			(at -13.299948 -14.249908)
			(size 0.4572 0.4572)
			(layers "F.Cu" "F.Mask" "F.Paste")
			(net "GND")
		)
		(pad "K12" smd circle
			(at -12.349988 -14.249908)
			(size 0.4572 0.4572)
			(layers "F.Cu" "F.Mask" "F.Paste")
			(net "GND")
		)
		(pad "K13" smd circle
			(at -11.400028 -14.249908)
			(size 0.4572 0.4572)
			(layers "F.Cu" "F.Mask" "F.Paste")
			(net "GND")
		)
		(pad "K14" smd circle
			(at -10.450068 -14.249908)
			(size 0.4572 0.4572)
			(layers "F.Cu" "F.Mask" "F.Paste")
			(net "GND")
		)
		(pad "K15" smd circle
			(at -9.500108 -14.249908)
			(size 0.4572 0.4572)
			(layers "F.Cu" "F.Mask" "F.Paste")
			(net "GND")
		)
		(pad "K16" smd circle
			(at -8.549894 -14.249908)
			(size 0.4572 0.4572)
			(layers "F.Cu" "F.Mask" "F.Paste")
			(net "GND")
		)
		(pad "K17" smd circle
			(at -7.599934 -14.249908)
			(size 0.4572 0.4572)
			(layers "F.Cu" "F.Mask" "F.Paste")
			(net "GND")
		)
		(pad "K18" smd circle
			(at -6.649974 -14.249908)
			(size 0.4572 0.4572)
			(layers "F.Cu" "F.Mask" "F.Paste")
			(net "GND")
		)
		(pad "K19" smd circle
			(at -5.700014 -14.249908)
			(size 0.4572 0.4572)
			(layers "F.Cu" "F.Mask" "F.Paste")
			(net "GND")
		)
		(pad "K20" smd circle
			(at -4.750054 -14.249908)
			(size 0.4572 0.4572)
			(layers "F.Cu" "F.Mask" "F.Paste")
			(net "GND")
		)
		(pad "K21" smd circle
			(at -3.800094 -14.249908)
			(size 0.4572 0.4572)
			(layers "F.Cu" "F.Mask" "F.Paste")
			(net "GND")
		)
		(pad "K22" smd circle
			(at -2.84988 -14.249908)
			(size 0.4572 0.4572)
			(layers "F.Cu" "F.Mask" "F.Paste")
			(net "GND")
		)
		(pad "K23" smd circle
			(at -1.89992 -14.249908)
			(size 0.4572 0.4572)
			(layers "F.Cu" "F.Mask" "F.Paste")
			(net "GND")
		)
		(pad "K24" smd circle
			(at -0.94996 -14.249908)
			(size 0.4572 0.4572)
			(layers "F.Cu" "F.Mask" "F.Paste")
			(net "GND")
		)
		(pad "K25" smd circle
			(at 0 -14.249908)
			(size 0.4572 0.4572)
			(layers "F.Cu" "F.Mask" "F.Paste")
			(net "GND")
		)
		(pad "K26" smd circle
			(at 0.94996 -14.249908)
			(size 0.4572 0.4572)
			(layers "F.Cu" "F.Mask" "F.Paste")
			(net "GND")
		)
		(pad "K27" smd circle
			(at 1.89992 -14.249908)
			(size 0.4572 0.4572)
			(layers "F.Cu" "F.Mask" "F.Paste")
			(net "GND")
		)
		(pad "K28" smd circle
			(at 2.84988 -14.249908)
			(size 0.4572 0.4572)
			(layers "F.Cu" "F.Mask" "F.Paste")
			(net "GND")
		)
		(pad "K29" smd circle
			(at 3.800094 -14.249908)
			(size 0.4572 0.4572)
			(layers "F.Cu" "F.Mask" "F.Paste")
			(net "GND")
		)
		(pad "K30" smd circle
			(at 4.750054 -14.249908)
			(size 0.4572 0.4572)
			(layers "F.Cu" "F.Mask" "F.Paste")
			(net "GND")
		)
		(pad "K31" smd circle
			(at 5.700014 -14.249908)
			(size 0.4572 0.4572)
			(layers "F.Cu" "F.Mask" "F.Paste")
			(net "GND")
		)
		(pad "K32" smd circle
			(at 6.649974 -14.249908)
			(size 0.4572 0.4572)
			(layers "F.Cu" "F.Mask" "F.Paste")
			(net "GND")
		)
		(pad "K33" smd circle
			(at 7.599934 -14.249908)
			(size 0.4572 0.4572)
			(layers "F.Cu" "F.Mask" "F.Paste")
			(net "GND")
		)
		(pad "K34" smd circle
			(at 8.549894 -14.249908)
			(size 0.4572 0.4572)
			(layers "F.Cu" "F.Mask" "F.Paste")
			(net "GND")
		)
		(pad "K35" smd circle
			(at 9.500108 -14.249908)
			(size 0.4572 0.4572)
			(layers "F.Cu" "F.Mask" "F.Paste")
			(net "GND")
		)
		(pad "K36" smd circle
			(at 10.450068 -14.249908)
			(size 0.4572 0.4572)
			(layers "F.Cu" "F.Mask" "F.Paste")
			(net "GND")
		)
		(pad "K37" smd circle
			(at 11.400028 -14.249908)
			(size 0.4572 0.4572)
			(layers "F.Cu" "F.Mask" "F.Paste")
			(net "GND")
		)
		(pad "K38" smd circle
			(at 12.349988 -14.249908)
			(size 0.4572 0.4572)
			(layers "F.Cu" "F.Mask" "F.Paste")
			(net "GND")
		)
		(pad "K39" smd circle
			(at 13.299948 -14.249908)
			(size 0.4572 0.4572)
			(layers "F.Cu" "F.Mask" "F.Paste")
			(net "GND")
		)
		(pad "K40" smd circle
			(at 14.249908 -14.249908)
			(size 0.4572 0.4572)
			(layers "F.Cu" "F.Mask" "F.Paste")
			(net "GND")
		)
		(pad "K41" smd circle
			(at 15.200122 -14.249908)
			(size 0.4572 0.4572)
			(layers "F.Cu" "F.Mask" "F.Paste")
			(net "GND")
		)
		(pad "K42" smd circle
			(at 16.150082 -14.249908)
			(size 0.4572 0.4572)
			(layers "F.Cu" "F.Mask" "F.Paste")
			(net "GND")
		)
		(pad "K43" smd circle
			(at 17.100042 -14.249908)
			(size 0.4572 0.4572)
			(layers "F.Cu" "F.Mask" "F.Paste")
			(net "GND")
		)
		(pad "K44" smd circle
			(at 18.050002 -14.249908)
			(size 0.4572 0.4572)
			(layers "F.Cu" "F.Mask" "F.Paste")
			(net "GND")
		)
		(pad "K45" smd circle
			(at 18.999962 -14.249908)
			(size 0.4572 0.4572)
			(layers "F.Cu" "F.Mask" "F.Paste")
			(net "GND")
		)
		(pad "K46" smd circle
			(at 19.949922 -14.249908)
			(size 0.4572 0.4572)
			(layers "F.Cu" "F.Mask" "F.Paste")
			(net "GND")
		)
		(pad "K47" smd circle
			(at 20.899882 -14.249908)
			(size 0.4572 0.4572)
			(layers "F.Cu" "F.Mask" "F.Paste")
			(net "GND")
		)
		(pad "K48" smd circle
			(at 21.850096 -14.249908)
			(size 0.4572 0.4572)
			(layers "F.Cu" "F.Mask" "F.Paste")
			(net "P5E_PEX1_STN4_RX_DP<70>")
		)
		(pad "K49" smd circle
			(at 22.800056 -14.249908)
			(size 0.4572 0.4572)
			(layers "F.Cu" "F.Mask" "F.Paste")
			(net "P5E_PEX1_STN4_RX_DN<70>")
		)
		(pad "L1" smd circle
			(at -22.800056 -13.299948)
			(size 0.4572 0.4572)
			(layers "F.Cu" "F.Mask" "F.Paste")
			(net "GND")
		)
		(pad "L2" smd circle
			(at -21.850096 -13.299948)
			(size 0.4572 0.4572)
			(layers "F.Cu" "F.Mask" "F.Paste")
			(net "GND")
		)
		(pad "L3" smd circle
			(at -20.899882 -13.299948)
			(size 0.4572 0.4572)
			(layers "F.Cu" "F.Mask" "F.Paste")
			(net "P5E_PEX1_STN7_RX_DN<120>")
		)
		(pad "L4" smd circle
			(at -19.949922 -13.299948)
			(size 0.4572 0.4572)
			(layers "F.Cu" "F.Mask" "F.Paste")
			(net "P5E_PEX1_STN7_RX_DP<120>")
		)
		(pad "L5" smd circle
			(at -18.999962 -13.299948)
			(size 0.4572 0.4572)
			(layers "F.Cu" "F.Mask" "F.Paste")
			(net "GND")
		)
		(pad "L6" smd circle
			(at -18.050002 -13.299948)
			(size 0.4572 0.4572)
			(layers "F.Cu" "F.Mask" "F.Paste")
			(net "P5E_PEX1_STN7_TX_DN<120>")
		)
		(pad "L7" smd circle
			(at -17.100042 -13.299948)
			(size 0.4572 0.4572)
			(layers "F.Cu" "F.Mask" "F.Paste")
			(net "P5E_PEX1_STN7_TX_DP<120>")
		)
		(pad "L8" smd circle
			(at -16.150082 -13.299948)
			(size 0.4572 0.4572)
			(layers "F.Cu" "F.Mask" "F.Paste")
			(net "GND")
		)
		(pad "L9" smd circle
			(at -15.200122 -13.299948)
			(size 0.4572 0.4572)
			(layers "F.Cu" "F.Mask" "F.Paste")
			(net "GND")
		)
		(pad "L10" smd circle
			(at -14.249908 -13.299948)
			(size 0.4572 0.4572)
			(layers "F.Cu" "F.Mask" "F.Paste")
			(net "GND")
		)
		(pad "L11" smd circle
			(at -13.299948 -13.299948)
			(size 0.4572 0.4572)
			(layers "F.Cu" "F.Mask" "F.Paste")
			(net "GND")
		)
		(pad "L12" smd circle
			(at -12.349988 -13.299948)
			(size 0.4572 0.4572)
			(layers "F.Cu" "F.Mask" "F.Paste")
			(net "PEX1_DBG_MODE0")
		)
		(pad "L13" smd circle
			(at -11.400028 -13.299948)
			(size 0.4572 0.4572)
			(layers "F.Cu" "F.Mask" "F.Paste")
			(net "PEX1_DBG_MODE1")
		)
		(pad "L14" smd circle
			(at -10.450068 -13.299948)
			(size 0.4572 0.4572)
			(layers "F.Cu" "F.Mask" "F.Paste")
			(net "GND")
		)
		(pad "L15" smd circle
			(at -9.500108 -13.299948)
			(size 0.4572 0.4572)
			(layers "F.Cu" "F.Mask" "F.Paste")
			(net "PU_PEX1_ATPG_MODE_L")
		)
		(pad "L16" smd circle
			(at -8.549894 -13.299948)
			(size 0.4572 0.4572)
			(layers "F.Cu" "F.Mask" "F.Paste")
			(net "PU_PEX1_PAD_TRI_L")
		)
		(pad "L17" smd circle
			(at -7.599934 -13.299948)
			(size 0.4572 0.4572)
			(layers "F.Cu" "F.Mask" "F.Paste")
			(net "TP_PEX1_TDI")
		)
		(pad "L18" smd circle
			(at -6.649974 -13.299948)
			(size 0.4572 0.4572)
			(layers "F.Cu" "F.Mask" "F.Paste")
			(net "PEX1_DBG_SEL0")
		)
		(pad "L19" smd circle
			(at -5.700014 -13.299948)
			(size 0.4572 0.4572)
			(layers "F.Cu" "F.Mask" "F.Paste")
			(net "TP_PEX1_TDO")
		)
		(pad "L20" smd circle
			(at -4.750054 -13.299948)
			(size 0.4572 0.4572)
			(layers "F.Cu" "F.Mask" "F.Paste")
			(net "PU_PEX1_TR_TCK")
		)
		(pad "L21" smd circle
			(at -3.800094 -13.299948)
			(size 0.4572 0.4572)
			(layers "F.Cu" "F.Mask" "F.Paste")
			(net "GND")
		)
		(pad "L22" smd circle
			(at -2.84988 -13.299948)
			(size 0.4572 0.4572)
			(layers "F.Cu" "F.Mask" "F.Paste")
			(net "Net_5289")
		)
		(pad "L23" smd circle
			(at -1.89992 -13.299948)
			(size 0.4572 0.4572)
			(layers "F.Cu" "F.Mask" "F.Paste")
			(net "Net_5293")
		)
		(pad "L24" smd circle
			(at -0.94996 -13.299948)
			(size 0.4572 0.4572)
			(layers "F.Cu" "F.Mask" "F.Paste")
			(net "Net_5288")
		)
		(pad "L25" smd circle
			(at 0 -13.299948)
			(size 0.4572 0.4572)
			(layers "F.Cu" "F.Mask" "F.Paste")
			(net "PEX1_SPARE5")
		)
		(pad "L26" smd circle
			(at 0.94996 -13.299948)
			(size 0.4572 0.4572)
			(layers "F.Cu" "F.Mask" "F.Paste")
			(net "PU_PEX1_SIO_BLINK")
		)
		(pad "L27" smd circle
			(at 1.89992 -13.299948)
			(size 0.4572 0.4572)
			(layers "F.Cu" "F.Mask" "F.Paste")
			(net "PEX1_SPARE2")
		)
		(pad "L28" smd circle
			(at 2.84988 -13.299948)
			(size 0.4572 0.4572)
			(layers "F.Cu" "F.Mask" "F.Paste")
			(net "PEX1_SPARE6")
		)
		(pad "L29" smd circle
			(at 3.800094 -13.299948)
			(size 0.4572 0.4572)
			(layers "F.Cu" "F.Mask" "F.Paste")
			(net "Net_5278")
		)
		(pad "L30" smd circle
			(at 4.750054 -13.299948)
			(size 0.4572 0.4572)
			(layers "F.Cu" "F.Mask" "F.Paste")
			(net "PEX1_SPARE1")
		)
		(pad "L31" smd circle
			(at 5.700014 -13.299948)
			(size 0.4572 0.4572)
			(layers "F.Cu" "F.Mask" "F.Paste")
			(net "Net_5282")
		)
		(pad "L32" smd circle
			(at 6.649974 -13.299948)
			(size 0.4572 0.4572)
			(layers "F.Cu" "F.Mask" "F.Paste")
			(net "PEX1_SPARE3")
		)
		(pad "L33" smd circle
			(at 7.599934 -13.299948)
			(size 0.4572 0.4572)
			(layers "F.Cu" "F.Mask" "F.Paste")
			(net "Net_5274")
		)
		(pad "L34" smd circle
			(at 8.549894 -13.299948)
			(size 0.4572 0.4572)
			(layers "F.Cu" "F.Mask" "F.Paste")
			(net "SMB_PEX1_SLAVE1_SCL")
		)
		(pad "L35" smd circle
			(at 9.500108 -13.299948)
			(size 0.4572 0.4572)
			(layers "F.Cu" "F.Mask" "F.Paste")
			(net "Net_5271")
		)
		(pad "L36" smd circle
			(at 10.450068 -13.299948)
			(size 0.4572 0.4572)
			(layers "F.Cu" "F.Mask" "F.Paste")
			(net "Net_5301")
		)
		(pad "L37" smd circle
			(at 11.400028 -13.299948)
			(size 0.4572 0.4572)
			(layers "F.Cu" "F.Mask" "F.Paste")
			(net "PEX1_EXT_GPIO_LATCH_N")
		)
		(pad "L38" smd circle
			(at 12.349988 -13.299948)
			(size 0.4572 0.4572)
			(layers "F.Cu" "F.Mask" "F.Paste")
			(net "Net_5298")
		)
		(pad "L39" smd circle
			(at 13.299948 -13.299948)
			(size 0.4572 0.4572)
			(layers "F.Cu" "F.Mask" "F.Paste")
			(net "SMB_PEX1_SLAVE_SDA")
		)
		(pad "L40" smd circle
			(at 14.249908 -13.299948)
			(size 0.4572 0.4572)
			(layers "F.Cu" "F.Mask" "F.Paste")
			(net "GND")
		)
		(pad "L41" smd circle
			(at 15.200122 -13.299948)
			(size 0.4572 0.4572)
			(layers "F.Cu" "F.Mask" "F.Paste")
			(net "GND")
		)
		(pad "L42" smd circle
			(at 16.150082 -13.299948)
			(size 0.4572 0.4572)
			(layers "F.Cu" "F.Mask" "F.Paste")
			(net "GND")
		)
		(pad "L43" smd circle
			(at 17.100042 -13.299948)
			(size 0.4572 0.4572)
			(layers "F.Cu" "F.Mask" "F.Paste")
			(net "P5E_PEX1_STN4_TX_DP<69>")
		)
		(pad "L44" smd circle
			(at 18.050002 -13.299948)
			(size 0.4572 0.4572)
			(layers "F.Cu" "F.Mask" "F.Paste")
			(net "P5E_PEX1_STN4_TX_DN<69>")
		)
		(pad "L45" smd circle
			(at 18.999962 -13.299948)
			(size 0.4572 0.4572)
			(layers "F.Cu" "F.Mask" "F.Paste")
			(net "GND")
		)
		(pad "L46" smd circle
			(at 19.949922 -13.299948)
			(size 0.4572 0.4572)
			(layers "F.Cu" "F.Mask" "F.Paste")
			(net "P5E_PEX1_STN4_RX_DP<69>")
		)
		(pad "L47" smd circle
			(at 20.899882 -13.299948)
			(size 0.4572 0.4572)
			(layers "F.Cu" "F.Mask" "F.Paste")
			(net "P5E_PEX1_STN4_RX_DN<69>")
		)
		(pad "L48" smd circle
			(at 21.850096 -13.299948)
			(size 0.4572 0.4572)
			(layers "F.Cu" "F.Mask" "F.Paste")
			(net "GND")
		)
		(pad "L49" smd circle
			(at 22.800056 -13.299948)
			(size 0.4572 0.4572)
			(layers "F.Cu" "F.Mask" "F.Paste")
			(net "GND")
		)
		(pad "M1" smd circle
			(at -22.800056 -12.349988)
			(size 0.4572 0.4572)
			(layers "F.Cu" "F.Mask" "F.Paste")
			(net "P5E_PEX1_STN7_RX_DN<119>")
		)
		(pad "M2" smd circle
			(at -21.850096 -12.349988)
			(size 0.4572 0.4572)
			(layers "F.Cu" "F.Mask" "F.Paste")
			(net "P5E_PEX1_STN7_RX_DP<119>")
		)
		(pad "M3" smd circle
			(at -20.899882 -12.349988)
			(size 0.4572 0.4572)
			(layers "F.Cu" "F.Mask" "F.Paste")
			(net "GND")
		)
		(pad "M4" smd circle
			(at -19.949922 -12.349988)
			(size 0.4572 0.4572)
			(layers "F.Cu" "F.Mask" "F.Paste")
			(net "GND")
		)
		(pad "M5" smd circle
			(at -18.999962 -12.349988)
			(size 0.4572 0.4572)
			(layers "F.Cu" "F.Mask" "F.Paste")
			(net "GND")
		)
		(pad "M6" smd circle
			(at -18.050002 -12.349988)
			(size 0.4572 0.4572)
			(layers "F.Cu" "F.Mask" "F.Paste")
			(net "GND")
		)
		(pad "M7" smd circle
			(at -17.100042 -12.349988)
			(size 0.4572 0.4572)
			(layers "F.Cu" "F.Mask" "F.Paste")
			(net "GND")
		)
		(pad "M8" smd circle
			(at -16.150082 -12.349988)
			(size 0.4572 0.4572)
			(layers "F.Cu" "F.Mask" "F.Paste")
			(net "P5E_PEX1_STN7_TX_DN<119>")
		)
		(pad "M9" smd circle
			(at -15.200122 -12.349988)
			(size 0.4572 0.4572)
			(layers "F.Cu" "F.Mask" "F.Paste")
			(net "P5E_PEX1_STN7_TX_DP<119>")
		)
		(pad "M10" smd circle
			(at -14.249908 -12.349988)
			(size 0.4572 0.4572)
			(layers "F.Cu" "F.Mask" "F.Paste")
			(net "GND")
		)
		(pad "M11" smd circle
			(at -13.299948 -12.349988)
			(size 0.4572 0.4572)
			(layers "F.Cu" "F.Mask" "F.Paste")
			(net "GND")
		)
		(pad "M12" smd circle
			(at -12.349988 -12.349988)
			(size 0.4572 0.4572)
			(layers "F.Cu" "F.Mask" "F.Paste")
			(net "GND")
		)
		(pad "M13" smd circle
			(at -11.400028 -12.349988)
			(size 0.4572 0.4572)
			(layers "F.Cu" "F.Mask" "F.Paste")
			(net "IRQ_PEX1_CLKREQ_INT_N")
		)
		(pad "M14" smd circle
			(at -10.450068 -12.349988)
			(size 0.4572 0.4572)
			(layers "F.Cu" "F.Mask" "F.Paste")
			(net "GND")
		)
		(pad "M15" smd circle
			(at -9.500108 -12.349988)
			(size 0.4572 0.4572)
			(layers "F.Cu" "F.Mask" "F.Paste")
			(net "TP_PEX1_TCK")
		)
		(pad "M16" smd circle
			(at -8.549894 -12.349988)
			(size 0.4572 0.4572)
			(layers "F.Cu" "F.Mask" "F.Paste")
			(net "PEX1_DFT_IDDT")
		)
		(pad "M17" smd circle
			(at -7.599934 -12.349988)
			(size 0.4572 0.4572)
			(layers "F.Cu" "F.Mask" "F.Paste")
			(net "RST_PEX1_SYS_N")
		)
		(pad "M18" smd circle
			(at -6.649974 -12.349988)
			(size 0.4572 0.4572)
			(layers "F.Cu" "F.Mask" "F.Paste")
			(net "TP_PEX1_TRST_L")
		)
		(pad "M19" smd circle
			(at -5.700014 -12.349988)
			(size 0.4572 0.4572)
			(layers "F.Cu" "F.Mask" "F.Paste")
			(net "PEX1_DBG_SEL1")
		)
		(pad "M20" smd circle
			(at -4.750054 -12.349988)
			(size 0.4572 0.4572)
			(layers "F.Cu" "F.Mask" "F.Paste")
			(net "TP_PEX1_TMS")
		)
		(pad "M21" smd circle
			(at -3.800094 -12.349988)
			(size 0.4572 0.4572)
			(layers "F.Cu" "F.Mask" "F.Paste")
			(net "GND")
		)
		(pad "M22" smd circle
			(at -2.84988 -12.349988)
			(size 0.4572 0.4572)
			(layers "F.Cu" "F.Mask" "F.Paste")
			(net "Net_5291")
		)
		(pad "M23" smd circle
			(at -1.89992 -12.349988)
			(size 0.4572 0.4572)
			(layers "F.Cu" "F.Mask" "F.Paste")
			(net "Net_5292")
		)
		(pad "M24" smd circle
			(at -0.94996 -12.349988)
			(size 0.4572 0.4572)
			(layers "F.Cu" "F.Mask" "F.Paste")
			(net "Net_5294")
		)
		(pad "M25" smd circle
			(at 0 -12.349988)
			(size 0.4572 0.4572)
			(layers "F.Cu" "F.Mask" "F.Paste")
			(net "PEX1_SPARE4")
		)
		(pad "M26" smd circle
			(at 0.94996 -12.349988)
			(size 0.4572 0.4572)
			(layers "F.Cu" "F.Mask" "F.Paste")
			(net "PEX1_SPARE0")
		)
		(pad "M27" smd circle
			(at 1.89992 -12.349988)
			(size 0.4572 0.4572)
			(layers "F.Cu" "F.Mask" "F.Paste")
			(net "PEX1_SPARE7")
		)
		(pad "M28" smd circle
			(at 2.84988 -12.349988)
			(size 0.4572 0.4572)
			(layers "F.Cu" "F.Mask" "F.Paste")
			(net "I2C0_PEX1_SHPC_SDA")
		)
		(pad "M29" smd circle
			(at 3.800094 -12.349988)
			(size 0.4572 0.4572)
			(layers "F.Cu" "F.Mask" "F.Paste")
			(net "I2C0_PEX1_SHPC_SCL")
		)
		(pad "M30" smd circle
			(at 4.750054 -12.349988)
			(size 0.4572 0.4572)
			(layers "F.Cu" "F.Mask" "F.Paste")
			(net "Net_5272")
		)
		(pad "M31" smd circle
			(at 5.700014 -12.349988)
			(size 0.4572 0.4572)
			(layers "F.Cu" "F.Mask" "F.Paste")
			(net "Net_5273")
		)
		(pad "M32" smd circle
			(at 6.649974 -12.349988)
			(size 0.4572 0.4572)
			(layers "F.Cu" "F.Mask" "F.Paste")
			(net "Net_5283")
		)
		(pad "M33" smd circle
			(at 7.599934 -12.349988)
			(size 0.4572 0.4572)
			(layers "F.Cu" "F.Mask" "F.Paste")
			(net "Net_5277")
		)
		(pad "M34" smd circle
			(at 8.549894 -12.349988)
			(size 0.4572 0.4572)
			(layers "F.Cu" "F.Mask" "F.Paste")
			(net "Net_5281")
		)
		(pad "M35" smd circle
			(at 9.500108 -12.349988)
			(size 0.4572 0.4572)
			(layers "F.Cu" "F.Mask" "F.Paste")
			(net "I2C0_PEX1_SCL")
		)
		(pad "M36" smd circle
			(at 10.450068 -12.349988)
			(size 0.4572 0.4572)
			(layers "F.Cu" "F.Mask" "F.Paste")
			(net "Net_5300")
		)
		(pad "M37" smd circle
			(at 11.400028 -12.349988)
			(size 0.4572 0.4572)
			(layers "F.Cu" "F.Mask" "F.Paste")
			(net "Net_5299")
		)
		(pad "M38" smd circle
			(at 12.349988 -12.349988)
			(size 0.4572 0.4572)
			(layers "F.Cu" "F.Mask" "F.Paste")
			(net "SMB_PEX1_SLAVE1_SDA")
		)
		(pad "M39" smd circle
			(at 13.299948 -12.349988)
			(size 0.4572 0.4572)
			(layers "F.Cu" "F.Mask" "F.Paste")
			(net "I2C0_PEX1_SDA")
		)
		(pad "M40" smd circle
			(at 14.249908 -12.349988)
			(size 0.4572 0.4572)
			(layers "F.Cu" "F.Mask" "F.Paste")
			(net "GND")
		)
		(pad "M41" smd circle
			(at 15.200122 -12.349988)
			(size 0.4572 0.4572)
			(layers "F.Cu" "F.Mask" "F.Paste")
			(net "P5E_PEX1_STN4_TX_DP<68>")
		)
		(pad "M42" smd circle
			(at 16.150082 -12.349988)
			(size 0.4572 0.4572)
			(layers "F.Cu" "F.Mask" "F.Paste")
			(net "P5E_PEX1_STN4_TX_DN<68>")
		)
		(pad "M43" smd circle
			(at 17.100042 -12.349988)
			(size 0.4572 0.4572)
			(layers "F.Cu" "F.Mask" "F.Paste")
			(net "GND")
		)
		(pad "M44" smd circle
			(at 18.050002 -12.349988)
			(size 0.4572 0.4572)
			(layers "F.Cu" "F.Mask" "F.Paste")
			(net "GND")
		)
		(pad "M45" smd circle
			(at 18.999962 -12.349988)
			(size 0.4572 0.4572)
			(layers "F.Cu" "F.Mask" "F.Paste")
			(net "GND")
		)
		(pad "M46" smd circle
			(at 19.949922 -12.349988)
			(size 0.4572 0.4572)
			(layers "F.Cu" "F.Mask" "F.Paste")
			(net "GND")
		)
		(pad "M47" smd circle
			(at 20.899882 -12.349988)
			(size 0.4572 0.4572)
			(layers "F.Cu" "F.Mask" "F.Paste")
			(net "GND")
		)
		(pad "M48" smd circle
			(at 21.850096 -12.349988)
			(size 0.4572 0.4572)
			(layers "F.Cu" "F.Mask" "F.Paste")
			(net "P5E_PEX1_STN4_RX_DP<68>")
		)
		(pad "M49" smd circle
			(at 22.800056 -12.349988)
			(size 0.4572 0.4572)
			(layers "F.Cu" "F.Mask" "F.Paste")
			(net "P5E_PEX1_STN4_RX_DN<68>")
		)
		(pad "N1" smd circle
			(at -22.800056 -11.400028)
			(size 0.4572 0.4572)
			(layers "F.Cu" "F.Mask" "F.Paste")
			(net "GND")
		)
		(pad "N2" smd circle
			(at -21.850096 -11.400028)
			(size 0.4572 0.4572)
			(layers "F.Cu" "F.Mask" "F.Paste")
			(net "GND")
		)
		(pad "N3" smd circle
			(at -20.899882 -11.400028)
			(size 0.4572 0.4572)
			(layers "F.Cu" "F.Mask" "F.Paste")
			(net "P5E_PEX1_STN7_RX_DN<118>")
		)
		(pad "N4" smd circle
			(at -19.949922 -11.400028)
			(size 0.4572 0.4572)
			(layers "F.Cu" "F.Mask" "F.Paste")
			(net "P5E_PEX1_STN7_RX_DP<118>")
		)
		(pad "N5" smd circle
			(at -18.999962 -11.400028)
			(size 0.4572 0.4572)
			(layers "F.Cu" "F.Mask" "F.Paste")
			(net "GND")
		)
		(pad "N6" smd circle
			(at -18.050002 -11.400028)
			(size 0.4572 0.4572)
			(layers "F.Cu" "F.Mask" "F.Paste")
			(net "P5E_PEX1_STN7_TX_DN<118>")
		)
		(pad "N7" smd circle
			(at -17.100042 -11.400028)
			(size 0.4572 0.4572)
			(layers "F.Cu" "F.Mask" "F.Paste")
			(net "P5E_PEX1_STN7_TX_DP<118>")
		)
		(pad "N8" smd circle
			(at -16.150082 -11.400028)
			(size 0.4572 0.4572)
			(layers "F.Cu" "F.Mask" "F.Paste")
			(net "GND")
		)
		(pad "N9" smd circle
			(at -15.200122 -11.400028)
			(size 0.4572 0.4572)
			(layers "F.Cu" "F.Mask" "F.Paste")
			(net "GND")
		)
		(pad "N10" smd circle
			(at -14.249908 -11.400028)
			(size 0.4572 0.4572)
			(layers "F.Cu" "F.Mask" "F.Paste")
			(net "GND")
		)
		(pad "N11" smd circle
			(at -13.299948 -11.400028)
			(size 0.4572 0.4572)
			(layers "F.Cu" "F.Mask" "F.Paste")
			(net "GND")
		)
		(pad "N12" smd circle
			(at -12.349988 -11.400028)
			(size 0.4572 0.4572)
			(layers "F.Cu" "F.Mask" "F.Paste")
			(net "GND")
		)
		(pad "N13" smd circle
			(at -11.400028 -11.400028)
			(size 0.4572 0.4572)
			(layers "F.Cu" "F.Mask" "F.Paste")
			(net "GND")
		)
		(pad "N14" smd circle
			(at -10.450068 -11.400028)
			(size 0.4572 0.4572)
			(layers "F.Cu" "F.Mask" "F.Paste")
			(net "GND")
		)
		(pad "N15" smd circle
			(at -9.500108 -11.400028)
			(size 0.4572 0.4572)
			(layers "F.Cu" "F.Mask" "F.Paste")
			(net "GND")
		)
		(pad "N16" smd circle
			(at -8.549894 -11.400028)
			(size 0.4572 0.4572)
			(layers "F.Cu" "F.Mask" "F.Paste")
			(net "GND")
		)
		(pad "N17" smd circle
			(at -7.599934 -11.400028)
			(size 0.4572 0.4572)
			(layers "F.Cu" "F.Mask" "F.Paste")
			(net "GND")
		)
		(pad "N18" smd circle
			(at -6.649974 -11.400028)
			(size 0.4572 0.4572)
			(layers "F.Cu" "F.Mask" "F.Paste")
			(net "GND")
		)
		(pad "N19" smd circle
			(at -5.700014 -11.400028)
			(size 0.4572 0.4572)
			(layers "F.Cu" "F.Mask" "F.Paste")
			(net "GND")
		)
		(pad "N20" smd circle
			(at -4.750054 -11.400028)
			(size 0.4572 0.4572)
			(layers "F.Cu" "F.Mask" "F.Paste")
			(net "GND")
		)
		(pad "N21" smd circle
			(at -3.800094 -11.400028)
			(size 0.4572 0.4572)
			(layers "F.Cu" "F.Mask" "F.Paste")
			(net "GND")
		)
		(pad "N22" smd circle
			(at -2.84988 -11.400028)
			(size 0.4572 0.4572)
			(layers "F.Cu" "F.Mask" "F.Paste")
			(net "GND")
		)
		(pad "N23" smd circle
			(at -1.89992 -11.400028)
			(size 0.4572 0.4572)
			(layers "F.Cu" "F.Mask" "F.Paste")
			(net "GND")
		)
		(pad "N24" smd circle
			(at -0.94996 -11.400028)
			(size 0.4572 0.4572)
			(layers "F.Cu" "F.Mask" "F.Paste")
			(net "GND")
		)
		(pad "N25" smd circle
			(at 0 -11.400028)
			(size 0.4572 0.4572)
			(layers "F.Cu" "F.Mask" "F.Paste")
			(net "GND")
		)
		(pad "N26" smd circle
			(at 0.94996 -11.400028)
			(size 0.4572 0.4572)
			(layers "F.Cu" "F.Mask" "F.Paste")
			(net "GND")
		)
		(pad "N27" smd circle
			(at 1.89992 -11.400028)
			(size 0.4572 0.4572)
			(layers "F.Cu" "F.Mask" "F.Paste")
			(net "GND")
		)
		(pad "N28" smd circle
			(at 2.84988 -11.400028)
			(size 0.4572 0.4572)
			(layers "F.Cu" "F.Mask" "F.Paste")
			(net "GND")
		)
		(pad "N29" smd circle
			(at 3.800094 -11.400028)
			(size 0.4572 0.4572)
			(layers "F.Cu" "F.Mask" "F.Paste")
			(net "GND")
		)
		(pad "N30" smd circle
			(at 4.750054 -11.400028)
			(size 0.4572 0.4572)
			(layers "F.Cu" "F.Mask" "F.Paste")
			(net "GND")
		)
		(pad "N31" smd circle
			(at 5.700014 -11.400028)
			(size 0.4572 0.4572)
			(layers "F.Cu" "F.Mask" "F.Paste")
			(net "GND")
		)
		(pad "N32" smd circle
			(at 6.649974 -11.400028)
			(size 0.4572 0.4572)
			(layers "F.Cu" "F.Mask" "F.Paste")
			(net "GND")
		)
		(pad "N33" smd circle
			(at 7.599934 -11.400028)
			(size 0.4572 0.4572)
			(layers "F.Cu" "F.Mask" "F.Paste")
			(net "GND")
		)
		(pad "N34" smd circle
			(at 8.549894 -11.400028)
			(size 0.4572 0.4572)
			(layers "F.Cu" "F.Mask" "F.Paste")
			(net "GND")
		)
		(pad "N35" smd circle
			(at 9.500108 -11.400028)
			(size 0.4572 0.4572)
			(layers "F.Cu" "F.Mask" "F.Paste")
			(net "GND")
		)
		(pad "N36" smd circle
			(at 10.450068 -11.400028)
			(size 0.4572 0.4572)
			(layers "F.Cu" "F.Mask" "F.Paste")
			(net "GND")
		)
		(pad "N37" smd circle
			(at 11.400028 -11.400028)
			(size 0.4572 0.4572)
			(layers "F.Cu" "F.Mask" "F.Paste")
			(net "GND")
		)
		(pad "N38" smd circle
			(at 12.349988 -11.400028)
			(size 0.4572 0.4572)
			(layers "F.Cu" "F.Mask" "F.Paste")
			(net "SMB_PEX1_SLAVE_SCL")
		)
		(pad "N39" smd circle
			(at 13.299948 -11.400028)
			(size 0.4572 0.4572)
			(layers "F.Cu" "F.Mask" "F.Paste")
			(net "Net_5280")
		)
		(pad "N40" smd circle
			(at 14.249908 -11.400028)
			(size 0.4572 0.4572)
			(layers "F.Cu" "F.Mask" "F.Paste")
			(net "GND")
		)
		(pad "N41" smd circle
			(at 15.200122 -11.400028)
			(size 0.4572 0.4572)
			(layers "F.Cu" "F.Mask" "F.Paste")
			(net "GND")
		)
		(pad "N42" smd circle
			(at 16.150082 -11.400028)
			(size 0.4572 0.4572)
			(layers "F.Cu" "F.Mask" "F.Paste")
			(net "GND")
		)
		(pad "N43" smd circle
			(at 17.100042 -11.400028)
			(size 0.4572 0.4572)
			(layers "F.Cu" "F.Mask" "F.Paste")
			(net "P5E_PEX1_STN4_TX_DP<67>")
		)
		(pad "N44" smd circle
			(at 18.050002 -11.400028)
			(size 0.4572 0.4572)
			(layers "F.Cu" "F.Mask" "F.Paste")
			(net "P5E_PEX1_STN4_TX_DN<67>")
		)
		(pad "N45" smd circle
			(at 18.999962 -11.400028)
			(size 0.4572 0.4572)
			(layers "F.Cu" "F.Mask" "F.Paste")
			(net "GND")
		)
		(pad "N46" smd circle
			(at 19.949922 -11.400028)
			(size 0.4572 0.4572)
			(layers "F.Cu" "F.Mask" "F.Paste")
			(net "P5E_PEX1_STN4_RX_DP<67>")
		)
		(pad "N47" smd circle
			(at 20.899882 -11.400028)
			(size 0.4572 0.4572)
			(layers "F.Cu" "F.Mask" "F.Paste")
			(net "P5E_PEX1_STN4_RX_DN<67>")
		)
		(pad "N48" smd circle
			(at 21.850096 -11.400028)
			(size 0.4572 0.4572)
			(layers "F.Cu" "F.Mask" "F.Paste")
			(net "GND")
		)
		(pad "N49" smd circle
			(at 22.800056 -11.400028)
			(size 0.4572 0.4572)
			(layers "F.Cu" "F.Mask" "F.Paste")
			(net "GND")
		)
		(pad "P1" smd circle
			(at -22.800056 -10.450068)
			(size 0.4572 0.4572)
			(layers "F.Cu" "F.Mask" "F.Paste")
			(net "P5E_PEX1_STN7_RX_DN<117>")
		)
		(pad "P2" smd circle
			(at -21.850096 -10.450068)
			(size 0.4572 0.4572)
			(layers "F.Cu" "F.Mask" "F.Paste")
			(net "P5E_PEX1_STN7_RX_DP<117>")
		)
		(pad "P3" smd circle
			(at -20.899882 -10.450068)
			(size 0.4572 0.4572)
			(layers "F.Cu" "F.Mask" "F.Paste")
			(net "GND")
		)
		(pad "P4" smd circle
			(at -19.949922 -10.450068)
			(size 0.4572 0.4572)
			(layers "F.Cu" "F.Mask" "F.Paste")
			(net "GND")
		)
		(pad "P5" smd circle
			(at -18.999962 -10.450068)
			(size 0.4572 0.4572)
			(layers "F.Cu" "F.Mask" "F.Paste")
			(net "GND")
		)
		(pad "P6" smd circle
			(at -18.050002 -10.450068)
			(size 0.4572 0.4572)
			(layers "F.Cu" "F.Mask" "F.Paste")
			(net "GND")
		)
		(pad "P7" smd circle
			(at -17.100042 -10.450068)
			(size 0.4572 0.4572)
			(layers "F.Cu" "F.Mask" "F.Paste")
			(net "GND")
		)
		(pad "P8" smd circle
			(at -16.150082 -10.450068)
			(size 0.4572 0.4572)
			(layers "F.Cu" "F.Mask" "F.Paste")
			(net "P5E_PEX1_STN7_TX_DN<117>")
		)
		(pad "P9" smd circle
			(at -15.200122 -10.450068)
			(size 0.4572 0.4572)
			(layers "F.Cu" "F.Mask" "F.Paste")
			(net "P5E_PEX1_STN7_TX_DP<117>")
		)
		(pad "P10" smd circle
			(at -14.249908 -10.450068)
			(size 0.4572 0.4572)
			(layers "F.Cu" "F.Mask" "F.Paste")
			(net "GND")
		)
		(pad "P11" smd circle
			(at -13.299948 -10.450068)
			(size 0.4572 0.4572)
			(layers "F.Cu" "F.Mask" "F.Paste")
			(net "GND")
		)
		(pad "P12" smd circle
			(at -12.349988 -10.450068)
			(size 0.4572 0.4572)
			(layers "F.Cu" "F.Mask" "F.Paste")
			(net "GND")
		)
		(pad "P13" smd circle
			(at -11.400028 -10.450068)
			(size 0.4572 0.4572)
			(layers "F.Cu" "F.Mask" "F.Paste")
			(net "GND")
		)
		(pad "P14" smd circle
			(at -10.450068 -10.450068)
			(size 0.4572 0.4572)
			(layers "F.Cu" "F.Mask" "F.Paste")
			(net "GND")
		)
		(pad "P15" smd circle
			(at -9.500108 -10.450068)
			(size 0.4572 0.4572)
			(layers "F.Cu" "F.Mask" "F.Paste")
			(net "GND")
		)
		(pad "P16" smd circle
			(at -8.549894 -10.450068)
			(size 0.4572 0.4572)
			(layers "F.Cu" "F.Mask" "F.Paste")
			(net "GND")
		)
		(pad "P17" smd circle
			(at -7.599934 -10.450068)
			(size 0.4572 0.4572)
			(layers "F.Cu" "F.Mask" "F.Paste")
			(net "GND")
		)
		(pad "P18" smd circle
			(at -6.649974 -10.450068)
			(size 0.4572 0.4572)
			(layers "F.Cu" "F.Mask" "F.Paste")
			(net "GND")
		)
		(pad "P19" smd circle
			(at -5.700014 -10.450068)
			(size 0.4572 0.4572)
			(layers "F.Cu" "F.Mask" "F.Paste")
			(net "GND")
		)
		(pad "P20" smd circle
			(at -4.750054 -10.450068)
			(size 0.4572 0.4572)
			(layers "F.Cu" "F.Mask" "F.Paste")
			(net "GND")
		)
		(pad "P21" smd circle
			(at -3.800094 -10.450068)
			(size 0.4572 0.4572)
			(layers "F.Cu" "F.Mask" "F.Paste")
			(net "GND")
		)
		(pad "P22" smd circle
			(at -2.84988 -10.450068)
			(size 0.4572 0.4572)
			(layers "F.Cu" "F.Mask" "F.Paste")
			(net "GND")
		)
		(pad "P23" smd circle
			(at -1.89992 -10.450068)
			(size 0.4572 0.4572)
			(layers "F.Cu" "F.Mask" "F.Paste")
			(net "GND")
		)
		(pad "P24" smd circle
			(at -0.94996 -10.450068)
			(size 0.4572 0.4572)
			(layers "F.Cu" "F.Mask" "F.Paste")
			(net "GND")
		)
		(pad "P25" smd circle
			(at 0 -10.450068)
			(size 0.4572 0.4572)
			(layers "F.Cu" "F.Mask" "F.Paste")
			(net "GND")
		)
		(pad "P26" smd circle
			(at 0.94996 -10.450068)
			(size 0.4572 0.4572)
			(layers "F.Cu" "F.Mask" "F.Paste")
			(net "GND")
		)
		(pad "P27" smd circle
			(at 1.89992 -10.450068)
			(size 0.4572 0.4572)
			(layers "F.Cu" "F.Mask" "F.Paste")
			(net "GND")
		)
		(pad "P28" smd circle
			(at 2.84988 -10.450068)
			(size 0.4572 0.4572)
			(layers "F.Cu" "F.Mask" "F.Paste")
			(net "GND")
		)
		(pad "P29" smd circle
			(at 3.800094 -10.450068)
			(size 0.4572 0.4572)
			(layers "F.Cu" "F.Mask" "F.Paste")
			(net "GND")
		)
		(pad "P30" smd circle
			(at 4.750054 -10.450068)
			(size 0.4572 0.4572)
			(layers "F.Cu" "F.Mask" "F.Paste")
			(net "GND")
		)
		(pad "P31" smd circle
			(at 5.700014 -10.450068)
			(size 0.4572 0.4572)
			(layers "F.Cu" "F.Mask" "F.Paste")
			(net "GND")
		)
		(pad "P32" smd circle
			(at 6.649974 -10.450068)
			(size 0.4572 0.4572)
			(layers "F.Cu" "F.Mask" "F.Paste")
			(net "GND")
		)
		(pad "P33" smd circle
			(at 7.599934 -10.450068)
			(size 0.4572 0.4572)
			(layers "F.Cu" "F.Mask" "F.Paste")
			(net "GND")
		)
		(pad "P34" smd circle
			(at 8.549894 -10.450068)
			(size 0.4572 0.4572)
			(layers "F.Cu" "F.Mask" "F.Paste")
			(net "GND")
		)
		(pad "P35" smd circle
			(at 9.500108 -10.450068)
			(size 0.4572 0.4572)
			(layers "F.Cu" "F.Mask" "F.Paste")
			(net "GND")
		)
		(pad "P36" smd circle
			(at 10.450068 -10.450068)
			(size 0.4572 0.4572)
			(layers "F.Cu" "F.Mask" "F.Paste")
			(net "Net_495")
		)
		(pad "P37" smd circle
			(at 11.400028 -10.450068)
			(size 0.4572 0.4572)
			(layers "F.Cu" "F.Mask" "F.Paste")
			(net "GND")
		)
		(pad "P38" smd circle
			(at 12.349988 -10.450068)
			(size 0.4572 0.4572)
			(layers "F.Cu" "F.Mask" "F.Paste")
			(net "RST_PEX1_S3_PERST_R_N")
		)
		(pad "P39" smd circle
			(at 13.299948 -10.450068)
			(size 0.4572 0.4572)
			(layers "F.Cu" "F.Mask" "F.Paste")
			(net "RST_PEX1_S1_PERST_R_N")
		)
		(pad "P40" smd circle
			(at 14.249908 -10.450068)
			(size 0.4572 0.4572)
			(layers "F.Cu" "F.Mask" "F.Paste")
			(net "GND")
		)
		(pad "P41" smd circle
			(at 15.200122 -10.450068)
			(size 0.4572 0.4572)
			(layers "F.Cu" "F.Mask" "F.Paste")
			(net "P5E_PEX1_STN4_TX_DP<66>")
		)
		(pad "P42" smd circle
			(at 16.150082 -10.450068)
			(size 0.4572 0.4572)
			(layers "F.Cu" "F.Mask" "F.Paste")
			(net "P5E_PEX1_STN4_TX_DN<66>")
		)
		(pad "P43" smd circle
			(at 17.100042 -10.450068)
			(size 0.4572 0.4572)
			(layers "F.Cu" "F.Mask" "F.Paste")
			(net "GND")
		)
		(pad "P44" smd circle
			(at 18.050002 -10.450068)
			(size 0.4572 0.4572)
			(layers "F.Cu" "F.Mask" "F.Paste")
			(net "GND")
		)
		(pad "P45" smd circle
			(at 18.999962 -10.450068)
			(size 0.4572 0.4572)
			(layers "F.Cu" "F.Mask" "F.Paste")
			(net "GND")
		)
		(pad "P46" smd circle
			(at 19.949922 -10.450068)
			(size 0.4572 0.4572)
			(layers "F.Cu" "F.Mask" "F.Paste")
			(net "GND")
		)
		(pad "P47" smd circle
			(at 20.899882 -10.450068)
			(size 0.4572 0.4572)
			(layers "F.Cu" "F.Mask" "F.Paste")
			(net "GND")
		)
		(pad "P48" smd circle
			(at 21.850096 -10.450068)
			(size 0.4572 0.4572)
			(layers "F.Cu" "F.Mask" "F.Paste")
			(net "P5E_PEX1_STN4_RX_DP<66>")
		)
		(pad "P49" smd circle
			(at 22.800056 -10.450068)
			(size 0.4572 0.4572)
			(layers "F.Cu" "F.Mask" "F.Paste")
			(net "P5E_PEX1_STN4_RX_DN<66>")
		)
		(pad "R1" smd circle
			(at -22.800056 -9.500108)
			(size 0.4572 0.4572)
			(layers "F.Cu" "F.Mask" "F.Paste")
			(net "GND")
		)
		(pad "R2" smd circle
			(at -21.850096 -9.500108)
			(size 0.4572 0.4572)
			(layers "F.Cu" "F.Mask" "F.Paste")
			(net "GND")
		)
		(pad "R3" smd circle
			(at -20.899882 -9.500108)
			(size 0.4572 0.4572)
			(layers "F.Cu" "F.Mask" "F.Paste")
			(net "P5E_PEX1_STN7_RX_DN<116>")
		)
		(pad "R4" smd circle
			(at -19.949922 -9.500108)
			(size 0.4572 0.4572)
			(layers "F.Cu" "F.Mask" "F.Paste")
			(net "P5E_PEX1_STN7_RX_DP<116>")
		)
		(pad "R5" smd circle
			(at -18.999962 -9.500108)
			(size 0.4572 0.4572)
			(layers "F.Cu" "F.Mask" "F.Paste")
			(net "GND")
		)
		(pad "R6" smd circle
			(at -18.050002 -9.500108)
			(size 0.4572 0.4572)
			(layers "F.Cu" "F.Mask" "F.Paste")
			(net "P5E_PEX1_STN7_TX_DN<116>")
		)
		(pad "R7" smd circle
			(at -17.100042 -9.500108)
			(size 0.4572 0.4572)
			(layers "F.Cu" "F.Mask" "F.Paste")
			(net "P5E_PEX1_STN7_TX_DP<116>")
		)
		(pad "R8" smd circle
			(at -16.150082 -9.500108)
			(size 0.4572 0.4572)
			(layers "F.Cu" "F.Mask" "F.Paste")
			(net "GND")
		)
		(pad "R9" smd circle
			(at -15.200122 -9.500108)
			(size 0.4572 0.4572)
			(layers "F.Cu" "F.Mask" "F.Paste")
			(net "GND")
		)
		(pad "R10" smd circle
			(at -14.249908 -9.500108)
			(size 0.4572 0.4572)
			(layers "F.Cu" "F.Mask" "F.Paste")
			(net "GND")
		)
		(pad "R11" smd circle
			(at -13.299948 -9.500108)
			(size 0.4572 0.4572)
			(layers "F.Cu" "F.Mask" "F.Paste")
			(net "GND")
		)
		(pad "R12" smd circle
			(at -12.349988 -9.500108)
			(size 0.4572 0.4572)
			(layers "F.Cu" "F.Mask" "F.Paste")
			(net "GND")
		)
		(pad "R13" smd circle
			(at -11.400028 -9.500108)
			(size 0.4572 0.4572)
			(layers "F.Cu" "F.Mask" "F.Paste")
			(net "GND")
		)
		(pad "R14" smd circle
			(at -10.450068 -9.500108)
			(size 0.4572 0.4572)
			(layers "F.Cu" "F.Mask" "F.Paste")
			(net "GND")
		)
		(pad "R15" smd circle
			(at -9.500108 -9.500108)
			(size 0.4572 0.4572)
			(layers "F.Cu" "F.Mask" "F.Paste")
			(net "GND")
		)
		(pad "R16" smd circle
			(at -8.549894 -9.500108)
			(size 0.4572 0.4572)
			(layers "F.Cu" "F.Mask" "F.Paste")
			(net "GND")
		)
		(pad "R17" smd circle
			(at -7.599934 -9.500108)
			(size 0.4572 0.4572)
			(layers "F.Cu" "F.Mask" "F.Paste")
			(net "GND")
		)
		(pad "R18" smd circle
			(at -6.649974 -9.500108)
			(size 0.4572 0.4572)
			(layers "F.Cu" "F.Mask" "F.Paste")
			(net "GND")
		)
		(pad "R19" smd circle
			(at -5.700014 -9.500108)
			(size 0.4572 0.4572)
			(layers "F.Cu" "F.Mask" "F.Paste")
			(net "GND")
		)
		(pad "R20" smd circle
			(at -4.750054 -9.500108)
			(size 0.4572 0.4572)
			(layers "F.Cu" "F.Mask" "F.Paste")
			(net "GND")
		)
		(pad "R21" smd circle
			(at -3.800094 -9.500108)
			(size 0.4572 0.4572)
			(layers "F.Cu" "F.Mask" "F.Paste")
			(net "GND")
		)
		(pad "R22" smd circle
			(at -2.84988 -9.500108)
			(size 0.4572 0.4572)
			(layers "F.Cu" "F.Mask" "F.Paste")
			(net "GND")
		)
		(pad "R23" smd circle
			(at -1.89992 -9.500108)
			(size 0.4572 0.4572)
			(layers "F.Cu" "F.Mask" "F.Paste")
			(net "GND")
		)
		(pad "R24" smd circle
			(at -0.94996 -9.500108)
			(size 0.4572 0.4572)
			(layers "F.Cu" "F.Mask" "F.Paste")
			(net "GND")
		)
		(pad "R25" smd circle
			(at 0 -9.500108)
			(size 0.4572 0.4572)
			(layers "F.Cu" "F.Mask" "F.Paste")
			(net "GND")
		)
		(pad "R26" smd circle
			(at 0.94996 -9.500108)
			(size 0.4572 0.4572)
			(layers "F.Cu" "F.Mask" "F.Paste")
			(net "GND")
		)
		(pad "R27" smd circle
			(at 1.89992 -9.500108)
			(size 0.4572 0.4572)
			(layers "F.Cu" "F.Mask" "F.Paste")
			(net "GND")
		)
		(pad "R28" smd circle
			(at 2.84988 -9.500108)
			(size 0.4572 0.4572)
			(layers "F.Cu" "F.Mask" "F.Paste")
			(net "GND")
		)
		(pad "R29" smd circle
			(at 3.800094 -9.500108)
			(size 0.4572 0.4572)
			(layers "F.Cu" "F.Mask" "F.Paste")
			(net "GND")
		)
		(pad "R30" smd circle
			(at 4.750054 -9.500108)
			(size 0.4572 0.4572)
			(layers "F.Cu" "F.Mask" "F.Paste")
			(net "GND")
		)
		(pad "R31" smd circle
			(at 5.700014 -9.500108)
			(size 0.4572 0.4572)
			(layers "F.Cu" "F.Mask" "F.Paste")
			(net "GND")
		)
		(pad "R32" smd circle
			(at 6.649974 -9.500108)
			(size 0.4572 0.4572)
			(layers "F.Cu" "F.Mask" "F.Paste")
			(net "GND")
		)
		(pad "R33" smd circle
			(at 7.599934 -9.500108)
			(size 0.4572 0.4572)
			(layers "F.Cu" "F.Mask" "F.Paste")
			(net "GND")
		)
		(pad "R34" smd circle
			(at 8.549894 -9.500108)
			(size 0.4572 0.4572)
			(layers "F.Cu" "F.Mask" "F.Paste")
			(net "GND")
		)
		(pad "R35" smd circle
			(at 9.500108 -9.500108)
			(size 0.4572 0.4572)
			(layers "F.Cu" "F.Mask" "F.Paste")
			(net "GND")
		)
		(pad "R36" smd circle
			(at 10.450068 -9.500108)
			(size 0.4572 0.4572)
			(layers "F.Cu" "F.Mask" "F.Paste")
			(net "Net_497")
		)
		(pad "R37" smd circle
			(at 11.400028 -9.500108)
			(size 0.4572 0.4572)
			(layers "F.Cu" "F.Mask" "F.Paste")
			(net "GND")
		)
		(pad "R38" smd circle
			(at 12.349988 -9.500108)
			(size 0.4572 0.4572)
			(layers "F.Cu" "F.Mask" "F.Paste")
			(net "Net_5228")
		)
		(pad "R39" smd circle
			(at 13.299948 -9.500108)
			(size 0.4572 0.4572)
			(layers "F.Cu" "F.Mask" "F.Paste")
			(net "Net_5222")
		)
		(pad "R40" smd circle
			(at 14.249908 -9.500108)
			(size 0.4572 0.4572)
			(layers "F.Cu" "F.Mask" "F.Paste")
			(net "GND")
		)
		(pad "R41" smd circle
			(at 15.200122 -9.500108)
			(size 0.4572 0.4572)
			(layers "F.Cu" "F.Mask" "F.Paste")
			(net "GND")
		)
		(pad "R42" smd circle
			(at 16.150082 -9.500108)
			(size 0.4572 0.4572)
			(layers "F.Cu" "F.Mask" "F.Paste")
			(net "GND")
		)
		(pad "R43" smd circle
			(at 17.100042 -9.500108)
			(size 0.4572 0.4572)
			(layers "F.Cu" "F.Mask" "F.Paste")
			(net "P5E_PEX1_STN4_TX_DP<65>")
		)
		(pad "R44" smd circle
			(at 18.050002 -9.500108)
			(size 0.4572 0.4572)
			(layers "F.Cu" "F.Mask" "F.Paste")
			(net "P5E_PEX1_STN4_TX_DN<65>")
		)
		(pad "R45" smd circle
			(at 18.999962 -9.500108)
			(size 0.4572 0.4572)
			(layers "F.Cu" "F.Mask" "F.Paste")
			(net "GND")
		)
		(pad "R46" smd circle
			(at 19.949922 -9.500108)
			(size 0.4572 0.4572)
			(layers "F.Cu" "F.Mask" "F.Paste")
			(net "P5E_PEX1_STN4_RX_DP<65>")
		)
		(pad "R47" smd circle
			(at 20.899882 -9.500108)
			(size 0.4572 0.4572)
			(layers "F.Cu" "F.Mask" "F.Paste")
			(net "P5E_PEX1_STN4_RX_DN<65>")
		)
		(pad "R48" smd circle
			(at 21.850096 -9.500108)
			(size 0.4572 0.4572)
			(layers "F.Cu" "F.Mask" "F.Paste")
			(net "GND")
		)
		(pad "R49" smd circle
			(at 22.800056 -9.500108)
			(size 0.4572 0.4572)
			(layers "F.Cu" "F.Mask" "F.Paste")
			(net "GND")
		)
		(pad "T1" smd circle
			(at -22.800056 -8.549894)
			(size 0.4572 0.4572)
			(layers "F.Cu" "F.Mask" "F.Paste")
			(net "P5E_PEX1_STN7_RX_DN<115>")
		)
		(pad "T2" smd circle
			(at -21.850096 -8.549894)
			(size 0.4572 0.4572)
			(layers "F.Cu" "F.Mask" "F.Paste")
			(net "P5E_PEX1_STN7_RX_DP<115>")
		)
		(pad "T3" smd circle
			(at -20.899882 -8.549894)
			(size 0.4572 0.4572)
			(layers "F.Cu" "F.Mask" "F.Paste")
			(net "GND")
		)
		(pad "T4" smd circle
			(at -19.949922 -8.549894)
			(size 0.4572 0.4572)
			(layers "F.Cu" "F.Mask" "F.Paste")
			(net "GND")
		)
		(pad "T5" smd circle
			(at -18.999962 -8.549894)
			(size 0.4572 0.4572)
			(layers "F.Cu" "F.Mask" "F.Paste")
			(net "GND")
		)
		(pad "T6" smd circle
			(at -18.050002 -8.549894)
			(size 0.4572 0.4572)
			(layers "F.Cu" "F.Mask" "F.Paste")
			(net "GND")
		)
		(pad "T7" smd circle
			(at -17.100042 -8.549894)
			(size 0.4572 0.4572)
			(layers "F.Cu" "F.Mask" "F.Paste")
			(net "GND")
		)
		(pad "T8" smd circle
			(at -16.150082 -8.549894)
			(size 0.4572 0.4572)
			(layers "F.Cu" "F.Mask" "F.Paste")
			(net "P5E_PEX1_STN7_TX_DN<115>")
		)
		(pad "T9" smd circle
			(at -15.200122 -8.549894)
			(size 0.4572 0.4572)
			(layers "F.Cu" "F.Mask" "F.Paste")
			(net "P5E_PEX1_STN7_TX_DP<115>")
		)
		(pad "T10" smd circle
			(at -14.249908 -8.549894)
			(size 0.4572 0.4572)
			(layers "F.Cu" "F.Mask" "F.Paste")
			(net "GND")
		)
		(pad "T11" smd circle
			(at -13.299948 -8.549894)
			(size 0.4572 0.4572)
			(layers "F.Cu" "F.Mask" "F.Paste")
			(net "GND")
		)
		(pad "T12" smd circle
			(at -12.349988 -8.549894)
			(size 0.4572 0.4572)
			(layers "F.Cu" "F.Mask" "F.Paste")
			(net "GND")
		)
		(pad "T13" smd circle
			(at -11.400028 -8.549894)
			(size 0.4572 0.4572)
			(layers "F.Cu" "F.Mask" "F.Paste")
			(net "GND")
		)
		(pad "T14" smd circle
			(at -10.450068 -8.549894)
			(size 0.4572 0.4572)
			(layers "F.Cu" "F.Mask" "F.Paste")
			(net "Net_504")
		)
		(pad "T15" smd circle
			(at -9.500108 -8.549894)
			(size 0.4572 0.4572)
			(layers "F.Cu" "F.Mask" "F.Paste")
			(net "GND")
		)
		(pad "T16" smd circle
			(at -8.549894 -8.549894)
			(size 0.4572 0.4572)
			(layers "F.Cu" "F.Mask" "F.Paste")
			(net "P1V25_SERDES_VDDPLL_PEX1")
		)
		(pad "T17" smd circle
			(at -7.599934 -8.549894)
			(size 0.4572 0.4572)
			(layers "F.Cu" "F.Mask" "F.Paste")
			(net "P1V25_SERDES_VDDPLL_PEX1")
		)
		(pad "T18" smd circle
			(at -6.649974 -8.549894)
			(size 0.4572 0.4572)
			(layers "F.Cu" "F.Mask" "F.Paste")
			(net "P1V25_SERDES_VDDPLL_PEX1")
		)
		(pad "T19" smd circle
			(at -5.700014 -8.549894)
			(size 0.4572 0.4572)
			(layers "F.Cu" "F.Mask" "F.Paste")
			(net "P1V25_SERDES_VDDPLL_PEX1")
		)
		(pad "T20" smd circle
			(at -4.750054 -8.549894)
			(size 0.4572 0.4572)
			(layers "F.Cu" "F.Mask" "F.Paste")
			(net "P1V25_SERDES_VDDPLL_PEX1")
		)
		(pad "T21" smd circle
			(at -3.800094 -8.549894)
			(size 0.4572 0.4572)
			(layers "F.Cu" "F.Mask" "F.Paste")
			(net "P1V25_SERDES_VDDPLL_PEX1")
		)
		(pad "T22" smd circle
			(at -2.84988 -8.549894)
			(size 0.4572 0.4572)
			(layers "F.Cu" "F.Mask" "F.Paste")
			(net "P1V25_SERDES_VDDPLL_PEX1")
		)
		(pad "T23" smd circle
			(at -1.89992 -8.549894)
			(size 0.4572 0.4572)
			(layers "F.Cu" "F.Mask" "F.Paste")
			(net "P1V25_SERDES_VDDPLL_PEX1")
		)
		(pad "T24" smd circle
			(at -0.94996 -8.549894)
			(size 0.4572 0.4572)
			(layers "F.Cu" "F.Mask" "F.Paste")
			(net "P1V25_SERDES_VDDPLL_PEX1")
		)
		(pad "T25" smd circle
			(at 0 -8.549894)
			(size 0.4572 0.4572)
			(layers "F.Cu" "F.Mask" "F.Paste")
			(net "P1V25_SERDES_VDDPLL_PEX1")
		)
		(pad "T26" smd circle
			(at 0.94996 -8.549894)
			(size 0.4572 0.4572)
			(layers "F.Cu" "F.Mask" "F.Paste")
			(net "P1V25_SERDES_VDDPLL_PEX1")
		)
		(pad "T27" smd circle
			(at 1.89992 -8.549894)
			(size 0.4572 0.4572)
			(layers "F.Cu" "F.Mask" "F.Paste")
			(net "P1V25_SERDES_VDDPLL_PEX1")
		)
		(pad "T28" smd circle
			(at 2.84988 -8.549894)
			(size 0.4572 0.4572)
			(layers "F.Cu" "F.Mask" "F.Paste")
			(net "P1V25_SERDES_VDDPLL_PEX1")
		)
		(pad "T29" smd circle
			(at 3.800094 -8.549894)
			(size 0.4572 0.4572)
			(layers "F.Cu" "F.Mask" "F.Paste")
			(net "P1V25_SERDES_VDDPLL_PEX1")
		)
		(pad "T30" smd circle
			(at 4.750054 -8.549894)
			(size 0.4572 0.4572)
			(layers "F.Cu" "F.Mask" "F.Paste")
			(net "P1V25_SERDES_VDDPLL_PEX1")
		)
		(pad "T31" smd circle
			(at 5.700014 -8.549894)
			(size 0.4572 0.4572)
			(layers "F.Cu" "F.Mask" "F.Paste")
			(net "P1V25_SERDES_VDDPLL_PEX1")
		)
		(pad "T32" smd circle
			(at 6.649974 -8.549894)
			(size 0.4572 0.4572)
			(layers "F.Cu" "F.Mask" "F.Paste")
			(net "P1V25_SERDES_VDDPLL_PEX1")
		)
		(pad "T33" smd circle
			(at 7.599934 -8.549894)
			(size 0.4572 0.4572)
			(layers "F.Cu" "F.Mask" "F.Paste")
			(net "P1V25_SERDES_VDDPLL_PEX1")
		)
		(pad "T34" smd circle
			(at 8.549894 -8.549894)
			(size 0.4572 0.4572)
			(layers "F.Cu" "F.Mask" "F.Paste")
			(net "GND")
		)
		(pad "T35" smd circle
			(at 9.500108 -8.549894)
			(size 0.4572 0.4572)
			(layers "F.Cu" "F.Mask" "F.Paste")
			(net "P1V8_VDDA_PEX1")
		)
		(pad "T36" smd circle
			(at 10.450068 -8.549894)
			(size 0.4572 0.4572)
			(layers "F.Cu" "F.Mask" "F.Paste")
			(net "Net_496")
		)
		(pad "T37" smd circle
			(at 11.400028 -8.549894)
			(size 0.4572 0.4572)
			(layers "F.Cu" "F.Mask" "F.Paste")
			(net "GND")
		)
		(pad "T38" smd circle
			(at 12.349988 -8.549894)
			(size 0.4572 0.4572)
			(layers "F.Cu" "F.Mask" "F.Paste")
			(net "RST_PEX1_S0_PERST_R_N")
		)
		(pad "T39" smd circle
			(at 13.299948 -8.549894)
			(size 0.4572 0.4572)
			(layers "F.Cu" "F.Mask" "F.Paste")
			(net "Net_391")
		)
		(pad "T40" smd circle
			(at 14.249908 -8.549894)
			(size 0.4572 0.4572)
			(layers "F.Cu" "F.Mask" "F.Paste")
			(net "GND")
		)
		(pad "T41" smd circle
			(at 15.200122 -8.549894)
			(size 0.4572 0.4572)
			(layers "F.Cu" "F.Mask" "F.Paste")
			(net "P5E_PEX1_STN4_TX_DP<64>")
		)
		(pad "T42" smd circle
			(at 16.150082 -8.549894)
			(size 0.4572 0.4572)
			(layers "F.Cu" "F.Mask" "F.Paste")
			(net "P5E_PEX1_STN4_TX_DN<64>")
		)
		(pad "T43" smd circle
			(at 17.100042 -8.549894)
			(size 0.4572 0.4572)
			(layers "F.Cu" "F.Mask" "F.Paste")
			(net "GND")
		)
		(pad "T44" smd circle
			(at 18.050002 -8.549894)
			(size 0.4572 0.4572)
			(layers "F.Cu" "F.Mask" "F.Paste")
			(net "GND")
		)
		(pad "T45" smd circle
			(at 18.999962 -8.549894)
			(size 0.4572 0.4572)
			(layers "F.Cu" "F.Mask" "F.Paste")
			(net "GND")
		)
		(pad "T46" smd circle
			(at 19.949922 -8.549894)
			(size 0.4572 0.4572)
			(layers "F.Cu" "F.Mask" "F.Paste")
			(net "GND")
		)
		(pad "T47" smd circle
			(at 20.899882 -8.549894)
			(size 0.4572 0.4572)
			(layers "F.Cu" "F.Mask" "F.Paste")
			(net "GND")
		)
		(pad "T48" smd circle
			(at 21.850096 -8.549894)
			(size 0.4572 0.4572)
			(layers "F.Cu" "F.Mask" "F.Paste")
			(net "P5E_PEX1_STN4_RX_DP<64>")
		)
		(pad "T49" smd circle
			(at 22.800056 -8.549894)
			(size 0.4572 0.4572)
			(layers "F.Cu" "F.Mask" "F.Paste")
			(net "P5E_PEX1_STN4_RX_DN<64>")
		)
		(pad "U1" smd circle
			(at -22.800056 -7.599934)
			(size 0.4572 0.4572)
			(layers "F.Cu" "F.Mask" "F.Paste")
			(net "GND")
		)
		(pad "U2" smd circle
			(at -21.850096 -7.599934)
			(size 0.4572 0.4572)
			(layers "F.Cu" "F.Mask" "F.Paste")
			(net "GND")
		)
		(pad "U3" smd circle
			(at -20.899882 -7.599934)
			(size 0.4572 0.4572)
			(layers "F.Cu" "F.Mask" "F.Paste")
			(net "P5E_PEX1_STN7_RX_DN<114>")
		)
		(pad "U4" smd circle
			(at -19.949922 -7.599934)
			(size 0.4572 0.4572)
			(layers "F.Cu" "F.Mask" "F.Paste")
			(net "P5E_PEX1_STN7_RX_DP<114>")
		)
		(pad "U5" smd circle
			(at -18.999962 -7.599934)
			(size 0.4572 0.4572)
			(layers "F.Cu" "F.Mask" "F.Paste")
			(net "GND")
		)
		(pad "U6" smd circle
			(at -18.050002 -7.599934)
			(size 0.4572 0.4572)
			(layers "F.Cu" "F.Mask" "F.Paste")
			(net "P5E_PEX1_STN7_TX_DN<114>")
		)
		(pad "U7" smd circle
			(at -17.100042 -7.599934)
			(size 0.4572 0.4572)
			(layers "F.Cu" "F.Mask" "F.Paste")
			(net "P5E_PEX1_STN7_TX_DP<114>")
		)
		(pad "U8" smd circle
			(at -16.150082 -7.599934)
			(size 0.4572 0.4572)
			(layers "F.Cu" "F.Mask" "F.Paste")
			(net "GND")
		)
		(pad "U9" smd circle
			(at -15.200122 -7.599934)
			(size 0.4572 0.4572)
			(layers "F.Cu" "F.Mask" "F.Paste")
			(net "GND")
		)
		(pad "U10" smd circle
			(at -14.249908 -7.599934)
			(size 0.4572 0.4572)
			(layers "F.Cu" "F.Mask" "F.Paste")
			(net "GND")
		)
		(pad "U11" smd circle
			(at -13.299948 -7.599934)
			(size 0.4572 0.4572)
			(layers "F.Cu" "F.Mask" "F.Paste")
			(net "GND")
		)
		(pad "U12" smd circle
			(at -12.349988 -7.599934)
			(size 0.4572 0.4572)
			(layers "F.Cu" "F.Mask" "F.Paste")
			(net "GND")
		)
		(pad "U13" smd circle
			(at -11.400028 -7.599934)
			(size 0.4572 0.4572)
			(layers "F.Cu" "F.Mask" "F.Paste")
			(net "GND")
		)
		(pad "U14" smd circle
			(at -10.450068 -7.599934)
			(size 0.4572 0.4572)
			(layers "F.Cu" "F.Mask" "F.Paste")
			(net "Net_499")
		)
		(pad "U15" smd circle
			(at -9.500108 -7.599934)
			(size 0.4572 0.4572)
			(layers "F.Cu" "F.Mask" "F.Paste")
			(net "GND")
		)
		(pad "U16" smd circle
			(at -8.549894 -7.599934)
			(size 0.4572 0.4572)
			(layers "F.Cu" "F.Mask" "F.Paste")
			(net "GND")
		)
		(pad "U17" smd circle
			(at -7.599934 -7.599934)
			(size 0.4572 0.4572)
			(layers "F.Cu" "F.Mask" "F.Paste")
			(net "GND")
		)
		(pad "U18" smd circle
			(at -6.649974 -7.599934)
			(size 0.4572 0.4572)
			(layers "F.Cu" "F.Mask" "F.Paste")
			(net "GND")
		)
		(pad "U19" smd circle
			(at -5.700014 -7.599934)
			(size 0.4572 0.4572)
			(layers "F.Cu" "F.Mask" "F.Paste")
			(net "GND")
		)
		(pad "U20" smd circle
			(at -4.750054 -7.599934)
			(size 0.4572 0.4572)
			(layers "F.Cu" "F.Mask" "F.Paste")
			(net "GND")
		)
		(pad "U21" smd circle
			(at -3.800094 -7.599934)
			(size 0.4572 0.4572)
			(layers "F.Cu" "F.Mask" "F.Paste")
			(net "GND")
		)
		(pad "U22" smd circle
			(at -2.84988 -7.599934)
			(size 0.4572 0.4572)
			(layers "F.Cu" "F.Mask" "F.Paste")
			(net "GND")
		)
		(pad "U23" smd circle
			(at -1.89992 -7.599934)
			(size 0.4572 0.4572)
			(layers "F.Cu" "F.Mask" "F.Paste")
			(net "GND")
		)
		(pad "U24" smd circle
			(at -0.94996 -7.599934)
			(size 0.4572 0.4572)
			(layers "F.Cu" "F.Mask" "F.Paste")
			(net "GND")
		)
		(pad "U25" smd circle
			(at 0 -7.599934)
			(size 0.4572 0.4572)
			(layers "F.Cu" "F.Mask" "F.Paste")
			(net "GND")
		)
		(pad "U26" smd circle
			(at 0.94996 -7.599934)
			(size 0.4572 0.4572)
			(layers "F.Cu" "F.Mask" "F.Paste")
			(net "GND")
		)
		(pad "U27" smd circle
			(at 1.89992 -7.599934)
			(size 0.4572 0.4572)
			(layers "F.Cu" "F.Mask" "F.Paste")
			(net "GND")
		)
		(pad "U28" smd circle
			(at 2.84988 -7.599934)
			(size 0.4572 0.4572)
			(layers "F.Cu" "F.Mask" "F.Paste")
			(net "GND")
		)
		(pad "U29" smd circle
			(at 3.800094 -7.599934)
			(size 0.4572 0.4572)
			(layers "F.Cu" "F.Mask" "F.Paste")
			(net "GND")
		)
		(pad "U30" smd circle
			(at 4.750054 -7.599934)
			(size 0.4572 0.4572)
			(layers "F.Cu" "F.Mask" "F.Paste")
			(net "GND")
		)
		(pad "U31" smd circle
			(at 5.700014 -7.599934)
			(size 0.4572 0.4572)
			(layers "F.Cu" "F.Mask" "F.Paste")
			(net "GND")
		)
		(pad "U32" smd circle
			(at 6.649974 -7.599934)
			(size 0.4572 0.4572)
			(layers "F.Cu" "F.Mask" "F.Paste")
			(net "GND")
		)
		(pad "U33" smd circle
			(at 7.599934 -7.599934)
			(size 0.4572 0.4572)
			(layers "F.Cu" "F.Mask" "F.Paste")
			(net "GND")
		)
		(pad "U34" smd circle
			(at 8.549894 -7.599934)
			(size 0.4572 0.4572)
			(layers "F.Cu" "F.Mask" "F.Paste")
			(net "GND")
		)
		(pad "U35" smd circle
			(at 9.500108 -7.599934)
			(size 0.4572 0.4572)
			(layers "F.Cu" "F.Mask" "F.Paste")
			(net "GND")
		)
		(pad "U36" smd circle
			(at 10.450068 -7.599934)
			(size 0.4572 0.4572)
			(layers "F.Cu" "F.Mask" "F.Paste")
			(net "Net_508")
		)
		(pad "U37" smd circle
			(at 11.400028 -7.599934)
			(size 0.4572 0.4572)
			(layers "F.Cu" "F.Mask" "F.Paste")
			(net "GND")
		)
		(pad "U38" smd circle
			(at 12.349988 -7.599934)
			(size 0.4572 0.4572)
			(layers "F.Cu" "F.Mask" "F.Paste")
			(net "Net_5231")
		)
		(pad "U39" smd circle
			(at 13.299948 -7.599934)
			(size 0.4572 0.4572)
			(layers "F.Cu" "F.Mask" "F.Paste")
			(net "Net_5225")
		)
		(pad "U40" smd circle
			(at 14.249908 -7.599934)
			(size 0.4572 0.4572)
			(layers "F.Cu" "F.Mask" "F.Paste")
			(net "GND")
		)
		(pad "U41" smd circle
			(at 15.200122 -7.599934)
			(size 0.4572 0.4572)
			(layers "F.Cu" "F.Mask" "F.Paste")
			(net "GND")
		)
		(pad "U42" smd circle
			(at 16.150082 -7.599934)
			(size 0.4572 0.4572)
			(layers "F.Cu" "F.Mask" "F.Paste")
			(net "GND")
		)
		(pad "U43" smd circle
			(at 17.100042 -7.599934)
			(size 0.4572 0.4572)
			(layers "F.Cu" "F.Mask" "F.Paste")
			(net "Net_1436")
		)
		(pad "U44" smd circle
			(at 18.050002 -7.599934)
			(size 0.4572 0.4572)
			(layers "F.Cu" "F.Mask" "F.Paste")
			(net "Net_1427")
		)
		(pad "U45" smd circle
			(at 18.999962 -7.599934)
			(size 0.4572 0.4572)
			(layers "F.Cu" "F.Mask" "F.Paste")
			(net "GND")
		)
		(pad "U46" smd circle
			(at 19.949922 -7.599934)
			(size 0.4572 0.4572)
			(layers "F.Cu" "F.Mask" "F.Paste")
			(net "Net_1606")
		)
		(pad "U47" smd circle
			(at 20.899882 -7.599934)
			(size 0.4572 0.4572)
			(layers "F.Cu" "F.Mask" "F.Paste")
			(net "Net_1599")
		)
		(pad "U48" smd circle
			(at 21.850096 -7.599934)
			(size 0.4572 0.4572)
			(layers "F.Cu" "F.Mask" "F.Paste")
			(net "GND")
		)
		(pad "U49" smd circle
			(at 22.800056 -7.599934)
			(size 0.4572 0.4572)
			(layers "F.Cu" "F.Mask" "F.Paste")
			(net "GND")
		)
		(pad "V1" smd circle
			(at -22.800056 -6.649974)
			(size 0.4572 0.4572)
			(layers "F.Cu" "F.Mask" "F.Paste")
			(net "P5E_PEX1_STN7_RX_DN<113>")
		)
		(pad "V2" smd circle
			(at -21.850096 -6.649974)
			(size 0.4572 0.4572)
			(layers "F.Cu" "F.Mask" "F.Paste")
			(net "P5E_PEX1_STN7_RX_DP<113>")
		)
		(pad "V3" smd circle
			(at -20.899882 -6.649974)
			(size 0.4572 0.4572)
			(layers "F.Cu" "F.Mask" "F.Paste")
			(net "GND")
		)
		(pad "V4" smd circle
			(at -19.949922 -6.649974)
			(size 0.4572 0.4572)
			(layers "F.Cu" "F.Mask" "F.Paste")
			(net "GND")
		)
		(pad "V5" smd circle
			(at -18.999962 -6.649974)
			(size 0.4572 0.4572)
			(layers "F.Cu" "F.Mask" "F.Paste")
			(net "GND")
		)
		(pad "V6" smd circle
			(at -18.050002 -6.649974)
			(size 0.4572 0.4572)
			(layers "F.Cu" "F.Mask" "F.Paste")
			(net "GND")
		)
		(pad "V7" smd circle
			(at -17.100042 -6.649974)
			(size 0.4572 0.4572)
			(layers "F.Cu" "F.Mask" "F.Paste")
			(net "GND")
		)
		(pad "V8" smd circle
			(at -16.150082 -6.649974)
			(size 0.4572 0.4572)
			(layers "F.Cu" "F.Mask" "F.Paste")
			(net "P5E_PEX1_STN7_TX_DN<113>")
		)
		(pad "V9" smd circle
			(at -15.200122 -6.649974)
			(size 0.4572 0.4572)
			(layers "F.Cu" "F.Mask" "F.Paste")
			(net "P5E_PEX1_STN7_TX_DP<113>")
		)
		(pad "V10" smd circle
			(at -14.249908 -6.649974)
			(size 0.4572 0.4572)
			(layers "F.Cu" "F.Mask" "F.Paste")
			(net "GND")
		)
		(pad "V11" smd circle
			(at -13.299948 -6.649974)
			(size 0.4572 0.4572)
			(layers "F.Cu" "F.Mask" "F.Paste")
			(net "GND")
		)
		(pad "V12" smd circle
			(at -12.349988 -6.649974)
			(size 0.4572 0.4572)
			(layers "F.Cu" "F.Mask" "F.Paste")
			(net "GND")
		)
		(pad "V13" smd circle
			(at -11.400028 -6.649974)
			(size 0.4572 0.4572)
			(layers "F.Cu" "F.Mask" "F.Paste")
			(net "GND")
		)
		(pad "V14" smd circle
			(at -10.450068 -6.649974)
			(size 0.4572 0.4572)
			(layers "F.Cu" "F.Mask" "F.Paste")
			(net "P1V8_VDDA_PEX1")
		)
		(pad "V15" smd circle
			(at -9.500108 -6.649974)
			(size 0.4572 0.4572)
			(layers "F.Cu" "F.Mask" "F.Paste")
			(net "GND")
		)
		(pad "V16" smd circle
			(at -8.549894 -6.649974)
			(size 0.4572 0.4572)
			(layers "F.Cu" "F.Mask" "F.Paste")
			(net "P1V25_PEX1")
		)
		(pad "V17" smd circle
			(at -7.599934 -6.649974)
			(size 0.4572 0.4572)
			(layers "F.Cu" "F.Mask" "F.Paste")
			(net "P1V25_PEX1")
		)
		(pad "V18" smd circle
			(at -6.649974 -6.649974)
			(size 0.4572 0.4572)
			(layers "F.Cu" "F.Mask" "F.Paste")
			(net "P1V25_PEX1")
		)
		(pad "V19" smd circle
			(at -5.700014 -6.649974)
			(size 0.4572 0.4572)
			(layers "F.Cu" "F.Mask" "F.Paste")
			(net "P1V25_PEX1")
		)
		(pad "V20" smd circle
			(at -4.750054 -6.649974)
			(size 0.4572 0.4572)
			(layers "F.Cu" "F.Mask" "F.Paste")
			(net "P1V25_PEX1")
		)
		(pad "V21" smd circle
			(at -3.800094 -6.649974)
			(size 0.4572 0.4572)
			(layers "F.Cu" "F.Mask" "F.Paste")
			(net "P1V25_PEX1")
		)
		(pad "V22" smd circle
			(at -2.84988 -6.649974)
			(size 0.4572 0.4572)
			(layers "F.Cu" "F.Mask" "F.Paste")
			(net "P1V25_PEX1")
		)
		(pad "V23" smd circle
			(at -1.89992 -6.649974)
			(size 0.4572 0.4572)
			(layers "F.Cu" "F.Mask" "F.Paste")
			(net "P1V25_PEX1")
		)
		(pad "V24" smd circle
			(at -0.94996 -6.649974)
			(size 0.4572 0.4572)
			(layers "F.Cu" "F.Mask" "F.Paste")
			(net "P1V25_PEX1")
		)
		(pad "V25" smd circle
			(at 0 -6.649974)
			(size 0.4572 0.4572)
			(layers "F.Cu" "F.Mask" "F.Paste")
			(net "P1V25_PEX1")
		)
		(pad "V26" smd circle
			(at 0.94996 -6.649974)
			(size 0.4572 0.4572)
			(layers "F.Cu" "F.Mask" "F.Paste")
			(net "P1V25_PEX1")
		)
		(pad "V27" smd circle
			(at 1.89992 -6.649974)
			(size 0.4572 0.4572)
			(layers "F.Cu" "F.Mask" "F.Paste")
			(net "P1V25_PEX1")
		)
		(pad "V28" smd circle
			(at 2.84988 -6.649974)
			(size 0.4572 0.4572)
			(layers "F.Cu" "F.Mask" "F.Paste")
			(net "P1V25_PEX1")
		)
		(pad "V29" smd circle
			(at 3.800094 -6.649974)
			(size 0.4572 0.4572)
			(layers "F.Cu" "F.Mask" "F.Paste")
			(net "P1V25_PEX1")
		)
		(pad "V30" smd circle
			(at 4.750054 -6.649974)
			(size 0.4572 0.4572)
			(layers "F.Cu" "F.Mask" "F.Paste")
			(net "P1V25_PEX1")
		)
		(pad "V31" smd circle
			(at 5.700014 -6.649974)
			(size 0.4572 0.4572)
			(layers "F.Cu" "F.Mask" "F.Paste")
			(net "P1V25_PEX1")
		)
		(pad "V32" smd circle
			(at 6.649974 -6.649974)
			(size 0.4572 0.4572)
			(layers "F.Cu" "F.Mask" "F.Paste")
			(net "P1V25_PEX1")
		)
		(pad "V33" smd circle
			(at 7.599934 -6.649974)
			(size 0.4572 0.4572)
			(layers "F.Cu" "F.Mask" "F.Paste")
			(net "P1V25_PEX1")
		)
		(pad "V34" smd circle
			(at 8.549894 -6.649974)
			(size 0.4572 0.4572)
			(layers "F.Cu" "F.Mask" "F.Paste")
			(net "GND")
		)
		(pad "V35" smd circle
			(at 9.500108 -6.649974)
			(size 0.4572 0.4572)
			(layers "F.Cu" "F.Mask" "F.Paste")
			(net "P1V8_PEX")
		)
		(pad "V36" smd circle
			(at 10.450068 -6.649974)
			(size 0.4572 0.4572)
			(layers "F.Cu" "F.Mask" "F.Paste")
			(net "GND")
		)
		(pad "V37" smd circle
			(at 11.400028 -6.649974)
			(size 0.4572 0.4572)
			(layers "F.Cu" "F.Mask" "F.Paste")
			(net "GND")
		)
		(pad "V38" smd circle
			(at 12.349988 -6.649974)
			(size 0.4572 0.4572)
			(layers "F.Cu" "F.Mask" "F.Paste")
			(net "GND")
		)
		(pad "V39" smd circle
			(at 13.299948 -6.649974)
			(size 0.4572 0.4572)
			(layers "F.Cu" "F.Mask" "F.Paste")
			(net "VSENSE_P0V8_PEX1_SKT_VSEN")
		)
		(pad "V40" smd circle
			(at 14.249908 -6.649974)
			(size 0.4572 0.4572)
			(layers "F.Cu" "F.Mask" "F.Paste")
			(net "GND")
		)
		(pad "V41" smd circle
			(at 15.200122 -6.649974)
			(size 0.4572 0.4572)
			(layers "F.Cu" "F.Mask" "F.Paste")
			(net "Net_1362")
		)
		(pad "V42" smd circle
			(at 16.150082 -6.649974)
			(size 0.4572 0.4572)
			(layers "F.Cu" "F.Mask" "F.Paste")
			(net "Net_1394")
		)
		(pad "V43" smd circle
			(at 17.100042 -6.649974)
			(size 0.4572 0.4572)
			(layers "F.Cu" "F.Mask" "F.Paste")
			(net "GND")
		)
		(pad "V44" smd circle
			(at 18.050002 -6.649974)
			(size 0.4572 0.4572)
			(layers "F.Cu" "F.Mask" "F.Paste")
			(net "GND")
		)
		(pad "V45" smd circle
			(at 18.999962 -6.649974)
			(size 0.4572 0.4572)
			(layers "F.Cu" "F.Mask" "F.Paste")
			(net "GND")
		)
		(pad "V46" smd circle
			(at 19.949922 -6.649974)
			(size 0.4572 0.4572)
			(layers "F.Cu" "F.Mask" "F.Paste")
			(net "GND")
		)
		(pad "V47" smd circle
			(at 20.899882 -6.649974)
			(size 0.4572 0.4572)
			(layers "F.Cu" "F.Mask" "F.Paste")
			(net "GND")
		)
		(pad "V48" smd circle
			(at 21.850096 -6.649974)
			(size 0.4572 0.4572)
			(layers "F.Cu" "F.Mask" "F.Paste")
			(net "Net_1621")
		)
		(pad "V49" smd circle
			(at 22.800056 -6.649974)
			(size 0.4572 0.4572)
			(layers "F.Cu" "F.Mask" "F.Paste")
			(net "Net_1634")
		)
		(pad "W1" smd circle
			(at -22.800056 -5.700014)
			(size 0.4572 0.4572)
			(layers "F.Cu" "F.Mask" "F.Paste")
			(net "GND")
		)
		(pad "W2" smd circle
			(at -21.850096 -5.700014)
			(size 0.4572 0.4572)
			(layers "F.Cu" "F.Mask" "F.Paste")
			(net "GND")
		)
		(pad "W3" smd circle
			(at -20.899882 -5.700014)
			(size 0.4572 0.4572)
			(layers "F.Cu" "F.Mask" "F.Paste")
			(net "P5E_PEX1_STN7_RX_DN<112>")
		)
		(pad "W4" smd circle
			(at -19.949922 -5.700014)
			(size 0.4572 0.4572)
			(layers "F.Cu" "F.Mask" "F.Paste")
			(net "P5E_PEX1_STN7_RX_DP<112>")
		)
		(pad "W5" smd circle
			(at -18.999962 -5.700014)
			(size 0.4572 0.4572)
			(layers "F.Cu" "F.Mask" "F.Paste")
			(net "GND")
		)
		(pad "W6" smd circle
			(at -18.050002 -5.700014)
			(size 0.4572 0.4572)
			(layers "F.Cu" "F.Mask" "F.Paste")
			(net "P5E_PEX1_STN7_TX_DN<112>")
		)
		(pad "W7" smd circle
			(at -17.100042 -5.700014)
			(size 0.4572 0.4572)
			(layers "F.Cu" "F.Mask" "F.Paste")
			(net "P5E_PEX1_STN7_TX_DP<112>")
		)
		(pad "W8" smd circle
			(at -16.150082 -5.700014)
			(size 0.4572 0.4572)
			(layers "F.Cu" "F.Mask" "F.Paste")
			(net "GND")
		)
		(pad "W9" smd circle
			(at -15.200122 -5.700014)
			(size 0.4572 0.4572)
			(layers "F.Cu" "F.Mask" "F.Paste")
			(net "GND")
		)
		(pad "W10" smd circle
			(at -14.249908 -5.700014)
			(size 0.4572 0.4572)
			(layers "F.Cu" "F.Mask" "F.Paste")
			(net "GND")
		)
		(pad "W11" smd circle
			(at -13.299948 -5.700014)
			(size 0.4572 0.4572)
			(layers "F.Cu" "F.Mask" "F.Paste")
			(net "GND")
		)
		(pad "W12" smd circle
			(at -12.349988 -5.700014)
			(size 0.4572 0.4572)
			(layers "F.Cu" "F.Mask" "F.Paste")
			(net "GND")
		)
		(pad "W13" smd circle
			(at -11.400028 -5.700014)
			(size 0.4572 0.4572)
			(layers "F.Cu" "F.Mask" "F.Paste")
			(net "GND")
		)
		(pad "W14" smd circle
			(at -10.450068 -5.700014)
			(size 0.4572 0.4572)
			(layers "F.Cu" "F.Mask" "F.Paste")
			(net "GND")
		)
		(pad "W15" smd circle
			(at -9.500108 -5.700014)
			(size 0.4572 0.4572)
			(layers "F.Cu" "F.Mask" "F.Paste")
			(net "GND")
		)
		(pad "W16" smd circle
			(at -8.549894 -5.700014)
			(size 0.4572 0.4572)
			(layers "F.Cu" "F.Mask" "F.Paste")
			(net "GND")
		)
		(pad "W17" smd circle
			(at -7.599934 -5.700014)
			(size 0.4572 0.4572)
			(layers "F.Cu" "F.Mask" "F.Paste")
			(net "GND")
		)
		(pad "W18" smd circle
			(at -6.649974 -5.700014)
			(size 0.4572 0.4572)
			(layers "F.Cu" "F.Mask" "F.Paste")
			(net "GND")
		)
		(pad "W19" smd circle
			(at -5.700014 -5.700014)
			(size 0.4572 0.4572)
			(layers "F.Cu" "F.Mask" "F.Paste")
			(net "GND")
		)
		(pad "W20" smd circle
			(at -4.750054 -5.700014)
			(size 0.4572 0.4572)
			(layers "F.Cu" "F.Mask" "F.Paste")
			(net "GND")
		)
		(pad "W21" smd circle
			(at -3.800094 -5.700014)
			(size 0.4572 0.4572)
			(layers "F.Cu" "F.Mask" "F.Paste")
			(net "GND")
		)
		(pad "W22" smd circle
			(at -2.84988 -5.700014)
			(size 0.4572 0.4572)
			(layers "F.Cu" "F.Mask" "F.Paste")
			(net "GND")
		)
		(pad "W23" smd circle
			(at -1.89992 -5.700014)
			(size 0.4572 0.4572)
			(layers "F.Cu" "F.Mask" "F.Paste")
			(net "GND")
		)
		(pad "W24" smd circle
			(at -0.94996 -5.700014)
			(size 0.4572 0.4572)
			(layers "F.Cu" "F.Mask" "F.Paste")
			(net "GND")
		)
		(pad "W25" smd circle
			(at 0 -5.700014)
			(size 0.4572 0.4572)
			(layers "F.Cu" "F.Mask" "F.Paste")
			(net "GND")
		)
		(pad "W26" smd circle
			(at 0.94996 -5.700014)
			(size 0.4572 0.4572)
			(layers "F.Cu" "F.Mask" "F.Paste")
			(net "GND")
		)
		(pad "W27" smd circle
			(at 1.89992 -5.700014)
			(size 0.4572 0.4572)
			(layers "F.Cu" "F.Mask" "F.Paste")
			(net "GND")
		)
		(pad "W28" smd circle
			(at 2.84988 -5.700014)
			(size 0.4572 0.4572)
			(layers "F.Cu" "F.Mask" "F.Paste")
			(net "GND")
		)
		(pad "W29" smd circle
			(at 3.800094 -5.700014)
			(size 0.4572 0.4572)
			(layers "F.Cu" "F.Mask" "F.Paste")
			(net "GND")
		)
		(pad "W30" smd circle
			(at 4.750054 -5.700014)
			(size 0.4572 0.4572)
			(layers "F.Cu" "F.Mask" "F.Paste")
			(net "GND")
		)
		(pad "W31" smd circle
			(at 5.700014 -5.700014)
			(size 0.4572 0.4572)
			(layers "F.Cu" "F.Mask" "F.Paste")
			(net "GND")
		)
		(pad "W32" smd circle
			(at 6.649974 -5.700014)
			(size 0.4572 0.4572)
			(layers "F.Cu" "F.Mask" "F.Paste")
			(net "GND")
		)
		(pad "W33" smd circle
			(at 7.599934 -5.700014)
			(size 0.4572 0.4572)
			(layers "F.Cu" "F.Mask" "F.Paste")
			(net "GND")
		)
		(pad "W34" smd circle
			(at 8.549894 -5.700014)
			(size 0.4572 0.4572)
			(layers "F.Cu" "F.Mask" "F.Paste")
			(net "GND")
		)
		(pad "W35" smd circle
			(at 9.500108 -5.700014)
			(size 0.4572 0.4572)
			(layers "F.Cu" "F.Mask" "F.Paste")
			(net "P1V8_PEX")
		)
		(pad "W36" smd circle
			(at 10.450068 -5.700014)
			(size 0.4572 0.4572)
			(layers "F.Cu" "F.Mask" "F.Paste")
			(net "GND")
		)
		(pad "W37" smd circle
			(at 11.400028 -5.700014)
			(size 0.4572 0.4572)
			(layers "F.Cu" "F.Mask" "F.Paste")
			(net "GND")
		)
		(pad "W38" smd circle
			(at 12.349988 -5.700014)
			(size 0.4572 0.4572)
			(layers "F.Cu" "F.Mask" "F.Paste")
			(net "GND")
		)
		(pad "W39" smd circle
			(at 13.299948 -5.700014)
			(size 0.4572 0.4572)
			(layers "F.Cu" "F.Mask" "F.Paste")
			(net "VSENSE_P0V8_PEX1_SKT_VRTN")
		)
		(pad "W40" smd circle
			(at 14.249908 -5.700014)
			(size 0.4572 0.4572)
			(layers "F.Cu" "F.Mask" "F.Paste")
			(net "GND")
		)
		(pad "W41" smd circle
			(at 15.200122 -5.700014)
			(size 0.4572 0.4572)
			(layers "F.Cu" "F.Mask" "F.Paste")
			(net "GND")
		)
		(pad "W42" smd circle
			(at 16.150082 -5.700014)
			(size 0.4572 0.4572)
			(layers "F.Cu" "F.Mask" "F.Paste")
			(net "GND")
		)
		(pad "W43" smd circle
			(at 17.100042 -5.700014)
			(size 0.4572 0.4572)
			(layers "F.Cu" "F.Mask" "F.Paste")
			(net "Net_1407")
		)
		(pad "W44" smd circle
			(at 18.050002 -5.700014)
			(size 0.4572 0.4572)
			(layers "F.Cu" "F.Mask" "F.Paste")
			(net "Net_1366")
		)
		(pad "W45" smd circle
			(at 18.999962 -5.700014)
			(size 0.4572 0.4572)
			(layers "F.Cu" "F.Mask" "F.Paste")
			(net "GND")
		)
		(pad "W46" smd circle
			(at 19.949922 -5.700014)
			(size 0.4572 0.4572)
			(layers "F.Cu" "F.Mask" "F.Paste")
			(net "Net_1631")
		)
		(pad "W47" smd circle
			(at 20.899882 -5.700014)
			(size 0.4572 0.4572)
			(layers "F.Cu" "F.Mask" "F.Paste")
			(net "Net_1618")
		)
		(pad "W48" smd circle
			(at 21.850096 -5.700014)
			(size 0.4572 0.4572)
			(layers "F.Cu" "F.Mask" "F.Paste")
			(net "GND")
		)
		(pad "W49" smd circle
			(at 22.800056 -5.700014)
			(size 0.4572 0.4572)
			(layers "F.Cu" "F.Mask" "F.Paste")
			(net "GND")
		)
		(pad "Y1" smd circle
			(at -22.800056 -4.750054)
			(size 0.4572 0.4572)
			(layers "F.Cu" "F.Mask" "F.Paste")
			(net "GND")
		)
		(pad "Y2" smd circle
			(at -21.850096 -4.750054)
			(size 0.4572 0.4572)
			(layers "F.Cu" "F.Mask" "F.Paste")
			(net "GND")
		)
		(pad "Y3" smd circle
			(at -20.899882 -4.750054)
			(size 0.4572 0.4572)
			(layers "F.Cu" "F.Mask" "F.Paste")
			(net "GND")
		)
		(pad "Y4" smd circle
			(at -19.949922 -4.750054)
			(size 0.4572 0.4572)
			(layers "F.Cu" "F.Mask" "F.Paste")
			(net "GND")
		)
		(pad "Y5" smd circle
			(at -18.999962 -4.750054)
			(size 0.4572 0.4572)
			(layers "F.Cu" "F.Mask" "F.Paste")
			(net "GND")
		)
		(pad "Y6" smd circle
			(at -18.050002 -4.750054)
			(size 0.4572 0.4572)
			(layers "F.Cu" "F.Mask" "F.Paste")
			(net "GND")
		)
		(pad "Y7" smd circle
			(at -17.100042 -4.750054)
			(size 0.4572 0.4572)
			(layers "F.Cu" "F.Mask" "F.Paste")
			(net "GND")
		)
		(pad "Y8" smd circle
			(at -16.150082 -4.750054)
			(size 0.4572 0.4572)
			(layers "F.Cu" "F.Mask" "F.Paste")
			(net "GND")
		)
		(pad "Y9" smd circle
			(at -15.200122 -4.750054)
			(size 0.4572 0.4572)
			(layers "F.Cu" "F.Mask" "F.Paste")
			(net "GND")
		)
		(pad "Y10" smd circle
			(at -14.249908 -4.750054)
			(size 0.4572 0.4572)
			(layers "F.Cu" "F.Mask" "F.Paste")
			(net "GND")
		)
		(pad "Y11" smd circle
			(at -13.299948 -4.750054)
			(size 0.4572 0.4572)
			(layers "F.Cu" "F.Mask" "F.Paste")
			(net "GND")
		)
		(pad "Y12" smd circle
			(at -12.349988 -4.750054)
			(size 0.4572 0.4572)
			(layers "F.Cu" "F.Mask" "F.Paste")
			(net "P1V8_PEX")
		)
		(pad "Y13" smd circle
			(at -11.400028 -4.750054)
			(size 0.4572 0.4572)
			(layers "F.Cu" "F.Mask" "F.Paste")
			(net "GND")
		)
		(pad "Y14" smd circle
			(at -10.450068 -4.750054)
			(size 0.4572 0.4572)
			(layers "F.Cu" "F.Mask" "F.Paste")
			(net "P0V8_PEX1")
		)
		(pad "Y15" smd circle
			(at -9.500108 -4.750054)
			(size 0.4572 0.4572)
			(layers "F.Cu" "F.Mask" "F.Paste")
			(net "GND")
		)
		(pad "Y16" smd circle
			(at -8.549894 -4.750054)
			(size 0.4572 0.4572)
			(layers "F.Cu" "F.Mask" "F.Paste")
			(net "P0V8_SERDES_VDDA_PEX1")
		)
		(pad "Y17" smd circle
			(at -7.599934 -4.750054)
			(size 0.4572 0.4572)
			(layers "F.Cu" "F.Mask" "F.Paste")
			(net "P0V8_SERDES_VDDA_PEX1")
		)
		(pad "Y18" smd circle
			(at -6.649974 -4.750054)
			(size 0.4572 0.4572)
			(layers "F.Cu" "F.Mask" "F.Paste")
			(net "P0V8_SERDES_VDDA_PEX1")
		)
		(pad "Y19" smd circle
			(at -5.700014 -4.750054)
			(size 0.4572 0.4572)
			(layers "F.Cu" "F.Mask" "F.Paste")
			(net "P0V8_SERDES_VDDA_PEX1")
		)
		(pad "Y20" smd circle
			(at -4.750054 -4.750054)
			(size 0.4572 0.4572)
			(layers "F.Cu" "F.Mask" "F.Paste")
			(net "P0V8_SERDES_VDDA_PEX1")
		)
		(pad "Y21" smd circle
			(at -3.800094 -4.750054)
			(size 0.4572 0.4572)
			(layers "F.Cu" "F.Mask" "F.Paste")
			(net "P0V8_SERDES_VDDA_PEX1")
		)
		(pad "Y22" smd circle
			(at -2.84988 -4.750054)
			(size 0.4572 0.4572)
			(layers "F.Cu" "F.Mask" "F.Paste")
			(net "P0V8_SERDES_VDDA_PEX1")
		)
		(pad "Y23" smd circle
			(at -1.89992 -4.750054)
			(size 0.4572 0.4572)
			(layers "F.Cu" "F.Mask" "F.Paste")
			(net "P0V8_SERDES_VDDA_PEX1")
		)
		(pad "Y24" smd circle
			(at -0.94996 -4.750054)
			(size 0.4572 0.4572)
			(layers "F.Cu" "F.Mask" "F.Paste")
			(net "P0V8_SERDES_VDDA_PEX1")
		)
		(pad "Y25" smd circle
			(at 0 -4.750054)
			(size 0.4572 0.4572)
			(layers "F.Cu" "F.Mask" "F.Paste")
			(net "P0V8_SERDES_VDDA_PEX1")
		)
		(pad "Y26" smd circle
			(at 0.94996 -4.750054)
			(size 0.4572 0.4572)
			(layers "F.Cu" "F.Mask" "F.Paste")
			(net "P0V8_SERDES_VDDA_PEX1")
		)
		(pad "Y27" smd circle
			(at 1.89992 -4.750054)
			(size 0.4572 0.4572)
			(layers "F.Cu" "F.Mask" "F.Paste")
			(net "P0V8_SERDES_VDDA_PEX1")
		)
		(pad "Y28" smd circle
			(at 2.84988 -4.750054)
			(size 0.4572 0.4572)
			(layers "F.Cu" "F.Mask" "F.Paste")
			(net "P0V8_SERDES_VDDA_PEX1")
		)
		(pad "Y29" smd circle
			(at 3.800094 -4.750054)
			(size 0.4572 0.4572)
			(layers "F.Cu" "F.Mask" "F.Paste")
			(net "P0V8_SERDES_VDDA_PEX1")
		)
		(pad "Y30" smd circle
			(at 4.750054 -4.750054)
			(size 0.4572 0.4572)
			(layers "F.Cu" "F.Mask" "F.Paste")
			(net "P0V8_SERDES_VDDA_PEX1")
		)
		(pad "Y31" smd circle
			(at 5.700014 -4.750054)
			(size 0.4572 0.4572)
			(layers "F.Cu" "F.Mask" "F.Paste")
			(net "P0V8_SERDES_VDDA_PEX1")
		)
		(pad "Y32" smd circle
			(at 6.649974 -4.750054)
			(size 0.4572 0.4572)
			(layers "F.Cu" "F.Mask" "F.Paste")
			(net "P0V8_SERDES_VDDA_PEX1")
		)
		(pad "Y33" smd circle
			(at 7.599934 -4.750054)
			(size 0.4572 0.4572)
			(layers "F.Cu" "F.Mask" "F.Paste")
			(net "P0V8_SERDES_VDDA_PEX1")
		)
		(pad "Y34" smd circle
			(at 8.549894 -4.750054)
			(size 0.4572 0.4572)
			(layers "F.Cu" "F.Mask" "F.Paste")
			(net "GND")
		)
		(pad "Y35" smd circle
			(at 9.500108 -4.750054)
			(size 0.4572 0.4572)
			(layers "F.Cu" "F.Mask" "F.Paste")
			(net "P1V8_PEX")
		)
		(pad "Y36" smd circle
			(at 10.450068 -4.750054)
			(size 0.4572 0.4572)
			(layers "F.Cu" "F.Mask" "F.Paste")
			(net "GND")
		)
		(pad "Y37" smd circle
			(at 11.400028 -4.750054)
			(size 0.4572 0.4572)
			(layers "F.Cu" "F.Mask" "F.Paste")
			(net "GND")
		)
		(pad "Y38" smd circle
			(at 12.349988 -4.750054)
			(size 0.4572 0.4572)
			(layers "F.Cu" "F.Mask" "F.Paste")
			(net "GND")
		)
		(pad "Y39" smd circle
			(at 13.299948 -4.750054)
			(size 0.4572 0.4572)
			(layers "F.Cu" "F.Mask" "F.Paste")
			(net "PEX1_ADCTEMP_VINP0")
		)
		(pad "Y40" smd circle
			(at 14.249908 -4.750054)
			(size 0.4572 0.4572)
			(layers "F.Cu" "F.Mask" "F.Paste")
			(net "GND")
		)
		(pad "Y41" smd circle
			(at 15.200122 -4.750054)
			(size 0.4572 0.4572)
			(layers "F.Cu" "F.Mask" "F.Paste")
			(net "Net_1356")
		)
		(pad "Y42" smd circle
			(at 16.150082 -4.750054)
			(size 0.4572 0.4572)
			(layers "F.Cu" "F.Mask" "F.Paste")
			(net "Net_1410")
		)
		(pad "Y43" smd circle
			(at 17.100042 -4.750054)
			(size 0.4572 0.4572)
			(layers "F.Cu" "F.Mask" "F.Paste")
			(net "GND")
		)
		(pad "Y44" smd circle
			(at 18.050002 -4.750054)
			(size 0.4572 0.4572)
			(layers "F.Cu" "F.Mask" "F.Paste")
			(net "GND")
		)
		(pad "Y45" smd circle
			(at 18.999962 -4.750054)
			(size 0.4572 0.4572)
			(layers "F.Cu" "F.Mask" "F.Paste")
			(net "GND")
		)
		(pad "Y46" smd circle
			(at 19.949922 -4.750054)
			(size 0.4572 0.4572)
			(layers "F.Cu" "F.Mask" "F.Paste")
			(net "GND")
		)
		(pad "Y47" smd circle
			(at 20.899882 -4.750054)
			(size 0.4572 0.4572)
			(layers "F.Cu" "F.Mask" "F.Paste")
			(net "GND")
		)
		(pad "Y48" smd circle
			(at 21.850096 -4.750054)
			(size 0.4572 0.4572)
			(layers "F.Cu" "F.Mask" "F.Paste")
			(net "Net_1524")
		)
		(pad "Y49" smd circle
			(at 22.800056 -4.750054)
			(size 0.4572 0.4572)
			(layers "F.Cu" "F.Mask" "F.Paste")
			(net "Net_1546")
		)
		(zone
			(layer "F.Cu")
			(hatch none 0.5)
			(connect_pads
				(clearance 0)
			)
			(min_thickness 0.25)
			(keepout
				(tracks allowed)
				(vias not_allowed)
				(pads allowed)
				(copperpour not_allowed)
				(footprints allowed)
			)
			(placement
				(enabled no)
				(sheetname "")
			)
			(fill
				(thermal_gap 0.5)
				(thermal_bridge_width 0.5)
				(island_removal_mode 0)
			)
			(polygon
				(pts
					(xy 176.029366 -319.741296) (xy 176.420526 -319.741296) (xy 176.420526 -295.62044) (xy 199.591422 -295.62044)
					(xy 199.591422 -295.22928) (xy 176.420526 -295.22928) (xy 176.420526 -272.058384) (xy 176.029366 -272.058384)
					(xy 176.029366 -295.22928) (xy 151.90851 -295.22928) (xy 151.90851 -295.62044) (xy 176.029366 -295.62044)
				)
			)
		)
	)
	(footprint ""
		(layer "F.Cu")
		(at 248.559574 -146.642328 -90)
		(property "Reference" "C916"
			(at 0 0 270)
			(layer "F.SilkS")
			(hide yes)
			(effects
				(font
					(size 1.27 1.27)
				)
			)
		)
		(property "Value" ""
			(at 0 0 270)
			(layer "F.Fab")
			(effects
				(font
					(size 1.27 1.27)
				)
			)
		)
		(duplicate_pad_numbers_are_jumpers no)
		(fp_line
			(start -0.7874 0.4064)
			(end -0.7874 -0.4064)
			(stroke
				(width 0.1524)
				(type default)
			)
			(layer "F.SilkS")
		)
		(fp_line
			(start 0.7874 0.4064)
			(end -0.7874 0.4064)
			(stroke
				(width 0.1524)
				(type default)
			)
			(layer "F.SilkS")
		)
		(fp_line
			(start -0.7874 -0.4064)
			(end 0.7874 -0.4064)
			(stroke
				(width 0.1524)
				(type default)
			)
			(layer "F.SilkS")
		)
		(fp_line
			(start 0.7874 -0.4064)
			(end 0.7874 0.4064)
			(stroke
				(width 0.1524)
				(type default)
			)
			(layer "F.SilkS")
		)
		(fp_line
			(start -0.67945 0.3048)
			(end -0.67945 -0.305054)
			(stroke
				(width 0.1)
				(type default)
			)
			(layer "F.Fab")
		)
		(fp_line
			(start -0.12065 0.3048)
			(end -0.67945 0.3048)
			(stroke
				(width 0.1)
				(type default)
			)
			(layer "F.Fab")
		)
		(fp_line
			(start 0.120396 0.3048)
			(end 0.120396 0.2794)
			(stroke
				(width 0.1)
				(type default)
			)
			(layer "F.Fab")
		)
		(fp_line
			(start 0.67945 0.3048)
			(end 0.120396 0.3048)
			(stroke
				(width 0.1)
				(type default)
			)
			(layer "F.Fab")
		)
		(fp_line
			(start -0.12065 0.2794)
			(end -0.12065 0.3048)
			(stroke
				(width 0.1)
				(type default)
			)
			(layer "F.Fab")
		)
		(fp_line
			(start 0.120396 0.2794)
			(end -0.12065 0.2794)
			(stroke
				(width 0.1)
				(type default)
			)
			(layer "F.Fab")
		)
		(fp_line
			(start -0.12065 -0.2794)
			(end 0.12065 -0.2794)
			(stroke
				(width 0.1)
				(type default)
			)
			(layer "F.Fab")
		)
		(fp_line
			(start 0.12065 -0.2794)
			(end 0.12065 -0.3048)
			(stroke
				(width 0.1)
				(type default)
			)
			(layer "F.Fab")
		)
		(fp_line
			(start 0.12065 -0.3048)
			(end 0.67945 -0.3048)
			(stroke
				(width 0.1)
				(type default)
			)
			(layer "F.Fab")
		)
		(fp_line
			(start 0.67945 -0.3048)
			(end 0.67945 0.3048)
			(stroke
				(width 0.1)
				(type default)
			)
			(layer "F.Fab")
		)
		(fp_line
			(start -0.67945 -0.305054)
			(end -0.12065 -0.305054)
			(stroke
				(width 0.1)
				(type default)
			)
			(layer "F.Fab")
		)
		(fp_line
			(start -0.12065 -0.305054)
			(end -0.12065 -0.2794)
			(stroke
				(width 0.1)
				(type default)
			)
			(layer "F.Fab")
		)
		(pad "1" smd circle
			(at -0.40005 0 270)
			(size 0 0)
			(layers "F.Cu" "F.Mask" "F.Paste")
			(net "P3V3_AUX")
		)
		(pad "2" smd circle
			(at 0.40005 0 270)
			(size 0 0)
			(layers "F.Cu" "F.Mask" "F.Paste")
			(net "GND")
		)
	)
	(footprint ""
		(layer "F.Cu")
		(at 56.339486 -155.822904 90)
		(property "Reference" "R45"
			(at 0 0 90)
			(layer "F.SilkS")
			(hide yes)
			(effects
				(font
					(size 1.27 1.27)
				)
			)
		)
		(property "Value" ""
			(at 0 0 90)
			(layer "F.Fab")
			(effects
				(font
					(size 1.27 1.27)
				)
			)
		)
		(duplicate_pad_numbers_are_jumpers no)
		(fp_line
			(start 0.7874 -0.4064)
			(end 0.7874 0.4064)
			(stroke
				(width 0.1524)
				(type default)
			)
			(layer "F.SilkS")
		)
		(fp_line
			(start -0.7874 -0.4064)
			(end 0.7874 -0.4064)
			(stroke
				(width 0.1524)
				(type default)
			)
			(layer "F.SilkS")
		)
		(fp_line
			(start 0.7874 0.4064)
			(end -0.7874 0.4064)
			(stroke
				(width 0.1524)
				(type default)
			)
			(layer "F.SilkS")
		)
		(fp_line
			(start -0.7874 0.4064)
			(end -0.7874 -0.4064)
			(stroke
				(width 0.1524)
				(type default)
			)
			(layer "F.SilkS")
		)
		(fp_line
			(start -0.12065 -0.305054)
			(end -0.12065 -0.2794)
			(stroke
				(width 0.1)
				(type default)
			)
			(layer "F.Fab")
		)
		(fp_line
			(start -0.67945 -0.305054)
			(end -0.12065 -0.305054)
			(stroke
				(width 0.1)
				(type default)
			)
			(layer "F.Fab")
		)
		(fp_line
			(start 0.67945 -0.3048)
			(end 0.67945 0.3048)
			(stroke
				(width 0.1)
				(type default)
			)
			(layer "F.Fab")
		)
		(fp_line
			(start 0.12065 -0.3048)
			(end 0.67945 -0.3048)
			(stroke
				(width 0.1)
				(type default)
			)
			(layer "F.Fab")
		)
		(fp_line
			(start 0.12065 -0.2794)
			(end 0.12065 -0.3048)
			(stroke
				(width 0.1)
				(type default)
			)
			(layer "F.Fab")
		)
		(fp_line
			(start -0.12065 -0.2794)
			(end 0.12065 -0.2794)
			(stroke
				(width 0.1)
				(type default)
			)
			(layer "F.Fab")
		)
		(fp_line
			(start 0.120396 0.2794)
			(end -0.12065 0.2794)
			(stroke
				(width 0.1)
				(type default)
			)
			(layer "F.Fab")
		)
		(fp_line
			(start -0.12065 0.2794)
			(end -0.12065 0.3048)
			(stroke
				(width 0.1)
				(type default)
			)
			(layer "F.Fab")
		)
		(fp_line
			(start 0.67945 0.3048)
			(end 0.120396 0.3048)
			(stroke
				(width 0.1)
				(type default)
			)
			(layer "F.Fab")
		)
		(fp_line
			(start 0.120396 0.3048)
			(end 0.120396 0.2794)
			(stroke
				(width 0.1)
				(type default)
			)
			(layer "F.Fab")
		)
		(fp_line
			(start -0.12065 0.3048)
			(end -0.67945 0.3048)
			(stroke
				(width 0.1)
				(type default)
			)
			(layer "F.Fab")
		)
		(fp_line
			(start -0.67945 0.3048)
			(end -0.67945 -0.305054)
			(stroke
				(width 0.1)
				(type default)
			)
			(layer "F.Fab")
		)
		(pad "1" smd circle
			(at -0.40005 0 90)
			(size 0 0)
			(layers "F.Cu" "F.Mask" "F.Paste")
			(net "RST_NIC0_PERST0_R_N")
		)
		(pad "2" smd circle
			(at 0.40005 0 90)
			(size 0 0)
			(layers "F.Cu" "F.Mask" "F.Paste")
			(net "RST_HP_NIC0_BUF_N")
		)
	)
	(footprint ""
		(layer "F.Cu")
		(at 104.932734 -237.306612 90)
		(property "Reference" "PC293"
			(at 0 0 90)
			(layer "F.SilkS")
			(hide yes)
			(effects
				(font
					(size 1.27 1.27)
				)
			)
		)
		(property "Value" ""
			(at 0 0 90)
			(layer "F.Fab")
			(effects
				(font
					(size 1.27 1.27)
				)
			)
		)
		(duplicate_pad_numbers_are_jumpers no)
		(fp_line
			(start 1.524 -0.762)
			(end 1.524 0.762)
			(stroke
				(width 0.1524)
				(type default)
			)
			(layer "F.SilkS")
		)
		(fp_line
			(start -1.524 -0.762)
			(end 1.524 -0.762)
			(stroke
				(width 0.1524)
				(type default)
			)
			(layer "F.SilkS")
		)
		(fp_line
			(start 1.524 0.762)
			(end -1.524 0.762)
			(stroke
				(width 0.1524)
				(type default)
			)
			(layer "F.SilkS")
		)
		(fp_line
			(start -1.524 0.762)
			(end -1.524 -0.762)
			(stroke
				(width 0.1524)
				(type default)
			)
			(layer "F.SilkS")
		)
		(fp_line
			(start 1.1049 -0.724916)
			(end -1.1049 -0.724916)
			(stroke
				(width 0.1)
				(type default)
			)
			(layer "F.Fab")
		)
		(fp_line
			(start -1.1049 -0.724916)
			(end -1.1049 0.724916)
			(stroke
				(width 0.1)
				(type default)
			)
			(layer "F.Fab")
		)
		(fp_line
			(start 1.1049 0.724916)
			(end 1.1049 -0.724916)
			(stroke
				(width 0.1)
				(type default)
			)
			(layer "F.Fab")
		)
		(fp_line
			(start -1.1049 0.724916)
			(end 1.1049 0.724916)
			(stroke
				(width 0.1)
				(type default)
			)
			(layer "F.Fab")
		)
		(pad "1" smd rect
			(at -0.889 0 270)
			(size 1.016 1.27)
			(layers "F.Cu" "F.Mask" "F.Paste")
			(net "P1V8_PEX_R")
		)
		(pad "2" smd rect
			(at 0.889 0 270)
			(size 1.016 1.27)
			(layers "F.Cu" "F.Mask" "F.Paste")
			(net "GND")
		)
	)
	(footprint ""
		(layer "F.Cu")
		(at 142.343886 -45.88891)
		(property "Reference" "R554"
			(at 0 0 0)
			(layer "F.SilkS")
			(hide yes)
			(effects
				(font
					(size 1.27 1.27)
				)
			)
		)
		(property "Value" ""
			(at 0 0 0)
			(layer "F.Fab")
			(effects
				(font
					(size 1.27 1.27)
				)
			)
		)
		(duplicate_pad_numbers_are_jumpers no)
		(fp_line
			(start -0.7874 -0.4064)
			(end 0.7874 -0.4064)
			(stroke
				(width 0.1524)
				(type default)
			)
			(layer "F.SilkS")
		)
		(fp_line
			(start -0.7874 0.4064)
			(end -0.7874 -0.4064)
			(stroke
				(width 0.1524)
				(type default)
			)
			(layer "F.SilkS")
		)
		(fp_line
			(start 0.7874 -0.4064)
			(end 0.7874 0.4064)
			(stroke
				(width 0.1524)
				(type default)
			)
			(layer "F.SilkS")
		)
		(fp_line
			(start 0.7874 0.4064)
			(end -0.7874 0.4064)
			(stroke
				(width 0.1524)
				(type default)
			)
			(layer "F.SilkS")
		)
		(fp_line
			(start -0.67945 -0.305054)
			(end -0.12065 -0.305054)
			(stroke
				(width 0.1)
				(type default)
			)
			(layer "F.Fab")
		)
		(fp_line
			(start -0.67945 0.3048)
			(end -0.67945 -0.305054)
			(stroke
				(width 0.1)
				(type default)
			)
			(layer "F.Fab")
		)
		(fp_line
			(start -0.12065 -0.305054)
			(end -0.12065 -0.2794)
			(stroke
				(width 0.1)
				(type default)
			)
			(layer "F.Fab")
		)
		(fp_line
			(start -0.12065 -0.2794)
			(end 0.12065 -0.2794)
			(stroke
				(width 0.1)
				(type default)
			)
			(layer "F.Fab")
		)
		(fp_line
			(start -0.12065 0.2794)
			(end -0.12065 0.3048)
			(stroke
				(width 0.1)
				(type default)
			)
			(layer "F.Fab")
		)
		(fp_line
			(start -0.12065 0.3048)
			(end -0.67945 0.3048)
			(stroke
				(width 0.1)
				(type default)
			)
			(layer "F.Fab")
		)
		(fp_line
			(start 0.120396 0.2794)
			(end -0.12065 0.2794)
			(stroke
				(width 0.1)
				(type default)
			)
			(layer "F.Fab")
		)
		(fp_line
			(start 0.120396 0.3048)
			(end 0.120396 0.2794)
			(stroke
				(width 0.1)
				(type default)
			)
			(layer "F.Fab")
		)
		(fp_line
			(start 0.12065 -0.3048)
			(end 0.67945 -0.3048)
			(stroke
				(width 0.1)
				(type default)
			)
			(layer "F.Fab")
		)
		(fp_line
			(start 0.12065 -0.2794)
			(end 0.12065 -0.3048)
			(stroke
				(width 0.1)
				(type default)
			)
			(layer "F.Fab")
		)
		(fp_line
			(start 0.67945 -0.3048)
			(end 0.67945 0.3048)
			(stroke
				(width 0.1)
				(type default)
			)
			(layer "F.Fab")
		)
		(fp_line
			(start 0.67945 0.3048)
			(end 0.120396 0.3048)
			(stroke
				(width 0.1)
				(type default)
			)
			(layer "F.Fab")
		)
		(pad "1" smd circle
			(at -0.40005 0)
			(size 0 0)
			(layers "F.Cu" "F.Mask" "F.Paste")
			(net "SSD4_ADC_A0")
		)
		(pad "2" smd circle
			(at 0.40005 0)
			(size 0 0)
			(layers "F.Cu" "F.Mask" "F.Paste")
			(net "GND")
		)
	)
	(footprint ""
		(layer "F.Cu")
		(at 236.909864 -227.737416 90)
		(property "Reference" "R6595"
			(at 0 0 90)
			(layer "F.SilkS")
			(hide yes)
			(effects
				(font
					(size 1.27 1.27)
				)
			)
		)
		(property "Value" ""
			(at 0 0 90)
			(layer "F.Fab")
			(effects
				(font
					(size 1.27 1.27)
				)
			)
		)
		(duplicate_pad_numbers_are_jumpers no)
		(fp_line
			(start 0.7874 -0.4064)
			(end 0.7874 0.4064)
			(stroke
				(width 0.1524)
				(type default)
			)
			(layer "F.SilkS")
		)
		(fp_line
			(start -0.7874 -0.4064)
			(end 0.7874 -0.4064)
			(stroke
				(width 0.1524)
				(type default)
			)
			(layer "F.SilkS")
		)
		(fp_line
			(start 0.7874 0.4064)
			(end -0.7874 0.4064)
			(stroke
				(width 0.1524)
				(type default)
			)
			(layer "F.SilkS")
		)
		(fp_line
			(start -0.7874 0.4064)
			(end -0.7874 -0.4064)
			(stroke
				(width 0.1524)
				(type default)
			)
			(layer "F.SilkS")
		)
		(fp_line
			(start -0.12065 -0.305054)
			(end -0.12065 -0.2794)
			(stroke
				(width 0.1)
				(type default)
			)
			(layer "F.Fab")
		)
		(fp_line
			(start -0.67945 -0.305054)
			(end -0.12065 -0.305054)
			(stroke
				(width 0.1)
				(type default)
			)
			(layer "F.Fab")
		)
		(fp_line
			(start 0.67945 -0.3048)
			(end 0.67945 0.3048)
			(stroke
				(width 0.1)
				(type default)
			)
			(layer "F.Fab")
		)
		(fp_line
			(start 0.12065 -0.3048)
			(end 0.67945 -0.3048)
			(stroke
				(width 0.1)
				(type default)
			)
			(layer "F.Fab")
		)
		(fp_line
			(start 0.12065 -0.2794)
			(end 0.12065 -0.3048)
			(stroke
				(width 0.1)
				(type default)
			)
			(layer "F.Fab")
		)
		(fp_line
			(start -0.12065 -0.2794)
			(end 0.12065 -0.2794)
			(stroke
				(width 0.1)
				(type default)
			)
			(layer "F.Fab")
		)
		(fp_line
			(start 0.120396 0.2794)
			(end -0.12065 0.2794)
			(stroke
				(width 0.1)
				(type default)
			)
			(layer "F.Fab")
		)
		(fp_line
			(start -0.12065 0.2794)
			(end -0.12065 0.3048)
			(stroke
				(width 0.1)
				(type default)
			)
			(layer "F.Fab")
		)
		(fp_line
			(start 0.67945 0.3048)
			(end 0.120396 0.3048)
			(stroke
				(width 0.1)
				(type default)
			)
			(layer "F.Fab")
		)
		(fp_line
			(start 0.120396 0.3048)
			(end 0.120396 0.2794)
			(stroke
				(width 0.1)
				(type default)
			)
			(layer "F.Fab")
		)
		(fp_line
			(start -0.12065 0.3048)
			(end -0.67945 0.3048)
			(stroke
				(width 0.1)
				(type default)
			)
			(layer "F.Fab")
		)
		(fp_line
			(start -0.67945 0.3048)
			(end -0.67945 -0.305054)
			(stroke
				(width 0.1)
				(type default)
			)
			(layer "F.Fab")
		)
		(pad "1" smd circle
			(at -0.40005 0 90)
			(size 0 0)
			(layers "F.Cu" "F.Mask" "F.Paste")
			(net "P1V8_PLL0_PEX2_SCALED")
		)
		(pad "2" smd circle
			(at 0.40005 0 90)
			(size 0 0)
			(layers "F.Cu" "F.Mask" "F.Paste")
			(net "GND")
		)
	)
	(footprint ""
		(layer "F.Cu")
		(at 224.851976 -372.074186 180)
		(property "Reference" "PC12"
			(at 0 0 180)
			(layer "F.SilkS")
			(hide yes)
			(effects
				(font
					(size 1.27 1.27)
				)
			)
		)
		(property "Value" ""
			(at 0 0 180)
			(layer "F.Fab")
			(effects
				(font
					(size 1.27 1.27)
				)
			)
		)
		(duplicate_pad_numbers_are_jumpers no)
		(fp_line
			(start 0.7874 0.4064)
			(end -0.7874 0.4064)
			(stroke
				(width 0.1524)
				(type default)
			)
			(layer "F.SilkS")
		)
		(fp_line
			(start 0.7874 -0.4064)
			(end 0.7874 0.4064)
			(stroke
				(width 0.1524)
				(type default)
			)
			(layer "F.SilkS")
		)
		(fp_line
			(start -0.7874 0.4064)
			(end -0.7874 -0.4064)
			(stroke
				(width 0.1524)
				(type default)
			)
			(layer "F.SilkS")
		)
		(fp_line
			(start -0.7874 -0.4064)
			(end 0.7874 -0.4064)
			(stroke
				(width 0.1524)
				(type default)
			)
			(layer "F.SilkS")
		)
		(fp_line
			(start 0.67945 0.3048)
			(end 0.120396 0.3048)
			(stroke
				(width 0.1)
				(type default)
			)
			(layer "F.Fab")
		)
		(fp_line
			(start 0.67945 -0.3048)
			(end 0.67945 0.3048)
			(stroke
				(width 0.1)
				(type default)
			)
			(layer "F.Fab")
		)
		(fp_line
			(start 0.12065 -0.2794)
			(end 0.12065 -0.3048)
			(stroke
				(width 0.1)
				(type default)
			)
			(layer "F.Fab")
		)
		(fp_line
			(start 0.12065 -0.3048)
			(end 0.67945 -0.3048)
			(stroke
				(width 0.1)
				(type default)
			)
			(layer "F.Fab")
		)
		(fp_line
			(start 0.120396 0.3048)
			(end 0.120396 0.2794)
			(stroke
				(width 0.1)
				(type default)
			)
			(layer "F.Fab")
		)
		(fp_line
			(start 0.120396 0.2794)
			(end -0.12065 0.2794)
			(stroke
				(width 0.1)
				(type default)
			)
			(layer "F.Fab")
		)
		(fp_line
			(start -0.12065 0.3048)
			(end -0.67945 0.3048)
			(stroke
				(width 0.1)
				(type default)
			)
			(layer "F.Fab")
		)
		(fp_line
			(start -0.12065 0.2794)
			(end -0.12065 0.3048)
			(stroke
				(width 0.1)
				(type default)
			)
			(layer "F.Fab")
		)
		(fp_line
			(start -0.12065 -0.2794)
			(end 0.12065 -0.2794)
			(stroke
				(width 0.1)
				(type default)
			)
			(layer "F.Fab")
		)
		(fp_line
			(start -0.12065 -0.305054)
			(end -0.12065 -0.2794)
			(stroke
				(width 0.1)
				(type default)
			)
			(layer "F.Fab")
		)
		(fp_line
			(start -0.67945 0.3048)
			(end -0.67945 -0.305054)
			(stroke
				(width 0.1)
				(type default)
			)
			(layer "F.Fab")
		)
		(fp_line
			(start -0.67945 -0.305054)
			(end -0.12065 -0.305054)
			(stroke
				(width 0.1)
				(type default)
			)
			(layer "F.Fab")
		)
		(pad "1" smd circle
			(at -0.40005 0 180)
			(size 0 0)
			(layers "F.Cu" "F.Mask" "F.Paste")
			(net "HSC_SS")
		)
		(pad "2" smd circle
			(at 0.40005 0 180)
			(size 0 0)
			(layers "F.Cu" "F.Mask" "F.Paste")
			(net "AGND_HSC")
		)
	)
	(footprint ""
		(layer "F.Cu")
		(at 443.109096 -95.041466 -90)
		(property "Reference" "PC351"
			(at 0 0 270)
			(layer "F.SilkS")
			(hide yes)
			(effects
				(font
					(size 1.27 1.27)
				)
			)
		)
		(property "Value" ""
			(at 0 0 270)
			(layer "F.Fab")
			(effects
				(font
					(size 1.27 1.27)
				)
			)
		)
		(duplicate_pad_numbers_are_jumpers no)
		(fp_line
			(start -0.7874 0.4064)
			(end -0.7874 -0.4064)
			(stroke
				(width 0.1524)
				(type default)
			)
			(layer "F.SilkS")
		)
		(fp_line
			(start 0.7874 0.4064)
			(end -0.7874 0.4064)
			(stroke
				(width 0.1524)
				(type default)
			)
			(layer "F.SilkS")
		)
		(fp_line
			(start -0.7874 -0.4064)
			(end 0.7874 -0.4064)
			(stroke
				(width 0.1524)
				(type default)
			)
			(layer "F.SilkS")
		)
		(fp_line
			(start 0.7874 -0.4064)
			(end 0.7874 0.4064)
			(stroke
				(width 0.1524)
				(type default)
			)
			(layer "F.SilkS")
		)
		(fp_line
			(start -0.6858 0.3048)
			(end -0.6858 -0.3048)
			(stroke
				(width 0.1)
				(type default)
			)
			(layer "F.Fab")
		)
		(fp_line
			(start -0.1016 0.3048)
			(end -0.6858 0.3048)
			(stroke
				(width 0.1)
				(type default)
			)
			(layer "F.Fab")
		)
		(fp_line
			(start 0.1016 0.3048)
			(end 0.1016 0.2794)
			(stroke
				(width 0.1)
				(type default)
			)
			(layer "F.Fab")
		)
		(fp_line
			(start 0.6858 0.3048)
			(end 0.1016 0.3048)
			(stroke
				(width 0.1)
				(type default)
			)
			(layer "F.Fab")
		)
		(fp_line
			(start -0.1016 0.2794)
			(end -0.1016 0.3048)
			(stroke
				(width 0.1)
				(type default)
			)
			(layer "F.Fab")
		)
		(fp_line
			(start 0.1016 0.2794)
			(end -0.1016 0.2794)
			(stroke
				(width 0.1)
				(type default)
			)
			(layer "F.Fab")
		)
		(fp_line
			(start -0.1016 -0.2794)
			(end 0.1016 -0.2794)
			(stroke
				(width 0.1)
				(type default)
			)
			(layer "F.Fab")
		)
		(fp_line
			(start 0.1016 -0.2794)
			(end 0.1016 -0.3048)
			(stroke
				(width 0.1)
				(type default)
			)
			(layer "F.Fab")
		)
		(fp_line
			(start -0.6858 -0.3048)
			(end -0.1016 -0.3048)
			(stroke
				(width 0.1)
				(type default)
			)
			(layer "F.Fab")
		)
		(fp_line
			(start -0.1016 -0.3048)
			(end -0.1016 -0.2794)
			(stroke
				(width 0.1)
				(type default)
			)
			(layer "F.Fab")
		)
		(fp_line
			(start 0.1016 -0.3048)
			(end 0.6858 -0.3048)
			(stroke
				(width 0.1)
				(type default)
			)
			(layer "F.Fab")
		)
		(fp_line
			(start 0.6858 -0.3048)
			(end 0.6858 0.3048)
			(stroke
				(width 0.1)
				(type default)
			)
			(layer "F.Fab")
		)
		(pad "1" smd rect
			(at -0.40005 0 90)
			(size 0.4572 0.508)
			(layers "F.Cu" "F.Mask" "F.Paste")
			(net "P12V_NIC7_SS")
		)
		(pad "2" smd rect
			(at 0.40005 0 90)
			(size 0.4572 0.508)
			(layers "F.Cu" "F.Mask" "F.Paste")
			(net "GND")
		)
	)
	(footprint ""
		(layer "F.Cu")
		(at 258.54533 -208.019396)
		(property "Reference" "R2620"
			(at 0 0 0)
			(layer "F.SilkS")
			(hide yes)
			(effects
				(font
					(size 1.27 1.27)
				)
			)
		)
		(property "Value" ""
			(at 0 0 0)
			(layer "F.Fab")
			(effects
				(font
					(size 1.27 1.27)
				)
			)
		)
		(duplicate_pad_numbers_are_jumpers no)
		(fp_line
			(start -0.7874 -0.4064)
			(end 0.7874 -0.4064)
			(stroke
				(width 0.1524)
				(type default)
			)
			(layer "F.SilkS")
		)
		(fp_line
			(start -0.7874 0.4064)
			(end -0.7874 -0.4064)
			(stroke
				(width 0.1524)
				(type default)
			)
			(layer "F.SilkS")
		)
		(fp_line
			(start 0.7874 -0.4064)
			(end 0.7874 0.4064)
			(stroke
				(width 0.1524)
				(type default)
			)
			(layer "F.SilkS")
		)
		(fp_line
			(start 0.7874 0.4064)
			(end -0.7874 0.4064)
			(stroke
				(width 0.1524)
				(type default)
			)
			(layer "F.SilkS")
		)
		(fp_line
			(start -0.67945 -0.305054)
			(end -0.12065 -0.305054)
			(stroke
				(width 0.1)
				(type default)
			)
			(layer "F.Fab")
		)
		(fp_line
			(start -0.67945 0.3048)
			(end -0.67945 -0.305054)
			(stroke
				(width 0.1)
				(type default)
			)
			(layer "F.Fab")
		)
		(fp_line
			(start -0.12065 -0.305054)
			(end -0.12065 -0.2794)
			(stroke
				(width 0.1)
				(type default)
			)
			(layer "F.Fab")
		)
		(fp_line
			(start -0.12065 -0.2794)
			(end 0.12065 -0.2794)
			(stroke
				(width 0.1)
				(type default)
			)
			(layer "F.Fab")
		)
		(fp_line
			(start -0.12065 0.2794)
			(end -0.12065 0.3048)
			(stroke
				(width 0.1)
				(type default)
			)
			(layer "F.Fab")
		)
		(fp_line
			(start -0.12065 0.3048)
			(end -0.67945 0.3048)
			(stroke
				(width 0.1)
				(type default)
			)
			(layer "F.Fab")
		)
		(fp_line
			(start 0.120396 0.2794)
			(end -0.12065 0.2794)
			(stroke
				(width 0.1)
				(type default)
			)
			(layer "F.Fab")
		)
		(fp_line
			(start 0.120396 0.3048)
			(end 0.120396 0.2794)
			(stroke
				(width 0.1)
				(type default)
			)
			(layer "F.Fab")
		)
		(fp_line
			(start 0.12065 -0.3048)
			(end 0.67945 -0.3048)
			(stroke
				(width 0.1)
				(type default)
			)
			(layer "F.Fab")
		)
		(fp_line
			(start 0.12065 -0.2794)
			(end 0.12065 -0.3048)
			(stroke
				(width 0.1)
				(type default)
			)
			(layer "F.Fab")
		)
		(fp_line
			(start 0.67945 -0.3048)
			(end 0.67945 0.3048)
			(stroke
				(width 0.1)
				(type default)
			)
			(layer "F.Fab")
		)
		(fp_line
			(start 0.67945 0.3048)
			(end 0.120396 0.3048)
			(stroke
				(width 0.1)
				(type default)
			)
			(layer "F.Fab")
		)
		(pad "1" smd circle
			(at -0.40005 0)
			(size 0 0)
			(layers "F.Cu" "F.Mask" "F.Paste")
			(net "JTAG_FPGA_TDO")
		)
		(pad "2" smd circle
			(at 0.40005 0)
			(size 0 0)
			(layers "F.Cu" "F.Mask" "F.Paste")
			(net "P3V3_AUX")
		)
	)
	(footprint ""
		(layer "F.Cu")
		(at 71.588122 -356.244906 90)
		(property "Reference" "C118"
			(at 0 0 90)
			(layer "F.SilkS")
			(hide yes)
			(effects
				(font
					(size 1.27 1.27)
				)
			)
		)
		(property "Value" ""
			(at 0 0 90)
			(layer "F.Fab")
			(effects
				(font
					(size 1.27 1.27)
				)
			)
		)
		(duplicate_pad_numbers_are_jumpers no)
		(fp_line
			(start 0.299974 -0.150114)
			(end 0.299974 0.150114)
			(stroke
				(width 0.1)
				(type default)
			)
			(layer "F.Fab")
		)
		(fp_line
			(start -0.299974 -0.150114)
			(end 0.299974 -0.150114)
			(stroke
				(width 0.1)
				(type default)
			)
			(layer "F.Fab")
		)
		(fp_line
			(start 0.299974 0.150114)
			(end -0.299974 0.150114)
			(stroke
				(width 0.1)
				(type default)
			)
			(layer "F.Fab")
		)
		(fp_line
			(start -0.299974 0.150114)
			(end -0.299974 -0.150114)
			(stroke
				(width 0.1)
				(type default)
			)
			(layer "F.Fab")
		)
		(pad "1" smd rect
			(at -0.2667 0 90)
			(size 0.3048 0.381)
			(layers "F.Cu" "F.Mask" "F.Paste")
			(net "P5E_PEX0_STN5_TX_DN<85>")
		)
		(pad "2" smd rect
			(at 0.2667 0 90)
			(size 0.3048 0.381)
			(layers "F.Cu" "F.Mask" "F.Paste")
			(net "P5E_PEX0_STN5_TX_C_DN<85>")
		)
	)
	(footprint ""
		(layer "F.Cu")
		(at 72.446388 -58.323734)
		(property "Reference" "PC355"
			(at 0 0 0)
			(layer "F.SilkS")
			(hide yes)
			(effects
				(font
					(size 1.27 1.27)
				)
			)
		)
		(property "Value" ""
			(at 0 0 0)
			(layer "F.Fab")
			(effects
				(font
					(size 1.27 1.27)
				)
			)
		)
		(duplicate_pad_numbers_are_jumpers no)
		(fp_line
			(start -1.524 -0.762)
			(end 1.524 -0.762)
			(stroke
				(width 0.1524)
				(type default)
			)
			(layer "F.SilkS")
		)
		(fp_line
			(start -1.524 0.762)
			(end -1.524 -0.762)
			(stroke
				(width 0.1524)
				(type default)
			)
			(layer "F.SilkS")
		)
		(fp_line
			(start 1.524 -0.762)
			(end 1.524 0.762)
			(stroke
				(width 0.1524)
				(type default)
			)
			(layer "F.SilkS")
		)
		(fp_line
			(start 1.524 0.762)
			(end -1.524 0.762)
			(stroke
				(width 0.1524)
				(type default)
			)
			(layer "F.SilkS")
		)
		(fp_line
			(start -1.1049 -0.724916)
			(end -1.1049 0.724916)
			(stroke
				(width 0.1)
				(type default)
			)
			(layer "F.Fab")
		)
		(fp_line
			(start -1.1049 0.724916)
			(end 1.1049 0.724916)
			(stroke
				(width 0.1)
				(type default)
			)
			(layer "F.Fab")
		)
		(fp_line
			(start 1.1049 -0.724916)
			(end -1.1049 -0.724916)
			(stroke
				(width 0.1)
				(type default)
			)
			(layer "F.Fab")
		)
		(fp_line
			(start 1.1049 0.724916)
			(end 1.1049 -0.724916)
			(stroke
				(width 0.1)
				(type default)
			)
			(layer "F.Fab")
		)
		(pad "1" smd rect
			(at -0.889 0 180)
			(size 1.016 1.27)
			(layers "F.Cu" "F.Mask" "F.Paste")
			(net "GND")
		)
		(pad "2" smd rect
			(at 0.889 0 180)
			(size 1.016 1.27)
			(layers "F.Cu" "F.Mask" "F.Paste")
			(net "P12V_AUX")
		)
	)
	(footprint ""
		(layer "F.Cu")
		(at 384.938524 -109.20984)
		(property "Reference" "C687"
			(at 0 0 0)
			(layer "F.SilkS")
			(hide yes)
			(effects
				(font
					(size 1.27 1.27)
				)
			)
		)
		(property "Value" ""
			(at 0 0 0)
			(layer "F.Fab")
			(effects
				(font
					(size 1.27 1.27)
				)
			)
		)
		(duplicate_pad_numbers_are_jumpers no)
		(fp_line
			(start -0.299974 -0.150114)
			(end 0.299974 -0.150114)
			(stroke
				(width 0.1)
				(type default)
			)
			(layer "F.Fab")
		)
		(fp_line
			(start -0.299974 0.150114)
			(end -0.299974 -0.150114)
			(stroke
				(width 0.1)
				(type default)
			)
			(layer "F.Fab")
		)
		(fp_line
			(start 0.299974 -0.150114)
			(end 0.299974 0.150114)
			(stroke
				(width 0.1)
				(type default)
			)
			(layer "F.Fab")
		)
		(fp_line
			(start 0.299974 0.150114)
			(end -0.299974 0.150114)
			(stroke
				(width 0.1)
				(type default)
			)
			(layer "F.Fab")
		)
		(pad "1" smd rect
			(at -0.2667 0)
			(size 0.3048 0.381)
			(layers "F.Cu" "F.Mask" "F.Paste")
			(net "P5E_PEX3_STN1_TX_DP<21>")
		)
		(pad "2" smd rect
			(at 0.2667 0)
			(size 0.3048 0.381)
			(layers "F.Cu" "F.Mask" "F.Paste")
			(net "P5E_PEX3_STN1_TX_C_DP<21>")
		)
	)
	(footprint ""
		(layer "F.Cu")
		(at 250.81992 -15.649956 180)
		(property "Reference" "H111"
			(at -0.576834 2.852166 0)
			(unlocked yes)
			(layer "B.SilkS")
			(effects
				(font
					(size 0.7874 0.5842)
					(thickness 0.1524)
				)
				(justify left mirror)
			)
		)
		(property "Value" ""
			(at 0 0 180)
			(layer "F.Fab")
			(effects
				(font
					(size 1.27 1.27)
				)
			)
		)
		(duplicate_pad_numbers_are_jumpers no)
		(pad "1" thru_hole rect
			(at 0 0 180)
			(size 4.2164 5.0038)
			(drill 2.0066
				(offset 0.099822 0)
			)
			(layers "*.Cu" "*.Mask")
			(remove_unused_layers no)
			(net "Net_8552")
			(clearance -0.8509)
			(padstack
				(mode front_inner_back)
				(layer "Inner"
					(shape circle)
					(size 4.0132 4.0132)
					(clearance -0.7493)
				)
				(layer "B.Cu"
					(shape circle)
					(size 4.0132 4.0132)
					(clearance -0.7493)
				)
			)
		)
	)
	(footprint ""
		(layer "F.Cu")
		(at 105.019094 -397.512286 90)
		(property "Reference" "R5456"
			(at 0 0 90)
			(layer "F.SilkS")
			(hide yes)
			(effects
				(font
					(size 1.27 1.27)
				)
			)
		)
		(property "Value" ""
			(at 0 0 90)
			(layer "F.Fab")
			(effects
				(font
					(size 1.27 1.27)
				)
			)
		)
		(duplicate_pad_numbers_are_jumpers no)
		(fp_line
			(start 0.7874 -0.4064)
			(end 0.7874 0.4064)
			(stroke
				(width 0.1524)
				(type default)
			)
			(layer "F.SilkS")
		)
		(fp_line
			(start -0.7874 -0.4064)
			(end 0.7874 -0.4064)
			(stroke
				(width 0.1524)
				(type default)
			)
			(layer "F.SilkS")
		)
		(fp_line
			(start 0.7874 0.4064)
			(end -0.7874 0.4064)
			(stroke
				(width 0.1524)
				(type default)
			)
			(layer "F.SilkS")
		)
		(fp_line
			(start -0.7874 0.4064)
			(end -0.7874 -0.4064)
			(stroke
				(width 0.1524)
				(type default)
			)
			(layer "F.SilkS")
		)
		(fp_line
			(start -0.12065 -0.305054)
			(end -0.12065 -0.2794)
			(stroke
				(width 0.1)
				(type default)
			)
			(layer "F.Fab")
		)
		(fp_line
			(start -0.67945 -0.305054)
			(end -0.12065 -0.305054)
			(stroke
				(width 0.1)
				(type default)
			)
			(layer "F.Fab")
		)
		(fp_line
			(start 0.67945 -0.3048)
			(end 0.67945 0.3048)
			(stroke
				(width 0.1)
				(type default)
			)
			(layer "F.Fab")
		)
		(fp_line
			(start 0.12065 -0.3048)
			(end 0.67945 -0.3048)
			(stroke
				(width 0.1)
				(type default)
			)
			(layer "F.Fab")
		)
		(fp_line
			(start 0.12065 -0.2794)
			(end 0.12065 -0.3048)
			(stroke
				(width 0.1)
				(type default)
			)
			(layer "F.Fab")
		)
		(fp_line
			(start -0.12065 -0.2794)
			(end 0.12065 -0.2794)
			(stroke
				(width 0.1)
				(type default)
			)
			(layer "F.Fab")
		)
		(fp_line
			(start 0.120396 0.2794)
			(end -0.12065 0.2794)
			(stroke
				(width 0.1)
				(type default)
			)
			(layer "F.Fab")
		)
		(fp_line
			(start -0.12065 0.2794)
			(end -0.12065 0.3048)
			(stroke
				(width 0.1)
				(type default)
			)
			(layer "F.Fab")
		)
		(fp_line
			(start 0.67945 0.3048)
			(end 0.120396 0.3048)
			(stroke
				(width 0.1)
				(type default)
			)
			(layer "F.Fab")
		)
		(fp_line
			(start 0.120396 0.3048)
			(end 0.120396 0.2794)
			(stroke
				(width 0.1)
				(type default)
			)
			(layer "F.Fab")
		)
		(fp_line
			(start -0.12065 0.3048)
			(end -0.67945 0.3048)
			(stroke
				(width 0.1)
				(type default)
			)
			(layer "F.Fab")
		)
		(fp_line
			(start -0.67945 0.3048)
			(end -0.67945 -0.305054)
			(stroke
				(width 0.1)
				(type default)
			)
			(layer "F.Fab")
		)
		(pad "1" smd circle
			(at -0.40005 0 90)
			(size 0 0)
			(layers "F.Cu" "F.Mask" "F.Paste")
			(net "RST_BIC_USB_HUB_R1_N")
		)
		(pad "2" smd circle
			(at 0.40005 0 90)
			(size 0 0)
			(layers "F.Cu" "F.Mask" "F.Paste")
			(net "GND")
		)
	)
	(footprint ""
		(layer "F.Cu")
		(at 220.631512 -231.416606 90)
		(property "Reference" "R4546"
			(at 0 0 90)
			(layer "F.SilkS")
			(hide yes)
			(effects
				(font
					(size 1.27 1.27)
				)
			)
		)
		(property "Value" ""
			(at 0 0 90)
			(layer "F.Fab")
			(effects
				(font
					(size 1.27 1.27)
				)
			)
		)
		(duplicate_pad_numbers_are_jumpers no)
		(fp_line
			(start 0.7874 -0.4064)
			(end 0.7874 0.4064)
			(stroke
				(width 0.1524)
				(type default)
			)
			(layer "F.SilkS")
		)
		(fp_line
			(start -0.7874 -0.4064)
			(end 0.7874 -0.4064)
			(stroke
				(width 0.1524)
				(type default)
			)
			(layer "F.SilkS")
		)
		(fp_line
			(start 0.7874 0.4064)
			(end -0.7874 0.4064)
			(stroke
				(width 0.1524)
				(type default)
			)
			(layer "F.SilkS")
		)
		(fp_line
			(start -0.7874 0.4064)
			(end -0.7874 -0.4064)
			(stroke
				(width 0.1524)
				(type default)
			)
			(layer "F.SilkS")
		)
		(fp_line
			(start -0.12065 -0.305054)
			(end -0.12065 -0.2794)
			(stroke
				(width 0.1)
				(type default)
			)
			(layer "F.Fab")
		)
		(fp_line
			(start -0.67945 -0.305054)
			(end -0.12065 -0.305054)
			(stroke
				(width 0.1)
				(type default)
			)
			(layer "F.Fab")
		)
		(fp_line
			(start 0.67945 -0.3048)
			(end 0.67945 0.3048)
			(stroke
				(width 0.1)
				(type default)
			)
			(layer "F.Fab")
		)
		(fp_line
			(start 0.12065 -0.3048)
			(end 0.67945 -0.3048)
			(stroke
				(width 0.1)
				(type default)
			)
			(layer "F.Fab")
		)
		(fp_line
			(start 0.12065 -0.2794)
			(end 0.12065 -0.3048)
			(stroke
				(width 0.1)
				(type default)
			)
			(layer "F.Fab")
		)
		(fp_line
			(start -0.12065 -0.2794)
			(end 0.12065 -0.2794)
			(stroke
				(width 0.1)
				(type default)
			)
			(layer "F.Fab")
		)
		(fp_line
			(start 0.120396 0.2794)
			(end -0.12065 0.2794)
			(stroke
				(width 0.1)
				(type default)
			)
			(layer "F.Fab")
		)
		(fp_line
			(start -0.12065 0.2794)
			(end -0.12065 0.3048)
			(stroke
				(width 0.1)
				(type default)
			)
			(layer "F.Fab")
		)
		(fp_line
			(start 0.67945 0.3048)
			(end 0.120396 0.3048)
			(stroke
				(width 0.1)
				(type default)
			)
			(layer "F.Fab")
		)
		(fp_line
			(start 0.120396 0.3048)
			(end 0.120396 0.2794)
			(stroke
				(width 0.1)
				(type default)
			)
			(layer "F.Fab")
		)
		(fp_line
			(start -0.12065 0.3048)
			(end -0.67945 0.3048)
			(stroke
				(width 0.1)
				(type default)
			)
			(layer "F.Fab")
		)
		(fp_line
			(start -0.67945 0.3048)
			(end -0.67945 -0.305054)
			(stroke
				(width 0.1)
				(type default)
			)
			(layer "F.Fab")
		)
		(pad "1" smd circle
			(at -0.40005 0 90)
			(size 0 0)
			(layers "F.Cu" "F.Mask" "F.Paste")
			(net "REV_ID2")
		)
		(pad "2" smd circle
			(at 0.40005 0 90)
			(size 0 0)
			(layers "F.Cu" "F.Mask" "F.Paste")
			(net "P3V3_AUX")
		)
	)
	(footprint ""
		(layer "F.Cu")
		(at 20.221448 -350.098614 90)
		(property "Reference" "C192"
			(at 0 0 90)
			(layer "F.SilkS")
			(hide yes)
			(effects
				(font
					(size 1.27 1.27)
				)
			)
		)
		(property "Value" ""
			(at 0 0 90)
			(layer "F.Fab")
			(effects
				(font
					(size 1.27 1.27)
				)
			)
		)
		(duplicate_pad_numbers_are_jumpers no)
		(fp_line
			(start 0.299974 -0.150114)
			(end 0.299974 0.150114)
			(stroke
				(width 0.1)
				(type default)
			)
			(layer "F.Fab")
		)
		(fp_line
			(start -0.299974 -0.150114)
			(end 0.299974 -0.150114)
			(stroke
				(width 0.1)
				(type default)
			)
			(layer "F.Fab")
		)
		(fp_line
			(start 0.299974 0.150114)
			(end -0.299974 0.150114)
			(stroke
				(width 0.1)
				(type default)
			)
			(layer "F.Fab")
		)
		(fp_line
			(start -0.299974 0.150114)
			(end -0.299974 -0.150114)
			(stroke
				(width 0.1)
				(type default)
			)
			(layer "F.Fab")
		)
		(pad "1" smd rect
			(at -0.2667 0 90)
			(size 0.3048 0.381)
			(layers "F.Cu" "F.Mask" "F.Paste")
			(net "P5E_PEX0_STN7_TX_DN<112>")
		)
		(pad "2" smd rect
			(at 0.2667 0 90)
			(size 0.3048 0.381)
			(layers "F.Cu" "F.Mask" "F.Paste")
			(net "P5E_PEX0_STN7_TX_C_DN<112>")
		)
	)
	(footprint ""
		(layer "F.Cu")
		(at 181.728872 -356.244906 90)
		(property "Reference" "C382"
			(at 0 0 90)
			(layer "F.SilkS")
			(hide yes)
			(effects
				(font
					(size 1.27 1.27)
				)
			)
		)
		(property "Value" ""
			(at 0 0 90)
			(layer "F.Fab")
			(effects
				(font
					(size 1.27 1.27)
				)
			)
		)
		(duplicate_pad_numbers_are_jumpers no)
		(fp_line
			(start 0.299974 -0.150114)
			(end 0.299974 0.150114)
			(stroke
				(width 0.1)
				(type default)
			)
			(layer "F.Fab")
		)
		(fp_line
			(start -0.299974 -0.150114)
			(end 0.299974 -0.150114)
			(stroke
				(width 0.1)
				(type default)
			)
			(layer "F.Fab")
		)
		(fp_line
			(start 0.299974 0.150114)
			(end -0.299974 0.150114)
			(stroke
				(width 0.1)
				(type default)
			)
			(layer "F.Fab")
		)
		(fp_line
			(start -0.299974 0.150114)
			(end -0.299974 -0.150114)
			(stroke
				(width 0.1)
				(type default)
			)
			(layer "F.Fab")
		)
		(pad "1" smd rect
			(at -0.2667 0 90)
			(size 0.3048 0.381)
			(layers "F.Cu" "F.Mask" "F.Paste")
			(net "P5E_PEX1_STN7_TX_DP<122>")
		)
		(pad "2" smd rect
			(at 0.2667 0 90)
			(size 0.3048 0.381)
			(layers "F.Cu" "F.Mask" "F.Paste")
			(net "P5E_PEX1_STN7_TX_C_DP<122>")
		)
	)
	(footprint ""
		(layer "F.Cu")
		(at 59.649868 -295.89984)
		(property "Reference" "PEX0"
			(at -3.360166 35.566858 0)
			(unlocked yes)
			(layer "F.SilkS")
			(effects
				(font
					(size 2.032 1.524)
					(thickness 0.1524)
				)
				(justify left)
			)
		)
		(property "Value" ""
			(at 0 0 0)
			(layer "F.Fab")
			(effects
				(font
					(size 1.27 1.27)
				)
			)
		)
		(duplicate_pad_numbers_are_jumpers no)
		(fp_line
			(start 23.750016 -23.750016)
			(end -23.750016 -23.750016)
			(stroke
				(width 0.1524)
				(type default)
			)
			(layer "F.SilkS")
		)
		(fp_line
			(start 23.750016 23.750016)
			(end 23.750016 -23.750016)
			(stroke
				(width 0.1524)
				(type default)
			)
			(layer "F.SilkS")
		)
		(fp_poly
			(pts
				(xy -21.850096 -23.750016) (xy -21.850096 -24.512016) (xy -24.512016 -24.512016) (xy -24.512016 -21.850096)
				(xy -23.750016 -21.850096) (xy -23.750016 -23.750016)
			)
			(stroke
				(width 0)
				(type default)
			)
			(fill yes)
			(layer "F.SilkS")
		)
		(fp_line
			(start -23.750016 -23.750016)
			(end -23.750016 23.750016)
			(stroke
				(width 0.1)
				(type default)
			)
			(layer "F.Fab")
		)
		(fp_line
			(start -23.750016 23.750016)
			(end 23.750016 23.750016)
			(stroke
				(width 0.1)
				(type default)
			)
			(layer "F.Fab")
		)
		(fp_line
			(start 23.750016 -23.750016)
			(end -23.750016 -23.750016)
			(stroke
				(width 0.1)
				(type default)
			)
			(layer "F.Fab")
		)
		(fp_line
			(start 23.750016 23.750016)
			(end 23.750016 -23.750016)
			(stroke
				(width 0.1)
				(type default)
			)
			(layer "F.Fab")
		)
		(fp_poly
			(pts
				(xy -21.850096 -23.750016) (xy -21.850096 -24.512016) (xy -24.512016 -24.512016) (xy -24.512016 -21.850096)
				(xy -23.750016 -21.850096) (xy -23.750016 -23.750016)
			)
			(stroke
				(width 0)
				(type default)
			)
			(fill yes)
			(layer "F.Fab")
		)
		(pad "A2" smd circle
			(at -21.850096 -22.800056)
			(size 0.4572 0.4572)
			(layers "F.Cu" "F.Mask" "F.Paste")
			(net "GND")
		)
		(pad "A3" smd circle
			(at -20.899882 -22.800056)
			(size 0.4572 0.4572)
			(layers "F.Cu" "F.Mask" "F.Paste")
			(net "P5E_PEX0_STN7_RX_DN<123>")
		)
		(pad "A4" smd circle
			(at -19.949922 -22.800056)
			(size 0.4572 0.4572)
			(layers "F.Cu" "F.Mask" "F.Paste")
			(net "GND")
		)
		(pad "A5" smd circle
			(at -18.999962 -22.800056)
			(size 0.4572 0.4572)
			(layers "F.Cu" "F.Mask" "F.Paste")
			(net "P5E_PEX0_STN7_RX_DN<125>")
		)
		(pad "A6" smd circle
			(at -18.050002 -22.800056)
			(size 0.4572 0.4572)
			(layers "F.Cu" "F.Mask" "F.Paste")
			(net "GND")
		)
		(pad "A7" smd circle
			(at -17.100042 -22.800056)
			(size 0.4572 0.4572)
			(layers "F.Cu" "F.Mask" "F.Paste")
			(net "P5E_PEX0_STN7_RX_DN<127>")
		)
		(pad "A8" smd circle
			(at -16.150082 -22.800056)
			(size 0.4572 0.4572)
			(layers "F.Cu" "F.Mask" "F.Paste")
			(net "GND")
		)
		(pad "A9" smd circle
			(at -15.200122 -22.800056)
			(size 0.4572 0.4572)
			(layers "F.Cu" "F.Mask" "F.Paste")
			(net "P5E_PEX0_STN6_RX_DN<110>")
		)
		(pad "A10" smd circle
			(at -14.249908 -22.800056)
			(size 0.4572 0.4572)
			(layers "F.Cu" "F.Mask" "F.Paste")
			(net "GND")
		)
		(pad "A11" smd circle
			(at -13.299948 -22.800056)
			(size 0.4572 0.4572)
			(layers "F.Cu" "F.Mask" "F.Paste")
			(net "P5E_PEX0_STN6_RX_DN<108>")
		)
		(pad "A12" smd circle
			(at -12.349988 -22.800056)
			(size 0.4572 0.4572)
			(layers "F.Cu" "F.Mask" "F.Paste")
			(net "GND")
		)
		(pad "A13" smd circle
			(at -11.400028 -22.800056)
			(size 0.4572 0.4572)
			(layers "F.Cu" "F.Mask" "F.Paste")
			(net "P5E_PEX0_STN6_RX_DN<106>")
		)
		(pad "A14" smd circle
			(at -10.450068 -22.800056)
			(size 0.4572 0.4572)
			(layers "F.Cu" "F.Mask" "F.Paste")
			(net "GND")
		)
		(pad "A15" smd circle
			(at -9.500108 -22.800056)
			(size 0.4572 0.4572)
			(layers "F.Cu" "F.Mask" "F.Paste")
			(net "P5E_PEX0_STN6_RX_DN<104>")
		)
		(pad "A16" smd circle
			(at -8.549894 -22.800056)
			(size 0.4572 0.4572)
			(layers "F.Cu" "F.Mask" "F.Paste")
			(net "GND")
		)
		(pad "A17" smd circle
			(at -7.599934 -22.800056)
			(size 0.4572 0.4572)
			(layers "F.Cu" "F.Mask" "F.Paste")
			(net "P5E_PEX0_STN6_RX_DN<102>")
		)
		(pad "A18" smd circle
			(at -6.649974 -22.800056)
			(size 0.4572 0.4572)
			(layers "F.Cu" "F.Mask" "F.Paste")
			(net "GND")
		)
		(pad "A19" smd circle
			(at -5.700014 -22.800056)
			(size 0.4572 0.4572)
			(layers "F.Cu" "F.Mask" "F.Paste")
			(net "P5E_PEX0_STN6_RX_DN<100>")
		)
		(pad "A20" smd circle
			(at -4.750054 -22.800056)
			(size 0.4572 0.4572)
			(layers "F.Cu" "F.Mask" "F.Paste")
			(net "GND")
		)
		(pad "A21" smd circle
			(at -3.800094 -22.800056)
			(size 0.4572 0.4572)
			(layers "F.Cu" "F.Mask" "F.Paste")
			(net "P5E_PEX0_STN6_RX_DN<98>")
		)
		(pad "A22" smd circle
			(at -2.84988 -22.800056)
			(size 0.4572 0.4572)
			(layers "F.Cu" "F.Mask" "F.Paste")
			(net "GND")
		)
		(pad "A23" smd circle
			(at -1.89992 -22.800056)
			(size 0.4572 0.4572)
			(layers "F.Cu" "F.Mask" "F.Paste")
			(net "P5E_PEX0_STN6_RX_DN<96>")
		)
		(pad "A24" smd circle
			(at -0.94996 -22.800056)
			(size 0.4572 0.4572)
			(layers "F.Cu" "F.Mask" "F.Paste")
			(net "GND")
		)
		(pad "A25" smd circle
			(at 0 -22.800056)
			(size 0.4572 0.4572)
			(layers "F.Cu" "F.Mask" "F.Paste")
			(net "P5E_PEX0_STN5_RX_DN<81>")
		)
		(pad "A26" smd circle
			(at 0.94996 -22.800056)
			(size 0.4572 0.4572)
			(layers "F.Cu" "F.Mask" "F.Paste")
			(net "GND")
		)
		(pad "A27" smd circle
			(at 1.89992 -22.800056)
			(size 0.4572 0.4572)
			(layers "F.Cu" "F.Mask" "F.Paste")
			(net "P5E_PEX0_STN5_RX_DN<83>")
		)
		(pad "A28" smd circle
			(at 2.84988 -22.800056)
			(size 0.4572 0.4572)
			(layers "F.Cu" "F.Mask" "F.Paste")
			(net "GND")
		)
		(pad "A29" smd circle
			(at 3.800094 -22.800056)
			(size 0.4572 0.4572)
			(layers "F.Cu" "F.Mask" "F.Paste")
			(net "P5E_PEX0_STN5_RX_DN<85>")
		)
		(pad "A30" smd circle
			(at 4.750054 -22.800056)
			(size 0.4572 0.4572)
			(layers "F.Cu" "F.Mask" "F.Paste")
			(net "GND")
		)
		(pad "A31" smd circle
			(at 5.700014 -22.800056)
			(size 0.4572 0.4572)
			(layers "F.Cu" "F.Mask" "F.Paste")
			(net "P5E_PEX0_STN5_RX_DN<87>")
		)
		(pad "A32" smd circle
			(at 6.649974 -22.800056)
			(size 0.4572 0.4572)
			(layers "F.Cu" "F.Mask" "F.Paste")
			(net "GND")
		)
		(pad "A33" smd circle
			(at 7.599934 -22.800056)
			(size 0.4572 0.4572)
			(layers "F.Cu" "F.Mask" "F.Paste")
			(net "P5E_PEX0_STN5_RX_DN<89>")
		)
		(pad "A34" smd circle
			(at 8.549894 -22.800056)
			(size 0.4572 0.4572)
			(layers "F.Cu" "F.Mask" "F.Paste")
			(net "GND")
		)
		(pad "A35" smd circle
			(at 9.500108 -22.800056)
			(size 0.4572 0.4572)
			(layers "F.Cu" "F.Mask" "F.Paste")
			(net "P5E_PEX0_STN5_RX_DN<91>")
		)
		(pad "A36" smd circle
			(at 10.450068 -22.800056)
			(size 0.4572 0.4572)
			(layers "F.Cu" "F.Mask" "F.Paste")
			(net "GND")
		)
		(pad "A37" smd circle
			(at 11.400028 -22.800056)
			(size 0.4572 0.4572)
			(layers "F.Cu" "F.Mask" "F.Paste")
			(net "P5E_PEX0_STN5_RX_DN<93>")
		)
		(pad "A38" smd circle
			(at 12.349988 -22.800056)
			(size 0.4572 0.4572)
			(layers "F.Cu" "F.Mask" "F.Paste")
			(net "GND")
		)
		(pad "A39" smd circle
			(at 13.299948 -22.800056)
			(size 0.4572 0.4572)
			(layers "F.Cu" "F.Mask" "F.Paste")
			(net "P5E_PEX0_STN5_RX_DN<95>")
		)
		(pad "A40" smd circle
			(at 14.249908 -22.800056)
			(size 0.4572 0.4572)
			(layers "F.Cu" "F.Mask" "F.Paste")
			(net "GND")
		)
		(pad "A41" smd circle
			(at 15.200122 -22.800056)
			(size 0.4572 0.4572)
			(layers "F.Cu" "F.Mask" "F.Paste")
			(net "P5E_PEX0_STN4_RX_DN<78>")
		)
		(pad "A42" smd circle
			(at 16.150082 -22.800056)
			(size 0.4572 0.4572)
			(layers "F.Cu" "F.Mask" "F.Paste")
			(net "GND")
		)
		(pad "A43" smd circle
			(at 17.100042 -22.800056)
			(size 0.4572 0.4572)
			(layers "F.Cu" "F.Mask" "F.Paste")
			(net "P5E_PEX0_STN4_RX_DN<76>")
		)
		(pad "A44" smd circle
			(at 18.050002 -22.800056)
			(size 0.4572 0.4572)
			(layers "F.Cu" "F.Mask" "F.Paste")
			(net "GND")
		)
		(pad "A45" smd circle
			(at 18.999962 -22.800056)
			(size 0.4572 0.4572)
			(layers "F.Cu" "F.Mask" "F.Paste")
			(net "P5E_PEX0_STN4_RX_DN<74>")
		)
		(pad "A46" smd circle
			(at 19.949922 -22.800056)
			(size 0.4572 0.4572)
			(layers "F.Cu" "F.Mask" "F.Paste")
			(net "GND")
		)
		(pad "A47" smd circle
			(at 20.899882 -22.800056)
			(size 0.4572 0.4572)
			(layers "F.Cu" "F.Mask" "F.Paste")
			(net "P5E_PEX0_STN4_RX_DN<72>")
		)
		(pad "A48" smd circle
			(at 21.850096 -22.800056)
			(size 0.4572 0.4572)
			(layers "F.Cu" "F.Mask" "F.Paste")
			(net "GND")
		)
		(pad "AA1" smd circle
			(at -22.800056 -3.800094)
			(size 0.4572 0.4572)
			(layers "F.Cu" "F.Mask" "F.Paste")
			(net "CLK_100M_PEX0_REF_R_DN")
		)
		(pad "AA2" smd circle
			(at -21.850096 -3.800094)
			(size 0.4572 0.4572)
			(layers "F.Cu" "F.Mask" "F.Paste")
			(net "CLK_100M_PEX0_REF_R_DP")
		)
		(pad "AA3" smd circle
			(at -20.899882 -3.800094)
			(size 0.4572 0.4572)
			(layers "F.Cu" "F.Mask" "F.Paste")
			(net "GND")
		)
		(pad "AA4" smd circle
			(at -19.949922 -3.800094)
			(size 0.4572 0.4572)
			(layers "F.Cu" "F.Mask" "F.Paste")
			(net "GND")
		)
		(pad "AA5" smd circle
			(at -18.999962 -3.800094)
			(size 0.4572 0.4572)
			(layers "F.Cu" "F.Mask" "F.Paste")
			(net "GND")
		)
		(pad "AA6" smd circle
			(at -18.050002 -3.800094)
			(size 0.4572 0.4572)
			(layers "F.Cu" "F.Mask" "F.Paste")
			(net "GND")
		)
		(pad "AA7" smd circle
			(at -17.100042 -3.800094)
			(size 0.4572 0.4572)
			(layers "F.Cu" "F.Mask" "F.Paste")
			(net "GND")
		)
		(pad "AA8" smd circle
			(at -16.150082 -3.800094)
			(size 0.4572 0.4572)
			(layers "F.Cu" "F.Mask" "F.Paste")
			(net "GND")
		)
		(pad "AA9" smd circle
			(at -15.200122 -3.800094)
			(size 0.4572 0.4572)
			(layers "F.Cu" "F.Mask" "F.Paste")
			(net "GND")
		)
		(pad "AA10" smd circle
			(at -14.249908 -3.800094)
			(size 0.4572 0.4572)
			(layers "F.Cu" "F.Mask" "F.Paste")
			(net "P1V8_VDDA_PEX0")
		)
		(pad "AA11" smd circle
			(at -13.299948 -3.800094)
			(size 0.4572 0.4572)
			(layers "F.Cu" "F.Mask" "F.Paste")
			(net "GND")
		)
		(pad "AA12" smd circle
			(at -12.349988 -3.800094)
			(size 0.4572 0.4572)
			(layers "F.Cu" "F.Mask" "F.Paste")
			(net "GND")
		)
		(pad "AA13" smd circle
			(at -11.400028 -3.800094)
			(size 0.4572 0.4572)
			(layers "F.Cu" "F.Mask" "F.Paste")
			(net "PCEPLL0_VDDA18_PEX0")
		)
		(pad "AA14" smd circle
			(at -10.450068 -3.800094)
			(size 0.4572 0.4572)
			(layers "F.Cu" "F.Mask" "F.Paste")
			(net "GND")
		)
		(pad "AA15" smd circle
			(at -9.500108 -3.800094)
			(size 0.4572 0.4572)
			(layers "F.Cu" "F.Mask" "F.Paste")
			(net "P0V8_PEX0")
		)
		(pad "AA16" smd circle
			(at -8.549894 -3.800094)
			(size 0.4572 0.4572)
			(layers "F.Cu" "F.Mask" "F.Paste")
			(net "GND")
		)
		(pad "AA17" smd circle
			(at -7.599934 -3.800094)
			(size 0.4572 0.4572)
			(layers "F.Cu" "F.Mask" "F.Paste")
			(net "GND")
		)
		(pad "AA18" smd circle
			(at -6.649974 -3.800094)
			(size 0.4572 0.4572)
			(layers "F.Cu" "F.Mask" "F.Paste")
			(net "GND")
		)
		(pad "AA19" smd circle
			(at -5.700014 -3.800094)
			(size 0.4572 0.4572)
			(layers "F.Cu" "F.Mask" "F.Paste")
			(net "GND")
		)
		(pad "AA20" smd circle
			(at -4.750054 -3.800094)
			(size 0.4572 0.4572)
			(layers "F.Cu" "F.Mask" "F.Paste")
			(net "GND")
		)
		(pad "AA21" smd circle
			(at -3.800094 -3.800094)
			(size 0.4572 0.4572)
			(layers "F.Cu" "F.Mask" "F.Paste")
			(net "GND")
		)
		(pad "AA22" smd circle
			(at -2.84988 -3.800094)
			(size 0.4572 0.4572)
			(layers "F.Cu" "F.Mask" "F.Paste")
			(net "GND")
		)
		(pad "AA23" smd circle
			(at -1.89992 -3.800094)
			(size 0.4572 0.4572)
			(layers "F.Cu" "F.Mask" "F.Paste")
			(net "GND")
		)
		(pad "AA24" smd circle
			(at -0.94996 -3.800094)
			(size 0.4572 0.4572)
			(layers "F.Cu" "F.Mask" "F.Paste")
			(net "GND")
		)
		(pad "AA25" smd circle
			(at 0 -3.800094)
			(size 0.4572 0.4572)
			(layers "F.Cu" "F.Mask" "F.Paste")
			(net "GND")
		)
		(pad "AA26" smd circle
			(at 0.94996 -3.800094)
			(size 0.4572 0.4572)
			(layers "F.Cu" "F.Mask" "F.Paste")
			(net "GND")
		)
		(pad "AA27" smd circle
			(at 1.89992 -3.800094)
			(size 0.4572 0.4572)
			(layers "F.Cu" "F.Mask" "F.Paste")
			(net "GND")
		)
		(pad "AA28" smd circle
			(at 2.84988 -3.800094)
			(size 0.4572 0.4572)
			(layers "F.Cu" "F.Mask" "F.Paste")
			(net "GND")
		)
		(pad "AA29" smd circle
			(at 3.800094 -3.800094)
			(size 0.4572 0.4572)
			(layers "F.Cu" "F.Mask" "F.Paste")
			(net "GND")
		)
		(pad "AA30" smd circle
			(at 4.750054 -3.800094)
			(size 0.4572 0.4572)
			(layers "F.Cu" "F.Mask" "F.Paste")
			(net "GND")
		)
		(pad "AA31" smd circle
			(at 5.700014 -3.800094)
			(size 0.4572 0.4572)
			(layers "F.Cu" "F.Mask" "F.Paste")
			(net "GND")
		)
		(pad "AA32" smd circle
			(at 6.649974 -3.800094)
			(size 0.4572 0.4572)
			(layers "F.Cu" "F.Mask" "F.Paste")
			(net "GND")
		)
		(pad "AA33" smd circle
			(at 7.599934 -3.800094)
			(size 0.4572 0.4572)
			(layers "F.Cu" "F.Mask" "F.Paste")
			(net "GND")
		)
		(pad "AA34" smd circle
			(at 8.549894 -3.800094)
			(size 0.4572 0.4572)
			(layers "F.Cu" "F.Mask" "F.Paste")
			(net "P1V8_VDDA_PEX0")
		)
		(pad "AA35" smd circle
			(at 9.500108 -3.800094)
			(size 0.4572 0.4572)
			(layers "F.Cu" "F.Mask" "F.Paste")
			(net "Net_480")
		)
		(pad "AA36" smd circle
			(at 10.450068 -3.800094)
			(size 0.4572 0.4572)
			(layers "F.Cu" "F.Mask" "F.Paste")
			(net "GND")
		)
		(pad "AA37" smd circle
			(at 11.400028 -3.800094)
			(size 0.4572 0.4572)
			(layers "F.Cu" "F.Mask" "F.Paste")
			(net "P1V8_VDDA_PEX0")
		)
		(pad "AA38" smd circle
			(at 12.349988 -3.800094)
			(size 0.4572 0.4572)
			(layers "F.Cu" "F.Mask" "F.Paste")
			(net "GND")
		)
		(pad "AA39" smd circle
			(at 13.299948 -3.800094)
			(size 0.4572 0.4572)
			(layers "F.Cu" "F.Mask" "F.Paste")
			(net "PEX0_ADCTEMP_VINP1")
		)
		(pad "AA40" smd circle
			(at 14.249908 -3.800094)
			(size 0.4572 0.4572)
			(layers "F.Cu" "F.Mask" "F.Paste")
			(net "GND")
		)
		(pad "AA41" smd circle
			(at 15.200122 -3.800094)
			(size 0.4572 0.4572)
			(layers "F.Cu" "F.Mask" "F.Paste")
			(net "GND")
		)
		(pad "AA42" smd circle
			(at 16.150082 -3.800094)
			(size 0.4572 0.4572)
			(layers "F.Cu" "F.Mask" "F.Paste")
			(net "GND")
		)
		(pad "AA43" smd circle
			(at 17.100042 -3.800094)
			(size 0.4572 0.4572)
			(layers "F.Cu" "F.Mask" "F.Paste")
			(net "Net_2818")
		)
		(pad "AA44" smd circle
			(at 18.050002 -3.800094)
			(size 0.4572 0.4572)
			(layers "F.Cu" "F.Mask" "F.Paste")
			(net "Net_2802")
		)
		(pad "AA45" smd circle
			(at 18.999962 -3.800094)
			(size 0.4572 0.4572)
			(layers "F.Cu" "F.Mask" "F.Paste")
			(net "GND")
		)
		(pad "AA46" smd circle
			(at 19.949922 -3.800094)
			(size 0.4572 0.4572)
			(layers "F.Cu" "F.Mask" "F.Paste")
			(net "Net_2786")
		)
		(pad "AA47" smd circle
			(at 20.899882 -3.800094)
			(size 0.4572 0.4572)
			(layers "F.Cu" "F.Mask" "F.Paste")
			(net "Net_2770")
		)
		(pad "AA48" smd circle
			(at 21.850096 -3.800094)
			(size 0.4572 0.4572)
			(layers "F.Cu" "F.Mask" "F.Paste")
			(net "GND")
		)
		(pad "AA49" smd circle
			(at 22.800056 -3.800094)
			(size 0.4572 0.4572)
			(layers "F.Cu" "F.Mask" "F.Paste")
			(net "GND")
		)
		(pad "AB1" smd circle
			(at -22.800056 -2.84988)
			(size 0.4572 0.4572)
			(layers "F.Cu" "F.Mask" "F.Paste")
			(net "GND")
		)
		(pad "AB2" smd circle
			(at -21.850096 -2.84988)
			(size 0.4572 0.4572)
			(layers "F.Cu" "F.Mask" "F.Paste")
			(net "GND")
		)
		(pad "AB3" smd circle
			(at -20.899882 -2.84988)
			(size 0.4572 0.4572)
			(layers "F.Cu" "F.Mask" "F.Paste")
			(net "GND")
		)
		(pad "AB4" smd circle
			(at -19.949922 -2.84988)
			(size 0.4572 0.4572)
			(layers "F.Cu" "F.Mask" "F.Paste")
			(net "CLK_100M_DB800ZL_PEX0_S0_R_DN")
		)
		(pad "AB5" smd circle
			(at -18.999962 -2.84988)
			(size 0.4572 0.4572)
			(layers "F.Cu" "F.Mask" "F.Paste")
			(net "CLK_100M_DB800ZL_PEX0_S0_R_DP")
		)
		(pad "AB6" smd circle
			(at -18.050002 -2.84988)
			(size 0.4572 0.4572)
			(layers "F.Cu" "F.Mask" "F.Paste")
			(net "GND")
		)
		(pad "AB7" smd circle
			(at -17.100042 -2.84988)
			(size 0.4572 0.4572)
			(layers "F.Cu" "F.Mask" "F.Paste")
			(net "Net_2914")
		)
		(pad "AB8" smd circle
			(at -16.150082 -2.84988)
			(size 0.4572 0.4572)
			(layers "F.Cu" "F.Mask" "F.Paste")
			(net "Net_2913")
		)
		(pad "AB9" smd circle
			(at -15.200122 -2.84988)
			(size 0.4572 0.4572)
			(layers "F.Cu" "F.Mask" "F.Paste")
			(net "GND")
		)
		(pad "AB10" smd circle
			(at -14.249908 -2.84988)
			(size 0.4572 0.4572)
			(layers "F.Cu" "F.Mask" "F.Paste")
			(net "P1V8_VDDA_PEX0")
		)
		(pad "AB11" smd circle
			(at -13.299948 -2.84988)
			(size 0.4572 0.4572)
			(layers "F.Cu" "F.Mask" "F.Paste")
			(net "GND")
		)
		(pad "AB12" smd circle
			(at -12.349988 -2.84988)
			(size 0.4572 0.4572)
			(layers "F.Cu" "F.Mask" "F.Paste")
			(net "PCEPLL1_VDDA18_PEX0")
		)
		(pad "AB13" smd circle
			(at -11.400028 -2.84988)
			(size 0.4572 0.4572)
			(layers "F.Cu" "F.Mask" "F.Paste")
			(net "GND")
		)
		(pad "AB14" smd circle
			(at -10.450068 -2.84988)
			(size 0.4572 0.4572)
			(layers "F.Cu" "F.Mask" "F.Paste")
			(net "P0V8_PEX0")
		)
		(pad "AB15" smd circle
			(at -9.500108 -2.84988)
			(size 0.4572 0.4572)
			(layers "F.Cu" "F.Mask" "F.Paste")
			(net "GND")
		)
		(pad "AB16" smd circle
			(at -8.549894 -2.84988)
			(size 0.4572 0.4572)
			(layers "F.Cu" "F.Mask" "F.Paste")
			(net "P0V8_SERDES_VDDA_PEX0")
		)
		(pad "AB17" smd circle
			(at -7.599934 -2.84988)
			(size 0.4572 0.4572)
			(layers "F.Cu" "F.Mask" "F.Paste")
			(net "P0V8_SERDES_VDDA_PEX0")
		)
		(pad "AB18" smd circle
			(at -6.649974 -2.84988)
			(size 0.4572 0.4572)
			(layers "F.Cu" "F.Mask" "F.Paste")
			(net "P0V8_SERDES_VDDA_PEX0")
		)
		(pad "AB19" smd circle
			(at -5.700014 -2.84988)
			(size 0.4572 0.4572)
			(layers "F.Cu" "F.Mask" "F.Paste")
			(net "P0V8_SERDES_VDDA_PEX0")
		)
		(pad "AB20" smd circle
			(at -4.750054 -2.84988)
			(size 0.4572 0.4572)
			(layers "F.Cu" "F.Mask" "F.Paste")
			(net "P0V8_SERDES_VDDA_PEX0")
		)
		(pad "AB21" smd circle
			(at -3.800094 -2.84988)
			(size 0.4572 0.4572)
			(layers "F.Cu" "F.Mask" "F.Paste")
			(net "P0V8_SERDES_VDDA_PEX0")
		)
		(pad "AB22" smd circle
			(at -2.84988 -2.84988)
			(size 0.4572 0.4572)
			(layers "F.Cu" "F.Mask" "F.Paste")
			(net "P0V8_SERDES_VDDA_PEX0")
		)
		(pad "AB23" smd circle
			(at -1.89992 -2.84988)
			(size 0.4572 0.4572)
			(layers "F.Cu" "F.Mask" "F.Paste")
			(net "P0V8_SERDES_VDDA_PEX0")
		)
		(pad "AB24" smd circle
			(at -0.94996 -2.84988)
			(size 0.4572 0.4572)
			(layers "F.Cu" "F.Mask" "F.Paste")
			(net "P0V8_SERDES_VDDA_PEX0")
		)
		(pad "AB25" smd circle
			(at 0 -2.84988)
			(size 0.4572 0.4572)
			(layers "F.Cu" "F.Mask" "F.Paste")
			(net "P0V8_SERDES_VDDA_PEX0")
		)
		(pad "AB26" smd circle
			(at 0.94996 -2.84988)
			(size 0.4572 0.4572)
			(layers "F.Cu" "F.Mask" "F.Paste")
			(net "P0V8_SERDES_VDDA_PEX0")
		)
		(pad "AB27" smd circle
			(at 1.89992 -2.84988)
			(size 0.4572 0.4572)
			(layers "F.Cu" "F.Mask" "F.Paste")
			(net "P0V8_SERDES_VDDA_PEX0")
		)
		(pad "AB28" smd circle
			(at 2.84988 -2.84988)
			(size 0.4572 0.4572)
			(layers "F.Cu" "F.Mask" "F.Paste")
			(net "P0V8_SERDES_VDDA_PEX0")
		)
		(pad "AB29" smd circle
			(at 3.800094 -2.84988)
			(size 0.4572 0.4572)
			(layers "F.Cu" "F.Mask" "F.Paste")
			(net "P0V8_SERDES_VDDA_PEX0")
		)
		(pad "AB30" smd circle
			(at 4.750054 -2.84988)
			(size 0.4572 0.4572)
			(layers "F.Cu" "F.Mask" "F.Paste")
			(net "P0V8_SERDES_VDDA_PEX0")
		)
		(pad "AB31" smd circle
			(at 5.700014 -2.84988)
			(size 0.4572 0.4572)
			(layers "F.Cu" "F.Mask" "F.Paste")
			(net "P0V8_SERDES_VDDA_PEX0")
		)
		(pad "AB32" smd circle
			(at 6.649974 -2.84988)
			(size 0.4572 0.4572)
			(layers "F.Cu" "F.Mask" "F.Paste")
			(net "P0V8_SERDES_VDDA_PEX0")
		)
		(pad "AB33" smd circle
			(at 7.599934 -2.84988)
			(size 0.4572 0.4572)
			(layers "F.Cu" "F.Mask" "F.Paste")
			(net "P0V8_SERDES_VDDA_PEX0")
		)
		(pad "AB34" smd circle
			(at 8.549894 -2.84988)
			(size 0.4572 0.4572)
			(layers "F.Cu" "F.Mask" "F.Paste")
			(net "GND")
		)
		(pad "AB35" smd circle
			(at 9.500108 -2.84988)
			(size 0.4572 0.4572)
			(layers "F.Cu" "F.Mask" "F.Paste")
			(net "Net_481")
		)
		(pad "AB36" smd circle
			(at 10.450068 -2.84988)
			(size 0.4572 0.4572)
			(layers "F.Cu" "F.Mask" "F.Paste")
			(net "GND")
		)
		(pad "AB37" smd circle
			(at 11.400028 -2.84988)
			(size 0.4572 0.4572)
			(layers "F.Cu" "F.Mask" "F.Paste")
			(net "GND")
		)
		(pad "AB38" smd circle
			(at 12.349988 -2.84988)
			(size 0.4572 0.4572)
			(layers "F.Cu" "F.Mask" "F.Paste")
			(net "GND")
		)
		(pad "AB39" smd circle
			(at 13.299948 -2.84988)
			(size 0.4572 0.4572)
			(layers "F.Cu" "F.Mask" "F.Paste")
			(net "GND")
		)
		(pad "AB40" smd circle
			(at 14.249908 -2.84988)
			(size 0.4572 0.4572)
			(layers "F.Cu" "F.Mask" "F.Paste")
			(net "GND")
		)
		(pad "AB41" smd circle
			(at 15.200122 -2.84988)
			(size 0.4572 0.4572)
			(layers "F.Cu" "F.Mask" "F.Paste")
			(net "Net_2819")
		)
		(pad "AB42" smd circle
			(at 16.150082 -2.84988)
			(size 0.4572 0.4572)
			(layers "F.Cu" "F.Mask" "F.Paste")
			(net "Net_2803")
		)
		(pad "AB43" smd circle
			(at 17.100042 -2.84988)
			(size 0.4572 0.4572)
			(layers "F.Cu" "F.Mask" "F.Paste")
			(net "GND")
		)
		(pad "AB44" smd circle
			(at 18.050002 -2.84988)
			(size 0.4572 0.4572)
			(layers "F.Cu" "F.Mask" "F.Paste")
			(net "GND")
		)
		(pad "AB45" smd circle
			(at 18.999962 -2.84988)
			(size 0.4572 0.4572)
			(layers "F.Cu" "F.Mask" "F.Paste")
			(net "GND")
		)
		(pad "AB46" smd circle
			(at 19.949922 -2.84988)
			(size 0.4572 0.4572)
			(layers "F.Cu" "F.Mask" "F.Paste")
			(net "GND")
		)
		(pad "AB47" smd circle
			(at 20.899882 -2.84988)
			(size 0.4572 0.4572)
			(layers "F.Cu" "F.Mask" "F.Paste")
			(net "GND")
		)
		(pad "AB48" smd circle
			(at 21.850096 -2.84988)
			(size 0.4572 0.4572)
			(layers "F.Cu" "F.Mask" "F.Paste")
			(net "Net_2787")
		)
		(pad "AB49" smd circle
			(at 22.800056 -2.84988)
			(size 0.4572 0.4572)
			(layers "F.Cu" "F.Mask" "F.Paste")
			(net "Net_2771")
		)
		(pad "AC1" smd circle
			(at -22.800056 -1.89992)
			(size 0.4572 0.4572)
			(layers "F.Cu" "F.Mask" "F.Paste")
			(net "CLK_100M_DB2000QL_PEX0_S1_R_DN")
		)
		(pad "AC2" smd circle
			(at -21.850096 -1.89992)
			(size 0.4572 0.4572)
			(layers "F.Cu" "F.Mask" "F.Paste")
			(net "CLK_100M_DB2000QL_PEX0_S1_R_DP")
		)
		(pad "AC3" smd circle
			(at -20.899882 -1.89992)
			(size 0.4572 0.4572)
			(layers "F.Cu" "F.Mask" "F.Paste")
			(net "GND")
		)
		(pad "AC4" smd circle
			(at -19.949922 -1.89992)
			(size 0.4572 0.4572)
			(layers "F.Cu" "F.Mask" "F.Paste")
			(net "GND")
		)
		(pad "AC5" smd circle
			(at -18.999962 -1.89992)
			(size 0.4572 0.4572)
			(layers "F.Cu" "F.Mask" "F.Paste")
			(net "GND")
		)
		(pad "AC6" smd circle
			(at -18.050002 -1.89992)
			(size 0.4572 0.4572)
			(layers "F.Cu" "F.Mask" "F.Paste")
			(net "GND")
		)
		(pad "AC7" smd circle
			(at -17.100042 -1.89992)
			(size 0.4572 0.4572)
			(layers "F.Cu" "F.Mask" "F.Paste")
			(net "Net_2916")
		)
		(pad "AC8" smd circle
			(at -16.150082 -1.89992)
			(size 0.4572 0.4572)
			(layers "F.Cu" "F.Mask" "F.Paste")
			(net "Net_2918")
		)
		(pad "AC9" smd circle
			(at -15.200122 -1.89992)
			(size 0.4572 0.4572)
			(layers "F.Cu" "F.Mask" "F.Paste")
			(net "GND")
		)
		(pad "AC10" smd circle
			(at -14.249908 -1.89992)
			(size 0.4572 0.4572)
			(layers "F.Cu" "F.Mask" "F.Paste")
			(net "P1V8_VDDA_PEX0")
		)
		(pad "AC11" smd circle
			(at -13.299948 -1.89992)
			(size 0.4572 0.4572)
			(layers "F.Cu" "F.Mask" "F.Paste")
			(net "GND")
		)
		(pad "AC12" smd circle
			(at -12.349988 -1.89992)
			(size 0.4572 0.4572)
			(layers "F.Cu" "F.Mask" "F.Paste")
			(net "GND")
		)
		(pad "AC13" smd circle
			(at -11.400028 -1.89992)
			(size 0.4572 0.4572)
			(layers "F.Cu" "F.Mask" "F.Paste")
			(net "SYSPLL_VDDA18_PEX0")
		)
		(pad "AC14" smd circle
			(at -10.450068 -1.89992)
			(size 0.4572 0.4572)
			(layers "F.Cu" "F.Mask" "F.Paste")
			(net "GND")
		)
		(pad "AC15" smd circle
			(at -9.500108 -1.89992)
			(size 0.4572 0.4572)
			(layers "F.Cu" "F.Mask" "F.Paste")
			(net "P0V8_PEX0")
		)
		(pad "AC16" smd circle
			(at -8.549894 -1.89992)
			(size 0.4572 0.4572)
			(layers "F.Cu" "F.Mask" "F.Paste")
			(net "GND")
		)
		(pad "AC17" smd circle
			(at -7.599934 -1.89992)
			(size 0.4572 0.4572)
			(layers "F.Cu" "F.Mask" "F.Paste")
			(net "P0V8_PEX0")
		)
		(pad "AC18" smd circle
			(at -6.649974 -1.89992)
			(size 0.4572 0.4572)
			(layers "F.Cu" "F.Mask" "F.Paste")
			(net "GND")
		)
		(pad "AC19" smd circle
			(at -5.700014 -1.89992)
			(size 0.4572 0.4572)
			(layers "F.Cu" "F.Mask" "F.Paste")
			(net "P0V8_PEX0")
		)
		(pad "AC20" smd circle
			(at -4.750054 -1.89992)
			(size 0.4572 0.4572)
			(layers "F.Cu" "F.Mask" "F.Paste")
			(net "GND")
		)
		(pad "AC21" smd circle
			(at -3.800094 -1.89992)
			(size 0.4572 0.4572)
			(layers "F.Cu" "F.Mask" "F.Paste")
			(net "P0V8_PEX0")
		)
		(pad "AC22" smd circle
			(at -2.84988 -1.89992)
			(size 0.4572 0.4572)
			(layers "F.Cu" "F.Mask" "F.Paste")
			(net "GND")
		)
		(pad "AC23" smd circle
			(at -1.89992 -1.89992)
			(size 0.4572 0.4572)
			(layers "F.Cu" "F.Mask" "F.Paste")
			(net "P0V8_PEX0")
		)
		(pad "AC24" smd circle
			(at -0.94996 -1.89992)
			(size 0.4572 0.4572)
			(layers "F.Cu" "F.Mask" "F.Paste")
			(net "GND")
		)
		(pad "AC25" smd circle
			(at 0 -1.89992)
			(size 0.4572 0.4572)
			(layers "F.Cu" "F.Mask" "F.Paste")
			(net "P0V8_PEX0")
		)
		(pad "AC26" smd circle
			(at 0.94996 -1.89992)
			(size 0.4572 0.4572)
			(layers "F.Cu" "F.Mask" "F.Paste")
			(net "GND")
		)
		(pad "AC27" smd circle
			(at 1.89992 -1.89992)
			(size 0.4572 0.4572)
			(layers "F.Cu" "F.Mask" "F.Paste")
			(net "P0V8_PEX0")
		)
		(pad "AC28" smd circle
			(at 2.84988 -1.89992)
			(size 0.4572 0.4572)
			(layers "F.Cu" "F.Mask" "F.Paste")
			(net "GND")
		)
		(pad "AC29" smd circle
			(at 3.800094 -1.89992)
			(size 0.4572 0.4572)
			(layers "F.Cu" "F.Mask" "F.Paste")
			(net "P0V8_PEX0")
		)
		(pad "AC30" smd circle
			(at 4.750054 -1.89992)
			(size 0.4572 0.4572)
			(layers "F.Cu" "F.Mask" "F.Paste")
			(net "GND")
		)
		(pad "AC31" smd circle
			(at 5.700014 -1.89992)
			(size 0.4572 0.4572)
			(layers "F.Cu" "F.Mask" "F.Paste")
			(net "P0V8_PEX0")
		)
		(pad "AC32" smd circle
			(at 6.649974 -1.89992)
			(size 0.4572 0.4572)
			(layers "F.Cu" "F.Mask" "F.Paste")
			(net "GND")
		)
		(pad "AC33" smd circle
			(at 7.599934 -1.89992)
			(size 0.4572 0.4572)
			(layers "F.Cu" "F.Mask" "F.Paste")
			(net "P0V8_PEX0")
		)
		(pad "AC34" smd circle
			(at 8.549894 -1.89992)
			(size 0.4572 0.4572)
			(layers "F.Cu" "F.Mask" "F.Paste")
			(net "GND")
		)
		(pad "AC35" smd circle
			(at 9.500108 -1.89992)
			(size 0.4572 0.4572)
			(layers "F.Cu" "F.Mask" "F.Paste")
			(net "GND")
		)
		(pad "AC36" smd circle
			(at 10.450068 -1.89992)
			(size 0.4572 0.4572)
			(layers "F.Cu" "F.Mask" "F.Paste")
			(net "P1V25_PEX0")
		)
		(pad "AC37" smd circle
			(at 11.400028 -1.89992)
			(size 0.4572 0.4572)
			(layers "F.Cu" "F.Mask" "F.Paste")
			(net "GND")
		)
		(pad "AC38" smd circle
			(at 12.349988 -1.89992)
			(size 0.4572 0.4572)
			(layers "F.Cu" "F.Mask" "F.Paste")
			(net "P1V25_SERDES_VDDPLL_PEX0")
		)
		(pad "AC39" smd circle
			(at 13.299948 -1.89992)
			(size 0.4572 0.4572)
			(layers "F.Cu" "F.Mask" "F.Paste")
			(net "GND")
		)
		(pad "AC40" smd circle
			(at 14.249908 -1.89992)
			(size 0.4572 0.4572)
			(layers "F.Cu" "F.Mask" "F.Paste")
			(net "GND")
		)
		(pad "AC41" smd circle
			(at 15.200122 -1.89992)
			(size 0.4572 0.4572)
			(layers "F.Cu" "F.Mask" "F.Paste")
			(net "GND")
		)
		(pad "AC42" smd circle
			(at 16.150082 -1.89992)
			(size 0.4572 0.4572)
			(layers "F.Cu" "F.Mask" "F.Paste")
			(net "GND")
		)
		(pad "AC43" smd circle
			(at 17.100042 -1.89992)
			(size 0.4572 0.4572)
			(layers "F.Cu" "F.Mask" "F.Paste")
			(net "Net_2820")
		)
		(pad "AC44" smd circle
			(at 18.050002 -1.89992)
			(size 0.4572 0.4572)
			(layers "F.Cu" "F.Mask" "F.Paste")
			(net "Net_2804")
		)
		(pad "AC45" smd circle
			(at 18.999962 -1.89992)
			(size 0.4572 0.4572)
			(layers "F.Cu" "F.Mask" "F.Paste")
			(net "GND")
		)
		(pad "AC46" smd circle
			(at 19.949922 -1.89992)
			(size 0.4572 0.4572)
			(layers "F.Cu" "F.Mask" "F.Paste")
			(net "Net_2788")
		)
		(pad "AC47" smd circle
			(at 20.899882 -1.89992)
			(size 0.4572 0.4572)
			(layers "F.Cu" "F.Mask" "F.Paste")
			(net "Net_2772")
		)
		(pad "AC48" smd circle
			(at 21.850096 -1.89992)
			(size 0.4572 0.4572)
			(layers "F.Cu" "F.Mask" "F.Paste")
			(net "GND")
		)
		(pad "AC49" smd circle
			(at 22.800056 -1.89992)
			(size 0.4572 0.4572)
			(layers "F.Cu" "F.Mask" "F.Paste")
			(net "GND")
		)
		(pad "AD1" smd circle
			(at -22.800056 -0.94996)
			(size 0.4572 0.4572)
			(layers "F.Cu" "F.Mask" "F.Paste")
			(net "GND")
		)
		(pad "AD2" smd circle
			(at -21.850096 -0.94996)
			(size 0.4572 0.4572)
			(layers "F.Cu" "F.Mask" "F.Paste")
			(net "GND")
		)
		(pad "AD3" smd circle
			(at -20.899882 -0.94996)
			(size 0.4572 0.4572)
			(layers "F.Cu" "F.Mask" "F.Paste")
			(net "GND")
		)
		(pad "AD4" smd circle
			(at -19.949922 -0.94996)
			(size 0.4572 0.4572)
			(layers "F.Cu" "F.Mask" "F.Paste")
			(net "Net_387")
		)
		(pad "AD5" smd circle
			(at -18.999962 -0.94996)
			(size 0.4572 0.4572)
			(layers "F.Cu" "F.Mask" "F.Paste")
			(net "Net_384")
		)
		(pad "AD6" smd circle
			(at -18.050002 -0.94996)
			(size 0.4572 0.4572)
			(layers "F.Cu" "F.Mask" "F.Paste")
			(net "GND")
		)
		(pad "AD7" smd circle
			(at -17.100042 -0.94996)
			(size 0.4572 0.4572)
			(layers "F.Cu" "F.Mask" "F.Paste")
			(net "Net_2915")
		)
		(pad "AD8" smd circle
			(at -16.150082 -0.94996)
			(size 0.4572 0.4572)
			(layers "F.Cu" "F.Mask" "F.Paste")
			(net "Net_2917")
		)
		(pad "AD9" smd circle
			(at -15.200122 -0.94996)
			(size 0.4572 0.4572)
			(layers "F.Cu" "F.Mask" "F.Paste")
			(net "GND")
		)
		(pad "AD10" smd circle
			(at -14.249908 -0.94996)
			(size 0.4572 0.4572)
			(layers "F.Cu" "F.Mask" "F.Paste")
			(net "GND")
		)
		(pad "AD11" smd circle
			(at -13.299948 -0.94996)
			(size 0.4572 0.4572)
			(layers "F.Cu" "F.Mask" "F.Paste")
			(net "GND")
		)
		(pad "AD12" smd circle
			(at -12.349988 -0.94996)
			(size 0.4572 0.4572)
			(layers "F.Cu" "F.Mask" "F.Paste")
			(net "PCEPLL2_VDDA18_PEX0")
		)
		(pad "AD13" smd circle
			(at -11.400028 -0.94996)
			(size 0.4572 0.4572)
			(layers "F.Cu" "F.Mask" "F.Paste")
			(net "GND")
		)
		(pad "AD14" smd circle
			(at -10.450068 -0.94996)
			(size 0.4572 0.4572)
			(layers "F.Cu" "F.Mask" "F.Paste")
			(net "P0V8_PEX0")
		)
		(pad "AD15" smd circle
			(at -9.500108 -0.94996)
			(size 0.4572 0.4572)
			(layers "F.Cu" "F.Mask" "F.Paste")
			(net "GND")
		)
		(pad "AD16" smd circle
			(at -8.549894 -0.94996)
			(size 0.4572 0.4572)
			(layers "F.Cu" "F.Mask" "F.Paste")
			(net "P0V8_PEX0")
		)
		(pad "AD17" smd circle
			(at -7.599934 -0.94996)
			(size 0.4572 0.4572)
			(layers "F.Cu" "F.Mask" "F.Paste")
			(net "GND")
		)
		(pad "AD18" smd circle
			(at -6.649974 -0.94996)
			(size 0.4572 0.4572)
			(layers "F.Cu" "F.Mask" "F.Paste")
			(net "P0V8_PEX0")
		)
		(pad "AD19" smd circle
			(at -5.700014 -0.94996)
			(size 0.4572 0.4572)
			(layers "F.Cu" "F.Mask" "F.Paste")
			(net "GND")
		)
		(pad "AD20" smd circle
			(at -4.750054 -0.94996)
			(size 0.4572 0.4572)
			(layers "F.Cu" "F.Mask" "F.Paste")
			(net "P0V8_PEX0")
		)
		(pad "AD21" smd circle
			(at -3.800094 -0.94996)
			(size 0.4572 0.4572)
			(layers "F.Cu" "F.Mask" "F.Paste")
			(net "GND")
		)
		(pad "AD22" smd circle
			(at -2.84988 -0.94996)
			(size 0.4572 0.4572)
			(layers "F.Cu" "F.Mask" "F.Paste")
			(net "P0V8_PEX0")
		)
		(pad "AD23" smd circle
			(at -1.89992 -0.94996)
			(size 0.4572 0.4572)
			(layers "F.Cu" "F.Mask" "F.Paste")
			(net "GND")
		)
		(pad "AD24" smd circle
			(at -0.94996 -0.94996)
			(size 0.4572 0.4572)
			(layers "F.Cu" "F.Mask" "F.Paste")
			(net "P0V8_PEX0")
		)
		(pad "AD25" smd circle
			(at 0 -0.94996)
			(size 0.4572 0.4572)
			(layers "F.Cu" "F.Mask" "F.Paste")
			(net "GND")
		)
		(pad "AD26" smd circle
			(at 0.94996 -0.94996)
			(size 0.4572 0.4572)
			(layers "F.Cu" "F.Mask" "F.Paste")
			(net "P0V8_PEX0")
		)
		(pad "AD27" smd circle
			(at 1.89992 -0.94996)
			(size 0.4572 0.4572)
			(layers "F.Cu" "F.Mask" "F.Paste")
			(net "GND")
		)
		(pad "AD28" smd circle
			(at 2.84988 -0.94996)
			(size 0.4572 0.4572)
			(layers "F.Cu" "F.Mask" "F.Paste")
			(net "P0V8_PEX0")
		)
		(pad "AD29" smd circle
			(at 3.800094 -0.94996)
			(size 0.4572 0.4572)
			(layers "F.Cu" "F.Mask" "F.Paste")
			(net "GND")
		)
		(pad "AD30" smd circle
			(at 4.750054 -0.94996)
			(size 0.4572 0.4572)
			(layers "F.Cu" "F.Mask" "F.Paste")
			(net "P0V8_PEX0")
		)
		(pad "AD31" smd circle
			(at 5.700014 -0.94996)
			(size 0.4572 0.4572)
			(layers "F.Cu" "F.Mask" "F.Paste")
			(net "GND")
		)
		(pad "AD32" smd circle
			(at 6.649974 -0.94996)
			(size 0.4572 0.4572)
			(layers "F.Cu" "F.Mask" "F.Paste")
			(net "P0V8_SERDES_VDDA_PEX0")
		)
		(pad "AD33" smd circle
			(at 7.599934 -0.94996)
			(size 0.4572 0.4572)
			(layers "F.Cu" "F.Mask" "F.Paste")
			(net "P0V8_SERDES_VDDA_PEX0")
		)
		(pad "AD34" smd circle
			(at 8.549894 -0.94996)
			(size 0.4572 0.4572)
			(layers "F.Cu" "F.Mask" "F.Paste")
			(net "P0V8_SERDES_VDDA_PEX0")
		)
		(pad "AD35" smd circle
			(at 9.500108 -0.94996)
			(size 0.4572 0.4572)
			(layers "F.Cu" "F.Mask" "F.Paste")
			(net "GND")
		)
		(pad "AD36" smd circle
			(at 10.450068 -0.94996)
			(size 0.4572 0.4572)
			(layers "F.Cu" "F.Mask" "F.Paste")
			(net "P1V25_PEX0")
		)
		(pad "AD37" smd circle
			(at 11.400028 -0.94996)
			(size 0.4572 0.4572)
			(layers "F.Cu" "F.Mask" "F.Paste")
			(net "GND")
		)
		(pad "AD38" smd circle
			(at 12.349988 -0.94996)
			(size 0.4572 0.4572)
			(layers "F.Cu" "F.Mask" "F.Paste")
			(net "P1V25_SERDES_VDDPLL_PEX0")
		)
		(pad "AD39" smd circle
			(at 13.299948 -0.94996)
			(size 0.4572 0.4572)
			(layers "F.Cu" "F.Mask" "F.Paste")
			(net "GND")
		)
		(pad "AD40" smd circle
			(at 14.249908 -0.94996)
			(size 0.4572 0.4572)
			(layers "F.Cu" "F.Mask" "F.Paste")
			(net "GND")
		)
		(pad "AD41" smd circle
			(at 15.200122 -0.94996)
			(size 0.4572 0.4572)
			(layers "F.Cu" "F.Mask" "F.Paste")
			(net "Net_2821")
		)
		(pad "AD42" smd circle
			(at 16.150082 -0.94996)
			(size 0.4572 0.4572)
			(layers "F.Cu" "F.Mask" "F.Paste")
			(net "Net_2805")
		)
		(pad "AD43" smd circle
			(at 17.100042 -0.94996)
			(size 0.4572 0.4572)
			(layers "F.Cu" "F.Mask" "F.Paste")
			(net "GND")
		)
		(pad "AD44" smd circle
			(at 18.050002 -0.94996)
			(size 0.4572 0.4572)
			(layers "F.Cu" "F.Mask" "F.Paste")
			(net "GND")
		)
		(pad "AD45" smd circle
			(at 18.999962 -0.94996)
			(size 0.4572 0.4572)
			(layers "F.Cu" "F.Mask" "F.Paste")
			(net "GND")
		)
		(pad "AD46" smd circle
			(at 19.949922 -0.94996)
			(size 0.4572 0.4572)
			(layers "F.Cu" "F.Mask" "F.Paste")
			(net "GND")
		)
		(pad "AD47" smd circle
			(at 20.899882 -0.94996)
			(size 0.4572 0.4572)
			(layers "F.Cu" "F.Mask" "F.Paste")
			(net "GND")
		)
		(pad "AD48" smd circle
			(at 21.850096 -0.94996)
			(size 0.4572 0.4572)
			(layers "F.Cu" "F.Mask" "F.Paste")
			(net "Net_2789")
		)
		(pad "AD49" smd circle
			(at 22.800056 -0.94996)
			(size 0.4572 0.4572)
			(layers "F.Cu" "F.Mask" "F.Paste")
			(net "Net_2773")
		)
		(pad "AE1" smd circle
			(at -22.800056 0)
			(size 0.4572 0.4572)
			(layers "F.Cu" "F.Mask" "F.Paste")
			(net "CLK_100M_DB800ZL_PEX0_S3_R_DN")
		)
		(pad "AE2" smd circle
			(at -21.850096 0)
			(size 0.4572 0.4572)
			(layers "F.Cu" "F.Mask" "F.Paste")
			(net "CLK_100M_DB800ZL_PEX0_S3_R_DP")
		)
		(pad "AE3" smd circle
			(at -20.899882 0)
			(size 0.4572 0.4572)
			(layers "F.Cu" "F.Mask" "F.Paste")
			(net "GND")
		)
		(pad "AE4" smd circle
			(at -19.949922 0)
			(size 0.4572 0.4572)
			(layers "F.Cu" "F.Mask" "F.Paste")
			(net "GND")
		)
		(pad "AE5" smd circle
			(at -18.999962 0)
			(size 0.4572 0.4572)
			(layers "F.Cu" "F.Mask" "F.Paste")
			(net "GND")
		)
		(pad "AE6" smd circle
			(at -18.050002 0)
			(size 0.4572 0.4572)
			(layers "F.Cu" "F.Mask" "F.Paste")
			(net "GND")
		)
		(pad "AE7" smd circle
			(at -17.100042 0)
			(size 0.4572 0.4572)
			(layers "F.Cu" "F.Mask" "F.Paste")
			(net "Net_2912")
		)
		(pad "AE8" smd circle
			(at -16.150082 0)
			(size 0.4572 0.4572)
			(layers "F.Cu" "F.Mask" "F.Paste")
			(net "Net_2919")
		)
		(pad "AE9" smd circle
			(at -15.200122 0)
			(size 0.4572 0.4572)
			(layers "F.Cu" "F.Mask" "F.Paste")
			(net "GND")
		)
		(pad "AE10" smd circle
			(at -14.249908 0)
			(size 0.4572 0.4572)
			(layers "F.Cu" "F.Mask" "F.Paste")
			(net "P1V8_PEX")
		)
		(pad "AE11" smd circle
			(at -13.299948 0)
			(size 0.4572 0.4572)
			(layers "F.Cu" "F.Mask" "F.Paste")
			(net "GND")
		)
		(pad "AE12" smd circle
			(at -12.349988 0)
			(size 0.4572 0.4572)
			(layers "F.Cu" "F.Mask" "F.Paste")
			(net "GND")
		)
		(pad "AE13" smd circle
			(at -11.400028 0)
			(size 0.4572 0.4572)
			(layers "F.Cu" "F.Mask" "F.Paste")
			(net "PCEPLL3_VDDA18_PEX0")
		)
		(pad "AE14" smd circle
			(at -10.450068 0)
			(size 0.4572 0.4572)
			(layers "F.Cu" "F.Mask" "F.Paste")
			(net "GND")
		)
		(pad "AE15" smd circle
			(at -9.500108 0)
			(size 0.4572 0.4572)
			(layers "F.Cu" "F.Mask" "F.Paste")
			(net "P0V8_PEX0")
		)
		(pad "AE16" smd circle
			(at -8.549894 0)
			(size 0.4572 0.4572)
			(layers "F.Cu" "F.Mask" "F.Paste")
			(net "GND")
		)
		(pad "AE17" smd circle
			(at -7.599934 0)
			(size 0.4572 0.4572)
			(layers "F.Cu" "F.Mask" "F.Paste")
			(net "P0V8_PEX0")
		)
		(pad "AE18" smd circle
			(at -6.649974 0)
			(size 0.4572 0.4572)
			(layers "F.Cu" "F.Mask" "F.Paste")
			(net "GND")
		)
		(pad "AE19" smd circle
			(at -5.700014 0)
			(size 0.4572 0.4572)
			(layers "F.Cu" "F.Mask" "F.Paste")
			(net "P0V8_PEX0")
		)
		(pad "AE20" smd circle
			(at -4.750054 0)
			(size 0.4572 0.4572)
			(layers "F.Cu" "F.Mask" "F.Paste")
			(net "GND")
		)
		(pad "AE21" smd circle
			(at -3.800094 0)
			(size 0.4572 0.4572)
			(layers "F.Cu" "F.Mask" "F.Paste")
			(net "P0V8_PEX0")
		)
		(pad "AE22" smd circle
			(at -2.84988 0)
			(size 0.4572 0.4572)
			(layers "F.Cu" "F.Mask" "F.Paste")
			(net "GND")
		)
		(pad "AE23" smd circle
			(at -1.89992 0)
			(size 0.4572 0.4572)
			(layers "F.Cu" "F.Mask" "F.Paste")
			(net "P0V8_PEX0")
		)
		(pad "AE24" smd circle
			(at -0.94996 0)
			(size 0.4572 0.4572)
			(layers "F.Cu" "F.Mask" "F.Paste")
			(net "GND")
		)
		(pad "AE25" smd circle
			(at 0 0)
			(size 0.4572 0.4572)
			(layers "F.Cu" "F.Mask" "F.Paste")
			(net "P0V8_PEX0")
		)
		(pad "AE26" smd circle
			(at 0.94996 0)
			(size 0.4572 0.4572)
			(layers "F.Cu" "F.Mask" "F.Paste")
			(net "GND")
		)
		(pad "AE27" smd circle
			(at 1.89992 0)
			(size 0.4572 0.4572)
			(layers "F.Cu" "F.Mask" "F.Paste")
			(net "P0V8_PEX0")
		)
		(pad "AE28" smd circle
			(at 2.84988 0)
			(size 0.4572 0.4572)
			(layers "F.Cu" "F.Mask" "F.Paste")
			(net "GND")
		)
		(pad "AE29" smd circle
			(at 3.800094 0)
			(size 0.4572 0.4572)
			(layers "F.Cu" "F.Mask" "F.Paste")
			(net "P0V8_PEX0")
		)
		(pad "AE30" smd circle
			(at 4.750054 0)
			(size 0.4572 0.4572)
			(layers "F.Cu" "F.Mask" "F.Paste")
			(net "GND")
		)
		(pad "AE31" smd circle
			(at 5.700014 0)
			(size 0.4572 0.4572)
			(layers "F.Cu" "F.Mask" "F.Paste")
			(net "P0V8_PEX0")
		)
		(pad "AE32" smd circle
			(at 6.649974 0)
			(size 0.4572 0.4572)
			(layers "F.Cu" "F.Mask" "F.Paste")
			(net "GND")
		)
		(pad "AE33" smd circle
			(at 7.599934 0)
			(size 0.4572 0.4572)
			(layers "F.Cu" "F.Mask" "F.Paste")
			(net "P0V8_SERDES_VDDA_PEX0")
		)
		(pad "AE34" smd circle
			(at 8.549894 0)
			(size 0.4572 0.4572)
			(layers "F.Cu" "F.Mask" "F.Paste")
			(net "P0V8_SERDES_VDDA_PEX0")
		)
		(pad "AE35" smd circle
			(at 9.500108 0)
			(size 0.4572 0.4572)
			(layers "F.Cu" "F.Mask" "F.Paste")
			(net "GND")
		)
		(pad "AE36" smd circle
			(at 10.450068 0)
			(size 0.4572 0.4572)
			(layers "F.Cu" "F.Mask" "F.Paste")
			(net "P1V25_PEX0")
		)
		(pad "AE37" smd circle
			(at 11.400028 0)
			(size 0.4572 0.4572)
			(layers "F.Cu" "F.Mask" "F.Paste")
			(net "GND")
		)
		(pad "AE38" smd circle
			(at 12.349988 0)
			(size 0.4572 0.4572)
			(layers "F.Cu" "F.Mask" "F.Paste")
			(net "P1V25_SERDES_VDDPLL_PEX0")
		)
		(pad "AE39" smd circle
			(at 13.299948 0)
			(size 0.4572 0.4572)
			(layers "F.Cu" "F.Mask" "F.Paste")
			(net "GND")
		)
		(pad "AE40" smd circle
			(at 14.249908 0)
			(size 0.4572 0.4572)
			(layers "F.Cu" "F.Mask" "F.Paste")
			(net "GND")
		)
		(pad "AE41" smd circle
			(at 15.200122 0)
			(size 0.4572 0.4572)
			(layers "F.Cu" "F.Mask" "F.Paste")
			(net "GND")
		)
		(pad "AE42" smd circle
			(at 16.150082 0)
			(size 0.4572 0.4572)
			(layers "F.Cu" "F.Mask" "F.Paste")
			(net "GND")
		)
		(pad "AE43" smd circle
			(at 17.100042 0)
			(size 0.4572 0.4572)
			(layers "F.Cu" "F.Mask" "F.Paste")
			(net "Net_2822")
		)
		(pad "AE44" smd circle
			(at 18.050002 0)
			(size 0.4572 0.4572)
			(layers "F.Cu" "F.Mask" "F.Paste")
			(net "Net_2806")
		)
		(pad "AE45" smd circle
			(at 18.999962 0)
			(size 0.4572 0.4572)
			(layers "F.Cu" "F.Mask" "F.Paste")
			(net "GND")
		)
		(pad "AE46" smd circle
			(at 19.949922 0)
			(size 0.4572 0.4572)
			(layers "F.Cu" "F.Mask" "F.Paste")
			(net "Net_2790")
		)
		(pad "AE47" smd circle
			(at 20.899882 0)
			(size 0.4572 0.4572)
			(layers "F.Cu" "F.Mask" "F.Paste")
			(net "Net_2774")
		)
		(pad "AE48" smd circle
			(at 21.850096 0)
			(size 0.4572 0.4572)
			(layers "F.Cu" "F.Mask" "F.Paste")
			(net "GND")
		)
		(pad "AE49" smd circle
			(at 22.800056 0)
			(size 0.4572 0.4572)
			(layers "F.Cu" "F.Mask" "F.Paste")
			(net "GND")
		)
		(pad "AF1" smd circle
			(at -22.800056 0.94996)
			(size 0.4572 0.4572)
			(layers "F.Cu" "F.Mask" "F.Paste")
			(net "GND")
		)
		(pad "AF2" smd circle
			(at -21.850096 0.94996)
			(size 0.4572 0.4572)
			(layers "F.Cu" "F.Mask" "F.Paste")
			(net "GND")
		)
		(pad "AF3" smd circle
			(at -20.899882 0.94996)
			(size 0.4572 0.4572)
			(layers "F.Cu" "F.Mask" "F.Paste")
			(net "GND")
		)
		(pad "AF4" smd circle
			(at -19.949922 0.94996)
			(size 0.4572 0.4572)
			(layers "F.Cu" "F.Mask" "F.Paste")
			(net "Net_2831")
		)
		(pad "AF5" smd circle
			(at -18.999962 0.94996)
			(size 0.4572 0.4572)
			(layers "F.Cu" "F.Mask" "F.Paste")
			(net "Net_2832")
		)
		(pad "AF6" smd circle
			(at -18.050002 0.94996)
			(size 0.4572 0.4572)
			(layers "F.Cu" "F.Mask" "F.Paste")
			(net "GND")
		)
		(pad "AF7" smd circle
			(at -17.100042 0.94996)
			(size 0.4572 0.4572)
			(layers "F.Cu" "F.Mask" "F.Paste")
			(net "SPI_PEX0_SDIO0")
		)
		(pad "AF8" smd circle
			(at -16.150082 0.94996)
			(size 0.4572 0.4572)
			(layers "F.Cu" "F.Mask" "F.Paste")
			(net "SPI_PEX0_SDIO1")
		)
		(pad "AF9" smd circle
			(at -15.200122 0.94996)
			(size 0.4572 0.4572)
			(layers "F.Cu" "F.Mask" "F.Paste")
			(net "GND")
		)
		(pad "AF10" smd circle
			(at -14.249908 0.94996)
			(size 0.4572 0.4572)
			(layers "F.Cu" "F.Mask" "F.Paste")
			(net "P1V8_PEX")
		)
		(pad "AF11" smd circle
			(at -13.299948 0.94996)
			(size 0.4572 0.4572)
			(layers "F.Cu" "F.Mask" "F.Paste")
			(net "GND")
		)
		(pad "AF12" smd circle
			(at -12.349988 0.94996)
			(size 0.4572 0.4572)
			(layers "F.Cu" "F.Mask" "F.Paste")
			(net "PCEPLL4_VDDA18_PEX0")
		)
		(pad "AF13" smd circle
			(at -11.400028 0.94996)
			(size 0.4572 0.4572)
			(layers "F.Cu" "F.Mask" "F.Paste")
			(net "GND")
		)
		(pad "AF14" smd circle
			(at -10.450068 0.94996)
			(size 0.4572 0.4572)
			(layers "F.Cu" "F.Mask" "F.Paste")
			(net "P0V8_PEX0")
		)
		(pad "AF15" smd circle
			(at -9.500108 0.94996)
			(size 0.4572 0.4572)
			(layers "F.Cu" "F.Mask" "F.Paste")
			(net "GND")
		)
		(pad "AF16" smd circle
			(at -8.549894 0.94996)
			(size 0.4572 0.4572)
			(layers "F.Cu" "F.Mask" "F.Paste")
			(net "P0V8_PEX0")
		)
		(pad "AF17" smd circle
			(at -7.599934 0.94996)
			(size 0.4572 0.4572)
			(layers "F.Cu" "F.Mask" "F.Paste")
			(net "GND")
		)
		(pad "AF18" smd circle
			(at -6.649974 0.94996)
			(size 0.4572 0.4572)
			(layers "F.Cu" "F.Mask" "F.Paste")
			(net "P0V8_PEX0")
		)
		(pad "AF19" smd circle
			(at -5.700014 0.94996)
			(size 0.4572 0.4572)
			(layers "F.Cu" "F.Mask" "F.Paste")
			(net "GND")
		)
		(pad "AF20" smd circle
			(at -4.750054 0.94996)
			(size 0.4572 0.4572)
			(layers "F.Cu" "F.Mask" "F.Paste")
			(net "P0V8_PEX0")
		)
		(pad "AF21" smd circle
			(at -3.800094 0.94996)
			(size 0.4572 0.4572)
			(layers "F.Cu" "F.Mask" "F.Paste")
			(net "GND")
		)
		(pad "AF22" smd circle
			(at -2.84988 0.94996)
			(size 0.4572 0.4572)
			(layers "F.Cu" "F.Mask" "F.Paste")
			(net "P0V8_PEX0")
		)
		(pad "AF23" smd circle
			(at -1.89992 0.94996)
			(size 0.4572 0.4572)
			(layers "F.Cu" "F.Mask" "F.Paste")
			(net "GND")
		)
		(pad "AF24" smd circle
			(at -0.94996 0.94996)
			(size 0.4572 0.4572)
			(layers "F.Cu" "F.Mask" "F.Paste")
			(net "P0V8_PEX0")
		)
		(pad "AF25" smd circle
			(at 0 0.94996)
			(size 0.4572 0.4572)
			(layers "F.Cu" "F.Mask" "F.Paste")
			(net "GND")
		)
		(pad "AF26" smd circle
			(at 0.94996 0.94996)
			(size 0.4572 0.4572)
			(layers "F.Cu" "F.Mask" "F.Paste")
			(net "P0V8_PEX0")
		)
		(pad "AF27" smd circle
			(at 1.89992 0.94996)
			(size 0.4572 0.4572)
			(layers "F.Cu" "F.Mask" "F.Paste")
			(net "GND")
		)
		(pad "AF28" smd circle
			(at 2.84988 0.94996)
			(size 0.4572 0.4572)
			(layers "F.Cu" "F.Mask" "F.Paste")
			(net "P0V8_PEX0")
		)
		(pad "AF29" smd circle
			(at 3.800094 0.94996)
			(size 0.4572 0.4572)
			(layers "F.Cu" "F.Mask" "F.Paste")
			(net "GND")
		)
		(pad "AF30" smd circle
			(at 4.750054 0.94996)
			(size 0.4572 0.4572)
			(layers "F.Cu" "F.Mask" "F.Paste")
			(net "P0V8_PEX0")
		)
		(pad "AF31" smd circle
			(at 5.700014 0.94996)
			(size 0.4572 0.4572)
			(layers "F.Cu" "F.Mask" "F.Paste")
			(net "GND")
		)
		(pad "AF32" smd circle
			(at 6.649974 0.94996)
			(size 0.4572 0.4572)
			(layers "F.Cu" "F.Mask" "F.Paste")
			(net "P0V8_SERDES_VDDA_PEX0")
		)
		(pad "AF33" smd circle
			(at 7.599934 0.94996)
			(size 0.4572 0.4572)
			(layers "F.Cu" "F.Mask" "F.Paste")
			(net "P0V8_SERDES_VDDA_PEX0")
		)
		(pad "AF34" smd circle
			(at 8.549894 0.94996)
			(size 0.4572 0.4572)
			(layers "F.Cu" "F.Mask" "F.Paste")
			(net "P0V8_SERDES_VDDA_PEX0")
		)
		(pad "AF35" smd circle
			(at 9.500108 0.94996)
			(size 0.4572 0.4572)
			(layers "F.Cu" "F.Mask" "F.Paste")
			(net "GND")
		)
		(pad "AF36" smd circle
			(at 10.450068 0.94996)
			(size 0.4572 0.4572)
			(layers "F.Cu" "F.Mask" "F.Paste")
			(net "P1V25_PEX0")
		)
		(pad "AF37" smd circle
			(at 11.400028 0.94996)
			(size 0.4572 0.4572)
			(layers "F.Cu" "F.Mask" "F.Paste")
			(net "GND")
		)
		(pad "AF38" smd circle
			(at 12.349988 0.94996)
			(size 0.4572 0.4572)
			(layers "F.Cu" "F.Mask" "F.Paste")
			(net "P1V25_SERDES_VDDPLL_PEX0")
		)
		(pad "AF39" smd circle
			(at 13.299948 0.94996)
			(size 0.4572 0.4572)
			(layers "F.Cu" "F.Mask" "F.Paste")
			(net "GND")
		)
		(pad "AF40" smd circle
			(at 14.249908 0.94996)
			(size 0.4572 0.4572)
			(layers "F.Cu" "F.Mask" "F.Paste")
			(net "GND")
		)
		(pad "AF41" smd circle
			(at 15.200122 0.94996)
			(size 0.4572 0.4572)
			(layers "F.Cu" "F.Mask" "F.Paste")
			(net "Net_2823")
		)
		(pad "AF42" smd circle
			(at 16.150082 0.94996)
			(size 0.4572 0.4572)
			(layers "F.Cu" "F.Mask" "F.Paste")
			(net "Net_2807")
		)
		(pad "AF43" smd circle
			(at 17.100042 0.94996)
			(size 0.4572 0.4572)
			(layers "F.Cu" "F.Mask" "F.Paste")
			(net "GND")
		)
		(pad "AF44" smd circle
			(at 18.050002 0.94996)
			(size 0.4572 0.4572)
			(layers "F.Cu" "F.Mask" "F.Paste")
			(net "GND")
		)
		(pad "AF45" smd circle
			(at 18.999962 0.94996)
			(size 0.4572 0.4572)
			(layers "F.Cu" "F.Mask" "F.Paste")
			(net "GND")
		)
		(pad "AF46" smd circle
			(at 19.949922 0.94996)
			(size 0.4572 0.4572)
			(layers "F.Cu" "F.Mask" "F.Paste")
			(net "GND")
		)
		(pad "AF47" smd circle
			(at 20.899882 0.94996)
			(size 0.4572 0.4572)
			(layers "F.Cu" "F.Mask" "F.Paste")
			(net "GND")
		)
		(pad "AF48" smd circle
			(at 21.850096 0.94996)
			(size 0.4572 0.4572)
			(layers "F.Cu" "F.Mask" "F.Paste")
			(net "Net_2791")
		)
		(pad "AF49" smd circle
			(at 22.800056 0.94996)
			(size 0.4572 0.4572)
			(layers "F.Cu" "F.Mask" "F.Paste")
			(net "Net_2775")
		)
		(pad "AG1" smd circle
			(at -22.800056 1.89992)
			(size 0.4572 0.4572)
			(layers "F.Cu" "F.Mask" "F.Paste")
			(net "Net_2834")
		)
		(pad "AG2" smd circle
			(at -21.850096 1.89992)
			(size 0.4572 0.4572)
			(layers "F.Cu" "F.Mask" "F.Paste")
			(net "Net_2835")
		)
		(pad "AG3" smd circle
			(at -20.899882 1.89992)
			(size 0.4572 0.4572)
			(layers "F.Cu" "F.Mask" "F.Paste")
			(net "GND")
		)
		(pad "AG4" smd circle
			(at -19.949922 1.89992)
			(size 0.4572 0.4572)
			(layers "F.Cu" "F.Mask" "F.Paste")
			(net "GND")
		)
		(pad "AG5" smd circle
			(at -18.999962 1.89992)
			(size 0.4572 0.4572)
			(layers "F.Cu" "F.Mask" "F.Paste")
			(net "GND")
		)
		(pad "AG6" smd circle
			(at -18.050002 1.89992)
			(size 0.4572 0.4572)
			(layers "F.Cu" "F.Mask" "F.Paste")
			(net "GND")
		)
		(pad "AG7" smd circle
			(at -17.100042 1.89992)
			(size 0.4572 0.4572)
			(layers "F.Cu" "F.Mask" "F.Paste")
			(net "SPI_PEX0_RST_N")
		)
		(pad "AG8" smd circle
			(at -16.150082 1.89992)
			(size 0.4572 0.4572)
			(layers "F.Cu" "F.Mask" "F.Paste")
			(net "SPI_PEX0_SDIO2")
		)
		(pad "AG9" smd circle
			(at -15.200122 1.89992)
			(size 0.4572 0.4572)
			(layers "F.Cu" "F.Mask" "F.Paste")
			(net "GND")
		)
		(pad "AG10" smd circle
			(at -14.249908 1.89992)
			(size 0.4572 0.4572)
			(layers "F.Cu" "F.Mask" "F.Paste")
			(net "GND")
		)
		(pad "AG11" smd circle
			(at -13.299948 1.89992)
			(size 0.4572 0.4572)
			(layers "F.Cu" "F.Mask" "F.Paste")
			(net "GND")
		)
		(pad "AG12" smd circle
			(at -12.349988 1.89992)
			(size 0.4572 0.4572)
			(layers "F.Cu" "F.Mask" "F.Paste")
			(net "GND")
		)
		(pad "AG13" smd circle
			(at -11.400028 1.89992)
			(size 0.4572 0.4572)
			(layers "F.Cu" "F.Mask" "F.Paste")
			(net "PCEPLL5_VDDA18_PEX0")
		)
		(pad "AG14" smd circle
			(at -10.450068 1.89992)
			(size 0.4572 0.4572)
			(layers "F.Cu" "F.Mask" "F.Paste")
			(net "GND")
		)
		(pad "AG15" smd circle
			(at -9.500108 1.89992)
			(size 0.4572 0.4572)
			(layers "F.Cu" "F.Mask" "F.Paste")
			(net "P0V8_PEX0")
		)
		(pad "AG16" smd circle
			(at -8.549894 1.89992)
			(size 0.4572 0.4572)
			(layers "F.Cu" "F.Mask" "F.Paste")
			(net "GND")
		)
		(pad "AG17" smd circle
			(at -7.599934 1.89992)
			(size 0.4572 0.4572)
			(layers "F.Cu" "F.Mask" "F.Paste")
			(net "P0V8_PEX0")
		)
		(pad "AG18" smd circle
			(at -6.649974 1.89992)
			(size 0.4572 0.4572)
			(layers "F.Cu" "F.Mask" "F.Paste")
			(net "GND")
		)
		(pad "AG19" smd circle
			(at -5.700014 1.89992)
			(size 0.4572 0.4572)
			(layers "F.Cu" "F.Mask" "F.Paste")
			(net "P0V8_PEX0")
		)
		(pad "AG20" smd circle
			(at -4.750054 1.89992)
			(size 0.4572 0.4572)
			(layers "F.Cu" "F.Mask" "F.Paste")
			(net "GND")
		)
		(pad "AG21" smd circle
			(at -3.800094 1.89992)
			(size 0.4572 0.4572)
			(layers "F.Cu" "F.Mask" "F.Paste")
			(net "P0V8_PEX0")
		)
		(pad "AG22" smd circle
			(at -2.84988 1.89992)
			(size 0.4572 0.4572)
			(layers "F.Cu" "F.Mask" "F.Paste")
			(net "GND")
		)
		(pad "AG23" smd circle
			(at -1.89992 1.89992)
			(size 0.4572 0.4572)
			(layers "F.Cu" "F.Mask" "F.Paste")
			(net "P0V8_PEX0")
		)
		(pad "AG24" smd circle
			(at -0.94996 1.89992)
			(size 0.4572 0.4572)
			(layers "F.Cu" "F.Mask" "F.Paste")
			(net "GND")
		)
		(pad "AG25" smd circle
			(at 0 1.89992)
			(size 0.4572 0.4572)
			(layers "F.Cu" "F.Mask" "F.Paste")
			(net "P0V8_PEX0")
		)
		(pad "AG26" smd circle
			(at 0.94996 1.89992)
			(size 0.4572 0.4572)
			(layers "F.Cu" "F.Mask" "F.Paste")
			(net "GND")
		)
		(pad "AG27" smd circle
			(at 1.89992 1.89992)
			(size 0.4572 0.4572)
			(layers "F.Cu" "F.Mask" "F.Paste")
			(net "P0V8_PEX0")
		)
		(pad "AG28" smd circle
			(at 2.84988 1.89992)
			(size 0.4572 0.4572)
			(layers "F.Cu" "F.Mask" "F.Paste")
			(net "GND")
		)
		(pad "AG29" smd circle
			(at 3.800094 1.89992)
			(size 0.4572 0.4572)
			(layers "F.Cu" "F.Mask" "F.Paste")
			(net "P0V8_PEX0")
		)
		(pad "AG30" smd circle
			(at 4.750054 1.89992)
			(size 0.4572 0.4572)
			(layers "F.Cu" "F.Mask" "F.Paste")
			(net "GND")
		)
		(pad "AG31" smd circle
			(at 5.700014 1.89992)
			(size 0.4572 0.4572)
			(layers "F.Cu" "F.Mask" "F.Paste")
			(net "P0V8_PEX0")
		)
		(pad "AG32" smd circle
			(at 6.649974 1.89992)
			(size 0.4572 0.4572)
			(layers "F.Cu" "F.Mask" "F.Paste")
			(net "GND")
		)
		(pad "AG33" smd circle
			(at 7.599934 1.89992)
			(size 0.4572 0.4572)
			(layers "F.Cu" "F.Mask" "F.Paste")
			(net "P0V8_PEX0")
		)
		(pad "AG34" smd circle
			(at 8.549894 1.89992)
			(size 0.4572 0.4572)
			(layers "F.Cu" "F.Mask" "F.Paste")
			(net "GND")
		)
		(pad "AG35" smd circle
			(at 9.500108 1.89992)
			(size 0.4572 0.4572)
			(layers "F.Cu" "F.Mask" "F.Paste")
			(net "GND")
		)
		(pad "AG36" smd circle
			(at 10.450068 1.89992)
			(size 0.4572 0.4572)
			(layers "F.Cu" "F.Mask" "F.Paste")
			(net "P1V25_PEX0")
		)
		(pad "AG37" smd circle
			(at 11.400028 1.89992)
			(size 0.4572 0.4572)
			(layers "F.Cu" "F.Mask" "F.Paste")
			(net "GND")
		)
		(pad "AG38" smd circle
			(at 12.349988 1.89992)
			(size 0.4572 0.4572)
			(layers "F.Cu" "F.Mask" "F.Paste")
			(net "P1V25_SERDES_VDDPLL_PEX0")
		)
		(pad "AG39" smd circle
			(at 13.299948 1.89992)
			(size 0.4572 0.4572)
			(layers "F.Cu" "F.Mask" "F.Paste")
			(net "GND")
		)
		(pad "AG40" smd circle
			(at 14.249908 1.89992)
			(size 0.4572 0.4572)
			(layers "F.Cu" "F.Mask" "F.Paste")
			(net "GND")
		)
		(pad "AG41" smd circle
			(at 15.200122 1.89992)
			(size 0.4572 0.4572)
			(layers "F.Cu" "F.Mask" "F.Paste")
			(net "GND")
		)
		(pad "AG42" smd circle
			(at 16.150082 1.89992)
			(size 0.4572 0.4572)
			(layers "F.Cu" "F.Mask" "F.Paste")
			(net "GND")
		)
		(pad "AG43" smd circle
			(at 17.100042 1.89992)
			(size 0.4572 0.4572)
			(layers "F.Cu" "F.Mask" "F.Paste")
			(net "Net_2824")
		)
		(pad "AG44" smd circle
			(at 18.050002 1.89992)
			(size 0.4572 0.4572)
			(layers "F.Cu" "F.Mask" "F.Paste")
			(net "Net_2808")
		)
		(pad "AG45" smd circle
			(at 18.999962 1.89992)
			(size 0.4572 0.4572)
			(layers "F.Cu" "F.Mask" "F.Paste")
			(net "GND")
		)
		(pad "AG46" smd circle
			(at 19.949922 1.89992)
			(size 0.4572 0.4572)
			(layers "F.Cu" "F.Mask" "F.Paste")
			(net "Net_2792")
		)
		(pad "AG47" smd circle
			(at 20.899882 1.89992)
			(size 0.4572 0.4572)
			(layers "F.Cu" "F.Mask" "F.Paste")
			(net "Net_2776")
		)
		(pad "AG48" smd circle
			(at 21.850096 1.89992)
			(size 0.4572 0.4572)
			(layers "F.Cu" "F.Mask" "F.Paste")
			(net "GND")
		)
		(pad "AG49" smd circle
			(at 22.800056 1.89992)
			(size 0.4572 0.4572)
			(layers "F.Cu" "F.Mask" "F.Paste")
			(net "GND")
		)
		(pad "AH1" smd circle
			(at -22.800056 2.84988)
			(size 0.4572 0.4572)
			(layers "F.Cu" "F.Mask" "F.Paste")
			(net "GND")
		)
		(pad "AH2" smd circle
			(at -21.850096 2.84988)
			(size 0.4572 0.4572)
			(layers "F.Cu" "F.Mask" "F.Paste")
			(net "GND")
		)
		(pad "AH3" smd circle
			(at -20.899882 2.84988)
			(size 0.4572 0.4572)
			(layers "F.Cu" "F.Mask" "F.Paste")
			(net "GND")
		)
		(pad "AH4" smd circle
			(at -19.949922 2.84988)
			(size 0.4572 0.4572)
			(layers "F.Cu" "F.Mask" "F.Paste")
			(net "Net_2837")
		)
		(pad "AH5" smd circle
			(at -18.999962 2.84988)
			(size 0.4572 0.4572)
			(layers "F.Cu" "F.Mask" "F.Paste")
			(net "Net_2838")
		)
		(pad "AH6" smd circle
			(at -18.050002 2.84988)
			(size 0.4572 0.4572)
			(layers "F.Cu" "F.Mask" "F.Paste")
			(net "GND")
		)
		(pad "AH7" smd circle
			(at -17.100042 2.84988)
			(size 0.4572 0.4572)
			(layers "F.Cu" "F.Mask" "F.Paste")
			(net "SPI_PEX0_CLK")
		)
		(pad "AH8" smd circle
			(at -16.150082 2.84988)
			(size 0.4572 0.4572)
			(layers "F.Cu" "F.Mask" "F.Paste")
			(net "SPI_PEX0_SDIO3")
		)
		(pad "AH9" smd circle
			(at -15.200122 2.84988)
			(size 0.4572 0.4572)
			(layers "F.Cu" "F.Mask" "F.Paste")
			(net "GND")
		)
		(pad "AH10" smd circle
			(at -14.249908 2.84988)
			(size 0.4572 0.4572)
			(layers "F.Cu" "F.Mask" "F.Paste")
			(net "P1V8_PEX")
		)
		(pad "AH11" smd circle
			(at -13.299948 2.84988)
			(size 0.4572 0.4572)
			(layers "F.Cu" "F.Mask" "F.Paste")
			(net "GND")
		)
		(pad "AH12" smd circle
			(at -12.349988 2.84988)
			(size 0.4572 0.4572)
			(layers "F.Cu" "F.Mask" "F.Paste")
			(net "PCEPLL6_VDDA18_PEX0")
		)
		(pad "AH13" smd circle
			(at -11.400028 2.84988)
			(size 0.4572 0.4572)
			(layers "F.Cu" "F.Mask" "F.Paste")
			(net "GND")
		)
		(pad "AH14" smd circle
			(at -10.450068 2.84988)
			(size 0.4572 0.4572)
			(layers "F.Cu" "F.Mask" "F.Paste")
			(net "P0V8_PEX0")
		)
		(pad "AH15" smd circle
			(at -9.500108 2.84988)
			(size 0.4572 0.4572)
			(layers "F.Cu" "F.Mask" "F.Paste")
			(net "GND")
		)
		(pad "AH16" smd circle
			(at -8.549894 2.84988)
			(size 0.4572 0.4572)
			(layers "F.Cu" "F.Mask" "F.Paste")
			(net "P0V8_SERDES_VDDA_PEX0")
		)
		(pad "AH17" smd circle
			(at -7.599934 2.84988)
			(size 0.4572 0.4572)
			(layers "F.Cu" "F.Mask" "F.Paste")
			(net "P0V8_SERDES_VDDA_PEX0")
		)
		(pad "AH18" smd circle
			(at -6.649974 2.84988)
			(size 0.4572 0.4572)
			(layers "F.Cu" "F.Mask" "F.Paste")
			(net "P0V8_SERDES_VDDA_PEX0")
		)
		(pad "AH19" smd circle
			(at -5.700014 2.84988)
			(size 0.4572 0.4572)
			(layers "F.Cu" "F.Mask" "F.Paste")
			(net "P0V8_SERDES_VDDA_PEX0")
		)
		(pad "AH20" smd circle
			(at -4.750054 2.84988)
			(size 0.4572 0.4572)
			(layers "F.Cu" "F.Mask" "F.Paste")
			(net "P0V8_SERDES_VDDA_PEX0")
		)
		(pad "AH21" smd circle
			(at -3.800094 2.84988)
			(size 0.4572 0.4572)
			(layers "F.Cu" "F.Mask" "F.Paste")
			(net "P0V8_SERDES_VDDA_PEX0")
		)
		(pad "AH22" smd circle
			(at -2.84988 2.84988)
			(size 0.4572 0.4572)
			(layers "F.Cu" "F.Mask" "F.Paste")
			(net "P0V8_SERDES_VDDA_PEX0")
		)
		(pad "AH23" smd circle
			(at -1.89992 2.84988)
			(size 0.4572 0.4572)
			(layers "F.Cu" "F.Mask" "F.Paste")
			(net "P0V8_SERDES_VDDA_PEX0")
		)
		(pad "AH24" smd circle
			(at -0.94996 2.84988)
			(size 0.4572 0.4572)
			(layers "F.Cu" "F.Mask" "F.Paste")
			(net "P0V8_SERDES_VDDA_PEX0")
		)
		(pad "AH25" smd circle
			(at 0 2.84988)
			(size 0.4572 0.4572)
			(layers "F.Cu" "F.Mask" "F.Paste")
			(net "P0V8_SERDES_VDDA_PEX0")
		)
		(pad "AH26" smd circle
			(at 0.94996 2.84988)
			(size 0.4572 0.4572)
			(layers "F.Cu" "F.Mask" "F.Paste")
			(net "P0V8_SERDES_VDDA_PEX0")
		)
		(pad "AH27" smd circle
			(at 1.89992 2.84988)
			(size 0.4572 0.4572)
			(layers "F.Cu" "F.Mask" "F.Paste")
			(net "P0V8_SERDES_VDDA_PEX0")
		)
		(pad "AH28" smd circle
			(at 2.84988 2.84988)
			(size 0.4572 0.4572)
			(layers "F.Cu" "F.Mask" "F.Paste")
			(net "P0V8_SERDES_VDDA_PEX0")
		)
		(pad "AH29" smd circle
			(at 3.800094 2.84988)
			(size 0.4572 0.4572)
			(layers "F.Cu" "F.Mask" "F.Paste")
			(net "P0V8_SERDES_VDDA_PEX0")
		)
		(pad "AH30" smd circle
			(at 4.750054 2.84988)
			(size 0.4572 0.4572)
			(layers "F.Cu" "F.Mask" "F.Paste")
			(net "P0V8_SERDES_VDDA_PEX0")
		)
		(pad "AH31" smd circle
			(at 5.700014 2.84988)
			(size 0.4572 0.4572)
			(layers "F.Cu" "F.Mask" "F.Paste")
			(net "P0V8_SERDES_VDDA_PEX0")
		)
		(pad "AH32" smd circle
			(at 6.649974 2.84988)
			(size 0.4572 0.4572)
			(layers "F.Cu" "F.Mask" "F.Paste")
			(net "P0V8_SERDES_VDDA_PEX0")
		)
		(pad "AH33" smd circle
			(at 7.599934 2.84988)
			(size 0.4572 0.4572)
			(layers "F.Cu" "F.Mask" "F.Paste")
			(net "P0V8_SERDES_VDDA_PEX0")
		)
		(pad "AH34" smd circle
			(at 8.549894 2.84988)
			(size 0.4572 0.4572)
			(layers "F.Cu" "F.Mask" "F.Paste")
			(net "GND")
		)
		(pad "AH35" smd circle
			(at 9.500108 2.84988)
			(size 0.4572 0.4572)
			(layers "F.Cu" "F.Mask" "F.Paste")
			(net "GND")
		)
		(pad "AH36" smd circle
			(at 10.450068 2.84988)
			(size 0.4572 0.4572)
			(layers "F.Cu" "F.Mask" "F.Paste")
			(net "GND")
		)
		(pad "AH37" smd circle
			(at 11.400028 2.84988)
			(size 0.4572 0.4572)
			(layers "F.Cu" "F.Mask" "F.Paste")
			(net "GND")
		)
		(pad "AH38" smd circle
			(at 12.349988 2.84988)
			(size 0.4572 0.4572)
			(layers "F.Cu" "F.Mask" "F.Paste")
			(net "GND")
		)
		(pad "AH39" smd circle
			(at 13.299948 2.84988)
			(size 0.4572 0.4572)
			(layers "F.Cu" "F.Mask" "F.Paste")
			(net "GND")
		)
		(pad "AH40" smd circle
			(at 14.249908 2.84988)
			(size 0.4572 0.4572)
			(layers "F.Cu" "F.Mask" "F.Paste")
			(net "GND")
		)
		(pad "AH41" smd circle
			(at 15.200122 2.84988)
			(size 0.4572 0.4572)
			(layers "F.Cu" "F.Mask" "F.Paste")
			(net "Net_2825")
		)
		(pad "AH42" smd circle
			(at 16.150082 2.84988)
			(size 0.4572 0.4572)
			(layers "F.Cu" "F.Mask" "F.Paste")
			(net "Net_2809")
		)
		(pad "AH43" smd circle
			(at 17.100042 2.84988)
			(size 0.4572 0.4572)
			(layers "F.Cu" "F.Mask" "F.Paste")
			(net "GND")
		)
		(pad "AH44" smd circle
			(at 18.050002 2.84988)
			(size 0.4572 0.4572)
			(layers "F.Cu" "F.Mask" "F.Paste")
			(net "GND")
		)
		(pad "AH45" smd circle
			(at 18.999962 2.84988)
			(size 0.4572 0.4572)
			(layers "F.Cu" "F.Mask" "F.Paste")
			(net "GND")
		)
		(pad "AH46" smd circle
			(at 19.949922 2.84988)
			(size 0.4572 0.4572)
			(layers "F.Cu" "F.Mask" "F.Paste")
			(net "GND")
		)
		(pad "AH47" smd circle
			(at 20.899882 2.84988)
			(size 0.4572 0.4572)
			(layers "F.Cu" "F.Mask" "F.Paste")
			(net "GND")
		)
		(pad "AH48" smd circle
			(at 21.850096 2.84988)
			(size 0.4572 0.4572)
			(layers "F.Cu" "F.Mask" "F.Paste")
			(net "Net_2793")
		)
		(pad "AH49" smd circle
			(at 22.800056 2.84988)
			(size 0.4572 0.4572)
			(layers "F.Cu" "F.Mask" "F.Paste")
			(net "Net_2777")
		)
		(pad "AJ1" smd circle
			(at -22.800056 3.800094)
			(size 0.4572 0.4572)
			(layers "F.Cu" "F.Mask" "F.Paste")
			(net "Net_2840")
		)
		(pad "AJ2" smd circle
			(at -21.850096 3.800094)
			(size 0.4572 0.4572)
			(layers "F.Cu" "F.Mask" "F.Paste")
			(net "Net_2841")
		)
		(pad "AJ3" smd circle
			(at -20.899882 3.800094)
			(size 0.4572 0.4572)
			(layers "F.Cu" "F.Mask" "F.Paste")
			(net "GND")
		)
		(pad "AJ4" smd circle
			(at -19.949922 3.800094)
			(size 0.4572 0.4572)
			(layers "F.Cu" "F.Mask" "F.Paste")
			(net "GND")
		)
		(pad "AJ5" smd circle
			(at -18.999962 3.800094)
			(size 0.4572 0.4572)
			(layers "F.Cu" "F.Mask" "F.Paste")
			(net "GND")
		)
		(pad "AJ6" smd circle
			(at -18.050002 3.800094)
			(size 0.4572 0.4572)
			(layers "F.Cu" "F.Mask" "F.Paste")
			(net "GND")
		)
		(pad "AJ7" smd circle
			(at -17.100042 3.800094)
			(size 0.4572 0.4572)
			(layers "F.Cu" "F.Mask" "F.Paste")
			(net "SPI_PEX0_CS_N")
		)
		(pad "AJ8" smd circle
			(at -16.150082 3.800094)
			(size 0.4572 0.4572)
			(layers "F.Cu" "F.Mask" "F.Paste")
			(net "Net_2911")
		)
		(pad "AJ9" smd circle
			(at -15.200122 3.800094)
			(size 0.4572 0.4572)
			(layers "F.Cu" "F.Mask" "F.Paste")
			(net "GND")
		)
		(pad "AJ10" smd circle
			(at -14.249908 3.800094)
			(size 0.4572 0.4572)
			(layers "F.Cu" "F.Mask" "F.Paste")
			(net "P1V8_PEX")
		)
		(pad "AJ11" smd circle
			(at -13.299948 3.800094)
			(size 0.4572 0.4572)
			(layers "F.Cu" "F.Mask" "F.Paste")
			(net "GND")
		)
		(pad "AJ12" smd circle
			(at -12.349988 3.800094)
			(size 0.4572 0.4572)
			(layers "F.Cu" "F.Mask" "F.Paste")
			(net "GND")
		)
		(pad "AJ13" smd circle
			(at -11.400028 3.800094)
			(size 0.4572 0.4572)
			(layers "F.Cu" "F.Mask" "F.Paste")
			(net "PCEPLL7_VDDA18_PEX0")
		)
		(pad "AJ14" smd circle
			(at -10.450068 3.800094)
			(size 0.4572 0.4572)
			(layers "F.Cu" "F.Mask" "F.Paste")
			(net "GND")
		)
		(pad "AJ15" smd circle
			(at -9.500108 3.800094)
			(size 0.4572 0.4572)
			(layers "F.Cu" "F.Mask" "F.Paste")
			(net "P0V8_PEX0")
		)
		(pad "AJ16" smd circle
			(at -8.549894 3.800094)
			(size 0.4572 0.4572)
			(layers "F.Cu" "F.Mask" "F.Paste")
			(net "GND")
		)
		(pad "AJ17" smd circle
			(at -7.599934 3.800094)
			(size 0.4572 0.4572)
			(layers "F.Cu" "F.Mask" "F.Paste")
			(net "GND")
		)
		(pad "AJ18" smd circle
			(at -6.649974 3.800094)
			(size 0.4572 0.4572)
			(layers "F.Cu" "F.Mask" "F.Paste")
			(net "GND")
		)
		(pad "AJ19" smd circle
			(at -5.700014 3.800094)
			(size 0.4572 0.4572)
			(layers "F.Cu" "F.Mask" "F.Paste")
			(net "GND")
		)
		(pad "AJ20" smd circle
			(at -4.750054 3.800094)
			(size 0.4572 0.4572)
			(layers "F.Cu" "F.Mask" "F.Paste")
			(net "GND")
		)
		(pad "AJ21" smd circle
			(at -3.800094 3.800094)
			(size 0.4572 0.4572)
			(layers "F.Cu" "F.Mask" "F.Paste")
			(net "GND")
		)
		(pad "AJ22" smd circle
			(at -2.84988 3.800094)
			(size 0.4572 0.4572)
			(layers "F.Cu" "F.Mask" "F.Paste")
			(net "GND")
		)
		(pad "AJ23" smd circle
			(at -1.89992 3.800094)
			(size 0.4572 0.4572)
			(layers "F.Cu" "F.Mask" "F.Paste")
			(net "GND")
		)
		(pad "AJ24" smd circle
			(at -0.94996 3.800094)
			(size 0.4572 0.4572)
			(layers "F.Cu" "F.Mask" "F.Paste")
			(net "GND")
		)
		(pad "AJ25" smd circle
			(at 0 3.800094)
			(size 0.4572 0.4572)
			(layers "F.Cu" "F.Mask" "F.Paste")
			(net "GND")
		)
		(pad "AJ26" smd circle
			(at 0.94996 3.800094)
			(size 0.4572 0.4572)
			(layers "F.Cu" "F.Mask" "F.Paste")
			(net "GND")
		)
		(pad "AJ27" smd circle
			(at 1.89992 3.800094)
			(size 0.4572 0.4572)
			(layers "F.Cu" "F.Mask" "F.Paste")
			(net "GND")
		)
		(pad "AJ28" smd circle
			(at 2.84988 3.800094)
			(size 0.4572 0.4572)
			(layers "F.Cu" "F.Mask" "F.Paste")
			(net "GND")
		)
		(pad "AJ29" smd circle
			(at 3.800094 3.800094)
			(size 0.4572 0.4572)
			(layers "F.Cu" "F.Mask" "F.Paste")
			(net "GND")
		)
		(pad "AJ30" smd circle
			(at 4.750054 3.800094)
			(size 0.4572 0.4572)
			(layers "F.Cu" "F.Mask" "F.Paste")
			(net "GND")
		)
		(pad "AJ31" smd circle
			(at 5.700014 3.800094)
			(size 0.4572 0.4572)
			(layers "F.Cu" "F.Mask" "F.Paste")
			(net "GND")
		)
		(pad "AJ32" smd circle
			(at 6.649974 3.800094)
			(size 0.4572 0.4572)
			(layers "F.Cu" "F.Mask" "F.Paste")
			(net "GND")
		)
		(pad "AJ33" smd circle
			(at 7.599934 3.800094)
			(size 0.4572 0.4572)
			(layers "F.Cu" "F.Mask" "F.Paste")
			(net "GND")
		)
		(pad "AJ34" smd circle
			(at 8.549894 3.800094)
			(size 0.4572 0.4572)
			(layers "F.Cu" "F.Mask" "F.Paste")
			(net "GND")
		)
		(pad "AJ35" smd circle
			(at 9.500108 3.800094)
			(size 0.4572 0.4572)
			(layers "F.Cu" "F.Mask" "F.Paste")
			(net "GND")
		)
		(pad "AJ36" smd circle
			(at 10.450068 3.800094)
			(size 0.4572 0.4572)
			(layers "F.Cu" "F.Mask" "F.Paste")
			(net "GND")
		)
		(pad "AJ37" smd circle
			(at 11.400028 3.800094)
			(size 0.4572 0.4572)
			(layers "F.Cu" "F.Mask" "F.Paste")
			(net "GND")
		)
		(pad "AJ38" smd circle
			(at 12.349988 3.800094)
			(size 0.4572 0.4572)
			(layers "F.Cu" "F.Mask" "F.Paste")
			(net "UART_PEX0_CLI_TX")
		)
		(pad "AJ39" smd circle
			(at 13.299948 3.800094)
			(size 0.4572 0.4572)
			(layers "F.Cu" "F.Mask" "F.Paste")
			(net "Net_2846")
		)
		(pad "AJ40" smd circle
			(at 14.249908 3.800094)
			(size 0.4572 0.4572)
			(layers "F.Cu" "F.Mask" "F.Paste")
			(net "GND")
		)
		(pad "AJ41" smd circle
			(at 15.200122 3.800094)
			(size 0.4572 0.4572)
			(layers "F.Cu" "F.Mask" "F.Paste")
			(net "GND")
		)
		(pad "AJ42" smd circle
			(at 16.150082 3.800094)
			(size 0.4572 0.4572)
			(layers "F.Cu" "F.Mask" "F.Paste")
			(net "GND")
		)
		(pad "AJ43" smd circle
			(at 17.100042 3.800094)
			(size 0.4572 0.4572)
			(layers "F.Cu" "F.Mask" "F.Paste")
			(net "Net_2826")
		)
		(pad "AJ44" smd circle
			(at 18.050002 3.800094)
			(size 0.4572 0.4572)
			(layers "F.Cu" "F.Mask" "F.Paste")
			(net "Net_2810")
		)
		(pad "AJ45" smd circle
			(at 18.999962 3.800094)
			(size 0.4572 0.4572)
			(layers "F.Cu" "F.Mask" "F.Paste")
			(net "GND")
		)
		(pad "AJ46" smd circle
			(at 19.949922 3.800094)
			(size 0.4572 0.4572)
			(layers "F.Cu" "F.Mask" "F.Paste")
			(net "Net_2794")
		)
		(pad "AJ47" smd circle
			(at 20.899882 3.800094)
			(size 0.4572 0.4572)
			(layers "F.Cu" "F.Mask" "F.Paste")
			(net "Net_2778")
		)
		(pad "AJ48" smd circle
			(at 21.850096 3.800094)
			(size 0.4572 0.4572)
			(layers "F.Cu" "F.Mask" "F.Paste")
			(net "GND")
		)
		(pad "AJ49" smd circle
			(at 22.800056 3.800094)
			(size 0.4572 0.4572)
			(layers "F.Cu" "F.Mask" "F.Paste")
			(net "GND")
		)
		(pad "AK1" smd circle
			(at -22.800056 4.750054)
			(size 0.4572 0.4572)
			(layers "F.Cu" "F.Mask" "F.Paste")
			(net "GND")
		)
		(pad "AK2" smd circle
			(at -21.850096 4.750054)
			(size 0.4572 0.4572)
			(layers "F.Cu" "F.Mask" "F.Paste")
			(net "GND")
		)
		(pad "AK3" smd circle
			(at -20.899882 4.750054)
			(size 0.4572 0.4572)
			(layers "F.Cu" "F.Mask" "F.Paste")
			(net "GND")
		)
		(pad "AK4" smd circle
			(at -19.949922 4.750054)
			(size 0.4572 0.4572)
			(layers "F.Cu" "F.Mask" "F.Paste")
			(net "Net_494")
		)
		(pad "AK5" smd circle
			(at -18.999962 4.750054)
			(size 0.4572 0.4572)
			(layers "F.Cu" "F.Mask" "F.Paste")
			(net "Net_490")
		)
		(pad "AK6" smd circle
			(at -18.050002 4.750054)
			(size 0.4572 0.4572)
			(layers "F.Cu" "F.Mask" "F.Paste")
			(net "GND")
		)
		(pad "AK7" smd circle
			(at -17.100042 4.750054)
			(size 0.4572 0.4572)
			(layers "F.Cu" "F.Mask" "F.Paste")
			(net "Net_2910")
		)
		(pad "AK8" smd circle
			(at -16.150082 4.750054)
			(size 0.4572 0.4572)
			(layers "F.Cu" "F.Mask" "F.Paste")
			(net "GND")
		)
		(pad "AK9" smd circle
			(at -15.200122 4.750054)
			(size 0.4572 0.4572)
			(layers "F.Cu" "F.Mask" "F.Paste")
			(net "GND")
		)
		(pad "AK10" smd circle
			(at -14.249908 4.750054)
			(size 0.4572 0.4572)
			(layers "F.Cu" "F.Mask" "F.Paste")
			(net "P1V8_PEX")
		)
		(pad "AK11" smd circle
			(at -13.299948 4.750054)
			(size 0.4572 0.4572)
			(layers "F.Cu" "F.Mask" "F.Paste")
			(net "GND")
		)
		(pad "AK12" smd circle
			(at -12.349988 4.750054)
			(size 0.4572 0.4572)
			(layers "F.Cu" "F.Mask" "F.Paste")
			(net "P1V8_PEX")
		)
		(pad "AK13" smd circle
			(at -11.400028 4.750054)
			(size 0.4572 0.4572)
			(layers "F.Cu" "F.Mask" "F.Paste")
			(net "GND")
		)
		(pad "AK14" smd circle
			(at -10.450068 4.750054)
			(size 0.4572 0.4572)
			(layers "F.Cu" "F.Mask" "F.Paste")
			(net "P0V8_PEX0")
		)
		(pad "AK15" smd circle
			(at -9.500108 4.750054)
			(size 0.4572 0.4572)
			(layers "F.Cu" "F.Mask" "F.Paste")
			(net "GND")
		)
		(pad "AK16" smd circle
			(at -8.549894 4.750054)
			(size 0.4572 0.4572)
			(layers "F.Cu" "F.Mask" "F.Paste")
			(net "P0V8_SERDES_VDDA_PEX0")
		)
		(pad "AK17" smd circle
			(at -7.599934 4.750054)
			(size 0.4572 0.4572)
			(layers "F.Cu" "F.Mask" "F.Paste")
			(net "P0V8_SERDES_VDDA_PEX0")
		)
		(pad "AK18" smd circle
			(at -6.649974 4.750054)
			(size 0.4572 0.4572)
			(layers "F.Cu" "F.Mask" "F.Paste")
			(net "P0V8_SERDES_VDDA_PEX0")
		)
		(pad "AK19" smd circle
			(at -5.700014 4.750054)
			(size 0.4572 0.4572)
			(layers "F.Cu" "F.Mask" "F.Paste")
			(net "P0V8_SERDES_VDDA_PEX0")
		)
		(pad "AK20" smd circle
			(at -4.750054 4.750054)
			(size 0.4572 0.4572)
			(layers "F.Cu" "F.Mask" "F.Paste")
			(net "P0V8_SERDES_VDDA_PEX0")
		)
		(pad "AK21" smd circle
			(at -3.800094 4.750054)
			(size 0.4572 0.4572)
			(layers "F.Cu" "F.Mask" "F.Paste")
			(net "P0V8_SERDES_VDDA_PEX0")
		)
		(pad "AK22" smd circle
			(at -2.84988 4.750054)
			(size 0.4572 0.4572)
			(layers "F.Cu" "F.Mask" "F.Paste")
			(net "P0V8_SERDES_VDDA_PEX0")
		)
		(pad "AK23" smd circle
			(at -1.89992 4.750054)
			(size 0.4572 0.4572)
			(layers "F.Cu" "F.Mask" "F.Paste")
			(net "P0V8_SERDES_VDDA_PEX0")
		)
		(pad "AK24" smd circle
			(at -0.94996 4.750054)
			(size 0.4572 0.4572)
			(layers "F.Cu" "F.Mask" "F.Paste")
			(net "P0V8_SERDES_VDDA_PEX0")
		)
		(pad "AK25" smd circle
			(at 0 4.750054)
			(size 0.4572 0.4572)
			(layers "F.Cu" "F.Mask" "F.Paste")
			(net "P0V8_SERDES_VDDA_PEX0")
		)
		(pad "AK26" smd circle
			(at 0.94996 4.750054)
			(size 0.4572 0.4572)
			(layers "F.Cu" "F.Mask" "F.Paste")
			(net "P0V8_SERDES_VDDA_PEX0")
		)
		(pad "AK27" smd circle
			(at 1.89992 4.750054)
			(size 0.4572 0.4572)
			(layers "F.Cu" "F.Mask" "F.Paste")
			(net "P0V8_SERDES_VDDA_PEX0")
		)
		(pad "AK28" smd circle
			(at 2.84988 4.750054)
			(size 0.4572 0.4572)
			(layers "F.Cu" "F.Mask" "F.Paste")
			(net "P0V8_SERDES_VDDA_PEX0")
		)
		(pad "AK29" smd circle
			(at 3.800094 4.750054)
			(size 0.4572 0.4572)
			(layers "F.Cu" "F.Mask" "F.Paste")
			(net "P0V8_SERDES_VDDA_PEX0")
		)
		(pad "AK30" smd circle
			(at 4.750054 4.750054)
			(size 0.4572 0.4572)
			(layers "F.Cu" "F.Mask" "F.Paste")
			(net "P0V8_SERDES_VDDA_PEX0")
		)
		(pad "AK31" smd circle
			(at 5.700014 4.750054)
			(size 0.4572 0.4572)
			(layers "F.Cu" "F.Mask" "F.Paste")
			(net "P0V8_SERDES_VDDA_PEX0")
		)
		(pad "AK32" smd circle
			(at 6.649974 4.750054)
			(size 0.4572 0.4572)
			(layers "F.Cu" "F.Mask" "F.Paste")
			(net "P0V8_SERDES_VDDA_PEX0")
		)
		(pad "AK33" smd circle
			(at 7.599934 4.750054)
			(size 0.4572 0.4572)
			(layers "F.Cu" "F.Mask" "F.Paste")
			(net "P0V8_SERDES_VDDA_PEX0")
		)
		(pad "AK34" smd circle
			(at 8.549894 4.750054)
			(size 0.4572 0.4572)
			(layers "F.Cu" "F.Mask" "F.Paste")
			(net "GND")
		)
		(pad "AK35" smd circle
			(at 9.500108 4.750054)
			(size 0.4572 0.4572)
			(layers "F.Cu" "F.Mask" "F.Paste")
			(net "P1V8_PEX")
		)
		(pad "AK36" smd circle
			(at 10.450068 4.750054)
			(size 0.4572 0.4572)
			(layers "F.Cu" "F.Mask" "F.Paste")
			(net "GND")
		)
		(pad "AK37" smd circle
			(at 11.400028 4.750054)
			(size 0.4572 0.4572)
			(layers "F.Cu" "F.Mask" "F.Paste")
			(net "GND")
		)
		(pad "AK38" smd circle
			(at 12.349988 4.750054)
			(size 0.4572 0.4572)
			(layers "F.Cu" "F.Mask" "F.Paste")
			(net "UART_PEX0_CLI_BUF_RX")
		)
		(pad "AK39" smd circle
			(at 13.299948 4.750054)
			(size 0.4572 0.4572)
			(layers "F.Cu" "F.Mask" "F.Paste")
			(net "UART_PEX0_SDB_BUF_RX")
		)
		(pad "AK40" smd circle
			(at 14.249908 4.750054)
			(size 0.4572 0.4572)
			(layers "F.Cu" "F.Mask" "F.Paste")
			(net "GND")
		)
		(pad "AK41" smd circle
			(at 15.200122 4.750054)
			(size 0.4572 0.4572)
			(layers "F.Cu" "F.Mask" "F.Paste")
			(net "Net_2827")
		)
		(pad "AK42" smd circle
			(at 16.150082 4.750054)
			(size 0.4572 0.4572)
			(layers "F.Cu" "F.Mask" "F.Paste")
			(net "Net_2811")
		)
		(pad "AK43" smd circle
			(at 17.100042 4.750054)
			(size 0.4572 0.4572)
			(layers "F.Cu" "F.Mask" "F.Paste")
			(net "GND")
		)
		(pad "AK44" smd circle
			(at 18.050002 4.750054)
			(size 0.4572 0.4572)
			(layers "F.Cu" "F.Mask" "F.Paste")
			(net "GND")
		)
		(pad "AK45" smd circle
			(at 18.999962 4.750054)
			(size 0.4572 0.4572)
			(layers "F.Cu" "F.Mask" "F.Paste")
			(net "GND")
		)
		(pad "AK46" smd circle
			(at 19.949922 4.750054)
			(size 0.4572 0.4572)
			(layers "F.Cu" "F.Mask" "F.Paste")
			(net "GND")
		)
		(pad "AK47" smd circle
			(at 20.899882 4.750054)
			(size 0.4572 0.4572)
			(layers "F.Cu" "F.Mask" "F.Paste")
			(net "GND")
		)
		(pad "AK48" smd circle
			(at 21.850096 4.750054)
			(size 0.4572 0.4572)
			(layers "F.Cu" "F.Mask" "F.Paste")
			(net "Net_2795")
		)
		(pad "AK49" smd circle
			(at 22.800056 4.750054)
			(size 0.4572 0.4572)
			(layers "F.Cu" "F.Mask" "F.Paste")
			(net "Net_2779")
		)
		(pad "AL1" smd circle
			(at -22.800056 5.700014)
			(size 0.4572 0.4572)
			(layers "F.Cu" "F.Mask" "F.Paste")
			(net "GND")
		)
		(pad "AL2" smd circle
			(at -21.850096 5.700014)
			(size 0.4572 0.4572)
			(layers "F.Cu" "F.Mask" "F.Paste")
			(net "GND")
		)
		(pad "AL3" smd circle
			(at -20.899882 5.700014)
			(size 0.4572 0.4572)
			(layers "F.Cu" "F.Mask" "F.Paste")
			(net "GND")
		)
		(pad "AL4" smd circle
			(at -19.949922 5.700014)
			(size 0.4572 0.4572)
			(layers "F.Cu" "F.Mask" "F.Paste")
			(net "GND")
		)
		(pad "AL5" smd circle
			(at -18.999962 5.700014)
			(size 0.4572 0.4572)
			(layers "F.Cu" "F.Mask" "F.Paste")
			(net "GND")
		)
		(pad "AL6" smd circle
			(at -18.050002 5.700014)
			(size 0.4572 0.4572)
			(layers "F.Cu" "F.Mask" "F.Paste")
			(net "GND")
		)
		(pad "AL7" smd circle
			(at -17.100042 5.700014)
			(size 0.4572 0.4572)
			(layers "F.Cu" "F.Mask" "F.Paste")
			(net "GND")
		)
		(pad "AL8" smd circle
			(at -16.150082 5.700014)
			(size 0.4572 0.4572)
			(layers "F.Cu" "F.Mask" "F.Paste")
			(net "GND")
		)
		(pad "AL9" smd circle
			(at -15.200122 5.700014)
			(size 0.4572 0.4572)
			(layers "F.Cu" "F.Mask" "F.Paste")
			(net "GND")
		)
		(pad "AL10" smd circle
			(at -14.249908 5.700014)
			(size 0.4572 0.4572)
			(layers "F.Cu" "F.Mask" "F.Paste")
			(net "GND")
		)
		(pad "AL11" smd circle
			(at -13.299948 5.700014)
			(size 0.4572 0.4572)
			(layers "F.Cu" "F.Mask" "F.Paste")
			(net "GND")
		)
		(pad "AL12" smd circle
			(at -12.349988 5.700014)
			(size 0.4572 0.4572)
			(layers "F.Cu" "F.Mask" "F.Paste")
			(net "GND")
		)
		(pad "AL13" smd circle
			(at -11.400028 5.700014)
			(size 0.4572 0.4572)
			(layers "F.Cu" "F.Mask" "F.Paste")
			(net "GND")
		)
		(pad "AL14" smd circle
			(at -10.450068 5.700014)
			(size 0.4572 0.4572)
			(layers "F.Cu" "F.Mask" "F.Paste")
			(net "VSSA_SENSE")
		)
		(pad "AL15" smd circle
			(at -9.500108 5.700014)
			(size 0.4572 0.4572)
			(layers "F.Cu" "F.Mask" "F.Paste")
			(net "VDDA_SENSE")
		)
		(pad "AL16" smd circle
			(at -8.549894 5.700014)
			(size 0.4572 0.4572)
			(layers "F.Cu" "F.Mask" "F.Paste")
			(net "GND")
		)
		(pad "AL17" smd circle
			(at -7.599934 5.700014)
			(size 0.4572 0.4572)
			(layers "F.Cu" "F.Mask" "F.Paste")
			(net "GND")
		)
		(pad "AL18" smd circle
			(at -6.649974 5.700014)
			(size 0.4572 0.4572)
			(layers "F.Cu" "F.Mask" "F.Paste")
			(net "GND")
		)
		(pad "AL19" smd circle
			(at -5.700014 5.700014)
			(size 0.4572 0.4572)
			(layers "F.Cu" "F.Mask" "F.Paste")
			(net "GND")
		)
		(pad "AL20" smd circle
			(at -4.750054 5.700014)
			(size 0.4572 0.4572)
			(layers "F.Cu" "F.Mask" "F.Paste")
			(net "GND")
		)
		(pad "AL21" smd circle
			(at -3.800094 5.700014)
			(size 0.4572 0.4572)
			(layers "F.Cu" "F.Mask" "F.Paste")
			(net "GND")
		)
		(pad "AL22" smd circle
			(at -2.84988 5.700014)
			(size 0.4572 0.4572)
			(layers "F.Cu" "F.Mask" "F.Paste")
			(net "GND")
		)
		(pad "AL23" smd circle
			(at -1.89992 5.700014)
			(size 0.4572 0.4572)
			(layers "F.Cu" "F.Mask" "F.Paste")
			(net "GND")
		)
		(pad "AL24" smd circle
			(at -0.94996 5.700014)
			(size 0.4572 0.4572)
			(layers "F.Cu" "F.Mask" "F.Paste")
			(net "GND")
		)
		(pad "AL25" smd circle
			(at 0 5.700014)
			(size 0.4572 0.4572)
			(layers "F.Cu" "F.Mask" "F.Paste")
			(net "GND")
		)
		(pad "AL26" smd circle
			(at 0.94996 5.700014)
			(size 0.4572 0.4572)
			(layers "F.Cu" "F.Mask" "F.Paste")
			(net "GND")
		)
		(pad "AL27" smd circle
			(at 1.89992 5.700014)
			(size 0.4572 0.4572)
			(layers "F.Cu" "F.Mask" "F.Paste")
			(net "GND")
		)
		(pad "AL28" smd circle
			(at 2.84988 5.700014)
			(size 0.4572 0.4572)
			(layers "F.Cu" "F.Mask" "F.Paste")
			(net "GND")
		)
		(pad "AL29" smd circle
			(at 3.800094 5.700014)
			(size 0.4572 0.4572)
			(layers "F.Cu" "F.Mask" "F.Paste")
			(net "GND")
		)
		(pad "AL30" smd circle
			(at 4.750054 5.700014)
			(size 0.4572 0.4572)
			(layers "F.Cu" "F.Mask" "F.Paste")
			(net "GND")
		)
		(pad "AL31" smd circle
			(at 5.700014 5.700014)
			(size 0.4572 0.4572)
			(layers "F.Cu" "F.Mask" "F.Paste")
			(net "GND")
		)
		(pad "AL32" smd circle
			(at 6.649974 5.700014)
			(size 0.4572 0.4572)
			(layers "F.Cu" "F.Mask" "F.Paste")
			(net "GND")
		)
		(pad "AL33" smd circle
			(at 7.599934 5.700014)
			(size 0.4572 0.4572)
			(layers "F.Cu" "F.Mask" "F.Paste")
			(net "GND")
		)
		(pad "AL34" smd circle
			(at 8.549894 5.700014)
			(size 0.4572 0.4572)
			(layers "F.Cu" "F.Mask" "F.Paste")
			(net "GND")
		)
		(pad "AL35" smd circle
			(at 9.500108 5.700014)
			(size 0.4572 0.4572)
			(layers "F.Cu" "F.Mask" "F.Paste")
			(net "P1V8_PEX")
		)
		(pad "AL36" smd circle
			(at 10.450068 5.700014)
			(size 0.4572 0.4572)
			(layers "F.Cu" "F.Mask" "F.Paste")
			(net "GND")
		)
		(pad "AL37" smd circle
			(at 11.400028 5.700014)
			(size 0.4572 0.4572)
			(layers "F.Cu" "F.Mask" "F.Paste")
			(net "GND")
		)
		(pad "AL38" smd circle
			(at 12.349988 5.700014)
			(size 0.4572 0.4572)
			(layers "F.Cu" "F.Mask" "F.Paste")
			(net "Net_2877")
		)
		(pad "AL39" smd circle
			(at 13.299948 5.700014)
			(size 0.4572 0.4572)
			(layers "F.Cu" "F.Mask" "F.Paste")
			(net "UART_PEX0_SDB_TX")
		)
		(pad "AL40" smd circle
			(at 14.249908 5.700014)
			(size 0.4572 0.4572)
			(layers "F.Cu" "F.Mask" "F.Paste")
			(net "GND")
		)
		(pad "AL41" smd circle
			(at 15.200122 5.700014)
			(size 0.4572 0.4572)
			(layers "F.Cu" "F.Mask" "F.Paste")
			(net "GND")
		)
		(pad "AL42" smd circle
			(at 16.150082 5.700014)
			(size 0.4572 0.4572)
			(layers "F.Cu" "F.Mask" "F.Paste")
			(net "GND")
		)
		(pad "AL43" smd circle
			(at 17.100042 5.700014)
			(size 0.4572 0.4572)
			(layers "F.Cu" "F.Mask" "F.Paste")
			(net "Net_2828")
		)
		(pad "AL44" smd circle
			(at 18.050002 5.700014)
			(size 0.4572 0.4572)
			(layers "F.Cu" "F.Mask" "F.Paste")
			(net "Net_2812")
		)
		(pad "AL45" smd circle
			(at 18.999962 5.700014)
			(size 0.4572 0.4572)
			(layers "F.Cu" "F.Mask" "F.Paste")
			(net "GND")
		)
		(pad "AL46" smd circle
			(at 19.949922 5.700014)
			(size 0.4572 0.4572)
			(layers "F.Cu" "F.Mask" "F.Paste")
			(net "Net_2796")
		)
		(pad "AL47" smd circle
			(at 20.899882 5.700014)
			(size 0.4572 0.4572)
			(layers "F.Cu" "F.Mask" "F.Paste")
			(net "Net_2780")
		)
		(pad "AL48" smd circle
			(at 21.850096 5.700014)
			(size 0.4572 0.4572)
			(layers "F.Cu" "F.Mask" "F.Paste")
			(net "GND")
		)
		(pad "AL49" smd circle
			(at 22.800056 5.700014)
			(size 0.4572 0.4572)
			(layers "F.Cu" "F.Mask" "F.Paste")
			(net "GND")
		)
		(pad "AM1" smd circle
			(at -22.800056 6.649974)
			(size 0.4572 0.4572)
			(layers "F.Cu" "F.Mask" "F.Paste")
			(net "P4E_PEX0_STN3_RX_DN<48>")
		)
		(pad "AM2" smd circle
			(at -21.850096 6.649974)
			(size 0.4572 0.4572)
			(layers "F.Cu" "F.Mask" "F.Paste")
			(net "P4E_PEX0_STN3_RX_DP<48>")
		)
		(pad "AM3" smd circle
			(at -20.899882 6.649974)
			(size 0.4572 0.4572)
			(layers "F.Cu" "F.Mask" "F.Paste")
			(net "GND")
		)
		(pad "AM4" smd circle
			(at -19.949922 6.649974)
			(size 0.4572 0.4572)
			(layers "F.Cu" "F.Mask" "F.Paste")
			(net "GND")
		)
		(pad "AM5" smd circle
			(at -18.999962 6.649974)
			(size 0.4572 0.4572)
			(layers "F.Cu" "F.Mask" "F.Paste")
			(net "GND")
		)
		(pad "AM6" smd circle
			(at -18.050002 6.649974)
			(size 0.4572 0.4572)
			(layers "F.Cu" "F.Mask" "F.Paste")
			(net "GND")
		)
		(pad "AM7" smd circle
			(at -17.100042 6.649974)
			(size 0.4572 0.4572)
			(layers "F.Cu" "F.Mask" "F.Paste")
			(net "GND")
		)
		(pad "AM8" smd circle
			(at -16.150082 6.649974)
			(size 0.4572 0.4572)
			(layers "F.Cu" "F.Mask" "F.Paste")
			(net "P4E_PEX0_STN3_TX_DN<48>")
		)
		(pad "AM9" smd circle
			(at -15.200122 6.649974)
			(size 0.4572 0.4572)
			(layers "F.Cu" "F.Mask" "F.Paste")
			(net "P4E_PEX0_STN3_TX_DP<48>")
		)
		(pad "AM10" smd circle
			(at -14.249908 6.649974)
			(size 0.4572 0.4572)
			(layers "F.Cu" "F.Mask" "F.Paste")
			(net "GND")
		)
		(pad "AM11" smd circle
			(at -13.299948 6.649974)
			(size 0.4572 0.4572)
			(layers "F.Cu" "F.Mask" "F.Paste")
			(net "GND")
		)
		(pad "AM12" smd circle
			(at -12.349988 6.649974)
			(size 0.4572 0.4572)
			(layers "F.Cu" "F.Mask" "F.Paste")
			(net "TP_PEX0_VDDQ_EFUSE")
		)
		(pad "AM13" smd circle
			(at -11.400028 6.649974)
			(size 0.4572 0.4572)
			(layers "F.Cu" "F.Mask" "F.Paste")
			(net "GND")
		)
		(pad "AM14" smd circle
			(at -10.450068 6.649974)
			(size 0.4572 0.4572)
			(layers "F.Cu" "F.Mask" "F.Paste")
			(net "P1V8_VDDA_PEX0")
		)
		(pad "AM15" smd circle
			(at -9.500108 6.649974)
			(size 0.4572 0.4572)
			(layers "F.Cu" "F.Mask" "F.Paste")
			(net "GND")
		)
		(pad "AM16" smd circle
			(at -8.549894 6.649974)
			(size 0.4572 0.4572)
			(layers "F.Cu" "F.Mask" "F.Paste")
			(net "P1V25_PEX0")
		)
		(pad "AM17" smd circle
			(at -7.599934 6.649974)
			(size 0.4572 0.4572)
			(layers "F.Cu" "F.Mask" "F.Paste")
			(net "P1V25_PEX0")
		)
		(pad "AM18" smd circle
			(at -6.649974 6.649974)
			(size 0.4572 0.4572)
			(layers "F.Cu" "F.Mask" "F.Paste")
			(net "P1V25_PEX0")
		)
		(pad "AM19" smd circle
			(at -5.700014 6.649974)
			(size 0.4572 0.4572)
			(layers "F.Cu" "F.Mask" "F.Paste")
			(net "P1V25_PEX0")
		)
		(pad "AM20" smd circle
			(at -4.750054 6.649974)
			(size 0.4572 0.4572)
			(layers "F.Cu" "F.Mask" "F.Paste")
			(net "P1V25_PEX0")
		)
		(pad "AM21" smd circle
			(at -3.800094 6.649974)
			(size 0.4572 0.4572)
			(layers "F.Cu" "F.Mask" "F.Paste")
			(net "P1V25_PEX0")
		)
		(pad "AM22" smd circle
			(at -2.84988 6.649974)
			(size 0.4572 0.4572)
			(layers "F.Cu" "F.Mask" "F.Paste")
			(net "P1V25_PEX0")
		)
		(pad "AM23" smd circle
			(at -1.89992 6.649974)
			(size 0.4572 0.4572)
			(layers "F.Cu" "F.Mask" "F.Paste")
			(net "P1V25_PEX0")
		)
		(pad "AM24" smd circle
			(at -0.94996 6.649974)
			(size 0.4572 0.4572)
			(layers "F.Cu" "F.Mask" "F.Paste")
			(net "P1V25_PEX0")
		)
		(pad "AM25" smd circle
			(at 0 6.649974)
			(size 0.4572 0.4572)
			(layers "F.Cu" "F.Mask" "F.Paste")
			(net "P1V25_PEX0")
		)
		(pad "AM26" smd circle
			(at 0.94996 6.649974)
			(size 0.4572 0.4572)
			(layers "F.Cu" "F.Mask" "F.Paste")
			(net "P1V25_PEX0")
		)
		(pad "AM27" smd circle
			(at 1.89992 6.649974)
			(size 0.4572 0.4572)
			(layers "F.Cu" "F.Mask" "F.Paste")
			(net "P1V25_PEX0")
		)
		(pad "AM28" smd circle
			(at 2.84988 6.649974)
			(size 0.4572 0.4572)
			(layers "F.Cu" "F.Mask" "F.Paste")
			(net "P1V25_PEX0")
		)
		(pad "AM29" smd circle
			(at 3.800094 6.649974)
			(size 0.4572 0.4572)
			(layers "F.Cu" "F.Mask" "F.Paste")
			(net "P1V25_PEX0")
		)
		(pad "AM30" smd circle
			(at 4.750054 6.649974)
			(size 0.4572 0.4572)
			(layers "F.Cu" "F.Mask" "F.Paste")
			(net "P1V25_PEX0")
		)
		(pad "AM31" smd circle
			(at 5.700014 6.649974)
			(size 0.4572 0.4572)
			(layers "F.Cu" "F.Mask" "F.Paste")
			(net "P1V25_PEX0")
		)
		(pad "AM32" smd circle
			(at 6.649974 6.649974)
			(size 0.4572 0.4572)
			(layers "F.Cu" "F.Mask" "F.Paste")
			(net "P1V25_PEX0")
		)
		(pad "AM33" smd circle
			(at 7.599934 6.649974)
			(size 0.4572 0.4572)
			(layers "F.Cu" "F.Mask" "F.Paste")
			(net "P1V25_PEX0")
		)
		(pad "AM34" smd circle
			(at 8.549894 6.649974)
			(size 0.4572 0.4572)
			(layers "F.Cu" "F.Mask" "F.Paste")
			(net "GND")
		)
		(pad "AM35" smd circle
			(at 9.500108 6.649974)
			(size 0.4572 0.4572)
			(layers "F.Cu" "F.Mask" "F.Paste")
			(net "P1V8_PEX")
		)
		(pad "AM36" smd circle
			(at 10.450068 6.649974)
			(size 0.4572 0.4572)
			(layers "F.Cu" "F.Mask" "F.Paste")
			(net "GND")
		)
		(pad "AM37" smd circle
			(at 11.400028 6.649974)
			(size 0.4572 0.4572)
			(layers "F.Cu" "F.Mask" "F.Paste")
			(net "GND")
		)
		(pad "AM38" smd circle
			(at 12.349988 6.649974)
			(size 0.4572 0.4572)
			(layers "F.Cu" "F.Mask" "F.Paste")
			(net "Net_2844")
		)
		(pad "AM39" smd circle
			(at 13.299948 6.649974)
			(size 0.4572 0.4572)
			(layers "F.Cu" "F.Mask" "F.Paste")
			(net "Net_2887")
		)
		(pad "AM40" smd circle
			(at 14.249908 6.649974)
			(size 0.4572 0.4572)
			(layers "F.Cu" "F.Mask" "F.Paste")
			(net "GND")
		)
		(pad "AM41" smd circle
			(at 15.200122 6.649974)
			(size 0.4572 0.4572)
			(layers "F.Cu" "F.Mask" "F.Paste")
			(net "Net_2829")
		)
		(pad "AM42" smd circle
			(at 16.150082 6.649974)
			(size 0.4572 0.4572)
			(layers "F.Cu" "F.Mask" "F.Paste")
			(net "Net_2813")
		)
		(pad "AM43" smd circle
			(at 17.100042 6.649974)
			(size 0.4572 0.4572)
			(layers "F.Cu" "F.Mask" "F.Paste")
			(net "GND")
		)
		(pad "AM44" smd circle
			(at 18.050002 6.649974)
			(size 0.4572 0.4572)
			(layers "F.Cu" "F.Mask" "F.Paste")
			(net "GND")
		)
		(pad "AM45" smd circle
			(at 18.999962 6.649974)
			(size 0.4572 0.4572)
			(layers "F.Cu" "F.Mask" "F.Paste")
			(net "GND")
		)
		(pad "AM46" smd circle
			(at 19.949922 6.649974)
			(size 0.4572 0.4572)
			(layers "F.Cu" "F.Mask" "F.Paste")
			(net "GND")
		)
		(pad "AM47" smd circle
			(at 20.899882 6.649974)
			(size 0.4572 0.4572)
			(layers "F.Cu" "F.Mask" "F.Paste")
			(net "GND")
		)
		(pad "AM48" smd circle
			(at 21.850096 6.649974)
			(size 0.4572 0.4572)
			(layers "F.Cu" "F.Mask" "F.Paste")
			(net "Net_2797")
		)
		(pad "AM49" smd circle
			(at 22.800056 6.649974)
			(size 0.4572 0.4572)
			(layers "F.Cu" "F.Mask" "F.Paste")
			(net "Net_2781")
		)
		(pad "AN1" smd circle
			(at -22.800056 7.599934)
			(size 0.4572 0.4572)
			(layers "F.Cu" "F.Mask" "F.Paste")
			(net "GND")
		)
		(pad "AN2" smd circle
			(at -21.850096 7.599934)
			(size 0.4572 0.4572)
			(layers "F.Cu" "F.Mask" "F.Paste")
			(net "GND")
		)
		(pad "AN3" smd circle
			(at -20.899882 7.599934)
			(size 0.4572 0.4572)
			(layers "F.Cu" "F.Mask" "F.Paste")
			(net "P4E_PEX0_STN3_RX_DN<49>")
		)
		(pad "AN4" smd circle
			(at -19.949922 7.599934)
			(size 0.4572 0.4572)
			(layers "F.Cu" "F.Mask" "F.Paste")
			(net "P4E_PEX0_STN3_RX_DP<49>")
		)
		(pad "AN5" smd circle
			(at -18.999962 7.599934)
			(size 0.4572 0.4572)
			(layers "F.Cu" "F.Mask" "F.Paste")
			(net "GND")
		)
		(pad "AN6" smd circle
			(at -18.050002 7.599934)
			(size 0.4572 0.4572)
			(layers "F.Cu" "F.Mask" "F.Paste")
			(net "P4E_PEX0_STN3_TX_DN<49>")
		)
		(pad "AN7" smd circle
			(at -17.100042 7.599934)
			(size 0.4572 0.4572)
			(layers "F.Cu" "F.Mask" "F.Paste")
			(net "P4E_PEX0_STN3_TX_DP<49>")
		)
		(pad "AN8" smd circle
			(at -16.150082 7.599934)
			(size 0.4572 0.4572)
			(layers "F.Cu" "F.Mask" "F.Paste")
			(net "GND")
		)
		(pad "AN9" smd circle
			(at -15.200122 7.599934)
			(size 0.4572 0.4572)
			(layers "F.Cu" "F.Mask" "F.Paste")
			(net "GND")
		)
		(pad "AN10" smd circle
			(at -14.249908 7.599934)
			(size 0.4572 0.4572)
			(layers "F.Cu" "F.Mask" "F.Paste")
			(net "GND")
		)
		(pad "AN11" smd circle
			(at -13.299948 7.599934)
			(size 0.4572 0.4572)
			(layers "F.Cu" "F.Mask" "F.Paste")
			(net "GND")
		)
		(pad "AN12" smd circle
			(at -12.349988 7.599934)
			(size 0.4572 0.4572)
			(layers "F.Cu" "F.Mask" "F.Paste")
			(net "GND")
		)
		(pad "AN13" smd circle
			(at -11.400028 7.599934)
			(size 0.4572 0.4572)
			(layers "F.Cu" "F.Mask" "F.Paste")
			(net "GND")
		)
		(pad "AN14" smd circle
			(at -10.450068 7.599934)
			(size 0.4572 0.4572)
			(layers "F.Cu" "F.Mask" "F.Paste")
			(net "Net_491")
		)
		(pad "AN15" smd circle
			(at -9.500108 7.599934)
			(size 0.4572 0.4572)
			(layers "F.Cu" "F.Mask" "F.Paste")
			(net "GND")
		)
		(pad "AN16" smd circle
			(at -8.549894 7.599934)
			(size 0.4572 0.4572)
			(layers "F.Cu" "F.Mask" "F.Paste")
			(net "GND")
		)
		(pad "AN17" smd circle
			(at -7.599934 7.599934)
			(size 0.4572 0.4572)
			(layers "F.Cu" "F.Mask" "F.Paste")
			(net "GND")
		)
		(pad "AN18" smd circle
			(at -6.649974 7.599934)
			(size 0.4572 0.4572)
			(layers "F.Cu" "F.Mask" "F.Paste")
			(net "GND")
		)
		(pad "AN19" smd circle
			(at -5.700014 7.599934)
			(size 0.4572 0.4572)
			(layers "F.Cu" "F.Mask" "F.Paste")
			(net "GND")
		)
		(pad "AN20" smd circle
			(at -4.750054 7.599934)
			(size 0.4572 0.4572)
			(layers "F.Cu" "F.Mask" "F.Paste")
			(net "GND")
		)
		(pad "AN21" smd circle
			(at -3.800094 7.599934)
			(size 0.4572 0.4572)
			(layers "F.Cu" "F.Mask" "F.Paste")
			(net "GND")
		)
		(pad "AN22" smd circle
			(at -2.84988 7.599934)
			(size 0.4572 0.4572)
			(layers "F.Cu" "F.Mask" "F.Paste")
			(net "GND")
		)
		(pad "AN23" smd circle
			(at -1.89992 7.599934)
			(size 0.4572 0.4572)
			(layers "F.Cu" "F.Mask" "F.Paste")
			(net "GND")
		)
		(pad "AN24" smd circle
			(at -0.94996 7.599934)
			(size 0.4572 0.4572)
			(layers "F.Cu" "F.Mask" "F.Paste")
			(net "GND")
		)
		(pad "AN25" smd circle
			(at 0 7.599934)
			(size 0.4572 0.4572)
			(layers "F.Cu" "F.Mask" "F.Paste")
			(net "GND")
		)
		(pad "AN26" smd circle
			(at 0.94996 7.599934)
			(size 0.4572 0.4572)
			(layers "F.Cu" "F.Mask" "F.Paste")
			(net "GND")
		)
		(pad "AN27" smd circle
			(at 1.89992 7.599934)
			(size 0.4572 0.4572)
			(layers "F.Cu" "F.Mask" "F.Paste")
			(net "GND")
		)
		(pad "AN28" smd circle
			(at 2.84988 7.599934)
			(size 0.4572 0.4572)
			(layers "F.Cu" "F.Mask" "F.Paste")
			(net "GND")
		)
		(pad "AN29" smd circle
			(at 3.800094 7.599934)
			(size 0.4572 0.4572)
			(layers "F.Cu" "F.Mask" "F.Paste")
			(net "GND")
		)
		(pad "AN30" smd circle
			(at 4.750054 7.599934)
			(size 0.4572 0.4572)
			(layers "F.Cu" "F.Mask" "F.Paste")
			(net "GND")
		)
		(pad "AN31" smd circle
			(at 5.700014 7.599934)
			(size 0.4572 0.4572)
			(layers "F.Cu" "F.Mask" "F.Paste")
			(net "GND")
		)
		(pad "AN32" smd circle
			(at 6.649974 7.599934)
			(size 0.4572 0.4572)
			(layers "F.Cu" "F.Mask" "F.Paste")
			(net "GND")
		)
		(pad "AN33" smd circle
			(at 7.599934 7.599934)
			(size 0.4572 0.4572)
			(layers "F.Cu" "F.Mask" "F.Paste")
			(net "GND")
		)
		(pad "AN34" smd circle
			(at 8.549894 7.599934)
			(size 0.4572 0.4572)
			(layers "F.Cu" "F.Mask" "F.Paste")
			(net "GND")
		)
		(pad "AN35" smd circle
			(at 9.500108 7.599934)
			(size 0.4572 0.4572)
			(layers "F.Cu" "F.Mask" "F.Paste")
			(net "GND")
		)
		(pad "AN36" smd circle
			(at 10.450068 7.599934)
			(size 0.4572 0.4572)
			(layers "F.Cu" "F.Mask" "F.Paste")
			(net "Net_493")
		)
		(pad "AN37" smd circle
			(at 11.400028 7.599934)
			(size 0.4572 0.4572)
			(layers "F.Cu" "F.Mask" "F.Paste")
			(net "GND")
		)
		(pad "AN38" smd circle
			(at 12.349988 7.599934)
			(size 0.4572 0.4572)
			(layers "F.Cu" "F.Mask" "F.Paste")
			(net "Net_2878")
		)
		(pad "AN39" smd circle
			(at 13.299948 7.599934)
			(size 0.4572 0.4572)
			(layers "F.Cu" "F.Mask" "F.Paste")
			(net "Net_2845")
		)
		(pad "AN40" smd circle
			(at 14.249908 7.599934)
			(size 0.4572 0.4572)
			(layers "F.Cu" "F.Mask" "F.Paste")
			(net "GND")
		)
		(pad "AN41" smd circle
			(at 15.200122 7.599934)
			(size 0.4572 0.4572)
			(layers "F.Cu" "F.Mask" "F.Paste")
			(net "GND")
		)
		(pad "AN42" smd circle
			(at 16.150082 7.599934)
			(size 0.4572 0.4572)
			(layers "F.Cu" "F.Mask" "F.Paste")
			(net "GND")
		)
		(pad "AN43" smd circle
			(at 17.100042 7.599934)
			(size 0.4572 0.4572)
			(layers "F.Cu" "F.Mask" "F.Paste")
			(net "P5E_PEX0_STN0_TX_DP<0>")
		)
		(pad "AN44" smd circle
			(at 18.050002 7.599934)
			(size 0.4572 0.4572)
			(layers "F.Cu" "F.Mask" "F.Paste")
			(net "P5E_PEX0_STN0_TX_DN<0>")
		)
		(pad "AN45" smd circle
			(at 18.999962 7.599934)
			(size 0.4572 0.4572)
			(layers "F.Cu" "F.Mask" "F.Paste")
			(net "GND")
		)
		(pad "AN46" smd circle
			(at 19.949922 7.599934)
			(size 0.4572 0.4572)
			(layers "F.Cu" "F.Mask" "F.Paste")
			(net "P5E_PEX0_STN0_RX_DP<0>")
		)
		(pad "AN47" smd circle
			(at 20.899882 7.599934)
			(size 0.4572 0.4572)
			(layers "F.Cu" "F.Mask" "F.Paste")
			(net "P5E_PEX0_STN0_RX_DN<0>")
		)
		(pad "AN48" smd circle
			(at 21.850096 7.599934)
			(size 0.4572 0.4572)
			(layers "F.Cu" "F.Mask" "F.Paste")
			(net "GND")
		)
		(pad "AN49" smd circle
			(at 22.800056 7.599934)
			(size 0.4572 0.4572)
			(layers "F.Cu" "F.Mask" "F.Paste")
			(net "GND")
		)
		(pad "AP1" smd circle
			(at -22.800056 8.549894)
			(size 0.4572 0.4572)
			(layers "F.Cu" "F.Mask" "F.Paste")
			(net "Net_2710")
		)
		(pad "AP2" smd circle
			(at -21.850096 8.549894)
			(size 0.4572 0.4572)
			(layers "F.Cu" "F.Mask" "F.Paste")
			(net "Net_2724")
		)
		(pad "AP3" smd circle
			(at -20.899882 8.549894)
			(size 0.4572 0.4572)
			(layers "F.Cu" "F.Mask" "F.Paste")
			(net "GND")
		)
		(pad "AP4" smd circle
			(at -19.949922 8.549894)
			(size 0.4572 0.4572)
			(layers "F.Cu" "F.Mask" "F.Paste")
			(net "GND")
		)
		(pad "AP5" smd circle
			(at -18.999962 8.549894)
			(size 0.4572 0.4572)
			(layers "F.Cu" "F.Mask" "F.Paste")
			(net "GND")
		)
		(pad "AP6" smd circle
			(at -18.050002 8.549894)
			(size 0.4572 0.4572)
			(layers "F.Cu" "F.Mask" "F.Paste")
			(net "GND")
		)
		(pad "AP7" smd circle
			(at -17.100042 8.549894)
			(size 0.4572 0.4572)
			(layers "F.Cu" "F.Mask" "F.Paste")
			(net "GND")
		)
		(pad "AP8" smd circle
			(at -16.150082 8.549894)
			(size 0.4572 0.4572)
			(layers "F.Cu" "F.Mask" "F.Paste")
			(net "Net_2738")
		)
		(pad "AP9" smd circle
			(at -15.200122 8.549894)
			(size 0.4572 0.4572)
			(layers "F.Cu" "F.Mask" "F.Paste")
			(net "Net_2752")
		)
		(pad "AP10" smd circle
			(at -14.249908 8.549894)
			(size 0.4572 0.4572)
			(layers "F.Cu" "F.Mask" "F.Paste")
			(net "GND")
		)
		(pad "AP11" smd circle
			(at -13.299948 8.549894)
			(size 0.4572 0.4572)
			(layers "F.Cu" "F.Mask" "F.Paste")
			(net "GND")
		)
		(pad "AP12" smd circle
			(at -12.349988 8.549894)
			(size 0.4572 0.4572)
			(layers "F.Cu" "F.Mask" "F.Paste")
			(net "GND")
		)
		(pad "AP13" smd circle
			(at -11.400028 8.549894)
			(size 0.4572 0.4572)
			(layers "F.Cu" "F.Mask" "F.Paste")
			(net "GND")
		)
		(pad "AP14" smd circle
			(at -10.450068 8.549894)
			(size 0.4572 0.4572)
			(layers "F.Cu" "F.Mask" "F.Paste")
			(net "Net_486")
		)
		(pad "AP15" smd circle
			(at -9.500108 8.549894)
			(size 0.4572 0.4572)
			(layers "F.Cu" "F.Mask" "F.Paste")
			(net "GND")
		)
		(pad "AP16" smd circle
			(at -8.549894 8.549894)
			(size 0.4572 0.4572)
			(layers "F.Cu" "F.Mask" "F.Paste")
			(net "P1V25_SERDES_VDDPLL_PEX0")
		)
		(pad "AP17" smd circle
			(at -7.599934 8.549894)
			(size 0.4572 0.4572)
			(layers "F.Cu" "F.Mask" "F.Paste")
			(net "P1V25_SERDES_VDDPLL_PEX0")
		)
		(pad "AP18" smd circle
			(at -6.649974 8.549894)
			(size 0.4572 0.4572)
			(layers "F.Cu" "F.Mask" "F.Paste")
			(net "P1V25_SERDES_VDDPLL_PEX0")
		)
		(pad "AP19" smd circle
			(at -5.700014 8.549894)
			(size 0.4572 0.4572)
			(layers "F.Cu" "F.Mask" "F.Paste")
			(net "P1V25_SERDES_VDDPLL_PEX0")
		)
		(pad "AP20" smd circle
			(at -4.750054 8.549894)
			(size 0.4572 0.4572)
			(layers "F.Cu" "F.Mask" "F.Paste")
			(net "P1V25_SERDES_VDDPLL_PEX0")
		)
		(pad "AP21" smd circle
			(at -3.800094 8.549894)
			(size 0.4572 0.4572)
			(layers "F.Cu" "F.Mask" "F.Paste")
			(net "P1V25_SERDES_VDDPLL_PEX0")
		)
		(pad "AP22" smd circle
			(at -2.84988 8.549894)
			(size 0.4572 0.4572)
			(layers "F.Cu" "F.Mask" "F.Paste")
			(net "P1V25_SERDES_VDDPLL_PEX0")
		)
		(pad "AP23" smd circle
			(at -1.89992 8.549894)
			(size 0.4572 0.4572)
			(layers "F.Cu" "F.Mask" "F.Paste")
			(net "P1V25_SERDES_VDDPLL_PEX0")
		)
		(pad "AP24" smd circle
			(at -0.94996 8.549894)
			(size 0.4572 0.4572)
			(layers "F.Cu" "F.Mask" "F.Paste")
			(net "P1V25_SERDES_VDDPLL_PEX0")
		)
		(pad "AP25" smd circle
			(at 0 8.549894)
			(size 0.4572 0.4572)
			(layers "F.Cu" "F.Mask" "F.Paste")
			(net "P1V25_SERDES_VDDPLL_PEX0")
		)
		(pad "AP26" smd circle
			(at 0.94996 8.549894)
			(size 0.4572 0.4572)
			(layers "F.Cu" "F.Mask" "F.Paste")
			(net "P1V25_SERDES_VDDPLL_PEX0")
		)
		(pad "AP27" smd circle
			(at 1.89992 8.549894)
			(size 0.4572 0.4572)
			(layers "F.Cu" "F.Mask" "F.Paste")
			(net "P1V25_SERDES_VDDPLL_PEX0")
		)
		(pad "AP28" smd circle
			(at 2.84988 8.549894)
			(size 0.4572 0.4572)
			(layers "F.Cu" "F.Mask" "F.Paste")
			(net "P1V25_SERDES_VDDPLL_PEX0")
		)
		(pad "AP29" smd circle
			(at 3.800094 8.549894)
			(size 0.4572 0.4572)
			(layers "F.Cu" "F.Mask" "F.Paste")
			(net "P1V25_SERDES_VDDPLL_PEX0")
		)
		(pad "AP30" smd circle
			(at 4.750054 8.549894)
			(size 0.4572 0.4572)
			(layers "F.Cu" "F.Mask" "F.Paste")
			(net "P1V25_SERDES_VDDPLL_PEX0")
		)
		(pad "AP31" smd circle
			(at 5.700014 8.549894)
			(size 0.4572 0.4572)
			(layers "F.Cu" "F.Mask" "F.Paste")
			(net "P1V25_SERDES_VDDPLL_PEX0")
		)
		(pad "AP32" smd circle
			(at 6.649974 8.549894)
			(size 0.4572 0.4572)
			(layers "F.Cu" "F.Mask" "F.Paste")
			(net "P1V25_SERDES_VDDPLL_PEX0")
		)
		(pad "AP33" smd circle
			(at 7.599934 8.549894)
			(size 0.4572 0.4572)
			(layers "F.Cu" "F.Mask" "F.Paste")
			(net "P1V25_SERDES_VDDPLL_PEX0")
		)
		(pad "AP34" smd circle
			(at 8.549894 8.549894)
			(size 0.4572 0.4572)
			(layers "F.Cu" "F.Mask" "F.Paste")
			(net "GND")
		)
		(pad "AP35" smd circle
			(at 9.500108 8.549894)
			(size 0.4572 0.4572)
			(layers "F.Cu" "F.Mask" "F.Paste")
			(net "P1V8_VDDA_PEX0")
		)
		(pad "AP36" smd circle
			(at 10.450068 8.549894)
			(size 0.4572 0.4572)
			(layers "F.Cu" "F.Mask" "F.Paste")
			(net "Net_485")
		)
		(pad "AP37" smd circle
			(at 11.400028 8.549894)
			(size 0.4572 0.4572)
			(layers "F.Cu" "F.Mask" "F.Paste")
			(net "GND")
		)
		(pad "AP38" smd circle
			(at 12.349988 8.549894)
			(size 0.4572 0.4572)
			(layers "F.Cu" "F.Mask" "F.Paste")
			(net "Net_2898")
		)
		(pad "AP39" smd circle
			(at 13.299948 8.549894)
			(size 0.4572 0.4572)
			(layers "F.Cu" "F.Mask" "F.Paste")
			(net "Net_2904")
		)
		(pad "AP40" smd circle
			(at 14.249908 8.549894)
			(size 0.4572 0.4572)
			(layers "F.Cu" "F.Mask" "F.Paste")
			(net "GND")
		)
		(pad "AP41" smd circle
			(at 15.200122 8.549894)
			(size 0.4572 0.4572)
			(layers "F.Cu" "F.Mask" "F.Paste")
			(net "P5E_PEX0_STN0_TX_DP<1>")
		)
		(pad "AP42" smd circle
			(at 16.150082 8.549894)
			(size 0.4572 0.4572)
			(layers "F.Cu" "F.Mask" "F.Paste")
			(net "P5E_PEX0_STN0_TX_DN<1>")
		)
		(pad "AP43" smd circle
			(at 17.100042 8.549894)
			(size 0.4572 0.4572)
			(layers "F.Cu" "F.Mask" "F.Paste")
			(net "GND")
		)
		(pad "AP44" smd circle
			(at 18.050002 8.549894)
			(size 0.4572 0.4572)
			(layers "F.Cu" "F.Mask" "F.Paste")
			(net "GND")
		)
		(pad "AP45" smd circle
			(at 18.999962 8.549894)
			(size 0.4572 0.4572)
			(layers "F.Cu" "F.Mask" "F.Paste")
			(net "GND")
		)
		(pad "AP46" smd circle
			(at 19.949922 8.549894)
			(size 0.4572 0.4572)
			(layers "F.Cu" "F.Mask" "F.Paste")
			(net "GND")
		)
		(pad "AP47" smd circle
			(at 20.899882 8.549894)
			(size 0.4572 0.4572)
			(layers "F.Cu" "F.Mask" "F.Paste")
			(net "GND")
		)
		(pad "AP48" smd circle
			(at 21.850096 8.549894)
			(size 0.4572 0.4572)
			(layers "F.Cu" "F.Mask" "F.Paste")
			(net "P5E_PEX0_STN0_RX_DP<1>")
		)
		(pad "AP49" smd circle
			(at 22.800056 8.549894)
			(size 0.4572 0.4572)
			(layers "F.Cu" "F.Mask" "F.Paste")
			(net "P5E_PEX0_STN0_RX_DN<1>")
		)
		(pad "AR1" smd circle
			(at -22.800056 9.500108)
			(size 0.4572 0.4572)
			(layers "F.Cu" "F.Mask" "F.Paste")
			(net "GND")
		)
		(pad "AR2" smd circle
			(at -21.850096 9.500108)
			(size 0.4572 0.4572)
			(layers "F.Cu" "F.Mask" "F.Paste")
			(net "GND")
		)
		(pad "AR3" smd circle
			(at -20.899882 9.500108)
			(size 0.4572 0.4572)
			(layers "F.Cu" "F.Mask" "F.Paste")
			(net "Net_2711")
		)
		(pad "AR4" smd circle
			(at -19.949922 9.500108)
			(size 0.4572 0.4572)
			(layers "F.Cu" "F.Mask" "F.Paste")
			(net "Net_2725")
		)
		(pad "AR5" smd circle
			(at -18.999962 9.500108)
			(size 0.4572 0.4572)
			(layers "F.Cu" "F.Mask" "F.Paste")
			(net "GND")
		)
		(pad "AR6" smd circle
			(at -18.050002 9.500108)
			(size 0.4572 0.4572)
			(layers "F.Cu" "F.Mask" "F.Paste")
			(net "Net_2739")
		)
		(pad "AR7" smd circle
			(at -17.100042 9.500108)
			(size 0.4572 0.4572)
			(layers "F.Cu" "F.Mask" "F.Paste")
			(net "Net_2753")
		)
		(pad "AR8" smd circle
			(at -16.150082 9.500108)
			(size 0.4572 0.4572)
			(layers "F.Cu" "F.Mask" "F.Paste")
			(net "GND")
		)
		(pad "AR9" smd circle
			(at -15.200122 9.500108)
			(size 0.4572 0.4572)
			(layers "F.Cu" "F.Mask" "F.Paste")
			(net "GND")
		)
		(pad "AR10" smd circle
			(at -14.249908 9.500108)
			(size 0.4572 0.4572)
			(layers "F.Cu" "F.Mask" "F.Paste")
			(net "GND")
		)
		(pad "AR11" smd circle
			(at -13.299948 9.500108)
			(size 0.4572 0.4572)
			(layers "F.Cu" "F.Mask" "F.Paste")
			(net "GND")
		)
		(pad "AR12" smd circle
			(at -12.349988 9.500108)
			(size 0.4572 0.4572)
			(layers "F.Cu" "F.Mask" "F.Paste")
			(net "GND")
		)
		(pad "AR13" smd circle
			(at -11.400028 9.500108)
			(size 0.4572 0.4572)
			(layers "F.Cu" "F.Mask" "F.Paste")
			(net "GND")
		)
		(pad "AR14" smd circle
			(at -10.450068 9.500108)
			(size 0.4572 0.4572)
			(layers "F.Cu" "F.Mask" "F.Paste")
			(net "GND")
		)
		(pad "AR15" smd circle
			(at -9.500108 9.500108)
			(size 0.4572 0.4572)
			(layers "F.Cu" "F.Mask" "F.Paste")
			(net "GND")
		)
		(pad "AR16" smd circle
			(at -8.549894 9.500108)
			(size 0.4572 0.4572)
			(layers "F.Cu" "F.Mask" "F.Paste")
			(net "GND")
		)
		(pad "AR17" smd circle
			(at -7.599934 9.500108)
			(size 0.4572 0.4572)
			(layers "F.Cu" "F.Mask" "F.Paste")
			(net "GND")
		)
		(pad "AR18" smd circle
			(at -6.649974 9.500108)
			(size 0.4572 0.4572)
			(layers "F.Cu" "F.Mask" "F.Paste")
			(net "GND")
		)
		(pad "AR19" smd circle
			(at -5.700014 9.500108)
			(size 0.4572 0.4572)
			(layers "F.Cu" "F.Mask" "F.Paste")
			(net "GND")
		)
		(pad "AR20" smd circle
			(at -4.750054 9.500108)
			(size 0.4572 0.4572)
			(layers "F.Cu" "F.Mask" "F.Paste")
			(net "GND")
		)
		(pad "AR21" smd circle
			(at -3.800094 9.500108)
			(size 0.4572 0.4572)
			(layers "F.Cu" "F.Mask" "F.Paste")
			(net "GND")
		)
		(pad "AR22" smd circle
			(at -2.84988 9.500108)
			(size 0.4572 0.4572)
			(layers "F.Cu" "F.Mask" "F.Paste")
			(net "GND")
		)
		(pad "AR23" smd circle
			(at -1.89992 9.500108)
			(size 0.4572 0.4572)
			(layers "F.Cu" "F.Mask" "F.Paste")
			(net "GND")
		)
		(pad "AR24" smd circle
			(at -0.94996 9.500108)
			(size 0.4572 0.4572)
			(layers "F.Cu" "F.Mask" "F.Paste")
			(net "GND")
		)
		(pad "AR25" smd circle
			(at 0 9.500108)
			(size 0.4572 0.4572)
			(layers "F.Cu" "F.Mask" "F.Paste")
			(net "GND")
		)
		(pad "AR26" smd circle
			(at 0.94996 9.500108)
			(size 0.4572 0.4572)
			(layers "F.Cu" "F.Mask" "F.Paste")
			(net "GND")
		)
		(pad "AR27" smd circle
			(at 1.89992 9.500108)
			(size 0.4572 0.4572)
			(layers "F.Cu" "F.Mask" "F.Paste")
			(net "GND")
		)
		(pad "AR28" smd circle
			(at 2.84988 9.500108)
			(size 0.4572 0.4572)
			(layers "F.Cu" "F.Mask" "F.Paste")
			(net "GND")
		)
		(pad "AR29" smd circle
			(at 3.800094 9.500108)
			(size 0.4572 0.4572)
			(layers "F.Cu" "F.Mask" "F.Paste")
			(net "GND")
		)
		(pad "AR30" smd circle
			(at 4.750054 9.500108)
			(size 0.4572 0.4572)
			(layers "F.Cu" "F.Mask" "F.Paste")
			(net "GND")
		)
		(pad "AR31" smd circle
			(at 5.700014 9.500108)
			(size 0.4572 0.4572)
			(layers "F.Cu" "F.Mask" "F.Paste")
			(net "GND")
		)
		(pad "AR32" smd circle
			(at 6.649974 9.500108)
			(size 0.4572 0.4572)
			(layers "F.Cu" "F.Mask" "F.Paste")
			(net "GND")
		)
		(pad "AR33" smd circle
			(at 7.599934 9.500108)
			(size 0.4572 0.4572)
			(layers "F.Cu" "F.Mask" "F.Paste")
			(net "GND")
		)
		(pad "AR34" smd circle
			(at 8.549894 9.500108)
			(size 0.4572 0.4572)
			(layers "F.Cu" "F.Mask" "F.Paste")
			(net "GND")
		)
		(pad "AR35" smd circle
			(at 9.500108 9.500108)
			(size 0.4572 0.4572)
			(layers "F.Cu" "F.Mask" "F.Paste")
			(net "GND")
		)
		(pad "AR36" smd circle
			(at 10.450068 9.500108)
			(size 0.4572 0.4572)
			(layers "F.Cu" "F.Mask" "F.Paste")
			(net "Net_483")
		)
		(pad "AR37" smd circle
			(at 11.400028 9.500108)
			(size 0.4572 0.4572)
			(layers "F.Cu" "F.Mask" "F.Paste")
			(net "GND")
		)
		(pad "AR38" smd circle
			(at 12.349988 9.500108)
			(size 0.4572 0.4572)
			(layers "F.Cu" "F.Mask" "F.Paste")
			(net "Net_2903")
		)
		(pad "AR39" smd circle
			(at 13.299948 9.500108)
			(size 0.4572 0.4572)
			(layers "F.Cu" "F.Mask" "F.Paste")
			(net "Net_2905")
		)
		(pad "AR40" smd circle
			(at 14.249908 9.500108)
			(size 0.4572 0.4572)
			(layers "F.Cu" "F.Mask" "F.Paste")
			(net "GND")
		)
		(pad "AR41" smd circle
			(at 15.200122 9.500108)
			(size 0.4572 0.4572)
			(layers "F.Cu" "F.Mask" "F.Paste")
			(net "GND")
		)
		(pad "AR42" smd circle
			(at 16.150082 9.500108)
			(size 0.4572 0.4572)
			(layers "F.Cu" "F.Mask" "F.Paste")
			(net "GND")
		)
		(pad "AR43" smd circle
			(at 17.100042 9.500108)
			(size 0.4572 0.4572)
			(layers "F.Cu" "F.Mask" "F.Paste")
			(net "P5E_PEX0_STN0_TX_DP<2>")
		)
		(pad "AR44" smd circle
			(at 18.050002 9.500108)
			(size 0.4572 0.4572)
			(layers "F.Cu" "F.Mask" "F.Paste")
			(net "P5E_PEX0_STN0_TX_DN<2>")
		)
		(pad "AR45" smd circle
			(at 18.999962 9.500108)
			(size 0.4572 0.4572)
			(layers "F.Cu" "F.Mask" "F.Paste")
			(net "GND")
		)
		(pad "AR46" smd circle
			(at 19.949922 9.500108)
			(size 0.4572 0.4572)
			(layers "F.Cu" "F.Mask" "F.Paste")
			(net "P5E_PEX0_STN0_RX_DP<2>")
		)
		(pad "AR47" smd circle
			(at 20.899882 9.500108)
			(size 0.4572 0.4572)
			(layers "F.Cu" "F.Mask" "F.Paste")
			(net "P5E_PEX0_STN0_RX_DN<2>")
		)
		(pad "AR48" smd circle
			(at 21.850096 9.500108)
			(size 0.4572 0.4572)
			(layers "F.Cu" "F.Mask" "F.Paste")
			(net "GND")
		)
		(pad "AR49" smd circle
			(at 22.800056 9.500108)
			(size 0.4572 0.4572)
			(layers "F.Cu" "F.Mask" "F.Paste")
			(net "GND")
		)
		(pad "AT1" smd circle
			(at -22.800056 10.450068)
			(size 0.4572 0.4572)
			(layers "F.Cu" "F.Mask" "F.Paste")
			(net "Net_2712")
		)
		(pad "AT2" smd circle
			(at -21.850096 10.450068)
			(size 0.4572 0.4572)
			(layers "F.Cu" "F.Mask" "F.Paste")
			(net "Net_2726")
		)
		(pad "AT3" smd circle
			(at -20.899882 10.450068)
			(size 0.4572 0.4572)
			(layers "F.Cu" "F.Mask" "F.Paste")
			(net "GND")
		)
		(pad "AT4" smd circle
			(at -19.949922 10.450068)
			(size 0.4572 0.4572)
			(layers "F.Cu" "F.Mask" "F.Paste")
			(net "GND")
		)
		(pad "AT5" smd circle
			(at -18.999962 10.450068)
			(size 0.4572 0.4572)
			(layers "F.Cu" "F.Mask" "F.Paste")
			(net "GND")
		)
		(pad "AT6" smd circle
			(at -18.050002 10.450068)
			(size 0.4572 0.4572)
			(layers "F.Cu" "F.Mask" "F.Paste")
			(net "GND")
		)
		(pad "AT7" smd circle
			(at -17.100042 10.450068)
			(size 0.4572 0.4572)
			(layers "F.Cu" "F.Mask" "F.Paste")
			(net "GND")
		)
		(pad "AT8" smd circle
			(at -16.150082 10.450068)
			(size 0.4572 0.4572)
			(layers "F.Cu" "F.Mask" "F.Paste")
			(net "Net_2740")
		)
		(pad "AT9" smd circle
			(at -15.200122 10.450068)
			(size 0.4572 0.4572)
			(layers "F.Cu" "F.Mask" "F.Paste")
			(net "Net_2754")
		)
		(pad "AT10" smd circle
			(at -14.249908 10.450068)
			(size 0.4572 0.4572)
			(layers "F.Cu" "F.Mask" "F.Paste")
			(net "GND")
		)
		(pad "AT11" smd circle
			(at -13.299948 10.450068)
			(size 0.4572 0.4572)
			(layers "F.Cu" "F.Mask" "F.Paste")
			(net "GND")
		)
		(pad "AT12" smd circle
			(at -12.349988 10.450068)
			(size 0.4572 0.4572)
			(layers "F.Cu" "F.Mask" "F.Paste")
			(net "GND")
		)
		(pad "AT13" smd circle
			(at -11.400028 10.450068)
			(size 0.4572 0.4572)
			(layers "F.Cu" "F.Mask" "F.Paste")
			(net "GND")
		)
		(pad "AT14" smd circle
			(at -10.450068 10.450068)
			(size 0.4572 0.4572)
			(layers "F.Cu" "F.Mask" "F.Paste")
			(net "GND")
		)
		(pad "AT15" smd circle
			(at -9.500108 10.450068)
			(size 0.4572 0.4572)
			(layers "F.Cu" "F.Mask" "F.Paste")
			(net "GND")
		)
		(pad "AT16" smd circle
			(at -8.549894 10.450068)
			(size 0.4572 0.4572)
			(layers "F.Cu" "F.Mask" "F.Paste")
			(net "GND")
		)
		(pad "AT17" smd circle
			(at -7.599934 10.450068)
			(size 0.4572 0.4572)
			(layers "F.Cu" "F.Mask" "F.Paste")
			(net "GND")
		)
		(pad "AT18" smd circle
			(at -6.649974 10.450068)
			(size 0.4572 0.4572)
			(layers "F.Cu" "F.Mask" "F.Paste")
			(net "GND")
		)
		(pad "AT19" smd circle
			(at -5.700014 10.450068)
			(size 0.4572 0.4572)
			(layers "F.Cu" "F.Mask" "F.Paste")
			(net "GND")
		)
		(pad "AT20" smd circle
			(at -4.750054 10.450068)
			(size 0.4572 0.4572)
			(layers "F.Cu" "F.Mask" "F.Paste")
			(net "GND")
		)
		(pad "AT21" smd circle
			(at -3.800094 10.450068)
			(size 0.4572 0.4572)
			(layers "F.Cu" "F.Mask" "F.Paste")
			(net "GND")
		)
		(pad "AT22" smd circle
			(at -2.84988 10.450068)
			(size 0.4572 0.4572)
			(layers "F.Cu" "F.Mask" "F.Paste")
			(net "GND")
		)
		(pad "AT23" smd circle
			(at -1.89992 10.450068)
			(size 0.4572 0.4572)
			(layers "F.Cu" "F.Mask" "F.Paste")
			(net "GND")
		)
		(pad "AT24" smd circle
			(at -0.94996 10.450068)
			(size 0.4572 0.4572)
			(layers "F.Cu" "F.Mask" "F.Paste")
			(net "GND")
		)
		(pad "AT25" smd circle
			(at 0 10.450068)
			(size 0.4572 0.4572)
			(layers "F.Cu" "F.Mask" "F.Paste")
			(net "GND")
		)
		(pad "AT26" smd circle
			(at 0.94996 10.450068)
			(size 0.4572 0.4572)
			(layers "F.Cu" "F.Mask" "F.Paste")
			(net "GND")
		)
		(pad "AT27" smd circle
			(at 1.89992 10.450068)
			(size 0.4572 0.4572)
			(layers "F.Cu" "F.Mask" "F.Paste")
			(net "GND")
		)
		(pad "AT28" smd circle
			(at 2.84988 10.450068)
			(size 0.4572 0.4572)
			(layers "F.Cu" "F.Mask" "F.Paste")
			(net "GND")
		)
		(pad "AT29" smd circle
			(at 3.800094 10.450068)
			(size 0.4572 0.4572)
			(layers "F.Cu" "F.Mask" "F.Paste")
			(net "GND")
		)
		(pad "AT30" smd circle
			(at 4.750054 10.450068)
			(size 0.4572 0.4572)
			(layers "F.Cu" "F.Mask" "F.Paste")
			(net "GND")
		)
		(pad "AT31" smd circle
			(at 5.700014 10.450068)
			(size 0.4572 0.4572)
			(layers "F.Cu" "F.Mask" "F.Paste")
			(net "GND")
		)
		(pad "AT32" smd circle
			(at 6.649974 10.450068)
			(size 0.4572 0.4572)
			(layers "F.Cu" "F.Mask" "F.Paste")
			(net "GND")
		)
		(pad "AT33" smd circle
			(at 7.599934 10.450068)
			(size 0.4572 0.4572)
			(layers "F.Cu" "F.Mask" "F.Paste")
			(net "GND")
		)
		(pad "AT34" smd circle
			(at 8.549894 10.450068)
			(size 0.4572 0.4572)
			(layers "F.Cu" "F.Mask" "F.Paste")
			(net "GND")
		)
		(pad "AT35" smd circle
			(at 9.500108 10.450068)
			(size 0.4572 0.4572)
			(layers "F.Cu" "F.Mask" "F.Paste")
			(net "GND")
		)
		(pad "AT36" smd circle
			(at 10.450068 10.450068)
			(size 0.4572 0.4572)
			(layers "F.Cu" "F.Mask" "F.Paste")
			(net "Net_492")
		)
		(pad "AT37" smd circle
			(at 11.400028 10.450068)
			(size 0.4572 0.4572)
			(layers "F.Cu" "F.Mask" "F.Paste")
			(net "GND")
		)
		(pad "AT38" smd circle
			(at 12.349988 10.450068)
			(size 0.4572 0.4572)
			(layers "F.Cu" "F.Mask" "F.Paste")
			(net "Net_2869")
		)
		(pad "AT39" smd circle
			(at 13.299948 10.450068)
			(size 0.4572 0.4572)
			(layers "F.Cu" "F.Mask" "F.Paste")
			(net "Net_2854")
		)
		(pad "AT40" smd circle
			(at 14.249908 10.450068)
			(size 0.4572 0.4572)
			(layers "F.Cu" "F.Mask" "F.Paste")
			(net "GND")
		)
		(pad "AT41" smd circle
			(at 15.200122 10.450068)
			(size 0.4572 0.4572)
			(layers "F.Cu" "F.Mask" "F.Paste")
			(net "P5E_PEX0_STN0_TX_DP<3>")
		)
		(pad "AT42" smd circle
			(at 16.150082 10.450068)
			(size 0.4572 0.4572)
			(layers "F.Cu" "F.Mask" "F.Paste")
			(net "P5E_PEX0_STN0_TX_DN<3>")
		)
		(pad "AT43" smd circle
			(at 17.100042 10.450068)
			(size 0.4572 0.4572)
			(layers "F.Cu" "F.Mask" "F.Paste")
			(net "GND")
		)
		(pad "AT44" smd circle
			(at 18.050002 10.450068)
			(size 0.4572 0.4572)
			(layers "F.Cu" "F.Mask" "F.Paste")
			(net "GND")
		)
		(pad "AT45" smd circle
			(at 18.999962 10.450068)
			(size 0.4572 0.4572)
			(layers "F.Cu" "F.Mask" "F.Paste")
			(net "GND")
		)
		(pad "AT46" smd circle
			(at 19.949922 10.450068)
			(size 0.4572 0.4572)
			(layers "F.Cu" "F.Mask" "F.Paste")
			(net "GND")
		)
		(pad "AT47" smd circle
			(at 20.899882 10.450068)
			(size 0.4572 0.4572)
			(layers "F.Cu" "F.Mask" "F.Paste")
			(net "GND")
		)
		(pad "AT48" smd circle
			(at 21.850096 10.450068)
			(size 0.4572 0.4572)
			(layers "F.Cu" "F.Mask" "F.Paste")
			(net "P5E_PEX0_STN0_RX_DP<3>")
		)
		(pad "AT49" smd circle
			(at 22.800056 10.450068)
			(size 0.4572 0.4572)
			(layers "F.Cu" "F.Mask" "F.Paste")
			(net "P5E_PEX0_STN0_RX_DN<3>")
		)
		(pad "AU1" smd circle
			(at -22.800056 11.400028)
			(size 0.4572 0.4572)
			(layers "F.Cu" "F.Mask" "F.Paste")
			(net "GND")
		)
		(pad "AU2" smd circle
			(at -21.850096 11.400028)
			(size 0.4572 0.4572)
			(layers "F.Cu" "F.Mask" "F.Paste")
			(net "GND")
		)
		(pad "AU3" smd circle
			(at -20.899882 11.400028)
			(size 0.4572 0.4572)
			(layers "F.Cu" "F.Mask" "F.Paste")
			(net "Net_2713")
		)
		(pad "AU4" smd circle
			(at -19.949922 11.400028)
			(size 0.4572 0.4572)
			(layers "F.Cu" "F.Mask" "F.Paste")
			(net "Net_2727")
		)
		(pad "AU5" smd circle
			(at -18.999962 11.400028)
			(size 0.4572 0.4572)
			(layers "F.Cu" "F.Mask" "F.Paste")
			(net "GND")
		)
		(pad "AU6" smd circle
			(at -18.050002 11.400028)
			(size 0.4572 0.4572)
			(layers "F.Cu" "F.Mask" "F.Paste")
			(net "Net_2741")
		)
		(pad "AU7" smd circle
			(at -17.100042 11.400028)
			(size 0.4572 0.4572)
			(layers "F.Cu" "F.Mask" "F.Paste")
			(net "Net_2755")
		)
		(pad "AU8" smd circle
			(at -16.150082 11.400028)
			(size 0.4572 0.4572)
			(layers "F.Cu" "F.Mask" "F.Paste")
			(net "GND")
		)
		(pad "AU9" smd circle
			(at -15.200122 11.400028)
			(size 0.4572 0.4572)
			(layers "F.Cu" "F.Mask" "F.Paste")
			(net "GND")
		)
		(pad "AU10" smd circle
			(at -14.249908 11.400028)
			(size 0.4572 0.4572)
			(layers "F.Cu" "F.Mask" "F.Paste")
			(net "GND")
		)
		(pad "AU11" smd circle
			(at -13.299948 11.400028)
			(size 0.4572 0.4572)
			(layers "F.Cu" "F.Mask" "F.Paste")
			(net "GND")
		)
		(pad "AU12" smd circle
			(at -12.349988 11.400028)
			(size 0.4572 0.4572)
			(layers "F.Cu" "F.Mask" "F.Paste")
			(net "GND")
		)
		(pad "AU13" smd circle
			(at -11.400028 11.400028)
			(size 0.4572 0.4572)
			(layers "F.Cu" "F.Mask" "F.Paste")
			(net "GND")
		)
		(pad "AU14" smd circle
			(at -10.450068 11.400028)
			(size 0.4572 0.4572)
			(layers "F.Cu" "F.Mask" "F.Paste")
			(net "GND")
		)
		(pad "AU15" smd circle
			(at -9.500108 11.400028)
			(size 0.4572 0.4572)
			(layers "F.Cu" "F.Mask" "F.Paste")
			(net "GND")
		)
		(pad "AU16" smd circle
			(at -8.549894 11.400028)
			(size 0.4572 0.4572)
			(layers "F.Cu" "F.Mask" "F.Paste")
			(net "GND")
		)
		(pad "AU17" smd circle
			(at -7.599934 11.400028)
			(size 0.4572 0.4572)
			(layers "F.Cu" "F.Mask" "F.Paste")
			(net "GND")
		)
		(pad "AU18" smd circle
			(at -6.649974 11.400028)
			(size 0.4572 0.4572)
			(layers "F.Cu" "F.Mask" "F.Paste")
			(net "GND")
		)
		(pad "AU19" smd circle
			(at -5.700014 11.400028)
			(size 0.4572 0.4572)
			(layers "F.Cu" "F.Mask" "F.Paste")
			(net "GND")
		)
		(pad "AU20" smd circle
			(at -4.750054 11.400028)
			(size 0.4572 0.4572)
			(layers "F.Cu" "F.Mask" "F.Paste")
			(net "GND")
		)
		(pad "AU21" smd circle
			(at -3.800094 11.400028)
			(size 0.4572 0.4572)
			(layers "F.Cu" "F.Mask" "F.Paste")
			(net "GND")
		)
		(pad "AU22" smd circle
			(at -2.84988 11.400028)
			(size 0.4572 0.4572)
			(layers "F.Cu" "F.Mask" "F.Paste")
			(net "GND")
		)
		(pad "AU23" smd circle
			(at -1.89992 11.400028)
			(size 0.4572 0.4572)
			(layers "F.Cu" "F.Mask" "F.Paste")
			(net "GND")
		)
		(pad "AU24" smd circle
			(at -0.94996 11.400028)
			(size 0.4572 0.4572)
			(layers "F.Cu" "F.Mask" "F.Paste")
			(net "GND")
		)
		(pad "AU25" smd circle
			(at 0 11.400028)
			(size 0.4572 0.4572)
			(layers "F.Cu" "F.Mask" "F.Paste")
			(net "GND")
		)
		(pad "AU26" smd circle
			(at 0.94996 11.400028)
			(size 0.4572 0.4572)
			(layers "F.Cu" "F.Mask" "F.Paste")
			(net "GND")
		)
		(pad "AU27" smd circle
			(at 1.89992 11.400028)
			(size 0.4572 0.4572)
			(layers "F.Cu" "F.Mask" "F.Paste")
			(net "GND")
		)
		(pad "AU28" smd circle
			(at 2.84988 11.400028)
			(size 0.4572 0.4572)
			(layers "F.Cu" "F.Mask" "F.Paste")
			(net "GND")
		)
		(pad "AU29" smd circle
			(at 3.800094 11.400028)
			(size 0.4572 0.4572)
			(layers "F.Cu" "F.Mask" "F.Paste")
			(net "GND")
		)
		(pad "AU30" smd circle
			(at 4.750054 11.400028)
			(size 0.4572 0.4572)
			(layers "F.Cu" "F.Mask" "F.Paste")
			(net "GND")
		)
		(pad "AU31" smd circle
			(at 5.700014 11.400028)
			(size 0.4572 0.4572)
			(layers "F.Cu" "F.Mask" "F.Paste")
			(net "GND")
		)
		(pad "AU32" smd circle
			(at 6.649974 11.400028)
			(size 0.4572 0.4572)
			(layers "F.Cu" "F.Mask" "F.Paste")
			(net "GND")
		)
		(pad "AU33" smd circle
			(at 7.599934 11.400028)
			(size 0.4572 0.4572)
			(layers "F.Cu" "F.Mask" "F.Paste")
			(net "GND")
		)
		(pad "AU34" smd circle
			(at 8.549894 11.400028)
			(size 0.4572 0.4572)
			(layers "F.Cu" "F.Mask" "F.Paste")
			(net "GND")
		)
		(pad "AU35" smd circle
			(at 9.500108 11.400028)
			(size 0.4572 0.4572)
			(layers "F.Cu" "F.Mask" "F.Paste")
			(net "GND")
		)
		(pad "AU36" smd circle
			(at 10.450068 11.400028)
			(size 0.4572 0.4572)
			(layers "F.Cu" "F.Mask" "F.Paste")
			(net "GND")
		)
		(pad "AU37" smd circle
			(at 11.400028 11.400028)
			(size 0.4572 0.4572)
			(layers "F.Cu" "F.Mask" "F.Paste")
			(net "GND")
		)
		(pad "AU38" smd circle
			(at 12.349988 11.400028)
			(size 0.4572 0.4572)
			(layers "F.Cu" "F.Mask" "F.Paste")
			(net "Net_2876")
		)
		(pad "AU39" smd circle
			(at 13.299948 11.400028)
			(size 0.4572 0.4572)
			(layers "F.Cu" "F.Mask" "F.Paste")
			(net "Net_2848")
		)
		(pad "AU40" smd circle
			(at 14.249908 11.400028)
			(size 0.4572 0.4572)
			(layers "F.Cu" "F.Mask" "F.Paste")
			(net "GND")
		)
		(pad "AU41" smd circle
			(at 15.200122 11.400028)
			(size 0.4572 0.4572)
			(layers "F.Cu" "F.Mask" "F.Paste")
			(net "GND")
		)
		(pad "AU42" smd circle
			(at 16.150082 11.400028)
			(size 0.4572 0.4572)
			(layers "F.Cu" "F.Mask" "F.Paste")
			(net "GND")
		)
		(pad "AU43" smd circle
			(at 17.100042 11.400028)
			(size 0.4572 0.4572)
			(layers "F.Cu" "F.Mask" "F.Paste")
			(net "P5E_PEX0_STN0_TX_DP<4>")
		)
		(pad "AU44" smd circle
			(at 18.050002 11.400028)
			(size 0.4572 0.4572)
			(layers "F.Cu" "F.Mask" "F.Paste")
			(net "P5E_PEX0_STN0_TX_DN<4>")
		)
		(pad "AU45" smd circle
			(at 18.999962 11.400028)
			(size 0.4572 0.4572)
			(layers "F.Cu" "F.Mask" "F.Paste")
			(net "GND")
		)
		(pad "AU46" smd circle
			(at 19.949922 11.400028)
			(size 0.4572 0.4572)
			(layers "F.Cu" "F.Mask" "F.Paste")
			(net "P5E_PEX0_STN0_RX_DP<4>")
		)
		(pad "AU47" smd circle
			(at 20.899882 11.400028)
			(size 0.4572 0.4572)
			(layers "F.Cu" "F.Mask" "F.Paste")
			(net "P5E_PEX0_STN0_RX_DN<4>")
		)
		(pad "AU48" smd circle
			(at 21.850096 11.400028)
			(size 0.4572 0.4572)
			(layers "F.Cu" "F.Mask" "F.Paste")
			(net "GND")
		)
		(pad "AU49" smd circle
			(at 22.800056 11.400028)
			(size 0.4572 0.4572)
			(layers "F.Cu" "F.Mask" "F.Paste")
			(net "GND")
		)
		(pad "AV1" smd circle
			(at -22.800056 12.349988)
			(size 0.4572 0.4572)
			(layers "F.Cu" "F.Mask" "F.Paste")
			(net "Net_2714")
		)
		(pad "AV2" smd circle
			(at -21.850096 12.349988)
			(size 0.4572 0.4572)
			(layers "F.Cu" "F.Mask" "F.Paste")
			(net "Net_2728")
		)
		(pad "AV3" smd circle
			(at -20.899882 12.349988)
			(size 0.4572 0.4572)
			(layers "F.Cu" "F.Mask" "F.Paste")
			(net "GND")
		)
		(pad "AV4" smd circle
			(at -19.949922 12.349988)
			(size 0.4572 0.4572)
			(layers "F.Cu" "F.Mask" "F.Paste")
			(net "GND")
		)
		(pad "AV5" smd circle
			(at -18.999962 12.349988)
			(size 0.4572 0.4572)
			(layers "F.Cu" "F.Mask" "F.Paste")
			(net "GND")
		)
		(pad "AV6" smd circle
			(at -18.050002 12.349988)
			(size 0.4572 0.4572)
			(layers "F.Cu" "F.Mask" "F.Paste")
			(net "GND")
		)
		(pad "AV7" smd circle
			(at -17.100042 12.349988)
			(size 0.4572 0.4572)
			(layers "F.Cu" "F.Mask" "F.Paste")
			(net "GND")
		)
		(pad "AV8" smd circle
			(at -16.150082 12.349988)
			(size 0.4572 0.4572)
			(layers "F.Cu" "F.Mask" "F.Paste")
			(net "Net_2742")
		)
		(pad "AV9" smd circle
			(at -15.200122 12.349988)
			(size 0.4572 0.4572)
			(layers "F.Cu" "F.Mask" "F.Paste")
			(net "Net_2756")
		)
		(pad "AV10" smd circle
			(at -14.249908 12.349988)
			(size 0.4572 0.4572)
			(layers "F.Cu" "F.Mask" "F.Paste")
			(net "GND")
		)
		(pad "AV11" smd circle
			(at -13.299948 12.349988)
			(size 0.4572 0.4572)
			(layers "F.Cu" "F.Mask" "F.Paste")
			(net "GND")
		)
		(pad "AV12" smd circle
			(at -12.349988 12.349988)
			(size 0.4572 0.4572)
			(layers "F.Cu" "F.Mask" "F.Paste")
			(net "Net_2866")
		)
		(pad "AV13" smd circle
			(at -11.400028 12.349988)
			(size 0.4572 0.4572)
			(layers "F.Cu" "F.Mask" "F.Paste")
			(net "Net_2867")
		)
		(pad "AV14" smd circle
			(at -10.450068 12.349988)
			(size 0.4572 0.4572)
			(layers "F.Cu" "F.Mask" "F.Paste")
			(net "Net_2858")
		)
		(pad "AV15" smd circle
			(at -9.500108 12.349988)
			(size 0.4572 0.4572)
			(layers "F.Cu" "F.Mask" "F.Paste")
			(net "Net_2852")
		)
		(pad "AV16" smd circle
			(at -8.549894 12.349988)
			(size 0.4572 0.4572)
			(layers "F.Cu" "F.Mask" "F.Paste")
			(net "Net_2861")
		)
		(pad "AV17" smd circle
			(at -7.599934 12.349988)
			(size 0.4572 0.4572)
			(layers "F.Cu" "F.Mask" "F.Paste")
			(net "Net_2862")
		)
		(pad "AV18" smd circle
			(at -6.649974 12.349988)
			(size 0.4572 0.4572)
			(layers "F.Cu" "F.Mask" "F.Paste")
			(net "Net_2857")
		)
		(pad "AV19" smd circle
			(at -5.700014 12.349988)
			(size 0.4572 0.4572)
			(layers "F.Cu" "F.Mask" "F.Paste")
			(net "Net_2853")
		)
		(pad "AV20" smd circle
			(at -4.750054 12.349988)
			(size 0.4572 0.4572)
			(layers "F.Cu" "F.Mask" "F.Paste")
			(net "GND")
		)
		(pad "AV21" smd circle
			(at -3.800094 12.349988)
			(size 0.4572 0.4572)
			(layers "F.Cu" "F.Mask" "F.Paste")
			(net "Net_2892")
		)
		(pad "AV22" smd circle
			(at -2.84988 12.349988)
			(size 0.4572 0.4572)
			(layers "F.Cu" "F.Mask" "F.Paste")
			(net "Net_2893")
		)
		(pad "AV23" smd circle
			(at -1.89992 12.349988)
			(size 0.4572 0.4572)
			(layers "F.Cu" "F.Mask" "F.Paste")
			(net "Net_2895")
		)
		(pad "AV24" smd circle
			(at -0.94996 12.349988)
			(size 0.4572 0.4572)
			(layers "F.Cu" "F.Mask" "F.Paste")
			(net "GND")
		)
		(pad "AV25" smd circle
			(at 0 12.349988)
			(size 0.4572 0.4572)
			(layers "F.Cu" "F.Mask" "F.Paste")
			(net "PEX0_MODE_SEL2")
		)
		(pad "AV26" smd circle
			(at 0.94996 12.349988)
			(size 0.4572 0.4572)
			(layers "F.Cu" "F.Mask" "F.Paste")
			(net "PEX0_MODE_SEL7")
		)
		(pad "AV27" smd circle
			(at 1.89992 12.349988)
			(size 0.4572 0.4572)
			(layers "F.Cu" "F.Mask" "F.Paste")
			(net "PEX0_MODE_SEL3")
		)
		(pad "AV28" smd circle
			(at 2.84988 12.349988)
			(size 0.4572 0.4572)
			(layers "F.Cu" "F.Mask" "F.Paste")
			(net "PEX0_MODE_SEL9")
		)
		(pad "AV29" smd circle
			(at 3.800094 12.349988)
			(size 0.4572 0.4572)
			(layers "F.Cu" "F.Mask" "F.Paste")
			(net "PEX0_PCA9555_INT_R_N")
		)
		(pad "AV30" smd circle
			(at 4.750054 12.349988)
			(size 0.4572 0.4572)
			(layers "F.Cu" "F.Mask" "F.Paste")
			(net "PEX0_SYS_ERR_N")
		)
		(pad "AV31" smd circle
			(at 5.700014 12.349988)
			(size 0.4572 0.4572)
			(layers "F.Cu" "F.Mask" "F.Paste")
			(net "PEX0_MODE_SEL6")
		)
		(pad "AV32" smd circle
			(at 6.649974 12.349988)
			(size 0.4572 0.4572)
			(layers "F.Cu" "F.Mask" "F.Paste")
			(net "PEX0_MODE_SEL10")
		)
		(pad "AV33" smd circle
			(at 7.599934 12.349988)
			(size 0.4572 0.4572)
			(layers "F.Cu" "F.Mask" "F.Paste")
			(net "Net_2870")
		)
		(pad "AV34" smd circle
			(at 8.549894 12.349988)
			(size 0.4572 0.4572)
			(layers "F.Cu" "F.Mask" "F.Paste")
			(net "Net_2843")
		)
		(pad "AV35" smd circle
			(at 9.500108 12.349988)
			(size 0.4572 0.4572)
			(layers "F.Cu" "F.Mask" "F.Paste")
			(net "Net_2872")
		)
		(pad "AV36" smd circle
			(at 10.450068 12.349988)
			(size 0.4572 0.4572)
			(layers "F.Cu" "F.Mask" "F.Paste")
			(net "Net_2849")
		)
		(pad "AV37" smd circle
			(at 11.400028 12.349988)
			(size 0.4572 0.4572)
			(layers "F.Cu" "F.Mask" "F.Paste")
			(net "Net_2874")
		)
		(pad "AV38" smd circle
			(at 12.349988 12.349988)
			(size 0.4572 0.4572)
			(layers "F.Cu" "F.Mask" "F.Paste")
			(net "Net_2873")
		)
		(pad "AV39" smd circle
			(at 13.299948 12.349988)
			(size 0.4572 0.4572)
			(layers "F.Cu" "F.Mask" "F.Paste")
			(net "Net_2865")
		)
		(pad "AV40" smd circle
			(at 14.249908 12.349988)
			(size 0.4572 0.4572)
			(layers "F.Cu" "F.Mask" "F.Paste")
			(net "GND")
		)
		(pad "AV41" smd circle
			(at 15.200122 12.349988)
			(size 0.4572 0.4572)
			(layers "F.Cu" "F.Mask" "F.Paste")
			(net "P5E_PEX0_STN0_TX_DP<5>")
		)
		(pad "AV42" smd circle
			(at 16.150082 12.349988)
			(size 0.4572 0.4572)
			(layers "F.Cu" "F.Mask" "F.Paste")
			(net "P5E_PEX0_STN0_TX_DN<5>")
		)
		(pad "AV43" smd circle
			(at 17.100042 12.349988)
			(size 0.4572 0.4572)
			(layers "F.Cu" "F.Mask" "F.Paste")
			(net "GND")
		)
		(pad "AV44" smd circle
			(at 18.050002 12.349988)
			(size 0.4572 0.4572)
			(layers "F.Cu" "F.Mask" "F.Paste")
			(net "GND")
		)
		(pad "AV45" smd circle
			(at 18.999962 12.349988)
			(size 0.4572 0.4572)
			(layers "F.Cu" "F.Mask" "F.Paste")
			(net "GND")
		)
		(pad "AV46" smd circle
			(at 19.949922 12.349988)
			(size 0.4572 0.4572)
			(layers "F.Cu" "F.Mask" "F.Paste")
			(net "GND")
		)
		(pad "AV47" smd circle
			(at 20.899882 12.349988)
			(size 0.4572 0.4572)
			(layers "F.Cu" "F.Mask" "F.Paste")
			(net "GND")
		)
		(pad "AV48" smd circle
			(at 21.850096 12.349988)
			(size 0.4572 0.4572)
			(layers "F.Cu" "F.Mask" "F.Paste")
			(net "P5E_PEX0_STN0_RX_DP<5>")
		)
		(pad "AV49" smd circle
			(at 22.800056 12.349988)
			(size 0.4572 0.4572)
			(layers "F.Cu" "F.Mask" "F.Paste")
			(net "P5E_PEX0_STN0_RX_DN<5>")
		)
		(pad "AW1" smd circle
			(at -22.800056 13.299948)
			(size 0.4572 0.4572)
			(layers "F.Cu" "F.Mask" "F.Paste")
			(net "GND")
		)
		(pad "AW2" smd circle
			(at -21.850096 13.299948)
			(size 0.4572 0.4572)
			(layers "F.Cu" "F.Mask" "F.Paste")
			(net "GND")
		)
		(pad "AW3" smd circle
			(at -20.899882 13.299948)
			(size 0.4572 0.4572)
			(layers "F.Cu" "F.Mask" "F.Paste")
			(net "Net_2715")
		)
		(pad "AW4" smd circle
			(at -19.949922 13.299948)
			(size 0.4572 0.4572)
			(layers "F.Cu" "F.Mask" "F.Paste")
			(net "Net_2729")
		)
		(pad "AW5" smd circle
			(at -18.999962 13.299948)
			(size 0.4572 0.4572)
			(layers "F.Cu" "F.Mask" "F.Paste")
			(net "GND")
		)
		(pad "AW6" smd circle
			(at -18.050002 13.299948)
			(size 0.4572 0.4572)
			(layers "F.Cu" "F.Mask" "F.Paste")
			(net "Net_2743")
		)
		(pad "AW7" smd circle
			(at -17.100042 13.299948)
			(size 0.4572 0.4572)
			(layers "F.Cu" "F.Mask" "F.Paste")
			(net "Net_2757")
		)
		(pad "AW8" smd circle
			(at -16.150082 13.299948)
			(size 0.4572 0.4572)
			(layers "F.Cu" "F.Mask" "F.Paste")
			(net "GND")
		)
		(pad "AW9" smd circle
			(at -15.200122 13.299948)
			(size 0.4572 0.4572)
			(layers "F.Cu" "F.Mask" "F.Paste")
			(net "GND")
		)
		(pad "AW10" smd circle
			(at -14.249908 13.299948)
			(size 0.4572 0.4572)
			(layers "F.Cu" "F.Mask" "F.Paste")
			(net "GND")
		)
		(pad "AW11" smd circle
			(at -13.299948 13.299948)
			(size 0.4572 0.4572)
			(layers "F.Cu" "F.Mask" "F.Paste")
			(net "GND")
		)
		(pad "AW12" smd circle
			(at -12.349988 13.299948)
			(size 0.4572 0.4572)
			(layers "F.Cu" "F.Mask" "F.Paste")
			(net "Net_2864")
		)
		(pad "AW13" smd circle
			(at -11.400028 13.299948)
			(size 0.4572 0.4572)
			(layers "F.Cu" "F.Mask" "F.Paste")
			(net "Net_2860")
		)
		(pad "AW14" smd circle
			(at -10.450068 13.299948)
			(size 0.4572 0.4572)
			(layers "F.Cu" "F.Mask" "F.Paste")
			(net "Net_2856")
		)
		(pad "AW15" smd circle
			(at -9.500108 13.299948)
			(size 0.4572 0.4572)
			(layers "F.Cu" "F.Mask" "F.Paste")
			(net "Net_2851")
		)
		(pad "AW16" smd circle
			(at -8.549894 13.299948)
			(size 0.4572 0.4572)
			(layers "F.Cu" "F.Mask" "F.Paste")
			(net "Net_2863")
		)
		(pad "AW17" smd circle
			(at -7.599934 13.299948)
			(size 0.4572 0.4572)
			(layers "F.Cu" "F.Mask" "F.Paste")
			(net "Net_2859")
		)
		(pad "AW18" smd circle
			(at -6.649974 13.299948)
			(size 0.4572 0.4572)
			(layers "F.Cu" "F.Mask" "F.Paste")
			(net "Net_2855")
		)
		(pad "AW19" smd circle
			(at -5.700014 13.299948)
			(size 0.4572 0.4572)
			(layers "F.Cu" "F.Mask" "F.Paste")
			(net "Net_2850")
		)
		(pad "AW20" smd circle
			(at -4.750054 13.299948)
			(size 0.4572 0.4572)
			(layers "F.Cu" "F.Mask" "F.Paste")
			(net "GND")
		)
		(pad "AW21" smd circle
			(at -3.800094 13.299948)
			(size 0.4572 0.4572)
			(layers "F.Cu" "F.Mask" "F.Paste")
			(net "Net_2884")
		)
		(pad "AW22" smd circle
			(at -2.84988 13.299948)
			(size 0.4572 0.4572)
			(layers "F.Cu" "F.Mask" "F.Paste")
			(net "Net_2894")
		)
		(pad "AW23" smd circle
			(at -1.89992 13.299948)
			(size 0.4572 0.4572)
			(layers "F.Cu" "F.Mask" "F.Paste")
			(net "Net_2883")
		)
		(pad "AW24" smd circle
			(at -0.94996 13.299948)
			(size 0.4572 0.4572)
			(layers "F.Cu" "F.Mask" "F.Paste")
			(net "GND")
		)
		(pad "AW25" smd circle
			(at 0 13.299948)
			(size 0.4572 0.4572)
			(layers "F.Cu" "F.Mask" "F.Paste")
			(net "PEX0_MODE_SEL5")
		)
		(pad "AW26" smd circle
			(at 0.94996 13.299948)
			(size 0.4572 0.4572)
			(layers "F.Cu" "F.Mask" "F.Paste")
			(net "PEX0_DBG_MODE3")
		)
		(pad "AW27" smd circle
			(at 1.89992 13.299948)
			(size 0.4572 0.4572)
			(layers "F.Cu" "F.Mask" "F.Paste")
			(net "PEX0_MODE_SEL0")
		)
		(pad "AW28" smd circle
			(at 2.84988 13.299948)
			(size 0.4572 0.4572)
			(layers "F.Cu" "F.Mask" "F.Paste")
			(net "PEX0_MODE_SEL4")
		)
		(pad "AW29" smd circle
			(at 3.800094 13.299948)
			(size 0.4572 0.4572)
			(layers "F.Cu" "F.Mask" "F.Paste")
			(net "PEX0_MODE_SEL8")
		)
		(pad "AW30" smd circle
			(at 4.750054 13.299948)
			(size 0.4572 0.4572)
			(layers "F.Cu" "F.Mask" "F.Paste")
			(net "PEX0_DBG_MODE2")
		)
		(pad "AW31" smd circle
			(at 5.700014 13.299948)
			(size 0.4572 0.4572)
			(layers "F.Cu" "F.Mask" "F.Paste")
			(net "PEX0_MODE_SEL11")
		)
		(pad "AW32" smd circle
			(at 6.649974 13.299948)
			(size 0.4572 0.4572)
			(layers "F.Cu" "F.Mask" "F.Paste")
			(net "PEX0_MODE_SEL12")
		)
		(pad "AW33" smd circle
			(at 7.599934 13.299948)
			(size 0.4572 0.4572)
			(layers "F.Cu" "F.Mask" "F.Paste")
			(net "Net_2868")
		)
		(pad "AW34" smd circle
			(at 8.549894 13.299948)
			(size 0.4572 0.4572)
			(layers "F.Cu" "F.Mask" "F.Paste")
			(net "PEX0_DBG_MODE4")
		)
		(pad "AW35" smd circle
			(at 9.500108 13.299948)
			(size 0.4572 0.4572)
			(layers "F.Cu" "F.Mask" "F.Paste")
			(net "Net_2847")
		)
		(pad "AW36" smd circle
			(at 10.450068 13.299948)
			(size 0.4572 0.4572)
			(layers "F.Cu" "F.Mask" "F.Paste")
			(net "Net_2871")
		)
		(pad "AW37" smd circle
			(at 11.400028 13.299948)
			(size 0.4572 0.4572)
			(layers "F.Cu" "F.Mask" "F.Paste")
			(net "Net_2875")
		)
		(pad "AW38" smd circle
			(at 12.349988 13.299948)
			(size 0.4572 0.4572)
			(layers "F.Cu" "F.Mask" "F.Paste")
			(net "PEX0_MODE_SEL1")
		)
		(pad "AW39" smd circle
			(at 13.299948 13.299948)
			(size 0.4572 0.4572)
			(layers "F.Cu" "F.Mask" "F.Paste")
			(net "Net_2842")
		)
		(pad "AW40" smd circle
			(at 14.249908 13.299948)
			(size 0.4572 0.4572)
			(layers "F.Cu" "F.Mask" "F.Paste")
			(net "GND")
		)
		(pad "AW41" smd circle
			(at 15.200122 13.299948)
			(size 0.4572 0.4572)
			(layers "F.Cu" "F.Mask" "F.Paste")
			(net "GND")
		)
		(pad "AW42" smd circle
			(at 16.150082 13.299948)
			(size 0.4572 0.4572)
			(layers "F.Cu" "F.Mask" "F.Paste")
			(net "GND")
		)
		(pad "AW43" smd circle
			(at 17.100042 13.299948)
			(size 0.4572 0.4572)
			(layers "F.Cu" "F.Mask" "F.Paste")
			(net "P5E_PEX0_STN0_TX_DP<6>")
		)
		(pad "AW44" smd circle
			(at 18.050002 13.299948)
			(size 0.4572 0.4572)
			(layers "F.Cu" "F.Mask" "F.Paste")
			(net "P5E_PEX0_STN0_TX_DN<6>")
		)
		(pad "AW45" smd circle
			(at 18.999962 13.299948)
			(size 0.4572 0.4572)
			(layers "F.Cu" "F.Mask" "F.Paste")
			(net "GND")
		)
		(pad "AW46" smd circle
			(at 19.949922 13.299948)
			(size 0.4572 0.4572)
			(layers "F.Cu" "F.Mask" "F.Paste")
			(net "P5E_PEX0_STN0_RX_DP<6>")
		)
		(pad "AW47" smd circle
			(at 20.899882 13.299948)
			(size 0.4572 0.4572)
			(layers "F.Cu" "F.Mask" "F.Paste")
			(net "P5E_PEX0_STN0_RX_DN<6>")
		)
		(pad "AW48" smd circle
			(at 21.850096 13.299948)
			(size 0.4572 0.4572)
			(layers "F.Cu" "F.Mask" "F.Paste")
			(net "GND")
		)
		(pad "AW49" smd circle
			(at 22.800056 13.299948)
			(size 0.4572 0.4572)
			(layers "F.Cu" "F.Mask" "F.Paste")
			(net "GND")
		)
		(pad "AY1" smd circle
			(at -22.800056 14.249908)
			(size 0.4572 0.4572)
			(layers "F.Cu" "F.Mask" "F.Paste")
			(net "Net_2716")
		)
		(pad "AY2" smd circle
			(at -21.850096 14.249908)
			(size 0.4572 0.4572)
			(layers "F.Cu" "F.Mask" "F.Paste")
			(net "Net_2730")
		)
		(pad "AY3" smd circle
			(at -20.899882 14.249908)
			(size 0.4572 0.4572)
			(layers "F.Cu" "F.Mask" "F.Paste")
			(net "GND")
		)
		(pad "AY4" smd circle
			(at -19.949922 14.249908)
			(size 0.4572 0.4572)
			(layers "F.Cu" "F.Mask" "F.Paste")
			(net "GND")
		)
		(pad "AY5" smd circle
			(at -18.999962 14.249908)
			(size 0.4572 0.4572)
			(layers "F.Cu" "F.Mask" "F.Paste")
			(net "GND")
		)
		(pad "AY6" smd circle
			(at -18.050002 14.249908)
			(size 0.4572 0.4572)
			(layers "F.Cu" "F.Mask" "F.Paste")
			(net "GND")
		)
		(pad "AY7" smd circle
			(at -17.100042 14.249908)
			(size 0.4572 0.4572)
			(layers "F.Cu" "F.Mask" "F.Paste")
			(net "GND")
		)
		(pad "AY8" smd circle
			(at -16.150082 14.249908)
			(size 0.4572 0.4572)
			(layers "F.Cu" "F.Mask" "F.Paste")
			(net "GND")
		)
		(pad "AY9" smd circle
			(at -15.200122 14.249908)
			(size 0.4572 0.4572)
			(layers "F.Cu" "F.Mask" "F.Paste")
			(net "GND")
		)
		(pad "AY10" smd circle
			(at -14.249908 14.249908)
			(size 0.4572 0.4572)
			(layers "F.Cu" "F.Mask" "F.Paste")
			(net "GND")
		)
		(pad "AY11" smd circle
			(at -13.299948 14.249908)
			(size 0.4572 0.4572)
			(layers "F.Cu" "F.Mask" "F.Paste")
			(net "GND")
		)
		(pad "AY12" smd circle
			(at -12.349988 14.249908)
			(size 0.4572 0.4572)
			(layers "F.Cu" "F.Mask" "F.Paste")
			(net "GND")
		)
		(pad "AY13" smd circle
			(at -11.400028 14.249908)
			(size 0.4572 0.4572)
			(layers "F.Cu" "F.Mask" "F.Paste")
			(net "GND")
		)
		(pad "AY14" smd circle
			(at -10.450068 14.249908)
			(size 0.4572 0.4572)
			(layers "F.Cu" "F.Mask" "F.Paste")
			(net "GND")
		)
		(pad "AY15" smd circle
			(at -9.500108 14.249908)
			(size 0.4572 0.4572)
			(layers "F.Cu" "F.Mask" "F.Paste")
			(net "GND")
		)
		(pad "AY16" smd circle
			(at -8.549894 14.249908)
			(size 0.4572 0.4572)
			(layers "F.Cu" "F.Mask" "F.Paste")
			(net "GND")
		)
		(pad "AY17" smd circle
			(at -7.599934 14.249908)
			(size 0.4572 0.4572)
			(layers "F.Cu" "F.Mask" "F.Paste")
			(net "GND")
		)
		(pad "AY18" smd circle
			(at -6.649974 14.249908)
			(size 0.4572 0.4572)
			(layers "F.Cu" "F.Mask" "F.Paste")
			(net "GND")
		)
		(pad "AY19" smd circle
			(at -5.700014 14.249908)
			(size 0.4572 0.4572)
			(layers "F.Cu" "F.Mask" "F.Paste")
			(net "GND")
		)
		(pad "AY20" smd circle
			(at -4.750054 14.249908)
			(size 0.4572 0.4572)
			(layers "F.Cu" "F.Mask" "F.Paste")
			(net "GND")
		)
		(pad "AY21" smd circle
			(at -3.800094 14.249908)
			(size 0.4572 0.4572)
			(layers "F.Cu" "F.Mask" "F.Paste")
			(net "GND")
		)
		(pad "AY22" smd circle
			(at -2.84988 14.249908)
			(size 0.4572 0.4572)
			(layers "F.Cu" "F.Mask" "F.Paste")
			(net "GND")
		)
		(pad "AY23" smd circle
			(at -1.89992 14.249908)
			(size 0.4572 0.4572)
			(layers "F.Cu" "F.Mask" "F.Paste")
			(net "GND")
		)
		(pad "AY24" smd circle
			(at -0.94996 14.249908)
			(size 0.4572 0.4572)
			(layers "F.Cu" "F.Mask" "F.Paste")
			(net "GND")
		)
		(pad "AY25" smd circle
			(at 0 14.249908)
			(size 0.4572 0.4572)
			(layers "F.Cu" "F.Mask" "F.Paste")
			(net "GND")
		)
		(pad "AY26" smd circle
			(at 0.94996 14.249908)
			(size 0.4572 0.4572)
			(layers "F.Cu" "F.Mask" "F.Paste")
			(net "GND")
		)
		(pad "AY27" smd circle
			(at 1.89992 14.249908)
			(size 0.4572 0.4572)
			(layers "F.Cu" "F.Mask" "F.Paste")
			(net "GND")
		)
		(pad "AY28" smd circle
			(at 2.84988 14.249908)
			(size 0.4572 0.4572)
			(layers "F.Cu" "F.Mask" "F.Paste")
			(net "GND")
		)
		(pad "AY29" smd circle
			(at 3.800094 14.249908)
			(size 0.4572 0.4572)
			(layers "F.Cu" "F.Mask" "F.Paste")
			(net "GND")
		)
		(pad "AY30" smd circle
			(at 4.750054 14.249908)
			(size 0.4572 0.4572)
			(layers "F.Cu" "F.Mask" "F.Paste")
			(net "GND")
		)
		(pad "AY31" smd circle
			(at 5.700014 14.249908)
			(size 0.4572 0.4572)
			(layers "F.Cu" "F.Mask" "F.Paste")
			(net "GND")
		)
		(pad "AY32" smd circle
			(at 6.649974 14.249908)
			(size 0.4572 0.4572)
			(layers "F.Cu" "F.Mask" "F.Paste")
			(net "GND")
		)
		(pad "AY33" smd circle
			(at 7.599934 14.249908)
			(size 0.4572 0.4572)
			(layers "F.Cu" "F.Mask" "F.Paste")
			(net "GND")
		)
		(pad "AY34" smd circle
			(at 8.549894 14.249908)
			(size 0.4572 0.4572)
			(layers "F.Cu" "F.Mask" "F.Paste")
			(net "GND")
		)
		(pad "AY35" smd circle
			(at 9.500108 14.249908)
			(size 0.4572 0.4572)
			(layers "F.Cu" "F.Mask" "F.Paste")
			(net "GND")
		)
		(pad "AY36" smd circle
			(at 10.450068 14.249908)
			(size 0.4572 0.4572)
			(layers "F.Cu" "F.Mask" "F.Paste")
			(net "GND")
		)
		(pad "AY37" smd circle
			(at 11.400028 14.249908)
			(size 0.4572 0.4572)
			(layers "F.Cu" "F.Mask" "F.Paste")
			(net "GND")
		)
		(pad "AY38" smd circle
			(at 12.349988 14.249908)
			(size 0.4572 0.4572)
			(layers "F.Cu" "F.Mask" "F.Paste")
			(net "GND")
		)
		(pad "AY39" smd circle
			(at 13.299948 14.249908)
			(size 0.4572 0.4572)
			(layers "F.Cu" "F.Mask" "F.Paste")
			(net "GND")
		)
		(pad "AY40" smd circle
			(at 14.249908 14.249908)
			(size 0.4572 0.4572)
			(layers "F.Cu" "F.Mask" "F.Paste")
			(net "GND")
		)
		(pad "AY41" smd circle
			(at 15.200122 14.249908)
			(size 0.4572 0.4572)
			(layers "F.Cu" "F.Mask" "F.Paste")
			(net "GND")
		)
		(pad "AY42" smd circle
			(at 16.150082 14.249908)
			(size 0.4572 0.4572)
			(layers "F.Cu" "F.Mask" "F.Paste")
			(net "GND")
		)
		(pad "AY43" smd circle
			(at 17.100042 14.249908)
			(size 0.4572 0.4572)
			(layers "F.Cu" "F.Mask" "F.Paste")
			(net "GND")
		)
		(pad "AY44" smd circle
			(at 18.050002 14.249908)
			(size 0.4572 0.4572)
			(layers "F.Cu" "F.Mask" "F.Paste")
			(net "GND")
		)
		(pad "AY45" smd circle
			(at 18.999962 14.249908)
			(size 0.4572 0.4572)
			(layers "F.Cu" "F.Mask" "F.Paste")
			(net "GND")
		)
		(pad "AY46" smd circle
			(at 19.949922 14.249908)
			(size 0.4572 0.4572)
			(layers "F.Cu" "F.Mask" "F.Paste")
			(net "GND")
		)
		(pad "AY47" smd circle
			(at 20.899882 14.249908)
			(size 0.4572 0.4572)
			(layers "F.Cu" "F.Mask" "F.Paste")
			(net "GND")
		)
		(pad "AY48" smd circle
			(at 21.850096 14.249908)
			(size 0.4572 0.4572)
			(layers "F.Cu" "F.Mask" "F.Paste")
			(net "P5E_PEX0_STN0_RX_DP<7>")
		)
		(pad "AY49" smd circle
			(at 22.800056 14.249908)
			(size 0.4572 0.4572)
			(layers "F.Cu" "F.Mask" "F.Paste")
			(net "P5E_PEX0_STN0_RX_DN<7>")
		)
		(pad "B1" smd circle
			(at -22.800056 -21.850096)
			(size 0.4572 0.4572)
			(layers "F.Cu" "F.Mask" "F.Paste")
			(net "GND")
		)
		(pad "B2" smd circle
			(at -21.850096 -21.850096)
			(size 0.4572 0.4572)
			(layers "F.Cu" "F.Mask" "F.Paste")
			(net "GND")
		)
		(pad "B3" smd circle
			(at -20.899882 -21.850096)
			(size 0.4572 0.4572)
			(layers "F.Cu" "F.Mask" "F.Paste")
			(net "P5E_PEX0_STN7_RX_DP<123>")
		)
		(pad "B4" smd circle
			(at -19.949922 -21.850096)
			(size 0.4572 0.4572)
			(layers "F.Cu" "F.Mask" "F.Paste")
			(net "GND")
		)
		(pad "B5" smd circle
			(at -18.999962 -21.850096)
			(size 0.4572 0.4572)
			(layers "F.Cu" "F.Mask" "F.Paste")
			(net "P5E_PEX0_STN7_RX_DP<125>")
		)
		(pad "B6" smd circle
			(at -18.050002 -21.850096)
			(size 0.4572 0.4572)
			(layers "F.Cu" "F.Mask" "F.Paste")
			(net "GND")
		)
		(pad "B7" smd circle
			(at -17.100042 -21.850096)
			(size 0.4572 0.4572)
			(layers "F.Cu" "F.Mask" "F.Paste")
			(net "P5E_PEX0_STN7_RX_DP<127>")
		)
		(pad "B8" smd circle
			(at -16.150082 -21.850096)
			(size 0.4572 0.4572)
			(layers "F.Cu" "F.Mask" "F.Paste")
			(net "GND")
		)
		(pad "B9" smd circle
			(at -15.200122 -21.850096)
			(size 0.4572 0.4572)
			(layers "F.Cu" "F.Mask" "F.Paste")
			(net "P5E_PEX0_STN6_RX_DP<110>")
		)
		(pad "B10" smd circle
			(at -14.249908 -21.850096)
			(size 0.4572 0.4572)
			(layers "F.Cu" "F.Mask" "F.Paste")
			(net "GND")
		)
		(pad "B11" smd circle
			(at -13.299948 -21.850096)
			(size 0.4572 0.4572)
			(layers "F.Cu" "F.Mask" "F.Paste")
			(net "P5E_PEX0_STN6_RX_DP<108>")
		)
		(pad "B12" smd circle
			(at -12.349988 -21.850096)
			(size 0.4572 0.4572)
			(layers "F.Cu" "F.Mask" "F.Paste")
			(net "GND")
		)
		(pad "B13" smd circle
			(at -11.400028 -21.850096)
			(size 0.4572 0.4572)
			(layers "F.Cu" "F.Mask" "F.Paste")
			(net "P5E_PEX0_STN6_RX_DP<106>")
		)
		(pad "B14" smd circle
			(at -10.450068 -21.850096)
			(size 0.4572 0.4572)
			(layers "F.Cu" "F.Mask" "F.Paste")
			(net "GND")
		)
		(pad "B15" smd circle
			(at -9.500108 -21.850096)
			(size 0.4572 0.4572)
			(layers "F.Cu" "F.Mask" "F.Paste")
			(net "P5E_PEX0_STN6_RX_DP<104>")
		)
		(pad "B16" smd circle
			(at -8.549894 -21.850096)
			(size 0.4572 0.4572)
			(layers "F.Cu" "F.Mask" "F.Paste")
			(net "GND")
		)
		(pad "B17" smd circle
			(at -7.599934 -21.850096)
			(size 0.4572 0.4572)
			(layers "F.Cu" "F.Mask" "F.Paste")
			(net "P5E_PEX0_STN6_RX_DP<102>")
		)
		(pad "B18" smd circle
			(at -6.649974 -21.850096)
			(size 0.4572 0.4572)
			(layers "F.Cu" "F.Mask" "F.Paste")
			(net "GND")
		)
		(pad "B19" smd circle
			(at -5.700014 -21.850096)
			(size 0.4572 0.4572)
			(layers "F.Cu" "F.Mask" "F.Paste")
			(net "P5E_PEX0_STN6_RX_DP<100>")
		)
		(pad "B20" smd circle
			(at -4.750054 -21.850096)
			(size 0.4572 0.4572)
			(layers "F.Cu" "F.Mask" "F.Paste")
			(net "GND")
		)
		(pad "B21" smd circle
			(at -3.800094 -21.850096)
			(size 0.4572 0.4572)
			(layers "F.Cu" "F.Mask" "F.Paste")
			(net "P5E_PEX0_STN6_RX_DP<98>")
		)
		(pad "B22" smd circle
			(at -2.84988 -21.850096)
			(size 0.4572 0.4572)
			(layers "F.Cu" "F.Mask" "F.Paste")
			(net "GND")
		)
		(pad "B23" smd circle
			(at -1.89992 -21.850096)
			(size 0.4572 0.4572)
			(layers "F.Cu" "F.Mask" "F.Paste")
			(net "P5E_PEX0_STN6_RX_DP<96>")
		)
		(pad "B24" smd circle
			(at -0.94996 -21.850096)
			(size 0.4572 0.4572)
			(layers "F.Cu" "F.Mask" "F.Paste")
			(net "GND")
		)
		(pad "B25" smd circle
			(at 0 -21.850096)
			(size 0.4572 0.4572)
			(layers "F.Cu" "F.Mask" "F.Paste")
			(net "P5E_PEX0_STN5_RX_DP<81>")
		)
		(pad "B26" smd circle
			(at 0.94996 -21.850096)
			(size 0.4572 0.4572)
			(layers "F.Cu" "F.Mask" "F.Paste")
			(net "GND")
		)
		(pad "B27" smd circle
			(at 1.89992 -21.850096)
			(size 0.4572 0.4572)
			(layers "F.Cu" "F.Mask" "F.Paste")
			(net "P5E_PEX0_STN5_RX_DP<83>")
		)
		(pad "B28" smd circle
			(at 2.84988 -21.850096)
			(size 0.4572 0.4572)
			(layers "F.Cu" "F.Mask" "F.Paste")
			(net "GND")
		)
		(pad "B29" smd circle
			(at 3.800094 -21.850096)
			(size 0.4572 0.4572)
			(layers "F.Cu" "F.Mask" "F.Paste")
			(net "P5E_PEX0_STN5_RX_DP<85>")
		)
		(pad "B30" smd circle
			(at 4.750054 -21.850096)
			(size 0.4572 0.4572)
			(layers "F.Cu" "F.Mask" "F.Paste")
			(net "GND")
		)
		(pad "B31" smd circle
			(at 5.700014 -21.850096)
			(size 0.4572 0.4572)
			(layers "F.Cu" "F.Mask" "F.Paste")
			(net "P5E_PEX0_STN5_RX_DP<87>")
		)
		(pad "B32" smd circle
			(at 6.649974 -21.850096)
			(size 0.4572 0.4572)
			(layers "F.Cu" "F.Mask" "F.Paste")
			(net "GND")
		)
		(pad "B33" smd circle
			(at 7.599934 -21.850096)
			(size 0.4572 0.4572)
			(layers "F.Cu" "F.Mask" "F.Paste")
			(net "P5E_PEX0_STN5_RX_DP<89>")
		)
		(pad "B34" smd circle
			(at 8.549894 -21.850096)
			(size 0.4572 0.4572)
			(layers "F.Cu" "F.Mask" "F.Paste")
			(net "GND")
		)
		(pad "B35" smd circle
			(at 9.500108 -21.850096)
			(size 0.4572 0.4572)
			(layers "F.Cu" "F.Mask" "F.Paste")
			(net "P5E_PEX0_STN5_RX_DP<91>")
		)
		(pad "B36" smd circle
			(at 10.450068 -21.850096)
			(size 0.4572 0.4572)
			(layers "F.Cu" "F.Mask" "F.Paste")
			(net "GND")
		)
		(pad "B37" smd circle
			(at 11.400028 -21.850096)
			(size 0.4572 0.4572)
			(layers "F.Cu" "F.Mask" "F.Paste")
			(net "P5E_PEX0_STN5_RX_DP<93>")
		)
		(pad "B38" smd circle
			(at 12.349988 -21.850096)
			(size 0.4572 0.4572)
			(layers "F.Cu" "F.Mask" "F.Paste")
			(net "GND")
		)
		(pad "B39" smd circle
			(at 13.299948 -21.850096)
			(size 0.4572 0.4572)
			(layers "F.Cu" "F.Mask" "F.Paste")
			(net "P5E_PEX0_STN5_RX_DP<95>")
		)
		(pad "B40" smd circle
			(at 14.249908 -21.850096)
			(size 0.4572 0.4572)
			(layers "F.Cu" "F.Mask" "F.Paste")
			(net "GND")
		)
		(pad "B41" smd circle
			(at 15.200122 -21.850096)
			(size 0.4572 0.4572)
			(layers "F.Cu" "F.Mask" "F.Paste")
			(net "P5E_PEX0_STN4_RX_DP<78>")
		)
		(pad "B42" smd circle
			(at 16.150082 -21.850096)
			(size 0.4572 0.4572)
			(layers "F.Cu" "F.Mask" "F.Paste")
			(net "GND")
		)
		(pad "B43" smd circle
			(at 17.100042 -21.850096)
			(size 0.4572 0.4572)
			(layers "F.Cu" "F.Mask" "F.Paste")
			(net "P5E_PEX0_STN4_RX_DP<76>")
		)
		(pad "B44" smd circle
			(at 18.050002 -21.850096)
			(size 0.4572 0.4572)
			(layers "F.Cu" "F.Mask" "F.Paste")
			(net "GND")
		)
		(pad "B45" smd circle
			(at 18.999962 -21.850096)
			(size 0.4572 0.4572)
			(layers "F.Cu" "F.Mask" "F.Paste")
			(net "P5E_PEX0_STN4_RX_DP<74>")
		)
		(pad "B46" smd circle
			(at 19.949922 -21.850096)
			(size 0.4572 0.4572)
			(layers "F.Cu" "F.Mask" "F.Paste")
			(net "GND")
		)
		(pad "B47" smd circle
			(at 20.899882 -21.850096)
			(size 0.4572 0.4572)
			(layers "F.Cu" "F.Mask" "F.Paste")
			(net "P5E_PEX0_STN4_RX_DP<72>")
		)
		(pad "B48" smd circle
			(at 21.850096 -21.850096)
			(size 0.4572 0.4572)
			(layers "F.Cu" "F.Mask" "F.Paste")
			(net "GND")
		)
		(pad "B49" smd circle
			(at 22.800056 -21.850096)
			(size 0.4572 0.4572)
			(layers "F.Cu" "F.Mask" "F.Paste")
			(net "GND")
		)
		(pad "BA1" smd circle
			(at -22.800056 15.200122)
			(size 0.4572 0.4572)
			(layers "F.Cu" "F.Mask" "F.Paste")
			(net "GND")
		)
		(pad "BA2" smd circle
			(at -21.850096 15.200122)
			(size 0.4572 0.4572)
			(layers "F.Cu" "F.Mask" "F.Paste")
			(net "GND")
		)
		(pad "BA3" smd circle
			(at -20.899882 15.200122)
			(size 0.4572 0.4572)
			(layers "F.Cu" "F.Mask" "F.Paste")
			(net "GND")
		)
		(pad "BA4" smd circle
			(at -19.949922 15.200122)
			(size 0.4572 0.4572)
			(layers "F.Cu" "F.Mask" "F.Paste")
			(net "Net_2761")
		)
		(pad "BA5" smd circle
			(at -18.999962 15.200122)
			(size 0.4572 0.4572)
			(layers "F.Cu" "F.Mask" "F.Paste")
			(net "GND")
		)
		(pad "BA6" smd circle
			(at -18.050002 15.200122)
			(size 0.4572 0.4572)
			(layers "F.Cu" "F.Mask" "F.Paste")
			(net "Net_2763")
		)
		(pad "BA7" smd circle
			(at -17.100042 15.200122)
			(size 0.4572 0.4572)
			(layers "F.Cu" "F.Mask" "F.Paste")
			(net "GND")
		)
		(pad "BA8" smd circle
			(at -16.150082 15.200122)
			(size 0.4572 0.4572)
			(layers "F.Cu" "F.Mask" "F.Paste")
			(net "Net_2765")
		)
		(pad "BA9" smd circle
			(at -15.200122 15.200122)
			(size 0.4572 0.4572)
			(layers "F.Cu" "F.Mask" "F.Paste")
			(net "GND")
		)
		(pad "BA10" smd circle
			(at -14.249908 15.200122)
			(size 0.4572 0.4572)
			(layers "F.Cu" "F.Mask" "F.Paste")
			(net "P5E_PEX0_STN2_TX_DP<46>")
		)
		(pad "BA11" smd circle
			(at -13.299948 15.200122)
			(size 0.4572 0.4572)
			(layers "F.Cu" "F.Mask" "F.Paste")
			(net "GND")
		)
		(pad "BA12" smd circle
			(at -12.349988 15.200122)
			(size 0.4572 0.4572)
			(layers "F.Cu" "F.Mask" "F.Paste")
			(net "P5E_PEX0_STN2_TX_DP<44>")
		)
		(pad "BA13" smd circle
			(at -11.400028 15.200122)
			(size 0.4572 0.4572)
			(layers "F.Cu" "F.Mask" "F.Paste")
			(net "GND")
		)
		(pad "BA14" smd circle
			(at -10.450068 15.200122)
			(size 0.4572 0.4572)
			(layers "F.Cu" "F.Mask" "F.Paste")
			(net "P5E_PEX0_STN2_TX_DP<42>")
		)
		(pad "BA15" smd circle
			(at -9.500108 15.200122)
			(size 0.4572 0.4572)
			(layers "F.Cu" "F.Mask" "F.Paste")
			(net "GND")
		)
		(pad "BA16" smd circle
			(at -8.549894 15.200122)
			(size 0.4572 0.4572)
			(layers "F.Cu" "F.Mask" "F.Paste")
			(net "P5E_PEX0_STN2_TX_DP<40>")
		)
		(pad "BA17" smd circle
			(at -7.599934 15.200122)
			(size 0.4572 0.4572)
			(layers "F.Cu" "F.Mask" "F.Paste")
			(net "GND")
		)
		(pad "BA18" smd circle
			(at -6.649974 15.200122)
			(size 0.4572 0.4572)
			(layers "F.Cu" "F.Mask" "F.Paste")
			(net "P5E_PEX0_STN2_TX_DP<38>")
		)
		(pad "BA19" smd circle
			(at -5.700014 15.200122)
			(size 0.4572 0.4572)
			(layers "F.Cu" "F.Mask" "F.Paste")
			(net "GND")
		)
		(pad "BA20" smd circle
			(at -4.750054 15.200122)
			(size 0.4572 0.4572)
			(layers "F.Cu" "F.Mask" "F.Paste")
			(net "P5E_PEX0_STN2_TX_DP<36>")
		)
		(pad "BA21" smd circle
			(at -3.800094 15.200122)
			(size 0.4572 0.4572)
			(layers "F.Cu" "F.Mask" "F.Paste")
			(net "GND")
		)
		(pad "BA22" smd circle
			(at -2.84988 15.200122)
			(size 0.4572 0.4572)
			(layers "F.Cu" "F.Mask" "F.Paste")
			(net "P5E_PEX0_STN2_TX_DP<34>")
		)
		(pad "BA23" smd circle
			(at -1.89992 15.200122)
			(size 0.4572 0.4572)
			(layers "F.Cu" "F.Mask" "F.Paste")
			(net "GND")
		)
		(pad "BA24" smd circle
			(at -0.94996 15.200122)
			(size 0.4572 0.4572)
			(layers "F.Cu" "F.Mask" "F.Paste")
			(net "P5E_PEX0_STN2_TX_DP<32>")
		)
		(pad "BA25" smd circle
			(at 0 15.200122)
			(size 0.4572 0.4572)
			(layers "F.Cu" "F.Mask" "F.Paste")
			(net "GND")
		)
		(pad "BA26" smd circle
			(at 0.94996 15.200122)
			(size 0.4572 0.4572)
			(layers "F.Cu" "F.Mask" "F.Paste")
			(net "P5E_PEX0_STN1_TX_DN<17>")
		)
		(pad "BA27" smd circle
			(at 1.89992 15.200122)
			(size 0.4572 0.4572)
			(layers "F.Cu" "F.Mask" "F.Paste")
			(net "GND")
		)
		(pad "BA28" smd circle
			(at 2.84988 15.200122)
			(size 0.4572 0.4572)
			(layers "F.Cu" "F.Mask" "F.Paste")
			(net "P5E_PEX0_STN1_TX_DN<19>")
		)
		(pad "BA29" smd circle
			(at 3.800094 15.200122)
			(size 0.4572 0.4572)
			(layers "F.Cu" "F.Mask" "F.Paste")
			(net "GND")
		)
		(pad "BA30" smd circle
			(at 4.750054 15.200122)
			(size 0.4572 0.4572)
			(layers "F.Cu" "F.Mask" "F.Paste")
			(net "P5E_PEX0_STN1_TX_DN<21>")
		)
		(pad "BA31" smd circle
			(at 5.700014 15.200122)
			(size 0.4572 0.4572)
			(layers "F.Cu" "F.Mask" "F.Paste")
			(net "GND")
		)
		(pad "BA32" smd circle
			(at 6.649974 15.200122)
			(size 0.4572 0.4572)
			(layers "F.Cu" "F.Mask" "F.Paste")
			(net "P5E_PEX0_STN1_TX_DN<23>")
		)
		(pad "BA33" smd circle
			(at 7.599934 15.200122)
			(size 0.4572 0.4572)
			(layers "F.Cu" "F.Mask" "F.Paste")
			(net "GND")
		)
		(pad "BA34" smd circle
			(at 8.549894 15.200122)
			(size 0.4572 0.4572)
			(layers "F.Cu" "F.Mask" "F.Paste")
			(net "P5E_PEX0_STN1_TX_DN<25>")
		)
		(pad "BA35" smd circle
			(at 9.500108 15.200122)
			(size 0.4572 0.4572)
			(layers "F.Cu" "F.Mask" "F.Paste")
			(net "GND")
		)
		(pad "BA36" smd circle
			(at 10.450068 15.200122)
			(size 0.4572 0.4572)
			(layers "F.Cu" "F.Mask" "F.Paste")
			(net "P5E_PEX0_STN1_TX_DN<27>")
		)
		(pad "BA37" smd circle
			(at 11.400028 15.200122)
			(size 0.4572 0.4572)
			(layers "F.Cu" "F.Mask" "F.Paste")
			(net "GND")
		)
		(pad "BA38" smd circle
			(at 12.349988 15.200122)
			(size 0.4572 0.4572)
			(layers "F.Cu" "F.Mask" "F.Paste")
			(net "P5E_PEX0_STN1_TX_DN<29>")
		)
		(pad "BA39" smd circle
			(at 13.299948 15.200122)
			(size 0.4572 0.4572)
			(layers "F.Cu" "F.Mask" "F.Paste")
			(net "GND")
		)
		(pad "BA40" smd circle
			(at 14.249908 15.200122)
			(size 0.4572 0.4572)
			(layers "F.Cu" "F.Mask" "F.Paste")
			(net "P5E_PEX0_STN1_TX_DN<31>")
		)
		(pad "BA41" smd circle
			(at 15.200122 15.200122)
			(size 0.4572 0.4572)
			(layers "F.Cu" "F.Mask" "F.Paste")
			(net "GND")
		)
		(pad "BA42" smd circle
			(at 16.150082 15.200122)
			(size 0.4572 0.4572)
			(layers "F.Cu" "F.Mask" "F.Paste")
			(net "P5E_PEX0_STN0_TX_DN<14>")
		)
		(pad "BA43" smd circle
			(at 17.100042 15.200122)
			(size 0.4572 0.4572)
			(layers "F.Cu" "F.Mask" "F.Paste")
			(net "GND")
		)
		(pad "BA44" smd circle
			(at 18.050002 15.200122)
			(size 0.4572 0.4572)
			(layers "F.Cu" "F.Mask" "F.Paste")
			(net "P5E_PEX0_STN0_TX_DN<12>")
		)
		(pad "BA45" smd circle
			(at 18.999962 15.200122)
			(size 0.4572 0.4572)
			(layers "F.Cu" "F.Mask" "F.Paste")
			(net "GND")
		)
		(pad "BA46" smd circle
			(at 19.949922 15.200122)
			(size 0.4572 0.4572)
			(layers "F.Cu" "F.Mask" "F.Paste")
			(net "P5E_PEX0_STN0_TX_DP<10>")
		)
		(pad "BA47" smd circle
			(at 20.899882 15.200122)
			(size 0.4572 0.4572)
			(layers "F.Cu" "F.Mask" "F.Paste")
			(net "GND")
		)
		(pad "BA48" smd circle
			(at 21.850096 15.200122)
			(size 0.4572 0.4572)
			(layers "F.Cu" "F.Mask" "F.Paste")
			(net "GND")
		)
		(pad "BA49" smd circle
			(at 22.800056 15.200122)
			(size 0.4572 0.4572)
			(layers "F.Cu" "F.Mask" "F.Paste")
			(net "GND")
		)
		(pad "BB1" smd circle
			(at -22.800056 16.150082)
			(size 0.4572 0.4572)
			(layers "F.Cu" "F.Mask" "F.Paste")
			(net "Net_2744")
		)
		(pad "BB2" smd circle
			(at -21.850096 16.150082)
			(size 0.4572 0.4572)
			(layers "F.Cu" "F.Mask" "F.Paste")
			(net "Net_2758")
		)
		(pad "BB3" smd circle
			(at -20.899882 16.150082)
			(size 0.4572 0.4572)
			(layers "F.Cu" "F.Mask" "F.Paste")
			(net "GND")
		)
		(pad "BB4" smd circle
			(at -19.949922 16.150082)
			(size 0.4572 0.4572)
			(layers "F.Cu" "F.Mask" "F.Paste")
			(net "Net_2747")
		)
		(pad "BB5" smd circle
			(at -18.999962 16.150082)
			(size 0.4572 0.4572)
			(layers "F.Cu" "F.Mask" "F.Paste")
			(net "GND")
		)
		(pad "BB6" smd circle
			(at -18.050002 16.150082)
			(size 0.4572 0.4572)
			(layers "F.Cu" "F.Mask" "F.Paste")
			(net "Net_2749")
		)
		(pad "BB7" smd circle
			(at -17.100042 16.150082)
			(size 0.4572 0.4572)
			(layers "F.Cu" "F.Mask" "F.Paste")
			(net "GND")
		)
		(pad "BB8" smd circle
			(at -16.150082 16.150082)
			(size 0.4572 0.4572)
			(layers "F.Cu" "F.Mask" "F.Paste")
			(net "Net_2751")
		)
		(pad "BB9" smd circle
			(at -15.200122 16.150082)
			(size 0.4572 0.4572)
			(layers "F.Cu" "F.Mask" "F.Paste")
			(net "GND")
		)
		(pad "BB10" smd circle
			(at -14.249908 16.150082)
			(size 0.4572 0.4572)
			(layers "F.Cu" "F.Mask" "F.Paste")
			(net "P5E_PEX0_STN2_TX_DN<46>")
		)
		(pad "BB11" smd circle
			(at -13.299948 16.150082)
			(size 0.4572 0.4572)
			(layers "F.Cu" "F.Mask" "F.Paste")
			(net "GND")
		)
		(pad "BB12" smd circle
			(at -12.349988 16.150082)
			(size 0.4572 0.4572)
			(layers "F.Cu" "F.Mask" "F.Paste")
			(net "P5E_PEX0_STN2_TX_DN<44>")
		)
		(pad "BB13" smd circle
			(at -11.400028 16.150082)
			(size 0.4572 0.4572)
			(layers "F.Cu" "F.Mask" "F.Paste")
			(net "GND")
		)
		(pad "BB14" smd circle
			(at -10.450068 16.150082)
			(size 0.4572 0.4572)
			(layers "F.Cu" "F.Mask" "F.Paste")
			(net "P5E_PEX0_STN2_TX_DN<42>")
		)
		(pad "BB15" smd circle
			(at -9.500108 16.150082)
			(size 0.4572 0.4572)
			(layers "F.Cu" "F.Mask" "F.Paste")
			(net "GND")
		)
		(pad "BB16" smd circle
			(at -8.549894 16.150082)
			(size 0.4572 0.4572)
			(layers "F.Cu" "F.Mask" "F.Paste")
			(net "P5E_PEX0_STN2_TX_DN<40>")
		)
		(pad "BB17" smd circle
			(at -7.599934 16.150082)
			(size 0.4572 0.4572)
			(layers "F.Cu" "F.Mask" "F.Paste")
			(net "GND")
		)
		(pad "BB18" smd circle
			(at -6.649974 16.150082)
			(size 0.4572 0.4572)
			(layers "F.Cu" "F.Mask" "F.Paste")
			(net "P5E_PEX0_STN2_TX_DN<38>")
		)
		(pad "BB19" smd circle
			(at -5.700014 16.150082)
			(size 0.4572 0.4572)
			(layers "F.Cu" "F.Mask" "F.Paste")
			(net "GND")
		)
		(pad "BB20" smd circle
			(at -4.750054 16.150082)
			(size 0.4572 0.4572)
			(layers "F.Cu" "F.Mask" "F.Paste")
			(net "P5E_PEX0_STN2_TX_DN<36>")
		)
		(pad "BB21" smd circle
			(at -3.800094 16.150082)
			(size 0.4572 0.4572)
			(layers "F.Cu" "F.Mask" "F.Paste")
			(net "GND")
		)
		(pad "BB22" smd circle
			(at -2.84988 16.150082)
			(size 0.4572 0.4572)
			(layers "F.Cu" "F.Mask" "F.Paste")
			(net "P5E_PEX0_STN2_TX_DN<34>")
		)
		(pad "BB23" smd circle
			(at -1.89992 16.150082)
			(size 0.4572 0.4572)
			(layers "F.Cu" "F.Mask" "F.Paste")
			(net "GND")
		)
		(pad "BB24" smd circle
			(at -0.94996 16.150082)
			(size 0.4572 0.4572)
			(layers "F.Cu" "F.Mask" "F.Paste")
			(net "P5E_PEX0_STN2_TX_DN<32>")
		)
		(pad "BB25" smd circle
			(at 0 16.150082)
			(size 0.4572 0.4572)
			(layers "F.Cu" "F.Mask" "F.Paste")
			(net "GND")
		)
		(pad "BB26" smd circle
			(at 0.94996 16.150082)
			(size 0.4572 0.4572)
			(layers "F.Cu" "F.Mask" "F.Paste")
			(net "P5E_PEX0_STN1_TX_DP<17>")
		)
		(pad "BB27" smd circle
			(at 1.89992 16.150082)
			(size 0.4572 0.4572)
			(layers "F.Cu" "F.Mask" "F.Paste")
			(net "GND")
		)
		(pad "BB28" smd circle
			(at 2.84988 16.150082)
			(size 0.4572 0.4572)
			(layers "F.Cu" "F.Mask" "F.Paste")
			(net "P5E_PEX0_STN1_TX_DP<19>")
		)
		(pad "BB29" smd circle
			(at 3.800094 16.150082)
			(size 0.4572 0.4572)
			(layers "F.Cu" "F.Mask" "F.Paste")
			(net "GND")
		)
		(pad "BB30" smd circle
			(at 4.750054 16.150082)
			(size 0.4572 0.4572)
			(layers "F.Cu" "F.Mask" "F.Paste")
			(net "P5E_PEX0_STN1_TX_DP<21>")
		)
		(pad "BB31" smd circle
			(at 5.700014 16.150082)
			(size 0.4572 0.4572)
			(layers "F.Cu" "F.Mask" "F.Paste")
			(net "GND")
		)
		(pad "BB32" smd circle
			(at 6.649974 16.150082)
			(size 0.4572 0.4572)
			(layers "F.Cu" "F.Mask" "F.Paste")
			(net "P5E_PEX0_STN1_TX_DP<23>")
		)
		(pad "BB33" smd circle
			(at 7.599934 16.150082)
			(size 0.4572 0.4572)
			(layers "F.Cu" "F.Mask" "F.Paste")
			(net "GND")
		)
		(pad "BB34" smd circle
			(at 8.549894 16.150082)
			(size 0.4572 0.4572)
			(layers "F.Cu" "F.Mask" "F.Paste")
			(net "P5E_PEX0_STN1_TX_DP<25>")
		)
		(pad "BB35" smd circle
			(at 9.500108 16.150082)
			(size 0.4572 0.4572)
			(layers "F.Cu" "F.Mask" "F.Paste")
			(net "GND")
		)
		(pad "BB36" smd circle
			(at 10.450068 16.150082)
			(size 0.4572 0.4572)
			(layers "F.Cu" "F.Mask" "F.Paste")
			(net "P5E_PEX0_STN1_TX_DP<27>")
		)
		(pad "BB37" smd circle
			(at 11.400028 16.150082)
			(size 0.4572 0.4572)
			(layers "F.Cu" "F.Mask" "F.Paste")
			(net "GND")
		)
		(pad "BB38" smd circle
			(at 12.349988 16.150082)
			(size 0.4572 0.4572)
			(layers "F.Cu" "F.Mask" "F.Paste")
			(net "P5E_PEX0_STN1_TX_DP<29>")
		)
		(pad "BB39" smd circle
			(at 13.299948 16.150082)
			(size 0.4572 0.4572)
			(layers "F.Cu" "F.Mask" "F.Paste")
			(net "GND")
		)
		(pad "BB40" smd circle
			(at 14.249908 16.150082)
			(size 0.4572 0.4572)
			(layers "F.Cu" "F.Mask" "F.Paste")
			(net "P5E_PEX0_STN1_TX_DP<31>")
		)
		(pad "BB41" smd circle
			(at 15.200122 16.150082)
			(size 0.4572 0.4572)
			(layers "F.Cu" "F.Mask" "F.Paste")
			(net "GND")
		)
		(pad "BB42" smd circle
			(at 16.150082 16.150082)
			(size 0.4572 0.4572)
			(layers "F.Cu" "F.Mask" "F.Paste")
			(net "P5E_PEX0_STN0_TX_DP<14>")
		)
		(pad "BB43" smd circle
			(at 17.100042 16.150082)
			(size 0.4572 0.4572)
			(layers "F.Cu" "F.Mask" "F.Paste")
			(net "GND")
		)
		(pad "BB44" smd circle
			(at 18.050002 16.150082)
			(size 0.4572 0.4572)
			(layers "F.Cu" "F.Mask" "F.Paste")
			(net "P5E_PEX0_STN0_TX_DP<12>")
		)
		(pad "BB45" smd circle
			(at 18.999962 16.150082)
			(size 0.4572 0.4572)
			(layers "F.Cu" "F.Mask" "F.Paste")
			(net "GND")
		)
		(pad "BB46" smd circle
			(at 19.949922 16.150082)
			(size 0.4572 0.4572)
			(layers "F.Cu" "F.Mask" "F.Paste")
			(net "P5E_PEX0_STN0_TX_DN<10>")
		)
		(pad "BB47" smd circle
			(at 20.899882 16.150082)
			(size 0.4572 0.4572)
			(layers "F.Cu" "F.Mask" "F.Paste")
			(net "GND")
		)
		(pad "BB48" smd circle
			(at 21.850096 16.150082)
			(size 0.4572 0.4572)
			(layers "F.Cu" "F.Mask" "F.Paste")
			(net "P5E_PEX0_STN0_TX_DP<7>")
		)
		(pad "BB49" smd circle
			(at 22.800056 16.150082)
			(size 0.4572 0.4572)
			(layers "F.Cu" "F.Mask" "F.Paste")
			(net "P5E_PEX0_STN0_TX_DN<7>")
		)
		(pad "BC1" smd circle
			(at -22.800056 17.100042)
			(size 0.4572 0.4572)
			(layers "F.Cu" "F.Mask" "F.Paste")
			(net "GND")
		)
		(pad "BC2" smd circle
			(at -21.850096 17.100042)
			(size 0.4572 0.4572)
			(layers "F.Cu" "F.Mask" "F.Paste")
			(net "GND")
		)
		(pad "BC3" smd circle
			(at -20.899882 17.100042)
			(size 0.4572 0.4572)
			(layers "F.Cu" "F.Mask" "F.Paste")
			(net "Net_2760")
		)
		(pad "BC4" smd circle
			(at -19.949922 17.100042)
			(size 0.4572 0.4572)
			(layers "F.Cu" "F.Mask" "F.Paste")
			(net "GND")
		)
		(pad "BC5" smd circle
			(at -18.999962 17.100042)
			(size 0.4572 0.4572)
			(layers "F.Cu" "F.Mask" "F.Paste")
			(net "Net_2762")
		)
		(pad "BC6" smd circle
			(at -18.050002 17.100042)
			(size 0.4572 0.4572)
			(layers "F.Cu" "F.Mask" "F.Paste")
			(net "GND")
		)
		(pad "BC7" smd circle
			(at -17.100042 17.100042)
			(size 0.4572 0.4572)
			(layers "F.Cu" "F.Mask" "F.Paste")
			(net "Net_2764")
		)
		(pad "BC8" smd circle
			(at -16.150082 17.100042)
			(size 0.4572 0.4572)
			(layers "F.Cu" "F.Mask" "F.Paste")
			(net "GND")
		)
		(pad "BC9" smd circle
			(at -15.200122 17.100042)
			(size 0.4572 0.4572)
			(layers "F.Cu" "F.Mask" "F.Paste")
			(net "P5E_PEX0_STN2_TX_DP<47>")
		)
		(pad "BC10" smd circle
			(at -14.249908 17.100042)
			(size 0.4572 0.4572)
			(layers "F.Cu" "F.Mask" "F.Paste")
			(net "GND")
		)
		(pad "BC11" smd circle
			(at -13.299948 17.100042)
			(size 0.4572 0.4572)
			(layers "F.Cu" "F.Mask" "F.Paste")
			(net "P5E_PEX0_STN2_TX_DP<45>")
		)
		(pad "BC12" smd circle
			(at -12.349988 17.100042)
			(size 0.4572 0.4572)
			(layers "F.Cu" "F.Mask" "F.Paste")
			(net "GND")
		)
		(pad "BC13" smd circle
			(at -11.400028 17.100042)
			(size 0.4572 0.4572)
			(layers "F.Cu" "F.Mask" "F.Paste")
			(net "P5E_PEX0_STN2_TX_DP<43>")
		)
		(pad "BC14" smd circle
			(at -10.450068 17.100042)
			(size 0.4572 0.4572)
			(layers "F.Cu" "F.Mask" "F.Paste")
			(net "GND")
		)
		(pad "BC15" smd circle
			(at -9.500108 17.100042)
			(size 0.4572 0.4572)
			(layers "F.Cu" "F.Mask" "F.Paste")
			(net "P5E_PEX0_STN2_TX_DP<41>")
		)
		(pad "BC16" smd circle
			(at -8.549894 17.100042)
			(size 0.4572 0.4572)
			(layers "F.Cu" "F.Mask" "F.Paste")
			(net "GND")
		)
		(pad "BC17" smd circle
			(at -7.599934 17.100042)
			(size 0.4572 0.4572)
			(layers "F.Cu" "F.Mask" "F.Paste")
			(net "P5E_PEX0_STN2_TX_DP<39>")
		)
		(pad "BC18" smd circle
			(at -6.649974 17.100042)
			(size 0.4572 0.4572)
			(layers "F.Cu" "F.Mask" "F.Paste")
			(net "GND")
		)
		(pad "BC19" smd circle
			(at -5.700014 17.100042)
			(size 0.4572 0.4572)
			(layers "F.Cu" "F.Mask" "F.Paste")
			(net "P5E_PEX0_STN2_TX_DP<37>")
		)
		(pad "BC20" smd circle
			(at -4.750054 17.100042)
			(size 0.4572 0.4572)
			(layers "F.Cu" "F.Mask" "F.Paste")
			(net "GND")
		)
		(pad "BC21" smd circle
			(at -3.800094 17.100042)
			(size 0.4572 0.4572)
			(layers "F.Cu" "F.Mask" "F.Paste")
			(net "P5E_PEX0_STN2_TX_DP<35>")
		)
		(pad "BC22" smd circle
			(at -2.84988 17.100042)
			(size 0.4572 0.4572)
			(layers "F.Cu" "F.Mask" "F.Paste")
			(net "GND")
		)
		(pad "BC23" smd circle
			(at -1.89992 17.100042)
			(size 0.4572 0.4572)
			(layers "F.Cu" "F.Mask" "F.Paste")
			(net "P5E_PEX0_STN2_TX_DP<33>")
		)
		(pad "BC24" smd circle
			(at -0.94996 17.100042)
			(size 0.4572 0.4572)
			(layers "F.Cu" "F.Mask" "F.Paste")
			(net "GND")
		)
		(pad "BC25" smd circle
			(at 0 17.100042)
			(size 0.4572 0.4572)
			(layers "F.Cu" "F.Mask" "F.Paste")
			(net "P5E_PEX0_STN1_TX_DP<16>")
		)
		(pad "BC26" smd circle
			(at 0.94996 17.100042)
			(size 0.4572 0.4572)
			(layers "F.Cu" "F.Mask" "F.Paste")
			(net "GND")
		)
		(pad "BC27" smd circle
			(at 1.89992 17.100042)
			(size 0.4572 0.4572)
			(layers "F.Cu" "F.Mask" "F.Paste")
			(net "P5E_PEX0_STN1_TX_DP<18>")
		)
		(pad "BC28" smd circle
			(at 2.84988 17.100042)
			(size 0.4572 0.4572)
			(layers "F.Cu" "F.Mask" "F.Paste")
			(net "GND")
		)
		(pad "BC29" smd circle
			(at 3.800094 17.100042)
			(size 0.4572 0.4572)
			(layers "F.Cu" "F.Mask" "F.Paste")
			(net "P5E_PEX0_STN1_TX_DP<20>")
		)
		(pad "BC30" smd circle
			(at 4.750054 17.100042)
			(size 0.4572 0.4572)
			(layers "F.Cu" "F.Mask" "F.Paste")
			(net "GND")
		)
		(pad "BC31" smd circle
			(at 5.700014 17.100042)
			(size 0.4572 0.4572)
			(layers "F.Cu" "F.Mask" "F.Paste")
			(net "P5E_PEX0_STN1_TX_DP<22>")
		)
		(pad "BC32" smd circle
			(at 6.649974 17.100042)
			(size 0.4572 0.4572)
			(layers "F.Cu" "F.Mask" "F.Paste")
			(net "GND")
		)
		(pad "BC33" smd circle
			(at 7.599934 17.100042)
			(size 0.4572 0.4572)
			(layers "F.Cu" "F.Mask" "F.Paste")
			(net "P5E_PEX0_STN1_TX_DP<24>")
		)
		(pad "BC34" smd circle
			(at 8.549894 17.100042)
			(size 0.4572 0.4572)
			(layers "F.Cu" "F.Mask" "F.Paste")
			(net "GND")
		)
		(pad "BC35" smd circle
			(at 9.500108 17.100042)
			(size 0.4572 0.4572)
			(layers "F.Cu" "F.Mask" "F.Paste")
			(net "P5E_PEX0_STN1_TX_DP<26>")
		)
		(pad "BC36" smd circle
			(at 10.450068 17.100042)
			(size 0.4572 0.4572)
			(layers "F.Cu" "F.Mask" "F.Paste")
			(net "GND")
		)
		(pad "BC37" smd circle
			(at 11.400028 17.100042)
			(size 0.4572 0.4572)
			(layers "F.Cu" "F.Mask" "F.Paste")
			(net "P5E_PEX0_STN1_TX_DP<28>")
		)
		(pad "BC38" smd circle
			(at 12.349988 17.100042)
			(size 0.4572 0.4572)
			(layers "F.Cu" "F.Mask" "F.Paste")
			(net "GND")
		)
		(pad "BC39" smd circle
			(at 13.299948 17.100042)
			(size 0.4572 0.4572)
			(layers "F.Cu" "F.Mask" "F.Paste")
			(net "P5E_PEX0_STN1_TX_DP<30>")
		)
		(pad "BC40" smd circle
			(at 14.249908 17.100042)
			(size 0.4572 0.4572)
			(layers "F.Cu" "F.Mask" "F.Paste")
			(net "GND")
		)
		(pad "BC41" smd circle
			(at 15.200122 17.100042)
			(size 0.4572 0.4572)
			(layers "F.Cu" "F.Mask" "F.Paste")
			(net "P5E_PEX0_STN0_TX_DP<15>")
		)
		(pad "BC42" smd circle
			(at 16.150082 17.100042)
			(size 0.4572 0.4572)
			(layers "F.Cu" "F.Mask" "F.Paste")
			(net "GND")
		)
		(pad "BC43" smd circle
			(at 17.100042 17.100042)
			(size 0.4572 0.4572)
			(layers "F.Cu" "F.Mask" "F.Paste")
			(net "P5E_PEX0_STN0_TX_DP<13>")
		)
		(pad "BC44" smd circle
			(at 18.050002 17.100042)
			(size 0.4572 0.4572)
			(layers "F.Cu" "F.Mask" "F.Paste")
			(net "GND")
		)
		(pad "BC45" smd circle
			(at 18.999962 17.100042)
			(size 0.4572 0.4572)
			(layers "F.Cu" "F.Mask" "F.Paste")
			(net "P5E_PEX0_STN0_TX_DP<11>")
		)
		(pad "BC46" smd circle
			(at 19.949922 17.100042)
			(size 0.4572 0.4572)
			(layers "F.Cu" "F.Mask" "F.Paste")
			(net "GND")
		)
		(pad "BC47" smd circle
			(at 20.899882 17.100042)
			(size 0.4572 0.4572)
			(layers "F.Cu" "F.Mask" "F.Paste")
			(net "P5E_PEX0_STN0_TX_DP<9>")
		)
		(pad "BC48" smd circle
			(at 21.850096 17.100042)
			(size 0.4572 0.4572)
			(layers "F.Cu" "F.Mask" "F.Paste")
			(net "GND")
		)
		(pad "BC49" smd circle
			(at 22.800056 17.100042)
			(size 0.4572 0.4572)
			(layers "F.Cu" "F.Mask" "F.Paste")
			(net "GND")
		)
		(pad "BD1" smd circle
			(at -22.800056 18.050002)
			(size 0.4572 0.4572)
			(layers "F.Cu" "F.Mask" "F.Paste")
			(net "GND")
		)
		(pad "BD2" smd circle
			(at -21.850096 18.050002)
			(size 0.4572 0.4572)
			(layers "F.Cu" "F.Mask" "F.Paste")
			(net "GND")
		)
		(pad "BD3" smd circle
			(at -20.899882 18.050002)
			(size 0.4572 0.4572)
			(layers "F.Cu" "F.Mask" "F.Paste")
			(net "Net_2746")
		)
		(pad "BD4" smd circle
			(at -19.949922 18.050002)
			(size 0.4572 0.4572)
			(layers "F.Cu" "F.Mask" "F.Paste")
			(net "GND")
		)
		(pad "BD5" smd circle
			(at -18.999962 18.050002)
			(size 0.4572 0.4572)
			(layers "F.Cu" "F.Mask" "F.Paste")
			(net "Net_2748")
		)
		(pad "BD6" smd circle
			(at -18.050002 18.050002)
			(size 0.4572 0.4572)
			(layers "F.Cu" "F.Mask" "F.Paste")
			(net "GND")
		)
		(pad "BD7" smd circle
			(at -17.100042 18.050002)
			(size 0.4572 0.4572)
			(layers "F.Cu" "F.Mask" "F.Paste")
			(net "Net_2750")
		)
		(pad "BD8" smd circle
			(at -16.150082 18.050002)
			(size 0.4572 0.4572)
			(layers "F.Cu" "F.Mask" "F.Paste")
			(net "GND")
		)
		(pad "BD9" smd circle
			(at -15.200122 18.050002)
			(size 0.4572 0.4572)
			(layers "F.Cu" "F.Mask" "F.Paste")
			(net "P5E_PEX0_STN2_TX_DN<47>")
		)
		(pad "BD10" smd circle
			(at -14.249908 18.050002)
			(size 0.4572 0.4572)
			(layers "F.Cu" "F.Mask" "F.Paste")
			(net "GND")
		)
		(pad "BD11" smd circle
			(at -13.299948 18.050002)
			(size 0.4572 0.4572)
			(layers "F.Cu" "F.Mask" "F.Paste")
			(net "P5E_PEX0_STN2_TX_DN<45>")
		)
		(pad "BD12" smd circle
			(at -12.349988 18.050002)
			(size 0.4572 0.4572)
			(layers "F.Cu" "F.Mask" "F.Paste")
			(net "GND")
		)
		(pad "BD13" smd circle
			(at -11.400028 18.050002)
			(size 0.4572 0.4572)
			(layers "F.Cu" "F.Mask" "F.Paste")
			(net "P5E_PEX0_STN2_TX_DN<43>")
		)
		(pad "BD14" smd circle
			(at -10.450068 18.050002)
			(size 0.4572 0.4572)
			(layers "F.Cu" "F.Mask" "F.Paste")
			(net "GND")
		)
		(pad "BD15" smd circle
			(at -9.500108 18.050002)
			(size 0.4572 0.4572)
			(layers "F.Cu" "F.Mask" "F.Paste")
			(net "P5E_PEX0_STN2_TX_DN<41>")
		)
		(pad "BD16" smd circle
			(at -8.549894 18.050002)
			(size 0.4572 0.4572)
			(layers "F.Cu" "F.Mask" "F.Paste")
			(net "GND")
		)
		(pad "BD17" smd circle
			(at -7.599934 18.050002)
			(size 0.4572 0.4572)
			(layers "F.Cu" "F.Mask" "F.Paste")
			(net "P5E_PEX0_STN2_TX_DN<39>")
		)
		(pad "BD18" smd circle
			(at -6.649974 18.050002)
			(size 0.4572 0.4572)
			(layers "F.Cu" "F.Mask" "F.Paste")
			(net "GND")
		)
		(pad "BD19" smd circle
			(at -5.700014 18.050002)
			(size 0.4572 0.4572)
			(layers "F.Cu" "F.Mask" "F.Paste")
			(net "P5E_PEX0_STN2_TX_DN<37>")
		)
		(pad "BD20" smd circle
			(at -4.750054 18.050002)
			(size 0.4572 0.4572)
			(layers "F.Cu" "F.Mask" "F.Paste")
			(net "GND")
		)
		(pad "BD21" smd circle
			(at -3.800094 18.050002)
			(size 0.4572 0.4572)
			(layers "F.Cu" "F.Mask" "F.Paste")
			(net "P5E_PEX0_STN2_TX_DN<35>")
		)
		(pad "BD22" smd circle
			(at -2.84988 18.050002)
			(size 0.4572 0.4572)
			(layers "F.Cu" "F.Mask" "F.Paste")
			(net "GND")
		)
		(pad "BD23" smd circle
			(at -1.89992 18.050002)
			(size 0.4572 0.4572)
			(layers "F.Cu" "F.Mask" "F.Paste")
			(net "P5E_PEX0_STN2_TX_DN<33>")
		)
		(pad "BD24" smd circle
			(at -0.94996 18.050002)
			(size 0.4572 0.4572)
			(layers "F.Cu" "F.Mask" "F.Paste")
			(net "GND")
		)
		(pad "BD25" smd circle
			(at 0 18.050002)
			(size 0.4572 0.4572)
			(layers "F.Cu" "F.Mask" "F.Paste")
			(net "P5E_PEX0_STN1_TX_DN<16>")
		)
		(pad "BD26" smd circle
			(at 0.94996 18.050002)
			(size 0.4572 0.4572)
			(layers "F.Cu" "F.Mask" "F.Paste")
			(net "GND")
		)
		(pad "BD27" smd circle
			(at 1.89992 18.050002)
			(size 0.4572 0.4572)
			(layers "F.Cu" "F.Mask" "F.Paste")
			(net "P5E_PEX0_STN1_TX_DN<18>")
		)
		(pad "BD28" smd circle
			(at 2.84988 18.050002)
			(size 0.4572 0.4572)
			(layers "F.Cu" "F.Mask" "F.Paste")
			(net "GND")
		)
		(pad "BD29" smd circle
			(at 3.800094 18.050002)
			(size 0.4572 0.4572)
			(layers "F.Cu" "F.Mask" "F.Paste")
			(net "P5E_PEX0_STN1_TX_DN<20>")
		)
		(pad "BD30" smd circle
			(at 4.750054 18.050002)
			(size 0.4572 0.4572)
			(layers "F.Cu" "F.Mask" "F.Paste")
			(net "GND")
		)
		(pad "BD31" smd circle
			(at 5.700014 18.050002)
			(size 0.4572 0.4572)
			(layers "F.Cu" "F.Mask" "F.Paste")
			(net "P5E_PEX0_STN1_TX_DN<22>")
		)
		(pad "BD32" smd circle
			(at 6.649974 18.050002)
			(size 0.4572 0.4572)
			(layers "F.Cu" "F.Mask" "F.Paste")
			(net "GND")
		)
		(pad "BD33" smd circle
			(at 7.599934 18.050002)
			(size 0.4572 0.4572)
			(layers "F.Cu" "F.Mask" "F.Paste")
			(net "P5E_PEX0_STN1_TX_DN<24>")
		)
		(pad "BD34" smd circle
			(at 8.549894 18.050002)
			(size 0.4572 0.4572)
			(layers "F.Cu" "F.Mask" "F.Paste")
			(net "GND")
		)
		(pad "BD35" smd circle
			(at 9.500108 18.050002)
			(size 0.4572 0.4572)
			(layers "F.Cu" "F.Mask" "F.Paste")
			(net "P5E_PEX0_STN1_TX_DN<26>")
		)
		(pad "BD36" smd circle
			(at 10.450068 18.050002)
			(size 0.4572 0.4572)
			(layers "F.Cu" "F.Mask" "F.Paste")
			(net "GND")
		)
		(pad "BD37" smd circle
			(at 11.400028 18.050002)
			(size 0.4572 0.4572)
			(layers "F.Cu" "F.Mask" "F.Paste")
			(net "P5E_PEX0_STN1_TX_DN<28>")
		)
		(pad "BD38" smd circle
			(at 12.349988 18.050002)
			(size 0.4572 0.4572)
			(layers "F.Cu" "F.Mask" "F.Paste")
			(net "GND")
		)
		(pad "BD39" smd circle
			(at 13.299948 18.050002)
			(size 0.4572 0.4572)
			(layers "F.Cu" "F.Mask" "F.Paste")
			(net "P5E_PEX0_STN1_TX_DN<30>")
		)
		(pad "BD40" smd circle
			(at 14.249908 18.050002)
			(size 0.4572 0.4572)
			(layers "F.Cu" "F.Mask" "F.Paste")
			(net "GND")
		)
		(pad "BD41" smd circle
			(at 15.200122 18.050002)
			(size 0.4572 0.4572)
			(layers "F.Cu" "F.Mask" "F.Paste")
			(net "P5E_PEX0_STN0_TX_DN<15>")
		)
		(pad "BD42" smd circle
			(at 16.150082 18.050002)
			(size 0.4572 0.4572)
			(layers "F.Cu" "F.Mask" "F.Paste")
			(net "GND")
		)
		(pad "BD43" smd circle
			(at 17.100042 18.050002)
			(size 0.4572 0.4572)
			(layers "F.Cu" "F.Mask" "F.Paste")
			(net "P5E_PEX0_STN0_TX_DN<13>")
		)
		(pad "BD44" smd circle
			(at 18.050002 18.050002)
			(size 0.4572 0.4572)
			(layers "F.Cu" "F.Mask" "F.Paste")
			(net "GND")
		)
		(pad "BD45" smd circle
			(at 18.999962 18.050002)
			(size 0.4572 0.4572)
			(layers "F.Cu" "F.Mask" "F.Paste")
			(net "P5E_PEX0_STN0_TX_DN<11>")
		)
		(pad "BD46" smd circle
			(at 19.949922 18.050002)
			(size 0.4572 0.4572)
			(layers "F.Cu" "F.Mask" "F.Paste")
			(net "GND")
		)
		(pad "BD47" smd circle
			(at 20.899882 18.050002)
			(size 0.4572 0.4572)
			(layers "F.Cu" "F.Mask" "F.Paste")
			(net "P5E_PEX0_STN0_TX_DN<9>")
		)
		(pad "BD48" smd circle
			(at 21.850096 18.050002)
			(size 0.4572 0.4572)
			(layers "F.Cu" "F.Mask" "F.Paste")
			(net "GND")
		)
		(pad "BD49" smd circle
			(at 22.800056 18.050002)
			(size 0.4572 0.4572)
			(layers "F.Cu" "F.Mask" "F.Paste")
			(net "GND")
		)
		(pad "BE1" smd circle
			(at -22.800056 18.999962)
			(size 0.4572 0.4572)
			(layers "F.Cu" "F.Mask" "F.Paste")
			(net "Net_2745")
		)
		(pad "BE2" smd circle
			(at -21.850096 18.999962)
			(size 0.4572 0.4572)
			(layers "F.Cu" "F.Mask" "F.Paste")
			(net "Net_2759")
		)
		(pad "BE3" smd circle
			(at -20.899882 18.999962)
			(size 0.4572 0.4572)
			(layers "F.Cu" "F.Mask" "F.Paste")
			(net "GND")
		)
		(pad "BE4" smd circle
			(at -19.949922 18.999962)
			(size 0.4572 0.4572)
			(layers "F.Cu" "F.Mask" "F.Paste")
			(net "GND")
		)
		(pad "BE5" smd circle
			(at -18.999962 18.999962)
			(size 0.4572 0.4572)
			(layers "F.Cu" "F.Mask" "F.Paste")
			(net "GND")
		)
		(pad "BE6" smd circle
			(at -18.050002 18.999962)
			(size 0.4572 0.4572)
			(layers "F.Cu" "F.Mask" "F.Paste")
			(net "GND")
		)
		(pad "BE7" smd circle
			(at -17.100042 18.999962)
			(size 0.4572 0.4572)
			(layers "F.Cu" "F.Mask" "F.Paste")
			(net "GND")
		)
		(pad "BE8" smd circle
			(at -16.150082 18.999962)
			(size 0.4572 0.4572)
			(layers "F.Cu" "F.Mask" "F.Paste")
			(net "GND")
		)
		(pad "BE9" smd circle
			(at -15.200122 18.999962)
			(size 0.4572 0.4572)
			(layers "F.Cu" "F.Mask" "F.Paste")
			(net "GND")
		)
		(pad "BE10" smd circle
			(at -14.249908 18.999962)
			(size 0.4572 0.4572)
			(layers "F.Cu" "F.Mask" "F.Paste")
			(net "GND")
		)
		(pad "BE11" smd circle
			(at -13.299948 18.999962)
			(size 0.4572 0.4572)
			(layers "F.Cu" "F.Mask" "F.Paste")
			(net "GND")
		)
		(pad "BE12" smd circle
			(at -12.349988 18.999962)
			(size 0.4572 0.4572)
			(layers "F.Cu" "F.Mask" "F.Paste")
			(net "GND")
		)
		(pad "BE13" smd circle
			(at -11.400028 18.999962)
			(size 0.4572 0.4572)
			(layers "F.Cu" "F.Mask" "F.Paste")
			(net "GND")
		)
		(pad "BE14" smd circle
			(at -10.450068 18.999962)
			(size 0.4572 0.4572)
			(layers "F.Cu" "F.Mask" "F.Paste")
			(net "GND")
		)
		(pad "BE15" smd circle
			(at -9.500108 18.999962)
			(size 0.4572 0.4572)
			(layers "F.Cu" "F.Mask" "F.Paste")
			(net "GND")
		)
		(pad "BE16" smd circle
			(at -8.549894 18.999962)
			(size 0.4572 0.4572)
			(layers "F.Cu" "F.Mask" "F.Paste")
			(net "GND")
		)
		(pad "BE17" smd circle
			(at -7.599934 18.999962)
			(size 0.4572 0.4572)
			(layers "F.Cu" "F.Mask" "F.Paste")
			(net "GND")
		)
		(pad "BE18" smd circle
			(at -6.649974 18.999962)
			(size 0.4572 0.4572)
			(layers "F.Cu" "F.Mask" "F.Paste")
			(net "GND")
		)
		(pad "BE19" smd circle
			(at -5.700014 18.999962)
			(size 0.4572 0.4572)
			(layers "F.Cu" "F.Mask" "F.Paste")
			(net "GND")
		)
		(pad "BE20" smd circle
			(at -4.750054 18.999962)
			(size 0.4572 0.4572)
			(layers "F.Cu" "F.Mask" "F.Paste")
			(net "GND")
		)
		(pad "BE21" smd circle
			(at -3.800094 18.999962)
			(size 0.4572 0.4572)
			(layers "F.Cu" "F.Mask" "F.Paste")
			(net "GND")
		)
		(pad "BE22" smd circle
			(at -2.84988 18.999962)
			(size 0.4572 0.4572)
			(layers "F.Cu" "F.Mask" "F.Paste")
			(net "GND")
		)
		(pad "BE23" smd circle
			(at -1.89992 18.999962)
			(size 0.4572 0.4572)
			(layers "F.Cu" "F.Mask" "F.Paste")
			(net "GND")
		)
		(pad "BE24" smd circle
			(at -0.94996 18.999962)
			(size 0.4572 0.4572)
			(layers "F.Cu" "F.Mask" "F.Paste")
			(net "GND")
		)
		(pad "BE25" smd circle
			(at 0 18.999962)
			(size 0.4572 0.4572)
			(layers "F.Cu" "F.Mask" "F.Paste")
			(net "GND")
		)
		(pad "BE26" smd circle
			(at 0.94996 18.999962)
			(size 0.4572 0.4572)
			(layers "F.Cu" "F.Mask" "F.Paste")
			(net "GND")
		)
		(pad "BE27" smd circle
			(at 1.89992 18.999962)
			(size 0.4572 0.4572)
			(layers "F.Cu" "F.Mask" "F.Paste")
			(net "GND")
		)
		(pad "BE28" smd circle
			(at 2.84988 18.999962)
			(size 0.4572 0.4572)
			(layers "F.Cu" "F.Mask" "F.Paste")
			(net "GND")
		)
		(pad "BE29" smd circle
			(at 3.800094 18.999962)
			(size 0.4572 0.4572)
			(layers "F.Cu" "F.Mask" "F.Paste")
			(net "GND")
		)
		(pad "BE30" smd circle
			(at 4.750054 18.999962)
			(size 0.4572 0.4572)
			(layers "F.Cu" "F.Mask" "F.Paste")
			(net "GND")
		)
		(pad "BE31" smd circle
			(at 5.700014 18.999962)
			(size 0.4572 0.4572)
			(layers "F.Cu" "F.Mask" "F.Paste")
			(net "GND")
		)
		(pad "BE32" smd circle
			(at 6.649974 18.999962)
			(size 0.4572 0.4572)
			(layers "F.Cu" "F.Mask" "F.Paste")
			(net "GND")
		)
		(pad "BE33" smd circle
			(at 7.599934 18.999962)
			(size 0.4572 0.4572)
			(layers "F.Cu" "F.Mask" "F.Paste")
			(net "GND")
		)
		(pad "BE34" smd circle
			(at 8.549894 18.999962)
			(size 0.4572 0.4572)
			(layers "F.Cu" "F.Mask" "F.Paste")
			(net "GND")
		)
		(pad "BE35" smd circle
			(at 9.500108 18.999962)
			(size 0.4572 0.4572)
			(layers "F.Cu" "F.Mask" "F.Paste")
			(net "GND")
		)
		(pad "BE36" smd circle
			(at 10.450068 18.999962)
			(size 0.4572 0.4572)
			(layers "F.Cu" "F.Mask" "F.Paste")
			(net "GND")
		)
		(pad "BE37" smd circle
			(at 11.400028 18.999962)
			(size 0.4572 0.4572)
			(layers "F.Cu" "F.Mask" "F.Paste")
			(net "GND")
		)
		(pad "BE38" smd circle
			(at 12.349988 18.999962)
			(size 0.4572 0.4572)
			(layers "F.Cu" "F.Mask" "F.Paste")
			(net "GND")
		)
		(pad "BE39" smd circle
			(at 13.299948 18.999962)
			(size 0.4572 0.4572)
			(layers "F.Cu" "F.Mask" "F.Paste")
			(net "GND")
		)
		(pad "BE40" smd circle
			(at 14.249908 18.999962)
			(size 0.4572 0.4572)
			(layers "F.Cu" "F.Mask" "F.Paste")
			(net "GND")
		)
		(pad "BE41" smd circle
			(at 15.200122 18.999962)
			(size 0.4572 0.4572)
			(layers "F.Cu" "F.Mask" "F.Paste")
			(net "GND")
		)
		(pad "BE42" smd circle
			(at 16.150082 18.999962)
			(size 0.4572 0.4572)
			(layers "F.Cu" "F.Mask" "F.Paste")
			(net "GND")
		)
		(pad "BE43" smd circle
			(at 17.100042 18.999962)
			(size 0.4572 0.4572)
			(layers "F.Cu" "F.Mask" "F.Paste")
			(net "GND")
		)
		(pad "BE44" smd circle
			(at 18.050002 18.999962)
			(size 0.4572 0.4572)
			(layers "F.Cu" "F.Mask" "F.Paste")
			(net "GND")
		)
		(pad "BE45" smd circle
			(at 18.999962 18.999962)
			(size 0.4572 0.4572)
			(layers "F.Cu" "F.Mask" "F.Paste")
			(net "GND")
		)
		(pad "BE46" smd circle
			(at 19.949922 18.999962)
			(size 0.4572 0.4572)
			(layers "F.Cu" "F.Mask" "F.Paste")
			(net "GND")
		)
		(pad "BE47" smd circle
			(at 20.899882 18.999962)
			(size 0.4572 0.4572)
			(layers "F.Cu" "F.Mask" "F.Paste")
			(net "GND")
		)
		(pad "BE48" smd circle
			(at 21.850096 18.999962)
			(size 0.4572 0.4572)
			(layers "F.Cu" "F.Mask" "F.Paste")
			(net "P5E_PEX0_STN0_TX_DP<8>")
		)
		(pad "BE49" smd circle
			(at 22.800056 18.999962)
			(size 0.4572 0.4572)
			(layers "F.Cu" "F.Mask" "F.Paste")
			(net "P5E_PEX0_STN0_TX_DN<8>")
		)
		(pad "BF1" smd circle
			(at -22.800056 19.949922)
			(size 0.4572 0.4572)
			(layers "F.Cu" "F.Mask" "F.Paste")
			(net "GND")
		)
		(pad "BF2" smd circle
			(at -21.850096 19.949922)
			(size 0.4572 0.4572)
			(layers "F.Cu" "F.Mask" "F.Paste")
			(net "GND")
		)
		(pad "BF3" smd circle
			(at -20.899882 19.949922)
			(size 0.4572 0.4572)
			(layers "F.Cu" "F.Mask" "F.Paste")
			(net "GND")
		)
		(pad "BF4" smd circle
			(at -19.949922 19.949922)
			(size 0.4572 0.4572)
			(layers "F.Cu" "F.Mask" "F.Paste")
			(net "Net_2733")
		)
		(pad "BF5" smd circle
			(at -18.999962 19.949922)
			(size 0.4572 0.4572)
			(layers "F.Cu" "F.Mask" "F.Paste")
			(net "GND")
		)
		(pad "BF6" smd circle
			(at -18.050002 19.949922)
			(size 0.4572 0.4572)
			(layers "F.Cu" "F.Mask" "F.Paste")
			(net "Net_2735")
		)
		(pad "BF7" smd circle
			(at -17.100042 19.949922)
			(size 0.4572 0.4572)
			(layers "F.Cu" "F.Mask" "F.Paste")
			(net "GND")
		)
		(pad "BF8" smd circle
			(at -16.150082 19.949922)
			(size 0.4572 0.4572)
			(layers "F.Cu" "F.Mask" "F.Paste")
			(net "Net_2737")
		)
		(pad "BF9" smd circle
			(at -15.200122 19.949922)
			(size 0.4572 0.4572)
			(layers "F.Cu" "F.Mask" "F.Paste")
			(net "GND")
		)
		(pad "BF10" smd circle
			(at -14.249908 19.949922)
			(size 0.4572 0.4572)
			(layers "F.Cu" "F.Mask" "F.Paste")
			(net "P5E_PEX0_STN2_RX_DP<46>")
		)
		(pad "BF11" smd circle
			(at -13.299948 19.949922)
			(size 0.4572 0.4572)
			(layers "F.Cu" "F.Mask" "F.Paste")
			(net "GND")
		)
		(pad "BF12" smd circle
			(at -12.349988 19.949922)
			(size 0.4572 0.4572)
			(layers "F.Cu" "F.Mask" "F.Paste")
			(net "P5E_PEX0_STN2_RX_DP<44>")
		)
		(pad "BF13" smd circle
			(at -11.400028 19.949922)
			(size 0.4572 0.4572)
			(layers "F.Cu" "F.Mask" "F.Paste")
			(net "GND")
		)
		(pad "BF14" smd circle
			(at -10.450068 19.949922)
			(size 0.4572 0.4572)
			(layers "F.Cu" "F.Mask" "F.Paste")
			(net "P5E_PEX0_STN2_RX_DP<42>")
		)
		(pad "BF15" smd circle
			(at -9.500108 19.949922)
			(size 0.4572 0.4572)
			(layers "F.Cu" "F.Mask" "F.Paste")
			(net "GND")
		)
		(pad "BF16" smd circle
			(at -8.549894 19.949922)
			(size 0.4572 0.4572)
			(layers "F.Cu" "F.Mask" "F.Paste")
			(net "P5E_PEX0_STN2_RX_DP<40>")
		)
		(pad "BF17" smd circle
			(at -7.599934 19.949922)
			(size 0.4572 0.4572)
			(layers "F.Cu" "F.Mask" "F.Paste")
			(net "GND")
		)
		(pad "BF18" smd circle
			(at -6.649974 19.949922)
			(size 0.4572 0.4572)
			(layers "F.Cu" "F.Mask" "F.Paste")
			(net "P5E_PEX0_STN2_RX_DP<38>")
		)
		(pad "BF19" smd circle
			(at -5.700014 19.949922)
			(size 0.4572 0.4572)
			(layers "F.Cu" "F.Mask" "F.Paste")
			(net "GND")
		)
		(pad "BF20" smd circle
			(at -4.750054 19.949922)
			(size 0.4572 0.4572)
			(layers "F.Cu" "F.Mask" "F.Paste")
			(net "P5E_PEX0_STN2_RX_DP<36>")
		)
		(pad "BF21" smd circle
			(at -3.800094 19.949922)
			(size 0.4572 0.4572)
			(layers "F.Cu" "F.Mask" "F.Paste")
			(net "GND")
		)
		(pad "BF22" smd circle
			(at -2.84988 19.949922)
			(size 0.4572 0.4572)
			(layers "F.Cu" "F.Mask" "F.Paste")
			(net "P5E_PEX0_STN2_RX_DP<34>")
		)
		(pad "BF23" smd circle
			(at -1.89992 19.949922)
			(size 0.4572 0.4572)
			(layers "F.Cu" "F.Mask" "F.Paste")
			(net "GND")
		)
		(pad "BF24" smd circle
			(at -0.94996 19.949922)
			(size 0.4572 0.4572)
			(layers "F.Cu" "F.Mask" "F.Paste")
			(net "P5E_PEX0_STN2_RX_DP<32>")
		)
		(pad "BF25" smd circle
			(at 0 19.949922)
			(size 0.4572 0.4572)
			(layers "F.Cu" "F.Mask" "F.Paste")
			(net "GND")
		)
		(pad "BF26" smd circle
			(at 0.94996 19.949922)
			(size 0.4572 0.4572)
			(layers "F.Cu" "F.Mask" "F.Paste")
			(net "P5E_PEX0_STN1_RX_DP<17>")
		)
		(pad "BF27" smd circle
			(at 1.89992 19.949922)
			(size 0.4572 0.4572)
			(layers "F.Cu" "F.Mask" "F.Paste")
			(net "GND")
		)
		(pad "BF28" smd circle
			(at 2.84988 19.949922)
			(size 0.4572 0.4572)
			(layers "F.Cu" "F.Mask" "F.Paste")
			(net "P5E_PEX0_STN1_RX_DP<19>")
		)
		(pad "BF29" smd circle
			(at 3.800094 19.949922)
			(size 0.4572 0.4572)
			(layers "F.Cu" "F.Mask" "F.Paste")
			(net "GND")
		)
		(pad "BF30" smd circle
			(at 4.750054 19.949922)
			(size 0.4572 0.4572)
			(layers "F.Cu" "F.Mask" "F.Paste")
			(net "P5E_PEX0_STN1_RX_DP<21>")
		)
		(pad "BF31" smd circle
			(at 5.700014 19.949922)
			(size 0.4572 0.4572)
			(layers "F.Cu" "F.Mask" "F.Paste")
			(net "GND")
		)
		(pad "BF32" smd circle
			(at 6.649974 19.949922)
			(size 0.4572 0.4572)
			(layers "F.Cu" "F.Mask" "F.Paste")
			(net "P5E_PEX0_STN1_RX_DP<23>")
		)
		(pad "BF33" smd circle
			(at 7.599934 19.949922)
			(size 0.4572 0.4572)
			(layers "F.Cu" "F.Mask" "F.Paste")
			(net "GND")
		)
		(pad "BF34" smd circle
			(at 8.549894 19.949922)
			(size 0.4572 0.4572)
			(layers "F.Cu" "F.Mask" "F.Paste")
			(net "P5E_PEX0_STN1_RX_DP<25>")
		)
		(pad "BF35" smd circle
			(at 9.500108 19.949922)
			(size 0.4572 0.4572)
			(layers "F.Cu" "F.Mask" "F.Paste")
			(net "GND")
		)
		(pad "BF36" smd circle
			(at 10.450068 19.949922)
			(size 0.4572 0.4572)
			(layers "F.Cu" "F.Mask" "F.Paste")
			(net "P5E_PEX0_STN1_RX_DP<27>")
		)
		(pad "BF37" smd circle
			(at 11.400028 19.949922)
			(size 0.4572 0.4572)
			(layers "F.Cu" "F.Mask" "F.Paste")
			(net "GND")
		)
		(pad "BF38" smd circle
			(at 12.349988 19.949922)
			(size 0.4572 0.4572)
			(layers "F.Cu" "F.Mask" "F.Paste")
			(net "P5E_PEX0_STN1_RX_DP<29>")
		)
		(pad "BF39" smd circle
			(at 13.299948 19.949922)
			(size 0.4572 0.4572)
			(layers "F.Cu" "F.Mask" "F.Paste")
			(net "GND")
		)
		(pad "BF40" smd circle
			(at 14.249908 19.949922)
			(size 0.4572 0.4572)
			(layers "F.Cu" "F.Mask" "F.Paste")
			(net "P5E_PEX0_STN1_RX_DP<31>")
		)
		(pad "BF41" smd circle
			(at 15.200122 19.949922)
			(size 0.4572 0.4572)
			(layers "F.Cu" "F.Mask" "F.Paste")
			(net "GND")
		)
		(pad "BF42" smd circle
			(at 16.150082 19.949922)
			(size 0.4572 0.4572)
			(layers "F.Cu" "F.Mask" "F.Paste")
			(net "P5E_PEX0_STN0_RX_DP<14>")
		)
		(pad "BF43" smd circle
			(at 17.100042 19.949922)
			(size 0.4572 0.4572)
			(layers "F.Cu" "F.Mask" "F.Paste")
			(net "GND")
		)
		(pad "BF44" smd circle
			(at 18.050002 19.949922)
			(size 0.4572 0.4572)
			(layers "F.Cu" "F.Mask" "F.Paste")
			(net "P5E_PEX0_STN0_RX_DP<12>")
		)
		(pad "BF45" smd circle
			(at 18.999962 19.949922)
			(size 0.4572 0.4572)
			(layers "F.Cu" "F.Mask" "F.Paste")
			(net "GND")
		)
		(pad "BF46" smd circle
			(at 19.949922 19.949922)
			(size 0.4572 0.4572)
			(layers "F.Cu" "F.Mask" "F.Paste")
			(net "P5E_PEX0_STN0_RX_DP<10>")
		)
		(pad "BF47" smd circle
			(at 20.899882 19.949922)
			(size 0.4572 0.4572)
			(layers "F.Cu" "F.Mask" "F.Paste")
			(net "GND")
		)
		(pad "BF48" smd circle
			(at 21.850096 19.949922)
			(size 0.4572 0.4572)
			(layers "F.Cu" "F.Mask" "F.Paste")
			(net "GND")
		)
		(pad "BF49" smd circle
			(at 22.800056 19.949922)
			(size 0.4572 0.4572)
			(layers "F.Cu" "F.Mask" "F.Paste")
			(net "GND")
		)
		(pad "BG1" smd circle
			(at -22.800056 20.899882)
			(size 0.4572 0.4572)
			(layers "F.Cu" "F.Mask" "F.Paste")
			(net "Net_2717")
		)
		(pad "BG2" smd circle
			(at -21.850096 20.899882)
			(size 0.4572 0.4572)
			(layers "F.Cu" "F.Mask" "F.Paste")
			(net "Net_2731")
		)
		(pad "BG3" smd circle
			(at -20.899882 20.899882)
			(size 0.4572 0.4572)
			(layers "F.Cu" "F.Mask" "F.Paste")
			(net "GND")
		)
		(pad "BG4" smd circle
			(at -19.949922 20.899882)
			(size 0.4572 0.4572)
			(layers "F.Cu" "F.Mask" "F.Paste")
			(net "Net_2719")
		)
		(pad "BG5" smd circle
			(at -18.999962 20.899882)
			(size 0.4572 0.4572)
			(layers "F.Cu" "F.Mask" "F.Paste")
			(net "GND")
		)
		(pad "BG6" smd circle
			(at -18.050002 20.899882)
			(size 0.4572 0.4572)
			(layers "F.Cu" "F.Mask" "F.Paste")
			(net "Net_2721")
		)
		(pad "BG7" smd circle
			(at -17.100042 20.899882)
			(size 0.4572 0.4572)
			(layers "F.Cu" "F.Mask" "F.Paste")
			(net "GND")
		)
		(pad "BG8" smd circle
			(at -16.150082 20.899882)
			(size 0.4572 0.4572)
			(layers "F.Cu" "F.Mask" "F.Paste")
			(net "Net_2723")
		)
		(pad "BG9" smd circle
			(at -15.200122 20.899882)
			(size 0.4572 0.4572)
			(layers "F.Cu" "F.Mask" "F.Paste")
			(net "GND")
		)
		(pad "BG10" smd circle
			(at -14.249908 20.899882)
			(size 0.4572 0.4572)
			(layers "F.Cu" "F.Mask" "F.Paste")
			(net "P5E_PEX0_STN2_RX_DN<46>")
		)
		(pad "BG11" smd circle
			(at -13.299948 20.899882)
			(size 0.4572 0.4572)
			(layers "F.Cu" "F.Mask" "F.Paste")
			(net "GND")
		)
		(pad "BG12" smd circle
			(at -12.349988 20.899882)
			(size 0.4572 0.4572)
			(layers "F.Cu" "F.Mask" "F.Paste")
			(net "P5E_PEX0_STN2_RX_DN<44>")
		)
		(pad "BG13" smd circle
			(at -11.400028 20.899882)
			(size 0.4572 0.4572)
			(layers "F.Cu" "F.Mask" "F.Paste")
			(net "GND")
		)
		(pad "BG14" smd circle
			(at -10.450068 20.899882)
			(size 0.4572 0.4572)
			(layers "F.Cu" "F.Mask" "F.Paste")
			(net "P5E_PEX0_STN2_RX_DN<42>")
		)
		(pad "BG15" smd circle
			(at -9.500108 20.899882)
			(size 0.4572 0.4572)
			(layers "F.Cu" "F.Mask" "F.Paste")
			(net "GND")
		)
		(pad "BG16" smd circle
			(at -8.549894 20.899882)
			(size 0.4572 0.4572)
			(layers "F.Cu" "F.Mask" "F.Paste")
			(net "P5E_PEX0_STN2_RX_DN<40>")
		)
		(pad "BG17" smd circle
			(at -7.599934 20.899882)
			(size 0.4572 0.4572)
			(layers "F.Cu" "F.Mask" "F.Paste")
			(net "GND")
		)
		(pad "BG18" smd circle
			(at -6.649974 20.899882)
			(size 0.4572 0.4572)
			(layers "F.Cu" "F.Mask" "F.Paste")
			(net "P5E_PEX0_STN2_RX_DN<38>")
		)
		(pad "BG19" smd circle
			(at -5.700014 20.899882)
			(size 0.4572 0.4572)
			(layers "F.Cu" "F.Mask" "F.Paste")
			(net "GND")
		)
		(pad "BG20" smd circle
			(at -4.750054 20.899882)
			(size 0.4572 0.4572)
			(layers "F.Cu" "F.Mask" "F.Paste")
			(net "P5E_PEX0_STN2_RX_DN<36>")
		)
		(pad "BG21" smd circle
			(at -3.800094 20.899882)
			(size 0.4572 0.4572)
			(layers "F.Cu" "F.Mask" "F.Paste")
			(net "GND")
		)
		(pad "BG22" smd circle
			(at -2.84988 20.899882)
			(size 0.4572 0.4572)
			(layers "F.Cu" "F.Mask" "F.Paste")
			(net "P5E_PEX0_STN2_RX_DN<34>")
		)
		(pad "BG23" smd circle
			(at -1.89992 20.899882)
			(size 0.4572 0.4572)
			(layers "F.Cu" "F.Mask" "F.Paste")
			(net "GND")
		)
		(pad "BG24" smd circle
			(at -0.94996 20.899882)
			(size 0.4572 0.4572)
			(layers "F.Cu" "F.Mask" "F.Paste")
			(net "P5E_PEX0_STN2_RX_DN<32>")
		)
		(pad "BG25" smd circle
			(at 0 20.899882)
			(size 0.4572 0.4572)
			(layers "F.Cu" "F.Mask" "F.Paste")
			(net "GND")
		)
		(pad "BG26" smd circle
			(at 0.94996 20.899882)
			(size 0.4572 0.4572)
			(layers "F.Cu" "F.Mask" "F.Paste")
			(net "P5E_PEX0_STN1_RX_DN<17>")
		)
		(pad "BG27" smd circle
			(at 1.89992 20.899882)
			(size 0.4572 0.4572)
			(layers "F.Cu" "F.Mask" "F.Paste")
			(net "GND")
		)
		(pad "BG28" smd circle
			(at 2.84988 20.899882)
			(size 0.4572 0.4572)
			(layers "F.Cu" "F.Mask" "F.Paste")
			(net "P5E_PEX0_STN1_RX_DN<19>")
		)
		(pad "BG29" smd circle
			(at 3.800094 20.899882)
			(size 0.4572 0.4572)
			(layers "F.Cu" "F.Mask" "F.Paste")
			(net "GND")
		)
		(pad "BG30" smd circle
			(at 4.750054 20.899882)
			(size 0.4572 0.4572)
			(layers "F.Cu" "F.Mask" "F.Paste")
			(net "P5E_PEX0_STN1_RX_DN<21>")
		)
		(pad "BG31" smd circle
			(at 5.700014 20.899882)
			(size 0.4572 0.4572)
			(layers "F.Cu" "F.Mask" "F.Paste")
			(net "GND")
		)
		(pad "BG32" smd circle
			(at 6.649974 20.899882)
			(size 0.4572 0.4572)
			(layers "F.Cu" "F.Mask" "F.Paste")
			(net "P5E_PEX0_STN1_RX_DN<23>")
		)
		(pad "BG33" smd circle
			(at 7.599934 20.899882)
			(size 0.4572 0.4572)
			(layers "F.Cu" "F.Mask" "F.Paste")
			(net "GND")
		)
		(pad "BG34" smd circle
			(at 8.549894 20.899882)
			(size 0.4572 0.4572)
			(layers "F.Cu" "F.Mask" "F.Paste")
			(net "P5E_PEX0_STN1_RX_DN<25>")
		)
		(pad "BG35" smd circle
			(at 9.500108 20.899882)
			(size 0.4572 0.4572)
			(layers "F.Cu" "F.Mask" "F.Paste")
			(net "GND")
		)
		(pad "BG36" smd circle
			(at 10.450068 20.899882)
			(size 0.4572 0.4572)
			(layers "F.Cu" "F.Mask" "F.Paste")
			(net "P5E_PEX0_STN1_RX_DN<27>")
		)
		(pad "BG37" smd circle
			(at 11.400028 20.899882)
			(size 0.4572 0.4572)
			(layers "F.Cu" "F.Mask" "F.Paste")
			(net "GND")
		)
		(pad "BG38" smd circle
			(at 12.349988 20.899882)
			(size 0.4572 0.4572)
			(layers "F.Cu" "F.Mask" "F.Paste")
			(net "P5E_PEX0_STN1_RX_DN<29>")
		)
		(pad "BG39" smd circle
			(at 13.299948 20.899882)
			(size 0.4572 0.4572)
			(layers "F.Cu" "F.Mask" "F.Paste")
			(net "GND")
		)
		(pad "BG40" smd circle
			(at 14.249908 20.899882)
			(size 0.4572 0.4572)
			(layers "F.Cu" "F.Mask" "F.Paste")
			(net "P5E_PEX0_STN1_RX_DN<31>")
		)
		(pad "BG41" smd circle
			(at 15.200122 20.899882)
			(size 0.4572 0.4572)
			(layers "F.Cu" "F.Mask" "F.Paste")
			(net "GND")
		)
		(pad "BG42" smd circle
			(at 16.150082 20.899882)
			(size 0.4572 0.4572)
			(layers "F.Cu" "F.Mask" "F.Paste")
			(net "P5E_PEX0_STN0_RX_DN<14>")
		)
		(pad "BG43" smd circle
			(at 17.100042 20.899882)
			(size 0.4572 0.4572)
			(layers "F.Cu" "F.Mask" "F.Paste")
			(net "GND")
		)
		(pad "BG44" smd circle
			(at 18.050002 20.899882)
			(size 0.4572 0.4572)
			(layers "F.Cu" "F.Mask" "F.Paste")
			(net "P5E_PEX0_STN0_RX_DN<12>")
		)
		(pad "BG45" smd circle
			(at 18.999962 20.899882)
			(size 0.4572 0.4572)
			(layers "F.Cu" "F.Mask" "F.Paste")
			(net "GND")
		)
		(pad "BG46" smd circle
			(at 19.949922 20.899882)
			(size 0.4572 0.4572)
			(layers "F.Cu" "F.Mask" "F.Paste")
			(net "P5E_PEX0_STN0_RX_DN<10>")
		)
		(pad "BG47" smd circle
			(at 20.899882 20.899882)
			(size 0.4572 0.4572)
			(layers "F.Cu" "F.Mask" "F.Paste")
			(net "GND")
		)
		(pad "BG48" smd circle
			(at 21.850096 20.899882)
			(size 0.4572 0.4572)
			(layers "F.Cu" "F.Mask" "F.Paste")
			(net "P5E_PEX0_STN0_RX_DP<8>")
		)
		(pad "BG49" smd circle
			(at 22.800056 20.899882)
			(size 0.4572 0.4572)
			(layers "F.Cu" "F.Mask" "F.Paste")
			(net "P5E_PEX0_STN0_RX_DN<8>")
		)
		(pad "BH1" smd circle
			(at -22.800056 21.850096)
			(size 0.4572 0.4572)
			(layers "F.Cu" "F.Mask" "F.Paste")
			(net "GND")
		)
		(pad "BH2" smd circle
			(at -21.850096 21.850096)
			(size 0.4572 0.4572)
			(layers "F.Cu" "F.Mask" "F.Paste")
			(net "GND")
		)
		(pad "BH3" smd circle
			(at -20.899882 21.850096)
			(size 0.4572 0.4572)
			(layers "F.Cu" "F.Mask" "F.Paste")
			(net "Net_2732")
		)
		(pad "BH4" smd circle
			(at -19.949922 21.850096)
			(size 0.4572 0.4572)
			(layers "F.Cu" "F.Mask" "F.Paste")
			(net "GND")
		)
		(pad "BH5" smd circle
			(at -18.999962 21.850096)
			(size 0.4572 0.4572)
			(layers "F.Cu" "F.Mask" "F.Paste")
			(net "Net_2734")
		)
		(pad "BH6" smd circle
			(at -18.050002 21.850096)
			(size 0.4572 0.4572)
			(layers "F.Cu" "F.Mask" "F.Paste")
			(net "GND")
		)
		(pad "BH7" smd circle
			(at -17.100042 21.850096)
			(size 0.4572 0.4572)
			(layers "F.Cu" "F.Mask" "F.Paste")
			(net "Net_2736")
		)
		(pad "BH8" smd circle
			(at -16.150082 21.850096)
			(size 0.4572 0.4572)
			(layers "F.Cu" "F.Mask" "F.Paste")
			(net "GND")
		)
		(pad "BH9" smd circle
			(at -15.200122 21.850096)
			(size 0.4572 0.4572)
			(layers "F.Cu" "F.Mask" "F.Paste")
			(net "P5E_PEX0_STN2_RX_DP<47>")
		)
		(pad "BH10" smd circle
			(at -14.249908 21.850096)
			(size 0.4572 0.4572)
			(layers "F.Cu" "F.Mask" "F.Paste")
			(net "GND")
		)
		(pad "BH11" smd circle
			(at -13.299948 21.850096)
			(size 0.4572 0.4572)
			(layers "F.Cu" "F.Mask" "F.Paste")
			(net "P5E_PEX0_STN2_RX_DP<45>")
		)
		(pad "BH12" smd circle
			(at -12.349988 21.850096)
			(size 0.4572 0.4572)
			(layers "F.Cu" "F.Mask" "F.Paste")
			(net "GND")
		)
		(pad "BH13" smd circle
			(at -11.400028 21.850096)
			(size 0.4572 0.4572)
			(layers "F.Cu" "F.Mask" "F.Paste")
			(net "P5E_PEX0_STN2_RX_DP<43>")
		)
		(pad "BH14" smd circle
			(at -10.450068 21.850096)
			(size 0.4572 0.4572)
			(layers "F.Cu" "F.Mask" "F.Paste")
			(net "GND")
		)
		(pad "BH15" smd circle
			(at -9.500108 21.850096)
			(size 0.4572 0.4572)
			(layers "F.Cu" "F.Mask" "F.Paste")
			(net "P5E_PEX0_STN2_RX_DP<41>")
		)
		(pad "BH16" smd circle
			(at -8.549894 21.850096)
			(size 0.4572 0.4572)
			(layers "F.Cu" "F.Mask" "F.Paste")
			(net "GND")
		)
		(pad "BH17" smd circle
			(at -7.599934 21.850096)
			(size 0.4572 0.4572)
			(layers "F.Cu" "F.Mask" "F.Paste")
			(net "P5E_PEX0_STN2_RX_DP<39>")
		)
		(pad "BH18" smd circle
			(at -6.649974 21.850096)
			(size 0.4572 0.4572)
			(layers "F.Cu" "F.Mask" "F.Paste")
			(net "GND")
		)
		(pad "BH19" smd circle
			(at -5.700014 21.850096)
			(size 0.4572 0.4572)
			(layers "F.Cu" "F.Mask" "F.Paste")
			(net "P5E_PEX0_STN2_RX_DP<37>")
		)
		(pad "BH20" smd circle
			(at -4.750054 21.850096)
			(size 0.4572 0.4572)
			(layers "F.Cu" "F.Mask" "F.Paste")
			(net "GND")
		)
		(pad "BH21" smd circle
			(at -3.800094 21.850096)
			(size 0.4572 0.4572)
			(layers "F.Cu" "F.Mask" "F.Paste")
			(net "P5E_PEX0_STN2_RX_DP<35>")
		)
		(pad "BH22" smd circle
			(at -2.84988 21.850096)
			(size 0.4572 0.4572)
			(layers "F.Cu" "F.Mask" "F.Paste")
			(net "GND")
		)
		(pad "BH23" smd circle
			(at -1.89992 21.850096)
			(size 0.4572 0.4572)
			(layers "F.Cu" "F.Mask" "F.Paste")
			(net "P5E_PEX0_STN2_RX_DP<33>")
		)
		(pad "BH24" smd circle
			(at -0.94996 21.850096)
			(size 0.4572 0.4572)
			(layers "F.Cu" "F.Mask" "F.Paste")
			(net "GND")
		)
		(pad "BH25" smd circle
			(at 0 21.850096)
			(size 0.4572 0.4572)
			(layers "F.Cu" "F.Mask" "F.Paste")
			(net "P5E_PEX0_STN1_RX_DP<16>")
		)
		(pad "BH26" smd circle
			(at 0.94996 21.850096)
			(size 0.4572 0.4572)
			(layers "F.Cu" "F.Mask" "F.Paste")
			(net "GND")
		)
		(pad "BH27" smd circle
			(at 1.89992 21.850096)
			(size 0.4572 0.4572)
			(layers "F.Cu" "F.Mask" "F.Paste")
			(net "P5E_PEX0_STN1_RX_DP<18>")
		)
		(pad "BH28" smd circle
			(at 2.84988 21.850096)
			(size 0.4572 0.4572)
			(layers "F.Cu" "F.Mask" "F.Paste")
			(net "GND")
		)
		(pad "BH29" smd circle
			(at 3.800094 21.850096)
			(size 0.4572 0.4572)
			(layers "F.Cu" "F.Mask" "F.Paste")
			(net "P5E_PEX0_STN1_RX_DP<20>")
		)
		(pad "BH30" smd circle
			(at 4.750054 21.850096)
			(size 0.4572 0.4572)
			(layers "F.Cu" "F.Mask" "F.Paste")
			(net "GND")
		)
		(pad "BH31" smd circle
			(at 5.700014 21.850096)
			(size 0.4572 0.4572)
			(layers "F.Cu" "F.Mask" "F.Paste")
			(net "P5E_PEX0_STN1_RX_DP<22>")
		)
		(pad "BH32" smd circle
			(at 6.649974 21.850096)
			(size 0.4572 0.4572)
			(layers "F.Cu" "F.Mask" "F.Paste")
			(net "GND")
		)
		(pad "BH33" smd circle
			(at 7.599934 21.850096)
			(size 0.4572 0.4572)
			(layers "F.Cu" "F.Mask" "F.Paste")
			(net "P5E_PEX0_STN1_RX_DP<24>")
		)
		(pad "BH34" smd circle
			(at 8.549894 21.850096)
			(size 0.4572 0.4572)
			(layers "F.Cu" "F.Mask" "F.Paste")
			(net "GND")
		)
		(pad "BH35" smd circle
			(at 9.500108 21.850096)
			(size 0.4572 0.4572)
			(layers "F.Cu" "F.Mask" "F.Paste")
			(net "P5E_PEX0_STN1_RX_DP<26>")
		)
		(pad "BH36" smd circle
			(at 10.450068 21.850096)
			(size 0.4572 0.4572)
			(layers "F.Cu" "F.Mask" "F.Paste")
			(net "GND")
		)
		(pad "BH37" smd circle
			(at 11.400028 21.850096)
			(size 0.4572 0.4572)
			(layers "F.Cu" "F.Mask" "F.Paste")
			(net "P5E_PEX0_STN1_RX_DP<28>")
		)
		(pad "BH38" smd circle
			(at 12.349988 21.850096)
			(size 0.4572 0.4572)
			(layers "F.Cu" "F.Mask" "F.Paste")
			(net "GND")
		)
		(pad "BH39" smd circle
			(at 13.299948 21.850096)
			(size 0.4572 0.4572)
			(layers "F.Cu" "F.Mask" "F.Paste")
			(net "P5E_PEX0_STN1_RX_DP<30>")
		)
		(pad "BH40" smd circle
			(at 14.249908 21.850096)
			(size 0.4572 0.4572)
			(layers "F.Cu" "F.Mask" "F.Paste")
			(net "GND")
		)
		(pad "BH41" smd circle
			(at 15.200122 21.850096)
			(size 0.4572 0.4572)
			(layers "F.Cu" "F.Mask" "F.Paste")
			(net "P5E_PEX0_STN0_RX_DP<15>")
		)
		(pad "BH42" smd circle
			(at 16.150082 21.850096)
			(size 0.4572 0.4572)
			(layers "F.Cu" "F.Mask" "F.Paste")
			(net "GND")
		)
		(pad "BH43" smd circle
			(at 17.100042 21.850096)
			(size 0.4572 0.4572)
			(layers "F.Cu" "F.Mask" "F.Paste")
			(net "P5E_PEX0_STN0_RX_DP<13>")
		)
		(pad "BH44" smd circle
			(at 18.050002 21.850096)
			(size 0.4572 0.4572)
			(layers "F.Cu" "F.Mask" "F.Paste")
			(net "GND")
		)
		(pad "BH45" smd circle
			(at 18.999962 21.850096)
			(size 0.4572 0.4572)
			(layers "F.Cu" "F.Mask" "F.Paste")
			(net "P5E_PEX0_STN0_RX_DP<11>")
		)
		(pad "BH46" smd circle
			(at 19.949922 21.850096)
			(size 0.4572 0.4572)
			(layers "F.Cu" "F.Mask" "F.Paste")
			(net "GND")
		)
		(pad "BH47" smd circle
			(at 20.899882 21.850096)
			(size 0.4572 0.4572)
			(layers "F.Cu" "F.Mask" "F.Paste")
			(net "P5E_PEX0_STN0_RX_DP<9>")
		)
		(pad "BH48" smd circle
			(at 21.850096 21.850096)
			(size 0.4572 0.4572)
			(layers "F.Cu" "F.Mask" "F.Paste")
			(net "GND")
		)
		(pad "BH49" smd circle
			(at 22.800056 21.850096)
			(size 0.4572 0.4572)
			(layers "F.Cu" "F.Mask" "F.Paste")
			(net "GND")
		)
		(pad "BJ2" smd circle
			(at -21.850096 22.800056)
			(size 0.4572 0.4572)
			(layers "F.Cu" "F.Mask" "F.Paste")
			(net "GND")
		)
		(pad "BJ3" smd circle
			(at -20.899882 22.800056)
			(size 0.4572 0.4572)
			(layers "F.Cu" "F.Mask" "F.Paste")
			(net "Net_2718")
		)
		(pad "BJ4" smd circle
			(at -19.949922 22.800056)
			(size 0.4572 0.4572)
			(layers "F.Cu" "F.Mask" "F.Paste")
			(net "GND")
		)
		(pad "BJ5" smd circle
			(at -18.999962 22.800056)
			(size 0.4572 0.4572)
			(layers "F.Cu" "F.Mask" "F.Paste")
			(net "Net_2720")
		)
		(pad "BJ6" smd circle
			(at -18.050002 22.800056)
			(size 0.4572 0.4572)
			(layers "F.Cu" "F.Mask" "F.Paste")
			(net "GND")
		)
		(pad "BJ7" smd circle
			(at -17.100042 22.800056)
			(size 0.4572 0.4572)
			(layers "F.Cu" "F.Mask" "F.Paste")
			(net "Net_2722")
		)
		(pad "BJ8" smd circle
			(at -16.150082 22.800056)
			(size 0.4572 0.4572)
			(layers "F.Cu" "F.Mask" "F.Paste")
			(net "GND")
		)
		(pad "BJ9" smd circle
			(at -15.200122 22.800056)
			(size 0.4572 0.4572)
			(layers "F.Cu" "F.Mask" "F.Paste")
			(net "P5E_PEX0_STN2_RX_DN<47>")
		)
		(pad "BJ10" smd circle
			(at -14.249908 22.800056)
			(size 0.4572 0.4572)
			(layers "F.Cu" "F.Mask" "F.Paste")
			(net "GND")
		)
		(pad "BJ11" smd circle
			(at -13.299948 22.800056)
			(size 0.4572 0.4572)
			(layers "F.Cu" "F.Mask" "F.Paste")
			(net "P5E_PEX0_STN2_RX_DN<45>")
		)
		(pad "BJ12" smd circle
			(at -12.349988 22.800056)
			(size 0.4572 0.4572)
			(layers "F.Cu" "F.Mask" "F.Paste")
			(net "GND")
		)
		(pad "BJ13" smd circle
			(at -11.400028 22.800056)
			(size 0.4572 0.4572)
			(layers "F.Cu" "F.Mask" "F.Paste")
			(net "P5E_PEX0_STN2_RX_DN<43>")
		)
		(pad "BJ14" smd circle
			(at -10.450068 22.800056)
			(size 0.4572 0.4572)
			(layers "F.Cu" "F.Mask" "F.Paste")
			(net "GND")
		)
		(pad "BJ15" smd circle
			(at -9.500108 22.800056)
			(size 0.4572 0.4572)
			(layers "F.Cu" "F.Mask" "F.Paste")
			(net "P5E_PEX0_STN2_RX_DN<41>")
		)
		(pad "BJ16" smd circle
			(at -8.549894 22.800056)
			(size 0.4572 0.4572)
			(layers "F.Cu" "F.Mask" "F.Paste")
			(net "GND")
		)
		(pad "BJ17" smd circle
			(at -7.599934 22.800056)
			(size 0.4572 0.4572)
			(layers "F.Cu" "F.Mask" "F.Paste")
			(net "P5E_PEX0_STN2_RX_DN<39>")
		)
		(pad "BJ18" smd circle
			(at -6.649974 22.800056)
			(size 0.4572 0.4572)
			(layers "F.Cu" "F.Mask" "F.Paste")
			(net "GND")
		)
		(pad "BJ19" smd circle
			(at -5.700014 22.800056)
			(size 0.4572 0.4572)
			(layers "F.Cu" "F.Mask" "F.Paste")
			(net "P5E_PEX0_STN2_RX_DN<37>")
		)
		(pad "BJ20" smd circle
			(at -4.750054 22.800056)
			(size 0.4572 0.4572)
			(layers "F.Cu" "F.Mask" "F.Paste")
			(net "GND")
		)
		(pad "BJ21" smd circle
			(at -3.800094 22.800056)
			(size 0.4572 0.4572)
			(layers "F.Cu" "F.Mask" "F.Paste")
			(net "P5E_PEX0_STN2_RX_DN<35>")
		)
		(pad "BJ22" smd circle
			(at -2.84988 22.800056)
			(size 0.4572 0.4572)
			(layers "F.Cu" "F.Mask" "F.Paste")
			(net "GND")
		)
		(pad "BJ23" smd circle
			(at -1.89992 22.800056)
			(size 0.4572 0.4572)
			(layers "F.Cu" "F.Mask" "F.Paste")
			(net "P5E_PEX0_STN2_RX_DN<33>")
		)
		(pad "BJ24" smd circle
			(at -0.94996 22.800056)
			(size 0.4572 0.4572)
			(layers "F.Cu" "F.Mask" "F.Paste")
			(net "GND")
		)
		(pad "BJ25" smd circle
			(at 0 22.800056)
			(size 0.4572 0.4572)
			(layers "F.Cu" "F.Mask" "F.Paste")
			(net "P5E_PEX0_STN1_RX_DN<16>")
		)
		(pad "BJ26" smd circle
			(at 0.94996 22.800056)
			(size 0.4572 0.4572)
			(layers "F.Cu" "F.Mask" "F.Paste")
			(net "GND")
		)
		(pad "BJ27" smd circle
			(at 1.89992 22.800056)
			(size 0.4572 0.4572)
			(layers "F.Cu" "F.Mask" "F.Paste")
			(net "P5E_PEX0_STN1_RX_DN<18>")
		)
		(pad "BJ28" smd circle
			(at 2.84988 22.800056)
			(size 0.4572 0.4572)
			(layers "F.Cu" "F.Mask" "F.Paste")
			(net "GND")
		)
		(pad "BJ29" smd circle
			(at 3.800094 22.800056)
			(size 0.4572 0.4572)
			(layers "F.Cu" "F.Mask" "F.Paste")
			(net "P5E_PEX0_STN1_RX_DN<20>")
		)
		(pad "BJ30" smd circle
			(at 4.750054 22.800056)
			(size 0.4572 0.4572)
			(layers "F.Cu" "F.Mask" "F.Paste")
			(net "GND")
		)
		(pad "BJ31" smd circle
			(at 5.700014 22.800056)
			(size 0.4572 0.4572)
			(layers "F.Cu" "F.Mask" "F.Paste")
			(net "P5E_PEX0_STN1_RX_DN<22>")
		)
		(pad "BJ32" smd circle
			(at 6.649974 22.800056)
			(size 0.4572 0.4572)
			(layers "F.Cu" "F.Mask" "F.Paste")
			(net "GND")
		)
		(pad "BJ33" smd circle
			(at 7.599934 22.800056)
			(size 0.4572 0.4572)
			(layers "F.Cu" "F.Mask" "F.Paste")
			(net "P5E_PEX0_STN1_RX_DN<24>")
		)
		(pad "BJ34" smd circle
			(at 8.549894 22.800056)
			(size 0.4572 0.4572)
			(layers "F.Cu" "F.Mask" "F.Paste")
			(net "GND")
		)
		(pad "BJ35" smd circle
			(at 9.500108 22.800056)
			(size 0.4572 0.4572)
			(layers "F.Cu" "F.Mask" "F.Paste")
			(net "P5E_PEX0_STN1_RX_DN<26>")
		)
		(pad "BJ36" smd circle
			(at 10.450068 22.800056)
			(size 0.4572 0.4572)
			(layers "F.Cu" "F.Mask" "F.Paste")
			(net "GND")
		)
		(pad "BJ37" smd circle
			(at 11.400028 22.800056)
			(size 0.4572 0.4572)
			(layers "F.Cu" "F.Mask" "F.Paste")
			(net "P5E_PEX0_STN1_RX_DN<28>")
		)
		(pad "BJ38" smd circle
			(at 12.349988 22.800056)
			(size 0.4572 0.4572)
			(layers "F.Cu" "F.Mask" "F.Paste")
			(net "GND")
		)
		(pad "BJ39" smd circle
			(at 13.299948 22.800056)
			(size 0.4572 0.4572)
			(layers "F.Cu" "F.Mask" "F.Paste")
			(net "P5E_PEX0_STN1_RX_DN<30>")
		)
		(pad "BJ40" smd circle
			(at 14.249908 22.800056)
			(size 0.4572 0.4572)
			(layers "F.Cu" "F.Mask" "F.Paste")
			(net "GND")
		)
		(pad "BJ41" smd circle
			(at 15.200122 22.800056)
			(size 0.4572 0.4572)
			(layers "F.Cu" "F.Mask" "F.Paste")
			(net "P5E_PEX0_STN0_RX_DN<15>")
		)
		(pad "BJ42" smd circle
			(at 16.150082 22.800056)
			(size 0.4572 0.4572)
			(layers "F.Cu" "F.Mask" "F.Paste")
			(net "GND")
		)
		(pad "BJ43" smd circle
			(at 17.100042 22.800056)
			(size 0.4572 0.4572)
			(layers "F.Cu" "F.Mask" "F.Paste")
			(net "P5E_PEX0_STN0_RX_DN<13>")
		)
		(pad "BJ44" smd circle
			(at 18.050002 22.800056)
			(size 0.4572 0.4572)
			(layers "F.Cu" "F.Mask" "F.Paste")
			(net "GND")
		)
		(pad "BJ45" smd circle
			(at 18.999962 22.800056)
			(size 0.4572 0.4572)
			(layers "F.Cu" "F.Mask" "F.Paste")
			(net "P5E_PEX0_STN0_RX_DN<11>")
		)
		(pad "BJ46" smd circle
			(at 19.949922 22.800056)
			(size 0.4572 0.4572)
			(layers "F.Cu" "F.Mask" "F.Paste")
			(net "GND")
		)
		(pad "BJ47" smd circle
			(at 20.899882 22.800056)
			(size 0.4572 0.4572)
			(layers "F.Cu" "F.Mask" "F.Paste")
			(net "P5E_PEX0_STN0_RX_DN<9>")
		)
		(pad "BJ48" smd circle
			(at 21.850096 22.800056)
			(size 0.4572 0.4572)
			(layers "F.Cu" "F.Mask" "F.Paste")
			(net "GND")
		)
		(pad "C1" smd circle
			(at -22.800056 -20.899882)
			(size 0.4572 0.4572)
			(layers "F.Cu" "F.Mask" "F.Paste")
			(net "P5E_PEX0_STN7_RX_DN<122>")
		)
		(pad "C2" smd circle
			(at -21.850096 -20.899882)
			(size 0.4572 0.4572)
			(layers "F.Cu" "F.Mask" "F.Paste")
			(net "P5E_PEX0_STN7_RX_DP<122>")
		)
		(pad "C3" smd circle
			(at -20.899882 -20.899882)
			(size 0.4572 0.4572)
			(layers "F.Cu" "F.Mask" "F.Paste")
			(net "GND")
		)
		(pad "C4" smd circle
			(at -19.949922 -20.899882)
			(size 0.4572 0.4572)
			(layers "F.Cu" "F.Mask" "F.Paste")
			(net "P5E_PEX0_STN7_RX_DN<124>")
		)
		(pad "C5" smd circle
			(at -18.999962 -20.899882)
			(size 0.4572 0.4572)
			(layers "F.Cu" "F.Mask" "F.Paste")
			(net "GND")
		)
		(pad "C6" smd circle
			(at -18.050002 -20.899882)
			(size 0.4572 0.4572)
			(layers "F.Cu" "F.Mask" "F.Paste")
			(net "P5E_PEX0_STN7_RX_DN<126>")
		)
		(pad "C7" smd circle
			(at -17.100042 -20.899882)
			(size 0.4572 0.4572)
			(layers "F.Cu" "F.Mask" "F.Paste")
			(net "GND")
		)
		(pad "C8" smd circle
			(at -16.150082 -20.899882)
			(size 0.4572 0.4572)
			(layers "F.Cu" "F.Mask" "F.Paste")
			(net "P5E_PEX0_STN6_RX_DN<111>")
		)
		(pad "C9" smd circle
			(at -15.200122 -20.899882)
			(size 0.4572 0.4572)
			(layers "F.Cu" "F.Mask" "F.Paste")
			(net "GND")
		)
		(pad "C10" smd circle
			(at -14.249908 -20.899882)
			(size 0.4572 0.4572)
			(layers "F.Cu" "F.Mask" "F.Paste")
			(net "P5E_PEX0_STN6_RX_DN<109>")
		)
		(pad "C11" smd circle
			(at -13.299948 -20.899882)
			(size 0.4572 0.4572)
			(layers "F.Cu" "F.Mask" "F.Paste")
			(net "GND")
		)
		(pad "C12" smd circle
			(at -12.349988 -20.899882)
			(size 0.4572 0.4572)
			(layers "F.Cu" "F.Mask" "F.Paste")
			(net "P5E_PEX0_STN6_RX_DN<107>")
		)
		(pad "C13" smd circle
			(at -11.400028 -20.899882)
			(size 0.4572 0.4572)
			(layers "F.Cu" "F.Mask" "F.Paste")
			(net "GND")
		)
		(pad "C14" smd circle
			(at -10.450068 -20.899882)
			(size 0.4572 0.4572)
			(layers "F.Cu" "F.Mask" "F.Paste")
			(net "P5E_PEX0_STN6_RX_DN<105>")
		)
		(pad "C15" smd circle
			(at -9.500108 -20.899882)
			(size 0.4572 0.4572)
			(layers "F.Cu" "F.Mask" "F.Paste")
			(net "GND")
		)
		(pad "C16" smd circle
			(at -8.549894 -20.899882)
			(size 0.4572 0.4572)
			(layers "F.Cu" "F.Mask" "F.Paste")
			(net "P5E_PEX0_STN6_RX_DN<103>")
		)
		(pad "C17" smd circle
			(at -7.599934 -20.899882)
			(size 0.4572 0.4572)
			(layers "F.Cu" "F.Mask" "F.Paste")
			(net "GND")
		)
		(pad "C18" smd circle
			(at -6.649974 -20.899882)
			(size 0.4572 0.4572)
			(layers "F.Cu" "F.Mask" "F.Paste")
			(net "P5E_PEX0_STN6_RX_DN<101>")
		)
		(pad "C19" smd circle
			(at -5.700014 -20.899882)
			(size 0.4572 0.4572)
			(layers "F.Cu" "F.Mask" "F.Paste")
			(net "GND")
		)
		(pad "C20" smd circle
			(at -4.750054 -20.899882)
			(size 0.4572 0.4572)
			(layers "F.Cu" "F.Mask" "F.Paste")
			(net "P5E_PEX0_STN6_RX_DN<99>")
		)
		(pad "C21" smd circle
			(at -3.800094 -20.899882)
			(size 0.4572 0.4572)
			(layers "F.Cu" "F.Mask" "F.Paste")
			(net "GND")
		)
		(pad "C22" smd circle
			(at -2.84988 -20.899882)
			(size 0.4572 0.4572)
			(layers "F.Cu" "F.Mask" "F.Paste")
			(net "P5E_PEX0_STN6_RX_DN<97>")
		)
		(pad "C23" smd circle
			(at -1.89992 -20.899882)
			(size 0.4572 0.4572)
			(layers "F.Cu" "F.Mask" "F.Paste")
			(net "GND")
		)
		(pad "C24" smd circle
			(at -0.94996 -20.899882)
			(size 0.4572 0.4572)
			(layers "F.Cu" "F.Mask" "F.Paste")
			(net "P5E_PEX0_STN5_RX_DN<80>")
		)
		(pad "C25" smd circle
			(at 0 -20.899882)
			(size 0.4572 0.4572)
			(layers "F.Cu" "F.Mask" "F.Paste")
			(net "GND")
		)
		(pad "C26" smd circle
			(at 0.94996 -20.899882)
			(size 0.4572 0.4572)
			(layers "F.Cu" "F.Mask" "F.Paste")
			(net "P5E_PEX0_STN5_RX_DN<82>")
		)
		(pad "C27" smd circle
			(at 1.89992 -20.899882)
			(size 0.4572 0.4572)
			(layers "F.Cu" "F.Mask" "F.Paste")
			(net "GND")
		)
		(pad "C28" smd circle
			(at 2.84988 -20.899882)
			(size 0.4572 0.4572)
			(layers "F.Cu" "F.Mask" "F.Paste")
			(net "P5E_PEX0_STN5_RX_DN<84>")
		)
		(pad "C29" smd circle
			(at 3.800094 -20.899882)
			(size 0.4572 0.4572)
			(layers "F.Cu" "F.Mask" "F.Paste")
			(net "GND")
		)
		(pad "C30" smd circle
			(at 4.750054 -20.899882)
			(size 0.4572 0.4572)
			(layers "F.Cu" "F.Mask" "F.Paste")
			(net "P5E_PEX0_STN5_RX_DN<86>")
		)
		(pad "C31" smd circle
			(at 5.700014 -20.899882)
			(size 0.4572 0.4572)
			(layers "F.Cu" "F.Mask" "F.Paste")
			(net "GND")
		)
		(pad "C32" smd circle
			(at 6.649974 -20.899882)
			(size 0.4572 0.4572)
			(layers "F.Cu" "F.Mask" "F.Paste")
			(net "P5E_PEX0_STN5_RX_DN<88>")
		)
		(pad "C33" smd circle
			(at 7.599934 -20.899882)
			(size 0.4572 0.4572)
			(layers "F.Cu" "F.Mask" "F.Paste")
			(net "GND")
		)
		(pad "C34" smd circle
			(at 8.549894 -20.899882)
			(size 0.4572 0.4572)
			(layers "F.Cu" "F.Mask" "F.Paste")
			(net "P5E_PEX0_STN5_RX_DN<90>")
		)
		(pad "C35" smd circle
			(at 9.500108 -20.899882)
			(size 0.4572 0.4572)
			(layers "F.Cu" "F.Mask" "F.Paste")
			(net "GND")
		)
		(pad "C36" smd circle
			(at 10.450068 -20.899882)
			(size 0.4572 0.4572)
			(layers "F.Cu" "F.Mask" "F.Paste")
			(net "P5E_PEX0_STN5_RX_DN<92>")
		)
		(pad "C37" smd circle
			(at 11.400028 -20.899882)
			(size 0.4572 0.4572)
			(layers "F.Cu" "F.Mask" "F.Paste")
			(net "GND")
		)
		(pad "C38" smd circle
			(at 12.349988 -20.899882)
			(size 0.4572 0.4572)
			(layers "F.Cu" "F.Mask" "F.Paste")
			(net "P5E_PEX0_STN5_RX_DN<94>")
		)
		(pad "C39" smd circle
			(at 13.299948 -20.899882)
			(size 0.4572 0.4572)
			(layers "F.Cu" "F.Mask" "F.Paste")
			(net "GND")
		)
		(pad "C40" smd circle
			(at 14.249908 -20.899882)
			(size 0.4572 0.4572)
			(layers "F.Cu" "F.Mask" "F.Paste")
			(net "P5E_PEX0_STN4_RX_DN<79>")
		)
		(pad "C41" smd circle
			(at 15.200122 -20.899882)
			(size 0.4572 0.4572)
			(layers "F.Cu" "F.Mask" "F.Paste")
			(net "GND")
		)
		(pad "C42" smd circle
			(at 16.150082 -20.899882)
			(size 0.4572 0.4572)
			(layers "F.Cu" "F.Mask" "F.Paste")
			(net "P5E_PEX0_STN4_RX_DN<77>")
		)
		(pad "C43" smd circle
			(at 17.100042 -20.899882)
			(size 0.4572 0.4572)
			(layers "F.Cu" "F.Mask" "F.Paste")
			(net "GND")
		)
		(pad "C44" smd circle
			(at 18.050002 -20.899882)
			(size 0.4572 0.4572)
			(layers "F.Cu" "F.Mask" "F.Paste")
			(net "P5E_PEX0_STN4_RX_DN<75>")
		)
		(pad "C45" smd circle
			(at 18.999962 -20.899882)
			(size 0.4572 0.4572)
			(layers "F.Cu" "F.Mask" "F.Paste")
			(net "GND")
		)
		(pad "C46" smd circle
			(at 19.949922 -20.899882)
			(size 0.4572 0.4572)
			(layers "F.Cu" "F.Mask" "F.Paste")
			(net "P5E_PEX0_STN4_RX_DN<73>")
		)
		(pad "C47" smd circle
			(at 20.899882 -20.899882)
			(size 0.4572 0.4572)
			(layers "F.Cu" "F.Mask" "F.Paste")
			(net "GND")
		)
		(pad "C48" smd circle
			(at 21.850096 -20.899882)
			(size 0.4572 0.4572)
			(layers "F.Cu" "F.Mask" "F.Paste")
			(net "P5E_PEX0_STN4_RX_DP<71>")
		)
		(pad "C49" smd circle
			(at 22.800056 -20.899882)
			(size 0.4572 0.4572)
			(layers "F.Cu" "F.Mask" "F.Paste")
			(net "P5E_PEX0_STN4_RX_DN<71>")
		)
		(pad "D1" smd circle
			(at -22.800056 -19.949922)
			(size 0.4572 0.4572)
			(layers "F.Cu" "F.Mask" "F.Paste")
			(net "GND")
		)
		(pad "D2" smd circle
			(at -21.850096 -19.949922)
			(size 0.4572 0.4572)
			(layers "F.Cu" "F.Mask" "F.Paste")
			(net "GND")
		)
		(pad "D3" smd circle
			(at -20.899882 -19.949922)
			(size 0.4572 0.4572)
			(layers "F.Cu" "F.Mask" "F.Paste")
			(net "GND")
		)
		(pad "D4" smd circle
			(at -19.949922 -19.949922)
			(size 0.4572 0.4572)
			(layers "F.Cu" "F.Mask" "F.Paste")
			(net "P5E_PEX0_STN7_RX_DP<124>")
		)
		(pad "D5" smd circle
			(at -18.999962 -19.949922)
			(size 0.4572 0.4572)
			(layers "F.Cu" "F.Mask" "F.Paste")
			(net "GND")
		)
		(pad "D6" smd circle
			(at -18.050002 -19.949922)
			(size 0.4572 0.4572)
			(layers "F.Cu" "F.Mask" "F.Paste")
			(net "P5E_PEX0_STN7_RX_DP<126>")
		)
		(pad "D7" smd circle
			(at -17.100042 -19.949922)
			(size 0.4572 0.4572)
			(layers "F.Cu" "F.Mask" "F.Paste")
			(net "GND")
		)
		(pad "D8" smd circle
			(at -16.150082 -19.949922)
			(size 0.4572 0.4572)
			(layers "F.Cu" "F.Mask" "F.Paste")
			(net "P5E_PEX0_STN6_RX_DP<111>")
		)
		(pad "D9" smd circle
			(at -15.200122 -19.949922)
			(size 0.4572 0.4572)
			(layers "F.Cu" "F.Mask" "F.Paste")
			(net "GND")
		)
		(pad "D10" smd circle
			(at -14.249908 -19.949922)
			(size 0.4572 0.4572)
			(layers "F.Cu" "F.Mask" "F.Paste")
			(net "P5E_PEX0_STN6_RX_DP<109>")
		)
		(pad "D11" smd circle
			(at -13.299948 -19.949922)
			(size 0.4572 0.4572)
			(layers "F.Cu" "F.Mask" "F.Paste")
			(net "GND")
		)
		(pad "D12" smd circle
			(at -12.349988 -19.949922)
			(size 0.4572 0.4572)
			(layers "F.Cu" "F.Mask" "F.Paste")
			(net "P5E_PEX0_STN6_RX_DP<107>")
		)
		(pad "D13" smd circle
			(at -11.400028 -19.949922)
			(size 0.4572 0.4572)
			(layers "F.Cu" "F.Mask" "F.Paste")
			(net "GND")
		)
		(pad "D14" smd circle
			(at -10.450068 -19.949922)
			(size 0.4572 0.4572)
			(layers "F.Cu" "F.Mask" "F.Paste")
			(net "P5E_PEX0_STN6_RX_DP<105>")
		)
		(pad "D15" smd circle
			(at -9.500108 -19.949922)
			(size 0.4572 0.4572)
			(layers "F.Cu" "F.Mask" "F.Paste")
			(net "GND")
		)
		(pad "D16" smd circle
			(at -8.549894 -19.949922)
			(size 0.4572 0.4572)
			(layers "F.Cu" "F.Mask" "F.Paste")
			(net "P5E_PEX0_STN6_RX_DP<103>")
		)
		(pad "D17" smd circle
			(at -7.599934 -19.949922)
			(size 0.4572 0.4572)
			(layers "F.Cu" "F.Mask" "F.Paste")
			(net "GND")
		)
		(pad "D18" smd circle
			(at -6.649974 -19.949922)
			(size 0.4572 0.4572)
			(layers "F.Cu" "F.Mask" "F.Paste")
			(net "P5E_PEX0_STN6_RX_DP<101>")
		)
		(pad "D19" smd circle
			(at -5.700014 -19.949922)
			(size 0.4572 0.4572)
			(layers "F.Cu" "F.Mask" "F.Paste")
			(net "GND")
		)
		(pad "D20" smd circle
			(at -4.750054 -19.949922)
			(size 0.4572 0.4572)
			(layers "F.Cu" "F.Mask" "F.Paste")
			(net "P5E_PEX0_STN6_RX_DP<99>")
		)
		(pad "D21" smd circle
			(at -3.800094 -19.949922)
			(size 0.4572 0.4572)
			(layers "F.Cu" "F.Mask" "F.Paste")
			(net "GND")
		)
		(pad "D22" smd circle
			(at -2.84988 -19.949922)
			(size 0.4572 0.4572)
			(layers "F.Cu" "F.Mask" "F.Paste")
			(net "P5E_PEX0_STN6_RX_DP<97>")
		)
		(pad "D23" smd circle
			(at -1.89992 -19.949922)
			(size 0.4572 0.4572)
			(layers "F.Cu" "F.Mask" "F.Paste")
			(net "GND")
		)
		(pad "D24" smd circle
			(at -0.94996 -19.949922)
			(size 0.4572 0.4572)
			(layers "F.Cu" "F.Mask" "F.Paste")
			(net "P5E_PEX0_STN5_RX_DP<80>")
		)
		(pad "D25" smd circle
			(at 0 -19.949922)
			(size 0.4572 0.4572)
			(layers "F.Cu" "F.Mask" "F.Paste")
			(net "GND")
		)
		(pad "D26" smd circle
			(at 0.94996 -19.949922)
			(size 0.4572 0.4572)
			(layers "F.Cu" "F.Mask" "F.Paste")
			(net "P5E_PEX0_STN5_RX_DP<82>")
		)
		(pad "D27" smd circle
			(at 1.89992 -19.949922)
			(size 0.4572 0.4572)
			(layers "F.Cu" "F.Mask" "F.Paste")
			(net "GND")
		)
		(pad "D28" smd circle
			(at 2.84988 -19.949922)
			(size 0.4572 0.4572)
			(layers "F.Cu" "F.Mask" "F.Paste")
			(net "P5E_PEX0_STN5_RX_DP<84>")
		)
		(pad "D29" smd circle
			(at 3.800094 -19.949922)
			(size 0.4572 0.4572)
			(layers "F.Cu" "F.Mask" "F.Paste")
			(net "GND")
		)
		(pad "D30" smd circle
			(at 4.750054 -19.949922)
			(size 0.4572 0.4572)
			(layers "F.Cu" "F.Mask" "F.Paste")
			(net "P5E_PEX0_STN5_RX_DP<86>")
		)
		(pad "D31" smd circle
			(at 5.700014 -19.949922)
			(size 0.4572 0.4572)
			(layers "F.Cu" "F.Mask" "F.Paste")
			(net "GND")
		)
		(pad "D32" smd circle
			(at 6.649974 -19.949922)
			(size 0.4572 0.4572)
			(layers "F.Cu" "F.Mask" "F.Paste")
			(net "P5E_PEX0_STN5_RX_DP<88>")
		)
		(pad "D33" smd circle
			(at 7.599934 -19.949922)
			(size 0.4572 0.4572)
			(layers "F.Cu" "F.Mask" "F.Paste")
			(net "GND")
		)
		(pad "D34" smd circle
			(at 8.549894 -19.949922)
			(size 0.4572 0.4572)
			(layers "F.Cu" "F.Mask" "F.Paste")
			(net "P5E_PEX0_STN5_RX_DP<90>")
		)
		(pad "D35" smd circle
			(at 9.500108 -19.949922)
			(size 0.4572 0.4572)
			(layers "F.Cu" "F.Mask" "F.Paste")
			(net "GND")
		)
		(pad "D36" smd circle
			(at 10.450068 -19.949922)
			(size 0.4572 0.4572)
			(layers "F.Cu" "F.Mask" "F.Paste")
			(net "P5E_PEX0_STN5_RX_DP<92>")
		)
		(pad "D37" smd circle
			(at 11.400028 -19.949922)
			(size 0.4572 0.4572)
			(layers "F.Cu" "F.Mask" "F.Paste")
			(net "GND")
		)
		(pad "D38" smd circle
			(at 12.349988 -19.949922)
			(size 0.4572 0.4572)
			(layers "F.Cu" "F.Mask" "F.Paste")
			(net "P5E_PEX0_STN5_RX_DP<94>")
		)
		(pad "D39" smd circle
			(at 13.299948 -19.949922)
			(size 0.4572 0.4572)
			(layers "F.Cu" "F.Mask" "F.Paste")
			(net "GND")
		)
		(pad "D40" smd circle
			(at 14.249908 -19.949922)
			(size 0.4572 0.4572)
			(layers "F.Cu" "F.Mask" "F.Paste")
			(net "P5E_PEX0_STN4_RX_DP<79>")
		)
		(pad "D41" smd circle
			(at 15.200122 -19.949922)
			(size 0.4572 0.4572)
			(layers "F.Cu" "F.Mask" "F.Paste")
			(net "GND")
		)
		(pad "D42" smd circle
			(at 16.150082 -19.949922)
			(size 0.4572 0.4572)
			(layers "F.Cu" "F.Mask" "F.Paste")
			(net "P5E_PEX0_STN4_RX_DP<77>")
		)
		(pad "D43" smd circle
			(at 17.100042 -19.949922)
			(size 0.4572 0.4572)
			(layers "F.Cu" "F.Mask" "F.Paste")
			(net "GND")
		)
		(pad "D44" smd circle
			(at 18.050002 -19.949922)
			(size 0.4572 0.4572)
			(layers "F.Cu" "F.Mask" "F.Paste")
			(net "P5E_PEX0_STN4_RX_DP<75>")
		)
		(pad "D45" smd circle
			(at 18.999962 -19.949922)
			(size 0.4572 0.4572)
			(layers "F.Cu" "F.Mask" "F.Paste")
			(net "GND")
		)
		(pad "D46" smd circle
			(at 19.949922 -19.949922)
			(size 0.4572 0.4572)
			(layers "F.Cu" "F.Mask" "F.Paste")
			(net "P5E_PEX0_STN4_RX_DP<73>")
		)
		(pad "D47" smd circle
			(at 20.899882 -19.949922)
			(size 0.4572 0.4572)
			(layers "F.Cu" "F.Mask" "F.Paste")
			(net "GND")
		)
		(pad "D48" smd circle
			(at 21.850096 -19.949922)
			(size 0.4572 0.4572)
			(layers "F.Cu" "F.Mask" "F.Paste")
			(net "GND")
		)
		(pad "D49" smd circle
			(at 22.800056 -19.949922)
			(size 0.4572 0.4572)
			(layers "F.Cu" "F.Mask" "F.Paste")
			(net "GND")
		)
		(pad "E1" smd circle
			(at -22.800056 -18.999962)
			(size 0.4572 0.4572)
			(layers "F.Cu" "F.Mask" "F.Paste")
			(net "P5E_PEX0_STN7_TX_DN<122>")
		)
		(pad "E2" smd circle
			(at -21.850096 -18.999962)
			(size 0.4572 0.4572)
			(layers "F.Cu" "F.Mask" "F.Paste")
			(net "P5E_PEX0_STN7_TX_DP<122>")
		)
		(pad "E3" smd circle
			(at -20.899882 -18.999962)
			(size 0.4572 0.4572)
			(layers "F.Cu" "F.Mask" "F.Paste")
			(net "GND")
		)
		(pad "E4" smd circle
			(at -19.949922 -18.999962)
			(size 0.4572 0.4572)
			(layers "F.Cu" "F.Mask" "F.Paste")
			(net "GND")
		)
		(pad "E5" smd circle
			(at -18.999962 -18.999962)
			(size 0.4572 0.4572)
			(layers "F.Cu" "F.Mask" "F.Paste")
			(net "GND")
		)
		(pad "E6" smd circle
			(at -18.050002 -18.999962)
			(size 0.4572 0.4572)
			(layers "F.Cu" "F.Mask" "F.Paste")
			(net "GND")
		)
		(pad "E7" smd circle
			(at -17.100042 -18.999962)
			(size 0.4572 0.4572)
			(layers "F.Cu" "F.Mask" "F.Paste")
			(net "GND")
		)
		(pad "E8" smd circle
			(at -16.150082 -18.999962)
			(size 0.4572 0.4572)
			(layers "F.Cu" "F.Mask" "F.Paste")
			(net "GND")
		)
		(pad "E9" smd circle
			(at -15.200122 -18.999962)
			(size 0.4572 0.4572)
			(layers "F.Cu" "F.Mask" "F.Paste")
			(net "GND")
		)
		(pad "E10" smd circle
			(at -14.249908 -18.999962)
			(size 0.4572 0.4572)
			(layers "F.Cu" "F.Mask" "F.Paste")
			(net "GND")
		)
		(pad "E11" smd circle
			(at -13.299948 -18.999962)
			(size 0.4572 0.4572)
			(layers "F.Cu" "F.Mask" "F.Paste")
			(net "GND")
		)
		(pad "E12" smd circle
			(at -12.349988 -18.999962)
			(size 0.4572 0.4572)
			(layers "F.Cu" "F.Mask" "F.Paste")
			(net "GND")
		)
		(pad "E13" smd circle
			(at -11.400028 -18.999962)
			(size 0.4572 0.4572)
			(layers "F.Cu" "F.Mask" "F.Paste")
			(net "GND")
		)
		(pad "E14" smd circle
			(at -10.450068 -18.999962)
			(size 0.4572 0.4572)
			(layers "F.Cu" "F.Mask" "F.Paste")
			(net "GND")
		)
		(pad "E15" smd circle
			(at -9.500108 -18.999962)
			(size 0.4572 0.4572)
			(layers "F.Cu" "F.Mask" "F.Paste")
			(net "GND")
		)
		(pad "E16" smd circle
			(at -8.549894 -18.999962)
			(size 0.4572 0.4572)
			(layers "F.Cu" "F.Mask" "F.Paste")
			(net "GND")
		)
		(pad "E17" smd circle
			(at -7.599934 -18.999962)
			(size 0.4572 0.4572)
			(layers "F.Cu" "F.Mask" "F.Paste")
			(net "GND")
		)
		(pad "E18" smd circle
			(at -6.649974 -18.999962)
			(size 0.4572 0.4572)
			(layers "F.Cu" "F.Mask" "F.Paste")
			(net "GND")
		)
		(pad "E19" smd circle
			(at -5.700014 -18.999962)
			(size 0.4572 0.4572)
			(layers "F.Cu" "F.Mask" "F.Paste")
			(net "GND")
		)
		(pad "E20" smd circle
			(at -4.750054 -18.999962)
			(size 0.4572 0.4572)
			(layers "F.Cu" "F.Mask" "F.Paste")
			(net "GND")
		)
		(pad "E21" smd circle
			(at -3.800094 -18.999962)
			(size 0.4572 0.4572)
			(layers "F.Cu" "F.Mask" "F.Paste")
			(net "GND")
		)
		(pad "E22" smd circle
			(at -2.84988 -18.999962)
			(size 0.4572 0.4572)
			(layers "F.Cu" "F.Mask" "F.Paste")
			(net "GND")
		)
		(pad "E23" smd circle
			(at -1.89992 -18.999962)
			(size 0.4572 0.4572)
			(layers "F.Cu" "F.Mask" "F.Paste")
			(net "GND")
		)
		(pad "E24" smd circle
			(at -0.94996 -18.999962)
			(size 0.4572 0.4572)
			(layers "F.Cu" "F.Mask" "F.Paste")
			(net "GND")
		)
		(pad "E25" smd circle
			(at 0 -18.999962)
			(size 0.4572 0.4572)
			(layers "F.Cu" "F.Mask" "F.Paste")
			(net "GND")
		)
		(pad "E26" smd circle
			(at 0.94996 -18.999962)
			(size 0.4572 0.4572)
			(layers "F.Cu" "F.Mask" "F.Paste")
			(net "GND")
		)
		(pad "E27" smd circle
			(at 1.89992 -18.999962)
			(size 0.4572 0.4572)
			(layers "F.Cu" "F.Mask" "F.Paste")
			(net "GND")
		)
		(pad "E28" smd circle
			(at 2.84988 -18.999962)
			(size 0.4572 0.4572)
			(layers "F.Cu" "F.Mask" "F.Paste")
			(net "GND")
		)
		(pad "E29" smd circle
			(at 3.800094 -18.999962)
			(size 0.4572 0.4572)
			(layers "F.Cu" "F.Mask" "F.Paste")
			(net "GND")
		)
		(pad "E30" smd circle
			(at 4.750054 -18.999962)
			(size 0.4572 0.4572)
			(layers "F.Cu" "F.Mask" "F.Paste")
			(net "GND")
		)
		(pad "E31" smd circle
			(at 5.700014 -18.999962)
			(size 0.4572 0.4572)
			(layers "F.Cu" "F.Mask" "F.Paste")
			(net "GND")
		)
		(pad "E32" smd circle
			(at 6.649974 -18.999962)
			(size 0.4572 0.4572)
			(layers "F.Cu" "F.Mask" "F.Paste")
			(net "GND")
		)
		(pad "E33" smd circle
			(at 7.599934 -18.999962)
			(size 0.4572 0.4572)
			(layers "F.Cu" "F.Mask" "F.Paste")
			(net "GND")
		)
		(pad "E34" smd circle
			(at 8.549894 -18.999962)
			(size 0.4572 0.4572)
			(layers "F.Cu" "F.Mask" "F.Paste")
			(net "GND")
		)
		(pad "E35" smd circle
			(at 9.500108 -18.999962)
			(size 0.4572 0.4572)
			(layers "F.Cu" "F.Mask" "F.Paste")
			(net "GND")
		)
		(pad "E36" smd circle
			(at 10.450068 -18.999962)
			(size 0.4572 0.4572)
			(layers "F.Cu" "F.Mask" "F.Paste")
			(net "GND")
		)
		(pad "E37" smd circle
			(at 11.400028 -18.999962)
			(size 0.4572 0.4572)
			(layers "F.Cu" "F.Mask" "F.Paste")
			(net "GND")
		)
		(pad "E38" smd circle
			(at 12.349988 -18.999962)
			(size 0.4572 0.4572)
			(layers "F.Cu" "F.Mask" "F.Paste")
			(net "GND")
		)
		(pad "E39" smd circle
			(at 13.299948 -18.999962)
			(size 0.4572 0.4572)
			(layers "F.Cu" "F.Mask" "F.Paste")
			(net "GND")
		)
		(pad "E40" smd circle
			(at 14.249908 -18.999962)
			(size 0.4572 0.4572)
			(layers "F.Cu" "F.Mask" "F.Paste")
			(net "GND")
		)
		(pad "E41" smd circle
			(at 15.200122 -18.999962)
			(size 0.4572 0.4572)
			(layers "F.Cu" "F.Mask" "F.Paste")
			(net "GND")
		)
		(pad "E42" smd circle
			(at 16.150082 -18.999962)
			(size 0.4572 0.4572)
			(layers "F.Cu" "F.Mask" "F.Paste")
			(net "GND")
		)
		(pad "E43" smd circle
			(at 17.100042 -18.999962)
			(size 0.4572 0.4572)
			(layers "F.Cu" "F.Mask" "F.Paste")
			(net "GND")
		)
		(pad "E44" smd circle
			(at 18.050002 -18.999962)
			(size 0.4572 0.4572)
			(layers "F.Cu" "F.Mask" "F.Paste")
			(net "GND")
		)
		(pad "E45" smd circle
			(at 18.999962 -18.999962)
			(size 0.4572 0.4572)
			(layers "F.Cu" "F.Mask" "F.Paste")
			(net "GND")
		)
		(pad "E46" smd circle
			(at 19.949922 -18.999962)
			(size 0.4572 0.4572)
			(layers "F.Cu" "F.Mask" "F.Paste")
			(net "GND")
		)
		(pad "E47" smd circle
			(at 20.899882 -18.999962)
			(size 0.4572 0.4572)
			(layers "F.Cu" "F.Mask" "F.Paste")
			(net "GND")
		)
		(pad "E48" smd circle
			(at 21.850096 -18.999962)
			(size 0.4572 0.4572)
			(layers "F.Cu" "F.Mask" "F.Paste")
			(net "P5E_PEX0_STN4_TX_DP<71>")
		)
		(pad "E49" smd circle
			(at 22.800056 -18.999962)
			(size 0.4572 0.4572)
			(layers "F.Cu" "F.Mask" "F.Paste")
			(net "P5E_PEX0_STN4_TX_DN<71>")
		)
		(pad "F1" smd circle
			(at -22.800056 -18.050002)
			(size 0.4572 0.4572)
			(layers "F.Cu" "F.Mask" "F.Paste")
			(net "GND")
		)
		(pad "F2" smd circle
			(at -21.850096 -18.050002)
			(size 0.4572 0.4572)
			(layers "F.Cu" "F.Mask" "F.Paste")
			(net "GND")
		)
		(pad "F3" smd circle
			(at -20.899882 -18.050002)
			(size 0.4572 0.4572)
			(layers "F.Cu" "F.Mask" "F.Paste")
			(net "P5E_PEX0_STN7_TX_DN<123>")
		)
		(pad "F4" smd circle
			(at -19.949922 -18.050002)
			(size 0.4572 0.4572)
			(layers "F.Cu" "F.Mask" "F.Paste")
			(net "GND")
		)
		(pad "F5" smd circle
			(at -18.999962 -18.050002)
			(size 0.4572 0.4572)
			(layers "F.Cu" "F.Mask" "F.Paste")
			(net "P5E_PEX0_STN7_TX_DN<125>")
		)
		(pad "F6" smd circle
			(at -18.050002 -18.050002)
			(size 0.4572 0.4572)
			(layers "F.Cu" "F.Mask" "F.Paste")
			(net "GND")
		)
		(pad "F7" smd circle
			(at -17.100042 -18.050002)
			(size 0.4572 0.4572)
			(layers "F.Cu" "F.Mask" "F.Paste")
			(net "P5E_PEX0_STN7_TX_DN<127>")
		)
		(pad "F8" smd circle
			(at -16.150082 -18.050002)
			(size 0.4572 0.4572)
			(layers "F.Cu" "F.Mask" "F.Paste")
			(net "GND")
		)
		(pad "F9" smd circle
			(at -15.200122 -18.050002)
			(size 0.4572 0.4572)
			(layers "F.Cu" "F.Mask" "F.Paste")
			(net "P5E_PEX0_STN6_TX_DN<110>")
		)
		(pad "F10" smd circle
			(at -14.249908 -18.050002)
			(size 0.4572 0.4572)
			(layers "F.Cu" "F.Mask" "F.Paste")
			(net "GND")
		)
		(pad "F11" smd circle
			(at -13.299948 -18.050002)
			(size 0.4572 0.4572)
			(layers "F.Cu" "F.Mask" "F.Paste")
			(net "P5E_PEX0_STN6_TX_DN<108>")
		)
		(pad "F12" smd circle
			(at -12.349988 -18.050002)
			(size 0.4572 0.4572)
			(layers "F.Cu" "F.Mask" "F.Paste")
			(net "GND")
		)
		(pad "F13" smd circle
			(at -11.400028 -18.050002)
			(size 0.4572 0.4572)
			(layers "F.Cu" "F.Mask" "F.Paste")
			(net "P5E_PEX0_STN6_TX_DN<106>")
		)
		(pad "F14" smd circle
			(at -10.450068 -18.050002)
			(size 0.4572 0.4572)
			(layers "F.Cu" "F.Mask" "F.Paste")
			(net "GND")
		)
		(pad "F15" smd circle
			(at -9.500108 -18.050002)
			(size 0.4572 0.4572)
			(layers "F.Cu" "F.Mask" "F.Paste")
			(net "P5E_PEX0_STN6_TX_DN<104>")
		)
		(pad "F16" smd circle
			(at -8.549894 -18.050002)
			(size 0.4572 0.4572)
			(layers "F.Cu" "F.Mask" "F.Paste")
			(net "GND")
		)
		(pad "F17" smd circle
			(at -7.599934 -18.050002)
			(size 0.4572 0.4572)
			(layers "F.Cu" "F.Mask" "F.Paste")
			(net "P5E_PEX0_STN6_TX_DN<102>")
		)
		(pad "F18" smd circle
			(at -6.649974 -18.050002)
			(size 0.4572 0.4572)
			(layers "F.Cu" "F.Mask" "F.Paste")
			(net "GND")
		)
		(pad "F19" smd circle
			(at -5.700014 -18.050002)
			(size 0.4572 0.4572)
			(layers "F.Cu" "F.Mask" "F.Paste")
			(net "P5E_PEX0_STN6_TX_DN<100>")
		)
		(pad "F20" smd circle
			(at -4.750054 -18.050002)
			(size 0.4572 0.4572)
			(layers "F.Cu" "F.Mask" "F.Paste")
			(net "GND")
		)
		(pad "F21" smd circle
			(at -3.800094 -18.050002)
			(size 0.4572 0.4572)
			(layers "F.Cu" "F.Mask" "F.Paste")
			(net "P5E_PEX0_STN6_TX_DN<98>")
		)
		(pad "F22" smd circle
			(at -2.84988 -18.050002)
			(size 0.4572 0.4572)
			(layers "F.Cu" "F.Mask" "F.Paste")
			(net "GND")
		)
		(pad "F23" smd circle
			(at -1.89992 -18.050002)
			(size 0.4572 0.4572)
			(layers "F.Cu" "F.Mask" "F.Paste")
			(net "P5E_PEX0_STN6_TX_DN<96>")
		)
		(pad "F24" smd circle
			(at -0.94996 -18.050002)
			(size 0.4572 0.4572)
			(layers "F.Cu" "F.Mask" "F.Paste")
			(net "GND")
		)
		(pad "F25" smd circle
			(at 0 -18.050002)
			(size 0.4572 0.4572)
			(layers "F.Cu" "F.Mask" "F.Paste")
			(net "P5E_PEX0_STN5_TX_DN<81>")
		)
		(pad "F26" smd circle
			(at 0.94996 -18.050002)
			(size 0.4572 0.4572)
			(layers "F.Cu" "F.Mask" "F.Paste")
			(net "GND")
		)
		(pad "F27" smd circle
			(at 1.89992 -18.050002)
			(size 0.4572 0.4572)
			(layers "F.Cu" "F.Mask" "F.Paste")
			(net "P5E_PEX0_STN5_TX_DN<83>")
		)
		(pad "F28" smd circle
			(at 2.84988 -18.050002)
			(size 0.4572 0.4572)
			(layers "F.Cu" "F.Mask" "F.Paste")
			(net "GND")
		)
		(pad "F29" smd circle
			(at 3.800094 -18.050002)
			(size 0.4572 0.4572)
			(layers "F.Cu" "F.Mask" "F.Paste")
			(net "P5E_PEX0_STN5_TX_DN<85>")
		)
		(pad "F30" smd circle
			(at 4.750054 -18.050002)
			(size 0.4572 0.4572)
			(layers "F.Cu" "F.Mask" "F.Paste")
			(net "GND")
		)
		(pad "F31" smd circle
			(at 5.700014 -18.050002)
			(size 0.4572 0.4572)
			(layers "F.Cu" "F.Mask" "F.Paste")
			(net "P5E_PEX0_STN5_TX_DN<87>")
		)
		(pad "F32" smd circle
			(at 6.649974 -18.050002)
			(size 0.4572 0.4572)
			(layers "F.Cu" "F.Mask" "F.Paste")
			(net "GND")
		)
		(pad "F33" smd circle
			(at 7.599934 -18.050002)
			(size 0.4572 0.4572)
			(layers "F.Cu" "F.Mask" "F.Paste")
			(net "P5E_PEX0_STN5_TX_DN<89>")
		)
		(pad "F34" smd circle
			(at 8.549894 -18.050002)
			(size 0.4572 0.4572)
			(layers "F.Cu" "F.Mask" "F.Paste")
			(net "GND")
		)
		(pad "F35" smd circle
			(at 9.500108 -18.050002)
			(size 0.4572 0.4572)
			(layers "F.Cu" "F.Mask" "F.Paste")
			(net "P5E_PEX0_STN5_TX_DN<91>")
		)
		(pad "F36" smd circle
			(at 10.450068 -18.050002)
			(size 0.4572 0.4572)
			(layers "F.Cu" "F.Mask" "F.Paste")
			(net "GND")
		)
		(pad "F37" smd circle
			(at 11.400028 -18.050002)
			(size 0.4572 0.4572)
			(layers "F.Cu" "F.Mask" "F.Paste")
			(net "P5E_PEX0_STN5_TX_DN<93>")
		)
		(pad "F38" smd circle
			(at 12.349988 -18.050002)
			(size 0.4572 0.4572)
			(layers "F.Cu" "F.Mask" "F.Paste")
			(net "GND")
		)
		(pad "F39" smd circle
			(at 13.299948 -18.050002)
			(size 0.4572 0.4572)
			(layers "F.Cu" "F.Mask" "F.Paste")
			(net "P5E_PEX0_STN5_TX_DN<95>")
		)
		(pad "F40" smd circle
			(at 14.249908 -18.050002)
			(size 0.4572 0.4572)
			(layers "F.Cu" "F.Mask" "F.Paste")
			(net "GND")
		)
		(pad "F41" smd circle
			(at 15.200122 -18.050002)
			(size 0.4572 0.4572)
			(layers "F.Cu" "F.Mask" "F.Paste")
			(net "P5E_PEX0_STN4_TX_DN<78>")
		)
		(pad "F42" smd circle
			(at 16.150082 -18.050002)
			(size 0.4572 0.4572)
			(layers "F.Cu" "F.Mask" "F.Paste")
			(net "GND")
		)
		(pad "F43" smd circle
			(at 17.100042 -18.050002)
			(size 0.4572 0.4572)
			(layers "F.Cu" "F.Mask" "F.Paste")
			(net "P5E_PEX0_STN4_TX_DN<76>")
		)
		(pad "F44" smd circle
			(at 18.050002 -18.050002)
			(size 0.4572 0.4572)
			(layers "F.Cu" "F.Mask" "F.Paste")
			(net "GND")
		)
		(pad "F45" smd circle
			(at 18.999962 -18.050002)
			(size 0.4572 0.4572)
			(layers "F.Cu" "F.Mask" "F.Paste")
			(net "P5E_PEX0_STN4_TX_DN<74>")
		)
		(pad "F46" smd circle
			(at 19.949922 -18.050002)
			(size 0.4572 0.4572)
			(layers "F.Cu" "F.Mask" "F.Paste")
			(net "GND")
		)
		(pad "F47" smd circle
			(at 20.899882 -18.050002)
			(size 0.4572 0.4572)
			(layers "F.Cu" "F.Mask" "F.Paste")
			(net "P5E_PEX0_STN4_TX_DN<72>")
		)
		(pad "F48" smd circle
			(at 21.850096 -18.050002)
			(size 0.4572 0.4572)
			(layers "F.Cu" "F.Mask" "F.Paste")
			(net "GND")
		)
		(pad "F49" smd circle
			(at 22.800056 -18.050002)
			(size 0.4572 0.4572)
			(layers "F.Cu" "F.Mask" "F.Paste")
			(net "GND")
		)
		(pad "G1" smd circle
			(at -22.800056 -17.100042)
			(size 0.4572 0.4572)
			(layers "F.Cu" "F.Mask" "F.Paste")
			(net "GND")
		)
		(pad "G2" smd circle
			(at -21.850096 -17.100042)
			(size 0.4572 0.4572)
			(layers "F.Cu" "F.Mask" "F.Paste")
			(net "GND")
		)
		(pad "G3" smd circle
			(at -20.899882 -17.100042)
			(size 0.4572 0.4572)
			(layers "F.Cu" "F.Mask" "F.Paste")
			(net "P5E_PEX0_STN7_TX_DP<123>")
		)
		(pad "G4" smd circle
			(at -19.949922 -17.100042)
			(size 0.4572 0.4572)
			(layers "F.Cu" "F.Mask" "F.Paste")
			(net "GND")
		)
		(pad "G5" smd circle
			(at -18.999962 -17.100042)
			(size 0.4572 0.4572)
			(layers "F.Cu" "F.Mask" "F.Paste")
			(net "P5E_PEX0_STN7_TX_DP<125>")
		)
		(pad "G6" smd circle
			(at -18.050002 -17.100042)
			(size 0.4572 0.4572)
			(layers "F.Cu" "F.Mask" "F.Paste")
			(net "GND")
		)
		(pad "G7" smd circle
			(at -17.100042 -17.100042)
			(size 0.4572 0.4572)
			(layers "F.Cu" "F.Mask" "F.Paste")
			(net "P5E_PEX0_STN7_TX_DP<127>")
		)
		(pad "G8" smd circle
			(at -16.150082 -17.100042)
			(size 0.4572 0.4572)
			(layers "F.Cu" "F.Mask" "F.Paste")
			(net "GND")
		)
		(pad "G9" smd circle
			(at -15.200122 -17.100042)
			(size 0.4572 0.4572)
			(layers "F.Cu" "F.Mask" "F.Paste")
			(net "P5E_PEX0_STN6_TX_DP<110>")
		)
		(pad "G10" smd circle
			(at -14.249908 -17.100042)
			(size 0.4572 0.4572)
			(layers "F.Cu" "F.Mask" "F.Paste")
			(net "GND")
		)
		(pad "G11" smd circle
			(at -13.299948 -17.100042)
			(size 0.4572 0.4572)
			(layers "F.Cu" "F.Mask" "F.Paste")
			(net "P5E_PEX0_STN6_TX_DP<108>")
		)
		(pad "G12" smd circle
			(at -12.349988 -17.100042)
			(size 0.4572 0.4572)
			(layers "F.Cu" "F.Mask" "F.Paste")
			(net "GND")
		)
		(pad "G13" smd circle
			(at -11.400028 -17.100042)
			(size 0.4572 0.4572)
			(layers "F.Cu" "F.Mask" "F.Paste")
			(net "P5E_PEX0_STN6_TX_DP<106>")
		)
		(pad "G14" smd circle
			(at -10.450068 -17.100042)
			(size 0.4572 0.4572)
			(layers "F.Cu" "F.Mask" "F.Paste")
			(net "GND")
		)
		(pad "G15" smd circle
			(at -9.500108 -17.100042)
			(size 0.4572 0.4572)
			(layers "F.Cu" "F.Mask" "F.Paste")
			(net "P5E_PEX0_STN6_TX_DP<104>")
		)
		(pad "G16" smd circle
			(at -8.549894 -17.100042)
			(size 0.4572 0.4572)
			(layers "F.Cu" "F.Mask" "F.Paste")
			(net "GND")
		)
		(pad "G17" smd circle
			(at -7.599934 -17.100042)
			(size 0.4572 0.4572)
			(layers "F.Cu" "F.Mask" "F.Paste")
			(net "P5E_PEX0_STN6_TX_DP<102>")
		)
		(pad "G18" smd circle
			(at -6.649974 -17.100042)
			(size 0.4572 0.4572)
			(layers "F.Cu" "F.Mask" "F.Paste")
			(net "GND")
		)
		(pad "G19" smd circle
			(at -5.700014 -17.100042)
			(size 0.4572 0.4572)
			(layers "F.Cu" "F.Mask" "F.Paste")
			(net "P5E_PEX0_STN6_TX_DP<100>")
		)
		(pad "G20" smd circle
			(at -4.750054 -17.100042)
			(size 0.4572 0.4572)
			(layers "F.Cu" "F.Mask" "F.Paste")
			(net "GND")
		)
		(pad "G21" smd circle
			(at -3.800094 -17.100042)
			(size 0.4572 0.4572)
			(layers "F.Cu" "F.Mask" "F.Paste")
			(net "P5E_PEX0_STN6_TX_DP<98>")
		)
		(pad "G22" smd circle
			(at -2.84988 -17.100042)
			(size 0.4572 0.4572)
			(layers "F.Cu" "F.Mask" "F.Paste")
			(net "GND")
		)
		(pad "G23" smd circle
			(at -1.89992 -17.100042)
			(size 0.4572 0.4572)
			(layers "F.Cu" "F.Mask" "F.Paste")
			(net "P5E_PEX0_STN6_TX_DP<96>")
		)
		(pad "G24" smd circle
			(at -0.94996 -17.100042)
			(size 0.4572 0.4572)
			(layers "F.Cu" "F.Mask" "F.Paste")
			(net "GND")
		)
		(pad "G25" smd circle
			(at 0 -17.100042)
			(size 0.4572 0.4572)
			(layers "F.Cu" "F.Mask" "F.Paste")
			(net "P5E_PEX0_STN5_TX_DP<81>")
		)
		(pad "G26" smd circle
			(at 0.94996 -17.100042)
			(size 0.4572 0.4572)
			(layers "F.Cu" "F.Mask" "F.Paste")
			(net "GND")
		)
		(pad "G27" smd circle
			(at 1.89992 -17.100042)
			(size 0.4572 0.4572)
			(layers "F.Cu" "F.Mask" "F.Paste")
			(net "P5E_PEX0_STN5_TX_DP<83>")
		)
		(pad "G28" smd circle
			(at 2.84988 -17.100042)
			(size 0.4572 0.4572)
			(layers "F.Cu" "F.Mask" "F.Paste")
			(net "GND")
		)
		(pad "G29" smd circle
			(at 3.800094 -17.100042)
			(size 0.4572 0.4572)
			(layers "F.Cu" "F.Mask" "F.Paste")
			(net "P5E_PEX0_STN5_TX_DP<85>")
		)
		(pad "G30" smd circle
			(at 4.750054 -17.100042)
			(size 0.4572 0.4572)
			(layers "F.Cu" "F.Mask" "F.Paste")
			(net "GND")
		)
		(pad "G31" smd circle
			(at 5.700014 -17.100042)
			(size 0.4572 0.4572)
			(layers "F.Cu" "F.Mask" "F.Paste")
			(net "P5E_PEX0_STN5_TX_DP<87>")
		)
		(pad "G32" smd circle
			(at 6.649974 -17.100042)
			(size 0.4572 0.4572)
			(layers "F.Cu" "F.Mask" "F.Paste")
			(net "GND")
		)
		(pad "G33" smd circle
			(at 7.599934 -17.100042)
			(size 0.4572 0.4572)
			(layers "F.Cu" "F.Mask" "F.Paste")
			(net "P5E_PEX0_STN5_TX_DP<89>")
		)
		(pad "G34" smd circle
			(at 8.549894 -17.100042)
			(size 0.4572 0.4572)
			(layers "F.Cu" "F.Mask" "F.Paste")
			(net "GND")
		)
		(pad "G35" smd circle
			(at 9.500108 -17.100042)
			(size 0.4572 0.4572)
			(layers "F.Cu" "F.Mask" "F.Paste")
			(net "P5E_PEX0_STN5_TX_DP<91>")
		)
		(pad "G36" smd circle
			(at 10.450068 -17.100042)
			(size 0.4572 0.4572)
			(layers "F.Cu" "F.Mask" "F.Paste")
			(net "GND")
		)
		(pad "G37" smd circle
			(at 11.400028 -17.100042)
			(size 0.4572 0.4572)
			(layers "F.Cu" "F.Mask" "F.Paste")
			(net "P5E_PEX0_STN5_TX_DP<93>")
		)
		(pad "G38" smd circle
			(at 12.349988 -17.100042)
			(size 0.4572 0.4572)
			(layers "F.Cu" "F.Mask" "F.Paste")
			(net "GND")
		)
		(pad "G39" smd circle
			(at 13.299948 -17.100042)
			(size 0.4572 0.4572)
			(layers "F.Cu" "F.Mask" "F.Paste")
			(net "P5E_PEX0_STN5_TX_DP<95>")
		)
		(pad "G40" smd circle
			(at 14.249908 -17.100042)
			(size 0.4572 0.4572)
			(layers "F.Cu" "F.Mask" "F.Paste")
			(net "GND")
		)
		(pad "G41" smd circle
			(at 15.200122 -17.100042)
			(size 0.4572 0.4572)
			(layers "F.Cu" "F.Mask" "F.Paste")
			(net "P5E_PEX0_STN4_TX_DP<78>")
		)
		(pad "G42" smd circle
			(at 16.150082 -17.100042)
			(size 0.4572 0.4572)
			(layers "F.Cu" "F.Mask" "F.Paste")
			(net "GND")
		)
		(pad "G43" smd circle
			(at 17.100042 -17.100042)
			(size 0.4572 0.4572)
			(layers "F.Cu" "F.Mask" "F.Paste")
			(net "P5E_PEX0_STN4_TX_DP<76>")
		)
		(pad "G44" smd circle
			(at 18.050002 -17.100042)
			(size 0.4572 0.4572)
			(layers "F.Cu" "F.Mask" "F.Paste")
			(net "GND")
		)
		(pad "G45" smd circle
			(at 18.999962 -17.100042)
			(size 0.4572 0.4572)
			(layers "F.Cu" "F.Mask" "F.Paste")
			(net "P5E_PEX0_STN4_TX_DP<74>")
		)
		(pad "G46" smd circle
			(at 19.949922 -17.100042)
			(size 0.4572 0.4572)
			(layers "F.Cu" "F.Mask" "F.Paste")
			(net "GND")
		)
		(pad "G47" smd circle
			(at 20.899882 -17.100042)
			(size 0.4572 0.4572)
			(layers "F.Cu" "F.Mask" "F.Paste")
			(net "P5E_PEX0_STN4_TX_DP<72>")
		)
		(pad "G48" smd circle
			(at 21.850096 -17.100042)
			(size 0.4572 0.4572)
			(layers "F.Cu" "F.Mask" "F.Paste")
			(net "GND")
		)
		(pad "G49" smd circle
			(at 22.800056 -17.100042)
			(size 0.4572 0.4572)
			(layers "F.Cu" "F.Mask" "F.Paste")
			(net "GND")
		)
		(pad "H1" smd circle
			(at -22.800056 -16.150082)
			(size 0.4572 0.4572)
			(layers "F.Cu" "F.Mask" "F.Paste")
			(net "P5E_PEX0_STN7_TX_DN<121>")
		)
		(pad "H2" smd circle
			(at -21.850096 -16.150082)
			(size 0.4572 0.4572)
			(layers "F.Cu" "F.Mask" "F.Paste")
			(net "P5E_PEX0_STN7_TX_DP<121>")
		)
		(pad "H3" smd circle
			(at -20.899882 -16.150082)
			(size 0.4572 0.4572)
			(layers "F.Cu" "F.Mask" "F.Paste")
			(net "GND")
		)
		(pad "H4" smd circle
			(at -19.949922 -16.150082)
			(size 0.4572 0.4572)
			(layers "F.Cu" "F.Mask" "F.Paste")
			(net "P5E_PEX0_STN7_TX_DN<124>")
		)
		(pad "H5" smd circle
			(at -18.999962 -16.150082)
			(size 0.4572 0.4572)
			(layers "F.Cu" "F.Mask" "F.Paste")
			(net "GND")
		)
		(pad "H6" smd circle
			(at -18.050002 -16.150082)
			(size 0.4572 0.4572)
			(layers "F.Cu" "F.Mask" "F.Paste")
			(net "P5E_PEX0_STN7_TX_DN<126>")
		)
		(pad "H7" smd circle
			(at -17.100042 -16.150082)
			(size 0.4572 0.4572)
			(layers "F.Cu" "F.Mask" "F.Paste")
			(net "GND")
		)
		(pad "H8" smd circle
			(at -16.150082 -16.150082)
			(size 0.4572 0.4572)
			(layers "F.Cu" "F.Mask" "F.Paste")
			(net "P5E_PEX0_STN6_TX_DN<111>")
		)
		(pad "H9" smd circle
			(at -15.200122 -16.150082)
			(size 0.4572 0.4572)
			(layers "F.Cu" "F.Mask" "F.Paste")
			(net "GND")
		)
		(pad "H10" smd circle
			(at -14.249908 -16.150082)
			(size 0.4572 0.4572)
			(layers "F.Cu" "F.Mask" "F.Paste")
			(net "P5E_PEX0_STN6_TX_DN<109>")
		)
		(pad "H11" smd circle
			(at -13.299948 -16.150082)
			(size 0.4572 0.4572)
			(layers "F.Cu" "F.Mask" "F.Paste")
			(net "GND")
		)
		(pad "H12" smd circle
			(at -12.349988 -16.150082)
			(size 0.4572 0.4572)
			(layers "F.Cu" "F.Mask" "F.Paste")
			(net "P5E_PEX0_STN6_TX_DN<107>")
		)
		(pad "H13" smd circle
			(at -11.400028 -16.150082)
			(size 0.4572 0.4572)
			(layers "F.Cu" "F.Mask" "F.Paste")
			(net "GND")
		)
		(pad "H14" smd circle
			(at -10.450068 -16.150082)
			(size 0.4572 0.4572)
			(layers "F.Cu" "F.Mask" "F.Paste")
			(net "P5E_PEX0_STN6_TX_DN<105>")
		)
		(pad "H15" smd circle
			(at -9.500108 -16.150082)
			(size 0.4572 0.4572)
			(layers "F.Cu" "F.Mask" "F.Paste")
			(net "GND")
		)
		(pad "H16" smd circle
			(at -8.549894 -16.150082)
			(size 0.4572 0.4572)
			(layers "F.Cu" "F.Mask" "F.Paste")
			(net "P5E_PEX0_STN6_TX_DN<103>")
		)
		(pad "H17" smd circle
			(at -7.599934 -16.150082)
			(size 0.4572 0.4572)
			(layers "F.Cu" "F.Mask" "F.Paste")
			(net "GND")
		)
		(pad "H18" smd circle
			(at -6.649974 -16.150082)
			(size 0.4572 0.4572)
			(layers "F.Cu" "F.Mask" "F.Paste")
			(net "P5E_PEX0_STN6_TX_DN<101>")
		)
		(pad "H19" smd circle
			(at -5.700014 -16.150082)
			(size 0.4572 0.4572)
			(layers "F.Cu" "F.Mask" "F.Paste")
			(net "GND")
		)
		(pad "H20" smd circle
			(at -4.750054 -16.150082)
			(size 0.4572 0.4572)
			(layers "F.Cu" "F.Mask" "F.Paste")
			(net "P5E_PEX0_STN6_TX_DN<99>")
		)
		(pad "H21" smd circle
			(at -3.800094 -16.150082)
			(size 0.4572 0.4572)
			(layers "F.Cu" "F.Mask" "F.Paste")
			(net "GND")
		)
		(pad "H22" smd circle
			(at -2.84988 -16.150082)
			(size 0.4572 0.4572)
			(layers "F.Cu" "F.Mask" "F.Paste")
			(net "P5E_PEX0_STN6_TX_DN<97>")
		)
		(pad "H23" smd circle
			(at -1.89992 -16.150082)
			(size 0.4572 0.4572)
			(layers "F.Cu" "F.Mask" "F.Paste")
			(net "GND")
		)
		(pad "H24" smd circle
			(at -0.94996 -16.150082)
			(size 0.4572 0.4572)
			(layers "F.Cu" "F.Mask" "F.Paste")
			(net "P5E_PEX0_STN5_TX_DN<80>")
		)
		(pad "H25" smd circle
			(at 0 -16.150082)
			(size 0.4572 0.4572)
			(layers "F.Cu" "F.Mask" "F.Paste")
			(net "GND")
		)
		(pad "H26" smd circle
			(at 0.94996 -16.150082)
			(size 0.4572 0.4572)
			(layers "F.Cu" "F.Mask" "F.Paste")
			(net "P5E_PEX0_STN5_TX_DN<82>")
		)
		(pad "H27" smd circle
			(at 1.89992 -16.150082)
			(size 0.4572 0.4572)
			(layers "F.Cu" "F.Mask" "F.Paste")
			(net "GND")
		)
		(pad "H28" smd circle
			(at 2.84988 -16.150082)
			(size 0.4572 0.4572)
			(layers "F.Cu" "F.Mask" "F.Paste")
			(net "P5E_PEX0_STN5_TX_DN<84>")
		)
		(pad "H29" smd circle
			(at 3.800094 -16.150082)
			(size 0.4572 0.4572)
			(layers "F.Cu" "F.Mask" "F.Paste")
			(net "GND")
		)
		(pad "H30" smd circle
			(at 4.750054 -16.150082)
			(size 0.4572 0.4572)
			(layers "F.Cu" "F.Mask" "F.Paste")
			(net "P5E_PEX0_STN5_TX_DN<86>")
		)
		(pad "H31" smd circle
			(at 5.700014 -16.150082)
			(size 0.4572 0.4572)
			(layers "F.Cu" "F.Mask" "F.Paste")
			(net "GND")
		)
		(pad "H32" smd circle
			(at 6.649974 -16.150082)
			(size 0.4572 0.4572)
			(layers "F.Cu" "F.Mask" "F.Paste")
			(net "P5E_PEX0_STN5_TX_DN<88>")
		)
		(pad "H33" smd circle
			(at 7.599934 -16.150082)
			(size 0.4572 0.4572)
			(layers "F.Cu" "F.Mask" "F.Paste")
			(net "GND")
		)
		(pad "H34" smd circle
			(at 8.549894 -16.150082)
			(size 0.4572 0.4572)
			(layers "F.Cu" "F.Mask" "F.Paste")
			(net "P5E_PEX0_STN5_TX_DN<90>")
		)
		(pad "H35" smd circle
			(at 9.500108 -16.150082)
			(size 0.4572 0.4572)
			(layers "F.Cu" "F.Mask" "F.Paste")
			(net "GND")
		)
		(pad "H36" smd circle
			(at 10.450068 -16.150082)
			(size 0.4572 0.4572)
			(layers "F.Cu" "F.Mask" "F.Paste")
			(net "P5E_PEX0_STN5_TX_DN<92>")
		)
		(pad "H37" smd circle
			(at 11.400028 -16.150082)
			(size 0.4572 0.4572)
			(layers "F.Cu" "F.Mask" "F.Paste")
			(net "GND")
		)
		(pad "H38" smd circle
			(at 12.349988 -16.150082)
			(size 0.4572 0.4572)
			(layers "F.Cu" "F.Mask" "F.Paste")
			(net "P5E_PEX0_STN5_TX_DN<94>")
		)
		(pad "H39" smd circle
			(at 13.299948 -16.150082)
			(size 0.4572 0.4572)
			(layers "F.Cu" "F.Mask" "F.Paste")
			(net "GND")
		)
		(pad "H40" smd circle
			(at 14.249908 -16.150082)
			(size 0.4572 0.4572)
			(layers "F.Cu" "F.Mask" "F.Paste")
			(net "P5E_PEX0_STN4_TX_DN<79>")
		)
		(pad "H41" smd circle
			(at 15.200122 -16.150082)
			(size 0.4572 0.4572)
			(layers "F.Cu" "F.Mask" "F.Paste")
			(net "GND")
		)
		(pad "H42" smd circle
			(at 16.150082 -16.150082)
			(size 0.4572 0.4572)
			(layers "F.Cu" "F.Mask" "F.Paste")
			(net "P5E_PEX0_STN4_TX_DN<77>")
		)
		(pad "H43" smd circle
			(at 17.100042 -16.150082)
			(size 0.4572 0.4572)
			(layers "F.Cu" "F.Mask" "F.Paste")
			(net "GND")
		)
		(pad "H44" smd circle
			(at 18.050002 -16.150082)
			(size 0.4572 0.4572)
			(layers "F.Cu" "F.Mask" "F.Paste")
			(net "P5E_PEX0_STN4_TX_DN<75>")
		)
		(pad "H45" smd circle
			(at 18.999962 -16.150082)
			(size 0.4572 0.4572)
			(layers "F.Cu" "F.Mask" "F.Paste")
			(net "GND")
		)
		(pad "H46" smd circle
			(at 19.949922 -16.150082)
			(size 0.4572 0.4572)
			(layers "F.Cu" "F.Mask" "F.Paste")
			(net "P5E_PEX0_STN4_TX_DN<73>")
		)
		(pad "H47" smd circle
			(at 20.899882 -16.150082)
			(size 0.4572 0.4572)
			(layers "F.Cu" "F.Mask" "F.Paste")
			(net "GND")
		)
		(pad "H48" smd circle
			(at 21.850096 -16.150082)
			(size 0.4572 0.4572)
			(layers "F.Cu" "F.Mask" "F.Paste")
			(net "P5E_PEX0_STN4_TX_DP<70>")
		)
		(pad "H49" smd circle
			(at 22.800056 -16.150082)
			(size 0.4572 0.4572)
			(layers "F.Cu" "F.Mask" "F.Paste")
			(net "P5E_PEX0_STN4_TX_DN<70>")
		)
		(pad "J1" smd circle
			(at -22.800056 -15.200122)
			(size 0.4572 0.4572)
			(layers "F.Cu" "F.Mask" "F.Paste")
			(net "GND")
		)
		(pad "J2" smd circle
			(at -21.850096 -15.200122)
			(size 0.4572 0.4572)
			(layers "F.Cu" "F.Mask" "F.Paste")
			(net "GND")
		)
		(pad "J3" smd circle
			(at -20.899882 -15.200122)
			(size 0.4572 0.4572)
			(layers "F.Cu" "F.Mask" "F.Paste")
			(net "GND")
		)
		(pad "J4" smd circle
			(at -19.949922 -15.200122)
			(size 0.4572 0.4572)
			(layers "F.Cu" "F.Mask" "F.Paste")
			(net "P5E_PEX0_STN7_TX_DP<124>")
		)
		(pad "J5" smd circle
			(at -18.999962 -15.200122)
			(size 0.4572 0.4572)
			(layers "F.Cu" "F.Mask" "F.Paste")
			(net "GND")
		)
		(pad "J6" smd circle
			(at -18.050002 -15.200122)
			(size 0.4572 0.4572)
			(layers "F.Cu" "F.Mask" "F.Paste")
			(net "P5E_PEX0_STN7_TX_DP<126>")
		)
		(pad "J7" smd circle
			(at -17.100042 -15.200122)
			(size 0.4572 0.4572)
			(layers "F.Cu" "F.Mask" "F.Paste")
			(net "GND")
		)
		(pad "J8" smd circle
			(at -16.150082 -15.200122)
			(size 0.4572 0.4572)
			(layers "F.Cu" "F.Mask" "F.Paste")
			(net "P5E_PEX0_STN6_TX_DP<111>")
		)
		(pad "J9" smd circle
			(at -15.200122 -15.200122)
			(size 0.4572 0.4572)
			(layers "F.Cu" "F.Mask" "F.Paste")
			(net "GND")
		)
		(pad "J10" smd circle
			(at -14.249908 -15.200122)
			(size 0.4572 0.4572)
			(layers "F.Cu" "F.Mask" "F.Paste")
			(net "P5E_PEX0_STN6_TX_DP<109>")
		)
		(pad "J11" smd circle
			(at -13.299948 -15.200122)
			(size 0.4572 0.4572)
			(layers "F.Cu" "F.Mask" "F.Paste")
			(net "GND")
		)
		(pad "J12" smd circle
			(at -12.349988 -15.200122)
			(size 0.4572 0.4572)
			(layers "F.Cu" "F.Mask" "F.Paste")
			(net "P5E_PEX0_STN6_TX_DP<107>")
		)
		(pad "J13" smd circle
			(at -11.400028 -15.200122)
			(size 0.4572 0.4572)
			(layers "F.Cu" "F.Mask" "F.Paste")
			(net "GND")
		)
		(pad "J14" smd circle
			(at -10.450068 -15.200122)
			(size 0.4572 0.4572)
			(layers "F.Cu" "F.Mask" "F.Paste")
			(net "P5E_PEX0_STN6_TX_DP<105>")
		)
		(pad "J15" smd circle
			(at -9.500108 -15.200122)
			(size 0.4572 0.4572)
			(layers "F.Cu" "F.Mask" "F.Paste")
			(net "GND")
		)
		(pad "J16" smd circle
			(at -8.549894 -15.200122)
			(size 0.4572 0.4572)
			(layers "F.Cu" "F.Mask" "F.Paste")
			(net "P5E_PEX0_STN6_TX_DP<103>")
		)
		(pad "J17" smd circle
			(at -7.599934 -15.200122)
			(size 0.4572 0.4572)
			(layers "F.Cu" "F.Mask" "F.Paste")
			(net "GND")
		)
		(pad "J18" smd circle
			(at -6.649974 -15.200122)
			(size 0.4572 0.4572)
			(layers "F.Cu" "F.Mask" "F.Paste")
			(net "P5E_PEX0_STN6_TX_DP<101>")
		)
		(pad "J19" smd circle
			(at -5.700014 -15.200122)
			(size 0.4572 0.4572)
			(layers "F.Cu" "F.Mask" "F.Paste")
			(net "GND")
		)
		(pad "J20" smd circle
			(at -4.750054 -15.200122)
			(size 0.4572 0.4572)
			(layers "F.Cu" "F.Mask" "F.Paste")
			(net "P5E_PEX0_STN6_TX_DP<99>")
		)
		(pad "J21" smd circle
			(at -3.800094 -15.200122)
			(size 0.4572 0.4572)
			(layers "F.Cu" "F.Mask" "F.Paste")
			(net "GND")
		)
		(pad "J22" smd circle
			(at -2.84988 -15.200122)
			(size 0.4572 0.4572)
			(layers "F.Cu" "F.Mask" "F.Paste")
			(net "P5E_PEX0_STN6_TX_DP<97>")
		)
		(pad "J23" smd circle
			(at -1.89992 -15.200122)
			(size 0.4572 0.4572)
			(layers "F.Cu" "F.Mask" "F.Paste")
			(net "GND")
		)
		(pad "J24" smd circle
			(at -0.94996 -15.200122)
			(size 0.4572 0.4572)
			(layers "F.Cu" "F.Mask" "F.Paste")
			(net "P5E_PEX0_STN5_TX_DP<80>")
		)
		(pad "J25" smd circle
			(at 0 -15.200122)
			(size 0.4572 0.4572)
			(layers "F.Cu" "F.Mask" "F.Paste")
			(net "GND")
		)
		(pad "J26" smd circle
			(at 0.94996 -15.200122)
			(size 0.4572 0.4572)
			(layers "F.Cu" "F.Mask" "F.Paste")
			(net "P5E_PEX0_STN5_TX_DP<82>")
		)
		(pad "J27" smd circle
			(at 1.89992 -15.200122)
			(size 0.4572 0.4572)
			(layers "F.Cu" "F.Mask" "F.Paste")
			(net "GND")
		)
		(pad "J28" smd circle
			(at 2.84988 -15.200122)
			(size 0.4572 0.4572)
			(layers "F.Cu" "F.Mask" "F.Paste")
			(net "P5E_PEX0_STN5_TX_DP<84>")
		)
		(pad "J29" smd circle
			(at 3.800094 -15.200122)
			(size 0.4572 0.4572)
			(layers "F.Cu" "F.Mask" "F.Paste")
			(net "GND")
		)
		(pad "J30" smd circle
			(at 4.750054 -15.200122)
			(size 0.4572 0.4572)
			(layers "F.Cu" "F.Mask" "F.Paste")
			(net "P5E_PEX0_STN5_TX_DP<86>")
		)
		(pad "J31" smd circle
			(at 5.700014 -15.200122)
			(size 0.4572 0.4572)
			(layers "F.Cu" "F.Mask" "F.Paste")
			(net "GND")
		)
		(pad "J32" smd circle
			(at 6.649974 -15.200122)
			(size 0.4572 0.4572)
			(layers "F.Cu" "F.Mask" "F.Paste")
			(net "P5E_PEX0_STN5_TX_DP<88>")
		)
		(pad "J33" smd circle
			(at 7.599934 -15.200122)
			(size 0.4572 0.4572)
			(layers "F.Cu" "F.Mask" "F.Paste")
			(net "GND")
		)
		(pad "J34" smd circle
			(at 8.549894 -15.200122)
			(size 0.4572 0.4572)
			(layers "F.Cu" "F.Mask" "F.Paste")
			(net "P5E_PEX0_STN5_TX_DP<90>")
		)
		(pad "J35" smd circle
			(at 9.500108 -15.200122)
			(size 0.4572 0.4572)
			(layers "F.Cu" "F.Mask" "F.Paste")
			(net "GND")
		)
		(pad "J36" smd circle
			(at 10.450068 -15.200122)
			(size 0.4572 0.4572)
			(layers "F.Cu" "F.Mask" "F.Paste")
			(net "P5E_PEX0_STN5_TX_DP<92>")
		)
		(pad "J37" smd circle
			(at 11.400028 -15.200122)
			(size 0.4572 0.4572)
			(layers "F.Cu" "F.Mask" "F.Paste")
			(net "GND")
		)
		(pad "J38" smd circle
			(at 12.349988 -15.200122)
			(size 0.4572 0.4572)
			(layers "F.Cu" "F.Mask" "F.Paste")
			(net "P5E_PEX0_STN5_TX_DP<94>")
		)
		(pad "J39" smd circle
			(at 13.299948 -15.200122)
			(size 0.4572 0.4572)
			(layers "F.Cu" "F.Mask" "F.Paste")
			(net "GND")
		)
		(pad "J40" smd circle
			(at 14.249908 -15.200122)
			(size 0.4572 0.4572)
			(layers "F.Cu" "F.Mask" "F.Paste")
			(net "P5E_PEX0_STN4_TX_DP<79>")
		)
		(pad "J41" smd circle
			(at 15.200122 -15.200122)
			(size 0.4572 0.4572)
			(layers "F.Cu" "F.Mask" "F.Paste")
			(net "GND")
		)
		(pad "J42" smd circle
			(at 16.150082 -15.200122)
			(size 0.4572 0.4572)
			(layers "F.Cu" "F.Mask" "F.Paste")
			(net "P5E_PEX0_STN4_TX_DP<77>")
		)
		(pad "J43" smd circle
			(at 17.100042 -15.200122)
			(size 0.4572 0.4572)
			(layers "F.Cu" "F.Mask" "F.Paste")
			(net "GND")
		)
		(pad "J44" smd circle
			(at 18.050002 -15.200122)
			(size 0.4572 0.4572)
			(layers "F.Cu" "F.Mask" "F.Paste")
			(net "P5E_PEX0_STN4_TX_DP<75>")
		)
		(pad "J45" smd circle
			(at 18.999962 -15.200122)
			(size 0.4572 0.4572)
			(layers "F.Cu" "F.Mask" "F.Paste")
			(net "GND")
		)
		(pad "J46" smd circle
			(at 19.949922 -15.200122)
			(size 0.4572 0.4572)
			(layers "F.Cu" "F.Mask" "F.Paste")
			(net "P5E_PEX0_STN4_TX_DP<73>")
		)
		(pad "J47" smd circle
			(at 20.899882 -15.200122)
			(size 0.4572 0.4572)
			(layers "F.Cu" "F.Mask" "F.Paste")
			(net "GND")
		)
		(pad "J48" smd circle
			(at 21.850096 -15.200122)
			(size 0.4572 0.4572)
			(layers "F.Cu" "F.Mask" "F.Paste")
			(net "GND")
		)
		(pad "J49" smd circle
			(at 22.800056 -15.200122)
			(size 0.4572 0.4572)
			(layers "F.Cu" "F.Mask" "F.Paste")
			(net "GND")
		)
		(pad "K1" smd circle
			(at -22.800056 -14.249908)
			(size 0.4572 0.4572)
			(layers "F.Cu" "F.Mask" "F.Paste")
			(net "P5E_PEX0_STN7_RX_DN<121>")
		)
		(pad "K2" smd circle
			(at -21.850096 -14.249908)
			(size 0.4572 0.4572)
			(layers "F.Cu" "F.Mask" "F.Paste")
			(net "P5E_PEX0_STN7_RX_DP<121>")
		)
		(pad "K3" smd circle
			(at -20.899882 -14.249908)
			(size 0.4572 0.4572)
			(layers "F.Cu" "F.Mask" "F.Paste")
			(net "GND")
		)
		(pad "K4" smd circle
			(at -19.949922 -14.249908)
			(size 0.4572 0.4572)
			(layers "F.Cu" "F.Mask" "F.Paste")
			(net "GND")
		)
		(pad "K5" smd circle
			(at -18.999962 -14.249908)
			(size 0.4572 0.4572)
			(layers "F.Cu" "F.Mask" "F.Paste")
			(net "GND")
		)
		(pad "K6" smd circle
			(at -18.050002 -14.249908)
			(size 0.4572 0.4572)
			(layers "F.Cu" "F.Mask" "F.Paste")
			(net "GND")
		)
		(pad "K7" smd circle
			(at -17.100042 -14.249908)
			(size 0.4572 0.4572)
			(layers "F.Cu" "F.Mask" "F.Paste")
			(net "GND")
		)
		(pad "K8" smd circle
			(at -16.150082 -14.249908)
			(size 0.4572 0.4572)
			(layers "F.Cu" "F.Mask" "F.Paste")
			(net "GND")
		)
		(pad "K9" smd circle
			(at -15.200122 -14.249908)
			(size 0.4572 0.4572)
			(layers "F.Cu" "F.Mask" "F.Paste")
			(net "GND")
		)
		(pad "K10" smd circle
			(at -14.249908 -14.249908)
			(size 0.4572 0.4572)
			(layers "F.Cu" "F.Mask" "F.Paste")
			(net "GND")
		)
		(pad "K11" smd circle
			(at -13.299948 -14.249908)
			(size 0.4572 0.4572)
			(layers "F.Cu" "F.Mask" "F.Paste")
			(net "GND")
		)
		(pad "K12" smd circle
			(at -12.349988 -14.249908)
			(size 0.4572 0.4572)
			(layers "F.Cu" "F.Mask" "F.Paste")
			(net "GND")
		)
		(pad "K13" smd circle
			(at -11.400028 -14.249908)
			(size 0.4572 0.4572)
			(layers "F.Cu" "F.Mask" "F.Paste")
			(net "GND")
		)
		(pad "K14" smd circle
			(at -10.450068 -14.249908)
			(size 0.4572 0.4572)
			(layers "F.Cu" "F.Mask" "F.Paste")
			(net "GND")
		)
		(pad "K15" smd circle
			(at -9.500108 -14.249908)
			(size 0.4572 0.4572)
			(layers "F.Cu" "F.Mask" "F.Paste")
			(net "GND")
		)
		(pad "K16" smd circle
			(at -8.549894 -14.249908)
			(size 0.4572 0.4572)
			(layers "F.Cu" "F.Mask" "F.Paste")
			(net "GND")
		)
		(pad "K17" smd circle
			(at -7.599934 -14.249908)
			(size 0.4572 0.4572)
			(layers "F.Cu" "F.Mask" "F.Paste")
			(net "GND")
		)
		(pad "K18" smd circle
			(at -6.649974 -14.249908)
			(size 0.4572 0.4572)
			(layers "F.Cu" "F.Mask" "F.Paste")
			(net "GND")
		)
		(pad "K19" smd circle
			(at -5.700014 -14.249908)
			(size 0.4572 0.4572)
			(layers "F.Cu" "F.Mask" "F.Paste")
			(net "GND")
		)
		(pad "K20" smd circle
			(at -4.750054 -14.249908)
			(size 0.4572 0.4572)
			(layers "F.Cu" "F.Mask" "F.Paste")
			(net "GND")
		)
		(pad "K21" smd circle
			(at -3.800094 -14.249908)
			(size 0.4572 0.4572)
			(layers "F.Cu" "F.Mask" "F.Paste")
			(net "GND")
		)
		(pad "K22" smd circle
			(at -2.84988 -14.249908)
			(size 0.4572 0.4572)
			(layers "F.Cu" "F.Mask" "F.Paste")
			(net "GND")
		)
		(pad "K23" smd circle
			(at -1.89992 -14.249908)
			(size 0.4572 0.4572)
			(layers "F.Cu" "F.Mask" "F.Paste")
			(net "GND")
		)
		(pad "K24" smd circle
			(at -0.94996 -14.249908)
			(size 0.4572 0.4572)
			(layers "F.Cu" "F.Mask" "F.Paste")
			(net "GND")
		)
		(pad "K25" smd circle
			(at 0 -14.249908)
			(size 0.4572 0.4572)
			(layers "F.Cu" "F.Mask" "F.Paste")
			(net "GND")
		)
		(pad "K26" smd circle
			(at 0.94996 -14.249908)
			(size 0.4572 0.4572)
			(layers "F.Cu" "F.Mask" "F.Paste")
			(net "GND")
		)
		(pad "K27" smd circle
			(at 1.89992 -14.249908)
			(size 0.4572 0.4572)
			(layers "F.Cu" "F.Mask" "F.Paste")
			(net "GND")
		)
		(pad "K28" smd circle
			(at 2.84988 -14.249908)
			(size 0.4572 0.4572)
			(layers "F.Cu" "F.Mask" "F.Paste")
			(net "GND")
		)
		(pad "K29" smd circle
			(at 3.800094 -14.249908)
			(size 0.4572 0.4572)
			(layers "F.Cu" "F.Mask" "F.Paste")
			(net "GND")
		)
		(pad "K30" smd circle
			(at 4.750054 -14.249908)
			(size 0.4572 0.4572)
			(layers "F.Cu" "F.Mask" "F.Paste")
			(net "GND")
		)
		(pad "K31" smd circle
			(at 5.700014 -14.249908)
			(size 0.4572 0.4572)
			(layers "F.Cu" "F.Mask" "F.Paste")
			(net "GND")
		)
		(pad "K32" smd circle
			(at 6.649974 -14.249908)
			(size 0.4572 0.4572)
			(layers "F.Cu" "F.Mask" "F.Paste")
			(net "GND")
		)
		(pad "K33" smd circle
			(at 7.599934 -14.249908)
			(size 0.4572 0.4572)
			(layers "F.Cu" "F.Mask" "F.Paste")
			(net "GND")
		)
		(pad "K34" smd circle
			(at 8.549894 -14.249908)
			(size 0.4572 0.4572)
			(layers "F.Cu" "F.Mask" "F.Paste")
			(net "GND")
		)
		(pad "K35" smd circle
			(at 9.500108 -14.249908)
			(size 0.4572 0.4572)
			(layers "F.Cu" "F.Mask" "F.Paste")
			(net "GND")
		)
		(pad "K36" smd circle
			(at 10.450068 -14.249908)
			(size 0.4572 0.4572)
			(layers "F.Cu" "F.Mask" "F.Paste")
			(net "GND")
		)
		(pad "K37" smd circle
			(at 11.400028 -14.249908)
			(size 0.4572 0.4572)
			(layers "F.Cu" "F.Mask" "F.Paste")
			(net "GND")
		)
		(pad "K38" smd circle
			(at 12.349988 -14.249908)
			(size 0.4572 0.4572)
			(layers "F.Cu" "F.Mask" "F.Paste")
			(net "GND")
		)
		(pad "K39" smd circle
			(at 13.299948 -14.249908)
			(size 0.4572 0.4572)
			(layers "F.Cu" "F.Mask" "F.Paste")
			(net "GND")
		)
		(pad "K40" smd circle
			(at 14.249908 -14.249908)
			(size 0.4572 0.4572)
			(layers "F.Cu" "F.Mask" "F.Paste")
			(net "GND")
		)
		(pad "K41" smd circle
			(at 15.200122 -14.249908)
			(size 0.4572 0.4572)
			(layers "F.Cu" "F.Mask" "F.Paste")
			(net "GND")
		)
		(pad "K42" smd circle
			(at 16.150082 -14.249908)
			(size 0.4572 0.4572)
			(layers "F.Cu" "F.Mask" "F.Paste")
			(net "GND")
		)
		(pad "K43" smd circle
			(at 17.100042 -14.249908)
			(size 0.4572 0.4572)
			(layers "F.Cu" "F.Mask" "F.Paste")
			(net "GND")
		)
		(pad "K44" smd circle
			(at 18.050002 -14.249908)
			(size 0.4572 0.4572)
			(layers "F.Cu" "F.Mask" "F.Paste")
			(net "GND")
		)
		(pad "K45" smd circle
			(at 18.999962 -14.249908)
			(size 0.4572 0.4572)
			(layers "F.Cu" "F.Mask" "F.Paste")
			(net "GND")
		)
		(pad "K46" smd circle
			(at 19.949922 -14.249908)
			(size 0.4572 0.4572)
			(layers "F.Cu" "F.Mask" "F.Paste")
			(net "GND")
		)
		(pad "K47" smd circle
			(at 20.899882 -14.249908)
			(size 0.4572 0.4572)
			(layers "F.Cu" "F.Mask" "F.Paste")
			(net "GND")
		)
		(pad "K48" smd circle
			(at 21.850096 -14.249908)
			(size 0.4572 0.4572)
			(layers "F.Cu" "F.Mask" "F.Paste")
			(net "P5E_PEX0_STN4_RX_DP<70>")
		)
		(pad "K49" smd circle
			(at 22.800056 -14.249908)
			(size 0.4572 0.4572)
			(layers "F.Cu" "F.Mask" "F.Paste")
			(net "P5E_PEX0_STN4_RX_DN<70>")
		)
		(pad "L1" smd circle
			(at -22.800056 -13.299948)
			(size 0.4572 0.4572)
			(layers "F.Cu" "F.Mask" "F.Paste")
			(net "GND")
		)
		(pad "L2" smd circle
			(at -21.850096 -13.299948)
			(size 0.4572 0.4572)
			(layers "F.Cu" "F.Mask" "F.Paste")
			(net "GND")
		)
		(pad "L3" smd circle
			(at -20.899882 -13.299948)
			(size 0.4572 0.4572)
			(layers "F.Cu" "F.Mask" "F.Paste")
			(net "P5E_PEX0_STN7_RX_DN<120>")
		)
		(pad "L4" smd circle
			(at -19.949922 -13.299948)
			(size 0.4572 0.4572)
			(layers "F.Cu" "F.Mask" "F.Paste")
			(net "P5E_PEX0_STN7_RX_DP<120>")
		)
		(pad "L5" smd circle
			(at -18.999962 -13.299948)
			(size 0.4572 0.4572)
			(layers "F.Cu" "F.Mask" "F.Paste")
			(net "GND")
		)
		(pad "L6" smd circle
			(at -18.050002 -13.299948)
			(size 0.4572 0.4572)
			(layers "F.Cu" "F.Mask" "F.Paste")
			(net "P5E_PEX0_STN7_TX_DN<120>")
		)
		(pad "L7" smd circle
			(at -17.100042 -13.299948)
			(size 0.4572 0.4572)
			(layers "F.Cu" "F.Mask" "F.Paste")
			(net "P5E_PEX0_STN7_TX_DP<120>")
		)
		(pad "L8" smd circle
			(at -16.150082 -13.299948)
			(size 0.4572 0.4572)
			(layers "F.Cu" "F.Mask" "F.Paste")
			(net "GND")
		)
		(pad "L9" smd circle
			(at -15.200122 -13.299948)
			(size 0.4572 0.4572)
			(layers "F.Cu" "F.Mask" "F.Paste")
			(net "GND")
		)
		(pad "L10" smd circle
			(at -14.249908 -13.299948)
			(size 0.4572 0.4572)
			(layers "F.Cu" "F.Mask" "F.Paste")
			(net "GND")
		)
		(pad "L11" smd circle
			(at -13.299948 -13.299948)
			(size 0.4572 0.4572)
			(layers "F.Cu" "F.Mask" "F.Paste")
			(net "GND")
		)
		(pad "L12" smd circle
			(at -12.349988 -13.299948)
			(size 0.4572 0.4572)
			(layers "F.Cu" "F.Mask" "F.Paste")
			(net "PEX0_DBG_MODE0")
		)
		(pad "L13" smd circle
			(at -11.400028 -13.299948)
			(size 0.4572 0.4572)
			(layers "F.Cu" "F.Mask" "F.Paste")
			(net "PEX0_DBG_MODE1")
		)
		(pad "L14" smd circle
			(at -10.450068 -13.299948)
			(size 0.4572 0.4572)
			(layers "F.Cu" "F.Mask" "F.Paste")
			(net "GND")
		)
		(pad "L15" smd circle
			(at -9.500108 -13.299948)
			(size 0.4572 0.4572)
			(layers "F.Cu" "F.Mask" "F.Paste")
			(net "PU_PEX0_ATPG_MODE_L")
		)
		(pad "L16" smd circle
			(at -8.549894 -13.299948)
			(size 0.4572 0.4572)
			(layers "F.Cu" "F.Mask" "F.Paste")
			(net "PU_PEX0_PAD_TRI_L")
		)
		(pad "L17" smd circle
			(at -7.599934 -13.299948)
			(size 0.4572 0.4572)
			(layers "F.Cu" "F.Mask" "F.Paste")
			(net "TP_PEX0_TDI")
		)
		(pad "L18" smd circle
			(at -6.649974 -13.299948)
			(size 0.4572 0.4572)
			(layers "F.Cu" "F.Mask" "F.Paste")
			(net "PEX0_DBG_SEL0")
		)
		(pad "L19" smd circle
			(at -5.700014 -13.299948)
			(size 0.4572 0.4572)
			(layers "F.Cu" "F.Mask" "F.Paste")
			(net "TP_PEX0_TDO")
		)
		(pad "L20" smd circle
			(at -4.750054 -13.299948)
			(size 0.4572 0.4572)
			(layers "F.Cu" "F.Mask" "F.Paste")
			(net "PU_PEX0_TR_TCK")
		)
		(pad "L21" smd circle
			(at -3.800094 -13.299948)
			(size 0.4572 0.4572)
			(layers "F.Cu" "F.Mask" "F.Paste")
			(net "GND")
		)
		(pad "L22" smd circle
			(at -2.84988 -13.299948)
			(size 0.4572 0.4572)
			(layers "F.Cu" "F.Mask" "F.Paste")
			(net "Net_2897")
		)
		(pad "L23" smd circle
			(at -1.89992 -13.299948)
			(size 0.4572 0.4572)
			(layers "F.Cu" "F.Mask" "F.Paste")
			(net "Net_2901")
		)
		(pad "L24" smd circle
			(at -0.94996 -13.299948)
			(size 0.4572 0.4572)
			(layers "F.Cu" "F.Mask" "F.Paste")
			(net "Net_2896")
		)
		(pad "L25" smd circle
			(at 0 -13.299948)
			(size 0.4572 0.4572)
			(layers "F.Cu" "F.Mask" "F.Paste")
			(net "PEX0_SPARE5")
		)
		(pad "L26" smd circle
			(at 0.94996 -13.299948)
			(size 0.4572 0.4572)
			(layers "F.Cu" "F.Mask" "F.Paste")
			(net "PU_PEX0_SIO_BLINK")
		)
		(pad "L27" smd circle
			(at 1.89992 -13.299948)
			(size 0.4572 0.4572)
			(layers "F.Cu" "F.Mask" "F.Paste")
			(net "PEX0_SPARE2")
		)
		(pad "L28" smd circle
			(at 2.84988 -13.299948)
			(size 0.4572 0.4572)
			(layers "F.Cu" "F.Mask" "F.Paste")
			(net "PEX0_SPARE6")
		)
		(pad "L29" smd circle
			(at 3.800094 -13.299948)
			(size 0.4572 0.4572)
			(layers "F.Cu" "F.Mask" "F.Paste")
			(net "Net_2886")
		)
		(pad "L30" smd circle
			(at 4.750054 -13.299948)
			(size 0.4572 0.4572)
			(layers "F.Cu" "F.Mask" "F.Paste")
			(net "PEX0_SPARE1")
		)
		(pad "L31" smd circle
			(at 5.700014 -13.299948)
			(size 0.4572 0.4572)
			(layers "F.Cu" "F.Mask" "F.Paste")
			(net "Net_2890")
		)
		(pad "L32" smd circle
			(at 6.649974 -13.299948)
			(size 0.4572 0.4572)
			(layers "F.Cu" "F.Mask" "F.Paste")
			(net "PEX0_SPARE3")
		)
		(pad "L33" smd circle
			(at 7.599934 -13.299948)
			(size 0.4572 0.4572)
			(layers "F.Cu" "F.Mask" "F.Paste")
			(net "Net_2882")
		)
		(pad "L34" smd circle
			(at 8.549894 -13.299948)
			(size 0.4572 0.4572)
			(layers "F.Cu" "F.Mask" "F.Paste")
			(net "SMB_PEX0_SLAVE1_SCL")
		)
		(pad "L35" smd circle
			(at 9.500108 -13.299948)
			(size 0.4572 0.4572)
			(layers "F.Cu" "F.Mask" "F.Paste")
			(net "Net_2879")
		)
		(pad "L36" smd circle
			(at 10.450068 -13.299948)
			(size 0.4572 0.4572)
			(layers "F.Cu" "F.Mask" "F.Paste")
			(net "Net_2909")
		)
		(pad "L37" smd circle
			(at 11.400028 -13.299948)
			(size 0.4572 0.4572)
			(layers "F.Cu" "F.Mask" "F.Paste")
			(net "PEX0_EXT_GPIO_LATCH_N")
		)
		(pad "L38" smd circle
			(at 12.349988 -13.299948)
			(size 0.4572 0.4572)
			(layers "F.Cu" "F.Mask" "F.Paste")
			(net "Net_2906")
		)
		(pad "L39" smd circle
			(at 13.299948 -13.299948)
			(size 0.4572 0.4572)
			(layers "F.Cu" "F.Mask" "F.Paste")
			(net "SMB_PEX0_SLAVE_SDA")
		)
		(pad "L40" smd circle
			(at 14.249908 -13.299948)
			(size 0.4572 0.4572)
			(layers "F.Cu" "F.Mask" "F.Paste")
			(net "GND")
		)
		(pad "L41" smd circle
			(at 15.200122 -13.299948)
			(size 0.4572 0.4572)
			(layers "F.Cu" "F.Mask" "F.Paste")
			(net "GND")
		)
		(pad "L42" smd circle
			(at 16.150082 -13.299948)
			(size 0.4572 0.4572)
			(layers "F.Cu" "F.Mask" "F.Paste")
			(net "GND")
		)
		(pad "L43" smd circle
			(at 17.100042 -13.299948)
			(size 0.4572 0.4572)
			(layers "F.Cu" "F.Mask" "F.Paste")
			(net "P5E_PEX0_STN4_TX_DP<69>")
		)
		(pad "L44" smd circle
			(at 18.050002 -13.299948)
			(size 0.4572 0.4572)
			(layers "F.Cu" "F.Mask" "F.Paste")
			(net "P5E_PEX0_STN4_TX_DN<69>")
		)
		(pad "L45" smd circle
			(at 18.999962 -13.299948)
			(size 0.4572 0.4572)
			(layers "F.Cu" "F.Mask" "F.Paste")
			(net "GND")
		)
		(pad "L46" smd circle
			(at 19.949922 -13.299948)
			(size 0.4572 0.4572)
			(layers "F.Cu" "F.Mask" "F.Paste")
			(net "P5E_PEX0_STN4_RX_DP<69>")
		)
		(pad "L47" smd circle
			(at 20.899882 -13.299948)
			(size 0.4572 0.4572)
			(layers "F.Cu" "F.Mask" "F.Paste")
			(net "P5E_PEX0_STN4_RX_DN<69>")
		)
		(pad "L48" smd circle
			(at 21.850096 -13.299948)
			(size 0.4572 0.4572)
			(layers "F.Cu" "F.Mask" "F.Paste")
			(net "GND")
		)
		(pad "L49" smd circle
			(at 22.800056 -13.299948)
			(size 0.4572 0.4572)
			(layers "F.Cu" "F.Mask" "F.Paste")
			(net "GND")
		)
		(pad "M1" smd circle
			(at -22.800056 -12.349988)
			(size 0.4572 0.4572)
			(layers "F.Cu" "F.Mask" "F.Paste")
			(net "P5E_PEX0_STN7_RX_DN<119>")
		)
		(pad "M2" smd circle
			(at -21.850096 -12.349988)
			(size 0.4572 0.4572)
			(layers "F.Cu" "F.Mask" "F.Paste")
			(net "P5E_PEX0_STN7_RX_DP<119>")
		)
		(pad "M3" smd circle
			(at -20.899882 -12.349988)
			(size 0.4572 0.4572)
			(layers "F.Cu" "F.Mask" "F.Paste")
			(net "GND")
		)
		(pad "M4" smd circle
			(at -19.949922 -12.349988)
			(size 0.4572 0.4572)
			(layers "F.Cu" "F.Mask" "F.Paste")
			(net "GND")
		)
		(pad "M5" smd circle
			(at -18.999962 -12.349988)
			(size 0.4572 0.4572)
			(layers "F.Cu" "F.Mask" "F.Paste")
			(net "GND")
		)
		(pad "M6" smd circle
			(at -18.050002 -12.349988)
			(size 0.4572 0.4572)
			(layers "F.Cu" "F.Mask" "F.Paste")
			(net "GND")
		)
		(pad "M7" smd circle
			(at -17.100042 -12.349988)
			(size 0.4572 0.4572)
			(layers "F.Cu" "F.Mask" "F.Paste")
			(net "GND")
		)
		(pad "M8" smd circle
			(at -16.150082 -12.349988)
			(size 0.4572 0.4572)
			(layers "F.Cu" "F.Mask" "F.Paste")
			(net "P5E_PEX0_STN7_TX_DN<119>")
		)
		(pad "M9" smd circle
			(at -15.200122 -12.349988)
			(size 0.4572 0.4572)
			(layers "F.Cu" "F.Mask" "F.Paste")
			(net "P5E_PEX0_STN7_TX_DP<119>")
		)
		(pad "M10" smd circle
			(at -14.249908 -12.349988)
			(size 0.4572 0.4572)
			(layers "F.Cu" "F.Mask" "F.Paste")
			(net "GND")
		)
		(pad "M11" smd circle
			(at -13.299948 -12.349988)
			(size 0.4572 0.4572)
			(layers "F.Cu" "F.Mask" "F.Paste")
			(net "GND")
		)
		(pad "M12" smd circle
			(at -12.349988 -12.349988)
			(size 0.4572 0.4572)
			(layers "F.Cu" "F.Mask" "F.Paste")
			(net "GND")
		)
		(pad "M13" smd circle
			(at -11.400028 -12.349988)
			(size 0.4572 0.4572)
			(layers "F.Cu" "F.Mask" "F.Paste")
			(net "IRQ_PEX0_CLKREQ_INT_N")
		)
		(pad "M14" smd circle
			(at -10.450068 -12.349988)
			(size 0.4572 0.4572)
			(layers "F.Cu" "F.Mask" "F.Paste")
			(net "GND")
		)
		(pad "M15" smd circle
			(at -9.500108 -12.349988)
			(size 0.4572 0.4572)
			(layers "F.Cu" "F.Mask" "F.Paste")
			(net "TP_PEX0_TCK")
		)
		(pad "M16" smd circle
			(at -8.549894 -12.349988)
			(size 0.4572 0.4572)
			(layers "F.Cu" "F.Mask" "F.Paste")
			(net "PEX0_DFT_IDDT")
		)
		(pad "M17" smd circle
			(at -7.599934 -12.349988)
			(size 0.4572 0.4572)
			(layers "F.Cu" "F.Mask" "F.Paste")
			(net "RST_PEX0_SYS_N")
		)
		(pad "M18" smd circle
			(at -6.649974 -12.349988)
			(size 0.4572 0.4572)
			(layers "F.Cu" "F.Mask" "F.Paste")
			(net "TP_PEX0_TRST_L")
		)
		(pad "M19" smd circle
			(at -5.700014 -12.349988)
			(size 0.4572 0.4572)
			(layers "F.Cu" "F.Mask" "F.Paste")
			(net "PEX0_DBG_SEL1")
		)
		(pad "M20" smd circle
			(at -4.750054 -12.349988)
			(size 0.4572 0.4572)
			(layers "F.Cu" "F.Mask" "F.Paste")
			(net "TP_PEX0_TMS")
		)
		(pad "M21" smd circle
			(at -3.800094 -12.349988)
			(size 0.4572 0.4572)
			(layers "F.Cu" "F.Mask" "F.Paste")
			(net "GND")
		)
		(pad "M22" smd circle
			(at -2.84988 -12.349988)
			(size 0.4572 0.4572)
			(layers "F.Cu" "F.Mask" "F.Paste")
			(net "Net_2899")
		)
		(pad "M23" smd circle
			(at -1.89992 -12.349988)
			(size 0.4572 0.4572)
			(layers "F.Cu" "F.Mask" "F.Paste")
			(net "Net_2900")
		)
		(pad "M24" smd circle
			(at -0.94996 -12.349988)
			(size 0.4572 0.4572)
			(layers "F.Cu" "F.Mask" "F.Paste")
			(net "Net_2902")
		)
		(pad "M25" smd circle
			(at 0 -12.349988)
			(size 0.4572 0.4572)
			(layers "F.Cu" "F.Mask" "F.Paste")
			(net "PEX0_SPARE4")
		)
		(pad "M26" smd circle
			(at 0.94996 -12.349988)
			(size 0.4572 0.4572)
			(layers "F.Cu" "F.Mask" "F.Paste")
			(net "PEX0_SPARE0")
		)
		(pad "M27" smd circle
			(at 1.89992 -12.349988)
			(size 0.4572 0.4572)
			(layers "F.Cu" "F.Mask" "F.Paste")
			(net "PEX0_SPARE7")
		)
		(pad "M28" smd circle
			(at 2.84988 -12.349988)
			(size 0.4572 0.4572)
			(layers "F.Cu" "F.Mask" "F.Paste")
			(net "I2C0_PEX0_SHPC_SDA")
		)
		(pad "M29" smd circle
			(at 3.800094 -12.349988)
			(size 0.4572 0.4572)
			(layers "F.Cu" "F.Mask" "F.Paste")
			(net "I2C0_PEX0_SHPC_SCL")
		)
		(pad "M30" smd circle
			(at 4.750054 -12.349988)
			(size 0.4572 0.4572)
			(layers "F.Cu" "F.Mask" "F.Paste")
			(net "Net_2880")
		)
		(pad "M31" smd circle
			(at 5.700014 -12.349988)
			(size 0.4572 0.4572)
			(layers "F.Cu" "F.Mask" "F.Paste")
			(net "Net_2881")
		)
		(pad "M32" smd circle
			(at 6.649974 -12.349988)
			(size 0.4572 0.4572)
			(layers "F.Cu" "F.Mask" "F.Paste")
			(net "Net_2891")
		)
		(pad "M33" smd circle
			(at 7.599934 -12.349988)
			(size 0.4572 0.4572)
			(layers "F.Cu" "F.Mask" "F.Paste")
			(net "Net_2885")
		)
		(pad "M34" smd circle
			(at 8.549894 -12.349988)
			(size 0.4572 0.4572)
			(layers "F.Cu" "F.Mask" "F.Paste")
			(net "Net_2889")
		)
		(pad "M35" smd circle
			(at 9.500108 -12.349988)
			(size 0.4572 0.4572)
			(layers "F.Cu" "F.Mask" "F.Paste")
			(net "I2C0_PEX0_SCL")
		)
		(pad "M36" smd circle
			(at 10.450068 -12.349988)
			(size 0.4572 0.4572)
			(layers "F.Cu" "F.Mask" "F.Paste")
			(net "Net_2908")
		)
		(pad "M37" smd circle
			(at 11.400028 -12.349988)
			(size 0.4572 0.4572)
			(layers "F.Cu" "F.Mask" "F.Paste")
			(net "Net_2907")
		)
		(pad "M38" smd circle
			(at 12.349988 -12.349988)
			(size 0.4572 0.4572)
			(layers "F.Cu" "F.Mask" "F.Paste")
			(net "SMB_PEX0_SLAVE1_SDA")
		)
		(pad "M39" smd circle
			(at 13.299948 -12.349988)
			(size 0.4572 0.4572)
			(layers "F.Cu" "F.Mask" "F.Paste")
			(net "I2C0_PEX0_SDA")
		)
		(pad "M40" smd circle
			(at 14.249908 -12.349988)
			(size 0.4572 0.4572)
			(layers "F.Cu" "F.Mask" "F.Paste")
			(net "GND")
		)
		(pad "M41" smd circle
			(at 15.200122 -12.349988)
			(size 0.4572 0.4572)
			(layers "F.Cu" "F.Mask" "F.Paste")
			(net "P5E_PEX0_STN4_TX_DP<68>")
		)
		(pad "M42" smd circle
			(at 16.150082 -12.349988)
			(size 0.4572 0.4572)
			(layers "F.Cu" "F.Mask" "F.Paste")
			(net "P5E_PEX0_STN4_TX_DN<68>")
		)
		(pad "M43" smd circle
			(at 17.100042 -12.349988)
			(size 0.4572 0.4572)
			(layers "F.Cu" "F.Mask" "F.Paste")
			(net "GND")
		)
		(pad "M44" smd circle
			(at 18.050002 -12.349988)
			(size 0.4572 0.4572)
			(layers "F.Cu" "F.Mask" "F.Paste")
			(net "GND")
		)
		(pad "M45" smd circle
			(at 18.999962 -12.349988)
			(size 0.4572 0.4572)
			(layers "F.Cu" "F.Mask" "F.Paste")
			(net "GND")
		)
		(pad "M46" smd circle
			(at 19.949922 -12.349988)
			(size 0.4572 0.4572)
			(layers "F.Cu" "F.Mask" "F.Paste")
			(net "GND")
		)
		(pad "M47" smd circle
			(at 20.899882 -12.349988)
			(size 0.4572 0.4572)
			(layers "F.Cu" "F.Mask" "F.Paste")
			(net "GND")
		)
		(pad "M48" smd circle
			(at 21.850096 -12.349988)
			(size 0.4572 0.4572)
			(layers "F.Cu" "F.Mask" "F.Paste")
			(net "P5E_PEX0_STN4_RX_DP<68>")
		)
		(pad "M49" smd circle
			(at 22.800056 -12.349988)
			(size 0.4572 0.4572)
			(layers "F.Cu" "F.Mask" "F.Paste")
			(net "P5E_PEX0_STN4_RX_DN<68>")
		)
		(pad "N1" smd circle
			(at -22.800056 -11.400028)
			(size 0.4572 0.4572)
			(layers "F.Cu" "F.Mask" "F.Paste")
			(net "GND")
		)
		(pad "N2" smd circle
			(at -21.850096 -11.400028)
			(size 0.4572 0.4572)
			(layers "F.Cu" "F.Mask" "F.Paste")
			(net "GND")
		)
		(pad "N3" smd circle
			(at -20.899882 -11.400028)
			(size 0.4572 0.4572)
			(layers "F.Cu" "F.Mask" "F.Paste")
			(net "P5E_PEX0_STN7_RX_DN<118>")
		)
		(pad "N4" smd circle
			(at -19.949922 -11.400028)
			(size 0.4572 0.4572)
			(layers "F.Cu" "F.Mask" "F.Paste")
			(net "P5E_PEX0_STN7_RX_DP<118>")
		)
		(pad "N5" smd circle
			(at -18.999962 -11.400028)
			(size 0.4572 0.4572)
			(layers "F.Cu" "F.Mask" "F.Paste")
			(net "GND")
		)
		(pad "N6" smd circle
			(at -18.050002 -11.400028)
			(size 0.4572 0.4572)
			(layers "F.Cu" "F.Mask" "F.Paste")
			(net "P5E_PEX0_STN7_TX_DN<118>")
		)
		(pad "N7" smd circle
			(at -17.100042 -11.400028)
			(size 0.4572 0.4572)
			(layers "F.Cu" "F.Mask" "F.Paste")
			(net "P5E_PEX0_STN7_TX_DP<118>")
		)
		(pad "N8" smd circle
			(at -16.150082 -11.400028)
			(size 0.4572 0.4572)
			(layers "F.Cu" "F.Mask" "F.Paste")
			(net "GND")
		)
		(pad "N9" smd circle
			(at -15.200122 -11.400028)
			(size 0.4572 0.4572)
			(layers "F.Cu" "F.Mask" "F.Paste")
			(net "GND")
		)
		(pad "N10" smd circle
			(at -14.249908 -11.400028)
			(size 0.4572 0.4572)
			(layers "F.Cu" "F.Mask" "F.Paste")
			(net "GND")
		)
		(pad "N11" smd circle
			(at -13.299948 -11.400028)
			(size 0.4572 0.4572)
			(layers "F.Cu" "F.Mask" "F.Paste")
			(net "GND")
		)
		(pad "N12" smd circle
			(at -12.349988 -11.400028)
			(size 0.4572 0.4572)
			(layers "F.Cu" "F.Mask" "F.Paste")
			(net "GND")
		)
		(pad "N13" smd circle
			(at -11.400028 -11.400028)
			(size 0.4572 0.4572)
			(layers "F.Cu" "F.Mask" "F.Paste")
			(net "GND")
		)
		(pad "N14" smd circle
			(at -10.450068 -11.400028)
			(size 0.4572 0.4572)
			(layers "F.Cu" "F.Mask" "F.Paste")
			(net "GND")
		)
		(pad "N15" smd circle
			(at -9.500108 -11.400028)
			(size 0.4572 0.4572)
			(layers "F.Cu" "F.Mask" "F.Paste")
			(net "GND")
		)
		(pad "N16" smd circle
			(at -8.549894 -11.400028)
			(size 0.4572 0.4572)
			(layers "F.Cu" "F.Mask" "F.Paste")
			(net "GND")
		)
		(pad "N17" smd circle
			(at -7.599934 -11.400028)
			(size 0.4572 0.4572)
			(layers "F.Cu" "F.Mask" "F.Paste")
			(net "GND")
		)
		(pad "N18" smd circle
			(at -6.649974 -11.400028)
			(size 0.4572 0.4572)
			(layers "F.Cu" "F.Mask" "F.Paste")
			(net "GND")
		)
		(pad "N19" smd circle
			(at -5.700014 -11.400028)
			(size 0.4572 0.4572)
			(layers "F.Cu" "F.Mask" "F.Paste")
			(net "GND")
		)
		(pad "N20" smd circle
			(at -4.750054 -11.400028)
			(size 0.4572 0.4572)
			(layers "F.Cu" "F.Mask" "F.Paste")
			(net "GND")
		)
		(pad "N21" smd circle
			(at -3.800094 -11.400028)
			(size 0.4572 0.4572)
			(layers "F.Cu" "F.Mask" "F.Paste")
			(net "GND")
		)
		(pad "N22" smd circle
			(at -2.84988 -11.400028)
			(size 0.4572 0.4572)
			(layers "F.Cu" "F.Mask" "F.Paste")
			(net "GND")
		)
		(pad "N23" smd circle
			(at -1.89992 -11.400028)
			(size 0.4572 0.4572)
			(layers "F.Cu" "F.Mask" "F.Paste")
			(net "GND")
		)
		(pad "N24" smd circle
			(at -0.94996 -11.400028)
			(size 0.4572 0.4572)
			(layers "F.Cu" "F.Mask" "F.Paste")
			(net "GND")
		)
		(pad "N25" smd circle
			(at 0 -11.400028)
			(size 0.4572 0.4572)
			(layers "F.Cu" "F.Mask" "F.Paste")
			(net "GND")
		)
		(pad "N26" smd circle
			(at 0.94996 -11.400028)
			(size 0.4572 0.4572)
			(layers "F.Cu" "F.Mask" "F.Paste")
			(net "GND")
		)
		(pad "N27" smd circle
			(at 1.89992 -11.400028)
			(size 0.4572 0.4572)
			(layers "F.Cu" "F.Mask" "F.Paste")
			(net "GND")
		)
		(pad "N28" smd circle
			(at 2.84988 -11.400028)
			(size 0.4572 0.4572)
			(layers "F.Cu" "F.Mask" "F.Paste")
			(net "GND")
		)
		(pad "N29" smd circle
			(at 3.800094 -11.400028)
			(size 0.4572 0.4572)
			(layers "F.Cu" "F.Mask" "F.Paste")
			(net "GND")
		)
		(pad "N30" smd circle
			(at 4.750054 -11.400028)
			(size 0.4572 0.4572)
			(layers "F.Cu" "F.Mask" "F.Paste")
			(net "GND")
		)
		(pad "N31" smd circle
			(at 5.700014 -11.400028)
			(size 0.4572 0.4572)
			(layers "F.Cu" "F.Mask" "F.Paste")
			(net "GND")
		)
		(pad "N32" smd circle
			(at 6.649974 -11.400028)
			(size 0.4572 0.4572)
			(layers "F.Cu" "F.Mask" "F.Paste")
			(net "GND")
		)
		(pad "N33" smd circle
			(at 7.599934 -11.400028)
			(size 0.4572 0.4572)
			(layers "F.Cu" "F.Mask" "F.Paste")
			(net "GND")
		)
		(pad "N34" smd circle
			(at 8.549894 -11.400028)
			(size 0.4572 0.4572)
			(layers "F.Cu" "F.Mask" "F.Paste")
			(net "GND")
		)
		(pad "N35" smd circle
			(at 9.500108 -11.400028)
			(size 0.4572 0.4572)
			(layers "F.Cu" "F.Mask" "F.Paste")
			(net "GND")
		)
		(pad "N36" smd circle
			(at 10.450068 -11.400028)
			(size 0.4572 0.4572)
			(layers "F.Cu" "F.Mask" "F.Paste")
			(net "GND")
		)
		(pad "N37" smd circle
			(at 11.400028 -11.400028)
			(size 0.4572 0.4572)
			(layers "F.Cu" "F.Mask" "F.Paste")
			(net "GND")
		)
		(pad "N38" smd circle
			(at 12.349988 -11.400028)
			(size 0.4572 0.4572)
			(layers "F.Cu" "F.Mask" "F.Paste")
			(net "SMB_PEX0_SLAVE_SCL")
		)
		(pad "N39" smd circle
			(at 13.299948 -11.400028)
			(size 0.4572 0.4572)
			(layers "F.Cu" "F.Mask" "F.Paste")
			(net "Net_2888")
		)
		(pad "N40" smd circle
			(at 14.249908 -11.400028)
			(size 0.4572 0.4572)
			(layers "F.Cu" "F.Mask" "F.Paste")
			(net "GND")
		)
		(pad "N41" smd circle
			(at 15.200122 -11.400028)
			(size 0.4572 0.4572)
			(layers "F.Cu" "F.Mask" "F.Paste")
			(net "GND")
		)
		(pad "N42" smd circle
			(at 16.150082 -11.400028)
			(size 0.4572 0.4572)
			(layers "F.Cu" "F.Mask" "F.Paste")
			(net "GND")
		)
		(pad "N43" smd circle
			(at 17.100042 -11.400028)
			(size 0.4572 0.4572)
			(layers "F.Cu" "F.Mask" "F.Paste")
			(net "P5E_PEX0_STN4_TX_DP<67>")
		)
		(pad "N44" smd circle
			(at 18.050002 -11.400028)
			(size 0.4572 0.4572)
			(layers "F.Cu" "F.Mask" "F.Paste")
			(net "P5E_PEX0_STN4_TX_DN<67>")
		)
		(pad "N45" smd circle
			(at 18.999962 -11.400028)
			(size 0.4572 0.4572)
			(layers "F.Cu" "F.Mask" "F.Paste")
			(net "GND")
		)
		(pad "N46" smd circle
			(at 19.949922 -11.400028)
			(size 0.4572 0.4572)
			(layers "F.Cu" "F.Mask" "F.Paste")
			(net "P5E_PEX0_STN4_RX_DP<67>")
		)
		(pad "N47" smd circle
			(at 20.899882 -11.400028)
			(size 0.4572 0.4572)
			(layers "F.Cu" "F.Mask" "F.Paste")
			(net "P5E_PEX0_STN4_RX_DN<67>")
		)
		(pad "N48" smd circle
			(at 21.850096 -11.400028)
			(size 0.4572 0.4572)
			(layers "F.Cu" "F.Mask" "F.Paste")
			(net "GND")
		)
		(pad "N49" smd circle
			(at 22.800056 -11.400028)
			(size 0.4572 0.4572)
			(layers "F.Cu" "F.Mask" "F.Paste")
			(net "GND")
		)
		(pad "P1" smd circle
			(at -22.800056 -10.450068)
			(size 0.4572 0.4572)
			(layers "F.Cu" "F.Mask" "F.Paste")
			(net "P5E_PEX0_STN7_RX_DN<117>")
		)
		(pad "P2" smd circle
			(at -21.850096 -10.450068)
			(size 0.4572 0.4572)
			(layers "F.Cu" "F.Mask" "F.Paste")
			(net "P5E_PEX0_STN7_RX_DP<117>")
		)
		(pad "P3" smd circle
			(at -20.899882 -10.450068)
			(size 0.4572 0.4572)
			(layers "F.Cu" "F.Mask" "F.Paste")
			(net "GND")
		)
		(pad "P4" smd circle
			(at -19.949922 -10.450068)
			(size 0.4572 0.4572)
			(layers "F.Cu" "F.Mask" "F.Paste")
			(net "GND")
		)
		(pad "P5" smd circle
			(at -18.999962 -10.450068)
			(size 0.4572 0.4572)
			(layers "F.Cu" "F.Mask" "F.Paste")
			(net "GND")
		)
		(pad "P6" smd circle
			(at -18.050002 -10.450068)
			(size 0.4572 0.4572)
			(layers "F.Cu" "F.Mask" "F.Paste")
			(net "GND")
		)
		(pad "P7" smd circle
			(at -17.100042 -10.450068)
			(size 0.4572 0.4572)
			(layers "F.Cu" "F.Mask" "F.Paste")
			(net "GND")
		)
		(pad "P8" smd circle
			(at -16.150082 -10.450068)
			(size 0.4572 0.4572)
			(layers "F.Cu" "F.Mask" "F.Paste")
			(net "P5E_PEX0_STN7_TX_DN<117>")
		)
		(pad "P9" smd circle
			(at -15.200122 -10.450068)
			(size 0.4572 0.4572)
			(layers "F.Cu" "F.Mask" "F.Paste")
			(net "P5E_PEX0_STN7_TX_DP<117>")
		)
		(pad "P10" smd circle
			(at -14.249908 -10.450068)
			(size 0.4572 0.4572)
			(layers "F.Cu" "F.Mask" "F.Paste")
			(net "GND")
		)
		(pad "P11" smd circle
			(at -13.299948 -10.450068)
			(size 0.4572 0.4572)
			(layers "F.Cu" "F.Mask" "F.Paste")
			(net "GND")
		)
		(pad "P12" smd circle
			(at -12.349988 -10.450068)
			(size 0.4572 0.4572)
			(layers "F.Cu" "F.Mask" "F.Paste")
			(net "GND")
		)
		(pad "P13" smd circle
			(at -11.400028 -10.450068)
			(size 0.4572 0.4572)
			(layers "F.Cu" "F.Mask" "F.Paste")
			(net "GND")
		)
		(pad "P14" smd circle
			(at -10.450068 -10.450068)
			(size 0.4572 0.4572)
			(layers "F.Cu" "F.Mask" "F.Paste")
			(net "GND")
		)
		(pad "P15" smd circle
			(at -9.500108 -10.450068)
			(size 0.4572 0.4572)
			(layers "F.Cu" "F.Mask" "F.Paste")
			(net "GND")
		)
		(pad "P16" smd circle
			(at -8.549894 -10.450068)
			(size 0.4572 0.4572)
			(layers "F.Cu" "F.Mask" "F.Paste")
			(net "GND")
		)
		(pad "P17" smd circle
			(at -7.599934 -10.450068)
			(size 0.4572 0.4572)
			(layers "F.Cu" "F.Mask" "F.Paste")
			(net "GND")
		)
		(pad "P18" smd circle
			(at -6.649974 -10.450068)
			(size 0.4572 0.4572)
			(layers "F.Cu" "F.Mask" "F.Paste")
			(net "GND")
		)
		(pad "P19" smd circle
			(at -5.700014 -10.450068)
			(size 0.4572 0.4572)
			(layers "F.Cu" "F.Mask" "F.Paste")
			(net "GND")
		)
		(pad "P20" smd circle
			(at -4.750054 -10.450068)
			(size 0.4572 0.4572)
			(layers "F.Cu" "F.Mask" "F.Paste")
			(net "GND")
		)
		(pad "P21" smd circle
			(at -3.800094 -10.450068)
			(size 0.4572 0.4572)
			(layers "F.Cu" "F.Mask" "F.Paste")
			(net "GND")
		)
		(pad "P22" smd circle
			(at -2.84988 -10.450068)
			(size 0.4572 0.4572)
			(layers "F.Cu" "F.Mask" "F.Paste")
			(net "GND")
		)
		(pad "P23" smd circle
			(at -1.89992 -10.450068)
			(size 0.4572 0.4572)
			(layers "F.Cu" "F.Mask" "F.Paste")
			(net "GND")
		)
		(pad "P24" smd circle
			(at -0.94996 -10.450068)
			(size 0.4572 0.4572)
			(layers "F.Cu" "F.Mask" "F.Paste")
			(net "GND")
		)
		(pad "P25" smd circle
			(at 0 -10.450068)
			(size 0.4572 0.4572)
			(layers "F.Cu" "F.Mask" "F.Paste")
			(net "GND")
		)
		(pad "P26" smd circle
			(at 0.94996 -10.450068)
			(size 0.4572 0.4572)
			(layers "F.Cu" "F.Mask" "F.Paste")
			(net "GND")
		)
		(pad "P27" smd circle
			(at 1.89992 -10.450068)
			(size 0.4572 0.4572)
			(layers "F.Cu" "F.Mask" "F.Paste")
			(net "GND")
		)
		(pad "P28" smd circle
			(at 2.84988 -10.450068)
			(size 0.4572 0.4572)
			(layers "F.Cu" "F.Mask" "F.Paste")
			(net "GND")
		)
		(pad "P29" smd circle
			(at 3.800094 -10.450068)
			(size 0.4572 0.4572)
			(layers "F.Cu" "F.Mask" "F.Paste")
			(net "GND")
		)
		(pad "P30" smd circle
			(at 4.750054 -10.450068)
			(size 0.4572 0.4572)
			(layers "F.Cu" "F.Mask" "F.Paste")
			(net "GND")
		)
		(pad "P31" smd circle
			(at 5.700014 -10.450068)
			(size 0.4572 0.4572)
			(layers "F.Cu" "F.Mask" "F.Paste")
			(net "GND")
		)
		(pad "P32" smd circle
			(at 6.649974 -10.450068)
			(size 0.4572 0.4572)
			(layers "F.Cu" "F.Mask" "F.Paste")
			(net "GND")
		)
		(pad "P33" smd circle
			(at 7.599934 -10.450068)
			(size 0.4572 0.4572)
			(layers "F.Cu" "F.Mask" "F.Paste")
			(net "GND")
		)
		(pad "P34" smd circle
			(at 8.549894 -10.450068)
			(size 0.4572 0.4572)
			(layers "F.Cu" "F.Mask" "F.Paste")
			(net "GND")
		)
		(pad "P35" smd circle
			(at 9.500108 -10.450068)
			(size 0.4572 0.4572)
			(layers "F.Cu" "F.Mask" "F.Paste")
			(net "GND")
		)
		(pad "P36" smd circle
			(at 10.450068 -10.450068)
			(size 0.4572 0.4572)
			(layers "F.Cu" "F.Mask" "F.Paste")
			(net "Net_484")
		)
		(pad "P37" smd circle
			(at 11.400028 -10.450068)
			(size 0.4572 0.4572)
			(layers "F.Cu" "F.Mask" "F.Paste")
			(net "GND")
		)
		(pad "P38" smd circle
			(at 12.349988 -10.450068)
			(size 0.4572 0.4572)
			(layers "F.Cu" "F.Mask" "F.Paste")
			(net "RST_PEX0_S3_PERST_R_N")
		)
		(pad "P39" smd circle
			(at 13.299948 -10.450068)
			(size 0.4572 0.4572)
			(layers "F.Cu" "F.Mask" "F.Paste")
			(net "RST_PEX0_S1_PERST_R_N")
		)
		(pad "P40" smd circle
			(at 14.249908 -10.450068)
			(size 0.4572 0.4572)
			(layers "F.Cu" "F.Mask" "F.Paste")
			(net "GND")
		)
		(pad "P41" smd circle
			(at 15.200122 -10.450068)
			(size 0.4572 0.4572)
			(layers "F.Cu" "F.Mask" "F.Paste")
			(net "P5E_PEX0_STN4_TX_DP<66>")
		)
		(pad "P42" smd circle
			(at 16.150082 -10.450068)
			(size 0.4572 0.4572)
			(layers "F.Cu" "F.Mask" "F.Paste")
			(net "P5E_PEX0_STN4_TX_DN<66>")
		)
		(pad "P43" smd circle
			(at 17.100042 -10.450068)
			(size 0.4572 0.4572)
			(layers "F.Cu" "F.Mask" "F.Paste")
			(net "GND")
		)
		(pad "P44" smd circle
			(at 18.050002 -10.450068)
			(size 0.4572 0.4572)
			(layers "F.Cu" "F.Mask" "F.Paste")
			(net "GND")
		)
		(pad "P45" smd circle
			(at 18.999962 -10.450068)
			(size 0.4572 0.4572)
			(layers "F.Cu" "F.Mask" "F.Paste")
			(net "GND")
		)
		(pad "P46" smd circle
			(at 19.949922 -10.450068)
			(size 0.4572 0.4572)
			(layers "F.Cu" "F.Mask" "F.Paste")
			(net "GND")
		)
		(pad "P47" smd circle
			(at 20.899882 -10.450068)
			(size 0.4572 0.4572)
			(layers "F.Cu" "F.Mask" "F.Paste")
			(net "GND")
		)
		(pad "P48" smd circle
			(at 21.850096 -10.450068)
			(size 0.4572 0.4572)
			(layers "F.Cu" "F.Mask" "F.Paste")
			(net "P5E_PEX0_STN4_RX_DP<66>")
		)
		(pad "P49" smd circle
			(at 22.800056 -10.450068)
			(size 0.4572 0.4572)
			(layers "F.Cu" "F.Mask" "F.Paste")
			(net "P5E_PEX0_STN4_RX_DN<66>")
		)
		(pad "R1" smd circle
			(at -22.800056 -9.500108)
			(size 0.4572 0.4572)
			(layers "F.Cu" "F.Mask" "F.Paste")
			(net "GND")
		)
		(pad "R2" smd circle
			(at -21.850096 -9.500108)
			(size 0.4572 0.4572)
			(layers "F.Cu" "F.Mask" "F.Paste")
			(net "GND")
		)
		(pad "R3" smd circle
			(at -20.899882 -9.500108)
			(size 0.4572 0.4572)
			(layers "F.Cu" "F.Mask" "F.Paste")
			(net "P5E_PEX0_STN7_RX_DN<116>")
		)
		(pad "R4" smd circle
			(at -19.949922 -9.500108)
			(size 0.4572 0.4572)
			(layers "F.Cu" "F.Mask" "F.Paste")
			(net "P5E_PEX0_STN7_RX_DP<116>")
		)
		(pad "R5" smd circle
			(at -18.999962 -9.500108)
			(size 0.4572 0.4572)
			(layers "F.Cu" "F.Mask" "F.Paste")
			(net "GND")
		)
		(pad "R6" smd circle
			(at -18.050002 -9.500108)
			(size 0.4572 0.4572)
			(layers "F.Cu" "F.Mask" "F.Paste")
			(net "P5E_PEX0_STN7_TX_DN<116>")
		)
		(pad "R7" smd circle
			(at -17.100042 -9.500108)
			(size 0.4572 0.4572)
			(layers "F.Cu" "F.Mask" "F.Paste")
			(net "P5E_PEX0_STN7_TX_DP<116>")
		)
		(pad "R8" smd circle
			(at -16.150082 -9.500108)
			(size 0.4572 0.4572)
			(layers "F.Cu" "F.Mask" "F.Paste")
			(net "GND")
		)
		(pad "R9" smd circle
			(at -15.200122 -9.500108)
			(size 0.4572 0.4572)
			(layers "F.Cu" "F.Mask" "F.Paste")
			(net "GND")
		)
		(pad "R10" smd circle
			(at -14.249908 -9.500108)
			(size 0.4572 0.4572)
			(layers "F.Cu" "F.Mask" "F.Paste")
			(net "GND")
		)
		(pad "R11" smd circle
			(at -13.299948 -9.500108)
			(size 0.4572 0.4572)
			(layers "F.Cu" "F.Mask" "F.Paste")
			(net "GND")
		)
		(pad "R12" smd circle
			(at -12.349988 -9.500108)
			(size 0.4572 0.4572)
			(layers "F.Cu" "F.Mask" "F.Paste")
			(net "GND")
		)
		(pad "R13" smd circle
			(at -11.400028 -9.500108)
			(size 0.4572 0.4572)
			(layers "F.Cu" "F.Mask" "F.Paste")
			(net "GND")
		)
		(pad "R14" smd circle
			(at -10.450068 -9.500108)
			(size 0.4572 0.4572)
			(layers "F.Cu" "F.Mask" "F.Paste")
			(net "GND")
		)
		(pad "R15" smd circle
			(at -9.500108 -9.500108)
			(size 0.4572 0.4572)
			(layers "F.Cu" "F.Mask" "F.Paste")
			(net "GND")
		)
		(pad "R16" smd circle
			(at -8.549894 -9.500108)
			(size 0.4572 0.4572)
			(layers "F.Cu" "F.Mask" "F.Paste")
			(net "GND")
		)
		(pad "R17" smd circle
			(at -7.599934 -9.500108)
			(size 0.4572 0.4572)
			(layers "F.Cu" "F.Mask" "F.Paste")
			(net "GND")
		)
		(pad "R18" smd circle
			(at -6.649974 -9.500108)
			(size 0.4572 0.4572)
			(layers "F.Cu" "F.Mask" "F.Paste")
			(net "GND")
		)
		(pad "R19" smd circle
			(at -5.700014 -9.500108)
			(size 0.4572 0.4572)
			(layers "F.Cu" "F.Mask" "F.Paste")
			(net "GND")
		)
		(pad "R20" smd circle
			(at -4.750054 -9.500108)
			(size 0.4572 0.4572)
			(layers "F.Cu" "F.Mask" "F.Paste")
			(net "GND")
		)
		(pad "R21" smd circle
			(at -3.800094 -9.500108)
			(size 0.4572 0.4572)
			(layers "F.Cu" "F.Mask" "F.Paste")
			(net "GND")
		)
		(pad "R22" smd circle
			(at -2.84988 -9.500108)
			(size 0.4572 0.4572)
			(layers "F.Cu" "F.Mask" "F.Paste")
			(net "GND")
		)
		(pad "R23" smd circle
			(at -1.89992 -9.500108)
			(size 0.4572 0.4572)
			(layers "F.Cu" "F.Mask" "F.Paste")
			(net "GND")
		)
		(pad "R24" smd circle
			(at -0.94996 -9.500108)
			(size 0.4572 0.4572)
			(layers "F.Cu" "F.Mask" "F.Paste")
			(net "GND")
		)
		(pad "R25" smd circle
			(at 0 -9.500108)
			(size 0.4572 0.4572)
			(layers "F.Cu" "F.Mask" "F.Paste")
			(net "GND")
		)
		(pad "R26" smd circle
			(at 0.94996 -9.500108)
			(size 0.4572 0.4572)
			(layers "F.Cu" "F.Mask" "F.Paste")
			(net "GND")
		)
		(pad "R27" smd circle
			(at 1.89992 -9.500108)
			(size 0.4572 0.4572)
			(layers "F.Cu" "F.Mask" "F.Paste")
			(net "GND")
		)
		(pad "R28" smd circle
			(at 2.84988 -9.500108)
			(size 0.4572 0.4572)
			(layers "F.Cu" "F.Mask" "F.Paste")
			(net "GND")
		)
		(pad "R29" smd circle
			(at 3.800094 -9.500108)
			(size 0.4572 0.4572)
			(layers "F.Cu" "F.Mask" "F.Paste")
			(net "GND")
		)
		(pad "R30" smd circle
			(at 4.750054 -9.500108)
			(size 0.4572 0.4572)
			(layers "F.Cu" "F.Mask" "F.Paste")
			(net "GND")
		)
		(pad "R31" smd circle
			(at 5.700014 -9.500108)
			(size 0.4572 0.4572)
			(layers "F.Cu" "F.Mask" "F.Paste")
			(net "GND")
		)
		(pad "R32" smd circle
			(at 6.649974 -9.500108)
			(size 0.4572 0.4572)
			(layers "F.Cu" "F.Mask" "F.Paste")
			(net "GND")
		)
		(pad "R33" smd circle
			(at 7.599934 -9.500108)
			(size 0.4572 0.4572)
			(layers "F.Cu" "F.Mask" "F.Paste")
			(net "GND")
		)
		(pad "R34" smd circle
			(at 8.549894 -9.500108)
			(size 0.4572 0.4572)
			(layers "F.Cu" "F.Mask" "F.Paste")
			(net "GND")
		)
		(pad "R35" smd circle
			(at 9.500108 -9.500108)
			(size 0.4572 0.4572)
			(layers "F.Cu" "F.Mask" "F.Paste")
			(net "GND")
		)
		(pad "R36" smd circle
			(at 10.450068 -9.500108)
			(size 0.4572 0.4572)
			(layers "F.Cu" "F.Mask" "F.Paste")
			(net "Net_488")
		)
		(pad "R37" smd circle
			(at 11.400028 -9.500108)
			(size 0.4572 0.4572)
			(layers "F.Cu" "F.Mask" "F.Paste")
			(net "GND")
		)
		(pad "R38" smd circle
			(at 12.349988 -9.500108)
			(size 0.4572 0.4572)
			(layers "F.Cu" "F.Mask" "F.Paste")
			(net "Net_2836")
		)
		(pad "R39" smd circle
			(at 13.299948 -9.500108)
			(size 0.4572 0.4572)
			(layers "F.Cu" "F.Mask" "F.Paste")
			(net "Net_2830")
		)
		(pad "R40" smd circle
			(at 14.249908 -9.500108)
			(size 0.4572 0.4572)
			(layers "F.Cu" "F.Mask" "F.Paste")
			(net "GND")
		)
		(pad "R41" smd circle
			(at 15.200122 -9.500108)
			(size 0.4572 0.4572)
			(layers "F.Cu" "F.Mask" "F.Paste")
			(net "GND")
		)
		(pad "R42" smd circle
			(at 16.150082 -9.500108)
			(size 0.4572 0.4572)
			(layers "F.Cu" "F.Mask" "F.Paste")
			(net "GND")
		)
		(pad "R43" smd circle
			(at 17.100042 -9.500108)
			(size 0.4572 0.4572)
			(layers "F.Cu" "F.Mask" "F.Paste")
			(net "P5E_PEX0_STN4_TX_DP<65>")
		)
		(pad "R44" smd circle
			(at 18.050002 -9.500108)
			(size 0.4572 0.4572)
			(layers "F.Cu" "F.Mask" "F.Paste")
			(net "P5E_PEX0_STN4_TX_DN<65>")
		)
		(pad "R45" smd circle
			(at 18.999962 -9.500108)
			(size 0.4572 0.4572)
			(layers "F.Cu" "F.Mask" "F.Paste")
			(net "GND")
		)
		(pad "R46" smd circle
			(at 19.949922 -9.500108)
			(size 0.4572 0.4572)
			(layers "F.Cu" "F.Mask" "F.Paste")
			(net "P5E_PEX0_STN4_RX_DP<65>")
		)
		(pad "R47" smd circle
			(at 20.899882 -9.500108)
			(size 0.4572 0.4572)
			(layers "F.Cu" "F.Mask" "F.Paste")
			(net "P5E_PEX0_STN4_RX_DN<65>")
		)
		(pad "R48" smd circle
			(at 21.850096 -9.500108)
			(size 0.4572 0.4572)
			(layers "F.Cu" "F.Mask" "F.Paste")
			(net "GND")
		)
		(pad "R49" smd circle
			(at 22.800056 -9.500108)
			(size 0.4572 0.4572)
			(layers "F.Cu" "F.Mask" "F.Paste")
			(net "GND")
		)
		(pad "T1" smd circle
			(at -22.800056 -8.549894)
			(size 0.4572 0.4572)
			(layers "F.Cu" "F.Mask" "F.Paste")
			(net "P5E_PEX0_STN7_RX_DN<115>")
		)
		(pad "T2" smd circle
			(at -21.850096 -8.549894)
			(size 0.4572 0.4572)
			(layers "F.Cu" "F.Mask" "F.Paste")
			(net "P5E_PEX0_STN7_RX_DP<115>")
		)
		(pad "T3" smd circle
			(at -20.899882 -8.549894)
			(size 0.4572 0.4572)
			(layers "F.Cu" "F.Mask" "F.Paste")
			(net "GND")
		)
		(pad "T4" smd circle
			(at -19.949922 -8.549894)
			(size 0.4572 0.4572)
			(layers "F.Cu" "F.Mask" "F.Paste")
			(net "GND")
		)
		(pad "T5" smd circle
			(at -18.999962 -8.549894)
			(size 0.4572 0.4572)
			(layers "F.Cu" "F.Mask" "F.Paste")
			(net "GND")
		)
		(pad "T6" smd circle
			(at -18.050002 -8.549894)
			(size 0.4572 0.4572)
			(layers "F.Cu" "F.Mask" "F.Paste")
			(net "GND")
		)
		(pad "T7" smd circle
			(at -17.100042 -8.549894)
			(size 0.4572 0.4572)
			(layers "F.Cu" "F.Mask" "F.Paste")
			(net "GND")
		)
		(pad "T8" smd circle
			(at -16.150082 -8.549894)
			(size 0.4572 0.4572)
			(layers "F.Cu" "F.Mask" "F.Paste")
			(net "P5E_PEX0_STN7_TX_DN<115>")
		)
		(pad "T9" smd circle
			(at -15.200122 -8.549894)
			(size 0.4572 0.4572)
			(layers "F.Cu" "F.Mask" "F.Paste")
			(net "P5E_PEX0_STN7_TX_DP<115>")
		)
		(pad "T10" smd circle
			(at -14.249908 -8.549894)
			(size 0.4572 0.4572)
			(layers "F.Cu" "F.Mask" "F.Paste")
			(net "GND")
		)
		(pad "T11" smd circle
			(at -13.299948 -8.549894)
			(size 0.4572 0.4572)
			(layers "F.Cu" "F.Mask" "F.Paste")
			(net "GND")
		)
		(pad "T12" smd circle
			(at -12.349988 -8.549894)
			(size 0.4572 0.4572)
			(layers "F.Cu" "F.Mask" "F.Paste")
			(net "GND")
		)
		(pad "T13" smd circle
			(at -11.400028 -8.549894)
			(size 0.4572 0.4572)
			(layers "F.Cu" "F.Mask" "F.Paste")
			(net "GND")
		)
		(pad "T14" smd circle
			(at -10.450068 -8.549894)
			(size 0.4572 0.4572)
			(layers "F.Cu" "F.Mask" "F.Paste")
			(net "Net_489")
		)
		(pad "T15" smd circle
			(at -9.500108 -8.549894)
			(size 0.4572 0.4572)
			(layers "F.Cu" "F.Mask" "F.Paste")
			(net "GND")
		)
		(pad "T16" smd circle
			(at -8.549894 -8.549894)
			(size 0.4572 0.4572)
			(layers "F.Cu" "F.Mask" "F.Paste")
			(net "P1V25_SERDES_VDDPLL_PEX0")
		)
		(pad "T17" smd circle
			(at -7.599934 -8.549894)
			(size 0.4572 0.4572)
			(layers "F.Cu" "F.Mask" "F.Paste")
			(net "P1V25_SERDES_VDDPLL_PEX0")
		)
		(pad "T18" smd circle
			(at -6.649974 -8.549894)
			(size 0.4572 0.4572)
			(layers "F.Cu" "F.Mask" "F.Paste")
			(net "P1V25_SERDES_VDDPLL_PEX0")
		)
		(pad "T19" smd circle
			(at -5.700014 -8.549894)
			(size 0.4572 0.4572)
			(layers "F.Cu" "F.Mask" "F.Paste")
			(net "P1V25_SERDES_VDDPLL_PEX0")
		)
		(pad "T20" smd circle
			(at -4.750054 -8.549894)
			(size 0.4572 0.4572)
			(layers "F.Cu" "F.Mask" "F.Paste")
			(net "P1V25_SERDES_VDDPLL_PEX0")
		)
		(pad "T21" smd circle
			(at -3.800094 -8.549894)
			(size 0.4572 0.4572)
			(layers "F.Cu" "F.Mask" "F.Paste")
			(net "P1V25_SERDES_VDDPLL_PEX0")
		)
		(pad "T22" smd circle
			(at -2.84988 -8.549894)
			(size 0.4572 0.4572)
			(layers "F.Cu" "F.Mask" "F.Paste")
			(net "P1V25_SERDES_VDDPLL_PEX0")
		)
		(pad "T23" smd circle
			(at -1.89992 -8.549894)
			(size 0.4572 0.4572)
			(layers "F.Cu" "F.Mask" "F.Paste")
			(net "P1V25_SERDES_VDDPLL_PEX0")
		)
		(pad "T24" smd circle
			(at -0.94996 -8.549894)
			(size 0.4572 0.4572)
			(layers "F.Cu" "F.Mask" "F.Paste")
			(net "P1V25_SERDES_VDDPLL_PEX0")
		)
		(pad "T25" smd circle
			(at 0 -8.549894)
			(size 0.4572 0.4572)
			(layers "F.Cu" "F.Mask" "F.Paste")
			(net "P1V25_SERDES_VDDPLL_PEX0")
		)
		(pad "T26" smd circle
			(at 0.94996 -8.549894)
			(size 0.4572 0.4572)
			(layers "F.Cu" "F.Mask" "F.Paste")
			(net "P1V25_SERDES_VDDPLL_PEX0")
		)
		(pad "T27" smd circle
			(at 1.89992 -8.549894)
			(size 0.4572 0.4572)
			(layers "F.Cu" "F.Mask" "F.Paste")
			(net "P1V25_SERDES_VDDPLL_PEX0")
		)
		(pad "T28" smd circle
			(at 2.84988 -8.549894)
			(size 0.4572 0.4572)
			(layers "F.Cu" "F.Mask" "F.Paste")
			(net "P1V25_SERDES_VDDPLL_PEX0")
		)
		(pad "T29" smd circle
			(at 3.800094 -8.549894)
			(size 0.4572 0.4572)
			(layers "F.Cu" "F.Mask" "F.Paste")
			(net "P1V25_SERDES_VDDPLL_PEX0")
		)
		(pad "T30" smd circle
			(at 4.750054 -8.549894)
			(size 0.4572 0.4572)
			(layers "F.Cu" "F.Mask" "F.Paste")
			(net "P1V25_SERDES_VDDPLL_PEX0")
		)
		(pad "T31" smd circle
			(at 5.700014 -8.549894)
			(size 0.4572 0.4572)
			(layers "F.Cu" "F.Mask" "F.Paste")
			(net "P1V25_SERDES_VDDPLL_PEX0")
		)
		(pad "T32" smd circle
			(at 6.649974 -8.549894)
			(size 0.4572 0.4572)
			(layers "F.Cu" "F.Mask" "F.Paste")
			(net "P1V25_SERDES_VDDPLL_PEX0")
		)
		(pad "T33" smd circle
			(at 7.599934 -8.549894)
			(size 0.4572 0.4572)
			(layers "F.Cu" "F.Mask" "F.Paste")
			(net "P1V25_SERDES_VDDPLL_PEX0")
		)
		(pad "T34" smd circle
			(at 8.549894 -8.549894)
			(size 0.4572 0.4572)
			(layers "F.Cu" "F.Mask" "F.Paste")
			(net "GND")
		)
		(pad "T35" smd circle
			(at 9.500108 -8.549894)
			(size 0.4572 0.4572)
			(layers "F.Cu" "F.Mask" "F.Paste")
			(net "P1V8_VDDA_PEX0")
		)
		(pad "T36" smd circle
			(at 10.450068 -8.549894)
			(size 0.4572 0.4572)
			(layers "F.Cu" "F.Mask" "F.Paste")
			(net "Net_479")
		)
		(pad "T37" smd circle
			(at 11.400028 -8.549894)
			(size 0.4572 0.4572)
			(layers "F.Cu" "F.Mask" "F.Paste")
			(net "GND")
		)
		(pad "T38" smd circle
			(at 12.349988 -8.549894)
			(size 0.4572 0.4572)
			(layers "F.Cu" "F.Mask" "F.Paste")
			(net "RST_PEX0_S0_PERST_R_N")
		)
		(pad "T39" smd circle
			(at 13.299948 -8.549894)
			(size 0.4572 0.4572)
			(layers "F.Cu" "F.Mask" "F.Paste")
			(net "Net_390")
		)
		(pad "T40" smd circle
			(at 14.249908 -8.549894)
			(size 0.4572 0.4572)
			(layers "F.Cu" "F.Mask" "F.Paste")
			(net "GND")
		)
		(pad "T41" smd circle
			(at 15.200122 -8.549894)
			(size 0.4572 0.4572)
			(layers "F.Cu" "F.Mask" "F.Paste")
			(net "P5E_PEX0_STN4_TX_DP<64>")
		)
		(pad "T42" smd circle
			(at 16.150082 -8.549894)
			(size 0.4572 0.4572)
			(layers "F.Cu" "F.Mask" "F.Paste")
			(net "P5E_PEX0_STN4_TX_DN<64>")
		)
		(pad "T43" smd circle
			(at 17.100042 -8.549894)
			(size 0.4572 0.4572)
			(layers "F.Cu" "F.Mask" "F.Paste")
			(net "GND")
		)
		(pad "T44" smd circle
			(at 18.050002 -8.549894)
			(size 0.4572 0.4572)
			(layers "F.Cu" "F.Mask" "F.Paste")
			(net "GND")
		)
		(pad "T45" smd circle
			(at 18.999962 -8.549894)
			(size 0.4572 0.4572)
			(layers "F.Cu" "F.Mask" "F.Paste")
			(net "GND")
		)
		(pad "T46" smd circle
			(at 19.949922 -8.549894)
			(size 0.4572 0.4572)
			(layers "F.Cu" "F.Mask" "F.Paste")
			(net "GND")
		)
		(pad "T47" smd circle
			(at 20.899882 -8.549894)
			(size 0.4572 0.4572)
			(layers "F.Cu" "F.Mask" "F.Paste")
			(net "GND")
		)
		(pad "T48" smd circle
			(at 21.850096 -8.549894)
			(size 0.4572 0.4572)
			(layers "F.Cu" "F.Mask" "F.Paste")
			(net "P5E_PEX0_STN4_RX_DP<64>")
		)
		(pad "T49" smd circle
			(at 22.800056 -8.549894)
			(size 0.4572 0.4572)
			(layers "F.Cu" "F.Mask" "F.Paste")
			(net "P5E_PEX0_STN4_RX_DN<64>")
		)
		(pad "U1" smd circle
			(at -22.800056 -7.599934)
			(size 0.4572 0.4572)
			(layers "F.Cu" "F.Mask" "F.Paste")
			(net "GND")
		)
		(pad "U2" smd circle
			(at -21.850096 -7.599934)
			(size 0.4572 0.4572)
			(layers "F.Cu" "F.Mask" "F.Paste")
			(net "GND")
		)
		(pad "U3" smd circle
			(at -20.899882 -7.599934)
			(size 0.4572 0.4572)
			(layers "F.Cu" "F.Mask" "F.Paste")
			(net "P5E_PEX0_STN7_RX_DN<114>")
		)
		(pad "U4" smd circle
			(at -19.949922 -7.599934)
			(size 0.4572 0.4572)
			(layers "F.Cu" "F.Mask" "F.Paste")
			(net "P5E_PEX0_STN7_RX_DP<114>")
		)
		(pad "U5" smd circle
			(at -18.999962 -7.599934)
			(size 0.4572 0.4572)
			(layers "F.Cu" "F.Mask" "F.Paste")
			(net "GND")
		)
		(pad "U6" smd circle
			(at -18.050002 -7.599934)
			(size 0.4572 0.4572)
			(layers "F.Cu" "F.Mask" "F.Paste")
			(net "P5E_PEX0_STN7_TX_DN<114>")
		)
		(pad "U7" smd circle
			(at -17.100042 -7.599934)
			(size 0.4572 0.4572)
			(layers "F.Cu" "F.Mask" "F.Paste")
			(net "P5E_PEX0_STN7_TX_DP<114>")
		)
		(pad "U8" smd circle
			(at -16.150082 -7.599934)
			(size 0.4572 0.4572)
			(layers "F.Cu" "F.Mask" "F.Paste")
			(net "GND")
		)
		(pad "U9" smd circle
			(at -15.200122 -7.599934)
			(size 0.4572 0.4572)
			(layers "F.Cu" "F.Mask" "F.Paste")
			(net "GND")
		)
		(pad "U10" smd circle
			(at -14.249908 -7.599934)
			(size 0.4572 0.4572)
			(layers "F.Cu" "F.Mask" "F.Paste")
			(net "GND")
		)
		(pad "U11" smd circle
			(at -13.299948 -7.599934)
			(size 0.4572 0.4572)
			(layers "F.Cu" "F.Mask" "F.Paste")
			(net "GND")
		)
		(pad "U12" smd circle
			(at -12.349988 -7.599934)
			(size 0.4572 0.4572)
			(layers "F.Cu" "F.Mask" "F.Paste")
			(net "GND")
		)
		(pad "U13" smd circle
			(at -11.400028 -7.599934)
			(size 0.4572 0.4572)
			(layers "F.Cu" "F.Mask" "F.Paste")
			(net "GND")
		)
		(pad "U14" smd circle
			(at -10.450068 -7.599934)
			(size 0.4572 0.4572)
			(layers "F.Cu" "F.Mask" "F.Paste")
			(net "Net_487")
		)
		(pad "U15" smd circle
			(at -9.500108 -7.599934)
			(size 0.4572 0.4572)
			(layers "F.Cu" "F.Mask" "F.Paste")
			(net "GND")
		)
		(pad "U16" smd circle
			(at -8.549894 -7.599934)
			(size 0.4572 0.4572)
			(layers "F.Cu" "F.Mask" "F.Paste")
			(net "GND")
		)
		(pad "U17" smd circle
			(at -7.599934 -7.599934)
			(size 0.4572 0.4572)
			(layers "F.Cu" "F.Mask" "F.Paste")
			(net "GND")
		)
		(pad "U18" smd circle
			(at -6.649974 -7.599934)
			(size 0.4572 0.4572)
			(layers "F.Cu" "F.Mask" "F.Paste")
			(net "GND")
		)
		(pad "U19" smd circle
			(at -5.700014 -7.599934)
			(size 0.4572 0.4572)
			(layers "F.Cu" "F.Mask" "F.Paste")
			(net "GND")
		)
		(pad "U20" smd circle
			(at -4.750054 -7.599934)
			(size 0.4572 0.4572)
			(layers "F.Cu" "F.Mask" "F.Paste")
			(net "GND")
		)
		(pad "U21" smd circle
			(at -3.800094 -7.599934)
			(size 0.4572 0.4572)
			(layers "F.Cu" "F.Mask" "F.Paste")
			(net "GND")
		)
		(pad "U22" smd circle
			(at -2.84988 -7.599934)
			(size 0.4572 0.4572)
			(layers "F.Cu" "F.Mask" "F.Paste")
			(net "GND")
		)
		(pad "U23" smd circle
			(at -1.89992 -7.599934)
			(size 0.4572 0.4572)
			(layers "F.Cu" "F.Mask" "F.Paste")
			(net "GND")
		)
		(pad "U24" smd circle
			(at -0.94996 -7.599934)
			(size 0.4572 0.4572)
			(layers "F.Cu" "F.Mask" "F.Paste")
			(net "GND")
		)
		(pad "U25" smd circle
			(at 0 -7.599934)
			(size 0.4572 0.4572)
			(layers "F.Cu" "F.Mask" "F.Paste")
			(net "GND")
		)
		(pad "U26" smd circle
			(at 0.94996 -7.599934)
			(size 0.4572 0.4572)
			(layers "F.Cu" "F.Mask" "F.Paste")
			(net "GND")
		)
		(pad "U27" smd circle
			(at 1.89992 -7.599934)
			(size 0.4572 0.4572)
			(layers "F.Cu" "F.Mask" "F.Paste")
			(net "GND")
		)
		(pad "U28" smd circle
			(at 2.84988 -7.599934)
			(size 0.4572 0.4572)
			(layers "F.Cu" "F.Mask" "F.Paste")
			(net "GND")
		)
		(pad "U29" smd circle
			(at 3.800094 -7.599934)
			(size 0.4572 0.4572)
			(layers "F.Cu" "F.Mask" "F.Paste")
			(net "GND")
		)
		(pad "U30" smd circle
			(at 4.750054 -7.599934)
			(size 0.4572 0.4572)
			(layers "F.Cu" "F.Mask" "F.Paste")
			(net "GND")
		)
		(pad "U31" smd circle
			(at 5.700014 -7.599934)
			(size 0.4572 0.4572)
			(layers "F.Cu" "F.Mask" "F.Paste")
			(net "GND")
		)
		(pad "U32" smd circle
			(at 6.649974 -7.599934)
			(size 0.4572 0.4572)
			(layers "F.Cu" "F.Mask" "F.Paste")
			(net "GND")
		)
		(pad "U33" smd circle
			(at 7.599934 -7.599934)
			(size 0.4572 0.4572)
			(layers "F.Cu" "F.Mask" "F.Paste")
			(net "GND")
		)
		(pad "U34" smd circle
			(at 8.549894 -7.599934)
			(size 0.4572 0.4572)
			(layers "F.Cu" "F.Mask" "F.Paste")
			(net "GND")
		)
		(pad "U35" smd circle
			(at 9.500108 -7.599934)
			(size 0.4572 0.4572)
			(layers "F.Cu" "F.Mask" "F.Paste")
			(net "GND")
		)
		(pad "U36" smd circle
			(at 10.450068 -7.599934)
			(size 0.4572 0.4572)
			(layers "F.Cu" "F.Mask" "F.Paste")
			(net "Net_482")
		)
		(pad "U37" smd circle
			(at 11.400028 -7.599934)
			(size 0.4572 0.4572)
			(layers "F.Cu" "F.Mask" "F.Paste")
			(net "GND")
		)
		(pad "U38" smd circle
			(at 12.349988 -7.599934)
			(size 0.4572 0.4572)
			(layers "F.Cu" "F.Mask" "F.Paste")
			(net "Net_2839")
		)
		(pad "U39" smd circle
			(at 13.299948 -7.599934)
			(size 0.4572 0.4572)
			(layers "F.Cu" "F.Mask" "F.Paste")
			(net "Net_2833")
		)
		(pad "U40" smd circle
			(at 14.249908 -7.599934)
			(size 0.4572 0.4572)
			(layers "F.Cu" "F.Mask" "F.Paste")
			(net "GND")
		)
		(pad "U41" smd circle
			(at 15.200122 -7.599934)
			(size 0.4572 0.4572)
			(layers "F.Cu" "F.Mask" "F.Paste")
			(net "GND")
		)
		(pad "U42" smd circle
			(at 16.150082 -7.599934)
			(size 0.4572 0.4572)
			(layers "F.Cu" "F.Mask" "F.Paste")
			(net "GND")
		)
		(pad "U43" smd circle
			(at 17.100042 -7.599934)
			(size 0.4572 0.4572)
			(layers "F.Cu" "F.Mask" "F.Paste")
			(net "Net_2814")
		)
		(pad "U44" smd circle
			(at 18.050002 -7.599934)
			(size 0.4572 0.4572)
			(layers "F.Cu" "F.Mask" "F.Paste")
			(net "Net_2798")
		)
		(pad "U45" smd circle
			(at 18.999962 -7.599934)
			(size 0.4572 0.4572)
			(layers "F.Cu" "F.Mask" "F.Paste")
			(net "GND")
		)
		(pad "U46" smd circle
			(at 19.949922 -7.599934)
			(size 0.4572 0.4572)
			(layers "F.Cu" "F.Mask" "F.Paste")
			(net "Net_2782")
		)
		(pad "U47" smd circle
			(at 20.899882 -7.599934)
			(size 0.4572 0.4572)
			(layers "F.Cu" "F.Mask" "F.Paste")
			(net "Net_2766")
		)
		(pad "U48" smd circle
			(at 21.850096 -7.599934)
			(size 0.4572 0.4572)
			(layers "F.Cu" "F.Mask" "F.Paste")
			(net "GND")
		)
		(pad "U49" smd circle
			(at 22.800056 -7.599934)
			(size 0.4572 0.4572)
			(layers "F.Cu" "F.Mask" "F.Paste")
			(net "GND")
		)
		(pad "V1" smd circle
			(at -22.800056 -6.649974)
			(size 0.4572 0.4572)
			(layers "F.Cu" "F.Mask" "F.Paste")
			(net "P5E_PEX0_STN7_RX_DN<113>")
		)
		(pad "V2" smd circle
			(at -21.850096 -6.649974)
			(size 0.4572 0.4572)
			(layers "F.Cu" "F.Mask" "F.Paste")
			(net "P5E_PEX0_STN7_RX_DP<113>")
		)
		(pad "V3" smd circle
			(at -20.899882 -6.649974)
			(size 0.4572 0.4572)
			(layers "F.Cu" "F.Mask" "F.Paste")
			(net "GND")
		)
		(pad "V4" smd circle
			(at -19.949922 -6.649974)
			(size 0.4572 0.4572)
			(layers "F.Cu" "F.Mask" "F.Paste")
			(net "GND")
		)
		(pad "V5" smd circle
			(at -18.999962 -6.649974)
			(size 0.4572 0.4572)
			(layers "F.Cu" "F.Mask" "F.Paste")
			(net "GND")
		)
		(pad "V6" smd circle
			(at -18.050002 -6.649974)
			(size 0.4572 0.4572)
			(layers "F.Cu" "F.Mask" "F.Paste")
			(net "GND")
		)
		(pad "V7" smd circle
			(at -17.100042 -6.649974)
			(size 0.4572 0.4572)
			(layers "F.Cu" "F.Mask" "F.Paste")
			(net "GND")
		)
		(pad "V8" smd circle
			(at -16.150082 -6.649974)
			(size 0.4572 0.4572)
			(layers "F.Cu" "F.Mask" "F.Paste")
			(net "P5E_PEX0_STN7_TX_DN<113>")
		)
		(pad "V9" smd circle
			(at -15.200122 -6.649974)
			(size 0.4572 0.4572)
			(layers "F.Cu" "F.Mask" "F.Paste")
			(net "P5E_PEX0_STN7_TX_DP<113>")
		)
		(pad "V10" smd circle
			(at -14.249908 -6.649974)
			(size 0.4572 0.4572)
			(layers "F.Cu" "F.Mask" "F.Paste")
			(net "GND")
		)
		(pad "V11" smd circle
			(at -13.299948 -6.649974)
			(size 0.4572 0.4572)
			(layers "F.Cu" "F.Mask" "F.Paste")
			(net "GND")
		)
		(pad "V12" smd circle
			(at -12.349988 -6.649974)
			(size 0.4572 0.4572)
			(layers "F.Cu" "F.Mask" "F.Paste")
			(net "GND")
		)
		(pad "V13" smd circle
			(at -11.400028 -6.649974)
			(size 0.4572 0.4572)
			(layers "F.Cu" "F.Mask" "F.Paste")
			(net "GND")
		)
		(pad "V14" smd circle
			(at -10.450068 -6.649974)
			(size 0.4572 0.4572)
			(layers "F.Cu" "F.Mask" "F.Paste")
			(net "P1V8_VDDA_PEX0")
		)
		(pad "V15" smd circle
			(at -9.500108 -6.649974)
			(size 0.4572 0.4572)
			(layers "F.Cu" "F.Mask" "F.Paste")
			(net "GND")
		)
		(pad "V16" smd circle
			(at -8.549894 -6.649974)
			(size 0.4572 0.4572)
			(layers "F.Cu" "F.Mask" "F.Paste")
			(net "P1V25_PEX0")
		)
		(pad "V17" smd circle
			(at -7.599934 -6.649974)
			(size 0.4572 0.4572)
			(layers "F.Cu" "F.Mask" "F.Paste")
			(net "P1V25_PEX0")
		)
		(pad "V18" smd circle
			(at -6.649974 -6.649974)
			(size 0.4572 0.4572)
			(layers "F.Cu" "F.Mask" "F.Paste")
			(net "P1V25_PEX0")
		)
		(pad "V19" smd circle
			(at -5.700014 -6.649974)
			(size 0.4572 0.4572)
			(layers "F.Cu" "F.Mask" "F.Paste")
			(net "P1V25_PEX0")
		)
		(pad "V20" smd circle
			(at -4.750054 -6.649974)
			(size 0.4572 0.4572)
			(layers "F.Cu" "F.Mask" "F.Paste")
			(net "P1V25_PEX0")
		)
		(pad "V21" smd circle
			(at -3.800094 -6.649974)
			(size 0.4572 0.4572)
			(layers "F.Cu" "F.Mask" "F.Paste")
			(net "P1V25_PEX0")
		)
		(pad "V22" smd circle
			(at -2.84988 -6.649974)
			(size 0.4572 0.4572)
			(layers "F.Cu" "F.Mask" "F.Paste")
			(net "P1V25_PEX0")
		)
		(pad "V23" smd circle
			(at -1.89992 -6.649974)
			(size 0.4572 0.4572)
			(layers "F.Cu" "F.Mask" "F.Paste")
			(net "P1V25_PEX0")
		)
		(pad "V24" smd circle
			(at -0.94996 -6.649974)
			(size 0.4572 0.4572)
			(layers "F.Cu" "F.Mask" "F.Paste")
			(net "P1V25_PEX0")
		)
		(pad "V25" smd circle
			(at 0 -6.649974)
			(size 0.4572 0.4572)
			(layers "F.Cu" "F.Mask" "F.Paste")
			(net "P1V25_PEX0")
		)
		(pad "V26" smd circle
			(at 0.94996 -6.649974)
			(size 0.4572 0.4572)
			(layers "F.Cu" "F.Mask" "F.Paste")
			(net "P1V25_PEX0")
		)
		(pad "V27" smd circle
			(at 1.89992 -6.649974)
			(size 0.4572 0.4572)
			(layers "F.Cu" "F.Mask" "F.Paste")
			(net "P1V25_PEX0")
		)
		(pad "V28" smd circle
			(at 2.84988 -6.649974)
			(size 0.4572 0.4572)
			(layers "F.Cu" "F.Mask" "F.Paste")
			(net "P1V25_PEX0")
		)
		(pad "V29" smd circle
			(at 3.800094 -6.649974)
			(size 0.4572 0.4572)
			(layers "F.Cu" "F.Mask" "F.Paste")
			(net "P1V25_PEX0")
		)
		(pad "V30" smd circle
			(at 4.750054 -6.649974)
			(size 0.4572 0.4572)
			(layers "F.Cu" "F.Mask" "F.Paste")
			(net "P1V25_PEX0")
		)
		(pad "V31" smd circle
			(at 5.700014 -6.649974)
			(size 0.4572 0.4572)
			(layers "F.Cu" "F.Mask" "F.Paste")
			(net "P1V25_PEX0")
		)
		(pad "V32" smd circle
			(at 6.649974 -6.649974)
			(size 0.4572 0.4572)
			(layers "F.Cu" "F.Mask" "F.Paste")
			(net "P1V25_PEX0")
		)
		(pad "V33" smd circle
			(at 7.599934 -6.649974)
			(size 0.4572 0.4572)
			(layers "F.Cu" "F.Mask" "F.Paste")
			(net "P1V25_PEX0")
		)
		(pad "V34" smd circle
			(at 8.549894 -6.649974)
			(size 0.4572 0.4572)
			(layers "F.Cu" "F.Mask" "F.Paste")
			(net "GND")
		)
		(pad "V35" smd circle
			(at 9.500108 -6.649974)
			(size 0.4572 0.4572)
			(layers "F.Cu" "F.Mask" "F.Paste")
			(net "P1V8_PEX")
		)
		(pad "V36" smd circle
			(at 10.450068 -6.649974)
			(size 0.4572 0.4572)
			(layers "F.Cu" "F.Mask" "F.Paste")
			(net "GND")
		)
		(pad "V37" smd circle
			(at 11.400028 -6.649974)
			(size 0.4572 0.4572)
			(layers "F.Cu" "F.Mask" "F.Paste")
			(net "GND")
		)
		(pad "V38" smd circle
			(at 12.349988 -6.649974)
			(size 0.4572 0.4572)
			(layers "F.Cu" "F.Mask" "F.Paste")
			(net "GND")
		)
		(pad "V39" smd circle
			(at 13.299948 -6.649974)
			(size 0.4572 0.4572)
			(layers "F.Cu" "F.Mask" "F.Paste")
			(net "VSENSE_P0V8_PEX0_SKT_VSEN")
		)
		(pad "V40" smd circle
			(at 14.249908 -6.649974)
			(size 0.4572 0.4572)
			(layers "F.Cu" "F.Mask" "F.Paste")
			(net "GND")
		)
		(pad "V41" smd circle
			(at 15.200122 -6.649974)
			(size 0.4572 0.4572)
			(layers "F.Cu" "F.Mask" "F.Paste")
			(net "Net_2815")
		)
		(pad "V42" smd circle
			(at 16.150082 -6.649974)
			(size 0.4572 0.4572)
			(layers "F.Cu" "F.Mask" "F.Paste")
			(net "Net_2799")
		)
		(pad "V43" smd circle
			(at 17.100042 -6.649974)
			(size 0.4572 0.4572)
			(layers "F.Cu" "F.Mask" "F.Paste")
			(net "GND")
		)
		(pad "V44" smd circle
			(at 18.050002 -6.649974)
			(size 0.4572 0.4572)
			(layers "F.Cu" "F.Mask" "F.Paste")
			(net "GND")
		)
		(pad "V45" smd circle
			(at 18.999962 -6.649974)
			(size 0.4572 0.4572)
			(layers "F.Cu" "F.Mask" "F.Paste")
			(net "GND")
		)
		(pad "V46" smd circle
			(at 19.949922 -6.649974)
			(size 0.4572 0.4572)
			(layers "F.Cu" "F.Mask" "F.Paste")
			(net "GND")
		)
		(pad "V47" smd circle
			(at 20.899882 -6.649974)
			(size 0.4572 0.4572)
			(layers "F.Cu" "F.Mask" "F.Paste")
			(net "GND")
		)
		(pad "V48" smd circle
			(at 21.850096 -6.649974)
			(size 0.4572 0.4572)
			(layers "F.Cu" "F.Mask" "F.Paste")
			(net "Net_2783")
		)
		(pad "V49" smd circle
			(at 22.800056 -6.649974)
			(size 0.4572 0.4572)
			(layers "F.Cu" "F.Mask" "F.Paste")
			(net "Net_2767")
		)
		(pad "W1" smd circle
			(at -22.800056 -5.700014)
			(size 0.4572 0.4572)
			(layers "F.Cu" "F.Mask" "F.Paste")
			(net "GND")
		)
		(pad "W2" smd circle
			(at -21.850096 -5.700014)
			(size 0.4572 0.4572)
			(layers "F.Cu" "F.Mask" "F.Paste")
			(net "GND")
		)
		(pad "W3" smd circle
			(at -20.899882 -5.700014)
			(size 0.4572 0.4572)
			(layers "F.Cu" "F.Mask" "F.Paste")
			(net "P5E_PEX0_STN7_RX_DN<112>")
		)
		(pad "W4" smd circle
			(at -19.949922 -5.700014)
			(size 0.4572 0.4572)
			(layers "F.Cu" "F.Mask" "F.Paste")
			(net "P5E_PEX0_STN7_RX_DP<112>")
		)
		(pad "W5" smd circle
			(at -18.999962 -5.700014)
			(size 0.4572 0.4572)
			(layers "F.Cu" "F.Mask" "F.Paste")
			(net "GND")
		)
		(pad "W6" smd circle
			(at -18.050002 -5.700014)
			(size 0.4572 0.4572)
			(layers "F.Cu" "F.Mask" "F.Paste")
			(net "P5E_PEX0_STN7_TX_DN<112>")
		)
		(pad "W7" smd circle
			(at -17.100042 -5.700014)
			(size 0.4572 0.4572)
			(layers "F.Cu" "F.Mask" "F.Paste")
			(net "P5E_PEX0_STN7_TX_DP<112>")
		)
		(pad "W8" smd circle
			(at -16.150082 -5.700014)
			(size 0.4572 0.4572)
			(layers "F.Cu" "F.Mask" "F.Paste")
			(net "GND")
		)
		(pad "W9" smd circle
			(at -15.200122 -5.700014)
			(size 0.4572 0.4572)
			(layers "F.Cu" "F.Mask" "F.Paste")
			(net "GND")
		)
		(pad "W10" smd circle
			(at -14.249908 -5.700014)
			(size 0.4572 0.4572)
			(layers "F.Cu" "F.Mask" "F.Paste")
			(net "GND")
		)
		(pad "W11" smd circle
			(at -13.299948 -5.700014)
			(size 0.4572 0.4572)
			(layers "F.Cu" "F.Mask" "F.Paste")
			(net "GND")
		)
		(pad "W12" smd circle
			(at -12.349988 -5.700014)
			(size 0.4572 0.4572)
			(layers "F.Cu" "F.Mask" "F.Paste")
			(net "GND")
		)
		(pad "W13" smd circle
			(at -11.400028 -5.700014)
			(size 0.4572 0.4572)
			(layers "F.Cu" "F.Mask" "F.Paste")
			(net "GND")
		)
		(pad "W14" smd circle
			(at -10.450068 -5.700014)
			(size 0.4572 0.4572)
			(layers "F.Cu" "F.Mask" "F.Paste")
			(net "GND")
		)
		(pad "W15" smd circle
			(at -9.500108 -5.700014)
			(size 0.4572 0.4572)
			(layers "F.Cu" "F.Mask" "F.Paste")
			(net "GND")
		)
		(pad "W16" smd circle
			(at -8.549894 -5.700014)
			(size 0.4572 0.4572)
			(layers "F.Cu" "F.Mask" "F.Paste")
			(net "GND")
		)
		(pad "W17" smd circle
			(at -7.599934 -5.700014)
			(size 0.4572 0.4572)
			(layers "F.Cu" "F.Mask" "F.Paste")
			(net "GND")
		)
		(pad "W18" smd circle
			(at -6.649974 -5.700014)
			(size 0.4572 0.4572)
			(layers "F.Cu" "F.Mask" "F.Paste")
			(net "GND")
		)
		(pad "W19" smd circle
			(at -5.700014 -5.700014)
			(size 0.4572 0.4572)
			(layers "F.Cu" "F.Mask" "F.Paste")
			(net "GND")
		)
		(pad "W20" smd circle
			(at -4.750054 -5.700014)
			(size 0.4572 0.4572)
			(layers "F.Cu" "F.Mask" "F.Paste")
			(net "GND")
		)
		(pad "W21" smd circle
			(at -3.800094 -5.700014)
			(size 0.4572 0.4572)
			(layers "F.Cu" "F.Mask" "F.Paste")
			(net "GND")
		)
		(pad "W22" smd circle
			(at -2.84988 -5.700014)
			(size 0.4572 0.4572)
			(layers "F.Cu" "F.Mask" "F.Paste")
			(net "GND")
		)
		(pad "W23" smd circle
			(at -1.89992 -5.700014)
			(size 0.4572 0.4572)
			(layers "F.Cu" "F.Mask" "F.Paste")
			(net "GND")
		)
		(pad "W24" smd circle
			(at -0.94996 -5.700014)
			(size 0.4572 0.4572)
			(layers "F.Cu" "F.Mask" "F.Paste")
			(net "GND")
		)
		(pad "W25" smd circle
			(at 0 -5.700014)
			(size 0.4572 0.4572)
			(layers "F.Cu" "F.Mask" "F.Paste")
			(net "GND")
		)
		(pad "W26" smd circle
			(at 0.94996 -5.700014)
			(size 0.4572 0.4572)
			(layers "F.Cu" "F.Mask" "F.Paste")
			(net "GND")
		)
		(pad "W27" smd circle
			(at 1.89992 -5.700014)
			(size 0.4572 0.4572)
			(layers "F.Cu" "F.Mask" "F.Paste")
			(net "GND")
		)
		(pad "W28" smd circle
			(at 2.84988 -5.700014)
			(size 0.4572 0.4572)
			(layers "F.Cu" "F.Mask" "F.Paste")
			(net "GND")
		)
		(pad "W29" smd circle
			(at 3.800094 -5.700014)
			(size 0.4572 0.4572)
			(layers "F.Cu" "F.Mask" "F.Paste")
			(net "GND")
		)
		(pad "W30" smd circle
			(at 4.750054 -5.700014)
			(size 0.4572 0.4572)
			(layers "F.Cu" "F.Mask" "F.Paste")
			(net "GND")
		)
		(pad "W31" smd circle
			(at 5.700014 -5.700014)
			(size 0.4572 0.4572)
			(layers "F.Cu" "F.Mask" "F.Paste")
			(net "GND")
		)
		(pad "W32" smd circle
			(at 6.649974 -5.700014)
			(size 0.4572 0.4572)
			(layers "F.Cu" "F.Mask" "F.Paste")
			(net "GND")
		)
		(pad "W33" smd circle
			(at 7.599934 -5.700014)
			(size 0.4572 0.4572)
			(layers "F.Cu" "F.Mask" "F.Paste")
			(net "GND")
		)
		(pad "W34" smd circle
			(at 8.549894 -5.700014)
			(size 0.4572 0.4572)
			(layers "F.Cu" "F.Mask" "F.Paste")
			(net "GND")
		)
		(pad "W35" smd circle
			(at 9.500108 -5.700014)
			(size 0.4572 0.4572)
			(layers "F.Cu" "F.Mask" "F.Paste")
			(net "P1V8_PEX")
		)
		(pad "W36" smd circle
			(at 10.450068 -5.700014)
			(size 0.4572 0.4572)
			(layers "F.Cu" "F.Mask" "F.Paste")
			(net "GND")
		)
		(pad "W37" smd circle
			(at 11.400028 -5.700014)
			(size 0.4572 0.4572)
			(layers "F.Cu" "F.Mask" "F.Paste")
			(net "GND")
		)
		(pad "W38" smd circle
			(at 12.349988 -5.700014)
			(size 0.4572 0.4572)
			(layers "F.Cu" "F.Mask" "F.Paste")
			(net "GND")
		)
		(pad "W39" smd circle
			(at 13.299948 -5.700014)
			(size 0.4572 0.4572)
			(layers "F.Cu" "F.Mask" "F.Paste")
			(net "VSENSE_P0V8_PEX0_SKT_VRTN")
		)
		(pad "W40" smd circle
			(at 14.249908 -5.700014)
			(size 0.4572 0.4572)
			(layers "F.Cu" "F.Mask" "F.Paste")
			(net "GND")
		)
		(pad "W41" smd circle
			(at 15.200122 -5.700014)
			(size 0.4572 0.4572)
			(layers "F.Cu" "F.Mask" "F.Paste")
			(net "GND")
		)
		(pad "W42" smd circle
			(at 16.150082 -5.700014)
			(size 0.4572 0.4572)
			(layers "F.Cu" "F.Mask" "F.Paste")
			(net "GND")
		)
		(pad "W43" smd circle
			(at 17.100042 -5.700014)
			(size 0.4572 0.4572)
			(layers "F.Cu" "F.Mask" "F.Paste")
			(net "Net_2816")
		)
		(pad "W44" smd circle
			(at 18.050002 -5.700014)
			(size 0.4572 0.4572)
			(layers "F.Cu" "F.Mask" "F.Paste")
			(net "Net_2800")
		)
		(pad "W45" smd circle
			(at 18.999962 -5.700014)
			(size 0.4572 0.4572)
			(layers "F.Cu" "F.Mask" "F.Paste")
			(net "GND")
		)
		(pad "W46" smd circle
			(at 19.949922 -5.700014)
			(size 0.4572 0.4572)
			(layers "F.Cu" "F.Mask" "F.Paste")
			(net "Net_2784")
		)
		(pad "W47" smd circle
			(at 20.899882 -5.700014)
			(size 0.4572 0.4572)
			(layers "F.Cu" "F.Mask" "F.Paste")
			(net "Net_2768")
		)
		(pad "W48" smd circle
			(at 21.850096 -5.700014)
			(size 0.4572 0.4572)
			(layers "F.Cu" "F.Mask" "F.Paste")
			(net "GND")
		)
		(pad "W49" smd circle
			(at 22.800056 -5.700014)
			(size 0.4572 0.4572)
			(layers "F.Cu" "F.Mask" "F.Paste")
			(net "GND")
		)
		(pad "Y1" smd circle
			(at -22.800056 -4.750054)
			(size 0.4572 0.4572)
			(layers "F.Cu" "F.Mask" "F.Paste")
			(net "GND")
		)
		(pad "Y2" smd circle
			(at -21.850096 -4.750054)
			(size 0.4572 0.4572)
			(layers "F.Cu" "F.Mask" "F.Paste")
			(net "GND")
		)
		(pad "Y3" smd circle
			(at -20.899882 -4.750054)
			(size 0.4572 0.4572)
			(layers "F.Cu" "F.Mask" "F.Paste")
			(net "GND")
		)
		(pad "Y4" smd circle
			(at -19.949922 -4.750054)
			(size 0.4572 0.4572)
			(layers "F.Cu" "F.Mask" "F.Paste")
			(net "GND")
		)
		(pad "Y5" smd circle
			(at -18.999962 -4.750054)
			(size 0.4572 0.4572)
			(layers "F.Cu" "F.Mask" "F.Paste")
			(net "GND")
		)
		(pad "Y6" smd circle
			(at -18.050002 -4.750054)
			(size 0.4572 0.4572)
			(layers "F.Cu" "F.Mask" "F.Paste")
			(net "GND")
		)
		(pad "Y7" smd circle
			(at -17.100042 -4.750054)
			(size 0.4572 0.4572)
			(layers "F.Cu" "F.Mask" "F.Paste")
			(net "GND")
		)
		(pad "Y8" smd circle
			(at -16.150082 -4.750054)
			(size 0.4572 0.4572)
			(layers "F.Cu" "F.Mask" "F.Paste")
			(net "GND")
		)
		(pad "Y9" smd circle
			(at -15.200122 -4.750054)
			(size 0.4572 0.4572)
			(layers "F.Cu" "F.Mask" "F.Paste")
			(net "GND")
		)
		(pad "Y10" smd circle
			(at -14.249908 -4.750054)
			(size 0.4572 0.4572)
			(layers "F.Cu" "F.Mask" "F.Paste")
			(net "GND")
		)
		(pad "Y11" smd circle
			(at -13.299948 -4.750054)
			(size 0.4572 0.4572)
			(layers "F.Cu" "F.Mask" "F.Paste")
			(net "GND")
		)
		(pad "Y12" smd circle
			(at -12.349988 -4.750054)
			(size 0.4572 0.4572)
			(layers "F.Cu" "F.Mask" "F.Paste")
			(net "P1V8_PEX")
		)
		(pad "Y13" smd circle
			(at -11.400028 -4.750054)
			(size 0.4572 0.4572)
			(layers "F.Cu" "F.Mask" "F.Paste")
			(net "GND")
		)
		(pad "Y14" smd circle
			(at -10.450068 -4.750054)
			(size 0.4572 0.4572)
			(layers "F.Cu" "F.Mask" "F.Paste")
			(net "P0V8_PEX0")
		)
		(pad "Y15" smd circle
			(at -9.500108 -4.750054)
			(size 0.4572 0.4572)
			(layers "F.Cu" "F.Mask" "F.Paste")
			(net "GND")
		)
		(pad "Y16" smd circle
			(at -8.549894 -4.750054)
			(size 0.4572 0.4572)
			(layers "F.Cu" "F.Mask" "F.Paste")
			(net "P0V8_SERDES_VDDA_PEX0")
		)
		(pad "Y17" smd circle
			(at -7.599934 -4.750054)
			(size 0.4572 0.4572)
			(layers "F.Cu" "F.Mask" "F.Paste")
			(net "P0V8_SERDES_VDDA_PEX0")
		)
		(pad "Y18" smd circle
			(at -6.649974 -4.750054)
			(size 0.4572 0.4572)
			(layers "F.Cu" "F.Mask" "F.Paste")
			(net "P0V8_SERDES_VDDA_PEX0")
		)
		(pad "Y19" smd circle
			(at -5.700014 -4.750054)
			(size 0.4572 0.4572)
			(layers "F.Cu" "F.Mask" "F.Paste")
			(net "P0V8_SERDES_VDDA_PEX0")
		)
		(pad "Y20" smd circle
			(at -4.750054 -4.750054)
			(size 0.4572 0.4572)
			(layers "F.Cu" "F.Mask" "F.Paste")
			(net "P0V8_SERDES_VDDA_PEX0")
		)
		(pad "Y21" smd circle
			(at -3.800094 -4.750054)
			(size 0.4572 0.4572)
			(layers "F.Cu" "F.Mask" "F.Paste")
			(net "P0V8_SERDES_VDDA_PEX0")
		)
		(pad "Y22" smd circle
			(at -2.84988 -4.750054)
			(size 0.4572 0.4572)
			(layers "F.Cu" "F.Mask" "F.Paste")
			(net "P0V8_SERDES_VDDA_PEX0")
		)
		(pad "Y23" smd circle
			(at -1.89992 -4.750054)
			(size 0.4572 0.4572)
			(layers "F.Cu" "F.Mask" "F.Paste")
			(net "P0V8_SERDES_VDDA_PEX0")
		)
		(pad "Y24" smd circle
			(at -0.94996 -4.750054)
			(size 0.4572 0.4572)
			(layers "F.Cu" "F.Mask" "F.Paste")
			(net "P0V8_SERDES_VDDA_PEX0")
		)
		(pad "Y25" smd circle
			(at 0 -4.750054)
			(size 0.4572 0.4572)
			(layers "F.Cu" "F.Mask" "F.Paste")
			(net "P0V8_SERDES_VDDA_PEX0")
		)
		(pad "Y26" smd circle
			(at 0.94996 -4.750054)
			(size 0.4572 0.4572)
			(layers "F.Cu" "F.Mask" "F.Paste")
			(net "P0V8_SERDES_VDDA_PEX0")
		)
		(pad "Y27" smd circle
			(at 1.89992 -4.750054)
			(size 0.4572 0.4572)
			(layers "F.Cu" "F.Mask" "F.Paste")
			(net "P0V8_SERDES_VDDA_PEX0")
		)
		(pad "Y28" smd circle
			(at 2.84988 -4.750054)
			(size 0.4572 0.4572)
			(layers "F.Cu" "F.Mask" "F.Paste")
			(net "P0V8_SERDES_VDDA_PEX0")
		)
		(pad "Y29" smd circle
			(at 3.800094 -4.750054)
			(size 0.4572 0.4572)
			(layers "F.Cu" "F.Mask" "F.Paste")
			(net "P0V8_SERDES_VDDA_PEX0")
		)
		(pad "Y30" smd circle
			(at 4.750054 -4.750054)
			(size 0.4572 0.4572)
			(layers "F.Cu" "F.Mask" "F.Paste")
			(net "P0V8_SERDES_VDDA_PEX0")
		)
		(pad "Y31" smd circle
			(at 5.700014 -4.750054)
			(size 0.4572 0.4572)
			(layers "F.Cu" "F.Mask" "F.Paste")
			(net "P0V8_SERDES_VDDA_PEX0")
		)
		(pad "Y32" smd circle
			(at 6.649974 -4.750054)
			(size 0.4572 0.4572)
			(layers "F.Cu" "F.Mask" "F.Paste")
			(net "P0V8_SERDES_VDDA_PEX0")
		)
		(pad "Y33" smd circle
			(at 7.599934 -4.750054)
			(size 0.4572 0.4572)
			(layers "F.Cu" "F.Mask" "F.Paste")
			(net "P0V8_SERDES_VDDA_PEX0")
		)
		(pad "Y34" smd circle
			(at 8.549894 -4.750054)
			(size 0.4572 0.4572)
			(layers "F.Cu" "F.Mask" "F.Paste")
			(net "GND")
		)
		(pad "Y35" smd circle
			(at 9.500108 -4.750054)
			(size 0.4572 0.4572)
			(layers "F.Cu" "F.Mask" "F.Paste")
			(net "P1V8_PEX")
		)
		(pad "Y36" smd circle
			(at 10.450068 -4.750054)
			(size 0.4572 0.4572)
			(layers "F.Cu" "F.Mask" "F.Paste")
			(net "GND")
		)
		(pad "Y37" smd circle
			(at 11.400028 -4.750054)
			(size 0.4572 0.4572)
			(layers "F.Cu" "F.Mask" "F.Paste")
			(net "GND")
		)
		(pad "Y38" smd circle
			(at 12.349988 -4.750054)
			(size 0.4572 0.4572)
			(layers "F.Cu" "F.Mask" "F.Paste")
			(net "GND")
		)
		(pad "Y39" smd circle
			(at 13.299948 -4.750054)
			(size 0.4572 0.4572)
			(layers "F.Cu" "F.Mask" "F.Paste")
			(net "PEX0_ADCTEMP_VINP0")
		)
		(pad "Y40" smd circle
			(at 14.249908 -4.750054)
			(size 0.4572 0.4572)
			(layers "F.Cu" "F.Mask" "F.Paste")
			(net "GND")
		)
		(pad "Y41" smd circle
			(at 15.200122 -4.750054)
			(size 0.4572 0.4572)
			(layers "F.Cu" "F.Mask" "F.Paste")
			(net "Net_2817")
		)
		(pad "Y42" smd circle
			(at 16.150082 -4.750054)
			(size 0.4572 0.4572)
			(layers "F.Cu" "F.Mask" "F.Paste")
			(net "Net_2801")
		)
		(pad "Y43" smd circle
			(at 17.100042 -4.750054)
			(size 0.4572 0.4572)
			(layers "F.Cu" "F.Mask" "F.Paste")
			(net "GND")
		)
		(pad "Y44" smd circle
			(at 18.050002 -4.750054)
			(size 0.4572 0.4572)
			(layers "F.Cu" "F.Mask" "F.Paste")
			(net "GND")
		)
		(pad "Y45" smd circle
			(at 18.999962 -4.750054)
			(size 0.4572 0.4572)
			(layers "F.Cu" "F.Mask" "F.Paste")
			(net "GND")
		)
		(pad "Y46" smd circle
			(at 19.949922 -4.750054)
			(size 0.4572 0.4572)
			(layers "F.Cu" "F.Mask" "F.Paste")
			(net "GND")
		)
		(pad "Y47" smd circle
			(at 20.899882 -4.750054)
			(size 0.4572 0.4572)
			(layers "F.Cu" "F.Mask" "F.Paste")
			(net "GND")
		)
		(pad "Y48" smd circle
			(at 21.850096 -4.750054)
			(size 0.4572 0.4572)
			(layers "F.Cu" "F.Mask" "F.Paste")
			(net "Net_2785")
		)
		(pad "Y49" smd circle
			(at 22.800056 -4.750054)
			(size 0.4572 0.4572)
			(layers "F.Cu" "F.Mask" "F.Paste")
			(net "Net_2769")
		)
		(zone
			(layer "F.Cu")
			(hatch none 0.5)
			(connect_pads
				(clearance 0)
			)
			(min_thickness 0.25)
			(keepout
				(tracks allowed)
				(vias not_allowed)
				(pads allowed)
				(copperpour not_allowed)
				(footprints allowed)
			)
			(placement
				(enabled no)
				(sheetname "")
			)
			(fill
				(thermal_gap 0.5)
				(thermal_bridge_width 0.5)
				(island_removal_mode 0)
			)
			(polygon
				(pts
					(xy 59.929268 -319.741296) (xy 60.320428 -319.741296) (xy 60.320428 -295.62044) (xy 83.491324 -295.62044)
					(xy 83.491324 -295.22928) (xy 60.320428 -295.22928) (xy 60.320428 -272.058384) (xy 59.929268 -272.058384)
					(xy 59.929268 -295.22928) (xy 35.808412 -295.22928) (xy 35.808412 -295.62044) (xy 59.929268 -295.62044)
				)
			)
		)
	)
	(footprint ""
		(layer "F.Cu")
		(at 271.480534 -121.005346)
		(property "Reference" "C467"
			(at 0 0 0)
			(layer "F.SilkS")
			(hide yes)
			(effects
				(font
					(size 1.27 1.27)
				)
			)
		)
		(property "Value" ""
			(at 0 0 0)
			(layer "F.Fab")
			(effects
				(font
					(size 1.27 1.27)
				)
			)
		)
		(duplicate_pad_numbers_are_jumpers no)
		(fp_line
			(start -0.299974 -0.150114)
			(end 0.299974 -0.150114)
			(stroke
				(width 0.1)
				(type default)
			)
			(layer "F.Fab")
		)
		(fp_line
			(start -0.299974 0.150114)
			(end -0.299974 -0.150114)
			(stroke
				(width 0.1)
				(type default)
			)
			(layer "F.Fab")
		)
		(fp_line
			(start 0.299974 -0.150114)
			(end 0.299974 0.150114)
			(stroke
				(width 0.1)
				(type default)
			)
			(layer "F.Fab")
		)
		(fp_line
			(start 0.299974 0.150114)
			(end -0.299974 0.150114)
			(stroke
				(width 0.1)
				(type default)
			)
			(layer "F.Fab")
		)
		(pad "1" smd rect
			(at -0.2667 0)
			(size 0.3048 0.381)
			(layers "F.Cu" "F.Mask" "F.Paste")
			(net "P5E_PEX2_STN1_TX_DN<25>")
		)
		(pad "2" smd rect
			(at 0.2667 0)
			(size 0.3048 0.381)
			(layers "F.Cu" "F.Mask" "F.Paste")
			(net "P5E_PEX2_STN1_TX_C_DN<25>")
		)
	)
	(footprint ""
		(layer "F.Cu")
		(at 104.65816 -212.783166 90)
		(property "Reference" "PL25"
			(at -0.286766 -1.32969 90)
			(unlocked yes)
			(layer "F.SilkS")
			(effects
				(font
					(size 0.7874 0.5842)
					(thickness 0.1524)
				)
			)
		)
		(property "Value" ""
			(at 0 0 90)
			(layer "F.Fab")
			(effects
				(font
					(size 1.27 1.27)
				)
			)
		)
		(duplicate_pad_numbers_are_jumpers no)
		(fp_line
			(start -1.27 -0.5842)
			(end 1.27 -0.5842)
			(stroke
				(width 0.1524)
				(type default)
			)
			(layer "F.SilkS")
		)
		(fp_line
			(start -1.27 -0.5588)
			(end -1.27 -0.5842)
			(stroke
				(width 0.1524)
				(type default)
			)
			(layer "F.SilkS")
		)
		(fp_line
			(start 1.27 0.5842)
			(end 1.27 -0.5842)
			(stroke
				(width 0.1524)
				(type default)
			)
			(layer "F.SilkS")
		)
		(fp_line
			(start 1.27 0.5842)
			(end -1.27 0.5842)
			(stroke
				(width 0.1524)
				(type default)
			)
			(layer "F.SilkS")
		)
		(fp_line
			(start -1.27 0.5842)
			(end -1.27 -0.5842)
			(stroke
				(width 0.1524)
				(type default)
			)
			(layer "F.SilkS")
		)
		(fp_line
			(start 0.9144 -0.508)
			(end 0.9144 -0.406654)
			(stroke
				(width 0.1)
				(type default)
			)
			(layer "F.Fab")
		)
		(fp_line
			(start -0.9144 -0.508)
			(end 0.9144 -0.508)
			(stroke
				(width 0.1)
				(type default)
			)
			(layer "F.Fab")
		)
		(fp_line
			(start 1.1938 -0.406654)
			(end 1.1938 0.4064)
			(stroke
				(width 0.1)
				(type default)
			)
			(layer "F.Fab")
		)
		(fp_line
			(start 0.9144 -0.406654)
			(end 1.1938 -0.406654)
			(stroke
				(width 0.1)
				(type default)
			)
			(layer "F.Fab")
		)
		(fp_line
			(start -0.9144 -0.406654)
			(end -0.9144 -0.508)
			(stroke
				(width 0.1)
				(type default)
			)
			(layer "F.Fab")
		)
		(fp_line
			(start -1.194308 -0.406654)
			(end -0.9144 -0.406654)
			(stroke
				(width 0.1)
				(type default)
			)
			(layer "F.Fab")
		)
		(fp_line
			(start 1.1938 0.4064)
			(end 0.9144 0.4064)
			(stroke
				(width 0.1)
				(type default)
			)
			(layer "F.Fab")
		)
		(fp_line
			(start 0.9144 0.4064)
			(end 0.9144 0.508)
			(stroke
				(width 0.1)
				(type default)
			)
			(layer "F.Fab")
		)
		(fp_line
			(start -0.9144 0.406654)
			(end -1.194308 0.406654)
			(stroke
				(width 0.1)
				(type default)
			)
			(layer "F.Fab")
		)
		(fp_line
			(start -1.194308 0.406654)
			(end -1.194308 -0.406654)
			(stroke
				(width 0.1)
				(type default)
			)
			(layer "F.Fab")
		)
		(fp_line
			(start 0.9144 0.508)
			(end -0.9144 0.508)
			(stroke
				(width 0.1)
				(type default)
			)
			(layer "F.Fab")
		)
		(fp_line
			(start -0.9144 0.508)
			(end -0.9144 0.406654)
			(stroke
				(width 0.1)
				(type default)
			)
			(layer "F.Fab")
		)
		(pad "1" smd rect
			(at -0.7366 0)
			(size 0.7112 0.8128)
			(layers "F.Cu" "F.Mask" "F.Paste")
			(net "P12V_AUX")
		)
		(pad "2" smd rect
			(at 0.7366 0)
			(size 0.7112 0.8128)
			(layers "F.Cu" "F.Mask" "F.Paste")
			(net "SW_P12V_P1V8_PEX_FLT")
		)
	)
	(footprint ""
		(layer "F.Cu")
		(at 4.150106 -365.193072 90)
		(property "Reference" "Q250"
			(at -1.651 -2.25933 90)
			(unlocked yes)
			(layer "F.SilkS")
			(effects
				(font
					(size 0.7874 0.5842)
					(thickness 0.1524)
				)
				(justify left)
			)
		)
		(property "Value" ""
			(at 0 0 90)
			(layer "F.Fab")
			(effects
				(font
					(size 1.27 1.27)
				)
			)
		)
		(duplicate_pad_numbers_are_jumpers no)
		(fp_line
			(start 1.603248 -1.500124)
			(end 1.603248 1.500124)
			(stroke
				(width 0.1524)
				(type default)
			)
			(layer "F.SilkS")
		)
		(fp_line
			(start -1.603248 -1.500124)
			(end 1.603248 -1.500124)
			(stroke
				(width 0.1524)
				(type default)
			)
			(layer "F.SilkS")
		)
		(fp_line
			(start 1.603248 1.500124)
			(end -1.603248 1.500124)
			(stroke
				(width 0.1524)
				(type default)
			)
			(layer "F.SilkS")
		)
		(fp_line
			(start -1.603248 1.500124)
			(end -1.603248 -1.500124)
			(stroke
				(width 0.1524)
				(type default)
			)
			(layer "F.SilkS")
		)
		(fp_line
			(start 0.700024 -1.500124)
			(end -0.700024 -1.500124)
			(stroke
				(width 0.1)
				(type default)
			)
			(layer "F.Fab")
		)
		(fp_line
			(start -0.700024 -1.500124)
			(end -0.700024 -1.169924)
			(stroke
				(width 0.1)
				(type default)
			)
			(layer "F.Fab")
		)
		(fp_line
			(start -0.700024 -1.169924)
			(end -1.249934 -1.169924)
			(stroke
				(width 0.1)
				(type default)
			)
			(layer "F.Fab")
		)
		(fp_line
			(start -1.249934 -1.169924)
			(end -1.249934 -0.729996)
			(stroke
				(width 0.1)
				(type default)
			)
			(layer "F.Fab")
		)
		(fp_line
			(start -0.6985 -0.729996)
			(end -0.6985 0.729996)
			(stroke
				(width 0.1)
				(type default)
			)
			(layer "F.Fab")
		)
		(fp_line
			(start -1.249934 -0.729996)
			(end -0.6985 -0.729996)
			(stroke
				(width 0.1)
				(type default)
			)
			(layer "F.Fab")
		)
		(fp_line
			(start 1.249934 -0.219964)
			(end 0.700024 -0.219964)
			(stroke
				(width 0.1)
				(type default)
			)
			(layer "F.Fab")
		)
		(fp_line
			(start 0.700024 -0.219964)
			(end 0.700024 -1.500124)
			(stroke
				(width 0.1)
				(type default)
			)
			(layer "F.Fab")
		)
		(fp_line
			(start 1.249934 0.219964)
			(end 1.249934 -0.219964)
			(stroke
				(width 0.1)
				(type default)
			)
			(layer "F.Fab")
		)
		(fp_line
			(start 0.700024 0.219964)
			(end 1.249934 0.219964)
			(stroke
				(width 0.1)
				(type default)
			)
			(layer "F.Fab")
		)
		(fp_line
			(start -0.6985 0.729996)
			(end -1.249934 0.729996)
			(stroke
				(width 0.1)
				(type default)
			)
			(layer "F.Fab")
		)
		(fp_line
			(start -1.249934 0.729996)
			(end -1.249934 1.169924)
			(stroke
				(width 0.1)
				(type default)
			)
			(layer "F.Fab")
		)
		(fp_line
			(start -0.700024 1.169924)
			(end -0.700024 1.500124)
			(stroke
				(width 0.1)
				(type default)
			)
			(layer "F.Fab")
		)
		(fp_line
			(start -1.249934 1.169924)
			(end -0.700024 1.169924)
			(stroke
				(width 0.1)
				(type default)
			)
			(layer "F.Fab")
		)
		(fp_line
			(start 0.700024 1.500124)
			(end 0.700024 0.219964)
			(stroke
				(width 0.1)
				(type default)
			)
			(layer "F.Fab")
		)
		(fp_line
			(start -0.700024 1.500124)
			(end 0.700024 1.500124)
			(stroke
				(width 0.1)
				(type default)
			)
			(layer "F.Fab")
		)
		(fp_rect
			(start -0.700024 1.500124)
			(end 0.700024 -1.500124)
			(stroke
				(width 0)
				(type default)
			)
			(fill no)
			(layer "F.Fab")
		)
		(pad "D" smd rect
			(at 0.999998 0)
			(size 0.8128 0.9144)
			(layers "F.Cu" "F.Mask" "F.Paste")
			(net "PG12_USB_HUB_N")
		)
		(pad "G" smd rect
			(at -0.999998 -0.94996)
			(size 0.8128 0.9144)
			(layers "F.Cu" "F.Mask" "F.Paste")
			(net "P1V2_USB_8042")
		)
		(pad "S" smd rect
			(at -0.999998 0.94996)
			(size 0.8128 0.9144)
			(layers "F.Cu" "F.Mask" "F.Paste")
			(net "GND")
		)
	)
	(footprint ""
		(layer "F.Cu")
		(at 106.787188 -92.368878 -90)
		(property "Reference" "R1131"
			(at 0 0 270)
			(layer "F.SilkS")
			(hide yes)
			(effects
				(font
					(size 1.27 1.27)
				)
			)
		)
		(property "Value" ""
			(at 0 0 270)
			(layer "F.Fab")
			(effects
				(font
					(size 1.27 1.27)
				)
			)
		)
		(duplicate_pad_numbers_are_jumpers no)
		(fp_line
			(start -0.7874 0.4064)
			(end -0.7874 -0.4064)
			(stroke
				(width 0.1524)
				(type default)
			)
			(layer "F.SilkS")
		)
		(fp_line
			(start 0.7874 0.4064)
			(end -0.7874 0.4064)
			(stroke
				(width 0.1524)
				(type default)
			)
			(layer "F.SilkS")
		)
		(fp_line
			(start -0.7874 -0.4064)
			(end 0.7874 -0.4064)
			(stroke
				(width 0.1524)
				(type default)
			)
			(layer "F.SilkS")
		)
		(fp_line
			(start 0.7874 -0.4064)
			(end 0.7874 0.4064)
			(stroke
				(width 0.1524)
				(type default)
			)
			(layer "F.SilkS")
		)
		(fp_line
			(start -0.67945 0.3048)
			(end -0.67945 -0.305054)
			(stroke
				(width 0.1)
				(type default)
			)
			(layer "F.Fab")
		)
		(fp_line
			(start -0.12065 0.3048)
			(end -0.67945 0.3048)
			(stroke
				(width 0.1)
				(type default)
			)
			(layer "F.Fab")
		)
		(fp_line
			(start 0.120396 0.3048)
			(end 0.120396 0.2794)
			(stroke
				(width 0.1)
				(type default)
			)
			(layer "F.Fab")
		)
		(fp_line
			(start 0.67945 0.3048)
			(end 0.120396 0.3048)
			(stroke
				(width 0.1)
				(type default)
			)
			(layer "F.Fab")
		)
		(fp_line
			(start -0.12065 0.2794)
			(end -0.12065 0.3048)
			(stroke
				(width 0.1)
				(type default)
			)
			(layer "F.Fab")
		)
		(fp_line
			(start 0.120396 0.2794)
			(end -0.12065 0.2794)
			(stroke
				(width 0.1)
				(type default)
			)
			(layer "F.Fab")
		)
		(fp_line
			(start -0.12065 -0.2794)
			(end 0.12065 -0.2794)
			(stroke
				(width 0.1)
				(type default)
			)
			(layer "F.Fab")
		)
		(fp_line
			(start 0.12065 -0.2794)
			(end 0.12065 -0.3048)
			(stroke
				(width 0.1)
				(type default)
			)
			(layer "F.Fab")
		)
		(fp_line
			(start 0.12065 -0.3048)
			(end 0.67945 -0.3048)
			(stroke
				(width 0.1)
				(type default)
			)
			(layer "F.Fab")
		)
		(fp_line
			(start 0.67945 -0.3048)
			(end 0.67945 0.3048)
			(stroke
				(width 0.1)
				(type default)
			)
			(layer "F.Fab")
		)
		(fp_line
			(start -0.67945 -0.305054)
			(end -0.12065 -0.305054)
			(stroke
				(width 0.1)
				(type default)
			)
			(layer "F.Fab")
		)
		(fp_line
			(start -0.12065 -0.305054)
			(end -0.12065 -0.2794)
			(stroke
				(width 0.1)
				(type default)
			)
			(layer "F.Fab")
		)
		(pad "1" smd circle
			(at -0.40005 0 270)
			(size 0 0)
			(layers "F.Cu" "F.Mask" "F.Paste")
			(net "P3V3")
		)
		(pad "2" smd circle
			(at 0.40005 0 270)
			(size 0 0)
			(layers "F.Cu" "F.Mask" "F.Paste")
			(net "PU_9ZXL0851_0_7_100M")
		)
	)
	(footprint ""
		(layer "F.Cu")
		(at 325.342504 -70.844918 -90)
		(property "Reference" "PD50"
			(at 3.992118 2.100834 90)
			(unlocked yes)
			(layer "F.SilkS")
			(effects
				(font
					(size 0.7874 0.5842)
					(thickness 0.1524)
				)
				(justify left)
			)
		)
		(property "Value" ""
			(at 0 0 270)
			(layer "F.Fab")
			(effects
				(font
					(size 1.27 1.27)
				)
			)
		)
		(duplicate_pad_numbers_are_jumpers no)
		(fp_line
			(start -3.400044 1.459992)
			(end -3.400044 -1.459992)
			(stroke
				(width 0.1524)
				(type default)
			)
			(layer "F.SilkS")
		)
		(fp_line
			(start 4.107942 1.459992)
			(end -3.400044 1.459992)
			(stroke
				(width 0.1524)
				(type default)
			)
			(layer "F.SilkS")
		)
		(fp_line
			(start -3.400044 -1.459992)
			(end 4.107942 -1.459992)
			(stroke
				(width 0.1524)
				(type default)
			)
			(layer "F.SilkS")
		)
		(fp_line
			(start 4.107942 -1.459992)
			(end 4.107942 1.459992)
			(stroke
				(width 0.1524)
				(type default)
			)
			(layer "F.SilkS")
		)
		(fp_poly
			(pts
				(xy 4.107942 -1.459992) (xy 4.107942 1.459992) (xy 3.308096 1.459992) (xy 3.308096 -1.459992)
			)
			(stroke
				(width 0)
				(type default)
			)
			(fill yes)
			(layer "F.SilkS")
		)
		(fp_line
			(start -2.29997 1.459992)
			(end -2.29997 -1.459992)
			(stroke
				(width 0.1)
				(type default)
			)
			(layer "F.Fab")
		)
		(fp_line
			(start 2.29997 1.459992)
			(end -2.29997 1.459992)
			(stroke
				(width 0.1)
				(type default)
			)
			(layer "F.Fab")
		)
		(fp_line
			(start -2.29997 -1.459992)
			(end 2.29997 -1.459992)
			(stroke
				(width 0.1)
				(type default)
			)
			(layer "F.Fab")
		)
		(fp_line
			(start 2.29997 -1.459992)
			(end 2.29997 1.459992)
			(stroke
				(width 0.1)
				(type default)
			)
			(layer "F.Fab")
		)
		(fp_text user "-"
			(at 5.4102 0.29845 90)
			(unlocked yes)
			(layer "F.SilkS")
			(effects
				(font
					(size 1.905 1.4224)
					(thickness 0.1524)
				)
				(justify left)
			)
		)
		(fp_text user "+"
			(at -5.257546 -0.23622 270)
			(unlocked yes)
			(layer "F.SilkS")
			(effects
				(font
					(size 1.905 1.4224)
					(thickness 0.1524)
				)
				(justify left)
			)
		)
		(fp_text user "-"
			(at 5.4102 0.29845 90)
			(unlocked yes)
			(layer "F.Fab")
			(effects
				(font
					(size 1.905 1.4224)
					(thickness 0.1524)
				)
				(justify left)
			)
		)
		(fp_text user "+"
			(at -4.7752 -0.12065 270)
			(unlocked yes)
			(layer "F.Fab")
			(effects
				(font
					(size 1.905 1.4224)
					(thickness 0.1524)
				)
				(justify left)
			)
		)
		(pad "A" smd rect
			(at -1.999996 0)
			(size 1.7018 2.5146)
			(layers "F.Cu" "F.Mask" "F.Paste")
			(net "GND")
		)
		(pad "C" smd rect
			(at 1.999996 0)
			(size 1.7018 2.5146)
			(layers "F.Cu" "F.Mask" "F.Paste")
			(net "P12V_SSD11_R")
		)
	)
	(footprint ""
		(layer "F.Cu")
		(at 209.926936 -188.652404 90)
		(property "Reference" "R5304"
			(at 0 0 90)
			(layer "F.SilkS")
			(hide yes)
			(effects
				(font
					(size 1.27 1.27)
				)
			)
		)
		(property "Value" ""
			(at 0 0 90)
			(layer "F.Fab")
			(effects
				(font
					(size 1.27 1.27)
				)
			)
		)
		(duplicate_pad_numbers_are_jumpers no)
		(fp_line
			(start 0.7874 -0.4064)
			(end 0.7874 0.4064)
			(stroke
				(width 0.1524)
				(type default)
			)
			(layer "F.SilkS")
		)
		(fp_line
			(start -0.7874 -0.4064)
			(end 0.7874 -0.4064)
			(stroke
				(width 0.1524)
				(type default)
			)
			(layer "F.SilkS")
		)
		(fp_line
			(start 0.7874 0.4064)
			(end -0.7874 0.4064)
			(stroke
				(width 0.1524)
				(type default)
			)
			(layer "F.SilkS")
		)
		(fp_line
			(start -0.7874 0.4064)
			(end -0.7874 -0.4064)
			(stroke
				(width 0.1524)
				(type default)
			)
			(layer "F.SilkS")
		)
		(fp_line
			(start -0.12065 -0.305054)
			(end -0.12065 -0.2794)
			(stroke
				(width 0.1)
				(type default)
			)
			(layer "F.Fab")
		)
		(fp_line
			(start -0.67945 -0.305054)
			(end -0.12065 -0.305054)
			(stroke
				(width 0.1)
				(type default)
			)
			(layer "F.Fab")
		)
		(fp_line
			(start 0.67945 -0.3048)
			(end 0.67945 0.3048)
			(stroke
				(width 0.1)
				(type default)
			)
			(layer "F.Fab")
		)
		(fp_line
			(start 0.12065 -0.3048)
			(end 0.67945 -0.3048)
			(stroke
				(width 0.1)
				(type default)
			)
			(layer "F.Fab")
		)
		(fp_line
			(start 0.12065 -0.2794)
			(end 0.12065 -0.3048)
			(stroke
				(width 0.1)
				(type default)
			)
			(layer "F.Fab")
		)
		(fp_line
			(start -0.12065 -0.2794)
			(end 0.12065 -0.2794)
			(stroke
				(width 0.1)
				(type default)
			)
			(layer "F.Fab")
		)
		(fp_line
			(start 0.120396 0.2794)
			(end -0.12065 0.2794)
			(stroke
				(width 0.1)
				(type default)
			)
			(layer "F.Fab")
		)
		(fp_line
			(start -0.12065 0.2794)
			(end -0.12065 0.3048)
			(stroke
				(width 0.1)
				(type default)
			)
			(layer "F.Fab")
		)
		(fp_line
			(start 0.67945 0.3048)
			(end 0.120396 0.3048)
			(stroke
				(width 0.1)
				(type default)
			)
			(layer "F.Fab")
		)
		(fp_line
			(start 0.120396 0.3048)
			(end 0.120396 0.2794)
			(stroke
				(width 0.1)
				(type default)
			)
			(layer "F.Fab")
		)
		(fp_line
			(start -0.12065 0.3048)
			(end -0.67945 0.3048)
			(stroke
				(width 0.1)
				(type default)
			)
			(layer "F.Fab")
		)
		(fp_line
			(start -0.67945 0.3048)
			(end -0.67945 -0.305054)
			(stroke
				(width 0.1)
				(type default)
			)
			(layer "F.Fab")
		)
		(pad "1" smd circle
			(at -0.40005 0 90)
			(size 0 0)
			(layers "F.Cu" "F.Mask" "F.Paste")
			(net "BIC_SEL_FLASH_SW3_R")
		)
		(pad "2" smd circle
			(at 0.40005 0 90)
			(size 0 0)
			(layers "F.Cu" "F.Mask" "F.Paste")
			(net "P3V3_AUX")
		)
	)
	(footprint ""
		(layer "F.Cu")
		(at 163.075112 -350.098614 90)
		(property "Reference" "C2513"
			(at 0 0 90)
			(layer "F.SilkS")
			(hide yes)
			(effects
				(font
					(size 1.27 1.27)
				)
			)
		)
		(property "Value" ""
			(at 0 0 90)
			(layer "F.Fab")
			(effects
				(font
					(size 1.27 1.27)
				)
			)
		)
		(duplicate_pad_numbers_are_jumpers no)
		(fp_line
			(start 0.299974 -0.150114)
			(end 0.299974 0.150114)
			(stroke
				(width 0.1)
				(type default)
			)
			(layer "F.Fab")
		)
		(fp_line
			(start -0.299974 -0.150114)
			(end 0.299974 -0.150114)
			(stroke
				(width 0.1)
				(type default)
			)
			(layer "F.Fab")
		)
		(fp_line
			(start 0.299974 0.150114)
			(end -0.299974 0.150114)
			(stroke
				(width 0.1)
				(type default)
			)
			(layer "F.Fab")
		)
		(fp_line
			(start -0.299974 0.150114)
			(end -0.299974 -0.150114)
			(stroke
				(width 0.1)
				(type default)
			)
			(layer "F.Fab")
		)
		(pad "1" smd rect
			(at -0.2667 0 90)
			(size 0.3048 0.381)
			(layers "F.Cu" "F.Mask" "F.Paste")
			(net "P5E_PEX1_STN4_TX_DN<79>")
		)
		(pad "2" smd rect
			(at 0.2667 0 90)
			(size 0.3048 0.381)
			(layers "F.Cu" "F.Mask" "F.Paste")
			(net "P5E_PEX1_STN4_TX_C_DN<79>")
		)
	)
	(footprint ""
		(layer "F.Cu")
		(at 352.67392 -27.006296 -90)
		(property "Reference" "PC960"
			(at 0 0 270)
			(layer "F.SilkS")
			(hide yes)
			(effects
				(font
					(size 1.27 1.27)
				)
			)
		)
		(property "Value" ""
			(at 0 0 270)
			(layer "F.Fab")
			(effects
				(font
					(size 1.27 1.27)
				)
			)
		)
		(duplicate_pad_numbers_are_jumpers no)
		(fp_line
			(start -0.7874 0.4064)
			(end -0.7874 -0.4064)
			(stroke
				(width 0.1524)
				(type default)
			)
			(layer "F.SilkS")
		)
		(fp_line
			(start 0.7874 0.4064)
			(end -0.7874 0.4064)
			(stroke
				(width 0.1524)
				(type default)
			)
			(layer "F.SilkS")
		)
		(fp_line
			(start -0.7874 -0.4064)
			(end 0.7874 -0.4064)
			(stroke
				(width 0.1524)
				(type default)
			)
			(layer "F.SilkS")
		)
		(fp_line
			(start 0.7874 -0.4064)
			(end 0.7874 0.4064)
			(stroke
				(width 0.1524)
				(type default)
			)
			(layer "F.SilkS")
		)
		(fp_line
			(start -0.67945 0.3048)
			(end -0.67945 -0.305054)
			(stroke
				(width 0.1)
				(type default)
			)
			(layer "F.Fab")
		)
		(fp_line
			(start -0.12065 0.3048)
			(end -0.67945 0.3048)
			(stroke
				(width 0.1)
				(type default)
			)
			(layer "F.Fab")
		)
		(fp_line
			(start 0.120396 0.3048)
			(end 0.120396 0.2794)
			(stroke
				(width 0.1)
				(type default)
			)
			(layer "F.Fab")
		)
		(fp_line
			(start 0.67945 0.3048)
			(end 0.120396 0.3048)
			(stroke
				(width 0.1)
				(type default)
			)
			(layer "F.Fab")
		)
		(fp_line
			(start -0.12065 0.2794)
			(end -0.12065 0.3048)
			(stroke
				(width 0.1)
				(type default)
			)
			(layer "F.Fab")
		)
		(fp_line
			(start 0.120396 0.2794)
			(end -0.12065 0.2794)
			(stroke
				(width 0.1)
				(type default)
			)
			(layer "F.Fab")
		)
		(fp_line
			(start -0.12065 -0.2794)
			(end 0.12065 -0.2794)
			(stroke
				(width 0.1)
				(type default)
			)
			(layer "F.Fab")
		)
		(fp_line
			(start 0.12065 -0.2794)
			(end 0.12065 -0.3048)
			(stroke
				(width 0.1)
				(type default)
			)
			(layer "F.Fab")
		)
		(fp_line
			(start 0.12065 -0.3048)
			(end 0.67945 -0.3048)
			(stroke
				(width 0.1)
				(type default)
			)
			(layer "F.Fab")
		)
		(fp_line
			(start 0.67945 -0.3048)
			(end 0.67945 0.3048)
			(stroke
				(width 0.1)
				(type default)
			)
			(layer "F.Fab")
		)
		(fp_line
			(start -0.67945 -0.305054)
			(end -0.12065 -0.305054)
			(stroke
				(width 0.1)
				(type default)
			)
			(layer "F.Fab")
		)
		(fp_line
			(start -0.12065 -0.305054)
			(end -0.12065 -0.2794)
			(stroke
				(width 0.1)
				(type default)
			)
			(layer "F.Fab")
		)
		(pad "1" smd circle
			(at -0.40005 0 270)
			(size 0 0)
			(layers "F.Cu" "F.Mask" "F.Paste")
			(net "P3V3_SSD12_CO_MODE")
		)
		(pad "2" smd circle
			(at 0.40005 0 270)
			(size 0 0)
			(layers "F.Cu" "F.Mask" "F.Paste")
			(net "GND")
		)
	)
	(footprint ""
		(layer "F.Cu")
		(at 405.594058 -35.264852)
		(property "Reference" "R5711"
			(at 0 0 0)
			(layer "F.SilkS")
			(hide yes)
			(effects
				(font
					(size 1.27 1.27)
				)
			)
		)
		(property "Value" ""
			(at 0 0 0)
			(layer "F.Fab")
			(effects
				(font
					(size 1.27 1.27)
				)
			)
		)
		(duplicate_pad_numbers_are_jumpers no)
		(fp_line
			(start -0.7874 -0.4064)
			(end 0.7874 -0.4064)
			(stroke
				(width 0.1524)
				(type default)
			)
			(layer "F.SilkS")
		)
		(fp_line
			(start -0.7874 0.4064)
			(end -0.7874 -0.4064)
			(stroke
				(width 0.1524)
				(type default)
			)
			(layer "F.SilkS")
		)
		(fp_line
			(start 0.7874 -0.4064)
			(end 0.7874 0.4064)
			(stroke
				(width 0.1524)
				(type default)
			)
			(layer "F.SilkS")
		)
		(fp_line
			(start 0.7874 0.4064)
			(end -0.7874 0.4064)
			(stroke
				(width 0.1524)
				(type default)
			)
			(layer "F.SilkS")
		)
		(fp_line
			(start -0.67945 -0.305054)
			(end -0.12065 -0.305054)
			(stroke
				(width 0.1)
				(type default)
			)
			(layer "F.Fab")
		)
		(fp_line
			(start -0.67945 0.3048)
			(end -0.67945 -0.305054)
			(stroke
				(width 0.1)
				(type default)
			)
			(layer "F.Fab")
		)
		(fp_line
			(start -0.12065 -0.305054)
			(end -0.12065 -0.2794)
			(stroke
				(width 0.1)
				(type default)
			)
			(layer "F.Fab")
		)
		(fp_line
			(start -0.12065 -0.2794)
			(end 0.12065 -0.2794)
			(stroke
				(width 0.1)
				(type default)
			)
			(layer "F.Fab")
		)
		(fp_line
			(start -0.12065 0.2794)
			(end -0.12065 0.3048)
			(stroke
				(width 0.1)
				(type default)
			)
			(layer "F.Fab")
		)
		(fp_line
			(start -0.12065 0.3048)
			(end -0.67945 0.3048)
			(stroke
				(width 0.1)
				(type default)
			)
			(layer "F.Fab")
		)
		(fp_line
			(start 0.120396 0.2794)
			(end -0.12065 0.2794)
			(stroke
				(width 0.1)
				(type default)
			)
			(layer "F.Fab")
		)
		(fp_line
			(start 0.120396 0.3048)
			(end 0.120396 0.2794)
			(stroke
				(width 0.1)
				(type default)
			)
			(layer "F.Fab")
		)
		(fp_line
			(start 0.12065 -0.3048)
			(end 0.67945 -0.3048)
			(stroke
				(width 0.1)
				(type default)
			)
			(layer "F.Fab")
		)
		(fp_line
			(start 0.12065 -0.2794)
			(end 0.12065 -0.3048)
			(stroke
				(width 0.1)
				(type default)
			)
			(layer "F.Fab")
		)
		(fp_line
			(start 0.67945 -0.3048)
			(end 0.67945 0.3048)
			(stroke
				(width 0.1)
				(type default)
			)
			(layer "F.Fab")
		)
		(fp_line
			(start 0.67945 0.3048)
			(end 0.120396 0.3048)
			(stroke
				(width 0.1)
				(type default)
			)
			(layer "F.Fab")
		)
		(pad "1" smd circle
			(at -0.40005 0)
			(size 0 0)
			(layers "F.Cu" "F.Mask" "F.Paste")
			(net "RST_SMB_SSD14_ISO_N")
		)
		(pad "2" smd circle
			(at 0.40005 0)
			(size 0 0)
			(layers "F.Cu" "F.Mask" "F.Paste")
			(net "GND")
		)
	)
	(footprint ""
		(layer "F.Cu")
		(at 396.327884 -35.876738)
		(property "Reference" "R6118"
			(at 0 0 0)
			(layer "F.SilkS")
			(hide yes)
			(effects
				(font
					(size 1.27 1.27)
				)
			)
		)
		(property "Value" ""
			(at 0 0 0)
			(layer "F.Fab")
			(effects
				(font
					(size 1.27 1.27)
				)
			)
		)
		(duplicate_pad_numbers_are_jumpers no)
		(fp_line
			(start -0.7874 -0.4064)
			(end 0.7874 -0.4064)
			(stroke
				(width 0.1524)
				(type default)
			)
			(layer "F.SilkS")
		)
		(fp_line
			(start -0.7874 0.4064)
			(end -0.7874 -0.4064)
			(stroke
				(width 0.1524)
				(type default)
			)
			(layer "F.SilkS")
		)
		(fp_line
			(start 0.7874 -0.4064)
			(end 0.7874 0.4064)
			(stroke
				(width 0.1524)
				(type default)
			)
			(layer "F.SilkS")
		)
		(fp_line
			(start 0.7874 0.4064)
			(end -0.7874 0.4064)
			(stroke
				(width 0.1524)
				(type default)
			)
			(layer "F.SilkS")
		)
		(fp_line
			(start -0.67945 -0.305054)
			(end -0.12065 -0.305054)
			(stroke
				(width 0.1)
				(type default)
			)
			(layer "F.Fab")
		)
		(fp_line
			(start -0.67945 0.3048)
			(end -0.67945 -0.305054)
			(stroke
				(width 0.1)
				(type default)
			)
			(layer "F.Fab")
		)
		(fp_line
			(start -0.12065 -0.305054)
			(end -0.12065 -0.2794)
			(stroke
				(width 0.1)
				(type default)
			)
			(layer "F.Fab")
		)
		(fp_line
			(start -0.12065 -0.2794)
			(end 0.12065 -0.2794)
			(stroke
				(width 0.1)
				(type default)
			)
			(layer "F.Fab")
		)
		(fp_line
			(start -0.12065 0.2794)
			(end -0.12065 0.3048)
			(stroke
				(width 0.1)
				(type default)
			)
			(layer "F.Fab")
		)
		(fp_line
			(start -0.12065 0.3048)
			(end -0.67945 0.3048)
			(stroke
				(width 0.1)
				(type default)
			)
			(layer "F.Fab")
		)
		(fp_line
			(start 0.120396 0.2794)
			(end -0.12065 0.2794)
			(stroke
				(width 0.1)
				(type default)
			)
			(layer "F.Fab")
		)
		(fp_line
			(start 0.120396 0.3048)
			(end 0.120396 0.2794)
			(stroke
				(width 0.1)
				(type default)
			)
			(layer "F.Fab")
		)
		(fp_line
			(start 0.12065 -0.3048)
			(end 0.67945 -0.3048)
			(stroke
				(width 0.1)
				(type default)
			)
			(layer "F.Fab")
		)
		(fp_line
			(start 0.12065 -0.2794)
			(end 0.12065 -0.3048)
			(stroke
				(width 0.1)
				(type default)
			)
			(layer "F.Fab")
		)
		(fp_line
			(start 0.67945 -0.3048)
			(end 0.67945 0.3048)
			(stroke
				(width 0.1)
				(type default)
			)
			(layer "F.Fab")
		)
		(fp_line
			(start 0.67945 0.3048)
			(end 0.120396 0.3048)
			(stroke
				(width 0.1)
				(type default)
			)
			(layer "F.Fab")
		)
		(pad "1" smd circle
			(at -0.40005 0)
			(size 0 0)
			(layers "F.Cu" "F.Mask" "F.Paste")
			(net "PWRGD_P3V3_SSD14_D")
		)
		(pad "2" smd circle
			(at 0.40005 0)
			(size 0 0)
			(layers "F.Cu" "F.Mask" "F.Paste")
			(net "PWRGD_P3V3_SSD14_R")
		)
	)
	(footprint ""
		(layer "F.Cu")
		(at 171.487592 -343.952322 90)
		(property "Reference" "C2520"
			(at 0 0 90)
			(layer "F.SilkS")
			(hide yes)
			(effects
				(font
					(size 1.27 1.27)
				)
			)
		)
		(property "Value" ""
			(at 0 0 90)
			(layer "F.Fab")
			(effects
				(font
					(size 1.27 1.27)
				)
			)
		)
		(duplicate_pad_numbers_are_jumpers no)
		(fp_line
			(start 0.299974 -0.150114)
			(end 0.299974 0.150114)
			(stroke
				(width 0.1)
				(type default)
			)
			(layer "F.Fab")
		)
		(fp_line
			(start -0.299974 -0.150114)
			(end 0.299974 -0.150114)
			(stroke
				(width 0.1)
				(type default)
			)
			(layer "F.Fab")
		)
		(fp_line
			(start 0.299974 0.150114)
			(end -0.299974 0.150114)
			(stroke
				(width 0.1)
				(type default)
			)
			(layer "F.Fab")
		)
		(fp_line
			(start -0.299974 0.150114)
			(end -0.299974 -0.150114)
			(stroke
				(width 0.1)
				(type default)
			)
			(layer "F.Fab")
		)
		(pad "1" smd rect
			(at -0.2667 0 90)
			(size 0.3048 0.381)
			(layers "F.Cu" "F.Mask" "F.Paste")
			(net "P5E_PEX1_STN4_TX_DP<75>")
		)
		(pad "2" smd rect
			(at 0.2667 0 90)
			(size 0.3048 0.381)
			(layers "F.Cu" "F.Mask" "F.Paste")
			(net "P5E_PEX1_STN4_TX_C_DP<75>")
		)
	)
	(footprint ""
		(layer "F.Cu")
		(at 321.84975 -270.89989)
		(property "Reference" "H86"
			(at -2.438908 -8.862568 0)
			(unlocked yes)
			(layer "F.SilkS")
			(effects
				(font
					(size 0.7874 0.5842)
					(thickness 0.1524)
				)
				(justify left)
			)
		)
		(property "Value" ""
			(at 0 0 0)
			(layer "F.Fab")
			(effects
				(font
					(size 1.27 1.27)
				)
			)
		)
		(duplicate_pad_numbers_are_jumpers no)
		(fp_arc
			(start -5.701792 -5.611368)
			(mid 3.031933 -7.403178)
			(end 7.999984 0)
			(stroke
				(width 0.1524)
				(type default)
			)
			(layer "F.SilkS")
		)
		(fp_arc
			(start 7.999984 0)
			(mid -0.332341 7.993016)
			(end -7.972298 -0.66421)
			(stroke
				(width 0.1524)
				(type default)
			)
			(layer "F.SilkS")
		)
		(fp_arc
			(start -5.443982 -5.862066)
			(mid 3.197507 -7.333195)
			(end 7.999984 0)
			(stroke
				(width 0.1524)
				(type default)
			)
			(layer "B.SilkS")
		)
		(fp_arc
			(start 7.999984 0)
			(mid -0.319455 7.993705)
			(end -7.974584 -0.638302)
			(stroke
				(width 0.1524)
				(type default)
			)
			(layer "B.SilkS")
		)
		(fp_circle
			(center 0 0)
			(end 7.999984 0)
			(stroke
				(width 0.1)
				(type default)
			)
			(fill no)
			(layer "B.Fab")
		)
		(fp_circle
			(center 0 0)
			(end 7.999984 0)
			(stroke
				(width 0.1)
				(type default)
			)
			(fill no)
			(layer "F.Fab")
		)
		(pad "" np_thru_hole circle
			(at 0 0)
			(size 4.5212 4.5212)
			(drill 4.5212)
			(layers "*.Cu" "*.Mask")
			(clearance 0.381)
			(thermal_gap 0.381)
		)
		(pad "2" thru_hole circle
			(at 3.6322 0)
			(size 0.762 0.762)
			(drill 0.5588)
			(layers "*.Cu" "*.Mask")
			(remove_unused_layers no)
			(net "GND")
			(clearance 0.1524)
			(thermal_gap 0.1524)
		)
		(pad "3" thru_hole circle
			(at 2.568448 -2.568448)
			(size 0.762 0.762)
			(drill 0.5588)
			(layers "*.Cu" "*.Mask")
			(remove_unused_layers no)
			(net "GND")
			(clearance 0.1524)
			(thermal_gap 0.1524)
		)
		(pad "4" thru_hole circle
			(at 0 -3.6322)
			(size 0.762 0.762)
			(drill 0.5588)
			(layers "*.Cu" "*.Mask")
			(remove_unused_layers no)
			(net "GND")
			(clearance 0.1524)
			(thermal_gap 0.1524)
		)
		(pad "5" thru_hole circle
			(at -2.568448 -2.568448)
			(size 0.762 0.762)
			(drill 0.5588)
			(layers "*.Cu" "*.Mask")
			(remove_unused_layers no)
			(net "GND")
			(clearance 0.1524)
			(thermal_gap 0.1524)
		)
		(pad "6" thru_hole circle
			(at -3.6322 0)
			(size 0.762 0.762)
			(drill 0.5588)
			(layers "*.Cu" "*.Mask")
			(remove_unused_layers no)
			(net "GND")
			(clearance 0.1524)
			(thermal_gap 0.1524)
		)
		(pad "7" thru_hole circle
			(at -2.568448 2.568448)
			(size 0.762 0.762)
			(drill 0.5588)
			(layers "*.Cu" "*.Mask")
			(remove_unused_layers no)
			(net "GND")
			(clearance 0.1524)
			(thermal_gap 0.1524)
		)
		(pad "8" thru_hole circle
			(at 0 3.6322)
			(size 0.762 0.762)
			(drill 0.5588)
			(layers "*.Cu" "*.Mask")
			(remove_unused_layers no)
			(net "GND")
			(clearance 0.1524)
			(thermal_gap 0.1524)
		)
		(pad "9" thru_hole circle
			(at 2.568448 2.568448)
			(size 0.762 0.762)
			(drill 0.5588)
			(layers "*.Cu" "*.Mask")
			(remove_unused_layers no)
			(net "GND")
			(clearance 0.1524)
			(thermal_gap 0.1524)
		)
		(zone
			(layer "F.Cu")
			(hatch none 0.5)
			(connect_pads
				(clearance 0)
			)
			(min_thickness 0.25)
			(keepout
				(tracks not_allowed)
				(vias allowed)
				(pads allowed)
				(copperpour not_allowed)
				(footprints allowed)
			)
			(placement
				(enabled no)
				(sheetname "")
			)
			(fill
				(thermal_gap 0.5)
				(thermal_bridge_width 0.5)
				(island_removal_mode 0)
			)
			(polygon
				(pts
					(arc
						(start 321.84975 -262.899906)
						(mid 313.849766 -270.89989)
						(end 321.84975 -278.899874)
					)
					(arc
						(start 321.84975 -275.64969)
						(mid 317.09995 -270.89989)
						(end 321.84975 -266.15009)
					)
				)
			)
		)
		(zone
			(layer "F.Cu")
			(hatch none 0.5)
			(connect_pads
				(clearance 0)
			)
			(min_thickness 0.25)
			(keepout
				(tracks not_allowed)
				(vias allowed)
				(pads allowed)
				(copperpour not_allowed)
				(footprints allowed)
			)
			(placement
				(enabled no)
				(sheetname "")
			)
			(fill
				(thermal_gap 0.5)
				(thermal_bridge_width 0.5)
				(island_removal_mode 0)
			)
			(polygon
				(pts
					(arc
						(start 321.84975 -262.899906)
						(mid 329.849734 -270.89989)
						(end 321.84975 -278.899874)
					)
					(arc
						(start 321.84975 -275.64969)
						(mid 326.59955 -270.89989)
						(end 321.84975 -266.15009)
					)
				)
			)
		)
		(zone
			(layers "F.Cu" "B.Cu" "In1.Cu" "In2.Cu" "In3.Cu" "In4.Cu" "In5.Cu" "In6.Cu"
				"In7.Cu" "In8.Cu" "In9.Cu" "In10.Cu" "In11.Cu" "In12.Cu" "In13.Cu" "In14.Cu"
				"In15.Cu" "In16.Cu"
			)
			(hatch none 0.5)
			(connect_pads
				(clearance 0)
			)
			(min_thickness 0.25)
			(keepout
				(tracks not_allowed)
				(vias allowed)
				(pads allowed)
				(copperpour not_allowed)
				(footprints allowed)
			)
			(placement
				(enabled no)
				(sheetname "")
			)
			(fill
				(thermal_gap 0.5)
				(thermal_bridge_width 0.5)
				(island_removal_mode 0)
			)
			(polygon
				(pts
					(arc
						(start 324.61581 -270.89989)
						(mid 319.08369 -270.89989)
						(end 324.61581 -270.89989)
					)
				)
			)
		)
		(zone
			(layer "B.Cu")
			(hatch none 0.5)
			(connect_pads
				(clearance 0)
			)
			(min_thickness 0.25)
			(keepout
				(tracks not_allowed)
				(vias allowed)
				(pads allowed)
				(copperpour not_allowed)
				(footprints allowed)
			)
			(placement
				(enabled no)
				(sheetname "")
			)
			(fill
				(thermal_gap 0.5)
				(thermal_bridge_width 0.5)
				(island_removal_mode 0)
			)
			(polygon
				(pts
					(arc
						(start 321.84975 -265.89609)
						(mid 316.84595 -270.89989)
						(end 321.84975 -275.90369)
					)
					(arc
						(start 321.84975 -275.42109)
						(mid 317.32855 -270.89989)
						(end 321.84975 -266.37869)
					)
				)
			)
		)
		(zone
			(layer "B.Cu")
			(hatch none 0.5)
			(connect_pads
				(clearance 0)
			)
			(min_thickness 0.25)
			(keepout
				(tracks not_allowed)
				(vias allowed)
				(pads allowed)
				(copperpour not_allowed)
				(footprints allowed)
			)
			(placement
				(enabled no)
				(sheetname "")
			)
			(fill
				(thermal_gap 0.5)
				(thermal_bridge_width 0.5)
				(island_removal_mode 0)
			)
			(polygon
				(pts
					(arc
						(start 321.84975 -265.89609)
						(mid 326.85355 -270.89989)
						(end 321.84975 -275.90369)
					)
					(arc
						(start 321.84975 -275.42109)
						(mid 326.37095 -270.89989)
						(end 321.84975 -266.37869)
					)
				)
			)
		)
	)
	(footprint ""
		(layer "F.Cu")
		(at 304.859436 -61.612526)
		(property "Reference" "PD48"
			(at -3.7084 -2.733548 0)
			(unlocked yes)
			(layer "F.SilkS")
			(effects
				(font
					(size 0.7874 0.5842)
					(thickness 0.1524)
				)
				(justify left)
			)
		)
		(property "Value" ""
			(at 0 0 0)
			(layer "F.Fab")
			(effects
				(font
					(size 1.27 1.27)
				)
			)
		)
		(duplicate_pad_numbers_are_jumpers no)
		(fp_line
			(start -3.656584 -1.970024)
			(end -3.656584 1.970024)
			(stroke
				(width 0.1524)
				(type default)
			)
			(layer "F.SilkS")
		)
		(fp_line
			(start -3.656584 1.970024)
			(end 4.240784 1.970024)
			(stroke
				(width 0.1524)
				(type default)
			)
			(layer "F.SilkS")
		)
		(fp_line
			(start 4.240784 -1.970024)
			(end -3.656584 -1.970024)
			(stroke
				(width 0.1524)
				(type default)
			)
			(layer "F.SilkS")
		)
		(fp_line
			(start 4.240784 1.970024)
			(end 4.240784 -1.970024)
			(stroke
				(width 0.1524)
				(type default)
			)
			(layer "F.SilkS")
		)
		(fp_poly
			(pts
				(xy 3.580384 1.970024) (xy 3.580384 -1.970024) (xy 4.240784 -1.970024) (xy 4.240784 1.970024)
			)
			(stroke
				(width 0)
				(type default)
			)
			(fill yes)
			(layer "F.SilkS")
		)
		(fp_line
			(start -2.3749 -1.970024)
			(end -2.3749 1.970024)
			(stroke
				(width 0.1)
				(type default)
			)
			(layer "F.Fab")
		)
		(fp_line
			(start -2.3749 1.970024)
			(end 2.3749 1.970024)
			(stroke
				(width 0.1)
				(type default)
			)
			(layer "F.Fab")
		)
		(fp_line
			(start 2.3749 -1.970024)
			(end -2.3749 -1.970024)
			(stroke
				(width 0.1)
				(type default)
			)
			(layer "F.Fab")
		)
		(fp_line
			(start 2.3749 1.970024)
			(end 2.3749 -1.970024)
			(stroke
				(width 0.1)
				(type default)
			)
			(layer "F.Fab")
		)
		(fp_text user "+"
			(at -4.9784 -0.23495 0)
			(unlocked yes)
			(layer "F.Fab")
			(effects
				(font
					(size 1.905 1.4224)
					(thickness 0.1524)
				)
				(justify left)
			)
		)
		(fp_text user "-"
			(at 4.1656 -0.23495 0)
			(unlocked yes)
			(layer "F.Fab")
			(effects
				(font
					(size 1.905 1.4224)
					(thickness 0.1524)
				)
				(justify left)
			)
		)
		(pad "A" smd rect
			(at -2.450084 0)
			(size 2.159 2.2606)
			(layers "F.Cu" "F.Mask" "F.Paste")
			(net "GND")
		)
		(pad "C" smd rect
			(at 2.450084 0)
			(size 2.159 2.2606)
			(layers "F.Cu" "F.Mask" "F.Paste")
			(net "P12V_AUX")
		)
	)
	(footprint ""
		(layer "F.Cu")
		(at 78.243684 -42.84091)
		(property "Reference" "R528"
			(at 0 0 0)
			(layer "F.SilkS")
			(hide yes)
			(effects
				(font
					(size 1.27 1.27)
				)
			)
		)
		(property "Value" ""
			(at 0 0 0)
			(layer "F.Fab")
			(effects
				(font
					(size 1.27 1.27)
				)
			)
		)
		(duplicate_pad_numbers_are_jumpers no)
		(fp_line
			(start -0.7874 -0.4064)
			(end 0.7874 -0.4064)
			(stroke
				(width 0.1524)
				(type default)
			)
			(layer "F.SilkS")
		)
		(fp_line
			(start -0.7874 0.4064)
			(end -0.7874 -0.4064)
			(stroke
				(width 0.1524)
				(type default)
			)
			(layer "F.SilkS")
		)
		(fp_line
			(start 0.7874 -0.4064)
			(end 0.7874 0.4064)
			(stroke
				(width 0.1524)
				(type default)
			)
			(layer "F.SilkS")
		)
		(fp_line
			(start 0.7874 0.4064)
			(end -0.7874 0.4064)
			(stroke
				(width 0.1524)
				(type default)
			)
			(layer "F.SilkS")
		)
		(fp_line
			(start -0.67945 -0.305054)
			(end -0.12065 -0.305054)
			(stroke
				(width 0.1)
				(type default)
			)
			(layer "F.Fab")
		)
		(fp_line
			(start -0.67945 0.3048)
			(end -0.67945 -0.305054)
			(stroke
				(width 0.1)
				(type default)
			)
			(layer "F.Fab")
		)
		(fp_line
			(start -0.12065 -0.305054)
			(end -0.12065 -0.2794)
			(stroke
				(width 0.1)
				(type default)
			)
			(layer "F.Fab")
		)
		(fp_line
			(start -0.12065 -0.2794)
			(end 0.12065 -0.2794)
			(stroke
				(width 0.1)
				(type default)
			)
			(layer "F.Fab")
		)
		(fp_line
			(start -0.12065 0.2794)
			(end -0.12065 0.3048)
			(stroke
				(width 0.1)
				(type default)
			)
			(layer "F.Fab")
		)
		(fp_line
			(start -0.12065 0.3048)
			(end -0.67945 0.3048)
			(stroke
				(width 0.1)
				(type default)
			)
			(layer "F.Fab")
		)
		(fp_line
			(start 0.120396 0.2794)
			(end -0.12065 0.2794)
			(stroke
				(width 0.1)
				(type default)
			)
			(layer "F.Fab")
		)
		(fp_line
			(start 0.120396 0.3048)
			(end 0.120396 0.2794)
			(stroke
				(width 0.1)
				(type default)
			)
			(layer "F.Fab")
		)
		(fp_line
			(start 0.12065 -0.3048)
			(end 0.67945 -0.3048)
			(stroke
				(width 0.1)
				(type default)
			)
			(layer "F.Fab")
		)
		(fp_line
			(start 0.12065 -0.2794)
			(end 0.12065 -0.3048)
			(stroke
				(width 0.1)
				(type default)
			)
			(layer "F.Fab")
		)
		(fp_line
			(start 0.67945 -0.3048)
			(end 0.67945 0.3048)
			(stroke
				(width 0.1)
				(type default)
			)
			(layer "F.Fab")
		)
		(fp_line
			(start 0.67945 0.3048)
			(end 0.120396 0.3048)
			(stroke
				(width 0.1)
				(type default)
			)
			(layer "F.Fab")
		)
		(pad "1" smd circle
			(at -0.40005 0)
			(size 0 0)
			(layers "F.Cu" "F.Mask" "F.Paste")
			(net "SSD2_ADC_A1")
		)
		(pad "2" smd circle
			(at 0.40005 0)
			(size 0 0)
			(layers "F.Cu" "F.Mask" "F.Paste")
			(net "P3V3_AUX")
		)
	)
	(footprint ""
		(layer "F.Cu")
		(at 190.78956 -402.66874 90)
		(property "Reference" "R4418"
			(at 0 0 90)
			(layer "F.SilkS")
			(hide yes)
			(effects
				(font
					(size 1.27 1.27)
				)
			)
		)
		(property "Value" ""
			(at 0 0 90)
			(layer "F.Fab")
			(effects
				(font
					(size 1.27 1.27)
				)
			)
		)
		(duplicate_pad_numbers_are_jumpers no)
		(fp_line
			(start 0.7874 -0.4064)
			(end 0.7874 0.4064)
			(stroke
				(width 0.1524)
				(type default)
			)
			(layer "F.SilkS")
		)
		(fp_line
			(start -0.7874 -0.4064)
			(end 0.7874 -0.4064)
			(stroke
				(width 0.1524)
				(type default)
			)
			(layer "F.SilkS")
		)
		(fp_line
			(start 0.7874 0.4064)
			(end -0.7874 0.4064)
			(stroke
				(width 0.1524)
				(type default)
			)
			(layer "F.SilkS")
		)
		(fp_line
			(start -0.7874 0.4064)
			(end -0.7874 -0.4064)
			(stroke
				(width 0.1524)
				(type default)
			)
			(layer "F.SilkS")
		)
		(fp_line
			(start -0.12065 -0.305054)
			(end -0.12065 -0.2794)
			(stroke
				(width 0.1)
				(type default)
			)
			(layer "F.Fab")
		)
		(fp_line
			(start -0.67945 -0.305054)
			(end -0.12065 -0.305054)
			(stroke
				(width 0.1)
				(type default)
			)
			(layer "F.Fab")
		)
		(fp_line
			(start 0.67945 -0.3048)
			(end 0.67945 0.3048)
			(stroke
				(width 0.1)
				(type default)
			)
			(layer "F.Fab")
		)
		(fp_line
			(start 0.12065 -0.3048)
			(end 0.67945 -0.3048)
			(stroke
				(width 0.1)
				(type default)
			)
			(layer "F.Fab")
		)
		(fp_line
			(start 0.12065 -0.2794)
			(end 0.12065 -0.3048)
			(stroke
				(width 0.1)
				(type default)
			)
			(layer "F.Fab")
		)
		(fp_line
			(start -0.12065 -0.2794)
			(end 0.12065 -0.2794)
			(stroke
				(width 0.1)
				(type default)
			)
			(layer "F.Fab")
		)
		(fp_line
			(start 0.120396 0.2794)
			(end -0.12065 0.2794)
			(stroke
				(width 0.1)
				(type default)
			)
			(layer "F.Fab")
		)
		(fp_line
			(start -0.12065 0.2794)
			(end -0.12065 0.3048)
			(stroke
				(width 0.1)
				(type default)
			)
			(layer "F.Fab")
		)
		(fp_line
			(start 0.67945 0.3048)
			(end 0.120396 0.3048)
			(stroke
				(width 0.1)
				(type default)
			)
			(layer "F.Fab")
		)
		(fp_line
			(start 0.120396 0.3048)
			(end 0.120396 0.2794)
			(stroke
				(width 0.1)
				(type default)
			)
			(layer "F.Fab")
		)
		(fp_line
			(start -0.12065 0.3048)
			(end -0.67945 0.3048)
			(stroke
				(width 0.1)
				(type default)
			)
			(layer "F.Fab")
		)
		(fp_line
			(start -0.67945 0.3048)
			(end -0.67945 -0.305054)
			(stroke
				(width 0.1)
				(type default)
			)
			(layer "F.Fab")
		)
		(pad "1" smd circle
			(at -0.40005 0 90)
			(size 0 0)
			(layers "F.Cu" "F.Mask" "F.Paste")
			(net "GND")
		)
		(pad "2" smd circle
			(at 0.40005 0 90)
			(size 0 0)
			(layers "F.Cu" "F.Mask" "F.Paste")
			(net "A_P12V_AUX_ADR_TRIGGER")
		)
	)
	(footprint ""
		(layer "F.Cu")
		(at 27.126184 -39.73576 -90)
		(property "Reference" "R5542"
			(at 0 0 270)
			(layer "F.SilkS")
			(hide yes)
			(effects
				(font
					(size 1.27 1.27)
				)
			)
		)
		(property "Value" ""
			(at 0 0 270)
			(layer "F.Fab")
			(effects
				(font
					(size 1.27 1.27)
				)
			)
		)
		(duplicate_pad_numbers_are_jumpers no)
		(fp_line
			(start -0.7874 0.4064)
			(end -0.7874 -0.4064)
			(stroke
				(width 0.1524)
				(type default)
			)
			(layer "F.SilkS")
		)
		(fp_line
			(start 0.7874 0.4064)
			(end -0.7874 0.4064)
			(stroke
				(width 0.1524)
				(type default)
			)
			(layer "F.SilkS")
		)
		(fp_line
			(start -0.7874 -0.4064)
			(end 0.7874 -0.4064)
			(stroke
				(width 0.1524)
				(type default)
			)
			(layer "F.SilkS")
		)
		(fp_line
			(start 0.7874 -0.4064)
			(end 0.7874 0.4064)
			(stroke
				(width 0.1524)
				(type default)
			)
			(layer "F.SilkS")
		)
		(fp_line
			(start -0.67945 0.3048)
			(end -0.67945 -0.305054)
			(stroke
				(width 0.1)
				(type default)
			)
			(layer "F.Fab")
		)
		(fp_line
			(start -0.12065 0.3048)
			(end -0.67945 0.3048)
			(stroke
				(width 0.1)
				(type default)
			)
			(layer "F.Fab")
		)
		(fp_line
			(start 0.120396 0.3048)
			(end 0.120396 0.2794)
			(stroke
				(width 0.1)
				(type default)
			)
			(layer "F.Fab")
		)
		(fp_line
			(start 0.67945 0.3048)
			(end 0.120396 0.3048)
			(stroke
				(width 0.1)
				(type default)
			)
			(layer "F.Fab")
		)
		(fp_line
			(start -0.12065 0.2794)
			(end -0.12065 0.3048)
			(stroke
				(width 0.1)
				(type default)
			)
			(layer "F.Fab")
		)
		(fp_line
			(start 0.120396 0.2794)
			(end -0.12065 0.2794)
			(stroke
				(width 0.1)
				(type default)
			)
			(layer "F.Fab")
		)
		(fp_line
			(start -0.12065 -0.2794)
			(end 0.12065 -0.2794)
			(stroke
				(width 0.1)
				(type default)
			)
			(layer "F.Fab")
		)
		(fp_line
			(start 0.12065 -0.2794)
			(end 0.12065 -0.3048)
			(stroke
				(width 0.1)
				(type default)
			)
			(layer "F.Fab")
		)
		(fp_line
			(start 0.12065 -0.3048)
			(end 0.67945 -0.3048)
			(stroke
				(width 0.1)
				(type default)
			)
			(layer "F.Fab")
		)
		(fp_line
			(start 0.67945 -0.3048)
			(end 0.67945 0.3048)
			(stroke
				(width 0.1)
				(type default)
			)
			(layer "F.Fab")
		)
		(fp_line
			(start -0.67945 -0.305054)
			(end -0.12065 -0.305054)
			(stroke
				(width 0.1)
				(type default)
			)
			(layer "F.Fab")
		)
		(fp_line
			(start -0.12065 -0.305054)
			(end -0.12065 -0.2794)
			(stroke
				(width 0.1)
				(type default)
			)
			(layer "F.Fab")
		)
		(pad "1" smd circle
			(at -0.40005 0 270)
			(size 0 0)
			(layers "F.Cu" "F.Mask" "F.Paste")
			(net "P3V3_AUX")
		)
		(pad "2" smd circle
			(at 0.40005 0 270)
			(size 0 0)
			(layers "F.Cu" "F.Mask" "F.Paste")
			(net "SSD1_AUX_P3V3_EN")
		)
	)
	(footprint ""
		(layer "F.Cu")
		(at 333.965042 -308.617112 -90)
		(property "Reference" "C4303"
			(at 0 0 270)
			(layer "F.SilkS")
			(hide yes)
			(effects
				(font
					(size 1.27 1.27)
				)
			)
		)
		(property "Value" ""
			(at 0 0 270)
			(layer "F.Fab")
			(effects
				(font
					(size 1.27 1.27)
				)
			)
		)
		(duplicate_pad_numbers_are_jumpers no)
		(fp_line
			(start -1.2954 0.5842)
			(end -1.2954 -0.5842)
			(stroke
				(width 0.1524)
				(type default)
			)
			(layer "F.SilkS")
		)
		(fp_line
			(start 1.2954 0.5842)
			(end -1.2954 0.5842)
			(stroke
				(width 0.1524)
				(type default)
			)
			(layer "F.SilkS")
		)
		(fp_line
			(start -1.2954 -0.5842)
			(end 1.2954 -0.5842)
			(stroke
				(width 0.1524)
				(type default)
			)
			(layer "F.SilkS")
		)
		(fp_line
			(start 1.2954 -0.5842)
			(end 1.2954 0.5842)
			(stroke
				(width 0.1524)
				(type default)
			)
			(layer "F.SilkS")
		)
		(fp_line
			(start -0.8636 0.4572)
			(end -0.8636 0.4064)
			(stroke
				(width 0.1)
				(type default)
			)
			(layer "F.Fab")
		)
		(fp_line
			(start 0.8636 0.4572)
			(end -0.8636 0.4572)
			(stroke
				(width 0.1)
				(type default)
			)
			(layer "F.Fab")
		)
		(fp_line
			(start -1.1938 0.4064)
			(end -1.1938 -0.4064)
			(stroke
				(width 0.1)
				(type default)
			)
			(layer "F.Fab")
		)
		(fp_line
			(start -0.8636 0.4064)
			(end -1.1938 0.4064)
			(stroke
				(width 0.1)
				(type default)
			)
			(layer "F.Fab")
		)
		(fp_line
			(start 0.8636 0.4064)
			(end 0.8636 0.4572)
			(stroke
				(width 0.1)
				(type default)
			)
			(layer "F.Fab")
		)
		(fp_line
			(start 1.1938 0.4064)
			(end 0.8636 0.4064)
			(stroke
				(width 0.1)
				(type default)
			)
			(layer "F.Fab")
		)
		(fp_line
			(start -1.1938 -0.4064)
			(end -0.8636 -0.4064)
			(stroke
				(width 0.1)
				(type default)
			)
			(layer "F.Fab")
		)
		(fp_line
			(start -0.8636 -0.4064)
			(end -0.8636 -0.4572)
			(stroke
				(width 0.1)
				(type default)
			)
			(layer "F.Fab")
		)
		(fp_line
			(start 0.8636 -0.4064)
			(end 1.1938 -0.4064)
			(stroke
				(width 0.1)
				(type default)
			)
			(layer "F.Fab")
		)
		(fp_line
			(start 1.1938 -0.4064)
			(end 1.1938 0.4064)
			(stroke
				(width 0.1)
				(type default)
			)
			(layer "F.Fab")
		)
		(fp_line
			(start -0.8636 -0.4572)
			(end 0.8636 -0.4572)
			(stroke
				(width 0.1)
				(type default)
			)
			(layer "F.Fab")
		)
		(fp_line
			(start 0.8636 -0.4572)
			(end 0.8636 -0.4064)
			(stroke
				(width 0.1)
				(type default)
			)
			(layer "F.Fab")
		)
		(pad "1" smd rect
			(at -0.7366 0 180)
			(size 0.7112 0.8128)
			(layers "F.Cu" "F.Mask" "F.Paste")
			(net "P0V8_PEX2")
		)
		(pad "2" smd rect
			(at 0.7366 0 180)
			(size 0.7112 0.8128)
			(layers "F.Cu" "F.Mask" "F.Paste")
			(net "GND")
		)
	)
	(footprint ""
		(layer "F.Cu")
		(at 251.671836 -369.875562 90)
		(property "Reference" "PQ6603"
			(at -8.232394 -2.673604 0)
			(unlocked yes)
			(layer "F.SilkS")
			(effects
				(font
					(size 0.7874 0.5842)
					(thickness 0.1524)
				)
				(justify left)
			)
		)
		(property "Value" ""
			(at 0 0 90)
			(layer "F.Fab")
			(effects
				(font
					(size 1.27 1.27)
				)
			)
		)
		(duplicate_pad_numbers_are_jumpers no)
		(fp_line
			(start 2.350008 -2.649982)
			(end 2.350008 -2.4892)
			(stroke
				(width 0.1524)
				(type default)
			)
			(layer "F.SilkS")
		)
		(fp_line
			(start -2.350008 -2.649982)
			(end 2.350008 -2.649982)
			(stroke
				(width 0.1524)
				(type default)
			)
			(layer "F.SilkS")
		)
		(fp_line
			(start -2.350008 -2.4384)
			(end -2.350008 -2.649982)
			(stroke
				(width 0.1524)
				(type default)
			)
			(layer "F.SilkS")
		)
		(fp_line
			(start 2.350008 2.4892)
			(end 2.350008 2.649982)
			(stroke
				(width 0.1524)
				(type default)
			)
			(layer "F.SilkS")
		)
		(fp_line
			(start 2.350008 2.649982)
			(end -2.350008 2.649982)
			(stroke
				(width 0.1524)
				(type default)
			)
			(layer "F.SilkS")
		)
		(fp_line
			(start -2.350008 2.649982)
			(end -2.350008 2.413)
			(stroke
				(width 0.1524)
				(type default)
			)
			(layer "F.SilkS")
		)
		(fp_poly
			(pts
				(xy -4.77393 -1.889252) (xy -5.81533 -2.308352) (xy -5.81533 -1.508252)
			)
			(stroke
				(width 0)
				(type default)
			)
			(fill yes)
			(layer "F.SilkS")
		)
		(fp_line
			(start 2.350008 -2.649982)
			(end 2.350008 2.649982)
			(stroke
				(width 0.1)
				(type default)
			)
			(layer "F.Fab")
		)
		(fp_line
			(start -2.350008 -2.649982)
			(end 2.350008 -2.649982)
			(stroke
				(width 0.1)
				(type default)
			)
			(layer "F.Fab")
		)
		(fp_line
			(start 2.350008 2.649982)
			(end -2.350008 2.649982)
			(stroke
				(width 0.1)
				(type default)
			)
			(layer "F.Fab")
		)
		(fp_line
			(start -2.350008 2.649982)
			(end -2.350008 -2.649982)
			(stroke
				(width 0.1)
				(type default)
			)
			(layer "F.Fab")
		)
		(fp_poly
			(pts
				(xy -3.717544 -1.905) (xy -4.758944 -2.3241) (xy -4.758944 -1.524)
			)
			(stroke
				(width 0)
				(type default)
			)
			(fill yes)
			(layer "F.Fab")
		)
		(pad "1" smd rect
			(at -2.999994 -1.905)
			(size 0.7112 1.1684)
			(layers "F.Cu" "F.Mask" "F.Paste")
			(net "P12V_AUX")
		)
		(pad "2" smd rect
			(at -2.999994 -0.635)
			(size 0.7112 1.1684)
			(layers "F.Cu" "F.Mask" "F.Paste")
			(net "P12V_AUX")
		)
		(pad "3" smd rect
			(at -2.999994 0.635)
			(size 0.7112 1.1684)
			(layers "F.Cu" "F.Mask" "F.Paste")
			(net "P12V_AUX")
		)
		(pad "4" smd rect
			(at -2.999994 1.905)
			(size 0.7112 1.1684)
			(layers "F.Cu" "F.Mask" "F.Paste")
			(net "HS_GATE2_R_2")
		)
		(pad "5" smd circle
			(at 0.925068 0)
			(size 0 0)
			(layers "F.Cu" "F.Mask" "F.Paste")
			(net "P12V_STBY_R2")
		)
		(zone
			(layer "F.Cu")
			(hatch none 0.5)
			(connect_pads
				(clearance 0)
			)
			(min_thickness 0.25)
			(keepout
				(tracks not_allowed)
				(vias allowed)
				(pads allowed)
				(copperpour not_allowed)
				(footprints allowed)
			)
			(placement
				(enabled no)
				(sheetname "")
			)
			(fill
				(thermal_gap 0.5)
				(thermal_bridge_width 0.5)
				(island_removal_mode 0)
			)
			(polygon
				(pts
					(xy 249.512836 -368.427762) (xy 253.830836 -368.427762) (xy 254.313436 -368.427762) (xy 254.313436 -367.526062)
					(xy 249.030236 -367.526062) (xy 249.030236 -368.427762)
				)
			)
		)
	)
	(footprint ""
		(layer "F.Cu")
		(at 256.681986 -37.025072)
		(property "Reference" "R5681"
			(at 0 0 0)
			(layer "F.SilkS")
			(hide yes)
			(effects
				(font
					(size 1.27 1.27)
				)
			)
		)
		(property "Value" ""
			(at 0 0 0)
			(layer "F.Fab")
			(effects
				(font
					(size 1.27 1.27)
				)
			)
		)
		(duplicate_pad_numbers_are_jumpers no)
		(fp_line
			(start -0.7874 -0.4064)
			(end 0.7874 -0.4064)
			(stroke
				(width 0.1524)
				(type default)
			)
			(layer "F.SilkS")
		)
		(fp_line
			(start -0.7874 0.4064)
			(end -0.7874 -0.4064)
			(stroke
				(width 0.1524)
				(type default)
			)
			(layer "F.SilkS")
		)
		(fp_line
			(start 0.7874 -0.4064)
			(end 0.7874 0.4064)
			(stroke
				(width 0.1524)
				(type default)
			)
			(layer "F.SilkS")
		)
		(fp_line
			(start 0.7874 0.4064)
			(end -0.7874 0.4064)
			(stroke
				(width 0.1524)
				(type default)
			)
			(layer "F.SilkS")
		)
		(fp_line
			(start -0.67945 -0.305054)
			(end -0.12065 -0.305054)
			(stroke
				(width 0.1)
				(type default)
			)
			(layer "F.Fab")
		)
		(fp_line
			(start -0.67945 0.3048)
			(end -0.67945 -0.305054)
			(stroke
				(width 0.1)
				(type default)
			)
			(layer "F.Fab")
		)
		(fp_line
			(start -0.12065 -0.305054)
			(end -0.12065 -0.2794)
			(stroke
				(width 0.1)
				(type default)
			)
			(layer "F.Fab")
		)
		(fp_line
			(start -0.12065 -0.2794)
			(end 0.12065 -0.2794)
			(stroke
				(width 0.1)
				(type default)
			)
			(layer "F.Fab")
		)
		(fp_line
			(start -0.12065 0.2794)
			(end -0.12065 0.3048)
			(stroke
				(width 0.1)
				(type default)
			)
			(layer "F.Fab")
		)
		(fp_line
			(start -0.12065 0.3048)
			(end -0.67945 0.3048)
			(stroke
				(width 0.1)
				(type default)
			)
			(layer "F.Fab")
		)
		(fp_line
			(start 0.120396 0.2794)
			(end -0.12065 0.2794)
			(stroke
				(width 0.1)
				(type default)
			)
			(layer "F.Fab")
		)
		(fp_line
			(start 0.120396 0.3048)
			(end 0.120396 0.2794)
			(stroke
				(width 0.1)
				(type default)
			)
			(layer "F.Fab")
		)
		(fp_line
			(start 0.12065 -0.3048)
			(end 0.67945 -0.3048)
			(stroke
				(width 0.1)
				(type default)
			)
			(layer "F.Fab")
		)
		(fp_line
			(start 0.12065 -0.2794)
			(end 0.12065 -0.3048)
			(stroke
				(width 0.1)
				(type default)
			)
			(layer "F.Fab")
		)
		(fp_line
			(start 0.67945 -0.3048)
			(end 0.67945 0.3048)
			(stroke
				(width 0.1)
				(type default)
			)
			(layer "F.Fab")
		)
		(fp_line
			(start 0.67945 0.3048)
			(end 0.120396 0.3048)
			(stroke
				(width 0.1)
				(type default)
			)
			(layer "F.Fab")
		)
		(pad "1" smd circle
			(at -0.40005 0)
			(size 0 0)
			(layers "F.Cu" "F.Mask" "F.Paste")
			(net "RST_SMB_SSD_R_N")
		)
		(pad "2" smd circle
			(at 0.40005 0)
			(size 0 0)
			(layers "F.Cu" "F.Mask" "F.Paste")
			(net "RST_SMB_SSD9_N")
		)
	)
	(footprint ""
		(layer "F.Cu")
		(at 220.493844 -96.139 90)
		(property "Reference" "R720"
			(at 0 0 90)
			(layer "F.SilkS")
			(hide yes)
			(effects
				(font
					(size 1.27 1.27)
				)
			)
		)
		(property "Value" ""
			(at 0 0 90)
			(layer "F.Fab")
			(effects
				(font
					(size 1.27 1.27)
				)
			)
		)
		(duplicate_pad_numbers_are_jumpers no)
		(fp_line
			(start 0.7874 -0.4064)
			(end 0.7874 0.4064)
			(stroke
				(width 0.1524)
				(type default)
			)
			(layer "F.SilkS")
		)
		(fp_line
			(start -0.7874 -0.4064)
			(end 0.7874 -0.4064)
			(stroke
				(width 0.1524)
				(type default)
			)
			(layer "F.SilkS")
		)
		(fp_line
			(start 0.7874 0.4064)
			(end -0.7874 0.4064)
			(stroke
				(width 0.1524)
				(type default)
			)
			(layer "F.SilkS")
		)
		(fp_line
			(start -0.7874 0.4064)
			(end -0.7874 -0.4064)
			(stroke
				(width 0.1524)
				(type default)
			)
			(layer "F.SilkS")
		)
		(fp_line
			(start -0.12065 -0.305054)
			(end -0.12065 -0.2794)
			(stroke
				(width 0.1)
				(type default)
			)
			(layer "F.Fab")
		)
		(fp_line
			(start -0.67945 -0.305054)
			(end -0.12065 -0.305054)
			(stroke
				(width 0.1)
				(type default)
			)
			(layer "F.Fab")
		)
		(fp_line
			(start 0.67945 -0.3048)
			(end 0.67945 0.3048)
			(stroke
				(width 0.1)
				(type default)
			)
			(layer "F.Fab")
		)
		(fp_line
			(start 0.12065 -0.3048)
			(end 0.67945 -0.3048)
			(stroke
				(width 0.1)
				(type default)
			)
			(layer "F.Fab")
		)
		(fp_line
			(start 0.12065 -0.2794)
			(end 0.12065 -0.3048)
			(stroke
				(width 0.1)
				(type default)
			)
			(layer "F.Fab")
		)
		(fp_line
			(start -0.12065 -0.2794)
			(end 0.12065 -0.2794)
			(stroke
				(width 0.1)
				(type default)
			)
			(layer "F.Fab")
		)
		(fp_line
			(start 0.120396 0.2794)
			(end -0.12065 0.2794)
			(stroke
				(width 0.1)
				(type default)
			)
			(layer "F.Fab")
		)
		(fp_line
			(start -0.12065 0.2794)
			(end -0.12065 0.3048)
			(stroke
				(width 0.1)
				(type default)
			)
			(layer "F.Fab")
		)
		(fp_line
			(start 0.67945 0.3048)
			(end 0.120396 0.3048)
			(stroke
				(width 0.1)
				(type default)
			)
			(layer "F.Fab")
		)
		(fp_line
			(start 0.120396 0.3048)
			(end 0.120396 0.2794)
			(stroke
				(width 0.1)
				(type default)
			)
			(layer "F.Fab")
		)
		(fp_line
			(start -0.12065 0.3048)
			(end -0.67945 0.3048)
			(stroke
				(width 0.1)
				(type default)
			)
			(layer "F.Fab")
		)
		(fp_line
			(start -0.67945 0.3048)
			(end -0.67945 -0.305054)
			(stroke
				(width 0.1)
				(type default)
			)
			(layer "F.Fab")
		)
		(pad "1" smd circle
			(at -0.40005 0 90)
			(size 0 0)
			(layers "F.Cu" "F.Mask" "F.Paste")
			(net "SMB_BIC_I2C6_MUX_NIC_ADC_R_SCL")
		)
		(pad "2" smd circle
			(at 0.40005 0 90)
			(size 0 0)
			(layers "F.Cu" "F.Mask" "F.Paste")
			(net "SMB_NIC3_ADC_SCL")
		)
	)
	(footprint ""
		(layer "F.Cu")
		(at 191.767968 -19.453098)
		(property "Reference" "R1681"
			(at 0 0 0)
			(layer "F.SilkS")
			(hide yes)
			(effects
				(font
					(size 1.27 1.27)
				)
			)
		)
		(property "Value" ""
			(at 0 0 0)
			(layer "F.Fab")
			(effects
				(font
					(size 1.27 1.27)
				)
			)
		)
		(duplicate_pad_numbers_are_jumpers no)
		(fp_line
			(start -0.7874 -0.4064)
			(end 0.7874 -0.4064)
			(stroke
				(width 0.1524)
				(type default)
			)
			(layer "F.SilkS")
		)
		(fp_line
			(start -0.7874 0.4064)
			(end -0.7874 -0.4064)
			(stroke
				(width 0.1524)
				(type default)
			)
			(layer "F.SilkS")
		)
		(fp_line
			(start 0.7874 -0.4064)
			(end 0.7874 0.4064)
			(stroke
				(width 0.1524)
				(type default)
			)
			(layer "F.SilkS")
		)
		(fp_line
			(start 0.7874 0.4064)
			(end -0.7874 0.4064)
			(stroke
				(width 0.1524)
				(type default)
			)
			(layer "F.SilkS")
		)
		(fp_line
			(start -0.67945 -0.305054)
			(end -0.12065 -0.305054)
			(stroke
				(width 0.1)
				(type default)
			)
			(layer "F.Fab")
		)
		(fp_line
			(start -0.67945 0.3048)
			(end -0.67945 -0.305054)
			(stroke
				(width 0.1)
				(type default)
			)
			(layer "F.Fab")
		)
		(fp_line
			(start -0.12065 -0.305054)
			(end -0.12065 -0.2794)
			(stroke
				(width 0.1)
				(type default)
			)
			(layer "F.Fab")
		)
		(fp_line
			(start -0.12065 -0.2794)
			(end 0.12065 -0.2794)
			(stroke
				(width 0.1)
				(type default)
			)
			(layer "F.Fab")
		)
		(fp_line
			(start -0.12065 0.2794)
			(end -0.12065 0.3048)
			(stroke
				(width 0.1)
				(type default)
			)
			(layer "F.Fab")
		)
		(fp_line
			(start -0.12065 0.3048)
			(end -0.67945 0.3048)
			(stroke
				(width 0.1)
				(type default)
			)
			(layer "F.Fab")
		)
		(fp_line
			(start 0.120396 0.2794)
			(end -0.12065 0.2794)
			(stroke
				(width 0.1)
				(type default)
			)
			(layer "F.Fab")
		)
		(fp_line
			(start 0.120396 0.3048)
			(end 0.120396 0.2794)
			(stroke
				(width 0.1)
				(type default)
			)
			(layer "F.Fab")
		)
		(fp_line
			(start 0.12065 -0.3048)
			(end 0.67945 -0.3048)
			(stroke
				(width 0.1)
				(type default)
			)
			(layer "F.Fab")
		)
		(fp_line
			(start 0.12065 -0.2794)
			(end 0.12065 -0.3048)
			(stroke
				(width 0.1)
				(type default)
			)
			(layer "F.Fab")
		)
		(fp_line
			(start 0.67945 -0.3048)
			(end 0.67945 0.3048)
			(stroke
				(width 0.1)
				(type default)
			)
			(layer "F.Fab")
		)
		(fp_line
			(start 0.67945 0.3048)
			(end 0.120396 0.3048)
			(stroke
				(width 0.1)
				(type default)
			)
			(layer "F.Fab")
		)
		(pad "1" smd circle
			(at -0.40005 0)
			(size 0 0)
			(layers "F.Cu" "F.Mask" "F.Paste")
			(net "SMB_ISO_SSD6_R_SDA")
		)
		(pad "2" smd circle
			(at 0.40005 0)
			(size 0 0)
			(layers "F.Cu" "F.Mask" "F.Paste")
			(net "SMB_ISO_SSD6_SDA")
		)
	)
	(footprint ""
		(layer "F.Cu")
		(at 366.226598 -25.432004 -90)
		(property "Reference" "C977"
			(at 0 0 270)
			(layer "F.SilkS")
			(hide yes)
			(effects
				(font
					(size 1.27 1.27)
				)
			)
		)
		(property "Value" ""
			(at 0 0 270)
			(layer "F.Fab")
			(effects
				(font
					(size 1.27 1.27)
				)
			)
		)
		(duplicate_pad_numbers_are_jumpers no)
		(fp_line
			(start -0.7874 0.4064)
			(end -0.7874 -0.4064)
			(stroke
				(width 0.1524)
				(type default)
			)
			(layer "F.SilkS")
		)
		(fp_line
			(start 0.7874 0.4064)
			(end -0.7874 0.4064)
			(stroke
				(width 0.1524)
				(type default)
			)
			(layer "F.SilkS")
		)
		(fp_line
			(start -0.7874 -0.4064)
			(end 0.7874 -0.4064)
			(stroke
				(width 0.1524)
				(type default)
			)
			(layer "F.SilkS")
		)
		(fp_line
			(start 0.7874 -0.4064)
			(end 0.7874 0.4064)
			(stroke
				(width 0.1524)
				(type default)
			)
			(layer "F.SilkS")
		)
		(fp_line
			(start -0.67945 0.3048)
			(end -0.67945 -0.305054)
			(stroke
				(width 0.1)
				(type default)
			)
			(layer "F.Fab")
		)
		(fp_line
			(start -0.12065 0.3048)
			(end -0.67945 0.3048)
			(stroke
				(width 0.1)
				(type default)
			)
			(layer "F.Fab")
		)
		(fp_line
			(start 0.120396 0.3048)
			(end 0.120396 0.2794)
			(stroke
				(width 0.1)
				(type default)
			)
			(layer "F.Fab")
		)
		(fp_line
			(start 0.67945 0.3048)
			(end 0.120396 0.3048)
			(stroke
				(width 0.1)
				(type default)
			)
			(layer "F.Fab")
		)
		(fp_line
			(start -0.12065 0.2794)
			(end -0.12065 0.3048)
			(stroke
				(width 0.1)
				(type default)
			)
			(layer "F.Fab")
		)
		(fp_line
			(start 0.120396 0.2794)
			(end -0.12065 0.2794)
			(stroke
				(width 0.1)
				(type default)
			)
			(layer "F.Fab")
		)
		(fp_line
			(start -0.12065 -0.2794)
			(end 0.12065 -0.2794)
			(stroke
				(width 0.1)
				(type default)
			)
			(layer "F.Fab")
		)
		(fp_line
			(start 0.12065 -0.2794)
			(end 0.12065 -0.3048)
			(stroke
				(width 0.1)
				(type default)
			)
			(layer "F.Fab")
		)
		(fp_line
			(start 0.12065 -0.3048)
			(end 0.67945 -0.3048)
			(stroke
				(width 0.1)
				(type default)
			)
			(layer "F.Fab")
		)
		(fp_line
			(start 0.67945 -0.3048)
			(end 0.67945 0.3048)
			(stroke
				(width 0.1)
				(type default)
			)
			(layer "F.Fab")
		)
		(fp_line
			(start -0.67945 -0.305054)
			(end -0.12065 -0.305054)
			(stroke
				(width 0.1)
				(type default)
			)
			(layer "F.Fab")
		)
		(fp_line
			(start -0.12065 -0.305054)
			(end -0.12065 -0.2794)
			(stroke
				(width 0.1)
				(type default)
			)
			(layer "F.Fab")
		)
		(pad "1" smd circle
			(at -0.40005 0 270)
			(size 0 0)
			(layers "F.Cu" "F.Mask" "F.Paste")
			(net "GND")
		)
		(pad "2" smd circle
			(at 0.40005 0 270)
			(size 0 0)
			(layers "F.Cu" "F.Mask" "F.Paste")
			(net "P3V3_SSD12")
		)
	)
	(footprint ""
		(layer "F.Cu")
		(at 329.671426 -25.342342 -90)
		(property "Reference" "R442"
			(at 0 0 270)
			(layer "F.SilkS")
			(hide yes)
			(effects
				(font
					(size 1.27 1.27)
				)
			)
		)
		(property "Value" ""
			(at 0 0 270)
			(layer "F.Fab")
			(effects
				(font
					(size 1.27 1.27)
				)
			)
		)
		(duplicate_pad_numbers_are_jumpers no)
		(fp_line
			(start -0.7874 0.4064)
			(end -0.7874 -0.4064)
			(stroke
				(width 0.1524)
				(type default)
			)
			(layer "F.SilkS")
		)
		(fp_line
			(start 0.7874 0.4064)
			(end -0.7874 0.4064)
			(stroke
				(width 0.1524)
				(type default)
			)
			(layer "F.SilkS")
		)
		(fp_line
			(start -0.7874 -0.4064)
			(end 0.7874 -0.4064)
			(stroke
				(width 0.1524)
				(type default)
			)
			(layer "F.SilkS")
		)
		(fp_line
			(start 0.7874 -0.4064)
			(end 0.7874 0.4064)
			(stroke
				(width 0.1524)
				(type default)
			)
			(layer "F.SilkS")
		)
		(fp_line
			(start -0.67945 0.3048)
			(end -0.67945 -0.305054)
			(stroke
				(width 0.1)
				(type default)
			)
			(layer "F.Fab")
		)
		(fp_line
			(start -0.12065 0.3048)
			(end -0.67945 0.3048)
			(stroke
				(width 0.1)
				(type default)
			)
			(layer "F.Fab")
		)
		(fp_line
			(start 0.120396 0.3048)
			(end 0.120396 0.2794)
			(stroke
				(width 0.1)
				(type default)
			)
			(layer "F.Fab")
		)
		(fp_line
			(start 0.67945 0.3048)
			(end 0.120396 0.3048)
			(stroke
				(width 0.1)
				(type default)
			)
			(layer "F.Fab")
		)
		(fp_line
			(start -0.12065 0.2794)
			(end -0.12065 0.3048)
			(stroke
				(width 0.1)
				(type default)
			)
			(layer "F.Fab")
		)
		(fp_line
			(start 0.120396 0.2794)
			(end -0.12065 0.2794)
			(stroke
				(width 0.1)
				(type default)
			)
			(layer "F.Fab")
		)
		(fp_line
			(start -0.12065 -0.2794)
			(end 0.12065 -0.2794)
			(stroke
				(width 0.1)
				(type default)
			)
			(layer "F.Fab")
		)
		(fp_line
			(start 0.12065 -0.2794)
			(end 0.12065 -0.3048)
			(stroke
				(width 0.1)
				(type default)
			)
			(layer "F.Fab")
		)
		(fp_line
			(start 0.12065 -0.3048)
			(end 0.67945 -0.3048)
			(stroke
				(width 0.1)
				(type default)
			)
			(layer "F.Fab")
		)
		(fp_line
			(start 0.67945 -0.3048)
			(end 0.67945 0.3048)
			(stroke
				(width 0.1)
				(type default)
			)
			(layer "F.Fab")
		)
		(fp_line
			(start -0.67945 -0.305054)
			(end -0.12065 -0.305054)
			(stroke
				(width 0.1)
				(type default)
			)
			(layer "F.Fab")
		)
		(fp_line
			(start -0.12065 -0.305054)
			(end -0.12065 -0.2794)
			(stroke
				(width 0.1)
				(type default)
			)
			(layer "F.Fab")
		)
		(pad "1" smd circle
			(at -0.40005 0 270)
			(size 0 0)
			(layers "F.Cu" "F.Mask" "F.Paste")
			(net "P3V3_SSD11")
		)
		(pad "2" smd circle
			(at 0.40005 0 270)
			(size 0 0)
			(layers "F.Cu" "F.Mask" "F.Paste")
			(net "DUALPORT_N_SSD11")
		)
	)
	(footprint ""
		(layer "F.Cu")
		(at 32.417004 -308.852062 -135)
		(property "Reference" "R1259"
			(at 0 0 225)
			(layer "F.SilkS")
			(hide yes)
			(effects
				(font
					(size 1.27 1.27)
				)
			)
		)
		(property "Value" ""
			(at 0 0 225)
			(layer "F.Fab")
			(effects
				(font
					(size 1.27 1.27)
				)
			)
		)
		(duplicate_pad_numbers_are_jumpers no)
		(fp_line
			(start 0.787389 0.406267)
			(end -0.787389 0.406267)
			(stroke
				(width 0.1524)
				(type default)
			)
			(layer "F.SilkS")
		)
		(fp_line
			(start 0.787389 -0.406267)
			(end 0.787389 0.406267)
			(stroke
				(width 0.1524)
				(type default)
			)
			(layer "F.SilkS")
		)
		(fp_line
			(start -0.787389 0.406267)
			(end -0.787389 -0.406267)
			(stroke
				(width 0.1524)
				(type default)
			)
			(layer "F.SilkS")
		)
		(fp_line
			(start -0.787389 -0.406267)
			(end 0.787389 -0.406267)
			(stroke
				(width 0.1524)
				(type default)
			)
			(layer "F.SilkS")
		)
		(fp_line
			(start 0.679446 0.30479)
			(end 0.120515 0.30479)
			(stroke
				(width 0.1)
				(type default)
			)
			(layer "F.Fab")
		)
		(fp_line
			(start 0.120515 0.30479)
			(end 0.120335 0.279466)
			(stroke
				(width 0.1)
				(type default)
			)
			(layer "F.Fab")
		)
		(fp_line
			(start 0.120335 0.279466)
			(end -0.120695 0.279466)
			(stroke
				(width 0.1)
				(type default)
			)
			(layer "F.Fab")
		)
		(fp_line
			(start 0.679446 -0.30479)
			(end 0.679446 0.30479)
			(stroke
				(width 0.1)
				(type default)
			)
			(layer "F.Fab")
		)
		(fp_line
			(start -0.120515 0.30479)
			(end -0.679446 0.30479)
			(stroke
				(width 0.1)
				(type default)
			)
			(layer "F.Fab")
		)
		(fp_line
			(start -0.120695 0.279466)
			(end -0.120515 0.30479)
			(stroke
				(width 0.1)
				(type default)
			)
			(layer "F.Fab")
		)
		(fp_line
			(start 0.120695 -0.279466)
			(end 0.120515 -0.30479)
			(stroke
				(width 0.1)
				(type default)
			)
			(layer "F.Fab")
		)
		(fp_line
			(start 0.120515 -0.30479)
			(end 0.679446 -0.30479)
			(stroke
				(width 0.1)
				(type default)
			)
			(layer "F.Fab")
		)
		(fp_line
			(start -0.679446 0.30479)
			(end -0.679446 -0.305149)
			(stroke
				(width 0.1)
				(type default)
			)
			(layer "F.Fab")
		)
		(fp_line
			(start -0.120695 -0.279466)
			(end 0.120695 -0.279466)
			(stroke
				(width 0.1)
				(type default)
			)
			(layer "F.Fab")
		)
		(fp_line
			(start -0.120695 -0.304969)
			(end -0.120695 -0.279466)
			(stroke
				(width 0.1)
				(type default)
			)
			(layer "F.Fab")
		)
		(fp_line
			(start -0.679446 -0.305149)
			(end -0.120695 -0.304969)
			(stroke
				(width 0.1)
				(type default)
			)
			(layer "F.Fab")
		)
		(pad "1" smd circle
			(at -0.40005 0 225)
			(size 0 0)
			(layers "F.Cu" "F.Mask" "F.Paste")
			(net "PU_PEX0_ATPG_MODE_L")
		)
		(pad "2" smd circle
			(at 0.40005 0 225)
			(size 0 0)
			(layers "F.Cu" "F.Mask" "F.Paste")
			(net "P1V8_PEX")
		)
	)
	(footprint ""
		(layer "F.Cu")
		(at 32.657288 -343.952322 90)
		(property "Reference" "C2163"
			(at 0 0 90)
			(layer "F.SilkS")
			(hide yes)
			(effects
				(font
					(size 1.27 1.27)
				)
			)
		)
		(property "Value" ""
			(at 0 0 90)
			(layer "F.Fab")
			(effects
				(font
					(size 1.27 1.27)
				)
			)
		)
		(duplicate_pad_numbers_are_jumpers no)
		(fp_line
			(start 0.299974 -0.150114)
			(end 0.299974 0.150114)
			(stroke
				(width 0.1)
				(type default)
			)
			(layer "F.Fab")
		)
		(fp_line
			(start -0.299974 -0.150114)
			(end 0.299974 -0.150114)
			(stroke
				(width 0.1)
				(type default)
			)
			(layer "F.Fab")
		)
		(fp_line
			(start 0.299974 0.150114)
			(end -0.299974 0.150114)
			(stroke
				(width 0.1)
				(type default)
			)
			(layer "F.Fab")
		)
		(fp_line
			(start -0.299974 0.150114)
			(end -0.299974 -0.150114)
			(stroke
				(width 0.1)
				(type default)
			)
			(layer "F.Fab")
		)
		(pad "1" smd rect
			(at -0.2667 0 90)
			(size 0.3048 0.381)
			(layers "F.Cu" "F.Mask" "F.Paste")
			(net "P5E_PEX0_STN4_TX_DN<74>")
		)
		(pad "2" smd rect
			(at 0.2667 0 90)
			(size 0.3048 0.381)
			(layers "F.Cu" "F.Mask" "F.Paste")
			(net "P5E_PEX0_STN4_TX_C_DN<74>")
		)
	)
	(footprint ""
		(layer "F.Cu")
		(at 434.141372 -356.244906 90)
		(property "Reference" "C800"
			(at 0 0 90)
			(layer "F.SilkS")
			(hide yes)
			(effects
				(font
					(size 1.27 1.27)
				)
			)
		)
		(property "Value" ""
			(at 0 0 90)
			(layer "F.Fab")
			(effects
				(font
					(size 1.27 1.27)
				)
			)
		)
		(duplicate_pad_numbers_are_jumpers no)
		(fp_line
			(start 0.299974 -0.150114)
			(end 0.299974 0.150114)
			(stroke
				(width 0.1)
				(type default)
			)
			(layer "F.Fab")
		)
		(fp_line
			(start -0.299974 -0.150114)
			(end 0.299974 -0.150114)
			(stroke
				(width 0.1)
				(type default)
			)
			(layer "F.Fab")
		)
		(fp_line
			(start 0.299974 0.150114)
			(end -0.299974 0.150114)
			(stroke
				(width 0.1)
				(type default)
			)
			(layer "F.Fab")
		)
		(fp_line
			(start -0.299974 0.150114)
			(end -0.299974 -0.150114)
			(stroke
				(width 0.1)
				(type default)
			)
			(layer "F.Fab")
		)
		(pad "1" smd rect
			(at -0.2667 0 90)
			(size 0.3048 0.381)
			(layers "F.Cu" "F.Mask" "F.Paste")
			(net "P5E_PEX3_STN7_TX_DP<124>")
		)
		(pad "2" smd rect
			(at 0.2667 0 90)
			(size 0.3048 0.381)
			(layers "F.Cu" "F.Mask" "F.Paste")
			(net "P5E_PEX3_STN7_TX_C_DP<124>")
		)
	)
	(footprint ""
		(layer "F.Cu")
		(at 211.512404 -213.881716 90)
		(property "Reference" "C2571"
			(at 0 0 90)
			(layer "F.SilkS")
			(hide yes)
			(effects
				(font
					(size 1.27 1.27)
				)
			)
		)
		(property "Value" ""
			(at 0 0 90)
			(layer "F.Fab")
			(effects
				(font
					(size 1.27 1.27)
				)
			)
		)
		(duplicate_pad_numbers_are_jumpers no)
		(fp_line
			(start 0.7874 -0.4064)
			(end 0.7874 0.4064)
			(stroke
				(width 0.1524)
				(type default)
			)
			(layer "F.SilkS")
		)
		(fp_line
			(start -0.7874 -0.4064)
			(end 0.7874 -0.4064)
			(stroke
				(width 0.1524)
				(type default)
			)
			(layer "F.SilkS")
		)
		(fp_line
			(start 0.7874 0.4064)
			(end -0.7874 0.4064)
			(stroke
				(width 0.1524)
				(type default)
			)
			(layer "F.SilkS")
		)
		(fp_line
			(start -0.7874 0.4064)
			(end -0.7874 -0.4064)
			(stroke
				(width 0.1524)
				(type default)
			)
			(layer "F.SilkS")
		)
		(fp_line
			(start -0.12065 -0.305054)
			(end -0.12065 -0.2794)
			(stroke
				(width 0.1)
				(type default)
			)
			(layer "F.Fab")
		)
		(fp_line
			(start -0.67945 -0.305054)
			(end -0.12065 -0.305054)
			(stroke
				(width 0.1)
				(type default)
			)
			(layer "F.Fab")
		)
		(fp_line
			(start 0.67945 -0.3048)
			(end 0.67945 0.3048)
			(stroke
				(width 0.1)
				(type default)
			)
			(layer "F.Fab")
		)
		(fp_line
			(start 0.12065 -0.3048)
			(end 0.67945 -0.3048)
			(stroke
				(width 0.1)
				(type default)
			)
			(layer "F.Fab")
		)
		(fp_line
			(start 0.12065 -0.2794)
			(end 0.12065 -0.3048)
			(stroke
				(width 0.1)
				(type default)
			)
			(layer "F.Fab")
		)
		(fp_line
			(start -0.12065 -0.2794)
			(end 0.12065 -0.2794)
			(stroke
				(width 0.1)
				(type default)
			)
			(layer "F.Fab")
		)
		(fp_line
			(start 0.120396 0.2794)
			(end -0.12065 0.2794)
			(stroke
				(width 0.1)
				(type default)
			)
			(layer "F.Fab")
		)
		(fp_line
			(start -0.12065 0.2794)
			(end -0.12065 0.3048)
			(stroke
				(width 0.1)
				(type default)
			)
			(layer "F.Fab")
		)
		(fp_line
			(start 0.67945 0.3048)
			(end 0.120396 0.3048)
			(stroke
				(width 0.1)
				(type default)
			)
			(layer "F.Fab")
		)
		(fp_line
			(start 0.120396 0.3048)
			(end 0.120396 0.2794)
			(stroke
				(width 0.1)
				(type default)
			)
			(layer "F.Fab")
		)
		(fp_line
			(start -0.12065 0.3048)
			(end -0.67945 0.3048)
			(stroke
				(width 0.1)
				(type default)
			)
			(layer "F.Fab")
		)
		(fp_line
			(start -0.67945 0.3048)
			(end -0.67945 -0.305054)
			(stroke
				(width 0.1)
				(type default)
			)
			(layer "F.Fab")
		)
		(pad "1" smd circle
			(at -0.40005 0 90)
			(size 0 0)
			(layers "F.Cu" "F.Mask" "F.Paste")
			(net "GND")
		)
		(pad "2" smd circle
			(at 0.40005 0 90)
			(size 0 0)
			(layers "F.Cu" "F.Mask" "F.Paste")
			(net "P3V3_AUX")
		)
	)
	(footprint ""
		(layer "F.Cu")
		(at 104.243632 -45.88891)
		(property "Reference" "R543"
			(at 0 0 0)
			(layer "F.SilkS")
			(hide yes)
			(effects
				(font
					(size 1.27 1.27)
				)
			)
		)
		(property "Value" ""
			(at 0 0 0)
			(layer "F.Fab")
			(effects
				(font
					(size 1.27 1.27)
				)
			)
		)
		(duplicate_pad_numbers_are_jumpers no)
		(fp_line
			(start -0.7874 -0.4064)
			(end 0.7874 -0.4064)
			(stroke
				(width 0.1524)
				(type default)
			)
			(layer "F.SilkS")
		)
		(fp_line
			(start -0.7874 0.4064)
			(end -0.7874 -0.4064)
			(stroke
				(width 0.1524)
				(type default)
			)
			(layer "F.SilkS")
		)
		(fp_line
			(start 0.7874 -0.4064)
			(end 0.7874 0.4064)
			(stroke
				(width 0.1524)
				(type default)
			)
			(layer "F.SilkS")
		)
		(fp_line
			(start 0.7874 0.4064)
			(end -0.7874 0.4064)
			(stroke
				(width 0.1524)
				(type default)
			)
			(layer "F.SilkS")
		)
		(fp_line
			(start -0.67945 -0.305054)
			(end -0.12065 -0.305054)
			(stroke
				(width 0.1)
				(type default)
			)
			(layer "F.Fab")
		)
		(fp_line
			(start -0.67945 0.3048)
			(end -0.67945 -0.305054)
			(stroke
				(width 0.1)
				(type default)
			)
			(layer "F.Fab")
		)
		(fp_line
			(start -0.12065 -0.305054)
			(end -0.12065 -0.2794)
			(stroke
				(width 0.1)
				(type default)
			)
			(layer "F.Fab")
		)
		(fp_line
			(start -0.12065 -0.2794)
			(end 0.12065 -0.2794)
			(stroke
				(width 0.1)
				(type default)
			)
			(layer "F.Fab")
		)
		(fp_line
			(start -0.12065 0.2794)
			(end -0.12065 0.3048)
			(stroke
				(width 0.1)
				(type default)
			)
			(layer "F.Fab")
		)
		(fp_line
			(start -0.12065 0.3048)
			(end -0.67945 0.3048)
			(stroke
				(width 0.1)
				(type default)
			)
			(layer "F.Fab")
		)
		(fp_line
			(start 0.120396 0.2794)
			(end -0.12065 0.2794)
			(stroke
				(width 0.1)
				(type default)
			)
			(layer "F.Fab")
		)
		(fp_line
			(start 0.120396 0.3048)
			(end 0.120396 0.2794)
			(stroke
				(width 0.1)
				(type default)
			)
			(layer "F.Fab")
		)
		(fp_line
			(start 0.12065 -0.3048)
			(end 0.67945 -0.3048)
			(stroke
				(width 0.1)
				(type default)
			)
			(layer "F.Fab")
		)
		(fp_line
			(start 0.12065 -0.2794)
			(end 0.12065 -0.3048)
			(stroke
				(width 0.1)
				(type default)
			)
			(layer "F.Fab")
		)
		(fp_line
			(start 0.67945 -0.3048)
			(end 0.67945 0.3048)
			(stroke
				(width 0.1)
				(type default)
			)
			(layer "F.Fab")
		)
		(fp_line
			(start 0.67945 0.3048)
			(end 0.120396 0.3048)
			(stroke
				(width 0.1)
				(type default)
			)
			(layer "F.Fab")
		)
		(pad "1" smd circle
			(at -0.40005 0)
			(size 0 0)
			(layers "F.Cu" "F.Mask" "F.Paste")
			(net "SSD3_ADC_A0")
		)
		(pad "2" smd circle
			(at 0.40005 0)
			(size 0 0)
			(layers "F.Cu" "F.Mask" "F.Paste")
			(net "GND")
		)
	)
	(footprint ""
		(layer "F.Cu")
		(at 102.027736 -275.813774 180)
		(property "Reference" "PC6610"
			(at 0 0 180)
			(layer "F.SilkS")
			(hide yes)
			(effects
				(font
					(size 1.27 1.27)
				)
			)
		)
		(property "Value" ""
			(at 0 0 180)
			(layer "F.Fab")
			(effects
				(font
					(size 1.27 1.27)
				)
			)
		)
		(duplicate_pad_numbers_are_jumpers no)
		(fp_line
			(start 1.524 0.762)
			(end -1.524 0.762)
			(stroke
				(width 0.1524)
				(type default)
			)
			(layer "F.SilkS")
		)
		(fp_line
			(start 1.524 -0.762)
			(end 1.524 0.762)
			(stroke
				(width 0.1524)
				(type default)
			)
			(layer "F.SilkS")
		)
		(fp_line
			(start -1.524 0.762)
			(end -1.524 -0.762)
			(stroke
				(width 0.1524)
				(type default)
			)
			(layer "F.SilkS")
		)
		(fp_line
			(start -1.524 -0.762)
			(end 1.524 -0.762)
			(stroke
				(width 0.1524)
				(type default)
			)
			(layer "F.SilkS")
		)
		(fp_line
			(start 1.1049 0.724916)
			(end 1.1049 -0.724916)
			(stroke
				(width 0.1)
				(type default)
			)
			(layer "F.Fab")
		)
		(fp_line
			(start 1.1049 -0.724916)
			(end -1.1049 -0.724916)
			(stroke
				(width 0.1)
				(type default)
			)
			(layer "F.Fab")
		)
		(fp_line
			(start -1.1049 0.724916)
			(end 1.1049 0.724916)
			(stroke
				(width 0.1)
				(type default)
			)
			(layer "F.Fab")
		)
		(fp_line
			(start -1.1049 -0.724916)
			(end -1.1049 0.724916)
			(stroke
				(width 0.1)
				(type default)
			)
			(layer "F.Fab")
		)
		(pad "1" smd rect
			(at -0.889 0)
			(size 1.016 1.27)
			(layers "F.Cu" "F.Mask" "F.Paste")
			(net "SW_P12V_P0V8_PEX0_FLT")
		)
		(pad "2" smd rect
			(at 0.889 0)
			(size 1.016 1.27)
			(layers "F.Cu" "F.Mask" "F.Paste")
			(net "GND")
		)
	)
	(footprint ""
		(layer "F.Cu")
		(at 429.175164 -63.086234)
		(property "Reference" "R6029"
			(at 0 0 0)
			(layer "F.SilkS")
			(hide yes)
			(effects
				(font
					(size 1.27 1.27)
				)
			)
		)
		(property "Value" ""
			(at 0 0 0)
			(layer "F.Fab")
			(effects
				(font
					(size 1.27 1.27)
				)
			)
		)
		(duplicate_pad_numbers_are_jumpers no)
		(fp_line
			(start -0.7874 -0.4064)
			(end 0.7874 -0.4064)
			(stroke
				(width 0.1524)
				(type default)
			)
			(layer "F.SilkS")
		)
		(fp_line
			(start -0.7874 0.4064)
			(end -0.7874 -0.4064)
			(stroke
				(width 0.1524)
				(type default)
			)
			(layer "F.SilkS")
		)
		(fp_line
			(start 0.7874 -0.4064)
			(end 0.7874 0.4064)
			(stroke
				(width 0.1524)
				(type default)
			)
			(layer "F.SilkS")
		)
		(fp_line
			(start 0.7874 0.4064)
			(end -0.7874 0.4064)
			(stroke
				(width 0.1524)
				(type default)
			)
			(layer "F.SilkS")
		)
		(fp_line
			(start -0.67945 -0.305054)
			(end -0.12065 -0.305054)
			(stroke
				(width 0.1)
				(type default)
			)
			(layer "F.Fab")
		)
		(fp_line
			(start -0.67945 0.3048)
			(end -0.67945 -0.305054)
			(stroke
				(width 0.1)
				(type default)
			)
			(layer "F.Fab")
		)
		(fp_line
			(start -0.12065 -0.305054)
			(end -0.12065 -0.2794)
			(stroke
				(width 0.1)
				(type default)
			)
			(layer "F.Fab")
		)
		(fp_line
			(start -0.12065 -0.2794)
			(end 0.12065 -0.2794)
			(stroke
				(width 0.1)
				(type default)
			)
			(layer "F.Fab")
		)
		(fp_line
			(start -0.12065 0.2794)
			(end -0.12065 0.3048)
			(stroke
				(width 0.1)
				(type default)
			)
			(layer "F.Fab")
		)
		(fp_line
			(start -0.12065 0.3048)
			(end -0.67945 0.3048)
			(stroke
				(width 0.1)
				(type default)
			)
			(layer "F.Fab")
		)
		(fp_line
			(start 0.120396 0.2794)
			(end -0.12065 0.2794)
			(stroke
				(width 0.1)
				(type default)
			)
			(layer "F.Fab")
		)
		(fp_line
			(start 0.120396 0.3048)
			(end 0.120396 0.2794)
			(stroke
				(width 0.1)
				(type default)
			)
			(layer "F.Fab")
		)
		(fp_line
			(start 0.12065 -0.3048)
			(end 0.67945 -0.3048)
			(stroke
				(width 0.1)
				(type default)
			)
			(layer "F.Fab")
		)
		(fp_line
			(start 0.12065 -0.2794)
			(end 0.12065 -0.3048)
			(stroke
				(width 0.1)
				(type default)
			)
			(layer "F.Fab")
		)
		(fp_line
			(start 0.67945 -0.3048)
			(end 0.67945 0.3048)
			(stroke
				(width 0.1)
				(type default)
			)
			(layer "F.Fab")
		)
		(fp_line
			(start 0.67945 0.3048)
			(end 0.120396 0.3048)
			(stroke
				(width 0.1)
				(type default)
			)
			(layer "F.Fab")
		)
		(pad "1" smd circle
			(at -0.40005 0)
			(size 0 0)
			(layers "F.Cu" "F.Mask" "F.Paste")
			(net "P12V_SSD15_R")
		)
		(pad "2" smd circle
			(at 0.40005 0)
			(size 0 0)
			(layers "F.Cu" "F.Mask" "F.Paste")
			(net "P12V_SSD15_PG_G1")
		)
	)
	(footprint ""
		(layer "F.Cu")
		(at 212.451442 -244.016276 90)
		(property "Reference" "R1537"
			(at 0 0 90)
			(layer "F.SilkS")
			(hide yes)
			(effects
				(font
					(size 1.27 1.27)
				)
			)
		)
		(property "Value" ""
			(at 0 0 90)
			(layer "F.Fab")
			(effects
				(font
					(size 1.27 1.27)
				)
			)
		)
		(duplicate_pad_numbers_are_jumpers no)
		(fp_line
			(start 0.7874 -0.4064)
			(end 0.7874 0.4064)
			(stroke
				(width 0.1524)
				(type default)
			)
			(layer "F.SilkS")
		)
		(fp_line
			(start -0.7874 -0.4064)
			(end 0.7874 -0.4064)
			(stroke
				(width 0.1524)
				(type default)
			)
			(layer "F.SilkS")
		)
		(fp_line
			(start 0.7874 0.4064)
			(end -0.7874 0.4064)
			(stroke
				(width 0.1524)
				(type default)
			)
			(layer "F.SilkS")
		)
		(fp_line
			(start -0.7874 0.4064)
			(end -0.7874 -0.4064)
			(stroke
				(width 0.1524)
				(type default)
			)
			(layer "F.SilkS")
		)
		(fp_line
			(start -0.12065 -0.305054)
			(end -0.12065 -0.2794)
			(stroke
				(width 0.1)
				(type default)
			)
			(layer "F.Fab")
		)
		(fp_line
			(start -0.67945 -0.305054)
			(end -0.12065 -0.305054)
			(stroke
				(width 0.1)
				(type default)
			)
			(layer "F.Fab")
		)
		(fp_line
			(start 0.67945 -0.3048)
			(end 0.67945 0.3048)
			(stroke
				(width 0.1)
				(type default)
			)
			(layer "F.Fab")
		)
		(fp_line
			(start 0.12065 -0.3048)
			(end 0.67945 -0.3048)
			(stroke
				(width 0.1)
				(type default)
			)
			(layer "F.Fab")
		)
		(fp_line
			(start 0.12065 -0.2794)
			(end 0.12065 -0.3048)
			(stroke
				(width 0.1)
				(type default)
			)
			(layer "F.Fab")
		)
		(fp_line
			(start -0.12065 -0.2794)
			(end 0.12065 -0.2794)
			(stroke
				(width 0.1)
				(type default)
			)
			(layer "F.Fab")
		)
		(fp_line
			(start 0.120396 0.2794)
			(end -0.12065 0.2794)
			(stroke
				(width 0.1)
				(type default)
			)
			(layer "F.Fab")
		)
		(fp_line
			(start -0.12065 0.2794)
			(end -0.12065 0.3048)
			(stroke
				(width 0.1)
				(type default)
			)
			(layer "F.Fab")
		)
		(fp_line
			(start 0.67945 0.3048)
			(end 0.120396 0.3048)
			(stroke
				(width 0.1)
				(type default)
			)
			(layer "F.Fab")
		)
		(fp_line
			(start 0.120396 0.3048)
			(end 0.120396 0.2794)
			(stroke
				(width 0.1)
				(type default)
			)
			(layer "F.Fab")
		)
		(fp_line
			(start -0.12065 0.3048)
			(end -0.67945 0.3048)
			(stroke
				(width 0.1)
				(type default)
			)
			(layer "F.Fab")
		)
		(fp_line
			(start -0.67945 0.3048)
			(end -0.67945 -0.305054)
			(stroke
				(width 0.1)
				(type default)
			)
			(layer "F.Fab")
		)
		(pad "1" smd circle
			(at -0.40005 0 90)
			(size 0 0)
			(layers "F.Cu" "F.Mask" "F.Paste")
			(net "SMB_PEX_R_SDA")
		)
		(pad "2" smd circle
			(at 0.40005 0 90)
			(size 0 0)
			(layers "F.Cu" "F.Mask" "F.Paste")
			(net "P3V3_AUX")
		)
	)
	(footprint ""
		(layer "F.Cu")
		(at 121.108978 -88.39073)
		(property "Reference" "R1561"
			(at 0 0 0)
			(layer "F.SilkS")
			(hide yes)
			(effects
				(font
					(size 1.27 1.27)
				)
			)
		)
		(property "Value" ""
			(at 0 0 0)
			(layer "F.Fab")
			(effects
				(font
					(size 1.27 1.27)
				)
			)
		)
		(duplicate_pad_numbers_are_jumpers no)
		(fp_line
			(start -0.7874 -0.4064)
			(end 0.7874 -0.4064)
			(stroke
				(width 0.1524)
				(type default)
			)
			(layer "F.SilkS")
		)
		(fp_line
			(start -0.7874 0.4064)
			(end -0.7874 -0.4064)
			(stroke
				(width 0.1524)
				(type default)
			)
			(layer "F.SilkS")
		)
		(fp_line
			(start 0.7874 -0.4064)
			(end 0.7874 0.4064)
			(stroke
				(width 0.1524)
				(type default)
			)
			(layer "F.SilkS")
		)
		(fp_line
			(start 0.7874 0.4064)
			(end -0.7874 0.4064)
			(stroke
				(width 0.1524)
				(type default)
			)
			(layer "F.SilkS")
		)
		(fp_line
			(start -0.67945 -0.305054)
			(end -0.12065 -0.305054)
			(stroke
				(width 0.1)
				(type default)
			)
			(layer "F.Fab")
		)
		(fp_line
			(start -0.67945 0.3048)
			(end -0.67945 -0.305054)
			(stroke
				(width 0.1)
				(type default)
			)
			(layer "F.Fab")
		)
		(fp_line
			(start -0.12065 -0.305054)
			(end -0.12065 -0.2794)
			(stroke
				(width 0.1)
				(type default)
			)
			(layer "F.Fab")
		)
		(fp_line
			(start -0.12065 -0.2794)
			(end 0.12065 -0.2794)
			(stroke
				(width 0.1)
				(type default)
			)
			(layer "F.Fab")
		)
		(fp_line
			(start -0.12065 0.2794)
			(end -0.12065 0.3048)
			(stroke
				(width 0.1)
				(type default)
			)
			(layer "F.Fab")
		)
		(fp_line
			(start -0.12065 0.3048)
			(end -0.67945 0.3048)
			(stroke
				(width 0.1)
				(type default)
			)
			(layer "F.Fab")
		)
		(fp_line
			(start 0.120396 0.2794)
			(end -0.12065 0.2794)
			(stroke
				(width 0.1)
				(type default)
			)
			(layer "F.Fab")
		)
		(fp_line
			(start 0.120396 0.3048)
			(end 0.120396 0.2794)
			(stroke
				(width 0.1)
				(type default)
			)
			(layer "F.Fab")
		)
		(fp_line
			(start 0.12065 -0.3048)
			(end 0.67945 -0.3048)
			(stroke
				(width 0.1)
				(type default)
			)
			(layer "F.Fab")
		)
		(fp_line
			(start 0.12065 -0.2794)
			(end 0.12065 -0.3048)
			(stroke
				(width 0.1)
				(type default)
			)
			(layer "F.Fab")
		)
		(fp_line
			(start 0.67945 -0.3048)
			(end 0.67945 0.3048)
			(stroke
				(width 0.1)
				(type default)
			)
			(layer "F.Fab")
		)
		(fp_line
			(start 0.67945 0.3048)
			(end 0.120396 0.3048)
			(stroke
				(width 0.1)
				(type default)
			)
			(layer "F.Fab")
		)
		(pad "1" smd circle
			(at -0.40005 0)
			(size 0 0)
			(layers "F.Cu" "F.Mask" "F.Paste")
			(net "P3V3_AUX")
		)
		(pad "2" smd circle
			(at 0.40005 0)
			(size 0 0)
			(layers "F.Cu" "F.Mask" "F.Paste")
			(net "SMB_BIC_I2C9_MUX0_SSD3_R_SCL")
		)
	)
	(footprint ""
		(layer "F.Cu")
		(at 29.649674 -270.89989)
		(property "Reference" "H94"
			(at 4.294632 7.569962 0)
			(unlocked yes)
			(layer "F.SilkS")
			(effects
				(font
					(size 0.7874 0.5842)
					(thickness 0.1524)
				)
				(justify left)
			)
		)
		(property "Value" ""
			(at 0 0 0)
			(layer "F.Fab")
			(effects
				(font
					(size 1.27 1.27)
				)
			)
		)
		(duplicate_pad_numbers_are_jumpers no)
		(fp_arc
			(start 7.975854 -0.620014)
			(mid 7.993928 -0.310241)
			(end 7.999984 0)
			(stroke
				(width 0.1524)
				(type default)
			)
			(layer "F.SilkS")
		)
		(fp_arc
			(start 7.999984 0)
			(mid -7.46541 2.875054)
			(end 5.932932 -5.366766)
			(stroke
				(width 0.1524)
				(type default)
			)
			(layer "F.SilkS")
		)
		(fp_circle
			(center 0 0)
			(end 7.999984 0)
			(stroke
				(width 0.1524)
				(type default)
			)
			(fill no)
			(layer "B.SilkS")
		)
		(fp_circle
			(center 0 0)
			(end 7.999984 0)
			(stroke
				(width 0.1)
				(type default)
			)
			(fill no)
			(layer "B.Fab")
		)
		(fp_circle
			(center 0 0)
			(end 7.999984 0)
			(stroke
				(width 0.1)
				(type default)
			)
			(fill no)
			(layer "F.Fab")
		)
		(pad "" np_thru_hole circle
			(at 0 0)
			(size 4.5212 4.5212)
			(drill 4.5212)
			(layers "*.Cu" "*.Mask")
			(clearance 0.381)
			(thermal_gap 0.381)
		)
		(pad "2" thru_hole circle
			(at 3.6322 0)
			(size 0.762 0.762)
			(drill 0.5588)
			(layers "*.Cu" "*.Mask")
			(remove_unused_layers no)
			(net "GND")
			(clearance 0.1524)
			(thermal_gap 0.1524)
		)
		(pad "3" thru_hole circle
			(at 2.568448 -2.568448)
			(size 0.762 0.762)
			(drill 0.5588)
			(layers "*.Cu" "*.Mask")
			(remove_unused_layers no)
			(net "GND")
			(clearance 0.1524)
			(thermal_gap 0.1524)
		)
		(pad "4" thru_hole circle
			(at 0 -3.6322)
			(size 0.762 0.762)
			(drill 0.5588)
			(layers "*.Cu" "*.Mask")
			(remove_unused_layers no)
			(net "GND")
			(clearance 0.1524)
			(thermal_gap 0.1524)
		)
		(pad "5" thru_hole circle
			(at -2.568448 -2.568448)
			(size 0.762 0.762)
			(drill 0.5588)
			(layers "*.Cu" "*.Mask")
			(remove_unused_layers no)
			(net "GND")
			(clearance 0.1524)
			(thermal_gap 0.1524)
		)
		(pad "6" thru_hole circle
			(at -3.6322 0)
			(size 0.762 0.762)
			(drill 0.5588)
			(layers "*.Cu" "*.Mask")
			(remove_unused_layers no)
			(net "GND")
			(clearance 0.1524)
			(thermal_gap 0.1524)
		)
		(pad "7" thru_hole circle
			(at -2.568448 2.568448)
			(size 0.762 0.762)
			(drill 0.5588)
			(layers "*.Cu" "*.Mask")
			(remove_unused_layers no)
			(net "GND")
			(clearance 0.1524)
			(thermal_gap 0.1524)
		)
		(pad "8" thru_hole circle
			(at 0 3.6322)
			(size 0.762 0.762)
			(drill 0.5588)
			(layers "*.Cu" "*.Mask")
			(remove_unused_layers no)
			(net "GND")
			(clearance 0.1524)
			(thermal_gap 0.1524)
		)
		(pad "9" thru_hole circle
			(at 2.568448 2.568448)
			(size 0.762 0.762)
			(drill 0.5588)
			(layers "*.Cu" "*.Mask")
			(remove_unused_layers no)
			(net "GND")
			(clearance 0.1524)
			(thermal_gap 0.1524)
		)
		(zone
			(layer "F.Cu")
			(hatch none 0.5)
			(connect_pads
				(clearance 0)
			)
			(min_thickness 0.25)
			(keepout
				(tracks not_allowed)
				(vias allowed)
				(pads allowed)
				(copperpour not_allowed)
				(footprints allowed)
			)
			(placement
				(enabled no)
				(sheetname "")
			)
			(fill
				(thermal_gap 0.5)
				(thermal_bridge_width 0.5)
				(island_removal_mode 0)
			)
			(polygon
				(pts
					(arc
						(start 29.649674 -262.899906)
						(mid 21.64969 -270.89989)
						(end 29.649674 -278.899874)
					)
					(arc
						(start 29.649674 -275.64969)
						(mid 24.899874 -270.89989)
						(end 29.649674 -266.15009)
					)
				)
			)
		)
		(zone
			(layer "F.Cu")
			(hatch none 0.5)
			(connect_pads
				(clearance 0)
			)
			(min_thickness 0.25)
			(keepout
				(tracks not_allowed)
				(vias allowed)
				(pads allowed)
				(copperpour not_allowed)
				(footprints allowed)
			)
			(placement
				(enabled no)
				(sheetname "")
			)
			(fill
				(thermal_gap 0.5)
				(thermal_bridge_width 0.5)
				(island_removal_mode 0)
			)
			(polygon
				(pts
					(arc
						(start 29.649674 -262.899906)
						(mid 37.649658 -270.89989)
						(end 29.649674 -278.899874)
					)
					(arc
						(start 29.649674 -275.64969)
						(mid 34.399474 -270.89989)
						(end 29.649674 -266.15009)
					)
				)
			)
		)
		(zone
			(layers "F.Cu" "B.Cu" "In1.Cu" "In2.Cu" "In3.Cu" "In4.Cu" "In5.Cu" "In6.Cu"
				"In7.Cu" "In8.Cu" "In9.Cu" "In10.Cu" "In11.Cu" "In12.Cu" "In13.Cu" "In14.Cu"
				"In15.Cu" "In16.Cu"
			)
			(hatch none 0.5)
			(connect_pads
				(clearance 0)
			)
			(min_thickness 0.25)
			(keepout
				(tracks not_allowed)
				(vias allowed)
				(pads allowed)
				(copperpour not_allowed)
				(footprints allowed)
			)
			(placement
				(enabled no)
				(sheetname "")
			)
			(fill
				(thermal_gap 0.5)
				(thermal_bridge_width 0.5)
				(island_removal_mode 0)
			)
			(polygon
				(pts
					(arc
						(start 32.415734 -270.89989)
						(mid 26.883614 -270.89989)
						(end 32.415734 -270.89989)
					)
				)
			)
		)
		(zone
			(layer "B.Cu")
			(hatch none 0.5)
			(connect_pads
				(clearance 0)
			)
			(min_thickness 0.25)
			(keepout
				(tracks not_allowed)
				(vias allowed)
				(pads allowed)
				(copperpour not_allowed)
				(footprints allowed)
			)
			(placement
				(enabled no)
				(sheetname "")
			)
			(fill
				(thermal_gap 0.5)
				(thermal_bridge_width 0.5)
				(island_removal_mode 0)
			)
			(polygon
				(pts
					(arc
						(start 29.649674 -265.89609)
						(mid 24.645874 -270.89989)
						(end 29.649674 -275.90369)
					)
					(arc
						(start 29.649674 -275.42109)
						(mid 25.128474 -270.89989)
						(end 29.649674 -266.37869)
					)
				)
			)
		)
		(zone
			(layer "B.Cu")
			(hatch none 0.5)
			(connect_pads
				(clearance 0)
			)
			(min_thickness 0.25)
			(keepout
				(tracks not_allowed)
				(vias allowed)
				(pads allowed)
				(copperpour not_allowed)
				(footprints allowed)
			)
			(placement
				(enabled no)
				(sheetname "")
			)
			(fill
				(thermal_gap 0.5)
				(thermal_bridge_width 0.5)
				(island_removal_mode 0)
			)
			(polygon
				(pts
					(arc
						(start 29.649674 -265.89609)
						(mid 34.653474 -270.89989)
						(end 29.649674 -275.90369)
					)
					(arc
						(start 29.649674 -275.42109)
						(mid 34.170874 -270.89989)
						(end 29.649674 -266.37869)
					)
				)
			)
		)
	)
	(footprint ""
		(layer "F.Cu")
		(at 311.532016 -32.848042 90)
		(property "Reference" "PC957"
			(at 0 0 90)
			(layer "F.SilkS")
			(hide yes)
			(effects
				(font
					(size 1.27 1.27)
				)
			)
		)
		(property "Value" ""
			(at 0 0 90)
			(layer "F.Fab")
			(effects
				(font
					(size 1.27 1.27)
				)
			)
		)
		(duplicate_pad_numbers_are_jumpers no)
		(fp_line
			(start 0.7874 -0.4064)
			(end 0.7874 0.4064)
			(stroke
				(width 0.1524)
				(type default)
			)
			(layer "F.SilkS")
		)
		(fp_line
			(start -0.7874 -0.4064)
			(end 0.7874 -0.4064)
			(stroke
				(width 0.1524)
				(type default)
			)
			(layer "F.SilkS")
		)
		(fp_line
			(start 0.7874 0.4064)
			(end -0.7874 0.4064)
			(stroke
				(width 0.1524)
				(type default)
			)
			(layer "F.SilkS")
		)
		(fp_line
			(start -0.7874 0.4064)
			(end -0.7874 -0.4064)
			(stroke
				(width 0.1524)
				(type default)
			)
			(layer "F.SilkS")
		)
		(fp_line
			(start -0.12065 -0.305054)
			(end -0.12065 -0.2794)
			(stroke
				(width 0.1)
				(type default)
			)
			(layer "F.Fab")
		)
		(fp_line
			(start -0.67945 -0.305054)
			(end -0.12065 -0.305054)
			(stroke
				(width 0.1)
				(type default)
			)
			(layer "F.Fab")
		)
		(fp_line
			(start 0.67945 -0.3048)
			(end 0.67945 0.3048)
			(stroke
				(width 0.1)
				(type default)
			)
			(layer "F.Fab")
		)
		(fp_line
			(start 0.12065 -0.3048)
			(end 0.67945 -0.3048)
			(stroke
				(width 0.1)
				(type default)
			)
			(layer "F.Fab")
		)
		(fp_line
			(start 0.12065 -0.2794)
			(end 0.12065 -0.3048)
			(stroke
				(width 0.1)
				(type default)
			)
			(layer "F.Fab")
		)
		(fp_line
			(start -0.12065 -0.2794)
			(end 0.12065 -0.2794)
			(stroke
				(width 0.1)
				(type default)
			)
			(layer "F.Fab")
		)
		(fp_line
			(start 0.120396 0.2794)
			(end -0.12065 0.2794)
			(stroke
				(width 0.1)
				(type default)
			)
			(layer "F.Fab")
		)
		(fp_line
			(start -0.12065 0.2794)
			(end -0.12065 0.3048)
			(stroke
				(width 0.1)
				(type default)
			)
			(layer "F.Fab")
		)
		(fp_line
			(start 0.67945 0.3048)
			(end 0.120396 0.3048)
			(stroke
				(width 0.1)
				(type default)
			)
			(layer "F.Fab")
		)
		(fp_line
			(start 0.120396 0.3048)
			(end 0.120396 0.2794)
			(stroke
				(width 0.1)
				(type default)
			)
			(layer "F.Fab")
		)
		(fp_line
			(start -0.12065 0.3048)
			(end -0.67945 0.3048)
			(stroke
				(width 0.1)
				(type default)
			)
			(layer "F.Fab")
		)
		(fp_line
			(start -0.67945 0.3048)
			(end -0.67945 -0.305054)
			(stroke
				(width 0.1)
				(type default)
			)
			(layer "F.Fab")
		)
		(pad "1" smd circle
			(at -0.40005 0 90)
			(size 0 0)
			(layers "F.Cu" "F.Mask" "F.Paste")
			(net "P3V3_SSD11_CO_DV_DT")
		)
		(pad "2" smd circle
			(at 0.40005 0 90)
			(size 0 0)
			(layers "F.Cu" "F.Mask" "F.Paste")
			(net "GND")
		)
	)
	(footprint ""
		(layer "F.Cu")
		(at 16.702786 -112.139476 -90)
		(property "Reference" "PC664"
			(at 0 0 270)
			(layer "F.SilkS")
			(hide yes)
			(effects
				(font
					(size 1.27 1.27)
				)
			)
		)
		(property "Value" ""
			(at 0 0 270)
			(layer "F.Fab")
			(effects
				(font
					(size 1.27 1.27)
				)
			)
		)
		(duplicate_pad_numbers_are_jumpers no)
		(fp_line
			(start -0.7874 0.4064)
			(end -0.7874 -0.4064)
			(stroke
				(width 0.1524)
				(type default)
			)
			(layer "F.SilkS")
		)
		(fp_line
			(start 0.7874 0.4064)
			(end -0.7874 0.4064)
			(stroke
				(width 0.1524)
				(type default)
			)
			(layer "F.SilkS")
		)
		(fp_line
			(start -0.7874 -0.4064)
			(end 0.7874 -0.4064)
			(stroke
				(width 0.1524)
				(type default)
			)
			(layer "F.SilkS")
		)
		(fp_line
			(start 0.7874 -0.4064)
			(end 0.7874 0.4064)
			(stroke
				(width 0.1524)
				(type default)
			)
			(layer "F.SilkS")
		)
		(fp_line
			(start -0.67945 0.3048)
			(end -0.67945 -0.305054)
			(stroke
				(width 0.1)
				(type default)
			)
			(layer "F.Fab")
		)
		(fp_line
			(start -0.12065 0.3048)
			(end -0.67945 0.3048)
			(stroke
				(width 0.1)
				(type default)
			)
			(layer "F.Fab")
		)
		(fp_line
			(start 0.120396 0.3048)
			(end 0.120396 0.2794)
			(stroke
				(width 0.1)
				(type default)
			)
			(layer "F.Fab")
		)
		(fp_line
			(start 0.67945 0.3048)
			(end 0.120396 0.3048)
			(stroke
				(width 0.1)
				(type default)
			)
			(layer "F.Fab")
		)
		(fp_line
			(start -0.12065 0.2794)
			(end -0.12065 0.3048)
			(stroke
				(width 0.1)
				(type default)
			)
			(layer "F.Fab")
		)
		(fp_line
			(start 0.120396 0.2794)
			(end -0.12065 0.2794)
			(stroke
				(width 0.1)
				(type default)
			)
			(layer "F.Fab")
		)
		(fp_line
			(start -0.12065 -0.2794)
			(end 0.12065 -0.2794)
			(stroke
				(width 0.1)
				(type default)
			)
			(layer "F.Fab")
		)
		(fp_line
			(start 0.12065 -0.2794)
			(end 0.12065 -0.3048)
			(stroke
				(width 0.1)
				(type default)
			)
			(layer "F.Fab")
		)
		(fp_line
			(start 0.12065 -0.3048)
			(end 0.67945 -0.3048)
			(stroke
				(width 0.1)
				(type default)
			)
			(layer "F.Fab")
		)
		(fp_line
			(start 0.67945 -0.3048)
			(end 0.67945 0.3048)
			(stroke
				(width 0.1)
				(type default)
			)
			(layer "F.Fab")
		)
		(fp_line
			(start -0.67945 -0.305054)
			(end -0.12065 -0.305054)
			(stroke
				(width 0.1)
				(type default)
			)
			(layer "F.Fab")
		)
		(fp_line
			(start -0.12065 -0.305054)
			(end -0.12065 -0.2794)
			(stroke
				(width 0.1)
				(type default)
			)
			(layer "F.Fab")
		)
		(pad "1" smd circle
			(at -0.40005 0 270)
			(size 0 0)
			(layers "F.Cu" "F.Mask" "F.Paste")
			(net "P3V3_NIC0_CO_MODE")
		)
		(pad "2" smd circle
			(at 0.40005 0 270)
			(size 0 0)
			(layers "F.Cu" "F.Mask" "F.Paste")
			(net "GND")
		)
	)
	(footprint ""
		(layer "F.Cu")
		(at 327.008998 -95.041466 -90)
		(property "Reference" "PC327"
			(at 0 0 270)
			(layer "F.SilkS")
			(hide yes)
			(effects
				(font
					(size 1.27 1.27)
				)
			)
		)
		(property "Value" ""
			(at 0 0 270)
			(layer "F.Fab")
			(effects
				(font
					(size 1.27 1.27)
				)
			)
		)
		(duplicate_pad_numbers_are_jumpers no)
		(fp_line
			(start -0.7874 0.4064)
			(end -0.7874 -0.4064)
			(stroke
				(width 0.1524)
				(type default)
			)
			(layer "F.SilkS")
		)
		(fp_line
			(start 0.7874 0.4064)
			(end -0.7874 0.4064)
			(stroke
				(width 0.1524)
				(type default)
			)
			(layer "F.SilkS")
		)
		(fp_line
			(start -0.7874 -0.4064)
			(end 0.7874 -0.4064)
			(stroke
				(width 0.1524)
				(type default)
			)
			(layer "F.SilkS")
		)
		(fp_line
			(start 0.7874 -0.4064)
			(end 0.7874 0.4064)
			(stroke
				(width 0.1524)
				(type default)
			)
			(layer "F.SilkS")
		)
		(fp_line
			(start -0.67945 0.3048)
			(end -0.67945 -0.305054)
			(stroke
				(width 0.1)
				(type default)
			)
			(layer "F.Fab")
		)
		(fp_line
			(start -0.12065 0.3048)
			(end -0.67945 0.3048)
			(stroke
				(width 0.1)
				(type default)
			)
			(layer "F.Fab")
		)
		(fp_line
			(start 0.120396 0.3048)
			(end 0.120396 0.2794)
			(stroke
				(width 0.1)
				(type default)
			)
			(layer "F.Fab")
		)
		(fp_line
			(start 0.67945 0.3048)
			(end 0.120396 0.3048)
			(stroke
				(width 0.1)
				(type default)
			)
			(layer "F.Fab")
		)
		(fp_line
			(start -0.12065 0.2794)
			(end -0.12065 0.3048)
			(stroke
				(width 0.1)
				(type default)
			)
			(layer "F.Fab")
		)
		(fp_line
			(start 0.120396 0.2794)
			(end -0.12065 0.2794)
			(stroke
				(width 0.1)
				(type default)
			)
			(layer "F.Fab")
		)
		(fp_line
			(start -0.12065 -0.2794)
			(end 0.12065 -0.2794)
			(stroke
				(width 0.1)
				(type default)
			)
			(layer "F.Fab")
		)
		(fp_line
			(start 0.12065 -0.2794)
			(end 0.12065 -0.3048)
			(stroke
				(width 0.1)
				(type default)
			)
			(layer "F.Fab")
		)
		(fp_line
			(start 0.12065 -0.3048)
			(end 0.67945 -0.3048)
			(stroke
				(width 0.1)
				(type default)
			)
			(layer "F.Fab")
		)
		(fp_line
			(start 0.67945 -0.3048)
			(end 0.67945 0.3048)
			(stroke
				(width 0.1)
				(type default)
			)
			(layer "F.Fab")
		)
		(fp_line
			(start -0.67945 -0.305054)
			(end -0.12065 -0.305054)
			(stroke
				(width 0.1)
				(type default)
			)
			(layer "F.Fab")
		)
		(fp_line
			(start -0.12065 -0.305054)
			(end -0.12065 -0.2794)
			(stroke
				(width 0.1)
				(type default)
			)
			(layer "F.Fab")
		)
		(pad "1" smd circle
			(at -0.40005 0 270)
			(size 0 0)
			(layers "F.Cu" "F.Mask" "F.Paste")
			(net "P12V_NIC5_SS")
		)
		(pad "2" smd circle
			(at 0.40005 0 270)
			(size 0 0)
			(layers "F.Cu" "F.Mask" "F.Paste")
			(net "GND")
		)
	)
	(footprint ""
		(layer "F.Cu")
		(at 337.488022 -319.420494 90)
		(property "Reference" "R5791"
			(at 0 0 90)
			(layer "F.SilkS")
			(hide yes)
			(effects
				(font
					(size 1.27 1.27)
				)
			)
		)
		(property "Value" ""
			(at 0 0 90)
			(layer "F.Fab")
			(effects
				(font
					(size 1.27 1.27)
				)
			)
		)
		(duplicate_pad_numbers_are_jumpers no)
		(fp_line
			(start 2.576322 -1.1303)
			(end 2.576322 1.1303)
			(stroke
				(width 0.1524)
				(type default)
			)
			(layer "F.SilkS")
		)
		(fp_line
			(start -2.576322 -1.1303)
			(end 2.576322 -1.1303)
			(stroke
				(width 0.1524)
				(type default)
			)
			(layer "F.SilkS")
		)
		(fp_line
			(start 2.576322 1.1303)
			(end -2.576322 1.1303)
			(stroke
				(width 0.1524)
				(type default)
			)
			(layer "F.SilkS")
		)
		(fp_line
			(start -2.576322 1.1303)
			(end -2.576322 -1.1303)
			(stroke
				(width 0.1524)
				(type default)
			)
			(layer "F.SilkS")
		)
		(fp_line
			(start 1.649984 -0.899922)
			(end -1.649984 -0.899922)
			(stroke
				(width 0.1)
				(type default)
			)
			(layer "F.Fab")
		)
		(fp_line
			(start -1.649984 -0.899922)
			(end -1.649984 0.899922)
			(stroke
				(width 0.1)
				(type default)
			)
			(layer "F.Fab")
		)
		(fp_line
			(start 1.649984 0.899922)
			(end 1.649984 -0.899922)
			(stroke
				(width 0.1)
				(type default)
			)
			(layer "F.Fab")
		)
		(fp_line
			(start -1.649984 0.899922)
			(end 1.649984 0.899922)
			(stroke
				(width 0.1)
				(type default)
			)
			(layer "F.Fab")
		)
		(pad "1A" smd rect
			(at -1.700022 0 90)
			(size 1.4986 2.0066)
			(layers "F.Cu" "F.Mask" "F.Paste")
			(net "P0V8_PEX2")
		)
		(pad "1B" smd rect
			(at -1.077722 0 90)
			(size 0.254 0.508)
			(layers "F.Cu" "F.Mask" "F.Paste")
			(net "P0V8_PEX2")
		)
		(pad "2A" smd rect
			(at 1.700022 0 90)
			(size 1.4986 2.0066)
			(layers "F.Cu" "F.Mask" "F.Paste")
			(net "P0V8_SERDES_VDDA_PEX2")
		)
		(pad "2B" smd rect
			(at 1.077722 0 90)
			(size 0.254 0.508)
			(layers "F.Cu" "F.Mask" "F.Paste")
			(net "P0V8_SERDES_VDDA_PEX2")
		)
	)
	(footprint ""
		(layer "F.Cu")
		(at 99.192334 -113.114582 -90)
		(property "Reference" "PD10"
			(at 4.046982 -2.205736 90)
			(unlocked yes)
			(layer "F.SilkS")
			(effects
				(font
					(size 0.7874 0.5842)
					(thickness 0.1524)
				)
				(justify left)
			)
		)
		(property "Value" ""
			(at 0 0 270)
			(layer "F.Fab")
			(effects
				(font
					(size 1.27 1.27)
				)
			)
		)
		(duplicate_pad_numbers_are_jumpers no)
		(fp_line
			(start -3.400044 1.459992)
			(end -3.400044 -1.459992)
			(stroke
				(width 0.1524)
				(type default)
			)
			(layer "F.SilkS")
		)
		(fp_line
			(start 4.107942 1.459992)
			(end -3.400044 1.459992)
			(stroke
				(width 0.1524)
				(type default)
			)
			(layer "F.SilkS")
		)
		(fp_line
			(start -3.400044 -1.459992)
			(end 4.107942 -1.459992)
			(stroke
				(width 0.1524)
				(type default)
			)
			(layer "F.SilkS")
		)
		(fp_line
			(start 4.107942 -1.459992)
			(end 4.107942 1.459992)
			(stroke
				(width 0.1524)
				(type default)
			)
			(layer "F.SilkS")
		)
		(fp_rect
			(start 4.107942 1.459992)
			(end 3.308096 -1.459992)
			(stroke
				(width 0)
				(type default)
			)
			(fill yes)
			(layer "F.SilkS")
		)
		(fp_line
			(start -2.29997 1.459992)
			(end -2.29997 -1.459992)
			(stroke
				(width 0.1)
				(type default)
			)
			(layer "F.Fab")
		)
		(fp_line
			(start 2.29997 1.459992)
			(end -2.29997 1.459992)
			(stroke
				(width 0.1)
				(type default)
			)
			(layer "F.Fab")
		)
		(fp_line
			(start -2.29997 -1.459992)
			(end 2.29997 -1.459992)
			(stroke
				(width 0.1)
				(type default)
			)
			(layer "F.Fab")
		)
		(fp_line
			(start 2.29997 -1.459992)
			(end 2.29997 1.459992)
			(stroke
				(width 0.1)
				(type default)
			)
			(layer "F.Fab")
		)
		(fp_text user "-"
			(at 5.4102 0.29845 90)
			(unlocked yes)
			(layer "F.SilkS")
			(effects
				(font
					(size 1.905 1.4224)
					(thickness 0.1524)
				)
				(justify left)
			)
		)
		(fp_text user "+"
			(at -4.7752 -0.12065 270)
			(unlocked yes)
			(layer "F.SilkS")
			(effects
				(font
					(size 1.905 1.4224)
					(thickness 0.1524)
				)
				(justify left)
			)
		)
		(fp_text user "-"
			(at 5.4102 0.29845 90)
			(unlocked yes)
			(layer "F.Fab")
			(effects
				(font
					(size 1.905 1.4224)
					(thickness 0.1524)
				)
				(justify left)
			)
		)
		(fp_text user "+"
			(at -4.7752 -0.12065 270)
			(unlocked yes)
			(layer "F.Fab")
			(effects
				(font
					(size 1.905 1.4224)
					(thickness 0.1524)
				)
				(justify left)
			)
		)
		(pad "A" smd rect
			(at -1.999996 0)
			(size 1.7018 2.5146)
			(layers "F.Cu" "F.Mask" "F.Paste")
			(net "GND")
		)
		(pad "C" smd rect
			(at 1.999996 0)
			(size 1.7018 2.5146)
			(layers "F.Cu" "F.Mask" "F.Paste")
			(net "P12V_NIC1_R")
		)
	)
	(footprint ""
		(layer "F.Cu")
		(at 376.641868 -27.006296 -90)
		(property "Reference" "PR7126"
			(at 0 0 270)
			(layer "F.SilkS")
			(hide yes)
			(effects
				(font
					(size 1.27 1.27)
				)
			)
		)
		(property "Value" ""
			(at 0 0 270)
			(layer "F.Fab")
			(effects
				(font
					(size 1.27 1.27)
				)
			)
		)
		(duplicate_pad_numbers_are_jumpers no)
		(fp_line
			(start -0.7874 0.4064)
			(end -0.7874 -0.4064)
			(stroke
				(width 0.1524)
				(type default)
			)
			(layer "F.SilkS")
		)
		(fp_line
			(start 0.7874 0.4064)
			(end -0.7874 0.4064)
			(stroke
				(width 0.1524)
				(type default)
			)
			(layer "F.SilkS")
		)
		(fp_line
			(start -0.7874 -0.4064)
			(end 0.7874 -0.4064)
			(stroke
				(width 0.1524)
				(type default)
			)
			(layer "F.SilkS")
		)
		(fp_line
			(start 0.7874 -0.4064)
			(end 0.7874 0.4064)
			(stroke
				(width 0.1524)
				(type default)
			)
			(layer "F.SilkS")
		)
		(fp_line
			(start -0.67945 0.3048)
			(end -0.67945 -0.305054)
			(stroke
				(width 0.1)
				(type default)
			)
			(layer "F.Fab")
		)
		(fp_line
			(start -0.12065 0.3048)
			(end -0.67945 0.3048)
			(stroke
				(width 0.1)
				(type default)
			)
			(layer "F.Fab")
		)
		(fp_line
			(start 0.120396 0.3048)
			(end 0.120396 0.2794)
			(stroke
				(width 0.1)
				(type default)
			)
			(layer "F.Fab")
		)
		(fp_line
			(start 0.67945 0.3048)
			(end 0.120396 0.3048)
			(stroke
				(width 0.1)
				(type default)
			)
			(layer "F.Fab")
		)
		(fp_line
			(start -0.12065 0.2794)
			(end -0.12065 0.3048)
			(stroke
				(width 0.1)
				(type default)
			)
			(layer "F.Fab")
		)
		(fp_line
			(start 0.120396 0.2794)
			(end -0.12065 0.2794)
			(stroke
				(width 0.1)
				(type default)
			)
			(layer "F.Fab")
		)
		(fp_line
			(start -0.12065 -0.2794)
			(end 0.12065 -0.2794)
			(stroke
				(width 0.1)
				(type default)
			)
			(layer "F.Fab")
		)
		(fp_line
			(start 0.12065 -0.2794)
			(end 0.12065 -0.3048)
			(stroke
				(width 0.1)
				(type default)
			)
			(layer "F.Fab")
		)
		(fp_line
			(start 0.12065 -0.3048)
			(end 0.67945 -0.3048)
			(stroke
				(width 0.1)
				(type default)
			)
			(layer "F.Fab")
		)
		(fp_line
			(start 0.67945 -0.3048)
			(end 0.67945 0.3048)
			(stroke
				(width 0.1)
				(type default)
			)
			(layer "F.Fab")
		)
		(fp_line
			(start -0.67945 -0.305054)
			(end -0.12065 -0.305054)
			(stroke
				(width 0.1)
				(type default)
			)
			(layer "F.Fab")
		)
		(fp_line
			(start -0.12065 -0.305054)
			(end -0.12065 -0.2794)
			(stroke
				(width 0.1)
				(type default)
			)
			(layer "F.Fab")
		)
		(pad "1" smd circle
			(at -0.40005 0 270)
			(size 0 0)
			(layers "F.Cu" "F.Mask" "F.Paste")
			(net "P3V3_SSD13_CO_ILIMIT")
		)
		(pad "2" smd circle
			(at 0.40005 0 270)
			(size 0 0)
			(layers "F.Cu" "F.Mask" "F.Paste")
			(net "GND")
		)
	)
	(footprint ""
		(layer "F.Cu")
		(at 132.27558 -152.71115 -90)
		(property "Reference" "R710"
			(at 0 0 270)
			(layer "F.SilkS")
			(hide yes)
			(effects
				(font
					(size 1.27 1.27)
				)
			)
		)
		(property "Value" ""
			(at 0 0 270)
			(layer "F.Fab")
			(effects
				(font
					(size 1.27 1.27)
				)
			)
		)
		(duplicate_pad_numbers_are_jumpers no)
		(fp_line
			(start -0.7874 0.4064)
			(end -0.7874 -0.4064)
			(stroke
				(width 0.1524)
				(type default)
			)
			(layer "F.SilkS")
		)
		(fp_line
			(start 0.7874 0.4064)
			(end -0.7874 0.4064)
			(stroke
				(width 0.1524)
				(type default)
			)
			(layer "F.SilkS")
		)
		(fp_line
			(start -0.7874 -0.4064)
			(end 0.7874 -0.4064)
			(stroke
				(width 0.1524)
				(type default)
			)
			(layer "F.SilkS")
		)
		(fp_line
			(start 0.7874 -0.4064)
			(end 0.7874 0.4064)
			(stroke
				(width 0.1524)
				(type default)
			)
			(layer "F.SilkS")
		)
		(fp_line
			(start -0.67945 0.3048)
			(end -0.67945 -0.305054)
			(stroke
				(width 0.1)
				(type default)
			)
			(layer "F.Fab")
		)
		(fp_line
			(start -0.12065 0.3048)
			(end -0.67945 0.3048)
			(stroke
				(width 0.1)
				(type default)
			)
			(layer "F.Fab")
		)
		(fp_line
			(start 0.120396 0.3048)
			(end 0.120396 0.2794)
			(stroke
				(width 0.1)
				(type default)
			)
			(layer "F.Fab")
		)
		(fp_line
			(start 0.67945 0.3048)
			(end 0.120396 0.3048)
			(stroke
				(width 0.1)
				(type default)
			)
			(layer "F.Fab")
		)
		(fp_line
			(start -0.12065 0.2794)
			(end -0.12065 0.3048)
			(stroke
				(width 0.1)
				(type default)
			)
			(layer "F.Fab")
		)
		(fp_line
			(start 0.120396 0.2794)
			(end -0.12065 0.2794)
			(stroke
				(width 0.1)
				(type default)
			)
			(layer "F.Fab")
		)
		(fp_line
			(start -0.12065 -0.2794)
			(end 0.12065 -0.2794)
			(stroke
				(width 0.1)
				(type default)
			)
			(layer "F.Fab")
		)
		(fp_line
			(start 0.12065 -0.2794)
			(end 0.12065 -0.3048)
			(stroke
				(width 0.1)
				(type default)
			)
			(layer "F.Fab")
		)
		(fp_line
			(start 0.12065 -0.3048)
			(end 0.67945 -0.3048)
			(stroke
				(width 0.1)
				(type default)
			)
			(layer "F.Fab")
		)
		(fp_line
			(start 0.67945 -0.3048)
			(end 0.67945 0.3048)
			(stroke
				(width 0.1)
				(type default)
			)
			(layer "F.Fab")
		)
		(fp_line
			(start -0.67945 -0.305054)
			(end -0.12065 -0.305054)
			(stroke
				(width 0.1)
				(type default)
			)
			(layer "F.Fab")
		)
		(fp_line
			(start -0.12065 -0.305054)
			(end -0.12065 -0.2794)
			(stroke
				(width 0.1)
				(type default)
			)
			(layer "F.Fab")
		)
		(pad "1" smd circle
			(at -0.40005 0 270)
			(size 0 0)
			(layers "F.Cu" "F.Mask" "F.Paste")
			(net "SMB_BIC_I2C6_MUX_NIC_ADC_R_SDA")
		)
		(pad "2" smd circle
			(at 0.40005 0 270)
			(size 0 0)
			(layers "F.Cu" "F.Mask" "F.Paste")
			(net "SMB_NIC2_ADC_SDA")
		)
	)
	(footprint ""
		(layer "F.Cu")
		(at 115.860068 -356.244906 90)
		(property "Reference" "C361"
			(at 0 0 90)
			(layer "F.SilkS")
			(hide yes)
			(effects
				(font
					(size 1.27 1.27)
				)
			)
		)
		(property "Value" ""
			(at 0 0 90)
			(layer "F.Fab")
			(effects
				(font
					(size 1.27 1.27)
				)
			)
		)
		(duplicate_pad_numbers_are_jumpers no)
		(fp_line
			(start 0.299974 -0.150114)
			(end 0.299974 0.150114)
			(stroke
				(width 0.1)
				(type default)
			)
			(layer "F.Fab")
		)
		(fp_line
			(start -0.299974 -0.150114)
			(end 0.299974 -0.150114)
			(stroke
				(width 0.1)
				(type default)
			)
			(layer "F.Fab")
		)
		(fp_line
			(start 0.299974 0.150114)
			(end -0.299974 0.150114)
			(stroke
				(width 0.1)
				(type default)
			)
			(layer "F.Fab")
		)
		(fp_line
			(start -0.299974 0.150114)
			(end -0.299974 -0.150114)
			(stroke
				(width 0.1)
				(type default)
			)
			(layer "F.Fab")
		)
		(pad "1" smd rect
			(at -0.2667 0 90)
			(size 0.3048 0.381)
			(layers "F.Cu" "F.Mask" "F.Paste")
			(net "P5E_PEX1_STN6_TX_DN<101>")
		)
		(pad "2" smd rect
			(at 0.2667 0 90)
			(size 0.3048 0.381)
			(layers "F.Cu" "F.Mask" "F.Paste")
			(net "P5E_PEX1_STN6_TX_C_DN<101>")
		)
	)
	(footprint ""
		(layer "F.Cu")
		(at 152.738328 -123.71324)
		(property "Reference" "C255"
			(at 0 0 0)
			(layer "F.SilkS")
			(hide yes)
			(effects
				(font
					(size 1.27 1.27)
				)
			)
		)
		(property "Value" ""
			(at 0 0 0)
			(layer "F.Fab")
			(effects
				(font
					(size 1.27 1.27)
				)
			)
		)
		(duplicate_pad_numbers_are_jumpers no)
		(fp_line
			(start -0.299974 -0.150114)
			(end 0.299974 -0.150114)
			(stroke
				(width 0.1)
				(type default)
			)
			(layer "F.Fab")
		)
		(fp_line
			(start -0.299974 0.150114)
			(end -0.299974 -0.150114)
			(stroke
				(width 0.1)
				(type default)
			)
			(layer "F.Fab")
		)
		(fp_line
			(start 0.299974 -0.150114)
			(end 0.299974 0.150114)
			(stroke
				(width 0.1)
				(type default)
			)
			(layer "F.Fab")
		)
		(fp_line
			(start 0.299974 0.150114)
			(end -0.299974 0.150114)
			(stroke
				(width 0.1)
				(type default)
			)
			(layer "F.Fab")
		)
		(pad "1" smd rect
			(at -0.2667 0)
			(size 0.3048 0.381)
			(layers "F.Cu" "F.Mask" "F.Paste")
			(net "P5E_PEX1_STN1_TX_DN<26>")
		)
		(pad "2" smd rect
			(at 0.2667 0)
			(size 0.3048 0.381)
			(layers "F.Cu" "F.Mask" "F.Paste")
			(net "P5E_PEX1_STN1_TX_C_DN<26>")
		)
	)
	(footprint ""
		(layer "F.Cu")
		(at 218.080844 -98.806 -90)
		(property "Reference" "R719"
			(at 0 0 270)
			(layer "F.SilkS")
			(hide yes)
			(effects
				(font
					(size 1.27 1.27)
				)
			)
		)
		(property "Value" ""
			(at 0 0 270)
			(layer "F.Fab")
			(effects
				(font
					(size 1.27 1.27)
				)
			)
		)
		(duplicate_pad_numbers_are_jumpers no)
		(fp_line
			(start -0.7874 0.4064)
			(end -0.7874 -0.4064)
			(stroke
				(width 0.1524)
				(type default)
			)
			(layer "F.SilkS")
		)
		(fp_line
			(start 0.7874 0.4064)
			(end -0.7874 0.4064)
			(stroke
				(width 0.1524)
				(type default)
			)
			(layer "F.SilkS")
		)
		(fp_line
			(start -0.7874 -0.4064)
			(end 0.7874 -0.4064)
			(stroke
				(width 0.1524)
				(type default)
			)
			(layer "F.SilkS")
		)
		(fp_line
			(start 0.7874 -0.4064)
			(end 0.7874 0.4064)
			(stroke
				(width 0.1524)
				(type default)
			)
			(layer "F.SilkS")
		)
		(fp_line
			(start -0.67945 0.3048)
			(end -0.67945 -0.305054)
			(stroke
				(width 0.1)
				(type default)
			)
			(layer "F.Fab")
		)
		(fp_line
			(start -0.12065 0.3048)
			(end -0.67945 0.3048)
			(stroke
				(width 0.1)
				(type default)
			)
			(layer "F.Fab")
		)
		(fp_line
			(start 0.120396 0.3048)
			(end 0.120396 0.2794)
			(stroke
				(width 0.1)
				(type default)
			)
			(layer "F.Fab")
		)
		(fp_line
			(start 0.67945 0.3048)
			(end 0.120396 0.3048)
			(stroke
				(width 0.1)
				(type default)
			)
			(layer "F.Fab")
		)
		(fp_line
			(start -0.12065 0.2794)
			(end -0.12065 0.3048)
			(stroke
				(width 0.1)
				(type default)
			)
			(layer "F.Fab")
		)
		(fp_line
			(start 0.120396 0.2794)
			(end -0.12065 0.2794)
			(stroke
				(width 0.1)
				(type default)
			)
			(layer "F.Fab")
		)
		(fp_line
			(start -0.12065 -0.2794)
			(end 0.12065 -0.2794)
			(stroke
				(width 0.1)
				(type default)
			)
			(layer "F.Fab")
		)
		(fp_line
			(start 0.12065 -0.2794)
			(end 0.12065 -0.3048)
			(stroke
				(width 0.1)
				(type default)
			)
			(layer "F.Fab")
		)
		(fp_line
			(start 0.12065 -0.3048)
			(end 0.67945 -0.3048)
			(stroke
				(width 0.1)
				(type default)
			)
			(layer "F.Fab")
		)
		(fp_line
			(start 0.67945 -0.3048)
			(end 0.67945 0.3048)
			(stroke
				(width 0.1)
				(type default)
			)
			(layer "F.Fab")
		)
		(fp_line
			(start -0.67945 -0.305054)
			(end -0.12065 -0.305054)
			(stroke
				(width 0.1)
				(type default)
			)
			(layer "F.Fab")
		)
		(fp_line
			(start -0.12065 -0.305054)
			(end -0.12065 -0.2794)
			(stroke
				(width 0.1)
				(type default)
			)
			(layer "F.Fab")
		)
		(pad "1" smd circle
			(at -0.40005 0 270)
			(size 0 0)
			(layers "F.Cu" "F.Mask" "F.Paste")
			(net "NIC3_ADC_A0")
		)
		(pad "2" smd circle
			(at 0.40005 0 270)
			(size 0 0)
			(layers "F.Cu" "F.Mask" "F.Paste")
			(net "GND")
		)
	)
	(footprint ""
		(layer "F.Cu")
		(at 312.21934 -153.390346 180)
		(property "Reference" "C426"
			(at 0 0 180)
			(layer "F.SilkS")
			(hide yes)
			(effects
				(font
					(size 1.27 1.27)
				)
			)
		)
		(property "Value" ""
			(at 0 0 180)
			(layer "F.Fab")
			(effects
				(font
					(size 1.27 1.27)
				)
			)
		)
		(duplicate_pad_numbers_are_jumpers no)
		(fp_line
			(start 0.299974 0.150114)
			(end -0.299974 0.150114)
			(stroke
				(width 0.1)
				(type default)
			)
			(layer "F.Fab")
		)
		(fp_line
			(start 0.299974 -0.150114)
			(end 0.299974 0.150114)
			(stroke
				(width 0.1)
				(type default)
			)
			(layer "F.Fab")
		)
		(fp_line
			(start -0.299974 0.150114)
			(end -0.299974 -0.150114)
			(stroke
				(width 0.1)
				(type default)
			)
			(layer "F.Fab")
		)
		(fp_line
			(start -0.299974 -0.150114)
			(end 0.299974 -0.150114)
			(stroke
				(width 0.1)
				(type default)
			)
			(layer "F.Fab")
		)
		(pad "1" smd rect
			(at -0.2667 0 180)
			(size 0.3048 0.381)
			(layers "F.Cu" "F.Mask" "F.Paste")
			(net "P5E_PEX2_STN0_TX_DP<14>")
		)
		(pad "2" smd rect
			(at 0.2667 0 180)
			(size 0.3048 0.381)
			(layers "F.Cu" "F.Mask" "F.Paste")
			(net "P5E_PEX2_STN0_TX_C_DP<14>")
		)
	)
	(footprint ""
		(layer "F.Cu")
		(at 146.18208 -299.391832 180)
		(property "Reference" "C3205"
			(at 0 0 180)
			(layer "F.SilkS")
			(hide yes)
			(effects
				(font
					(size 1.27 1.27)
				)
			)
		)
		(property "Value" ""
			(at 0 0 180)
			(layer "F.Fab")
			(effects
				(font
					(size 1.27 1.27)
				)
			)
		)
		(duplicate_pad_numbers_are_jumpers no)
		(fp_line
			(start 1.2954 0.5842)
			(end -1.2954 0.5842)
			(stroke
				(width 0.1524)
				(type default)
			)
			(layer "F.SilkS")
		)
		(fp_line
			(start 1.2954 -0.5842)
			(end 1.2954 0.5842)
			(stroke
				(width 0.1524)
				(type default)
			)
			(layer "F.SilkS")
		)
		(fp_line
			(start -1.2954 0.5842)
			(end -1.2954 -0.5842)
			(stroke
				(width 0.1524)
				(type default)
			)
			(layer "F.SilkS")
		)
		(fp_line
			(start -1.2954 -0.5842)
			(end 1.2954 -0.5842)
			(stroke
				(width 0.1524)
				(type default)
			)
			(layer "F.SilkS")
		)
		(fp_line
			(start 1.1938 0.4064)
			(end 0.8636 0.4064)
			(stroke
				(width 0.1)
				(type default)
			)
			(layer "F.Fab")
		)
		(fp_line
			(start 1.1938 -0.4064)
			(end 1.1938 0.4064)
			(stroke
				(width 0.1)
				(type default)
			)
			(layer "F.Fab")
		)
		(fp_line
			(start 0.8636 0.4572)
			(end -0.8636 0.4572)
			(stroke
				(width 0.1)
				(type default)
			)
			(layer "F.Fab")
		)
		(fp_line
			(start 0.8636 0.4064)
			(end 0.8636 0.4572)
			(stroke
				(width 0.1)
				(type default)
			)
			(layer "F.Fab")
		)
		(fp_line
			(start 0.8636 -0.4064)
			(end 1.1938 -0.4064)
			(stroke
				(width 0.1)
				(type default)
			)
			(layer "F.Fab")
		)
		(fp_line
			(start 0.8636 -0.4572)
			(end 0.8636 -0.4064)
			(stroke
				(width 0.1)
				(type default)
			)
			(layer "F.Fab")
		)
		(fp_line
			(start -0.8636 0.4572)
			(end -0.8636 0.4064)
			(stroke
				(width 0.1)
				(type default)
			)
			(layer "F.Fab")
		)
		(fp_line
			(start -0.8636 0.4064)
			(end -1.1938 0.4064)
			(stroke
				(width 0.1)
				(type default)
			)
			(layer "F.Fab")
		)
		(fp_line
			(start -0.8636 -0.4064)
			(end -0.8636 -0.4572)
			(stroke
				(width 0.1)
				(type default)
			)
			(layer "F.Fab")
		)
		(fp_line
			(start -0.8636 -0.4572)
			(end 0.8636 -0.4572)
			(stroke
				(width 0.1)
				(type default)
			)
			(layer "F.Fab")
		)
		(fp_line
			(start -1.1938 0.4064)
			(end -1.1938 -0.4064)
			(stroke
				(width 0.1)
				(type default)
			)
			(layer "F.Fab")
		)
		(fp_line
			(start -1.1938 -0.4064)
			(end -0.8636 -0.4064)
			(stroke
				(width 0.1)
				(type default)
			)
			(layer "F.Fab")
		)
		(pad "1" smd rect
			(at -0.7366 0 90)
			(size 0.7112 0.8128)
			(layers "F.Cu" "F.Mask" "F.Paste")
			(net "PCEPLL1_VDDA18_PEX1_R")
		)
		(pad "2" smd rect
			(at 0.7366 0 90)
			(size 0.7112 0.8128)
			(layers "F.Cu" "F.Mask" "F.Paste")
			(net "GND")
		)
	)
	(footprint ""
		(layer "F.Cu")
		(at 16.041116 -115.695476)
		(property "Reference" "PU80"
			(at -2.425446 3.173476 90)
			(unlocked yes)
			(layer "F.SilkS")
			(effects
				(font
					(size 0.7874 0.5842)
					(thickness 0.1524)
				)
			)
		)
		(property "Value" ""
			(at 0 0 0)
			(layer "F.Fab")
			(effects
				(font
					(size 1.27 1.27)
				)
			)
		)
		(duplicate_pad_numbers_are_jumpers no)
		(fp_line
			(start -1.239774 -1.495298)
			(end 1.239774 -1.495298)
			(stroke
				(width 0.1524)
				(type default)
			)
			(layer "F.SilkS")
		)
		(fp_line
			(start -1.239774 1.495298)
			(end -1.239774 -1.495298)
			(stroke
				(width 0.1524)
				(type default)
			)
			(layer "F.SilkS")
		)
		(fp_line
			(start 1.239774 -1.495298)
			(end 1.239774 1.495298)
			(stroke
				(width 0.1524)
				(type default)
			)
			(layer "F.SilkS")
		)
		(fp_line
			(start 1.239774 1.495298)
			(end -1.239774 1.495298)
			(stroke
				(width 0.1524)
				(type default)
			)
			(layer "F.SilkS")
		)
		(fp_poly
			(pts
				(xy -1.713738 -1.75895) (xy -2.432304 -1.040638) (xy -1.354582 -0.681482)
			)
			(stroke
				(width 0)
				(type default)
			)
			(fill yes)
			(layer "F.SilkS")
		)
		(fp_line
			(start -0.8001 -1.050036)
			(end 0.8001 -1.050036)
			(stroke
				(width 0.1)
				(type default)
			)
			(layer "F.Fab")
		)
		(fp_line
			(start -0.8001 1.050036)
			(end -0.8001 -1.050036)
			(stroke
				(width 0.1)
				(type default)
			)
			(layer "F.Fab")
		)
		(fp_line
			(start 0.8001 -1.050036)
			(end 0.8001 1.050036)
			(stroke
				(width 0.1)
				(type default)
			)
			(layer "F.Fab")
		)
		(fp_line
			(start 0.8001 1.050036)
			(end -0.8001 1.050036)
			(stroke
				(width 0.1)
				(type default)
			)
			(layer "F.Fab")
		)
		(fp_poly
			(pts
				(xy -2.458974 -0.508) (xy -2.458974 0.508) (xy -1.442974 0)
			)
			(stroke
				(width 0)
				(type default)
			)
			(fill yes)
			(layer "F.Fab")
		)
		(pad "1_2" smd circle
			(at -0.374904 0 90)
			(size 0 0)
			(layers "F.Cu" "F.Mask" "F.Paste")
			(net "P3V3_AUX")
		)
		(pad "3" smd rect
			(at -0.499872 0.999998)
			(size 0.254 0.7112)
			(layers "F.Cu" "F.Mask" "F.Paste")
			(net "GND")
		)
		(pad "4" smd rect
			(at 0 0.999998)
			(size 0.254 0.7112)
			(layers "F.Cu" "F.Mask" "F.Paste")
			(net "P3V3_NIC0_CO_ILIMIT")
		)
		(pad "5" smd rect
			(at 0.499872 0.999998)
			(size 0.254 0.7112)
			(layers "F.Cu" "F.Mask" "F.Paste")
			(net "P3V3_NIC0_CO_MODE")
		)
		(pad "6_7" smd circle
			(at 0.374904 0 270)
			(size 0 0)
			(layers "F.Cu" "F.Mask" "F.Paste")
			(net "P3V3_NIC0")
		)
		(pad "8" smd rect
			(at 0.499872 -0.999998)
			(size 0.254 0.7112)
			(layers "F.Cu" "F.Mask" "F.Paste")
			(net "P3V3_NIC0_CO_GATE")
		)
		(pad "9" smd rect
			(at 0 -0.999998)
			(size 0.254 0.7112)
			(layers "F.Cu" "F.Mask" "F.Paste")
			(net "P3V3_NIC0_CO_EN")
		)
		(pad "10" smd rect
			(at -0.499872 -0.999998)
			(size 0.254 0.7112)
			(layers "F.Cu" "F.Mask" "F.Paste")
			(net "P3V3_NIC0_CO_DV_DT")
		)
	)
	(footprint ""
		(layer "F.Cu")
		(at 105.688384 -170.951652 180)
		(property "Reference" "PC24"
			(at 0 0 180)
			(layer "F.SilkS")
			(hide yes)
			(effects
				(font
					(size 1.27 1.27)
				)
			)
		)
		(property "Value" ""
			(at 0 0 180)
			(layer "F.Fab")
			(effects
				(font
					(size 1.27 1.27)
				)
			)
		)
		(duplicate_pad_numbers_are_jumpers no)
		(fp_line
			(start 3.400044 3.400044)
			(end -2.146046 3.400044)
			(stroke
				(width 0.1524)
				(type default)
			)
			(layer "F.SilkS")
		)
		(fp_line
			(start 3.400044 0.9398)
			(end 3.400044 3.400044)
			(stroke
				(width 0.1524)
				(type default)
			)
			(layer "F.SilkS")
		)
		(fp_line
			(start 3.400044 -0.9398)
			(end 3.400044 -3.400044)
			(stroke
				(width 0.1524)
				(type default)
			)
			(layer "F.SilkS")
		)
		(fp_line
			(start 3.400044 -3.400044)
			(end -2.146046 -3.400044)
			(stroke
				(width 0.1524)
				(type default)
			)
			(layer "F.SilkS")
		)
		(fp_line
			(start -2.146046 3.400044)
			(end -3.400044 2.146046)
			(stroke
				(width 0.1524)
				(type default)
			)
			(layer "F.SilkS")
		)
		(fp_line
			(start -2.146046 -3.400044)
			(end -3.400044 -2.146046)
			(stroke
				(width 0.1524)
				(type default)
			)
			(layer "F.SilkS")
		)
		(fp_line
			(start -3.400044 2.146046)
			(end -3.400044 0.9398)
			(stroke
				(width 0.1524)
				(type default)
			)
			(layer "F.SilkS")
		)
		(fp_line
			(start -3.400044 -2.146046)
			(end -3.400044 -0.9398)
			(stroke
				(width 0.1524)
				(type default)
			)
			(layer "F.SilkS")
		)
		(fp_line
			(start 3.400044 3.400044)
			(end 3.400044 -3.400044)
			(stroke
				(width 0.1)
				(type default)
			)
			(layer "F.Fab")
		)
		(fp_line
			(start 3.400044 -3.400044)
			(end -3.400044 -3.400044)
			(stroke
				(width 0.1)
				(type default)
			)
			(layer "F.Fab")
		)
		(fp_line
			(start -3.400044 3.400044)
			(end 3.400044 3.400044)
			(stroke
				(width 0.1)
				(type default)
			)
			(layer "F.Fab")
		)
		(fp_line
			(start -3.400044 -3.400044)
			(end -3.400044 3.400044)
			(stroke
				(width 0.1)
				(type default)
			)
			(layer "F.Fab")
		)
		(pad "1" smd rect
			(at -2.70002 0 90)
			(size 1.6002 3.5052)
			(layers "F.Cu" "F.Mask" "F.Paste")
			(net "SW_P12V_P3V3_AUX_FLT")
		)
		(pad "2" smd rect
			(at 2.70002 0 90)
			(size 1.6002 3.5052)
			(layers "F.Cu" "F.Mask" "F.Paste")
			(net "GND")
		)
	)
	(footprint ""
		(layer "F.Cu")
		(at 134.5311 -123.903994 -90)
		(property "Reference" "PC477"
			(at 0 0 270)
			(layer "F.SilkS")
			(hide yes)
			(effects
				(font
					(size 1.27 1.27)
				)
			)
		)
		(property "Value" ""
			(at 0 0 270)
			(layer "F.Fab")
			(effects
				(font
					(size 1.27 1.27)
				)
			)
		)
		(duplicate_pad_numbers_are_jumpers no)
		(fp_line
			(start -1.524 0.762)
			(end -1.524 -0.762)
			(stroke
				(width 0.1524)
				(type default)
			)
			(layer "F.SilkS")
		)
		(fp_line
			(start 1.524 0.762)
			(end -1.524 0.762)
			(stroke
				(width 0.1524)
				(type default)
			)
			(layer "F.SilkS")
		)
		(fp_line
			(start -1.524 -0.762)
			(end 1.524 -0.762)
			(stroke
				(width 0.1524)
				(type default)
			)
			(layer "F.SilkS")
		)
		(fp_line
			(start 1.524 -0.762)
			(end 1.524 0.762)
			(stroke
				(width 0.1524)
				(type default)
			)
			(layer "F.SilkS")
		)
		(fp_line
			(start -1.1049 0.724916)
			(end 1.1049 0.724916)
			(stroke
				(width 0.1)
				(type default)
			)
			(layer "F.Fab")
		)
		(fp_line
			(start 1.1049 0.724916)
			(end 1.1049 -0.724916)
			(stroke
				(width 0.1)
				(type default)
			)
			(layer "F.Fab")
		)
		(fp_line
			(start -1.1049 -0.724916)
			(end -1.1049 0.724916)
			(stroke
				(width 0.1)
				(type default)
			)
			(layer "F.Fab")
		)
		(fp_line
			(start 1.1049 -0.724916)
			(end -1.1049 -0.724916)
			(stroke
				(width 0.1)
				(type default)
			)
			(layer "F.Fab")
		)
		(pad "1" smd rect
			(at -0.889 0 90)
			(size 1.016 1.27)
			(layers "F.Cu" "F.Mask" "F.Paste")
			(net "P3V3_NIC2")
		)
		(pad "2" smd rect
			(at 0.889 0 90)
			(size 1.016 1.27)
			(layers "F.Cu" "F.Mask" "F.Paste")
			(net "GND")
		)
	)
	(footprint ""
		(layer "F.Cu")
		(at 262.281924 -286.590232 180)
		(property "Reference" "C3409"
			(at 0 0 180)
			(layer "F.SilkS")
			(hide yes)
			(effects
				(font
					(size 1.27 1.27)
				)
			)
		)
		(property "Value" ""
			(at 0 0 180)
			(layer "F.Fab")
			(effects
				(font
					(size 1.27 1.27)
				)
			)
		)
		(duplicate_pad_numbers_are_jumpers no)
		(fp_line
			(start 1.2954 0.5842)
			(end -1.2954 0.5842)
			(stroke
				(width 0.1524)
				(type default)
			)
			(layer "F.SilkS")
		)
		(fp_line
			(start 1.2954 -0.5842)
			(end 1.2954 0.5842)
			(stroke
				(width 0.1524)
				(type default)
			)
			(layer "F.SilkS")
		)
		(fp_line
			(start -1.2954 0.5842)
			(end -1.2954 -0.5842)
			(stroke
				(width 0.1524)
				(type default)
			)
			(layer "F.SilkS")
		)
		(fp_line
			(start -1.2954 -0.5842)
			(end 1.2954 -0.5842)
			(stroke
				(width 0.1524)
				(type default)
			)
			(layer "F.SilkS")
		)
		(fp_line
			(start 1.1938 0.4064)
			(end 0.8636 0.4064)
			(stroke
				(width 0.1)
				(type default)
			)
			(layer "F.Fab")
		)
		(fp_line
			(start 1.1938 -0.4064)
			(end 1.1938 0.4064)
			(stroke
				(width 0.1)
				(type default)
			)
			(layer "F.Fab")
		)
		(fp_line
			(start 0.8636 0.4572)
			(end -0.8636 0.4572)
			(stroke
				(width 0.1)
				(type default)
			)
			(layer "F.Fab")
		)
		(fp_line
			(start 0.8636 0.4064)
			(end 0.8636 0.4572)
			(stroke
				(width 0.1)
				(type default)
			)
			(layer "F.Fab")
		)
		(fp_line
			(start 0.8636 -0.4064)
			(end 1.1938 -0.4064)
			(stroke
				(width 0.1)
				(type default)
			)
			(layer "F.Fab")
		)
		(fp_line
			(start 0.8636 -0.4572)
			(end 0.8636 -0.4064)
			(stroke
				(width 0.1)
				(type default)
			)
			(layer "F.Fab")
		)
		(fp_line
			(start -0.8636 0.4572)
			(end -0.8636 0.4064)
			(stroke
				(width 0.1)
				(type default)
			)
			(layer "F.Fab")
		)
		(fp_line
			(start -0.8636 0.4064)
			(end -1.1938 0.4064)
			(stroke
				(width 0.1)
				(type default)
			)
			(layer "F.Fab")
		)
		(fp_line
			(start -0.8636 -0.4064)
			(end -0.8636 -0.4572)
			(stroke
				(width 0.1)
				(type default)
			)
			(layer "F.Fab")
		)
		(fp_line
			(start -0.8636 -0.4572)
			(end 0.8636 -0.4572)
			(stroke
				(width 0.1)
				(type default)
			)
			(layer "F.Fab")
		)
		(fp_line
			(start -1.1938 0.4064)
			(end -1.1938 -0.4064)
			(stroke
				(width 0.1)
				(type default)
			)
			(layer "F.Fab")
		)
		(fp_line
			(start -1.1938 -0.4064)
			(end -0.8636 -0.4064)
			(stroke
				(width 0.1)
				(type default)
			)
			(layer "F.Fab")
		)
		(pad "1" smd rect
			(at -0.7366 0 90)
			(size 0.7112 0.8128)
			(layers "F.Cu" "F.Mask" "F.Paste")
			(net "PCEPLL6_VDDA18_PEX2_R")
		)
		(pad "2" smd rect
			(at 0.7366 0 90)
			(size 0.7112 0.8128)
			(layers "F.Cu" "F.Mask" "F.Paste")
			(net "GND")
		)
	)
	(footprint ""
		(layer "F.Cu")
		(at 91.168982 -123.067318 90)
		(property "Reference" "PC465"
			(at 0 0 90)
			(layer "F.SilkS")
			(hide yes)
			(effects
				(font
					(size 1.27 1.27)
				)
			)
		)
		(property "Value" ""
			(at 0 0 90)
			(layer "F.Fab")
			(effects
				(font
					(size 1.27 1.27)
				)
			)
		)
		(duplicate_pad_numbers_are_jumpers no)
		(fp_line
			(start 1.524 -0.762)
			(end 1.524 0.762)
			(stroke
				(width 0.1524)
				(type default)
			)
			(layer "F.SilkS")
		)
		(fp_line
			(start -1.524 -0.762)
			(end 1.524 -0.762)
			(stroke
				(width 0.1524)
				(type default)
			)
			(layer "F.SilkS")
		)
		(fp_line
			(start 1.524 0.762)
			(end -1.524 0.762)
			(stroke
				(width 0.1524)
				(type default)
			)
			(layer "F.SilkS")
		)
		(fp_line
			(start -1.524 0.762)
			(end -1.524 -0.762)
			(stroke
				(width 0.1524)
				(type default)
			)
			(layer "F.SilkS")
		)
		(fp_line
			(start 1.1049 -0.724916)
			(end -1.1049 -0.724916)
			(stroke
				(width 0.1)
				(type default)
			)
			(layer "F.Fab")
		)
		(fp_line
			(start -1.1049 -0.724916)
			(end -1.1049 0.724916)
			(stroke
				(width 0.1)
				(type default)
			)
			(layer "F.Fab")
		)
		(fp_line
			(start 1.1049 0.724916)
			(end 1.1049 -0.724916)
			(stroke
				(width 0.1)
				(type default)
			)
			(layer "F.Fab")
		)
		(fp_line
			(start -1.1049 0.724916)
			(end 1.1049 0.724916)
			(stroke
				(width 0.1)
				(type default)
			)
			(layer "F.Fab")
		)
		(pad "1" smd rect
			(at -0.889 0 270)
			(size 1.016 1.27)
			(layers "F.Cu" "F.Mask" "F.Paste")
			(net "P3V3_NIC1")
		)
		(pad "2" smd rect
			(at 0.889 0 270)
			(size 1.016 1.27)
			(layers "F.Cu" "F.Mask" "F.Paste")
			(net "GND")
		)
	)
	(footprint ""
		(layer "F.Cu")
		(at 225.738944 -98.36912 -90)
		(property "Reference" "PC469"
			(at 0 0 270)
			(layer "F.SilkS")
			(hide yes)
			(effects
				(font
					(size 1.27 1.27)
				)
			)
		)
		(property "Value" ""
			(at 0 0 270)
			(layer "F.Fab")
			(effects
				(font
					(size 1.27 1.27)
				)
			)
		)
		(duplicate_pad_numbers_are_jumpers no)
		(fp_line
			(start -0.7874 0.4064)
			(end -0.7874 -0.4064)
			(stroke
				(width 0.1524)
				(type default)
			)
			(layer "F.SilkS")
		)
		(fp_line
			(start 0.7874 0.4064)
			(end -0.7874 0.4064)
			(stroke
				(width 0.1524)
				(type default)
			)
			(layer "F.SilkS")
		)
		(fp_line
			(start -0.7874 -0.4064)
			(end 0.7874 -0.4064)
			(stroke
				(width 0.1524)
				(type default)
			)
			(layer "F.SilkS")
		)
		(fp_line
			(start 0.7874 -0.4064)
			(end 0.7874 0.4064)
			(stroke
				(width 0.1524)
				(type default)
			)
			(layer "F.SilkS")
		)
		(fp_line
			(start -0.67945 0.3048)
			(end -0.67945 -0.305054)
			(stroke
				(width 0.1)
				(type default)
			)
			(layer "F.Fab")
		)
		(fp_line
			(start -0.12065 0.3048)
			(end -0.67945 0.3048)
			(stroke
				(width 0.1)
				(type default)
			)
			(layer "F.Fab")
		)
		(fp_line
			(start 0.120396 0.3048)
			(end 0.120396 0.2794)
			(stroke
				(width 0.1)
				(type default)
			)
			(layer "F.Fab")
		)
		(fp_line
			(start 0.67945 0.3048)
			(end 0.120396 0.3048)
			(stroke
				(width 0.1)
				(type default)
			)
			(layer "F.Fab")
		)
		(fp_line
			(start -0.12065 0.2794)
			(end -0.12065 0.3048)
			(stroke
				(width 0.1)
				(type default)
			)
			(layer "F.Fab")
		)
		(fp_line
			(start 0.120396 0.2794)
			(end -0.12065 0.2794)
			(stroke
				(width 0.1)
				(type default)
			)
			(layer "F.Fab")
		)
		(fp_line
			(start -0.12065 -0.2794)
			(end 0.12065 -0.2794)
			(stroke
				(width 0.1)
				(type default)
			)
			(layer "F.Fab")
		)
		(fp_line
			(start 0.12065 -0.2794)
			(end 0.12065 -0.3048)
			(stroke
				(width 0.1)
				(type default)
			)
			(layer "F.Fab")
		)
		(fp_line
			(start 0.12065 -0.3048)
			(end 0.67945 -0.3048)
			(stroke
				(width 0.1)
				(type default)
			)
			(layer "F.Fab")
		)
		(fp_line
			(start 0.67945 -0.3048)
			(end 0.67945 0.3048)
			(stroke
				(width 0.1)
				(type default)
			)
			(layer "F.Fab")
		)
		(fp_line
			(start -0.67945 -0.305054)
			(end -0.12065 -0.305054)
			(stroke
				(width 0.1)
				(type default)
			)
			(layer "F.Fab")
		)
		(fp_line
			(start -0.12065 -0.305054)
			(end -0.12065 -0.2794)
			(stroke
				(width 0.1)
				(type default)
			)
			(layer "F.Fab")
		)
		(pad "1" smd circle
			(at -0.40005 0 270)
			(size 0 0)
			(layers "F.Cu" "F.Mask" "F.Paste")
			(net "P5V_AUX")
		)
		(pad "2" smd circle
			(at 0.40005 0 270)
			(size 0 0)
			(layers "F.Cu" "F.Mask" "F.Paste")
			(net "GND")
		)
	)
	(footprint ""
		(layer "F.Cu")
		(at 432.80203 -141.150848 -90)
		(property "Reference" "U44"
			(at 2.722118 0.13843 0)
			(unlocked yes)
			(layer "F.SilkS")
			(effects
				(font
					(size 0.7874 0.5842)
					(thickness 0.1524)
				)
			)
		)
		(property "Value" ""
			(at 0 0 270)
			(layer "F.Fab")
			(effects
				(font
					(size 1.27 1.27)
				)
			)
		)
		(duplicate_pad_numbers_are_jumpers no)
		(fp_line
			(start -1.949958 1.610106)
			(end -1.949958 -1.610106)
			(stroke
				(width 0.1524)
				(type default)
			)
			(layer "F.SilkS")
		)
		(fp_line
			(start 1.949958 1.610106)
			(end -1.949958 1.610106)
			(stroke
				(width 0.1524)
				(type default)
			)
			(layer "F.SilkS")
		)
		(fp_line
			(start 1.949958 -1.560068)
			(end 1.949958 1.610106)
			(stroke
				(width 0.1524)
				(type default)
			)
			(layer "F.SilkS")
		)
		(fp_line
			(start -1.949958 -1.610106)
			(end 1.949958 -1.610106)
			(stroke
				(width 0.1524)
				(type default)
			)
			(layer "F.SilkS")
		)
		(fp_line
			(start -0.750062 1.560068)
			(end -0.750062 -1.560068)
			(stroke
				(width 0.1)
				(type default)
			)
			(layer "F.Fab")
		)
		(fp_line
			(start 0.750062 1.560068)
			(end -0.750062 1.560068)
			(stroke
				(width 0.1)
				(type default)
			)
			(layer "F.Fab")
		)
		(fp_line
			(start -0.750062 -1.560068)
			(end 0.750062 -1.560068)
			(stroke
				(width 0.1)
				(type default)
			)
			(layer "F.Fab")
		)
		(fp_line
			(start 0.750062 -1.560068)
			(end 0.750062 1.560068)
			(stroke
				(width 0.1)
				(type default)
			)
			(layer "F.Fab")
		)
		(pad "D" smd rect
			(at 1.100074 0 180)
			(size 1.016 1.4224)
			(layers "F.Cu" "F.Mask" "F.Paste")
			(net "HP_NIC7_EN")
		)
		(pad "G" smd rect
			(at -1.100074 -0.94996 180)
			(size 1.016 1.4224)
			(layers "F.Cu" "F.Mask" "F.Paste")
			(net "PRSNT_NIC7_R_N")
		)
		(pad "S" smd rect
			(at -1.100074 0.94996 180)
			(size 1.016 1.4224)
			(layers "F.Cu" "F.Mask" "F.Paste")
			(net "GND")
		)
	)
	(footprint ""
		(layer "F.Cu")
		(at 306.085494 -25.1587 -90)
		(property "Reference" "R5756"
			(at 0 0 270)
			(layer "F.SilkS")
			(hide yes)
			(effects
				(font
					(size 1.27 1.27)
				)
			)
		)
		(property "Value" ""
			(at 0 0 270)
			(layer "F.Fab")
			(effects
				(font
					(size 1.27 1.27)
				)
			)
		)
		(duplicate_pad_numbers_are_jumpers no)
		(fp_line
			(start -0.7874 0.4064)
			(end -0.7874 -0.4064)
			(stroke
				(width 0.1524)
				(type default)
			)
			(layer "F.SilkS")
		)
		(fp_line
			(start 0.7874 0.4064)
			(end -0.7874 0.4064)
			(stroke
				(width 0.1524)
				(type default)
			)
			(layer "F.SilkS")
		)
		(fp_line
			(start -0.7874 -0.4064)
			(end 0.7874 -0.4064)
			(stroke
				(width 0.1524)
				(type default)
			)
			(layer "F.SilkS")
		)
		(fp_line
			(start 0.7874 -0.4064)
			(end 0.7874 0.4064)
			(stroke
				(width 0.1524)
				(type default)
			)
			(layer "F.SilkS")
		)
		(fp_line
			(start -0.67945 0.3048)
			(end -0.67945 -0.305054)
			(stroke
				(width 0.1)
				(type default)
			)
			(layer "F.Fab")
		)
		(fp_line
			(start -0.12065 0.3048)
			(end -0.67945 0.3048)
			(stroke
				(width 0.1)
				(type default)
			)
			(layer "F.Fab")
		)
		(fp_line
			(start 0.120396 0.3048)
			(end 0.120396 0.2794)
			(stroke
				(width 0.1)
				(type default)
			)
			(layer "F.Fab")
		)
		(fp_line
			(start 0.67945 0.3048)
			(end 0.120396 0.3048)
			(stroke
				(width 0.1)
				(type default)
			)
			(layer "F.Fab")
		)
		(fp_line
			(start -0.12065 0.2794)
			(end -0.12065 0.3048)
			(stroke
				(width 0.1)
				(type default)
			)
			(layer "F.Fab")
		)
		(fp_line
			(start 0.120396 0.2794)
			(end -0.12065 0.2794)
			(stroke
				(width 0.1)
				(type default)
			)
			(layer "F.Fab")
		)
		(fp_line
			(start -0.12065 -0.2794)
			(end 0.12065 -0.2794)
			(stroke
				(width 0.1)
				(type default)
			)
			(layer "F.Fab")
		)
		(fp_line
			(start 0.12065 -0.2794)
			(end 0.12065 -0.3048)
			(stroke
				(width 0.1)
				(type default)
			)
			(layer "F.Fab")
		)
		(fp_line
			(start 0.12065 -0.3048)
			(end 0.67945 -0.3048)
			(stroke
				(width 0.1)
				(type default)
			)
			(layer "F.Fab")
		)
		(fp_line
			(start 0.67945 -0.3048)
			(end 0.67945 0.3048)
			(stroke
				(width 0.1)
				(type default)
			)
			(layer "F.Fab")
		)
		(fp_line
			(start -0.67945 -0.305054)
			(end -0.12065 -0.305054)
			(stroke
				(width 0.1)
				(type default)
			)
			(layer "F.Fab")
		)
		(fp_line
			(start -0.12065 -0.305054)
			(end -0.12065 -0.2794)
			(stroke
				(width 0.1)
				(type default)
			)
			(layer "F.Fab")
		)
		(pad "1" smd circle
			(at -0.40005 0 270)
			(size 0 0)
			(layers "F.Cu" "F.Mask" "F.Paste")
			(net "SSD10_LED_ISO_N")
		)
		(pad "2" smd circle
			(at 0.40005 0 270)
			(size 0 0)
			(layers "F.Cu" "F.Mask" "F.Paste")
			(net "SSD10_LED_ISO_R_N")
		)
	)
	(footprint ""
		(layer "F.Cu")
		(at 58.995056 -98.734372)
		(property "Reference" "R52"
			(at 0 0 0)
			(layer "F.SilkS")
			(hide yes)
			(effects
				(font
					(size 1.27 1.27)
				)
			)
		)
		(property "Value" ""
			(at 0 0 0)
			(layer "F.Fab")
			(effects
				(font
					(size 1.27 1.27)
				)
			)
		)
		(duplicate_pad_numbers_are_jumpers no)
		(fp_line
			(start -0.7874 -0.4064)
			(end 0.7874 -0.4064)
			(stroke
				(width 0.1524)
				(type default)
			)
			(layer "F.SilkS")
		)
		(fp_line
			(start -0.7874 0.4064)
			(end -0.7874 -0.4064)
			(stroke
				(width 0.1524)
				(type default)
			)
			(layer "F.SilkS")
		)
		(fp_line
			(start 0.7874 -0.4064)
			(end 0.7874 0.4064)
			(stroke
				(width 0.1524)
				(type default)
			)
			(layer "F.SilkS")
		)
		(fp_line
			(start 0.7874 0.4064)
			(end -0.7874 0.4064)
			(stroke
				(width 0.1524)
				(type default)
			)
			(layer "F.SilkS")
		)
		(fp_line
			(start -0.67945 -0.305054)
			(end -0.12065 -0.305054)
			(stroke
				(width 0.1)
				(type default)
			)
			(layer "F.Fab")
		)
		(fp_line
			(start -0.67945 0.3048)
			(end -0.67945 -0.305054)
			(stroke
				(width 0.1)
				(type default)
			)
			(layer "F.Fab")
		)
		(fp_line
			(start -0.12065 -0.305054)
			(end -0.12065 -0.2794)
			(stroke
				(width 0.1)
				(type default)
			)
			(layer "F.Fab")
		)
		(fp_line
			(start -0.12065 -0.2794)
			(end 0.12065 -0.2794)
			(stroke
				(width 0.1)
				(type default)
			)
			(layer "F.Fab")
		)
		(fp_line
			(start -0.12065 0.2794)
			(end -0.12065 0.3048)
			(stroke
				(width 0.1)
				(type default)
			)
			(layer "F.Fab")
		)
		(fp_line
			(start -0.12065 0.3048)
			(end -0.67945 0.3048)
			(stroke
				(width 0.1)
				(type default)
			)
			(layer "F.Fab")
		)
		(fp_line
			(start 0.120396 0.2794)
			(end -0.12065 0.2794)
			(stroke
				(width 0.1)
				(type default)
			)
			(layer "F.Fab")
		)
		(fp_line
			(start 0.120396 0.3048)
			(end 0.120396 0.2794)
			(stroke
				(width 0.1)
				(type default)
			)
			(layer "F.Fab")
		)
		(fp_line
			(start 0.12065 -0.3048)
			(end 0.67945 -0.3048)
			(stroke
				(width 0.1)
				(type default)
			)
			(layer "F.Fab")
		)
		(fp_line
			(start 0.12065 -0.2794)
			(end 0.12065 -0.3048)
			(stroke
				(width 0.1)
				(type default)
			)
			(layer "F.Fab")
		)
		(fp_line
			(start 0.67945 -0.3048)
			(end 0.67945 0.3048)
			(stroke
				(width 0.1)
				(type default)
			)
			(layer "F.Fab")
		)
		(fp_line
			(start 0.67945 0.3048)
			(end 0.120396 0.3048)
			(stroke
				(width 0.1)
				(type default)
			)
			(layer "F.Fab")
		)
		(pad "1" smd circle
			(at -0.40005 0)
			(size 0 0)
			(layers "F.Cu" "F.Mask" "F.Paste")
			(net "NIC1_RBT_ARB_OUT")
		)
		(pad "2" smd circle
			(at 0.40005 0)
			(size 0 0)
			(layers "F.Cu" "F.Mask" "F.Paste")
			(net "NIC1_RBT_ARB_IN")
		)
	)
	(footprint ""
		(layer "F.Cu")
		(at 428.319438 -143.504666 180)
		(property "Reference" "C648"
			(at 0 0 180)
			(layer "F.SilkS")
			(hide yes)
			(effects
				(font
					(size 1.27 1.27)
				)
			)
		)
		(property "Value" ""
			(at 0 0 180)
			(layer "F.Fab")
			(effects
				(font
					(size 1.27 1.27)
				)
			)
		)
		(duplicate_pad_numbers_are_jumpers no)
		(fp_line
			(start 0.299974 0.150114)
			(end -0.299974 0.150114)
			(stroke
				(width 0.1)
				(type default)
			)
			(layer "F.Fab")
		)
		(fp_line
			(start 0.299974 -0.150114)
			(end 0.299974 0.150114)
			(stroke
				(width 0.1)
				(type default)
			)
			(layer "F.Fab")
		)
		(fp_line
			(start -0.299974 0.150114)
			(end -0.299974 -0.150114)
			(stroke
				(width 0.1)
				(type default)
			)
			(layer "F.Fab")
		)
		(fp_line
			(start -0.299974 -0.150114)
			(end 0.299974 -0.150114)
			(stroke
				(width 0.1)
				(type default)
			)
			(layer "F.Fab")
		)
		(pad "1" smd rect
			(at -0.2667 0 180)
			(size 0.3048 0.381)
			(layers "F.Cu" "F.Mask" "F.Paste")
			(net "P5E_PEX3_STN0_TX_DP<8>")
		)
		(pad "2" smd rect
			(at 0.2667 0 180)
			(size 0.3048 0.381)
			(layers "F.Cu" "F.Mask" "F.Paste")
			(net "P5E_PEX3_STN0_TX_C_DP<8>")
		)
	)
	(footprint ""
		(layer "F.Cu")
		(at 248.375678 -152.71115 -90)
		(property "Reference" "R732"
			(at 0 0 270)
			(layer "F.SilkS")
			(hide yes)
			(effects
				(font
					(size 1.27 1.27)
				)
			)
		)
		(property "Value" ""
			(at 0 0 270)
			(layer "F.Fab")
			(effects
				(font
					(size 1.27 1.27)
				)
			)
		)
		(duplicate_pad_numbers_are_jumpers no)
		(fp_line
			(start -0.7874 0.4064)
			(end -0.7874 -0.4064)
			(stroke
				(width 0.1524)
				(type default)
			)
			(layer "F.SilkS")
		)
		(fp_line
			(start 0.7874 0.4064)
			(end -0.7874 0.4064)
			(stroke
				(width 0.1524)
				(type default)
			)
			(layer "F.SilkS")
		)
		(fp_line
			(start -0.7874 -0.4064)
			(end 0.7874 -0.4064)
			(stroke
				(width 0.1524)
				(type default)
			)
			(layer "F.SilkS")
		)
		(fp_line
			(start 0.7874 -0.4064)
			(end 0.7874 0.4064)
			(stroke
				(width 0.1524)
				(type default)
			)
			(layer "F.SilkS")
		)
		(fp_line
			(start -0.67945 0.3048)
			(end -0.67945 -0.305054)
			(stroke
				(width 0.1)
				(type default)
			)
			(layer "F.Fab")
		)
		(fp_line
			(start -0.12065 0.3048)
			(end -0.67945 0.3048)
			(stroke
				(width 0.1)
				(type default)
			)
			(layer "F.Fab")
		)
		(fp_line
			(start 0.120396 0.3048)
			(end 0.120396 0.2794)
			(stroke
				(width 0.1)
				(type default)
			)
			(layer "F.Fab")
		)
		(fp_line
			(start 0.67945 0.3048)
			(end 0.120396 0.3048)
			(stroke
				(width 0.1)
				(type default)
			)
			(layer "F.Fab")
		)
		(fp_line
			(start -0.12065 0.2794)
			(end -0.12065 0.3048)
			(stroke
				(width 0.1)
				(type default)
			)
			(layer "F.Fab")
		)
		(fp_line
			(start 0.120396 0.2794)
			(end -0.12065 0.2794)
			(stroke
				(width 0.1)
				(type default)
			)
			(layer "F.Fab")
		)
		(fp_line
			(start -0.12065 -0.2794)
			(end 0.12065 -0.2794)
			(stroke
				(width 0.1)
				(type default)
			)
			(layer "F.Fab")
		)
		(fp_line
			(start 0.12065 -0.2794)
			(end 0.12065 -0.3048)
			(stroke
				(width 0.1)
				(type default)
			)
			(layer "F.Fab")
		)
		(fp_line
			(start 0.12065 -0.3048)
			(end 0.67945 -0.3048)
			(stroke
				(width 0.1)
				(type default)
			)
			(layer "F.Fab")
		)
		(fp_line
			(start 0.67945 -0.3048)
			(end 0.67945 0.3048)
			(stroke
				(width 0.1)
				(type default)
			)
			(layer "F.Fab")
		)
		(fp_line
			(start -0.67945 -0.305054)
			(end -0.12065 -0.305054)
			(stroke
				(width 0.1)
				(type default)
			)
			(layer "F.Fab")
		)
		(fp_line
			(start -0.12065 -0.305054)
			(end -0.12065 -0.2794)
			(stroke
				(width 0.1)
				(type default)
			)
			(layer "F.Fab")
		)
		(pad "1" smd circle
			(at -0.40005 0 270)
			(size 0 0)
			(layers "F.Cu" "F.Mask" "F.Paste")
			(net "SMB_BIC_I2C6_MUX_NIC_ADC_R_SDA")
		)
		(pad "2" smd circle
			(at 0.40005 0 270)
			(size 0 0)
			(layers "F.Cu" "F.Mask" "F.Paste")
			(net "SMB_NIC4_ADC_SDA")
		)
	)
	(footprint ""
		(layer "F.Cu")
		(at 328.295 -237.363 90)
		(property "Reference" "Q19"
			(at 1.7018 -1.95453 90)
			(unlocked yes)
			(layer "F.SilkS")
			(effects
				(font
					(size 0.7874 0.5842)
					(thickness 0.1524)
				)
			)
		)
		(property "Value" ""
			(at 0 0 90)
			(layer "F.Fab")
			(effects
				(font
					(size 1.27 1.27)
				)
			)
		)
		(duplicate_pad_numbers_are_jumpers no)
		(fp_line
			(start 1.376172 -1.199896)
			(end 1.376172 1.199896)
			(stroke
				(width 0.1524)
				(type default)
			)
			(layer "F.SilkS")
		)
		(fp_line
			(start 0.508 -1.199896)
			(end 1.376172 -1.199896)
			(stroke
				(width 0.1524)
				(type default)
			)
			(layer "F.SilkS")
		)
		(fp_line
			(start -0.508 -1.199896)
			(end 0 -0.762)
			(stroke
				(width 0.1524)
				(type default)
			)
			(layer "F.SilkS")
		)
		(fp_line
			(start -1.376172 -1.199896)
			(end -0.508 -1.199896)
			(stroke
				(width 0.1524)
				(type default)
			)
			(layer "F.SilkS")
		)
		(fp_line
			(start 0 -0.762)
			(end 0.508 -1.199896)
			(stroke
				(width 0.1524)
				(type default)
			)
			(layer "F.SilkS")
		)
		(fp_line
			(start 1.376172 1.199896)
			(end -1.376172 1.199896)
			(stroke
				(width 0.1524)
				(type default)
			)
			(layer "F.SilkS")
		)
		(fp_line
			(start -1.376172 1.199896)
			(end -1.376172 -1.199896)
			(stroke
				(width 0.1524)
				(type default)
			)
			(layer "F.SilkS")
		)
		(fp_poly
			(pts
				(xy -1.4605 -0.7493) (xy -2.2225 -1.1303) (xy -2.2225 -0.3683)
			)
			(stroke
				(width 0)
				(type default)
			)
			(fill yes)
			(layer "F.SilkS")
		)
		(fp_line
			(start 0.674878 -1.100074)
			(end 0.674878 1.100074)
			(stroke
				(width 0.1)
				(type default)
			)
			(layer "F.Fab")
		)
		(fp_line
			(start -0.674878 -1.100074)
			(end 0.674878 -1.100074)
			(stroke
				(width 0.1)
				(type default)
			)
			(layer "F.Fab")
		)
		(fp_line
			(start 0.674878 1.100074)
			(end -0.674878 1.100074)
			(stroke
				(width 0.1)
				(type default)
			)
			(layer "F.Fab")
		)
		(fp_line
			(start -0.674878 1.100074)
			(end -0.674878 -1.100074)
			(stroke
				(width 0.1)
				(type default)
			)
			(layer "F.Fab")
		)
		(fp_poly
			(pts
				(xy -1.4605 -0.7493) (xy -2.2225 -1.1303) (xy -2.2225 -0.3683)
			)
			(stroke
				(width 0)
				(type default)
			)
			(fill yes)
			(layer "F.Fab")
		)
		(pad "1" smd rect
			(at -0.899922 -0.750062)
			(size 0.6096 0.6096)
			(layers "F.Cu" "F.Mask" "F.Paste")
			(net "GND")
		)
		(pad "2" smd rect
			(at -0.899922 0)
			(size 0.4064 0.6096)
			(layers "F.Cu" "F.Mask" "F.Paste")
			(net "PRSNT_GPU_N")
		)
		(pad "3" smd rect
			(at -0.899922 0.750062)
			(size 0.6096 0.6096)
			(layers "F.Cu" "F.Mask" "F.Paste")
			(net "PRSNT_GPU_ISO_N")
		)
		(pad "4" smd rect
			(at 0.899922 0.750062)
			(size 0.6096 0.6096)
			(layers "F.Cu" "F.Mask" "F.Paste")
			(net "GND")
		)
		(pad "5" smd rect
			(at 0.899922 0)
			(size 0.4064 0.6096)
			(layers "F.Cu" "F.Mask" "F.Paste")
			(net "PRSNT_GPU_ISO")
		)
		(pad "6" smd rect
			(at 0.899922 -0.750062)
			(size 0.6096 0.6096)
			(layers "F.Cu" "F.Mask" "F.Paste")
			(net "PRSNT_GPU_ISO")
		)
	)
	(footprint ""
		(layer "F.Cu")
		(at 131.404868 -343.952322 90)
		(property "Reference" "C2258"
			(at 0 0 90)
			(layer "F.SilkS")
			(hide yes)
			(effects
				(font
					(size 1.27 1.27)
				)
			)
		)
		(property "Value" ""
			(at 0 0 90)
			(layer "F.Fab")
			(effects
				(font
					(size 1.27 1.27)
				)
			)
		)
		(duplicate_pad_numbers_are_jumpers no)
		(fp_line
			(start 0.299974 -0.150114)
			(end 0.299974 0.150114)
			(stroke
				(width 0.1)
				(type default)
			)
			(layer "F.Fab")
		)
		(fp_line
			(start -0.299974 -0.150114)
			(end 0.299974 -0.150114)
			(stroke
				(width 0.1)
				(type default)
			)
			(layer "F.Fab")
		)
		(fp_line
			(start 0.299974 0.150114)
			(end -0.299974 0.150114)
			(stroke
				(width 0.1)
				(type default)
			)
			(layer "F.Fab")
		)
		(fp_line
			(start -0.299974 0.150114)
			(end -0.299974 -0.150114)
			(stroke
				(width 0.1)
				(type default)
			)
			(layer "F.Fab")
		)
		(pad "1" smd rect
			(at -0.2667 0 90)
			(size 0.3048 0.381)
			(layers "F.Cu" "F.Mask" "F.Paste")
			(net "P5E_PEX1_STN5_TX_DN<88>")
		)
		(pad "2" smd rect
			(at 0.2667 0 90)
			(size 0.3048 0.381)
			(layers "F.Cu" "F.Mask" "F.Paste")
			(net "P5E_PEX1_STN5_TX_C_DN<88>")
		)
	)
	(footprint ""
		(layer "F.Cu")
		(at 234.271058 -82.118708)
		(property "Reference" "R6726"
			(at 0 0 0)
			(layer "F.SilkS")
			(hide yes)
			(effects
				(font
					(size 1.27 1.27)
				)
			)
		)
		(property "Value" ""
			(at 0 0 0)
			(layer "F.Fab")
			(effects
				(font
					(size 1.27 1.27)
				)
			)
		)
		(duplicate_pad_numbers_are_jumpers no)
		(fp_line
			(start -0.7874 -0.4064)
			(end 0.7874 -0.4064)
			(stroke
				(width 0.1524)
				(type default)
			)
			(layer "F.SilkS")
		)
		(fp_line
			(start -0.7874 0.4064)
			(end -0.7874 -0.4064)
			(stroke
				(width 0.1524)
				(type default)
			)
			(layer "F.SilkS")
		)
		(fp_line
			(start 0.7874 -0.4064)
			(end 0.7874 0.4064)
			(stroke
				(width 0.1524)
				(type default)
			)
			(layer "F.SilkS")
		)
		(fp_line
			(start 0.7874 0.4064)
			(end 0.004572 0.4064)
			(stroke
				(width 0.1524)
				(type default)
			)
			(layer "F.SilkS")
		)
		(fp_line
			(start -0.67945 -0.305054)
			(end -0.12065 -0.305054)
			(stroke
				(width 0.1)
				(type default)
			)
			(layer "F.Fab")
		)
		(fp_line
			(start -0.67945 0.3048)
			(end -0.67945 -0.305054)
			(stroke
				(width 0.1)
				(type default)
			)
			(layer "F.Fab")
		)
		(fp_line
			(start -0.12065 -0.305054)
			(end -0.12065 -0.2794)
			(stroke
				(width 0.1)
				(type default)
			)
			(layer "F.Fab")
		)
		(fp_line
			(start -0.12065 -0.2794)
			(end 0.12065 -0.2794)
			(stroke
				(width 0.1)
				(type default)
			)
			(layer "F.Fab")
		)
		(fp_line
			(start -0.12065 0.2794)
			(end -0.12065 0.3048)
			(stroke
				(width 0.1)
				(type default)
			)
			(layer "F.Fab")
		)
		(fp_line
			(start -0.12065 0.3048)
			(end -0.67945 0.3048)
			(stroke
				(width 0.1)
				(type default)
			)
			(layer "F.Fab")
		)
		(fp_line
			(start 0.120396 0.2794)
			(end -0.12065 0.2794)
			(stroke
				(width 0.1)
				(type default)
			)
			(layer "F.Fab")
		)
		(fp_line
			(start 0.120396 0.3048)
			(end 0.120396 0.2794)
			(stroke
				(width 0.1)
				(type default)
			)
			(layer "F.Fab")
		)
		(fp_line
			(start 0.12065 -0.3048)
			(end 0.67945 -0.3048)
			(stroke
				(width 0.1)
				(type default)
			)
			(layer "F.Fab")
		)
		(fp_line
			(start 0.12065 -0.2794)
			(end 0.12065 -0.3048)
			(stroke
				(width 0.1)
				(type default)
			)
			(layer "F.Fab")
		)
		(fp_line
			(start 0.67945 -0.3048)
			(end 0.67945 0.3048)
			(stroke
				(width 0.1)
				(type default)
			)
			(layer "F.Fab")
		)
		(fp_line
			(start 0.67945 0.3048)
			(end 0.120396 0.3048)
			(stroke
				(width 0.1)
				(type default)
			)
			(layer "F.Fab")
		)
		(pad "1" smd rect
			(at -0.40005 0 180)
			(size 0.4572 0.508)
			(layers "F.Cu" "F.Mask" "F.Paste")
			(net "USB2_CP2108_SDB_DP")
		)
		(pad "2" smd rect
			(at 0.40005 0 180)
			(size 0.4572 0.508)
			(layers "F.Cu" "F.Mask" "F.Paste")
			(net "GND")
		)
	)
	(footprint ""
		(layer "F.Cu")
		(at 223.50476 -314.068714 180)
		(property "Reference" "PC228"
			(at 0 0 180)
			(layer "F.SilkS")
			(hide yes)
			(effects
				(font
					(size 1.27 1.27)
				)
			)
		)
		(property "Value" ""
			(at 0 0 180)
			(layer "F.Fab")
			(effects
				(font
					(size 1.27 1.27)
				)
			)
		)
		(duplicate_pad_numbers_are_jumpers no)
		(fp_line
			(start 1.524 0.762)
			(end -1.524 0.762)
			(stroke
				(width 0.1524)
				(type default)
			)
			(layer "F.SilkS")
		)
		(fp_line
			(start 1.524 -0.762)
			(end 1.524 0.762)
			(stroke
				(width 0.1524)
				(type default)
			)
			(layer "F.SilkS")
		)
		(fp_line
			(start -1.524 0.762)
			(end -1.524 -0.762)
			(stroke
				(width 0.1524)
				(type default)
			)
			(layer "F.SilkS")
		)
		(fp_line
			(start -1.524 -0.762)
			(end 1.524 -0.762)
			(stroke
				(width 0.1524)
				(type default)
			)
			(layer "F.SilkS")
		)
		(fp_line
			(start 1.1049 0.724916)
			(end 1.1049 -0.724916)
			(stroke
				(width 0.1)
				(type default)
			)
			(layer "F.Fab")
		)
		(fp_line
			(start 1.1049 -0.724916)
			(end -1.1049 -0.724916)
			(stroke
				(width 0.1)
				(type default)
			)
			(layer "F.Fab")
		)
		(fp_line
			(start -1.1049 0.724916)
			(end 1.1049 0.724916)
			(stroke
				(width 0.1)
				(type default)
			)
			(layer "F.Fab")
		)
		(fp_line
			(start -1.1049 -0.724916)
			(end -1.1049 0.724916)
			(stroke
				(width 0.1)
				(type default)
			)
			(layer "F.Fab")
		)
		(pad "1" smd rect
			(at -0.889 0)
			(size 1.016 1.27)
			(layers "F.Cu" "F.Mask" "F.Paste")
			(net "SW_P12V_P1V25_PEX1_FLT")
		)
		(pad "2" smd rect
			(at 0.889 0)
			(size 1.016 1.27)
			(layers "F.Cu" "F.Mask" "F.Paste")
			(net "GND")
		)
	)
	(footprint ""
		(layer "F.Cu")
		(at 361.188 -184.15 180)
		(property "Reference" "R4648"
			(at 0 0 180)
			(layer "F.SilkS")
			(hide yes)
			(effects
				(font
					(size 1.27 1.27)
				)
			)
		)
		(property "Value" ""
			(at 0 0 180)
			(layer "F.Fab")
			(effects
				(font
					(size 1.27 1.27)
				)
			)
		)
		(duplicate_pad_numbers_are_jumpers no)
		(fp_line
			(start 0.7874 0.4064)
			(end -0.7874 0.4064)
			(stroke
				(width 0.1524)
				(type default)
			)
			(layer "F.SilkS")
		)
		(fp_line
			(start 0.7874 -0.4064)
			(end 0.7874 0.4064)
			(stroke
				(width 0.1524)
				(type default)
			)
			(layer "F.SilkS")
		)
		(fp_line
			(start -0.7874 0.4064)
			(end -0.7874 -0.4064)
			(stroke
				(width 0.1524)
				(type default)
			)
			(layer "F.SilkS")
		)
		(fp_line
			(start -0.7874 -0.4064)
			(end 0.7874 -0.4064)
			(stroke
				(width 0.1524)
				(type default)
			)
			(layer "F.SilkS")
		)
		(fp_line
			(start 0.67945 0.3048)
			(end 0.120396 0.3048)
			(stroke
				(width 0.1)
				(type default)
			)
			(layer "F.Fab")
		)
		(fp_line
			(start 0.67945 -0.3048)
			(end 0.67945 0.3048)
			(stroke
				(width 0.1)
				(type default)
			)
			(layer "F.Fab")
		)
		(fp_line
			(start 0.12065 -0.2794)
			(end 0.12065 -0.3048)
			(stroke
				(width 0.1)
				(type default)
			)
			(layer "F.Fab")
		)
		(fp_line
			(start 0.12065 -0.3048)
			(end 0.67945 -0.3048)
			(stroke
				(width 0.1)
				(type default)
			)
			(layer "F.Fab")
		)
		(fp_line
			(start 0.120396 0.3048)
			(end 0.120396 0.2794)
			(stroke
				(width 0.1)
				(type default)
			)
			(layer "F.Fab")
		)
		(fp_line
			(start 0.120396 0.2794)
			(end -0.12065 0.2794)
			(stroke
				(width 0.1)
				(type default)
			)
			(layer "F.Fab")
		)
		(fp_line
			(start -0.12065 0.3048)
			(end -0.67945 0.3048)
			(stroke
				(width 0.1)
				(type default)
			)
			(layer "F.Fab")
		)
		(fp_line
			(start -0.12065 0.2794)
			(end -0.12065 0.3048)
			(stroke
				(width 0.1)
				(type default)
			)
			(layer "F.Fab")
		)
		(fp_line
			(start -0.12065 -0.2794)
			(end 0.12065 -0.2794)
			(stroke
				(width 0.1)
				(type default)
			)
			(layer "F.Fab")
		)
		(fp_line
			(start -0.12065 -0.305054)
			(end -0.12065 -0.2794)
			(stroke
				(width 0.1)
				(type default)
			)
			(layer "F.Fab")
		)
		(fp_line
			(start -0.67945 0.3048)
			(end -0.67945 -0.305054)
			(stroke
				(width 0.1)
				(type default)
			)
			(layer "F.Fab")
		)
		(fp_line
			(start -0.67945 -0.305054)
			(end -0.12065 -0.305054)
			(stroke
				(width 0.1)
				(type default)
			)
			(layer "F.Fab")
		)
		(pad "1" smd circle
			(at -0.40005 0 180)
			(size 0 0)
			(layers "F.Cu" "F.Mask" "F.Paste")
			(net "RST_PEX_SSD3_PERST_N")
		)
		(pad "2" smd circle
			(at 0.40005 0 180)
			(size 0 0)
			(layers "F.Cu" "F.Mask" "F.Paste")
			(net "RST_PEX_SSD3_PERST_R_N")
		)
	)
	(footprint ""
		(layer "F.Cu")
		(at 393.669266 -84.928202 180)
		(property "Reference" "R1774"
			(at 0 0 180)
			(layer "F.SilkS")
			(hide yes)
			(effects
				(font
					(size 1.27 1.27)
				)
			)
		)
		(property "Value" ""
			(at 0 0 180)
			(layer "F.Fab")
			(effects
				(font
					(size 1.27 1.27)
				)
			)
		)
		(duplicate_pad_numbers_are_jumpers no)
		(fp_line
			(start 0.7874 0.4064)
			(end -0.7874 0.4064)
			(stroke
				(width 0.1524)
				(type default)
			)
			(layer "F.SilkS")
		)
		(fp_line
			(start 0.7874 -0.4064)
			(end 0.7874 0.4064)
			(stroke
				(width 0.1524)
				(type default)
			)
			(layer "F.SilkS")
		)
		(fp_line
			(start -0.7874 0.4064)
			(end -0.7874 -0.4064)
			(stroke
				(width 0.1524)
				(type default)
			)
			(layer "F.SilkS")
		)
		(fp_line
			(start -0.7874 -0.4064)
			(end 0.7874 -0.4064)
			(stroke
				(width 0.1524)
				(type default)
			)
			(layer "F.SilkS")
		)
		(fp_line
			(start 0.67945 0.3048)
			(end 0.120396 0.3048)
			(stroke
				(width 0.1)
				(type default)
			)
			(layer "F.Fab")
		)
		(fp_line
			(start 0.67945 -0.3048)
			(end 0.67945 0.3048)
			(stroke
				(width 0.1)
				(type default)
			)
			(layer "F.Fab")
		)
		(fp_line
			(start 0.12065 -0.2794)
			(end 0.12065 -0.3048)
			(stroke
				(width 0.1)
				(type default)
			)
			(layer "F.Fab")
		)
		(fp_line
			(start 0.12065 -0.3048)
			(end 0.67945 -0.3048)
			(stroke
				(width 0.1)
				(type default)
			)
			(layer "F.Fab")
		)
		(fp_line
			(start 0.120396 0.3048)
			(end 0.120396 0.2794)
			(stroke
				(width 0.1)
				(type default)
			)
			(layer "F.Fab")
		)
		(fp_line
			(start 0.120396 0.2794)
			(end -0.12065 0.2794)
			(stroke
				(width 0.1)
				(type default)
			)
			(layer "F.Fab")
		)
		(fp_line
			(start -0.12065 0.3048)
			(end -0.67945 0.3048)
			(stroke
				(width 0.1)
				(type default)
			)
			(layer "F.Fab")
		)
		(fp_line
			(start -0.12065 0.2794)
			(end -0.12065 0.3048)
			(stroke
				(width 0.1)
				(type default)
			)
			(layer "F.Fab")
		)
		(fp_line
			(start -0.12065 -0.2794)
			(end 0.12065 -0.2794)
			(stroke
				(width 0.1)
				(type default)
			)
			(layer "F.Fab")
		)
		(fp_line
			(start -0.12065 -0.305054)
			(end -0.12065 -0.2794)
			(stroke
				(width 0.1)
				(type default)
			)
			(layer "F.Fab")
		)
		(fp_line
			(start -0.67945 0.3048)
			(end -0.67945 -0.305054)
			(stroke
				(width 0.1)
				(type default)
			)
			(layer "F.Fab")
		)
		(fp_line
			(start -0.67945 -0.305054)
			(end -0.12065 -0.305054)
			(stroke
				(width 0.1)
				(type default)
			)
			(layer "F.Fab")
		)
		(pad "1" smd circle
			(at -0.40005 0 180)
			(size 0 0)
			(layers "F.Cu" "F.Mask" "F.Paste")
			(net "SMB_BIC_I2C6_MUX_VR_R_SDA")
		)
		(pad "2" smd circle
			(at 0.40005 0 180)
			(size 0 0)
			(layers "F.Cu" "F.Mask" "F.Paste")
			(net "SMB_BIC_I2C6_MUX_VR_SDA")
		)
	)
	(footprint ""
		(layer "F.Cu")
		(at 387.580632 -133.129782)
		(property "Reference" "C671"
			(at 0 0 0)
			(layer "F.SilkS")
			(hide yes)
			(effects
				(font
					(size 1.27 1.27)
				)
			)
		)
		(property "Value" ""
			(at 0 0 0)
			(layer "F.Fab")
			(effects
				(font
					(size 1.27 1.27)
				)
			)
		)
		(duplicate_pad_numbers_are_jumpers no)
		(fp_line
			(start -0.299974 -0.150114)
			(end 0.299974 -0.150114)
			(stroke
				(width 0.1)
				(type default)
			)
			(layer "F.Fab")
		)
		(fp_line
			(start -0.299974 0.150114)
			(end -0.299974 -0.150114)
			(stroke
				(width 0.1)
				(type default)
			)
			(layer "F.Fab")
		)
		(fp_line
			(start 0.299974 -0.150114)
			(end 0.299974 0.150114)
			(stroke
				(width 0.1)
				(type default)
			)
			(layer "F.Fab")
		)
		(fp_line
			(start 0.299974 0.150114)
			(end -0.299974 0.150114)
			(stroke
				(width 0.1)
				(type default)
			)
			(layer "F.Fab")
		)
		(pad "1" smd rect
			(at -0.2667 0)
			(size 0.3048 0.381)
			(layers "F.Cu" "F.Mask" "F.Paste")
			(net "P5E_PEX3_STN1_TX_DP<29>")
		)
		(pad "2" smd rect
			(at 0.2667 0)
			(size 0.3048 0.381)
			(layers "F.Cu" "F.Mask" "F.Paste")
			(net "P5E_PEX3_STN1_TX_C_DP<29>")
		)
	)
	(footprint ""
		(layer "F.Cu")
		(at 36.312094 -137.2489 -90)
		(property "Reference" "C853"
			(at 0 0 270)
			(layer "F.SilkS")
			(hide yes)
			(effects
				(font
					(size 1.27 1.27)
				)
			)
		)
		(property "Value" ""
			(at 0 0 270)
			(layer "F.Fab")
			(effects
				(font
					(size 1.27 1.27)
				)
			)
		)
		(duplicate_pad_numbers_are_jumpers no)
		(fp_line
			(start -0.7874 0.4064)
			(end -0.7874 -0.4064)
			(stroke
				(width 0.1524)
				(type default)
			)
			(layer "F.SilkS")
		)
		(fp_line
			(start 0.7874 0.4064)
			(end -0.7874 0.4064)
			(stroke
				(width 0.1524)
				(type default)
			)
			(layer "F.SilkS")
		)
		(fp_line
			(start -0.7874 -0.4064)
			(end 0.7874 -0.4064)
			(stroke
				(width 0.1524)
				(type default)
			)
			(layer "F.SilkS")
		)
		(fp_line
			(start 0.7874 -0.4064)
			(end 0.7874 0.4064)
			(stroke
				(width 0.1524)
				(type default)
			)
			(layer "F.SilkS")
		)
		(fp_line
			(start -0.67945 0.3048)
			(end -0.67945 -0.305054)
			(stroke
				(width 0.1)
				(type default)
			)
			(layer "F.Fab")
		)
		(fp_line
			(start -0.12065 0.3048)
			(end -0.67945 0.3048)
			(stroke
				(width 0.1)
				(type default)
			)
			(layer "F.Fab")
		)
		(fp_line
			(start 0.120396 0.3048)
			(end 0.120396 0.2794)
			(stroke
				(width 0.1)
				(type default)
			)
			(layer "F.Fab")
		)
		(fp_line
			(start 0.67945 0.3048)
			(end 0.120396 0.3048)
			(stroke
				(width 0.1)
				(type default)
			)
			(layer "F.Fab")
		)
		(fp_line
			(start -0.12065 0.2794)
			(end -0.12065 0.3048)
			(stroke
				(width 0.1)
				(type default)
			)
			(layer "F.Fab")
		)
		(fp_line
			(start 0.120396 0.2794)
			(end -0.12065 0.2794)
			(stroke
				(width 0.1)
				(type default)
			)
			(layer "F.Fab")
		)
		(fp_line
			(start -0.12065 -0.2794)
			(end 0.12065 -0.2794)
			(stroke
				(width 0.1)
				(type default)
			)
			(layer "F.Fab")
		)
		(fp_line
			(start 0.12065 -0.2794)
			(end 0.12065 -0.3048)
			(stroke
				(width 0.1)
				(type default)
			)
			(layer "F.Fab")
		)
		(fp_line
			(start 0.12065 -0.3048)
			(end 0.67945 -0.3048)
			(stroke
				(width 0.1)
				(type default)
			)
			(layer "F.Fab")
		)
		(fp_line
			(start 0.67945 -0.3048)
			(end 0.67945 0.3048)
			(stroke
				(width 0.1)
				(type default)
			)
			(layer "F.Fab")
		)
		(fp_line
			(start -0.67945 -0.305054)
			(end -0.12065 -0.305054)
			(stroke
				(width 0.1)
				(type default)
			)
			(layer "F.Fab")
		)
		(fp_line
			(start -0.12065 -0.305054)
			(end -0.12065 -0.2794)
			(stroke
				(width 0.1)
				(type default)
			)
			(layer "F.Fab")
		)
		(pad "1" smd circle
			(at -0.40005 0 270)
			(size 0 0)
			(layers "F.Cu" "F.Mask" "F.Paste")
			(net "P3V3_NIC0")
		)
		(pad "2" smd circle
			(at 0.40005 0 270)
			(size 0 0)
			(layers "F.Cu" "F.Mask" "F.Paste")
			(net "GND")
		)
	)
	(footprint ""
		(layer "F.Cu")
		(at 253.455678 -152.71115 90)
		(property "Reference" "R729"
			(at 0 0 90)
			(layer "F.SilkS")
			(hide yes)
			(effects
				(font
					(size 1.27 1.27)
				)
			)
		)
		(property "Value" ""
			(at 0 0 90)
			(layer "F.Fab")
			(effects
				(font
					(size 1.27 1.27)
				)
			)
		)
		(duplicate_pad_numbers_are_jumpers no)
		(fp_line
			(start 0.7874 -0.4064)
			(end 0.7874 0.4064)
			(stroke
				(width 0.1524)
				(type default)
			)
			(layer "F.SilkS")
		)
		(fp_line
			(start -0.7874 -0.4064)
			(end 0.7874 -0.4064)
			(stroke
				(width 0.1524)
				(type default)
			)
			(layer "F.SilkS")
		)
		(fp_line
			(start 0.7874 0.4064)
			(end -0.7874 0.4064)
			(stroke
				(width 0.1524)
				(type default)
			)
			(layer "F.SilkS")
		)
		(fp_line
			(start -0.7874 0.4064)
			(end -0.7874 -0.4064)
			(stroke
				(width 0.1524)
				(type default)
			)
			(layer "F.SilkS")
		)
		(fp_line
			(start -0.12065 -0.305054)
			(end -0.12065 -0.2794)
			(stroke
				(width 0.1)
				(type default)
			)
			(layer "F.Fab")
		)
		(fp_line
			(start -0.67945 -0.305054)
			(end -0.12065 -0.305054)
			(stroke
				(width 0.1)
				(type default)
			)
			(layer "F.Fab")
		)
		(fp_line
			(start 0.67945 -0.3048)
			(end 0.67945 0.3048)
			(stroke
				(width 0.1)
				(type default)
			)
			(layer "F.Fab")
		)
		(fp_line
			(start 0.12065 -0.3048)
			(end 0.67945 -0.3048)
			(stroke
				(width 0.1)
				(type default)
			)
			(layer "F.Fab")
		)
		(fp_line
			(start 0.12065 -0.2794)
			(end 0.12065 -0.3048)
			(stroke
				(width 0.1)
				(type default)
			)
			(layer "F.Fab")
		)
		(fp_line
			(start -0.12065 -0.2794)
			(end 0.12065 -0.2794)
			(stroke
				(width 0.1)
				(type default)
			)
			(layer "F.Fab")
		)
		(fp_line
			(start 0.120396 0.2794)
			(end -0.12065 0.2794)
			(stroke
				(width 0.1)
				(type default)
			)
			(layer "F.Fab")
		)
		(fp_line
			(start -0.12065 0.2794)
			(end -0.12065 0.3048)
			(stroke
				(width 0.1)
				(type default)
			)
			(layer "F.Fab")
		)
		(fp_line
			(start 0.67945 0.3048)
			(end 0.120396 0.3048)
			(stroke
				(width 0.1)
				(type default)
			)
			(layer "F.Fab")
		)
		(fp_line
			(start 0.120396 0.3048)
			(end 0.120396 0.2794)
			(stroke
				(width 0.1)
				(type default)
			)
			(layer "F.Fab")
		)
		(fp_line
			(start -0.12065 0.3048)
			(end -0.67945 0.3048)
			(stroke
				(width 0.1)
				(type default)
			)
			(layer "F.Fab")
		)
		(fp_line
			(start -0.67945 0.3048)
			(end -0.67945 -0.305054)
			(stroke
				(width 0.1)
				(type default)
			)
			(layer "F.Fab")
		)
		(pad "1" smd circle
			(at -0.40005 0 90)
			(size 0 0)
			(layers "F.Cu" "F.Mask" "F.Paste")
			(net "NIC4_ADC_A1")
		)
		(pad "2" smd circle
			(at 0.40005 0 90)
			(size 0 0)
			(layers "F.Cu" "F.Mask" "F.Paste")
			(net "GND")
		)
	)
	(footprint ""
		(layer "F.Cu")
		(at 211.400136 -181.613556 -90)
		(property "Reference" "C3626"
			(at 0 0 270)
			(layer "F.SilkS")
			(hide yes)
			(effects
				(font
					(size 1.27 1.27)
				)
			)
		)
		(property "Value" ""
			(at 0 0 270)
			(layer "F.Fab")
			(effects
				(font
					(size 1.27 1.27)
				)
			)
		)
		(duplicate_pad_numbers_are_jumpers no)
		(fp_line
			(start -0.7874 0.4064)
			(end -0.7874 -0.4064)
			(stroke
				(width 0.1524)
				(type default)
			)
			(layer "F.SilkS")
		)
		(fp_line
			(start 0.7874 0.4064)
			(end -0.7874 0.4064)
			(stroke
				(width 0.1524)
				(type default)
			)
			(layer "F.SilkS")
		)
		(fp_line
			(start -0.7874 -0.4064)
			(end 0.7874 -0.4064)
			(stroke
				(width 0.1524)
				(type default)
			)
			(layer "F.SilkS")
		)
		(fp_line
			(start 0.7874 -0.4064)
			(end 0.7874 0.4064)
			(stroke
				(width 0.1524)
				(type default)
			)
			(layer "F.SilkS")
		)
		(fp_line
			(start -0.67945 0.3048)
			(end -0.67945 -0.305054)
			(stroke
				(width 0.1)
				(type default)
			)
			(layer "F.Fab")
		)
		(fp_line
			(start -0.12065 0.3048)
			(end -0.67945 0.3048)
			(stroke
				(width 0.1)
				(type default)
			)
			(layer "F.Fab")
		)
		(fp_line
			(start 0.120396 0.3048)
			(end 0.120396 0.2794)
			(stroke
				(width 0.1)
				(type default)
			)
			(layer "F.Fab")
		)
		(fp_line
			(start 0.67945 0.3048)
			(end 0.120396 0.3048)
			(stroke
				(width 0.1)
				(type default)
			)
			(layer "F.Fab")
		)
		(fp_line
			(start -0.12065 0.2794)
			(end -0.12065 0.3048)
			(stroke
				(width 0.1)
				(type default)
			)
			(layer "F.Fab")
		)
		(fp_line
			(start 0.120396 0.2794)
			(end -0.12065 0.2794)
			(stroke
				(width 0.1)
				(type default)
			)
			(layer "F.Fab")
		)
		(fp_line
			(start -0.12065 -0.2794)
			(end 0.12065 -0.2794)
			(stroke
				(width 0.1)
				(type default)
			)
			(layer "F.Fab")
		)
		(fp_line
			(start 0.12065 -0.2794)
			(end 0.12065 -0.3048)
			(stroke
				(width 0.1)
				(type default)
			)
			(layer "F.Fab")
		)
		(fp_line
			(start 0.12065 -0.3048)
			(end 0.67945 -0.3048)
			(stroke
				(width 0.1)
				(type default)
			)
			(layer "F.Fab")
		)
		(fp_line
			(start 0.67945 -0.3048)
			(end 0.67945 0.3048)
			(stroke
				(width 0.1)
				(type default)
			)
			(layer "F.Fab")
		)
		(fp_line
			(start -0.67945 -0.305054)
			(end -0.12065 -0.305054)
			(stroke
				(width 0.1)
				(type default)
			)
			(layer "F.Fab")
		)
		(fp_line
			(start -0.12065 -0.305054)
			(end -0.12065 -0.2794)
			(stroke
				(width 0.1)
				(type default)
			)
			(layer "F.Fab")
		)
		(pad "1" smd circle
			(at -0.40005 0 270)
			(size 0 0)
			(layers "F.Cu" "F.Mask" "F.Paste")
			(net "P3V3_AUX")
		)
		(pad "2" smd circle
			(at 0.40005 0 270)
			(size 0 0)
			(layers "F.Cu" "F.Mask" "F.Paste")
			(net "GND")
		)
	)
	(footprint ""
		(layer "F.Cu")
		(at 19.885914 -413.969708 90)
		(property "Reference" "R5589"
			(at 0 0 90)
			(layer "F.SilkS")
			(hide yes)
			(effects
				(font
					(size 1.27 1.27)
				)
			)
		)
		(property "Value" ""
			(at 0 0 90)
			(layer "F.Fab")
			(effects
				(font
					(size 1.27 1.27)
				)
			)
		)
		(duplicate_pad_numbers_are_jumpers no)
		(fp_line
			(start 0.7874 -0.4064)
			(end 0.7874 0.4064)
			(stroke
				(width 0.1524)
				(type default)
			)
			(layer "F.SilkS")
		)
		(fp_line
			(start -0.7874 -0.4064)
			(end 0.7874 -0.4064)
			(stroke
				(width 0.1524)
				(type default)
			)
			(layer "F.SilkS")
		)
		(fp_line
			(start 0.7874 0.4064)
			(end -0.7874 0.4064)
			(stroke
				(width 0.1524)
				(type default)
			)
			(layer "F.SilkS")
		)
		(fp_line
			(start -0.7874 0.4064)
			(end -0.7874 -0.4064)
			(stroke
				(width 0.1524)
				(type default)
			)
			(layer "F.SilkS")
		)
		(fp_line
			(start -0.12065 -0.305054)
			(end -0.12065 -0.2794)
			(stroke
				(width 0.1)
				(type default)
			)
			(layer "F.Fab")
		)
		(fp_line
			(start -0.67945 -0.305054)
			(end -0.12065 -0.305054)
			(stroke
				(width 0.1)
				(type default)
			)
			(layer "F.Fab")
		)
		(fp_line
			(start 0.67945 -0.3048)
			(end 0.67945 0.3048)
			(stroke
				(width 0.1)
				(type default)
			)
			(layer "F.Fab")
		)
		(fp_line
			(start 0.12065 -0.3048)
			(end 0.67945 -0.3048)
			(stroke
				(width 0.1)
				(type default)
			)
			(layer "F.Fab")
		)
		(fp_line
			(start 0.12065 -0.2794)
			(end 0.12065 -0.3048)
			(stroke
				(width 0.1)
				(type default)
			)
			(layer "F.Fab")
		)
		(fp_line
			(start -0.12065 -0.2794)
			(end 0.12065 -0.2794)
			(stroke
				(width 0.1)
				(type default)
			)
			(layer "F.Fab")
		)
		(fp_line
			(start 0.120396 0.2794)
			(end -0.12065 0.2794)
			(stroke
				(width 0.1)
				(type default)
			)
			(layer "F.Fab")
		)
		(fp_line
			(start -0.12065 0.2794)
			(end -0.12065 0.3048)
			(stroke
				(width 0.1)
				(type default)
			)
			(layer "F.Fab")
		)
		(fp_line
			(start 0.67945 0.3048)
			(end 0.120396 0.3048)
			(stroke
				(width 0.1)
				(type default)
			)
			(layer "F.Fab")
		)
		(fp_line
			(start 0.120396 0.3048)
			(end 0.120396 0.2794)
			(stroke
				(width 0.1)
				(type default)
			)
			(layer "F.Fab")
		)
		(fp_line
			(start -0.12065 0.3048)
			(end -0.67945 0.3048)
			(stroke
				(width 0.1)
				(type default)
			)
			(layer "F.Fab")
		)
		(fp_line
			(start -0.67945 0.3048)
			(end -0.67945 -0.305054)
			(stroke
				(width 0.1)
				(type default)
			)
			(layer "F.Fab")
		)
		(pad "1" smd circle
			(at -0.40005 0 90)
			(size 0 0)
			(layers "F.Cu" "F.Mask" "F.Paste")
			(net "LM75_0_A1")
		)
		(pad "2" smd circle
			(at 0.40005 0 90)
			(size 0 0)
			(layers "F.Cu" "F.Mask" "F.Paste")
			(net "P3V3_AUX")
		)
	)
	(footprint ""
		(layer "F.Cu")
		(at 29.649674 -320.900044)
		(property "Reference" "H91"
			(at -6.35889 -8.560562 0)
			(unlocked yes)
			(layer "F.SilkS")
			(effects
				(font
					(size 0.7874 0.5842)
					(thickness 0.1524)
				)
				(justify left)
			)
		)
		(property "Value" ""
			(at 0 0 0)
			(layer "F.Fab")
			(effects
				(font
					(size 1.27 1.27)
				)
			)
		)
		(duplicate_pad_numbers_are_jumpers no)
		(fp_arc
			(start 5.723636 5.58927)
			(mid -7.409086 -3.017493)
			(end 7.999984 0)
			(stroke
				(width 0.1524)
				(type default)
			)
			(layer "F.SilkS")
		)
		(fp_arc
			(start -7.158482 -3.570986)
			(mid -5.682378 -5.630896)
			(end -3.63601 -7.125716)
			(stroke
				(width 0.1524)
				(type default)
			)
			(layer "B.SilkS")
		)
		(fp_arc
			(start -2.03708 -7.736078)
			(mid 4.550125 -6.580543)
			(end 7.957312 -0.825754)
			(stroke
				(width 0.1524)
				(type default)
			)
			(layer "B.SilkS")
		)
		(fp_arc
			(start -0.713232 7.968234)
			(mid -6.539883 4.607652)
			(end -7.74319 -2.010156)
			(stroke
				(width 0.1524)
				(type default)
			)
			(layer "B.SilkS")
		)
		(fp_arc
			(start 5.242052 6.043168)
			(mid 3.165825 7.347029)
			(end 0.792226 7.960868)
			(stroke
				(width 0.1524)
				(type default)
			)
			(layer "B.SilkS")
		)
		(fp_circle
			(center 0 0)
			(end 7.999984 0)
			(stroke
				(width 0.1)
				(type default)
			)
			(fill no)
			(layer "B.Fab")
		)
		(fp_circle
			(center 0 0)
			(end 7.999984 0)
			(stroke
				(width 0.1)
				(type default)
			)
			(fill no)
			(layer "F.Fab")
		)
		(pad "" np_thru_hole circle
			(at 0 0)
			(size 4.5212 4.5212)
			(drill 4.5212)
			(layers "*.Cu" "*.Mask")
			(clearance 0.381)
			(thermal_gap 0.381)
		)
		(pad "2" thru_hole circle
			(at 3.6322 0)
			(size 0.762 0.762)
			(drill 0.5588)
			(layers "*.Cu" "*.Mask")
			(remove_unused_layers no)
			(net "GND")
			(clearance 0.1524)
			(thermal_gap 0.1524)
		)
		(pad "3" thru_hole circle
			(at 2.568448 -2.568448)
			(size 0.762 0.762)
			(drill 0.5588)
			(layers "*.Cu" "*.Mask")
			(remove_unused_layers no)
			(net "GND")
			(clearance 0.1524)
			(thermal_gap 0.1524)
		)
		(pad "4" thru_hole circle
			(at 0 -3.6322)
			(size 0.762 0.762)
			(drill 0.5588)
			(layers "*.Cu" "*.Mask")
			(remove_unused_layers no)
			(net "GND")
			(clearance 0.1524)
			(thermal_gap 0.1524)
		)
		(pad "5" thru_hole circle
			(at -2.568448 -2.568448)
			(size 0.762 0.762)
			(drill 0.5588)
			(layers "*.Cu" "*.Mask")
			(remove_unused_layers no)
			(net "GND")
			(clearance 0.1524)
			(thermal_gap 0.1524)
		)
		(pad "6" thru_hole circle
			(at -3.6322 0)
			(size 0.762 0.762)
			(drill 0.5588)
			(layers "*.Cu" "*.Mask")
			(remove_unused_layers no)
			(net "GND")
			(clearance 0.1524)
			(thermal_gap 0.1524)
		)
		(pad "7" thru_hole circle
			(at -2.568448 2.568448)
			(size 0.762 0.762)
			(drill 0.5588)
			(layers "*.Cu" "*.Mask")
			(remove_unused_layers no)
			(net "GND")
			(clearance 0.1524)
			(thermal_gap 0.1524)
		)
		(pad "8" thru_hole circle
			(at 0 3.6322)
			(size 0.762 0.762)
			(drill 0.5588)
			(layers "*.Cu" "*.Mask")
			(remove_unused_layers no)
			(net "GND")
			(clearance 0.1524)
			(thermal_gap 0.1524)
		)
		(pad "9" thru_hole circle
			(at 2.568448 2.568448)
			(size 0.762 0.762)
			(drill 0.5588)
			(layers "*.Cu" "*.Mask")
			(remove_unused_layers no)
			(net "GND")
			(clearance 0.1524)
			(thermal_gap 0.1524)
		)
		(zone
			(layer "F.Cu")
			(hatch none 0.5)
			(connect_pads
				(clearance 0)
			)
			(min_thickness 0.25)
			(keepout
				(tracks not_allowed)
				(vias allowed)
				(pads allowed)
				(copperpour not_allowed)
				(footprints allowed)
			)
			(placement
				(enabled no)
				(sheetname "")
			)
			(fill
				(thermal_gap 0.5)
				(thermal_bridge_width 0.5)
				(island_removal_mode 0)
			)
			(polygon
				(pts
					(arc
						(start 29.649674 -312.90006)
						(mid 21.64969 -320.900044)
						(end 29.649674 -328.900028)
					)
					(arc
						(start 29.649674 -325.649844)
						(mid 24.899874 -320.900044)
						(end 29.649674 -316.150244)
					)
				)
			)
		)
		(zone
			(layer "F.Cu")
			(hatch none 0.5)
			(connect_pads
				(clearance 0)
			)
			(min_thickness 0.25)
			(keepout
				(tracks not_allowed)
				(vias allowed)
				(pads allowed)
				(copperpour not_allowed)
				(footprints allowed)
			)
			(placement
				(enabled no)
				(sheetname "")
			)
			(fill
				(thermal_gap 0.5)
				(thermal_bridge_width 0.5)
				(island_removal_mode 0)
			)
			(polygon
				(pts
					(arc
						(start 29.649674 -312.90006)
						(mid 37.649658 -320.900044)
						(end 29.649674 -328.900028)
					)
					(arc
						(start 29.649674 -325.649844)
						(mid 34.399474 -320.900044)
						(end 29.649674 -316.150244)
					)
				)
			)
		)
		(zone
			(layers "F.Cu" "B.Cu" "In1.Cu" "In2.Cu" "In3.Cu" "In4.Cu" "In5.Cu" "In6.Cu"
				"In7.Cu" "In8.Cu" "In9.Cu" "In10.Cu" "In11.Cu" "In12.Cu" "In13.Cu" "In14.Cu"
				"In15.Cu" "In16.Cu"
			)
			(hatch none 0.5)
			(connect_pads
				(clearance 0)
			)
			(min_thickness 0.25)
			(keepout
				(tracks not_allowed)
				(vias allowed)
				(pads allowed)
				(copperpour not_allowed)
				(footprints allowed)
			)
			(placement
				(enabled no)
				(sheetname "")
			)
			(fill
				(thermal_gap 0.5)
				(thermal_bridge_width 0.5)
				(island_removal_mode 0)
			)
			(polygon
				(pts
					(arc
						(start 32.415734 -320.900044)
						(mid 26.883614 -320.900044)
						(end 32.415734 -320.900044)
					)
				)
			)
		)
		(zone
			(layer "B.Cu")
			(hatch none 0.5)
			(connect_pads
				(clearance 0)
			)
			(min_thickness 0.25)
			(keepout
				(tracks not_allowed)
				(vias allowed)
				(pads allowed)
				(copperpour not_allowed)
				(footprints allowed)
			)
			(placement
				(enabled no)
				(sheetname "")
			)
			(fill
				(thermal_gap 0.5)
				(thermal_bridge_width 0.5)
				(island_removal_mode 0)
			)
			(polygon
				(pts
					(arc
						(start 29.649674 -315.896244)
						(mid 24.645874 -320.900044)
						(end 29.649674 -325.903844)
					)
					(arc
						(start 29.649674 -325.421244)
						(mid 25.128474 -320.900044)
						(end 29.649674 -316.378844)
					)
				)
			)
		)
		(zone
			(layer "B.Cu")
			(hatch none 0.5)
			(connect_pads
				(clearance 0)
			)
			(min_thickness 0.25)
			(keepout
				(tracks not_allowed)
				(vias allowed)
				(pads allowed)
				(copperpour not_allowed)
				(footprints allowed)
			)
			(placement
				(enabled no)
				(sheetname "")
			)
			(fill
				(thermal_gap 0.5)
				(thermal_bridge_width 0.5)
				(island_removal_mode 0)
			)
			(polygon
				(pts
					(arc
						(start 29.649674 -315.896244)
						(mid 34.653474 -320.900044)
						(end 29.649674 -325.903844)
					)
					(arc
						(start 29.649674 -325.421244)
						(mid 34.170874 -320.900044)
						(end 29.649674 -316.378844)
					)
				)
			)
		)
	)
	(footprint ""
		(layer "F.Cu")
		(at 314.314332 -140.134848 -90)
		(property "Reference" "R299"
			(at 0 0 270)
			(layer "F.SilkS")
			(hide yes)
			(effects
				(font
					(size 1.27 1.27)
				)
			)
		)
		(property "Value" ""
			(at 0 0 270)
			(layer "F.Fab")
			(effects
				(font
					(size 1.27 1.27)
				)
			)
		)
		(duplicate_pad_numbers_are_jumpers no)
		(fp_line
			(start -0.7874 0.4064)
			(end -0.7874 -0.4064)
			(stroke
				(width 0.1524)
				(type default)
			)
			(layer "F.SilkS")
		)
		(fp_line
			(start 0.7874 0.4064)
			(end -0.7874 0.4064)
			(stroke
				(width 0.1524)
				(type default)
			)
			(layer "F.SilkS")
		)
		(fp_line
			(start -0.7874 -0.4064)
			(end 0.7874 -0.4064)
			(stroke
				(width 0.1524)
				(type default)
			)
			(layer "F.SilkS")
		)
		(fp_line
			(start 0.7874 -0.4064)
			(end 0.7874 0.4064)
			(stroke
				(width 0.1524)
				(type default)
			)
			(layer "F.SilkS")
		)
		(fp_line
			(start -0.67945 0.3048)
			(end -0.67945 -0.305054)
			(stroke
				(width 0.1)
				(type default)
			)
			(layer "F.Fab")
		)
		(fp_line
			(start -0.12065 0.3048)
			(end -0.67945 0.3048)
			(stroke
				(width 0.1)
				(type default)
			)
			(layer "F.Fab")
		)
		(fp_line
			(start 0.120396 0.3048)
			(end 0.120396 0.2794)
			(stroke
				(width 0.1)
				(type default)
			)
			(layer "F.Fab")
		)
		(fp_line
			(start 0.67945 0.3048)
			(end 0.120396 0.3048)
			(stroke
				(width 0.1)
				(type default)
			)
			(layer "F.Fab")
		)
		(fp_line
			(start -0.12065 0.2794)
			(end -0.12065 0.3048)
			(stroke
				(width 0.1)
				(type default)
			)
			(layer "F.Fab")
		)
		(fp_line
			(start 0.120396 0.2794)
			(end -0.12065 0.2794)
			(stroke
				(width 0.1)
				(type default)
			)
			(layer "F.Fab")
		)
		(fp_line
			(start -0.12065 -0.2794)
			(end 0.12065 -0.2794)
			(stroke
				(width 0.1)
				(type default)
			)
			(layer "F.Fab")
		)
		(fp_line
			(start 0.12065 -0.2794)
			(end 0.12065 -0.3048)
			(stroke
				(width 0.1)
				(type default)
			)
			(layer "F.Fab")
		)
		(fp_line
			(start 0.12065 -0.3048)
			(end 0.67945 -0.3048)
			(stroke
				(width 0.1)
				(type default)
			)
			(layer "F.Fab")
		)
		(fp_line
			(start 0.67945 -0.3048)
			(end 0.67945 0.3048)
			(stroke
				(width 0.1)
				(type default)
			)
			(layer "F.Fab")
		)
		(fp_line
			(start -0.67945 -0.305054)
			(end -0.12065 -0.305054)
			(stroke
				(width 0.1)
				(type default)
			)
			(layer "F.Fab")
		)
		(fp_line
			(start -0.12065 -0.305054)
			(end -0.12065 -0.2794)
			(stroke
				(width 0.1)
				(type default)
			)
			(layer "F.Fab")
		)
		(pad "1" smd circle
			(at -0.40005 0 270)
			(size 0 0)
			(layers "F.Cu" "F.Mask" "F.Paste")
			(net "P3V3_AUX")
		)
		(pad "2" smd circle
			(at 0.40005 0 270)
			(size 0 0)
			(layers "F.Cu" "F.Mask" "F.Paste")
			(net "HP_NIC5_EN")
		)
	)
	(footprint ""
		(layer "F.Cu")
		(at 421.247316 -21.37156)
		(property "Reference" "C3973"
			(at 0 0 0)
			(layer "F.SilkS")
			(hide yes)
			(effects
				(font
					(size 1.27 1.27)
				)
			)
		)
		(property "Value" ""
			(at 0 0 0)
			(layer "F.Fab")
			(effects
				(font
					(size 1.27 1.27)
				)
			)
		)
		(duplicate_pad_numbers_are_jumpers no)
		(fp_line
			(start -0.7874 -0.4064)
			(end 0.7874 -0.4064)
			(stroke
				(width 0.1524)
				(type default)
			)
			(layer "F.SilkS")
		)
		(fp_line
			(start -0.7874 0.4064)
			(end -0.7874 -0.4064)
			(stroke
				(width 0.1524)
				(type default)
			)
			(layer "F.SilkS")
		)
		(fp_line
			(start 0.7874 -0.4064)
			(end 0.7874 0.4064)
			(stroke
				(width 0.1524)
				(type default)
			)
			(layer "F.SilkS")
		)
		(fp_line
			(start 0.7874 0.4064)
			(end -0.7874 0.4064)
			(stroke
				(width 0.1524)
				(type default)
			)
			(layer "F.SilkS")
		)
		(fp_line
			(start -0.67945 -0.305054)
			(end -0.12065 -0.305054)
			(stroke
				(width 0.1)
				(type default)
			)
			(layer "F.Fab")
		)
		(fp_line
			(start -0.67945 0.3048)
			(end -0.67945 -0.305054)
			(stroke
				(width 0.1)
				(type default)
			)
			(layer "F.Fab")
		)
		(fp_line
			(start -0.12065 -0.305054)
			(end -0.12065 -0.2794)
			(stroke
				(width 0.1)
				(type default)
			)
			(layer "F.Fab")
		)
		(fp_line
			(start -0.12065 -0.2794)
			(end 0.12065 -0.2794)
			(stroke
				(width 0.1)
				(type default)
			)
			(layer "F.Fab")
		)
		(fp_line
			(start -0.12065 0.2794)
			(end -0.12065 0.3048)
			(stroke
				(width 0.1)
				(type default)
			)
			(layer "F.Fab")
		)
		(fp_line
			(start -0.12065 0.3048)
			(end -0.67945 0.3048)
			(stroke
				(width 0.1)
				(type default)
			)
			(layer "F.Fab")
		)
		(fp_line
			(start 0.120396 0.2794)
			(end -0.12065 0.2794)
			(stroke
				(width 0.1)
				(type default)
			)
			(layer "F.Fab")
		)
		(fp_line
			(start 0.120396 0.3048)
			(end 0.120396 0.2794)
			(stroke
				(width 0.1)
				(type default)
			)
			(layer "F.Fab")
		)
		(fp_line
			(start 0.12065 -0.3048)
			(end 0.67945 -0.3048)
			(stroke
				(width 0.1)
				(type default)
			)
			(layer "F.Fab")
		)
		(fp_line
			(start 0.12065 -0.2794)
			(end 0.12065 -0.3048)
			(stroke
				(width 0.1)
				(type default)
			)
			(layer "F.Fab")
		)
		(fp_line
			(start 0.67945 -0.3048)
			(end 0.67945 0.3048)
			(stroke
				(width 0.1)
				(type default)
			)
			(layer "F.Fab")
		)
		(fp_line
			(start 0.67945 0.3048)
			(end 0.120396 0.3048)
			(stroke
				(width 0.1)
				(type default)
			)
			(layer "F.Fab")
		)
		(pad "1" smd circle
			(at -0.40005 0)
			(size 0 0)
			(layers "F.Cu" "F.Mask" "F.Paste")
			(net "P12V_SSD14")
		)
		(pad "2" smd circle
			(at 0.40005 0)
			(size 0 0)
			(layers "F.Cu" "F.Mask" "F.Paste")
			(net "GND")
		)
	)
	(footprint ""
		(layer "F.Cu")
		(at 116.850414 -279.486868 -90)
		(property "Reference" "PC122"
			(at 0 0 270)
			(layer "F.SilkS")
			(hide yes)
			(effects
				(font
					(size 1.27 1.27)
				)
			)
		)
		(property "Value" ""
			(at 0 0 270)
			(layer "F.Fab")
			(effects
				(font
					(size 1.27 1.27)
				)
			)
		)
		(duplicate_pad_numbers_are_jumpers no)
		(fp_line
			(start -0.7874 0.4064)
			(end -0.7874 -0.4064)
			(stroke
				(width 0.1524)
				(type default)
			)
			(layer "F.SilkS")
		)
		(fp_line
			(start 0.7874 0.4064)
			(end -0.7874 0.4064)
			(stroke
				(width 0.1524)
				(type default)
			)
			(layer "F.SilkS")
		)
		(fp_line
			(start -0.7874 -0.4064)
			(end 0.7874 -0.4064)
			(stroke
				(width 0.1524)
				(type default)
			)
			(layer "F.SilkS")
		)
		(fp_line
			(start 0.7874 -0.4064)
			(end 0.7874 0.4064)
			(stroke
				(width 0.1524)
				(type default)
			)
			(layer "F.SilkS")
		)
		(fp_line
			(start -0.67945 0.3048)
			(end -0.67945 -0.305054)
			(stroke
				(width 0.1)
				(type default)
			)
			(layer "F.Fab")
		)
		(fp_line
			(start -0.12065 0.3048)
			(end -0.67945 0.3048)
			(stroke
				(width 0.1)
				(type default)
			)
			(layer "F.Fab")
		)
		(fp_line
			(start 0.120396 0.3048)
			(end 0.120396 0.2794)
			(stroke
				(width 0.1)
				(type default)
			)
			(layer "F.Fab")
		)
		(fp_line
			(start 0.67945 0.3048)
			(end 0.120396 0.3048)
			(stroke
				(width 0.1)
				(type default)
			)
			(layer "F.Fab")
		)
		(fp_line
			(start -0.12065 0.2794)
			(end -0.12065 0.3048)
			(stroke
				(width 0.1)
				(type default)
			)
			(layer "F.Fab")
		)
		(fp_line
			(start 0.120396 0.2794)
			(end -0.12065 0.2794)
			(stroke
				(width 0.1)
				(type default)
			)
			(layer "F.Fab")
		)
		(fp_line
			(start -0.12065 -0.2794)
			(end 0.12065 -0.2794)
			(stroke
				(width 0.1)
				(type default)
			)
			(layer "F.Fab")
		)
		(fp_line
			(start 0.12065 -0.2794)
			(end 0.12065 -0.3048)
			(stroke
				(width 0.1)
				(type default)
			)
			(layer "F.Fab")
		)
		(fp_line
			(start 0.12065 -0.3048)
			(end 0.67945 -0.3048)
			(stroke
				(width 0.1)
				(type default)
			)
			(layer "F.Fab")
		)
		(fp_line
			(start 0.67945 -0.3048)
			(end 0.67945 0.3048)
			(stroke
				(width 0.1)
				(type default)
			)
			(layer "F.Fab")
		)
		(fp_line
			(start -0.67945 -0.305054)
			(end -0.12065 -0.305054)
			(stroke
				(width 0.1)
				(type default)
			)
			(layer "F.Fab")
		)
		(fp_line
			(start -0.12065 -0.305054)
			(end -0.12065 -0.2794)
			(stroke
				(width 0.1)
				(type default)
			)
			(layer "F.Fab")
		)
		(pad "1" smd circle
			(at -0.40005 0 270)
			(size 0 0)
			(layers "F.Cu" "F.Mask" "F.Paste")
			(net "P0V8_PEX0_VREF")
		)
		(pad "2" smd circle
			(at 0.40005 0 270)
			(size 0 0)
			(layers "F.Cu" "F.Mask" "F.Paste")
			(net "GND")
		)
	)
	(footprint ""
		(layer "F.Cu")
		(at 44.178728 -350.098614 90)
		(property "Reference" "C167"
			(at 0 0 90)
			(layer "F.SilkS")
			(hide yes)
			(effects
				(font
					(size 1.27 1.27)
				)
			)
		)
		(property "Value" ""
			(at 0 0 90)
			(layer "F.Fab")
			(effects
				(font
					(size 1.27 1.27)
				)
			)
		)
		(duplicate_pad_numbers_are_jumpers no)
		(fp_line
			(start 0.299974 -0.150114)
			(end 0.299974 0.150114)
			(stroke
				(width 0.1)
				(type default)
			)
			(layer "F.Fab")
		)
		(fp_line
			(start -0.299974 -0.150114)
			(end 0.299974 -0.150114)
			(stroke
				(width 0.1)
				(type default)
			)
			(layer "F.Fab")
		)
		(fp_line
			(start 0.299974 0.150114)
			(end -0.299974 0.150114)
			(stroke
				(width 0.1)
				(type default)
			)
			(layer "F.Fab")
		)
		(fp_line
			(start -0.299974 0.150114)
			(end -0.299974 -0.150114)
			(stroke
				(width 0.1)
				(type default)
			)
			(layer "F.Fab")
		)
		(pad "1" smd rect
			(at -0.2667 0 90)
			(size 0.3048 0.381)
			(layers "F.Cu" "F.Mask" "F.Paste")
			(net "P5E_PEX0_STN7_TX_DP<124>")
		)
		(pad "2" smd rect
			(at 0.2667 0 90)
			(size 0.3048 0.381)
			(layers "F.Cu" "F.Mask" "F.Paste")
			(net "P5E_PEX0_STN7_TX_C_DP<124>")
		)
	)
	(footprint ""
		(layer "F.Cu")
		(at 20.150074 -301.410116)
		(property "Reference" "H138"
			(at -0.365252 4.196842 0)
			(unlocked yes)
			(layer "F.SilkS")
			(effects
				(font
					(size 0.7874 0.5842)
					(thickness 0.1524)
				)
				(justify left)
			)
		)
		(property "Value" ""
			(at 0 0 0)
			(layer "F.Fab")
			(effects
				(font
					(size 1.27 1.27)
				)
			)
		)
		(duplicate_pad_numbers_are_jumpers no)
		(pad "1" thru_hole circle
			(at 0 0)
			(size 6.5024 6.5024)
			(drill 3.2004)
			(layers "*.Cu" "*.Mask")
			(remove_unused_layers no)
			(net "GND")
			(clearance -1.397)
		)
	)
	(footprint ""
		(layer "F.Cu")
		(at 36.638484 -109.20984)
		(property "Reference" "C54"
			(at 0 0 0)
			(layer "F.SilkS")
			(hide yes)
			(effects
				(font
					(size 1.27 1.27)
				)
			)
		)
		(property "Value" ""
			(at 0 0 0)
			(layer "F.Fab")
			(effects
				(font
					(size 1.27 1.27)
				)
			)
		)
		(duplicate_pad_numbers_are_jumpers no)
		(fp_line
			(start -0.299974 -0.150114)
			(end 0.299974 -0.150114)
			(stroke
				(width 0.1)
				(type default)
			)
			(layer "F.Fab")
		)
		(fp_line
			(start -0.299974 0.150114)
			(end -0.299974 -0.150114)
			(stroke
				(width 0.1)
				(type default)
			)
			(layer "F.Fab")
		)
		(fp_line
			(start 0.299974 -0.150114)
			(end 0.299974 0.150114)
			(stroke
				(width 0.1)
				(type default)
			)
			(layer "F.Fab")
		)
		(fp_line
			(start 0.299974 0.150114)
			(end -0.299974 0.150114)
			(stroke
				(width 0.1)
				(type default)
			)
			(layer "F.Fab")
		)
		(pad "1" smd rect
			(at -0.2667 0)
			(size 0.3048 0.381)
			(layers "F.Cu" "F.Mask" "F.Paste")
			(net "P5E_PEX0_STN1_TX_DP<21>")
		)
		(pad "2" smd rect
			(at 0.2667 0)
			(size 0.3048 0.381)
			(layers "F.Cu" "F.Mask" "F.Paste")
			(net "P5E_PEX0_STN1_TX_C_DP<21>")
		)
	)
	(footprint ""
		(layer "F.Cu")
		(at 165.212014 -210.09991)
		(property "Reference" "ME3"
			(at 0 0 0)
			(layer "F.SilkS")
			(hide yes)
			(effects
				(font
					(size 1.27 1.27)
				)
			)
		)
		(property "Value" ""
			(at 0 0 0)
			(layer "F.Fab")
			(effects
				(font
					(size 1.27 1.27)
				)
			)
		)
		(duplicate_pad_numbers_are_jumpers no)
		(fp_line
			(start -3.1369 2.5527)
			(end -3.1115 2.5019)
			(stroke
				(width 0.1524)
				(type default)
			)
			(layer "F.SilkS")
		)
		(fp_line
			(start -3.1369 3.0861)
			(end -2.8321 3.0861)
			(stroke
				(width 0.1524)
				(type default)
			)
			(layer "F.SilkS")
		)
		(fp_line
			(start -3.1242 2.9972)
			(end -3.1369 3.0861)
			(stroke
				(width 0.1524)
				(type default)
			)
			(layer "F.SilkS")
		)
		(fp_line
			(start -3.1115 2.5019)
			(end -3.0861 2.4765)
			(stroke
				(width 0.1524)
				(type default)
			)
			(layer "F.SilkS")
		)
		(fp_line
			(start -3.0988 2.921)
			(end -3.1242 2.9972)
			(stroke
				(width 0.1524)
				(type default)
			)
			(layer "F.SilkS")
		)
		(fp_line
			(start -3.0861 2.4765)
			(end -3.048 2.4511)
			(stroke
				(width 0.1524)
				(type default)
			)
			(layer "F.SilkS")
		)
		(fp_line
			(start -3.0734 2.8829)
			(end -3.0988 2.921)
			(stroke
				(width 0.1524)
				(type default)
			)
			(layer "F.SilkS")
		)
		(fp_line
			(start -3.048 2.4511)
			(end -2.9972 2.4384)
			(stroke
				(width 0.1524)
				(type default)
			)
			(layer "F.SilkS")
		)
		(fp_line
			(start -3.048 2.8575)
			(end -3.0734 2.8829)
			(stroke
				(width 0.1524)
				(type default)
			)
			(layer "F.SilkS")
		)
		(fp_line
			(start -3.0099 2.8067)
			(end -3.048 2.8575)
			(stroke
				(width 0.1524)
				(type default)
			)
			(layer "F.SilkS")
		)
		(fp_line
			(start -2.9972 2.4384)
			(end -2.9337 2.4511)
			(stroke
				(width 0.1524)
				(type default)
			)
			(layer "F.SilkS")
		)
		(fp_line
			(start -2.9591 2.7686)
			(end -3.0099 2.8067)
			(stroke
				(width 0.1524)
				(type default)
			)
			(layer "F.SilkS")
		)
		(fp_line
			(start -2.9337 2.4511)
			(end -2.8702 2.5146)
			(stroke
				(width 0.1524)
				(type default)
			)
			(layer "F.SilkS")
		)
		(fp_line
			(start -2.921 2.7432)
			(end -2.9591 2.7686)
			(stroke
				(width 0.1524)
				(type default)
			)
			(layer "F.SilkS")
		)
		(fp_line
			(start -2.8956 2.7178)
			(end -2.921 2.7432)
			(stroke
				(width 0.1524)
				(type default)
			)
			(layer "F.SilkS")
		)
		(fp_line
			(start -2.8702 2.5146)
			(end -2.8575 2.5527)
			(stroke
				(width 0.1524)
				(type default)
			)
			(layer "F.SilkS")
		)
		(fp_line
			(start -2.8702 2.6797)
			(end -2.8956 2.7178)
			(stroke
				(width 0.1524)
				(type default)
			)
			(layer "F.SilkS")
		)
		(fp_line
			(start -2.8575 2.5527)
			(end -2.8575 2.6416)
			(stroke
				(width 0.1524)
				(type default)
			)
			(layer "F.SilkS")
		)
		(fp_line
			(start -2.8575 2.6416)
			(end -2.8702 2.6797)
			(stroke
				(width 0.1524)
				(type default)
			)
			(layer "F.SilkS")
		)
		(fp_line
			(start -2.5908 2.6543)
			(end -2.5908 3.0861)
			(stroke
				(width 0.1524)
				(type default)
			)
			(layer "F.SilkS")
		)
		(fp_line
			(start -2.5908 2.7813)
			(end -2.5654 2.7305)
			(stroke
				(width 0.1524)
				(type default)
			)
			(layer "F.SilkS")
		)
		(fp_line
			(start -2.5654 2.7305)
			(end -2.54 2.6924)
			(stroke
				(width 0.1524)
				(type default)
			)
			(layer "F.SilkS")
		)
		(fp_line
			(start -2.54 2.6924)
			(end -2.5146 2.667)
			(stroke
				(width 0.1524)
				(type default)
			)
			(layer "F.SilkS")
		)
		(fp_line
			(start -2.5146 2.667)
			(end -2.4638 2.6543)
			(stroke
				(width 0.1524)
				(type default)
			)
			(layer "F.SilkS")
		)
		(fp_line
			(start -2.4638 2.6543)
			(end -2.4257 2.6543)
			(stroke
				(width 0.1524)
				(type default)
			)
			(layer "F.SilkS")
		)
		(fp_line
			(start -2.4257 2.6543)
			(end -2.3749 2.667)
			(stroke
				(width 0.1524)
				(type default)
			)
			(layer "F.SilkS")
		)
		(fp_line
			(start -2.3749 2.667)
			(end -2.3368 2.7178)
			(stroke
				(width 0.1524)
				(type default)
			)
			(layer "F.SilkS")
		)
		(fp_line
			(start -2.3368 2.7178)
			(end -2.3114 2.7686)
			(stroke
				(width 0.1524)
				(type default)
			)
			(layer "F.SilkS")
		)
		(fp_line
			(start -2.3114 2.7686)
			(end -2.3114 3.0861)
			(stroke
				(width 0.1524)
				(type default)
			)
			(layer "F.SilkS")
		)
		(fp_line
			(start -2.0701 2.8575)
			(end -2.0701 2.9083)
			(stroke
				(width 0.1524)
				(type default)
			)
			(layer "F.SilkS")
		)
		(fp_line
			(start -2.0701 2.9083)
			(end -2.0574 2.9718)
			(stroke
				(width 0.1524)
				(type default)
			)
			(layer "F.SilkS")
		)
		(fp_line
			(start -2.0574 2.8194)
			(end -2.0701 2.8575)
			(stroke
				(width 0.1524)
				(type default)
			)
			(layer "F.SilkS")
		)
		(fp_line
			(start -2.0574 2.9718)
			(end -2.032 3.0099)
			(stroke
				(width 0.1524)
				(type default)
			)
			(layer "F.SilkS")
		)
		(fp_line
			(start -2.0447 2.794)
			(end -2.0574 2.8194)
			(stroke
				(width 0.1524)
				(type default)
			)
			(layer "F.SilkS")
		)
		(fp_line
			(start -2.032 3.0099)
			(end -2.0066 3.0353)
			(stroke
				(width 0.1524)
				(type default)
			)
			(layer "F.SilkS")
		)
		(fp_line
			(start -2.0066 2.7559)
			(end -2.0447 2.794)
			(stroke
				(width 0.1524)
				(type default)
			)
			(layer "F.SilkS")
		)
		(fp_line
			(start -2.0066 3.0353)
			(end -1.9685 3.0607)
			(stroke
				(width 0.1524)
				(type default)
			)
			(layer "F.SilkS")
		)
		(fp_line
			(start -1.9685 2.7305)
			(end -2.0066 2.7559)
			(stroke
				(width 0.1524)
				(type default)
			)
			(layer "F.SilkS")
		)
		(fp_line
			(start -1.9685 3.0607)
			(end -1.9304 3.0734)
			(stroke
				(width 0.1524)
				(type default)
			)
			(layer "F.SilkS")
		)
		(fp_line
			(start -1.9304 3.0734)
			(end -1.8796 3.0734)
			(stroke
				(width 0.1524)
				(type default)
			)
			(layer "F.SilkS")
		)
		(fp_line
			(start -1.9177 2.7178)
			(end -1.9685 2.7305)
			(stroke
				(width 0.1524)
				(type default)
			)
			(layer "F.SilkS")
		)
		(fp_line
			(start -1.8796 3.0734)
			(end -1.8161 3.0607)
			(stroke
				(width 0.1524)
				(type default)
			)
			(layer "F.SilkS")
		)
		(fp_line
			(start -1.8542 2.7178)
			(end -1.9177 2.7178)
			(stroke
				(width 0.1524)
				(type default)
			)
			(layer "F.SilkS")
		)
		(fp_line
			(start -1.8161 2.7305)
			(end -1.8542 2.7178)
			(stroke
				(width 0.1524)
				(type default)
			)
			(layer "F.SilkS")
		)
		(fp_line
			(start -1.8161 3.0607)
			(end -1.778 3.0353)
			(stroke
				(width 0.1524)
				(type default)
			)
			(layer "F.SilkS")
		)
		(fp_line
			(start -1.778 2.7559)
			(end -1.8161 2.7305)
			(stroke
				(width 0.1524)
				(type default)
			)
			(layer "F.SilkS")
		)
		(fp_line
			(start -1.778 3.0353)
			(end -1.7526 3.0099)
			(stroke
				(width 0.1524)
				(type default)
			)
			(layer "F.SilkS")
		)
		(fp_line
			(start -1.7526 2.4384)
			(end -1.7526 3.0861)
			(stroke
				(width 0.1524)
				(type default)
			)
			(layer "F.SilkS")
		)
		(fp_line
			(start -1.7526 2.7813)
			(end -1.778 2.7559)
			(stroke
				(width 0.1524)
				(type default)
			)
			(layer "F.SilkS")
		)
		(fp_line
			(start -1.3208 -1.524)
			(end 1.4732 1.397)
			(stroke
				(width 0.1524)
				(type default)
			)
			(layer "F.SilkS")
		)
		(fp_line
			(start -1.1938 -1.27)
			(end -1.1938 1.2954)
			(stroke
				(width 0.254)
				(type default)
			)
			(layer "F.SilkS")
		)
		(fp_line
			(start -1.1938 -1.27)
			(end -0.5588 -1.27)
			(stroke
				(width 0.254)
				(type default)
			)
			(layer "F.SilkS")
		)
		(fp_line
			(start -1.1557 2.4257)
			(end -1.1557 3.0861)
			(stroke
				(width 0.1524)
				(type default)
			)
			(layer "F.SilkS")
		)
		(fp_line
			(start -1.016 4.7498)
			(end -1.016 4.826)
			(stroke
				(width 0.254)
				(type default)
			)
			(layer "F.SilkS")
		)
		(fp_line
			(start -1.016 4.7752)
			(end 0.3048 4.7752)
			(stroke
				(width 0.254)
				(type default)
			)
			(layer "F.SilkS")
		)
		(fp_line
			(start -1.016 4.826)
			(end -0.9906 4.953)
			(stroke
				(width 0.254)
				(type default)
			)
			(layer "F.SilkS")
		)
		(fp_line
			(start -0.9906 4.5974)
			(end -1.016 4.7498)
			(stroke
				(width 0.254)
				(type default)
			)
			(layer "F.SilkS")
		)
		(fp_line
			(start -0.9906 4.953)
			(end -0.9652 5.0292)
			(stroke
				(width 0.254)
				(type default)
			)
			(layer "F.SilkS")
		)
		(fp_line
			(start -0.9652 4.5212)
			(end -0.9906 4.5974)
			(stroke
				(width 0.254)
				(type default)
			)
			(layer "F.SilkS")
		)
		(fp_line
			(start -0.9652 5.0292)
			(end -0.9144 5.1308)
			(stroke
				(width 0.254)
				(type default)
			)
			(layer "F.SilkS")
		)
		(fp_line
			(start -0.9144 4.4196)
			(end -0.9652 4.5212)
			(stroke
				(width 0.254)
				(type default)
			)
			(layer "F.SilkS")
		)
		(fp_line
			(start -0.9144 5.1308)
			(end -0.8382 5.2324)
			(stroke
				(width 0.254)
				(type default)
			)
			(layer "F.SilkS")
		)
		(fp_line
			(start -0.8382 4.318)
			(end -0.9144 4.4196)
			(stroke
				(width 0.254)
				(type default)
			)
			(layer "F.SilkS")
		)
		(fp_line
			(start -0.8382 5.2324)
			(end -0.7112 5.334)
			(stroke
				(width 0.254)
				(type default)
			)
			(layer "F.SilkS")
		)
		(fp_line
			(start -0.8128 4.2926)
			(end -0.8382 4.318)
			(stroke
				(width 0.254)
				(type default)
			)
			(layer "F.SilkS")
		)
		(fp_line
			(start -0.7747 2.6543)
			(end -0.5969 3.0861)
			(stroke
				(width 0.1524)
				(type default)
			)
			(layer "F.SilkS")
		)
		(fp_line
			(start -0.7112 4.2164)
			(end -0.8128 4.2926)
			(stroke
				(width 0.254)
				(type default)
			)
			(layer "F.SilkS")
		)
		(fp_line
			(start -0.7112 5.334)
			(end -0.6096 5.3848)
			(stroke
				(width 0.254)
				(type default)
			)
			(layer "F.SilkS")
		)
		(fp_line
			(start -0.6096 4.1656)
			(end -0.7112 4.2164)
			(stroke
				(width 0.254)
				(type default)
			)
			(layer "F.SilkS")
		)
		(fp_line
			(start -0.6096 5.3848)
			(end -0.5334 5.4102)
			(stroke
				(width 0.254)
				(type default)
			)
			(layer "F.SilkS")
		)
		(fp_line
			(start -0.5969 3.0861)
			(end -0.4191 2.6543)
			(stroke
				(width 0.1524)
				(type default)
			)
			(layer "F.SilkS")
		)
		(fp_line
			(start -0.5588 0)
			(end -1.1938 0)
			(stroke
				(width 0.254)
				(type default)
			)
			(layer "F.SilkS")
		)
		(fp_line
			(start -0.5334 4.1402)
			(end -0.6096 4.1656)
			(stroke
				(width 0.254)
				(type default)
			)
			(layer "F.SilkS")
		)
		(fp_line
			(start -0.5334 5.4102)
			(end -0.381 5.4356)
			(stroke
				(width 0.254)
				(type default)
			)
			(layer "F.SilkS")
		)
		(fp_line
			(start -0.4064 4.1148)
			(end -0.5334 4.1402)
			(stroke
				(width 0.254)
				(type default)
			)
			(layer "F.SilkS")
		)
		(fp_line
			(start -0.381 5.4356)
			(end -0.3556 5.4356)
			(stroke
				(width 0.254)
				(type default)
			)
			(layer "F.SilkS")
		)
		(fp_line
			(start -0.3556 5.4356)
			(end -0.1778 5.4102)
			(stroke
				(width 0.254)
				(type default)
			)
			(layer "F.SilkS")
		)
		(fp_line
			(start -0.3048 4.1148)
			(end -0.4064 4.1148)
			(stroke
				(width 0.254)
				(type default)
			)
			(layer "F.SilkS")
		)
		(fp_line
			(start -0.1778 4.1402)
			(end -0.3048 4.1148)
			(stroke
				(width 0.254)
				(type default)
			)
			(layer "F.SilkS")
		)
		(fp_line
			(start -0.1778 5.4102)
			(end -0.1016 5.3848)
			(stroke
				(width 0.254)
				(type default)
			)
			(layer "F.SilkS")
		)
		(fp_line
			(start -0.1016 4.1656)
			(end -0.1778 4.1402)
			(stroke
				(width 0.254)
				(type default)
			)
			(layer "F.SilkS")
		)
		(fp_line
			(start -0.1016 5.3848)
			(end -0.0508 5.3594)
			(stroke
				(width 0.254)
				(type default)
			)
			(layer "F.SilkS")
		)
		(fp_line
			(start -0.0508 5.3594)
			(end 0.1016 5.2578)
			(stroke
				(width 0.254)
				(type default)
			)
			(layer "F.SilkS")
		)
		(fp_line
			(start -0.0381 2.4257)
			(end -0.0381 3.0861)
			(stroke
				(width 0.1524)
				(type default)
			)
			(layer "F.SilkS")
		)
		(fp_line
			(start 0 4.2164)
			(end -0.1016 4.1656)
			(stroke
				(width 0.254)
				(type default)
			)
			(layer "F.SilkS")
		)
		(fp_line
			(start 0.1016 5.2578)
			(end 0.2032 5.1308)
			(stroke
				(width 0.254)
				(type default)
			)
			(layer "F.SilkS")
		)
		(fp_line
			(start 0.127 4.318)
			(end 0 4.2164)
			(stroke
				(width 0.254)
				(type default)
			)
			(layer "F.SilkS")
		)
		(fp_line
			(start 0.2032 4.4196)
			(end 0.127 4.318)
			(stroke
				(width 0.254)
				(type default)
			)
			(layer "F.SilkS")
		)
		(fp_line
			(start 0.254 4.5212)
			(end 0.2032 4.4196)
			(stroke
				(width 0.254)
				(type default)
			)
			(layer "F.SilkS")
		)
		(fp_line
			(start 0.2794 4.5974)
			(end 0.254 4.5212)
			(stroke
				(width 0.254)
				(type default)
			)
			(layer "F.SilkS")
		)
		(fp_line
			(start 0.3048 4.7752)
			(end 0.2794 4.5974)
			(stroke
				(width 0.254)
				(type default)
			)
			(layer "F.SilkS")
		)
		(fp_line
			(start 0.3556 -1.27)
			(end 0.3556 1.2954)
			(stroke
				(width 0.254)
				(type default)
			)
			(layer "F.SilkS")
		)
		(fp_line
			(start 0.635 4.3434)
			(end 0.9144 4.191)
			(stroke
				(width 0.254)
				(type default)
			)
			(layer "F.SilkS")
		)
		(fp_line
			(start 0.6731 2.3495)
			(end 0.6731 2.3749)
			(stroke
				(width 0.1524)
				(type default)
			)
			(layer "F.SilkS")
		)
		(fp_line
			(start 0.6731 2.3749)
			(end 0.6985 2.4003)
			(stroke
				(width 0.1524)
				(type default)
			)
			(layer "F.SilkS")
		)
		(fp_line
			(start 0.6985 2.3241)
			(end 0.6731 2.3495)
			(stroke
				(width 0.1524)
				(type default)
			)
			(layer "F.SilkS")
		)
		(fp_line
			(start 0.6985 2.4003)
			(end 0.7239 2.3749)
			(stroke
				(width 0.1524)
				(type default)
			)
			(layer "F.SilkS")
		)
		(fp_line
			(start 0.6985 2.6416)
			(end 0.6985 3.0861)
			(stroke
				(width 0.1524)
				(type default)
			)
			(layer "F.SilkS")
		)
		(fp_line
			(start 0.7239 2.3495)
			(end 0.6985 2.3241)
			(stroke
				(width 0.1524)
				(type default)
			)
			(layer "F.SilkS")
		)
		(fp_line
			(start 0.7239 2.3749)
			(end 0.7239 2.3495)
			(stroke
				(width 0.1524)
				(type default)
			)
			(layer "F.SilkS")
		)
		(fp_line
			(start 0.9144 4.191)
			(end 0.9144 5.461)
			(stroke
				(width 0.254)
				(type default)
			)
			(layer "F.SilkS")
		)
		(fp_line
			(start 1.143 2.6543)
			(end 1.143 3.0861)
			(stroke
				(width 0.1524)
				(type default)
			)
			(layer "F.SilkS")
		)
		(fp_line
			(start 1.143 2.7813)
			(end 1.1684 2.7305)
			(stroke
				(width 0.1524)
				(type default)
			)
			(layer "F.SilkS")
		)
		(fp_line
			(start 1.1684 2.7305)
			(end 1.1938 2.6924)
			(stroke
				(width 0.1524)
				(type default)
			)
			(layer "F.SilkS")
		)
		(fp_line
			(start 1.1938 2.6924)
			(end 1.2192 2.667)
			(stroke
				(width 0.1524)
				(type default)
			)
			(layer "F.SilkS")
		)
		(fp_line
			(start 1.2192 2.667)
			(end 1.27 2.6543)
			(stroke
				(width 0.1524)
				(type default)
			)
			(layer "F.SilkS")
		)
		(fp_line
			(start 1.27 2.6543)
			(end 1.3081 2.6543)
			(stroke
				(width 0.1524)
				(type default)
			)
			(layer "F.SilkS")
		)
		(fp_line
			(start 1.3081 2.6543)
			(end 1.3589 2.667)
			(stroke
				(width 0.1524)
				(type default)
			)
			(layer "F.SilkS")
		)
		(fp_line
			(start 1.3589 2.667)
			(end 1.397 2.7178)
			(stroke
				(width 0.1524)
				(type default)
			)
			(layer "F.SilkS")
		)
		(fp_line
			(start 1.397 2.7178)
			(end 1.4224 2.7686)
			(stroke
				(width 0.1524)
				(type default)
			)
			(layer "F.SilkS")
		)
		(fp_line
			(start 1.4224 2.7686)
			(end 1.4224 3.0861)
			(stroke
				(width 0.1524)
				(type default)
			)
			(layer "F.SilkS")
		)
		(fp_line
			(start 1.7018 2.667)
			(end 1.9304 2.667)
			(stroke
				(width 0.1524)
				(type default)
			)
			(layer "F.SilkS")
		)
		(fp_line
			(start 1.8161 2.4511)
			(end 1.8161 3.0861)
			(stroke
				(width 0.1524)
				(type default)
			)
			(layer "F.SilkS")
		)
		(fp_line
			(start 1.8161 3.0861)
			(end 1.9939 3.0734)
			(stroke
				(width 0.1524)
				(type default)
			)
			(layer "F.SilkS")
		)
		(fp_line
			(start 2.1844 2.8575)
			(end 2.1844 2.8956)
			(stroke
				(width 0.1524)
				(type default)
			)
			(layer "F.SilkS")
		)
		(fp_line
			(start 2.1844 2.8956)
			(end 2.1971 2.9464)
			(stroke
				(width 0.1524)
				(type default)
			)
			(layer "F.SilkS")
		)
		(fp_line
			(start 2.1971 2.794)
			(end 2.1844 2.8575)
			(stroke
				(width 0.1524)
				(type default)
			)
			(layer "F.SilkS")
		)
		(fp_line
			(start 2.1971 2.9464)
			(end 2.2098 2.9718)
			(stroke
				(width 0.1524)
				(type default)
			)
			(layer "F.SilkS")
		)
		(fp_line
			(start 2.2098 2.7686)
			(end 2.1971 2.794)
			(stroke
				(width 0.1524)
				(type default)
			)
			(layer "F.SilkS")
		)
		(fp_line
			(start 2.2098 2.9718)
			(end 2.2352 3.0099)
			(stroke
				(width 0.1524)
				(type default)
			)
			(layer "F.SilkS")
		)
		(fp_line
			(start 2.2352 2.7305)
			(end 2.2098 2.7686)
			(stroke
				(width 0.1524)
				(type default)
			)
			(layer "F.SilkS")
		)
		(fp_line
			(start 2.2352 3.0099)
			(end 2.2606 3.0353)
			(stroke
				(width 0.1524)
				(type default)
			)
			(layer "F.SilkS")
		)
		(fp_line
			(start 2.2606 2.7051)
			(end 2.2352 2.7305)
			(stroke
				(width 0.1524)
				(type default)
			)
			(layer "F.SilkS")
		)
		(fp_line
			(start 2.2606 3.0353)
			(end 2.2987 3.0607)
			(stroke
				(width 0.1524)
				(type default)
			)
			(layer "F.SilkS")
		)
		(fp_line
			(start 2.2987 2.6797)
			(end 2.2606 2.7051)
			(stroke
				(width 0.1524)
				(type default)
			)
			(layer "F.SilkS")
		)
		(fp_line
			(start 2.2987 3.0607)
			(end 2.3241 3.0734)
			(stroke
				(width 0.1524)
				(type default)
			)
			(layer "F.SilkS")
		)
		(fp_line
			(start 2.3241 2.667)
			(end 2.2987 2.6797)
			(stroke
				(width 0.1524)
				(type default)
			)
			(layer "F.SilkS")
		)
		(fp_line
			(start 2.3241 3.0734)
			(end 2.3876 3.0861)
			(stroke
				(width 0.1524)
				(type default)
			)
			(layer "F.SilkS")
		)
		(fp_line
			(start 2.3749 2.6543)
			(end 2.3241 2.667)
			(stroke
				(width 0.1524)
				(type default)
			)
			(layer "F.SilkS")
		)
		(fp_line
			(start 2.3876 3.0861)
			(end 2.4384 3.0861)
			(stroke
				(width 0.1524)
				(type default)
			)
			(layer "F.SilkS")
		)
		(fp_line
			(start 2.413 2.6543)
			(end 2.3749 2.6543)
			(stroke
				(width 0.1524)
				(type default)
			)
			(layer "F.SilkS")
		)
		(fp_line
			(start 2.4384 3.0861)
			(end 2.5019 3.0607)
			(stroke
				(width 0.1524)
				(type default)
			)
			(layer "F.SilkS")
		)
		(fp_line
			(start 2.4638 2.667)
			(end 2.413 2.6543)
			(stroke
				(width 0.1524)
				(type default)
			)
			(layer "F.SilkS")
		)
		(fp_line
			(start 2.5019 2.6797)
			(end 2.4638 2.667)
			(stroke
				(width 0.1524)
				(type default)
			)
			(layer "F.SilkS")
		)
		(fp_line
			(start 2.8194 2.667)
			(end 3.048 2.667)
			(stroke
				(width 0.1524)
				(type default)
			)
			(layer "F.SilkS")
		)
		(fp_line
			(start 2.9337 2.4511)
			(end 2.9337 3.0861)
			(stroke
				(width 0.1524)
				(type default)
			)
			(layer "F.SilkS")
		)
		(fp_line
			(start 2.9337 3.0861)
			(end 3.1115 3.0734)
			(stroke
				(width 0.1524)
				(type default)
			)
			(layer "F.SilkS")
		)
		(fp_arc
			(start -1.5748 4.826)
			(mid -0.985649 3.828331)
			(end 0.127 3.5052)
			(stroke
				(width 0.1524)
				(type default)
			)
			(layer "F.SilkS")
		)
		(fp_arc
			(start -0.5588 -1.27)
			(mid 0.0762 -0.635)
			(end -0.5588 0)
			(stroke
				(width 0.254)
				(type default)
			)
			(layer "F.SilkS")
		)
		(fp_arc
			(start -0.127 3.5052)
			(mid 0.985653 3.828369)
			(end 1.5748 4.826)
			(stroke
				(width 0.1524)
				(type default)
			)
			(layer "F.SilkS")
		)
		(fp_arc
			(start 0.1524 6.096)
			(mid -0.964565 5.805567)
			(end -1.5748 4.826)
			(stroke
				(width 0.1524)
				(type default)
			)
			(layer "F.SilkS")
		)
		(fp_arc
			(start 1.5748 4.826)
			(mid 0.964538 5.805581)
			(end -0.1524 6.096)
			(stroke
				(width 0.1524)
				(type default)
			)
			(layer "F.SilkS")
		)
		(fp_circle
			(center -1.8923 2.8956)
			(end -1.71196 2.8956)
			(stroke
				(width 0.1524)
				(type default)
			)
			(fill no)
			(layer "F.SilkS")
		)
		(fp_circle
			(center 0 0)
			(end 2.03454 0)
			(stroke
				(width 0.1524)
				(type default)
			)
			(fill no)
			(layer "F.SilkS")
		)
		(fp_circle
			(center 0.9652 0.6858)
			(end 1.57734 0.6858)
			(stroke
				(width 0.254)
				(type default)
			)
			(fill no)
			(layer "F.SilkS")
		)
	)
	(footprint ""
		(layer "F.Cu")
		(at 325.130668 -229.526592 -90)
		(property "Reference" "R3006"
			(at 0 0 270)
			(layer "F.SilkS")
			(hide yes)
			(effects
				(font
					(size 1.27 1.27)
				)
			)
		)
		(property "Value" ""
			(at 0 0 270)
			(layer "F.Fab")
			(effects
				(font
					(size 1.27 1.27)
				)
			)
		)
		(duplicate_pad_numbers_are_jumpers no)
		(fp_line
			(start -0.7874 0.4064)
			(end -0.7874 -0.4064)
			(stroke
				(width 0.1524)
				(type default)
			)
			(layer "F.SilkS")
		)
		(fp_line
			(start 0.7874 0.4064)
			(end -0.7874 0.4064)
			(stroke
				(width 0.1524)
				(type default)
			)
			(layer "F.SilkS")
		)
		(fp_line
			(start -0.7874 -0.4064)
			(end 0.7874 -0.4064)
			(stroke
				(width 0.1524)
				(type default)
			)
			(layer "F.SilkS")
		)
		(fp_line
			(start 0.7874 -0.4064)
			(end 0.7874 0.4064)
			(stroke
				(width 0.1524)
				(type default)
			)
			(layer "F.SilkS")
		)
		(fp_line
			(start -0.67945 0.3048)
			(end -0.67945 -0.305054)
			(stroke
				(width 0.1)
				(type default)
			)
			(layer "F.Fab")
		)
		(fp_line
			(start -0.12065 0.3048)
			(end -0.67945 0.3048)
			(stroke
				(width 0.1)
				(type default)
			)
			(layer "F.Fab")
		)
		(fp_line
			(start 0.120396 0.3048)
			(end 0.120396 0.2794)
			(stroke
				(width 0.1)
				(type default)
			)
			(layer "F.Fab")
		)
		(fp_line
			(start 0.67945 0.3048)
			(end 0.120396 0.3048)
			(stroke
				(width 0.1)
				(type default)
			)
			(layer "F.Fab")
		)
		(fp_line
			(start -0.12065 0.2794)
			(end -0.12065 0.3048)
			(stroke
				(width 0.1)
				(type default)
			)
			(layer "F.Fab")
		)
		(fp_line
			(start 0.120396 0.2794)
			(end -0.12065 0.2794)
			(stroke
				(width 0.1)
				(type default)
			)
			(layer "F.Fab")
		)
		(fp_line
			(start -0.12065 -0.2794)
			(end 0.12065 -0.2794)
			(stroke
				(width 0.1)
				(type default)
			)
			(layer "F.Fab")
		)
		(fp_line
			(start 0.12065 -0.2794)
			(end 0.12065 -0.3048)
			(stroke
				(width 0.1)
				(type default)
			)
			(layer "F.Fab")
		)
		(fp_line
			(start 0.12065 -0.3048)
			(end 0.67945 -0.3048)
			(stroke
				(width 0.1)
				(type default)
			)
			(layer "F.Fab")
		)
		(fp_line
			(start 0.67945 -0.3048)
			(end 0.67945 0.3048)
			(stroke
				(width 0.1)
				(type default)
			)
			(layer "F.Fab")
		)
		(fp_line
			(start -0.67945 -0.305054)
			(end -0.12065 -0.305054)
			(stroke
				(width 0.1)
				(type default)
			)
			(layer "F.Fab")
		)
		(fp_line
			(start -0.12065 -0.305054)
			(end -0.12065 -0.2794)
			(stroke
				(width 0.1)
				(type default)
			)
			(layer "F.Fab")
		)
		(pad "1" smd circle
			(at -0.40005 0 270)
			(size 0 0)
			(layers "F.Cu" "F.Mask" "F.Paste")
			(net "P3V3_LED")
		)
		(pad "2" smd circle
			(at 0.40005 0 270)
			(size 0 0)
			(layers "F.Cu" "F.Mask" "F.Paste")
			(net "FPGA_HEARTBEAT")
		)
	)
	(footprint ""
		(layer "F.Cu")
		(at 244.81282 -288.017204)
		(property "Reference" "PC256"
			(at 0 0 0)
			(layer "F.SilkS")
			(hide yes)
			(effects
				(font
					(size 1.27 1.27)
				)
			)
		)
		(property "Value" ""
			(at 0 0 0)
			(layer "F.Fab")
			(effects
				(font
					(size 1.27 1.27)
				)
			)
		)
		(duplicate_pad_numbers_are_jumpers no)
		(fp_line
			(start -0.7874 -0.4064)
			(end 0.7874 -0.4064)
			(stroke
				(width 0.1524)
				(type default)
			)
			(layer "F.SilkS")
		)
		(fp_line
			(start -0.7874 0.4064)
			(end -0.7874 -0.4064)
			(stroke
				(width 0.1524)
				(type default)
			)
			(layer "F.SilkS")
		)
		(fp_line
			(start 0.7874 -0.4064)
			(end 0.7874 0.4064)
			(stroke
				(width 0.1524)
				(type default)
			)
			(layer "F.SilkS")
		)
		(fp_line
			(start 0.7874 0.4064)
			(end -0.7874 0.4064)
			(stroke
				(width 0.1524)
				(type default)
			)
			(layer "F.SilkS")
		)
		(fp_line
			(start -0.67945 -0.305054)
			(end -0.12065 -0.305054)
			(stroke
				(width 0.1)
				(type default)
			)
			(layer "F.Fab")
		)
		(fp_line
			(start -0.67945 0.3048)
			(end -0.67945 -0.305054)
			(stroke
				(width 0.1)
				(type default)
			)
			(layer "F.Fab")
		)
		(fp_line
			(start -0.12065 -0.305054)
			(end -0.12065 -0.2794)
			(stroke
				(width 0.1)
				(type default)
			)
			(layer "F.Fab")
		)
		(fp_line
			(start -0.12065 -0.2794)
			(end 0.12065 -0.2794)
			(stroke
				(width 0.1)
				(type default)
			)
			(layer "F.Fab")
		)
		(fp_line
			(start -0.12065 0.2794)
			(end -0.12065 0.3048)
			(stroke
				(width 0.1)
				(type default)
			)
			(layer "F.Fab")
		)
		(fp_line
			(start -0.12065 0.3048)
			(end -0.67945 0.3048)
			(stroke
				(width 0.1)
				(type default)
			)
			(layer "F.Fab")
		)
		(fp_line
			(start 0.120396 0.2794)
			(end -0.12065 0.2794)
			(stroke
				(width 0.1)
				(type default)
			)
			(layer "F.Fab")
		)
		(fp_line
			(start 0.120396 0.3048)
			(end 0.120396 0.2794)
			(stroke
				(width 0.1)
				(type default)
			)
			(layer "F.Fab")
		)
		(fp_line
			(start 0.12065 -0.3048)
			(end 0.67945 -0.3048)
			(stroke
				(width 0.1)
				(type default)
			)
			(layer "F.Fab")
		)
		(fp_line
			(start 0.12065 -0.2794)
			(end 0.12065 -0.3048)
			(stroke
				(width 0.1)
				(type default)
			)
			(layer "F.Fab")
		)
		(fp_line
			(start 0.67945 -0.3048)
			(end 0.67945 0.3048)
			(stroke
				(width 0.1)
				(type default)
			)
			(layer "F.Fab")
		)
		(fp_line
			(start 0.67945 0.3048)
			(end 0.120396 0.3048)
			(stroke
				(width 0.1)
				(type default)
			)
			(layer "F.Fab")
		)
		(pad "1" smd circle
			(at -0.40005 0)
			(size 0 0)
			(layers "F.Cu" "F.Mask" "F.Paste")
			(net "P1V25_PEX2_R")
		)
		(pad "2" smd circle
			(at 0.40005 0)
			(size 0 0)
			(layers "F.Cu" "F.Mask" "F.Paste")
			(net "GND")
		)
	)
	(footprint ""
		(layer "F.Cu")
		(at 378.738384 -250.070874 -90)
		(property "Reference" "R1405"
			(at 0 0 270)
			(layer "F.SilkS")
			(hide yes)
			(effects
				(font
					(size 1.27 1.27)
				)
			)
		)
		(property "Value" ""
			(at 0 0 270)
			(layer "F.Fab")
			(effects
				(font
					(size 1.27 1.27)
				)
			)
		)
		(duplicate_pad_numbers_are_jumpers no)
		(fp_line
			(start -0.7874 0.4064)
			(end -0.7874 -0.4064)
			(stroke
				(width 0.1524)
				(type default)
			)
			(layer "F.SilkS")
		)
		(fp_line
			(start 0.7874 0.4064)
			(end -0.7874 0.4064)
			(stroke
				(width 0.1524)
				(type default)
			)
			(layer "F.SilkS")
		)
		(fp_line
			(start -0.7874 -0.4064)
			(end 0.7874 -0.4064)
			(stroke
				(width 0.1524)
				(type default)
			)
			(layer "F.SilkS")
		)
		(fp_line
			(start 0.7874 -0.4064)
			(end 0.7874 0.4064)
			(stroke
				(width 0.1524)
				(type default)
			)
			(layer "F.SilkS")
		)
		(fp_line
			(start -0.67945 0.3048)
			(end -0.67945 -0.305054)
			(stroke
				(width 0.1)
				(type default)
			)
			(layer "F.Fab")
		)
		(fp_line
			(start -0.12065 0.3048)
			(end -0.67945 0.3048)
			(stroke
				(width 0.1)
				(type default)
			)
			(layer "F.Fab")
		)
		(fp_line
			(start 0.120396 0.3048)
			(end 0.120396 0.2794)
			(stroke
				(width 0.1)
				(type default)
			)
			(layer "F.Fab")
		)
		(fp_line
			(start 0.67945 0.3048)
			(end 0.120396 0.3048)
			(stroke
				(width 0.1)
				(type default)
			)
			(layer "F.Fab")
		)
		(fp_line
			(start -0.12065 0.2794)
			(end -0.12065 0.3048)
			(stroke
				(width 0.1)
				(type default)
			)
			(layer "F.Fab")
		)
		(fp_line
			(start 0.120396 0.2794)
			(end -0.12065 0.2794)
			(stroke
				(width 0.1)
				(type default)
			)
			(layer "F.Fab")
		)
		(fp_line
			(start -0.12065 -0.2794)
			(end 0.12065 -0.2794)
			(stroke
				(width 0.1)
				(type default)
			)
			(layer "F.Fab")
		)
		(fp_line
			(start 0.12065 -0.2794)
			(end 0.12065 -0.3048)
			(stroke
				(width 0.1)
				(type default)
			)
			(layer "F.Fab")
		)
		(fp_line
			(start 0.12065 -0.3048)
			(end 0.67945 -0.3048)
			(stroke
				(width 0.1)
				(type default)
			)
			(layer "F.Fab")
		)
		(fp_line
			(start 0.67945 -0.3048)
			(end 0.67945 0.3048)
			(stroke
				(width 0.1)
				(type default)
			)
			(layer "F.Fab")
		)
		(fp_line
			(start -0.67945 -0.305054)
			(end -0.12065 -0.305054)
			(stroke
				(width 0.1)
				(type default)
			)
			(layer "F.Fab")
		)
		(fp_line
			(start -0.12065 -0.305054)
			(end -0.12065 -0.2794)
			(stroke
				(width 0.1)
				(type default)
			)
			(layer "F.Fab")
		)
		(pad "1" smd circle
			(at -0.40005 0 270)
			(size 0 0)
			(layers "F.Cu" "F.Mask" "F.Paste")
			(net "PEX3_MODE_SEL0")
		)
		(pad "2" smd circle
			(at 0.40005 0 270)
			(size 0 0)
			(layers "F.Cu" "F.Mask" "F.Paste")
			(net "P1V8_PEX")
		)
	)
	(footprint ""
		(layer "F.Cu")
		(at 149.303486 -390.398254 -90)
		(property "Reference" "R1841"
			(at 0 0 270)
			(layer "F.SilkS")
			(hide yes)
			(effects
				(font
					(size 1.27 1.27)
				)
			)
		)
		(property "Value" ""
			(at 0 0 270)
			(layer "F.Fab")
			(effects
				(font
					(size 1.27 1.27)
				)
			)
		)
		(duplicate_pad_numbers_are_jumpers no)
		(fp_line
			(start -0.7874 0.4064)
			(end -0.7874 -0.4064)
			(stroke
				(width 0.1524)
				(type default)
			)
			(layer "F.SilkS")
		)
		(fp_line
			(start 0.7874 0.4064)
			(end -0.7874 0.4064)
			(stroke
				(width 0.1524)
				(type default)
			)
			(layer "F.SilkS")
		)
		(fp_line
			(start -0.7874 -0.4064)
			(end 0.7874 -0.4064)
			(stroke
				(width 0.1524)
				(type default)
			)
			(layer "F.SilkS")
		)
		(fp_line
			(start 0.7874 -0.4064)
			(end 0.7874 0.4064)
			(stroke
				(width 0.1524)
				(type default)
			)
			(layer "F.SilkS")
		)
		(fp_line
			(start -0.67945 0.3048)
			(end -0.67945 -0.305054)
			(stroke
				(width 0.1)
				(type default)
			)
			(layer "F.Fab")
		)
		(fp_line
			(start -0.12065 0.3048)
			(end -0.67945 0.3048)
			(stroke
				(width 0.1)
				(type default)
			)
			(layer "F.Fab")
		)
		(fp_line
			(start 0.120396 0.3048)
			(end 0.120396 0.2794)
			(stroke
				(width 0.1)
				(type default)
			)
			(layer "F.Fab")
		)
		(fp_line
			(start 0.67945 0.3048)
			(end 0.120396 0.3048)
			(stroke
				(width 0.1)
				(type default)
			)
			(layer "F.Fab")
		)
		(fp_line
			(start -0.12065 0.2794)
			(end -0.12065 0.3048)
			(stroke
				(width 0.1)
				(type default)
			)
			(layer "F.Fab")
		)
		(fp_line
			(start 0.120396 0.2794)
			(end -0.12065 0.2794)
			(stroke
				(width 0.1)
				(type default)
			)
			(layer "F.Fab")
		)
		(fp_line
			(start -0.12065 -0.2794)
			(end 0.12065 -0.2794)
			(stroke
				(width 0.1)
				(type default)
			)
			(layer "F.Fab")
		)
		(fp_line
			(start 0.12065 -0.2794)
			(end 0.12065 -0.3048)
			(stroke
				(width 0.1)
				(type default)
			)
			(layer "F.Fab")
		)
		(fp_line
			(start 0.12065 -0.3048)
			(end 0.67945 -0.3048)
			(stroke
				(width 0.1)
				(type default)
			)
			(layer "F.Fab")
		)
		(fp_line
			(start 0.67945 -0.3048)
			(end 0.67945 0.3048)
			(stroke
				(width 0.1)
				(type default)
			)
			(layer "F.Fab")
		)
		(fp_line
			(start -0.67945 -0.305054)
			(end -0.12065 -0.305054)
			(stroke
				(width 0.1)
				(type default)
			)
			(layer "F.Fab")
		)
		(fp_line
			(start -0.12065 -0.305054)
			(end -0.12065 -0.2794)
			(stroke
				(width 0.1)
				(type default)
			)
			(layer "F.Fab")
		)
		(pad "1" smd circle
			(at -0.40005 0 270)
			(size 0 0)
			(layers "F.Cu" "F.Mask" "F.Paste")
			(net "GPU_BASE_HMC_READY_R")
		)
		(pad "2" smd circle
			(at 0.40005 0 270)
			(size 0 0)
			(layers "F.Cu" "F.Mask" "F.Paste")
			(net "GPU_BASE_HMC_READY")
		)
	)
	(footprint ""
		(layer "F.Cu")
		(at 252.85954 -61.612526)
		(property "Reference" "PD113"
			(at -3.7084 -2.733548 0)
			(unlocked yes)
			(layer "F.SilkS")
			(effects
				(font
					(size 0.7874 0.5842)
					(thickness 0.1524)
				)
				(justify left)
			)
		)
		(property "Value" ""
			(at 0 0 0)
			(layer "F.Fab")
			(effects
				(font
					(size 1.27 1.27)
				)
			)
		)
		(duplicate_pad_numbers_are_jumpers no)
		(fp_line
			(start -3.656584 -1.970024)
			(end -3.656584 1.970024)
			(stroke
				(width 0.1524)
				(type default)
			)
			(layer "F.SilkS")
		)
		(fp_line
			(start -3.656584 1.970024)
			(end 4.240784 1.970024)
			(stroke
				(width 0.1524)
				(type default)
			)
			(layer "F.SilkS")
		)
		(fp_line
			(start 4.240784 -1.970024)
			(end -3.656584 -1.970024)
			(stroke
				(width 0.1524)
				(type default)
			)
			(layer "F.SilkS")
		)
		(fp_line
			(start 4.240784 1.970024)
			(end 4.240784 -1.970024)
			(stroke
				(width 0.1524)
				(type default)
			)
			(layer "F.SilkS")
		)
		(fp_poly
			(pts
				(xy 3.580384 1.970024) (xy 3.580384 -1.970024) (xy 4.240784 -1.970024) (xy 4.240784 1.970024)
			)
			(stroke
				(width 0)
				(type default)
			)
			(fill yes)
			(layer "F.SilkS")
		)
		(fp_line
			(start -2.3749 -1.970024)
			(end -2.3749 1.970024)
			(stroke
				(width 0.1)
				(type default)
			)
			(layer "F.Fab")
		)
		(fp_line
			(start -2.3749 1.970024)
			(end 2.3749 1.970024)
			(stroke
				(width 0.1)
				(type default)
			)
			(layer "F.Fab")
		)
		(fp_line
			(start 2.3749 -1.970024)
			(end -2.3749 -1.970024)
			(stroke
				(width 0.1)
				(type default)
			)
			(layer "F.Fab")
		)
		(fp_line
			(start 2.3749 1.970024)
			(end 2.3749 -1.970024)
			(stroke
				(width 0.1)
				(type default)
			)
			(layer "F.Fab")
		)
		(fp_text user "+"
			(at -4.9784 -0.23495 0)
			(unlocked yes)
			(layer "F.Fab")
			(effects
				(font
					(size 1.905 1.4224)
					(thickness 0.1524)
				)
				(justify left)
			)
		)
		(fp_text user "-"
			(at 4.1656 -0.23495 0)
			(unlocked yes)
			(layer "F.Fab")
			(effects
				(font
					(size 1.905 1.4224)
					(thickness 0.1524)
				)
				(justify left)
			)
		)
		(pad "A" smd rect
			(at -2.450084 0)
			(size 2.159 2.2606)
			(layers "F.Cu" "F.Mask" "F.Paste")
			(net "GND")
		)
		(pad "C" smd rect
			(at 2.450084 0)
			(size 2.159 2.2606)
			(layers "F.Cu" "F.Mask" "F.Paste")
			(net "P12V_AUX")
		)
	)
	(footprint ""
		(layer "F.Cu")
		(at 81.639664 -87.349076 -90)
		(property "Reference" "R96"
			(at 0 0 270)
			(layer "F.SilkS")
			(hide yes)
			(effects
				(font
					(size 1.27 1.27)
				)
			)
		)
		(property "Value" ""
			(at 0 0 270)
			(layer "F.Fab")
			(effects
				(font
					(size 1.27 1.27)
				)
			)
		)
		(duplicate_pad_numbers_are_jumpers no)
		(fp_line
			(start -0.7874 0.4064)
			(end -0.7874 -0.4064)
			(stroke
				(width 0.1524)
				(type default)
			)
			(layer "F.SilkS")
		)
		(fp_line
			(start 0.7874 0.4064)
			(end -0.7874 0.4064)
			(stroke
				(width 0.1524)
				(type default)
			)
			(layer "F.SilkS")
		)
		(fp_line
			(start -0.7874 -0.4064)
			(end 0.7874 -0.4064)
			(stroke
				(width 0.1524)
				(type default)
			)
			(layer "F.SilkS")
		)
		(fp_line
			(start 0.7874 -0.4064)
			(end 0.7874 0.4064)
			(stroke
				(width 0.1524)
				(type default)
			)
			(layer "F.SilkS")
		)
		(fp_line
			(start -0.67945 0.3048)
			(end -0.67945 -0.305054)
			(stroke
				(width 0.1)
				(type default)
			)
			(layer "F.Fab")
		)
		(fp_line
			(start -0.12065 0.3048)
			(end -0.67945 0.3048)
			(stroke
				(width 0.1)
				(type default)
			)
			(layer "F.Fab")
		)
		(fp_line
			(start 0.120396 0.3048)
			(end 0.120396 0.2794)
			(stroke
				(width 0.1)
				(type default)
			)
			(layer "F.Fab")
		)
		(fp_line
			(start 0.67945 0.3048)
			(end 0.120396 0.3048)
			(stroke
				(width 0.1)
				(type default)
			)
			(layer "F.Fab")
		)
		(fp_line
			(start -0.12065 0.2794)
			(end -0.12065 0.3048)
			(stroke
				(width 0.1)
				(type default)
			)
			(layer "F.Fab")
		)
		(fp_line
			(start 0.120396 0.2794)
			(end -0.12065 0.2794)
			(stroke
				(width 0.1)
				(type default)
			)
			(layer "F.Fab")
		)
		(fp_line
			(start -0.12065 -0.2794)
			(end 0.12065 -0.2794)
			(stroke
				(width 0.1)
				(type default)
			)
			(layer "F.Fab")
		)
		(fp_line
			(start 0.12065 -0.2794)
			(end 0.12065 -0.3048)
			(stroke
				(width 0.1)
				(type default)
			)
			(layer "F.Fab")
		)
		(fp_line
			(start 0.12065 -0.3048)
			(end 0.67945 -0.3048)
			(stroke
				(width 0.1)
				(type default)
			)
			(layer "F.Fab")
		)
		(fp_line
			(start 0.67945 -0.3048)
			(end 0.67945 0.3048)
			(stroke
				(width 0.1)
				(type default)
			)
			(layer "F.Fab")
		)
		(fp_line
			(start -0.67945 -0.305054)
			(end -0.12065 -0.305054)
			(stroke
				(width 0.1)
				(type default)
			)
			(layer "F.Fab")
		)
		(fp_line
			(start -0.12065 -0.305054)
			(end -0.12065 -0.2794)
			(stroke
				(width 0.1)
				(type default)
			)
			(layer "F.Fab")
		)
		(pad "1" smd circle
			(at -0.40005 0 270)
			(size 0 0)
			(layers "F.Cu" "F.Mask" "F.Paste")
			(net "RST_NIC1_PERST0_R_N")
		)
		(pad "2" smd circle
			(at 0.40005 0 270)
			(size 0 0)
			(layers "F.Cu" "F.Mask" "F.Paste")
			(net "RST_HP_NIC1_BUF_N")
		)
	)
	(footprint ""
		(layer "F.Cu")
		(at 259.021072 -357.383842 90)
		(property "Reference" "PD2"
			(at 1.544574 4.171442 0)
			(unlocked yes)
			(layer "F.SilkS")
			(effects
				(font
					(size 0.7874 0.5842)
					(thickness 0.1524)
				)
			)
		)
		(property "Value" ""
			(at 0 0 90)
			(layer "F.Fab")
			(effects
				(font
					(size 1.27 1.27)
				)
			)
		)
		(duplicate_pad_numbers_are_jumpers no)
		(fp_line
			(start 3.541776 -2.54)
			(end 3.541776 2.54)
			(stroke
				(width 0.1524)
				(type default)
			)
			(layer "F.SilkS")
		)
		(fp_line
			(start -3.539744 -2.54)
			(end 3.541776 -2.54)
			(stroke
				(width 0.1524)
				(type default)
			)
			(layer "F.SilkS")
		)
		(fp_line
			(start 3.541776 2.54)
			(end -3.539744 2.54)
			(stroke
				(width 0.1524)
				(type default)
			)
			(layer "F.SilkS")
		)
		(fp_line
			(start -3.539744 2.54)
			(end -3.539744 -2.54)
			(stroke
				(width 0.1524)
				(type default)
			)
			(layer "F.SilkS")
		)
		(fp_poly
			(pts
				(xy -4.699 0.531876) (xy -4.699 1.547876) (xy -3.683 1.039876)
			)
			(stroke
				(width 0)
				(type default)
			)
			(fill yes)
			(layer "F.SilkS")
		)
		(fp_line
			(start 3.074924 -2.175002)
			(end 3.074924 2.175002)
			(stroke
				(width 0.1)
				(type default)
			)
			(layer "F.Fab")
		)
		(fp_line
			(start -3.074924 -2.175002)
			(end 3.074924 -2.175002)
			(stroke
				(width 0.1)
				(type default)
			)
			(layer "F.Fab")
		)
		(fp_line
			(start 3.074924 2.175002)
			(end -3.074924 2.175002)
			(stroke
				(width 0.1)
				(type default)
			)
			(layer "F.Fab")
		)
		(fp_line
			(start -3.074924 2.175002)
			(end -3.074924 -2.175002)
			(stroke
				(width 0.1)
				(type default)
			)
			(layer "F.Fab")
		)
		(fp_poly
			(pts
				(xy -4.699 0.531876) (xy -4.699 1.547876) (xy -3.683 1.039876)
			)
			(stroke
				(width 0)
				(type default)
			)
			(fill yes)
			(layer "F.Fab")
		)
		(pad "1" smd rect
			(at -2.765044 1.039876 270)
			(size 1.27 1.4224)
			(layers "F.Cu" "F.Mask" "F.Paste")
			(net "GND")
		)
		(pad "2" smd rect
			(at -2.765044 -1.039876 270)
			(size 1.27 1.4224)
			(layers "F.Cu" "F.Mask" "F.Paste")
			(net "GND")
		)
		(pad "K" smd rect
			(at 1.039876 0 270)
			(size 4.7244 4.8006)
			(layers "F.Cu" "F.Mask" "F.Paste")
			(net "P12V_AUX")
		)
	)
	(footprint ""
		(layer "F.Cu")
		(at 13.503402 -285.730442)
		(property "Reference" "PC216"
			(at 0 0 0)
			(layer "F.SilkS")
			(hide yes)
			(effects
				(font
					(size 1.27 1.27)
				)
			)
		)
		(property "Value" ""
			(at 0 0 0)
			(layer "F.Fab")
			(effects
				(font
					(size 1.27 1.27)
				)
			)
		)
		(duplicate_pad_numbers_are_jumpers no)
		(fp_line
			(start -0.7874 -0.4064)
			(end 0.7874 -0.4064)
			(stroke
				(width 0.1524)
				(type default)
			)
			(layer "F.SilkS")
		)
		(fp_line
			(start -0.7874 0.4064)
			(end -0.7874 -0.4064)
			(stroke
				(width 0.1524)
				(type default)
			)
			(layer "F.SilkS")
		)
		(fp_line
			(start 0.7874 -0.4064)
			(end 0.7874 0.4064)
			(stroke
				(width 0.1524)
				(type default)
			)
			(layer "F.SilkS")
		)
		(fp_line
			(start 0.7874 0.4064)
			(end -0.7874 0.4064)
			(stroke
				(width 0.1524)
				(type default)
			)
			(layer "F.SilkS")
		)
		(fp_line
			(start -0.67945 -0.305054)
			(end -0.12065 -0.305054)
			(stroke
				(width 0.1)
				(type default)
			)
			(layer "F.Fab")
		)
		(fp_line
			(start -0.67945 0.3048)
			(end -0.67945 -0.305054)
			(stroke
				(width 0.1)
				(type default)
			)
			(layer "F.Fab")
		)
		(fp_line
			(start -0.12065 -0.305054)
			(end -0.12065 -0.2794)
			(stroke
				(width 0.1)
				(type default)
			)
			(layer "F.Fab")
		)
		(fp_line
			(start -0.12065 -0.2794)
			(end 0.12065 -0.2794)
			(stroke
				(width 0.1)
				(type default)
			)
			(layer "F.Fab")
		)
		(fp_line
			(start -0.12065 0.2794)
			(end -0.12065 0.3048)
			(stroke
				(width 0.1)
				(type default)
			)
			(layer "F.Fab")
		)
		(fp_line
			(start -0.12065 0.3048)
			(end -0.67945 0.3048)
			(stroke
				(width 0.1)
				(type default)
			)
			(layer "F.Fab")
		)
		(fp_line
			(start 0.120396 0.2794)
			(end -0.12065 0.2794)
			(stroke
				(width 0.1)
				(type default)
			)
			(layer "F.Fab")
		)
		(fp_line
			(start 0.120396 0.3048)
			(end 0.120396 0.2794)
			(stroke
				(width 0.1)
				(type default)
			)
			(layer "F.Fab")
		)
		(fp_line
			(start 0.12065 -0.3048)
			(end 0.67945 -0.3048)
			(stroke
				(width 0.1)
				(type default)
			)
			(layer "F.Fab")
		)
		(fp_line
			(start 0.12065 -0.2794)
			(end 0.12065 -0.3048)
			(stroke
				(width 0.1)
				(type default)
			)
			(layer "F.Fab")
		)
		(fp_line
			(start 0.67945 -0.3048)
			(end 0.67945 0.3048)
			(stroke
				(width 0.1)
				(type default)
			)
			(layer "F.Fab")
		)
		(fp_line
			(start 0.67945 0.3048)
			(end 0.120396 0.3048)
			(stroke
				(width 0.1)
				(type default)
			)
			(layer "F.Fab")
		)
		(pad "1" smd circle
			(at -0.40005 0)
			(size 0 0)
			(layers "F.Cu" "F.Mask" "F.Paste")
			(net "P1V25_PEX0_R")
		)
		(pad "2" smd circle
			(at 0.40005 0)
			(size 0 0)
			(layers "F.Cu" "F.Mask" "F.Paste")
			(net "GND")
		)
	)
	(footprint ""
		(layer "F.Cu")
		(at 336.551778 -93.154246 -90)
		(property "Reference" "R3509"
			(at 0 0 270)
			(layer "F.SilkS")
			(hide yes)
			(effects
				(font
					(size 1.27 1.27)
				)
			)
		)
		(property "Value" ""
			(at 0 0 270)
			(layer "F.Fab")
			(effects
				(font
					(size 1.27 1.27)
				)
			)
		)
		(duplicate_pad_numbers_are_jumpers no)
		(fp_line
			(start -0.7874 0.4064)
			(end -0.7874 -0.4064)
			(stroke
				(width 0.1524)
				(type default)
			)
			(layer "F.SilkS")
		)
		(fp_line
			(start 0.7874 0.4064)
			(end -0.7874 0.4064)
			(stroke
				(width 0.1524)
				(type default)
			)
			(layer "F.SilkS")
		)
		(fp_line
			(start -0.7874 -0.4064)
			(end 0.7874 -0.4064)
			(stroke
				(width 0.1524)
				(type default)
			)
			(layer "F.SilkS")
		)
		(fp_line
			(start 0.7874 -0.4064)
			(end 0.7874 0.4064)
			(stroke
				(width 0.1524)
				(type default)
			)
			(layer "F.SilkS")
		)
		(fp_line
			(start -0.67945 0.3048)
			(end -0.67945 -0.305054)
			(stroke
				(width 0.1)
				(type default)
			)
			(layer "F.Fab")
		)
		(fp_line
			(start -0.12065 0.3048)
			(end -0.67945 0.3048)
			(stroke
				(width 0.1)
				(type default)
			)
			(layer "F.Fab")
		)
		(fp_line
			(start 0.120396 0.3048)
			(end 0.120396 0.2794)
			(stroke
				(width 0.1)
				(type default)
			)
			(layer "F.Fab")
		)
		(fp_line
			(start 0.67945 0.3048)
			(end 0.120396 0.3048)
			(stroke
				(width 0.1)
				(type default)
			)
			(layer "F.Fab")
		)
		(fp_line
			(start -0.12065 0.2794)
			(end -0.12065 0.3048)
			(stroke
				(width 0.1)
				(type default)
			)
			(layer "F.Fab")
		)
		(fp_line
			(start 0.120396 0.2794)
			(end -0.12065 0.2794)
			(stroke
				(width 0.1)
				(type default)
			)
			(layer "F.Fab")
		)
		(fp_line
			(start -0.12065 -0.2794)
			(end 0.12065 -0.2794)
			(stroke
				(width 0.1)
				(type default)
			)
			(layer "F.Fab")
		)
		(fp_line
			(start 0.12065 -0.2794)
			(end 0.12065 -0.3048)
			(stroke
				(width 0.1)
				(type default)
			)
			(layer "F.Fab")
		)
		(fp_line
			(start 0.12065 -0.3048)
			(end 0.67945 -0.3048)
			(stroke
				(width 0.1)
				(type default)
			)
			(layer "F.Fab")
		)
		(fp_line
			(start 0.67945 -0.3048)
			(end 0.67945 0.3048)
			(stroke
				(width 0.1)
				(type default)
			)
			(layer "F.Fab")
		)
		(fp_line
			(start -0.67945 -0.305054)
			(end -0.12065 -0.305054)
			(stroke
				(width 0.1)
				(type default)
			)
			(layer "F.Fab")
		)
		(fp_line
			(start -0.12065 -0.305054)
			(end -0.12065 -0.2794)
			(stroke
				(width 0.1)
				(type default)
			)
			(layer "F.Fab")
		)
		(pad "1" smd circle
			(at -0.40005 0 270)
			(size 0 0)
			(layers "F.Cu" "F.Mask" "F.Paste")
			(net "P3V3")
		)
		(pad "2" smd circle
			(at 0.40005 0 270)
			(size 0 0)
			(layers "F.Cu" "F.Mask" "F.Paste")
			(net "PU_9ZXL0851_8_15_100M")
		)
	)
	(footprint ""
		(layer "F.Cu")
		(at 48.027844 -35.876738)
		(property "Reference" "R5882"
			(at 0 0 0)
			(layer "F.SilkS")
			(hide yes)
			(effects
				(font
					(size 1.27 1.27)
				)
			)
		)
		(property "Value" ""
			(at 0 0 0)
			(layer "F.Fab")
			(effects
				(font
					(size 1.27 1.27)
				)
			)
		)
		(duplicate_pad_numbers_are_jumpers no)
		(fp_line
			(start -0.7874 -0.4064)
			(end 0.7874 -0.4064)
			(stroke
				(width 0.1524)
				(type default)
			)
			(layer "F.SilkS")
		)
		(fp_line
			(start -0.7874 0.4064)
			(end -0.7874 -0.4064)
			(stroke
				(width 0.1524)
				(type default)
			)
			(layer "F.SilkS")
		)
		(fp_line
			(start 0.7874 -0.4064)
			(end 0.7874 0.4064)
			(stroke
				(width 0.1524)
				(type default)
			)
			(layer "F.SilkS")
		)
		(fp_line
			(start 0.7874 0.4064)
			(end -0.7874 0.4064)
			(stroke
				(width 0.1524)
				(type default)
			)
			(layer "F.SilkS")
		)
		(fp_line
			(start -0.67945 -0.305054)
			(end -0.12065 -0.305054)
			(stroke
				(width 0.1)
				(type default)
			)
			(layer "F.Fab")
		)
		(fp_line
			(start -0.67945 0.3048)
			(end -0.67945 -0.305054)
			(stroke
				(width 0.1)
				(type default)
			)
			(layer "F.Fab")
		)
		(fp_line
			(start -0.12065 -0.305054)
			(end -0.12065 -0.2794)
			(stroke
				(width 0.1)
				(type default)
			)
			(layer "F.Fab")
		)
		(fp_line
			(start -0.12065 -0.2794)
			(end 0.12065 -0.2794)
			(stroke
				(width 0.1)
				(type default)
			)
			(layer "F.Fab")
		)
		(fp_line
			(start -0.12065 0.2794)
			(end -0.12065 0.3048)
			(stroke
				(width 0.1)
				(type default)
			)
			(layer "F.Fab")
		)
		(fp_line
			(start -0.12065 0.3048)
			(end -0.67945 0.3048)
			(stroke
				(width 0.1)
				(type default)
			)
			(layer "F.Fab")
		)
		(fp_line
			(start 0.120396 0.2794)
			(end -0.12065 0.2794)
			(stroke
				(width 0.1)
				(type default)
			)
			(layer "F.Fab")
		)
		(fp_line
			(start 0.120396 0.3048)
			(end 0.120396 0.2794)
			(stroke
				(width 0.1)
				(type default)
			)
			(layer "F.Fab")
		)
		(fp_line
			(start 0.12065 -0.3048)
			(end 0.67945 -0.3048)
			(stroke
				(width 0.1)
				(type default)
			)
			(layer "F.Fab")
		)
		(fp_line
			(start 0.12065 -0.2794)
			(end 0.12065 -0.3048)
			(stroke
				(width 0.1)
				(type default)
			)
			(layer "F.Fab")
		)
		(fp_line
			(start 0.67945 -0.3048)
			(end 0.67945 0.3048)
			(stroke
				(width 0.1)
				(type default)
			)
			(layer "F.Fab")
		)
		(fp_line
			(start 0.67945 0.3048)
			(end 0.120396 0.3048)
			(stroke
				(width 0.1)
				(type default)
			)
			(layer "F.Fab")
		)
		(pad "1" smd circle
			(at -0.40005 0)
			(size 0 0)
			(layers "F.Cu" "F.Mask" "F.Paste")
			(net "PWRGD_P3V3_SSD2_D")
		)
		(pad "2" smd circle
			(at 0.40005 0)
			(size 0 0)
			(layers "F.Cu" "F.Mask" "F.Paste")
			(net "PWRGD_P3V3_SSD2_R")
		)
	)
	(footprint ""
		(layer "F.Cu")
		(at 340.995 -234.061 90)
		(property "Reference" "R3594"
			(at 0 0 90)
			(layer "F.SilkS")
			(hide yes)
			(effects
				(font
					(size 1.27 1.27)
				)
			)
		)
		(property "Value" ""
			(at 0 0 90)
			(layer "F.Fab")
			(effects
				(font
					(size 1.27 1.27)
				)
			)
		)
		(duplicate_pad_numbers_are_jumpers no)
		(fp_line
			(start 0.7874 -0.4064)
			(end 0.7874 0.4064)
			(stroke
				(width 0.1524)
				(type default)
			)
			(layer "F.SilkS")
		)
		(fp_line
			(start -0.7874 -0.4064)
			(end 0.7874 -0.4064)
			(stroke
				(width 0.1524)
				(type default)
			)
			(layer "F.SilkS")
		)
		(fp_line
			(start 0.7874 0.4064)
			(end -0.7874 0.4064)
			(stroke
				(width 0.1524)
				(type default)
			)
			(layer "F.SilkS")
		)
		(fp_line
			(start -0.7874 0.4064)
			(end -0.7874 -0.4064)
			(stroke
				(width 0.1524)
				(type default)
			)
			(layer "F.SilkS")
		)
		(fp_line
			(start -0.12065 -0.305054)
			(end -0.12065 -0.2794)
			(stroke
				(width 0.1)
				(type default)
			)
			(layer "F.Fab")
		)
		(fp_line
			(start -0.67945 -0.305054)
			(end -0.12065 -0.305054)
			(stroke
				(width 0.1)
				(type default)
			)
			(layer "F.Fab")
		)
		(fp_line
			(start 0.67945 -0.3048)
			(end 0.67945 0.3048)
			(stroke
				(width 0.1)
				(type default)
			)
			(layer "F.Fab")
		)
		(fp_line
			(start 0.12065 -0.3048)
			(end 0.67945 -0.3048)
			(stroke
				(width 0.1)
				(type default)
			)
			(layer "F.Fab")
		)
		(fp_line
			(start 0.12065 -0.2794)
			(end 0.12065 -0.3048)
			(stroke
				(width 0.1)
				(type default)
			)
			(layer "F.Fab")
		)
		(fp_line
			(start -0.12065 -0.2794)
			(end 0.12065 -0.2794)
			(stroke
				(width 0.1)
				(type default)
			)
			(layer "F.Fab")
		)
		(fp_line
			(start 0.120396 0.2794)
			(end -0.12065 0.2794)
			(stroke
				(width 0.1)
				(type default)
			)
			(layer "F.Fab")
		)
		(fp_line
			(start -0.12065 0.2794)
			(end -0.12065 0.3048)
			(stroke
				(width 0.1)
				(type default)
			)
			(layer "F.Fab")
		)
		(fp_line
			(start 0.67945 0.3048)
			(end 0.120396 0.3048)
			(stroke
				(width 0.1)
				(type default)
			)
			(layer "F.Fab")
		)
		(fp_line
			(start 0.120396 0.3048)
			(end 0.120396 0.2794)
			(stroke
				(width 0.1)
				(type default)
			)
			(layer "F.Fab")
		)
		(fp_line
			(start -0.12065 0.3048)
			(end -0.67945 0.3048)
			(stroke
				(width 0.1)
				(type default)
			)
			(layer "F.Fab")
		)
		(fp_line
			(start -0.67945 0.3048)
			(end -0.67945 -0.305054)
			(stroke
				(width 0.1)
				(type default)
			)
			(layer "F.Fab")
		)
		(pad "1" smd circle
			(at -0.40005 0 90)
			(size 0 0)
			(layers "F.Cu" "F.Mask" "F.Paste")
			(net "SSD1_PWR_EN")
		)
		(pad "2" smd circle
			(at 0.40005 0 90)
			(size 0 0)
			(layers "F.Cu" "F.Mask" "F.Paste")
			(net "SSD1_PWR_EN_R")
		)
	)
	(footprint ""
		(layer "F.Cu")
		(at 462.465674 -275.62683)
		(property "Reference" "R803"
			(at 0 0 0)
			(layer "F.SilkS")
			(hide yes)
			(effects
				(font
					(size 1.27 1.27)
				)
			)
		)
		(property "Value" ""
			(at 0 0 0)
			(layer "F.Fab")
			(effects
				(font
					(size 1.27 1.27)
				)
			)
		)
		(duplicate_pad_numbers_are_jumpers no)
		(fp_line
			(start -0.7874 -0.4064)
			(end 0.7874 -0.4064)
			(stroke
				(width 0.1524)
				(type default)
			)
			(layer "F.SilkS")
		)
		(fp_line
			(start -0.7874 0.4064)
			(end -0.7874 -0.4064)
			(stroke
				(width 0.1524)
				(type default)
			)
			(layer "F.SilkS")
		)
		(fp_line
			(start 0.7874 -0.4064)
			(end 0.7874 0.4064)
			(stroke
				(width 0.1524)
				(type default)
			)
			(layer "F.SilkS")
		)
		(fp_line
			(start 0.7874 0.4064)
			(end -0.7874 0.4064)
			(stroke
				(width 0.1524)
				(type default)
			)
			(layer "F.SilkS")
		)
		(fp_line
			(start -0.67945 -0.305054)
			(end -0.12065 -0.305054)
			(stroke
				(width 0.1)
				(type default)
			)
			(layer "F.Fab")
		)
		(fp_line
			(start -0.67945 0.3048)
			(end -0.67945 -0.305054)
			(stroke
				(width 0.1)
				(type default)
			)
			(layer "F.Fab")
		)
		(fp_line
			(start -0.12065 -0.305054)
			(end -0.12065 -0.2794)
			(stroke
				(width 0.1)
				(type default)
			)
			(layer "F.Fab")
		)
		(fp_line
			(start -0.12065 -0.2794)
			(end 0.12065 -0.2794)
			(stroke
				(width 0.1)
				(type default)
			)
			(layer "F.Fab")
		)
		(fp_line
			(start -0.12065 0.2794)
			(end -0.12065 0.3048)
			(stroke
				(width 0.1)
				(type default)
			)
			(layer "F.Fab")
		)
		(fp_line
			(start -0.12065 0.3048)
			(end -0.67945 0.3048)
			(stroke
				(width 0.1)
				(type default)
			)
			(layer "F.Fab")
		)
		(fp_line
			(start 0.120396 0.2794)
			(end -0.12065 0.2794)
			(stroke
				(width 0.1)
				(type default)
			)
			(layer "F.Fab")
		)
		(fp_line
			(start 0.120396 0.3048)
			(end 0.120396 0.2794)
			(stroke
				(width 0.1)
				(type default)
			)
			(layer "F.Fab")
		)
		(fp_line
			(start 0.12065 -0.3048)
			(end 0.67945 -0.3048)
			(stroke
				(width 0.1)
				(type default)
			)
			(layer "F.Fab")
		)
		(fp_line
			(start 0.12065 -0.2794)
			(end 0.12065 -0.3048)
			(stroke
				(width 0.1)
				(type default)
			)
			(layer "F.Fab")
		)
		(fp_line
			(start 0.67945 -0.3048)
			(end 0.67945 0.3048)
			(stroke
				(width 0.1)
				(type default)
			)
			(layer "F.Fab")
		)
		(fp_line
			(start 0.67945 0.3048)
			(end 0.120396 0.3048)
			(stroke
				(width 0.1)
				(type default)
			)
			(layer "F.Fab")
		)
		(pad "1" smd circle
			(at -0.40005 0)
			(size 0 0)
			(layers "F.Cu" "F.Mask" "F.Paste")
			(net "PEX3_P1V25_ADC_A0")
		)
		(pad "2" smd circle
			(at 0.40005 0)
			(size 0 0)
			(layers "F.Cu" "F.Mask" "F.Paste")
			(net "P3V3_AUX")
		)
	)
	(footprint ""
		(layer "F.Cu")
		(at 459.5368 -308.285896 90)
		(property "Reference" "PC282"
			(at 0 0 90)
			(layer "F.SilkS")
			(hide yes)
			(effects
				(font
					(size 1.27 1.27)
				)
			)
		)
		(property "Value" ""
			(at 0 0 90)
			(layer "F.Fab")
			(effects
				(font
					(size 1.27 1.27)
				)
			)
		)
		(duplicate_pad_numbers_are_jumpers no)
		(fp_line
			(start 0.7874 -0.4064)
			(end 0.7874 0.4064)
			(stroke
				(width 0.1524)
				(type default)
			)
			(layer "F.SilkS")
		)
		(fp_line
			(start -0.7874 -0.4064)
			(end 0.7874 -0.4064)
			(stroke
				(width 0.1524)
				(type default)
			)
			(layer "F.SilkS")
		)
		(fp_line
			(start 0.7874 0.4064)
			(end -0.7874 0.4064)
			(stroke
				(width 0.1524)
				(type default)
			)
			(layer "F.SilkS")
		)
		(fp_line
			(start -0.7874 0.4064)
			(end -0.7874 -0.4064)
			(stroke
				(width 0.1524)
				(type default)
			)
			(layer "F.SilkS")
		)
		(fp_line
			(start -0.12065 -0.305054)
			(end -0.12065 -0.2794)
			(stroke
				(width 0.1)
				(type default)
			)
			(layer "F.Fab")
		)
		(fp_line
			(start -0.67945 -0.305054)
			(end -0.12065 -0.305054)
			(stroke
				(width 0.1)
				(type default)
			)
			(layer "F.Fab")
		)
		(fp_line
			(start 0.67945 -0.3048)
			(end 0.67945 0.3048)
			(stroke
				(width 0.1)
				(type default)
			)
			(layer "F.Fab")
		)
		(fp_line
			(start 0.12065 -0.3048)
			(end 0.67945 -0.3048)
			(stroke
				(width 0.1)
				(type default)
			)
			(layer "F.Fab")
		)
		(fp_line
			(start 0.12065 -0.2794)
			(end 0.12065 -0.3048)
			(stroke
				(width 0.1)
				(type default)
			)
			(layer "F.Fab")
		)
		(fp_line
			(start -0.12065 -0.2794)
			(end 0.12065 -0.2794)
			(stroke
				(width 0.1)
				(type default)
			)
			(layer "F.Fab")
		)
		(fp_line
			(start 0.120396 0.2794)
			(end -0.12065 0.2794)
			(stroke
				(width 0.1)
				(type default)
			)
			(layer "F.Fab")
		)
		(fp_line
			(start -0.12065 0.2794)
			(end -0.12065 0.3048)
			(stroke
				(width 0.1)
				(type default)
			)
			(layer "F.Fab")
		)
		(fp_line
			(start 0.67945 0.3048)
			(end 0.120396 0.3048)
			(stroke
				(width 0.1)
				(type default)
			)
			(layer "F.Fab")
		)
		(fp_line
			(start 0.120396 0.3048)
			(end 0.120396 0.2794)
			(stroke
				(width 0.1)
				(type default)
			)
			(layer "F.Fab")
		)
		(fp_line
			(start -0.12065 0.3048)
			(end -0.67945 0.3048)
			(stroke
				(width 0.1)
				(type default)
			)
			(layer "F.Fab")
		)
		(fp_line
			(start -0.67945 0.3048)
			(end -0.67945 -0.305054)
			(stroke
				(width 0.1)
				(type default)
			)
			(layer "F.Fab")
		)
		(pad "1" smd circle
			(at -0.40005 0 90)
			(size 0 0)
			(layers "F.Cu" "F.Mask" "F.Paste")
			(net "P1V25_PEX3_REF")
		)
		(pad "2" smd circle
			(at 0.40005 0 90)
			(size 0 0)
			(layers "F.Cu" "F.Mask" "F.Paste")
			(net "SH_P1V25_PEX3_FB_N")
		)
	)
	(footprint ""
		(layer "F.Cu")
		(at 428.319438 -147.104608 180)
		(property "Reference" "C644"
			(at 0 0 180)
			(layer "F.SilkS")
			(hide yes)
			(effects
				(font
					(size 1.27 1.27)
				)
			)
		)
		(property "Value" ""
			(at 0 0 180)
			(layer "F.Fab")
			(effects
				(font
					(size 1.27 1.27)
				)
			)
		)
		(duplicate_pad_numbers_are_jumpers no)
		(fp_line
			(start 0.299974 0.150114)
			(end -0.299974 0.150114)
			(stroke
				(width 0.1)
				(type default)
			)
			(layer "F.Fab")
		)
		(fp_line
			(start 0.299974 -0.150114)
			(end 0.299974 0.150114)
			(stroke
				(width 0.1)
				(type default)
			)
			(layer "F.Fab")
		)
		(fp_line
			(start -0.299974 0.150114)
			(end -0.299974 -0.150114)
			(stroke
				(width 0.1)
				(type default)
			)
			(layer "F.Fab")
		)
		(fp_line
			(start -0.299974 -0.150114)
			(end 0.299974 -0.150114)
			(stroke
				(width 0.1)
				(type default)
			)
			(layer "F.Fab")
		)
		(pad "1" smd rect
			(at -0.2667 0 180)
			(size 0.3048 0.381)
			(layers "F.Cu" "F.Mask" "F.Paste")
			(net "P5E_PEX3_STN0_TX_DP<10>")
		)
		(pad "2" smd rect
			(at 0.2667 0 180)
			(size 0.3048 0.381)
			(layers "F.Cu" "F.Mask" "F.Paste")
			(net "P5E_PEX3_STN0_TX_C_DP<10>")
		)
	)
	(footprint ""
		(layer "F.Cu")
		(at 429.175164 -64.102234 180)
		(property "Reference" "PR7098"
			(at 0 0 180)
			(layer "F.SilkS")
			(hide yes)
			(effects
				(font
					(size 1.27 1.27)
				)
			)
		)
		(property "Value" ""
			(at 0 0 180)
			(layer "F.Fab")
			(effects
				(font
					(size 1.27 1.27)
				)
			)
		)
		(duplicate_pad_numbers_are_jumpers no)
		(fp_line
			(start 0.7874 0.4064)
			(end -0.7874 0.4064)
			(stroke
				(width 0.1524)
				(type default)
			)
			(layer "F.SilkS")
		)
		(fp_line
			(start 0.7874 -0.4064)
			(end 0.7874 0.4064)
			(stroke
				(width 0.1524)
				(type default)
			)
			(layer "F.SilkS")
		)
		(fp_line
			(start -0.7874 0.4064)
			(end -0.7874 -0.4064)
			(stroke
				(width 0.1524)
				(type default)
			)
			(layer "F.SilkS")
		)
		(fp_line
			(start -0.7874 -0.4064)
			(end 0.7874 -0.4064)
			(stroke
				(width 0.1524)
				(type default)
			)
			(layer "F.SilkS")
		)
		(fp_line
			(start 0.67945 0.3048)
			(end 0.120396 0.3048)
			(stroke
				(width 0.1)
				(type default)
			)
			(layer "F.Fab")
		)
		(fp_line
			(start 0.67945 -0.3048)
			(end 0.67945 0.3048)
			(stroke
				(width 0.1)
				(type default)
			)
			(layer "F.Fab")
		)
		(fp_line
			(start 0.12065 -0.2794)
			(end 0.12065 -0.3048)
			(stroke
				(width 0.1)
				(type default)
			)
			(layer "F.Fab")
		)
		(fp_line
			(start 0.12065 -0.3048)
			(end 0.67945 -0.3048)
			(stroke
				(width 0.1)
				(type default)
			)
			(layer "F.Fab")
		)
		(fp_line
			(start 0.120396 0.3048)
			(end 0.120396 0.2794)
			(stroke
				(width 0.1)
				(type default)
			)
			(layer "F.Fab")
		)
		(fp_line
			(start 0.120396 0.2794)
			(end -0.12065 0.2794)
			(stroke
				(width 0.1)
				(type default)
			)
			(layer "F.Fab")
		)
		(fp_line
			(start -0.12065 0.3048)
			(end -0.67945 0.3048)
			(stroke
				(width 0.1)
				(type default)
			)
			(layer "F.Fab")
		)
		(fp_line
			(start -0.12065 0.2794)
			(end -0.12065 0.3048)
			(stroke
				(width 0.1)
				(type default)
			)
			(layer "F.Fab")
		)
		(fp_line
			(start -0.12065 -0.2794)
			(end 0.12065 -0.2794)
			(stroke
				(width 0.1)
				(type default)
			)
			(layer "F.Fab")
		)
		(fp_line
			(start -0.12065 -0.305054)
			(end -0.12065 -0.2794)
			(stroke
				(width 0.1)
				(type default)
			)
			(layer "F.Fab")
		)
		(fp_line
			(start -0.67945 0.3048)
			(end -0.67945 -0.305054)
			(stroke
				(width 0.1)
				(type default)
			)
			(layer "F.Fab")
		)
		(fp_line
			(start -0.67945 -0.305054)
			(end -0.12065 -0.305054)
			(stroke
				(width 0.1)
				(type default)
			)
			(layer "F.Fab")
		)
		(pad "1" smd circle
			(at -0.40005 0 180)
			(size 0 0)
			(layers "F.Cu" "F.Mask" "F.Paste")
			(net "P12V_SSD15_PG_G1")
		)
		(pad "2" smd circle
			(at 0.40005 0 180)
			(size 0 0)
			(layers "F.Cu" "F.Mask" "F.Paste")
			(net "GND")
		)
	)
	(footprint ""
		(layer "F.Cu")
		(at 88.495886 -310.509412 135)
		(property "Reference" "R1238"
			(at 0 0 135)
			(layer "F.SilkS")
			(hide yes)
			(effects
				(font
					(size 1.27 1.27)
				)
			)
		)
		(property "Value" ""
			(at 0 0 135)
			(layer "F.Fab")
			(effects
				(font
					(size 1.27 1.27)
				)
			)
		)
		(duplicate_pad_numbers_are_jumpers no)
		(fp_line
			(start 0.787389 -0.406267)
			(end 0.787389 0.406267)
			(stroke
				(width 0.1524)
				(type default)
			)
			(layer "F.SilkS")
		)
		(fp_line
			(start 0.787389 0.406267)
			(end -0.787389 0.406267)
			(stroke
				(width 0.1524)
				(type default)
			)
			(layer "F.SilkS")
		)
		(fp_line
			(start -0.787389 -0.406267)
			(end 0.787389 -0.406267)
			(stroke
				(width 0.1524)
				(type default)
			)
			(layer "F.SilkS")
		)
		(fp_line
			(start -0.787389 0.406267)
			(end -0.787389 -0.406267)
			(stroke
				(width 0.1524)
				(type default)
			)
			(layer "F.SilkS")
		)
		(fp_line
			(start 0.679446 -0.30479)
			(end 0.679446 0.30479)
			(stroke
				(width 0.1)
				(type default)
			)
			(layer "F.Fab")
		)
		(fp_line
			(start 0.120515 -0.30479)
			(end 0.679446 -0.30479)
			(stroke
				(width 0.1)
				(type default)
			)
			(layer "F.Fab")
		)
		(fp_line
			(start 0.120695 -0.279466)
			(end 0.120515 -0.30479)
			(stroke
				(width 0.1)
				(type default)
			)
			(layer "F.Fab")
		)
		(fp_line
			(start 0.679446 0.30479)
			(end 0.120515 0.30479)
			(stroke
				(width 0.1)
				(type default)
			)
			(layer "F.Fab")
		)
		(fp_line
			(start -0.120695 -0.304969)
			(end -0.120695 -0.279466)
			(stroke
				(width 0.1)
				(type default)
			)
			(layer "F.Fab")
		)
		(fp_line
			(start -0.120695 -0.279466)
			(end 0.120695 -0.279466)
			(stroke
				(width 0.1)
				(type default)
			)
			(layer "F.Fab")
		)
		(fp_line
			(start 0.120335 0.279466)
			(end -0.120695 0.279466)
			(stroke
				(width 0.1)
				(type default)
			)
			(layer "F.Fab")
		)
		(fp_line
			(start 0.120515 0.30479)
			(end 0.120335 0.279466)
			(stroke
				(width 0.1)
				(type default)
			)
			(layer "F.Fab")
		)
		(fp_line
			(start -0.679446 -0.305149)
			(end -0.120695 -0.304969)
			(stroke
				(width 0.1)
				(type default)
			)
			(layer "F.Fab")
		)
		(fp_line
			(start -0.120695 0.279466)
			(end -0.120515 0.30479)
			(stroke
				(width 0.1)
				(type default)
			)
			(layer "F.Fab")
		)
		(fp_line
			(start -0.120515 0.30479)
			(end -0.679446 0.30479)
			(stroke
				(width 0.1)
				(type default)
			)
			(layer "F.Fab")
		)
		(fp_line
			(start -0.679446 0.30479)
			(end -0.679446 -0.305149)
			(stroke
				(width 0.1)
				(type default)
			)
			(layer "F.Fab")
		)
		(pad "1" smd circle
			(at -0.40005 0 135)
			(size 0 0)
			(layers "F.Cu" "F.Mask" "F.Paste")
			(net "PEX0_SPARE2")
		)
		(pad "2" smd circle
			(at 0.40005 0 135)
			(size 0 0)
			(layers "F.Cu" "F.Mask" "F.Paste")
			(net "P1V8_PEX")
		)
	)
	(footprint ""
		(layer "F.Cu")
		(at 278.112982 -343.952322 90)
		(property "Reference" "C606"
			(at 0 0 90)
			(layer "F.SilkS")
			(hide yes)
			(effects
				(font
					(size 1.27 1.27)
				)
			)
		)
		(property "Value" ""
			(at 0 0 90)
			(layer "F.Fab")
			(effects
				(font
					(size 1.27 1.27)
				)
			)
		)
		(duplicate_pad_numbers_are_jumpers no)
		(fp_line
			(start 0.299974 -0.150114)
			(end 0.299974 0.150114)
			(stroke
				(width 0.1)
				(type default)
			)
			(layer "F.Fab")
		)
		(fp_line
			(start -0.299974 -0.150114)
			(end 0.299974 -0.150114)
			(stroke
				(width 0.1)
				(type default)
			)
			(layer "F.Fab")
		)
		(fp_line
			(start 0.299974 0.150114)
			(end -0.299974 0.150114)
			(stroke
				(width 0.1)
				(type default)
			)
			(layer "F.Fab")
		)
		(fp_line
			(start -0.299974 0.150114)
			(end -0.299974 -0.150114)
			(stroke
				(width 0.1)
				(type default)
			)
			(layer "F.Fab")
		)
		(pad "1" smd rect
			(at -0.2667 0 90)
			(size 0.3048 0.381)
			(layers "F.Cu" "F.Mask" "F.Paste")
			(net "P5E_PEX2_STN7_TX_DN<116>")
		)
		(pad "2" smd rect
			(at 0.2667 0 90)
			(size 0.3048 0.381)
			(layers "F.Cu" "F.Mask" "F.Paste")
			(net "P5E_PEX2_STN7_TX_C_DN<116>")
		)
	)
	(footprint ""
		(layer "F.Cu")
		(at 437.42229 -102.319328 45)
		(property "Reference" "C624"
			(at 0 0 45)
			(layer "F.SilkS")
			(hide yes)
			(effects
				(font
					(size 1.27 1.27)
				)
			)
		)
		(property "Value" ""
			(at 0 0 45)
			(layer "F.Fab")
			(effects
				(font
					(size 1.27 1.27)
				)
			)
		)
		(duplicate_pad_numbers_are_jumpers no)
		(fp_line
			(start -0.787389 -0.406267)
			(end 0.787389 -0.406267)
			(stroke
				(width 0.1524)
				(type default)
			)
			(layer "F.SilkS")
		)
		(fp_line
			(start -0.787389 0.406267)
			(end -0.787389 -0.406267)
			(stroke
				(width 0.1524)
				(type default)
			)
			(layer "F.SilkS")
		)
		(fp_line
			(start 0.787389 -0.406267)
			(end 0.787389 0.406267)
			(stroke
				(width 0.1524)
				(type default)
			)
			(layer "F.SilkS")
		)
		(fp_line
			(start 0.787389 0.406267)
			(end -0.787389 0.406267)
			(stroke
				(width 0.1524)
				(type default)
			)
			(layer "F.SilkS")
		)
		(fp_line
			(start -0.679446 -0.305149)
			(end -0.120695 -0.304969)
			(stroke
				(width 0.1)
				(type default)
			)
			(layer "F.Fab")
		)
		(fp_line
			(start -0.120695 -0.304969)
			(end -0.120695 -0.279466)
			(stroke
				(width 0.1)
				(type default)
			)
			(layer "F.Fab")
		)
		(fp_line
			(start -0.120695 -0.279466)
			(end 0.120695 -0.279466)
			(stroke
				(width 0.1)
				(type default)
			)
			(layer "F.Fab")
		)
		(fp_line
			(start -0.679446 0.30479)
			(end -0.679446 -0.305149)
			(stroke
				(width 0.1)
				(type default)
			)
			(layer "F.Fab")
		)
		(fp_line
			(start 0.120515 -0.30479)
			(end 0.679446 -0.30479)
			(stroke
				(width 0.1)
				(type default)
			)
			(layer "F.Fab")
		)
		(fp_line
			(start 0.120695 -0.279466)
			(end 0.120515 -0.30479)
			(stroke
				(width 0.1)
				(type default)
			)
			(layer "F.Fab")
		)
		(fp_line
			(start -0.120695 0.279466)
			(end -0.120515 0.30479)
			(stroke
				(width 0.1)
				(type default)
			)
			(layer "F.Fab")
		)
		(fp_line
			(start -0.120515 0.30479)
			(end -0.679446 0.30479)
			(stroke
				(width 0.1)
				(type default)
			)
			(layer "F.Fab")
		)
		(fp_line
			(start 0.679446 -0.30479)
			(end 0.679446 0.30479)
			(stroke
				(width 0.1)
				(type default)
			)
			(layer "F.Fab")
		)
		(fp_line
			(start 0.120335 0.279466)
			(end -0.120695 0.279466)
			(stroke
				(width 0.1)
				(type default)
			)
			(layer "F.Fab")
		)
		(fp_line
			(start 0.120515 0.30479)
			(end 0.120335 0.279466)
			(stroke
				(width 0.1)
				(type default)
			)
			(layer "F.Fab")
		)
		(fp_line
			(start 0.679446 0.30479)
			(end 0.120515 0.30479)
			(stroke
				(width 0.1)
				(type default)
			)
			(layer "F.Fab")
		)
		(pad "1" smd circle
			(at -0.40005 0 45)
			(size 0 0)
			(layers "F.Cu" "F.Mask" "F.Paste")
			(net "P12V_NIC7_VIN_P")
		)
		(pad "2" smd circle
			(at 0.40005 0 45)
			(size 0 0)
			(layers "F.Cu" "F.Mask" "F.Paste")
			(net "P12V_NIC7_VIN_N")
		)
	)
	(footprint ""
		(layer "F.Cu")
		(at 89.12225 -102.319328 45)
		(property "Reference" "C414"
			(at 0 0 45)
			(layer "F.SilkS")
			(hide yes)
			(effects
				(font
					(size 1.27 1.27)
				)
			)
		)
		(property "Value" ""
			(at 0 0 45)
			(layer "F.Fab")
			(effects
				(font
					(size 1.27 1.27)
				)
			)
		)
		(duplicate_pad_numbers_are_jumpers no)
		(fp_line
			(start -0.787389 -0.406267)
			(end 0.787389 -0.406267)
			(stroke
				(width 0.1524)
				(type default)
			)
			(layer "F.SilkS")
		)
		(fp_line
			(start -0.787389 0.406267)
			(end -0.787389 -0.406267)
			(stroke
				(width 0.1524)
				(type default)
			)
			(layer "F.SilkS")
		)
		(fp_line
			(start 0.787389 -0.406267)
			(end 0.787389 0.406267)
			(stroke
				(width 0.1524)
				(type default)
			)
			(layer "F.SilkS")
		)
		(fp_line
			(start 0.787389 0.406267)
			(end -0.787389 0.406267)
			(stroke
				(width 0.1524)
				(type default)
			)
			(layer "F.SilkS")
		)
		(fp_line
			(start -0.679446 -0.305149)
			(end -0.120695 -0.304969)
			(stroke
				(width 0.1)
				(type default)
			)
			(layer "F.Fab")
		)
		(fp_line
			(start -0.120695 -0.304969)
			(end -0.120695 -0.279466)
			(stroke
				(width 0.1)
				(type default)
			)
			(layer "F.Fab")
		)
		(fp_line
			(start -0.120695 -0.279466)
			(end 0.120695 -0.279466)
			(stroke
				(width 0.1)
				(type default)
			)
			(layer "F.Fab")
		)
		(fp_line
			(start -0.679446 0.30479)
			(end -0.679446 -0.305149)
			(stroke
				(width 0.1)
				(type default)
			)
			(layer "F.Fab")
		)
		(fp_line
			(start 0.120515 -0.30479)
			(end 0.679446 -0.30479)
			(stroke
				(width 0.1)
				(type default)
			)
			(layer "F.Fab")
		)
		(fp_line
			(start 0.120695 -0.279466)
			(end 0.120515 -0.30479)
			(stroke
				(width 0.1)
				(type default)
			)
			(layer "F.Fab")
		)
		(fp_line
			(start -0.120695 0.279466)
			(end -0.120515 0.30479)
			(stroke
				(width 0.1)
				(type default)
			)
			(layer "F.Fab")
		)
		(fp_line
			(start -0.120515 0.30479)
			(end -0.679446 0.30479)
			(stroke
				(width 0.1)
				(type default)
			)
			(layer "F.Fab")
		)
		(fp_line
			(start 0.679446 -0.30479)
			(end 0.679446 0.30479)
			(stroke
				(width 0.1)
				(type default)
			)
			(layer "F.Fab")
		)
		(fp_line
			(start 0.120335 0.279466)
			(end -0.120695 0.279466)
			(stroke
				(width 0.1)
				(type default)
			)
			(layer "F.Fab")
		)
		(fp_line
			(start 0.120515 0.30479)
			(end 0.120335 0.279466)
			(stroke
				(width 0.1)
				(type default)
			)
			(layer "F.Fab")
		)
		(fp_line
			(start 0.679446 0.30479)
			(end 0.120515 0.30479)
			(stroke
				(width 0.1)
				(type default)
			)
			(layer "F.Fab")
		)
		(pad "1" smd circle
			(at -0.40005 0 45)
			(size 0 0)
			(layers "F.Cu" "F.Mask" "F.Paste")
			(net "P12V_NIC1_VIN_P")
		)
		(pad "2" smd circle
			(at 0.40005 0 45)
			(size 0 0)
			(layers "F.Cu" "F.Mask" "F.Paste")
			(net "P12V_NIC1_VIN_N")
		)
	)
	(footprint ""
		(layer "F.Cu")
		(at 200.691496 -113.41354)
		(property "Reference" "R184"
			(at 0 0 0)
			(layer "F.SilkS")
			(hide yes)
			(effects
				(font
					(size 1.27 1.27)
				)
			)
		)
		(property "Value" ""
			(at 0 0 0)
			(layer "F.Fab")
			(effects
				(font
					(size 1.27 1.27)
				)
			)
		)
		(duplicate_pad_numbers_are_jumpers no)
		(fp_line
			(start -0.7874 -0.4064)
			(end 0.7874 -0.4064)
			(stroke
				(width 0.1524)
				(type default)
			)
			(layer "F.SilkS")
		)
		(fp_line
			(start -0.7874 0.4064)
			(end -0.7874 -0.4064)
			(stroke
				(width 0.1524)
				(type default)
			)
			(layer "F.SilkS")
		)
		(fp_line
			(start 0.7874 -0.4064)
			(end 0.7874 0.4064)
			(stroke
				(width 0.1524)
				(type default)
			)
			(layer "F.SilkS")
		)
		(fp_line
			(start 0.7874 0.4064)
			(end -0.7874 0.4064)
			(stroke
				(width 0.1524)
				(type default)
			)
			(layer "F.SilkS")
		)
		(fp_line
			(start -0.67945 -0.305054)
			(end -0.12065 -0.305054)
			(stroke
				(width 0.1)
				(type default)
			)
			(layer "F.Fab")
		)
		(fp_line
			(start -0.67945 0.3048)
			(end -0.67945 -0.305054)
			(stroke
				(width 0.1)
				(type default)
			)
			(layer "F.Fab")
		)
		(fp_line
			(start -0.12065 -0.305054)
			(end -0.12065 -0.2794)
			(stroke
				(width 0.1)
				(type default)
			)
			(layer "F.Fab")
		)
		(fp_line
			(start -0.12065 -0.2794)
			(end 0.12065 -0.2794)
			(stroke
				(width 0.1)
				(type default)
			)
			(layer "F.Fab")
		)
		(fp_line
			(start -0.12065 0.2794)
			(end -0.12065 0.3048)
			(stroke
				(width 0.1)
				(type default)
			)
			(layer "F.Fab")
		)
		(fp_line
			(start -0.12065 0.3048)
			(end -0.67945 0.3048)
			(stroke
				(width 0.1)
				(type default)
			)
			(layer "F.Fab")
		)
		(fp_line
			(start 0.120396 0.2794)
			(end -0.12065 0.2794)
			(stroke
				(width 0.1)
				(type default)
			)
			(layer "F.Fab")
		)
		(fp_line
			(start 0.120396 0.3048)
			(end 0.120396 0.2794)
			(stroke
				(width 0.1)
				(type default)
			)
			(layer "F.Fab")
		)
		(fp_line
			(start 0.12065 -0.3048)
			(end 0.67945 -0.3048)
			(stroke
				(width 0.1)
				(type default)
			)
			(layer "F.Fab")
		)
		(fp_line
			(start 0.12065 -0.2794)
			(end 0.12065 -0.3048)
			(stroke
				(width 0.1)
				(type default)
			)
			(layer "F.Fab")
		)
		(fp_line
			(start 0.67945 -0.3048)
			(end 0.67945 0.3048)
			(stroke
				(width 0.1)
				(type default)
			)
			(layer "F.Fab")
		)
		(fp_line
			(start 0.67945 0.3048)
			(end 0.120396 0.3048)
			(stroke
				(width 0.1)
				(type default)
			)
			(layer "F.Fab")
		)
		(pad "1" smd circle
			(at -0.40005 0)
			(size 0 0)
			(layers "F.Cu" "F.Mask" "F.Paste")
			(net "NIC3_BIF1_N")
		)
		(pad "2" smd circle
			(at 0.40005 0)
			(size 0 0)
			(layers "F.Cu" "F.Mask" "F.Paste")
			(net "P3V3_AUX")
		)
	)
	(footprint ""
		(layer "F.Cu")
		(at 447.50609 -113.114582 -90)
		(property "Reference" "PD99"
			(at 3.945382 -2.22758 90)
			(unlocked yes)
			(layer "F.SilkS")
			(effects
				(font
					(size 0.7874 0.5842)
					(thickness 0.1524)
				)
				(justify left)
			)
		)
		(property "Value" ""
			(at 0 0 270)
			(layer "F.Fab")
			(effects
				(font
					(size 1.27 1.27)
				)
			)
		)
		(duplicate_pad_numbers_are_jumpers no)
		(fp_line
			(start -3.400044 1.459992)
			(end -3.400044 -1.459992)
			(stroke
				(width 0.1524)
				(type default)
			)
			(layer "F.SilkS")
		)
		(fp_line
			(start 4.107942 1.459992)
			(end -3.400044 1.459992)
			(stroke
				(width 0.1524)
				(type default)
			)
			(layer "F.SilkS")
		)
		(fp_line
			(start -3.400044 -1.459992)
			(end 4.107942 -1.459992)
			(stroke
				(width 0.1524)
				(type default)
			)
			(layer "F.SilkS")
		)
		(fp_line
			(start 4.107942 -1.459992)
			(end 4.107942 1.459992)
			(stroke
				(width 0.1524)
				(type default)
			)
			(layer "F.SilkS")
		)
		(fp_rect
			(start 4.107942 1.459992)
			(end 3.308096 -1.459992)
			(stroke
				(width 0)
				(type default)
			)
			(fill yes)
			(layer "F.SilkS")
		)
		(fp_line
			(start -2.29997 1.459992)
			(end -2.29997 -1.459992)
			(stroke
				(width 0.1)
				(type default)
			)
			(layer "F.Fab")
		)
		(fp_line
			(start 2.29997 1.459992)
			(end -2.29997 1.459992)
			(stroke
				(width 0.1)
				(type default)
			)
			(layer "F.Fab")
		)
		(fp_line
			(start -2.29997 -1.459992)
			(end 2.29997 -1.459992)
			(stroke
				(width 0.1)
				(type default)
			)
			(layer "F.Fab")
		)
		(fp_line
			(start 2.29997 -1.459992)
			(end 2.29997 1.459992)
			(stroke
				(width 0.1)
				(type default)
			)
			(layer "F.Fab")
		)
		(fp_text user "-"
			(at 3.36169 2.127504 90)
			(unlocked yes)
			(layer "F.SilkS")
			(effects
				(font
					(size 1.905 1.4224)
					(thickness 0.1524)
				)
				(justify left)
			)
		)
		(fp_text user "+"
			(at -4.7752 -0.12065 270)
			(unlocked yes)
			(layer "F.SilkS")
			(effects
				(font
					(size 1.905 1.4224)
					(thickness 0.1524)
				)
				(justify left)
			)
		)
		(fp_text user "-"
			(at 5.4102 0.29845 90)
			(unlocked yes)
			(layer "F.Fab")
			(effects
				(font
					(size 1.905 1.4224)
					(thickness 0.1524)
				)
				(justify left)
			)
		)
		(fp_text user "+"
			(at -4.7752 -0.12065 270)
			(unlocked yes)
			(layer "F.Fab")
			(effects
				(font
					(size 1.905 1.4224)
					(thickness 0.1524)
				)
				(justify left)
			)
		)
		(pad "A" smd rect
			(at -1.999996 0)
			(size 1.7018 2.5146)
			(layers "F.Cu" "F.Mask" "F.Paste")
			(net "GND")
		)
		(pad "C" smd rect
			(at 1.999996 0)
			(size 1.7018 2.5146)
			(layers "F.Cu" "F.Mask" "F.Paste")
			(net "P12V_NIC7_R")
		)
	)
	(footprint ""
		(layer "F.Cu")
		(at 126.210314 -122.931428 180)
		(property "Reference" "PC457"
			(at 0 0 180)
			(layer "F.SilkS")
			(hide yes)
			(effects
				(font
					(size 1.27 1.27)
				)
			)
		)
		(property "Value" ""
			(at 0 0 180)
			(layer "F.Fab")
			(effects
				(font
					(size 1.27 1.27)
				)
			)
		)
		(duplicate_pad_numbers_are_jumpers no)
		(fp_line
			(start 0.7874 0.4064)
			(end -0.7874 0.4064)
			(stroke
				(width 0.1524)
				(type default)
			)
			(layer "F.SilkS")
		)
		(fp_line
			(start 0.7874 -0.4064)
			(end 0.7874 0.4064)
			(stroke
				(width 0.1524)
				(type default)
			)
			(layer "F.SilkS")
		)
		(fp_line
			(start -0.7874 0.4064)
			(end -0.7874 -0.4064)
			(stroke
				(width 0.1524)
				(type default)
			)
			(layer "F.SilkS")
		)
		(fp_line
			(start -0.7874 -0.4064)
			(end 0.7874 -0.4064)
			(stroke
				(width 0.1524)
				(type default)
			)
			(layer "F.SilkS")
		)
		(fp_line
			(start 0.67945 0.3048)
			(end 0.120396 0.3048)
			(stroke
				(width 0.1)
				(type default)
			)
			(layer "F.Fab")
		)
		(fp_line
			(start 0.67945 -0.3048)
			(end 0.67945 0.3048)
			(stroke
				(width 0.1)
				(type default)
			)
			(layer "F.Fab")
		)
		(fp_line
			(start 0.12065 -0.2794)
			(end 0.12065 -0.3048)
			(stroke
				(width 0.1)
				(type default)
			)
			(layer "F.Fab")
		)
		(fp_line
			(start 0.12065 -0.3048)
			(end 0.67945 -0.3048)
			(stroke
				(width 0.1)
				(type default)
			)
			(layer "F.Fab")
		)
		(fp_line
			(start 0.120396 0.3048)
			(end 0.120396 0.2794)
			(stroke
				(width 0.1)
				(type default)
			)
			(layer "F.Fab")
		)
		(fp_line
			(start 0.120396 0.2794)
			(end -0.12065 0.2794)
			(stroke
				(width 0.1)
				(type default)
			)
			(layer "F.Fab")
		)
		(fp_line
			(start -0.12065 0.3048)
			(end -0.67945 0.3048)
			(stroke
				(width 0.1)
				(type default)
			)
			(layer "F.Fab")
		)
		(fp_line
			(start -0.12065 0.2794)
			(end -0.12065 0.3048)
			(stroke
				(width 0.1)
				(type default)
			)
			(layer "F.Fab")
		)
		(fp_line
			(start -0.12065 -0.2794)
			(end 0.12065 -0.2794)
			(stroke
				(width 0.1)
				(type default)
			)
			(layer "F.Fab")
		)
		(fp_line
			(start -0.12065 -0.305054)
			(end -0.12065 -0.2794)
			(stroke
				(width 0.1)
				(type default)
			)
			(layer "F.Fab")
		)
		(fp_line
			(start -0.67945 0.3048)
			(end -0.67945 -0.305054)
			(stroke
				(width 0.1)
				(type default)
			)
			(layer "F.Fab")
		)
		(fp_line
			(start -0.67945 -0.305054)
			(end -0.12065 -0.305054)
			(stroke
				(width 0.1)
				(type default)
			)
			(layer "F.Fab")
		)
		(pad "1" smd circle
			(at -0.40005 0 180)
			(size 0 0)
			(layers "F.Cu" "F.Mask" "F.Paste")
			(net "P5V_AUX")
		)
		(pad "2" smd circle
			(at 0.40005 0 180)
			(size 0 0)
			(layers "F.Cu" "F.Mask" "F.Paste")
			(net "GND")
		)
	)
	(footprint ""
		(layer "F.Cu")
		(at 366.955578 -87.213694 180)
		(property "Reference" "R1626"
			(at 0 0 180)
			(layer "F.SilkS")
			(hide yes)
			(effects
				(font
					(size 1.27 1.27)
				)
			)
		)
		(property "Value" ""
			(at 0 0 180)
			(layer "F.Fab")
			(effects
				(font
					(size 1.27 1.27)
				)
			)
		)
		(duplicate_pad_numbers_are_jumpers no)
		(fp_line
			(start 0.7874 0.4064)
			(end -0.7874 0.4064)
			(stroke
				(width 0.1524)
				(type default)
			)
			(layer "F.SilkS")
		)
		(fp_line
			(start 0.7874 -0.4064)
			(end 0.7874 0.4064)
			(stroke
				(width 0.1524)
				(type default)
			)
			(layer "F.SilkS")
		)
		(fp_line
			(start -0.7874 0.4064)
			(end -0.7874 -0.4064)
			(stroke
				(width 0.1524)
				(type default)
			)
			(layer "F.SilkS")
		)
		(fp_line
			(start -0.7874 -0.4064)
			(end 0.7874 -0.4064)
			(stroke
				(width 0.1524)
				(type default)
			)
			(layer "F.SilkS")
		)
		(fp_line
			(start 0.67945 0.3048)
			(end 0.120396 0.3048)
			(stroke
				(width 0.1)
				(type default)
			)
			(layer "F.Fab")
		)
		(fp_line
			(start 0.67945 -0.3048)
			(end 0.67945 0.3048)
			(stroke
				(width 0.1)
				(type default)
			)
			(layer "F.Fab")
		)
		(fp_line
			(start 0.12065 -0.2794)
			(end 0.12065 -0.3048)
			(stroke
				(width 0.1)
				(type default)
			)
			(layer "F.Fab")
		)
		(fp_line
			(start 0.12065 -0.3048)
			(end 0.67945 -0.3048)
			(stroke
				(width 0.1)
				(type default)
			)
			(layer "F.Fab")
		)
		(fp_line
			(start 0.120396 0.3048)
			(end 0.120396 0.2794)
			(stroke
				(width 0.1)
				(type default)
			)
			(layer "F.Fab")
		)
		(fp_line
			(start 0.120396 0.2794)
			(end -0.12065 0.2794)
			(stroke
				(width 0.1)
				(type default)
			)
			(layer "F.Fab")
		)
		(fp_line
			(start -0.12065 0.3048)
			(end -0.67945 0.3048)
			(stroke
				(width 0.1)
				(type default)
			)
			(layer "F.Fab")
		)
		(fp_line
			(start -0.12065 0.2794)
			(end -0.12065 0.3048)
			(stroke
				(width 0.1)
				(type default)
			)
			(layer "F.Fab")
		)
		(fp_line
			(start -0.12065 -0.2794)
			(end 0.12065 -0.2794)
			(stroke
				(width 0.1)
				(type default)
			)
			(layer "F.Fab")
		)
		(fp_line
			(start -0.12065 -0.305054)
			(end -0.12065 -0.2794)
			(stroke
				(width 0.1)
				(type default)
			)
			(layer "F.Fab")
		)
		(fp_line
			(start -0.67945 0.3048)
			(end -0.67945 -0.305054)
			(stroke
				(width 0.1)
				(type default)
			)
			(layer "F.Fab")
		)
		(fp_line
			(start -0.67945 -0.305054)
			(end -0.12065 -0.305054)
			(stroke
				(width 0.1)
				(type default)
			)
			(layer "F.Fab")
		)
		(pad "1" smd circle
			(at -0.40005 0 180)
			(size 0 0)
			(layers "F.Cu" "F.Mask" "F.Paste")
			(net "SMB_BIC_I2C9_MUX1_SSD14_R_SCL")
		)
		(pad "2" smd circle
			(at 0.40005 0 180)
			(size 0 0)
			(layers "F.Cu" "F.Mask" "F.Paste")
			(net "SMB_BIC_I2C9_MUX1_SSD14_SCL")
		)
	)
	(footprint ""
		(layer "F.Cu")
		(at 438.233058 -311.946544 135)
		(property "Reference" "R1438"
			(at 0 0 135)
			(layer "F.SilkS")
			(hide yes)
			(effects
				(font
					(size 1.27 1.27)
				)
			)
		)
		(property "Value" ""
			(at 0 0 135)
			(layer "F.Fab")
			(effects
				(font
					(size 1.27 1.27)
				)
			)
		)
		(duplicate_pad_numbers_are_jumpers no)
		(fp_line
			(start 0.787389 -0.406267)
			(end 0.787389 0.406267)
			(stroke
				(width 0.1524)
				(type default)
			)
			(layer "F.SilkS")
		)
		(fp_line
			(start 0.787389 0.406267)
			(end -0.787389 0.406267)
			(stroke
				(width 0.1524)
				(type default)
			)
			(layer "F.SilkS")
		)
		(fp_line
			(start -0.787389 -0.406267)
			(end 0.787389 -0.406267)
			(stroke
				(width 0.1524)
				(type default)
			)
			(layer "F.SilkS")
		)
		(fp_line
			(start -0.787389 0.406267)
			(end -0.787389 -0.406267)
			(stroke
				(width 0.1524)
				(type default)
			)
			(layer "F.SilkS")
		)
		(fp_line
			(start 0.679446 -0.30479)
			(end 0.679446 0.30479)
			(stroke
				(width 0.1)
				(type default)
			)
			(layer "F.Fab")
		)
		(fp_line
			(start 0.120515 -0.30479)
			(end 0.679446 -0.30479)
			(stroke
				(width 0.1)
				(type default)
			)
			(layer "F.Fab")
		)
		(fp_line
			(start 0.120695 -0.279466)
			(end 0.120515 -0.30479)
			(stroke
				(width 0.1)
				(type default)
			)
			(layer "F.Fab")
		)
		(fp_line
			(start 0.679446 0.30479)
			(end 0.120515 0.30479)
			(stroke
				(width 0.1)
				(type default)
			)
			(layer "F.Fab")
		)
		(fp_line
			(start -0.120695 -0.304969)
			(end -0.120695 -0.279466)
			(stroke
				(width 0.1)
				(type default)
			)
			(layer "F.Fab")
		)
		(fp_line
			(start -0.120695 -0.279466)
			(end 0.120695 -0.279466)
			(stroke
				(width 0.1)
				(type default)
			)
			(layer "F.Fab")
		)
		(fp_line
			(start 0.120335 0.279466)
			(end -0.120695 0.279466)
			(stroke
				(width 0.1)
				(type default)
			)
			(layer "F.Fab")
		)
		(fp_line
			(start 0.120515 0.30479)
			(end 0.120335 0.279466)
			(stroke
				(width 0.1)
				(type default)
			)
			(layer "F.Fab")
		)
		(fp_line
			(start -0.679446 -0.305149)
			(end -0.120695 -0.304969)
			(stroke
				(width 0.1)
				(type default)
			)
			(layer "F.Fab")
		)
		(fp_line
			(start -0.120695 0.279466)
			(end -0.120515 0.30479)
			(stroke
				(width 0.1)
				(type default)
			)
			(layer "F.Fab")
		)
		(fp_line
			(start -0.120515 0.30479)
			(end -0.679446 0.30479)
			(stroke
				(width 0.1)
				(type default)
			)
			(layer "F.Fab")
		)
		(fp_line
			(start -0.679446 0.30479)
			(end -0.679446 -0.305149)
			(stroke
				(width 0.1)
				(type default)
			)
			(layer "F.Fab")
		)
		(pad "1" smd circle
			(at -0.40005 0 135)
			(size 0 0)
			(layers "F.Cu" "F.Mask" "F.Paste")
			(net "PEX3_SPARE5")
		)
		(pad "2" smd circle
			(at 0.40005 0 135)
			(size 0 0)
			(layers "F.Cu" "F.Mask" "F.Paste")
			(net "P1V8_PEX")
		)
	)
	(footprint ""
		(layer "F.Cu")
		(at 233.933746 -120.381268 -90)
		(property "Reference" "R947"
			(at 0 0 270)
			(layer "F.SilkS")
			(hide yes)
			(effects
				(font
					(size 1.27 1.27)
				)
			)
		)
		(property "Value" ""
			(at 0 0 270)
			(layer "F.Fab")
			(effects
				(font
					(size 1.27 1.27)
				)
			)
		)
		(duplicate_pad_numbers_are_jumpers no)
		(fp_line
			(start -0.7874 0.4064)
			(end -0.7874 -0.4064)
			(stroke
				(width 0.1524)
				(type default)
			)
			(layer "F.SilkS")
		)
		(fp_line
			(start 0.7874 0.4064)
			(end -0.7874 0.4064)
			(stroke
				(width 0.1524)
				(type default)
			)
			(layer "F.SilkS")
		)
		(fp_line
			(start -0.7874 -0.4064)
			(end 0.7874 -0.4064)
			(stroke
				(width 0.1524)
				(type default)
			)
			(layer "F.SilkS")
		)
		(fp_line
			(start 0.7874 -0.4064)
			(end 0.7874 0.4064)
			(stroke
				(width 0.1524)
				(type default)
			)
			(layer "F.SilkS")
		)
		(fp_line
			(start -0.67945 0.3048)
			(end -0.67945 -0.305054)
			(stroke
				(width 0.1)
				(type default)
			)
			(layer "F.Fab")
		)
		(fp_line
			(start -0.12065 0.3048)
			(end -0.67945 0.3048)
			(stroke
				(width 0.1)
				(type default)
			)
			(layer "F.Fab")
		)
		(fp_line
			(start 0.120396 0.3048)
			(end 0.120396 0.2794)
			(stroke
				(width 0.1)
				(type default)
			)
			(layer "F.Fab")
		)
		(fp_line
			(start 0.67945 0.3048)
			(end 0.120396 0.3048)
			(stroke
				(width 0.1)
				(type default)
			)
			(layer "F.Fab")
		)
		(fp_line
			(start -0.12065 0.2794)
			(end -0.12065 0.3048)
			(stroke
				(width 0.1)
				(type default)
			)
			(layer "F.Fab")
		)
		(fp_line
			(start 0.120396 0.2794)
			(end -0.12065 0.2794)
			(stroke
				(width 0.1)
				(type default)
			)
			(layer "F.Fab")
		)
		(fp_line
			(start -0.12065 -0.2794)
			(end 0.12065 -0.2794)
			(stroke
				(width 0.1)
				(type default)
			)
			(layer "F.Fab")
		)
		(fp_line
			(start 0.12065 -0.2794)
			(end 0.12065 -0.3048)
			(stroke
				(width 0.1)
				(type default)
			)
			(layer "F.Fab")
		)
		(fp_line
			(start 0.12065 -0.3048)
			(end 0.67945 -0.3048)
			(stroke
				(width 0.1)
				(type default)
			)
			(layer "F.Fab")
		)
		(fp_line
			(start 0.67945 -0.3048)
			(end 0.67945 0.3048)
			(stroke
				(width 0.1)
				(type default)
			)
			(layer "F.Fab")
		)
		(fp_line
			(start -0.67945 -0.305054)
			(end -0.12065 -0.305054)
			(stroke
				(width 0.1)
				(type default)
			)
			(layer "F.Fab")
		)
		(fp_line
			(start -0.12065 -0.305054)
			(end -0.12065 -0.2794)
			(stroke
				(width 0.1)
				(type default)
			)
			(layer "F.Fab")
		)
		(pad "1" smd circle
			(at -0.40005 0 270)
			(size 0 0)
			(layers "F.Cu" "F.Mask" "F.Paste")
			(net "P3V3_AUX")
		)
		(pad "2" smd circle
			(at 0.40005 0 270)
			(size 0 0)
			(layers "F.Cu" "F.Mask" "F.Paste")
			(net "PWRGD_P12V_NIC3_CO")
		)
	)
	(footprint ""
		(layer "F.Cu")
		(at 469.310212 -555.019972 180)
		(property "Reference" "SCREW_SSD11_2"
			(at -5.6007 -1.402334 0)
			(unlocked yes)
			(layer "B.SilkS")
			(effects
				(font
					(size 0.7874 0.5842)
					(thickness 0.1524)
				)
				(justify mirror)
			)
		)
		(property "Value" ""
			(at 0 0 180)
			(layer "F.Fab")
			(effects
				(font
					(size 1.27 1.27)
				)
			)
		)
		(duplicate_pad_numbers_are_jumpers no)
		(pad "1" thru_hole circle
			(at 0 0 180)
			(size 0.4572 0.4572)
			(drill 0.2032)
			(layers "*.Cu" "*.Mask")
			(remove_unused_layers no)
			(net "Net_9151")
			(clearance 0.127)
			(thermal_gap 0.127)
			(padstack
				(mode front_inner_back)
				(layer "Inner"
					(shape circle)
					(size 0.4572 0.4572)
					(clearance 0.127)
				)
				(layer "B.Cu"
					(shape circle)
					(size 0.508 0.508)
					(clearance 0.1016)
				)
			)
		)
	)
	(footprint ""
		(layer "F.Cu")
		(at 2.87528 -63.086234 180)
		(property "Reference" "PR6907"
			(at 0 0 180)
			(layer "F.SilkS")
			(hide yes)
			(effects
				(font
					(size 1.27 1.27)
				)
			)
		)
		(property "Value" ""
			(at 0 0 180)
			(layer "F.Fab")
			(effects
				(font
					(size 1.27 1.27)
				)
			)
		)
		(duplicate_pad_numbers_are_jumpers no)
		(fp_line
			(start 0.7874 0.4064)
			(end -0.7874 0.4064)
			(stroke
				(width 0.1524)
				(type default)
			)
			(layer "F.SilkS")
		)
		(fp_line
			(start 0.7874 -0.4064)
			(end 0.7874 0.4064)
			(stroke
				(width 0.1524)
				(type default)
			)
			(layer "F.SilkS")
		)
		(fp_line
			(start -0.7874 0.4064)
			(end -0.7874 -0.4064)
			(stroke
				(width 0.1524)
				(type default)
			)
			(layer "F.SilkS")
		)
		(fp_line
			(start -0.7874 -0.4064)
			(end 0.7874 -0.4064)
			(stroke
				(width 0.1524)
				(type default)
			)
			(layer "F.SilkS")
		)
		(fp_line
			(start 0.67945 0.3048)
			(end 0.120396 0.3048)
			(stroke
				(width 0.1)
				(type default)
			)
			(layer "F.Fab")
		)
		(fp_line
			(start 0.67945 -0.3048)
			(end 0.67945 0.3048)
			(stroke
				(width 0.1)
				(type default)
			)
			(layer "F.Fab")
		)
		(fp_line
			(start 0.12065 -0.2794)
			(end 0.12065 -0.3048)
			(stroke
				(width 0.1)
				(type default)
			)
			(layer "F.Fab")
		)
		(fp_line
			(start 0.12065 -0.3048)
			(end 0.67945 -0.3048)
			(stroke
				(width 0.1)
				(type default)
			)
			(layer "F.Fab")
		)
		(fp_line
			(start 0.120396 0.3048)
			(end 0.120396 0.2794)
			(stroke
				(width 0.1)
				(type default)
			)
			(layer "F.Fab")
		)
		(fp_line
			(start 0.120396 0.2794)
			(end -0.12065 0.2794)
			(stroke
				(width 0.1)
				(type default)
			)
			(layer "F.Fab")
		)
		(fp_line
			(start -0.12065 0.3048)
			(end -0.67945 0.3048)
			(stroke
				(width 0.1)
				(type default)
			)
			(layer "F.Fab")
		)
		(fp_line
			(start -0.12065 0.2794)
			(end -0.12065 0.3048)
			(stroke
				(width 0.1)
				(type default)
			)
			(layer "F.Fab")
		)
		(fp_line
			(start -0.12065 -0.2794)
			(end 0.12065 -0.2794)
			(stroke
				(width 0.1)
				(type default)
			)
			(layer "F.Fab")
		)
		(fp_line
			(start -0.12065 -0.305054)
			(end -0.12065 -0.2794)
			(stroke
				(width 0.1)
				(type default)
			)
			(layer "F.Fab")
		)
		(fp_line
			(start -0.67945 0.3048)
			(end -0.67945 -0.305054)
			(stroke
				(width 0.1)
				(type default)
			)
			(layer "F.Fab")
		)
		(fp_line
			(start -0.67945 -0.305054)
			(end -0.12065 -0.305054)
			(stroke
				(width 0.1)
				(type default)
			)
			(layer "F.Fab")
		)
		(pad "1" smd circle
			(at -0.40005 0 180)
			(size 0 0)
			(layers "F.Cu" "F.Mask" "F.Paste")
			(net "P12V_SSD0_PG_G1")
		)
		(pad "2" smd circle
			(at 0.40005 0 180)
			(size 0 0)
			(layers "F.Cu" "F.Mask" "F.Paste")
			(net "GND")
		)
	)
	(footprint ""
		(layer "F.Cu")
		(at 206.623158 -80.611472)
		(property "Reference" "R4306"
			(at 0 0 0)
			(layer "F.SilkS")
			(hide yes)
			(effects
				(font
					(size 1.27 1.27)
				)
			)
		)
		(property "Value" ""
			(at 0 0 0)
			(layer "F.Fab")
			(effects
				(font
					(size 1.27 1.27)
				)
			)
		)
		(duplicate_pad_numbers_are_jumpers no)
		(fp_line
			(start -0.7874 -0.4064)
			(end 0.7874 -0.4064)
			(stroke
				(width 0.1524)
				(type default)
			)
			(layer "F.SilkS")
		)
		(fp_line
			(start -0.7874 0.4064)
			(end -0.7874 -0.4064)
			(stroke
				(width 0.1524)
				(type default)
			)
			(layer "F.SilkS")
		)
		(fp_line
			(start 0.7874 -0.4064)
			(end 0.7874 0.4064)
			(stroke
				(width 0.1524)
				(type default)
			)
			(layer "F.SilkS")
		)
		(fp_line
			(start 0.7874 0.4064)
			(end -0.7874 0.4064)
			(stroke
				(width 0.1524)
				(type default)
			)
			(layer "F.SilkS")
		)
		(fp_line
			(start -0.67945 -0.305054)
			(end -0.12065 -0.305054)
			(stroke
				(width 0.1)
				(type default)
			)
			(layer "F.Fab")
		)
		(fp_line
			(start -0.67945 0.3048)
			(end -0.67945 -0.305054)
			(stroke
				(width 0.1)
				(type default)
			)
			(layer "F.Fab")
		)
		(fp_line
			(start -0.12065 -0.305054)
			(end -0.12065 -0.2794)
			(stroke
				(width 0.1)
				(type default)
			)
			(layer "F.Fab")
		)
		(fp_line
			(start -0.12065 -0.2794)
			(end 0.12065 -0.2794)
			(stroke
				(width 0.1)
				(type default)
			)
			(layer "F.Fab")
		)
		(fp_line
			(start -0.12065 0.2794)
			(end -0.12065 0.3048)
			(stroke
				(width 0.1)
				(type default)
			)
			(layer "F.Fab")
		)
		(fp_line
			(start -0.12065 0.3048)
			(end -0.67945 0.3048)
			(stroke
				(width 0.1)
				(type default)
			)
			(layer "F.Fab")
		)
		(fp_line
			(start 0.120396 0.2794)
			(end -0.12065 0.2794)
			(stroke
				(width 0.1)
				(type default)
			)
			(layer "F.Fab")
		)
		(fp_line
			(start 0.120396 0.3048)
			(end 0.120396 0.2794)
			(stroke
				(width 0.1)
				(type default)
			)
			(layer "F.Fab")
		)
		(fp_line
			(start 0.12065 -0.3048)
			(end 0.67945 -0.3048)
			(stroke
				(width 0.1)
				(type default)
			)
			(layer "F.Fab")
		)
		(fp_line
			(start 0.12065 -0.2794)
			(end 0.12065 -0.3048)
			(stroke
				(width 0.1)
				(type default)
			)
			(layer "F.Fab")
		)
		(fp_line
			(start 0.67945 -0.3048)
			(end 0.67945 0.3048)
			(stroke
				(width 0.1)
				(type default)
			)
			(layer "F.Fab")
		)
		(fp_line
			(start 0.67945 0.3048)
			(end 0.120396 0.3048)
			(stroke
				(width 0.1)
				(type default)
			)
			(layer "F.Fab")
		)
		(pad "1" smd circle
			(at -0.40005 0)
			(size 0 0)
			(layers "F.Cu" "F.Mask" "F.Paste")
			(net "SSD4_LED_R")
		)
		(pad "2" smd circle
			(at 0.40005 0)
			(size 0 0)
			(layers "F.Cu" "F.Mask" "F.Paste")
			(net "SSD4_LED")
		)
	)
	(footprint ""
		(layer "F.Cu")
		(at 115.356386 -86.469982 180)
		(property "Reference" "R1146"
			(at 0 0 180)
			(layer "F.SilkS")
			(hide yes)
			(effects
				(font
					(size 1.27 1.27)
				)
			)
		)
		(property "Value" ""
			(at 0 0 180)
			(layer "F.Fab")
			(effects
				(font
					(size 1.27 1.27)
				)
			)
		)
		(duplicate_pad_numbers_are_jumpers no)
		(fp_line
			(start -0.7874 -0.4064)
			(end 0.7874 -0.4064)
			(stroke
				(width 0.1524)
				(type default)
			)
			(layer "F.SilkS")
		)
		(fp_line
			(start 0.67945 0.3048)
			(end 0.120396 0.3048)
			(stroke
				(width 0.1)
				(type default)
			)
			(layer "F.Fab")
		)
		(fp_line
			(start 0.67945 -0.3048)
			(end 0.67945 0.3048)
			(stroke
				(width 0.1)
				(type default)
			)
			(layer "F.Fab")
		)
		(fp_line
			(start 0.12065 -0.2794)
			(end 0.12065 -0.3048)
			(stroke
				(width 0.1)
				(type default)
			)
			(layer "F.Fab")
		)
		(fp_line
			(start 0.12065 -0.3048)
			(end 0.67945 -0.3048)
			(stroke
				(width 0.1)
				(type default)
			)
			(layer "F.Fab")
		)
		(fp_line
			(start 0.120396 0.3048)
			(end 0.120396 0.2794)
			(stroke
				(width 0.1)
				(type default)
			)
			(layer "F.Fab")
		)
		(fp_line
			(start 0.120396 0.2794)
			(end -0.12065 0.2794)
			(stroke
				(width 0.1)
				(type default)
			)
			(layer "F.Fab")
		)
		(fp_line
			(start -0.12065 0.3048)
			(end -0.67945 0.3048)
			(stroke
				(width 0.1)
				(type default)
			)
			(layer "F.Fab")
		)
		(fp_line
			(start -0.12065 0.2794)
			(end -0.12065 0.3048)
			(stroke
				(width 0.1)
				(type default)
			)
			(layer "F.Fab")
		)
		(fp_line
			(start -0.12065 -0.2794)
			(end 0.12065 -0.2794)
			(stroke
				(width 0.1)
				(type default)
			)
			(layer "F.Fab")
		)
		(fp_line
			(start -0.12065 -0.305054)
			(end -0.12065 -0.2794)
			(stroke
				(width 0.1)
				(type default)
			)
			(layer "F.Fab")
		)
		(fp_line
			(start -0.67945 0.3048)
			(end -0.67945 -0.305054)
			(stroke
				(width 0.1)
				(type default)
			)
			(layer "F.Fab")
		)
		(fp_line
			(start -0.67945 -0.305054)
			(end -0.12065 -0.305054)
			(stroke
				(width 0.1)
				(type default)
			)
			(layer "F.Fab")
		)
		(pad "1" smd circle
			(at -0.40005 0 180)
			(size 0 0)
			(layers "F.Cu" "F.Mask" "F.Paste")
			(net "CLK_100M_DB800ZL_SSD5_R_DP")
		)
		(pad "2" smd circle
			(at 0.40005 0 180)
			(size 0 0)
			(layers "F.Cu" "F.Mask" "F.Paste")
			(net "CLK_100M_DB800ZL_SSD5_DP")
		)
	)
	(footprint ""
		(layer "F.Cu")
		(at 320.354452 -223.389698 180)
		(property "Reference" "D15"
			(at 3.743452 0.103632 0)
			(unlocked yes)
			(layer "F.SilkS")
			(effects
				(font
					(size 0.7874 0.5842)
					(thickness 0.1524)
				)
				(justify left)
			)
		)
		(property "Value" ""
			(at 0 0 180)
			(layer "F.Fab")
			(effects
				(font
					(size 1.27 1.27)
				)
			)
		)
		(duplicate_pad_numbers_are_jumpers no)
		(fp_line
			(start 1.16078 0.4826)
			(end -0.64008 0.4826)
			(stroke
				(width 0.1524)
				(type default)
			)
			(layer "F.SilkS")
		)
		(fp_line
			(start 1.16078 -0.4826)
			(end 1.16078 0.4826)
			(stroke
				(width 0.1524)
				(type default)
			)
			(layer "F.SilkS")
		)
		(fp_line
			(start 1.03378 0.4826)
			(end -0.79248 0.4826)
			(stroke
				(width 0.1524)
				(type default)
			)
			(layer "F.SilkS")
		)
		(fp_line
			(start 1.03378 -0.4826)
			(end 1.03378 0.4826)
			(stroke
				(width 0.1524)
				(type default)
			)
			(layer "F.SilkS")
		)
		(fp_line
			(start 0.90678 0.4826)
			(end -0.90678 0.4826)
			(stroke
				(width 0.1524)
				(type default)
			)
			(layer "F.SilkS")
		)
		(fp_line
			(start 0.90678 -0.4826)
			(end 0.90678 0.4826)
			(stroke
				(width 0.1524)
				(type default)
			)
			(layer "F.SilkS")
		)
		(fp_line
			(start -0.64008 -0.4826)
			(end 1.16078 -0.4826)
			(stroke
				(width 0.1524)
				(type default)
			)
			(layer "F.SilkS")
		)
		(fp_line
			(start -0.79248 -0.4826)
			(end 1.03378 -0.4826)
			(stroke
				(width 0.1524)
				(type default)
			)
			(layer "F.SilkS")
		)
		(fp_line
			(start -0.89408 -0.4826)
			(end 0.90678 -0.4826)
			(stroke
				(width 0.1524)
				(type default)
			)
			(layer "F.SilkS")
		)
		(fp_line
			(start -0.90678 0.4826)
			(end -0.90678 -0.4699)
			(stroke
				(width 0.1524)
				(type default)
			)
			(layer "F.SilkS")
		)
		(fp_line
			(start 0.499872 0.249936)
			(end -0.499872 0.249936)
			(stroke
				(width 0.1)
				(type default)
			)
			(layer "F.Fab")
		)
		(fp_line
			(start 0.499872 -0.249936)
			(end 0.499872 0.249936)
			(stroke
				(width 0.1)
				(type default)
			)
			(layer "F.Fab")
		)
		(fp_line
			(start -0.499872 0.249936)
			(end -0.499872 -0.249936)
			(stroke
				(width 0.1)
				(type default)
			)
			(layer "F.Fab")
		)
		(fp_line
			(start -0.499872 -0.249936)
			(end 0.499872 -0.249936)
			(stroke
				(width 0.1)
				(type default)
			)
			(layer "F.Fab")
		)
		(pad "A" smd rect
			(at -0.47498 0 180)
			(size 0.6096 0.7112)
			(layers "F.Cu" "F.Mask" "F.Paste")
			(net "LED_POSTCODE_R_2")
		)
		(pad "C" smd rect
			(at 0.47498 0 180)
			(size 0.6096 0.7112)
			(layers "F.Cu" "F.Mask" "F.Paste")
			(net "FPGA_DEBUG_LED_R_N")
		)
	)
	(footprint ""
		(layer "F.Cu")
		(at 210.439 -203.835)
		(property "Reference" "C2556"
			(at 0 0 0)
			(layer "F.SilkS")
			(hide yes)
			(effects
				(font
					(size 1.27 1.27)
				)
			)
		)
		(property "Value" ""
			(at 0 0 0)
			(layer "F.Fab")
			(effects
				(font
					(size 1.27 1.27)
				)
			)
		)
		(duplicate_pad_numbers_are_jumpers no)
		(fp_line
			(start -0.7874 -0.4064)
			(end 0.7874 -0.4064)
			(stroke
				(width 0.1524)
				(type default)
			)
			(layer "F.SilkS")
		)
		(fp_line
			(start -0.7874 0.4064)
			(end -0.7874 -0.4064)
			(stroke
				(width 0.1524)
				(type default)
			)
			(layer "F.SilkS")
		)
		(fp_line
			(start 0.7874 -0.4064)
			(end 0.7874 0.4064)
			(stroke
				(width 0.1524)
				(type default)
			)
			(layer "F.SilkS")
		)
		(fp_line
			(start 0.7874 0.4064)
			(end -0.7874 0.4064)
			(stroke
				(width 0.1524)
				(type default)
			)
			(layer "F.SilkS")
		)
		(fp_line
			(start -0.67945 -0.305054)
			(end -0.12065 -0.305054)
			(stroke
				(width 0.1)
				(type default)
			)
			(layer "F.Fab")
		)
		(fp_line
			(start -0.67945 0.3048)
			(end -0.67945 -0.305054)
			(stroke
				(width 0.1)
				(type default)
			)
			(layer "F.Fab")
		)
		(fp_line
			(start -0.12065 -0.305054)
			(end -0.12065 -0.2794)
			(stroke
				(width 0.1)
				(type default)
			)
			(layer "F.Fab")
		)
		(fp_line
			(start -0.12065 -0.2794)
			(end 0.12065 -0.2794)
			(stroke
				(width 0.1)
				(type default)
			)
			(layer "F.Fab")
		)
		(fp_line
			(start -0.12065 0.2794)
			(end -0.12065 0.3048)
			(stroke
				(width 0.1)
				(type default)
			)
			(layer "F.Fab")
		)
		(fp_line
			(start -0.12065 0.3048)
			(end -0.67945 0.3048)
			(stroke
				(width 0.1)
				(type default)
			)
			(layer "F.Fab")
		)
		(fp_line
			(start 0.120396 0.2794)
			(end -0.12065 0.2794)
			(stroke
				(width 0.1)
				(type default)
			)
			(layer "F.Fab")
		)
		(fp_line
			(start 0.120396 0.3048)
			(end 0.120396 0.2794)
			(stroke
				(width 0.1)
				(type default)
			)
			(layer "F.Fab")
		)
		(fp_line
			(start 0.12065 -0.3048)
			(end 0.67945 -0.3048)
			(stroke
				(width 0.1)
				(type default)
			)
			(layer "F.Fab")
		)
		(fp_line
			(start 0.12065 -0.2794)
			(end 0.12065 -0.3048)
			(stroke
				(width 0.1)
				(type default)
			)
			(layer "F.Fab")
		)
		(fp_line
			(start 0.67945 -0.3048)
			(end 0.67945 0.3048)
			(stroke
				(width 0.1)
				(type default)
			)
			(layer "F.Fab")
		)
		(fp_line
			(start 0.67945 0.3048)
			(end 0.120396 0.3048)
			(stroke
				(width 0.1)
				(type default)
			)
			(layer "F.Fab")
		)
		(pad "1" smd circle
			(at -0.40005 0)
			(size 0 0)
			(layers "F.Cu" "F.Mask" "F.Paste")
			(net "GND")
		)
		(pad "2" smd circle
			(at 0.40005 0)
			(size 0 0)
			(layers "F.Cu" "F.Mask" "F.Paste")
			(net "P1V2_AUX")
		)
	)
	(footprint ""
		(layer "F.Cu")
		(at 310.467756 -56.353456)
		(property "Reference" "C2873"
			(at 0 0 0)
			(layer "F.SilkS")
			(hide yes)
			(effects
				(font
					(size 1.27 1.27)
				)
			)
		)
		(property "Value" ""
			(at 0 0 0)
			(layer "F.Fab")
			(effects
				(font
					(size 1.27 1.27)
				)
			)
		)
		(duplicate_pad_numbers_are_jumpers no)
		(fp_line
			(start -0.7874 -0.4064)
			(end 0.7874 -0.4064)
			(stroke
				(width 0.1524)
				(type default)
			)
			(layer "F.SilkS")
		)
		(fp_line
			(start -0.7874 0.4064)
			(end -0.7874 -0.4064)
			(stroke
				(width 0.1524)
				(type default)
			)
			(layer "F.SilkS")
		)
		(fp_line
			(start 0.7874 -0.4064)
			(end 0.7874 0.4064)
			(stroke
				(width 0.1524)
				(type default)
			)
			(layer "F.SilkS")
		)
		(fp_line
			(start 0.7874 0.4064)
			(end -0.7874 0.4064)
			(stroke
				(width 0.1524)
				(type default)
			)
			(layer "F.SilkS")
		)
		(fp_line
			(start -0.67945 -0.305054)
			(end -0.12065 -0.305054)
			(stroke
				(width 0.1)
				(type default)
			)
			(layer "F.Fab")
		)
		(fp_line
			(start -0.67945 0.3048)
			(end -0.67945 -0.305054)
			(stroke
				(width 0.1)
				(type default)
			)
			(layer "F.Fab")
		)
		(fp_line
			(start -0.12065 -0.305054)
			(end -0.12065 -0.2794)
			(stroke
				(width 0.1)
				(type default)
			)
			(layer "F.Fab")
		)
		(fp_line
			(start -0.12065 -0.2794)
			(end 0.12065 -0.2794)
			(stroke
				(width 0.1)
				(type default)
			)
			(layer "F.Fab")
		)
		(fp_line
			(start -0.12065 0.2794)
			(end -0.12065 0.3048)
			(stroke
				(width 0.1)
				(type default)
			)
			(layer "F.Fab")
		)
		(fp_line
			(start -0.12065 0.3048)
			(end -0.67945 0.3048)
			(stroke
				(width 0.1)
				(type default)
			)
			(layer "F.Fab")
		)
		(fp_line
			(start 0.120396 0.2794)
			(end -0.12065 0.2794)
			(stroke
				(width 0.1)
				(type default)
			)
			(layer "F.Fab")
		)
		(fp_line
			(start 0.120396 0.3048)
			(end 0.120396 0.2794)
			(stroke
				(width 0.1)
				(type default)
			)
			(layer "F.Fab")
		)
		(fp_line
			(start 0.12065 -0.3048)
			(end 0.67945 -0.3048)
			(stroke
				(width 0.1)
				(type default)
			)
			(layer "F.Fab")
		)
		(fp_line
			(start 0.12065 -0.2794)
			(end 0.12065 -0.3048)
			(stroke
				(width 0.1)
				(type default)
			)
			(layer "F.Fab")
		)
		(fp_line
			(start 0.67945 -0.3048)
			(end 0.67945 0.3048)
			(stroke
				(width 0.1)
				(type default)
			)
			(layer "F.Fab")
		)
		(fp_line
			(start 0.67945 0.3048)
			(end 0.120396 0.3048)
			(stroke
				(width 0.1)
				(type default)
			)
			(layer "F.Fab")
		)
		(pad "1" smd circle
			(at -0.40005 0)
			(size 0 0)
			(layers "F.Cu" "F.Mask" "F.Paste")
			(net "SSD10_PWR_EN_R")
		)
		(pad "2" smd circle
			(at 0.40005 0)
			(size 0 0)
			(layers "F.Cu" "F.Mask" "F.Paste")
			(net "GND")
		)
	)
	(footprint ""
		(layer "F.Cu")
		(at 58.0644 -141.6558 180)
		(property "Reference" "R35"
			(at 0 0 180)
			(layer "F.SilkS")
			(hide yes)
			(effects
				(font
					(size 1.27 1.27)
				)
			)
		)
		(property "Value" ""
			(at 0 0 180)
			(layer "F.Fab")
			(effects
				(font
					(size 1.27 1.27)
				)
			)
		)
		(duplicate_pad_numbers_are_jumpers no)
		(fp_line
			(start 0.7874 0.4064)
			(end -0.7874 0.4064)
			(stroke
				(width 0.1524)
				(type default)
			)
			(layer "F.SilkS")
		)
		(fp_line
			(start 0.7874 -0.4064)
			(end 0.7874 0.4064)
			(stroke
				(width 0.1524)
				(type default)
			)
			(layer "F.SilkS")
		)
		(fp_line
			(start -0.7874 0.4064)
			(end -0.7874 -0.4064)
			(stroke
				(width 0.1524)
				(type default)
			)
			(layer "F.SilkS")
		)
		(fp_line
			(start -0.7874 -0.4064)
			(end 0.7874 -0.4064)
			(stroke
				(width 0.1524)
				(type default)
			)
			(layer "F.SilkS")
		)
		(fp_line
			(start 0.67945 0.3048)
			(end 0.120396 0.3048)
			(stroke
				(width 0.1)
				(type default)
			)
			(layer "F.Fab")
		)
		(fp_line
			(start 0.67945 -0.3048)
			(end 0.67945 0.3048)
			(stroke
				(width 0.1)
				(type default)
			)
			(layer "F.Fab")
		)
		(fp_line
			(start 0.12065 -0.2794)
			(end 0.12065 -0.3048)
			(stroke
				(width 0.1)
				(type default)
			)
			(layer "F.Fab")
		)
		(fp_line
			(start 0.12065 -0.3048)
			(end 0.67945 -0.3048)
			(stroke
				(width 0.1)
				(type default)
			)
			(layer "F.Fab")
		)
		(fp_line
			(start 0.120396 0.3048)
			(end 0.120396 0.2794)
			(stroke
				(width 0.1)
				(type default)
			)
			(layer "F.Fab")
		)
		(fp_line
			(start 0.120396 0.2794)
			(end -0.12065 0.2794)
			(stroke
				(width 0.1)
				(type default)
			)
			(layer "F.Fab")
		)
		(fp_line
			(start -0.12065 0.3048)
			(end -0.67945 0.3048)
			(stroke
				(width 0.1)
				(type default)
			)
			(layer "F.Fab")
		)
		(fp_line
			(start -0.12065 0.2794)
			(end -0.12065 0.3048)
			(stroke
				(width 0.1)
				(type default)
			)
			(layer "F.Fab")
		)
		(fp_line
			(start -0.12065 -0.2794)
			(end 0.12065 -0.2794)
			(stroke
				(width 0.1)
				(type default)
			)
			(layer "F.Fab")
		)
		(fp_line
			(start -0.12065 -0.305054)
			(end -0.12065 -0.2794)
			(stroke
				(width 0.1)
				(type default)
			)
			(layer "F.Fab")
		)
		(fp_line
			(start -0.67945 0.3048)
			(end -0.67945 -0.305054)
			(stroke
				(width 0.1)
				(type default)
			)
			(layer "F.Fab")
		)
		(fp_line
			(start -0.67945 -0.305054)
			(end -0.12065 -0.305054)
			(stroke
				(width 0.1)
				(type default)
			)
			(layer "F.Fab")
		)
		(pad "1" smd circle
			(at -0.40005 0 180)
			(size 0 0)
			(layers "F.Cu" "F.Mask" "F.Paste")
			(net "RST_SMB_NIC0_MUX_ISO_N")
		)
		(pad "2" smd circle
			(at 0.40005 0 180)
			(size 0 0)
			(layers "F.Cu" "F.Mask" "F.Paste")
			(net "P3V3_NIC0")
		)
	)
	(footprint ""
		(layer "F.Cu")
		(at 380.48946 -356.244906 90)
		(property "Reference" "C788"
			(at 0 0 90)
			(layer "F.SilkS")
			(hide yes)
			(effects
				(font
					(size 1.27 1.27)
				)
			)
		)
		(property "Value" ""
			(at 0 0 90)
			(layer "F.Fab")
			(effects
				(font
					(size 1.27 1.27)
				)
			)
		)
		(duplicate_pad_numbers_are_jumpers no)
		(fp_line
			(start 0.299974 -0.150114)
			(end 0.299974 0.150114)
			(stroke
				(width 0.1)
				(type default)
			)
			(layer "F.Fab")
		)
		(fp_line
			(start -0.299974 -0.150114)
			(end 0.299974 -0.150114)
			(stroke
				(width 0.1)
				(type default)
			)
			(layer "F.Fab")
		)
		(fp_line
			(start 0.299974 0.150114)
			(end -0.299974 0.150114)
			(stroke
				(width 0.1)
				(type default)
			)
			(layer "F.Fab")
		)
		(fp_line
			(start -0.299974 0.150114)
			(end -0.299974 -0.150114)
			(stroke
				(width 0.1)
				(type default)
			)
			(layer "F.Fab")
		)
		(pad "1" smd rect
			(at -0.2667 0 90)
			(size 0.3048 0.381)
			(layers "F.Cu" "F.Mask" "F.Paste")
			(net "P5E_PEX3_STN6_TX_DP<98>")
		)
		(pad "2" smd rect
			(at 0.2667 0 90)
			(size 0.3048 0.381)
			(layers "F.Cu" "F.Mask" "F.Paste")
			(net "P5E_PEX3_STN6_TX_C_DP<98>")
		)
	)
	(footprint ""
		(layer "F.Cu")
		(at 140.074142 -178.945286 180)
		(property "Reference" "R1103"
			(at 0 0 180)
			(layer "F.SilkS")
			(hide yes)
			(effects
				(font
					(size 1.27 1.27)
				)
			)
		)
		(property "Value" ""
			(at 0 0 180)
			(layer "F.Fab")
			(effects
				(font
					(size 1.27 1.27)
				)
			)
		)
		(duplicate_pad_numbers_are_jumpers no)
		(fp_line
			(start 0.7874 0.4064)
			(end -0.7874 0.4064)
			(stroke
				(width 0.1524)
				(type default)
			)
			(layer "F.SilkS")
		)
		(fp_line
			(start 0.67945 0.3048)
			(end 0.120396 0.3048)
			(stroke
				(width 0.1)
				(type default)
			)
			(layer "F.Fab")
		)
		(fp_line
			(start 0.67945 -0.3048)
			(end 0.67945 0.3048)
			(stroke
				(width 0.1)
				(type default)
			)
			(layer "F.Fab")
		)
		(fp_line
			(start 0.12065 -0.2794)
			(end 0.12065 -0.3048)
			(stroke
				(width 0.1)
				(type default)
			)
			(layer "F.Fab")
		)
		(fp_line
			(start 0.12065 -0.3048)
			(end 0.67945 -0.3048)
			(stroke
				(width 0.1)
				(type default)
			)
			(layer "F.Fab")
		)
		(fp_line
			(start 0.120396 0.3048)
			(end 0.120396 0.2794)
			(stroke
				(width 0.1)
				(type default)
			)
			(layer "F.Fab")
		)
		(fp_line
			(start 0.120396 0.2794)
			(end -0.12065 0.2794)
			(stroke
				(width 0.1)
				(type default)
			)
			(layer "F.Fab")
		)
		(fp_line
			(start -0.12065 0.3048)
			(end -0.67945 0.3048)
			(stroke
				(width 0.1)
				(type default)
			)
			(layer "F.Fab")
		)
		(fp_line
			(start -0.12065 0.2794)
			(end -0.12065 0.3048)
			(stroke
				(width 0.1)
				(type default)
			)
			(layer "F.Fab")
		)
		(fp_line
			(start -0.12065 -0.2794)
			(end 0.12065 -0.2794)
			(stroke
				(width 0.1)
				(type default)
			)
			(layer "F.Fab")
		)
		(fp_line
			(start -0.12065 -0.305054)
			(end -0.12065 -0.2794)
			(stroke
				(width 0.1)
				(type default)
			)
			(layer "F.Fab")
		)
		(fp_line
			(start -0.67945 0.3048)
			(end -0.67945 -0.305054)
			(stroke
				(width 0.1)
				(type default)
			)
			(layer "F.Fab")
		)
		(fp_line
			(start -0.67945 -0.305054)
			(end -0.12065 -0.305054)
			(stroke
				(width 0.1)
				(type default)
			)
			(layer "F.Fab")
		)
		(pad "1" smd circle
			(at -0.40005 0 180)
			(size 0 0)
			(layers "F.Cu" "F.Mask" "F.Paste")
			(net "CLK_100M_DB2000QL_NIC4_R_DN")
		)
		(pad "2" smd circle
			(at 0.40005 0 180)
			(size 0 0)
			(layers "F.Cu" "F.Mask" "F.Paste")
			(net "CLK_100M_DB2000QL_NIC4_DN")
		)
	)
	(footprint ""
		(layer "F.Cu")
		(at 340.458044 -356.244906 90)
		(property "Reference" "C521"
			(at 0 0 90)
			(layer "F.SilkS")
			(hide yes)
			(effects
				(font
					(size 1.27 1.27)
				)
			)
		)
		(property "Value" ""
			(at 0 0 90)
			(layer "F.Fab")
			(effects
				(font
					(size 1.27 1.27)
				)
			)
		)
		(duplicate_pad_numbers_are_jumpers no)
		(fp_line
			(start 0.299974 -0.150114)
			(end 0.299974 0.150114)
			(stroke
				(width 0.1)
				(type default)
			)
			(layer "F.Fab")
		)
		(fp_line
			(start -0.299974 -0.150114)
			(end 0.299974 -0.150114)
			(stroke
				(width 0.1)
				(type default)
			)
			(layer "F.Fab")
		)
		(fp_line
			(start 0.299974 0.150114)
			(end -0.299974 0.150114)
			(stroke
				(width 0.1)
				(type default)
			)
			(layer "F.Fab")
		)
		(fp_line
			(start -0.299974 0.150114)
			(end -0.299974 -0.150114)
			(stroke
				(width 0.1)
				(type default)
			)
			(layer "F.Fab")
		)
		(pad "1" smd rect
			(at -0.2667 0 90)
			(size 0.3048 0.381)
			(layers "F.Cu" "F.Mask" "F.Paste")
			(net "P5E_PEX2_STN5_TX_DP<94>")
		)
		(pad "2" smd rect
			(at 0.2667 0 90)
			(size 0.3048 0.381)
			(layers "F.Cu" "F.Mask" "F.Paste")
			(net "P5E_PEX2_STN5_TX_C_DP<94>")
		)
	)
	(footprint ""
		(layer "F.Cu")
		(at 83.754214 -48.21809)
		(property "Reference" "PD66"
			(at -3.337814 2.24536 0)
			(unlocked yes)
			(layer "F.SilkS")
			(effects
				(font
					(size 0.7874 0.5842)
					(thickness 0.1524)
				)
				(justify left)
			)
		)
		(property "Value" ""
			(at 0 0 0)
			(layer "F.Fab")
			(effects
				(font
					(size 1.27 1.27)
				)
			)
		)
		(duplicate_pad_numbers_are_jumpers no)
		(fp_line
			(start -3.400044 -1.459992)
			(end 4.107942 -1.459992)
			(stroke
				(width 0.1524)
				(type default)
			)
			(layer "F.SilkS")
		)
		(fp_line
			(start -3.400044 1.459992)
			(end -3.400044 -1.459992)
			(stroke
				(width 0.1524)
				(type default)
			)
			(layer "F.SilkS")
		)
		(fp_line
			(start 4.107942 -1.459992)
			(end 4.107942 1.459992)
			(stroke
				(width 0.1524)
				(type default)
			)
			(layer "F.SilkS")
		)
		(fp_line
			(start 4.107942 1.459992)
			(end -3.400044 1.459992)
			(stroke
				(width 0.1524)
				(type default)
			)
			(layer "F.SilkS")
		)
		(fp_poly
			(pts
				(xy 4.107942 -1.459992) (xy 4.107942 1.459992) (xy 3.308096 1.459992) (xy 3.308096 -1.459992)
			)
			(stroke
				(width 0)
				(type default)
			)
			(fill yes)
			(layer "F.SilkS")
		)
		(fp_line
			(start -2.29997 -1.459992)
			(end 2.29997 -1.459992)
			(stroke
				(width 0.1)
				(type default)
			)
			(layer "F.Fab")
		)
		(fp_line
			(start -2.29997 1.459992)
			(end -2.29997 -1.459992)
			(stroke
				(width 0.1)
				(type default)
			)
			(layer "F.Fab")
		)
		(fp_line
			(start 2.29997 -1.459992)
			(end 2.29997 1.459992)
			(stroke
				(width 0.1)
				(type default)
			)
			(layer "F.Fab")
		)
		(fp_line
			(start 2.29997 1.459992)
			(end -2.29997 1.459992)
			(stroke
				(width 0.1)
				(type default)
			)
			(layer "F.Fab")
		)
		(fp_text user "+"
			(at -4.7752 -0.12065 0)
			(unlocked yes)
			(layer "F.SilkS")
			(effects
				(font
					(size 1.905 1.4224)
					(thickness 0.1524)
				)
				(justify left)
			)
		)
		(fp_text user "-"
			(at 5.4102 0.29845 180)
			(unlocked yes)
			(layer "F.SilkS")
			(effects
				(font
					(size 1.905 1.4224)
					(thickness 0.1524)
				)
				(justify left)
			)
		)
		(fp_text user "+"
			(at -4.7752 -0.12065 0)
			(unlocked yes)
			(layer "F.Fab")
			(effects
				(font
					(size 1.905 1.4224)
					(thickness 0.1524)
				)
				(justify left)
			)
		)
		(fp_text user "-"
			(at 5.4102 0.29845 180)
			(unlocked yes)
			(layer "F.Fab")
			(effects
				(font
					(size 1.905 1.4224)
					(thickness 0.1524)
				)
				(justify left)
			)
		)
		(pad "A" smd rect
			(at -1.999996 0 90)
			(size 1.7018 2.5146)
			(layers "F.Cu" "F.Mask" "F.Paste")
			(net "GND")
		)
		(pad "C" smd rect
			(at 1.999996 0 90)
			(size 1.7018 2.5146)
			(layers "F.Cu" "F.Mask" "F.Paste")
			(net "P3V3_SSD3")
		)
	)
	(footprint ""
		(layer "F.Cu")
		(at 206.033116 -311.946544 135)
		(property "Reference" "R1302"
			(at 0 0 135)
			(layer "F.SilkS")
			(hide yes)
			(effects
				(font
					(size 1.27 1.27)
				)
			)
		)
		(property "Value" ""
			(at 0 0 135)
			(layer "F.Fab")
			(effects
				(font
					(size 1.27 1.27)
				)
			)
		)
		(duplicate_pad_numbers_are_jumpers no)
		(fp_line
			(start 0.787389 -0.406267)
			(end 0.787389 0.406267)
			(stroke
				(width 0.1524)
				(type default)
			)
			(layer "F.SilkS")
		)
		(fp_line
			(start 0.787389 0.406267)
			(end -0.787389 0.406267)
			(stroke
				(width 0.1524)
				(type default)
			)
			(layer "F.SilkS")
		)
		(fp_line
			(start -0.787389 -0.406267)
			(end 0.787389 -0.406267)
			(stroke
				(width 0.1524)
				(type default)
			)
			(layer "F.SilkS")
		)
		(fp_line
			(start -0.787389 0.406267)
			(end -0.787389 -0.406267)
			(stroke
				(width 0.1524)
				(type default)
			)
			(layer "F.SilkS")
		)
		(fp_line
			(start 0.679446 -0.30479)
			(end 0.679446 0.30479)
			(stroke
				(width 0.1)
				(type default)
			)
			(layer "F.Fab")
		)
		(fp_line
			(start 0.120515 -0.30479)
			(end 0.679446 -0.30479)
			(stroke
				(width 0.1)
				(type default)
			)
			(layer "F.Fab")
		)
		(fp_line
			(start 0.120695 -0.279466)
			(end 0.120515 -0.30479)
			(stroke
				(width 0.1)
				(type default)
			)
			(layer "F.Fab")
		)
		(fp_line
			(start 0.679446 0.30479)
			(end 0.120515 0.30479)
			(stroke
				(width 0.1)
				(type default)
			)
			(layer "F.Fab")
		)
		(fp_line
			(start -0.120695 -0.304969)
			(end -0.120695 -0.279466)
			(stroke
				(width 0.1)
				(type default)
			)
			(layer "F.Fab")
		)
		(fp_line
			(start -0.120695 -0.279466)
			(end 0.120695 -0.279466)
			(stroke
				(width 0.1)
				(type default)
			)
			(layer "F.Fab")
		)
		(fp_line
			(start 0.120335 0.279466)
			(end -0.120695 0.279466)
			(stroke
				(width 0.1)
				(type default)
			)
			(layer "F.Fab")
		)
		(fp_line
			(start 0.120515 0.30479)
			(end 0.120335 0.279466)
			(stroke
				(width 0.1)
				(type default)
			)
			(layer "F.Fab")
		)
		(fp_line
			(start -0.679446 -0.305149)
			(end -0.120695 -0.304969)
			(stroke
				(width 0.1)
				(type default)
			)
			(layer "F.Fab")
		)
		(fp_line
			(start -0.120695 0.279466)
			(end -0.120515 0.30479)
			(stroke
				(width 0.1)
				(type default)
			)
			(layer "F.Fab")
		)
		(fp_line
			(start -0.120515 0.30479)
			(end -0.679446 0.30479)
			(stroke
				(width 0.1)
				(type default)
			)
			(layer "F.Fab")
		)
		(fp_line
			(start -0.679446 0.30479)
			(end -0.679446 -0.305149)
			(stroke
				(width 0.1)
				(type default)
			)
			(layer "F.Fab")
		)
		(pad "1" smd circle
			(at -0.40005 0 135)
			(size 0 0)
			(layers "F.Cu" "F.Mask" "F.Paste")
			(net "PEX1_SPARE5")
		)
		(pad "2" smd circle
			(at 0.40005 0 135)
			(size 0 0)
			(layers "F.Cu" "F.Mask" "F.Paste")
			(net "P1V8_PEX")
		)
	)
	(footprint ""
		(layer "F.Cu")
		(at 251.698506 -66.32194 -90)
		(property "Reference" "PC865"
			(at 0 0 270)
			(layer "F.SilkS")
			(hide yes)
			(effects
				(font
					(size 1.27 1.27)
				)
			)
		)
		(property "Value" ""
			(at 0 0 270)
			(layer "F.Fab")
			(effects
				(font
					(size 1.27 1.27)
				)
			)
		)
		(duplicate_pad_numbers_are_jumpers no)
		(fp_line
			(start -0.7874 0.4064)
			(end -0.7874 -0.4064)
			(stroke
				(width 0.1524)
				(type default)
			)
			(layer "F.SilkS")
		)
		(fp_line
			(start 0.7874 0.4064)
			(end -0.7874 0.4064)
			(stroke
				(width 0.1524)
				(type default)
			)
			(layer "F.SilkS")
		)
		(fp_line
			(start -0.7874 -0.4064)
			(end 0.7874 -0.4064)
			(stroke
				(width 0.1524)
				(type default)
			)
			(layer "F.SilkS")
		)
		(fp_line
			(start 0.7874 -0.4064)
			(end 0.7874 0.4064)
			(stroke
				(width 0.1524)
				(type default)
			)
			(layer "F.SilkS")
		)
		(fp_line
			(start -0.67945 0.3048)
			(end -0.67945 -0.305054)
			(stroke
				(width 0.1)
				(type default)
			)
			(layer "F.Fab")
		)
		(fp_line
			(start -0.12065 0.3048)
			(end -0.67945 0.3048)
			(stroke
				(width 0.1)
				(type default)
			)
			(layer "F.Fab")
		)
		(fp_line
			(start 0.120396 0.3048)
			(end 0.120396 0.2794)
			(stroke
				(width 0.1)
				(type default)
			)
			(layer "F.Fab")
		)
		(fp_line
			(start 0.67945 0.3048)
			(end 0.120396 0.3048)
			(stroke
				(width 0.1)
				(type default)
			)
			(layer "F.Fab")
		)
		(fp_line
			(start -0.12065 0.2794)
			(end -0.12065 0.3048)
			(stroke
				(width 0.1)
				(type default)
			)
			(layer "F.Fab")
		)
		(fp_line
			(start 0.120396 0.2794)
			(end -0.12065 0.2794)
			(stroke
				(width 0.1)
				(type default)
			)
			(layer "F.Fab")
		)
		(fp_line
			(start -0.12065 -0.2794)
			(end 0.12065 -0.2794)
			(stroke
				(width 0.1)
				(type default)
			)
			(layer "F.Fab")
		)
		(fp_line
			(start 0.12065 -0.2794)
			(end 0.12065 -0.3048)
			(stroke
				(width 0.1)
				(type default)
			)
			(layer "F.Fab")
		)
		(fp_line
			(start 0.12065 -0.3048)
			(end 0.67945 -0.3048)
			(stroke
				(width 0.1)
				(type default)
			)
			(layer "F.Fab")
		)
		(fp_line
			(start 0.67945 -0.3048)
			(end 0.67945 0.3048)
			(stroke
				(width 0.1)
				(type default)
			)
			(layer "F.Fab")
		)
		(fp_line
			(start -0.67945 -0.305054)
			(end -0.12065 -0.305054)
			(stroke
				(width 0.1)
				(type default)
			)
			(layer "F.Fab")
		)
		(fp_line
			(start -0.12065 -0.305054)
			(end -0.12065 -0.2794)
			(stroke
				(width 0.1)
				(type default)
			)
			(layer "F.Fab")
		)
		(pad "1" smd circle
			(at -0.40005 0 270)
			(size 0 0)
			(layers "F.Cu" "F.Mask" "F.Paste")
			(net "P12V_SSD8_CO_GATE")
		)
		(pad "2" smd circle
			(at 0.40005 0 270)
			(size 0 0)
			(layers "F.Cu" "F.Mask" "F.Paste")
			(net "GND")
		)
	)
	(footprint ""
		(layer "F.Cu")
		(at 8.120634 -26.666444 -90)
		(property "Reference" "R4051"
			(at 0 0 270)
			(layer "F.SilkS")
			(hide yes)
			(effects
				(font
					(size 1.27 1.27)
				)
			)
		)
		(property "Value" ""
			(at 0 0 270)
			(layer "F.Fab")
			(effects
				(font
					(size 1.27 1.27)
				)
			)
		)
		(duplicate_pad_numbers_are_jumpers no)
		(fp_line
			(start -0.7874 0.4064)
			(end -0.7874 -0.4064)
			(stroke
				(width 0.1524)
				(type default)
			)
			(layer "F.SilkS")
		)
		(fp_line
			(start 0.7874 0.4064)
			(end -0.7874 0.4064)
			(stroke
				(width 0.1524)
				(type default)
			)
			(layer "F.SilkS")
		)
		(fp_line
			(start -0.7874 -0.4064)
			(end 0.7874 -0.4064)
			(stroke
				(width 0.1524)
				(type default)
			)
			(layer "F.SilkS")
		)
		(fp_line
			(start 0.7874 -0.4064)
			(end 0.7874 0.4064)
			(stroke
				(width 0.1524)
				(type default)
			)
			(layer "F.SilkS")
		)
		(fp_line
			(start -0.67945 0.3048)
			(end -0.67945 -0.305054)
			(stroke
				(width 0.1)
				(type default)
			)
			(layer "F.Fab")
		)
		(fp_line
			(start -0.12065 0.3048)
			(end -0.67945 0.3048)
			(stroke
				(width 0.1)
				(type default)
			)
			(layer "F.Fab")
		)
		(fp_line
			(start 0.120396 0.3048)
			(end 0.120396 0.2794)
			(stroke
				(width 0.1)
				(type default)
			)
			(layer "F.Fab")
		)
		(fp_line
			(start 0.67945 0.3048)
			(end 0.120396 0.3048)
			(stroke
				(width 0.1)
				(type default)
			)
			(layer "F.Fab")
		)
		(fp_line
			(start -0.12065 0.2794)
			(end -0.12065 0.3048)
			(stroke
				(width 0.1)
				(type default)
			)
			(layer "F.Fab")
		)
		(fp_line
			(start 0.120396 0.2794)
			(end -0.12065 0.2794)
			(stroke
				(width 0.1)
				(type default)
			)
			(layer "F.Fab")
		)
		(fp_line
			(start -0.12065 -0.2794)
			(end 0.12065 -0.2794)
			(stroke
				(width 0.1)
				(type default)
			)
			(layer "F.Fab")
		)
		(fp_line
			(start 0.12065 -0.2794)
			(end 0.12065 -0.3048)
			(stroke
				(width 0.1)
				(type default)
			)
			(layer "F.Fab")
		)
		(fp_line
			(start 0.12065 -0.3048)
			(end 0.67945 -0.3048)
			(stroke
				(width 0.1)
				(type default)
			)
			(layer "F.Fab")
		)
		(fp_line
			(start 0.67945 -0.3048)
			(end 0.67945 0.3048)
			(stroke
				(width 0.1)
				(type default)
			)
			(layer "F.Fab")
		)
		(fp_line
			(start -0.67945 -0.305054)
			(end -0.12065 -0.305054)
			(stroke
				(width 0.1)
				(type default)
			)
			(layer "F.Fab")
		)
		(fp_line
			(start -0.12065 -0.305054)
			(end -0.12065 -0.2794)
			(stroke
				(width 0.1)
				(type default)
			)
			(layer "F.Fab")
		)
		(pad "1" smd circle
			(at -0.40005 0 270)
			(size 0 0)
			(layers "F.Cu" "F.Mask" "F.Paste")
			(net "PRSNT_SSD0_R_N")
		)
		(pad "2" smd circle
			(at 0.40005 0 270)
			(size 0 0)
			(layers "F.Cu" "F.Mask" "F.Paste")
			(net "PRSNT_SSD0_N")
		)
	)
	(footprint ""
		(layer "F.Cu")
		(at 121.494296 -29.507688 -90)
		(property "Reference" "PC921"
			(at 0 0 270)
			(layer "F.SilkS")
			(hide yes)
			(effects
				(font
					(size 1.27 1.27)
				)
			)
		)
		(property "Value" ""
			(at 0 0 270)
			(layer "F.Fab")
			(effects
				(font
					(size 1.27 1.27)
				)
			)
		)
		(duplicate_pad_numbers_are_jumpers no)
		(fp_line
			(start -1.524 0.762)
			(end -1.524 -0.762)
			(stroke
				(width 0.1524)
				(type default)
			)
			(layer "F.SilkS")
		)
		(fp_line
			(start 1.524 0.762)
			(end -1.524 0.762)
			(stroke
				(width 0.1524)
				(type default)
			)
			(layer "F.SilkS")
		)
		(fp_line
			(start -1.524 -0.762)
			(end 1.524 -0.762)
			(stroke
				(width 0.1524)
				(type default)
			)
			(layer "F.SilkS")
		)
		(fp_line
			(start 1.524 -0.762)
			(end 1.524 0.762)
			(stroke
				(width 0.1524)
				(type default)
			)
			(layer "F.SilkS")
		)
		(fp_line
			(start -1.1049 0.724916)
			(end 1.1049 0.724916)
			(stroke
				(width 0.1)
				(type default)
			)
			(layer "F.Fab")
		)
		(fp_line
			(start 1.1049 0.724916)
			(end 1.1049 -0.724916)
			(stroke
				(width 0.1)
				(type default)
			)
			(layer "F.Fab")
		)
		(fp_line
			(start -1.1049 -0.724916)
			(end -1.1049 0.724916)
			(stroke
				(width 0.1)
				(type default)
			)
			(layer "F.Fab")
		)
		(fp_line
			(start 1.1049 -0.724916)
			(end -1.1049 -0.724916)
			(stroke
				(width 0.1)
				(type default)
			)
			(layer "F.Fab")
		)
		(pad "1" smd rect
			(at -0.889 0 90)
			(size 1.016 1.27)
			(layers "F.Cu" "F.Mask" "F.Paste")
			(net "P3V3_SSD4")
		)
		(pad "2" smd rect
			(at 0.889 0 90)
			(size 1.016 1.27)
			(layers "F.Cu" "F.Mask" "F.Paste")
			(net "GND")
		)
	)
	(footprint ""
		(layer "F.Cu")
		(at 135.346948 -38.49116 180)
		(property "Reference" "R6065"
			(at 0 0 180)
			(layer "F.SilkS")
			(hide yes)
			(effects
				(font
					(size 1.27 1.27)
				)
			)
		)
		(property "Value" ""
			(at 0 0 180)
			(layer "F.Fab")
			(effects
				(font
					(size 1.27 1.27)
				)
			)
		)
		(duplicate_pad_numbers_are_jumpers no)
		(fp_line
			(start 0.7874 0.4064)
			(end -0.7874 0.4064)
			(stroke
				(width 0.1524)
				(type default)
			)
			(layer "F.SilkS")
		)
		(fp_line
			(start 0.7874 -0.4064)
			(end 0.7874 0.4064)
			(stroke
				(width 0.1524)
				(type default)
			)
			(layer "F.SilkS")
		)
		(fp_line
			(start -0.7874 0.4064)
			(end -0.7874 -0.4064)
			(stroke
				(width 0.1524)
				(type default)
			)
			(layer "F.SilkS")
		)
		(fp_line
			(start -0.7874 -0.4064)
			(end 0.7874 -0.4064)
			(stroke
				(width 0.1524)
				(type default)
			)
			(layer "F.SilkS")
		)
		(fp_line
			(start 0.67945 0.3048)
			(end 0.120396 0.3048)
			(stroke
				(width 0.1)
				(type default)
			)
			(layer "F.Fab")
		)
		(fp_line
			(start 0.67945 -0.3048)
			(end 0.67945 0.3048)
			(stroke
				(width 0.1)
				(type default)
			)
			(layer "F.Fab")
		)
		(fp_line
			(start 0.12065 -0.2794)
			(end 0.12065 -0.3048)
			(stroke
				(width 0.1)
				(type default)
			)
			(layer "F.Fab")
		)
		(fp_line
			(start 0.12065 -0.3048)
			(end 0.67945 -0.3048)
			(stroke
				(width 0.1)
				(type default)
			)
			(layer "F.Fab")
		)
		(fp_line
			(start 0.120396 0.3048)
			(end 0.120396 0.2794)
			(stroke
				(width 0.1)
				(type default)
			)
			(layer "F.Fab")
		)
		(fp_line
			(start 0.120396 0.2794)
			(end -0.12065 0.2794)
			(stroke
				(width 0.1)
				(type default)
			)
			(layer "F.Fab")
		)
		(fp_line
			(start -0.12065 0.3048)
			(end -0.67945 0.3048)
			(stroke
				(width 0.1)
				(type default)
			)
			(layer "F.Fab")
		)
		(fp_line
			(start -0.12065 0.2794)
			(end -0.12065 0.3048)
			(stroke
				(width 0.1)
				(type default)
			)
			(layer "F.Fab")
		)
		(fp_line
			(start -0.12065 -0.2794)
			(end 0.12065 -0.2794)
			(stroke
				(width 0.1)
				(type default)
			)
			(layer "F.Fab")
		)
		(fp_line
			(start -0.12065 -0.305054)
			(end -0.12065 -0.2794)
			(stroke
				(width 0.1)
				(type default)
			)
			(layer "F.Fab")
		)
		(fp_line
			(start -0.67945 0.3048)
			(end -0.67945 -0.305054)
			(stroke
				(width 0.1)
				(type default)
			)
			(layer "F.Fab")
		)
		(fp_line
			(start -0.67945 -0.305054)
			(end -0.12065 -0.305054)
			(stroke
				(width 0.1)
				(type default)
			)
			(layer "F.Fab")
		)
		(pad "1" smd circle
			(at -0.40005 0 180)
			(size 0 0)
			(layers "F.Cu" "F.Mask" "F.Paste")
			(net "P3V3_SSD5_PG_G1")
		)
		(pad "2" smd circle
			(at 0.40005 0 180)
			(size 0 0)
			(layers "F.Cu" "F.Mask" "F.Paste")
			(net "GND")
		)
	)
	(footprint ""
		(layer "F.Cu")
		(at 165.75659 -20.467574 180)
		(property "Reference" "R1664"
			(at 0 0 180)
			(layer "F.SilkS")
			(hide yes)
			(effects
				(font
					(size 1.27 1.27)
				)
			)
		)
		(property "Value" ""
			(at 0 0 180)
			(layer "F.Fab")
			(effects
				(font
					(size 1.27 1.27)
				)
			)
		)
		(duplicate_pad_numbers_are_jumpers no)
		(fp_line
			(start 0.7874 0.4064)
			(end -0.7874 0.4064)
			(stroke
				(width 0.1524)
				(type default)
			)
			(layer "F.SilkS")
		)
		(fp_line
			(start 0.7874 -0.4064)
			(end 0.7874 0.4064)
			(stroke
				(width 0.1524)
				(type default)
			)
			(layer "F.SilkS")
		)
		(fp_line
			(start -0.7874 0.4064)
			(end -0.7874 -0.4064)
			(stroke
				(width 0.1524)
				(type default)
			)
			(layer "F.SilkS")
		)
		(fp_line
			(start -0.7874 -0.4064)
			(end 0.7874 -0.4064)
			(stroke
				(width 0.1524)
				(type default)
			)
			(layer "F.SilkS")
		)
		(fp_line
			(start 0.67945 0.3048)
			(end 0.120396 0.3048)
			(stroke
				(width 0.1)
				(type default)
			)
			(layer "F.Fab")
		)
		(fp_line
			(start 0.67945 -0.3048)
			(end 0.67945 0.3048)
			(stroke
				(width 0.1)
				(type default)
			)
			(layer "F.Fab")
		)
		(fp_line
			(start 0.12065 -0.2794)
			(end 0.12065 -0.3048)
			(stroke
				(width 0.1)
				(type default)
			)
			(layer "F.Fab")
		)
		(fp_line
			(start 0.12065 -0.3048)
			(end 0.67945 -0.3048)
			(stroke
				(width 0.1)
				(type default)
			)
			(layer "F.Fab")
		)
		(fp_line
			(start 0.120396 0.3048)
			(end 0.120396 0.2794)
			(stroke
				(width 0.1)
				(type default)
			)
			(layer "F.Fab")
		)
		(fp_line
			(start 0.120396 0.2794)
			(end -0.12065 0.2794)
			(stroke
				(width 0.1)
				(type default)
			)
			(layer "F.Fab")
		)
		(fp_line
			(start -0.12065 0.3048)
			(end -0.67945 0.3048)
			(stroke
				(width 0.1)
				(type default)
			)
			(layer "F.Fab")
		)
		(fp_line
			(start -0.12065 0.2794)
			(end -0.12065 0.3048)
			(stroke
				(width 0.1)
				(type default)
			)
			(layer "F.Fab")
		)
		(fp_line
			(start -0.12065 -0.2794)
			(end 0.12065 -0.2794)
			(stroke
				(width 0.1)
				(type default)
			)
			(layer "F.Fab")
		)
		(fp_line
			(start -0.12065 -0.305054)
			(end -0.12065 -0.2794)
			(stroke
				(width 0.1)
				(type default)
			)
			(layer "F.Fab")
		)
		(fp_line
			(start -0.67945 0.3048)
			(end -0.67945 -0.305054)
			(stroke
				(width 0.1)
				(type default)
			)
			(layer "F.Fab")
		)
		(fp_line
			(start -0.67945 -0.305054)
			(end -0.12065 -0.305054)
			(stroke
				(width 0.1)
				(type default)
			)
			(layer "F.Fab")
		)
		(pad "1" smd circle
			(at -0.40005 0 180)
			(size 0 0)
			(layers "F.Cu" "F.Mask" "F.Paste")
			(net "P3V3_SSD5")
		)
		(pad "2" smd circle
			(at 0.40005 0 180)
			(size 0 0)
			(layers "F.Cu" "F.Mask" "F.Paste")
			(net "SMB_ISO_SSD5_SDA")
		)
	)
	(footprint ""
		(layer "F.Cu")
		(at 452.567802 -52.035456 180)
		(property "Reference" "R877"
			(at 0 0 180)
			(layer "F.SilkS")
			(hide yes)
			(effects
				(font
					(size 1.27 1.27)
				)
			)
		)
		(property "Value" ""
			(at 0 0 180)
			(layer "F.Fab")
			(effects
				(font
					(size 1.27 1.27)
				)
			)
		)
		(duplicate_pad_numbers_are_jumpers no)
		(fp_line
			(start 0.7874 0.4064)
			(end -0.7874 0.4064)
			(stroke
				(width 0.1524)
				(type default)
			)
			(layer "F.SilkS")
		)
		(fp_line
			(start 0.7874 -0.4064)
			(end 0.7874 0.4064)
			(stroke
				(width 0.1524)
				(type default)
			)
			(layer "F.SilkS")
		)
		(fp_line
			(start -0.7874 0.4064)
			(end -0.7874 -0.4064)
			(stroke
				(width 0.1524)
				(type default)
			)
			(layer "F.SilkS")
		)
		(fp_line
			(start -0.7874 -0.4064)
			(end 0.7874 -0.4064)
			(stroke
				(width 0.1524)
				(type default)
			)
			(layer "F.SilkS")
		)
		(fp_line
			(start 0.67945 0.3048)
			(end 0.120396 0.3048)
			(stroke
				(width 0.1)
				(type default)
			)
			(layer "F.Fab")
		)
		(fp_line
			(start 0.67945 -0.3048)
			(end 0.67945 0.3048)
			(stroke
				(width 0.1)
				(type default)
			)
			(layer "F.Fab")
		)
		(fp_line
			(start 0.12065 -0.2794)
			(end 0.12065 -0.3048)
			(stroke
				(width 0.1)
				(type default)
			)
			(layer "F.Fab")
		)
		(fp_line
			(start 0.12065 -0.3048)
			(end 0.67945 -0.3048)
			(stroke
				(width 0.1)
				(type default)
			)
			(layer "F.Fab")
		)
		(fp_line
			(start 0.120396 0.3048)
			(end 0.120396 0.2794)
			(stroke
				(width 0.1)
				(type default)
			)
			(layer "F.Fab")
		)
		(fp_line
			(start 0.120396 0.2794)
			(end -0.12065 0.2794)
			(stroke
				(width 0.1)
				(type default)
			)
			(layer "F.Fab")
		)
		(fp_line
			(start -0.12065 0.3048)
			(end -0.67945 0.3048)
			(stroke
				(width 0.1)
				(type default)
			)
			(layer "F.Fab")
		)
		(fp_line
			(start -0.12065 0.2794)
			(end -0.12065 0.3048)
			(stroke
				(width 0.1)
				(type default)
			)
			(layer "F.Fab")
		)
		(fp_line
			(start -0.12065 -0.2794)
			(end 0.12065 -0.2794)
			(stroke
				(width 0.1)
				(type default)
			)
			(layer "F.Fab")
		)
		(fp_line
			(start -0.12065 -0.305054)
			(end -0.12065 -0.2794)
			(stroke
				(width 0.1)
				(type default)
			)
			(layer "F.Fab")
		)
		(fp_line
			(start -0.67945 0.3048)
			(end -0.67945 -0.305054)
			(stroke
				(width 0.1)
				(type default)
			)
			(layer "F.Fab")
		)
		(fp_line
			(start -0.67945 -0.305054)
			(end -0.12065 -0.305054)
			(stroke
				(width 0.1)
				(type default)
			)
			(layer "F.Fab")
		)
		(pad "1" smd circle
			(at -0.40005 0 180)
			(size 0 0)
			(layers "F.Cu" "F.Mask" "F.Paste")
			(net "P3V3_AUX")
		)
		(pad "2" smd circle
			(at 0.40005 0 180)
			(size 0 0)
			(layers "F.Cu" "F.Mask" "F.Paste")
			(net "PWRGD_P12V_SSD15")
		)
	)
	(footprint ""
		(layer "F.Cu")
		(at 304.687478 -25.342342 -90)
		(property "Reference" "R440"
			(at 0 0 270)
			(layer "F.SilkS")
			(hide yes)
			(effects
				(font
					(size 1.27 1.27)
				)
			)
		)
		(property "Value" ""
			(at 0 0 270)
			(layer "F.Fab")
			(effects
				(font
					(size 1.27 1.27)
				)
			)
		)
		(duplicate_pad_numbers_are_jumpers no)
		(fp_line
			(start -0.7874 0.4064)
			(end -0.7874 -0.4064)
			(stroke
				(width 0.1524)
				(type default)
			)
			(layer "F.SilkS")
		)
		(fp_line
			(start 0.7874 0.4064)
			(end -0.7874 0.4064)
			(stroke
				(width 0.1524)
				(type default)
			)
			(layer "F.SilkS")
		)
		(fp_line
			(start -0.7874 -0.4064)
			(end 0.7874 -0.4064)
			(stroke
				(width 0.1524)
				(type default)
			)
			(layer "F.SilkS")
		)
		(fp_line
			(start 0.7874 -0.4064)
			(end 0.7874 0.4064)
			(stroke
				(width 0.1524)
				(type default)
			)
			(layer "F.SilkS")
		)
		(fp_line
			(start -0.67945 0.3048)
			(end -0.67945 -0.305054)
			(stroke
				(width 0.1)
				(type default)
			)
			(layer "F.Fab")
		)
		(fp_line
			(start -0.12065 0.3048)
			(end -0.67945 0.3048)
			(stroke
				(width 0.1)
				(type default)
			)
			(layer "F.Fab")
		)
		(fp_line
			(start 0.120396 0.3048)
			(end 0.120396 0.2794)
			(stroke
				(width 0.1)
				(type default)
			)
			(layer "F.Fab")
		)
		(fp_line
			(start 0.67945 0.3048)
			(end 0.120396 0.3048)
			(stroke
				(width 0.1)
				(type default)
			)
			(layer "F.Fab")
		)
		(fp_line
			(start -0.12065 0.2794)
			(end -0.12065 0.3048)
			(stroke
				(width 0.1)
				(type default)
			)
			(layer "F.Fab")
		)
		(fp_line
			(start 0.120396 0.2794)
			(end -0.12065 0.2794)
			(stroke
				(width 0.1)
				(type default)
			)
			(layer "F.Fab")
		)
		(fp_line
			(start -0.12065 -0.2794)
			(end 0.12065 -0.2794)
			(stroke
				(width 0.1)
				(type default)
			)
			(layer "F.Fab")
		)
		(fp_line
			(start 0.12065 -0.2794)
			(end 0.12065 -0.3048)
			(stroke
				(width 0.1)
				(type default)
			)
			(layer "F.Fab")
		)
		(fp_line
			(start 0.12065 -0.3048)
			(end 0.67945 -0.3048)
			(stroke
				(width 0.1)
				(type default)
			)
			(layer "F.Fab")
		)
		(fp_line
			(start 0.67945 -0.3048)
			(end 0.67945 0.3048)
			(stroke
				(width 0.1)
				(type default)
			)
			(layer "F.Fab")
		)
		(fp_line
			(start -0.67945 -0.305054)
			(end -0.12065 -0.305054)
			(stroke
				(width 0.1)
				(type default)
			)
			(layer "F.Fab")
		)
		(fp_line
			(start -0.12065 -0.305054)
			(end -0.12065 -0.2794)
			(stroke
				(width 0.1)
				(type default)
			)
			(layer "F.Fab")
		)
		(pad "1" smd circle
			(at -0.40005 0 270)
			(size 0 0)
			(layers "F.Cu" "F.Mask" "F.Paste")
			(net "GND")
		)
		(pad "2" smd circle
			(at 0.40005 0 270)
			(size 0 0)
			(layers "F.Cu" "F.Mask" "F.Paste")
			(net "DUALPORT_N_SSD10")
		)
	)
	(footprint ""
		(layer "F.Cu")
		(at 337.051396 -99.177602 -90)
		(property "Reference" "PD96"
			(at 3.876802 -2.751074 90)
			(unlocked yes)
			(layer "F.SilkS")
			(effects
				(font
					(size 0.7874 0.5842)
					(thickness 0.1524)
				)
				(justify left)
			)
		)
		(property "Value" ""
			(at 0 0 270)
			(layer "F.Fab")
			(effects
				(font
					(size 1.27 1.27)
				)
			)
		)
		(duplicate_pad_numbers_are_jumpers no)
		(fp_line
			(start -3.656584 1.970024)
			(end 4.240784 1.970024)
			(stroke
				(width 0.1524)
				(type default)
			)
			(layer "F.SilkS")
		)
		(fp_line
			(start 4.240784 1.970024)
			(end 4.240784 -1.970024)
			(stroke
				(width 0.1524)
				(type default)
			)
			(layer "F.SilkS")
		)
		(fp_line
			(start -3.656584 -1.970024)
			(end -3.656584 1.970024)
			(stroke
				(width 0.1524)
				(type default)
			)
			(layer "F.SilkS")
		)
		(fp_line
			(start 4.240784 -1.970024)
			(end -3.656584 -1.970024)
			(stroke
				(width 0.1524)
				(type default)
			)
			(layer "F.SilkS")
		)
		(fp_rect
			(start 4.240784 1.970024)
			(end 3.580384 -1.970024)
			(stroke
				(width 0)
				(type default)
			)
			(fill yes)
			(layer "F.SilkS")
		)
		(fp_line
			(start -2.3749 1.970024)
			(end 2.3749 1.970024)
			(stroke
				(width 0.1)
				(type default)
			)
			(layer "F.Fab")
		)
		(fp_line
			(start 2.3749 1.970024)
			(end 2.3749 -1.970024)
			(stroke
				(width 0.1)
				(type default)
			)
			(layer "F.Fab")
		)
		(fp_line
			(start -2.3749 -1.970024)
			(end -2.3749 1.970024)
			(stroke
				(width 0.1)
				(type default)
			)
			(layer "F.Fab")
		)
		(fp_line
			(start 2.3749 -1.970024)
			(end -2.3749 -1.970024)
			(stroke
				(width 0.1)
				(type default)
			)
			(layer "F.Fab")
		)
		(fp_text user "+"
			(at -4.9784 -0.23495 270)
			(unlocked yes)
			(layer "F.Fab")
			(effects
				(font
					(size 1.905 1.4224)
					(thickness 0.1524)
				)
				(justify left)
			)
		)
		(fp_text user "-"
			(at 4.1656 -0.23495 270)
			(unlocked yes)
			(layer "F.Fab")
			(effects
				(font
					(size 1.905 1.4224)
					(thickness 0.1524)
				)
				(justify left)
			)
		)
		(pad "A" smd rect
			(at -2.450084 0 270)
			(size 2.159 2.2606)
			(layers "F.Cu" "F.Mask" "F.Paste")
			(net "GND")
		)
		(pad "C" smd rect
			(at 2.450084 0 270)
			(size 2.159 2.2606)
			(layers "F.Cu" "F.Mask" "F.Paste")
			(net "P12V_AUX")
		)
	)
	(footprint ""
		(layer "F.Cu")
		(at 310.467756 -54.067456)
		(property "Reference" "PR233"
			(at 0 0 0)
			(layer "F.SilkS")
			(hide yes)
			(effects
				(font
					(size 1.27 1.27)
				)
			)
		)
		(property "Value" ""
			(at 0 0 0)
			(layer "F.Fab")
			(effects
				(font
					(size 1.27 1.27)
				)
			)
		)
		(duplicate_pad_numbers_are_jumpers no)
		(fp_line
			(start -0.7874 -0.4064)
			(end 0.7874 -0.4064)
			(stroke
				(width 0.1524)
				(type default)
			)
			(layer "F.SilkS")
		)
		(fp_line
			(start -0.7874 0.4064)
			(end -0.7874 -0.4064)
			(stroke
				(width 0.1524)
				(type default)
			)
			(layer "F.SilkS")
		)
		(fp_line
			(start 0.7874 -0.4064)
			(end 0.7874 0.4064)
			(stroke
				(width 0.1524)
				(type default)
			)
			(layer "F.SilkS")
		)
		(fp_line
			(start 0.7874 0.4064)
			(end -0.7874 0.4064)
			(stroke
				(width 0.1524)
				(type default)
			)
			(layer "F.SilkS")
		)
		(fp_line
			(start -0.67945 -0.305054)
			(end -0.12065 -0.305054)
			(stroke
				(width 0.1)
				(type default)
			)
			(layer "F.Fab")
		)
		(fp_line
			(start -0.67945 0.3048)
			(end -0.67945 -0.305054)
			(stroke
				(width 0.1)
				(type default)
			)
			(layer "F.Fab")
		)
		(fp_line
			(start -0.12065 -0.305054)
			(end -0.12065 -0.2794)
			(stroke
				(width 0.1)
				(type default)
			)
			(layer "F.Fab")
		)
		(fp_line
			(start -0.12065 -0.2794)
			(end 0.12065 -0.2794)
			(stroke
				(width 0.1)
				(type default)
			)
			(layer "F.Fab")
		)
		(fp_line
			(start -0.12065 0.2794)
			(end -0.12065 0.3048)
			(stroke
				(width 0.1)
				(type default)
			)
			(layer "F.Fab")
		)
		(fp_line
			(start -0.12065 0.3048)
			(end -0.67945 0.3048)
			(stroke
				(width 0.1)
				(type default)
			)
			(layer "F.Fab")
		)
		(fp_line
			(start 0.120396 0.2794)
			(end -0.12065 0.2794)
			(stroke
				(width 0.1)
				(type default)
			)
			(layer "F.Fab")
		)
		(fp_line
			(start 0.120396 0.3048)
			(end 0.120396 0.2794)
			(stroke
				(width 0.1)
				(type default)
			)
			(layer "F.Fab")
		)
		(fp_line
			(start 0.12065 -0.3048)
			(end 0.67945 -0.3048)
			(stroke
				(width 0.1)
				(type default)
			)
			(layer "F.Fab")
		)
		(fp_line
			(start 0.12065 -0.2794)
			(end 0.12065 -0.3048)
			(stroke
				(width 0.1)
				(type default)
			)
			(layer "F.Fab")
		)
		(fp_line
			(start 0.67945 -0.3048)
			(end 0.67945 0.3048)
			(stroke
				(width 0.1)
				(type default)
			)
			(layer "F.Fab")
		)
		(fp_line
			(start 0.67945 0.3048)
			(end 0.120396 0.3048)
			(stroke
				(width 0.1)
				(type default)
			)
			(layer "F.Fab")
		)
		(pad "1" smd circle
			(at -0.40005 0)
			(size 0 0)
			(layers "F.Cu" "F.Mask" "F.Paste")
			(net "P12V_SSD10_OCP")
		)
		(pad "2" smd circle
			(at 0.40005 0)
			(size 0 0)
			(layers "F.Cu" "F.Mask" "F.Paste")
			(net "GND")
		)
	)
	(footprint ""
		(layer "F.Cu")
		(at 452.051674 -208.948782 90)
		(property "Reference" "U108"
			(at -2.813558 -1.527302 0)
			(unlocked yes)
			(layer "F.SilkS")
			(effects
				(font
					(size 0.7874 0.5842)
					(thickness 0.1524)
				)
				(justify left)
			)
		)
		(property "Value" ""
			(at 0 0 90)
			(layer "F.Fab")
			(effects
				(font
					(size 1.27 1.27)
				)
			)
		)
		(duplicate_pad_numbers_are_jumpers no)
		(fp_poly
			(pts
				(xy -1.5113 -0.750062) (xy -2.1463 -1.067562) (xy -2.1463 -0.432562)
			)
			(stroke
				(width 0)
				(type default)
			)
			(fill yes)
			(layer "F.SilkS")
		)
		(fp_line
			(start 0.700024 -1.500124)
			(end 0.700024 1.500124)
			(stroke
				(width 0.1)
				(type default)
			)
			(layer "F.Fab")
		)
		(fp_line
			(start -0.700024 -1.500124)
			(end 0.700024 -1.500124)
			(stroke
				(width 0.1)
				(type default)
			)
			(layer "F.Fab")
		)
		(fp_line
			(start 0.700024 1.500124)
			(end -0.700024 1.500124)
			(stroke
				(width 0.1)
				(type default)
			)
			(layer "F.Fab")
		)
		(fp_line
			(start -0.700024 1.500124)
			(end -0.700024 -1.500124)
			(stroke
				(width 0.1)
				(type default)
			)
			(layer "F.Fab")
		)
		(fp_poly
			(pts
				(xy -1.5113 -0.750062) (xy -2.1463 -1.067562) (xy -2.1463 -0.432562)
			)
			(stroke
				(width 0)
				(type default)
			)
			(fill yes)
			(layer "F.Fab")
		)
		(pad "1" smd rect
			(at -0.999998 -0.750062 90)
			(size 0.7112 1.016)
			(layers "F.Cu" "F.Mask" "F.Paste")
			(net "GND")
		)
		(pad "2" smd rect
			(at -0.999998 0.94996)
			(size 0.6096 0.7112)
			(layers "F.Cu" "F.Mask" "F.Paste")
			(net "USB2_FT4232_MUX_D_DN")
		)
		(pad "3" smd rect
			(at 0.999998 0.94996)
			(size 0.6096 0.7112)
			(layers "F.Cu" "F.Mask" "F.Paste")
			(net "USB2_FT4232_MUX_D_DP")
		)
		(pad "4" smd rect
			(at 0.999998 -0.94996)
			(size 0.6096 0.7112)
			(layers "F.Cu" "F.Mask" "F.Paste")
			(net "USB_VBUS_CONN")
		)
	)
	(footprint ""
		(layer "F.Cu")
		(at 367.54689 -38.49116 180)
		(property "Reference" "R6113"
			(at 0 0 180)
			(layer "F.SilkS")
			(hide yes)
			(effects
				(font
					(size 1.27 1.27)
				)
			)
		)
		(property "Value" ""
			(at 0 0 180)
			(layer "F.Fab")
			(effects
				(font
					(size 1.27 1.27)
				)
			)
		)
		(duplicate_pad_numbers_are_jumpers no)
		(fp_line
			(start 0.7874 0.4064)
			(end -0.7874 0.4064)
			(stroke
				(width 0.1524)
				(type default)
			)
			(layer "F.SilkS")
		)
		(fp_line
			(start 0.7874 -0.4064)
			(end 0.7874 0.4064)
			(stroke
				(width 0.1524)
				(type default)
			)
			(layer "F.SilkS")
		)
		(fp_line
			(start -0.7874 0.4064)
			(end -0.7874 -0.4064)
			(stroke
				(width 0.1524)
				(type default)
			)
			(layer "F.SilkS")
		)
		(fp_line
			(start -0.7874 -0.4064)
			(end 0.7874 -0.4064)
			(stroke
				(width 0.1524)
				(type default)
			)
			(layer "F.SilkS")
		)
		(fp_line
			(start 0.67945 0.3048)
			(end 0.120396 0.3048)
			(stroke
				(width 0.1)
				(type default)
			)
			(layer "F.Fab")
		)
		(fp_line
			(start 0.67945 -0.3048)
			(end 0.67945 0.3048)
			(stroke
				(width 0.1)
				(type default)
			)
			(layer "F.Fab")
		)
		(fp_line
			(start 0.12065 -0.2794)
			(end 0.12065 -0.3048)
			(stroke
				(width 0.1)
				(type default)
			)
			(layer "F.Fab")
		)
		(fp_line
			(start 0.12065 -0.3048)
			(end 0.67945 -0.3048)
			(stroke
				(width 0.1)
				(type default)
			)
			(layer "F.Fab")
		)
		(fp_line
			(start 0.120396 0.3048)
			(end 0.120396 0.2794)
			(stroke
				(width 0.1)
				(type default)
			)
			(layer "F.Fab")
		)
		(fp_line
			(start 0.120396 0.2794)
			(end -0.12065 0.2794)
			(stroke
				(width 0.1)
				(type default)
			)
			(layer "F.Fab")
		)
		(fp_line
			(start -0.12065 0.3048)
			(end -0.67945 0.3048)
			(stroke
				(width 0.1)
				(type default)
			)
			(layer "F.Fab")
		)
		(fp_line
			(start -0.12065 0.2794)
			(end -0.12065 0.3048)
			(stroke
				(width 0.1)
				(type default)
			)
			(layer "F.Fab")
		)
		(fp_line
			(start -0.12065 -0.2794)
			(end 0.12065 -0.2794)
			(stroke
				(width 0.1)
				(type default)
			)
			(layer "F.Fab")
		)
		(fp_line
			(start -0.12065 -0.305054)
			(end -0.12065 -0.2794)
			(stroke
				(width 0.1)
				(type default)
			)
			(layer "F.Fab")
		)
		(fp_line
			(start -0.67945 0.3048)
			(end -0.67945 -0.305054)
			(stroke
				(width 0.1)
				(type default)
			)
			(layer "F.Fab")
		)
		(fp_line
			(start -0.67945 -0.305054)
			(end -0.12065 -0.305054)
			(stroke
				(width 0.1)
				(type default)
			)
			(layer "F.Fab")
		)
		(pad "1" smd circle
			(at -0.40005 0 180)
			(size 0 0)
			(layers "F.Cu" "F.Mask" "F.Paste")
			(net "P3V3_SSD13_PG_G1")
		)
		(pad "2" smd circle
			(at 0.40005 0 180)
			(size 0 0)
			(layers "F.Cu" "F.Mask" "F.Paste")
			(net "GND")
		)
	)
	(footprint ""
		(layer "F.Cu")
		(at 460.027782 -254.344932 -90)
		(property "Reference" "C4399"
			(at 0 0 270)
			(layer "F.SilkS")
			(hide yes)
			(effects
				(font
					(size 1.27 1.27)
				)
			)
		)
		(property "Value" ""
			(at 0 0 270)
			(layer "F.Fab")
			(effects
				(font
					(size 1.27 1.27)
				)
			)
		)
		(duplicate_pad_numbers_are_jumpers no)
		(fp_line
			(start -1.524 0.762)
			(end -1.524 -0.762)
			(stroke
				(width 0.1524)
				(type default)
			)
			(layer "F.SilkS")
		)
		(fp_line
			(start 1.524 0.762)
			(end -1.524 0.762)
			(stroke
				(width 0.1524)
				(type default)
			)
			(layer "F.SilkS")
		)
		(fp_line
			(start -1.524 -0.762)
			(end 1.524 -0.762)
			(stroke
				(width 0.1524)
				(type default)
			)
			(layer "F.SilkS")
		)
		(fp_line
			(start 1.524 -0.762)
			(end 1.524 0.762)
			(stroke
				(width 0.1524)
				(type default)
			)
			(layer "F.SilkS")
		)
		(fp_line
			(start -1.1049 0.724916)
			(end 1.1049 0.724916)
			(stroke
				(width 0.1)
				(type default)
			)
			(layer "F.Fab")
		)
		(fp_line
			(start 1.1049 0.724916)
			(end 1.1049 -0.724916)
			(stroke
				(width 0.1)
				(type default)
			)
			(layer "F.Fab")
		)
		(fp_line
			(start -1.1049 -0.724916)
			(end -1.1049 0.724916)
			(stroke
				(width 0.1)
				(type default)
			)
			(layer "F.Fab")
		)
		(fp_line
			(start 1.1049 -0.724916)
			(end -1.1049 -0.724916)
			(stroke
				(width 0.1)
				(type default)
			)
			(layer "F.Fab")
		)
		(pad "1" smd rect
			(at -0.889 0 90)
			(size 1.016 1.27)
			(layers "F.Cu" "F.Mask" "F.Paste")
			(net "P1V25_SERDES_VDDPLL_PEX3_C5")
		)
		(pad "2" smd rect
			(at 0.889 0 90)
			(size 1.016 1.27)
			(layers "F.Cu" "F.Mask" "F.Paste")
			(net "GND")
		)
		(zone
			(layer "F.Cu")
			(hatch none 0.5)
			(connect_pads
				(clearance 0)
			)
			(min_thickness 0.25)
			(keepout
				(tracks not_allowed)
				(vias allowed)
				(pads allowed)
				(copperpour not_allowed)
				(footprints allowed)
			)
			(placement
				(enabled no)
				(sheetname "")
			)
			(fill
				(thermal_gap 0.5)
				(thermal_bridge_width 0.5)
				(island_removal_mode 0)
			)
			(polygon
				(pts
					(xy 460.752698 -254.675132) (xy 459.302866 -254.675132) (xy 459.302866 -254.014732) (xy 460.752698 -254.014732)
				)
			)
		)
	)
	(footprint ""
		(layer "F.Cu")
		(at 115.720368 -320.820034 90)
		(property "Reference" "C4216"
			(at 0 0 90)
			(layer "F.SilkS")
			(hide yes)
			(effects
				(font
					(size 1.27 1.27)
				)
			)
		)
		(property "Value" ""
			(at 0 0 90)
			(layer "F.Fab")
			(effects
				(font
					(size 1.27 1.27)
				)
			)
		)
		(duplicate_pad_numbers_are_jumpers no)
		(fp_line
			(start 1.2954 -0.5842)
			(end 1.2954 0.5842)
			(stroke
				(width 0.1524)
				(type default)
			)
			(layer "F.SilkS")
		)
		(fp_line
			(start -1.2954 -0.5842)
			(end 1.2954 -0.5842)
			(stroke
				(width 0.1524)
				(type default)
			)
			(layer "F.SilkS")
		)
		(fp_line
			(start 1.2954 0.5842)
			(end -1.2954 0.5842)
			(stroke
				(width 0.1524)
				(type default)
			)
			(layer "F.SilkS")
		)
		(fp_line
			(start -1.2954 0.5842)
			(end -1.2954 -0.5842)
			(stroke
				(width 0.1524)
				(type default)
			)
			(layer "F.SilkS")
		)
		(fp_line
			(start 0.8636 -0.4572)
			(end 0.8636 -0.4064)
			(stroke
				(width 0.1)
				(type default)
			)
			(layer "F.Fab")
		)
		(fp_line
			(start -0.8636 -0.4572)
			(end 0.8636 -0.4572)
			(stroke
				(width 0.1)
				(type default)
			)
			(layer "F.Fab")
		)
		(fp_line
			(start 1.1938 -0.4064)
			(end 1.1938 0.4064)
			(stroke
				(width 0.1)
				(type default)
			)
			(layer "F.Fab")
		)
		(fp_line
			(start 0.8636 -0.4064)
			(end 1.1938 -0.4064)
			(stroke
				(width 0.1)
				(type default)
			)
			(layer "F.Fab")
		)
		(fp_line
			(start -0.8636 -0.4064)
			(end -0.8636 -0.4572)
			(stroke
				(width 0.1)
				(type default)
			)
			(layer "F.Fab")
		)
		(fp_line
			(start -1.1938 -0.4064)
			(end -0.8636 -0.4064)
			(stroke
				(width 0.1)
				(type default)
			)
			(layer "F.Fab")
		)
		(fp_line
			(start 1.1938 0.4064)
			(end 0.8636 0.4064)
			(stroke
				(width 0.1)
				(type default)
			)
			(layer "F.Fab")
		)
		(fp_line
			(start 0.8636 0.4064)
			(end 0.8636 0.4572)
			(stroke
				(width 0.1)
				(type default)
			)
			(layer "F.Fab")
		)
		(fp_line
			(start -0.8636 0.4064)
			(end -1.1938 0.4064)
			(stroke
				(width 0.1)
				(type default)
			)
			(layer "F.Fab")
		)
		(fp_line
			(start -1.1938 0.4064)
			(end -1.1938 -0.4064)
			(stroke
				(width 0.1)
				(type default)
			)
			(layer "F.Fab")
		)
		(fp_line
			(start 0.8636 0.4572)
			(end -0.8636 0.4572)
			(stroke
				(width 0.1)
				(type default)
			)
			(layer "F.Fab")
		)
		(fp_line
			(start -0.8636 0.4572)
			(end -0.8636 0.4064)
			(stroke
				(width 0.1)
				(type default)
			)
			(layer "F.Fab")
		)
		(pad "1" smd rect
			(at -0.7366 0)
			(size 0.7112 0.8128)
			(layers "F.Cu" "F.Mask" "F.Paste")
			(net "P0V8_SERDES_VDDA_PEX0_C10")
		)
		(pad "2" smd rect
			(at 0.7366 0)
			(size 0.7112 0.8128)
			(layers "F.Cu" "F.Mask" "F.Paste")
			(net "GND")
		)
	)
	(footprint ""
		(layer "F.Cu")
		(at 86.210902 -61.386974)
		(property "Reference" "R4495"
			(at 0 0 0)
			(layer "F.SilkS")
			(hide yes)
			(effects
				(font
					(size 1.27 1.27)
				)
			)
		)
		(property "Value" ""
			(at 0 0 0)
			(layer "F.Fab")
			(effects
				(font
					(size 1.27 1.27)
				)
			)
		)
		(duplicate_pad_numbers_are_jumpers no)
		(fp_line
			(start -0.7874 -0.4064)
			(end 0.7874 -0.4064)
			(stroke
				(width 0.1524)
				(type default)
			)
			(layer "F.SilkS")
		)
		(fp_line
			(start -0.7874 0.4064)
			(end -0.7874 -0.4064)
			(stroke
				(width 0.1524)
				(type default)
			)
			(layer "F.SilkS")
		)
		(fp_line
			(start 0.7874 -0.4064)
			(end 0.7874 0.4064)
			(stroke
				(width 0.1524)
				(type default)
			)
			(layer "F.SilkS")
		)
		(fp_line
			(start 0.7874 0.4064)
			(end -0.7874 0.4064)
			(stroke
				(width 0.1524)
				(type default)
			)
			(layer "F.SilkS")
		)
		(fp_line
			(start -0.67945 -0.305054)
			(end -0.12065 -0.305054)
			(stroke
				(width 0.1)
				(type default)
			)
			(layer "F.Fab")
		)
		(fp_line
			(start -0.67945 0.3048)
			(end -0.67945 -0.305054)
			(stroke
				(width 0.1)
				(type default)
			)
			(layer "F.Fab")
		)
		(fp_line
			(start -0.12065 -0.305054)
			(end -0.12065 -0.2794)
			(stroke
				(width 0.1)
				(type default)
			)
			(layer "F.Fab")
		)
		(fp_line
			(start -0.12065 -0.2794)
			(end 0.12065 -0.2794)
			(stroke
				(width 0.1)
				(type default)
			)
			(layer "F.Fab")
		)
		(fp_line
			(start -0.12065 0.2794)
			(end -0.12065 0.3048)
			(stroke
				(width 0.1)
				(type default)
			)
			(layer "F.Fab")
		)
		(fp_line
			(start -0.12065 0.3048)
			(end -0.67945 0.3048)
			(stroke
				(width 0.1)
				(type default)
			)
			(layer "F.Fab")
		)
		(fp_line
			(start 0.120396 0.2794)
			(end -0.12065 0.2794)
			(stroke
				(width 0.1)
				(type default)
			)
			(layer "F.Fab")
		)
		(fp_line
			(start 0.120396 0.3048)
			(end 0.120396 0.2794)
			(stroke
				(width 0.1)
				(type default)
			)
			(layer "F.Fab")
		)
		(fp_line
			(start 0.12065 -0.3048)
			(end 0.67945 -0.3048)
			(stroke
				(width 0.1)
				(type default)
			)
			(layer "F.Fab")
		)
		(fp_line
			(start 0.12065 -0.2794)
			(end 0.12065 -0.3048)
			(stroke
				(width 0.1)
				(type default)
			)
			(layer "F.Fab")
		)
		(fp_line
			(start 0.67945 -0.3048)
			(end 0.67945 0.3048)
			(stroke
				(width 0.1)
				(type default)
			)
			(layer "F.Fab")
		)
		(fp_line
			(start 0.67945 0.3048)
			(end 0.120396 0.3048)
			(stroke
				(width 0.1)
				(type default)
			)
			(layer "F.Fab")
		)
		(pad "1" smd circle
			(at -0.40005 0)
			(size 0 0)
			(layers "F.Cu" "F.Mask" "F.Paste")
			(net "PWRGD_P3V3_SSD3")
		)
		(pad "2" smd circle
			(at 0.40005 0)
			(size 0 0)
			(layers "F.Cu" "F.Mask" "F.Paste")
			(net "PWRGD_P3V3_SSD3_R")
		)
	)
	(footprint ""
		(layer "F.Cu")
		(at 458.219048 -254.344932 -90)
		(property "Reference" "C4398"
			(at 0 0 270)
			(layer "F.SilkS")
			(hide yes)
			(effects
				(font
					(size 1.27 1.27)
				)
			)
		)
		(property "Value" ""
			(at 0 0 270)
			(layer "F.Fab")
			(effects
				(font
					(size 1.27 1.27)
				)
			)
		)
		(duplicate_pad_numbers_are_jumpers no)
		(fp_line
			(start -1.524 0.762)
			(end -1.524 -0.762)
			(stroke
				(width 0.1524)
				(type default)
			)
			(layer "F.SilkS")
		)
		(fp_line
			(start 1.524 0.762)
			(end -1.524 0.762)
			(stroke
				(width 0.1524)
				(type default)
			)
			(layer "F.SilkS")
		)
		(fp_line
			(start -1.524 -0.762)
			(end 1.524 -0.762)
			(stroke
				(width 0.1524)
				(type default)
			)
			(layer "F.SilkS")
		)
		(fp_line
			(start 1.524 -0.762)
			(end 1.524 0.762)
			(stroke
				(width 0.1524)
				(type default)
			)
			(layer "F.SilkS")
		)
		(fp_line
			(start -1.1049 0.724916)
			(end 1.1049 0.724916)
			(stroke
				(width 0.1)
				(type default)
			)
			(layer "F.Fab")
		)
		(fp_line
			(start 1.1049 0.724916)
			(end 1.1049 -0.724916)
			(stroke
				(width 0.1)
				(type default)
			)
			(layer "F.Fab")
		)
		(fp_line
			(start -1.1049 -0.724916)
			(end -1.1049 0.724916)
			(stroke
				(width 0.1)
				(type default)
			)
			(layer "F.Fab")
		)
		(fp_line
			(start 1.1049 -0.724916)
			(end -1.1049 -0.724916)
			(stroke
				(width 0.1)
				(type default)
			)
			(layer "F.Fab")
		)
		(pad "1" smd rect
			(at -0.889 0 90)
			(size 1.016 1.27)
			(layers "F.Cu" "F.Mask" "F.Paste")
			(net "P1V25_SERDES_VDDPLL_PEX3_C4")
		)
		(pad "2" smd rect
			(at 0.889 0 90)
			(size 1.016 1.27)
			(layers "F.Cu" "F.Mask" "F.Paste")
			(net "GND")
		)
		(zone
			(layer "F.Cu")
			(hatch none 0.5)
			(connect_pads
				(clearance 0)
			)
			(min_thickness 0.25)
			(keepout
				(tracks not_allowed)
				(vias allowed)
				(pads allowed)
				(copperpour not_allowed)
				(footprints allowed)
			)
			(placement
				(enabled no)
				(sheetname "")
			)
			(fill
				(thermal_gap 0.5)
				(thermal_bridge_width 0.5)
				(island_removal_mode 0)
			)
			(polygon
				(pts
					(xy 458.943964 -254.675132) (xy 457.494132 -254.675132) (xy 457.494132 -254.014732) (xy 458.943964 -254.014732)
				)
			)
		)
	)
	(footprint ""
		(layer "F.Cu")
		(at 313.075066 -63.086234)
		(property "Reference" "R6009"
			(at 0 0 0)
			(layer "F.SilkS")
			(hide yes)
			(effects
				(font
					(size 1.27 1.27)
				)
			)
		)
		(property "Value" ""
			(at 0 0 0)
			(layer "F.Fab")
			(effects
				(font
					(size 1.27 1.27)
				)
			)
		)
		(duplicate_pad_numbers_are_jumpers no)
		(fp_line
			(start -0.7874 -0.4064)
			(end 0.7874 -0.4064)
			(stroke
				(width 0.1524)
				(type default)
			)
			(layer "F.SilkS")
		)
		(fp_line
			(start -0.7874 0.4064)
			(end -0.7874 -0.4064)
			(stroke
				(width 0.1524)
				(type default)
			)
			(layer "F.SilkS")
		)
		(fp_line
			(start 0.7874 -0.4064)
			(end 0.7874 0.4064)
			(stroke
				(width 0.1524)
				(type default)
			)
			(layer "F.SilkS")
		)
		(fp_line
			(start 0.7874 0.4064)
			(end -0.7874 0.4064)
			(stroke
				(width 0.1524)
				(type default)
			)
			(layer "F.SilkS")
		)
		(fp_line
			(start -0.67945 -0.305054)
			(end -0.12065 -0.305054)
			(stroke
				(width 0.1)
				(type default)
			)
			(layer "F.Fab")
		)
		(fp_line
			(start -0.67945 0.3048)
			(end -0.67945 -0.305054)
			(stroke
				(width 0.1)
				(type default)
			)
			(layer "F.Fab")
		)
		(fp_line
			(start -0.12065 -0.305054)
			(end -0.12065 -0.2794)
			(stroke
				(width 0.1)
				(type default)
			)
			(layer "F.Fab")
		)
		(fp_line
			(start -0.12065 -0.2794)
			(end 0.12065 -0.2794)
			(stroke
				(width 0.1)
				(type default)
			)
			(layer "F.Fab")
		)
		(fp_line
			(start -0.12065 0.2794)
			(end -0.12065 0.3048)
			(stroke
				(width 0.1)
				(type default)
			)
			(layer "F.Fab")
		)
		(fp_line
			(start -0.12065 0.3048)
			(end -0.67945 0.3048)
			(stroke
				(width 0.1)
				(type default)
			)
			(layer "F.Fab")
		)
		(fp_line
			(start 0.120396 0.2794)
			(end -0.12065 0.2794)
			(stroke
				(width 0.1)
				(type default)
			)
			(layer "F.Fab")
		)
		(fp_line
			(start 0.120396 0.3048)
			(end 0.120396 0.2794)
			(stroke
				(width 0.1)
				(type default)
			)
			(layer "F.Fab")
		)
		(fp_line
			(start 0.12065 -0.3048)
			(end 0.67945 -0.3048)
			(stroke
				(width 0.1)
				(type default)
			)
			(layer "F.Fab")
		)
		(fp_line
			(start 0.12065 -0.2794)
			(end 0.12065 -0.3048)
			(stroke
				(width 0.1)
				(type default)
			)
			(layer "F.Fab")
		)
		(fp_line
			(start 0.67945 -0.3048)
			(end 0.67945 0.3048)
			(stroke
				(width 0.1)
				(type default)
			)
			(layer "F.Fab")
		)
		(fp_line
			(start 0.67945 0.3048)
			(end 0.120396 0.3048)
			(stroke
				(width 0.1)
				(type default)
			)
			(layer "F.Fab")
		)
		(pad "1" smd circle
			(at -0.40005 0)
			(size 0 0)
			(layers "F.Cu" "F.Mask" "F.Paste")
			(net "P12V_SSD11_R")
		)
		(pad "2" smd circle
			(at 0.40005 0)
			(size 0 0)
			(layers "F.Cu" "F.Mask" "F.Paste")
			(net "P12V_SSD11_PG_G1")
		)
	)
	(footprint ""
		(layer "F.Cu")
		(at 206.793592 -350.312482 -90)
		(property "Reference" "C3869"
			(at 0 0 270)
			(layer "F.SilkS")
			(hide yes)
			(effects
				(font
					(size 1.27 1.27)
				)
			)
		)
		(property "Value" ""
			(at 0 0 270)
			(layer "F.Fab")
			(effects
				(font
					(size 1.27 1.27)
				)
			)
		)
		(duplicate_pad_numbers_are_jumpers no)
		(fp_line
			(start -0.7874 0.4064)
			(end -0.7874 -0.4064)
			(stroke
				(width 0.1524)
				(type default)
			)
			(layer "F.SilkS")
		)
		(fp_line
			(start 0.7874 0.4064)
			(end -0.7874 0.4064)
			(stroke
				(width 0.1524)
				(type default)
			)
			(layer "F.SilkS")
		)
		(fp_line
			(start -0.7874 -0.4064)
			(end 0.7874 -0.4064)
			(stroke
				(width 0.1524)
				(type default)
			)
			(layer "F.SilkS")
		)
		(fp_line
			(start 0.7874 -0.4064)
			(end 0.7874 0.4064)
			(stroke
				(width 0.1524)
				(type default)
			)
			(layer "F.SilkS")
		)
		(fp_line
			(start -0.67945 0.3048)
			(end -0.67945 -0.305054)
			(stroke
				(width 0.1)
				(type default)
			)
			(layer "F.Fab")
		)
		(fp_line
			(start -0.12065 0.3048)
			(end -0.67945 0.3048)
			(stroke
				(width 0.1)
				(type default)
			)
			(layer "F.Fab")
		)
		(fp_line
			(start 0.120396 0.3048)
			(end 0.120396 0.2794)
			(stroke
				(width 0.1)
				(type default)
			)
			(layer "F.Fab")
		)
		(fp_line
			(start 0.67945 0.3048)
			(end 0.120396 0.3048)
			(stroke
				(width 0.1)
				(type default)
			)
			(layer "F.Fab")
		)
		(fp_line
			(start -0.12065 0.2794)
			(end -0.12065 0.3048)
			(stroke
				(width 0.1)
				(type default)
			)
			(layer "F.Fab")
		)
		(fp_line
			(start 0.120396 0.2794)
			(end -0.12065 0.2794)
			(stroke
				(width 0.1)
				(type default)
			)
			(layer "F.Fab")
		)
		(fp_line
			(start -0.12065 -0.2794)
			(end 0.12065 -0.2794)
			(stroke
				(width 0.1)
				(type default)
			)
			(layer "F.Fab")
		)
		(fp_line
			(start 0.12065 -0.2794)
			(end 0.12065 -0.3048)
			(stroke
				(width 0.1)
				(type default)
			)
			(layer "F.Fab")
		)
		(fp_line
			(start 0.12065 -0.3048)
			(end 0.67945 -0.3048)
			(stroke
				(width 0.1)
				(type default)
			)
			(layer "F.Fab")
		)
		(fp_line
			(start 0.67945 -0.3048)
			(end 0.67945 0.3048)
			(stroke
				(width 0.1)
				(type default)
			)
			(layer "F.Fab")
		)
		(fp_line
			(start -0.67945 -0.305054)
			(end -0.12065 -0.305054)
			(stroke
				(width 0.1)
				(type default)
			)
			(layer "F.Fab")
		)
		(fp_line
			(start -0.12065 -0.305054)
			(end -0.12065 -0.2794)
			(stroke
				(width 0.1)
				(type default)
			)
			(layer "F.Fab")
		)
		(pad "1" smd circle
			(at -0.40005 0 270)
			(size 0 0)
			(layers "F.Cu" "F.Mask" "F.Paste")
			(net "P3V3_AUX")
		)
		(pad "2" smd circle
			(at 0.40005 0 270)
			(size 0 0)
			(layers "F.Cu" "F.Mask" "F.Paste")
			(net "GND")
		)
	)
	(footprint ""
		(layer "F.Cu")
		(at 326.667368 -112.903508 90)
		(property "Reference" "PC805"
			(at 0 0 90)
			(layer "F.SilkS")
			(hide yes)
			(effects
				(font
					(size 1.27 1.27)
				)
			)
		)
		(property "Value" ""
			(at 0 0 90)
			(layer "F.Fab")
			(effects
				(font
					(size 1.27 1.27)
				)
			)
		)
		(duplicate_pad_numbers_are_jumpers no)
		(fp_line
			(start 1.524 -0.762)
			(end 1.524 0.762)
			(stroke
				(width 0.1524)
				(type default)
			)
			(layer "F.SilkS")
		)
		(fp_line
			(start -1.524 -0.762)
			(end 1.524 -0.762)
			(stroke
				(width 0.1524)
				(type default)
			)
			(layer "F.SilkS")
		)
		(fp_line
			(start 1.524 0.762)
			(end -1.524 0.762)
			(stroke
				(width 0.1524)
				(type default)
			)
			(layer "F.SilkS")
		)
		(fp_line
			(start -1.524 0.762)
			(end -1.524 -0.762)
			(stroke
				(width 0.1524)
				(type default)
			)
			(layer "F.SilkS")
		)
		(fp_line
			(start 1.1049 -0.724916)
			(end -1.1049 -0.724916)
			(stroke
				(width 0.1)
				(type default)
			)
			(layer "F.Fab")
		)
		(fp_line
			(start -1.1049 -0.724916)
			(end -1.1049 0.724916)
			(stroke
				(width 0.1)
				(type default)
			)
			(layer "F.Fab")
		)
		(fp_line
			(start 1.1049 0.724916)
			(end 1.1049 -0.724916)
			(stroke
				(width 0.1)
				(type default)
			)
			(layer "F.Fab")
		)
		(fp_line
			(start -1.1049 0.724916)
			(end 1.1049 0.724916)
			(stroke
				(width 0.1)
				(type default)
			)
			(layer "F.Fab")
		)
		(pad "1" smd rect
			(at -0.889 0 270)
			(size 1.016 1.27)
			(layers "F.Cu" "F.Mask" "F.Paste")
			(net "P12V_NIC5_R")
		)
		(pad "2" smd rect
			(at 0.889 0 270)
			(size 1.016 1.27)
			(layers "F.Cu" "F.Mask" "F.Paste")
			(net "GND")
		)
	)
	(footprint ""
		(layer "F.Cu")
		(at 213.806024 18.035524)
		(property "Reference" "DE01F_2"
			(at -3.6068 -2.962148 0)
			(unlocked yes)
			(layer "F.SilkS")
			(effects
				(font
					(size 0.7874 0.5842)
					(thickness 0.1524)
				)
				(justify left)
			)
		)
		(property "Value" ""
			(at 0 0 0)
			(layer "F.Fab")
			(effects
				(font
					(size 1.27 1.27)
				)
			)
		)
		(duplicate_pad_numbers_are_jumpers no)
		(pad "" np_thru_hole circle
			(at -2.8829 -1.27 270)
			(size 1.0414 1.0414)
			(drill 1.0414)
			(layers "*.Cu" "*.Mask")
			(clearance 0.381)
			(thermal_gap 0.381)
		)
		(pad "" np_thru_hole circle
			(at -2.8829 1.27 270)
			(size 1.0414 1.0414)
			(drill 1.0414)
			(layers "*.Cu" "*.Mask")
			(clearance 0.381)
			(thermal_gap 0.381)
		)
		(pad "" np_thru_hole circle
			(at 3.4671 -1.27 270)
			(size 1.0414 1.0414)
			(drill 1.0414)
			(layers "*.Cu" "*.Mask")
			(clearance 0.381)
			(thermal_gap 0.381)
		)
		(pad "" np_thru_hole circle
			(at 3.4671 1.27 270)
			(size 1.0414 1.0414)
			(drill 1.0414)
			(layers "*.Cu" "*.Mask")
			(clearance 0.381)
			(thermal_gap 0.381)
		)
		(pad "1" smd rect
			(at 0.8255 -0.249936 270)
			(size 0.3048 0.508)
			(layers "F.Cu" "F.Mask" "F.Paste")
			(net "85_5INCH_TOP_DN")
		)
		(pad "2" smd rect
			(at 0.8255 0.249936 270)
			(size 0.3048 0.508)
			(layers "F.Cu" "F.Mask" "F.Paste")
			(net "85_5INCH_TOP_DP")
		)
		(pad "3" smd circle
			(at 0 0)
			(size 0 0)
			(layers "F.Cu" "F.Mask" "F.Paste")
			(net "COUPON_GND2")
		)
		(zone
			(layer "F.Cu")
			(hatch none 0.5)
			(connect_pads
				(clearance 0)
			)
			(min_thickness 0.25)
			(keepout
				(tracks not_allowed)
				(vias allowed)
				(pads allowed)
				(copperpour not_allowed)
				(footprints allowed)
			)
			(placement
				(enabled no)
				(sheetname "")
			)
			(fill
				(thermal_gap 0.5)
				(thermal_bridge_width 0.5)
				(island_removal_mode 0)
			)
			(polygon
				(pts
					(xy 214.923624 17.486884) (xy 214.923624 17.582388) (xy 214.326724 17.582388) (xy 214.326724 17.988788)
					(xy 214.923624 17.988788) (xy 214.923624 18.08226) (xy 214.326724 18.08226) (xy 214.326724 18.48866)
					(xy 214.923624 18.48866) (xy 214.923624 18.584164) (xy 214.225124 18.584164) (xy 214.225124 17.486884)
				)
			)
		)
		(zone
			(layers "F.Cu" "B.Cu" "In1.Cu" "In2.Cu" "In3.Cu" "In4.Cu" "In5.Cu" "In6.Cu"
				"In7.Cu" "In8.Cu" "In9.Cu" "In10.Cu" "In11.Cu" "In12.Cu" "In13.Cu" "In14.Cu"
				"In15.Cu" "In16.Cu"
			)
			(hatch none 0.5)
			(connect_pads
				(clearance 0)
			)
			(min_thickness 0.25)
			(keepout
				(tracks not_allowed)
				(vias allowed)
				(pads allowed)
				(copperpour not_allowed)
				(footprints allowed)
			)
			(placement
				(enabled no)
				(sheetname "")
			)
			(fill
				(thermal_gap 0.5)
				(thermal_bridge_width 0.5)
				(island_removal_mode 0)
			)
			(polygon
				(pts
					(arc
						(start 211.850224 16.765524)
						(mid 209.996024 16.765524)
						(end 211.850224 16.765524)
					)
				)
			)
		)
		(zone
			(layers "F.Cu" "B.Cu" "In1.Cu" "In2.Cu" "In3.Cu" "In4.Cu" "In5.Cu" "In6.Cu"
				"In7.Cu" "In8.Cu" "In9.Cu" "In10.Cu" "In11.Cu" "In12.Cu" "In13.Cu" "In14.Cu"
				"In15.Cu" "In16.Cu"
			)
			(hatch none 0.5)
			(connect_pads
				(clearance 0)
			)
			(min_thickness 0.25)
			(keepout
				(tracks not_allowed)
				(vias allowed)
				(pads allowed)
				(copperpour not_allowed)
				(footprints allowed)
			)
			(placement
				(enabled no)
				(sheetname "")
			)
			(fill
				(thermal_gap 0.5)
				(thermal_bridge_width 0.5)
				(island_removal_mode 0)
			)
			(polygon
				(pts
					(arc
						(start 211.850224 19.305524)
						(mid 209.996024 19.305524)
						(end 211.850224 19.305524)
					)
				)
			)
		)
		(zone
			(layers "F.Cu" "B.Cu" "In1.Cu" "In2.Cu" "In3.Cu" "In4.Cu" "In5.Cu" "In6.Cu"
				"In7.Cu" "In8.Cu" "In9.Cu" "In10.Cu" "In11.Cu" "In12.Cu" "In13.Cu" "In14.Cu"
				"In15.Cu" "In16.Cu"
			)
			(hatch none 0.5)
			(connect_pads
				(clearance 0)
			)
			(min_thickness 0.25)
			(keepout
				(tracks not_allowed)
				(vias allowed)
				(pads allowed)
				(copperpour not_allowed)
				(footprints allowed)
			)
			(placement
				(enabled no)
				(sheetname "")
			)
			(fill
				(thermal_gap 0.5)
				(thermal_bridge_width 0.5)
				(island_removal_mode 0)
			)
			(polygon
				(pts
					(arc
						(start 218.200224 16.765524)
						(mid 216.346024 16.765524)
						(end 218.200224 16.765524)
					)
				)
			)
		)
		(zone
			(layers "F.Cu" "B.Cu" "In1.Cu" "In2.Cu" "In3.Cu" "In4.Cu" "In5.Cu" "In6.Cu"
				"In7.Cu" "In8.Cu" "In9.Cu" "In10.Cu" "In11.Cu" "In12.Cu" "In13.Cu" "In14.Cu"
				"In15.Cu" "In16.Cu"
			)
			(hatch none 0.5)
			(connect_pads
				(clearance 0)
			)
			(min_thickness 0.25)
			(keepout
				(tracks not_allowed)
				(vias allowed)
				(pads allowed)
				(copperpour not_allowed)
				(footprints allowed)
			)
			(placement
				(enabled no)
				(sheetname "")
			)
			(fill
				(thermal_gap 0.5)
				(thermal_bridge_width 0.5)
				(island_removal_mode 0)
			)
			(polygon
				(pts
					(arc
						(start 218.200224 19.305524)
						(mid 216.346024 19.305524)
						(end 218.200224 19.305524)
					)
				)
			)
		)
	)
	(footprint ""
		(layer "F.Cu")
		(at 419.189408 -230.956866 180)
		(property "Reference" "R6617"
			(at 0 0 180)
			(layer "F.SilkS")
			(hide yes)
			(effects
				(font
					(size 1.27 1.27)
				)
			)
		)
		(property "Value" ""
			(at 0 0 180)
			(layer "F.Fab")
			(effects
				(font
					(size 1.27 1.27)
				)
			)
		)
		(duplicate_pad_numbers_are_jumpers no)
		(fp_line
			(start 0.7874 0.4064)
			(end -0.7874 0.4064)
			(stroke
				(width 0.1524)
				(type default)
			)
			(layer "F.SilkS")
		)
		(fp_line
			(start 0.7874 -0.4064)
			(end 0.7874 0.4064)
			(stroke
				(width 0.1524)
				(type default)
			)
			(layer "F.SilkS")
		)
		(fp_line
			(start -0.7874 0.4064)
			(end -0.7874 -0.4064)
			(stroke
				(width 0.1524)
				(type default)
			)
			(layer "F.SilkS")
		)
		(fp_line
			(start -0.7874 -0.4064)
			(end 0.7874 -0.4064)
			(stroke
				(width 0.1524)
				(type default)
			)
			(layer "F.SilkS")
		)
		(fp_line
			(start 0.67945 0.3048)
			(end 0.120396 0.3048)
			(stroke
				(width 0.1)
				(type default)
			)
			(layer "F.Fab")
		)
		(fp_line
			(start 0.67945 -0.3048)
			(end 0.67945 0.3048)
			(stroke
				(width 0.1)
				(type default)
			)
			(layer "F.Fab")
		)
		(fp_line
			(start 0.12065 -0.2794)
			(end 0.12065 -0.3048)
			(stroke
				(width 0.1)
				(type default)
			)
			(layer "F.Fab")
		)
		(fp_line
			(start 0.12065 -0.3048)
			(end 0.67945 -0.3048)
			(stroke
				(width 0.1)
				(type default)
			)
			(layer "F.Fab")
		)
		(fp_line
			(start 0.120396 0.3048)
			(end 0.120396 0.2794)
			(stroke
				(width 0.1)
				(type default)
			)
			(layer "F.Fab")
		)
		(fp_line
			(start 0.120396 0.2794)
			(end -0.12065 0.2794)
			(stroke
				(width 0.1)
				(type default)
			)
			(layer "F.Fab")
		)
		(fp_line
			(start -0.12065 0.3048)
			(end -0.67945 0.3048)
			(stroke
				(width 0.1)
				(type default)
			)
			(layer "F.Fab")
		)
		(fp_line
			(start -0.12065 0.2794)
			(end -0.12065 0.3048)
			(stroke
				(width 0.1)
				(type default)
			)
			(layer "F.Fab")
		)
		(fp_line
			(start -0.12065 -0.2794)
			(end 0.12065 -0.2794)
			(stroke
				(width 0.1)
				(type default)
			)
			(layer "F.Fab")
		)
		(fp_line
			(start -0.12065 -0.305054)
			(end -0.12065 -0.2794)
			(stroke
				(width 0.1)
				(type default)
			)
			(layer "F.Fab")
		)
		(fp_line
			(start -0.67945 0.3048)
			(end -0.67945 -0.305054)
			(stroke
				(width 0.1)
				(type default)
			)
			(layer "F.Fab")
		)
		(fp_line
			(start -0.67945 -0.305054)
			(end -0.12065 -0.305054)
			(stroke
				(width 0.1)
				(type default)
			)
			(layer "F.Fab")
		)
		(pad "1" smd circle
			(at -0.40005 0 180)
			(size 0 0)
			(layers "F.Cu" "F.Mask" "F.Paste")
			(net "UART_PEX3_SDB_R_RX")
		)
		(pad "2" smd circle
			(at 0.40005 0 180)
			(size 0 0)
			(layers "F.Cu" "F.Mask" "F.Paste")
			(net "UART_PEX3_SDB_R1_RX")
		)
	)
	(footprint ""
		(layer "F.Cu")
		(at 199.001888 -32.849312 90)
		(property "Reference" "R5674"
			(at 0 0 90)
			(layer "F.SilkS")
			(hide yes)
			(effects
				(font
					(size 1.27 1.27)
				)
			)
		)
		(property "Value" ""
			(at 0 0 90)
			(layer "F.Fab")
			(effects
				(font
					(size 1.27 1.27)
				)
			)
		)
		(duplicate_pad_numbers_are_jumpers no)
		(fp_line
			(start 0.7874 -0.4064)
			(end 0.7874 0.4064)
			(stroke
				(width 0.1524)
				(type default)
			)
			(layer "F.SilkS")
		)
		(fp_line
			(start -0.7874 -0.4064)
			(end 0.7874 -0.4064)
			(stroke
				(width 0.1524)
				(type default)
			)
			(layer "F.SilkS")
		)
		(fp_line
			(start 0.7874 0.4064)
			(end -0.7874 0.4064)
			(stroke
				(width 0.1524)
				(type default)
			)
			(layer "F.SilkS")
		)
		(fp_line
			(start -0.7874 0.4064)
			(end -0.7874 -0.4064)
			(stroke
				(width 0.1524)
				(type default)
			)
			(layer "F.SilkS")
		)
		(fp_line
			(start -0.12065 -0.305054)
			(end -0.12065 -0.2794)
			(stroke
				(width 0.1)
				(type default)
			)
			(layer "F.Fab")
		)
		(fp_line
			(start -0.67945 -0.305054)
			(end -0.12065 -0.305054)
			(stroke
				(width 0.1)
				(type default)
			)
			(layer "F.Fab")
		)
		(fp_line
			(start 0.67945 -0.3048)
			(end 0.67945 0.3048)
			(stroke
				(width 0.1)
				(type default)
			)
			(layer "F.Fab")
		)
		(fp_line
			(start 0.12065 -0.3048)
			(end 0.67945 -0.3048)
			(stroke
				(width 0.1)
				(type default)
			)
			(layer "F.Fab")
		)
		(fp_line
			(start 0.12065 -0.2794)
			(end 0.12065 -0.3048)
			(stroke
				(width 0.1)
				(type default)
			)
			(layer "F.Fab")
		)
		(fp_line
			(start -0.12065 -0.2794)
			(end 0.12065 -0.2794)
			(stroke
				(width 0.1)
				(type default)
			)
			(layer "F.Fab")
		)
		(fp_line
			(start 0.120396 0.2794)
			(end -0.12065 0.2794)
			(stroke
				(width 0.1)
				(type default)
			)
			(layer "F.Fab")
		)
		(fp_line
			(start -0.12065 0.2794)
			(end -0.12065 0.3048)
			(stroke
				(width 0.1)
				(type default)
			)
			(layer "F.Fab")
		)
		(fp_line
			(start 0.67945 0.3048)
			(end 0.120396 0.3048)
			(stroke
				(width 0.1)
				(type default)
			)
			(layer "F.Fab")
		)
		(fp_line
			(start 0.120396 0.3048)
			(end 0.120396 0.2794)
			(stroke
				(width 0.1)
				(type default)
			)
			(layer "F.Fab")
		)
		(fp_line
			(start -0.12065 0.3048)
			(end -0.67945 0.3048)
			(stroke
				(width 0.1)
				(type default)
			)
			(layer "F.Fab")
		)
		(fp_line
			(start -0.67945 0.3048)
			(end -0.67945 -0.305054)
			(stroke
				(width 0.1)
				(type default)
			)
			(layer "F.Fab")
		)
		(pad "1" smd circle
			(at -0.40005 0 90)
			(size 0 0)
			(layers "F.Cu" "F.Mask" "F.Paste")
			(net "RST_SMB_SSD7_ISO_R_N")
		)
		(pad "2" smd circle
			(at 0.40005 0 90)
			(size 0 0)
			(layers "F.Cu" "F.Mask" "F.Paste")
			(net "RST_SMB_SSD7_ISO_N")
		)
	)
	(footprint ""
		(layer "F.Cu")
		(at 404.18004 -141.9352)
		(property "Reference" "R316"
			(at 0 0 0)
			(layer "F.SilkS")
			(hide yes)
			(effects
				(font
					(size 1.27 1.27)
				)
			)
		)
		(property "Value" ""
			(at 0 0 0)
			(layer "F.Fab")
			(effects
				(font
					(size 1.27 1.27)
				)
			)
		)
		(duplicate_pad_numbers_are_jumpers no)
		(fp_line
			(start -0.7874 -0.4064)
			(end 0.7874 -0.4064)
			(stroke
				(width 0.1524)
				(type default)
			)
			(layer "F.SilkS")
		)
		(fp_line
			(start -0.7874 0.4064)
			(end -0.7874 -0.4064)
			(stroke
				(width 0.1524)
				(type default)
			)
			(layer "F.SilkS")
		)
		(fp_line
			(start 0.7874 -0.4064)
			(end 0.7874 0.4064)
			(stroke
				(width 0.1524)
				(type default)
			)
			(layer "F.SilkS")
		)
		(fp_line
			(start 0.7874 0.4064)
			(end -0.7874 0.4064)
			(stroke
				(width 0.1524)
				(type default)
			)
			(layer "F.SilkS")
		)
		(fp_line
			(start -0.67945 -0.305054)
			(end -0.12065 -0.305054)
			(stroke
				(width 0.1)
				(type default)
			)
			(layer "F.Fab")
		)
		(fp_line
			(start -0.67945 0.3048)
			(end -0.67945 -0.305054)
			(stroke
				(width 0.1)
				(type default)
			)
			(layer "F.Fab")
		)
		(fp_line
			(start -0.12065 -0.305054)
			(end -0.12065 -0.2794)
			(stroke
				(width 0.1)
				(type default)
			)
			(layer "F.Fab")
		)
		(fp_line
			(start -0.12065 -0.2794)
			(end 0.12065 -0.2794)
			(stroke
				(width 0.1)
				(type default)
			)
			(layer "F.Fab")
		)
		(fp_line
			(start -0.12065 0.2794)
			(end -0.12065 0.3048)
			(stroke
				(width 0.1)
				(type default)
			)
			(layer "F.Fab")
		)
		(fp_line
			(start -0.12065 0.3048)
			(end -0.67945 0.3048)
			(stroke
				(width 0.1)
				(type default)
			)
			(layer "F.Fab")
		)
		(fp_line
			(start 0.120396 0.2794)
			(end -0.12065 0.2794)
			(stroke
				(width 0.1)
				(type default)
			)
			(layer "F.Fab")
		)
		(fp_line
			(start 0.120396 0.3048)
			(end 0.120396 0.2794)
			(stroke
				(width 0.1)
				(type default)
			)
			(layer "F.Fab")
		)
		(fp_line
			(start 0.12065 -0.3048)
			(end 0.67945 -0.3048)
			(stroke
				(width 0.1)
				(type default)
			)
			(layer "F.Fab")
		)
		(fp_line
			(start 0.12065 -0.2794)
			(end 0.12065 -0.3048)
			(stroke
				(width 0.1)
				(type default)
			)
			(layer "F.Fab")
		)
		(fp_line
			(start 0.67945 -0.3048)
			(end 0.67945 0.3048)
			(stroke
				(width 0.1)
				(type default)
			)
			(layer "F.Fab")
		)
		(fp_line
			(start 0.67945 0.3048)
			(end 0.120396 0.3048)
			(stroke
				(width 0.1)
				(type default)
			)
			(layer "F.Fab")
		)
		(pad "1" smd circle
			(at -0.40005 0)
			(size 0 0)
			(layers "F.Cu" "F.Mask" "F.Paste")
			(net "SMB_NIC6_LS_SDA")
		)
		(pad "2" smd circle
			(at 0.40005 0)
			(size 0 0)
			(layers "F.Cu" "F.Mask" "F.Paste")
			(net "P3V3_NIC6")
		)
	)
	(footprint ""
		(layer "F.Cu")
		(at 145.697956 -197.2818)
		(property "Reference" "R6641"
			(at 0 0 0)
			(layer "F.SilkS")
			(hide yes)
			(effects
				(font
					(size 1.27 1.27)
				)
			)
		)
		(property "Value" ""
			(at 0 0 0)
			(layer "F.Fab")
			(effects
				(font
					(size 1.27 1.27)
				)
			)
		)
		(duplicate_pad_numbers_are_jumpers no)
		(fp_line
			(start -0.7874 -0.4064)
			(end 0.7874 -0.4064)
			(stroke
				(width 0.1524)
				(type default)
			)
			(layer "F.SilkS")
		)
		(fp_line
			(start -0.7874 0.4064)
			(end -0.7874 -0.4064)
			(stroke
				(width 0.1524)
				(type default)
			)
			(layer "F.SilkS")
		)
		(fp_line
			(start 0.7874 -0.4064)
			(end 0.7874 0.4064)
			(stroke
				(width 0.1524)
				(type default)
			)
			(layer "F.SilkS")
		)
		(fp_line
			(start 0.7874 0.4064)
			(end -0.7874 0.4064)
			(stroke
				(width 0.1524)
				(type default)
			)
			(layer "F.SilkS")
		)
		(fp_line
			(start -0.67945 -0.305054)
			(end -0.12065 -0.305054)
			(stroke
				(width 0.1)
				(type default)
			)
			(layer "F.Fab")
		)
		(fp_line
			(start -0.67945 0.3048)
			(end -0.67945 -0.305054)
			(stroke
				(width 0.1)
				(type default)
			)
			(layer "F.Fab")
		)
		(fp_line
			(start -0.12065 -0.305054)
			(end -0.12065 -0.2794)
			(stroke
				(width 0.1)
				(type default)
			)
			(layer "F.Fab")
		)
		(fp_line
			(start -0.12065 -0.2794)
			(end 0.12065 -0.2794)
			(stroke
				(width 0.1)
				(type default)
			)
			(layer "F.Fab")
		)
		(fp_line
			(start -0.12065 0.2794)
			(end -0.12065 0.3048)
			(stroke
				(width 0.1)
				(type default)
			)
			(layer "F.Fab")
		)
		(fp_line
			(start -0.12065 0.3048)
			(end -0.67945 0.3048)
			(stroke
				(width 0.1)
				(type default)
			)
			(layer "F.Fab")
		)
		(fp_line
			(start 0.120396 0.2794)
			(end -0.12065 0.2794)
			(stroke
				(width 0.1)
				(type default)
			)
			(layer "F.Fab")
		)
		(fp_line
			(start 0.120396 0.3048)
			(end 0.120396 0.2794)
			(stroke
				(width 0.1)
				(type default)
			)
			(layer "F.Fab")
		)
		(fp_line
			(start 0.12065 -0.3048)
			(end 0.67945 -0.3048)
			(stroke
				(width 0.1)
				(type default)
			)
			(layer "F.Fab")
		)
		(fp_line
			(start 0.12065 -0.2794)
			(end 0.12065 -0.3048)
			(stroke
				(width 0.1)
				(type default)
			)
			(layer "F.Fab")
		)
		(fp_line
			(start 0.67945 -0.3048)
			(end 0.67945 0.3048)
			(stroke
				(width 0.1)
				(type default)
			)
			(layer "F.Fab")
		)
		(fp_line
			(start 0.67945 0.3048)
			(end 0.120396 0.3048)
			(stroke
				(width 0.1)
				(type default)
			)
			(layer "F.Fab")
		)
		(pad "1" smd circle
			(at -0.40005 0)
			(size 0 0)
			(layers "F.Cu" "F.Mask" "F.Paste")
			(net "UART_PEX0_CLI_RX")
		)
		(pad "2" smd circle
			(at 0.40005 0)
			(size 0 0)
			(layers "F.Cu" "F.Mask" "F.Paste")
			(net "UART_PEX0_CLI_R_RX")
		)
	)
	(footprint ""
		(layer "F.Cu")
		(at 243.505228 -211.563712 90)
		(property "Reference" "R4893"
			(at 0 0 90)
			(layer "F.SilkS")
			(hide yes)
			(effects
				(font
					(size 1.27 1.27)
				)
			)
		)
		(property "Value" ""
			(at 0 0 90)
			(layer "F.Fab")
			(effects
				(font
					(size 1.27 1.27)
				)
			)
		)
		(duplicate_pad_numbers_are_jumpers no)
		(fp_line
			(start 0.7874 -0.4064)
			(end 0.7874 0.4064)
			(stroke
				(width 0.1524)
				(type default)
			)
			(layer "F.SilkS")
		)
		(fp_line
			(start -0.7874 -0.4064)
			(end 0.7874 -0.4064)
			(stroke
				(width 0.1524)
				(type default)
			)
			(layer "F.SilkS")
		)
		(fp_line
			(start 0.7874 0.4064)
			(end -0.7874 0.4064)
			(stroke
				(width 0.1524)
				(type default)
			)
			(layer "F.SilkS")
		)
		(fp_line
			(start -0.7874 0.4064)
			(end -0.7874 -0.4064)
			(stroke
				(width 0.1524)
				(type default)
			)
			(layer "F.SilkS")
		)
		(fp_line
			(start -0.12065 -0.305054)
			(end -0.12065 -0.2794)
			(stroke
				(width 0.1)
				(type default)
			)
			(layer "F.Fab")
		)
		(fp_line
			(start -0.67945 -0.305054)
			(end -0.12065 -0.305054)
			(stroke
				(width 0.1)
				(type default)
			)
			(layer "F.Fab")
		)
		(fp_line
			(start 0.67945 -0.3048)
			(end 0.67945 0.3048)
			(stroke
				(width 0.1)
				(type default)
			)
			(layer "F.Fab")
		)
		(fp_line
			(start 0.12065 -0.3048)
			(end 0.67945 -0.3048)
			(stroke
				(width 0.1)
				(type default)
			)
			(layer "F.Fab")
		)
		(fp_line
			(start 0.12065 -0.2794)
			(end 0.12065 -0.3048)
			(stroke
				(width 0.1)
				(type default)
			)
			(layer "F.Fab")
		)
		(fp_line
			(start -0.12065 -0.2794)
			(end 0.12065 -0.2794)
			(stroke
				(width 0.1)
				(type default)
			)
			(layer "F.Fab")
		)
		(fp_line
			(start 0.120396 0.2794)
			(end -0.12065 0.2794)
			(stroke
				(width 0.1)
				(type default)
			)
			(layer "F.Fab")
		)
		(fp_line
			(start -0.12065 0.2794)
			(end -0.12065 0.3048)
			(stroke
				(width 0.1)
				(type default)
			)
			(layer "F.Fab")
		)
		(fp_line
			(start 0.67945 0.3048)
			(end 0.120396 0.3048)
			(stroke
				(width 0.1)
				(type default)
			)
			(layer "F.Fab")
		)
		(fp_line
			(start 0.120396 0.3048)
			(end 0.120396 0.2794)
			(stroke
				(width 0.1)
				(type default)
			)
			(layer "F.Fab")
		)
		(fp_line
			(start -0.12065 0.3048)
			(end -0.67945 0.3048)
			(stroke
				(width 0.1)
				(type default)
			)
			(layer "F.Fab")
		)
		(fp_line
			(start -0.67945 0.3048)
			(end -0.67945 -0.305054)
			(stroke
				(width 0.1)
				(type default)
			)
			(layer "F.Fab")
		)
		(pad "1" smd circle
			(at -0.40005 0 90)
			(size 0 0)
			(layers "F.Cu" "F.Mask" "F.Paste")
			(net "JTAG_BIC_TDO_R")
		)
		(pad "2" smd circle
			(at 0.40005 0 90)
			(size 0 0)
			(layers "F.Cu" "F.Mask" "F.Paste")
			(net "JTAG_BIC_TDO_R1")
		)
	)
	(footprint ""
		(layer "F.Cu")
		(at 197.739508 -87.349076 -90)
		(property "Reference" "R198"
			(at 0 0 270)
			(layer "F.SilkS")
			(hide yes)
			(effects
				(font
					(size 1.27 1.27)
				)
			)
		)
		(property "Value" ""
			(at 0 0 270)
			(layer "F.Fab")
			(effects
				(font
					(size 1.27 1.27)
				)
			)
		)
		(duplicate_pad_numbers_are_jumpers no)
		(fp_line
			(start -0.7874 0.4064)
			(end -0.7874 -0.4064)
			(stroke
				(width 0.1524)
				(type default)
			)
			(layer "F.SilkS")
		)
		(fp_line
			(start 0.7874 0.4064)
			(end -0.7874 0.4064)
			(stroke
				(width 0.1524)
				(type default)
			)
			(layer "F.SilkS")
		)
		(fp_line
			(start -0.7874 -0.4064)
			(end 0.7874 -0.4064)
			(stroke
				(width 0.1524)
				(type default)
			)
			(layer "F.SilkS")
		)
		(fp_line
			(start 0.7874 -0.4064)
			(end 0.7874 0.4064)
			(stroke
				(width 0.1524)
				(type default)
			)
			(layer "F.SilkS")
		)
		(fp_line
			(start -0.67945 0.3048)
			(end -0.67945 -0.305054)
			(stroke
				(width 0.1)
				(type default)
			)
			(layer "F.Fab")
		)
		(fp_line
			(start -0.12065 0.3048)
			(end -0.67945 0.3048)
			(stroke
				(width 0.1)
				(type default)
			)
			(layer "F.Fab")
		)
		(fp_line
			(start 0.120396 0.3048)
			(end 0.120396 0.2794)
			(stroke
				(width 0.1)
				(type default)
			)
			(layer "F.Fab")
		)
		(fp_line
			(start 0.67945 0.3048)
			(end 0.120396 0.3048)
			(stroke
				(width 0.1)
				(type default)
			)
			(layer "F.Fab")
		)
		(fp_line
			(start -0.12065 0.2794)
			(end -0.12065 0.3048)
			(stroke
				(width 0.1)
				(type default)
			)
			(layer "F.Fab")
		)
		(fp_line
			(start 0.120396 0.2794)
			(end -0.12065 0.2794)
			(stroke
				(width 0.1)
				(type default)
			)
			(layer "F.Fab")
		)
		(fp_line
			(start -0.12065 -0.2794)
			(end 0.12065 -0.2794)
			(stroke
				(width 0.1)
				(type default)
			)
			(layer "F.Fab")
		)
		(fp_line
			(start 0.12065 -0.2794)
			(end 0.12065 -0.3048)
			(stroke
				(width 0.1)
				(type default)
			)
			(layer "F.Fab")
		)
		(fp_line
			(start 0.12065 -0.3048)
			(end 0.67945 -0.3048)
			(stroke
				(width 0.1)
				(type default)
			)
			(layer "F.Fab")
		)
		(fp_line
			(start 0.67945 -0.3048)
			(end 0.67945 0.3048)
			(stroke
				(width 0.1)
				(type default)
			)
			(layer "F.Fab")
		)
		(fp_line
			(start -0.67945 -0.305054)
			(end -0.12065 -0.305054)
			(stroke
				(width 0.1)
				(type default)
			)
			(layer "F.Fab")
		)
		(fp_line
			(start -0.12065 -0.305054)
			(end -0.12065 -0.2794)
			(stroke
				(width 0.1)
				(type default)
			)
			(layer "F.Fab")
		)
		(pad "1" smd circle
			(at -0.40005 0 270)
			(size 0 0)
			(layers "F.Cu" "F.Mask" "F.Paste")
			(net "RST_NIC3_PERST0_R_N")
		)
		(pad "2" smd circle
			(at 0.40005 0 270)
			(size 0 0)
			(layers "F.Cu" "F.Mask" "F.Paste")
			(net "RST_HP_NIC3_BUF_N")
		)
	)
	(footprint ""
		(layer "F.Cu")
		(at 264.611358 -286.844232 -90)
		(property "Reference" "R4584"
			(at 0 0 270)
			(layer "F.SilkS")
			(hide yes)
			(effects
				(font
					(size 1.27 1.27)
				)
			)
		)
		(property "Value" ""
			(at 0 0 270)
			(layer "F.Fab")
			(effects
				(font
					(size 1.27 1.27)
				)
			)
		)
		(duplicate_pad_numbers_are_jumpers no)
		(fp_line
			(start -0.7874 0.4064)
			(end -0.7874 -0.4064)
			(stroke
				(width 0.1524)
				(type default)
			)
			(layer "F.SilkS")
		)
		(fp_line
			(start 0.7874 0.4064)
			(end -0.7874 0.4064)
			(stroke
				(width 0.1524)
				(type default)
			)
			(layer "F.SilkS")
		)
		(fp_line
			(start -0.7874 -0.4064)
			(end 0.7874 -0.4064)
			(stroke
				(width 0.1524)
				(type default)
			)
			(layer "F.SilkS")
		)
		(fp_line
			(start 0.7874 -0.4064)
			(end 0.7874 0.4064)
			(stroke
				(width 0.1524)
				(type default)
			)
			(layer "F.SilkS")
		)
		(fp_line
			(start -0.67945 0.3048)
			(end -0.67945 -0.305054)
			(stroke
				(width 0.1)
				(type default)
			)
			(layer "F.Fab")
		)
		(fp_line
			(start -0.12065 0.3048)
			(end -0.67945 0.3048)
			(stroke
				(width 0.1)
				(type default)
			)
			(layer "F.Fab")
		)
		(fp_line
			(start 0.120396 0.3048)
			(end 0.120396 0.2794)
			(stroke
				(width 0.1)
				(type default)
			)
			(layer "F.Fab")
		)
		(fp_line
			(start 0.67945 0.3048)
			(end 0.120396 0.3048)
			(stroke
				(width 0.1)
				(type default)
			)
			(layer "F.Fab")
		)
		(fp_line
			(start -0.12065 0.2794)
			(end -0.12065 0.3048)
			(stroke
				(width 0.1)
				(type default)
			)
			(layer "F.Fab")
		)
		(fp_line
			(start 0.120396 0.2794)
			(end -0.12065 0.2794)
			(stroke
				(width 0.1)
				(type default)
			)
			(layer "F.Fab")
		)
		(fp_line
			(start -0.12065 -0.2794)
			(end 0.12065 -0.2794)
			(stroke
				(width 0.1)
				(type default)
			)
			(layer "F.Fab")
		)
		(fp_line
			(start 0.12065 -0.2794)
			(end 0.12065 -0.3048)
			(stroke
				(width 0.1)
				(type default)
			)
			(layer "F.Fab")
		)
		(fp_line
			(start 0.12065 -0.3048)
			(end 0.67945 -0.3048)
			(stroke
				(width 0.1)
				(type default)
			)
			(layer "F.Fab")
		)
		(fp_line
			(start 0.67945 -0.3048)
			(end 0.67945 0.3048)
			(stroke
				(width 0.1)
				(type default)
			)
			(layer "F.Fab")
		)
		(fp_line
			(start -0.67945 -0.305054)
			(end -0.12065 -0.305054)
			(stroke
				(width 0.1)
				(type default)
			)
			(layer "F.Fab")
		)
		(fp_line
			(start -0.12065 -0.305054)
			(end -0.12065 -0.2794)
			(stroke
				(width 0.1)
				(type default)
			)
			(layer "F.Fab")
		)
		(pad "1" smd circle
			(at -0.40005 0 270)
			(size 0 0)
			(layers "F.Cu" "F.Mask" "F.Paste")
			(net "PCEPLL6_VDDA18_PEX2")
		)
		(pad "2" smd circle
			(at 0.40005 0 270)
			(size 0 0)
			(layers "F.Cu" "F.Mask" "F.Paste")
			(net "PCEPLL6_VDDA18_PEX2_R")
		)
	)
	(footprint ""
		(layer "F.Cu")
		(at 352.232214 -155.321)
		(property "Reference" "R4821"
			(at 0 0 0)
			(layer "F.SilkS")
			(hide yes)
			(effects
				(font
					(size 1.27 1.27)
				)
			)
		)
		(property "Value" ""
			(at 0 0 0)
			(layer "F.Fab")
			(effects
				(font
					(size 1.27 1.27)
				)
			)
		)
		(duplicate_pad_numbers_are_jumpers no)
		(fp_line
			(start -0.7874 -0.4064)
			(end 0.7874 -0.4064)
			(stroke
				(width 0.1524)
				(type default)
			)
			(layer "F.SilkS")
		)
		(fp_line
			(start -0.7874 0.4064)
			(end -0.7874 -0.4064)
			(stroke
				(width 0.1524)
				(type default)
			)
			(layer "F.SilkS")
		)
		(fp_line
			(start 0.7874 -0.4064)
			(end 0.7874 0.4064)
			(stroke
				(width 0.1524)
				(type default)
			)
			(layer "F.SilkS")
		)
		(fp_line
			(start 0.7874 0.4064)
			(end -0.7874 0.4064)
			(stroke
				(width 0.1524)
				(type default)
			)
			(layer "F.SilkS")
		)
		(fp_line
			(start -0.67945 -0.305054)
			(end -0.12065 -0.305054)
			(stroke
				(width 0.1)
				(type default)
			)
			(layer "F.Fab")
		)
		(fp_line
			(start -0.67945 0.3048)
			(end -0.67945 -0.305054)
			(stroke
				(width 0.1)
				(type default)
			)
			(layer "F.Fab")
		)
		(fp_line
			(start -0.12065 -0.305054)
			(end -0.12065 -0.2794)
			(stroke
				(width 0.1)
				(type default)
			)
			(layer "F.Fab")
		)
		(fp_line
			(start -0.12065 -0.2794)
			(end 0.12065 -0.2794)
			(stroke
				(width 0.1)
				(type default)
			)
			(layer "F.Fab")
		)
		(fp_line
			(start -0.12065 0.2794)
			(end -0.12065 0.3048)
			(stroke
				(width 0.1)
				(type default)
			)
			(layer "F.Fab")
		)
		(fp_line
			(start -0.12065 0.3048)
			(end -0.67945 0.3048)
			(stroke
				(width 0.1)
				(type default)
			)
			(layer "F.Fab")
		)
		(fp_line
			(start 0.120396 0.2794)
			(end -0.12065 0.2794)
			(stroke
				(width 0.1)
				(type default)
			)
			(layer "F.Fab")
		)
		(fp_line
			(start 0.120396 0.3048)
			(end 0.120396 0.2794)
			(stroke
				(width 0.1)
				(type default)
			)
			(layer "F.Fab")
		)
		(fp_line
			(start 0.12065 -0.3048)
			(end 0.67945 -0.3048)
			(stroke
				(width 0.1)
				(type default)
			)
			(layer "F.Fab")
		)
		(fp_line
			(start 0.12065 -0.2794)
			(end 0.12065 -0.3048)
			(stroke
				(width 0.1)
				(type default)
			)
			(layer "F.Fab")
		)
		(fp_line
			(start 0.67945 -0.3048)
			(end 0.67945 0.3048)
			(stroke
				(width 0.1)
				(type default)
			)
			(layer "F.Fab")
		)
		(fp_line
			(start 0.67945 0.3048)
			(end 0.120396 0.3048)
			(stroke
				(width 0.1)
				(type default)
			)
			(layer "F.Fab")
		)
		(pad "1" smd circle
			(at -0.40005 0)
			(size 0 0)
			(layers "F.Cu" "F.Mask" "F.Paste")
			(net "NIC6_PEX_PWR_EN")
		)
		(pad "2" smd circle
			(at 0.40005 0)
			(size 0 0)
			(layers "F.Cu" "F.Mask" "F.Paste")
			(net "NIC6_PEX_PWR_EN_R")
		)
	)
	(footprint ""
		(layer "F.Cu")
		(at 213.319868 -210.174586)
		(property "Reference" "R5523"
			(at 0 0 0)
			(layer "F.SilkS")
			(hide yes)
			(effects
				(font
					(size 1.27 1.27)
				)
			)
		)
		(property "Value" ""
			(at 0 0 0)
			(layer "F.Fab")
			(effects
				(font
					(size 1.27 1.27)
				)
			)
		)
		(duplicate_pad_numbers_are_jumpers no)
		(fp_line
			(start -0.7874 -0.4064)
			(end 0.7874 -0.4064)
			(stroke
				(width 0.1524)
				(type default)
			)
			(layer "F.SilkS")
		)
		(fp_line
			(start -0.7874 0.4064)
			(end -0.7874 -0.4064)
			(stroke
				(width 0.1524)
				(type default)
			)
			(layer "F.SilkS")
		)
		(fp_line
			(start 0.7874 -0.4064)
			(end 0.7874 0.4064)
			(stroke
				(width 0.1524)
				(type default)
			)
			(layer "F.SilkS")
		)
		(fp_line
			(start 0.7874 0.4064)
			(end -0.7874 0.4064)
			(stroke
				(width 0.1524)
				(type default)
			)
			(layer "F.SilkS")
		)
		(fp_line
			(start -0.67945 -0.305054)
			(end -0.12065 -0.305054)
			(stroke
				(width 0.1)
				(type default)
			)
			(layer "F.Fab")
		)
		(fp_line
			(start -0.67945 0.3048)
			(end -0.67945 -0.305054)
			(stroke
				(width 0.1)
				(type default)
			)
			(layer "F.Fab")
		)
		(fp_line
			(start -0.12065 -0.305054)
			(end -0.12065 -0.2794)
			(stroke
				(width 0.1)
				(type default)
			)
			(layer "F.Fab")
		)
		(fp_line
			(start -0.12065 -0.2794)
			(end 0.12065 -0.2794)
			(stroke
				(width 0.1)
				(type default)
			)
			(layer "F.Fab")
		)
		(fp_line
			(start -0.12065 0.2794)
			(end -0.12065 0.3048)
			(stroke
				(width 0.1)
				(type default)
			)
			(layer "F.Fab")
		)
		(fp_line
			(start -0.12065 0.3048)
			(end -0.67945 0.3048)
			(stroke
				(width 0.1)
				(type default)
			)
			(layer "F.Fab")
		)
		(fp_line
			(start 0.120396 0.2794)
			(end -0.12065 0.2794)
			(stroke
				(width 0.1)
				(type default)
			)
			(layer "F.Fab")
		)
		(fp_line
			(start 0.120396 0.3048)
			(end 0.120396 0.2794)
			(stroke
				(width 0.1)
				(type default)
			)
			(layer "F.Fab")
		)
		(fp_line
			(start 0.12065 -0.3048)
			(end 0.67945 -0.3048)
			(stroke
				(width 0.1)
				(type default)
			)
			(layer "F.Fab")
		)
		(fp_line
			(start 0.12065 -0.2794)
			(end 0.12065 -0.3048)
			(stroke
				(width 0.1)
				(type default)
			)
			(layer "F.Fab")
		)
		(fp_line
			(start 0.67945 -0.3048)
			(end 0.67945 0.3048)
			(stroke
				(width 0.1)
				(type default)
			)
			(layer "F.Fab")
		)
		(fp_line
			(start 0.67945 0.3048)
			(end 0.120396 0.3048)
			(stroke
				(width 0.1)
				(type default)
			)
			(layer "F.Fab")
		)
		(pad "1" smd circle
			(at -0.40005 0)
			(size 0 0)
			(layers "F.Cu" "F.Mask" "F.Paste")
			(net "P3V3_AUX")
		)
		(pad "2" smd circle
			(at 0.40005 0)
			(size 0 0)
			(layers "F.Cu" "F.Mask" "F.Paste")
			(net "RST_SSD_LED_IOEXP_R_N")
		)
	)
	(footprint ""
		(layer "F.Cu")
		(at 131.370578 -190.358522 180)
		(property "Reference" "R6675"
			(at 0 0 180)
			(layer "F.SilkS")
			(hide yes)
			(effects
				(font
					(size 1.27 1.27)
				)
			)
		)
		(property "Value" ""
			(at 0 0 180)
			(layer "F.Fab")
			(effects
				(font
					(size 1.27 1.27)
				)
			)
		)
		(duplicate_pad_numbers_are_jumpers no)
		(fp_line
			(start 0.7874 0.4064)
			(end -0.7874 0.4064)
			(stroke
				(width 0.1524)
				(type default)
			)
			(layer "F.SilkS")
		)
		(fp_line
			(start 0.7874 -0.4064)
			(end 0.7874 0.4064)
			(stroke
				(width 0.1524)
				(type default)
			)
			(layer "F.SilkS")
		)
		(fp_line
			(start -0.7874 0.4064)
			(end -0.7874 -0.4064)
			(stroke
				(width 0.1524)
				(type default)
			)
			(layer "F.SilkS")
		)
		(fp_line
			(start -0.7874 -0.4064)
			(end 0.7874 -0.4064)
			(stroke
				(width 0.1524)
				(type default)
			)
			(layer "F.SilkS")
		)
		(fp_line
			(start 0.67945 0.3048)
			(end 0.120396 0.3048)
			(stroke
				(width 0.1)
				(type default)
			)
			(layer "F.Fab")
		)
		(fp_line
			(start 0.67945 -0.3048)
			(end 0.67945 0.3048)
			(stroke
				(width 0.1)
				(type default)
			)
			(layer "F.Fab")
		)
		(fp_line
			(start 0.12065 -0.2794)
			(end 0.12065 -0.3048)
			(stroke
				(width 0.1)
				(type default)
			)
			(layer "F.Fab")
		)
		(fp_line
			(start 0.12065 -0.3048)
			(end 0.67945 -0.3048)
			(stroke
				(width 0.1)
				(type default)
			)
			(layer "F.Fab")
		)
		(fp_line
			(start 0.120396 0.3048)
			(end 0.120396 0.2794)
			(stroke
				(width 0.1)
				(type default)
			)
			(layer "F.Fab")
		)
		(fp_line
			(start 0.120396 0.2794)
			(end -0.12065 0.2794)
			(stroke
				(width 0.1)
				(type default)
			)
			(layer "F.Fab")
		)
		(fp_line
			(start -0.12065 0.3048)
			(end -0.67945 0.3048)
			(stroke
				(width 0.1)
				(type default)
			)
			(layer "F.Fab")
		)
		(fp_line
			(start -0.12065 0.2794)
			(end -0.12065 0.3048)
			(stroke
				(width 0.1)
				(type default)
			)
			(layer "F.Fab")
		)
		(fp_line
			(start -0.12065 -0.2794)
			(end 0.12065 -0.2794)
			(stroke
				(width 0.1)
				(type default)
			)
			(layer "F.Fab")
		)
		(fp_line
			(start -0.12065 -0.305054)
			(end -0.12065 -0.2794)
			(stroke
				(width 0.1)
				(type default)
			)
			(layer "F.Fab")
		)
		(fp_line
			(start -0.67945 0.3048)
			(end -0.67945 -0.305054)
			(stroke
				(width 0.1)
				(type default)
			)
			(layer "F.Fab")
		)
		(fp_line
			(start -0.67945 -0.305054)
			(end -0.12065 -0.305054)
			(stroke
				(width 0.1)
				(type default)
			)
			(layer "F.Fab")
		)
		(pad "1" smd circle
			(at -0.40005 0 180)
			(size 0 0)
			(layers "F.Cu" "F.Mask" "F.Paste")
			(net "NIC6_CLK_EN_BUF_R_N")
		)
		(pad "2" smd circle
			(at 0.40005 0 180)
			(size 0 0)
			(layers "F.Cu" "F.Mask" "F.Paste")
			(net "P3V3")
		)
	)
	(footprint ""
		(layer "F.Cu")
		(at 275.004022 -356.244906 90)
		(property "Reference" "C2348"
			(at 0 0 90)
			(layer "F.SilkS")
			(hide yes)
			(effects
				(font
					(size 1.27 1.27)
				)
			)
		)
		(property "Value" ""
			(at 0 0 90)
			(layer "F.Fab")
			(effects
				(font
					(size 1.27 1.27)
				)
			)
		)
		(duplicate_pad_numbers_are_jumpers no)
		(fp_line
			(start 0.299974 -0.150114)
			(end 0.299974 0.150114)
			(stroke
				(width 0.1)
				(type default)
			)
			(layer "F.Fab")
		)
		(fp_line
			(start -0.299974 -0.150114)
			(end 0.299974 -0.150114)
			(stroke
				(width 0.1)
				(type default)
			)
			(layer "F.Fab")
		)
		(fp_line
			(start 0.299974 0.150114)
			(end -0.299974 0.150114)
			(stroke
				(width 0.1)
				(type default)
			)
			(layer "F.Fab")
		)
		(fp_line
			(start -0.299974 0.150114)
			(end -0.299974 -0.150114)
			(stroke
				(width 0.1)
				(type default)
			)
			(layer "F.Fab")
		)
		(pad "1" smd rect
			(at -0.2667 0 90)
			(size 0.3048 0.381)
			(layers "F.Cu" "F.Mask" "F.Paste")
			(net "P5E_PEX2_STN4_TX_DN<76>")
		)
		(pad "2" smd rect
			(at 0.2667 0 90)
			(size 0.3048 0.381)
			(layers "F.Cu" "F.Mask" "F.Paste")
			(net "P5E_PEX2_STN4_TX_C_DN<76>")
		)
	)
	(footprint ""
		(layer "F.Cu")
		(at 387.580632 -125.519942)
		(property "Reference" "C675"
			(at 0 0 0)
			(layer "F.SilkS")
			(hide yes)
			(effects
				(font
					(size 1.27 1.27)
				)
			)
		)
		(property "Value" ""
			(at 0 0 0)
			(layer "F.Fab")
			(effects
				(font
					(size 1.27 1.27)
				)
			)
		)
		(duplicate_pad_numbers_are_jumpers no)
		(fp_line
			(start -0.299974 -0.150114)
			(end 0.299974 -0.150114)
			(stroke
				(width 0.1)
				(type default)
			)
			(layer "F.Fab")
		)
		(fp_line
			(start -0.299974 0.150114)
			(end -0.299974 -0.150114)
			(stroke
				(width 0.1)
				(type default)
			)
			(layer "F.Fab")
		)
		(fp_line
			(start 0.299974 -0.150114)
			(end 0.299974 0.150114)
			(stroke
				(width 0.1)
				(type default)
			)
			(layer "F.Fab")
		)
		(fp_line
			(start 0.299974 0.150114)
			(end -0.299974 0.150114)
			(stroke
				(width 0.1)
				(type default)
			)
			(layer "F.Fab")
		)
		(pad "1" smd rect
			(at -0.2667 0)
			(size 0.3048 0.381)
			(layers "F.Cu" "F.Mask" "F.Paste")
			(net "P5E_PEX3_STN1_TX_DP<27>")
		)
		(pad "2" smd rect
			(at 0.2667 0)
			(size 0.3048 0.381)
			(layers "F.Cu" "F.Mask" "F.Paste")
			(net "P5E_PEX3_STN1_TX_C_DP<27>")
		)
	)
	(footprint ""
		(layer "F.Cu")
		(at 288.181542 -157.8356)
		(property "Reference" "R252"
			(at 0 0 0)
			(layer "F.SilkS")
			(hide yes)
			(effects
				(font
					(size 1.27 1.27)
				)
			)
		)
		(property "Value" ""
			(at 0 0 0)
			(layer "F.Fab")
			(effects
				(font
					(size 1.27 1.27)
				)
			)
		)
		(duplicate_pad_numbers_are_jumpers no)
		(fp_line
			(start -0.7874 -0.4064)
			(end 0.7874 -0.4064)
			(stroke
				(width 0.1524)
				(type default)
			)
			(layer "F.SilkS")
		)
		(fp_line
			(start -0.7874 0.4064)
			(end -0.7874 -0.4064)
			(stroke
				(width 0.1524)
				(type default)
			)
			(layer "F.SilkS")
		)
		(fp_line
			(start 0.7874 -0.4064)
			(end 0.7874 0.4064)
			(stroke
				(width 0.1524)
				(type default)
			)
			(layer "F.SilkS")
		)
		(fp_line
			(start 0.7874 0.4064)
			(end -0.7874 0.4064)
			(stroke
				(width 0.1524)
				(type default)
			)
			(layer "F.SilkS")
		)
		(fp_line
			(start -0.67945 -0.305054)
			(end -0.12065 -0.305054)
			(stroke
				(width 0.1)
				(type default)
			)
			(layer "F.Fab")
		)
		(fp_line
			(start -0.67945 0.3048)
			(end -0.67945 -0.305054)
			(stroke
				(width 0.1)
				(type default)
			)
			(layer "F.Fab")
		)
		(fp_line
			(start -0.12065 -0.305054)
			(end -0.12065 -0.2794)
			(stroke
				(width 0.1)
				(type default)
			)
			(layer "F.Fab")
		)
		(fp_line
			(start -0.12065 -0.2794)
			(end 0.12065 -0.2794)
			(stroke
				(width 0.1)
				(type default)
			)
			(layer "F.Fab")
		)
		(fp_line
			(start -0.12065 0.2794)
			(end -0.12065 0.3048)
			(stroke
				(width 0.1)
				(type default)
			)
			(layer "F.Fab")
		)
		(fp_line
			(start -0.12065 0.3048)
			(end -0.67945 0.3048)
			(stroke
				(width 0.1)
				(type default)
			)
			(layer "F.Fab")
		)
		(fp_line
			(start 0.120396 0.2794)
			(end -0.12065 0.2794)
			(stroke
				(width 0.1)
				(type default)
			)
			(layer "F.Fab")
		)
		(fp_line
			(start 0.120396 0.3048)
			(end 0.120396 0.2794)
			(stroke
				(width 0.1)
				(type default)
			)
			(layer "F.Fab")
		)
		(fp_line
			(start 0.12065 -0.3048)
			(end 0.67945 -0.3048)
			(stroke
				(width 0.1)
				(type default)
			)
			(layer "F.Fab")
		)
		(fp_line
			(start 0.12065 -0.2794)
			(end 0.12065 -0.3048)
			(stroke
				(width 0.1)
				(type default)
			)
			(layer "F.Fab")
		)
		(fp_line
			(start 0.67945 -0.3048)
			(end 0.67945 0.3048)
			(stroke
				(width 0.1)
				(type default)
			)
			(layer "F.Fab")
		)
		(fp_line
			(start 0.67945 0.3048)
			(end 0.120396 0.3048)
			(stroke
				(width 0.1)
				(type default)
			)
			(layer "F.Fab")
		)
		(pad "1" smd circle
			(at -0.40005 0)
			(size 0 0)
			(layers "F.Cu" "F.Mask" "F.Paste")
			(net "RST_NIC4_PERST3_R_N")
		)
		(pad "2" smd circle
			(at 0.40005 0)
			(size 0 0)
			(layers "F.Cu" "F.Mask" "F.Paste")
			(net "RST_HP_NIC4_BUF_N")
		)
	)
	(footprint ""
		(layer "F.Cu")
		(at 166.330884 -196.884798)
		(property "Reference" "R3403"
			(at 0 0 0)
			(layer "F.SilkS")
			(hide yes)
			(effects
				(font
					(size 1.27 1.27)
				)
			)
		)
		(property "Value" ""
			(at 0 0 0)
			(layer "F.Fab")
			(effects
				(font
					(size 1.27 1.27)
				)
			)
		)
		(duplicate_pad_numbers_are_jumpers no)
		(fp_line
			(start -0.7874 -0.4064)
			(end 0.7874 -0.4064)
			(stroke
				(width 0.1524)
				(type default)
			)
			(layer "F.SilkS")
		)
		(fp_line
			(start -0.7874 0.4064)
			(end -0.7874 -0.4064)
			(stroke
				(width 0.1524)
				(type default)
			)
			(layer "F.SilkS")
		)
		(fp_line
			(start 0.7874 -0.4064)
			(end 0.7874 0.4064)
			(stroke
				(width 0.1524)
				(type default)
			)
			(layer "F.SilkS")
		)
		(fp_line
			(start 0.7874 0.4064)
			(end -0.7874 0.4064)
			(stroke
				(width 0.1524)
				(type default)
			)
			(layer "F.SilkS")
		)
		(fp_line
			(start -0.67945 -0.305054)
			(end -0.12065 -0.305054)
			(stroke
				(width 0.1)
				(type default)
			)
			(layer "F.Fab")
		)
		(fp_line
			(start -0.67945 0.3048)
			(end -0.67945 -0.305054)
			(stroke
				(width 0.1)
				(type default)
			)
			(layer "F.Fab")
		)
		(fp_line
			(start -0.12065 -0.305054)
			(end -0.12065 -0.2794)
			(stroke
				(width 0.1)
				(type default)
			)
			(layer "F.Fab")
		)
		(fp_line
			(start -0.12065 -0.2794)
			(end 0.12065 -0.2794)
			(stroke
				(width 0.1)
				(type default)
			)
			(layer "F.Fab")
		)
		(fp_line
			(start -0.12065 0.2794)
			(end -0.12065 0.3048)
			(stroke
				(width 0.1)
				(type default)
			)
			(layer "F.Fab")
		)
		(fp_line
			(start -0.12065 0.3048)
			(end -0.67945 0.3048)
			(stroke
				(width 0.1)
				(type default)
			)
			(layer "F.Fab")
		)
		(fp_line
			(start 0.120396 0.2794)
			(end -0.12065 0.2794)
			(stroke
				(width 0.1)
				(type default)
			)
			(layer "F.Fab")
		)
		(fp_line
			(start 0.120396 0.3048)
			(end 0.120396 0.2794)
			(stroke
				(width 0.1)
				(type default)
			)
			(layer "F.Fab")
		)
		(fp_line
			(start 0.12065 -0.3048)
			(end 0.67945 -0.3048)
			(stroke
				(width 0.1)
				(type default)
			)
			(layer "F.Fab")
		)
		(fp_line
			(start 0.12065 -0.2794)
			(end 0.12065 -0.3048)
			(stroke
				(width 0.1)
				(type default)
			)
			(layer "F.Fab")
		)
		(fp_line
			(start 0.67945 -0.3048)
			(end 0.67945 0.3048)
			(stroke
				(width 0.1)
				(type default)
			)
			(layer "F.Fab")
		)
		(fp_line
			(start 0.67945 0.3048)
			(end 0.120396 0.3048)
			(stroke
				(width 0.1)
				(type default)
			)
			(layer "F.Fab")
		)
		(pad "1" smd circle
			(at -0.40005 0)
			(size 0 0)
			(layers "F.Cu" "F.Mask" "F.Paste")
			(net "SPI_BIC1_CLK_LS01_R1")
		)
		(pad "2" smd circle
			(at 0.40005 0)
			(size 0 0)
			(layers "F.Cu" "F.Mask" "F.Paste")
			(net "SPI_BIC1_CLK_LS01_R")
		)
	)
	(footprint ""
		(layer "F.Cu")
		(at 337.221322 -303.698402 90)
		(property "Reference" "PC169"
			(at 0 0 90)
			(layer "F.SilkS")
			(hide yes)
			(effects
				(font
					(size 1.27 1.27)
				)
			)
		)
		(property "Value" ""
			(at 0 0 90)
			(layer "F.Fab")
			(effects
				(font
					(size 1.27 1.27)
				)
			)
		)
		(duplicate_pad_numbers_are_jumpers no)
		(fp_line
			(start -4.53898 -2.150618)
			(end -4.539742 2.152142)
			(stroke
				(width 0.1524)
				(type default)
			)
			(layer "F.SilkS")
		)
		(fp_line
			(start -4.69138 -2.150618)
			(end -4.692396 2.161032)
			(stroke
				(width 0.1524)
				(type default)
			)
			(layer "F.SilkS")
		)
		(fp_line
			(start -4.84378 -2.150618)
			(end -4.53898 -2.150618)
			(stroke
				(width 0.1524)
				(type default)
			)
			(layer "F.SilkS")
		)
		(fp_line
			(start -4.84378 -2.150618)
			(end -4.842256 2.163064)
			(stroke
				(width 0.1524)
				(type default)
			)
			(layer "F.SilkS")
		)
		(fp_line
			(start 4.53898 -2.15011)
			(end 4.53898 2.15011)
			(stroke
				(width 0.1524)
				(type default)
			)
			(layer "F.SilkS")
		)
		(fp_line
			(start -4.53898 -2.15011)
			(end 4.53898 -2.15011)
			(stroke
				(width 0.1524)
				(type default)
			)
			(layer "F.SilkS")
		)
		(fp_line
			(start 4.53898 2.15011)
			(end -4.53898 2.15011)
			(stroke
				(width 0.1524)
				(type default)
			)
			(layer "F.SilkS")
		)
		(fp_line
			(start -4.53898 2.15011)
			(end -4.53898 -2.15011)
			(stroke
				(width 0.1524)
				(type default)
			)
			(layer "F.SilkS")
		)
		(fp_line
			(start -4.83108 2.150364)
			(end -4.447794 2.149348)
			(stroke
				(width 0.1524)
				(type default)
			)
			(layer "F.SilkS")
		)
		(fp_line
			(start 3.64998 -2.15011)
			(end 3.64998 2.15011)
			(stroke
				(width 0.1)
				(type default)
			)
			(layer "F.Fab")
		)
		(fp_line
			(start -3.64998 -2.15011)
			(end 3.64998 -2.15011)
			(stroke
				(width 0.1)
				(type default)
			)
			(layer "F.Fab")
		)
		(fp_line
			(start 3.64998 2.15011)
			(end -3.64998 2.15011)
			(stroke
				(width 0.1)
				(type default)
			)
			(layer "F.Fab")
		)
		(fp_line
			(start -3.64998 2.15011)
			(end -3.64998 -2.15011)
			(stroke
				(width 0.1)
				(type default)
			)
			(layer "F.Fab")
		)
		(fp_text user "-"
			(at 4.729226 -0.216662 90)
			(unlocked yes)
			(layer "F.SilkS")
			(effects
				(font
					(size 1.905 1.4224)
					(thickness 0.1524)
				)
				(justify left)
			)
		)
		(fp_text user "+"
			(at -5.031486 2.604262 90)
			(unlocked yes)
			(layer "F.SilkS")
			(effects
				(font
					(size 1.905 1.4224)
					(thickness 0.1524)
				)
				(justify left)
			)
		)
		(fp_text user "+"
			(at -6.214872 -0.337058 90)
			(unlocked yes)
			(layer "F.Fab")
			(effects
				(font
					(size 1.905 1.4224)
					(thickness 0.1524)
				)
				(justify left)
			)
		)
		(fp_text user "-"
			(at 4.313174 -0.094488 90)
			(unlocked yes)
			(layer "F.Fab")
			(effects
				(font
					(size 1.905 1.4224)
					(thickness 0.1524)
				)
				(justify left)
			)
		)
		(pad "1" smd rect
			(at -3.199892 0 90)
			(size 2.413 2.8194)
			(layers "F.Cu" "F.Mask" "F.Paste")
			(net "P0V8_PEX2")
		)
		(pad "2" smd rect
			(at 3.199892 0 90)
			(size 2.413 2.8194)
			(layers "F.Cu" "F.Mask" "F.Paste")
			(net "GND")
		)
	)
	(footprint ""
		(layer "F.Cu")
		(at 456.532996 -235.191046 90)
		(property "Reference" "R6611"
			(at 0 0 90)
			(layer "F.SilkS")
			(hide yes)
			(effects
				(font
					(size 1.27 1.27)
				)
			)
		)
		(property "Value" ""
			(at 0 0 90)
			(layer "F.Fab")
			(effects
				(font
					(size 1.27 1.27)
				)
			)
		)
		(duplicate_pad_numbers_are_jumpers no)
		(fp_line
			(start 0.7874 -0.4064)
			(end 0.7874 0.4064)
			(stroke
				(width 0.1524)
				(type default)
			)
			(layer "F.SilkS")
		)
		(fp_line
			(start -0.7874 -0.4064)
			(end 0.7874 -0.4064)
			(stroke
				(width 0.1524)
				(type default)
			)
			(layer "F.SilkS")
		)
		(fp_line
			(start 0.7874 0.4064)
			(end -0.7874 0.4064)
			(stroke
				(width 0.1524)
				(type default)
			)
			(layer "F.SilkS")
		)
		(fp_line
			(start -0.7874 0.4064)
			(end -0.7874 -0.4064)
			(stroke
				(width 0.1524)
				(type default)
			)
			(layer "F.SilkS")
		)
		(fp_line
			(start -0.12065 -0.305054)
			(end -0.12065 -0.2794)
			(stroke
				(width 0.1)
				(type default)
			)
			(layer "F.Fab")
		)
		(fp_line
			(start -0.67945 -0.305054)
			(end -0.12065 -0.305054)
			(stroke
				(width 0.1)
				(type default)
			)
			(layer "F.Fab")
		)
		(fp_line
			(start 0.67945 -0.3048)
			(end 0.67945 0.3048)
			(stroke
				(width 0.1)
				(type default)
			)
			(layer "F.Fab")
		)
		(fp_line
			(start 0.12065 -0.3048)
			(end 0.67945 -0.3048)
			(stroke
				(width 0.1)
				(type default)
			)
			(layer "F.Fab")
		)
		(fp_line
			(start 0.12065 -0.2794)
			(end 0.12065 -0.3048)
			(stroke
				(width 0.1)
				(type default)
			)
			(layer "F.Fab")
		)
		(fp_line
			(start -0.12065 -0.2794)
			(end 0.12065 -0.2794)
			(stroke
				(width 0.1)
				(type default)
			)
			(layer "F.Fab")
		)
		(fp_line
			(start 0.120396 0.2794)
			(end -0.12065 0.2794)
			(stroke
				(width 0.1)
				(type default)
			)
			(layer "F.Fab")
		)
		(fp_line
			(start -0.12065 0.2794)
			(end -0.12065 0.3048)
			(stroke
				(width 0.1)
				(type default)
			)
			(layer "F.Fab")
		)
		(fp_line
			(start 0.67945 0.3048)
			(end 0.120396 0.3048)
			(stroke
				(width 0.1)
				(type default)
			)
			(layer "F.Fab")
		)
		(fp_line
			(start 0.120396 0.3048)
			(end 0.120396 0.2794)
			(stroke
				(width 0.1)
				(type default)
			)
			(layer "F.Fab")
		)
		(fp_line
			(start -0.12065 0.3048)
			(end -0.67945 0.3048)
			(stroke
				(width 0.1)
				(type default)
			)
			(layer "F.Fab")
		)
		(fp_line
			(start -0.67945 0.3048)
			(end -0.67945 -0.305054)
			(stroke
				(width 0.1)
				(type default)
			)
			(layer "F.Fab")
		)
		(pad "1" smd circle
			(at -0.40005 0 90)
			(size 0 0)
			(layers "F.Cu" "F.Mask" "F.Paste")
			(net "UART_PEX1_SDB_CP2108_RX")
		)
		(pad "2" smd circle
			(at 0.40005 0 90)
			(size 0 0)
			(layers "F.Cu" "F.Mask" "F.Paste")
			(net "UART_PEX1_SDB_R_RX")
		)
	)
	(footprint ""
		(layer "F.Cu")
		(at 108.007404 -164.52342 180)
		(property "Reference" "PC26"
			(at 0 0 180)
			(layer "F.SilkS")
			(hide yes)
			(effects
				(font
					(size 1.27 1.27)
				)
			)
		)
		(property "Value" ""
			(at 0 0 180)
			(layer "F.Fab")
			(effects
				(font
					(size 1.27 1.27)
				)
			)
		)
		(duplicate_pad_numbers_are_jumpers no)
		(fp_line
			(start 1.524 0.762)
			(end -1.524 0.762)
			(stroke
				(width 0.1524)
				(type default)
			)
			(layer "F.SilkS")
		)
		(fp_line
			(start 1.524 -0.762)
			(end 1.524 0.762)
			(stroke
				(width 0.1524)
				(type default)
			)
			(layer "F.SilkS")
		)
		(fp_line
			(start -1.524 0.762)
			(end -1.524 -0.762)
			(stroke
				(width 0.1524)
				(type default)
			)
			(layer "F.SilkS")
		)
		(fp_line
			(start -1.524 -0.762)
			(end 1.524 -0.762)
			(stroke
				(width 0.1524)
				(type default)
			)
			(layer "F.SilkS")
		)
		(fp_line
			(start 1.1049 0.724916)
			(end 1.1049 -0.724916)
			(stroke
				(width 0.1)
				(type default)
			)
			(layer "F.Fab")
		)
		(fp_line
			(start 1.1049 -0.724916)
			(end -1.1049 -0.724916)
			(stroke
				(width 0.1)
				(type default)
			)
			(layer "F.Fab")
		)
		(fp_line
			(start -1.1049 0.724916)
			(end 1.1049 0.724916)
			(stroke
				(width 0.1)
				(type default)
			)
			(layer "F.Fab")
		)
		(fp_line
			(start -1.1049 -0.724916)
			(end -1.1049 0.724916)
			(stroke
				(width 0.1)
				(type default)
			)
			(layer "F.Fab")
		)
		(pad "1" smd rect
			(at -0.889 0)
			(size 1.016 1.27)
			(layers "F.Cu" "F.Mask" "F.Paste")
			(net "SW_P12V_P3V3_AUX_FLT")
		)
		(pad "2" smd rect
			(at 0.889 0)
			(size 1.016 1.27)
			(layers "F.Cu" "F.Mask" "F.Paste")
			(net "GND")
		)
	)
	(footprint ""
		(layer "F.Cu")
		(at 141.458442 -252.356874 -90)
		(property "Reference" "R1296"
			(at 0 0 270)
			(layer "F.SilkS")
			(hide yes)
			(effects
				(font
					(size 1.27 1.27)
				)
			)
		)
		(property "Value" ""
			(at 0 0 270)
			(layer "F.Fab")
			(effects
				(font
					(size 1.27 1.27)
				)
			)
		)
		(duplicate_pad_numbers_are_jumpers no)
		(fp_line
			(start -0.7874 0.4064)
			(end -0.7874 -0.4064)
			(stroke
				(width 0.1524)
				(type default)
			)
			(layer "F.SilkS")
		)
		(fp_line
			(start 0.7874 0.4064)
			(end -0.7874 0.4064)
			(stroke
				(width 0.1524)
				(type default)
			)
			(layer "F.SilkS")
		)
		(fp_line
			(start -0.7874 -0.4064)
			(end 0.7874 -0.4064)
			(stroke
				(width 0.1524)
				(type default)
			)
			(layer "F.SilkS")
		)
		(fp_line
			(start 0.7874 -0.4064)
			(end 0.7874 0.4064)
			(stroke
				(width 0.1524)
				(type default)
			)
			(layer "F.SilkS")
		)
		(fp_line
			(start -0.67945 0.3048)
			(end -0.67945 -0.305054)
			(stroke
				(width 0.1)
				(type default)
			)
			(layer "F.Fab")
		)
		(fp_line
			(start -0.12065 0.3048)
			(end -0.67945 0.3048)
			(stroke
				(width 0.1)
				(type default)
			)
			(layer "F.Fab")
		)
		(fp_line
			(start 0.120396 0.3048)
			(end 0.120396 0.2794)
			(stroke
				(width 0.1)
				(type default)
			)
			(layer "F.Fab")
		)
		(fp_line
			(start 0.67945 0.3048)
			(end 0.120396 0.3048)
			(stroke
				(width 0.1)
				(type default)
			)
			(layer "F.Fab")
		)
		(fp_line
			(start -0.12065 0.2794)
			(end -0.12065 0.3048)
			(stroke
				(width 0.1)
				(type default)
			)
			(layer "F.Fab")
		)
		(fp_line
			(start 0.120396 0.2794)
			(end -0.12065 0.2794)
			(stroke
				(width 0.1)
				(type default)
			)
			(layer "F.Fab")
		)
		(fp_line
			(start -0.12065 -0.2794)
			(end 0.12065 -0.2794)
			(stroke
				(width 0.1)
				(type default)
			)
			(layer "F.Fab")
		)
		(fp_line
			(start 0.12065 -0.2794)
			(end 0.12065 -0.3048)
			(stroke
				(width 0.1)
				(type default)
			)
			(layer "F.Fab")
		)
		(fp_line
			(start 0.12065 -0.3048)
			(end 0.67945 -0.3048)
			(stroke
				(width 0.1)
				(type default)
			)
			(layer "F.Fab")
		)
		(fp_line
			(start 0.67945 -0.3048)
			(end 0.67945 0.3048)
			(stroke
				(width 0.1)
				(type default)
			)
			(layer "F.Fab")
		)
		(fp_line
			(start -0.67945 -0.305054)
			(end -0.12065 -0.305054)
			(stroke
				(width 0.1)
				(type default)
			)
			(layer "F.Fab")
		)
		(fp_line
			(start -0.12065 -0.305054)
			(end -0.12065 -0.2794)
			(stroke
				(width 0.1)
				(type default)
			)
			(layer "F.Fab")
		)
		(pad "1" smd circle
			(at -0.40005 0 270)
			(size 0 0)
			(layers "F.Cu" "F.Mask" "F.Paste")
			(net "GND")
		)
		(pad "2" smd circle
			(at 0.40005 0 270)
			(size 0 0)
			(layers "F.Cu" "F.Mask" "F.Paste")
			(net "PEX1_MODE_SEL7")
		)
	)
	(footprint ""
		(layer "F.Cu")
		(at 67.564762 -356.244906 90)
		(property "Reference" "C135"
			(at 0 0 90)
			(layer "F.SilkS")
			(hide yes)
			(effects
				(font
					(size 1.27 1.27)
				)
			)
		)
		(property "Value" ""
			(at 0 0 90)
			(layer "F.Fab")
			(effects
				(font
					(size 1.27 1.27)
				)
			)
		)
		(duplicate_pad_numbers_are_jumpers no)
		(fp_line
			(start 0.299974 -0.150114)
			(end 0.299974 0.150114)
			(stroke
				(width 0.1)
				(type default)
			)
			(layer "F.Fab")
		)
		(fp_line
			(start -0.299974 -0.150114)
			(end 0.299974 -0.150114)
			(stroke
				(width 0.1)
				(type default)
			)
			(layer "F.Fab")
		)
		(fp_line
			(start 0.299974 0.150114)
			(end -0.299974 0.150114)
			(stroke
				(width 0.1)
				(type default)
			)
			(layer "F.Fab")
		)
		(fp_line
			(start -0.299974 0.150114)
			(end -0.299974 -0.150114)
			(stroke
				(width 0.1)
				(type default)
			)
			(layer "F.Fab")
		)
		(pad "1" smd rect
			(at -0.2667 0 90)
			(size 0.3048 0.381)
			(layers "F.Cu" "F.Mask" "F.Paste")
			(net "P5E_PEX0_STN6_TX_DP<108>")
		)
		(pad "2" smd rect
			(at 0.2667 0 90)
			(size 0.3048 0.381)
			(layers "F.Cu" "F.Mask" "F.Paste")
			(net "P5E_PEX0_STN6_TX_C_DP<108>")
		)
	)
	(footprint ""
		(layer "F.Cu")
		(at 324.271386 -96.811592 -90)
		(property "Reference" "R735"
			(at 0 0 270)
			(layer "F.SilkS")
			(hide yes)
			(effects
				(font
					(size 1.27 1.27)
				)
			)
		)
		(property "Value" ""
			(at 0 0 270)
			(layer "F.Fab")
			(effects
				(font
					(size 1.27 1.27)
				)
			)
		)
		(duplicate_pad_numbers_are_jumpers no)
		(fp_line
			(start -0.7874 0.4064)
			(end -0.7874 -0.4064)
			(stroke
				(width 0.1524)
				(type default)
			)
			(layer "F.SilkS")
		)
		(fp_line
			(start 0.7874 0.4064)
			(end -0.7874 0.4064)
			(stroke
				(width 0.1524)
				(type default)
			)
			(layer "F.SilkS")
		)
		(fp_line
			(start -0.7874 -0.4064)
			(end 0.7874 -0.4064)
			(stroke
				(width 0.1524)
				(type default)
			)
			(layer "F.SilkS")
		)
		(fp_line
			(start 0.7874 -0.4064)
			(end 0.7874 0.4064)
			(stroke
				(width 0.1524)
				(type default)
			)
			(layer "F.SilkS")
		)
		(fp_line
			(start -0.67945 0.3048)
			(end -0.67945 -0.305054)
			(stroke
				(width 0.1)
				(type default)
			)
			(layer "F.Fab")
		)
		(fp_line
			(start -0.12065 0.3048)
			(end -0.67945 0.3048)
			(stroke
				(width 0.1)
				(type default)
			)
			(layer "F.Fab")
		)
		(fp_line
			(start 0.120396 0.3048)
			(end 0.120396 0.2794)
			(stroke
				(width 0.1)
				(type default)
			)
			(layer "F.Fab")
		)
		(fp_line
			(start 0.67945 0.3048)
			(end 0.120396 0.3048)
			(stroke
				(width 0.1)
				(type default)
			)
			(layer "F.Fab")
		)
		(fp_line
			(start -0.12065 0.2794)
			(end -0.12065 0.3048)
			(stroke
				(width 0.1)
				(type default)
			)
			(layer "F.Fab")
		)
		(fp_line
			(start 0.120396 0.2794)
			(end -0.12065 0.2794)
			(stroke
				(width 0.1)
				(type default)
			)
			(layer "F.Fab")
		)
		(fp_line
			(start -0.12065 -0.2794)
			(end 0.12065 -0.2794)
			(stroke
				(width 0.1)
				(type default)
			)
			(layer "F.Fab")
		)
		(fp_line
			(start 0.12065 -0.2794)
			(end 0.12065 -0.3048)
			(stroke
				(width 0.1)
				(type default)
			)
			(layer "F.Fab")
		)
		(fp_line
			(start 0.12065 -0.3048)
			(end 0.67945 -0.3048)
			(stroke
				(width 0.1)
				(type default)
			)
			(layer "F.Fab")
		)
		(fp_line
			(start 0.67945 -0.3048)
			(end 0.67945 0.3048)
			(stroke
				(width 0.1)
				(type default)
			)
			(layer "F.Fab")
		)
		(fp_line
			(start -0.67945 -0.305054)
			(end -0.12065 -0.305054)
			(stroke
				(width 0.1)
				(type default)
			)
			(layer "F.Fab")
		)
		(fp_line
			(start -0.12065 -0.305054)
			(end -0.12065 -0.2794)
			(stroke
				(width 0.1)
				(type default)
			)
			(layer "F.Fab")
		)
		(pad "1" smd circle
			(at -0.40005 0 270)
			(size 0 0)
			(layers "F.Cu" "F.Mask" "F.Paste")
			(net "P3V3_AUX")
		)
		(pad "2" smd circle
			(at 0.40005 0 270)
			(size 0 0)
			(layers "F.Cu" "F.Mask" "F.Paste")
			(net "NIC_ADC_ALERT_N")
		)
	)
	(footprint ""
		(layer "F.Cu")
		(at 109.54639 -285.088584 90)
		(property "Reference" "PC74"
			(at 0 0 90)
			(layer "F.SilkS")
			(hide yes)
			(effects
				(font
					(size 1.27 1.27)
				)
			)
		)
		(property "Value" ""
			(at 0 0 90)
			(layer "F.Fab")
			(effects
				(font
					(size 1.27 1.27)
				)
			)
		)
		(duplicate_pad_numbers_are_jumpers no)
		(fp_line
			(start 0.7874 -0.4064)
			(end 0.7874 0.4064)
			(stroke
				(width 0.1524)
				(type default)
			)
			(layer "F.SilkS")
		)
		(fp_line
			(start -0.7874 -0.4064)
			(end 0.7874 -0.4064)
			(stroke
				(width 0.1524)
				(type default)
			)
			(layer "F.SilkS")
		)
		(fp_line
			(start 0.7874 0.4064)
			(end -0.7874 0.4064)
			(stroke
				(width 0.1524)
				(type default)
			)
			(layer "F.SilkS")
		)
		(fp_line
			(start -0.7874 0.4064)
			(end -0.7874 -0.4064)
			(stroke
				(width 0.1524)
				(type default)
			)
			(layer "F.SilkS")
		)
		(fp_line
			(start -0.12065 -0.305054)
			(end -0.12065 -0.2794)
			(stroke
				(width 0.1)
				(type default)
			)
			(layer "F.Fab")
		)
		(fp_line
			(start -0.67945 -0.305054)
			(end -0.12065 -0.305054)
			(stroke
				(width 0.1)
				(type default)
			)
			(layer "F.Fab")
		)
		(fp_line
			(start 0.67945 -0.3048)
			(end 0.67945 0.3048)
			(stroke
				(width 0.1)
				(type default)
			)
			(layer "F.Fab")
		)
		(fp_line
			(start 0.12065 -0.3048)
			(end 0.67945 -0.3048)
			(stroke
				(width 0.1)
				(type default)
			)
			(layer "F.Fab")
		)
		(fp_line
			(start 0.12065 -0.2794)
			(end 0.12065 -0.3048)
			(stroke
				(width 0.1)
				(type default)
			)
			(layer "F.Fab")
		)
		(fp_line
			(start -0.12065 -0.2794)
			(end 0.12065 -0.2794)
			(stroke
				(width 0.1)
				(type default)
			)
			(layer "F.Fab")
		)
		(fp_line
			(start 0.120396 0.2794)
			(end -0.12065 0.2794)
			(stroke
				(width 0.1)
				(type default)
			)
			(layer "F.Fab")
		)
		(fp_line
			(start -0.12065 0.2794)
			(end -0.12065 0.3048)
			(stroke
				(width 0.1)
				(type default)
			)
			(layer "F.Fab")
		)
		(fp_line
			(start 0.67945 0.3048)
			(end 0.120396 0.3048)
			(stroke
				(width 0.1)
				(type default)
			)
			(layer "F.Fab")
		)
		(fp_line
			(start 0.120396 0.3048)
			(end 0.120396 0.2794)
			(stroke
				(width 0.1)
				(type default)
			)
			(layer "F.Fab")
		)
		(fp_line
			(start -0.12065 0.3048)
			(end -0.67945 0.3048)
			(stroke
				(width 0.1)
				(type default)
			)
			(layer "F.Fab")
		)
		(fp_line
			(start -0.67945 0.3048)
			(end -0.67945 -0.305054)
			(stroke
				(width 0.1)
				(type default)
			)
			(layer "F.Fab")
		)
		(pad "1" smd circle
			(at -0.40005 0 90)
			(size 0 0)
			(layers "F.Cu" "F.Mask" "F.Paste")
			(net "P0V8_PEX0_PVCC")
		)
		(pad "2" smd circle
			(at 0.40005 0 90)
			(size 0 0)
			(layers "F.Cu" "F.Mask" "F.Paste")
			(net "GND")
		)
	)
	(footprint ""
		(layer "F.Cu")
		(at 281.221942 -343.952322 90)
		(property "Reference" "C2352"
			(at 0 0 90)
			(layer "F.SilkS")
			(hide yes)
			(effects
				(font
					(size 1.27 1.27)
				)
			)
		)
		(property "Value" ""
			(at 0 0 90)
			(layer "F.Fab")
			(effects
				(font
					(size 1.27 1.27)
				)
			)
		)
		(duplicate_pad_numbers_are_jumpers no)
		(fp_line
			(start 0.299974 -0.150114)
			(end 0.299974 0.150114)
			(stroke
				(width 0.1)
				(type default)
			)
			(layer "F.Fab")
		)
		(fp_line
			(start -0.299974 -0.150114)
			(end 0.299974 -0.150114)
			(stroke
				(width 0.1)
				(type default)
			)
			(layer "F.Fab")
		)
		(fp_line
			(start 0.299974 0.150114)
			(end -0.299974 0.150114)
			(stroke
				(width 0.1)
				(type default)
			)
			(layer "F.Fab")
		)
		(fp_line
			(start -0.299974 0.150114)
			(end -0.299974 -0.150114)
			(stroke
				(width 0.1)
				(type default)
			)
			(layer "F.Fab")
		)
		(pad "1" smd rect
			(at -0.2667 0 90)
			(size 0.3048 0.381)
			(layers "F.Cu" "F.Mask" "F.Paste")
			(net "P5E_PEX2_STN4_TX_DN<74>")
		)
		(pad "2" smd rect
			(at 0.2667 0 90)
			(size 0.3048 0.381)
			(layers "F.Cu" "F.Mask" "F.Paste")
			(net "P5E_PEX2_STN4_TX_C_DN<74>")
		)
	)
	(footprint ""
		(layer "F.Cu")
		(at 115.356386 -85.384386 180)
		(property "Reference" "R1145"
			(at 0 0 180)
			(layer "F.SilkS")
			(hide yes)
			(effects
				(font
					(size 1.27 1.27)
				)
			)
		)
		(property "Value" ""
			(at 0 0 180)
			(layer "F.Fab")
			(effects
				(font
					(size 1.27 1.27)
				)
			)
		)
		(duplicate_pad_numbers_are_jumpers no)
		(fp_line
			(start 0.7874 0.4064)
			(end -0.7874 0.4064)
			(stroke
				(width 0.1524)
				(type default)
			)
			(layer "F.SilkS")
		)
		(fp_line
			(start 0.67945 0.3048)
			(end 0.120396 0.3048)
			(stroke
				(width 0.1)
				(type default)
			)
			(layer "F.Fab")
		)
		(fp_line
			(start 0.67945 -0.3048)
			(end 0.67945 0.3048)
			(stroke
				(width 0.1)
				(type default)
			)
			(layer "F.Fab")
		)
		(fp_line
			(start 0.12065 -0.2794)
			(end 0.12065 -0.3048)
			(stroke
				(width 0.1)
				(type default)
			)
			(layer "F.Fab")
		)
		(fp_line
			(start 0.12065 -0.3048)
			(end 0.67945 -0.3048)
			(stroke
				(width 0.1)
				(type default)
			)
			(layer "F.Fab")
		)
		(fp_line
			(start 0.120396 0.3048)
			(end 0.120396 0.2794)
			(stroke
				(width 0.1)
				(type default)
			)
			(layer "F.Fab")
		)
		(fp_line
			(start 0.120396 0.2794)
			(end -0.12065 0.2794)
			(stroke
				(width 0.1)
				(type default)
			)
			(layer "F.Fab")
		)
		(fp_line
			(start -0.12065 0.3048)
			(end -0.67945 0.3048)
			(stroke
				(width 0.1)
				(type default)
			)
			(layer "F.Fab")
		)
		(fp_line
			(start -0.12065 0.2794)
			(end -0.12065 0.3048)
			(stroke
				(width 0.1)
				(type default)
			)
			(layer "F.Fab")
		)
		(fp_line
			(start -0.12065 -0.2794)
			(end 0.12065 -0.2794)
			(stroke
				(width 0.1)
				(type default)
			)
			(layer "F.Fab")
		)
		(fp_line
			(start -0.12065 -0.305054)
			(end -0.12065 -0.2794)
			(stroke
				(width 0.1)
				(type default)
			)
			(layer "F.Fab")
		)
		(fp_line
			(start -0.67945 0.3048)
			(end -0.67945 -0.305054)
			(stroke
				(width 0.1)
				(type default)
			)
			(layer "F.Fab")
		)
		(fp_line
			(start -0.67945 -0.305054)
			(end -0.12065 -0.305054)
			(stroke
				(width 0.1)
				(type default)
			)
			(layer "F.Fab")
		)
		(pad "1" smd circle
			(at -0.40005 0 180)
			(size 0 0)
			(layers "F.Cu" "F.Mask" "F.Paste")
			(net "CLK_100M_DB800ZL_SSD4_R_DN")
		)
		(pad "2" smd circle
			(at 0.40005 0 180)
			(size 0 0)
			(layers "F.Cu" "F.Mask" "F.Paste")
			(net "CLK_100M_DB800ZL_SSD4_DN")
		)
	)
	(footprint ""
		(layer "F.Cu")
		(at 262.07212 -32.848042 90)
		(property "Reference" "PC942"
			(at 0 0 90)
			(layer "F.SilkS")
			(hide yes)
			(effects
				(font
					(size 1.27 1.27)
				)
			)
		)
		(property "Value" ""
			(at 0 0 90)
			(layer "F.Fab")
			(effects
				(font
					(size 1.27 1.27)
				)
			)
		)
		(duplicate_pad_numbers_are_jumpers no)
		(fp_line
			(start 0.7874 -0.4064)
			(end 0.7874 0.4064)
			(stroke
				(width 0.1524)
				(type default)
			)
			(layer "F.SilkS")
		)
		(fp_line
			(start -0.7874 -0.4064)
			(end 0.7874 -0.4064)
			(stroke
				(width 0.1524)
				(type default)
			)
			(layer "F.SilkS")
		)
		(fp_line
			(start 0.7874 0.4064)
			(end -0.7874 0.4064)
			(stroke
				(width 0.1524)
				(type default)
			)
			(layer "F.SilkS")
		)
		(fp_line
			(start -0.7874 0.4064)
			(end -0.7874 -0.4064)
			(stroke
				(width 0.1524)
				(type default)
			)
			(layer "F.SilkS")
		)
		(fp_line
			(start -0.12065 -0.305054)
			(end -0.12065 -0.2794)
			(stroke
				(width 0.1)
				(type default)
			)
			(layer "F.Fab")
		)
		(fp_line
			(start -0.67945 -0.305054)
			(end -0.12065 -0.305054)
			(stroke
				(width 0.1)
				(type default)
			)
			(layer "F.Fab")
		)
		(fp_line
			(start 0.67945 -0.3048)
			(end 0.67945 0.3048)
			(stroke
				(width 0.1)
				(type default)
			)
			(layer "F.Fab")
		)
		(fp_line
			(start 0.12065 -0.3048)
			(end 0.67945 -0.3048)
			(stroke
				(width 0.1)
				(type default)
			)
			(layer "F.Fab")
		)
		(fp_line
			(start 0.12065 -0.2794)
			(end 0.12065 -0.3048)
			(stroke
				(width 0.1)
				(type default)
			)
			(layer "F.Fab")
		)
		(fp_line
			(start -0.12065 -0.2794)
			(end 0.12065 -0.2794)
			(stroke
				(width 0.1)
				(type default)
			)
			(layer "F.Fab")
		)
		(fp_line
			(start 0.120396 0.2794)
			(end -0.12065 0.2794)
			(stroke
				(width 0.1)
				(type default)
			)
			(layer "F.Fab")
		)
		(fp_line
			(start -0.12065 0.2794)
			(end -0.12065 0.3048)
			(stroke
				(width 0.1)
				(type default)
			)
			(layer "F.Fab")
		)
		(fp_line
			(start 0.67945 0.3048)
			(end 0.120396 0.3048)
			(stroke
				(width 0.1)
				(type default)
			)
			(layer "F.Fab")
		)
		(fp_line
			(start 0.120396 0.3048)
			(end 0.120396 0.2794)
			(stroke
				(width 0.1)
				(type default)
			)
			(layer "F.Fab")
		)
		(fp_line
			(start -0.12065 0.3048)
			(end -0.67945 0.3048)
			(stroke
				(width 0.1)
				(type default)
			)
			(layer "F.Fab")
		)
		(fp_line
			(start -0.67945 0.3048)
			(end -0.67945 -0.305054)
			(stroke
				(width 0.1)
				(type default)
			)
			(layer "F.Fab")
		)
		(pad "1" smd circle
			(at -0.40005 0 90)
			(size 0 0)
			(layers "F.Cu" "F.Mask" "F.Paste")
			(net "P3V3_SSD9_CO_GATE")
		)
		(pad "2" smd circle
			(at 0.40005 0 90)
			(size 0 0)
			(layers "F.Cu" "F.Mask" "F.Paste")
			(net "GND")
		)
	)
	(footprint ""
		(layer "F.Cu")
		(at 31.394146 -29.507688 -90)
		(property "Reference" "PC673"
			(at 0 0 270)
			(layer "F.SilkS")
			(hide yes)
			(effects
				(font
					(size 1.27 1.27)
				)
			)
		)
		(property "Value" ""
			(at 0 0 270)
			(layer "F.Fab")
			(effects
				(font
					(size 1.27 1.27)
				)
			)
		)
		(duplicate_pad_numbers_are_jumpers no)
		(fp_line
			(start -1.524 0.762)
			(end -1.524 -0.762)
			(stroke
				(width 0.1524)
				(type default)
			)
			(layer "F.SilkS")
		)
		(fp_line
			(start 1.524 0.762)
			(end -1.524 0.762)
			(stroke
				(width 0.1524)
				(type default)
			)
			(layer "F.SilkS")
		)
		(fp_line
			(start -1.524 -0.762)
			(end 1.524 -0.762)
			(stroke
				(width 0.1524)
				(type default)
			)
			(layer "F.SilkS")
		)
		(fp_line
			(start 1.524 -0.762)
			(end 1.524 0.762)
			(stroke
				(width 0.1524)
				(type default)
			)
			(layer "F.SilkS")
		)
		(fp_line
			(start -1.1049 0.724916)
			(end 1.1049 0.724916)
			(stroke
				(width 0.1)
				(type default)
			)
			(layer "F.Fab")
		)
		(fp_line
			(start 1.1049 0.724916)
			(end 1.1049 -0.724916)
			(stroke
				(width 0.1)
				(type default)
			)
			(layer "F.Fab")
		)
		(fp_line
			(start -1.1049 -0.724916)
			(end -1.1049 0.724916)
			(stroke
				(width 0.1)
				(type default)
			)
			(layer "F.Fab")
		)
		(fp_line
			(start 1.1049 -0.724916)
			(end -1.1049 -0.724916)
			(stroke
				(width 0.1)
				(type default)
			)
			(layer "F.Fab")
		)
		(pad "1" smd rect
			(at -0.889 0 90)
			(size 1.016 1.27)
			(layers "F.Cu" "F.Mask" "F.Paste")
			(net "P3V3_SSD1")
		)
		(pad "2" smd rect
			(at 0.889 0 90)
			(size 1.016 1.27)
			(layers "F.Cu" "F.Mask" "F.Paste")
			(net "GND")
		)
	)
	(footprint ""
		(layer "F.Cu")
		(at 205.105254 -298.87291 -90)
		(property "Reference" "R3926"
			(at 0 0 270)
			(layer "F.SilkS")
			(hide yes)
			(effects
				(font
					(size 1.27 1.27)
				)
			)
		)
		(property "Value" ""
			(at 0 0 270)
			(layer "F.Fab")
			(effects
				(font
					(size 1.27 1.27)
				)
			)
		)
		(duplicate_pad_numbers_are_jumpers no)
		(fp_line
			(start -0.7874 0.4064)
			(end -0.7874 -0.4064)
			(stroke
				(width 0.1524)
				(type default)
			)
			(layer "F.SilkS")
		)
		(fp_line
			(start 0.7874 0.4064)
			(end -0.7874 0.4064)
			(stroke
				(width 0.1524)
				(type default)
			)
			(layer "F.SilkS")
		)
		(fp_line
			(start -0.7874 -0.4064)
			(end 0.7874 -0.4064)
			(stroke
				(width 0.1524)
				(type default)
			)
			(layer "F.SilkS")
		)
		(fp_line
			(start 0.7874 -0.4064)
			(end 0.7874 0.4064)
			(stroke
				(width 0.1524)
				(type default)
			)
			(layer "F.SilkS")
		)
		(fp_line
			(start -0.67945 0.3048)
			(end -0.67945 -0.305054)
			(stroke
				(width 0.1)
				(type default)
			)
			(layer "F.Fab")
		)
		(fp_line
			(start -0.12065 0.3048)
			(end -0.67945 0.3048)
			(stroke
				(width 0.1)
				(type default)
			)
			(layer "F.Fab")
		)
		(fp_line
			(start 0.120396 0.3048)
			(end 0.120396 0.2794)
			(stroke
				(width 0.1)
				(type default)
			)
			(layer "F.Fab")
		)
		(fp_line
			(start 0.67945 0.3048)
			(end 0.120396 0.3048)
			(stroke
				(width 0.1)
				(type default)
			)
			(layer "F.Fab")
		)
		(fp_line
			(start -0.12065 0.2794)
			(end -0.12065 0.3048)
			(stroke
				(width 0.1)
				(type default)
			)
			(layer "F.Fab")
		)
		(fp_line
			(start 0.120396 0.2794)
			(end -0.12065 0.2794)
			(stroke
				(width 0.1)
				(type default)
			)
			(layer "F.Fab")
		)
		(fp_line
			(start -0.12065 -0.2794)
			(end 0.12065 -0.2794)
			(stroke
				(width 0.1)
				(type default)
			)
			(layer "F.Fab")
		)
		(fp_line
			(start 0.12065 -0.2794)
			(end 0.12065 -0.3048)
			(stroke
				(width 0.1)
				(type default)
			)
			(layer "F.Fab")
		)
		(fp_line
			(start 0.12065 -0.3048)
			(end 0.67945 -0.3048)
			(stroke
				(width 0.1)
				(type default)
			)
			(layer "F.Fab")
		)
		(fp_line
			(start 0.67945 -0.3048)
			(end 0.67945 0.3048)
			(stroke
				(width 0.1)
				(type default)
			)
			(layer "F.Fab")
		)
		(fp_line
			(start -0.67945 -0.305054)
			(end -0.12065 -0.305054)
			(stroke
				(width 0.1)
				(type default)
			)
			(layer "F.Fab")
		)
		(fp_line
			(start -0.12065 -0.305054)
			(end -0.12065 -0.2794)
			(stroke
				(width 0.1)
				(type default)
			)
			(layer "F.Fab")
		)
		(pad "1" smd circle
			(at -0.40005 0 270)
			(size 0 0)
			(layers "F.Cu" "F.Mask" "F.Paste")
			(net "I2C_PEX1_HOST_SDA")
		)
		(pad "2" smd circle
			(at 0.40005 0 270)
			(size 0 0)
			(layers "F.Cu" "F.Mask" "F.Paste")
			(net "I2C_PEX1_HOST_R_SDA")
		)
	)
	(footprint ""
		(layer "F.Cu")
		(at 339.344 -238.633 -90)
		(property "Reference" "R1794"
			(at 0 0 270)
			(layer "F.SilkS")
			(hide yes)
			(effects
				(font
					(size 1.27 1.27)
				)
			)
		)
		(property "Value" ""
			(at 0 0 270)
			(layer "F.Fab")
			(effects
				(font
					(size 1.27 1.27)
				)
			)
		)
		(duplicate_pad_numbers_are_jumpers no)
		(fp_line
			(start -0.7874 0.4064)
			(end -0.7874 -0.4064)
			(stroke
				(width 0.1524)
				(type default)
			)
			(layer "F.SilkS")
		)
		(fp_line
			(start 0.7874 0.4064)
			(end -0.7874 0.4064)
			(stroke
				(width 0.1524)
				(type default)
			)
			(layer "F.SilkS")
		)
		(fp_line
			(start -0.7874 -0.4064)
			(end 0.7874 -0.4064)
			(stroke
				(width 0.1524)
				(type default)
			)
			(layer "F.SilkS")
		)
		(fp_line
			(start 0.7874 -0.4064)
			(end 0.7874 0.4064)
			(stroke
				(width 0.1524)
				(type default)
			)
			(layer "F.SilkS")
		)
		(fp_line
			(start -0.67945 0.3048)
			(end -0.67945 -0.305054)
			(stroke
				(width 0.1)
				(type default)
			)
			(layer "F.Fab")
		)
		(fp_line
			(start -0.12065 0.3048)
			(end -0.67945 0.3048)
			(stroke
				(width 0.1)
				(type default)
			)
			(layer "F.Fab")
		)
		(fp_line
			(start 0.120396 0.3048)
			(end 0.120396 0.2794)
			(stroke
				(width 0.1)
				(type default)
			)
			(layer "F.Fab")
		)
		(fp_line
			(start 0.67945 0.3048)
			(end 0.120396 0.3048)
			(stroke
				(width 0.1)
				(type default)
			)
			(layer "F.Fab")
		)
		(fp_line
			(start -0.12065 0.2794)
			(end -0.12065 0.3048)
			(stroke
				(width 0.1)
				(type default)
			)
			(layer "F.Fab")
		)
		(fp_line
			(start 0.120396 0.2794)
			(end -0.12065 0.2794)
			(stroke
				(width 0.1)
				(type default)
			)
			(layer "F.Fab")
		)
		(fp_line
			(start -0.12065 -0.2794)
			(end 0.12065 -0.2794)
			(stroke
				(width 0.1)
				(type default)
			)
			(layer "F.Fab")
		)
		(fp_line
			(start 0.12065 -0.2794)
			(end 0.12065 -0.3048)
			(stroke
				(width 0.1)
				(type default)
			)
			(layer "F.Fab")
		)
		(fp_line
			(start 0.12065 -0.3048)
			(end 0.67945 -0.3048)
			(stroke
				(width 0.1)
				(type default)
			)
			(layer "F.Fab")
		)
		(fp_line
			(start 0.67945 -0.3048)
			(end 0.67945 0.3048)
			(stroke
				(width 0.1)
				(type default)
			)
			(layer "F.Fab")
		)
		(fp_line
			(start -0.67945 -0.305054)
			(end -0.12065 -0.305054)
			(stroke
				(width 0.1)
				(type default)
			)
			(layer "F.Fab")
		)
		(fp_line
			(start -0.12065 -0.305054)
			(end -0.12065 -0.2794)
			(stroke
				(width 0.1)
				(type default)
			)
			(layer "F.Fab")
		)
		(pad "1" smd circle
			(at -0.40005 0 270)
			(size 0 0)
			(layers "F.Cu" "F.Mask" "F.Paste")
			(net "RST_MB_PERST_2_ISO_N")
		)
		(pad "2" smd circle
			(at 0.40005 0 270)
			(size 0 0)
			(layers "F.Cu" "F.Mask" "F.Paste")
			(net "RST_MB_PERST_2_ISO_R_N")
		)
	)
	(footprint ""
		(layer "F.Cu")
		(at 359.85831 -261.814564 180)
		(property "Reference" "C836"
			(at 0 0 180)
			(layer "F.SilkS")
			(hide yes)
			(effects
				(font
					(size 1.27 1.27)
				)
			)
		)
		(property "Value" ""
			(at 0 0 180)
			(layer "F.Fab")
			(effects
				(font
					(size 1.27 1.27)
				)
			)
		)
		(duplicate_pad_numbers_are_jumpers no)
		(fp_line
			(start 0.7874 0.4064)
			(end -0.7874 0.4064)
			(stroke
				(width 0.1524)
				(type default)
			)
			(layer "F.SilkS")
		)
		(fp_line
			(start 0.7874 -0.4064)
			(end 0.7874 0.4064)
			(stroke
				(width 0.1524)
				(type default)
			)
			(layer "F.SilkS")
		)
		(fp_line
			(start -0.7874 0.4064)
			(end -0.7874 -0.4064)
			(stroke
				(width 0.1524)
				(type default)
			)
			(layer "F.SilkS")
		)
		(fp_line
			(start -0.7874 -0.4064)
			(end 0.7874 -0.4064)
			(stroke
				(width 0.1524)
				(type default)
			)
			(layer "F.SilkS")
		)
		(fp_line
			(start 0.67945 0.3048)
			(end 0.120396 0.3048)
			(stroke
				(width 0.1)
				(type default)
			)
			(layer "F.Fab")
		)
		(fp_line
			(start 0.67945 -0.3048)
			(end 0.67945 0.3048)
			(stroke
				(width 0.1)
				(type default)
			)
			(layer "F.Fab")
		)
		(fp_line
			(start 0.12065 -0.2794)
			(end 0.12065 -0.3048)
			(stroke
				(width 0.1)
				(type default)
			)
			(layer "F.Fab")
		)
		(fp_line
			(start 0.12065 -0.3048)
			(end 0.67945 -0.3048)
			(stroke
				(width 0.1)
				(type default)
			)
			(layer "F.Fab")
		)
		(fp_line
			(start 0.120396 0.3048)
			(end 0.120396 0.2794)
			(stroke
				(width 0.1)
				(type default)
			)
			(layer "F.Fab")
		)
		(fp_line
			(start 0.120396 0.2794)
			(end -0.12065 0.2794)
			(stroke
				(width 0.1)
				(type default)
			)
			(layer "F.Fab")
		)
		(fp_line
			(start -0.12065 0.3048)
			(end -0.67945 0.3048)
			(stroke
				(width 0.1)
				(type default)
			)
			(layer "F.Fab")
		)
		(fp_line
			(start -0.12065 0.2794)
			(end -0.12065 0.3048)
			(stroke
				(width 0.1)
				(type default)
			)
			(layer "F.Fab")
		)
		(fp_line
			(start -0.12065 -0.2794)
			(end 0.12065 -0.2794)
			(stroke
				(width 0.1)
				(type default)
			)
			(layer "F.Fab")
		)
		(fp_line
			(start -0.12065 -0.305054)
			(end -0.12065 -0.2794)
			(stroke
				(width 0.1)
				(type default)
			)
			(layer "F.Fab")
		)
		(fp_line
			(start -0.67945 0.3048)
			(end -0.67945 -0.305054)
			(stroke
				(width 0.1)
				(type default)
			)
			(layer "F.Fab")
		)
		(fp_line
			(start -0.67945 -0.305054)
			(end -0.12065 -0.305054)
			(stroke
				(width 0.1)
				(type default)
			)
			(layer "F.Fab")
		)
		(pad "1" smd circle
			(at -0.40005 0 180)
			(size 0 0)
			(layers "F.Cu" "F.Mask" "F.Paste")
			(net "GND")
		)
		(pad "2" smd circle
			(at 0.40005 0 180)
			(size 0 0)
			(layers "F.Cu" "F.Mask" "F.Paste")
			(net "FM_P0V8_PEX3_EN_R")
		)
	)
	(footprint ""
		(layer "F.Cu")
		(at 13.434822 -133.088126 180)
		(property "Reference" "PC353"
			(at 0 0 180)
			(layer "F.SilkS")
			(hide yes)
			(effects
				(font
					(size 1.27 1.27)
				)
			)
		)
		(property "Value" ""
			(at 0 0 180)
			(layer "F.Fab")
			(effects
				(font
					(size 1.27 1.27)
				)
			)
		)
		(duplicate_pad_numbers_are_jumpers no)
		(fp_line
			(start 1.524 0.762)
			(end -1.524 0.762)
			(stroke
				(width 0.1524)
				(type default)
			)
			(layer "F.SilkS")
		)
		(fp_line
			(start 1.524 -0.762)
			(end 1.524 0.762)
			(stroke
				(width 0.1524)
				(type default)
			)
			(layer "F.SilkS")
		)
		(fp_line
			(start -1.524 0.762)
			(end -1.524 -0.762)
			(stroke
				(width 0.1524)
				(type default)
			)
			(layer "F.SilkS")
		)
		(fp_line
			(start -1.524 -0.762)
			(end 1.524 -0.762)
			(stroke
				(width 0.1524)
				(type default)
			)
			(layer "F.SilkS")
		)
		(fp_line
			(start 1.1049 0.724916)
			(end 1.1049 -0.724916)
			(stroke
				(width 0.1)
				(type default)
			)
			(layer "F.Fab")
		)
		(fp_line
			(start 1.1049 -0.724916)
			(end -1.1049 -0.724916)
			(stroke
				(width 0.1)
				(type default)
			)
			(layer "F.Fab")
		)
		(fp_line
			(start -1.1049 0.724916)
			(end 1.1049 0.724916)
			(stroke
				(width 0.1)
				(type default)
			)
			(layer "F.Fab")
		)
		(fp_line
			(start -1.1049 -0.724916)
			(end -1.1049 0.724916)
			(stroke
				(width 0.1)
				(type default)
			)
			(layer "F.Fab")
		)
		(pad "1" smd rect
			(at -0.889 0)
			(size 1.016 1.27)
			(layers "F.Cu" "F.Mask" "F.Paste")
			(net "GND")
		)
		(pad "2" smd rect
			(at 0.889 0)
			(size 1.016 1.27)
			(layers "F.Cu" "F.Mask" "F.Paste")
			(net "P12V_AUX")
		)
	)
	(footprint ""
		(layer "F.Cu")
		(at 290.06673 -52.543456 180)
		(property "Reference" "PC572"
			(at 0 0 180)
			(layer "F.SilkS")
			(hide yes)
			(effects
				(font
					(size 1.27 1.27)
				)
			)
		)
		(property "Value" ""
			(at 0 0 180)
			(layer "F.Fab")
			(effects
				(font
					(size 1.27 1.27)
				)
			)
		)
		(duplicate_pad_numbers_are_jumpers no)
		(fp_line
			(start 0.7874 0.4064)
			(end -0.7874 0.4064)
			(stroke
				(width 0.1524)
				(type default)
			)
			(layer "F.SilkS")
		)
		(fp_line
			(start 0.7874 -0.4064)
			(end 0.7874 0.4064)
			(stroke
				(width 0.1524)
				(type default)
			)
			(layer "F.SilkS")
		)
		(fp_line
			(start -0.7874 0.4064)
			(end -0.7874 -0.4064)
			(stroke
				(width 0.1524)
				(type default)
			)
			(layer "F.SilkS")
		)
		(fp_line
			(start -0.7874 -0.4064)
			(end 0.7874 -0.4064)
			(stroke
				(width 0.1524)
				(type default)
			)
			(layer "F.SilkS")
		)
		(fp_line
			(start 0.67945 0.3048)
			(end 0.120396 0.3048)
			(stroke
				(width 0.1)
				(type default)
			)
			(layer "F.Fab")
		)
		(fp_line
			(start 0.67945 -0.3048)
			(end 0.67945 0.3048)
			(stroke
				(width 0.1)
				(type default)
			)
			(layer "F.Fab")
		)
		(fp_line
			(start 0.12065 -0.2794)
			(end 0.12065 -0.3048)
			(stroke
				(width 0.1)
				(type default)
			)
			(layer "F.Fab")
		)
		(fp_line
			(start 0.12065 -0.3048)
			(end 0.67945 -0.3048)
			(stroke
				(width 0.1)
				(type default)
			)
			(layer "F.Fab")
		)
		(fp_line
			(start 0.120396 0.3048)
			(end 0.120396 0.2794)
			(stroke
				(width 0.1)
				(type default)
			)
			(layer "F.Fab")
		)
		(fp_line
			(start 0.120396 0.2794)
			(end -0.12065 0.2794)
			(stroke
				(width 0.1)
				(type default)
			)
			(layer "F.Fab")
		)
		(fp_line
			(start -0.12065 0.3048)
			(end -0.67945 0.3048)
			(stroke
				(width 0.1)
				(type default)
			)
			(layer "F.Fab")
		)
		(fp_line
			(start -0.12065 0.2794)
			(end -0.12065 0.3048)
			(stroke
				(width 0.1)
				(type default)
			)
			(layer "F.Fab")
		)
		(fp_line
			(start -0.12065 -0.2794)
			(end 0.12065 -0.2794)
			(stroke
				(width 0.1)
				(type default)
			)
			(layer "F.Fab")
		)
		(fp_line
			(start -0.12065 -0.305054)
			(end -0.12065 -0.2794)
			(stroke
				(width 0.1)
				(type default)
			)
			(layer "F.Fab")
		)
		(fp_line
			(start -0.67945 0.3048)
			(end -0.67945 -0.305054)
			(stroke
				(width 0.1)
				(type default)
			)
			(layer "F.Fab")
		)
		(fp_line
			(start -0.67945 -0.305054)
			(end -0.12065 -0.305054)
			(stroke
				(width 0.1)
				(type default)
			)
			(layer "F.Fab")
		)
		(pad "1" smd circle
			(at -0.40005 0 180)
			(size 0 0)
			(layers "F.Cu" "F.Mask" "F.Paste")
			(net "P3V3_SSD10")
		)
		(pad "2" smd circle
			(at 0.40005 0 180)
			(size 0 0)
			(layers "F.Cu" "F.Mask" "F.Paste")
			(net "GND")
		)
	)
	(footprint ""
		(layer "F.Cu")
		(at 278.634444 -30.03169 180)
		(property "Reference" "C500"
			(at 0 0 180)
			(layer "F.SilkS")
			(hide yes)
			(effects
				(font
					(size 1.27 1.27)
				)
			)
		)
		(property "Value" ""
			(at 0 0 180)
			(layer "F.Fab")
			(effects
				(font
					(size 1.27 1.27)
				)
			)
		)
		(duplicate_pad_numbers_are_jumpers no)
		(fp_line
			(start 0.299974 0.150114)
			(end -0.299974 0.150114)
			(stroke
				(width 0.1)
				(type default)
			)
			(layer "F.Fab")
		)
		(fp_line
			(start 0.299974 -0.150114)
			(end 0.299974 0.150114)
			(stroke
				(width 0.1)
				(type default)
			)
			(layer "F.Fab")
		)
		(fp_line
			(start -0.299974 0.150114)
			(end -0.299974 -0.150114)
			(stroke
				(width 0.1)
				(type default)
			)
			(layer "F.Fab")
		)
		(fp_line
			(start -0.299974 -0.150114)
			(end 0.299974 -0.150114)
			(stroke
				(width 0.1)
				(type default)
			)
			(layer "F.Fab")
		)
		(pad "1" smd rect
			(at -0.2667 0 180)
			(size 0.3048 0.381)
			(layers "F.Cu" "F.Mask" "F.Paste")
			(net "P5E_PEX2_STN2_TX_DN<41>")
		)
		(pad "2" smd rect
			(at 0.2667 0 180)
			(size 0.3048 0.381)
			(layers "F.Cu" "F.Mask" "F.Paste")
			(net "P5E_PEX2_STN2_TX_C_DN<41>")
		)
	)
	(footprint ""
		(layer "F.Cu")
		(at 324.395846 -103.259128)
		(property "Reference" "C617"
			(at 0 0 0)
			(layer "F.SilkS")
			(hide yes)
			(effects
				(font
					(size 1.27 1.27)
				)
			)
		)
		(property "Value" ""
			(at 0 0 0)
			(layer "F.Fab")
			(effects
				(font
					(size 1.27 1.27)
				)
			)
		)
		(duplicate_pad_numbers_are_jumpers no)
		(fp_line
			(start -0.7874 -0.4064)
			(end 0.7874 -0.4064)
			(stroke
				(width 0.1524)
				(type default)
			)
			(layer "F.SilkS")
		)
		(fp_line
			(start -0.7874 0.4064)
			(end -0.7874 -0.4064)
			(stroke
				(width 0.1524)
				(type default)
			)
			(layer "F.SilkS")
		)
		(fp_line
			(start 0.7874 -0.4064)
			(end 0.7874 0.4064)
			(stroke
				(width 0.1524)
				(type default)
			)
			(layer "F.SilkS")
		)
		(fp_line
			(start 0.7874 0.4064)
			(end -0.7874 0.4064)
			(stroke
				(width 0.1524)
				(type default)
			)
			(layer "F.SilkS")
		)
		(fp_line
			(start -0.67945 -0.305054)
			(end -0.12065 -0.305054)
			(stroke
				(width 0.1)
				(type default)
			)
			(layer "F.Fab")
		)
		(fp_line
			(start -0.67945 0.3048)
			(end -0.67945 -0.305054)
			(stroke
				(width 0.1)
				(type default)
			)
			(layer "F.Fab")
		)
		(fp_line
			(start -0.12065 -0.305054)
			(end -0.12065 -0.2794)
			(stroke
				(width 0.1)
				(type default)
			)
			(layer "F.Fab")
		)
		(fp_line
			(start -0.12065 -0.2794)
			(end 0.12065 -0.2794)
			(stroke
				(width 0.1)
				(type default)
			)
			(layer "F.Fab")
		)
		(fp_line
			(start -0.12065 0.2794)
			(end -0.12065 0.3048)
			(stroke
				(width 0.1)
				(type default)
			)
			(layer "F.Fab")
		)
		(fp_line
			(start -0.12065 0.3048)
			(end -0.67945 0.3048)
			(stroke
				(width 0.1)
				(type default)
			)
			(layer "F.Fab")
		)
		(fp_line
			(start 0.120396 0.2794)
			(end -0.12065 0.2794)
			(stroke
				(width 0.1)
				(type default)
			)
			(layer "F.Fab")
		)
		(fp_line
			(start 0.120396 0.3048)
			(end 0.120396 0.2794)
			(stroke
				(width 0.1)
				(type default)
			)
			(layer "F.Fab")
		)
		(fp_line
			(start 0.12065 -0.3048)
			(end 0.67945 -0.3048)
			(stroke
				(width 0.1)
				(type default)
			)
			(layer "F.Fab")
		)
		(fp_line
			(start 0.12065 -0.2794)
			(end 0.12065 -0.3048)
			(stroke
				(width 0.1)
				(type default)
			)
			(layer "F.Fab")
		)
		(fp_line
			(start 0.67945 -0.3048)
			(end 0.67945 0.3048)
			(stroke
				(width 0.1)
				(type default)
			)
			(layer "F.Fab")
		)
		(fp_line
			(start 0.67945 0.3048)
			(end 0.120396 0.3048)
			(stroke
				(width 0.1)
				(type default)
			)
			(layer "F.Fab")
		)
		(pad "1" smd circle
			(at -0.40005 0)
			(size 0 0)
			(layers "F.Cu" "F.Mask" "F.Paste")
			(net "P12V_NIC5_R")
		)
		(pad "2" smd circle
			(at 0.40005 0)
			(size 0 0)
			(layers "F.Cu" "F.Mask" "F.Paste")
			(net "GND")
		)
	)
	(footprint ""
		(layer "F.Cu")
		(at 25.358344 -250.070874 -90)
		(property "Reference" "R1159"
			(at 0 0 270)
			(layer "F.SilkS")
			(hide yes)
			(effects
				(font
					(size 1.27 1.27)
				)
			)
		)
		(property "Value" ""
			(at 0 0 270)
			(layer "F.Fab")
			(effects
				(font
					(size 1.27 1.27)
				)
			)
		)
		(duplicate_pad_numbers_are_jumpers no)
		(fp_line
			(start -0.7874 0.4064)
			(end -0.7874 -0.4064)
			(stroke
				(width 0.1524)
				(type default)
			)
			(layer "F.SilkS")
		)
		(fp_line
			(start 0.7874 0.4064)
			(end -0.7874 0.4064)
			(stroke
				(width 0.1524)
				(type default)
			)
			(layer "F.SilkS")
		)
		(fp_line
			(start -0.7874 -0.4064)
			(end 0.7874 -0.4064)
			(stroke
				(width 0.1524)
				(type default)
			)
			(layer "F.SilkS")
		)
		(fp_line
			(start 0.7874 -0.4064)
			(end 0.7874 0.4064)
			(stroke
				(width 0.1524)
				(type default)
			)
			(layer "F.SilkS")
		)
		(fp_line
			(start -0.67945 0.3048)
			(end -0.67945 -0.305054)
			(stroke
				(width 0.1)
				(type default)
			)
			(layer "F.Fab")
		)
		(fp_line
			(start -0.12065 0.3048)
			(end -0.67945 0.3048)
			(stroke
				(width 0.1)
				(type default)
			)
			(layer "F.Fab")
		)
		(fp_line
			(start 0.120396 0.3048)
			(end 0.120396 0.2794)
			(stroke
				(width 0.1)
				(type default)
			)
			(layer "F.Fab")
		)
		(fp_line
			(start 0.67945 0.3048)
			(end 0.120396 0.3048)
			(stroke
				(width 0.1)
				(type default)
			)
			(layer "F.Fab")
		)
		(fp_line
			(start -0.12065 0.2794)
			(end -0.12065 0.3048)
			(stroke
				(width 0.1)
				(type default)
			)
			(layer "F.Fab")
		)
		(fp_line
			(start 0.120396 0.2794)
			(end -0.12065 0.2794)
			(stroke
				(width 0.1)
				(type default)
			)
			(layer "F.Fab")
		)
		(fp_line
			(start -0.12065 -0.2794)
			(end 0.12065 -0.2794)
			(stroke
				(width 0.1)
				(type default)
			)
			(layer "F.Fab")
		)
		(fp_line
			(start 0.12065 -0.2794)
			(end 0.12065 -0.3048)
			(stroke
				(width 0.1)
				(type default)
			)
			(layer "F.Fab")
		)
		(fp_line
			(start 0.12065 -0.3048)
			(end 0.67945 -0.3048)
			(stroke
				(width 0.1)
				(type default)
			)
			(layer "F.Fab")
		)
		(fp_line
			(start 0.67945 -0.3048)
			(end 0.67945 0.3048)
			(stroke
				(width 0.1)
				(type default)
			)
			(layer "F.Fab")
		)
		(fp_line
			(start -0.67945 -0.305054)
			(end -0.12065 -0.305054)
			(stroke
				(width 0.1)
				(type default)
			)
			(layer "F.Fab")
		)
		(fp_line
			(start -0.12065 -0.305054)
			(end -0.12065 -0.2794)
			(stroke
				(width 0.1)
				(type default)
			)
			(layer "F.Fab")
		)
		(pad "1" smd circle
			(at -0.40005 0 270)
			(size 0 0)
			(layers "F.Cu" "F.Mask" "F.Paste")
			(net "PEX0_MODE_SEL7")
		)
		(pad "2" smd circle
			(at 0.40005 0 270)
			(size 0 0)
			(layers "F.Cu" "F.Mask" "F.Paste")
			(net "P1V8_PEX")
		)
	)
	(footprint ""
		(layer "F.Cu")
		(at 181.728872 -350.098614 90)
		(property "Reference" "C2531"
			(at 0 0 90)
			(layer "F.SilkS")
			(hide yes)
			(effects
				(font
					(size 1.27 1.27)
				)
			)
		)
		(property "Value" ""
			(at 0 0 90)
			(layer "F.Fab")
			(effects
				(font
					(size 1.27 1.27)
				)
			)
		)
		(duplicate_pad_numbers_are_jumpers no)
		(fp_line
			(start 0.299974 -0.150114)
			(end 0.299974 0.150114)
			(stroke
				(width 0.1)
				(type default)
			)
			(layer "F.Fab")
		)
		(fp_line
			(start -0.299974 -0.150114)
			(end 0.299974 -0.150114)
			(stroke
				(width 0.1)
				(type default)
			)
			(layer "F.Fab")
		)
		(fp_line
			(start 0.299974 0.150114)
			(end -0.299974 0.150114)
			(stroke
				(width 0.1)
				(type default)
			)
			(layer "F.Fab")
		)
		(fp_line
			(start -0.299974 0.150114)
			(end -0.299974 -0.150114)
			(stroke
				(width 0.1)
				(type default)
			)
			(layer "F.Fab")
		)
		(pad "1" smd rect
			(at -0.2667 0 90)
			(size 0.3048 0.381)
			(layers "F.Cu" "F.Mask" "F.Paste")
			(net "P5E_PEX1_STN4_TX_DN<70>")
		)
		(pad "2" smd rect
			(at 0.2667 0 90)
			(size 0.3048 0.381)
			(layers "F.Cu" "F.Mask" "F.Paste")
			(net "P5E_PEX1_STN4_TX_C_DN<70>")
		)
	)
	(footprint ""
		(layer "F.Cu")
		(at 130.26263 -94.16542)
		(property "Reference" "U124"
			(at -2.1844 -4.587748 0)
			(unlocked yes)
			(layer "F.SilkS")
			(effects
				(font
					(size 0.7874 0.5842)
					(thickness 0.1524)
				)
				(justify left)
			)
		)
		(property "Value" ""
			(at 0 0 0)
			(layer "F.Fab")
			(effects
				(font
					(size 1.27 1.27)
				)
			)
		)
		(duplicate_pad_numbers_are_jumpers no)
		(fp_line
			(start -1.8542 -3.949954)
			(end -1.8542 3.949954)
			(stroke
				(width 0.1524)
				(type default)
			)
			(layer "F.SilkS")
		)
		(fp_line
			(start -1.8542 3.949954)
			(end 1.8542 3.949954)
			(stroke
				(width 0.1524)
				(type default)
			)
			(layer "F.SilkS")
		)
		(fp_line
			(start -1.282954 -3.949954)
			(end -1.8542 -3.949954)
			(stroke
				(width 0.1524)
				(type default)
			)
			(layer "F.SilkS")
		)
		(fp_line
			(start 0 -2.667)
			(end -1.282954 -3.949954)
			(stroke
				(width 0.1524)
				(type default)
			)
			(layer "F.SilkS")
		)
		(fp_line
			(start 1.282954 -3.949954)
			(end 0 -2.667)
			(stroke
				(width 0.1524)
				(type default)
			)
			(layer "F.SilkS")
		)
		(fp_line
			(start 1.8542 -3.949954)
			(end 1.282954 -3.949954)
			(stroke
				(width 0.1524)
				(type default)
			)
			(layer "F.SilkS")
		)
		(fp_line
			(start 1.8542 3.949954)
			(end 1.8542 -3.949954)
			(stroke
				(width 0.1524)
				(type default)
			)
			(layer "F.SilkS")
		)
		(fp_poly
			(pts
				(xy -4.8006 -4.08305) (xy -4.8006 -3.06705) (xy -3.7846 -3.57505)
			)
			(stroke
				(width 0)
				(type default)
			)
			(fill yes)
			(layer "F.SilkS")
		)
		(fp_line
			(start -2.249932 -3.949954)
			(end -2.249932 3.949954)
			(stroke
				(width 0.1)
				(type default)
			)
			(layer "F.Fab")
		)
		(fp_line
			(start -2.249932 3.949954)
			(end 2.249932 3.949954)
			(stroke
				(width 0.1)
				(type default)
			)
			(layer "F.Fab")
		)
		(fp_line
			(start 2.249932 -3.949954)
			(end -2.249932 -3.949954)
			(stroke
				(width 0.1)
				(type default)
			)
			(layer "F.Fab")
		)
		(fp_line
			(start 2.249932 3.949954)
			(end 2.249932 -3.949954)
			(stroke
				(width 0.1)
				(type default)
			)
			(layer "F.Fab")
		)
		(fp_poly
			(pts
				(xy -4.8006 -4.08305) (xy -4.8006 -3.06705) (xy -3.7846 -3.57505)
			)
			(stroke
				(width 0)
				(type default)
			)
			(fill yes)
			(layer "F.Fab")
		)
		(pad "1" smd rect
			(at -2.800096 -3.57505 270)
			(size 0.3048 1.6002)
			(layers "F.Cu" "F.Mask" "F.Paste")
			(net "BIC_I2C9_SSD_MUX0_A0")
		)
		(pad "2" smd rect
			(at -2.800096 -2.925064 270)
			(size 0.3048 1.6002)
			(layers "F.Cu" "F.Mask" "F.Paste")
			(net "BIC_I2C9_SSD_MUX0_A1")
		)
		(pad "3" smd rect
			(at -2.800096 -2.275078 270)
			(size 0.3048 1.6002)
			(layers "F.Cu" "F.Mask" "F.Paste")
			(net "RST_BIC_I2C9_SSD_MUX0_R_N")
		)
		(pad "4" smd rect
			(at -2.800096 -1.625092 270)
			(size 0.3048 1.6002)
			(layers "F.Cu" "F.Mask" "F.Paste")
			(net "SMB_BIC_I2C9_MUX0_SSD0_SDA")
		)
		(pad "5" smd rect
			(at -2.800096 -0.975106 270)
			(size 0.3048 1.6002)
			(layers "F.Cu" "F.Mask" "F.Paste")
			(net "SMB_BIC_I2C9_MUX0_SSD0_SCL")
		)
		(pad "6" smd rect
			(at -2.800096 -0.32512 270)
			(size 0.3048 1.6002)
			(layers "F.Cu" "F.Mask" "F.Paste")
			(net "SMB_BIC_I2C9_MUX0_SSD1_SDA")
		)
		(pad "7" smd rect
			(at -2.800096 0.32512 270)
			(size 0.3048 1.6002)
			(layers "F.Cu" "F.Mask" "F.Paste")
			(net "SMB_BIC_I2C9_MUX0_SSD1_SCL")
		)
		(pad "8" smd rect
			(at -2.800096 0.975106 270)
			(size 0.3048 1.6002)
			(layers "F.Cu" "F.Mask" "F.Paste")
			(net "SMB_BIC_I2C9_MUX0_SSD2_SDA")
		)
		(pad "9" smd rect
			(at -2.800096 1.625092 270)
			(size 0.3048 1.6002)
			(layers "F.Cu" "F.Mask" "F.Paste")
			(net "SMB_BIC_I2C9_MUX0_SSD2_SCL")
		)
		(pad "10" smd rect
			(at -2.800096 2.275078 270)
			(size 0.3048 1.6002)
			(layers "F.Cu" "F.Mask" "F.Paste")
			(net "SMB_BIC_I2C9_MUX0_SSD3_SDA")
		)
		(pad "11" smd rect
			(at -2.800096 2.925064 270)
			(size 0.3048 1.6002)
			(layers "F.Cu" "F.Mask" "F.Paste")
			(net "SMB_BIC_I2C9_MUX0_SSD3_SCL")
		)
		(pad "12" smd rect
			(at -2.800096 3.57505 270)
			(size 0.3048 1.6002)
			(layers "F.Cu" "F.Mask" "F.Paste")
			(net "GND")
		)
		(pad "13" smd rect
			(at 2.800096 3.57505 270)
			(size 0.3048 1.6002)
			(layers "F.Cu" "F.Mask" "F.Paste")
			(net "SMB_BIC_I2C9_MUX0_SSD4_SDA")
		)
		(pad "14" smd rect
			(at 2.800096 2.925064 270)
			(size 0.3048 1.6002)
			(layers "F.Cu" "F.Mask" "F.Paste")
			(net "SMB_BIC_I2C9_MUX0_SSD4_SCL")
		)
		(pad "15" smd rect
			(at 2.800096 2.275078 270)
			(size 0.3048 1.6002)
			(layers "F.Cu" "F.Mask" "F.Paste")
			(net "SMB_BIC_I2C9_MUX0_SSD5_SDA")
		)
		(pad "16" smd rect
			(at 2.800096 1.625092 270)
			(size 0.3048 1.6002)
			(layers "F.Cu" "F.Mask" "F.Paste")
			(net "SMB_BIC_I2C9_MUX0_SSD5_SCL")
		)
		(pad "17" smd rect
			(at 2.800096 0.975106 270)
			(size 0.3048 1.6002)
			(layers "F.Cu" "F.Mask" "F.Paste")
			(net "SMB_BIC_I2C9_MUX0_SSD6_SDA")
		)
		(pad "18" smd rect
			(at 2.800096 0.32512 270)
			(size 0.3048 1.6002)
			(layers "F.Cu" "F.Mask" "F.Paste")
			(net "SMB_BIC_I2C9_MUX0_SSD6_SCL")
		)
		(pad "19" smd rect
			(at 2.800096 -0.32512 270)
			(size 0.3048 1.6002)
			(layers "F.Cu" "F.Mask" "F.Paste")
			(net "SMB_BIC_I2C9_MUX0_SSD7_SDA")
		)
		(pad "20" smd rect
			(at 2.800096 -0.975106 270)
			(size 0.3048 1.6002)
			(layers "F.Cu" "F.Mask" "F.Paste")
			(net "SMB_BIC_I2C9_MUX0_SSD7_SCL")
		)
		(pad "21" smd rect
			(at 2.800096 -1.625092 270)
			(size 0.3048 1.6002)
			(layers "F.Cu" "F.Mask" "F.Paste")
			(net "BIC_I2C9_SSD_MUX0_A2")
		)
		(pad "22" smd rect
			(at 2.800096 -2.275078 270)
			(size 0.3048 1.6002)
			(layers "F.Cu" "F.Mask" "F.Paste")
			(net "SMB_BIC_I2C9_SSD_MUX0_SCL")
		)
		(pad "23" smd rect
			(at 2.800096 -2.925064 270)
			(size 0.3048 1.6002)
			(layers "F.Cu" "F.Mask" "F.Paste")
			(net "SMB_BIC_I2C9_SSD_MUX0_SDA")
		)
		(pad "24" smd rect
			(at 2.800096 -3.57505 270)
			(size 0.3048 1.6002)
			(layers "F.Cu" "F.Mask" "F.Paste")
			(net "P3V3_AUX")
		)
	)
	(footprint ""
		(layer "F.Cu")
		(at 139.724892 -259.378958)
		(property "Reference" "R1328"
			(at 0 0 0)
			(layer "F.SilkS")
			(hide yes)
			(effects
				(font
					(size 1.27 1.27)
				)
			)
		)
		(property "Value" ""
			(at 0 0 0)
			(layer "F.Fab")
			(effects
				(font
					(size 1.27 1.27)
				)
			)
		)
		(duplicate_pad_numbers_are_jumpers no)
		(fp_line
			(start -0.7874 -0.4064)
			(end 0.7874 -0.4064)
			(stroke
				(width 0.1524)
				(type default)
			)
			(layer "F.SilkS")
		)
		(fp_line
			(start -0.7874 0.4064)
			(end -0.7874 -0.4064)
			(stroke
				(width 0.1524)
				(type default)
			)
			(layer "F.SilkS")
		)
		(fp_line
			(start 0.7874 -0.4064)
			(end 0.7874 0.4064)
			(stroke
				(width 0.1524)
				(type default)
			)
			(layer "F.SilkS")
		)
		(fp_line
			(start 0.7874 0.4064)
			(end -0.7874 0.4064)
			(stroke
				(width 0.1524)
				(type default)
			)
			(layer "F.SilkS")
		)
		(fp_line
			(start -0.67945 -0.305054)
			(end -0.12065 -0.305054)
			(stroke
				(width 0.1)
				(type default)
			)
			(layer "F.Fab")
		)
		(fp_line
			(start -0.67945 0.3048)
			(end -0.67945 -0.305054)
			(stroke
				(width 0.1)
				(type default)
			)
			(layer "F.Fab")
		)
		(fp_line
			(start -0.12065 -0.305054)
			(end -0.12065 -0.2794)
			(stroke
				(width 0.1)
				(type default)
			)
			(layer "F.Fab")
		)
		(fp_line
			(start -0.12065 -0.2794)
			(end 0.12065 -0.2794)
			(stroke
				(width 0.1)
				(type default)
			)
			(layer "F.Fab")
		)
		(fp_line
			(start -0.12065 0.2794)
			(end -0.12065 0.3048)
			(stroke
				(width 0.1)
				(type default)
			)
			(layer "F.Fab")
		)
		(fp_line
			(start -0.12065 0.3048)
			(end -0.67945 0.3048)
			(stroke
				(width 0.1)
				(type default)
			)
			(layer "F.Fab")
		)
		(fp_line
			(start 0.120396 0.2794)
			(end -0.12065 0.2794)
			(stroke
				(width 0.1)
				(type default)
			)
			(layer "F.Fab")
		)
		(fp_line
			(start 0.120396 0.3048)
			(end 0.120396 0.2794)
			(stroke
				(width 0.1)
				(type default)
			)
			(layer "F.Fab")
		)
		(fp_line
			(start 0.12065 -0.3048)
			(end 0.67945 -0.3048)
			(stroke
				(width 0.1)
				(type default)
			)
			(layer "F.Fab")
		)
		(fp_line
			(start 0.12065 -0.2794)
			(end 0.12065 -0.3048)
			(stroke
				(width 0.1)
				(type default)
			)
			(layer "F.Fab")
		)
		(fp_line
			(start 0.67945 -0.3048)
			(end 0.67945 0.3048)
			(stroke
				(width 0.1)
				(type default)
			)
			(layer "F.Fab")
		)
		(fp_line
			(start 0.67945 0.3048)
			(end 0.120396 0.3048)
			(stroke
				(width 0.1)
				(type default)
			)
			(layer "F.Fab")
		)
		(pad "1" smd circle
			(at -0.40005 0)
			(size 0 0)
			(layers "F.Cu" "F.Mask" "F.Paste")
			(net "PEX1_SYS_ERR_N_G")
		)
		(pad "2" smd circle
			(at 0.40005 0)
			(size 0 0)
			(layers "F.Cu" "F.Mask" "F.Paste")
			(net "P3V3_AUX")
		)
	)
	(footprint ""
		(layer "F.Cu")
		(at 428.957486 -107.552998 -90)
		(property "Reference" "C951"
			(at 0 0 270)
			(layer "F.SilkS")
			(hide yes)
			(effects
				(font
					(size 1.27 1.27)
				)
			)
		)
		(property "Value" ""
			(at 0 0 270)
			(layer "F.Fab")
			(effects
				(font
					(size 1.27 1.27)
				)
			)
		)
		(duplicate_pad_numbers_are_jumpers no)
		(fp_line
			(start -1.524 0.762)
			(end -1.524 -0.762)
			(stroke
				(width 0.1524)
				(type default)
			)
			(layer "F.SilkS")
		)
		(fp_line
			(start 1.524 0.762)
			(end -1.524 0.762)
			(stroke
				(width 0.1524)
				(type default)
			)
			(layer "F.SilkS")
		)
		(fp_line
			(start -1.524 -0.762)
			(end 1.524 -0.762)
			(stroke
				(width 0.1524)
				(type default)
			)
			(layer "F.SilkS")
		)
		(fp_line
			(start 1.524 -0.762)
			(end 1.524 0.762)
			(stroke
				(width 0.1524)
				(type default)
			)
			(layer "F.SilkS")
		)
		(fp_line
			(start -1.1049 0.724916)
			(end 1.1049 0.724916)
			(stroke
				(width 0.1)
				(type default)
			)
			(layer "F.Fab")
		)
		(fp_line
			(start 1.1049 0.724916)
			(end 1.1049 -0.724916)
			(stroke
				(width 0.1)
				(type default)
			)
			(layer "F.Fab")
		)
		(fp_line
			(start -1.1049 -0.724916)
			(end -1.1049 0.724916)
			(stroke
				(width 0.1)
				(type default)
			)
			(layer "F.Fab")
		)
		(fp_line
			(start 1.1049 -0.724916)
			(end -1.1049 -0.724916)
			(stroke
				(width 0.1)
				(type default)
			)
			(layer "F.Fab")
		)
		(pad "1" smd rect
			(at -0.889 0 90)
			(size 1.016 1.27)
			(layers "F.Cu" "F.Mask" "F.Paste")
			(net "P12V_NIC7")
		)
		(pad "2" smd rect
			(at 0.889 0 90)
			(size 1.016 1.27)
			(layers "F.Cu" "F.Mask" "F.Paste")
			(net "GND")
		)
	)
	(footprint ""
		(layer "F.Cu")
		(at 79.332074 -32.848042 90)
		(property "Reference" "PC687"
			(at 0 0 90)
			(layer "F.SilkS")
			(hide yes)
			(effects
				(font
					(size 1.27 1.27)
				)
			)
		)
		(property "Value" ""
			(at 0 0 90)
			(layer "F.Fab")
			(effects
				(font
					(size 1.27 1.27)
				)
			)
		)
		(duplicate_pad_numbers_are_jumpers no)
		(fp_line
			(start 0.7874 -0.4064)
			(end 0.7874 0.4064)
			(stroke
				(width 0.1524)
				(type default)
			)
			(layer "F.SilkS")
		)
		(fp_line
			(start -0.7874 -0.4064)
			(end 0.7874 -0.4064)
			(stroke
				(width 0.1524)
				(type default)
			)
			(layer "F.SilkS")
		)
		(fp_line
			(start 0.7874 0.4064)
			(end -0.7874 0.4064)
			(stroke
				(width 0.1524)
				(type default)
			)
			(layer "F.SilkS")
		)
		(fp_line
			(start -0.7874 0.4064)
			(end -0.7874 -0.4064)
			(stroke
				(width 0.1524)
				(type default)
			)
			(layer "F.SilkS")
		)
		(fp_line
			(start -0.12065 -0.305054)
			(end -0.12065 -0.2794)
			(stroke
				(width 0.1)
				(type default)
			)
			(layer "F.Fab")
		)
		(fp_line
			(start -0.67945 -0.305054)
			(end -0.12065 -0.305054)
			(stroke
				(width 0.1)
				(type default)
			)
			(layer "F.Fab")
		)
		(fp_line
			(start 0.67945 -0.3048)
			(end 0.67945 0.3048)
			(stroke
				(width 0.1)
				(type default)
			)
			(layer "F.Fab")
		)
		(fp_line
			(start 0.12065 -0.3048)
			(end 0.67945 -0.3048)
			(stroke
				(width 0.1)
				(type default)
			)
			(layer "F.Fab")
		)
		(fp_line
			(start 0.12065 -0.2794)
			(end 0.12065 -0.3048)
			(stroke
				(width 0.1)
				(type default)
			)
			(layer "F.Fab")
		)
		(fp_line
			(start -0.12065 -0.2794)
			(end 0.12065 -0.2794)
			(stroke
				(width 0.1)
				(type default)
			)
			(layer "F.Fab")
		)
		(fp_line
			(start 0.120396 0.2794)
			(end -0.12065 0.2794)
			(stroke
				(width 0.1)
				(type default)
			)
			(layer "F.Fab")
		)
		(fp_line
			(start -0.12065 0.2794)
			(end -0.12065 0.3048)
			(stroke
				(width 0.1)
				(type default)
			)
			(layer "F.Fab")
		)
		(fp_line
			(start 0.67945 0.3048)
			(end 0.120396 0.3048)
			(stroke
				(width 0.1)
				(type default)
			)
			(layer "F.Fab")
		)
		(fp_line
			(start 0.120396 0.3048)
			(end 0.120396 0.2794)
			(stroke
				(width 0.1)
				(type default)
			)
			(layer "F.Fab")
		)
		(fp_line
			(start -0.12065 0.3048)
			(end -0.67945 0.3048)
			(stroke
				(width 0.1)
				(type default)
			)
			(layer "F.Fab")
		)
		(fp_line
			(start -0.67945 0.3048)
			(end -0.67945 -0.305054)
			(stroke
				(width 0.1)
				(type default)
			)
			(layer "F.Fab")
		)
		(pad "1" smd circle
			(at -0.40005 0 90)
			(size 0 0)
			(layers "F.Cu" "F.Mask" "F.Paste")
			(net "P3V3_SSD3_CO_DV_DT")
		)
		(pad "2" smd circle
			(at 0.40005 0 90)
			(size 0 0)
			(layers "F.Cu" "F.Mask" "F.Paste")
			(net "GND")
		)
	)
	(footprint ""
		(layer "F.Cu")
		(at 344.612976 -90.169746 180)
		(property "Reference" "R1183"
			(at 0 0 180)
			(layer "F.SilkS")
			(hide yes)
			(effects
				(font
					(size 1.27 1.27)
				)
			)
		)
		(property "Value" ""
			(at 0 0 180)
			(layer "F.Fab")
			(effects
				(font
					(size 1.27 1.27)
				)
			)
		)
		(duplicate_pad_numbers_are_jumpers no)
		(fp_line
			(start 0.7874 0.4064)
			(end -0.7874 0.4064)
			(stroke
				(width 0.1524)
				(type default)
			)
			(layer "F.SilkS")
		)
		(fp_line
			(start 0.67945 0.3048)
			(end 0.120396 0.3048)
			(stroke
				(width 0.1)
				(type default)
			)
			(layer "F.Fab")
		)
		(fp_line
			(start 0.67945 -0.3048)
			(end 0.67945 0.3048)
			(stroke
				(width 0.1)
				(type default)
			)
			(layer "F.Fab")
		)
		(fp_line
			(start 0.12065 -0.2794)
			(end 0.12065 -0.3048)
			(stroke
				(width 0.1)
				(type default)
			)
			(layer "F.Fab")
		)
		(fp_line
			(start 0.12065 -0.3048)
			(end 0.67945 -0.3048)
			(stroke
				(width 0.1)
				(type default)
			)
			(layer "F.Fab")
		)
		(fp_line
			(start 0.120396 0.3048)
			(end 0.120396 0.2794)
			(stroke
				(width 0.1)
				(type default)
			)
			(layer "F.Fab")
		)
		(fp_line
			(start 0.120396 0.2794)
			(end -0.12065 0.2794)
			(stroke
				(width 0.1)
				(type default)
			)
			(layer "F.Fab")
		)
		(fp_line
			(start -0.12065 0.3048)
			(end -0.67945 0.3048)
			(stroke
				(width 0.1)
				(type default)
			)
			(layer "F.Fab")
		)
		(fp_line
			(start -0.12065 0.2794)
			(end -0.12065 0.3048)
			(stroke
				(width 0.1)
				(type default)
			)
			(layer "F.Fab")
		)
		(fp_line
			(start -0.12065 -0.2794)
			(end 0.12065 -0.2794)
			(stroke
				(width 0.1)
				(type default)
			)
			(layer "F.Fab")
		)
		(fp_line
			(start -0.12065 -0.305054)
			(end -0.12065 -0.2794)
			(stroke
				(width 0.1)
				(type default)
			)
			(layer "F.Fab")
		)
		(fp_line
			(start -0.67945 0.3048)
			(end -0.67945 -0.305054)
			(stroke
				(width 0.1)
				(type default)
			)
			(layer "F.Fab")
		)
		(fp_line
			(start -0.67945 -0.305054)
			(end -0.12065 -0.305054)
			(stroke
				(width 0.1)
				(type default)
			)
			(layer "F.Fab")
		)
		(pad "1" smd circle
			(at -0.40005 0 180)
			(size 0 0)
			(layers "F.Cu" "F.Mask" "F.Paste")
			(net "CLK_100M_DB800ZL_SSD14_R_DN")
		)
		(pad "2" smd circle
			(at 0.40005 0 180)
			(size 0 0)
			(layers "F.Cu" "F.Mask" "F.Paste")
			(net "CLK_100M_DB800ZL_SSD14_DN")
		)
	)
	(footprint ""
		(layer "F.Cu")
		(at 48.647096 -54.3941)
		(property "Reference" "PU32"
			(at -1.707642 3.085592 0)
			(unlocked yes)
			(layer "F.SilkS")
			(effects
				(font
					(size 0.7874 0.5842)
					(thickness 0.1524)
				)
				(justify left)
			)
		)
		(property "Value" ""
			(at 0 0 0)
			(layer "F.Fab")
			(effects
				(font
					(size 1.27 1.27)
				)
			)
		)
		(duplicate_pad_numbers_are_jumpers no)
		(fp_line
			(start -1.943608 -1.549908)
			(end 1.943608 -1.549908)
			(stroke
				(width 0.1524)
				(type default)
			)
			(layer "F.SilkS")
		)
		(fp_line
			(start -1.943608 1.549908)
			(end -1.943608 -1.549908)
			(stroke
				(width 0.1524)
				(type default)
			)
			(layer "F.SilkS")
		)
		(fp_line
			(start 1.943608 -1.549908)
			(end 1.943608 1.549908)
			(stroke
				(width 0.1524)
				(type default)
			)
			(layer "F.SilkS")
		)
		(fp_line
			(start 1.943608 1.549908)
			(end -1.943608 1.549908)
			(stroke
				(width 0.1524)
				(type default)
			)
			(layer "F.SilkS")
		)
		(fp_poly
			(pts
				(xy -2.019808 -1.549908) (xy -1.257808 -1.549908) (xy -1.257808 -1.880108) (xy -2.019808 -1.880108)
			)
			(stroke
				(width 0)
				(type default)
			)
			(fill yes)
			(layer "F.SilkS")
		)
		(fp_line
			(start -1.549908 -1.549908)
			(end 1.549908 -1.549908)
			(stroke
				(width 0.1)
				(type default)
			)
			(layer "F.Fab")
		)
		(fp_line
			(start -1.549908 1.549908)
			(end -1.549908 -1.549908)
			(stroke
				(width 0.1)
				(type default)
			)
			(layer "F.Fab")
		)
		(fp_line
			(start 1.549908 -1.549908)
			(end 1.549908 1.549908)
			(stroke
				(width 0.1)
				(type default)
			)
			(layer "F.Fab")
		)
		(fp_line
			(start 1.549908 1.549908)
			(end -1.549908 1.549908)
			(stroke
				(width 0.1)
				(type default)
			)
			(layer "F.Fab")
		)
		(fp_poly
			(pts
				(xy -2.019808 -1.549908) (xy -1.257808 -1.549908) (xy -1.257808 -1.880108) (xy -2.019808 -1.880108)
			)
			(stroke
				(width 0)
				(type default)
			)
			(fill yes)
			(layer "F.Fab")
		)
		(pad "1" smd rect
			(at -1.500124 -1.249934 270)
			(size 0.2794 0.6096)
			(layers "F.Cu" "F.Mask" "F.Paste")
			(net "P12V_SSD1_R")
		)
		(pad "2" smd rect
			(at -1.500124 -0.750062 270)
			(size 0.2794 0.6096)
			(layers "F.Cu" "F.Mask" "F.Paste")
			(net "P12V_SSD1_R")
		)
		(pad "3" smd rect
			(at -1.500124 -0.249936 270)
			(size 0.2794 0.6096)
			(layers "F.Cu" "F.Mask" "F.Paste")
			(net "P12V_SSD1_R")
		)
		(pad "4" smd rect
			(at -1.500124 0.249936 270)
			(size 0.2794 0.6096)
			(layers "F.Cu" "F.Mask" "F.Paste")
			(net "P12V_SSD1_R")
		)
		(pad "5" smd rect
			(at -1.500124 0.750062 270)
			(size 0.2794 0.6096)
			(layers "F.Cu" "F.Mask" "F.Paste")
			(net "P12V_SSD1_R")
		)
		(pad "6" smd rect
			(at -1.500124 1.249934 270)
			(size 0.2794 0.6096)
			(layers "F.Cu" "F.Mask" "F.Paste")
			(net "GND")
		)
		(pad "7" smd rect
			(at 1.500124 1.249934 270)
			(size 0.2794 0.6096)
			(layers "F.Cu" "F.Mask" "F.Paste")
			(net "P12V_SSD1_SS")
		)
		(pad "8" smd rect
			(at 1.500124 0.750062 270)
			(size 0.2794 0.6096)
			(layers "F.Cu" "F.Mask" "F.Paste")
			(net "PWRGD_P12V_SSD1")
		)
		(pad "9" smd rect
			(at 1.500124 0.249936 270)
			(size 0.2794 0.6096)
			(layers "F.Cu" "F.Mask" "F.Paste")
			(net "P12V_SSD1_OCP")
		)
		(pad "10" smd rect
			(at 1.500124 -0.249936 270)
			(size 0.2794 0.6096)
			(layers "F.Cu" "F.Mask" "F.Paste")
			(net "P5V_AUX")
		)
		(pad "11" smd rect
			(at 1.500124 -0.750062 270)
			(size 0.2794 0.6096)
			(layers "F.Cu" "F.Mask" "F.Paste")
			(net "SSD1_PWR_EN_R")
		)
		(pad "12" smd rect
			(at 1.500124 -1.249934 270)
			(size 0.2794 0.6096)
			(layers "F.Cu" "F.Mask" "F.Paste")
			(net "P12V_AUX")
		)
		(pad "13" smd rect
			(at 0 0)
			(size 1.9812 2.7178)
			(layers "F.Cu" "F.Mask" "F.Paste")
			(net "P12V_AUX")
		)
		(zone
			(layer "F.Cu")
			(hatch none 0.5)
			(connect_pads
				(clearance 0)
			)
			(min_thickness 0.25)
			(keepout
				(tracks not_allowed)
				(vias allowed)
				(pads allowed)
				(copperpour not_allowed)
				(footprints allowed)
			)
			(placement
				(enabled no)
				(sheetname "")
			)
			(fill
				(thermal_gap 0.5)
				(thermal_bridge_width 0.5)
				(island_removal_mode 0)
			)
			(polygon
				(pts
					(xy 49.790096 -55.9435) (xy 49.790096 -55.8165) (xy 49.790096 -52.8447) (xy 49.790096 -52.844192)
					(xy 47.504096 -52.844192) (xy 47.504096 -52.8447) (xy 47.504096 -52.9717) (xy 47.504096 -54.3941)
					(xy 47.605696 -54.3941) (xy 47.605696 -52.9717) (xy 49.688496 -52.9717) (xy 49.688496 -55.8165)
					(xy 47.605696 -55.8165) (xy 47.605696 -54.4195) (xy 47.504096 -54.4195) (xy 47.504096 -55.8165)
					(xy 47.504096 -55.9435) (xy 47.504096 -55.944008) (xy 49.790096 -55.944008)
				)
			)
		)
	)
	(footprint ""
		(layer "F.Cu")
		(at 282.315412 -42.853102 180)
		(property "Reference" "R5899"
			(at 0 0 180)
			(layer "F.SilkS")
			(hide yes)
			(effects
				(font
					(size 1.27 1.27)
				)
			)
		)
		(property "Value" ""
			(at 0 0 180)
			(layer "F.Fab")
			(effects
				(font
					(size 1.27 1.27)
				)
			)
		)
		(duplicate_pad_numbers_are_jumpers no)
		(fp_line
			(start 0.7874 0.4064)
			(end -0.7874 0.4064)
			(stroke
				(width 0.1524)
				(type default)
			)
			(layer "F.SilkS")
		)
		(fp_line
			(start 0.7874 -0.4064)
			(end 0.7874 0.4064)
			(stroke
				(width 0.1524)
				(type default)
			)
			(layer "F.SilkS")
		)
		(fp_line
			(start -0.7874 0.4064)
			(end -0.7874 -0.4064)
			(stroke
				(width 0.1524)
				(type default)
			)
			(layer "F.SilkS")
		)
		(fp_line
			(start -0.7874 -0.4064)
			(end 0.7874 -0.4064)
			(stroke
				(width 0.1524)
				(type default)
			)
			(layer "F.SilkS")
		)
		(fp_line
			(start 0.67945 0.3048)
			(end 0.120396 0.3048)
			(stroke
				(width 0.1)
				(type default)
			)
			(layer "F.Fab")
		)
		(fp_line
			(start 0.67945 -0.3048)
			(end 0.67945 0.3048)
			(stroke
				(width 0.1)
				(type default)
			)
			(layer "F.Fab")
		)
		(fp_line
			(start 0.12065 -0.2794)
			(end 0.12065 -0.3048)
			(stroke
				(width 0.1)
				(type default)
			)
			(layer "F.Fab")
		)
		(fp_line
			(start 0.12065 -0.3048)
			(end 0.67945 -0.3048)
			(stroke
				(width 0.1)
				(type default)
			)
			(layer "F.Fab")
		)
		(fp_line
			(start 0.120396 0.3048)
			(end 0.120396 0.2794)
			(stroke
				(width 0.1)
				(type default)
			)
			(layer "F.Fab")
		)
		(fp_line
			(start 0.120396 0.2794)
			(end -0.12065 0.2794)
			(stroke
				(width 0.1)
				(type default)
			)
			(layer "F.Fab")
		)
		(fp_line
			(start -0.12065 0.3048)
			(end -0.67945 0.3048)
			(stroke
				(width 0.1)
				(type default)
			)
			(layer "F.Fab")
		)
		(fp_line
			(start -0.12065 0.2794)
			(end -0.12065 0.3048)
			(stroke
				(width 0.1)
				(type default)
			)
			(layer "F.Fab")
		)
		(fp_line
			(start -0.12065 -0.2794)
			(end 0.12065 -0.2794)
			(stroke
				(width 0.1)
				(type default)
			)
			(layer "F.Fab")
		)
		(fp_line
			(start -0.12065 -0.305054)
			(end -0.12065 -0.2794)
			(stroke
				(width 0.1)
				(type default)
			)
			(layer "F.Fab")
		)
		(fp_line
			(start -0.67945 0.3048)
			(end -0.67945 -0.305054)
			(stroke
				(width 0.1)
				(type default)
			)
			(layer "F.Fab")
		)
		(fp_line
			(start -0.67945 -0.305054)
			(end -0.12065 -0.305054)
			(stroke
				(width 0.1)
				(type default)
			)
			(layer "F.Fab")
		)
		(pad "1" smd circle
			(at -0.40005 0 180)
			(size 0 0)
			(layers "F.Cu" "F.Mask" "F.Paste")
			(net "SSD9_ADC_A1")
		)
		(pad "2" smd circle
			(at 0.40005 0 180)
			(size 0 0)
			(layers "F.Cu" "F.Mask" "F.Paste")
			(net "SMB_SSD9_ADC_SDA")
		)
	)
	(footprint ""
		(layer "F.Cu")
		(at 2.71526 -380.182628 180)
		(property "Reference" "C4460"
			(at 0 0 180)
			(layer "F.SilkS")
			(hide yes)
			(effects
				(font
					(size 1.27 1.27)
				)
			)
		)
		(property "Value" ""
			(at 0 0 180)
			(layer "F.Fab")
			(effects
				(font
					(size 1.27 1.27)
				)
			)
		)
		(duplicate_pad_numbers_are_jumpers no)
		(fp_line
			(start 0.7874 0.4064)
			(end -0.7874 0.4064)
			(stroke
				(width 0.1524)
				(type default)
			)
			(layer "F.SilkS")
		)
		(fp_line
			(start 0.7874 -0.4064)
			(end 0.7874 0.4064)
			(stroke
				(width 0.1524)
				(type default)
			)
			(layer "F.SilkS")
		)
		(fp_line
			(start -0.7874 0.4064)
			(end -0.7874 -0.4064)
			(stroke
				(width 0.1524)
				(type default)
			)
			(layer "F.SilkS")
		)
		(fp_line
			(start -0.7874 -0.4064)
			(end 0.7874 -0.4064)
			(stroke
				(width 0.1524)
				(type default)
			)
			(layer "F.SilkS")
		)
		(fp_line
			(start 0.67945 0.3048)
			(end 0.120396 0.3048)
			(stroke
				(width 0.1)
				(type default)
			)
			(layer "F.Fab")
		)
		(fp_line
			(start 0.67945 -0.3048)
			(end 0.67945 0.3048)
			(stroke
				(width 0.1)
				(type default)
			)
			(layer "F.Fab")
		)
		(fp_line
			(start 0.12065 -0.2794)
			(end 0.12065 -0.3048)
			(stroke
				(width 0.1)
				(type default)
			)
			(layer "F.Fab")
		)
		(fp_line
			(start 0.12065 -0.3048)
			(end 0.67945 -0.3048)
			(stroke
				(width 0.1)
				(type default)
			)
			(layer "F.Fab")
		)
		(fp_line
			(start 0.120396 0.3048)
			(end 0.120396 0.2794)
			(stroke
				(width 0.1)
				(type default)
			)
			(layer "F.Fab")
		)
		(fp_line
			(start 0.120396 0.2794)
			(end -0.12065 0.2794)
			(stroke
				(width 0.1)
				(type default)
			)
			(layer "F.Fab")
		)
		(fp_line
			(start -0.12065 0.3048)
			(end -0.67945 0.3048)
			(stroke
				(width 0.1)
				(type default)
			)
			(layer "F.Fab")
		)
		(fp_line
			(start -0.12065 0.2794)
			(end -0.12065 0.3048)
			(stroke
				(width 0.1)
				(type default)
			)
			(layer "F.Fab")
		)
		(fp_line
			(start -0.12065 -0.2794)
			(end 0.12065 -0.2794)
			(stroke
				(width 0.1)
				(type default)
			)
			(layer "F.Fab")
		)
		(fp_line
			(start -0.12065 -0.305054)
			(end -0.12065 -0.2794)
			(stroke
				(width 0.1)
				(type default)
			)
			(layer "F.Fab")
		)
		(fp_line
			(start -0.67945 0.3048)
			(end -0.67945 -0.305054)
			(stroke
				(width 0.1)
				(type default)
			)
			(layer "F.Fab")
		)
		(fp_line
			(start -0.67945 -0.305054)
			(end -0.12065 -0.305054)
			(stroke
				(width 0.1)
				(type default)
			)
			(layer "F.Fab")
		)
		(pad "1" smd circle
			(at -0.40005 0 180)
			(size 0 0)
			(layers "F.Cu" "F.Mask" "F.Paste")
			(net "BIC_USB_8042_HUB_XOUT")
		)
		(pad "2" smd circle
			(at 0.40005 0 180)
			(size 0 0)
			(layers "F.Cu" "F.Mask" "F.Paste")
			(net "GND")
		)
	)
	(footprint ""
		(layer "F.Cu")
		(at 194.343782 -49.95291 180)
		(property "Reference" "R5896"
			(at 0 0 180)
			(layer "F.SilkS")
			(hide yes)
			(effects
				(font
					(size 1.27 1.27)
				)
			)
		)
		(property "Value" ""
			(at 0 0 180)
			(layer "F.Fab")
			(effects
				(font
					(size 1.27 1.27)
				)
			)
		)
		(duplicate_pad_numbers_are_jumpers no)
		(fp_line
			(start 0.7874 0.4064)
			(end -0.7874 0.4064)
			(stroke
				(width 0.1524)
				(type default)
			)
			(layer "F.SilkS")
		)
		(fp_line
			(start 0.7874 -0.4064)
			(end 0.7874 0.4064)
			(stroke
				(width 0.1524)
				(type default)
			)
			(layer "F.SilkS")
		)
		(fp_line
			(start -0.7874 0.4064)
			(end -0.7874 -0.4064)
			(stroke
				(width 0.1524)
				(type default)
			)
			(layer "F.SilkS")
		)
		(fp_line
			(start -0.7874 -0.4064)
			(end 0.7874 -0.4064)
			(stroke
				(width 0.1524)
				(type default)
			)
			(layer "F.SilkS")
		)
		(fp_line
			(start 0.67945 0.3048)
			(end 0.120396 0.3048)
			(stroke
				(width 0.1)
				(type default)
			)
			(layer "F.Fab")
		)
		(fp_line
			(start 0.67945 -0.3048)
			(end 0.67945 0.3048)
			(stroke
				(width 0.1)
				(type default)
			)
			(layer "F.Fab")
		)
		(fp_line
			(start 0.12065 -0.2794)
			(end 0.12065 -0.3048)
			(stroke
				(width 0.1)
				(type default)
			)
			(layer "F.Fab")
		)
		(fp_line
			(start 0.12065 -0.3048)
			(end 0.67945 -0.3048)
			(stroke
				(width 0.1)
				(type default)
			)
			(layer "F.Fab")
		)
		(fp_line
			(start 0.120396 0.3048)
			(end 0.120396 0.2794)
			(stroke
				(width 0.1)
				(type default)
			)
			(layer "F.Fab")
		)
		(fp_line
			(start 0.120396 0.2794)
			(end -0.12065 0.2794)
			(stroke
				(width 0.1)
				(type default)
			)
			(layer "F.Fab")
		)
		(fp_line
			(start -0.12065 0.3048)
			(end -0.67945 0.3048)
			(stroke
				(width 0.1)
				(type default)
			)
			(layer "F.Fab")
		)
		(fp_line
			(start -0.12065 0.2794)
			(end -0.12065 0.3048)
			(stroke
				(width 0.1)
				(type default)
			)
			(layer "F.Fab")
		)
		(fp_line
			(start -0.12065 -0.2794)
			(end 0.12065 -0.2794)
			(stroke
				(width 0.1)
				(type default)
			)
			(layer "F.Fab")
		)
		(fp_line
			(start -0.12065 -0.305054)
			(end -0.12065 -0.2794)
			(stroke
				(width 0.1)
				(type default)
			)
			(layer "F.Fab")
		)
		(fp_line
			(start -0.67945 0.3048)
			(end -0.67945 -0.305054)
			(stroke
				(width 0.1)
				(type default)
			)
			(layer "F.Fab")
		)
		(fp_line
			(start -0.67945 -0.305054)
			(end -0.12065 -0.305054)
			(stroke
				(width 0.1)
				(type default)
			)
			(layer "F.Fab")
		)
		(pad "1" smd circle
			(at -0.40005 0 180)
			(size 0 0)
			(layers "F.Cu" "F.Mask" "F.Paste")
			(net "SSD6_ADC_A0")
		)
		(pad "2" smd circle
			(at 0.40005 0 180)
			(size 0 0)
			(layers "F.Cu" "F.Mask" "F.Paste")
			(net "SMB_SSD6_ADC_SDA")
		)
	)
	(footprint ""
		(layer "F.Cu")
		(at 46.434502 -30.03169 180)
		(property "Reference" "C78"
			(at 0 0 180)
			(layer "F.SilkS")
			(hide yes)
			(effects
				(font
					(size 1.27 1.27)
				)
			)
		)
		(property "Value" ""
			(at 0 0 180)
			(layer "F.Fab")
			(effects
				(font
					(size 1.27 1.27)
				)
			)
		)
		(duplicate_pad_numbers_are_jumpers no)
		(fp_line
			(start 0.299974 0.150114)
			(end -0.299974 0.150114)
			(stroke
				(width 0.1)
				(type default)
			)
			(layer "F.Fab")
		)
		(fp_line
			(start 0.299974 -0.150114)
			(end 0.299974 0.150114)
			(stroke
				(width 0.1)
				(type default)
			)
			(layer "F.Fab")
		)
		(fp_line
			(start -0.299974 0.150114)
			(end -0.299974 -0.150114)
			(stroke
				(width 0.1)
				(type default)
			)
			(layer "F.Fab")
		)
		(fp_line
			(start -0.299974 -0.150114)
			(end 0.299974 -0.150114)
			(stroke
				(width 0.1)
				(type default)
			)
			(layer "F.Fab")
		)
		(pad "1" smd rect
			(at -0.2667 0 180)
			(size 0.3048 0.381)
			(layers "F.Cu" "F.Mask" "F.Paste")
			(net "P5E_PEX0_STN2_TX_DN<41>")
		)
		(pad "2" smd rect
			(at 0.2667 0 180)
			(size 0.3048 0.381)
			(layers "F.Cu" "F.Mask" "F.Paste")
			(net "P5E_PEX0_STN2_TX_C_DN<41>")
		)
	)
	(footprint ""
		(layer "F.Cu")
		(at 130.09118 -280.44902 -90)
		(property "Reference" "PR112"
			(at 0 0 270)
			(layer "F.SilkS")
			(hide yes)
			(effects
				(font
					(size 1.27 1.27)
				)
			)
		)
		(property "Value" ""
			(at 0 0 270)
			(layer "F.Fab")
			(effects
				(font
					(size 1.27 1.27)
				)
			)
		)
		(duplicate_pad_numbers_are_jumpers no)
		(fp_line
			(start -0.7874 0.4064)
			(end -0.7874 -0.4064)
			(stroke
				(width 0.1524)
				(type default)
			)
			(layer "F.SilkS")
		)
		(fp_line
			(start 0.7874 0.4064)
			(end -0.7874 0.4064)
			(stroke
				(width 0.1524)
				(type default)
			)
			(layer "F.SilkS")
		)
		(fp_line
			(start -0.7874 -0.4064)
			(end 0.7874 -0.4064)
			(stroke
				(width 0.1524)
				(type default)
			)
			(layer "F.SilkS")
		)
		(fp_line
			(start 0.7874 -0.4064)
			(end 0.7874 0.4064)
			(stroke
				(width 0.1524)
				(type default)
			)
			(layer "F.SilkS")
		)
		(fp_line
			(start -0.67945 0.3048)
			(end -0.67945 -0.305054)
			(stroke
				(width 0.1)
				(type default)
			)
			(layer "F.Fab")
		)
		(fp_line
			(start -0.12065 0.3048)
			(end -0.67945 0.3048)
			(stroke
				(width 0.1)
				(type default)
			)
			(layer "F.Fab")
		)
		(fp_line
			(start 0.120396 0.3048)
			(end 0.120396 0.2794)
			(stroke
				(width 0.1)
				(type default)
			)
			(layer "F.Fab")
		)
		(fp_line
			(start 0.67945 0.3048)
			(end 0.120396 0.3048)
			(stroke
				(width 0.1)
				(type default)
			)
			(layer "F.Fab")
		)
		(fp_line
			(start -0.12065 0.2794)
			(end -0.12065 0.3048)
			(stroke
				(width 0.1)
				(type default)
			)
			(layer "F.Fab")
		)
		(fp_line
			(start 0.120396 0.2794)
			(end -0.12065 0.2794)
			(stroke
				(width 0.1)
				(type default)
			)
			(layer "F.Fab")
		)
		(fp_line
			(start -0.12065 -0.2794)
			(end 0.12065 -0.2794)
			(stroke
				(width 0.1)
				(type default)
			)
			(layer "F.Fab")
		)
		(fp_line
			(start 0.12065 -0.2794)
			(end 0.12065 -0.3048)
			(stroke
				(width 0.1)
				(type default)
			)
			(layer "F.Fab")
		)
		(fp_line
			(start 0.12065 -0.3048)
			(end 0.67945 -0.3048)
			(stroke
				(width 0.1)
				(type default)
			)
			(layer "F.Fab")
		)
		(fp_line
			(start 0.67945 -0.3048)
			(end 0.67945 0.3048)
			(stroke
				(width 0.1)
				(type default)
			)
			(layer "F.Fab")
		)
		(fp_line
			(start -0.67945 -0.305054)
			(end -0.12065 -0.305054)
			(stroke
				(width 0.1)
				(type default)
			)
			(layer "F.Fab")
		)
		(fp_line
			(start -0.12065 -0.305054)
			(end -0.12065 -0.2794)
			(stroke
				(width 0.1)
				(type default)
			)
			(layer "F.Fab")
		)
		(pad "1" smd circle
			(at -0.40005 0 270)
			(size 0 0)
			(layers "F.Cu" "F.Mask" "F.Paste")
			(net "SW_P0V8_PEX1_BOOT2")
		)
		(pad "2" smd circle
			(at 0.40005 0 270)
			(size 0 0)
			(layers "F.Cu" "F.Mask" "F.Paste")
			(net "SW_P0V8_PEX1_BOOT2_R")
		)
	)
	(footprint ""
		(layer "F.Cu")
		(at 372.415562 -42.853102 180)
		(property "Reference" "R5904"
			(at 0 0 180)
			(layer "F.SilkS")
			(hide yes)
			(effects
				(font
					(size 1.27 1.27)
				)
			)
		)
		(property "Value" ""
			(at 0 0 180)
			(layer "F.Fab")
			(effects
				(font
					(size 1.27 1.27)
				)
			)
		)
		(duplicate_pad_numbers_are_jumpers no)
		(fp_line
			(start 0.7874 0.4064)
			(end -0.7874 0.4064)
			(stroke
				(width 0.1524)
				(type default)
			)
			(layer "F.SilkS")
		)
		(fp_line
			(start 0.7874 -0.4064)
			(end 0.7874 0.4064)
			(stroke
				(width 0.1524)
				(type default)
			)
			(layer "F.SilkS")
		)
		(fp_line
			(start -0.7874 0.4064)
			(end -0.7874 -0.4064)
			(stroke
				(width 0.1524)
				(type default)
			)
			(layer "F.SilkS")
		)
		(fp_line
			(start -0.7874 -0.4064)
			(end 0.7874 -0.4064)
			(stroke
				(width 0.1524)
				(type default)
			)
			(layer "F.SilkS")
		)
		(fp_line
			(start 0.67945 0.3048)
			(end 0.120396 0.3048)
			(stroke
				(width 0.1)
				(type default)
			)
			(layer "F.Fab")
		)
		(fp_line
			(start 0.67945 -0.3048)
			(end 0.67945 0.3048)
			(stroke
				(width 0.1)
				(type default)
			)
			(layer "F.Fab")
		)
		(fp_line
			(start 0.12065 -0.2794)
			(end 0.12065 -0.3048)
			(stroke
				(width 0.1)
				(type default)
			)
			(layer "F.Fab")
		)
		(fp_line
			(start 0.12065 -0.3048)
			(end 0.67945 -0.3048)
			(stroke
				(width 0.1)
				(type default)
			)
			(layer "F.Fab")
		)
		(fp_line
			(start 0.120396 0.3048)
			(end 0.120396 0.2794)
			(stroke
				(width 0.1)
				(type default)
			)
			(layer "F.Fab")
		)
		(fp_line
			(start 0.120396 0.2794)
			(end -0.12065 0.2794)
			(stroke
				(width 0.1)
				(type default)
			)
			(layer "F.Fab")
		)
		(fp_line
			(start -0.12065 0.3048)
			(end -0.67945 0.3048)
			(stroke
				(width 0.1)
				(type default)
			)
			(layer "F.Fab")
		)
		(fp_line
			(start -0.12065 0.2794)
			(end -0.12065 0.3048)
			(stroke
				(width 0.1)
				(type default)
			)
			(layer "F.Fab")
		)
		(fp_line
			(start -0.12065 -0.2794)
			(end 0.12065 -0.2794)
			(stroke
				(width 0.1)
				(type default)
			)
			(layer "F.Fab")
		)
		(fp_line
			(start -0.12065 -0.305054)
			(end -0.12065 -0.2794)
			(stroke
				(width 0.1)
				(type default)
			)
			(layer "F.Fab")
		)
		(fp_line
			(start -0.67945 0.3048)
			(end -0.67945 -0.305054)
			(stroke
				(width 0.1)
				(type default)
			)
			(layer "F.Fab")
		)
		(fp_line
			(start -0.67945 -0.305054)
			(end -0.12065 -0.305054)
			(stroke
				(width 0.1)
				(type default)
			)
			(layer "F.Fab")
		)
		(pad "1" smd circle
			(at -0.40005 0 180)
			(size 0 0)
			(layers "F.Cu" "F.Mask" "F.Paste")
			(net "SSD12_ADC_A1")
		)
		(pad "2" smd circle
			(at 0.40005 0 180)
			(size 0 0)
			(layers "F.Cu" "F.Mask" "F.Paste")
			(net "SMB_SSD12_ADC_SCL")
		)
	)
	(footprint ""
		(layer "F.Cu")
		(at 15.59052 -305.808634 -90)
		(property "Reference" "PC978"
			(at 0 0 270)
			(layer "F.SilkS")
			(hide yes)
			(effects
				(font
					(size 1.27 1.27)
				)
			)
		)
		(property "Value" ""
			(at 0 0 270)
			(layer "F.Fab")
			(effects
				(font
					(size 1.27 1.27)
				)
			)
		)
		(duplicate_pad_numbers_are_jumpers no)
		(fp_line
			(start -0.7874 0.4064)
			(end -0.7874 -0.4064)
			(stroke
				(width 0.1524)
				(type default)
			)
			(layer "F.SilkS")
		)
		(fp_line
			(start 0.7874 0.4064)
			(end -0.7874 0.4064)
			(stroke
				(width 0.1524)
				(type default)
			)
			(layer "F.SilkS")
		)
		(fp_line
			(start -0.7874 -0.4064)
			(end 0.7874 -0.4064)
			(stroke
				(width 0.1524)
				(type default)
			)
			(layer "F.SilkS")
		)
		(fp_line
			(start 0.7874 -0.4064)
			(end 0.7874 0.4064)
			(stroke
				(width 0.1524)
				(type default)
			)
			(layer "F.SilkS")
		)
		(fp_line
			(start -0.67945 0.3048)
			(end -0.67945 -0.305054)
			(stroke
				(width 0.1)
				(type default)
			)
			(layer "F.Fab")
		)
		(fp_line
			(start -0.12065 0.3048)
			(end -0.67945 0.3048)
			(stroke
				(width 0.1)
				(type default)
			)
			(layer "F.Fab")
		)
		(fp_line
			(start 0.120396 0.3048)
			(end 0.120396 0.2794)
			(stroke
				(width 0.1)
				(type default)
			)
			(layer "F.Fab")
		)
		(fp_line
			(start 0.67945 0.3048)
			(end 0.120396 0.3048)
			(stroke
				(width 0.1)
				(type default)
			)
			(layer "F.Fab")
		)
		(fp_line
			(start -0.12065 0.2794)
			(end -0.12065 0.3048)
			(stroke
				(width 0.1)
				(type default)
			)
			(layer "F.Fab")
		)
		(fp_line
			(start 0.120396 0.2794)
			(end -0.12065 0.2794)
			(stroke
				(width 0.1)
				(type default)
			)
			(layer "F.Fab")
		)
		(fp_line
			(start -0.12065 -0.2794)
			(end 0.12065 -0.2794)
			(stroke
				(width 0.1)
				(type default)
			)
			(layer "F.Fab")
		)
		(fp_line
			(start 0.12065 -0.2794)
			(end 0.12065 -0.3048)
			(stroke
				(width 0.1)
				(type default)
			)
			(layer "F.Fab")
		)
		(fp_line
			(start 0.12065 -0.3048)
			(end 0.67945 -0.3048)
			(stroke
				(width 0.1)
				(type default)
			)
			(layer "F.Fab")
		)
		(fp_line
			(start 0.67945 -0.3048)
			(end 0.67945 0.3048)
			(stroke
				(width 0.1)
				(type default)
			)
			(layer "F.Fab")
		)
		(fp_line
			(start -0.67945 -0.305054)
			(end -0.12065 -0.305054)
			(stroke
				(width 0.1)
				(type default)
			)
			(layer "F.Fab")
		)
		(fp_line
			(start -0.12065 -0.305054)
			(end -0.12065 -0.2794)
			(stroke
				(width 0.1)
				(type default)
			)
			(layer "F.Fab")
		)
		(pad "1" smd circle
			(at -0.40005 0 270)
			(size 0 0)
			(layers "F.Cu" "F.Mask" "F.Paste")
			(net "SH_P1V25_PEX0_FB_P")
		)
		(pad "2" smd circle
			(at 0.40005 0 270)
			(size 0 0)
			(layers "F.Cu" "F.Mask" "F.Paste")
			(net "SH_P1V25_PEX0_FB_N")
		)
	)
	(footprint ""
		(layer "F.Cu")
		(at 260.305042 -307.084984 45)
		(property "Reference" "R1349"
			(at 0 0 45)
			(layer "F.SilkS")
			(hide yes)
			(effects
				(font
					(size 1.27 1.27)
				)
			)
		)
		(property "Value" ""
			(at 0 0 45)
			(layer "F.Fab")
			(effects
				(font
					(size 1.27 1.27)
				)
			)
		)
		(duplicate_pad_numbers_are_jumpers no)
		(fp_line
			(start -0.787389 -0.406267)
			(end 0.787389 -0.406267)
			(stroke
				(width 0.1524)
				(type default)
			)
			(layer "F.SilkS")
		)
		(fp_line
			(start -0.787389 0.406267)
			(end -0.787389 -0.406267)
			(stroke
				(width 0.1524)
				(type default)
			)
			(layer "F.SilkS")
		)
		(fp_line
			(start 0.787389 -0.406267)
			(end 0.787389 0.406267)
			(stroke
				(width 0.1524)
				(type default)
			)
			(layer "F.SilkS")
		)
		(fp_line
			(start 0.787389 0.406267)
			(end -0.787389 0.406267)
			(stroke
				(width 0.1524)
				(type default)
			)
			(layer "F.SilkS")
		)
		(fp_line
			(start -0.679446 -0.305149)
			(end -0.120695 -0.304969)
			(stroke
				(width 0.1)
				(type default)
			)
			(layer "F.Fab")
		)
		(fp_line
			(start -0.120695 -0.304969)
			(end -0.120695 -0.279466)
			(stroke
				(width 0.1)
				(type default)
			)
			(layer "F.Fab")
		)
		(fp_line
			(start -0.120695 -0.279466)
			(end 0.120695 -0.279466)
			(stroke
				(width 0.1)
				(type default)
			)
			(layer "F.Fab")
		)
		(fp_line
			(start -0.679446 0.30479)
			(end -0.679446 -0.305149)
			(stroke
				(width 0.1)
				(type default)
			)
			(layer "F.Fab")
		)
		(fp_line
			(start 0.120515 -0.30479)
			(end 0.679446 -0.30479)
			(stroke
				(width 0.1)
				(type default)
			)
			(layer "F.Fab")
		)
		(fp_line
			(start 0.120695 -0.279466)
			(end 0.120515 -0.30479)
			(stroke
				(width 0.1)
				(type default)
			)
			(layer "F.Fab")
		)
		(fp_line
			(start -0.120695 0.279466)
			(end -0.120515 0.30479)
			(stroke
				(width 0.1)
				(type default)
			)
			(layer "F.Fab")
		)
		(fp_line
			(start -0.120515 0.30479)
			(end -0.679446 0.30479)
			(stroke
				(width 0.1)
				(type default)
			)
			(layer "F.Fab")
		)
		(fp_line
			(start 0.679446 -0.30479)
			(end 0.679446 0.30479)
			(stroke
				(width 0.1)
				(type default)
			)
			(layer "F.Fab")
		)
		(fp_line
			(start 0.120335 0.279466)
			(end -0.120695 0.279466)
			(stroke
				(width 0.1)
				(type default)
			)
			(layer "F.Fab")
		)
		(fp_line
			(start 0.120515 0.30479)
			(end 0.120335 0.279466)
			(stroke
				(width 0.1)
				(type default)
			)
			(layer "F.Fab")
		)
		(fp_line
			(start 0.679446 0.30479)
			(end 0.120515 0.30479)
			(stroke
				(width 0.1)
				(type default)
			)
			(layer "F.Fab")
		)
		(pad "1" smd circle
			(at -0.40005 0 45)
			(size 0 0)
			(layers "F.Cu" "F.Mask" "F.Paste")
			(net "GND")
		)
		(pad "2" smd circle
			(at 0.40005 0 45)
			(size 0 0)
			(layers "F.Cu" "F.Mask" "F.Paste")
			(net "PEX2_DBG_SEL0")
		)
	)
	(footprint ""
		(layer "F.Cu")
		(at 222.552006 -195.22821 -90)
		(property "Reference" "U305"
			(at 0 0 270)
			(layer "F.SilkS")
			(hide yes)
			(effects
				(font
					(size 1.27 1.27)
				)
			)
		)
		(property "Value" ""
			(at 0 0 270)
			(layer "F.Fab")
			(effects
				(font
					(size 1.27 1.27)
				)
			)
		)
		(duplicate_pad_numbers_are_jumpers no)
		(fp_line
			(start -1.0414 1.575054)
			(end -1.0414 -1.575054)
			(stroke
				(width 0.1524)
				(type default)
			)
			(layer "F.SilkS")
		)
		(fp_line
			(start 1.0414 1.575054)
			(end -1.0414 1.575054)
			(stroke
				(width 0.1524)
				(type default)
			)
			(layer "F.SilkS")
		)
		(fp_line
			(start 0 -1.272032)
			(end -0.254 -1.575054)
			(stroke
				(width 0.1524)
				(type default)
			)
			(layer "F.SilkS")
		)
		(fp_line
			(start -1.0414 -1.575054)
			(end -0.254 -1.575054)
			(stroke
				(width 0.1524)
				(type default)
			)
			(layer "F.SilkS")
		)
		(fp_line
			(start 0.2286 -1.575054)
			(end 0 -1.272032)
			(stroke
				(width 0.1524)
				(type default)
			)
			(layer "F.SilkS")
		)
		(fp_line
			(start 0.254 -1.575054)
			(end 1.0414 -1.575054)
			(stroke
				(width 0.1524)
				(type default)
			)
			(layer "F.SilkS")
		)
		(fp_line
			(start 1.0414 -1.575054)
			(end 1.0414 1.575054)
			(stroke
				(width 0.1524)
				(type default)
			)
			(layer "F.SilkS")
		)
		(fp_poly
			(pts
				(xy -2.710688 -0.975106) (xy -3.726688 -1.483106) (xy -3.726688 -0.467106)
			)
			(stroke
				(width 0)
				(type default)
			)
			(fill yes)
			(layer "F.SilkS")
		)
		(fp_line
			(start -1.4478 1.5748)
			(end -1.4478 1.2192)
			(stroke
				(width 0.1)
				(type default)
			)
			(layer "F.Fab")
		)
		(fp_line
			(start 1.4478 1.5748)
			(end -1.4478 1.5748)
			(stroke
				(width 0.1)
				(type default)
			)
			(layer "F.Fab")
		)
		(fp_line
			(start -2.5654 1.2192)
			(end -2.5654 -1.2192)
			(stroke
				(width 0.1)
				(type default)
			)
			(layer "F.Fab")
		)
		(fp_line
			(start -1.4478 1.2192)
			(end -2.5654 1.2192)
			(stroke
				(width 0.1)
				(type default)
			)
			(layer "F.Fab")
		)
		(fp_line
			(start 1.4478 1.2192)
			(end 1.4478 1.5748)
			(stroke
				(width 0.1)
				(type default)
			)
			(layer "F.Fab")
		)
		(fp_line
			(start 2.5654 1.2192)
			(end 1.4478 1.2192)
			(stroke
				(width 0.1)
				(type default)
			)
			(layer "F.Fab")
		)
		(fp_line
			(start -2.5654 -1.2192)
			(end -1.4478 -1.2192)
			(stroke
				(width 0.1)
				(type default)
			)
			(layer "F.Fab")
		)
		(fp_line
			(start -1.4478 -1.2192)
			(end -1.4478 -1.5748)
			(stroke
				(width 0.1)
				(type default)
			)
			(layer "F.Fab")
		)
		(fp_line
			(start 1.4478 -1.2192)
			(end 2.5654 -1.2192)
			(stroke
				(width 0.1)
				(type default)
			)
			(layer "F.Fab")
		)
		(fp_line
			(start 2.5654 -1.2192)
			(end 2.5654 1.2192)
			(stroke
				(width 0.1)
				(type default)
			)
			(layer "F.Fab")
		)
		(fp_line
			(start -1.4478 -1.5748)
			(end 1.4478 -1.5748)
			(stroke
				(width 0.1)
				(type default)
			)
			(layer "F.Fab")
		)
		(fp_line
			(start 1.4478 -1.5748)
			(end 1.4478 -1.2192)
			(stroke
				(width 0.1)
				(type default)
			)
			(layer "F.Fab")
		)
		(fp_poly
			(pts
				(xy -2.710688 -0.975106) (xy -3.726688 -1.483106) (xy -3.726688 -0.467106)
			)
			(stroke
				(width 0)
				(type default)
			)
			(fill yes)
			(layer "F.Fab")
		)
		(pad "1" smd rect
			(at -1.849882 -0.975106 180)
			(size 0.3556 1.3208)
			(layers "F.Cu" "F.Mask" "F.Paste")
			(net "SPI_BIC1_CLK_R5")
		)
		(pad "2" smd rect
			(at -1.849882 -0.32512 180)
			(size 0.3556 1.3208)
			(layers "F.Cu" "F.Mask" "F.Paste")
			(net "SPI_BIC1_MISO_R5")
		)
		(pad "3" smd rect
			(at -1.849882 0.32512 180)
			(size 0.3556 1.3208)
			(layers "F.Cu" "F.Mask" "F.Paste")
			(net "SPI_BIC1_MOSI_R5")
		)
		(pad "4" smd rect
			(at -1.849882 0.975106 180)
			(size 0.3556 1.3208)
			(layers "F.Cu" "F.Mask" "F.Paste")
			(net "GND")
		)
		(pad "5" smd rect
			(at 1.849882 0.975106 180)
			(size 0.3556 1.3208)
			(layers "F.Cu" "F.Mask" "F.Paste")
			(net "SPI2_DO_BUF")
		)
		(pad "6" smd rect
			(at 1.849882 0.32512 180)
			(size 0.3556 1.3208)
			(layers "F.Cu" "F.Mask" "F.Paste")
			(net "SPI2_DI_BUF")
		)
		(pad "7" smd rect
			(at 1.849882 -0.32512 180)
			(size 0.3556 1.3208)
			(layers "F.Cu" "F.Mask" "F.Paste")
			(net "SPI2_CLK_BUF")
		)
		(pad "8" smd rect
			(at 1.849882 -0.975106 180)
			(size 0.3556 1.3208)
			(layers "F.Cu" "F.Mask" "F.Paste")
			(net "P3V3_AUX")
		)
	)
	(footprint ""
		(layer "F.Cu")
		(at 104.724454 -119.77624)
		(property "Reference" "Q213"
			(at 0.63754 -1.933194 0)
			(unlocked yes)
			(layer "F.SilkS")
			(effects
				(font
					(size 0.7874 0.5842)
					(thickness 0.1524)
				)
			)
		)
		(property "Value" ""
			(at 0 0 0)
			(layer "F.Fab")
			(effects
				(font
					(size 1.27 1.27)
				)
			)
		)
		(duplicate_pad_numbers_are_jumpers no)
		(fp_line
			(start -1.376172 -1.199896)
			(end -0.508 -1.199896)
			(stroke
				(width 0.1524)
				(type default)
			)
			(layer "F.SilkS")
		)
		(fp_line
			(start -1.376172 1.199896)
			(end -1.376172 -1.199896)
			(stroke
				(width 0.1524)
				(type default)
			)
			(layer "F.SilkS")
		)
		(fp_line
			(start -0.508 -1.199896)
			(end 0 -0.762)
			(stroke
				(width 0.1524)
				(type default)
			)
			(layer "F.SilkS")
		)
		(fp_line
			(start 0 -0.762)
			(end 0.508 -1.199896)
			(stroke
				(width 0.1524)
				(type default)
			)
			(layer "F.SilkS")
		)
		(fp_line
			(start 0.508 -1.199896)
			(end 1.376172 -1.199896)
			(stroke
				(width 0.1524)
				(type default)
			)
			(layer "F.SilkS")
		)
		(fp_line
			(start 1.376172 -1.199896)
			(end 1.376172 1.199896)
			(stroke
				(width 0.1524)
				(type default)
			)
			(layer "F.SilkS")
		)
		(fp_line
			(start 1.376172 1.199896)
			(end -1.376172 1.199896)
			(stroke
				(width 0.1524)
				(type default)
			)
			(layer "F.SilkS")
		)
		(fp_poly
			(pts
				(xy -1.048766 -1.358138) (xy -1.31826 -2.166366) (xy -1.856994 -1.627632)
			)
			(stroke
				(width 0)
				(type default)
			)
			(fill yes)
			(layer "F.SilkS")
		)
		(fp_line
			(start -0.674878 -1.100074)
			(end 0.674878 -1.100074)
			(stroke
				(width 0.1)
				(type default)
			)
			(layer "F.Fab")
		)
		(fp_line
			(start -0.674878 1.100074)
			(end -0.674878 -1.100074)
			(stroke
				(width 0.1)
				(type default)
			)
			(layer "F.Fab")
		)
		(fp_line
			(start 0.674878 -1.100074)
			(end 0.674878 1.100074)
			(stroke
				(width 0.1)
				(type default)
			)
			(layer "F.Fab")
		)
		(fp_line
			(start 0.674878 1.100074)
			(end -0.674878 1.100074)
			(stroke
				(width 0.1)
				(type default)
			)
			(layer "F.Fab")
		)
		(fp_poly
			(pts
				(xy -1.4605 -0.7493) (xy -2.2225 -1.1303) (xy -2.2225 -0.3683)
			)
			(stroke
				(width 0)
				(type default)
			)
			(fill yes)
			(layer "F.Fab")
		)
		(pad "1" smd rect
			(at -0.899922 -0.750062 270)
			(size 0.6096 0.6096)
			(layers "F.Cu" "F.Mask" "F.Paste")
			(net "GND")
		)
		(pad "2" smd rect
			(at -0.899922 0 270)
			(size 0.4064 0.6096)
			(layers "F.Cu" "F.Mask" "F.Paste")
			(net "P3V3_NIC1_PG_G1")
		)
		(pad "3" smd rect
			(at -0.899922 0.750062 270)
			(size 0.6096 0.6096)
			(layers "F.Cu" "F.Mask" "F.Paste")
			(net "PWRGD_P3V3_NIC1_D")
		)
		(pad "4" smd rect
			(at 0.899922 0.750062 270)
			(size 0.6096 0.6096)
			(layers "F.Cu" "F.Mask" "F.Paste")
			(net "GND")
		)
		(pad "5" smd rect
			(at 0.899922 0 270)
			(size 0.4064 0.6096)
			(layers "F.Cu" "F.Mask" "F.Paste")
			(net "P3V3_NIC1_PG_G2")
		)
		(pad "6" smd rect
			(at 0.899922 -0.750062 270)
			(size 0.6096 0.6096)
			(layers "F.Cu" "F.Mask" "F.Paste")
			(net "P3V3_NIC1_PG_G2")
		)
	)
	(footprint ""
		(layer "F.Cu")
		(at 314.861448 -145.311114 180)
		(property "Reference" "C435"
			(at 0 0 180)
			(layer "F.SilkS")
			(hide yes)
			(effects
				(font
					(size 1.27 1.27)
				)
			)
		)
		(property "Value" ""
			(at 0 0 180)
			(layer "F.Fab")
			(effects
				(font
					(size 1.27 1.27)
				)
			)
		)
		(duplicate_pad_numbers_are_jumpers no)
		(fp_line
			(start 0.299974 0.150114)
			(end -0.299974 0.150114)
			(stroke
				(width 0.1)
				(type default)
			)
			(layer "F.Fab")
		)
		(fp_line
			(start 0.299974 -0.150114)
			(end 0.299974 0.150114)
			(stroke
				(width 0.1)
				(type default)
			)
			(layer "F.Fab")
		)
		(fp_line
			(start -0.299974 0.150114)
			(end -0.299974 -0.150114)
			(stroke
				(width 0.1)
				(type default)
			)
			(layer "F.Fab")
		)
		(fp_line
			(start -0.299974 -0.150114)
			(end 0.299974 -0.150114)
			(stroke
				(width 0.1)
				(type default)
			)
			(layer "F.Fab")
		)
		(pad "1" smd rect
			(at -0.2667 0 180)
			(size 0.3048 0.381)
			(layers "F.Cu" "F.Mask" "F.Paste")
			(net "P5E_PEX2_STN0_TX_DP<9>")
		)
		(pad "2" smd rect
			(at 0.2667 0 180)
			(size 0.3048 0.381)
			(layers "F.Cu" "F.Mask" "F.Paste")
			(net "P5E_PEX2_STN0_TX_C_DP<9>")
		)
	)
	(footprint ""
		(layer "F.Cu")
		(at 219.202 -197.612)
		(property "Reference" "R1523"
			(at 0 0 0)
			(layer "F.SilkS")
			(hide yes)
			(effects
				(font
					(size 1.27 1.27)
				)
			)
		)
		(property "Value" ""
			(at 0 0 0)
			(layer "F.Fab")
			(effects
				(font
					(size 1.27 1.27)
				)
			)
		)
		(duplicate_pad_numbers_are_jumpers no)
		(fp_line
			(start -0.7874 -0.4064)
			(end 0.7874 -0.4064)
			(stroke
				(width 0.1524)
				(type default)
			)
			(layer "F.SilkS")
		)
		(fp_line
			(start -0.7874 0.4064)
			(end -0.7874 -0.4064)
			(stroke
				(width 0.1524)
				(type default)
			)
			(layer "F.SilkS")
		)
		(fp_line
			(start 0.7874 -0.4064)
			(end 0.7874 0.4064)
			(stroke
				(width 0.1524)
				(type default)
			)
			(layer "F.SilkS")
		)
		(fp_line
			(start 0.7874 0.4064)
			(end -0.7874 0.4064)
			(stroke
				(width 0.1524)
				(type default)
			)
			(layer "F.SilkS")
		)
		(fp_line
			(start -0.67945 -0.305054)
			(end -0.12065 -0.305054)
			(stroke
				(width 0.1)
				(type default)
			)
			(layer "F.Fab")
		)
		(fp_line
			(start -0.67945 0.3048)
			(end -0.67945 -0.305054)
			(stroke
				(width 0.1)
				(type default)
			)
			(layer "F.Fab")
		)
		(fp_line
			(start -0.12065 -0.305054)
			(end -0.12065 -0.2794)
			(stroke
				(width 0.1)
				(type default)
			)
			(layer "F.Fab")
		)
		(fp_line
			(start -0.12065 -0.2794)
			(end 0.12065 -0.2794)
			(stroke
				(width 0.1)
				(type default)
			)
			(layer "F.Fab")
		)
		(fp_line
			(start -0.12065 0.2794)
			(end -0.12065 0.3048)
			(stroke
				(width 0.1)
				(type default)
			)
			(layer "F.Fab")
		)
		(fp_line
			(start -0.12065 0.3048)
			(end -0.67945 0.3048)
			(stroke
				(width 0.1)
				(type default)
			)
			(layer "F.Fab")
		)
		(fp_line
			(start 0.120396 0.2794)
			(end -0.12065 0.2794)
			(stroke
				(width 0.1)
				(type default)
			)
			(layer "F.Fab")
		)
		(fp_line
			(start 0.120396 0.3048)
			(end 0.120396 0.2794)
			(stroke
				(width 0.1)
				(type default)
			)
			(layer "F.Fab")
		)
		(fp_line
			(start 0.12065 -0.3048)
			(end 0.67945 -0.3048)
			(stroke
				(width 0.1)
				(type default)
			)
			(layer "F.Fab")
		)
		(fp_line
			(start 0.12065 -0.2794)
			(end 0.12065 -0.3048)
			(stroke
				(width 0.1)
				(type default)
			)
			(layer "F.Fab")
		)
		(fp_line
			(start 0.67945 -0.3048)
			(end 0.67945 0.3048)
			(stroke
				(width 0.1)
				(type default)
			)
			(layer "F.Fab")
		)
		(fp_line
			(start 0.67945 0.3048)
			(end 0.120396 0.3048)
			(stroke
				(width 0.1)
				(type default)
			)
			(layer "F.Fab")
		)
		(pad "1" smd circle
			(at -0.40005 0)
			(size 0 0)
			(layers "F.Cu" "F.Mask" "F.Paste")
			(net "SMB_NIC6_LS_R_SCL")
		)
		(pad "2" smd circle
			(at 0.40005 0)
			(size 0 0)
			(layers "F.Cu" "F.Mask" "F.Paste")
			(net "P3V3_NIC6")
		)
	)
	(footprint ""
		(layer "F.Cu")
		(at 245.825264 -119.105426 90)
		(property "Reference" "R6040"
			(at 0 0 90)
			(layer "F.SilkS")
			(hide yes)
			(effects
				(font
					(size 1.27 1.27)
				)
			)
		)
		(property "Value" ""
			(at 0 0 90)
			(layer "F.Fab")
			(effects
				(font
					(size 1.27 1.27)
				)
			)
		)
		(duplicate_pad_numbers_are_jumpers no)
		(fp_line
			(start 0.7874 -0.4064)
			(end 0.7874 0.4064)
			(stroke
				(width 0.1524)
				(type default)
			)
			(layer "F.SilkS")
		)
		(fp_line
			(start -0.7874 -0.4064)
			(end 0.7874 -0.4064)
			(stroke
				(width 0.1524)
				(type default)
			)
			(layer "F.SilkS")
		)
		(fp_line
			(start 0.7874 0.4064)
			(end -0.7874 0.4064)
			(stroke
				(width 0.1524)
				(type default)
			)
			(layer "F.SilkS")
		)
		(fp_line
			(start -0.7874 0.4064)
			(end -0.7874 -0.4064)
			(stroke
				(width 0.1524)
				(type default)
			)
			(layer "F.SilkS")
		)
		(fp_line
			(start -0.12065 -0.305054)
			(end -0.12065 -0.2794)
			(stroke
				(width 0.1)
				(type default)
			)
			(layer "F.Fab")
		)
		(fp_line
			(start -0.67945 -0.305054)
			(end -0.12065 -0.305054)
			(stroke
				(width 0.1)
				(type default)
			)
			(layer "F.Fab")
		)
		(fp_line
			(start 0.67945 -0.3048)
			(end 0.67945 0.3048)
			(stroke
				(width 0.1)
				(type default)
			)
			(layer "F.Fab")
		)
		(fp_line
			(start 0.12065 -0.3048)
			(end 0.67945 -0.3048)
			(stroke
				(width 0.1)
				(type default)
			)
			(layer "F.Fab")
		)
		(fp_line
			(start 0.12065 -0.2794)
			(end 0.12065 -0.3048)
			(stroke
				(width 0.1)
				(type default)
			)
			(layer "F.Fab")
		)
		(fp_line
			(start -0.12065 -0.2794)
			(end 0.12065 -0.2794)
			(stroke
				(width 0.1)
				(type default)
			)
			(layer "F.Fab")
		)
		(fp_line
			(start 0.120396 0.2794)
			(end -0.12065 0.2794)
			(stroke
				(width 0.1)
				(type default)
			)
			(layer "F.Fab")
		)
		(fp_line
			(start -0.12065 0.2794)
			(end -0.12065 0.3048)
			(stroke
				(width 0.1)
				(type default)
			)
			(layer "F.Fab")
		)
		(fp_line
			(start 0.67945 0.3048)
			(end 0.120396 0.3048)
			(stroke
				(width 0.1)
				(type default)
			)
			(layer "F.Fab")
		)
		(fp_line
			(start 0.120396 0.3048)
			(end 0.120396 0.2794)
			(stroke
				(width 0.1)
				(type default)
			)
			(layer "F.Fab")
		)
		(fp_line
			(start -0.12065 0.3048)
			(end -0.67945 0.3048)
			(stroke
				(width 0.1)
				(type default)
			)
			(layer "F.Fab")
		)
		(fp_line
			(start -0.67945 0.3048)
			(end -0.67945 -0.305054)
			(stroke
				(width 0.1)
				(type default)
			)
			(layer "F.Fab")
		)
		(pad "1" smd circle
			(at -0.40005 0 90)
			(size 0 0)
			(layers "F.Cu" "F.Mask" "F.Paste")
			(net "P3V3_NIC4_PG_G1")
		)
		(pad "2" smd circle
			(at 0.40005 0 90)
			(size 0 0)
			(layers "F.Cu" "F.Mask" "F.Paste")
			(net "GND")
		)
	)
	(footprint ""
		(layer "F.Cu")
		(at 138.127994 -35.876738)
		(property "Reference" "R6059"
			(at 0 0 0)
			(layer "F.SilkS")
			(hide yes)
			(effects
				(font
					(size 1.27 1.27)
				)
			)
		)
		(property "Value" ""
			(at 0 0 0)
			(layer "F.Fab")
			(effects
				(font
					(size 1.27 1.27)
				)
			)
		)
		(duplicate_pad_numbers_are_jumpers no)
		(fp_line
			(start -0.7874 -0.4064)
			(end 0.7874 -0.4064)
			(stroke
				(width 0.1524)
				(type default)
			)
			(layer "F.SilkS")
		)
		(fp_line
			(start -0.7874 0.4064)
			(end -0.7874 -0.4064)
			(stroke
				(width 0.1524)
				(type default)
			)
			(layer "F.SilkS")
		)
		(fp_line
			(start 0.7874 -0.4064)
			(end 0.7874 0.4064)
			(stroke
				(width 0.1524)
				(type default)
			)
			(layer "F.SilkS")
		)
		(fp_line
			(start 0.7874 0.4064)
			(end -0.7874 0.4064)
			(stroke
				(width 0.1524)
				(type default)
			)
			(layer "F.SilkS")
		)
		(fp_line
			(start -0.67945 -0.305054)
			(end -0.12065 -0.305054)
			(stroke
				(width 0.1)
				(type default)
			)
			(layer "F.Fab")
		)
		(fp_line
			(start -0.67945 0.3048)
			(end -0.67945 -0.305054)
			(stroke
				(width 0.1)
				(type default)
			)
			(layer "F.Fab")
		)
		(fp_line
			(start -0.12065 -0.305054)
			(end -0.12065 -0.2794)
			(stroke
				(width 0.1)
				(type default)
			)
			(layer "F.Fab")
		)
		(fp_line
			(start -0.12065 -0.2794)
			(end 0.12065 -0.2794)
			(stroke
				(width 0.1)
				(type default)
			)
			(layer "F.Fab")
		)
		(fp_line
			(start -0.12065 0.2794)
			(end -0.12065 0.3048)
			(stroke
				(width 0.1)
				(type default)
			)
			(layer "F.Fab")
		)
		(fp_line
			(start -0.12065 0.3048)
			(end -0.67945 0.3048)
			(stroke
				(width 0.1)
				(type default)
			)
			(layer "F.Fab")
		)
		(fp_line
			(start 0.120396 0.2794)
			(end -0.12065 0.2794)
			(stroke
				(width 0.1)
				(type default)
			)
			(layer "F.Fab")
		)
		(fp_line
			(start 0.120396 0.3048)
			(end 0.120396 0.2794)
			(stroke
				(width 0.1)
				(type default)
			)
			(layer "F.Fab")
		)
		(fp_line
			(start 0.12065 -0.3048)
			(end 0.67945 -0.3048)
			(stroke
				(width 0.1)
				(type default)
			)
			(layer "F.Fab")
		)
		(fp_line
			(start 0.12065 -0.2794)
			(end 0.12065 -0.3048)
			(stroke
				(width 0.1)
				(type default)
			)
			(layer "F.Fab")
		)
		(fp_line
			(start 0.67945 -0.3048)
			(end 0.67945 0.3048)
			(stroke
				(width 0.1)
				(type default)
			)
			(layer "F.Fab")
		)
		(fp_line
			(start 0.67945 0.3048)
			(end 0.120396 0.3048)
			(stroke
				(width 0.1)
				(type default)
			)
			(layer "F.Fab")
		)
		(pad "1" smd circle
			(at -0.40005 0)
			(size 0 0)
			(layers "F.Cu" "F.Mask" "F.Paste")
			(net "PWRGD_P3V3_SSD5_D")
		)
		(pad "2" smd circle
			(at 0.40005 0)
			(size 0 0)
			(layers "F.Cu" "F.Mask" "F.Paste")
			(net "PWRGD_P3V3_SSD5_R")
		)
	)
	(footprint ""
		(layer "F.Cu")
		(at 136.531096 -196.821806 180)
		(property "Reference" "R916"
			(at 0 0 180)
			(layer "F.SilkS")
			(hide yes)
			(effects
				(font
					(size 1.27 1.27)
				)
			)
		)
		(property "Value" ""
			(at 0 0 180)
			(layer "F.Fab")
			(effects
				(font
					(size 1.27 1.27)
				)
			)
		)
		(duplicate_pad_numbers_are_jumpers no)
		(fp_line
			(start 1.2954 0.5842)
			(end -1.2954 0.5842)
			(stroke
				(width 0.1524)
				(type default)
			)
			(layer "F.SilkS")
		)
		(fp_line
			(start 1.2954 -0.5842)
			(end 1.2954 0.5842)
			(stroke
				(width 0.1524)
				(type default)
			)
			(layer "F.SilkS")
		)
		(fp_line
			(start -1.2954 0.5842)
			(end -1.2954 -0.5842)
			(stroke
				(width 0.1524)
				(type default)
			)
			(layer "F.SilkS")
		)
		(fp_line
			(start -1.2954 -0.5842)
			(end 1.2954 -0.5842)
			(stroke
				(width 0.1524)
				(type default)
			)
			(layer "F.SilkS")
		)
		(fp_line
			(start 1.1938 0.4064)
			(end 0.8636 0.4064)
			(stroke
				(width 0.1)
				(type default)
			)
			(layer "F.Fab")
		)
		(fp_line
			(start 1.1938 -0.406654)
			(end 1.1938 0.4064)
			(stroke
				(width 0.1)
				(type default)
			)
			(layer "F.Fab")
		)
		(fp_line
			(start 0.8636 0.4572)
			(end -0.8636 0.4572)
			(stroke
				(width 0.1)
				(type default)
			)
			(layer "F.Fab")
		)
		(fp_line
			(start 0.8636 0.4064)
			(end 0.8636 0.4572)
			(stroke
				(width 0.1)
				(type default)
			)
			(layer "F.Fab")
		)
		(fp_line
			(start 0.8636 -0.406654)
			(end 1.1938 -0.406654)
			(stroke
				(width 0.1)
				(type default)
			)
			(layer "F.Fab")
		)
		(fp_line
			(start 0.8636 -0.4572)
			(end 0.8636 -0.406654)
			(stroke
				(width 0.1)
				(type default)
			)
			(layer "F.Fab")
		)
		(fp_line
			(start -0.8636 0.4572)
			(end -0.8636 0.4318)
			(stroke
				(width 0.1)
				(type default)
			)
			(layer "F.Fab")
		)
		(fp_line
			(start -0.8636 0.4318)
			(end -0.8636 0.4064)
			(stroke
				(width 0.1)
				(type default)
			)
			(layer "F.Fab")
		)
		(fp_line
			(start -0.8636 0.4064)
			(end -1.1938 0.4064)
			(stroke
				(width 0.1)
				(type default)
			)
			(layer "F.Fab")
		)
		(fp_line
			(start -0.8636 -0.406654)
			(end -0.8636 -0.4572)
			(stroke
				(width 0.1)
				(type default)
			)
			(layer "F.Fab")
		)
		(fp_line
			(start -0.8636 -0.4572)
			(end 0.8636 -0.4572)
			(stroke
				(width 0.1)
				(type default)
			)
			(layer "F.Fab")
		)
		(fp_line
			(start -1.1938 0.4064)
			(end -1.1938 -0.406654)
			(stroke
				(width 0.1)
				(type default)
			)
			(layer "F.Fab")
		)
		(fp_line
			(start -1.1938 -0.406654)
			(end -0.8636 -0.406654)
			(stroke
				(width 0.1)
				(type default)
			)
			(layer "F.Fab")
		)
		(pad "1" smd rect
			(at -0.7366 0 90)
			(size 0.7112 0.8128)
			(layers "F.Cu" "F.Mask" "F.Paste")
			(net "OSC_CLI_OUT")
		)
		(pad "2" smd rect
			(at 0.7366 0 90)
			(size 0.7112 0.8128)
			(layers "F.Cu" "F.Mask" "F.Paste")
			(net "OSC_CLI_IN")
		)
	)
	(footprint ""
		(layer "F.Cu")
		(at 80.019398 -147.104608 180)
		(property "Reference" "C11"
			(at 0 0 180)
			(layer "F.SilkS")
			(hide yes)
			(effects
				(font
					(size 1.27 1.27)
				)
			)
		)
		(property "Value" ""
			(at 0 0 180)
			(layer "F.Fab")
			(effects
				(font
					(size 1.27 1.27)
				)
			)
		)
		(duplicate_pad_numbers_are_jumpers no)
		(fp_line
			(start 0.299974 0.150114)
			(end -0.299974 0.150114)
			(stroke
				(width 0.1)
				(type default)
			)
			(layer "F.Fab")
		)
		(fp_line
			(start 0.299974 -0.150114)
			(end 0.299974 0.150114)
			(stroke
				(width 0.1)
				(type default)
			)
			(layer "F.Fab")
		)
		(fp_line
			(start -0.299974 0.150114)
			(end -0.299974 -0.150114)
			(stroke
				(width 0.1)
				(type default)
			)
			(layer "F.Fab")
		)
		(fp_line
			(start -0.299974 -0.150114)
			(end 0.299974 -0.150114)
			(stroke
				(width 0.1)
				(type default)
			)
			(layer "F.Fab")
		)
		(pad "1" smd rect
			(at -0.2667 0 180)
			(size 0.3048 0.381)
			(layers "F.Cu" "F.Mask" "F.Paste")
			(net "P5E_PEX0_STN0_TX_DP<10>")
		)
		(pad "2" smd rect
			(at 0.2667 0 180)
			(size 0.3048 0.381)
			(layers "F.Cu" "F.Mask" "F.Paste")
			(net "P5E_PEX0_STN0_TX_C_DP<10>")
		)
	)
	(footprint ""
		(layer "F.Cu")
		(at 146.473926 -27.006296 -90)
		(property "Reference" "PC926"
			(at 0 0 270)
			(layer "F.SilkS")
			(hide yes)
			(effects
				(font
					(size 1.27 1.27)
				)
			)
		)
		(property "Value" ""
			(at 0 0 270)
			(layer "F.Fab")
			(effects
				(font
					(size 1.27 1.27)
				)
			)
		)
		(duplicate_pad_numbers_are_jumpers no)
		(fp_line
			(start -0.7874 0.4064)
			(end -0.7874 -0.4064)
			(stroke
				(width 0.1524)
				(type default)
			)
			(layer "F.SilkS")
		)
		(fp_line
			(start 0.7874 0.4064)
			(end -0.7874 0.4064)
			(stroke
				(width 0.1524)
				(type default)
			)
			(layer "F.SilkS")
		)
		(fp_line
			(start -0.7874 -0.4064)
			(end 0.7874 -0.4064)
			(stroke
				(width 0.1524)
				(type default)
			)
			(layer "F.SilkS")
		)
		(fp_line
			(start 0.7874 -0.4064)
			(end 0.7874 0.4064)
			(stroke
				(width 0.1524)
				(type default)
			)
			(layer "F.SilkS")
		)
		(fp_line
			(start -0.67945 0.3048)
			(end -0.67945 -0.305054)
			(stroke
				(width 0.1)
				(type default)
			)
			(layer "F.Fab")
		)
		(fp_line
			(start -0.12065 0.3048)
			(end -0.67945 0.3048)
			(stroke
				(width 0.1)
				(type default)
			)
			(layer "F.Fab")
		)
		(fp_line
			(start 0.120396 0.3048)
			(end 0.120396 0.2794)
			(stroke
				(width 0.1)
				(type default)
			)
			(layer "F.Fab")
		)
		(fp_line
			(start 0.67945 0.3048)
			(end 0.120396 0.3048)
			(stroke
				(width 0.1)
				(type default)
			)
			(layer "F.Fab")
		)
		(fp_line
			(start -0.12065 0.2794)
			(end -0.12065 0.3048)
			(stroke
				(width 0.1)
				(type default)
			)
			(layer "F.Fab")
		)
		(fp_line
			(start 0.120396 0.2794)
			(end -0.12065 0.2794)
			(stroke
				(width 0.1)
				(type default)
			)
			(layer "F.Fab")
		)
		(fp_line
			(start -0.12065 -0.2794)
			(end 0.12065 -0.2794)
			(stroke
				(width 0.1)
				(type default)
			)
			(layer "F.Fab")
		)
		(fp_line
			(start 0.12065 -0.2794)
			(end 0.12065 -0.3048)
			(stroke
				(width 0.1)
				(type default)
			)
			(layer "F.Fab")
		)
		(fp_line
			(start 0.12065 -0.3048)
			(end 0.67945 -0.3048)
			(stroke
				(width 0.1)
				(type default)
			)
			(layer "F.Fab")
		)
		(fp_line
			(start 0.67945 -0.3048)
			(end 0.67945 0.3048)
			(stroke
				(width 0.1)
				(type default)
			)
			(layer "F.Fab")
		)
		(fp_line
			(start -0.67945 -0.305054)
			(end -0.12065 -0.305054)
			(stroke
				(width 0.1)
				(type default)
			)
			(layer "F.Fab")
		)
		(fp_line
			(start -0.12065 -0.305054)
			(end -0.12065 -0.2794)
			(stroke
				(width 0.1)
				(type default)
			)
			(layer "F.Fab")
		)
		(pad "1" smd circle
			(at -0.40005 0 270)
			(size 0 0)
			(layers "F.Cu" "F.Mask" "F.Paste")
			(net "P3V3_SSD5_CO_MODE")
		)
		(pad "2" smd circle
			(at 0.40005 0 270)
			(size 0 0)
			(layers "F.Cu" "F.Mask" "F.Paste")
			(net "GND")
		)
	)
	(footprint ""
		(layer "F.Cu")
		(at 78.243684 -48.93691 180)
		(property "Reference" "R534"
			(at 0 0 180)
			(layer "F.SilkS")
			(hide yes)
			(effects
				(font
					(size 1.27 1.27)
				)
			)
		)
		(property "Value" ""
			(at 0 0 180)
			(layer "F.Fab")
			(effects
				(font
					(size 1.27 1.27)
				)
			)
		)
		(duplicate_pad_numbers_are_jumpers no)
		(fp_line
			(start 0.7874 0.4064)
			(end -0.7874 0.4064)
			(stroke
				(width 0.1524)
				(type default)
			)
			(layer "F.SilkS")
		)
		(fp_line
			(start 0.7874 -0.4064)
			(end 0.7874 0.4064)
			(stroke
				(width 0.1524)
				(type default)
			)
			(layer "F.SilkS")
		)
		(fp_line
			(start -0.7874 0.4064)
			(end -0.7874 -0.4064)
			(stroke
				(width 0.1524)
				(type default)
			)
			(layer "F.SilkS")
		)
		(fp_line
			(start -0.7874 -0.4064)
			(end 0.7874 -0.4064)
			(stroke
				(width 0.1524)
				(type default)
			)
			(layer "F.SilkS")
		)
		(fp_line
			(start 0.67945 0.3048)
			(end 0.120396 0.3048)
			(stroke
				(width 0.1)
				(type default)
			)
			(layer "F.Fab")
		)
		(fp_line
			(start 0.67945 -0.3048)
			(end 0.67945 0.3048)
			(stroke
				(width 0.1)
				(type default)
			)
			(layer "F.Fab")
		)
		(fp_line
			(start 0.12065 -0.2794)
			(end 0.12065 -0.3048)
			(stroke
				(width 0.1)
				(type default)
			)
			(layer "F.Fab")
		)
		(fp_line
			(start 0.12065 -0.3048)
			(end 0.67945 -0.3048)
			(stroke
				(width 0.1)
				(type default)
			)
			(layer "F.Fab")
		)
		(fp_line
			(start 0.120396 0.3048)
			(end 0.120396 0.2794)
			(stroke
				(width 0.1)
				(type default)
			)
			(layer "F.Fab")
		)
		(fp_line
			(start 0.120396 0.2794)
			(end -0.12065 0.2794)
			(stroke
				(width 0.1)
				(type default)
			)
			(layer "F.Fab")
		)
		(fp_line
			(start -0.12065 0.3048)
			(end -0.67945 0.3048)
			(stroke
				(width 0.1)
				(type default)
			)
			(layer "F.Fab")
		)
		(fp_line
			(start -0.12065 0.2794)
			(end -0.12065 0.3048)
			(stroke
				(width 0.1)
				(type default)
			)
			(layer "F.Fab")
		)
		(fp_line
			(start -0.12065 -0.2794)
			(end 0.12065 -0.2794)
			(stroke
				(width 0.1)
				(type default)
			)
			(layer "F.Fab")
		)
		(fp_line
			(start -0.12065 -0.305054)
			(end -0.12065 -0.2794)
			(stroke
				(width 0.1)
				(type default)
			)
			(layer "F.Fab")
		)
		(fp_line
			(start -0.67945 0.3048)
			(end -0.67945 -0.305054)
			(stroke
				(width 0.1)
				(type default)
			)
			(layer "F.Fab")
		)
		(fp_line
			(start -0.67945 -0.305054)
			(end -0.12065 -0.305054)
			(stroke
				(width 0.1)
				(type default)
			)
			(layer "F.Fab")
		)
		(pad "1" smd circle
			(at -0.40005 0 180)
			(size 0 0)
			(layers "F.Cu" "F.Mask" "F.Paste")
			(net "SMB_BIC_I2C6_MUX_SSD_0_7_ADC_R_SDA")
		)
		(pad "2" smd circle
			(at 0.40005 0 180)
			(size 0 0)
			(layers "F.Cu" "F.Mask" "F.Paste")
			(net "SMB_SSD2_ADC_SDA")
		)
	)
	(footprint ""
		(layer "F.Cu")
		(at 252.873002 -22.867366 90)
		(property "Reference" "C3928"
			(at 0 0 90)
			(layer "F.SilkS")
			(hide yes)
			(effects
				(font
					(size 1.27 1.27)
				)
			)
		)
		(property "Value" ""
			(at 0 0 90)
			(layer "F.Fab")
			(effects
				(font
					(size 1.27 1.27)
				)
			)
		)
		(duplicate_pad_numbers_are_jumpers no)
		(fp_line
			(start 0.7874 -0.4064)
			(end 0.7874 0.4064)
			(stroke
				(width 0.1524)
				(type default)
			)
			(layer "F.SilkS")
		)
		(fp_line
			(start -0.7874 -0.4064)
			(end 0.7874 -0.4064)
			(stroke
				(width 0.1524)
				(type default)
			)
			(layer "F.SilkS")
		)
		(fp_line
			(start 0.7874 0.4064)
			(end -0.7874 0.4064)
			(stroke
				(width 0.1524)
				(type default)
			)
			(layer "F.SilkS")
		)
		(fp_line
			(start -0.7874 0.4064)
			(end -0.7874 -0.4064)
			(stroke
				(width 0.1524)
				(type default)
			)
			(layer "F.SilkS")
		)
		(fp_line
			(start -0.12065 -0.305054)
			(end -0.12065 -0.2794)
			(stroke
				(width 0.1)
				(type default)
			)
			(layer "F.Fab")
		)
		(fp_line
			(start -0.67945 -0.305054)
			(end -0.12065 -0.305054)
			(stroke
				(width 0.1)
				(type default)
			)
			(layer "F.Fab")
		)
		(fp_line
			(start 0.67945 -0.3048)
			(end 0.67945 0.3048)
			(stroke
				(width 0.1)
				(type default)
			)
			(layer "F.Fab")
		)
		(fp_line
			(start 0.12065 -0.3048)
			(end 0.67945 -0.3048)
			(stroke
				(width 0.1)
				(type default)
			)
			(layer "F.Fab")
		)
		(fp_line
			(start 0.12065 -0.2794)
			(end 0.12065 -0.3048)
			(stroke
				(width 0.1)
				(type default)
			)
			(layer "F.Fab")
		)
		(fp_line
			(start -0.12065 -0.2794)
			(end 0.12065 -0.2794)
			(stroke
				(width 0.1)
				(type default)
			)
			(layer "F.Fab")
		)
		(fp_line
			(start 0.120396 0.2794)
			(end -0.12065 0.2794)
			(stroke
				(width 0.1)
				(type default)
			)
			(layer "F.Fab")
		)
		(fp_line
			(start -0.12065 0.2794)
			(end -0.12065 0.3048)
			(stroke
				(width 0.1)
				(type default)
			)
			(layer "F.Fab")
		)
		(fp_line
			(start 0.67945 0.3048)
			(end 0.120396 0.3048)
			(stroke
				(width 0.1)
				(type default)
			)
			(layer "F.Fab")
		)
		(fp_line
			(start 0.120396 0.3048)
			(end 0.120396 0.2794)
			(stroke
				(width 0.1)
				(type default)
			)
			(layer "F.Fab")
		)
		(fp_line
			(start -0.12065 0.3048)
			(end -0.67945 0.3048)
			(stroke
				(width 0.1)
				(type default)
			)
			(layer "F.Fab")
		)
		(fp_line
			(start -0.67945 0.3048)
			(end -0.67945 -0.305054)
			(stroke
				(width 0.1)
				(type default)
			)
			(layer "F.Fab")
		)
		(pad "1" smd circle
			(at -0.40005 0 90)
			(size 0 0)
			(layers "F.Cu" "F.Mask" "F.Paste")
			(net "P12V_SSD8")
		)
		(pad "2" smd circle
			(at 0.40005 0 90)
			(size 0 0)
			(layers "F.Cu" "F.Mask" "F.Paste")
			(net "GND")
		)
	)
	(footprint ""
		(layer "F.Cu")
		(at 45.471588 -25.342342 -90)
		(property "Reference" "R412"
			(at 0 0 270)
			(layer "F.SilkS")
			(hide yes)
			(effects
				(font
					(size 1.27 1.27)
				)
			)
		)
		(property "Value" ""
			(at 0 0 270)
			(layer "F.Fab")
			(effects
				(font
					(size 1.27 1.27)
				)
			)
		)
		(duplicate_pad_numbers_are_jumpers no)
		(fp_line
			(start -0.7874 0.4064)
			(end -0.7874 -0.4064)
			(stroke
				(width 0.1524)
				(type default)
			)
			(layer "F.SilkS")
		)
		(fp_line
			(start 0.7874 0.4064)
			(end -0.7874 0.4064)
			(stroke
				(width 0.1524)
				(type default)
			)
			(layer "F.SilkS")
		)
		(fp_line
			(start -0.7874 -0.4064)
			(end 0.7874 -0.4064)
			(stroke
				(width 0.1524)
				(type default)
			)
			(layer "F.SilkS")
		)
		(fp_line
			(start 0.7874 -0.4064)
			(end 0.7874 0.4064)
			(stroke
				(width 0.1524)
				(type default)
			)
			(layer "F.SilkS")
		)
		(fp_line
			(start -0.67945 0.3048)
			(end -0.67945 -0.305054)
			(stroke
				(width 0.1)
				(type default)
			)
			(layer "F.Fab")
		)
		(fp_line
			(start -0.12065 0.3048)
			(end -0.67945 0.3048)
			(stroke
				(width 0.1)
				(type default)
			)
			(layer "F.Fab")
		)
		(fp_line
			(start 0.120396 0.3048)
			(end 0.120396 0.2794)
			(stroke
				(width 0.1)
				(type default)
			)
			(layer "F.Fab")
		)
		(fp_line
			(start 0.67945 0.3048)
			(end 0.120396 0.3048)
			(stroke
				(width 0.1)
				(type default)
			)
			(layer "F.Fab")
		)
		(fp_line
			(start -0.12065 0.2794)
			(end -0.12065 0.3048)
			(stroke
				(width 0.1)
				(type default)
			)
			(layer "F.Fab")
		)
		(fp_line
			(start 0.120396 0.2794)
			(end -0.12065 0.2794)
			(stroke
				(width 0.1)
				(type default)
			)
			(layer "F.Fab")
		)
		(fp_line
			(start -0.12065 -0.2794)
			(end 0.12065 -0.2794)
			(stroke
				(width 0.1)
				(type default)
			)
			(layer "F.Fab")
		)
		(fp_line
			(start 0.12065 -0.2794)
			(end 0.12065 -0.3048)
			(stroke
				(width 0.1)
				(type default)
			)
			(layer "F.Fab")
		)
		(fp_line
			(start 0.12065 -0.3048)
			(end 0.67945 -0.3048)
			(stroke
				(width 0.1)
				(type default)
			)
			(layer "F.Fab")
		)
		(fp_line
			(start 0.67945 -0.3048)
			(end 0.67945 0.3048)
			(stroke
				(width 0.1)
				(type default)
			)
			(layer "F.Fab")
		)
		(fp_line
			(start -0.67945 -0.305054)
			(end -0.12065 -0.305054)
			(stroke
				(width 0.1)
				(type default)
			)
			(layer "F.Fab")
		)
		(fp_line
			(start -0.12065 -0.305054)
			(end -0.12065 -0.2794)
			(stroke
				(width 0.1)
				(type default)
			)
			(layer "F.Fab")
		)
		(pad "1" smd circle
			(at -0.40005 0 270)
			(size 0 0)
			(layers "F.Cu" "F.Mask" "F.Paste")
			(net "P3V3_SSD1")
		)
		(pad "2" smd circle
			(at 0.40005 0 270)
			(size 0 0)
			(layers "F.Cu" "F.Mask" "F.Paste")
			(net "DUALPORT_N_SSD1")
		)
	)
	(footprint ""
		(layer "F.Cu")
		(at 333.801212 -303.649634 90)
		(property "Reference" "PC150"
			(at 0 0 90)
			(layer "F.SilkS")
			(hide yes)
			(effects
				(font
					(size 1.27 1.27)
				)
			)
		)
		(property "Value" ""
			(at 0 0 90)
			(layer "F.Fab")
			(effects
				(font
					(size 1.27 1.27)
				)
			)
		)
		(duplicate_pad_numbers_are_jumpers no)
		(fp_line
			(start 1.524 -0.762)
			(end 1.524 0.762)
			(stroke
				(width 0.1524)
				(type default)
			)
			(layer "F.SilkS")
		)
		(fp_line
			(start -1.524 -0.762)
			(end 1.524 -0.762)
			(stroke
				(width 0.1524)
				(type default)
			)
			(layer "F.SilkS")
		)
		(fp_line
			(start 1.524 0.762)
			(end -1.524 0.762)
			(stroke
				(width 0.1524)
				(type default)
			)
			(layer "F.SilkS")
		)
		(fp_line
			(start -1.524 0.762)
			(end -1.524 -0.762)
			(stroke
				(width 0.1524)
				(type default)
			)
			(layer "F.SilkS")
		)
		(fp_line
			(start 1.1049 -0.724916)
			(end -1.1049 -0.724916)
			(stroke
				(width 0.1)
				(type default)
			)
			(layer "F.Fab")
		)
		(fp_line
			(start -1.1049 -0.724916)
			(end -1.1049 0.724916)
			(stroke
				(width 0.1)
				(type default)
			)
			(layer "F.Fab")
		)
		(fp_line
			(start 1.1049 0.724916)
			(end 1.1049 -0.724916)
			(stroke
				(width 0.1)
				(type default)
			)
			(layer "F.Fab")
		)
		(fp_line
			(start -1.1049 0.724916)
			(end 1.1049 0.724916)
			(stroke
				(width 0.1)
				(type default)
			)
			(layer "F.Fab")
		)
		(pad "1" smd rect
			(at -0.889 0 270)
			(size 1.016 1.27)
			(layers "F.Cu" "F.Mask" "F.Paste")
			(net "P0V8_PEX2")
		)
		(pad "2" smd rect
			(at 0.889 0 270)
			(size 1.016 1.27)
			(layers "F.Cu" "F.Mask" "F.Paste")
			(net "GND")
		)
	)
	(footprint ""
		(layer "F.Cu")
		(at 308.473856 -26.31186 -90)
		(property "Reference" "U410"
			(at -0.15494 -2.321814 90)
			(unlocked yes)
			(layer "F.SilkS")
			(effects
				(font
					(size 0.7874 0.5842)
					(thickness 0.1524)
				)
			)
		)
		(property "Value" ""
			(at 0 0 270)
			(layer "F.Fab")
			(effects
				(font
					(size 1.27 1.27)
				)
			)
		)
		(duplicate_pad_numbers_are_jumpers no)
		(fp_line
			(start -1.949958 1.610106)
			(end -1.949958 -1.610106)
			(stroke
				(width 0.1524)
				(type default)
			)
			(layer "F.SilkS")
		)
		(fp_line
			(start 1.949958 1.610106)
			(end -1.949958 1.610106)
			(stroke
				(width 0.1524)
				(type default)
			)
			(layer "F.SilkS")
		)
		(fp_line
			(start 1.949958 -1.560068)
			(end 1.949958 1.610106)
			(stroke
				(width 0.1524)
				(type default)
			)
			(layer "F.SilkS")
		)
		(fp_line
			(start -1.949958 -1.610106)
			(end 1.949958 -1.610106)
			(stroke
				(width 0.1524)
				(type default)
			)
			(layer "F.SilkS")
		)
		(fp_line
			(start -0.750062 1.560068)
			(end -0.750062 -1.560068)
			(stroke
				(width 0.1)
				(type default)
			)
			(layer "F.Fab")
		)
		(fp_line
			(start 0.750062 1.560068)
			(end -0.750062 1.560068)
			(stroke
				(width 0.1)
				(type default)
			)
			(layer "F.Fab")
		)
		(fp_line
			(start -0.750062 -1.560068)
			(end 0.750062 -1.560068)
			(stroke
				(width 0.1)
				(type default)
			)
			(layer "F.Fab")
		)
		(fp_line
			(start 0.750062 -1.560068)
			(end 0.750062 1.560068)
			(stroke
				(width 0.1)
				(type default)
			)
			(layer "F.Fab")
		)
		(pad "D" smd rect
			(at 1.100074 0 180)
			(size 1.016 1.4224)
			(layers "F.Cu" "F.Mask" "F.Paste")
			(net "SSD10_LED_ISO_N")
		)
		(pad "G" smd rect
			(at -1.100074 -0.94996 180)
			(size 1.016 1.4224)
			(layers "F.Cu" "F.Mask" "F.Paste")
			(net "SSD10_LED_R")
		)
		(pad "S" smd rect
			(at -1.100074 0.94996 180)
			(size 1.016 1.4224)
			(layers "F.Cu" "F.Mask" "F.Paste")
			(net "GND")
		)
	)
	(footprint ""
		(layer "F.Cu")
		(at 112.475772 -279.101804)
		(property "Reference" "PC75"
			(at 0 0 0)
			(layer "F.SilkS")
			(hide yes)
			(effects
				(font
					(size 1.27 1.27)
				)
			)
		)
		(property "Value" ""
			(at 0 0 0)
			(layer "F.Fab")
			(effects
				(font
					(size 1.27 1.27)
				)
			)
		)
		(duplicate_pad_numbers_are_jumpers no)
		(fp_line
			(start -0.7874 -0.4064)
			(end 0.7874 -0.4064)
			(stroke
				(width 0.1524)
				(type default)
			)
			(layer "F.SilkS")
		)
		(fp_line
			(start -0.7874 0.4064)
			(end -0.7874 -0.4064)
			(stroke
				(width 0.1524)
				(type default)
			)
			(layer "F.SilkS")
		)
		(fp_line
			(start 0.7874 -0.4064)
			(end 0.7874 0.4064)
			(stroke
				(width 0.1524)
				(type default)
			)
			(layer "F.SilkS")
		)
		(fp_line
			(start 0.7874 0.4064)
			(end -0.7874 0.4064)
			(stroke
				(width 0.1524)
				(type default)
			)
			(layer "F.SilkS")
		)
		(fp_line
			(start -0.67945 -0.305054)
			(end -0.12065 -0.305054)
			(stroke
				(width 0.1)
				(type default)
			)
			(layer "F.Fab")
		)
		(fp_line
			(start -0.67945 0.3048)
			(end -0.67945 -0.305054)
			(stroke
				(width 0.1)
				(type default)
			)
			(layer "F.Fab")
		)
		(fp_line
			(start -0.12065 -0.305054)
			(end -0.12065 -0.2794)
			(stroke
				(width 0.1)
				(type default)
			)
			(layer "F.Fab")
		)
		(fp_line
			(start -0.12065 -0.2794)
			(end 0.12065 -0.2794)
			(stroke
				(width 0.1)
				(type default)
			)
			(layer "F.Fab")
		)
		(fp_line
			(start -0.12065 0.2794)
			(end -0.12065 0.3048)
			(stroke
				(width 0.1)
				(type default)
			)
			(layer "F.Fab")
		)
		(fp_line
			(start -0.12065 0.3048)
			(end -0.67945 0.3048)
			(stroke
				(width 0.1)
				(type default)
			)
			(layer "F.Fab")
		)
		(fp_line
			(start 0.120396 0.2794)
			(end -0.12065 0.2794)
			(stroke
				(width 0.1)
				(type default)
			)
			(layer "F.Fab")
		)
		(fp_line
			(start 0.120396 0.3048)
			(end 0.120396 0.2794)
			(stroke
				(width 0.1)
				(type default)
			)
			(layer "F.Fab")
		)
		(fp_line
			(start 0.12065 -0.3048)
			(end 0.67945 -0.3048)
			(stroke
				(width 0.1)
				(type default)
			)
			(layer "F.Fab")
		)
		(fp_line
			(start 0.12065 -0.2794)
			(end 0.12065 -0.3048)
			(stroke
				(width 0.1)
				(type default)
			)
			(layer "F.Fab")
		)
		(fp_line
			(start 0.67945 -0.3048)
			(end 0.67945 0.3048)
			(stroke
				(width 0.1)
				(type default)
			)
			(layer "F.Fab")
		)
		(fp_line
			(start 0.67945 0.3048)
			(end 0.120396 0.3048)
			(stroke
				(width 0.1)
				(type default)
			)
			(layer "F.Fab")
		)
		(pad "1" smd circle
			(at -0.40005 0)
			(size 0 0)
			(layers "F.Cu" "F.Mask" "F.Paste")
			(net "SW_P12V_P0V8_PEX0_FLT")
		)
		(pad "2" smd circle
			(at 0.40005 0)
			(size 0 0)
			(layers "F.Cu" "F.Mask" "F.Paste")
			(net "GND")
		)
	)
	(footprint ""
		(layer "F.Cu")
		(at 399.364454 -29.079952 180)
		(property "Reference" "R6211"
			(at 0 0 180)
			(layer "F.SilkS")
			(hide yes)
			(effects
				(font
					(size 1.27 1.27)
				)
			)
		)
		(property "Value" ""
			(at 0 0 180)
			(layer "F.Fab")
			(effects
				(font
					(size 1.27 1.27)
				)
			)
		)
		(duplicate_pad_numbers_are_jumpers no)
		(fp_line
			(start 0.7874 0.4064)
			(end -0.7874 0.4064)
			(stroke
				(width 0.1524)
				(type default)
			)
			(layer "F.SilkS")
		)
		(fp_line
			(start 0.7874 -0.4064)
			(end 0.7874 0.4064)
			(stroke
				(width 0.1524)
				(type default)
			)
			(layer "F.SilkS")
		)
		(fp_line
			(start -0.7874 0.4064)
			(end -0.7874 -0.4064)
			(stroke
				(width 0.1524)
				(type default)
			)
			(layer "F.SilkS")
		)
		(fp_line
			(start -0.7874 -0.4064)
			(end 0.7874 -0.4064)
			(stroke
				(width 0.1524)
				(type default)
			)
			(layer "F.SilkS")
		)
		(fp_line
			(start 0.67945 0.3048)
			(end 0.120396 0.3048)
			(stroke
				(width 0.1)
				(type default)
			)
			(layer "F.Fab")
		)
		(fp_line
			(start 0.67945 -0.3048)
			(end 0.67945 0.3048)
			(stroke
				(width 0.1)
				(type default)
			)
			(layer "F.Fab")
		)
		(fp_line
			(start 0.12065 -0.2794)
			(end 0.12065 -0.3048)
			(stroke
				(width 0.1)
				(type default)
			)
			(layer "F.Fab")
		)
		(fp_line
			(start 0.12065 -0.3048)
			(end 0.67945 -0.3048)
			(stroke
				(width 0.1)
				(type default)
			)
			(layer "F.Fab")
		)
		(fp_line
			(start 0.120396 0.3048)
			(end 0.120396 0.2794)
			(stroke
				(width 0.1)
				(type default)
			)
			(layer "F.Fab")
		)
		(fp_line
			(start 0.120396 0.2794)
			(end -0.12065 0.2794)
			(stroke
				(width 0.1)
				(type default)
			)
			(layer "F.Fab")
		)
		(fp_line
			(start -0.12065 0.3048)
			(end -0.67945 0.3048)
			(stroke
				(width 0.1)
				(type default)
			)
			(layer "F.Fab")
		)
		(fp_line
			(start -0.12065 0.2794)
			(end -0.12065 0.3048)
			(stroke
				(width 0.1)
				(type default)
			)
			(layer "F.Fab")
		)
		(fp_line
			(start -0.12065 -0.2794)
			(end 0.12065 -0.2794)
			(stroke
				(width 0.1)
				(type default)
			)
			(layer "F.Fab")
		)
		(fp_line
			(start -0.12065 -0.305054)
			(end -0.12065 -0.2794)
			(stroke
				(width 0.1)
				(type default)
			)
			(layer "F.Fab")
		)
		(fp_line
			(start -0.67945 0.3048)
			(end -0.67945 -0.305054)
			(stroke
				(width 0.1)
				(type default)
			)
			(layer "F.Fab")
		)
		(fp_line
			(start -0.67945 -0.305054)
			(end -0.12065 -0.305054)
			(stroke
				(width 0.1)
				(type default)
			)
			(layer "F.Fab")
		)
		(pad "1" smd circle
			(at -0.40005 0 180)
			(size 0 0)
			(layers "F.Cu" "F.Mask" "F.Paste")
			(net "GND")
		)
		(pad "2" smd circle
			(at 0.40005 0 180)
			(size 0 0)
			(layers "F.Cu" "F.Mask" "F.Paste")
			(net "SSD13_PWRDIS_R")
		)
	)
	(footprint ""
		(layer "F.Cu")
		(at 14.286992 -444.739014 180)
		(property "Reference" "X2"
			(at -0.1778 -1.92913 180)
			(unlocked yes)
			(layer "F.SilkS")
			(effects
				(font
					(size 0.7874 0.5842)
					(thickness 0.1524)
				)
				(justify left)
			)
		)
		(property "Value" ""
			(at 0 0 180)
			(layer "F.Fab")
			(effects
				(font
					(size 1.27 1.27)
				)
			)
		)
		(property "Device Type" "TP_TDR_4P_FTS_MPKT4_H025P0200_IO_TP15_TP_TDR_4P_DIP"
			(at 1.30175 1.27 270)
			(unlocked yes)
			(layer "F.Fab")
			(hide yes)
			(effects
				(font
					(size 0.635 0.4064)
					(thickness 0.1524)
				)
			)
		)
		(property "User Part Number" "TP15"
			(at 1.30175 1.27 270)
			(unlocked yes)
			(layer "Cmts.User")
			(hide yes)
			(effects
				(font
					(size 0.635 0.4064)
					(thickness 0.1524)
				)
			)
		)
		(duplicate_pad_numbers_are_jumpers no)
		(fp_line
			(start 2.54 3.81)
			(end 2.54 3.6703)
			(stroke
				(width 0.1524)
				(type default)
			)
			(layer "F.SilkS")
		)
		(fp_line
			(start 2.54 1.4097)
			(end 2.54 1.1303)
			(stroke
				(width 0.1524)
				(type default)
			)
			(layer "F.SilkS")
		)
		(fp_line
			(start 2.54 -1.1303)
			(end 2.54 -1.27)
			(stroke
				(width 0.1524)
				(type default)
			)
			(layer "F.SilkS")
		)
		(fp_line
			(start 2.54 -1.27)
			(end 0 -1.27)
			(stroke
				(width 0.1524)
				(type default)
			)
			(layer "F.SilkS")
		)
		(fp_line
			(start 0 3.81)
			(end 2.54 3.81)
			(stroke
				(width 0.1524)
				(type default)
			)
			(layer "F.SilkS")
		)
		(fp_line
			(start 0 3.175)
			(end 0 3.81)
			(stroke
				(width 0.1524)
				(type default)
			)
			(layer "F.SilkS")
		)
		(fp_line
			(start 0 0.635)
			(end 0 1.905)
			(stroke
				(width 0.1524)
				(type default)
			)
			(layer "F.SilkS")
		)
		(fp_line
			(start 0 -1.27)
			(end 0 -0.635)
			(stroke
				(width 0.1524)
				(type default)
			)
			(layer "F.SilkS")
		)
		(fp_poly
			(pts
				(xy -0.761746 0) (xy -2.285746 -0.762) (xy -2.285746 0.762)
			)
			(stroke
				(width 0)
				(type default)
			)
			(fill yes)
			(layer "F.SilkS")
		)
		(fp_line
			(start 2.54 3.81)
			(end 2.54 -1.27)
			(stroke
				(width 0.1)
				(type default)
			)
			(layer "F.Fab")
		)
		(fp_line
			(start 2.54 -1.27)
			(end 0 -1.27)
			(stroke
				(width 0.1)
				(type default)
			)
			(layer "F.Fab")
		)
		(fp_line
			(start 0 3.81)
			(end 2.54 3.81)
			(stroke
				(width 0.1)
				(type default)
			)
			(layer "F.Fab")
		)
		(fp_line
			(start 0 -1.27)
			(end 0 3.81)
			(stroke
				(width 0.1)
				(type default)
			)
			(layer "F.Fab")
		)
		(fp_poly
			(pts
				(xy -0.761746 0) (xy -2.285746 -0.762) (xy -2.285746 0.762)
			)
			(stroke
				(width 0)
				(type default)
			)
			(fill yes)
			(layer "F.Fab")
		)
		(pad "1" thru_hole circle
			(at 0 0 180)
			(size 1.0033 1.0033)
			(drill 0.249936)
			(layers "*.Cu" "*.Mask")
			(remove_unused_layers no)
			(net "TDR_DIFF_85_TOP_DIP")
			(clearance 0.10795)
			(thermal_gap 0.10795)
			(padstack
				(mode front_inner_back)
				(layer "Inner"
					(shape circle)
					(size 0.8001 0.8001)
					(clearance 0.1524)
				)
				(layer "B.Cu"
					(shape circle)
					(size 1.0033 1.0033)
					(clearance 0.10795)
				)
			)
		)
		(pad "2" thru_hole circle
			(at 2.54 0 180)
			(size 1.9939 1.9939)
			(drill 0.249936)
			(layers "*.Cu" "*.Mask")
			(remove_unused_layers no)
			(net "COUPON_GND1")
			(clearance 0.10795)
			(thermal_gap 0.10795)
			(padstack
				(mode front_inner_back)
				(layer "Inner"
					(shape circle)
					(size 0.8001 0.8001)
					(clearance 0.1524)
				)
				(layer "B.Cu"
					(shape circle)
					(size 1.9939 1.9939)
					(clearance 0.10795)
				)
			)
		)
		(pad "3" thru_hole circle
			(at 2.54 2.54 180)
			(size 1.9939 1.9939)
			(drill 0.249936)
			(layers "*.Cu" "*.Mask")
			(remove_unused_layers no)
			(net "COUPON_GND1")
			(clearance 0.10795)
			(thermal_gap 0.10795)
			(padstack
				(mode front_inner_back)
				(layer "Inner"
					(shape circle)
					(size 0.8001 0.8001)
					(clearance 0.1524)
				)
				(layer "B.Cu"
					(shape circle)
					(size 1.9939 1.9939)
					(clearance 0.10795)
				)
			)
		)
		(pad "4" thru_hole circle
			(at 0 2.54 180)
			(size 1.0033 1.0033)
			(drill 0.249936)
			(layers "*.Cu" "*.Mask")
			(remove_unused_layers no)
			(net "TDR_DIFF_85_TOP_DIN")
			(clearance 0.10795)
			(thermal_gap 0.10795)
			(padstack
				(mode front_inner_back)
				(layer "Inner"
					(shape circle)
					(size 0.8001 0.8001)
					(clearance 0.1524)
				)
				(layer "B.Cu"
					(shape circle)
					(size 1.0033 1.0033)
					(clearance 0.10795)
				)
			)
		)
	)
	(footprint ""
		(layer "F.Cu")
		(at 333.502 -205.232 -90)
		(property "Reference" "R4116"
			(at 0 0 270)
			(layer "F.SilkS")
			(hide yes)
			(effects
				(font
					(size 1.27 1.27)
				)
			)
		)
		(property "Value" ""
			(at 0 0 270)
			(layer "F.Fab")
			(effects
				(font
					(size 1.27 1.27)
				)
			)
		)
		(duplicate_pad_numbers_are_jumpers no)
		(fp_line
			(start -0.7874 0.4064)
			(end -0.7874 -0.4064)
			(stroke
				(width 0.1524)
				(type default)
			)
			(layer "F.SilkS")
		)
		(fp_line
			(start 0.7874 0.4064)
			(end -0.7874 0.4064)
			(stroke
				(width 0.1524)
				(type default)
			)
			(layer "F.SilkS")
		)
		(fp_line
			(start -0.7874 -0.4064)
			(end 0.7874 -0.4064)
			(stroke
				(width 0.1524)
				(type default)
			)
			(layer "F.SilkS")
		)
		(fp_line
			(start 0.7874 -0.4064)
			(end 0.7874 0.4064)
			(stroke
				(width 0.1524)
				(type default)
			)
			(layer "F.SilkS")
		)
		(fp_line
			(start -0.67945 0.3048)
			(end -0.67945 -0.305054)
			(stroke
				(width 0.1)
				(type default)
			)
			(layer "F.Fab")
		)
		(fp_line
			(start -0.12065 0.3048)
			(end -0.67945 0.3048)
			(stroke
				(width 0.1)
				(type default)
			)
			(layer "F.Fab")
		)
		(fp_line
			(start 0.120396 0.3048)
			(end 0.120396 0.2794)
			(stroke
				(width 0.1)
				(type default)
			)
			(layer "F.Fab")
		)
		(fp_line
			(start 0.67945 0.3048)
			(end 0.120396 0.3048)
			(stroke
				(width 0.1)
				(type default)
			)
			(layer "F.Fab")
		)
		(fp_line
			(start -0.12065 0.2794)
			(end -0.12065 0.3048)
			(stroke
				(width 0.1)
				(type default)
			)
			(layer "F.Fab")
		)
		(fp_line
			(start 0.120396 0.2794)
			(end -0.12065 0.2794)
			(stroke
				(width 0.1)
				(type default)
			)
			(layer "F.Fab")
		)
		(fp_line
			(start -0.12065 -0.2794)
			(end 0.12065 -0.2794)
			(stroke
				(width 0.1)
				(type default)
			)
			(layer "F.Fab")
		)
		(fp_line
			(start 0.12065 -0.2794)
			(end 0.12065 -0.3048)
			(stroke
				(width 0.1)
				(type default)
			)
			(layer "F.Fab")
		)
		(fp_line
			(start 0.12065 -0.3048)
			(end 0.67945 -0.3048)
			(stroke
				(width 0.1)
				(type default)
			)
			(layer "F.Fab")
		)
		(fp_line
			(start 0.67945 -0.3048)
			(end 0.67945 0.3048)
			(stroke
				(width 0.1)
				(type default)
			)
			(layer "F.Fab")
		)
		(fp_line
			(start -0.67945 -0.305054)
			(end -0.12065 -0.305054)
			(stroke
				(width 0.1)
				(type default)
			)
			(layer "F.Fab")
		)
		(fp_line
			(start -0.12065 -0.305054)
			(end -0.12065 -0.2794)
			(stroke
				(width 0.1)
				(type default)
			)
			(layer "F.Fab")
		)
		(pad "1" smd circle
			(at -0.40005 0 270)
			(size 0 0)
			(layers "F.Cu" "F.Mask" "F.Paste")
			(net "SSD8_PWRDIS")
		)
		(pad "2" smd circle
			(at 0.40005 0 270)
			(size 0 0)
			(layers "F.Cu" "F.Mask" "F.Paste")
			(net "SSD8_PWRDIS_R")
		)
	)
	(footprint ""
		(layer "F.Cu")
		(at 141.458442 -250.070874 -90)
		(property "Reference" "R1276"
			(at 0 0 270)
			(layer "F.SilkS")
			(hide yes)
			(effects
				(font
					(size 1.27 1.27)
				)
			)
		)
		(property "Value" ""
			(at 0 0 270)
			(layer "F.Fab")
			(effects
				(font
					(size 1.27 1.27)
				)
			)
		)
		(duplicate_pad_numbers_are_jumpers no)
		(fp_line
			(start -0.7874 0.4064)
			(end -0.7874 -0.4064)
			(stroke
				(width 0.1524)
				(type default)
			)
			(layer "F.SilkS")
		)
		(fp_line
			(start 0.7874 0.4064)
			(end -0.7874 0.4064)
			(stroke
				(width 0.1524)
				(type default)
			)
			(layer "F.SilkS")
		)
		(fp_line
			(start -0.7874 -0.4064)
			(end 0.7874 -0.4064)
			(stroke
				(width 0.1524)
				(type default)
			)
			(layer "F.SilkS")
		)
		(fp_line
			(start 0.7874 -0.4064)
			(end 0.7874 0.4064)
			(stroke
				(width 0.1524)
				(type default)
			)
			(layer "F.SilkS")
		)
		(fp_line
			(start -0.67945 0.3048)
			(end -0.67945 -0.305054)
			(stroke
				(width 0.1)
				(type default)
			)
			(layer "F.Fab")
		)
		(fp_line
			(start -0.12065 0.3048)
			(end -0.67945 0.3048)
			(stroke
				(width 0.1)
				(type default)
			)
			(layer "F.Fab")
		)
		(fp_line
			(start 0.120396 0.3048)
			(end 0.120396 0.2794)
			(stroke
				(width 0.1)
				(type default)
			)
			(layer "F.Fab")
		)
		(fp_line
			(start 0.67945 0.3048)
			(end 0.120396 0.3048)
			(stroke
				(width 0.1)
				(type default)
			)
			(layer "F.Fab")
		)
		(fp_line
			(start -0.12065 0.2794)
			(end -0.12065 0.3048)
			(stroke
				(width 0.1)
				(type default)
			)
			(layer "F.Fab")
		)
		(fp_line
			(start 0.120396 0.2794)
			(end -0.12065 0.2794)
			(stroke
				(width 0.1)
				(type default)
			)
			(layer "F.Fab")
		)
		(fp_line
			(start -0.12065 -0.2794)
			(end 0.12065 -0.2794)
			(stroke
				(width 0.1)
				(type default)
			)
			(layer "F.Fab")
		)
		(fp_line
			(start 0.12065 -0.2794)
			(end 0.12065 -0.3048)
			(stroke
				(width 0.1)
				(type default)
			)
			(layer "F.Fab")
		)
		(fp_line
			(start 0.12065 -0.3048)
			(end 0.67945 -0.3048)
			(stroke
				(width 0.1)
				(type default)
			)
			(layer "F.Fab")
		)
		(fp_line
			(start 0.67945 -0.3048)
			(end 0.67945 0.3048)
			(stroke
				(width 0.1)
				(type default)
			)
			(layer "F.Fab")
		)
		(fp_line
			(start -0.67945 -0.305054)
			(end -0.12065 -0.305054)
			(stroke
				(width 0.1)
				(type default)
			)
			(layer "F.Fab")
		)
		(fp_line
			(start -0.12065 -0.305054)
			(end -0.12065 -0.2794)
			(stroke
				(width 0.1)
				(type default)
			)
			(layer "F.Fab")
		)
		(pad "1" smd circle
			(at -0.40005 0 270)
			(size 0 0)
			(layers "F.Cu" "F.Mask" "F.Paste")
			(net "PEX1_MODE_SEL7")
		)
		(pad "2" smd circle
			(at 0.40005 0 270)
			(size 0 0)
			(layers "F.Cu" "F.Mask" "F.Paste")
			(net "P1V8_PEX")
		)
	)
	(footprint ""
		(layer "F.Cu")
		(at 80.000602 -343.952322 90)
		(property "Reference" "C145"
			(at 0 0 90)
			(layer "F.SilkS")
			(hide yes)
			(effects
				(font
					(size 1.27 1.27)
				)
			)
		)
		(property "Value" ""
			(at 0 0 90)
			(layer "F.Fab")
			(effects
				(font
					(size 1.27 1.27)
				)
			)
		)
		(duplicate_pad_numbers_are_jumpers no)
		(fp_line
			(start 0.299974 -0.150114)
			(end 0.299974 0.150114)
			(stroke
				(width 0.1)
				(type default)
			)
			(layer "F.Fab")
		)
		(fp_line
			(start -0.299974 -0.150114)
			(end 0.299974 -0.150114)
			(stroke
				(width 0.1)
				(type default)
			)
			(layer "F.Fab")
		)
		(fp_line
			(start 0.299974 0.150114)
			(end -0.299974 0.150114)
			(stroke
				(width 0.1)
				(type default)
			)
			(layer "F.Fab")
		)
		(fp_line
			(start -0.299974 0.150114)
			(end -0.299974 -0.150114)
			(stroke
				(width 0.1)
				(type default)
			)
			(layer "F.Fab")
		)
		(pad "1" smd rect
			(at -0.2667 0 90)
			(size 0.3048 0.381)
			(layers "F.Cu" "F.Mask" "F.Paste")
			(net "P5E_PEX0_STN6_TX_DP<103>")
		)
		(pad "2" smd rect
			(at 0.2667 0 90)
			(size 0.3048 0.381)
			(layers "F.Cu" "F.Mask" "F.Paste")
			(net "P5E_PEX0_STN6_TX_C_DP<103>")
		)
	)
	(footprint ""
		(layer "F.Cu")
		(at 142.947644 -390.171686 -90)
		(property "Reference" "R4105"
			(at 0 0 270)
			(layer "F.SilkS")
			(hide yes)
			(effects
				(font
					(size 1.27 1.27)
				)
			)
		)
		(property "Value" ""
			(at 0 0 270)
			(layer "F.Fab")
			(effects
				(font
					(size 1.27 1.27)
				)
			)
		)
		(duplicate_pad_numbers_are_jumpers no)
		(fp_line
			(start -0.7874 0.4064)
			(end -0.7874 -0.4064)
			(stroke
				(width 0.1524)
				(type default)
			)
			(layer "F.SilkS")
		)
		(fp_line
			(start 0.7874 0.4064)
			(end -0.7874 0.4064)
			(stroke
				(width 0.1524)
				(type default)
			)
			(layer "F.SilkS")
		)
		(fp_line
			(start -0.7874 -0.4064)
			(end 0.7874 -0.4064)
			(stroke
				(width 0.1524)
				(type default)
			)
			(layer "F.SilkS")
		)
		(fp_line
			(start 0.7874 -0.4064)
			(end 0.7874 0.4064)
			(stroke
				(width 0.1524)
				(type default)
			)
			(layer "F.SilkS")
		)
		(fp_line
			(start -0.67945 0.3048)
			(end -0.67945 -0.305054)
			(stroke
				(width 0.1)
				(type default)
			)
			(layer "F.Fab")
		)
		(fp_line
			(start -0.12065 0.3048)
			(end -0.67945 0.3048)
			(stroke
				(width 0.1)
				(type default)
			)
			(layer "F.Fab")
		)
		(fp_line
			(start 0.120396 0.3048)
			(end 0.120396 0.2794)
			(stroke
				(width 0.1)
				(type default)
			)
			(layer "F.Fab")
		)
		(fp_line
			(start 0.67945 0.3048)
			(end 0.120396 0.3048)
			(stroke
				(width 0.1)
				(type default)
			)
			(layer "F.Fab")
		)
		(fp_line
			(start -0.12065 0.2794)
			(end -0.12065 0.3048)
			(stroke
				(width 0.1)
				(type default)
			)
			(layer "F.Fab")
		)
		(fp_line
			(start 0.120396 0.2794)
			(end -0.12065 0.2794)
			(stroke
				(width 0.1)
				(type default)
			)
			(layer "F.Fab")
		)
		(fp_line
			(start -0.12065 -0.2794)
			(end 0.12065 -0.2794)
			(stroke
				(width 0.1)
				(type default)
			)
			(layer "F.Fab")
		)
		(fp_line
			(start 0.12065 -0.2794)
			(end 0.12065 -0.3048)
			(stroke
				(width 0.1)
				(type default)
			)
			(layer "F.Fab")
		)
		(fp_line
			(start 0.12065 -0.3048)
			(end 0.67945 -0.3048)
			(stroke
				(width 0.1)
				(type default)
			)
			(layer "F.Fab")
		)
		(fp_line
			(start 0.67945 -0.3048)
			(end 0.67945 0.3048)
			(stroke
				(width 0.1)
				(type default)
			)
			(layer "F.Fab")
		)
		(fp_line
			(start -0.67945 -0.305054)
			(end -0.12065 -0.305054)
			(stroke
				(width 0.1)
				(type default)
			)
			(layer "F.Fab")
		)
		(fp_line
			(start -0.12065 -0.305054)
			(end -0.12065 -0.2794)
			(stroke
				(width 0.1)
				(type default)
			)
			(layer "F.Fab")
		)
		(pad "1" smd circle
			(at -0.40005 0 270)
			(size 0 0)
			(layers "F.Cu" "F.Mask" "F.Paste")
			(net "SMB_MB_BMC_SCL")
		)
		(pad "2" smd circle
			(at 0.40005 0 270)
			(size 0 0)
			(layers "F.Cu" "F.Mask" "F.Paste")
			(net "SMB_MB_BMC_R_SCL")
		)
	)
	(footprint ""
		(layer "F.Cu")
		(at 223.586294 -174.49038 180)
		(property "Reference" "R3147"
			(at 0 0 180)
			(layer "F.SilkS")
			(hide yes)
			(effects
				(font
					(size 1.27 1.27)
				)
			)
		)
		(property "Value" ""
			(at 0 0 180)
			(layer "F.Fab")
			(effects
				(font
					(size 1.27 1.27)
				)
			)
		)
		(duplicate_pad_numbers_are_jumpers no)
		(fp_line
			(start 0.7874 0.4064)
			(end -0.7874 0.4064)
			(stroke
				(width 0.1524)
				(type default)
			)
			(layer "F.SilkS")
		)
		(fp_line
			(start 0.7874 -0.4064)
			(end 0.7874 0.4064)
			(stroke
				(width 0.1524)
				(type default)
			)
			(layer "F.SilkS")
		)
		(fp_line
			(start -0.7874 0.4064)
			(end -0.7874 -0.4064)
			(stroke
				(width 0.1524)
				(type default)
			)
			(layer "F.SilkS")
		)
		(fp_line
			(start -0.7874 -0.4064)
			(end 0.7874 -0.4064)
			(stroke
				(width 0.1524)
				(type default)
			)
			(layer "F.SilkS")
		)
		(fp_line
			(start 0.67945 0.3048)
			(end 0.120396 0.3048)
			(stroke
				(width 0.1)
				(type default)
			)
			(layer "F.Fab")
		)
		(fp_line
			(start 0.67945 -0.3048)
			(end 0.67945 0.3048)
			(stroke
				(width 0.1)
				(type default)
			)
			(layer "F.Fab")
		)
		(fp_line
			(start 0.12065 -0.2794)
			(end 0.12065 -0.3048)
			(stroke
				(width 0.1)
				(type default)
			)
			(layer "F.Fab")
		)
		(fp_line
			(start 0.12065 -0.3048)
			(end 0.67945 -0.3048)
			(stroke
				(width 0.1)
				(type default)
			)
			(layer "F.Fab")
		)
		(fp_line
			(start 0.120396 0.3048)
			(end 0.120396 0.2794)
			(stroke
				(width 0.1)
				(type default)
			)
			(layer "F.Fab")
		)
		(fp_line
			(start 0.120396 0.2794)
			(end -0.12065 0.2794)
			(stroke
				(width 0.1)
				(type default)
			)
			(layer "F.Fab")
		)
		(fp_line
			(start -0.12065 0.3048)
			(end -0.67945 0.3048)
			(stroke
				(width 0.1)
				(type default)
			)
			(layer "F.Fab")
		)
		(fp_line
			(start -0.12065 0.2794)
			(end -0.12065 0.3048)
			(stroke
				(width 0.1)
				(type default)
			)
			(layer "F.Fab")
		)
		(fp_line
			(start -0.12065 -0.2794)
			(end 0.12065 -0.2794)
			(stroke
				(width 0.1)
				(type default)
			)
			(layer "F.Fab")
		)
		(fp_line
			(start -0.12065 -0.305054)
			(end -0.12065 -0.2794)
			(stroke
				(width 0.1)
				(type default)
			)
			(layer "F.Fab")
		)
		(fp_line
			(start -0.67945 0.3048)
			(end -0.67945 -0.305054)
			(stroke
				(width 0.1)
				(type default)
			)
			(layer "F.Fab")
		)
		(fp_line
			(start -0.67945 -0.305054)
			(end -0.12065 -0.305054)
			(stroke
				(width 0.1)
				(type default)
			)
			(layer "F.Fab")
		)
		(pad "1" smd circle
			(at -0.40005 0 180)
			(size 0 0)
			(layers "F.Cu" "F.Mask" "F.Paste")
			(net "ADM1085_IN")
		)
		(pad "2" smd circle
			(at 0.40005 0 180)
			(size 0 0)
			(layers "F.Cu" "F.Mask" "F.Paste")
			(net "GND")
		)
	)
	(footprint ""
		(layer "F.Cu")
		(at 393.669266 -82.642202 180)
		(property "Reference" "R1770"
			(at 0 0 180)
			(layer "F.SilkS")
			(hide yes)
			(effects
				(font
					(size 1.27 1.27)
				)
			)
		)
		(property "Value" ""
			(at 0 0 180)
			(layer "F.Fab")
			(effects
				(font
					(size 1.27 1.27)
				)
			)
		)
		(duplicate_pad_numbers_are_jumpers no)
		(fp_line
			(start 0.7874 0.4064)
			(end -0.7874 0.4064)
			(stroke
				(width 0.1524)
				(type default)
			)
			(layer "F.SilkS")
		)
		(fp_line
			(start 0.7874 -0.4064)
			(end 0.7874 0.4064)
			(stroke
				(width 0.1524)
				(type default)
			)
			(layer "F.SilkS")
		)
		(fp_line
			(start -0.7874 0.4064)
			(end -0.7874 -0.4064)
			(stroke
				(width 0.1524)
				(type default)
			)
			(layer "F.SilkS")
		)
		(fp_line
			(start -0.7874 -0.4064)
			(end 0.7874 -0.4064)
			(stroke
				(width 0.1524)
				(type default)
			)
			(layer "F.SilkS")
		)
		(fp_line
			(start 0.67945 0.3048)
			(end 0.120396 0.3048)
			(stroke
				(width 0.1)
				(type default)
			)
			(layer "F.Fab")
		)
		(fp_line
			(start 0.67945 -0.3048)
			(end 0.67945 0.3048)
			(stroke
				(width 0.1)
				(type default)
			)
			(layer "F.Fab")
		)
		(fp_line
			(start 0.12065 -0.2794)
			(end 0.12065 -0.3048)
			(stroke
				(width 0.1)
				(type default)
			)
			(layer "F.Fab")
		)
		(fp_line
			(start 0.12065 -0.3048)
			(end 0.67945 -0.3048)
			(stroke
				(width 0.1)
				(type default)
			)
			(layer "F.Fab")
		)
		(fp_line
			(start 0.120396 0.3048)
			(end 0.120396 0.2794)
			(stroke
				(width 0.1)
				(type default)
			)
			(layer "F.Fab")
		)
		(fp_line
			(start 0.120396 0.2794)
			(end -0.12065 0.2794)
			(stroke
				(width 0.1)
				(type default)
			)
			(layer "F.Fab")
		)
		(fp_line
			(start -0.12065 0.3048)
			(end -0.67945 0.3048)
			(stroke
				(width 0.1)
				(type default)
			)
			(layer "F.Fab")
		)
		(fp_line
			(start -0.12065 0.2794)
			(end -0.12065 0.3048)
			(stroke
				(width 0.1)
				(type default)
			)
			(layer "F.Fab")
		)
		(fp_line
			(start -0.12065 -0.2794)
			(end 0.12065 -0.2794)
			(stroke
				(width 0.1)
				(type default)
			)
			(layer "F.Fab")
		)
		(fp_line
			(start -0.12065 -0.305054)
			(end -0.12065 -0.2794)
			(stroke
				(width 0.1)
				(type default)
			)
			(layer "F.Fab")
		)
		(fp_line
			(start -0.67945 0.3048)
			(end -0.67945 -0.305054)
			(stroke
				(width 0.1)
				(type default)
			)
			(layer "F.Fab")
		)
		(fp_line
			(start -0.67945 -0.305054)
			(end -0.12065 -0.305054)
			(stroke
				(width 0.1)
				(type default)
			)
			(layer "F.Fab")
		)
		(pad "1" smd circle
			(at -0.40005 0 180)
			(size 0 0)
			(layers "F.Cu" "F.Mask" "F.Paste")
			(net "SMB_BIC_I2C6_MUX_CLK_R_SDA")
		)
		(pad "2" smd circle
			(at 0.40005 0 180)
			(size 0 0)
			(layers "F.Cu" "F.Mask" "F.Paste")
			(net "SMB_BIC_I2C6_MUX_CLK_SDA")
		)
	)
	(footprint ""
		(layer "F.Cu")
		(at 355.81463 -303.698402 90)
		(property "Reference" "PC201"
			(at 0 0 90)
			(layer "F.SilkS")
			(hide yes)
			(effects
				(font
					(size 1.27 1.27)
				)
			)
		)
		(property "Value" ""
			(at 0 0 90)
			(layer "F.Fab")
			(effects
				(font
					(size 1.27 1.27)
				)
			)
		)
		(duplicate_pad_numbers_are_jumpers no)
		(fp_line
			(start -4.53898 -2.150618)
			(end -4.539742 2.152142)
			(stroke
				(width 0.1524)
				(type default)
			)
			(layer "F.SilkS")
		)
		(fp_line
			(start -4.69138 -2.150618)
			(end -4.692396 2.161032)
			(stroke
				(width 0.1524)
				(type default)
			)
			(layer "F.SilkS")
		)
		(fp_line
			(start -4.84378 -2.150618)
			(end -4.53898 -2.150618)
			(stroke
				(width 0.1524)
				(type default)
			)
			(layer "F.SilkS")
		)
		(fp_line
			(start -4.84378 -2.150618)
			(end -4.842256 2.163064)
			(stroke
				(width 0.1524)
				(type default)
			)
			(layer "F.SilkS")
		)
		(fp_line
			(start 4.53898 -2.15011)
			(end 4.53898 2.15011)
			(stroke
				(width 0.1524)
				(type default)
			)
			(layer "F.SilkS")
		)
		(fp_line
			(start -4.53898 -2.15011)
			(end 4.53898 -2.15011)
			(stroke
				(width 0.1524)
				(type default)
			)
			(layer "F.SilkS")
		)
		(fp_line
			(start 4.53898 2.15011)
			(end -4.53898 2.15011)
			(stroke
				(width 0.1524)
				(type default)
			)
			(layer "F.SilkS")
		)
		(fp_line
			(start -4.53898 2.15011)
			(end -4.53898 -2.15011)
			(stroke
				(width 0.1524)
				(type default)
			)
			(layer "F.SilkS")
		)
		(fp_line
			(start -4.83108 2.150364)
			(end -4.447794 2.149348)
			(stroke
				(width 0.1524)
				(type default)
			)
			(layer "F.SilkS")
		)
		(fp_line
			(start 3.64998 -2.15011)
			(end 3.64998 2.15011)
			(stroke
				(width 0.1)
				(type default)
			)
			(layer "F.Fab")
		)
		(fp_line
			(start -3.64998 -2.15011)
			(end 3.64998 -2.15011)
			(stroke
				(width 0.1)
				(type default)
			)
			(layer "F.Fab")
		)
		(fp_line
			(start 3.64998 2.15011)
			(end -3.64998 2.15011)
			(stroke
				(width 0.1)
				(type default)
			)
			(layer "F.Fab")
		)
		(fp_line
			(start -3.64998 2.15011)
			(end -3.64998 -2.15011)
			(stroke
				(width 0.1)
				(type default)
			)
			(layer "F.Fab")
		)
		(fp_text user "-"
			(at 2.737866 -3.438398 90)
			(unlocked yes)
			(layer "F.SilkS")
			(effects
				(font
					(size 1.905 1.4224)
					(thickness 0.1524)
				)
				(justify left)
			)
		)
		(fp_text user "+"
			(at -4.899406 2.707132 90)
			(unlocked yes)
			(layer "F.SilkS")
			(effects
				(font
					(size 1.905 1.4224)
					(thickness 0.1524)
				)
				(justify left)
			)
		)
		(fp_text user "+"
			(at -6.214872 -0.337058 90)
			(unlocked yes)
			(layer "F.Fab")
			(effects
				(font
					(size 1.905 1.4224)
					(thickness 0.1524)
				)
				(justify left)
			)
		)
		(fp_text user "-"
			(at 4.313174 -0.094488 90)
			(unlocked yes)
			(layer "F.Fab")
			(effects
				(font
					(size 1.905 1.4224)
					(thickness 0.1524)
				)
				(justify left)
			)
		)
		(pad "1" smd rect
			(at -3.199892 0 90)
			(size 2.413 2.8194)
			(layers "F.Cu" "F.Mask" "F.Paste")
			(net "P0V8_PEX3")
		)
		(pad "2" smd rect
			(at 3.199892 0 90)
			(size 2.413 2.8194)
			(layers "F.Cu" "F.Mask" "F.Paste")
			(net "GND")
		)
	)
	(footprint ""
		(layer "F.Cu")
		(at 127.280162 -167.752014 180)
		(property "Reference" "R6661"
			(at 0 0 180)
			(layer "F.SilkS")
			(hide yes)
			(effects
				(font
					(size 1.27 1.27)
				)
			)
		)
		(property "Value" ""
			(at 0 0 180)
			(layer "F.Fab")
			(effects
				(font
					(size 1.27 1.27)
				)
			)
		)
		(duplicate_pad_numbers_are_jumpers no)
		(fp_line
			(start 0.7874 0.4064)
			(end -0.7874 0.4064)
			(stroke
				(width 0.1524)
				(type default)
			)
			(layer "F.SilkS")
		)
		(fp_line
			(start 0.7874 -0.4064)
			(end 0.7874 0.4064)
			(stroke
				(width 0.1524)
				(type default)
			)
			(layer "F.SilkS")
		)
		(fp_line
			(start -0.7874 0.4064)
			(end -0.7874 -0.4064)
			(stroke
				(width 0.1524)
				(type default)
			)
			(layer "F.SilkS")
		)
		(fp_line
			(start -0.7874 -0.4064)
			(end 0.7874 -0.4064)
			(stroke
				(width 0.1524)
				(type default)
			)
			(layer "F.SilkS")
		)
		(fp_line
			(start 0.67945 0.3048)
			(end 0.120396 0.3048)
			(stroke
				(width 0.1)
				(type default)
			)
			(layer "F.Fab")
		)
		(fp_line
			(start 0.67945 -0.3048)
			(end 0.67945 0.3048)
			(stroke
				(width 0.1)
				(type default)
			)
			(layer "F.Fab")
		)
		(fp_line
			(start 0.12065 -0.2794)
			(end 0.12065 -0.3048)
			(stroke
				(width 0.1)
				(type default)
			)
			(layer "F.Fab")
		)
		(fp_line
			(start 0.12065 -0.3048)
			(end 0.67945 -0.3048)
			(stroke
				(width 0.1)
				(type default)
			)
			(layer "F.Fab")
		)
		(fp_line
			(start 0.120396 0.3048)
			(end 0.120396 0.2794)
			(stroke
				(width 0.1)
				(type default)
			)
			(layer "F.Fab")
		)
		(fp_line
			(start 0.120396 0.2794)
			(end -0.12065 0.2794)
			(stroke
				(width 0.1)
				(type default)
			)
			(layer "F.Fab")
		)
		(fp_line
			(start -0.12065 0.3048)
			(end -0.67945 0.3048)
			(stroke
				(width 0.1)
				(type default)
			)
			(layer "F.Fab")
		)
		(fp_line
			(start -0.12065 0.2794)
			(end -0.12065 0.3048)
			(stroke
				(width 0.1)
				(type default)
			)
			(layer "F.Fab")
		)
		(fp_line
			(start -0.12065 -0.2794)
			(end 0.12065 -0.2794)
			(stroke
				(width 0.1)
				(type default)
			)
			(layer "F.Fab")
		)
		(fp_line
			(start -0.12065 -0.305054)
			(end -0.12065 -0.2794)
			(stroke
				(width 0.1)
				(type default)
			)
			(layer "F.Fab")
		)
		(fp_line
			(start -0.67945 0.3048)
			(end -0.67945 -0.305054)
			(stroke
				(width 0.1)
				(type default)
			)
			(layer "F.Fab")
		)
		(fp_line
			(start -0.67945 -0.305054)
			(end -0.12065 -0.305054)
			(stroke
				(width 0.1)
				(type default)
			)
			(layer "F.Fab")
		)
		(pad "1" smd circle
			(at -0.40005 0 180)
			(size 0 0)
			(layers "F.Cu" "F.Mask" "F.Paste")
			(net "NIC0_CLK_EN_BUF_N")
		)
		(pad "2" smd circle
			(at 0.40005 0 180)
			(size 0 0)
			(layers "F.Cu" "F.Mask" "F.Paste")
			(net "NIC0_CLK_EN_BUF_R_N")
		)
	)
	(footprint ""
		(layer "F.Cu")
		(at 7.771892 -24.807418)
		(property "Reference" "R410"
			(at 0 0 0)
			(layer "F.SilkS")
			(hide yes)
			(effects
				(font
					(size 1.27 1.27)
				)
			)
		)
		(property "Value" ""
			(at 0 0 0)
			(layer "F.Fab")
			(effects
				(font
					(size 1.27 1.27)
				)
			)
		)
		(duplicate_pad_numbers_are_jumpers no)
		(fp_line
			(start -0.7874 -0.4064)
			(end 0.7874 -0.4064)
			(stroke
				(width 0.1524)
				(type default)
			)
			(layer "F.SilkS")
		)
		(fp_line
			(start -0.7874 0.4064)
			(end -0.7874 -0.4064)
			(stroke
				(width 0.1524)
				(type default)
			)
			(layer "F.SilkS")
		)
		(fp_line
			(start 0.7874 -0.4064)
			(end 0.7874 0.4064)
			(stroke
				(width 0.1524)
				(type default)
			)
			(layer "F.SilkS")
		)
		(fp_line
			(start 0.7874 0.4064)
			(end -0.7874 0.4064)
			(stroke
				(width 0.1524)
				(type default)
			)
			(layer "F.SilkS")
		)
		(fp_line
			(start -0.67945 -0.305054)
			(end -0.12065 -0.305054)
			(stroke
				(width 0.1)
				(type default)
			)
			(layer "F.Fab")
		)
		(fp_line
			(start -0.67945 0.3048)
			(end -0.67945 -0.305054)
			(stroke
				(width 0.1)
				(type default)
			)
			(layer "F.Fab")
		)
		(fp_line
			(start -0.12065 -0.305054)
			(end -0.12065 -0.2794)
			(stroke
				(width 0.1)
				(type default)
			)
			(layer "F.Fab")
		)
		(fp_line
			(start -0.12065 -0.2794)
			(end 0.12065 -0.2794)
			(stroke
				(width 0.1)
				(type default)
			)
			(layer "F.Fab")
		)
		(fp_line
			(start -0.12065 0.2794)
			(end -0.12065 0.3048)
			(stroke
				(width 0.1)
				(type default)
			)
			(layer "F.Fab")
		)
		(fp_line
			(start -0.12065 0.3048)
			(end -0.67945 0.3048)
			(stroke
				(width 0.1)
				(type default)
			)
			(layer "F.Fab")
		)
		(fp_line
			(start 0.120396 0.2794)
			(end -0.12065 0.2794)
			(stroke
				(width 0.1)
				(type default)
			)
			(layer "F.Fab")
		)
		(fp_line
			(start 0.120396 0.3048)
			(end 0.120396 0.2794)
			(stroke
				(width 0.1)
				(type default)
			)
			(layer "F.Fab")
		)
		(fp_line
			(start 0.12065 -0.3048)
			(end 0.67945 -0.3048)
			(stroke
				(width 0.1)
				(type default)
			)
			(layer "F.Fab")
		)
		(fp_line
			(start 0.12065 -0.2794)
			(end 0.12065 -0.3048)
			(stroke
				(width 0.1)
				(type default)
			)
			(layer "F.Fab")
		)
		(fp_line
			(start 0.67945 -0.3048)
			(end 0.67945 0.3048)
			(stroke
				(width 0.1)
				(type default)
			)
			(layer "F.Fab")
		)
		(fp_line
			(start 0.67945 0.3048)
			(end 0.120396 0.3048)
			(stroke
				(width 0.1)
				(type default)
			)
			(layer "F.Fab")
		)
		(pad "1" smd circle
			(at -0.40005 0)
			(size 0 0)
			(layers "F.Cu" "F.Mask" "F.Paste")
			(net "P3V3_SSD0")
		)
		(pad "2" smd circle
			(at 0.40005 0)
			(size 0 0)
			(layers "F.Cu" "F.Mask" "F.Paste")
			(net "PU_CLKREQ0")
		)
	)
	(footprint ""
		(layer "F.Cu")
		(at 30.153356 -297.791632)
		(property "Reference" "L88"
			(at 0 0 0)
			(layer "F.SilkS")
			(hide yes)
			(effects
				(font
					(size 1.27 1.27)
				)
			)
		)
		(property "Value" ""
			(at 0 0 0)
			(layer "F.Fab")
			(effects
				(font
					(size 1.27 1.27)
				)
			)
		)
		(duplicate_pad_numbers_are_jumpers no)
		(fp_line
			(start -1.63576 -0.8128)
			(end -1.63576 0.8128)
			(stroke
				(width 0.1524)
				(type default)
			)
			(layer "F.SilkS")
		)
		(fp_line
			(start -1.63576 -0.8128)
			(end 1.63576 -0.8128)
			(stroke
				(width 0.1524)
				(type default)
			)
			(layer "F.SilkS")
		)
		(fp_line
			(start 1.63576 -0.8128)
			(end 1.63576 0.8128)
			(stroke
				(width 0.1524)
				(type default)
			)
			(layer "F.SilkS")
		)
		(fp_line
			(start 1.63576 0.8128)
			(end -1.63576 0.8128)
			(stroke
				(width 0.1524)
				(type default)
			)
			(layer "F.SilkS")
		)
		(fp_line
			(start -1.56083 -0.738632)
			(end -1.56083 0.7366)
			(stroke
				(width 0.1)
				(type default)
			)
			(layer "F.Fab")
		)
		(fp_line
			(start -1.56083 0.7366)
			(end -1.524 0.7366)
			(stroke
				(width 0.1)
				(type default)
			)
			(layer "F.Fab")
		)
		(fp_line
			(start -1.524 0.7366)
			(end 1.524 0.7366)
			(stroke
				(width 0.1)
				(type default)
			)
			(layer "F.Fab")
		)
		(fp_line
			(start 1.524 0.7366)
			(end 1.560576 0.7366)
			(stroke
				(width 0.1)
				(type default)
			)
			(layer "F.Fab")
		)
		(fp_line
			(start 1.560576 -0.738632)
			(end -1.56083 -0.738632)
			(stroke
				(width 0.1)
				(type default)
			)
			(layer "F.Fab")
		)
		(fp_line
			(start 1.560576 0.7366)
			(end 1.560576 -0.738632)
			(stroke
				(width 0.1)
				(type default)
			)
			(layer "F.Fab")
		)
		(pad "1" smd rect
			(at -0.94996 0 180)
			(size 1.1176 1.3716)
			(layers "F.Cu" "F.Mask" "F.Paste")
			(net "P1V8_PLL0_PEX0")
		)
		(pad "2" smd rect
			(at 0.94996 0 180)
			(size 1.1176 1.3716)
			(layers "F.Cu" "F.Mask" "F.Paste")
			(net "PCEPLL0_VDDA18_PEX0")
		)
	)
	(footprint ""
		(layer "F.Cu")
		(at 227.562664 -207.02016 -90)
		(property "Reference" "R5292"
			(at 0 0 270)
			(layer "F.SilkS")
			(hide yes)
			(effects
				(font
					(size 1.27 1.27)
				)
			)
		)
		(property "Value" ""
			(at 0 0 270)
			(layer "F.Fab")
			(effects
				(font
					(size 1.27 1.27)
				)
			)
		)
		(duplicate_pad_numbers_are_jumpers no)
		(fp_line
			(start -0.7874 0.4064)
			(end -0.7874 -0.4064)
			(stroke
				(width 0.1524)
				(type default)
			)
			(layer "F.SilkS")
		)
		(fp_line
			(start 0.7874 0.4064)
			(end -0.7874 0.4064)
			(stroke
				(width 0.1524)
				(type default)
			)
			(layer "F.SilkS")
		)
		(fp_line
			(start -0.7874 -0.4064)
			(end 0.7874 -0.4064)
			(stroke
				(width 0.1524)
				(type default)
			)
			(layer "F.SilkS")
		)
		(fp_line
			(start 0.7874 -0.4064)
			(end 0.7874 0.4064)
			(stroke
				(width 0.1524)
				(type default)
			)
			(layer "F.SilkS")
		)
		(fp_line
			(start -0.67945 0.3048)
			(end -0.67945 -0.305054)
			(stroke
				(width 0.1)
				(type default)
			)
			(layer "F.Fab")
		)
		(fp_line
			(start -0.12065 0.3048)
			(end -0.67945 0.3048)
			(stroke
				(width 0.1)
				(type default)
			)
			(layer "F.Fab")
		)
		(fp_line
			(start 0.120396 0.3048)
			(end 0.120396 0.2794)
			(stroke
				(width 0.1)
				(type default)
			)
			(layer "F.Fab")
		)
		(fp_line
			(start 0.67945 0.3048)
			(end 0.120396 0.3048)
			(stroke
				(width 0.1)
				(type default)
			)
			(layer "F.Fab")
		)
		(fp_line
			(start -0.12065 0.2794)
			(end -0.12065 0.3048)
			(stroke
				(width 0.1)
				(type default)
			)
			(layer "F.Fab")
		)
		(fp_line
			(start 0.120396 0.2794)
			(end -0.12065 0.2794)
			(stroke
				(width 0.1)
				(type default)
			)
			(layer "F.Fab")
		)
		(fp_line
			(start -0.12065 -0.2794)
			(end 0.12065 -0.2794)
			(stroke
				(width 0.1)
				(type default)
			)
			(layer "F.Fab")
		)
		(fp_line
			(start 0.12065 -0.2794)
			(end 0.12065 -0.3048)
			(stroke
				(width 0.1)
				(type default)
			)
			(layer "F.Fab")
		)
		(fp_line
			(start 0.12065 -0.3048)
			(end 0.67945 -0.3048)
			(stroke
				(width 0.1)
				(type default)
			)
			(layer "F.Fab")
		)
		(fp_line
			(start 0.67945 -0.3048)
			(end 0.67945 0.3048)
			(stroke
				(width 0.1)
				(type default)
			)
			(layer "F.Fab")
		)
		(fp_line
			(start -0.67945 -0.305054)
			(end -0.12065 -0.305054)
			(stroke
				(width 0.1)
				(type default)
			)
			(layer "F.Fab")
		)
		(fp_line
			(start -0.12065 -0.305054)
			(end -0.12065 -0.2794)
			(stroke
				(width 0.1)
				(type default)
			)
			(layer "F.Fab")
		)
		(pad "1" smd circle
			(at -0.40005 0 270)
			(size 0 0)
			(layers "F.Cu" "F.Mask" "F.Paste")
			(net "BIC_SYS_READY_N")
		)
		(pad "2" smd circle
			(at 0.40005 0 270)
			(size 0 0)
			(layers "F.Cu" "F.Mask" "F.Paste")
			(net "BIC_SYS_READY_R_N")
		)
	)
	(footprint ""
		(layer "F.Cu")
		(at 311.662318 -22.937216 90)
		(property "Reference" "R1711"
			(at 0 0 90)
			(layer "F.SilkS")
			(hide yes)
			(effects
				(font
					(size 1.27 1.27)
				)
			)
		)
		(property "Value" ""
			(at 0 0 90)
			(layer "F.Fab")
			(effects
				(font
					(size 1.27 1.27)
				)
			)
		)
		(duplicate_pad_numbers_are_jumpers no)
		(fp_line
			(start 0.7874 -0.4064)
			(end 0.7874 0.4064)
			(stroke
				(width 0.1524)
				(type default)
			)
			(layer "F.SilkS")
		)
		(fp_line
			(start -0.7874 -0.4064)
			(end 0.7874 -0.4064)
			(stroke
				(width 0.1524)
				(type default)
			)
			(layer "F.SilkS")
		)
		(fp_line
			(start 0.7874 0.4064)
			(end -0.7874 0.4064)
			(stroke
				(width 0.1524)
				(type default)
			)
			(layer "F.SilkS")
		)
		(fp_line
			(start -0.7874 0.4064)
			(end -0.7874 -0.4064)
			(stroke
				(width 0.1524)
				(type default)
			)
			(layer "F.SilkS")
		)
		(fp_line
			(start -0.12065 -0.305054)
			(end -0.12065 -0.2794)
			(stroke
				(width 0.1)
				(type default)
			)
			(layer "F.Fab")
		)
		(fp_line
			(start -0.67945 -0.305054)
			(end -0.12065 -0.305054)
			(stroke
				(width 0.1)
				(type default)
			)
			(layer "F.Fab")
		)
		(fp_line
			(start 0.67945 -0.3048)
			(end 0.67945 0.3048)
			(stroke
				(width 0.1)
				(type default)
			)
			(layer "F.Fab")
		)
		(fp_line
			(start 0.12065 -0.3048)
			(end 0.67945 -0.3048)
			(stroke
				(width 0.1)
				(type default)
			)
			(layer "F.Fab")
		)
		(fp_line
			(start 0.12065 -0.2794)
			(end 0.12065 -0.3048)
			(stroke
				(width 0.1)
				(type default)
			)
			(layer "F.Fab")
		)
		(fp_line
			(start -0.12065 -0.2794)
			(end 0.12065 -0.2794)
			(stroke
				(width 0.1)
				(type default)
			)
			(layer "F.Fab")
		)
		(fp_line
			(start 0.120396 0.2794)
			(end -0.12065 0.2794)
			(stroke
				(width 0.1)
				(type default)
			)
			(layer "F.Fab")
		)
		(fp_line
			(start -0.12065 0.2794)
			(end -0.12065 0.3048)
			(stroke
				(width 0.1)
				(type default)
			)
			(layer "F.Fab")
		)
		(fp_line
			(start 0.67945 0.3048)
			(end 0.120396 0.3048)
			(stroke
				(width 0.1)
				(type default)
			)
			(layer "F.Fab")
		)
		(fp_line
			(start 0.120396 0.3048)
			(end 0.120396 0.2794)
			(stroke
				(width 0.1)
				(type default)
			)
			(layer "F.Fab")
		)
		(fp_line
			(start -0.12065 0.3048)
			(end -0.67945 0.3048)
			(stroke
				(width 0.1)
				(type default)
			)
			(layer "F.Fab")
		)
		(fp_line
			(start -0.67945 0.3048)
			(end -0.67945 -0.305054)
			(stroke
				(width 0.1)
				(type default)
			)
			(layer "F.Fab")
		)
		(pad "1" smd circle
			(at -0.40005 0 90)
			(size 0 0)
			(layers "F.Cu" "F.Mask" "F.Paste")
			(net "SMB_BIC_I2C9_MUX1_SSD10_R_SDA")
		)
		(pad "2" smd circle
			(at 0.40005 0 90)
			(size 0 0)
			(layers "F.Cu" "F.Mask" "F.Paste")
			(net "SMB_ISO_SSD10_SDA")
		)
	)
	(footprint ""
		(layer "F.Cu")
		(at 127.381508 -356.244906 90)
		(property "Reference" "C2273"
			(at 0 0 90)
			(layer "F.SilkS")
			(hide yes)
			(effects
				(font
					(size 1.27 1.27)
				)
			)
		)
		(property "Value" ""
			(at 0 0 90)
			(layer "F.Fab")
			(effects
				(font
					(size 1.27 1.27)
				)
			)
		)
		(duplicate_pad_numbers_are_jumpers no)
		(fp_line
			(start 0.299974 -0.150114)
			(end 0.299974 0.150114)
			(stroke
				(width 0.1)
				(type default)
			)
			(layer "F.Fab")
		)
		(fp_line
			(start -0.299974 -0.150114)
			(end 0.299974 -0.150114)
			(stroke
				(width 0.1)
				(type default)
			)
			(layer "F.Fab")
		)
		(fp_line
			(start 0.299974 0.150114)
			(end -0.299974 0.150114)
			(stroke
				(width 0.1)
				(type default)
			)
			(layer "F.Fab")
		)
		(fp_line
			(start -0.299974 0.150114)
			(end -0.299974 -0.150114)
			(stroke
				(width 0.1)
				(type default)
			)
			(layer "F.Fab")
		)
		(pad "1" smd rect
			(at -0.2667 0 90)
			(size 0.3048 0.381)
			(layers "F.Cu" "F.Mask" "F.Paste")
			(net "P5E_PEX1_STN5_TX_DP<80>")
		)
		(pad "2" smd rect
			(at 0.2667 0 90)
			(size 0.3048 0.381)
			(layers "F.Cu" "F.Mask" "F.Paste")
			(net "P5E_PEX1_STN5_TX_C_DP<80>")
		)
	)
	(footprint ""
		(layer "F.Cu")
		(at 198.76135 -147.99691 180)
		(property "Reference" "C221"
			(at 0 0 180)
			(layer "F.SilkS")
			(hide yes)
			(effects
				(font
					(size 1.27 1.27)
				)
			)
		)
		(property "Value" ""
			(at 0 0 180)
			(layer "F.Fab")
			(effects
				(font
					(size 1.27 1.27)
				)
			)
		)
		(duplicate_pad_numbers_are_jumpers no)
		(fp_line
			(start 0.299974 0.150114)
			(end -0.299974 0.150114)
			(stroke
				(width 0.1)
				(type default)
			)
			(layer "F.Fab")
		)
		(fp_line
			(start 0.299974 -0.150114)
			(end 0.299974 0.150114)
			(stroke
				(width 0.1)
				(type default)
			)
			(layer "F.Fab")
		)
		(fp_line
			(start -0.299974 0.150114)
			(end -0.299974 -0.150114)
			(stroke
				(width 0.1)
				(type default)
			)
			(layer "F.Fab")
		)
		(fp_line
			(start -0.299974 -0.150114)
			(end 0.299974 -0.150114)
			(stroke
				(width 0.1)
				(type default)
			)
			(layer "F.Fab")
		)
		(pad "1" smd rect
			(at -0.2667 0 180)
			(size 0.3048 0.381)
			(layers "F.Cu" "F.Mask" "F.Paste")
			(net "P5E_PEX1_STN0_TX_DN<11>")
		)
		(pad "2" smd rect
			(at 0.2667 0 180)
			(size 0.3048 0.381)
			(layers "F.Cu" "F.Mask" "F.Paste")
			(net "P5E_PEX1_STN0_TX_C_DN<11>")
		)
	)
	(footprint ""
		(layer "F.Cu")
		(at 292.73119 -195.362068 90)
		(property "Reference" "R3369"
			(at 0 0 90)
			(layer "F.SilkS")
			(hide yes)
			(effects
				(font
					(size 1.27 1.27)
				)
			)
		)
		(property "Value" ""
			(at 0 0 90)
			(layer "F.Fab")
			(effects
				(font
					(size 1.27 1.27)
				)
			)
		)
		(duplicate_pad_numbers_are_jumpers no)
		(fp_line
			(start 0.7874 -0.4064)
			(end 0.7874 0.4064)
			(stroke
				(width 0.1524)
				(type default)
			)
			(layer "F.SilkS")
		)
		(fp_line
			(start -0.7874 -0.4064)
			(end 0.7874 -0.4064)
			(stroke
				(width 0.1524)
				(type default)
			)
			(layer "F.SilkS")
		)
		(fp_line
			(start 0.7874 0.4064)
			(end -0.7874 0.4064)
			(stroke
				(width 0.1524)
				(type default)
			)
			(layer "F.SilkS")
		)
		(fp_line
			(start -0.7874 0.4064)
			(end -0.7874 -0.4064)
			(stroke
				(width 0.1524)
				(type default)
			)
			(layer "F.SilkS")
		)
		(fp_line
			(start -0.12065 -0.305054)
			(end -0.12065 -0.2794)
			(stroke
				(width 0.1)
				(type default)
			)
			(layer "F.Fab")
		)
		(fp_line
			(start -0.67945 -0.305054)
			(end -0.12065 -0.305054)
			(stroke
				(width 0.1)
				(type default)
			)
			(layer "F.Fab")
		)
		(fp_line
			(start 0.67945 -0.3048)
			(end 0.67945 0.3048)
			(stroke
				(width 0.1)
				(type default)
			)
			(layer "F.Fab")
		)
		(fp_line
			(start 0.12065 -0.3048)
			(end 0.67945 -0.3048)
			(stroke
				(width 0.1)
				(type default)
			)
			(layer "F.Fab")
		)
		(fp_line
			(start 0.12065 -0.2794)
			(end 0.12065 -0.3048)
			(stroke
				(width 0.1)
				(type default)
			)
			(layer "F.Fab")
		)
		(fp_line
			(start -0.12065 -0.2794)
			(end 0.12065 -0.2794)
			(stroke
				(width 0.1)
				(type default)
			)
			(layer "F.Fab")
		)
		(fp_line
			(start 0.120396 0.2794)
			(end -0.12065 0.2794)
			(stroke
				(width 0.1)
				(type default)
			)
			(layer "F.Fab")
		)
		(fp_line
			(start -0.12065 0.2794)
			(end -0.12065 0.3048)
			(stroke
				(width 0.1)
				(type default)
			)
			(layer "F.Fab")
		)
		(fp_line
			(start 0.67945 0.3048)
			(end 0.120396 0.3048)
			(stroke
				(width 0.1)
				(type default)
			)
			(layer "F.Fab")
		)
		(fp_line
			(start 0.120396 0.3048)
			(end 0.120396 0.2794)
			(stroke
				(width 0.1)
				(type default)
			)
			(layer "F.Fab")
		)
		(fp_line
			(start -0.12065 0.3048)
			(end -0.67945 0.3048)
			(stroke
				(width 0.1)
				(type default)
			)
			(layer "F.Fab")
		)
		(fp_line
			(start -0.67945 0.3048)
			(end -0.67945 -0.305054)
			(stroke
				(width 0.1)
				(type default)
			)
			(layer "F.Fab")
		)
		(pad "1" smd circle
			(at -0.40005 0 90)
			(size 0 0)
			(layers "F.Cu" "F.Mask" "F.Paste")
			(net "SPI_BIC1_LS23_EN_N")
		)
		(pad "2" smd circle
			(at 0.40005 0 90)
			(size 0 0)
			(layers "F.Cu" "F.Mask" "F.Paste")
			(net "SPI_BIC1_LS23_EN_R_N")
		)
	)
	(footprint ""
		(layer "F.Cu")
		(at 349.05061 -279.486868 -90)
		(property "Reference" "PC166"
			(at 0 0 270)
			(layer "F.SilkS")
			(hide yes)
			(effects
				(font
					(size 1.27 1.27)
				)
			)
		)
		(property "Value" ""
			(at 0 0 270)
			(layer "F.Fab")
			(effects
				(font
					(size 1.27 1.27)
				)
			)
		)
		(duplicate_pad_numbers_are_jumpers no)
		(fp_line
			(start -0.7874 0.4064)
			(end -0.7874 -0.4064)
			(stroke
				(width 0.1524)
				(type default)
			)
			(layer "F.SilkS")
		)
		(fp_line
			(start 0.7874 0.4064)
			(end -0.7874 0.4064)
			(stroke
				(width 0.1524)
				(type default)
			)
			(layer "F.SilkS")
		)
		(fp_line
			(start -0.7874 -0.4064)
			(end 0.7874 -0.4064)
			(stroke
				(width 0.1524)
				(type default)
			)
			(layer "F.SilkS")
		)
		(fp_line
			(start 0.7874 -0.4064)
			(end 0.7874 0.4064)
			(stroke
				(width 0.1524)
				(type default)
			)
			(layer "F.SilkS")
		)
		(fp_line
			(start -0.67945 0.3048)
			(end -0.67945 -0.305054)
			(stroke
				(width 0.1)
				(type default)
			)
			(layer "F.Fab")
		)
		(fp_line
			(start -0.12065 0.3048)
			(end -0.67945 0.3048)
			(stroke
				(width 0.1)
				(type default)
			)
			(layer "F.Fab")
		)
		(fp_line
			(start 0.120396 0.3048)
			(end 0.120396 0.2794)
			(stroke
				(width 0.1)
				(type default)
			)
			(layer "F.Fab")
		)
		(fp_line
			(start 0.67945 0.3048)
			(end 0.120396 0.3048)
			(stroke
				(width 0.1)
				(type default)
			)
			(layer "F.Fab")
		)
		(fp_line
			(start -0.12065 0.2794)
			(end -0.12065 0.3048)
			(stroke
				(width 0.1)
				(type default)
			)
			(layer "F.Fab")
		)
		(fp_line
			(start 0.120396 0.2794)
			(end -0.12065 0.2794)
			(stroke
				(width 0.1)
				(type default)
			)
			(layer "F.Fab")
		)
		(fp_line
			(start -0.12065 -0.2794)
			(end 0.12065 -0.2794)
			(stroke
				(width 0.1)
				(type default)
			)
			(layer "F.Fab")
		)
		(fp_line
			(start 0.12065 -0.2794)
			(end 0.12065 -0.3048)
			(stroke
				(width 0.1)
				(type default)
			)
			(layer "F.Fab")
		)
		(fp_line
			(start 0.12065 -0.3048)
			(end 0.67945 -0.3048)
			(stroke
				(width 0.1)
				(type default)
			)
			(layer "F.Fab")
		)
		(fp_line
			(start 0.67945 -0.3048)
			(end 0.67945 0.3048)
			(stroke
				(width 0.1)
				(type default)
			)
			(layer "F.Fab")
		)
		(fp_line
			(start -0.67945 -0.305054)
			(end -0.12065 -0.305054)
			(stroke
				(width 0.1)
				(type default)
			)
			(layer "F.Fab")
		)
		(fp_line
			(start -0.12065 -0.305054)
			(end -0.12065 -0.2794)
			(stroke
				(width 0.1)
				(type default)
			)
			(layer "F.Fab")
		)
		(pad "1" smd circle
			(at -0.40005 0 270)
			(size 0 0)
			(layers "F.Cu" "F.Mask" "F.Paste")
			(net "P0V8_PEX2_VREF")
		)
		(pad "2" smd circle
			(at 0.40005 0 270)
			(size 0 0)
			(layers "F.Cu" "F.Mask" "F.Paste")
			(net "GND")
		)
	)
	(footprint ""
		(layer "F.Cu")
		(at 387.882384 -252.356874 -90)
		(property "Reference" "R3965"
			(at 0 0 270)
			(layer "F.SilkS")
			(hide yes)
			(effects
				(font
					(size 1.27 1.27)
				)
			)
		)
		(property "Value" ""
			(at 0 0 270)
			(layer "F.Fab")
			(effects
				(font
					(size 1.27 1.27)
				)
			)
		)
		(duplicate_pad_numbers_are_jumpers no)
		(fp_line
			(start -0.7874 0.4064)
			(end -0.7874 -0.4064)
			(stroke
				(width 0.1524)
				(type default)
			)
			(layer "F.SilkS")
		)
		(fp_line
			(start 0.7874 0.4064)
			(end -0.7874 0.4064)
			(stroke
				(width 0.1524)
				(type default)
			)
			(layer "F.SilkS")
		)
		(fp_line
			(start -0.7874 -0.4064)
			(end 0.7874 -0.4064)
			(stroke
				(width 0.1524)
				(type default)
			)
			(layer "F.SilkS")
		)
		(fp_line
			(start 0.7874 -0.4064)
			(end 0.7874 0.4064)
			(stroke
				(width 0.1524)
				(type default)
			)
			(layer "F.SilkS")
		)
		(fp_line
			(start -0.67945 0.3048)
			(end -0.67945 -0.305054)
			(stroke
				(width 0.1)
				(type default)
			)
			(layer "F.Fab")
		)
		(fp_line
			(start -0.12065 0.3048)
			(end -0.67945 0.3048)
			(stroke
				(width 0.1)
				(type default)
			)
			(layer "F.Fab")
		)
		(fp_line
			(start 0.120396 0.3048)
			(end 0.120396 0.2794)
			(stroke
				(width 0.1)
				(type default)
			)
			(layer "F.Fab")
		)
		(fp_line
			(start 0.67945 0.3048)
			(end 0.120396 0.3048)
			(stroke
				(width 0.1)
				(type default)
			)
			(layer "F.Fab")
		)
		(fp_line
			(start -0.12065 0.2794)
			(end -0.12065 0.3048)
			(stroke
				(width 0.1)
				(type default)
			)
			(layer "F.Fab")
		)
		(fp_line
			(start 0.120396 0.2794)
			(end -0.12065 0.2794)
			(stroke
				(width 0.1)
				(type default)
			)
			(layer "F.Fab")
		)
		(fp_line
			(start -0.12065 -0.2794)
			(end 0.12065 -0.2794)
			(stroke
				(width 0.1)
				(type default)
			)
			(layer "F.Fab")
		)
		(fp_line
			(start 0.12065 -0.2794)
			(end 0.12065 -0.3048)
			(stroke
				(width 0.1)
				(type default)
			)
			(layer "F.Fab")
		)
		(fp_line
			(start 0.12065 -0.3048)
			(end 0.67945 -0.3048)
			(stroke
				(width 0.1)
				(type default)
			)
			(layer "F.Fab")
		)
		(fp_line
			(start 0.67945 -0.3048)
			(end 0.67945 0.3048)
			(stroke
				(width 0.1)
				(type default)
			)
			(layer "F.Fab")
		)
		(fp_line
			(start -0.67945 -0.305054)
			(end -0.12065 -0.305054)
			(stroke
				(width 0.1)
				(type default)
			)
			(layer "F.Fab")
		)
		(fp_line
			(start -0.12065 -0.305054)
			(end -0.12065 -0.2794)
			(stroke
				(width 0.1)
				(type default)
			)
			(layer "F.Fab")
		)
		(pad "1" smd circle
			(at -0.40005 0 270)
			(size 0 0)
			(layers "F.Cu" "F.Mask" "F.Paste")
			(net "PEX3_PCA9555_INT_R_N")
		)
		(pad "2" smd circle
			(at 0.40005 0 270)
			(size 0 0)
			(layers "F.Cu" "F.Mask" "F.Paste")
			(net "P1V8_PEX")
		)
	)
	(footprint ""
		(layer "F.Cu")
		(at 83.034124 -2.998724)
		(property "Reference" "R5813"
			(at 0 0 0)
			(layer "F.SilkS")
			(hide yes)
			(effects
				(font
					(size 1.27 1.27)
				)
			)
		)
		(property "Value" ""
			(at 0 0 0)
			(layer "F.Fab")
			(effects
				(font
					(size 1.27 1.27)
				)
			)
		)
		(duplicate_pad_numbers_are_jumpers no)
		(fp_line
			(start -0.7874 -0.4064)
			(end 0.7874 -0.4064)
			(stroke
				(width 0.1524)
				(type default)
			)
			(layer "F.SilkS")
		)
		(fp_line
			(start -0.7874 0.4064)
			(end -0.7874 -0.4064)
			(stroke
				(width 0.1524)
				(type default)
			)
			(layer "F.SilkS")
		)
		(fp_line
			(start 0.7874 -0.4064)
			(end 0.7874 0.4064)
			(stroke
				(width 0.1524)
				(type default)
			)
			(layer "F.SilkS")
		)
		(fp_line
			(start 0.7874 0.4064)
			(end -0.7874 0.4064)
			(stroke
				(width 0.1524)
				(type default)
			)
			(layer "F.SilkS")
		)
		(fp_line
			(start -0.67945 -0.305054)
			(end -0.12065 -0.305054)
			(stroke
				(width 0.1)
				(type default)
			)
			(layer "F.Fab")
		)
		(fp_line
			(start -0.67945 0.3048)
			(end -0.67945 -0.305054)
			(stroke
				(width 0.1)
				(type default)
			)
			(layer "F.Fab")
		)
		(fp_line
			(start -0.12065 -0.305054)
			(end -0.12065 -0.2794)
			(stroke
				(width 0.1)
				(type default)
			)
			(layer "F.Fab")
		)
		(fp_line
			(start -0.12065 -0.2794)
			(end 0.12065 -0.2794)
			(stroke
				(width 0.1)
				(type default)
			)
			(layer "F.Fab")
		)
		(fp_line
			(start -0.12065 0.2794)
			(end -0.12065 0.3048)
			(stroke
				(width 0.1)
				(type default)
			)
			(layer "F.Fab")
		)
		(fp_line
			(start -0.12065 0.3048)
			(end -0.67945 0.3048)
			(stroke
				(width 0.1)
				(type default)
			)
			(layer "F.Fab")
		)
		(fp_line
			(start 0.120396 0.2794)
			(end -0.12065 0.2794)
			(stroke
				(width 0.1)
				(type default)
			)
			(layer "F.Fab")
		)
		(fp_line
			(start 0.120396 0.3048)
			(end 0.120396 0.2794)
			(stroke
				(width 0.1)
				(type default)
			)
			(layer "F.Fab")
		)
		(fp_line
			(start 0.12065 -0.3048)
			(end 0.67945 -0.3048)
			(stroke
				(width 0.1)
				(type default)
			)
			(layer "F.Fab")
		)
		(fp_line
			(start 0.12065 -0.2794)
			(end 0.12065 -0.3048)
			(stroke
				(width 0.1)
				(type default)
			)
			(layer "F.Fab")
		)
		(fp_line
			(start 0.67945 -0.3048)
			(end 0.67945 0.3048)
			(stroke
				(width 0.1)
				(type default)
			)
			(layer "F.Fab")
		)
		(fp_line
			(start 0.67945 0.3048)
			(end 0.120396 0.3048)
			(stroke
				(width 0.1)
				(type default)
			)
			(layer "F.Fab")
		)
		(pad "1" smd circle
			(at -0.40005 0)
			(size 0 0)
			(layers "F.Cu" "F.Mask" "F.Paste")
			(net "LM75_2_A2")
		)
		(pad "2" smd circle
			(at 0.40005 0)
			(size 0 0)
			(layers "F.Cu" "F.Mask" "F.Paste")
			(net "GND")
		)
	)
	(footprint ""
		(layer "F.Cu")
		(at 324.993 -232.156)
		(property "Reference" "C2841"
			(at 0 0 0)
			(layer "F.SilkS")
			(hide yes)
			(effects
				(font
					(size 1.27 1.27)
				)
			)
		)
		(property "Value" ""
			(at 0 0 0)
			(layer "F.Fab")
			(effects
				(font
					(size 1.27 1.27)
				)
			)
		)
		(duplicate_pad_numbers_are_jumpers no)
		(fp_line
			(start -0.7874 -0.4064)
			(end 0.7874 -0.4064)
			(stroke
				(width 0.1524)
				(type default)
			)
			(layer "F.SilkS")
		)
		(fp_line
			(start -0.7874 0.4064)
			(end -0.7874 -0.4064)
			(stroke
				(width 0.1524)
				(type default)
			)
			(layer "F.SilkS")
		)
		(fp_line
			(start 0.7874 -0.4064)
			(end 0.7874 0.4064)
			(stroke
				(width 0.1524)
				(type default)
			)
			(layer "F.SilkS")
		)
		(fp_line
			(start 0.7874 0.4064)
			(end -0.7874 0.4064)
			(stroke
				(width 0.1524)
				(type default)
			)
			(layer "F.SilkS")
		)
		(fp_line
			(start -0.67945 -0.305054)
			(end -0.12065 -0.305054)
			(stroke
				(width 0.1)
				(type default)
			)
			(layer "F.Fab")
		)
		(fp_line
			(start -0.67945 0.3048)
			(end -0.67945 -0.305054)
			(stroke
				(width 0.1)
				(type default)
			)
			(layer "F.Fab")
		)
		(fp_line
			(start -0.12065 -0.305054)
			(end -0.12065 -0.2794)
			(stroke
				(width 0.1)
				(type default)
			)
			(layer "F.Fab")
		)
		(fp_line
			(start -0.12065 -0.2794)
			(end 0.12065 -0.2794)
			(stroke
				(width 0.1)
				(type default)
			)
			(layer "F.Fab")
		)
		(fp_line
			(start -0.12065 0.2794)
			(end -0.12065 0.3048)
			(stroke
				(width 0.1)
				(type default)
			)
			(layer "F.Fab")
		)
		(fp_line
			(start -0.12065 0.3048)
			(end -0.67945 0.3048)
			(stroke
				(width 0.1)
				(type default)
			)
			(layer "F.Fab")
		)
		(fp_line
			(start 0.120396 0.2794)
			(end -0.12065 0.2794)
			(stroke
				(width 0.1)
				(type default)
			)
			(layer "F.Fab")
		)
		(fp_line
			(start 0.120396 0.3048)
			(end 0.120396 0.2794)
			(stroke
				(width 0.1)
				(type default)
			)
			(layer "F.Fab")
		)
		(fp_line
			(start 0.12065 -0.3048)
			(end 0.67945 -0.3048)
			(stroke
				(width 0.1)
				(type default)
			)
			(layer "F.Fab")
		)
		(fp_line
			(start 0.12065 -0.2794)
			(end 0.12065 -0.3048)
			(stroke
				(width 0.1)
				(type default)
			)
			(layer "F.Fab")
		)
		(fp_line
			(start 0.67945 -0.3048)
			(end 0.67945 0.3048)
			(stroke
				(width 0.1)
				(type default)
			)
			(layer "F.Fab")
		)
		(fp_line
			(start 0.67945 0.3048)
			(end 0.120396 0.3048)
			(stroke
				(width 0.1)
				(type default)
			)
			(layer "F.Fab")
		)
		(pad "1" smd circle
			(at -0.40005 0)
			(size 0 0)
			(layers "F.Cu" "F.Mask" "F.Paste")
			(net "GND")
		)
		(pad "2" smd circle
			(at 0.40005 0)
			(size 0 0)
			(layers "F.Cu" "F.Mask" "F.Paste")
			(net "P3V3_AUX")
		)
	)
	(footprint ""
		(layer "F.Cu")
		(at 377.123706 -306.366418 45)
		(property "Reference" "R1455"
			(at 0 0 45)
			(layer "F.SilkS")
			(hide yes)
			(effects
				(font
					(size 1.27 1.27)
				)
			)
		)
		(property "Value" ""
			(at 0 0 45)
			(layer "F.Fab")
			(effects
				(font
					(size 1.27 1.27)
				)
			)
		)
		(duplicate_pad_numbers_are_jumpers no)
		(fp_line
			(start -0.787389 -0.406267)
			(end 0.787389 -0.406267)
			(stroke
				(width 0.1524)
				(type default)
			)
			(layer "F.SilkS")
		)
		(fp_line
			(start -0.787389 0.406267)
			(end -0.787389 -0.406267)
			(stroke
				(width 0.1524)
				(type default)
			)
			(layer "F.SilkS")
		)
		(fp_line
			(start 0.787389 -0.406267)
			(end 0.787389 0.406267)
			(stroke
				(width 0.1524)
				(type default)
			)
			(layer "F.SilkS")
		)
		(fp_line
			(start 0.787389 0.406267)
			(end -0.787389 0.406267)
			(stroke
				(width 0.1524)
				(type default)
			)
			(layer "F.SilkS")
		)
		(fp_line
			(start -0.679446 -0.305149)
			(end -0.120695 -0.304969)
			(stroke
				(width 0.1)
				(type default)
			)
			(layer "F.Fab")
		)
		(fp_line
			(start -0.120695 -0.304969)
			(end -0.120695 -0.279466)
			(stroke
				(width 0.1)
				(type default)
			)
			(layer "F.Fab")
		)
		(fp_line
			(start -0.120695 -0.279466)
			(end 0.120695 -0.279466)
			(stroke
				(width 0.1)
				(type default)
			)
			(layer "F.Fab")
		)
		(fp_line
			(start -0.679446 0.30479)
			(end -0.679446 -0.305149)
			(stroke
				(width 0.1)
				(type default)
			)
			(layer "F.Fab")
		)
		(fp_line
			(start 0.120515 -0.30479)
			(end 0.679446 -0.30479)
			(stroke
				(width 0.1)
				(type default)
			)
			(layer "F.Fab")
		)
		(fp_line
			(start 0.120695 -0.279466)
			(end 0.120515 -0.30479)
			(stroke
				(width 0.1)
				(type default)
			)
			(layer "F.Fab")
		)
		(fp_line
			(start -0.120695 0.279466)
			(end -0.120515 0.30479)
			(stroke
				(width 0.1)
				(type default)
			)
			(layer "F.Fab")
		)
		(fp_line
			(start -0.120515 0.30479)
			(end -0.679446 0.30479)
			(stroke
				(width 0.1)
				(type default)
			)
			(layer "F.Fab")
		)
		(fp_line
			(start 0.679446 -0.30479)
			(end 0.679446 0.30479)
			(stroke
				(width 0.1)
				(type default)
			)
			(layer "F.Fab")
		)
		(fp_line
			(start 0.120335 0.279466)
			(end -0.120695 0.279466)
			(stroke
				(width 0.1)
				(type default)
			)
			(layer "F.Fab")
		)
		(fp_line
			(start 0.120515 0.30479)
			(end 0.120335 0.279466)
			(stroke
				(width 0.1)
				(type default)
			)
			(layer "F.Fab")
		)
		(fp_line
			(start 0.679446 0.30479)
			(end 0.120515 0.30479)
			(stroke
				(width 0.1)
				(type default)
			)
			(layer "F.Fab")
		)
		(pad "1" smd circle
			(at -0.40005 0 45)
			(size 0 0)
			(layers "F.Cu" "F.Mask" "F.Paste")
			(net "GND")
		)
		(pad "2" smd circle
			(at 0.40005 0 45)
			(size 0 0)
			(layers "F.Cu" "F.Mask" "F.Paste")
			(net "PEX3_DFT_IDDT")
		)
	)
	(footprint ""
		(layer "F.Cu")
		(at 406.166828 -52.543456 180)
		(property "Reference" "PC574"
			(at 0 0 180)
			(layer "F.SilkS")
			(hide yes)
			(effects
				(font
					(size 1.27 1.27)
				)
			)
		)
		(property "Value" ""
			(at 0 0 180)
			(layer "F.Fab")
			(effects
				(font
					(size 1.27 1.27)
				)
			)
		)
		(duplicate_pad_numbers_are_jumpers no)
		(fp_line
			(start 0.7874 0.4064)
			(end -0.7874 0.4064)
			(stroke
				(width 0.1524)
				(type default)
			)
			(layer "F.SilkS")
		)
		(fp_line
			(start 0.7874 -0.4064)
			(end 0.7874 0.4064)
			(stroke
				(width 0.1524)
				(type default)
			)
			(layer "F.SilkS")
		)
		(fp_line
			(start -0.7874 0.4064)
			(end -0.7874 -0.4064)
			(stroke
				(width 0.1524)
				(type default)
			)
			(layer "F.SilkS")
		)
		(fp_line
			(start -0.7874 -0.4064)
			(end 0.7874 -0.4064)
			(stroke
				(width 0.1524)
				(type default)
			)
			(layer "F.SilkS")
		)
		(fp_line
			(start 0.67945 0.3048)
			(end 0.120396 0.3048)
			(stroke
				(width 0.1)
				(type default)
			)
			(layer "F.Fab")
		)
		(fp_line
			(start 0.67945 -0.3048)
			(end 0.67945 0.3048)
			(stroke
				(width 0.1)
				(type default)
			)
			(layer "F.Fab")
		)
		(fp_line
			(start 0.12065 -0.2794)
			(end 0.12065 -0.3048)
			(stroke
				(width 0.1)
				(type default)
			)
			(layer "F.Fab")
		)
		(fp_line
			(start 0.12065 -0.3048)
			(end 0.67945 -0.3048)
			(stroke
				(width 0.1)
				(type default)
			)
			(layer "F.Fab")
		)
		(fp_line
			(start 0.120396 0.3048)
			(end 0.120396 0.2794)
			(stroke
				(width 0.1)
				(type default)
			)
			(layer "F.Fab")
		)
		(fp_line
			(start 0.120396 0.2794)
			(end -0.12065 0.2794)
			(stroke
				(width 0.1)
				(type default)
			)
			(layer "F.Fab")
		)
		(fp_line
			(start -0.12065 0.3048)
			(end -0.67945 0.3048)
			(stroke
				(width 0.1)
				(type default)
			)
			(layer "F.Fab")
		)
		(fp_line
			(start -0.12065 0.2794)
			(end -0.12065 0.3048)
			(stroke
				(width 0.1)
				(type default)
			)
			(layer "F.Fab")
		)
		(fp_line
			(start -0.12065 -0.2794)
			(end 0.12065 -0.2794)
			(stroke
				(width 0.1)
				(type default)
			)
			(layer "F.Fab")
		)
		(fp_line
			(start -0.12065 -0.305054)
			(end -0.12065 -0.2794)
			(stroke
				(width 0.1)
				(type default)
			)
			(layer "F.Fab")
		)
		(fp_line
			(start -0.67945 0.3048)
			(end -0.67945 -0.305054)
			(stroke
				(width 0.1)
				(type default)
			)
			(layer "F.Fab")
		)
		(fp_line
			(start -0.67945 -0.305054)
			(end -0.12065 -0.305054)
			(stroke
				(width 0.1)
				(type default)
			)
			(layer "F.Fab")
		)
		(pad "1" smd circle
			(at -0.40005 0 180)
			(size 0 0)
			(layers "F.Cu" "F.Mask" "F.Paste")
			(net "P3V3_SSD14")
		)
		(pad "2" smd circle
			(at 0.40005 0 180)
			(size 0 0)
			(layers "F.Cu" "F.Mask" "F.Paste")
			(net "GND")
		)
	)
	(footprint ""
		(layer "F.Cu")
		(at 262.353298 -281.789632)
		(property "Reference" "L128"
			(at 0 0 0)
			(layer "F.SilkS")
			(hide yes)
			(effects
				(font
					(size 1.27 1.27)
				)
			)
		)
		(property "Value" ""
			(at 0 0 0)
			(layer "F.Fab")
			(effects
				(font
					(size 1.27 1.27)
				)
			)
		)
		(duplicate_pad_numbers_are_jumpers no)
		(fp_line
			(start -1.63576 -0.8128)
			(end -1.63576 0.8128)
			(stroke
				(width 0.1524)
				(type default)
			)
			(layer "F.SilkS")
		)
		(fp_line
			(start -1.63576 -0.8128)
			(end 1.63576 -0.8128)
			(stroke
				(width 0.1524)
				(type default)
			)
			(layer "F.SilkS")
		)
		(fp_line
			(start 1.63576 -0.8128)
			(end 1.63576 0.8128)
			(stroke
				(width 0.1524)
				(type default)
			)
			(layer "F.SilkS")
		)
		(fp_line
			(start 1.63576 0.8128)
			(end -1.63576 0.8128)
			(stroke
				(width 0.1524)
				(type default)
			)
			(layer "F.SilkS")
		)
		(fp_line
			(start -1.56083 -0.738632)
			(end -1.56083 0.7366)
			(stroke
				(width 0.1)
				(type default)
			)
			(layer "F.Fab")
		)
		(fp_line
			(start -1.56083 0.7366)
			(end -1.524 0.7366)
			(stroke
				(width 0.1)
				(type default)
			)
			(layer "F.Fab")
		)
		(fp_line
			(start -1.524 0.7366)
			(end 1.524 0.7366)
			(stroke
				(width 0.1)
				(type default)
			)
			(layer "F.Fab")
		)
		(fp_line
			(start 1.524 0.7366)
			(end 1.560576 0.7366)
			(stroke
				(width 0.1)
				(type default)
			)
			(layer "F.Fab")
		)
		(fp_line
			(start 1.560576 -0.738632)
			(end -1.56083 -0.738632)
			(stroke
				(width 0.1)
				(type default)
			)
			(layer "F.Fab")
		)
		(fp_line
			(start 1.560576 0.7366)
			(end 1.560576 -0.738632)
			(stroke
				(width 0.1)
				(type default)
			)
			(layer "F.Fab")
		)
		(pad "1" smd rect
			(at -0.94996 0 180)
			(size 1.1176 1.3716)
			(layers "F.Cu" "F.Mask" "F.Paste")
			(net "P1V8_PLL0_PEX2")
		)
		(pad "2" smd rect
			(at 0.94996 0 180)
			(size 1.1176 1.3716)
			(layers "F.Cu" "F.Mask" "F.Paste")
			(net "SYSPLL_VDDA18_PEX2")
		)
	)
	(footprint ""
		(layer "F.Cu")
		(at 219.223844 -96.139 90)
		(property "Reference" "R713"
			(at 0 0 90)
			(layer "F.SilkS")
			(hide yes)
			(effects
				(font
					(size 1.27 1.27)
				)
			)
		)
		(property "Value" ""
			(at 0 0 90)
			(layer "F.Fab")
			(effects
				(font
					(size 1.27 1.27)
				)
			)
		)
		(duplicate_pad_numbers_are_jumpers no)
		(fp_line
			(start 0.7874 -0.4064)
			(end 0.7874 0.4064)
			(stroke
				(width 0.1524)
				(type default)
			)
			(layer "F.SilkS")
		)
		(fp_line
			(start -0.7874 -0.4064)
			(end 0.7874 -0.4064)
			(stroke
				(width 0.1524)
				(type default)
			)
			(layer "F.SilkS")
		)
		(fp_line
			(start 0.7874 0.4064)
			(end -0.7874 0.4064)
			(stroke
				(width 0.1524)
				(type default)
			)
			(layer "F.SilkS")
		)
		(fp_line
			(start -0.7874 0.4064)
			(end -0.7874 -0.4064)
			(stroke
				(width 0.1524)
				(type default)
			)
			(layer "F.SilkS")
		)
		(fp_line
			(start -0.12065 -0.305054)
			(end -0.12065 -0.2794)
			(stroke
				(width 0.1)
				(type default)
			)
			(layer "F.Fab")
		)
		(fp_line
			(start -0.67945 -0.305054)
			(end -0.12065 -0.305054)
			(stroke
				(width 0.1)
				(type default)
			)
			(layer "F.Fab")
		)
		(fp_line
			(start 0.67945 -0.3048)
			(end 0.67945 0.3048)
			(stroke
				(width 0.1)
				(type default)
			)
			(layer "F.Fab")
		)
		(fp_line
			(start 0.12065 -0.3048)
			(end 0.67945 -0.3048)
			(stroke
				(width 0.1)
				(type default)
			)
			(layer "F.Fab")
		)
		(fp_line
			(start 0.12065 -0.2794)
			(end 0.12065 -0.3048)
			(stroke
				(width 0.1)
				(type default)
			)
			(layer "F.Fab")
		)
		(fp_line
			(start -0.12065 -0.2794)
			(end 0.12065 -0.2794)
			(stroke
				(width 0.1)
				(type default)
			)
			(layer "F.Fab")
		)
		(fp_line
			(start 0.120396 0.2794)
			(end -0.12065 0.2794)
			(stroke
				(width 0.1)
				(type default)
			)
			(layer "F.Fab")
		)
		(fp_line
			(start -0.12065 0.2794)
			(end -0.12065 0.3048)
			(stroke
				(width 0.1)
				(type default)
			)
			(layer "F.Fab")
		)
		(fp_line
			(start 0.67945 0.3048)
			(end 0.120396 0.3048)
			(stroke
				(width 0.1)
				(type default)
			)
			(layer "F.Fab")
		)
		(fp_line
			(start 0.120396 0.3048)
			(end 0.120396 0.2794)
			(stroke
				(width 0.1)
				(type default)
			)
			(layer "F.Fab")
		)
		(fp_line
			(start -0.12065 0.3048)
			(end -0.67945 0.3048)
			(stroke
				(width 0.1)
				(type default)
			)
			(layer "F.Fab")
		)
		(fp_line
			(start -0.67945 0.3048)
			(end -0.67945 -0.305054)
			(stroke
				(width 0.1)
				(type default)
			)
			(layer "F.Fab")
		)
		(pad "1" smd circle
			(at -0.40005 0 90)
			(size 0 0)
			(layers "F.Cu" "F.Mask" "F.Paste")
			(net "P3V3_AUX")
		)
		(pad "2" smd circle
			(at 0.40005 0 90)
			(size 0 0)
			(layers "F.Cu" "F.Mask" "F.Paste")
			(net "NIC_ADC_ALERT_N")
		)
	)
	(footprint ""
		(layer "F.Cu")
		(at 336.042 -183.007 180)
		(property "Reference" "R4739"
			(at 0 0 180)
			(layer "F.SilkS")
			(hide yes)
			(effects
				(font
					(size 1.27 1.27)
				)
			)
		)
		(property "Value" ""
			(at 0 0 180)
			(layer "F.Fab")
			(effects
				(font
					(size 1.27 1.27)
				)
			)
		)
		(duplicate_pad_numbers_are_jumpers no)
		(fp_line
			(start 0.7874 0.4064)
			(end -0.7874 0.4064)
			(stroke
				(width 0.1524)
				(type default)
			)
			(layer "F.SilkS")
		)
		(fp_line
			(start 0.7874 -0.4064)
			(end 0.7874 0.4064)
			(stroke
				(width 0.1524)
				(type default)
			)
			(layer "F.SilkS")
		)
		(fp_line
			(start -0.7874 0.4064)
			(end -0.7874 -0.4064)
			(stroke
				(width 0.1524)
				(type default)
			)
			(layer "F.SilkS")
		)
		(fp_line
			(start -0.7874 -0.4064)
			(end 0.7874 -0.4064)
			(stroke
				(width 0.1524)
				(type default)
			)
			(layer "F.SilkS")
		)
		(fp_line
			(start 0.67945 0.3048)
			(end 0.120396 0.3048)
			(stroke
				(width 0.1)
				(type default)
			)
			(layer "F.Fab")
		)
		(fp_line
			(start 0.67945 -0.3048)
			(end 0.67945 0.3048)
			(stroke
				(width 0.1)
				(type default)
			)
			(layer "F.Fab")
		)
		(fp_line
			(start 0.12065 -0.2794)
			(end 0.12065 -0.3048)
			(stroke
				(width 0.1)
				(type default)
			)
			(layer "F.Fab")
		)
		(fp_line
			(start 0.12065 -0.3048)
			(end 0.67945 -0.3048)
			(stroke
				(width 0.1)
				(type default)
			)
			(layer "F.Fab")
		)
		(fp_line
			(start 0.120396 0.3048)
			(end 0.120396 0.2794)
			(stroke
				(width 0.1)
				(type default)
			)
			(layer "F.Fab")
		)
		(fp_line
			(start 0.120396 0.2794)
			(end -0.12065 0.2794)
			(stroke
				(width 0.1)
				(type default)
			)
			(layer "F.Fab")
		)
		(fp_line
			(start -0.12065 0.3048)
			(end -0.67945 0.3048)
			(stroke
				(width 0.1)
				(type default)
			)
			(layer "F.Fab")
		)
		(fp_line
			(start -0.12065 0.2794)
			(end -0.12065 0.3048)
			(stroke
				(width 0.1)
				(type default)
			)
			(layer "F.Fab")
		)
		(fp_line
			(start -0.12065 -0.2794)
			(end 0.12065 -0.2794)
			(stroke
				(width 0.1)
				(type default)
			)
			(layer "F.Fab")
		)
		(fp_line
			(start -0.12065 -0.305054)
			(end -0.12065 -0.2794)
			(stroke
				(width 0.1)
				(type default)
			)
			(layer "F.Fab")
		)
		(fp_line
			(start -0.67945 0.3048)
			(end -0.67945 -0.305054)
			(stroke
				(width 0.1)
				(type default)
			)
			(layer "F.Fab")
		)
		(fp_line
			(start -0.67945 -0.305054)
			(end -0.12065 -0.305054)
			(stroke
				(width 0.1)
				(type default)
			)
			(layer "F.Fab")
		)
		(pad "1" smd circle
			(at -0.40005 0 180)
			(size 0 0)
			(layers "F.Cu" "F.Mask" "F.Paste")
			(net "SSD8_PEX_PWR_EN_R")
		)
		(pad "2" smd circle
			(at 0.40005 0 180)
			(size 0 0)
			(layers "F.Cu" "F.Mask" "F.Paste")
			(net "GND")
		)
	)
	(footprint ""
		(layer "F.Cu")
		(at 376.809 -173.13402)
		(property "Reference" "R4666"
			(at 0 0 0)
			(layer "F.SilkS")
			(hide yes)
			(effects
				(font
					(size 1.27 1.27)
				)
			)
		)
		(property "Value" ""
			(at 0 0 0)
			(layer "F.Fab")
			(effects
				(font
					(size 1.27 1.27)
				)
			)
		)
		(duplicate_pad_numbers_are_jumpers no)
		(fp_line
			(start -0.7874 -0.4064)
			(end 0.7874 -0.4064)
			(stroke
				(width 0.1524)
				(type default)
			)
			(layer "F.SilkS")
		)
		(fp_line
			(start -0.7874 0.4064)
			(end -0.7874 -0.4064)
			(stroke
				(width 0.1524)
				(type default)
			)
			(layer "F.SilkS")
		)
		(fp_line
			(start 0.7874 -0.4064)
			(end 0.7874 0.4064)
			(stroke
				(width 0.1524)
				(type default)
			)
			(layer "F.SilkS")
		)
		(fp_line
			(start 0.7874 0.4064)
			(end -0.7874 0.4064)
			(stroke
				(width 0.1524)
				(type default)
			)
			(layer "F.SilkS")
		)
		(fp_line
			(start -0.67945 -0.305054)
			(end -0.12065 -0.305054)
			(stroke
				(width 0.1)
				(type default)
			)
			(layer "F.Fab")
		)
		(fp_line
			(start -0.67945 0.3048)
			(end -0.67945 -0.305054)
			(stroke
				(width 0.1)
				(type default)
			)
			(layer "F.Fab")
		)
		(fp_line
			(start -0.12065 -0.305054)
			(end -0.12065 -0.2794)
			(stroke
				(width 0.1)
				(type default)
			)
			(layer "F.Fab")
		)
		(fp_line
			(start -0.12065 -0.2794)
			(end 0.12065 -0.2794)
			(stroke
				(width 0.1)
				(type default)
			)
			(layer "F.Fab")
		)
		(fp_line
			(start -0.12065 0.2794)
			(end -0.12065 0.3048)
			(stroke
				(width 0.1)
				(type default)
			)
			(layer "F.Fab")
		)
		(fp_line
			(start -0.12065 0.3048)
			(end -0.67945 0.3048)
			(stroke
				(width 0.1)
				(type default)
			)
			(layer "F.Fab")
		)
		(fp_line
			(start 0.120396 0.2794)
			(end -0.12065 0.2794)
			(stroke
				(width 0.1)
				(type default)
			)
			(layer "F.Fab")
		)
		(fp_line
			(start 0.120396 0.3048)
			(end 0.120396 0.2794)
			(stroke
				(width 0.1)
				(type default)
			)
			(layer "F.Fab")
		)
		(fp_line
			(start 0.12065 -0.3048)
			(end 0.67945 -0.3048)
			(stroke
				(width 0.1)
				(type default)
			)
			(layer "F.Fab")
		)
		(fp_line
			(start 0.12065 -0.2794)
			(end 0.12065 -0.3048)
			(stroke
				(width 0.1)
				(type default)
			)
			(layer "F.Fab")
		)
		(fp_line
			(start 0.67945 -0.3048)
			(end 0.67945 0.3048)
			(stroke
				(width 0.1)
				(type default)
			)
			(layer "F.Fab")
		)
		(fp_line
			(start 0.67945 0.3048)
			(end 0.120396 0.3048)
			(stroke
				(width 0.1)
				(type default)
			)
			(layer "F.Fab")
		)
		(pad "1" smd circle
			(at -0.40005 0)
			(size 0 0)
			(layers "F.Cu" "F.Mask" "F.Paste")
			(net "P3V3_AUX")
		)
		(pad "2" smd circle
			(at 0.40005 0)
			(size 0 0)
			(layers "F.Cu" "F.Mask" "F.Paste")
			(net "NIC3_PEX_PWR_EN_R")
		)
	)
	(footprint ""
		(layer "F.Cu")
		(at 380.690882 -230.43896 180)
		(property "Reference" "C2578"
			(at 0 0 180)
			(layer "F.SilkS")
			(hide yes)
			(effects
				(font
					(size 1.27 1.27)
				)
			)
		)
		(property "Value" ""
			(at 0 0 180)
			(layer "F.Fab")
			(effects
				(font
					(size 1.27 1.27)
				)
			)
		)
		(duplicate_pad_numbers_are_jumpers no)
		(fp_line
			(start 0.7874 0.4064)
			(end -0.7874 0.4064)
			(stroke
				(width 0.1524)
				(type default)
			)
			(layer "F.SilkS")
		)
		(fp_line
			(start 0.7874 -0.4064)
			(end 0.7874 0.4064)
			(stroke
				(width 0.1524)
				(type default)
			)
			(layer "F.SilkS")
		)
		(fp_line
			(start -0.7874 0.4064)
			(end -0.7874 -0.4064)
			(stroke
				(width 0.1524)
				(type default)
			)
			(layer "F.SilkS")
		)
		(fp_line
			(start -0.7874 -0.4064)
			(end 0.7874 -0.4064)
			(stroke
				(width 0.1524)
				(type default)
			)
			(layer "F.SilkS")
		)
		(fp_line
			(start 0.67945 0.3048)
			(end 0.120396 0.3048)
			(stroke
				(width 0.1)
				(type default)
			)
			(layer "F.Fab")
		)
		(fp_line
			(start 0.67945 -0.3048)
			(end 0.67945 0.3048)
			(stroke
				(width 0.1)
				(type default)
			)
			(layer "F.Fab")
		)
		(fp_line
			(start 0.12065 -0.2794)
			(end 0.12065 -0.3048)
			(stroke
				(width 0.1)
				(type default)
			)
			(layer "F.Fab")
		)
		(fp_line
			(start 0.12065 -0.3048)
			(end 0.67945 -0.3048)
			(stroke
				(width 0.1)
				(type default)
			)
			(layer "F.Fab")
		)
		(fp_line
			(start 0.120396 0.3048)
			(end 0.120396 0.2794)
			(stroke
				(width 0.1)
				(type default)
			)
			(layer "F.Fab")
		)
		(fp_line
			(start 0.120396 0.2794)
			(end -0.12065 0.2794)
			(stroke
				(width 0.1)
				(type default)
			)
			(layer "F.Fab")
		)
		(fp_line
			(start -0.12065 0.3048)
			(end -0.67945 0.3048)
			(stroke
				(width 0.1)
				(type default)
			)
			(layer "F.Fab")
		)
		(fp_line
			(start -0.12065 0.2794)
			(end -0.12065 0.3048)
			(stroke
				(width 0.1)
				(type default)
			)
			(layer "F.Fab")
		)
		(fp_line
			(start -0.12065 -0.2794)
			(end 0.12065 -0.2794)
			(stroke
				(width 0.1)
				(type default)
			)
			(layer "F.Fab")
		)
		(fp_line
			(start -0.12065 -0.305054)
			(end -0.12065 -0.2794)
			(stroke
				(width 0.1)
				(type default)
			)
			(layer "F.Fab")
		)
		(fp_line
			(start -0.67945 0.3048)
			(end -0.67945 -0.305054)
			(stroke
				(width 0.1)
				(type default)
			)
			(layer "F.Fab")
		)
		(fp_line
			(start -0.67945 -0.305054)
			(end -0.12065 -0.305054)
			(stroke
				(width 0.1)
				(type default)
			)
			(layer "F.Fab")
		)
		(pad "1" smd circle
			(at -0.40005 0 180)
			(size 0 0)
			(layers "F.Cu" "F.Mask" "F.Paste")
			(net "OSC_SDB_IN")
		)
		(pad "2" smd circle
			(at 0.40005 0 180)
			(size 0 0)
			(layers "F.Cu" "F.Mask" "F.Paste")
			(net "GND")
		)
	)
	(footprint ""
		(layer "F.Cu")
		(at 359.396538 -308.438296 -90)
		(property "Reference" "C4360"
			(at 0 0 270)
			(layer "F.SilkS")
			(hide yes)
			(effects
				(font
					(size 1.27 1.27)
				)
			)
		)
		(property "Value" ""
			(at 0 0 270)
			(layer "F.Fab")
			(effects
				(font
					(size 1.27 1.27)
				)
			)
		)
		(duplicate_pad_numbers_are_jumpers no)
		(fp_line
			(start -1.2954 0.5842)
			(end -1.2954 -0.5842)
			(stroke
				(width 0.1524)
				(type default)
			)
			(layer "F.SilkS")
		)
		(fp_line
			(start 1.2954 0.5842)
			(end -1.2954 0.5842)
			(stroke
				(width 0.1524)
				(type default)
			)
			(layer "F.SilkS")
		)
		(fp_line
			(start -1.2954 -0.5842)
			(end 1.2954 -0.5842)
			(stroke
				(width 0.1524)
				(type default)
			)
			(layer "F.SilkS")
		)
		(fp_line
			(start 1.2954 -0.5842)
			(end 1.2954 0.5842)
			(stroke
				(width 0.1524)
				(type default)
			)
			(layer "F.SilkS")
		)
		(fp_line
			(start -0.8636 0.4572)
			(end -0.8636 0.4064)
			(stroke
				(width 0.1)
				(type default)
			)
			(layer "F.Fab")
		)
		(fp_line
			(start 0.8636 0.4572)
			(end -0.8636 0.4572)
			(stroke
				(width 0.1)
				(type default)
			)
			(layer "F.Fab")
		)
		(fp_line
			(start -1.1938 0.4064)
			(end -1.1938 -0.4064)
			(stroke
				(width 0.1)
				(type default)
			)
			(layer "F.Fab")
		)
		(fp_line
			(start -0.8636 0.4064)
			(end -1.1938 0.4064)
			(stroke
				(width 0.1)
				(type default)
			)
			(layer "F.Fab")
		)
		(fp_line
			(start 0.8636 0.4064)
			(end 0.8636 0.4572)
			(stroke
				(width 0.1)
				(type default)
			)
			(layer "F.Fab")
		)
		(fp_line
			(start 1.1938 0.4064)
			(end 0.8636 0.4064)
			(stroke
				(width 0.1)
				(type default)
			)
			(layer "F.Fab")
		)
		(fp_line
			(start -1.1938 -0.4064)
			(end -0.8636 -0.4064)
			(stroke
				(width 0.1)
				(type default)
			)
			(layer "F.Fab")
		)
		(fp_line
			(start -0.8636 -0.4064)
			(end -0.8636 -0.4572)
			(stroke
				(width 0.1)
				(type default)
			)
			(layer "F.Fab")
		)
		(fp_line
			(start 0.8636 -0.4064)
			(end 1.1938 -0.4064)
			(stroke
				(width 0.1)
				(type default)
			)
			(layer "F.Fab")
		)
		(fp_line
			(start 1.1938 -0.4064)
			(end 1.1938 0.4064)
			(stroke
				(width 0.1)
				(type default)
			)
			(layer "F.Fab")
		)
		(fp_line
			(start -0.8636 -0.4572)
			(end 0.8636 -0.4572)
			(stroke
				(width 0.1)
				(type default)
			)
			(layer "F.Fab")
		)
		(fp_line
			(start 0.8636 -0.4572)
			(end 0.8636 -0.4064)
			(stroke
				(width 0.1)
				(type default)
			)
			(layer "F.Fab")
		)
		(pad "1" smd rect
			(at -0.7366 0 180)
			(size 0.7112 0.8128)
			(layers "F.Cu" "F.Mask" "F.Paste")
			(net "P0V8_PEX3")
		)
		(pad "2" smd rect
			(at 0.7366 0 180)
			(size 0.7112 0.8128)
			(layers "F.Cu" "F.Mask" "F.Paste")
			(net "GND")
		)
	)
	(footprint ""
		(layer "F.Cu")
		(at 214.44839 -211.215732 180)
		(property "Reference" "R6413"
			(at 0 0 180)
			(layer "F.SilkS")
			(hide yes)
			(effects
				(font
					(size 1.27 1.27)
				)
			)
		)
		(property "Value" ""
			(at 0 0 180)
			(layer "F.Fab")
			(effects
				(font
					(size 1.27 1.27)
				)
			)
		)
		(duplicate_pad_numbers_are_jumpers no)
		(fp_line
			(start 0.7874 0.4064)
			(end -0.7874 0.4064)
			(stroke
				(width 0.1524)
				(type default)
			)
			(layer "F.SilkS")
		)
		(fp_line
			(start 0.7874 -0.4064)
			(end 0.7874 0.4064)
			(stroke
				(width 0.1524)
				(type default)
			)
			(layer "F.SilkS")
		)
		(fp_line
			(start -0.7874 0.4064)
			(end -0.7874 -0.4064)
			(stroke
				(width 0.1524)
				(type default)
			)
			(layer "F.SilkS")
		)
		(fp_line
			(start -0.7874 -0.4064)
			(end 0.7874 -0.4064)
			(stroke
				(width 0.1524)
				(type default)
			)
			(layer "F.SilkS")
		)
		(fp_line
			(start 0.67945 0.3048)
			(end 0.120396 0.3048)
			(stroke
				(width 0.1)
				(type default)
			)
			(layer "F.Fab")
		)
		(fp_line
			(start 0.67945 -0.3048)
			(end 0.67945 0.3048)
			(stroke
				(width 0.1)
				(type default)
			)
			(layer "F.Fab")
		)
		(fp_line
			(start 0.12065 -0.2794)
			(end 0.12065 -0.3048)
			(stroke
				(width 0.1)
				(type default)
			)
			(layer "F.Fab")
		)
		(fp_line
			(start 0.12065 -0.3048)
			(end 0.67945 -0.3048)
			(stroke
				(width 0.1)
				(type default)
			)
			(layer "F.Fab")
		)
		(fp_line
			(start 0.120396 0.3048)
			(end 0.120396 0.2794)
			(stroke
				(width 0.1)
				(type default)
			)
			(layer "F.Fab")
		)
		(fp_line
			(start 0.120396 0.2794)
			(end -0.12065 0.2794)
			(stroke
				(width 0.1)
				(type default)
			)
			(layer "F.Fab")
		)
		(fp_line
			(start -0.12065 0.3048)
			(end -0.67945 0.3048)
			(stroke
				(width 0.1)
				(type default)
			)
			(layer "F.Fab")
		)
		(fp_line
			(start -0.12065 0.2794)
			(end -0.12065 0.3048)
			(stroke
				(width 0.1)
				(type default)
			)
			(layer "F.Fab")
		)
		(fp_line
			(start -0.12065 -0.2794)
			(end 0.12065 -0.2794)
			(stroke
				(width 0.1)
				(type default)
			)
			(layer "F.Fab")
		)
		(fp_line
			(start -0.12065 -0.305054)
			(end -0.12065 -0.2794)
			(stroke
				(width 0.1)
				(type default)
			)
			(layer "F.Fab")
		)
		(fp_line
			(start -0.67945 0.3048)
			(end -0.67945 -0.305054)
			(stroke
				(width 0.1)
				(type default)
			)
			(layer "F.Fab")
		)
		(fp_line
			(start -0.67945 -0.305054)
			(end -0.12065 -0.305054)
			(stroke
				(width 0.1)
				(type default)
			)
			(layer "F.Fab")
		)
		(pad "1" smd circle
			(at -0.40005 0 180)
			(size 0 0)
			(layers "F.Cu" "F.Mask" "F.Paste")
			(net "RST_BIC_I2C9_SSD_MUX1_N")
		)
		(pad "2" smd circle
			(at 0.40005 0 180)
			(size 0 0)
			(layers "F.Cu" "F.Mask" "F.Paste")
			(net "P3V3_AUX")
		)
	)
	(footprint ""
		(layer "F.Cu")
		(at 123.71324 -138.360404 180)
		(property "Reference" "R4450"
			(at 0 0 180)
			(layer "F.SilkS")
			(hide yes)
			(effects
				(font
					(size 1.27 1.27)
				)
			)
		)
		(property "Value" ""
			(at 0 0 180)
			(layer "F.Fab")
			(effects
				(font
					(size 1.27 1.27)
				)
			)
		)
		(duplicate_pad_numbers_are_jumpers no)
		(fp_line
			(start 0.7874 0.4064)
			(end -0.7874 0.4064)
			(stroke
				(width 0.1524)
				(type default)
			)
			(layer "F.SilkS")
		)
		(fp_line
			(start 0.7874 -0.4064)
			(end 0.7874 0.4064)
			(stroke
				(width 0.1524)
				(type default)
			)
			(layer "F.SilkS")
		)
		(fp_line
			(start -0.7874 0.4064)
			(end -0.7874 -0.4064)
			(stroke
				(width 0.1524)
				(type default)
			)
			(layer "F.SilkS")
		)
		(fp_line
			(start -0.7874 -0.4064)
			(end 0.7874 -0.4064)
			(stroke
				(width 0.1524)
				(type default)
			)
			(layer "F.SilkS")
		)
		(fp_line
			(start 0.67945 0.3048)
			(end 0.120396 0.3048)
			(stroke
				(width 0.1)
				(type default)
			)
			(layer "F.Fab")
		)
		(fp_line
			(start 0.67945 -0.3048)
			(end 0.67945 0.3048)
			(stroke
				(width 0.1)
				(type default)
			)
			(layer "F.Fab")
		)
		(fp_line
			(start 0.12065 -0.2794)
			(end 0.12065 -0.3048)
			(stroke
				(width 0.1)
				(type default)
			)
			(layer "F.Fab")
		)
		(fp_line
			(start 0.12065 -0.3048)
			(end 0.67945 -0.3048)
			(stroke
				(width 0.1)
				(type default)
			)
			(layer "F.Fab")
		)
		(fp_line
			(start 0.120396 0.3048)
			(end 0.120396 0.2794)
			(stroke
				(width 0.1)
				(type default)
			)
			(layer "F.Fab")
		)
		(fp_line
			(start 0.120396 0.2794)
			(end -0.12065 0.2794)
			(stroke
				(width 0.1)
				(type default)
			)
			(layer "F.Fab")
		)
		(fp_line
			(start -0.12065 0.3048)
			(end -0.67945 0.3048)
			(stroke
				(width 0.1)
				(type default)
			)
			(layer "F.Fab")
		)
		(fp_line
			(start -0.12065 0.2794)
			(end -0.12065 0.3048)
			(stroke
				(width 0.1)
				(type default)
			)
			(layer "F.Fab")
		)
		(fp_line
			(start -0.12065 -0.2794)
			(end 0.12065 -0.2794)
			(stroke
				(width 0.1)
				(type default)
			)
			(layer "F.Fab")
		)
		(fp_line
			(start -0.12065 -0.305054)
			(end -0.12065 -0.2794)
			(stroke
				(width 0.1)
				(type default)
			)
			(layer "F.Fab")
		)
		(fp_line
			(start -0.67945 0.3048)
			(end -0.67945 -0.305054)
			(stroke
				(width 0.1)
				(type default)
			)
			(layer "F.Fab")
		)
		(fp_line
			(start -0.67945 -0.305054)
			(end -0.12065 -0.305054)
			(stroke
				(width 0.1)
				(type default)
			)
			(layer "F.Fab")
		)
		(pad "1" smd circle
			(at -0.40005 0 180)
			(size 0 0)
			(layers "F.Cu" "F.Mask" "F.Paste")
			(net "PWRGD_P12V_NIC2")
		)
		(pad "2" smd circle
			(at 0.40005 0 180)
			(size 0 0)
			(layers "F.Cu" "F.Mask" "F.Paste")
			(net "PWRGD_P12V_NIC2_R")
		)
	)
	(footprint ""
		(layer "F.Cu")
		(at 213.062566 -235.756958 90)
		(property "Reference" "R1540"
			(at 0 0 90)
			(layer "F.SilkS")
			(hide yes)
			(effects
				(font
					(size 1.27 1.27)
				)
			)
		)
		(property "Value" ""
			(at 0 0 90)
			(layer "F.Fab")
			(effects
				(font
					(size 1.27 1.27)
				)
			)
		)
		(duplicate_pad_numbers_are_jumpers no)
		(fp_line
			(start 0.7874 -0.4064)
			(end 0.7874 0.4064)
			(stroke
				(width 0.1524)
				(type default)
			)
			(layer "F.SilkS")
		)
		(fp_line
			(start -0.7874 -0.4064)
			(end 0.7874 -0.4064)
			(stroke
				(width 0.1524)
				(type default)
			)
			(layer "F.SilkS")
		)
		(fp_line
			(start 0.7874 0.4064)
			(end -0.7874 0.4064)
			(stroke
				(width 0.1524)
				(type default)
			)
			(layer "F.SilkS")
		)
		(fp_line
			(start -0.7874 0.4064)
			(end -0.7874 -0.4064)
			(stroke
				(width 0.1524)
				(type default)
			)
			(layer "F.SilkS")
		)
		(fp_line
			(start -0.12065 -0.305054)
			(end -0.12065 -0.2794)
			(stroke
				(width 0.1)
				(type default)
			)
			(layer "F.Fab")
		)
		(fp_line
			(start -0.67945 -0.305054)
			(end -0.12065 -0.305054)
			(stroke
				(width 0.1)
				(type default)
			)
			(layer "F.Fab")
		)
		(fp_line
			(start 0.67945 -0.3048)
			(end 0.67945 0.3048)
			(stroke
				(width 0.1)
				(type default)
			)
			(layer "F.Fab")
		)
		(fp_line
			(start 0.12065 -0.3048)
			(end 0.67945 -0.3048)
			(stroke
				(width 0.1)
				(type default)
			)
			(layer "F.Fab")
		)
		(fp_line
			(start 0.12065 -0.2794)
			(end 0.12065 -0.3048)
			(stroke
				(width 0.1)
				(type default)
			)
			(layer "F.Fab")
		)
		(fp_line
			(start -0.12065 -0.2794)
			(end 0.12065 -0.2794)
			(stroke
				(width 0.1)
				(type default)
			)
			(layer "F.Fab")
		)
		(fp_line
			(start 0.120396 0.2794)
			(end -0.12065 0.2794)
			(stroke
				(width 0.1)
				(type default)
			)
			(layer "F.Fab")
		)
		(fp_line
			(start -0.12065 0.2794)
			(end -0.12065 0.3048)
			(stroke
				(width 0.1)
				(type default)
			)
			(layer "F.Fab")
		)
		(fp_line
			(start 0.67945 0.3048)
			(end 0.120396 0.3048)
			(stroke
				(width 0.1)
				(type default)
			)
			(layer "F.Fab")
		)
		(fp_line
			(start 0.120396 0.3048)
			(end 0.120396 0.2794)
			(stroke
				(width 0.1)
				(type default)
			)
			(layer "F.Fab")
		)
		(fp_line
			(start -0.12065 0.3048)
			(end -0.67945 0.3048)
			(stroke
				(width 0.1)
				(type default)
			)
			(layer "F.Fab")
		)
		(fp_line
			(start -0.67945 0.3048)
			(end -0.67945 -0.305054)
			(stroke
				(width 0.1)
				(type default)
			)
			(layer "F.Fab")
		)
		(pad "1" smd circle
			(at -0.40005 0 90)
			(size 0 0)
			(layers "F.Cu" "F.Mask" "F.Paste")
			(net "P1V8_PEX")
		)
		(pad "2" smd circle
			(at 0.40005 0 90)
			(size 0 0)
			(layers "F.Cu" "F.Mask" "F.Paste")
			(net "SMB_PEX_LS_SDA")
		)
	)
	(footprint ""
		(layer "F.Cu")
		(at 377.455176 -53.468524 90)
		(property "Reference" "PC559"
			(at 0 0 90)
			(layer "F.SilkS")
			(hide yes)
			(effects
				(font
					(size 1.27 1.27)
				)
			)
		)
		(property "Value" ""
			(at 0 0 90)
			(layer "F.Fab")
			(effects
				(font
					(size 1.27 1.27)
				)
			)
		)
		(duplicate_pad_numbers_are_jumpers no)
		(fp_line
			(start 1.524 -0.762)
			(end 1.524 0.762)
			(stroke
				(width 0.1524)
				(type default)
			)
			(layer "F.SilkS")
		)
		(fp_line
			(start -1.524 -0.762)
			(end 1.524 -0.762)
			(stroke
				(width 0.1524)
				(type default)
			)
			(layer "F.SilkS")
		)
		(fp_line
			(start 1.524 0.762)
			(end -1.524 0.762)
			(stroke
				(width 0.1524)
				(type default)
			)
			(layer "F.SilkS")
		)
		(fp_line
			(start -1.524 0.762)
			(end -1.524 -0.762)
			(stroke
				(width 0.1524)
				(type default)
			)
			(layer "F.SilkS")
		)
		(fp_line
			(start 1.1049 -0.724916)
			(end -1.1049 -0.724916)
			(stroke
				(width 0.1)
				(type default)
			)
			(layer "F.Fab")
		)
		(fp_line
			(start -1.1049 -0.724916)
			(end -1.1049 0.724916)
			(stroke
				(width 0.1)
				(type default)
			)
			(layer "F.Fab")
		)
		(fp_line
			(start 1.1049 0.724916)
			(end 1.1049 -0.724916)
			(stroke
				(width 0.1)
				(type default)
			)
			(layer "F.Fab")
		)
		(fp_line
			(start -1.1049 0.724916)
			(end 1.1049 0.724916)
			(stroke
				(width 0.1)
				(type default)
			)
			(layer "F.Fab")
		)
		(pad "1" smd rect
			(at -0.889 0 270)
			(size 1.016 1.27)
			(layers "F.Cu" "F.Mask" "F.Paste")
			(net "GND")
		)
		(pad "2" smd rect
			(at 0.889 0 270)
			(size 1.016 1.27)
			(layers "F.Cu" "F.Mask" "F.Paste")
			(net "P3V3_AUX")
		)
	)
	(footprint ""
		(layer "F.Cu")
		(at 82.666078 -77.889608 180)
		(property "Reference" "C868"
			(at 0 0 180)
			(layer "F.SilkS")
			(hide yes)
			(effects
				(font
					(size 1.27 1.27)
				)
			)
		)
		(property "Value" ""
			(at 0 0 180)
			(layer "F.Fab")
			(effects
				(font
					(size 1.27 1.27)
				)
			)
		)
		(duplicate_pad_numbers_are_jumpers no)
		(fp_line
			(start 0.7874 0.4064)
			(end -0.7874 0.4064)
			(stroke
				(width 0.1524)
				(type default)
			)
			(layer "F.SilkS")
		)
		(fp_line
			(start 0.7874 -0.4064)
			(end 0.7874 0.4064)
			(stroke
				(width 0.1524)
				(type default)
			)
			(layer "F.SilkS")
		)
		(fp_line
			(start -0.7874 0.4064)
			(end -0.7874 -0.4064)
			(stroke
				(width 0.1524)
				(type default)
			)
			(layer "F.SilkS")
		)
		(fp_line
			(start -0.7874 -0.4064)
			(end 0.7874 -0.4064)
			(stroke
				(width 0.1524)
				(type default)
			)
			(layer "F.SilkS")
		)
		(fp_line
			(start 0.67945 0.3048)
			(end 0.120396 0.3048)
			(stroke
				(width 0.1)
				(type default)
			)
			(layer "F.Fab")
		)
		(fp_line
			(start 0.67945 -0.3048)
			(end 0.67945 0.3048)
			(stroke
				(width 0.1)
				(type default)
			)
			(layer "F.Fab")
		)
		(fp_line
			(start 0.12065 -0.2794)
			(end 0.12065 -0.3048)
			(stroke
				(width 0.1)
				(type default)
			)
			(layer "F.Fab")
		)
		(fp_line
			(start 0.12065 -0.3048)
			(end 0.67945 -0.3048)
			(stroke
				(width 0.1)
				(type default)
			)
			(layer "F.Fab")
		)
		(fp_line
			(start 0.120396 0.3048)
			(end 0.120396 0.2794)
			(stroke
				(width 0.1)
				(type default)
			)
			(layer "F.Fab")
		)
		(fp_line
			(start 0.120396 0.2794)
			(end -0.12065 0.2794)
			(stroke
				(width 0.1)
				(type default)
			)
			(layer "F.Fab")
		)
		(fp_line
			(start -0.12065 0.3048)
			(end -0.67945 0.3048)
			(stroke
				(width 0.1)
				(type default)
			)
			(layer "F.Fab")
		)
		(fp_line
			(start -0.12065 0.2794)
			(end -0.12065 0.3048)
			(stroke
				(width 0.1)
				(type default)
			)
			(layer "F.Fab")
		)
		(fp_line
			(start -0.12065 -0.2794)
			(end 0.12065 -0.2794)
			(stroke
				(width 0.1)
				(type default)
			)
			(layer "F.Fab")
		)
		(fp_line
			(start -0.12065 -0.305054)
			(end -0.12065 -0.2794)
			(stroke
				(width 0.1)
				(type default)
			)
			(layer "F.Fab")
		)
		(fp_line
			(start -0.67945 0.3048)
			(end -0.67945 -0.305054)
			(stroke
				(width 0.1)
				(type default)
			)
			(layer "F.Fab")
		)
		(fp_line
			(start -0.67945 -0.305054)
			(end -0.12065 -0.305054)
			(stroke
				(width 0.1)
				(type default)
			)
			(layer "F.Fab")
		)
		(pad "1" smd circle
			(at -0.40005 0 180)
			(size 0 0)
			(layers "F.Cu" "F.Mask" "F.Paste")
			(net "P3V3_NIC1")
		)
		(pad "2" smd circle
			(at 0.40005 0 180)
			(size 0 0)
			(layers "F.Cu" "F.Mask" "F.Paste")
			(net "GND")
		)
	)
	(footprint ""
		(layer "F.Cu")
		(at 327.53173 -223.972882)
		(property "Reference" "R4171"
			(at 0 0 0)
			(layer "F.SilkS")
			(hide yes)
			(effects
				(font
					(size 1.27 1.27)
				)
			)
		)
		(property "Value" ""
			(at 0 0 0)
			(layer "F.Fab")
			(effects
				(font
					(size 1.27 1.27)
				)
			)
		)
		(duplicate_pad_numbers_are_jumpers no)
		(fp_line
			(start -0.7874 -0.4064)
			(end 0.7874 -0.4064)
			(stroke
				(width 0.1524)
				(type default)
			)
			(layer "F.SilkS")
		)
		(fp_line
			(start -0.7874 0.4064)
			(end -0.7874 -0.4064)
			(stroke
				(width 0.1524)
				(type default)
			)
			(layer "F.SilkS")
		)
		(fp_line
			(start 0.7874 -0.4064)
			(end 0.7874 0.4064)
			(stroke
				(width 0.1524)
				(type default)
			)
			(layer "F.SilkS")
		)
		(fp_line
			(start 0.7874 0.4064)
			(end -0.7874 0.4064)
			(stroke
				(width 0.1524)
				(type default)
			)
			(layer "F.SilkS")
		)
		(fp_line
			(start -0.67945 -0.305054)
			(end -0.12065 -0.305054)
			(stroke
				(width 0.1)
				(type default)
			)
			(layer "F.Fab")
		)
		(fp_line
			(start -0.67945 0.3048)
			(end -0.67945 -0.305054)
			(stroke
				(width 0.1)
				(type default)
			)
			(layer "F.Fab")
		)
		(fp_line
			(start -0.12065 -0.305054)
			(end -0.12065 -0.2794)
			(stroke
				(width 0.1)
				(type default)
			)
			(layer "F.Fab")
		)
		(fp_line
			(start -0.12065 -0.2794)
			(end 0.12065 -0.2794)
			(stroke
				(width 0.1)
				(type default)
			)
			(layer "F.Fab")
		)
		(fp_line
			(start -0.12065 0.2794)
			(end -0.12065 0.3048)
			(stroke
				(width 0.1)
				(type default)
			)
			(layer "F.Fab")
		)
		(fp_line
			(start -0.12065 0.3048)
			(end -0.67945 0.3048)
			(stroke
				(width 0.1)
				(type default)
			)
			(layer "F.Fab")
		)
		(fp_line
			(start 0.120396 0.2794)
			(end -0.12065 0.2794)
			(stroke
				(width 0.1)
				(type default)
			)
			(layer "F.Fab")
		)
		(fp_line
			(start 0.120396 0.3048)
			(end 0.120396 0.2794)
			(stroke
				(width 0.1)
				(type default)
			)
			(layer "F.Fab")
		)
		(fp_line
			(start 0.12065 -0.3048)
			(end 0.67945 -0.3048)
			(stroke
				(width 0.1)
				(type default)
			)
			(layer "F.Fab")
		)
		(fp_line
			(start 0.12065 -0.2794)
			(end 0.12065 -0.3048)
			(stroke
				(width 0.1)
				(type default)
			)
			(layer "F.Fab")
		)
		(fp_line
			(start 0.67945 -0.3048)
			(end 0.67945 0.3048)
			(stroke
				(width 0.1)
				(type default)
			)
			(layer "F.Fab")
		)
		(fp_line
			(start 0.67945 0.3048)
			(end 0.120396 0.3048)
			(stroke
				(width 0.1)
				(type default)
			)
			(layer "F.Fab")
		)
		(pad "1" smd circle
			(at -0.40005 0)
			(size 0 0)
			(layers "F.Cu" "F.Mask" "F.Paste")
			(net "RST_PEX0_PERST_R_N")
		)
		(pad "2" smd circle
			(at 0.40005 0)
			(size 0 0)
			(layers "F.Cu" "F.Mask" "F.Paste")
			(net "RST_PEX0_PERST_N")
		)
	)
	(footprint ""
		(layer "F.Cu")
		(at 307.856382 -17.419574 180)
		(property "Reference" "R1702"
			(at 0 0 180)
			(layer "F.SilkS")
			(hide yes)
			(effects
				(font
					(size 1.27 1.27)
				)
			)
		)
		(property "Value" ""
			(at 0 0 180)
			(layer "F.Fab")
			(effects
				(font
					(size 1.27 1.27)
				)
			)
		)
		(duplicate_pad_numbers_are_jumpers no)
		(fp_line
			(start 0.7874 0.4064)
			(end -0.7874 0.4064)
			(stroke
				(width 0.1524)
				(type default)
			)
			(layer "F.SilkS")
		)
		(fp_line
			(start 0.7874 -0.4064)
			(end 0.7874 0.4064)
			(stroke
				(width 0.1524)
				(type default)
			)
			(layer "F.SilkS")
		)
		(fp_line
			(start -0.7874 0.4064)
			(end -0.7874 -0.4064)
			(stroke
				(width 0.1524)
				(type default)
			)
			(layer "F.SilkS")
		)
		(fp_line
			(start -0.7874 -0.4064)
			(end 0.7874 -0.4064)
			(stroke
				(width 0.1524)
				(type default)
			)
			(layer "F.SilkS")
		)
		(fp_line
			(start 0.67945 0.3048)
			(end 0.120396 0.3048)
			(stroke
				(width 0.1)
				(type default)
			)
			(layer "F.Fab")
		)
		(fp_line
			(start 0.67945 -0.3048)
			(end 0.67945 0.3048)
			(stroke
				(width 0.1)
				(type default)
			)
			(layer "F.Fab")
		)
		(fp_line
			(start 0.12065 -0.2794)
			(end 0.12065 -0.3048)
			(stroke
				(width 0.1)
				(type default)
			)
			(layer "F.Fab")
		)
		(fp_line
			(start 0.12065 -0.3048)
			(end 0.67945 -0.3048)
			(stroke
				(width 0.1)
				(type default)
			)
			(layer "F.Fab")
		)
		(fp_line
			(start 0.120396 0.3048)
			(end 0.120396 0.2794)
			(stroke
				(width 0.1)
				(type default)
			)
			(layer "F.Fab")
		)
		(fp_line
			(start 0.120396 0.2794)
			(end -0.12065 0.2794)
			(stroke
				(width 0.1)
				(type default)
			)
			(layer "F.Fab")
		)
		(fp_line
			(start -0.12065 0.3048)
			(end -0.67945 0.3048)
			(stroke
				(width 0.1)
				(type default)
			)
			(layer "F.Fab")
		)
		(fp_line
			(start -0.12065 0.2794)
			(end -0.12065 0.3048)
			(stroke
				(width 0.1)
				(type default)
			)
			(layer "F.Fab")
		)
		(fp_line
			(start -0.12065 -0.2794)
			(end 0.12065 -0.2794)
			(stroke
				(width 0.1)
				(type default)
			)
			(layer "F.Fab")
		)
		(fp_line
			(start -0.12065 -0.305054)
			(end -0.12065 -0.2794)
			(stroke
				(width 0.1)
				(type default)
			)
			(layer "F.Fab")
		)
		(fp_line
			(start -0.67945 0.3048)
			(end -0.67945 -0.305054)
			(stroke
				(width 0.1)
				(type default)
			)
			(layer "F.Fab")
		)
		(fp_line
			(start -0.67945 -0.305054)
			(end -0.12065 -0.305054)
			(stroke
				(width 0.1)
				(type default)
			)
			(layer "F.Fab")
		)
		(pad "1" smd circle
			(at -0.40005 0 180)
			(size 0 0)
			(layers "F.Cu" "F.Mask" "F.Paste")
			(net "P3V3_SSD10")
		)
		(pad "2" smd circle
			(at 0.40005 0 180)
			(size 0 0)
			(layers "F.Cu" "F.Mask" "F.Paste")
			(net "SMB_ISO_SSD10_SCL")
		)
	)
	(footprint ""
		(layer "F.Cu")
		(at 17.911826 -146.263614 180)
		(property "Reference" "C410"
			(at 0 0 180)
			(layer "F.SilkS")
			(hide yes)
			(effects
				(font
					(size 1.27 1.27)
				)
			)
		)
		(property "Value" ""
			(at 0 0 180)
			(layer "F.Fab")
			(effects
				(font
					(size 1.27 1.27)
				)
			)
		)
		(duplicate_pad_numbers_are_jumpers no)
		(fp_line
			(start 0.7874 0.4064)
			(end -0.7874 0.4064)
			(stroke
				(width 0.1524)
				(type default)
			)
			(layer "F.SilkS")
		)
		(fp_line
			(start 0.7874 -0.4064)
			(end 0.7874 0.4064)
			(stroke
				(width 0.1524)
				(type default)
			)
			(layer "F.SilkS")
		)
		(fp_line
			(start -0.7874 0.4064)
			(end -0.7874 -0.4064)
			(stroke
				(width 0.1524)
				(type default)
			)
			(layer "F.SilkS")
		)
		(fp_line
			(start -0.7874 -0.4064)
			(end 0.7874 -0.4064)
			(stroke
				(width 0.1524)
				(type default)
			)
			(layer "F.SilkS")
		)
		(fp_line
			(start 0.67945 0.3048)
			(end 0.120396 0.3048)
			(stroke
				(width 0.1)
				(type default)
			)
			(layer "F.Fab")
		)
		(fp_line
			(start 0.67945 -0.3048)
			(end 0.67945 0.3048)
			(stroke
				(width 0.1)
				(type default)
			)
			(layer "F.Fab")
		)
		(fp_line
			(start 0.12065 -0.2794)
			(end 0.12065 -0.3048)
			(stroke
				(width 0.1)
				(type default)
			)
			(layer "F.Fab")
		)
		(fp_line
			(start 0.12065 -0.3048)
			(end 0.67945 -0.3048)
			(stroke
				(width 0.1)
				(type default)
			)
			(layer "F.Fab")
		)
		(fp_line
			(start 0.120396 0.3048)
			(end 0.120396 0.2794)
			(stroke
				(width 0.1)
				(type default)
			)
			(layer "F.Fab")
		)
		(fp_line
			(start 0.120396 0.2794)
			(end -0.12065 0.2794)
			(stroke
				(width 0.1)
				(type default)
			)
			(layer "F.Fab")
		)
		(fp_line
			(start -0.12065 0.3048)
			(end -0.67945 0.3048)
			(stroke
				(width 0.1)
				(type default)
			)
			(layer "F.Fab")
		)
		(fp_line
			(start -0.12065 0.2794)
			(end -0.12065 0.3048)
			(stroke
				(width 0.1)
				(type default)
			)
			(layer "F.Fab")
		)
		(fp_line
			(start -0.12065 -0.2794)
			(end 0.12065 -0.2794)
			(stroke
				(width 0.1)
				(type default)
			)
			(layer "F.Fab")
		)
		(fp_line
			(start -0.12065 -0.305054)
			(end -0.12065 -0.2794)
			(stroke
				(width 0.1)
				(type default)
			)
			(layer "F.Fab")
		)
		(fp_line
			(start -0.67945 0.3048)
			(end -0.67945 -0.305054)
			(stroke
				(width 0.1)
				(type default)
			)
			(layer "F.Fab")
		)
		(fp_line
			(start -0.67945 -0.305054)
			(end -0.12065 -0.305054)
			(stroke
				(width 0.1)
				(type default)
			)
			(layer "F.Fab")
		)
		(pad "1" smd circle
			(at -0.40005 0 180)
			(size 0 0)
			(layers "F.Cu" "F.Mask" "F.Paste")
			(net "P12V_NIC0_R")
		)
		(pad "2" smd circle
			(at 0.40005 0 180)
			(size 0 0)
			(layers "F.Cu" "F.Mask" "F.Paste")
			(net "GND")
		)
	)
	(footprint ""
		(layer "F.Cu")
		(at 304.325274 -42.849038 180)
		(property "Reference" "R623"
			(at 0 0 180)
			(layer "F.SilkS")
			(hide yes)
			(effects
				(font
					(size 1.27 1.27)
				)
			)
		)
		(property "Value" ""
			(at 0 0 180)
			(layer "F.Fab")
			(effects
				(font
					(size 1.27 1.27)
				)
			)
		)
		(duplicate_pad_numbers_are_jumpers no)
		(fp_line
			(start 0.7874 0.4064)
			(end -0.7874 0.4064)
			(stroke
				(width 0.1524)
				(type default)
			)
			(layer "F.SilkS")
		)
		(fp_line
			(start 0.7874 -0.4064)
			(end 0.7874 0.4064)
			(stroke
				(width 0.1524)
				(type default)
			)
			(layer "F.SilkS")
		)
		(fp_line
			(start -0.7874 0.4064)
			(end -0.7874 -0.4064)
			(stroke
				(width 0.1524)
				(type default)
			)
			(layer "F.SilkS")
		)
		(fp_line
			(start -0.7874 -0.4064)
			(end 0.7874 -0.4064)
			(stroke
				(width 0.1524)
				(type default)
			)
			(layer "F.SilkS")
		)
		(fp_line
			(start 0.67945 0.3048)
			(end 0.120396 0.3048)
			(stroke
				(width 0.1)
				(type default)
			)
			(layer "F.Fab")
		)
		(fp_line
			(start 0.67945 -0.3048)
			(end 0.67945 0.3048)
			(stroke
				(width 0.1)
				(type default)
			)
			(layer "F.Fab")
		)
		(fp_line
			(start 0.12065 -0.2794)
			(end 0.12065 -0.3048)
			(stroke
				(width 0.1)
				(type default)
			)
			(layer "F.Fab")
		)
		(fp_line
			(start 0.12065 -0.3048)
			(end 0.67945 -0.3048)
			(stroke
				(width 0.1)
				(type default)
			)
			(layer "F.Fab")
		)
		(fp_line
			(start 0.120396 0.3048)
			(end 0.120396 0.2794)
			(stroke
				(width 0.1)
				(type default)
			)
			(layer "F.Fab")
		)
		(fp_line
			(start 0.120396 0.2794)
			(end -0.12065 0.2794)
			(stroke
				(width 0.1)
				(type default)
			)
			(layer "F.Fab")
		)
		(fp_line
			(start -0.12065 0.3048)
			(end -0.67945 0.3048)
			(stroke
				(width 0.1)
				(type default)
			)
			(layer "F.Fab")
		)
		(fp_line
			(start -0.12065 0.2794)
			(end -0.12065 0.3048)
			(stroke
				(width 0.1)
				(type default)
			)
			(layer "F.Fab")
		)
		(fp_line
			(start -0.12065 -0.2794)
			(end 0.12065 -0.2794)
			(stroke
				(width 0.1)
				(type default)
			)
			(layer "F.Fab")
		)
		(fp_line
			(start -0.12065 -0.305054)
			(end -0.12065 -0.2794)
			(stroke
				(width 0.1)
				(type default)
			)
			(layer "F.Fab")
		)
		(fp_line
			(start -0.67945 0.3048)
			(end -0.67945 -0.305054)
			(stroke
				(width 0.1)
				(type default)
			)
			(layer "F.Fab")
		)
		(fp_line
			(start -0.67945 -0.305054)
			(end -0.12065 -0.305054)
			(stroke
				(width 0.1)
				(type default)
			)
			(layer "F.Fab")
		)
		(pad "1" smd circle
			(at -0.40005 0 180)
			(size 0 0)
			(layers "F.Cu" "F.Mask" "F.Paste")
			(net "P12V_SSD10_R")
		)
		(pad "2" smd circle
			(at 0.40005 0 180)
			(size 0 0)
			(layers "F.Cu" "F.Mask" "F.Paste")
			(net "P12V_SSD10_VIN_P")
		)
	)
	(footprint ""
		(layer "F.Cu")
		(at 196.224398 -84.476336 180)
		(property "Reference" "U26"
			(at -2.862072 -0.249936 90)
			(unlocked yes)
			(layer "F.SilkS")
			(effects
				(font
					(size 0.7874 0.5842)
					(thickness 0.1524)
				)
				(justify left)
			)
		)
		(property "Value" ""
			(at 0 0 180)
			(layer "F.Fab")
			(effects
				(font
					(size 1.27 1.27)
				)
			)
		)
		(duplicate_pad_numbers_are_jumpers no)
		(fp_line
			(start 2.0574 1.651)
			(end -2.0574 1.651)
			(stroke
				(width 0.1524)
				(type default)
			)
			(layer "F.SilkS")
		)
		(fp_line
			(start 2.0574 -1.651)
			(end 2.0574 1.651)
			(stroke
				(width 0.1524)
				(type default)
			)
			(layer "F.SilkS")
		)
		(fp_line
			(start 0.381 -1.651)
			(end 2.0574 -1.651)
			(stroke
				(width 0.1524)
				(type default)
			)
			(layer "F.SilkS")
		)
		(fp_line
			(start 0 -1.016)
			(end 0.381 -1.651)
			(stroke
				(width 0.1524)
				(type default)
			)
			(layer "F.SilkS")
		)
		(fp_line
			(start -0.381 -1.651)
			(end 0 -1.016)
			(stroke
				(width 0.1524)
				(type default)
			)
			(layer "F.SilkS")
		)
		(fp_line
			(start -2.0574 1.651)
			(end -2.0574 -1.651)
			(stroke
				(width 0.1524)
				(type default)
			)
			(layer "F.SilkS")
		)
		(fp_line
			(start -2.0574 -1.651)
			(end -0.381 -1.651)
			(stroke
				(width 0.1524)
				(type default)
			)
			(layer "F.SilkS")
		)
		(fp_poly
			(pts
				(xy -2.71272 -0.719328) (xy -2.71272 -1.344168) (xy -2.159 -1.016)
			)
			(stroke
				(width 0)
				(type default)
			)
			(fill yes)
			(layer "F.SilkS")
		)
		(fp_line
			(start 1.599946 1.199896)
			(end 0.899922 1.199896)
			(stroke
				(width 0.1)
				(type default)
			)
			(layer "F.Fab")
		)
		(fp_line
			(start 1.599946 -1.199896)
			(end 1.599946 1.199896)
			(stroke
				(width 0.1)
				(type default)
			)
			(layer "F.Fab")
		)
		(fp_line
			(start 0.899922 1.549908)
			(end -0.899922 1.549908)
			(stroke
				(width 0.1)
				(type default)
			)
			(layer "F.Fab")
		)
		(fp_line
			(start 0.899922 1.199896)
			(end 0.899922 1.549908)
			(stroke
				(width 0.1)
				(type default)
			)
			(layer "F.Fab")
		)
		(fp_line
			(start 0.899922 -1.199896)
			(end 1.599946 -1.199896)
			(stroke
				(width 0.1)
				(type default)
			)
			(layer "F.Fab")
		)
		(fp_line
			(start 0.899922 -1.549908)
			(end 0.899922 -1.199896)
			(stroke
				(width 0.1)
				(type default)
			)
			(layer "F.Fab")
		)
		(fp_line
			(start -0.899922 1.549908)
			(end -0.899922 1.199896)
			(stroke
				(width 0.1)
				(type default)
			)
			(layer "F.Fab")
		)
		(fp_line
			(start -0.899922 1.199896)
			(end -1.599946 1.199896)
			(stroke
				(width 0.1)
				(type default)
			)
			(layer "F.Fab")
		)
		(fp_line
			(start -0.899922 -1.199896)
			(end -0.899922 -1.549908)
			(stroke
				(width 0.1)
				(type default)
			)
			(layer "F.Fab")
		)
		(fp_line
			(start -0.899922 -1.549908)
			(end 0.899922 -1.549908)
			(stroke
				(width 0.1)
				(type default)
			)
			(layer "F.Fab")
		)
		(fp_line
			(start -1.599946 1.199896)
			(end -1.599946 -1.199896)
			(stroke
				(width 0.1)
				(type default)
			)
			(layer "F.Fab")
		)
		(fp_line
			(start -1.599946 -1.199896)
			(end -0.899922 -1.199896)
			(stroke
				(width 0.1)
				(type default)
			)
			(layer "F.Fab")
		)
		(fp_poly
			(pts
				(xy -2.71272 -0.719328) (xy -2.71272 -1.344168) (xy -2.159 -1.016)
			)
			(stroke
				(width 0)
				(type default)
			)
			(fill yes)
			(layer "F.Fab")
		)
		(pad "1" smd rect
			(at -1.225042 -0.94996 90)
			(size 0.5588 1.3462)
			(layers "F.Cu" "F.Mask" "F.Paste")
			(net "HP_NIC3_PWRGD_R")
		)
		(pad "2" smd rect
			(at -1.225042 0 90)
			(size 0.5588 1.3462)
			(layers "F.Cu" "F.Mask" "F.Paste")
			(net "RST_NIC3_PERST_R_N")
		)
		(pad "3" smd rect
			(at -1.225042 0.94996 90)
			(size 0.5588 1.3462)
			(layers "F.Cu" "F.Mask" "F.Paste")
			(net "GND")
		)
		(pad "4" smd rect
			(at 1.225042 0.94996 90)
			(size 0.5588 1.3462)
			(layers "F.Cu" "F.Mask" "F.Paste")
			(net "RST_HP_NIC3_N")
		)
		(pad "5" smd rect
			(at 1.225042 -0.94996 90)
			(size 0.5588 1.3462)
			(layers "F.Cu" "F.Mask" "F.Paste")
			(net "P3V3_AUX")
		)
	)
	(footprint ""
		(layer "F.Cu")
		(at 295.877742 -114.267742)
		(property "Reference" "R293"
			(at 0 0 0)
			(layer "F.SilkS")
			(hide yes)
			(effects
				(font
					(size 1.27 1.27)
				)
			)
		)
		(property "Value" ""
			(at 0 0 0)
			(layer "F.Fab")
			(effects
				(font
					(size 1.27 1.27)
				)
			)
		)
		(duplicate_pad_numbers_are_jumpers no)
		(fp_line
			(start -0.7874 -0.4064)
			(end 0.7874 -0.4064)
			(stroke
				(width 0.1524)
				(type default)
			)
			(layer "F.SilkS")
		)
		(fp_line
			(start -0.7874 0.4064)
			(end -0.7874 -0.4064)
			(stroke
				(width 0.1524)
				(type default)
			)
			(layer "F.SilkS")
		)
		(fp_line
			(start 0.7874 -0.4064)
			(end 0.7874 0.4064)
			(stroke
				(width 0.1524)
				(type default)
			)
			(layer "F.SilkS")
		)
		(fp_line
			(start 0.7874 0.4064)
			(end -0.7874 0.4064)
			(stroke
				(width 0.1524)
				(type default)
			)
			(layer "F.SilkS")
		)
		(fp_line
			(start -0.67945 -0.305054)
			(end -0.12065 -0.305054)
			(stroke
				(width 0.1)
				(type default)
			)
			(layer "F.Fab")
		)
		(fp_line
			(start -0.67945 0.3048)
			(end -0.67945 -0.305054)
			(stroke
				(width 0.1)
				(type default)
			)
			(layer "F.Fab")
		)
		(fp_line
			(start -0.12065 -0.305054)
			(end -0.12065 -0.2794)
			(stroke
				(width 0.1)
				(type default)
			)
			(layer "F.Fab")
		)
		(fp_line
			(start -0.12065 -0.2794)
			(end 0.12065 -0.2794)
			(stroke
				(width 0.1)
				(type default)
			)
			(layer "F.Fab")
		)
		(fp_line
			(start -0.12065 0.2794)
			(end -0.12065 0.3048)
			(stroke
				(width 0.1)
				(type default)
			)
			(layer "F.Fab")
		)
		(fp_line
			(start -0.12065 0.3048)
			(end -0.67945 0.3048)
			(stroke
				(width 0.1)
				(type default)
			)
			(layer "F.Fab")
		)
		(fp_line
			(start 0.120396 0.2794)
			(end -0.12065 0.2794)
			(stroke
				(width 0.1)
				(type default)
			)
			(layer "F.Fab")
		)
		(fp_line
			(start 0.120396 0.3048)
			(end 0.120396 0.2794)
			(stroke
				(width 0.1)
				(type default)
			)
			(layer "F.Fab")
		)
		(fp_line
			(start 0.12065 -0.3048)
			(end 0.67945 -0.3048)
			(stroke
				(width 0.1)
				(type default)
			)
			(layer "F.Fab")
		)
		(fp_line
			(start 0.12065 -0.2794)
			(end 0.12065 -0.3048)
			(stroke
				(width 0.1)
				(type default)
			)
			(layer "F.Fab")
		)
		(fp_line
			(start 0.67945 -0.3048)
			(end 0.67945 0.3048)
			(stroke
				(width 0.1)
				(type default)
			)
			(layer "F.Fab")
		)
		(fp_line
			(start 0.67945 0.3048)
			(end 0.120396 0.3048)
			(stroke
				(width 0.1)
				(type default)
			)
			(layer "F.Fab")
		)
		(pad "1" smd circle
			(at -0.40005 0)
			(size 0 0)
			(layers "F.Cu" "F.Mask" "F.Paste")
			(net "RST_SMB_NIC5_MUX_ISO_N")
		)
		(pad "2" smd circle
			(at 0.40005 0)
			(size 0 0)
			(layers "F.Cu" "F.Mask" "F.Paste")
			(net "GND")
		)
	)
	(footprint ""
		(layer "F.Cu")
		(at 334.473804 -26.31186 -90)
		(property "Reference" "U411"
			(at -0.10414 -2.433066 90)
			(unlocked yes)
			(layer "F.SilkS")
			(effects
				(font
					(size 0.7874 0.5842)
					(thickness 0.1524)
				)
			)
		)
		(property "Value" ""
			(at 0 0 270)
			(layer "F.Fab")
			(effects
				(font
					(size 1.27 1.27)
				)
			)
		)
		(duplicate_pad_numbers_are_jumpers no)
		(fp_line
			(start -1.949958 1.610106)
			(end -1.949958 -1.610106)
			(stroke
				(width 0.1524)
				(type default)
			)
			(layer "F.SilkS")
		)
		(fp_line
			(start 1.949958 1.610106)
			(end -1.949958 1.610106)
			(stroke
				(width 0.1524)
				(type default)
			)
			(layer "F.SilkS")
		)
		(fp_line
			(start 1.949958 -1.560068)
			(end 1.949958 1.610106)
			(stroke
				(width 0.1524)
				(type default)
			)
			(layer "F.SilkS")
		)
		(fp_line
			(start -1.949958 -1.610106)
			(end 1.949958 -1.610106)
			(stroke
				(width 0.1524)
				(type default)
			)
			(layer "F.SilkS")
		)
		(fp_line
			(start -0.750062 1.560068)
			(end -0.750062 -1.560068)
			(stroke
				(width 0.1)
				(type default)
			)
			(layer "F.Fab")
		)
		(fp_line
			(start 0.750062 1.560068)
			(end -0.750062 1.560068)
			(stroke
				(width 0.1)
				(type default)
			)
			(layer "F.Fab")
		)
		(fp_line
			(start -0.750062 -1.560068)
			(end 0.750062 -1.560068)
			(stroke
				(width 0.1)
				(type default)
			)
			(layer "F.Fab")
		)
		(fp_line
			(start 0.750062 -1.560068)
			(end 0.750062 1.560068)
			(stroke
				(width 0.1)
				(type default)
			)
			(layer "F.Fab")
		)
		(pad "D" smd rect
			(at 1.100074 0 180)
			(size 1.016 1.4224)
			(layers "F.Cu" "F.Mask" "F.Paste")
			(net "SSD11_LED_ISO_N")
		)
		(pad "G" smd rect
			(at -1.100074 -0.94996 180)
			(size 1.016 1.4224)
			(layers "F.Cu" "F.Mask" "F.Paste")
			(net "SSD11_LED_R")
		)
		(pad "S" smd rect
			(at -1.100074 0.94996 180)
			(size 1.016 1.4224)
			(layers "F.Cu" "F.Mask" "F.Paste")
			(net "GND")
		)
	)
	(footprint ""
		(layer "F.Cu")
		(at 142.926308 -350.098614 90)
		(property "Reference" "C2259"
			(at 0 0 90)
			(layer "F.SilkS")
			(hide yes)
			(effects
				(font
					(size 1.27 1.27)
				)
			)
		)
		(property "Value" ""
			(at 0 0 90)
			(layer "F.Fab")
			(effects
				(font
					(size 1.27 1.27)
				)
			)
		)
		(duplicate_pad_numbers_are_jumpers no)
		(fp_line
			(start 0.299974 -0.150114)
			(end 0.299974 0.150114)
			(stroke
				(width 0.1)
				(type default)
			)
			(layer "F.Fab")
		)
		(fp_line
			(start -0.299974 -0.150114)
			(end 0.299974 -0.150114)
			(stroke
				(width 0.1)
				(type default)
			)
			(layer "F.Fab")
		)
		(fp_line
			(start 0.299974 0.150114)
			(end -0.299974 0.150114)
			(stroke
				(width 0.1)
				(type default)
			)
			(layer "F.Fab")
		)
		(fp_line
			(start -0.299974 0.150114)
			(end -0.299974 -0.150114)
			(stroke
				(width 0.1)
				(type default)
			)
			(layer "F.Fab")
		)
		(pad "1" smd rect
			(at -0.2667 0 90)
			(size 0.3048 0.381)
			(layers "F.Cu" "F.Mask" "F.Paste")
			(net "P5E_PEX1_STN5_TX_DP<87>")
		)
		(pad "2" smd rect
			(at 0.2667 0 90)
			(size 0.3048 0.381)
			(layers "F.Cu" "F.Mask" "F.Paste")
			(net "P5E_PEX1_STN5_TX_C_DP<87>")
		)
	)
	(footprint ""
		(layer "F.Cu")
		(at 26.243788 -42.84091)
		(property "Reference" "R505"
			(at 0 0 0)
			(layer "F.SilkS")
			(hide yes)
			(effects
				(font
					(size 1.27 1.27)
				)
			)
		)
		(property "Value" ""
			(at 0 0 0)
			(layer "F.Fab")
			(effects
				(font
					(size 1.27 1.27)
				)
			)
		)
		(duplicate_pad_numbers_are_jumpers no)
		(fp_line
			(start -0.7874 -0.4064)
			(end 0.7874 -0.4064)
			(stroke
				(width 0.1524)
				(type default)
			)
			(layer "F.SilkS")
		)
		(fp_line
			(start -0.7874 0.4064)
			(end -0.7874 -0.4064)
			(stroke
				(width 0.1524)
				(type default)
			)
			(layer "F.SilkS")
		)
		(fp_line
			(start 0.7874 -0.4064)
			(end 0.7874 0.4064)
			(stroke
				(width 0.1524)
				(type default)
			)
			(layer "F.SilkS")
		)
		(fp_line
			(start 0.7874 0.4064)
			(end -0.7874 0.4064)
			(stroke
				(width 0.1524)
				(type default)
			)
			(layer "F.SilkS")
		)
		(fp_line
			(start -0.67945 -0.305054)
			(end -0.12065 -0.305054)
			(stroke
				(width 0.1)
				(type default)
			)
			(layer "F.Fab")
		)
		(fp_line
			(start -0.67945 0.3048)
			(end -0.67945 -0.305054)
			(stroke
				(width 0.1)
				(type default)
			)
			(layer "F.Fab")
		)
		(fp_line
			(start -0.12065 -0.305054)
			(end -0.12065 -0.2794)
			(stroke
				(width 0.1)
				(type default)
			)
			(layer "F.Fab")
		)
		(fp_line
			(start -0.12065 -0.2794)
			(end 0.12065 -0.2794)
			(stroke
				(width 0.1)
				(type default)
			)
			(layer "F.Fab")
		)
		(fp_line
			(start -0.12065 0.2794)
			(end -0.12065 0.3048)
			(stroke
				(width 0.1)
				(type default)
			)
			(layer "F.Fab")
		)
		(fp_line
			(start -0.12065 0.3048)
			(end -0.67945 0.3048)
			(stroke
				(width 0.1)
				(type default)
			)
			(layer "F.Fab")
		)
		(fp_line
			(start 0.120396 0.2794)
			(end -0.12065 0.2794)
			(stroke
				(width 0.1)
				(type default)
			)
			(layer "F.Fab")
		)
		(fp_line
			(start 0.120396 0.3048)
			(end 0.120396 0.2794)
			(stroke
				(width 0.1)
				(type default)
			)
			(layer "F.Fab")
		)
		(fp_line
			(start 0.12065 -0.3048)
			(end 0.67945 -0.3048)
			(stroke
				(width 0.1)
				(type default)
			)
			(layer "F.Fab")
		)
		(fp_line
			(start 0.12065 -0.2794)
			(end 0.12065 -0.3048)
			(stroke
				(width 0.1)
				(type default)
			)
			(layer "F.Fab")
		)
		(fp_line
			(start 0.67945 -0.3048)
			(end 0.67945 0.3048)
			(stroke
				(width 0.1)
				(type default)
			)
			(layer "F.Fab")
		)
		(fp_line
			(start 0.67945 0.3048)
			(end 0.120396 0.3048)
			(stroke
				(width 0.1)
				(type default)
			)
			(layer "F.Fab")
		)
		(pad "1" smd circle
			(at -0.40005 0)
			(size 0 0)
			(layers "F.Cu" "F.Mask" "F.Paste")
			(net "SSD0_ADC_A1")
		)
		(pad "2" smd circle
			(at 0.40005 0)
			(size 0 0)
			(layers "F.Cu" "F.Mask" "F.Paste")
			(net "P3V3_AUX")
		)
	)
	(footprint ""
		(layer "F.Cu")
		(at 214.373968 -72.766682 90)
		(property "Reference" "PR7069"
			(at 0 0 90)
			(layer "F.SilkS")
			(hide yes)
			(effects
				(font
					(size 1.27 1.27)
				)
			)
		)
		(property "Value" ""
			(at 0 0 90)
			(layer "F.Fab")
			(effects
				(font
					(size 1.27 1.27)
				)
			)
		)
		(duplicate_pad_numbers_are_jumpers no)
		(fp_line
			(start 0.7874 -0.4064)
			(end 0.7874 0.4064)
			(stroke
				(width 0.1524)
				(type default)
			)
			(layer "F.SilkS")
		)
		(fp_line
			(start -0.7874 -0.4064)
			(end 0.7874 -0.4064)
			(stroke
				(width 0.1524)
				(type default)
			)
			(layer "F.SilkS")
		)
		(fp_line
			(start 0.7874 0.4064)
			(end -0.7874 0.4064)
			(stroke
				(width 0.1524)
				(type default)
			)
			(layer "F.SilkS")
		)
		(fp_line
			(start -0.7874 0.4064)
			(end -0.7874 -0.4064)
			(stroke
				(width 0.1524)
				(type default)
			)
			(layer "F.SilkS")
		)
		(fp_line
			(start -0.12065 -0.305054)
			(end -0.12065 -0.2794)
			(stroke
				(width 0.1)
				(type default)
			)
			(layer "F.Fab")
		)
		(fp_line
			(start -0.67945 -0.305054)
			(end -0.12065 -0.305054)
			(stroke
				(width 0.1)
				(type default)
			)
			(layer "F.Fab")
		)
		(fp_line
			(start 0.67945 -0.3048)
			(end 0.67945 0.3048)
			(stroke
				(width 0.1)
				(type default)
			)
			(layer "F.Fab")
		)
		(fp_line
			(start 0.12065 -0.3048)
			(end 0.67945 -0.3048)
			(stroke
				(width 0.1)
				(type default)
			)
			(layer "F.Fab")
		)
		(fp_line
			(start 0.12065 -0.2794)
			(end 0.12065 -0.3048)
			(stroke
				(width 0.1)
				(type default)
			)
			(layer "F.Fab")
		)
		(fp_line
			(start -0.12065 -0.2794)
			(end 0.12065 -0.2794)
			(stroke
				(width 0.1)
				(type default)
			)
			(layer "F.Fab")
		)
		(fp_line
			(start 0.120396 0.2794)
			(end -0.12065 0.2794)
			(stroke
				(width 0.1)
				(type default)
			)
			(layer "F.Fab")
		)
		(fp_line
			(start -0.12065 0.2794)
			(end -0.12065 0.3048)
			(stroke
				(width 0.1)
				(type default)
			)
			(layer "F.Fab")
		)
		(fp_line
			(start 0.67945 0.3048)
			(end 0.120396 0.3048)
			(stroke
				(width 0.1)
				(type default)
			)
			(layer "F.Fab")
		)
		(fp_line
			(start 0.120396 0.3048)
			(end 0.120396 0.2794)
			(stroke
				(width 0.1)
				(type default)
			)
			(layer "F.Fab")
		)
		(fp_line
			(start -0.12065 0.3048)
			(end -0.67945 0.3048)
			(stroke
				(width 0.1)
				(type default)
			)
			(layer "F.Fab")
		)
		(fp_line
			(start -0.67945 0.3048)
			(end -0.67945 -0.305054)
			(stroke
				(width 0.1)
				(type default)
			)
			(layer "F.Fab")
		)
		(pad "1" smd circle
			(at -0.40005 0 90)
			(size 0 0)
			(layers "F.Cu" "F.Mask" "F.Paste")
			(net "P12V_SSD7_CO_MODE")
		)
		(pad "2" smd circle
			(at 0.40005 0 90)
			(size 0 0)
			(layers "F.Cu" "F.Mask" "F.Paste")
			(net "GND")
		)
	)
	(footprint ""
		(layer "F.Cu")
		(at 253.730506 -66.32194 -90)
		(property "Reference" "PC866"
			(at 0 0 270)
			(layer "F.SilkS")
			(hide yes)
			(effects
				(font
					(size 1.27 1.27)
				)
			)
		)
		(property "Value" ""
			(at 0 0 270)
			(layer "F.Fab")
			(effects
				(font
					(size 1.27 1.27)
				)
			)
		)
		(duplicate_pad_numbers_are_jumpers no)
		(fp_line
			(start -0.7874 0.4064)
			(end -0.7874 -0.4064)
			(stroke
				(width 0.1524)
				(type default)
			)
			(layer "F.SilkS")
		)
		(fp_line
			(start 0.7874 0.4064)
			(end -0.7874 0.4064)
			(stroke
				(width 0.1524)
				(type default)
			)
			(layer "F.SilkS")
		)
		(fp_line
			(start -0.7874 -0.4064)
			(end 0.7874 -0.4064)
			(stroke
				(width 0.1524)
				(type default)
			)
			(layer "F.SilkS")
		)
		(fp_line
			(start 0.7874 -0.4064)
			(end 0.7874 0.4064)
			(stroke
				(width 0.1524)
				(type default)
			)
			(layer "F.SilkS")
		)
		(fp_line
			(start -0.67945 0.3048)
			(end -0.67945 -0.305054)
			(stroke
				(width 0.1)
				(type default)
			)
			(layer "F.Fab")
		)
		(fp_line
			(start -0.12065 0.3048)
			(end -0.67945 0.3048)
			(stroke
				(width 0.1)
				(type default)
			)
			(layer "F.Fab")
		)
		(fp_line
			(start 0.120396 0.3048)
			(end 0.120396 0.2794)
			(stroke
				(width 0.1)
				(type default)
			)
			(layer "F.Fab")
		)
		(fp_line
			(start 0.67945 0.3048)
			(end 0.120396 0.3048)
			(stroke
				(width 0.1)
				(type default)
			)
			(layer "F.Fab")
		)
		(fp_line
			(start -0.12065 0.2794)
			(end -0.12065 0.3048)
			(stroke
				(width 0.1)
				(type default)
			)
			(layer "F.Fab")
		)
		(fp_line
			(start 0.120396 0.2794)
			(end -0.12065 0.2794)
			(stroke
				(width 0.1)
				(type default)
			)
			(layer "F.Fab")
		)
		(fp_line
			(start -0.12065 -0.2794)
			(end 0.12065 -0.2794)
			(stroke
				(width 0.1)
				(type default)
			)
			(layer "F.Fab")
		)
		(fp_line
			(start 0.12065 -0.2794)
			(end 0.12065 -0.3048)
			(stroke
				(width 0.1)
				(type default)
			)
			(layer "F.Fab")
		)
		(fp_line
			(start 0.12065 -0.3048)
			(end 0.67945 -0.3048)
			(stroke
				(width 0.1)
				(type default)
			)
			(layer "F.Fab")
		)
		(fp_line
			(start 0.67945 -0.3048)
			(end 0.67945 0.3048)
			(stroke
				(width 0.1)
				(type default)
			)
			(layer "F.Fab")
		)
		(fp_line
			(start -0.67945 -0.305054)
			(end -0.12065 -0.305054)
			(stroke
				(width 0.1)
				(type default)
			)
			(layer "F.Fab")
		)
		(fp_line
			(start -0.12065 -0.305054)
			(end -0.12065 -0.2794)
			(stroke
				(width 0.1)
				(type default)
			)
			(layer "F.Fab")
		)
		(pad "1" smd circle
			(at -0.40005 0 270)
			(size 0 0)
			(layers "F.Cu" "F.Mask" "F.Paste")
			(net "P12V_SSD8_CO_DV_DT")
		)
		(pad "2" smd circle
			(at 0.40005 0 270)
			(size 0 0)
			(layers "F.Cu" "F.Mask" "F.Paste")
			(net "GND")
		)
	)
	(footprint ""
		(layer "F.Cu")
		(at 384.54584 -258.463034)
		(property "Reference" "C3567"
			(at 0 0 0)
			(layer "F.SilkS")
			(hide yes)
			(effects
				(font
					(size 1.27 1.27)
				)
			)
		)
		(property "Value" ""
			(at 0 0 0)
			(layer "F.Fab")
			(effects
				(font
					(size 1.27 1.27)
				)
			)
		)
		(duplicate_pad_numbers_are_jumpers no)
		(fp_line
			(start -1.2954 -0.5842)
			(end 1.2954 -0.5842)
			(stroke
				(width 0.1524)
				(type default)
			)
			(layer "F.SilkS")
		)
		(fp_line
			(start -1.2954 0.5842)
			(end -1.2954 -0.5842)
			(stroke
				(width 0.1524)
				(type default)
			)
			(layer "F.SilkS")
		)
		(fp_line
			(start 1.2954 -0.5842)
			(end 1.2954 0.5842)
			(stroke
				(width 0.1524)
				(type default)
			)
			(layer "F.SilkS")
		)
		(fp_line
			(start 1.2954 0.5842)
			(end -1.2954 0.5842)
			(stroke
				(width 0.1524)
				(type default)
			)
			(layer "F.SilkS")
		)
		(fp_line
			(start -1.1938 -0.4064)
			(end -0.8636 -0.4064)
			(stroke
				(width 0.1)
				(type default)
			)
			(layer "F.Fab")
		)
		(fp_line
			(start -1.1938 0.4064)
			(end -1.1938 -0.4064)
			(stroke
				(width 0.1)
				(type default)
			)
			(layer "F.Fab")
		)
		(fp_line
			(start -0.8636 -0.4572)
			(end 0.8636 -0.4572)
			(stroke
				(width 0.1)
				(type default)
			)
			(layer "F.Fab")
		)
		(fp_line
			(start -0.8636 -0.4064)
			(end -0.8636 -0.4572)
			(stroke
				(width 0.1)
				(type default)
			)
			(layer "F.Fab")
		)
		(fp_line
			(start -0.8636 0.4064)
			(end -1.1938 0.4064)
			(stroke
				(width 0.1)
				(type default)
			)
			(layer "F.Fab")
		)
		(fp_line
			(start -0.8636 0.4572)
			(end -0.8636 0.4064)
			(stroke
				(width 0.1)
				(type default)
			)
			(layer "F.Fab")
		)
		(fp_line
			(start 0.8636 -0.4572)
			(end 0.8636 -0.4064)
			(stroke
				(width 0.1)
				(type default)
			)
			(layer "F.Fab")
		)
		(fp_line
			(start 0.8636 -0.4064)
			(end 1.1938 -0.4064)
			(stroke
				(width 0.1)
				(type default)
			)
			(layer "F.Fab")
		)
		(fp_line
			(start 0.8636 0.4064)
			(end 0.8636 0.4572)
			(stroke
				(width 0.1)
				(type default)
			)
			(layer "F.Fab")
		)
		(fp_line
			(start 0.8636 0.4572)
			(end -0.8636 0.4572)
			(stroke
				(width 0.1)
				(type default)
			)
			(layer "F.Fab")
		)
		(fp_line
			(start 1.1938 -0.4064)
			(end 1.1938 0.4064)
			(stroke
				(width 0.1)
				(type default)
			)
			(layer "F.Fab")
		)
		(fp_line
			(start 1.1938 0.4064)
			(end 0.8636 0.4064)
			(stroke
				(width 0.1)
				(type default)
			)
			(layer "F.Fab")
		)
		(pad "1" smd rect
			(at -0.7366 0 270)
			(size 0.7112 0.8128)
			(layers "F.Cu" "F.Mask" "F.Paste")
			(net "PCEPLL5_VDDA18_PEX3")
		)
		(pad "2" smd rect
			(at 0.7366 0 270)
			(size 0.7112 0.8128)
			(layers "F.Cu" "F.Mask" "F.Paste")
			(net "GND")
		)
	)
	(footprint ""
		(layer "F.Cu")
		(at 210.130136 -179.848256 -90)
		(property "Reference" "R5421"
			(at 0 0 270)
			(layer "F.SilkS")
			(hide yes)
			(effects
				(font
					(size 1.27 1.27)
				)
			)
		)
		(property "Value" ""
			(at 0 0 270)
			(layer "F.Fab")
			(effects
				(font
					(size 1.27 1.27)
				)
			)
		)
		(duplicate_pad_numbers_are_jumpers no)
		(fp_line
			(start -0.7874 0.4064)
			(end -0.7874 -0.4064)
			(stroke
				(width 0.1524)
				(type default)
			)
			(layer "F.SilkS")
		)
		(fp_line
			(start 0.7874 0.4064)
			(end -0.7874 0.4064)
			(stroke
				(width 0.1524)
				(type default)
			)
			(layer "F.SilkS")
		)
		(fp_line
			(start -0.7874 -0.4064)
			(end 0.7874 -0.4064)
			(stroke
				(width 0.1524)
				(type default)
			)
			(layer "F.SilkS")
		)
		(fp_line
			(start 0.7874 -0.4064)
			(end 0.7874 0.4064)
			(stroke
				(width 0.1524)
				(type default)
			)
			(layer "F.SilkS")
		)
		(fp_line
			(start -0.67945 0.3048)
			(end -0.67945 -0.305054)
			(stroke
				(width 0.1)
				(type default)
			)
			(layer "F.Fab")
		)
		(fp_line
			(start -0.12065 0.3048)
			(end -0.67945 0.3048)
			(stroke
				(width 0.1)
				(type default)
			)
			(layer "F.Fab")
		)
		(fp_line
			(start 0.120396 0.3048)
			(end 0.120396 0.2794)
			(stroke
				(width 0.1)
				(type default)
			)
			(layer "F.Fab")
		)
		(fp_line
			(start 0.67945 0.3048)
			(end 0.120396 0.3048)
			(stroke
				(width 0.1)
				(type default)
			)
			(layer "F.Fab")
		)
		(fp_line
			(start -0.12065 0.2794)
			(end -0.12065 0.3048)
			(stroke
				(width 0.1)
				(type default)
			)
			(layer "F.Fab")
		)
		(fp_line
			(start 0.120396 0.2794)
			(end -0.12065 0.2794)
			(stroke
				(width 0.1)
				(type default)
			)
			(layer "F.Fab")
		)
		(fp_line
			(start -0.12065 -0.2794)
			(end 0.12065 -0.2794)
			(stroke
				(width 0.1)
				(type default)
			)
			(layer "F.Fab")
		)
		(fp_line
			(start 0.12065 -0.2794)
			(end 0.12065 -0.3048)
			(stroke
				(width 0.1)
				(type default)
			)
			(layer "F.Fab")
		)
		(fp_line
			(start 0.12065 -0.3048)
			(end 0.67945 -0.3048)
			(stroke
				(width 0.1)
				(type default)
			)
			(layer "F.Fab")
		)
		(fp_line
			(start 0.67945 -0.3048)
			(end 0.67945 0.3048)
			(stroke
				(width 0.1)
				(type default)
			)
			(layer "F.Fab")
		)
		(fp_line
			(start -0.67945 -0.305054)
			(end -0.12065 -0.305054)
			(stroke
				(width 0.1)
				(type default)
			)
			(layer "F.Fab")
		)
		(fp_line
			(start -0.12065 -0.305054)
			(end -0.12065 -0.2794)
			(stroke
				(width 0.1)
				(type default)
			)
			(layer "F.Fab")
		)
		(pad "1" smd circle
			(at -0.40005 0 270)
			(size 0 0)
			(layers "F.Cu" "F.Mask" "F.Paste")
			(net "SEL_FLASH_PEX3_BUF_R")
		)
		(pad "2" smd circle
			(at 0.40005 0 270)
			(size 0 0)
			(layers "F.Cu" "F.Mask" "F.Paste")
			(net "P3V3_AUX")
		)
	)
	(footprint ""
		(layer "F.Cu")
		(at 134.366 -285.088584 90)
		(property "Reference" "PC90"
			(at 0 0 90)
			(layer "F.SilkS")
			(hide yes)
			(effects
				(font
					(size 1.27 1.27)
				)
			)
		)
		(property "Value" ""
			(at 0 0 90)
			(layer "F.Fab")
			(effects
				(font
					(size 1.27 1.27)
				)
			)
		)
		(duplicate_pad_numbers_are_jumpers no)
		(fp_line
			(start 0.7874 -0.4064)
			(end 0.7874 0.4064)
			(stroke
				(width 0.1524)
				(type default)
			)
			(layer "F.SilkS")
		)
		(fp_line
			(start -0.7874 -0.4064)
			(end 0.7874 -0.4064)
			(stroke
				(width 0.1524)
				(type default)
			)
			(layer "F.SilkS")
		)
		(fp_line
			(start 0.7874 0.4064)
			(end -0.7874 0.4064)
			(stroke
				(width 0.1524)
				(type default)
			)
			(layer "F.SilkS")
		)
		(fp_line
			(start -0.7874 0.4064)
			(end -0.7874 -0.4064)
			(stroke
				(width 0.1524)
				(type default)
			)
			(layer "F.SilkS")
		)
		(fp_line
			(start -0.12065 -0.305054)
			(end -0.12065 -0.2794)
			(stroke
				(width 0.1)
				(type default)
			)
			(layer "F.Fab")
		)
		(fp_line
			(start -0.67945 -0.305054)
			(end -0.12065 -0.305054)
			(stroke
				(width 0.1)
				(type default)
			)
			(layer "F.Fab")
		)
		(fp_line
			(start 0.67945 -0.3048)
			(end 0.67945 0.3048)
			(stroke
				(width 0.1)
				(type default)
			)
			(layer "F.Fab")
		)
		(fp_line
			(start 0.12065 -0.3048)
			(end 0.67945 -0.3048)
			(stroke
				(width 0.1)
				(type default)
			)
			(layer "F.Fab")
		)
		(fp_line
			(start 0.12065 -0.2794)
			(end 0.12065 -0.3048)
			(stroke
				(width 0.1)
				(type default)
			)
			(layer "F.Fab")
		)
		(fp_line
			(start -0.12065 -0.2794)
			(end 0.12065 -0.2794)
			(stroke
				(width 0.1)
				(type default)
			)
			(layer "F.Fab")
		)
		(fp_line
			(start 0.120396 0.2794)
			(end -0.12065 0.2794)
			(stroke
				(width 0.1)
				(type default)
			)
			(layer "F.Fab")
		)
		(fp_line
			(start -0.12065 0.2794)
			(end -0.12065 0.3048)
			(stroke
				(width 0.1)
				(type default)
			)
			(layer "F.Fab")
		)
		(fp_line
			(start 0.67945 0.3048)
			(end 0.120396 0.3048)
			(stroke
				(width 0.1)
				(type default)
			)
			(layer "F.Fab")
		)
		(fp_line
			(start 0.120396 0.3048)
			(end 0.120396 0.2794)
			(stroke
				(width 0.1)
				(type default)
			)
			(layer "F.Fab")
		)
		(fp_line
			(start -0.12065 0.3048)
			(end -0.67945 0.3048)
			(stroke
				(width 0.1)
				(type default)
			)
			(layer "F.Fab")
		)
		(fp_line
			(start -0.67945 0.3048)
			(end -0.67945 -0.305054)
			(stroke
				(width 0.1)
				(type default)
			)
			(layer "F.Fab")
		)
		(pad "1" smd circle
			(at -0.40005 0 90)
			(size 0 0)
			(layers "F.Cu" "F.Mask" "F.Paste")
			(net "P0V8_PEX1_PVCC")
		)
		(pad "2" smd circle
			(at 0.40005 0 90)
			(size 0 0)
			(layers "F.Cu" "F.Mask" "F.Paste")
			(net "GND")
		)
	)
	(footprint ""
		(layer "F.Cu")
		(at 214.587582 -25.342342 -90)
		(property "Reference" "R432"
			(at 0 0 270)
			(layer "F.SilkS")
			(hide yes)
			(effects
				(font
					(size 1.27 1.27)
				)
			)
		)
		(property "Value" ""
			(at 0 0 270)
			(layer "F.Fab")
			(effects
				(font
					(size 1.27 1.27)
				)
			)
		)
		(duplicate_pad_numbers_are_jumpers no)
		(fp_line
			(start -0.7874 0.4064)
			(end -0.7874 -0.4064)
			(stroke
				(width 0.1524)
				(type default)
			)
			(layer "F.SilkS")
		)
		(fp_line
			(start 0.7874 0.4064)
			(end -0.7874 0.4064)
			(stroke
				(width 0.1524)
				(type default)
			)
			(layer "F.SilkS")
		)
		(fp_line
			(start -0.7874 -0.4064)
			(end 0.7874 -0.4064)
			(stroke
				(width 0.1524)
				(type default)
			)
			(layer "F.SilkS")
		)
		(fp_line
			(start 0.7874 -0.4064)
			(end 0.7874 0.4064)
			(stroke
				(width 0.1524)
				(type default)
			)
			(layer "F.SilkS")
		)
		(fp_line
			(start -0.67945 0.3048)
			(end -0.67945 -0.305054)
			(stroke
				(width 0.1)
				(type default)
			)
			(layer "F.Fab")
		)
		(fp_line
			(start -0.12065 0.3048)
			(end -0.67945 0.3048)
			(stroke
				(width 0.1)
				(type default)
			)
			(layer "F.Fab")
		)
		(fp_line
			(start 0.120396 0.3048)
			(end 0.120396 0.2794)
			(stroke
				(width 0.1)
				(type default)
			)
			(layer "F.Fab")
		)
		(fp_line
			(start 0.67945 0.3048)
			(end 0.120396 0.3048)
			(stroke
				(width 0.1)
				(type default)
			)
			(layer "F.Fab")
		)
		(fp_line
			(start -0.12065 0.2794)
			(end -0.12065 0.3048)
			(stroke
				(width 0.1)
				(type default)
			)
			(layer "F.Fab")
		)
		(fp_line
			(start 0.120396 0.2794)
			(end -0.12065 0.2794)
			(stroke
				(width 0.1)
				(type default)
			)
			(layer "F.Fab")
		)
		(fp_line
			(start -0.12065 -0.2794)
			(end 0.12065 -0.2794)
			(stroke
				(width 0.1)
				(type default)
			)
			(layer "F.Fab")
		)
		(fp_line
			(start 0.12065 -0.2794)
			(end 0.12065 -0.3048)
			(stroke
				(width 0.1)
				(type default)
			)
			(layer "F.Fab")
		)
		(fp_line
			(start 0.12065 -0.3048)
			(end 0.67945 -0.3048)
			(stroke
				(width 0.1)
				(type default)
			)
			(layer "F.Fab")
		)
		(fp_line
			(start 0.67945 -0.3048)
			(end 0.67945 0.3048)
			(stroke
				(width 0.1)
				(type default)
			)
			(layer "F.Fab")
		)
		(fp_line
			(start -0.67945 -0.305054)
			(end -0.12065 -0.305054)
			(stroke
				(width 0.1)
				(type default)
			)
			(layer "F.Fab")
		)
		(fp_line
			(start -0.12065 -0.305054)
			(end -0.12065 -0.2794)
			(stroke
				(width 0.1)
				(type default)
			)
			(layer "F.Fab")
		)
		(pad "1" smd circle
			(at -0.40005 0 270)
			(size 0 0)
			(layers "F.Cu" "F.Mask" "F.Paste")
			(net "GND")
		)
		(pad "2" smd circle
			(at 0.40005 0 270)
			(size 0 0)
			(layers "F.Cu" "F.Mask" "F.Paste")
			(net "DUALPORT_N_SSD7")
		)
	)
	(footprint ""
		(layer "F.Cu")
		(at 124.311156 -61.386974)
		(property "Reference" "R4483"
			(at 0 0 0)
			(layer "F.SilkS")
			(hide yes)
			(effects
				(font
					(size 1.27 1.27)
				)
			)
		)
		(property "Value" ""
			(at 0 0 0)
			(layer "F.Fab")
			(effects
				(font
					(size 1.27 1.27)
				)
			)
		)
		(duplicate_pad_numbers_are_jumpers no)
		(fp_line
			(start -0.7874 -0.4064)
			(end 0.7874 -0.4064)
			(stroke
				(width 0.1524)
				(type default)
			)
			(layer "F.SilkS")
		)
		(fp_line
			(start -0.7874 0.4064)
			(end -0.7874 -0.4064)
			(stroke
				(width 0.1524)
				(type default)
			)
			(layer "F.SilkS")
		)
		(fp_line
			(start 0.7874 -0.4064)
			(end 0.7874 0.4064)
			(stroke
				(width 0.1524)
				(type default)
			)
			(layer "F.SilkS")
		)
		(fp_line
			(start 0.7874 0.4064)
			(end -0.7874 0.4064)
			(stroke
				(width 0.1524)
				(type default)
			)
			(layer "F.SilkS")
		)
		(fp_line
			(start -0.67945 -0.305054)
			(end -0.12065 -0.305054)
			(stroke
				(width 0.1)
				(type default)
			)
			(layer "F.Fab")
		)
		(fp_line
			(start -0.67945 0.3048)
			(end -0.67945 -0.305054)
			(stroke
				(width 0.1)
				(type default)
			)
			(layer "F.Fab")
		)
		(fp_line
			(start -0.12065 -0.305054)
			(end -0.12065 -0.2794)
			(stroke
				(width 0.1)
				(type default)
			)
			(layer "F.Fab")
		)
		(fp_line
			(start -0.12065 -0.2794)
			(end 0.12065 -0.2794)
			(stroke
				(width 0.1)
				(type default)
			)
			(layer "F.Fab")
		)
		(fp_line
			(start -0.12065 0.2794)
			(end -0.12065 0.3048)
			(stroke
				(width 0.1)
				(type default)
			)
			(layer "F.Fab")
		)
		(fp_line
			(start -0.12065 0.3048)
			(end -0.67945 0.3048)
			(stroke
				(width 0.1)
				(type default)
			)
			(layer "F.Fab")
		)
		(fp_line
			(start 0.120396 0.2794)
			(end -0.12065 0.2794)
			(stroke
				(width 0.1)
				(type default)
			)
			(layer "F.Fab")
		)
		(fp_line
			(start 0.120396 0.3048)
			(end 0.120396 0.2794)
			(stroke
				(width 0.1)
				(type default)
			)
			(layer "F.Fab")
		)
		(fp_line
			(start 0.12065 -0.3048)
			(end 0.67945 -0.3048)
			(stroke
				(width 0.1)
				(type default)
			)
			(layer "F.Fab")
		)
		(fp_line
			(start 0.12065 -0.2794)
			(end 0.12065 -0.3048)
			(stroke
				(width 0.1)
				(type default)
			)
			(layer "F.Fab")
		)
		(fp_line
			(start 0.67945 -0.3048)
			(end 0.67945 0.3048)
			(stroke
				(width 0.1)
				(type default)
			)
			(layer "F.Fab")
		)
		(fp_line
			(start 0.67945 0.3048)
			(end 0.120396 0.3048)
			(stroke
				(width 0.1)
				(type default)
			)
			(layer "F.Fab")
		)
		(pad "1" smd circle
			(at -0.40005 0)
			(size 0 0)
			(layers "F.Cu" "F.Mask" "F.Paste")
			(net "PWRGD_P3V3_SSD4")
		)
		(pad "2" smd circle
			(at 0.40005 0)
			(size 0 0)
			(layers "F.Cu" "F.Mask" "F.Paste")
			(net "PWRGD_P3V3_SSD4_R")
		)
	)
	(footprint ""
		(layer "F.Cu")
		(at 16.785336 -275.248624)
		(property "Reference" "R772"
			(at 0 0 0)
			(layer "F.SilkS")
			(hide yes)
			(effects
				(font
					(size 1.27 1.27)
				)
			)
		)
		(property "Value" ""
			(at 0 0 0)
			(layer "F.Fab")
			(effects
				(font
					(size 1.27 1.27)
				)
			)
		)
		(duplicate_pad_numbers_are_jumpers no)
		(fp_line
			(start -0.7874 -0.4064)
			(end 0.7874 -0.4064)
			(stroke
				(width 0.1524)
				(type default)
			)
			(layer "F.SilkS")
		)
		(fp_line
			(start -0.7874 0.4064)
			(end -0.7874 -0.4064)
			(stroke
				(width 0.1524)
				(type default)
			)
			(layer "F.SilkS")
		)
		(fp_line
			(start 0.7874 -0.4064)
			(end 0.7874 0.4064)
			(stroke
				(width 0.1524)
				(type default)
			)
			(layer "F.SilkS")
		)
		(fp_line
			(start 0.7874 0.4064)
			(end -0.7874 0.4064)
			(stroke
				(width 0.1524)
				(type default)
			)
			(layer "F.SilkS")
		)
		(fp_line
			(start -0.67945 -0.305054)
			(end -0.12065 -0.305054)
			(stroke
				(width 0.1)
				(type default)
			)
			(layer "F.Fab")
		)
		(fp_line
			(start -0.67945 0.3048)
			(end -0.67945 -0.305054)
			(stroke
				(width 0.1)
				(type default)
			)
			(layer "F.Fab")
		)
		(fp_line
			(start -0.12065 -0.305054)
			(end -0.12065 -0.2794)
			(stroke
				(width 0.1)
				(type default)
			)
			(layer "F.Fab")
		)
		(fp_line
			(start -0.12065 -0.2794)
			(end 0.12065 -0.2794)
			(stroke
				(width 0.1)
				(type default)
			)
			(layer "F.Fab")
		)
		(fp_line
			(start -0.12065 0.2794)
			(end -0.12065 0.3048)
			(stroke
				(width 0.1)
				(type default)
			)
			(layer "F.Fab")
		)
		(fp_line
			(start -0.12065 0.3048)
			(end -0.67945 0.3048)
			(stroke
				(width 0.1)
				(type default)
			)
			(layer "F.Fab")
		)
		(fp_line
			(start 0.120396 0.2794)
			(end -0.12065 0.2794)
			(stroke
				(width 0.1)
				(type default)
			)
			(layer "F.Fab")
		)
		(fp_line
			(start 0.120396 0.3048)
			(end 0.120396 0.2794)
			(stroke
				(width 0.1)
				(type default)
			)
			(layer "F.Fab")
		)
		(fp_line
			(start 0.12065 -0.3048)
			(end 0.67945 -0.3048)
			(stroke
				(width 0.1)
				(type default)
			)
			(layer "F.Fab")
		)
		(fp_line
			(start 0.12065 -0.2794)
			(end 0.12065 -0.3048)
			(stroke
				(width 0.1)
				(type default)
			)
			(layer "F.Fab")
		)
		(fp_line
			(start 0.67945 -0.3048)
			(end 0.67945 0.3048)
			(stroke
				(width 0.1)
				(type default)
			)
			(layer "F.Fab")
		)
		(fp_line
			(start 0.67945 0.3048)
			(end 0.120396 0.3048)
			(stroke
				(width 0.1)
				(type default)
			)
			(layer "F.Fab")
		)
		(pad "1" smd circle
			(at -0.40005 0)
			(size 0 0)
			(layers "F.Cu" "F.Mask" "F.Paste")
			(net "PEX0_P1V25_ADC_ALERT_N")
		)
		(pad "2" smd circle
			(at 0.40005 0)
			(size 0 0)
			(layers "F.Cu" "F.Mask" "F.Paste")
			(net "PEX_ADC_ALERT_N")
		)
	)
	(footprint ""
		(layer "F.Cu")
		(at 276.820122 -15.649956 180)
		(property "Reference" "H120"
			(at -1.255776 2.800096 0)
			(unlocked yes)
			(layer "B.SilkS")
			(effects
				(font
					(size 0.7874 0.5842)
					(thickness 0.1524)
				)
				(justify left mirror)
			)
		)
		(property "Value" ""
			(at 0 0 180)
			(layer "F.Fab")
			(effects
				(font
					(size 1.27 1.27)
				)
			)
		)
		(duplicate_pad_numbers_are_jumpers no)
		(pad "1" thru_hole rect
			(at 0 0 180)
			(size 4.2164 5.0038)
			(drill 2.0066
				(offset 0.099822 0)
			)
			(layers "*.Cu" "*.Mask")
			(remove_unused_layers no)
			(net "Net_8543")
			(clearance -0.8509)
			(padstack
				(mode front_inner_back)
				(layer "Inner"
					(shape circle)
					(size 4.0132 4.0132)
					(clearance -0.7493)
				)
				(layer "B.Cu"
					(shape circle)
					(size 4.0132 4.0132)
					(clearance -0.7493)
				)
			)
		)
	)
	(footprint ""
		(layer "F.Cu")
		(at 474.236288 -552.440348 180)
		(property "Reference" "J43_OTH"
			(at -3.2385 -1.402334 0)
			(unlocked yes)
			(layer "B.SilkS")
			(effects
				(font
					(size 0.7874 0.5842)
					(thickness 0.1524)
				)
				(justify mirror)
			)
		)
		(property "Value" ""
			(at 0 0 180)
			(layer "F.Fab")
			(effects
				(font
					(size 1.27 1.27)
				)
			)
		)
		(duplicate_pad_numbers_are_jumpers no)
		(pad "1" thru_hole circle
			(at 0 0 180)
			(size 0.4572 0.4572)
			(drill 0.2032)
			(layers "*.Cu" "*.Mask")
			(remove_unused_layers no)
			(net "Net_9093")
			(clearance 0.127)
			(thermal_gap 0.127)
			(padstack
				(mode front_inner_back)
				(layer "Inner"
					(shape circle)
					(size 0.4572 0.4572)
					(clearance 0.127)
				)
				(layer "B.Cu"
					(shape circle)
					(size 0.508 0.508)
					(clearance 0.1016)
				)
			)
		)
	)
	(footprint ""
		(layer "F.Cu")
		(at 162.773106 -22.867366 90)
		(property "Reference" "C3907"
			(at 0 0 90)
			(layer "F.SilkS")
			(hide yes)
			(effects
				(font
					(size 1.27 1.27)
				)
			)
		)
		(property "Value" ""
			(at 0 0 90)
			(layer "F.Fab")
			(effects
				(font
					(size 1.27 1.27)
				)
			)
		)
		(duplicate_pad_numbers_are_jumpers no)
		(fp_line
			(start 0.7874 -0.4064)
			(end 0.7874 0.4064)
			(stroke
				(width 0.1524)
				(type default)
			)
			(layer "F.SilkS")
		)
		(fp_line
			(start -0.7874 -0.4064)
			(end 0.7874 -0.4064)
			(stroke
				(width 0.1524)
				(type default)
			)
			(layer "F.SilkS")
		)
		(fp_line
			(start 0.7874 0.4064)
			(end -0.7874 0.4064)
			(stroke
				(width 0.1524)
				(type default)
			)
			(layer "F.SilkS")
		)
		(fp_line
			(start -0.7874 0.4064)
			(end -0.7874 -0.4064)
			(stroke
				(width 0.1524)
				(type default)
			)
			(layer "F.SilkS")
		)
		(fp_line
			(start -0.12065 -0.305054)
			(end -0.12065 -0.2794)
			(stroke
				(width 0.1)
				(type default)
			)
			(layer "F.Fab")
		)
		(fp_line
			(start -0.67945 -0.305054)
			(end -0.12065 -0.305054)
			(stroke
				(width 0.1)
				(type default)
			)
			(layer "F.Fab")
		)
		(fp_line
			(start 0.67945 -0.3048)
			(end 0.67945 0.3048)
			(stroke
				(width 0.1)
				(type default)
			)
			(layer "F.Fab")
		)
		(fp_line
			(start 0.12065 -0.3048)
			(end 0.67945 -0.3048)
			(stroke
				(width 0.1)
				(type default)
			)
			(layer "F.Fab")
		)
		(fp_line
			(start 0.12065 -0.2794)
			(end 0.12065 -0.3048)
			(stroke
				(width 0.1)
				(type default)
			)
			(layer "F.Fab")
		)
		(fp_line
			(start -0.12065 -0.2794)
			(end 0.12065 -0.2794)
			(stroke
				(width 0.1)
				(type default)
			)
			(layer "F.Fab")
		)
		(fp_line
			(start 0.120396 0.2794)
			(end -0.12065 0.2794)
			(stroke
				(width 0.1)
				(type default)
			)
			(layer "F.Fab")
		)
		(fp_line
			(start -0.12065 0.2794)
			(end -0.12065 0.3048)
			(stroke
				(width 0.1)
				(type default)
			)
			(layer "F.Fab")
		)
		(fp_line
			(start 0.67945 0.3048)
			(end 0.120396 0.3048)
			(stroke
				(width 0.1)
				(type default)
			)
			(layer "F.Fab")
		)
		(fp_line
			(start 0.120396 0.3048)
			(end 0.120396 0.2794)
			(stroke
				(width 0.1)
				(type default)
			)
			(layer "F.Fab")
		)
		(fp_line
			(start -0.12065 0.3048)
			(end -0.67945 0.3048)
			(stroke
				(width 0.1)
				(type default)
			)
			(layer "F.Fab")
		)
		(fp_line
			(start -0.67945 0.3048)
			(end -0.67945 -0.305054)
			(stroke
				(width 0.1)
				(type default)
			)
			(layer "F.Fab")
		)
		(pad "1" smd circle
			(at -0.40005 0 90)
			(size 0 0)
			(layers "F.Cu" "F.Mask" "F.Paste")
			(net "P12V_SSD5")
		)
		(pad "2" smd circle
			(at 0.40005 0 90)
			(size 0 0)
			(layers "F.Cu" "F.Mask" "F.Paste")
			(net "GND")
		)
	)
	(footprint ""
		(layer "F.Cu")
		(at 319.609724 -356.244906 90)
		(property "Reference" "C558"
			(at 0 0 90)
			(layer "F.SilkS")
			(hide yes)
			(effects
				(font
					(size 1.27 1.27)
				)
			)
		)
		(property "Value" ""
			(at 0 0 90)
			(layer "F.Fab")
			(effects
				(font
					(size 1.27 1.27)
				)
			)
		)
		(duplicate_pad_numbers_are_jumpers no)
		(fp_line
			(start 0.299974 -0.150114)
			(end 0.299974 0.150114)
			(stroke
				(width 0.1)
				(type default)
			)
			(layer "F.Fab")
		)
		(fp_line
			(start -0.299974 -0.150114)
			(end 0.299974 -0.150114)
			(stroke
				(width 0.1)
				(type default)
			)
			(layer "F.Fab")
		)
		(fp_line
			(start 0.299974 0.150114)
			(end -0.299974 0.150114)
			(stroke
				(width 0.1)
				(type default)
			)
			(layer "F.Fab")
		)
		(fp_line
			(start -0.299974 0.150114)
			(end -0.299974 -0.150114)
			(stroke
				(width 0.1)
				(type default)
			)
			(layer "F.Fab")
		)
		(pad "1" smd rect
			(at -0.2667 0 90)
			(size 0.3048 0.381)
			(layers "F.Cu" "F.Mask" "F.Paste")
			(net "P5E_PEX2_STN6_TX_DN<108>")
		)
		(pad "2" smd rect
			(at 0.2667 0 90)
			(size 0.3048 0.381)
			(layers "F.Cu" "F.Mask" "F.Paste")
			(net "P5E_PEX2_STN6_TX_C_DN<108>")
		)
	)
	(footprint ""
		(layer "F.Cu")
		(at 264.611358 -296.445432 -90)
		(property "Reference" "R4578"
			(at 0 0 270)
			(layer "F.SilkS")
			(hide yes)
			(effects
				(font
					(size 1.27 1.27)
				)
			)
		)
		(property "Value" ""
			(at 0 0 270)
			(layer "F.Fab")
			(effects
				(font
					(size 1.27 1.27)
				)
			)
		)
		(duplicate_pad_numbers_are_jumpers no)
		(fp_line
			(start -0.7874 0.4064)
			(end -0.7874 -0.4064)
			(stroke
				(width 0.1524)
				(type default)
			)
			(layer "F.SilkS")
		)
		(fp_line
			(start 0.7874 0.4064)
			(end -0.7874 0.4064)
			(stroke
				(width 0.1524)
				(type default)
			)
			(layer "F.SilkS")
		)
		(fp_line
			(start -0.7874 -0.4064)
			(end 0.7874 -0.4064)
			(stroke
				(width 0.1524)
				(type default)
			)
			(layer "F.SilkS")
		)
		(fp_line
			(start 0.7874 -0.4064)
			(end 0.7874 0.4064)
			(stroke
				(width 0.1524)
				(type default)
			)
			(layer "F.SilkS")
		)
		(fp_line
			(start -0.67945 0.3048)
			(end -0.67945 -0.305054)
			(stroke
				(width 0.1)
				(type default)
			)
			(layer "F.Fab")
		)
		(fp_line
			(start -0.12065 0.3048)
			(end -0.67945 0.3048)
			(stroke
				(width 0.1)
				(type default)
			)
			(layer "F.Fab")
		)
		(fp_line
			(start 0.120396 0.3048)
			(end 0.120396 0.2794)
			(stroke
				(width 0.1)
				(type default)
			)
			(layer "F.Fab")
		)
		(fp_line
			(start 0.67945 0.3048)
			(end 0.120396 0.3048)
			(stroke
				(width 0.1)
				(type default)
			)
			(layer "F.Fab")
		)
		(fp_line
			(start -0.12065 0.2794)
			(end -0.12065 0.3048)
			(stroke
				(width 0.1)
				(type default)
			)
			(layer "F.Fab")
		)
		(fp_line
			(start 0.120396 0.2794)
			(end -0.12065 0.2794)
			(stroke
				(width 0.1)
				(type default)
			)
			(layer "F.Fab")
		)
		(fp_line
			(start -0.12065 -0.2794)
			(end 0.12065 -0.2794)
			(stroke
				(width 0.1)
				(type default)
			)
			(layer "F.Fab")
		)
		(fp_line
			(start 0.12065 -0.2794)
			(end 0.12065 -0.3048)
			(stroke
				(width 0.1)
				(type default)
			)
			(layer "F.Fab")
		)
		(fp_line
			(start 0.12065 -0.3048)
			(end 0.67945 -0.3048)
			(stroke
				(width 0.1)
				(type default)
			)
			(layer "F.Fab")
		)
		(fp_line
			(start 0.67945 -0.3048)
			(end 0.67945 0.3048)
			(stroke
				(width 0.1)
				(type default)
			)
			(layer "F.Fab")
		)
		(fp_line
			(start -0.67945 -0.305054)
			(end -0.12065 -0.305054)
			(stroke
				(width 0.1)
				(type default)
			)
			(layer "F.Fab")
		)
		(fp_line
			(start -0.12065 -0.305054)
			(end -0.12065 -0.2794)
			(stroke
				(width 0.1)
				(type default)
			)
			(layer "F.Fab")
		)
		(pad "1" smd circle
			(at -0.40005 0 270)
			(size 0 0)
			(layers "F.Cu" "F.Mask" "F.Paste")
			(net "PCEPLL0_VDDA18_PEX2")
		)
		(pad "2" smd circle
			(at 0.40005 0 270)
			(size 0 0)
			(layers "F.Cu" "F.Mask" "F.Paste")
			(net "PCEPLL0_VDDA18_PEX2_R")
		)
	)
	(footprint ""
		(layer "F.Cu")
		(at 365.92764 -308.397148 -90)
		(property "Reference" "C4361"
			(at 0 0 270)
			(layer "F.SilkS")
			(hide yes)
			(effects
				(font
					(size 1.27 1.27)
				)
			)
		)
		(property "Value" ""
			(at 0 0 270)
			(layer "F.Fab")
			(effects
				(font
					(size 1.27 1.27)
				)
			)
		)
		(duplicate_pad_numbers_are_jumpers no)
		(fp_line
			(start -1.2954 0.5842)
			(end -1.2954 -0.5842)
			(stroke
				(width 0.1524)
				(type default)
			)
			(layer "F.SilkS")
		)
		(fp_line
			(start 1.2954 0.5842)
			(end -1.2954 0.5842)
			(stroke
				(width 0.1524)
				(type default)
			)
			(layer "F.SilkS")
		)
		(fp_line
			(start -1.2954 -0.5842)
			(end 1.2954 -0.5842)
			(stroke
				(width 0.1524)
				(type default)
			)
			(layer "F.SilkS")
		)
		(fp_line
			(start 1.2954 -0.5842)
			(end 1.2954 0.5842)
			(stroke
				(width 0.1524)
				(type default)
			)
			(layer "F.SilkS")
		)
		(fp_line
			(start -0.8636 0.4572)
			(end -0.8636 0.4064)
			(stroke
				(width 0.1)
				(type default)
			)
			(layer "F.Fab")
		)
		(fp_line
			(start 0.8636 0.4572)
			(end -0.8636 0.4572)
			(stroke
				(width 0.1)
				(type default)
			)
			(layer "F.Fab")
		)
		(fp_line
			(start -1.1938 0.4064)
			(end -1.1938 -0.4064)
			(stroke
				(width 0.1)
				(type default)
			)
			(layer "F.Fab")
		)
		(fp_line
			(start -0.8636 0.4064)
			(end -1.1938 0.4064)
			(stroke
				(width 0.1)
				(type default)
			)
			(layer "F.Fab")
		)
		(fp_line
			(start 0.8636 0.4064)
			(end 0.8636 0.4572)
			(stroke
				(width 0.1)
				(type default)
			)
			(layer "F.Fab")
		)
		(fp_line
			(start 1.1938 0.4064)
			(end 0.8636 0.4064)
			(stroke
				(width 0.1)
				(type default)
			)
			(layer "F.Fab")
		)
		(fp_line
			(start -1.1938 -0.4064)
			(end -0.8636 -0.4064)
			(stroke
				(width 0.1)
				(type default)
			)
			(layer "F.Fab")
		)
		(fp_line
			(start -0.8636 -0.4064)
			(end -0.8636 -0.4572)
			(stroke
				(width 0.1)
				(type default)
			)
			(layer "F.Fab")
		)
		(fp_line
			(start 0.8636 -0.4064)
			(end 1.1938 -0.4064)
			(stroke
				(width 0.1)
				(type default)
			)
			(layer "F.Fab")
		)
		(fp_line
			(start 1.1938 -0.4064)
			(end 1.1938 0.4064)
			(stroke
				(width 0.1)
				(type default)
			)
			(layer "F.Fab")
		)
		(fp_line
			(start -0.8636 -0.4572)
			(end 0.8636 -0.4572)
			(stroke
				(width 0.1)
				(type default)
			)
			(layer "F.Fab")
		)
		(fp_line
			(start 0.8636 -0.4572)
			(end 0.8636 -0.4064)
			(stroke
				(width 0.1)
				(type default)
			)
			(layer "F.Fab")
		)
		(pad "1" smd rect
			(at -0.7366 0 180)
			(size 0.7112 0.8128)
			(layers "F.Cu" "F.Mask" "F.Paste")
			(net "P0V8_PEX3")
		)
		(pad "2" smd rect
			(at 0.7366 0 180)
			(size 0.7112 0.8128)
			(layers "F.Cu" "F.Mask" "F.Paste")
			(net "GND")
		)
	)
	(footprint ""
		(layer "F.Cu")
		(at 336.042 -167.005 180)
		(property "Reference" "R4742"
			(at 0 0 180)
			(layer "F.SilkS")
			(hide yes)
			(effects
				(font
					(size 1.27 1.27)
				)
			)
		)
		(property "Value" ""
			(at 0 0 180)
			(layer "F.Fab")
			(effects
				(font
					(size 1.27 1.27)
				)
			)
		)
		(duplicate_pad_numbers_are_jumpers no)
		(fp_line
			(start 0.7874 0.4064)
			(end -0.7874 0.4064)
			(stroke
				(width 0.1524)
				(type default)
			)
			(layer "F.SilkS")
		)
		(fp_line
			(start 0.7874 -0.4064)
			(end 0.7874 0.4064)
			(stroke
				(width 0.1524)
				(type default)
			)
			(layer "F.SilkS")
		)
		(fp_line
			(start -0.7874 0.4064)
			(end -0.7874 -0.4064)
			(stroke
				(width 0.1524)
				(type default)
			)
			(layer "F.SilkS")
		)
		(fp_line
			(start -0.7874 -0.4064)
			(end 0.7874 -0.4064)
			(stroke
				(width 0.1524)
				(type default)
			)
			(layer "F.SilkS")
		)
		(fp_line
			(start 0.67945 0.3048)
			(end 0.120396 0.3048)
			(stroke
				(width 0.1)
				(type default)
			)
			(layer "F.Fab")
		)
		(fp_line
			(start 0.67945 -0.3048)
			(end 0.67945 0.3048)
			(stroke
				(width 0.1)
				(type default)
			)
			(layer "F.Fab")
		)
		(fp_line
			(start 0.12065 -0.2794)
			(end 0.12065 -0.3048)
			(stroke
				(width 0.1)
				(type default)
			)
			(layer "F.Fab")
		)
		(fp_line
			(start 0.12065 -0.3048)
			(end 0.67945 -0.3048)
			(stroke
				(width 0.1)
				(type default)
			)
			(layer "F.Fab")
		)
		(fp_line
			(start 0.120396 0.3048)
			(end 0.120396 0.2794)
			(stroke
				(width 0.1)
				(type default)
			)
			(layer "F.Fab")
		)
		(fp_line
			(start 0.120396 0.2794)
			(end -0.12065 0.2794)
			(stroke
				(width 0.1)
				(type default)
			)
			(layer "F.Fab")
		)
		(fp_line
			(start -0.12065 0.3048)
			(end -0.67945 0.3048)
			(stroke
				(width 0.1)
				(type default)
			)
			(layer "F.Fab")
		)
		(fp_line
			(start -0.12065 0.2794)
			(end -0.12065 0.3048)
			(stroke
				(width 0.1)
				(type default)
			)
			(layer "F.Fab")
		)
		(fp_line
			(start -0.12065 -0.2794)
			(end 0.12065 -0.2794)
			(stroke
				(width 0.1)
				(type default)
			)
			(layer "F.Fab")
		)
		(fp_line
			(start -0.12065 -0.305054)
			(end -0.12065 -0.2794)
			(stroke
				(width 0.1)
				(type default)
			)
			(layer "F.Fab")
		)
		(fp_line
			(start -0.67945 0.3048)
			(end -0.67945 -0.305054)
			(stroke
				(width 0.1)
				(type default)
			)
			(layer "F.Fab")
		)
		(fp_line
			(start -0.67945 -0.305054)
			(end -0.12065 -0.305054)
			(stroke
				(width 0.1)
				(type default)
			)
			(layer "F.Fab")
		)
		(pad "1" smd circle
			(at -0.40005 0 180)
			(size 0 0)
			(layers "F.Cu" "F.Mask" "F.Paste")
			(net "SSD11_PEX_PWR_EN_R")
		)
		(pad "2" smd circle
			(at 0.40005 0 180)
			(size 0 0)
			(layers "F.Cu" "F.Mask" "F.Paste")
			(net "GND")
		)
	)
	(footprint ""
		(layer "F.Cu")
		(at 79.12608 -37.9349 90)
		(property "Reference" "R5549"
			(at 0 0 90)
			(layer "F.SilkS")
			(hide yes)
			(effects
				(font
					(size 1.27 1.27)
				)
			)
		)
		(property "Value" ""
			(at 0 0 90)
			(layer "F.Fab")
			(effects
				(font
					(size 1.27 1.27)
				)
			)
		)
		(duplicate_pad_numbers_are_jumpers no)
		(fp_line
			(start 0.7874 -0.4064)
			(end 0.7874 0.4064)
			(stroke
				(width 0.1524)
				(type default)
			)
			(layer "F.SilkS")
		)
		(fp_line
			(start -0.7874 -0.4064)
			(end 0.7874 -0.4064)
			(stroke
				(width 0.1524)
				(type default)
			)
			(layer "F.SilkS")
		)
		(fp_line
			(start 0.7874 0.4064)
			(end -0.7874 0.4064)
			(stroke
				(width 0.1524)
				(type default)
			)
			(layer "F.SilkS")
		)
		(fp_line
			(start -0.7874 0.4064)
			(end -0.7874 -0.4064)
			(stroke
				(width 0.1524)
				(type default)
			)
			(layer "F.SilkS")
		)
		(fp_line
			(start -0.12065 -0.305054)
			(end -0.12065 -0.2794)
			(stroke
				(width 0.1)
				(type default)
			)
			(layer "F.Fab")
		)
		(fp_line
			(start -0.67945 -0.305054)
			(end -0.12065 -0.305054)
			(stroke
				(width 0.1)
				(type default)
			)
			(layer "F.Fab")
		)
		(fp_line
			(start 0.67945 -0.3048)
			(end 0.67945 0.3048)
			(stroke
				(width 0.1)
				(type default)
			)
			(layer "F.Fab")
		)
		(fp_line
			(start 0.12065 -0.3048)
			(end 0.67945 -0.3048)
			(stroke
				(width 0.1)
				(type default)
			)
			(layer "F.Fab")
		)
		(fp_line
			(start 0.12065 -0.2794)
			(end 0.12065 -0.3048)
			(stroke
				(width 0.1)
				(type default)
			)
			(layer "F.Fab")
		)
		(fp_line
			(start -0.12065 -0.2794)
			(end 0.12065 -0.2794)
			(stroke
				(width 0.1)
				(type default)
			)
			(layer "F.Fab")
		)
		(fp_line
			(start 0.120396 0.2794)
			(end -0.12065 0.2794)
			(stroke
				(width 0.1)
				(type default)
			)
			(layer "F.Fab")
		)
		(fp_line
			(start -0.12065 0.2794)
			(end -0.12065 0.3048)
			(stroke
				(width 0.1)
				(type default)
			)
			(layer "F.Fab")
		)
		(fp_line
			(start 0.67945 0.3048)
			(end 0.120396 0.3048)
			(stroke
				(width 0.1)
				(type default)
			)
			(layer "F.Fab")
		)
		(fp_line
			(start 0.120396 0.3048)
			(end 0.120396 0.2794)
			(stroke
				(width 0.1)
				(type default)
			)
			(layer "F.Fab")
		)
		(fp_line
			(start -0.12065 0.3048)
			(end -0.67945 0.3048)
			(stroke
				(width 0.1)
				(type default)
			)
			(layer "F.Fab")
		)
		(fp_line
			(start -0.67945 0.3048)
			(end -0.67945 -0.305054)
			(stroke
				(width 0.1)
				(type default)
			)
			(layer "F.Fab")
		)
		(pad "1" smd circle
			(at -0.40005 0 90)
			(size 0 0)
			(layers "F.Cu" "F.Mask" "F.Paste")
			(net "SSD3_AUX_P3V3_EN_R")
		)
		(pad "2" smd circle
			(at 0.40005 0 90)
			(size 0 0)
			(layers "F.Cu" "F.Mask" "F.Paste")
			(net "SSD3_AUX_P3V3_EN")
		)
	)
	(footprint ""
		(layer "F.Cu")
		(at 461.76311 -254.344932 -90)
		(property "Reference" "C4412"
			(at 0 0 270)
			(layer "F.SilkS")
			(hide yes)
			(effects
				(font
					(size 1.27 1.27)
				)
			)
		)
		(property "Value" ""
			(at 0 0 270)
			(layer "F.Fab")
			(effects
				(font
					(size 1.27 1.27)
				)
			)
		)
		(duplicate_pad_numbers_are_jumpers no)
		(fp_line
			(start -1.524 0.762)
			(end -1.524 -0.762)
			(stroke
				(width 0.1524)
				(type default)
			)
			(layer "F.SilkS")
		)
		(fp_line
			(start 1.524 0.762)
			(end -1.524 0.762)
			(stroke
				(width 0.1524)
				(type default)
			)
			(layer "F.SilkS")
		)
		(fp_line
			(start -1.524 -0.762)
			(end 1.524 -0.762)
			(stroke
				(width 0.1524)
				(type default)
			)
			(layer "F.SilkS")
		)
		(fp_line
			(start 1.524 -0.762)
			(end 1.524 0.762)
			(stroke
				(width 0.1524)
				(type default)
			)
			(layer "F.SilkS")
		)
		(fp_line
			(start -1.1049 0.724916)
			(end 1.1049 0.724916)
			(stroke
				(width 0.1)
				(type default)
			)
			(layer "F.Fab")
		)
		(fp_line
			(start 1.1049 0.724916)
			(end 1.1049 -0.724916)
			(stroke
				(width 0.1)
				(type default)
			)
			(layer "F.Fab")
		)
		(fp_line
			(start -1.1049 -0.724916)
			(end -1.1049 0.724916)
			(stroke
				(width 0.1)
				(type default)
			)
			(layer "F.Fab")
		)
		(fp_line
			(start 1.1049 -0.724916)
			(end -1.1049 -0.724916)
			(stroke
				(width 0.1)
				(type default)
			)
			(layer "F.Fab")
		)
		(pad "1" smd rect
			(at -0.889 0 90)
			(size 1.016 1.27)
			(layers "F.Cu" "F.Mask" "F.Paste")
			(net "P1V25_SERDES_VDDPLL_PEX3_C10")
		)
		(pad "2" smd rect
			(at 0.889 0 90)
			(size 1.016 1.27)
			(layers "F.Cu" "F.Mask" "F.Paste")
			(net "GND")
		)
		(zone
			(layer "F.Cu")
			(hatch none 0.5)
			(connect_pads
				(clearance 0)
			)
			(min_thickness 0.25)
			(keepout
				(tracks not_allowed)
				(vias allowed)
				(pads allowed)
				(copperpour not_allowed)
				(footprints allowed)
			)
			(placement
				(enabled no)
				(sheetname "")
			)
			(fill
				(thermal_gap 0.5)
				(thermal_bridge_width 0.5)
				(island_removal_mode 0)
			)
			(polygon
				(pts
					(xy 462.488026 -254.675132) (xy 461.038194 -254.675132) (xy 461.038194 -254.014732) (xy 462.488026 -254.014732)
				)
			)
		)
	)
	(footprint ""
		(layer "F.Cu")
		(at 421.705532 -343.952322 90)
		(property "Reference" "C814"
			(at 0 0 90)
			(layer "F.SilkS")
			(hide yes)
			(effects
				(font
					(size 1.27 1.27)
				)
			)
		)
		(property "Value" ""
			(at 0 0 90)
			(layer "F.Fab")
			(effects
				(font
					(size 1.27 1.27)
				)
			)
		)
		(duplicate_pad_numbers_are_jumpers no)
		(fp_line
			(start 0.299974 -0.150114)
			(end 0.299974 0.150114)
			(stroke
				(width 0.1)
				(type default)
			)
			(layer "F.Fab")
		)
		(fp_line
			(start -0.299974 -0.150114)
			(end 0.299974 -0.150114)
			(stroke
				(width 0.1)
				(type default)
			)
			(layer "F.Fab")
		)
		(fp_line
			(start 0.299974 0.150114)
			(end -0.299974 0.150114)
			(stroke
				(width 0.1)
				(type default)
			)
			(layer "F.Fab")
		)
		(fp_line
			(start -0.299974 0.150114)
			(end -0.299974 -0.150114)
			(stroke
				(width 0.1)
				(type default)
			)
			(layer "F.Fab")
		)
		(pad "1" smd rect
			(at -0.2667 0 90)
			(size 0.3048 0.381)
			(layers "F.Cu" "F.Mask" "F.Paste")
			(net "P5E_PEX3_STN7_TX_DP<117>")
		)
		(pad "2" smd rect
			(at 0.2667 0 90)
			(size 0.3048 0.381)
			(layers "F.Cu" "F.Mask" "F.Paste")
			(net "P5E_PEX3_STN7_TX_C_DP<117>")
		)
	)
	(footprint ""
		(layer "F.Cu")
		(at 327.533 -214.249 180)
		(property "Reference" "R4155"
			(at 0 0 180)
			(layer "F.SilkS")
			(hide yes)
			(effects
				(font
					(size 1.27 1.27)
				)
			)
		)
		(property "Value" ""
			(at 0 0 180)
			(layer "F.Fab")
			(effects
				(font
					(size 1.27 1.27)
				)
			)
		)
		(duplicate_pad_numbers_are_jumpers no)
		(fp_line
			(start 0.7874 0.4064)
			(end -0.7874 0.4064)
			(stroke
				(width 0.1524)
				(type default)
			)
			(layer "F.SilkS")
		)
		(fp_line
			(start 0.7874 -0.4064)
			(end 0.7874 0.4064)
			(stroke
				(width 0.1524)
				(type default)
			)
			(layer "F.SilkS")
		)
		(fp_line
			(start -0.7874 0.4064)
			(end -0.7874 -0.4064)
			(stroke
				(width 0.1524)
				(type default)
			)
			(layer "F.SilkS")
		)
		(fp_line
			(start -0.7874 -0.4064)
			(end 0.7874 -0.4064)
			(stroke
				(width 0.1524)
				(type default)
			)
			(layer "F.SilkS")
		)
		(fp_line
			(start 0.67945 0.3048)
			(end 0.120396 0.3048)
			(stroke
				(width 0.1)
				(type default)
			)
			(layer "F.Fab")
		)
		(fp_line
			(start 0.67945 -0.3048)
			(end 0.67945 0.3048)
			(stroke
				(width 0.1)
				(type default)
			)
			(layer "F.Fab")
		)
		(fp_line
			(start 0.12065 -0.2794)
			(end 0.12065 -0.3048)
			(stroke
				(width 0.1)
				(type default)
			)
			(layer "F.Fab")
		)
		(fp_line
			(start 0.12065 -0.3048)
			(end 0.67945 -0.3048)
			(stroke
				(width 0.1)
				(type default)
			)
			(layer "F.Fab")
		)
		(fp_line
			(start 0.120396 0.3048)
			(end 0.120396 0.2794)
			(stroke
				(width 0.1)
				(type default)
			)
			(layer "F.Fab")
		)
		(fp_line
			(start 0.120396 0.2794)
			(end -0.12065 0.2794)
			(stroke
				(width 0.1)
				(type default)
			)
			(layer "F.Fab")
		)
		(fp_line
			(start -0.12065 0.3048)
			(end -0.67945 0.3048)
			(stroke
				(width 0.1)
				(type default)
			)
			(layer "F.Fab")
		)
		(fp_line
			(start -0.12065 0.2794)
			(end -0.12065 0.3048)
			(stroke
				(width 0.1)
				(type default)
			)
			(layer "F.Fab")
		)
		(fp_line
			(start -0.12065 -0.2794)
			(end 0.12065 -0.2794)
			(stroke
				(width 0.1)
				(type default)
			)
			(layer "F.Fab")
		)
		(fp_line
			(start -0.12065 -0.305054)
			(end -0.12065 -0.2794)
			(stroke
				(width 0.1)
				(type default)
			)
			(layer "F.Fab")
		)
		(fp_line
			(start -0.67945 0.3048)
			(end -0.67945 -0.305054)
			(stroke
				(width 0.1)
				(type default)
			)
			(layer "F.Fab")
		)
		(fp_line
			(start -0.67945 -0.305054)
			(end -0.12065 -0.305054)
			(stroke
				(width 0.1)
				(type default)
			)
			(layer "F.Fab")
		)
		(pad "1" smd circle
			(at -0.40005 0 180)
			(size 0 0)
			(layers "F.Cu" "F.Mask" "F.Paste")
			(net "PRSNT_SSD8_FPGA_N")
		)
		(pad "2" smd circle
			(at 0.40005 0 180)
			(size 0 0)
			(layers "F.Cu" "F.Mask" "F.Paste")
			(net "PRSNT_SSD8_FPGA_R_N")
		)
	)
	(footprint ""
		(layer "F.Cu")
		(at 39.280592 -125.519942)
		(property "Reference" "C42"
			(at 0 0 0)
			(layer "F.SilkS")
			(hide yes)
			(effects
				(font
					(size 1.27 1.27)
				)
			)
		)
		(property "Value" ""
			(at 0 0 0)
			(layer "F.Fab")
			(effects
				(font
					(size 1.27 1.27)
				)
			)
		)
		(duplicate_pad_numbers_are_jumpers no)
		(fp_line
			(start -0.299974 -0.150114)
			(end 0.299974 -0.150114)
			(stroke
				(width 0.1)
				(type default)
			)
			(layer "F.Fab")
		)
		(fp_line
			(start -0.299974 0.150114)
			(end -0.299974 -0.150114)
			(stroke
				(width 0.1)
				(type default)
			)
			(layer "F.Fab")
		)
		(fp_line
			(start 0.299974 -0.150114)
			(end 0.299974 0.150114)
			(stroke
				(width 0.1)
				(type default)
			)
			(layer "F.Fab")
		)
		(fp_line
			(start 0.299974 0.150114)
			(end -0.299974 0.150114)
			(stroke
				(width 0.1)
				(type default)
			)
			(layer "F.Fab")
		)
		(pad "1" smd rect
			(at -0.2667 0)
			(size 0.3048 0.381)
			(layers "F.Cu" "F.Mask" "F.Paste")
			(net "P5E_PEX0_STN1_TX_DP<27>")
		)
		(pad "2" smd rect
			(at 0.2667 0)
			(size 0.3048 0.381)
			(layers "F.Cu" "F.Mask" "F.Paste")
			(net "P5E_PEX0_STN1_TX_C_DP<27>")
		)
	)
	(footprint ""
		(layer "F.Cu")
		(at 184.491884 -195.106798 180)
		(property "Reference" "R470"
			(at 0 0 180)
			(layer "F.SilkS")
			(hide yes)
			(effects
				(font
					(size 1.27 1.27)
				)
			)
		)
		(property "Value" ""
			(at 0 0 180)
			(layer "F.Fab")
			(effects
				(font
					(size 1.27 1.27)
				)
			)
		)
		(duplicate_pad_numbers_are_jumpers no)
		(fp_line
			(start 0.7874 0.4064)
			(end -0.7874 0.4064)
			(stroke
				(width 0.1524)
				(type default)
			)
			(layer "F.SilkS")
		)
		(fp_line
			(start 0.7874 -0.4064)
			(end 0.7874 0.4064)
			(stroke
				(width 0.1524)
				(type default)
			)
			(layer "F.SilkS")
		)
		(fp_line
			(start -0.7874 0.4064)
			(end -0.7874 -0.4064)
			(stroke
				(width 0.1524)
				(type default)
			)
			(layer "F.SilkS")
		)
		(fp_line
			(start -0.7874 -0.4064)
			(end 0.7874 -0.4064)
			(stroke
				(width 0.1524)
				(type default)
			)
			(layer "F.SilkS")
		)
		(fp_line
			(start 0.67945 0.3048)
			(end 0.120396 0.3048)
			(stroke
				(width 0.1)
				(type default)
			)
			(layer "F.Fab")
		)
		(fp_line
			(start 0.67945 -0.3048)
			(end 0.67945 0.3048)
			(stroke
				(width 0.1)
				(type default)
			)
			(layer "F.Fab")
		)
		(fp_line
			(start 0.12065 -0.2794)
			(end 0.12065 -0.3048)
			(stroke
				(width 0.1)
				(type default)
			)
			(layer "F.Fab")
		)
		(fp_line
			(start 0.12065 -0.3048)
			(end 0.67945 -0.3048)
			(stroke
				(width 0.1)
				(type default)
			)
			(layer "F.Fab")
		)
		(fp_line
			(start 0.120396 0.3048)
			(end 0.120396 0.2794)
			(stroke
				(width 0.1)
				(type default)
			)
			(layer "F.Fab")
		)
		(fp_line
			(start 0.120396 0.2794)
			(end -0.12065 0.2794)
			(stroke
				(width 0.1)
				(type default)
			)
			(layer "F.Fab")
		)
		(fp_line
			(start -0.12065 0.3048)
			(end -0.67945 0.3048)
			(stroke
				(width 0.1)
				(type default)
			)
			(layer "F.Fab")
		)
		(fp_line
			(start -0.12065 0.2794)
			(end -0.12065 0.3048)
			(stroke
				(width 0.1)
				(type default)
			)
			(layer "F.Fab")
		)
		(fp_line
			(start -0.12065 -0.2794)
			(end 0.12065 -0.2794)
			(stroke
				(width 0.1)
				(type default)
			)
			(layer "F.Fab")
		)
		(fp_line
			(start -0.12065 -0.305054)
			(end -0.12065 -0.2794)
			(stroke
				(width 0.1)
				(type default)
			)
			(layer "F.Fab")
		)
		(fp_line
			(start -0.67945 0.3048)
			(end -0.67945 -0.305054)
			(stroke
				(width 0.1)
				(type default)
			)
			(layer "F.Fab")
		)
		(fp_line
			(start -0.67945 -0.305054)
			(end -0.12065 -0.305054)
			(stroke
				(width 0.1)
				(type default)
			)
			(layer "F.Fab")
		)
		(pad "1" smd circle
			(at -0.40005 0 180)
			(size 0 0)
			(layers "F.Cu" "F.Mask" "F.Paste")
			(net "SPI_BIC1_CLK_R2")
		)
		(pad "2" smd circle
			(at 0.40005 0 180)
			(size 0 0)
			(layers "F.Cu" "F.Mask" "F.Paste")
			(net "SPI_BIC1_CLK_R3")
		)
	)
	(footprint ""
		(layer "F.Cu")
		(at 350.380554 -81.501234)
		(property "Reference" "R1601"
			(at 0 0 0)
			(layer "F.SilkS")
			(hide yes)
			(effects
				(font
					(size 1.27 1.27)
				)
			)
		)
		(property "Value" ""
			(at 0 0 0)
			(layer "F.Fab")
			(effects
				(font
					(size 1.27 1.27)
				)
			)
		)
		(duplicate_pad_numbers_are_jumpers no)
		(fp_line
			(start -0.7874 -0.4064)
			(end 0.7874 -0.4064)
			(stroke
				(width 0.1524)
				(type default)
			)
			(layer "F.SilkS")
		)
		(fp_line
			(start -0.7874 0.4064)
			(end -0.7874 -0.4064)
			(stroke
				(width 0.1524)
				(type default)
			)
			(layer "F.SilkS")
		)
		(fp_line
			(start 0.7874 -0.4064)
			(end 0.7874 0.4064)
			(stroke
				(width 0.1524)
				(type default)
			)
			(layer "F.SilkS")
		)
		(fp_line
			(start 0.7874 0.4064)
			(end -0.7874 0.4064)
			(stroke
				(width 0.1524)
				(type default)
			)
			(layer "F.SilkS")
		)
		(fp_line
			(start -0.67945 -0.305054)
			(end -0.12065 -0.305054)
			(stroke
				(width 0.1)
				(type default)
			)
			(layer "F.Fab")
		)
		(fp_line
			(start -0.67945 0.3048)
			(end -0.67945 -0.305054)
			(stroke
				(width 0.1)
				(type default)
			)
			(layer "F.Fab")
		)
		(fp_line
			(start -0.12065 -0.305054)
			(end -0.12065 -0.2794)
			(stroke
				(width 0.1)
				(type default)
			)
			(layer "F.Fab")
		)
		(fp_line
			(start -0.12065 -0.2794)
			(end 0.12065 -0.2794)
			(stroke
				(width 0.1)
				(type default)
			)
			(layer "F.Fab")
		)
		(fp_line
			(start -0.12065 0.2794)
			(end -0.12065 0.3048)
			(stroke
				(width 0.1)
				(type default)
			)
			(layer "F.Fab")
		)
		(fp_line
			(start -0.12065 0.3048)
			(end -0.67945 0.3048)
			(stroke
				(width 0.1)
				(type default)
			)
			(layer "F.Fab")
		)
		(fp_line
			(start 0.120396 0.2794)
			(end -0.12065 0.2794)
			(stroke
				(width 0.1)
				(type default)
			)
			(layer "F.Fab")
		)
		(fp_line
			(start 0.120396 0.3048)
			(end 0.120396 0.2794)
			(stroke
				(width 0.1)
				(type default)
			)
			(layer "F.Fab")
		)
		(fp_line
			(start 0.12065 -0.3048)
			(end 0.67945 -0.3048)
			(stroke
				(width 0.1)
				(type default)
			)
			(layer "F.Fab")
		)
		(fp_line
			(start 0.12065 -0.2794)
			(end 0.12065 -0.3048)
			(stroke
				(width 0.1)
				(type default)
			)
			(layer "F.Fab")
		)
		(fp_line
			(start 0.67945 -0.3048)
			(end 0.67945 0.3048)
			(stroke
				(width 0.1)
				(type default)
			)
			(layer "F.Fab")
		)
		(fp_line
			(start 0.67945 0.3048)
			(end 0.120396 0.3048)
			(stroke
				(width 0.1)
				(type default)
			)
			(layer "F.Fab")
		)
		(pad "1" smd circle
			(at -0.40005 0)
			(size 0 0)
			(layers "F.Cu" "F.Mask" "F.Paste")
			(net "P3V3_AUX")
		)
		(pad "2" smd circle
			(at 0.40005 0)
			(size 0 0)
			(layers "F.Cu" "F.Mask" "F.Paste")
			(net "SMB_BIC_I2C9_MUX1_SSD11_R_SCL")
		)
	)
	(footprint ""
		(layer "F.Cu")
		(at 16.785336 -273.216624)
		(property "Reference" "R769"
			(at 0 0 0)
			(layer "F.SilkS")
			(hide yes)
			(effects
				(font
					(size 1.27 1.27)
				)
			)
		)
		(property "Value" ""
			(at 0 0 0)
			(layer "F.Fab")
			(effects
				(font
					(size 1.27 1.27)
				)
			)
		)
		(duplicate_pad_numbers_are_jumpers no)
		(fp_line
			(start -0.7874 -0.4064)
			(end 0.7874 -0.4064)
			(stroke
				(width 0.1524)
				(type default)
			)
			(layer "F.SilkS")
		)
		(fp_line
			(start -0.7874 0.4064)
			(end -0.7874 -0.4064)
			(stroke
				(width 0.1524)
				(type default)
			)
			(layer "F.SilkS")
		)
		(fp_line
			(start 0.7874 -0.4064)
			(end 0.7874 0.4064)
			(stroke
				(width 0.1524)
				(type default)
			)
			(layer "F.SilkS")
		)
		(fp_line
			(start 0.7874 0.4064)
			(end -0.7874 0.4064)
			(stroke
				(width 0.1524)
				(type default)
			)
			(layer "F.SilkS")
		)
		(fp_line
			(start -0.67945 -0.305054)
			(end -0.12065 -0.305054)
			(stroke
				(width 0.1)
				(type default)
			)
			(layer "F.Fab")
		)
		(fp_line
			(start -0.67945 0.3048)
			(end -0.67945 -0.305054)
			(stroke
				(width 0.1)
				(type default)
			)
			(layer "F.Fab")
		)
		(fp_line
			(start -0.12065 -0.305054)
			(end -0.12065 -0.2794)
			(stroke
				(width 0.1)
				(type default)
			)
			(layer "F.Fab")
		)
		(fp_line
			(start -0.12065 -0.2794)
			(end 0.12065 -0.2794)
			(stroke
				(width 0.1)
				(type default)
			)
			(layer "F.Fab")
		)
		(fp_line
			(start -0.12065 0.2794)
			(end -0.12065 0.3048)
			(stroke
				(width 0.1)
				(type default)
			)
			(layer "F.Fab")
		)
		(fp_line
			(start -0.12065 0.3048)
			(end -0.67945 0.3048)
			(stroke
				(width 0.1)
				(type default)
			)
			(layer "F.Fab")
		)
		(fp_line
			(start 0.120396 0.2794)
			(end -0.12065 0.2794)
			(stroke
				(width 0.1)
				(type default)
			)
			(layer "F.Fab")
		)
		(fp_line
			(start 0.120396 0.3048)
			(end 0.120396 0.2794)
			(stroke
				(width 0.1)
				(type default)
			)
			(layer "F.Fab")
		)
		(fp_line
			(start 0.12065 -0.3048)
			(end 0.67945 -0.3048)
			(stroke
				(width 0.1)
				(type default)
			)
			(layer "F.Fab")
		)
		(fp_line
			(start 0.12065 -0.2794)
			(end 0.12065 -0.3048)
			(stroke
				(width 0.1)
				(type default)
			)
			(layer "F.Fab")
		)
		(fp_line
			(start 0.67945 -0.3048)
			(end 0.67945 0.3048)
			(stroke
				(width 0.1)
				(type default)
			)
			(layer "F.Fab")
		)
		(fp_line
			(start 0.67945 0.3048)
			(end 0.120396 0.3048)
			(stroke
				(width 0.1)
				(type default)
			)
			(layer "F.Fab")
		)
		(pad "1" smd circle
			(at -0.40005 0)
			(size 0 0)
			(layers "F.Cu" "F.Mask" "F.Paste")
			(net "PEX0_P1V25_ADC_A0")
		)
		(pad "2" smd circle
			(at 0.40005 0)
			(size 0 0)
			(layers "F.Cu" "F.Mask" "F.Paste")
			(net "P3V3_AUX")
		)
	)
	(footprint ""
		(layer "F.Cu")
		(at 275.963126 -402.33219 -90)
		(property "Reference" "R1805"
			(at 0 0 270)
			(layer "F.SilkS")
			(hide yes)
			(effects
				(font
					(size 1.27 1.27)
				)
			)
		)
		(property "Value" ""
			(at 0 0 270)
			(layer "F.Fab")
			(effects
				(font
					(size 1.27 1.27)
				)
			)
		)
		(duplicate_pad_numbers_are_jumpers no)
		(fp_line
			(start -0.7874 0.4064)
			(end -0.7874 -0.4064)
			(stroke
				(width 0.1524)
				(type default)
			)
			(layer "F.SilkS")
		)
		(fp_line
			(start 0.7874 0.4064)
			(end -0.7874 0.4064)
			(stroke
				(width 0.1524)
				(type default)
			)
			(layer "F.SilkS")
		)
		(fp_line
			(start -0.7874 -0.4064)
			(end 0.7874 -0.4064)
			(stroke
				(width 0.1524)
				(type default)
			)
			(layer "F.SilkS")
		)
		(fp_line
			(start 0.7874 -0.4064)
			(end 0.7874 0.4064)
			(stroke
				(width 0.1524)
				(type default)
			)
			(layer "F.SilkS")
		)
		(fp_line
			(start -0.67945 0.3048)
			(end -0.67945 -0.305054)
			(stroke
				(width 0.1)
				(type default)
			)
			(layer "F.Fab")
		)
		(fp_line
			(start -0.12065 0.3048)
			(end -0.67945 0.3048)
			(stroke
				(width 0.1)
				(type default)
			)
			(layer "F.Fab")
		)
		(fp_line
			(start 0.120396 0.3048)
			(end 0.120396 0.2794)
			(stroke
				(width 0.1)
				(type default)
			)
			(layer "F.Fab")
		)
		(fp_line
			(start 0.67945 0.3048)
			(end 0.120396 0.3048)
			(stroke
				(width 0.1)
				(type default)
			)
			(layer "F.Fab")
		)
		(fp_line
			(start -0.12065 0.2794)
			(end -0.12065 0.3048)
			(stroke
				(width 0.1)
				(type default)
			)
			(layer "F.Fab")
		)
		(fp_line
			(start 0.120396 0.2794)
			(end -0.12065 0.2794)
			(stroke
				(width 0.1)
				(type default)
			)
			(layer "F.Fab")
		)
		(fp_line
			(start -0.12065 -0.2794)
			(end 0.12065 -0.2794)
			(stroke
				(width 0.1)
				(type default)
			)
			(layer "F.Fab")
		)
		(fp_line
			(start 0.12065 -0.2794)
			(end 0.12065 -0.3048)
			(stroke
				(width 0.1)
				(type default)
			)
			(layer "F.Fab")
		)
		(fp_line
			(start 0.12065 -0.3048)
			(end 0.67945 -0.3048)
			(stroke
				(width 0.1)
				(type default)
			)
			(layer "F.Fab")
		)
		(fp_line
			(start 0.67945 -0.3048)
			(end 0.67945 0.3048)
			(stroke
				(width 0.1)
				(type default)
			)
			(layer "F.Fab")
		)
		(fp_line
			(start -0.67945 -0.305054)
			(end -0.12065 -0.305054)
			(stroke
				(width 0.1)
				(type default)
			)
			(layer "F.Fab")
		)
		(fp_line
			(start -0.12065 -0.305054)
			(end -0.12065 -0.2794)
			(stroke
				(width 0.1)
				(type default)
			)
			(layer "F.Fab")
		)
		(pad "1" smd circle
			(at -0.40005 0 270)
			(size 0 0)
			(layers "F.Cu" "F.Mask" "F.Paste")
			(net "P3V3_AUX")
		)
		(pad "2" smd circle
			(at 0.40005 0 270)
			(size 0 0)
			(layers "F.Cu" "F.Mask" "F.Paste")
			(net "MB_BMC_MON_ISO_R")
		)
	)
	(footprint ""
		(layer "F.Cu")
		(at 374.884188 -29.222954 -90)
		(property "Reference" "PC949"
			(at 0 0 270)
			(layer "F.SilkS")
			(hide yes)
			(effects
				(font
					(size 1.27 1.27)
				)
			)
		)
		(property "Value" ""
			(at 0 0 270)
			(layer "F.Fab")
			(effects
				(font
					(size 1.27 1.27)
				)
			)
		)
		(duplicate_pad_numbers_are_jumpers no)
		(fp_line
			(start -0.7874 0.4064)
			(end -0.7874 -0.4064)
			(stroke
				(width 0.1524)
				(type default)
			)
			(layer "F.SilkS")
		)
		(fp_line
			(start 0.7874 0.4064)
			(end -0.7874 0.4064)
			(stroke
				(width 0.1524)
				(type default)
			)
			(layer "F.SilkS")
		)
		(fp_line
			(start -0.7874 -0.4064)
			(end 0.7874 -0.4064)
			(stroke
				(width 0.1524)
				(type default)
			)
			(layer "F.SilkS")
		)
		(fp_line
			(start 0.7874 -0.4064)
			(end 0.7874 0.4064)
			(stroke
				(width 0.1524)
				(type default)
			)
			(layer "F.SilkS")
		)
		(fp_line
			(start -0.67945 0.3048)
			(end -0.67945 -0.305054)
			(stroke
				(width 0.1)
				(type default)
			)
			(layer "F.Fab")
		)
		(fp_line
			(start -0.12065 0.3048)
			(end -0.67945 0.3048)
			(stroke
				(width 0.1)
				(type default)
			)
			(layer "F.Fab")
		)
		(fp_line
			(start 0.120396 0.3048)
			(end 0.120396 0.2794)
			(stroke
				(width 0.1)
				(type default)
			)
			(layer "F.Fab")
		)
		(fp_line
			(start 0.67945 0.3048)
			(end 0.120396 0.3048)
			(stroke
				(width 0.1)
				(type default)
			)
			(layer "F.Fab")
		)
		(fp_line
			(start -0.12065 0.2794)
			(end -0.12065 0.3048)
			(stroke
				(width 0.1)
				(type default)
			)
			(layer "F.Fab")
		)
		(fp_line
			(start 0.120396 0.2794)
			(end -0.12065 0.2794)
			(stroke
				(width 0.1)
				(type default)
			)
			(layer "F.Fab")
		)
		(fp_line
			(start -0.12065 -0.2794)
			(end 0.12065 -0.2794)
			(stroke
				(width 0.1)
				(type default)
			)
			(layer "F.Fab")
		)
		(fp_line
			(start 0.12065 -0.2794)
			(end 0.12065 -0.3048)
			(stroke
				(width 0.1)
				(type default)
			)
			(layer "F.Fab")
		)
		(fp_line
			(start 0.12065 -0.3048)
			(end 0.67945 -0.3048)
			(stroke
				(width 0.1)
				(type default)
			)
			(layer "F.Fab")
		)
		(fp_line
			(start 0.67945 -0.3048)
			(end 0.67945 0.3048)
			(stroke
				(width 0.1)
				(type default)
			)
			(layer "F.Fab")
		)
		(fp_line
			(start -0.67945 -0.305054)
			(end -0.12065 -0.305054)
			(stroke
				(width 0.1)
				(type default)
			)
			(layer "F.Fab")
		)
		(fp_line
			(start -0.12065 -0.305054)
			(end -0.12065 -0.2794)
			(stroke
				(width 0.1)
				(type default)
			)
			(layer "F.Fab")
		)
		(pad "1" smd circle
			(at -0.40005 0 270)
			(size 0 0)
			(layers "F.Cu" "F.Mask" "F.Paste")
			(net "P3V3_AUX")
		)
		(pad "2" smd circle
			(at 0.40005 0 270)
			(size 0 0)
			(layers "F.Cu" "F.Mask" "F.Paste")
			(net "GND")
		)
	)
	(footprint ""
		(layer "F.Cu")
		(at 353.822 -178.562)
		(property "Reference" "R4758"
			(at 0 0 0)
			(layer "F.SilkS")
			(hide yes)
			(effects
				(font
					(size 1.27 1.27)
				)
			)
		)
		(property "Value" ""
			(at 0 0 0)
			(layer "F.Fab")
			(effects
				(font
					(size 1.27 1.27)
				)
			)
		)
		(duplicate_pad_numbers_are_jumpers no)
		(fp_line
			(start -0.7874 -0.4064)
			(end 0.7874 -0.4064)
			(stroke
				(width 0.1524)
				(type default)
			)
			(layer "F.SilkS")
		)
		(fp_line
			(start -0.7874 0.4064)
			(end -0.7874 -0.4064)
			(stroke
				(width 0.1524)
				(type default)
			)
			(layer "F.SilkS")
		)
		(fp_line
			(start 0.7874 -0.4064)
			(end 0.7874 0.4064)
			(stroke
				(width 0.1524)
				(type default)
			)
			(layer "F.SilkS")
		)
		(fp_line
			(start 0.7874 0.4064)
			(end -0.7874 0.4064)
			(stroke
				(width 0.1524)
				(type default)
			)
			(layer "F.SilkS")
		)
		(fp_line
			(start -0.67945 -0.305054)
			(end -0.12065 -0.305054)
			(stroke
				(width 0.1)
				(type default)
			)
			(layer "F.Fab")
		)
		(fp_line
			(start -0.67945 0.3048)
			(end -0.67945 -0.305054)
			(stroke
				(width 0.1)
				(type default)
			)
			(layer "F.Fab")
		)
		(fp_line
			(start -0.12065 -0.305054)
			(end -0.12065 -0.2794)
			(stroke
				(width 0.1)
				(type default)
			)
			(layer "F.Fab")
		)
		(fp_line
			(start -0.12065 -0.2794)
			(end 0.12065 -0.2794)
			(stroke
				(width 0.1)
				(type default)
			)
			(layer "F.Fab")
		)
		(fp_line
			(start -0.12065 0.2794)
			(end -0.12065 0.3048)
			(stroke
				(width 0.1)
				(type default)
			)
			(layer "F.Fab")
		)
		(fp_line
			(start -0.12065 0.3048)
			(end -0.67945 0.3048)
			(stroke
				(width 0.1)
				(type default)
			)
			(layer "F.Fab")
		)
		(fp_line
			(start 0.120396 0.2794)
			(end -0.12065 0.2794)
			(stroke
				(width 0.1)
				(type default)
			)
			(layer "F.Fab")
		)
		(fp_line
			(start 0.120396 0.3048)
			(end 0.120396 0.2794)
			(stroke
				(width 0.1)
				(type default)
			)
			(layer "F.Fab")
		)
		(fp_line
			(start 0.12065 -0.3048)
			(end 0.67945 -0.3048)
			(stroke
				(width 0.1)
				(type default)
			)
			(layer "F.Fab")
		)
		(fp_line
			(start 0.12065 -0.2794)
			(end 0.12065 -0.3048)
			(stroke
				(width 0.1)
				(type default)
			)
			(layer "F.Fab")
		)
		(fp_line
			(start 0.67945 -0.3048)
			(end 0.67945 0.3048)
			(stroke
				(width 0.1)
				(type default)
			)
			(layer "F.Fab")
		)
		(fp_line
			(start 0.67945 0.3048)
			(end 0.120396 0.3048)
			(stroke
				(width 0.1)
				(type default)
			)
			(layer "F.Fab")
		)
		(pad "1" smd circle
			(at -0.40005 0)
			(size 0 0)
			(layers "F.Cu" "F.Mask" "F.Paste")
			(net "NIC4_PEX_PWR_EN")
		)
		(pad "2" smd circle
			(at 0.40005 0)
			(size 0 0)
			(layers "F.Cu" "F.Mask" "F.Paste")
			(net "NIC4_PEX_PWR_EN_R")
		)
	)
	(footprint ""
		(layer "F.Cu")
		(at 400.884136 -29.222954 -90)
		(property "Reference" "PC968"
			(at 0 0 270)
			(layer "F.SilkS")
			(hide yes)
			(effects
				(font
					(size 1.27 1.27)
				)
			)
		)
		(property "Value" ""
			(at 0 0 270)
			(layer "F.Fab")
			(effects
				(font
					(size 1.27 1.27)
				)
			)
		)
		(duplicate_pad_numbers_are_jumpers no)
		(fp_line
			(start -0.7874 0.4064)
			(end -0.7874 -0.4064)
			(stroke
				(width 0.1524)
				(type default)
			)
			(layer "F.SilkS")
		)
		(fp_line
			(start 0.7874 0.4064)
			(end -0.7874 0.4064)
			(stroke
				(width 0.1524)
				(type default)
			)
			(layer "F.SilkS")
		)
		(fp_line
			(start -0.7874 -0.4064)
			(end 0.7874 -0.4064)
			(stroke
				(width 0.1524)
				(type default)
			)
			(layer "F.SilkS")
		)
		(fp_line
			(start 0.7874 -0.4064)
			(end 0.7874 0.4064)
			(stroke
				(width 0.1524)
				(type default)
			)
			(layer "F.SilkS")
		)
		(fp_line
			(start -0.67945 0.3048)
			(end -0.67945 -0.305054)
			(stroke
				(width 0.1)
				(type default)
			)
			(layer "F.Fab")
		)
		(fp_line
			(start -0.12065 0.3048)
			(end -0.67945 0.3048)
			(stroke
				(width 0.1)
				(type default)
			)
			(layer "F.Fab")
		)
		(fp_line
			(start 0.120396 0.3048)
			(end 0.120396 0.2794)
			(stroke
				(width 0.1)
				(type default)
			)
			(layer "F.Fab")
		)
		(fp_line
			(start 0.67945 0.3048)
			(end 0.120396 0.3048)
			(stroke
				(width 0.1)
				(type default)
			)
			(layer "F.Fab")
		)
		(fp_line
			(start -0.12065 0.2794)
			(end -0.12065 0.3048)
			(stroke
				(width 0.1)
				(type default)
			)
			(layer "F.Fab")
		)
		(fp_line
			(start 0.120396 0.2794)
			(end -0.12065 0.2794)
			(stroke
				(width 0.1)
				(type default)
			)
			(layer "F.Fab")
		)
		(fp_line
			(start -0.12065 -0.2794)
			(end 0.12065 -0.2794)
			(stroke
				(width 0.1)
				(type default)
			)
			(layer "F.Fab")
		)
		(fp_line
			(start 0.12065 -0.2794)
			(end 0.12065 -0.3048)
			(stroke
				(width 0.1)
				(type default)
			)
			(layer "F.Fab")
		)
		(fp_line
			(start 0.12065 -0.3048)
			(end 0.67945 -0.3048)
			(stroke
				(width 0.1)
				(type default)
			)
			(layer "F.Fab")
		)
		(fp_line
			(start 0.67945 -0.3048)
			(end 0.67945 0.3048)
			(stroke
				(width 0.1)
				(type default)
			)
			(layer "F.Fab")
		)
		(fp_line
			(start -0.67945 -0.305054)
			(end -0.12065 -0.305054)
			(stroke
				(width 0.1)
				(type default)
			)
			(layer "F.Fab")
		)
		(fp_line
			(start -0.12065 -0.305054)
			(end -0.12065 -0.2794)
			(stroke
				(width 0.1)
				(type default)
			)
			(layer "F.Fab")
		)
		(pad "1" smd circle
			(at -0.40005 0 270)
			(size 0 0)
			(layers "F.Cu" "F.Mask" "F.Paste")
			(net "P3V3_AUX")
		)
		(pad "2" smd circle
			(at 0.40005 0 270)
			(size 0 0)
			(layers "F.Cu" "F.Mask" "F.Paste")
			(net "GND")
		)
	)
	(footprint ""
		(layer "F.Cu")
		(at 409.92679 -389.955532 180)
		(property "Reference" "C4159"
			(at 0 0 180)
			(layer "F.SilkS")
			(hide yes)
			(effects
				(font
					(size 1.27 1.27)
				)
			)
		)
		(property "Value" ""
			(at 0 0 180)
			(layer "F.Fab")
			(effects
				(font
					(size 1.27 1.27)
				)
			)
		)
		(duplicate_pad_numbers_are_jumpers no)
		(fp_line
			(start 0.7874 0.4064)
			(end -0.7874 0.4064)
			(stroke
				(width 0.1524)
				(type default)
			)
			(layer "F.SilkS")
		)
		(fp_line
			(start 0.7874 -0.4064)
			(end 0.7874 0.4064)
			(stroke
				(width 0.1524)
				(type default)
			)
			(layer "F.SilkS")
		)
		(fp_line
			(start -0.7874 0.4064)
			(end -0.7874 -0.4064)
			(stroke
				(width 0.1524)
				(type default)
			)
			(layer "F.SilkS")
		)
		(fp_line
			(start -0.7874 -0.4064)
			(end 0.7874 -0.4064)
			(stroke
				(width 0.1524)
				(type default)
			)
			(layer "F.SilkS")
		)
		(fp_line
			(start 0.67945 0.3048)
			(end 0.120396 0.3048)
			(stroke
				(width 0.1)
				(type default)
			)
			(layer "F.Fab")
		)
		(fp_line
			(start 0.67945 -0.3048)
			(end 0.67945 0.3048)
			(stroke
				(width 0.1)
				(type default)
			)
			(layer "F.Fab")
		)
		(fp_line
			(start 0.12065 -0.2794)
			(end 0.12065 -0.3048)
			(stroke
				(width 0.1)
				(type default)
			)
			(layer "F.Fab")
		)
		(fp_line
			(start 0.12065 -0.3048)
			(end 0.67945 -0.3048)
			(stroke
				(width 0.1)
				(type default)
			)
			(layer "F.Fab")
		)
		(fp_line
			(start 0.120396 0.3048)
			(end 0.120396 0.2794)
			(stroke
				(width 0.1)
				(type default)
			)
			(layer "F.Fab")
		)
		(fp_line
			(start 0.120396 0.2794)
			(end -0.12065 0.2794)
			(stroke
				(width 0.1)
				(type default)
			)
			(layer "F.Fab")
		)
		(fp_line
			(start -0.12065 0.3048)
			(end -0.67945 0.3048)
			(stroke
				(width 0.1)
				(type default)
			)
			(layer "F.Fab")
		)
		(fp_line
			(start -0.12065 0.2794)
			(end -0.12065 0.3048)
			(stroke
				(width 0.1)
				(type default)
			)
			(layer "F.Fab")
		)
		(fp_line
			(start -0.12065 -0.2794)
			(end 0.12065 -0.2794)
			(stroke
				(width 0.1)
				(type default)
			)
			(layer "F.Fab")
		)
		(fp_line
			(start -0.12065 -0.305054)
			(end -0.12065 -0.2794)
			(stroke
				(width 0.1)
				(type default)
			)
			(layer "F.Fab")
		)
		(fp_line
			(start -0.67945 0.3048)
			(end -0.67945 -0.305054)
			(stroke
				(width 0.1)
				(type default)
			)
			(layer "F.Fab")
		)
		(fp_line
			(start -0.67945 -0.305054)
			(end -0.12065 -0.305054)
			(stroke
				(width 0.1)
				(type default)
			)
			(layer "F.Fab")
		)
		(pad "1" smd circle
			(at -0.40005 0 180)
			(size 0 0)
			(layers "F.Cu" "F.Mask" "F.Paste")
			(net "GND")
		)
		(pad "2" smd circle
			(at 0.40005 0 180)
			(size 0 0)
			(layers "F.Cu" "F.Mask" "F.Paste")
			(net "GPU_3V3IO_RSVD1")
		)
	)
	(footprint ""
		(layer "F.Cu")
		(at 106.52506 -128.045464 -90)
		(property "Reference" "PD3"
			(at 3.839464 2.07899 90)
			(unlocked yes)
			(layer "F.SilkS")
			(effects
				(font
					(size 0.7874 0.5842)
					(thickness 0.1524)
				)
				(justify left)
			)
		)
		(property "Value" ""
			(at 0 0 270)
			(layer "F.Fab")
			(effects
				(font
					(size 1.27 1.27)
				)
			)
		)
		(duplicate_pad_numbers_are_jumpers no)
		(fp_line
			(start -3.400044 1.459992)
			(end -3.400044 -1.459992)
			(stroke
				(width 0.1524)
				(type default)
			)
			(layer "F.SilkS")
		)
		(fp_line
			(start 4.107942 1.459992)
			(end -3.400044 1.459992)
			(stroke
				(width 0.1524)
				(type default)
			)
			(layer "F.SilkS")
		)
		(fp_line
			(start -3.400044 -1.459992)
			(end 4.107942 -1.459992)
			(stroke
				(width 0.1524)
				(type default)
			)
			(layer "F.SilkS")
		)
		(fp_line
			(start 4.107942 -1.459992)
			(end 4.107942 1.459992)
			(stroke
				(width 0.1524)
				(type default)
			)
			(layer "F.SilkS")
		)
		(fp_poly
			(pts
				(xy 4.107942 -1.459992) (xy 4.107942 1.459992) (xy 3.308096 1.459992) (xy 3.308096 -1.459992)
			)
			(stroke
				(width 0)
				(type default)
			)
			(fill yes)
			(layer "F.SilkS")
		)
		(fp_line
			(start -2.29997 1.459992)
			(end -2.29997 -1.459992)
			(stroke
				(width 0.1)
				(type default)
			)
			(layer "F.Fab")
		)
		(fp_line
			(start 2.29997 1.459992)
			(end -2.29997 1.459992)
			(stroke
				(width 0.1)
				(type default)
			)
			(layer "F.Fab")
		)
		(fp_line
			(start -2.29997 -1.459992)
			(end 2.29997 -1.459992)
			(stroke
				(width 0.1)
				(type default)
			)
			(layer "F.Fab")
		)
		(fp_line
			(start 2.29997 -1.459992)
			(end 2.29997 1.459992)
			(stroke
				(width 0.1)
				(type default)
			)
			(layer "F.Fab")
		)
		(fp_text user "-"
			(at 5.4102 0.29845 90)
			(unlocked yes)
			(layer "F.SilkS")
			(effects
				(font
					(size 1.905 1.4224)
					(thickness 0.1524)
				)
				(justify left)
			)
		)
		(fp_text user "+"
			(at -4.7752 -0.12065 270)
			(unlocked yes)
			(layer "F.SilkS")
			(effects
				(font
					(size 1.905 1.4224)
					(thickness 0.1524)
				)
				(justify left)
			)
		)
		(fp_text user "-"
			(at 5.4102 0.29845 90)
			(unlocked yes)
			(layer "F.Fab")
			(effects
				(font
					(size 1.905 1.4224)
					(thickness 0.1524)
				)
				(justify left)
			)
		)
		(fp_text user "+"
			(at -4.7752 -0.12065 270)
			(unlocked yes)
			(layer "F.Fab")
			(effects
				(font
					(size 1.905 1.4224)
					(thickness 0.1524)
				)
				(justify left)
			)
		)
		(pad "A" smd rect
			(at -1.999996 0)
			(size 1.7018 2.5146)
			(layers "F.Cu" "F.Mask" "F.Paste")
			(net "GND")
		)
		(pad "C" smd rect
			(at 1.999996 0)
			(size 1.7018 2.5146)
			(layers "F.Cu" "F.Mask" "F.Paste")
			(net "P3V3")
		)
	)
	(footprint ""
		(layer "F.Cu")
		(at 336.443574 -44.87291)
		(property "Reference" "R628"
			(at 0 0 0)
			(layer "F.SilkS")
			(hide yes)
			(effects
				(font
					(size 1.27 1.27)
				)
			)
		)
		(property "Value" ""
			(at 0 0 0)
			(layer "F.Fab")
			(effects
				(font
					(size 1.27 1.27)
				)
			)
		)
		(duplicate_pad_numbers_are_jumpers no)
		(fp_line
			(start -0.7874 -0.4064)
			(end 0.7874 -0.4064)
			(stroke
				(width 0.1524)
				(type default)
			)
			(layer "F.SilkS")
		)
		(fp_line
			(start -0.7874 0.4064)
			(end -0.7874 -0.4064)
			(stroke
				(width 0.1524)
				(type default)
			)
			(layer "F.SilkS")
		)
		(fp_line
			(start 0.7874 -0.4064)
			(end 0.7874 0.4064)
			(stroke
				(width 0.1524)
				(type default)
			)
			(layer "F.SilkS")
		)
		(fp_line
			(start 0.7874 0.4064)
			(end -0.7874 0.4064)
			(stroke
				(width 0.1524)
				(type default)
			)
			(layer "F.SilkS")
		)
		(fp_line
			(start -0.67945 -0.305054)
			(end -0.12065 -0.305054)
			(stroke
				(width 0.1)
				(type default)
			)
			(layer "F.Fab")
		)
		(fp_line
			(start -0.67945 0.3048)
			(end -0.67945 -0.305054)
			(stroke
				(width 0.1)
				(type default)
			)
			(layer "F.Fab")
		)
		(fp_line
			(start -0.12065 -0.305054)
			(end -0.12065 -0.2794)
			(stroke
				(width 0.1)
				(type default)
			)
			(layer "F.Fab")
		)
		(fp_line
			(start -0.12065 -0.2794)
			(end 0.12065 -0.2794)
			(stroke
				(width 0.1)
				(type default)
			)
			(layer "F.Fab")
		)
		(fp_line
			(start -0.12065 0.2794)
			(end -0.12065 0.3048)
			(stroke
				(width 0.1)
				(type default)
			)
			(layer "F.Fab")
		)
		(fp_line
			(start -0.12065 0.3048)
			(end -0.67945 0.3048)
			(stroke
				(width 0.1)
				(type default)
			)
			(layer "F.Fab")
		)
		(fp_line
			(start 0.120396 0.2794)
			(end -0.12065 0.2794)
			(stroke
				(width 0.1)
				(type default)
			)
			(layer "F.Fab")
		)
		(fp_line
			(start 0.120396 0.3048)
			(end 0.120396 0.2794)
			(stroke
				(width 0.1)
				(type default)
			)
			(layer "F.Fab")
		)
		(fp_line
			(start 0.12065 -0.3048)
			(end 0.67945 -0.3048)
			(stroke
				(width 0.1)
				(type default)
			)
			(layer "F.Fab")
		)
		(fp_line
			(start 0.12065 -0.2794)
			(end 0.12065 -0.3048)
			(stroke
				(width 0.1)
				(type default)
			)
			(layer "F.Fab")
		)
		(fp_line
			(start 0.67945 -0.3048)
			(end 0.67945 0.3048)
			(stroke
				(width 0.1)
				(type default)
			)
			(layer "F.Fab")
		)
		(fp_line
			(start 0.67945 0.3048)
			(end 0.120396 0.3048)
			(stroke
				(width 0.1)
				(type default)
			)
			(layer "F.Fab")
		)
		(pad "1" smd circle
			(at -0.40005 0)
			(size 0 0)
			(layers "F.Cu" "F.Mask" "F.Paste")
			(net "SSD11_ADC_A0")
		)
		(pad "2" smd circle
			(at 0.40005 0)
			(size 0 0)
			(layers "F.Cu" "F.Mask" "F.Paste")
			(net "P3V3_AUX")
		)
	)
	(footprint ""
		(layer "F.Cu")
		(at 239.550194 -62.551056 90)
		(property "Reference" "Q204"
			(at -0.219456 -2.058924 90)
			(unlocked yes)
			(layer "F.SilkS")
			(effects
				(font
					(size 0.7874 0.5842)
					(thickness 0.1524)
				)
			)
		)
		(property "Value" ""
			(at 0 0 90)
			(layer "F.Fab")
			(effects
				(font
					(size 1.27 1.27)
				)
			)
		)
		(duplicate_pad_numbers_are_jumpers no)
		(fp_line
			(start 1.376172 -1.199896)
			(end 1.376172 1.199896)
			(stroke
				(width 0.1524)
				(type default)
			)
			(layer "F.SilkS")
		)
		(fp_line
			(start 0.508 -1.199896)
			(end 1.376172 -1.199896)
			(stroke
				(width 0.1524)
				(type default)
			)
			(layer "F.SilkS")
		)
		(fp_line
			(start -0.508 -1.199896)
			(end 0 -0.762)
			(stroke
				(width 0.1524)
				(type default)
			)
			(layer "F.SilkS")
		)
		(fp_line
			(start -1.376172 -1.199896)
			(end -0.508 -1.199896)
			(stroke
				(width 0.1524)
				(type default)
			)
			(layer "F.SilkS")
		)
		(fp_line
			(start 0 -0.762)
			(end 0.508 -1.199896)
			(stroke
				(width 0.1524)
				(type default)
			)
			(layer "F.SilkS")
		)
		(fp_line
			(start 1.376172 1.199896)
			(end -1.376172 1.199896)
			(stroke
				(width 0.1524)
				(type default)
			)
			(layer "F.SilkS")
		)
		(fp_line
			(start -1.376172 1.199896)
			(end -1.376172 -1.199896)
			(stroke
				(width 0.1524)
				(type default)
			)
			(layer "F.SilkS")
		)
		(fp_poly
			(pts
				(xy -1.299972 -0.794004) (xy -2.061972 -1.175004) (xy -2.061972 -0.413004)
			)
			(stroke
				(width 0)
				(type default)
			)
			(fill yes)
			(layer "F.SilkS")
		)
		(fp_line
			(start 0.674878 -1.100074)
			(end 0.674878 1.100074)
			(stroke
				(width 0.1)
				(type default)
			)
			(layer "F.Fab")
		)
		(fp_line
			(start -0.674878 -1.100074)
			(end 0.674878 -1.100074)
			(stroke
				(width 0.1)
				(type default)
			)
			(layer "F.Fab")
		)
		(fp_line
			(start 0.674878 1.100074)
			(end -0.674878 1.100074)
			(stroke
				(width 0.1)
				(type default)
			)
			(layer "F.Fab")
		)
		(fp_line
			(start -0.674878 1.100074)
			(end -0.674878 -1.100074)
			(stroke
				(width 0.1)
				(type default)
			)
			(layer "F.Fab")
		)
		(fp_poly
			(pts
				(xy -1.4605 -0.7493) (xy -2.2225 -1.1303) (xy -2.2225 -0.3683)
			)
			(stroke
				(width 0)
				(type default)
			)
			(fill yes)
			(layer "F.Fab")
		)
		(pad "1" smd rect
			(at -0.899922 -0.750062)
			(size 0.6096 0.6096)
			(layers "F.Cu" "F.Mask" "F.Paste")
			(net "GND")
		)
		(pad "2" smd rect
			(at -0.899922 0)
			(size 0.4064 0.6096)
			(layers "F.Cu" "F.Mask" "F.Paste")
			(net "P12V_SSD8_PG_G1")
		)
		(pad "3" smd rect
			(at -0.899922 0.750062)
			(size 0.6096 0.6096)
			(layers "F.Cu" "F.Mask" "F.Paste")
			(net "PWRGD_P12V_SSD8_D")
		)
		(pad "4" smd rect
			(at 0.899922 0.750062)
			(size 0.6096 0.6096)
			(layers "F.Cu" "F.Mask" "F.Paste")
			(net "GND")
		)
		(pad "5" smd rect
			(at 0.899922 0)
			(size 0.4064 0.6096)
			(layers "F.Cu" "F.Mask" "F.Paste")
			(net "P12V_SSD8_PG_G2")
		)
		(pad "6" smd rect
			(at 0.899922 -0.750062)
			(size 0.6096 0.6096)
			(layers "F.Cu" "F.Mask" "F.Paste")
			(net "P12V_SSD8_PG_G2")
		)
	)
	(footprint ""
		(layer "F.Cu")
		(at 127.034544 -303.649634 90)
		(property "Reference" "PC102"
			(at 0 0 90)
			(layer "F.SilkS")
			(hide yes)
			(effects
				(font
					(size 1.27 1.27)
				)
			)
		)
		(property "Value" ""
			(at 0 0 90)
			(layer "F.Fab")
			(effects
				(font
					(size 1.27 1.27)
				)
			)
		)
		(duplicate_pad_numbers_are_jumpers no)
		(fp_line
			(start 1.524 -0.762)
			(end 1.524 0.762)
			(stroke
				(width 0.1524)
				(type default)
			)
			(layer "F.SilkS")
		)
		(fp_line
			(start -1.524 -0.762)
			(end 1.524 -0.762)
			(stroke
				(width 0.1524)
				(type default)
			)
			(layer "F.SilkS")
		)
		(fp_line
			(start 1.524 0.762)
			(end -1.524 0.762)
			(stroke
				(width 0.1524)
				(type default)
			)
			(layer "F.SilkS")
		)
		(fp_line
			(start -1.524 0.762)
			(end -1.524 -0.762)
			(stroke
				(width 0.1524)
				(type default)
			)
			(layer "F.SilkS")
		)
		(fp_line
			(start 1.1049 -0.724916)
			(end -1.1049 -0.724916)
			(stroke
				(width 0.1)
				(type default)
			)
			(layer "F.Fab")
		)
		(fp_line
			(start -1.1049 -0.724916)
			(end -1.1049 0.724916)
			(stroke
				(width 0.1)
				(type default)
			)
			(layer "F.Fab")
		)
		(fp_line
			(start 1.1049 0.724916)
			(end 1.1049 -0.724916)
			(stroke
				(width 0.1)
				(type default)
			)
			(layer "F.Fab")
		)
		(fp_line
			(start -1.1049 0.724916)
			(end 1.1049 0.724916)
			(stroke
				(width 0.1)
				(type default)
			)
			(layer "F.Fab")
		)
		(pad "1" smd rect
			(at -0.889 0 270)
			(size 1.016 1.27)
			(layers "F.Cu" "F.Mask" "F.Paste")
			(net "P0V8_PEX1")
		)
		(pad "2" smd rect
			(at 0.889 0 270)
			(size 1.016 1.27)
			(layers "F.Cu" "F.Mask" "F.Paste")
			(net "GND")
		)
	)
	(footprint ""
		(layer "F.Cu")
		(at 26.243788 -46.90491)
		(property "Reference" "R509"
			(at 0 0 0)
			(layer "F.SilkS")
			(hide yes)
			(effects
				(font
					(size 1.27 1.27)
				)
			)
		)
		(property "Value" ""
			(at 0 0 0)
			(layer "F.Fab")
			(effects
				(font
					(size 1.27 1.27)
				)
			)
		)
		(duplicate_pad_numbers_are_jumpers no)
		(fp_line
			(start -0.7874 -0.4064)
			(end 0.7874 -0.4064)
			(stroke
				(width 0.1524)
				(type default)
			)
			(layer "F.SilkS")
		)
		(fp_line
			(start -0.7874 0.4064)
			(end -0.7874 -0.4064)
			(stroke
				(width 0.1524)
				(type default)
			)
			(layer "F.SilkS")
		)
		(fp_line
			(start 0.7874 -0.4064)
			(end 0.7874 0.4064)
			(stroke
				(width 0.1524)
				(type default)
			)
			(layer "F.SilkS")
		)
		(fp_line
			(start 0.7874 0.4064)
			(end -0.7874 0.4064)
			(stroke
				(width 0.1524)
				(type default)
			)
			(layer "F.SilkS")
		)
		(fp_line
			(start -0.67945 -0.305054)
			(end -0.12065 -0.305054)
			(stroke
				(width 0.1)
				(type default)
			)
			(layer "F.Fab")
		)
		(fp_line
			(start -0.67945 0.3048)
			(end -0.67945 -0.305054)
			(stroke
				(width 0.1)
				(type default)
			)
			(layer "F.Fab")
		)
		(fp_line
			(start -0.12065 -0.305054)
			(end -0.12065 -0.2794)
			(stroke
				(width 0.1)
				(type default)
			)
			(layer "F.Fab")
		)
		(fp_line
			(start -0.12065 -0.2794)
			(end 0.12065 -0.2794)
			(stroke
				(width 0.1)
				(type default)
			)
			(layer "F.Fab")
		)
		(fp_line
			(start -0.12065 0.2794)
			(end -0.12065 0.3048)
			(stroke
				(width 0.1)
				(type default)
			)
			(layer "F.Fab")
		)
		(fp_line
			(start -0.12065 0.3048)
			(end -0.67945 0.3048)
			(stroke
				(width 0.1)
				(type default)
			)
			(layer "F.Fab")
		)
		(fp_line
			(start 0.120396 0.2794)
			(end -0.12065 0.2794)
			(stroke
				(width 0.1)
				(type default)
			)
			(layer "F.Fab")
		)
		(fp_line
			(start 0.120396 0.3048)
			(end 0.120396 0.2794)
			(stroke
				(width 0.1)
				(type default)
			)
			(layer "F.Fab")
		)
		(fp_line
			(start 0.12065 -0.3048)
			(end 0.67945 -0.3048)
			(stroke
				(width 0.1)
				(type default)
			)
			(layer "F.Fab")
		)
		(fp_line
			(start 0.12065 -0.2794)
			(end 0.12065 -0.3048)
			(stroke
				(width 0.1)
				(type default)
			)
			(layer "F.Fab")
		)
		(fp_line
			(start 0.67945 -0.3048)
			(end 0.67945 0.3048)
			(stroke
				(width 0.1)
				(type default)
			)
			(layer "F.Fab")
		)
		(fp_line
			(start 0.67945 0.3048)
			(end 0.120396 0.3048)
			(stroke
				(width 0.1)
				(type default)
			)
			(layer "F.Fab")
		)
		(pad "1" smd circle
			(at -0.40005 0)
			(size 0 0)
			(layers "F.Cu" "F.Mask" "F.Paste")
			(net "SSD0_ADC_ALERT_N")
		)
		(pad "2" smd circle
			(at 0.40005 0)
			(size 0 0)
			(layers "F.Cu" "F.Mask" "F.Paste")
			(net "SSD_0_7_ADC_ALERT_N")
		)
	)
	(footprint ""
		(layer "F.Cu")
		(at 227.31476 -312.671714)
		(property "Reference" "PC224"
			(at 0 0 0)
			(layer "F.SilkS")
			(hide yes)
			(effects
				(font
					(size 1.27 1.27)
				)
			)
		)
		(property "Value" ""
			(at 0 0 0)
			(layer "F.Fab")
			(effects
				(font
					(size 1.27 1.27)
				)
			)
		)
		(duplicate_pad_numbers_are_jumpers no)
		(fp_line
			(start -1.524 -0.762)
			(end 1.524 -0.762)
			(stroke
				(width 0.1524)
				(type default)
			)
			(layer "F.SilkS")
		)
		(fp_line
			(start -1.524 0.762)
			(end -1.524 -0.762)
			(stroke
				(width 0.1524)
				(type default)
			)
			(layer "F.SilkS")
		)
		(fp_line
			(start 1.524 -0.762)
			(end 1.524 0.762)
			(stroke
				(width 0.1524)
				(type default)
			)
			(layer "F.SilkS")
		)
		(fp_line
			(start 1.524 0.762)
			(end -1.524 0.762)
			(stroke
				(width 0.1524)
				(type default)
			)
			(layer "F.SilkS")
		)
		(fp_line
			(start -1.1049 -0.724916)
			(end -1.1049 0.724916)
			(stroke
				(width 0.1)
				(type default)
			)
			(layer "F.Fab")
		)
		(fp_line
			(start -1.1049 0.724916)
			(end 1.1049 0.724916)
			(stroke
				(width 0.1)
				(type default)
			)
			(layer "F.Fab")
		)
		(fp_line
			(start 1.1049 -0.724916)
			(end -1.1049 -0.724916)
			(stroke
				(width 0.1)
				(type default)
			)
			(layer "F.Fab")
		)
		(fp_line
			(start 1.1049 0.724916)
			(end 1.1049 -0.724916)
			(stroke
				(width 0.1)
				(type default)
			)
			(layer "F.Fab")
		)
		(pad "1" smd rect
			(at -0.889 0 180)
			(size 1.016 1.27)
			(layers "F.Cu" "F.Mask" "F.Paste")
			(net "SW_P12V_P1V25_PEX1_FLT")
		)
		(pad "2" smd rect
			(at 0.889 0 180)
			(size 1.016 1.27)
			(layers "F.Cu" "F.Mask" "F.Paste")
			(net "GND")
		)
	)
	(footprint ""
		(layer "F.Cu")
		(at 211.37118 -120.021858)
		(property "Reference" "PU52"
			(at -0.845312 2.627122 0)
			(unlocked yes)
			(layer "F.SilkS")
			(effects
				(font
					(size 0.7874 0.5842)
					(thickness 0.1524)
				)
				(justify left)
			)
		)
		(property "Value" ""
			(at 0 0 0)
			(layer "F.Fab")
			(effects
				(font
					(size 1.27 1.27)
				)
			)
		)
		(duplicate_pad_numbers_are_jumpers no)
		(fp_line
			(start -1.943608 -1.549908)
			(end 1.943608 -1.549908)
			(stroke
				(width 0.1524)
				(type default)
			)
			(layer "F.SilkS")
		)
		(fp_line
			(start -1.943608 1.549908)
			(end -1.943608 -1.549908)
			(stroke
				(width 0.1524)
				(type default)
			)
			(layer "F.SilkS")
		)
		(fp_line
			(start 1.943608 -1.549908)
			(end 1.943608 1.549908)
			(stroke
				(width 0.1524)
				(type default)
			)
			(layer "F.SilkS")
		)
		(fp_line
			(start 1.943608 1.549908)
			(end -1.943608 1.549908)
			(stroke
				(width 0.1524)
				(type default)
			)
			(layer "F.SilkS")
		)
		(fp_poly
			(pts
				(xy -2.019808 -1.549908) (xy -1.257808 -1.549908) (xy -1.257808 -1.880108) (xy -2.019808 -1.880108)
			)
			(stroke
				(width 0)
				(type default)
			)
			(fill yes)
			(layer "F.SilkS")
		)
		(fp_line
			(start -1.549908 -1.549908)
			(end 1.549908 -1.549908)
			(stroke
				(width 0.1)
				(type default)
			)
			(layer "F.Fab")
		)
		(fp_line
			(start -1.549908 1.549908)
			(end -1.549908 -1.549908)
			(stroke
				(width 0.1)
				(type default)
			)
			(layer "F.Fab")
		)
		(fp_line
			(start 1.549908 -1.549908)
			(end 1.549908 1.549908)
			(stroke
				(width 0.1)
				(type default)
			)
			(layer "F.Fab")
		)
		(fp_line
			(start 1.549908 1.549908)
			(end -1.549908 1.549908)
			(stroke
				(width 0.1)
				(type default)
			)
			(layer "F.Fab")
		)
		(fp_poly
			(pts
				(xy -2.019808 -1.549908) (xy -1.257808 -1.549908) (xy -1.257808 -1.880108) (xy -2.019808 -1.880108)
			)
			(stroke
				(width 0)
				(type default)
			)
			(fill yes)
			(layer "F.Fab")
		)
		(pad "1" smd rect
			(at -1.500124 -1.249934 270)
			(size 0.2794 0.6096)
			(layers "F.Cu" "F.Mask" "F.Paste")
			(net "P3V3_NIC3")
		)
		(pad "2" smd rect
			(at -1.500124 -0.750062 270)
			(size 0.2794 0.6096)
			(layers "F.Cu" "F.Mask" "F.Paste")
			(net "P3V3_NIC3")
		)
		(pad "3" smd rect
			(at -1.500124 -0.249936 270)
			(size 0.2794 0.6096)
			(layers "F.Cu" "F.Mask" "F.Paste")
			(net "P3V3_NIC3")
		)
		(pad "4" smd rect
			(at -1.500124 0.249936 270)
			(size 0.2794 0.6096)
			(layers "F.Cu" "F.Mask" "F.Paste")
			(net "P3V3_NIC3")
		)
		(pad "5" smd rect
			(at -1.500124 0.750062 270)
			(size 0.2794 0.6096)
			(layers "F.Cu" "F.Mask" "F.Paste")
			(net "P3V3_NIC3")
		)
		(pad "6" smd rect
			(at -1.500124 1.249934 270)
			(size 0.2794 0.6096)
			(layers "F.Cu" "F.Mask" "F.Paste")
			(net "GND")
		)
		(pad "7" smd rect
			(at 1.500124 1.249934 270)
			(size 0.2794 0.6096)
			(layers "F.Cu" "F.Mask" "F.Paste")
			(net "P3V3_NIC3_SS")
		)
		(pad "8" smd rect
			(at 1.500124 0.750062 270)
			(size 0.2794 0.6096)
			(layers "F.Cu" "F.Mask" "F.Paste")
			(net "PWRGD_P3V3_NIC3")
		)
		(pad "9" smd rect
			(at 1.500124 0.249936 270)
			(size 0.2794 0.6096)
			(layers "F.Cu" "F.Mask" "F.Paste")
			(net "P3V3_NIC3_OCP")
		)
		(pad "10" smd rect
			(at 1.500124 -0.249936 270)
			(size 0.2794 0.6096)
			(layers "F.Cu" "F.Mask" "F.Paste")
			(net "P5V_AUX")
		)
		(pad "11" smd rect
			(at 1.500124 -0.750062 270)
			(size 0.2794 0.6096)
			(layers "F.Cu" "F.Mask" "F.Paste")
			(net "HP_NIC3_EN")
		)
		(pad "12" smd rect
			(at 1.500124 -1.249934 270)
			(size 0.2794 0.6096)
			(layers "F.Cu" "F.Mask" "F.Paste")
			(net "P3V3_AUX")
		)
		(pad "13" smd rect
			(at 0 0)
			(size 1.9812 2.7178)
			(layers "F.Cu" "F.Mask" "F.Paste")
			(net "P3V3_AUX")
		)
		(zone
			(layer "F.Cu")
			(hatch none 0.5)
			(connect_pads
				(clearance 0)
			)
			(min_thickness 0.25)
			(keepout
				(tracks not_allowed)
				(vias allowed)
				(pads allowed)
				(copperpour not_allowed)
				(footprints allowed)
			)
			(placement
				(enabled no)
				(sheetname "")
			)
			(fill
				(thermal_gap 0.5)
				(thermal_bridge_width 0.5)
				(island_removal_mode 0)
			)
			(polygon
				(pts
					(xy 212.51418 -121.571258) (xy 212.51418 -121.444258) (xy 212.51418 -118.472458) (xy 212.51418 -118.47195)
					(xy 210.22818 -118.47195) (xy 210.22818 -118.472458) (xy 210.22818 -118.599458) (xy 210.22818 -120.021858)
					(xy 210.32978 -120.021858) (xy 210.32978 -118.599458) (xy 212.41258 -118.599458) (xy 212.41258 -121.444258)
					(xy 210.32978 -121.444258) (xy 210.32978 -120.047258) (xy 210.22818 -120.047258) (xy 210.22818 -121.444258)
					(xy 210.22818 -121.571258) (xy 210.22818 -121.571766) (xy 212.51418 -121.571766)
				)
			)
		)
	)
	(footprint ""
		(layer "F.Cu")
		(at 219.825316 -122.758962)
		(property "Reference" "R5957"
			(at 0 0 0)
			(layer "F.SilkS")
			(hide yes)
			(effects
				(font
					(size 1.27 1.27)
				)
			)
		)
		(property "Value" ""
			(at 0 0 0)
			(layer "F.Fab")
			(effects
				(font
					(size 1.27 1.27)
				)
			)
		)
		(duplicate_pad_numbers_are_jumpers no)
		(fp_line
			(start -0.7874 -0.4064)
			(end 0.7874 -0.4064)
			(stroke
				(width 0.1524)
				(type default)
			)
			(layer "F.SilkS")
		)
		(fp_line
			(start -0.7874 0.4064)
			(end -0.7874 -0.4064)
			(stroke
				(width 0.1524)
				(type default)
			)
			(layer "F.SilkS")
		)
		(fp_line
			(start 0.7874 -0.4064)
			(end 0.7874 0.4064)
			(stroke
				(width 0.1524)
				(type default)
			)
			(layer "F.SilkS")
		)
		(fp_line
			(start 0.7874 0.4064)
			(end -0.7874 0.4064)
			(stroke
				(width 0.1524)
				(type default)
			)
			(layer "F.SilkS")
		)
		(fp_line
			(start -0.67945 -0.305054)
			(end -0.12065 -0.305054)
			(stroke
				(width 0.1)
				(type default)
			)
			(layer "F.Fab")
		)
		(fp_line
			(start -0.67945 0.3048)
			(end -0.67945 -0.305054)
			(stroke
				(width 0.1)
				(type default)
			)
			(layer "F.Fab")
		)
		(fp_line
			(start -0.12065 -0.305054)
			(end -0.12065 -0.2794)
			(stroke
				(width 0.1)
				(type default)
			)
			(layer "F.Fab")
		)
		(fp_line
			(start -0.12065 -0.2794)
			(end 0.12065 -0.2794)
			(stroke
				(width 0.1)
				(type default)
			)
			(layer "F.Fab")
		)
		(fp_line
			(start -0.12065 0.2794)
			(end -0.12065 0.3048)
			(stroke
				(width 0.1)
				(type default)
			)
			(layer "F.Fab")
		)
		(fp_line
			(start -0.12065 0.3048)
			(end -0.67945 0.3048)
			(stroke
				(width 0.1)
				(type default)
			)
			(layer "F.Fab")
		)
		(fp_line
			(start 0.120396 0.2794)
			(end -0.12065 0.2794)
			(stroke
				(width 0.1)
				(type default)
			)
			(layer "F.Fab")
		)
		(fp_line
			(start 0.120396 0.3048)
			(end 0.120396 0.2794)
			(stroke
				(width 0.1)
				(type default)
			)
			(layer "F.Fab")
		)
		(fp_line
			(start 0.12065 -0.3048)
			(end 0.67945 -0.3048)
			(stroke
				(width 0.1)
				(type default)
			)
			(layer "F.Fab")
		)
		(fp_line
			(start 0.12065 -0.2794)
			(end 0.12065 -0.3048)
			(stroke
				(width 0.1)
				(type default)
			)
			(layer "F.Fab")
		)
		(fp_line
			(start 0.67945 -0.3048)
			(end 0.67945 0.3048)
			(stroke
				(width 0.1)
				(type default)
			)
			(layer "F.Fab")
		)
		(fp_line
			(start 0.67945 0.3048)
			(end 0.120396 0.3048)
			(stroke
				(width 0.1)
				(type default)
			)
			(layer "F.Fab")
		)
		(pad "1" smd circle
			(at -0.40005 0)
			(size 0 0)
			(layers "F.Cu" "F.Mask" "F.Paste")
			(net "P3V3_AUX")
		)
		(pad "2" smd circle
			(at 0.40005 0)
			(size 0 0)
			(layers "F.Cu" "F.Mask" "F.Paste")
			(net "PWRGD_P3V3_NIC3_D")
		)
	)
	(footprint ""
		(layer "F.Cu")
		(at 83.293966 -35.264852)
		(property "Reference" "R5659"
			(at 0 0 0)
			(layer "F.SilkS")
			(hide yes)
			(effects
				(font
					(size 1.27 1.27)
				)
			)
		)
		(property "Value" ""
			(at 0 0 0)
			(layer "F.Fab")
			(effects
				(font
					(size 1.27 1.27)
				)
			)
		)
		(duplicate_pad_numbers_are_jumpers no)
		(fp_line
			(start -0.7874 -0.4064)
			(end 0.7874 -0.4064)
			(stroke
				(width 0.1524)
				(type default)
			)
			(layer "F.SilkS")
		)
		(fp_line
			(start -0.7874 0.4064)
			(end -0.7874 -0.4064)
			(stroke
				(width 0.1524)
				(type default)
			)
			(layer "F.SilkS")
		)
		(fp_line
			(start 0.7874 -0.4064)
			(end 0.7874 0.4064)
			(stroke
				(width 0.1524)
				(type default)
			)
			(layer "F.SilkS")
		)
		(fp_line
			(start 0.7874 0.4064)
			(end -0.7874 0.4064)
			(stroke
				(width 0.1524)
				(type default)
			)
			(layer "F.SilkS")
		)
		(fp_line
			(start -0.67945 -0.305054)
			(end -0.12065 -0.305054)
			(stroke
				(width 0.1)
				(type default)
			)
			(layer "F.Fab")
		)
		(fp_line
			(start -0.67945 0.3048)
			(end -0.67945 -0.305054)
			(stroke
				(width 0.1)
				(type default)
			)
			(layer "F.Fab")
		)
		(fp_line
			(start -0.12065 -0.305054)
			(end -0.12065 -0.2794)
			(stroke
				(width 0.1)
				(type default)
			)
			(layer "F.Fab")
		)
		(fp_line
			(start -0.12065 -0.2794)
			(end 0.12065 -0.2794)
			(stroke
				(width 0.1)
				(type default)
			)
			(layer "F.Fab")
		)
		(fp_line
			(start -0.12065 0.2794)
			(end -0.12065 0.3048)
			(stroke
				(width 0.1)
				(type default)
			)
			(layer "F.Fab")
		)
		(fp_line
			(start -0.12065 0.3048)
			(end -0.67945 0.3048)
			(stroke
				(width 0.1)
				(type default)
			)
			(layer "F.Fab")
		)
		(fp_line
			(start 0.120396 0.2794)
			(end -0.12065 0.2794)
			(stroke
				(width 0.1)
				(type default)
			)
			(layer "F.Fab")
		)
		(fp_line
			(start 0.120396 0.3048)
			(end 0.120396 0.2794)
			(stroke
				(width 0.1)
				(type default)
			)
			(layer "F.Fab")
		)
		(fp_line
			(start 0.12065 -0.3048)
			(end 0.67945 -0.3048)
			(stroke
				(width 0.1)
				(type default)
			)
			(layer "F.Fab")
		)
		(fp_line
			(start 0.12065 -0.2794)
			(end 0.12065 -0.3048)
			(stroke
				(width 0.1)
				(type default)
			)
			(layer "F.Fab")
		)
		(fp_line
			(start 0.67945 -0.3048)
			(end 0.67945 0.3048)
			(stroke
				(width 0.1)
				(type default)
			)
			(layer "F.Fab")
		)
		(fp_line
			(start 0.67945 0.3048)
			(end 0.120396 0.3048)
			(stroke
				(width 0.1)
				(type default)
			)
			(layer "F.Fab")
		)
		(pad "1" smd circle
			(at -0.40005 0)
			(size 0 0)
			(layers "F.Cu" "F.Mask" "F.Paste")
			(net "RST_SMB_SSD3_ISO_N")
		)
		(pad "2" smd circle
			(at 0.40005 0)
			(size 0 0)
			(layers "F.Cu" "F.Mask" "F.Paste")
			(net "GND")
		)
	)
	(footprint ""
		(layer "F.Cu")
		(at 324.589648 -298.885102 -90)
		(property "Reference" "R3973"
			(at 0 0 270)
			(layer "F.SilkS")
			(hide yes)
			(effects
				(font
					(size 1.27 1.27)
				)
			)
		)
		(property "Value" ""
			(at 0 0 270)
			(layer "F.Fab")
			(effects
				(font
					(size 1.27 1.27)
				)
			)
		)
		(duplicate_pad_numbers_are_jumpers no)
		(fp_line
			(start -0.7874 0.4064)
			(end -0.7874 -0.4064)
			(stroke
				(width 0.1524)
				(type default)
			)
			(layer "F.SilkS")
		)
		(fp_line
			(start 0.7874 0.4064)
			(end -0.7874 0.4064)
			(stroke
				(width 0.1524)
				(type default)
			)
			(layer "F.SilkS")
		)
		(fp_line
			(start -0.7874 -0.4064)
			(end 0.7874 -0.4064)
			(stroke
				(width 0.1524)
				(type default)
			)
			(layer "F.SilkS")
		)
		(fp_line
			(start 0.7874 -0.4064)
			(end 0.7874 0.4064)
			(stroke
				(width 0.1524)
				(type default)
			)
			(layer "F.SilkS")
		)
		(fp_line
			(start -0.67945 0.3048)
			(end -0.67945 -0.305054)
			(stroke
				(width 0.1)
				(type default)
			)
			(layer "F.Fab")
		)
		(fp_line
			(start -0.12065 0.3048)
			(end -0.67945 0.3048)
			(stroke
				(width 0.1)
				(type default)
			)
			(layer "F.Fab")
		)
		(fp_line
			(start 0.120396 0.3048)
			(end 0.120396 0.2794)
			(stroke
				(width 0.1)
				(type default)
			)
			(layer "F.Fab")
		)
		(fp_line
			(start 0.67945 0.3048)
			(end 0.120396 0.3048)
			(stroke
				(width 0.1)
				(type default)
			)
			(layer "F.Fab")
		)
		(fp_line
			(start -0.12065 0.2794)
			(end -0.12065 0.3048)
			(stroke
				(width 0.1)
				(type default)
			)
			(layer "F.Fab")
		)
		(fp_line
			(start 0.120396 0.2794)
			(end -0.12065 0.2794)
			(stroke
				(width 0.1)
				(type default)
			)
			(layer "F.Fab")
		)
		(fp_line
			(start -0.12065 -0.2794)
			(end 0.12065 -0.2794)
			(stroke
				(width 0.1)
				(type default)
			)
			(layer "F.Fab")
		)
		(fp_line
			(start 0.12065 -0.2794)
			(end 0.12065 -0.3048)
			(stroke
				(width 0.1)
				(type default)
			)
			(layer "F.Fab")
		)
		(fp_line
			(start 0.12065 -0.3048)
			(end 0.67945 -0.3048)
			(stroke
				(width 0.1)
				(type default)
			)
			(layer "F.Fab")
		)
		(fp_line
			(start 0.67945 -0.3048)
			(end 0.67945 0.3048)
			(stroke
				(width 0.1)
				(type default)
			)
			(layer "F.Fab")
		)
		(fp_line
			(start -0.67945 -0.305054)
			(end -0.12065 -0.305054)
			(stroke
				(width 0.1)
				(type default)
			)
			(layer "F.Fab")
		)
		(fp_line
			(start -0.12065 -0.305054)
			(end -0.12065 -0.2794)
			(stroke
				(width 0.1)
				(type default)
			)
			(layer "F.Fab")
		)
		(pad "1" smd circle
			(at -0.40005 0 270)
			(size 0 0)
			(layers "F.Cu" "F.Mask" "F.Paste")
			(net "I2C_PEX2_HOST_SCL")
		)
		(pad "2" smd circle
			(at 0.40005 0 270)
			(size 0 0)
			(layers "F.Cu" "F.Mask" "F.Paste")
			(net "I2C_PEX2_HOST_R_SCL")
		)
	)
	(footprint ""
		(layer "F.Cu")
		(at 230.294434 -368.957606 180)
		(property "Reference" "PU3"
			(at -5.235448 -2.776982 0)
			(unlocked yes)
			(layer "F.SilkS")
			(effects
				(font
					(size 0.7874 0.5842)
					(thickness 0.1524)
				)
			)
		)
		(property "Value" ""
			(at 0 0 180)
			(layer "F.Fab")
			(effects
				(font
					(size 1.27 1.27)
				)
			)
		)
		(duplicate_pad_numbers_are_jumpers no)
		(fp_line
			(start 2.567686 2.567686)
			(end 2.567686 -2.567686)
			(stroke
				(width 0.1524)
				(type default)
			)
			(layer "F.SilkS")
		)
		(fp_line
			(start 2.567686 -2.567686)
			(end -2.567686 -2.567686)
			(stroke
				(width 0.1524)
				(type default)
			)
			(layer "F.SilkS")
		)
		(fp_line
			(start -2.567686 2.567686)
			(end 2.567686 2.567686)
			(stroke
				(width 0.1524)
				(type default)
			)
			(layer "F.SilkS")
		)
		(fp_line
			(start -2.567686 -2.567686)
			(end -2.567686 2.567686)
			(stroke
				(width 0.1524)
				(type default)
			)
			(layer "F.SilkS")
		)
		(fp_poly
			(pts
				(xy -2.965704 -3.687064) (xy -3.684016 -2.968752) (xy -2.606548 -2.609342)
			)
			(stroke
				(width 0)
				(type default)
			)
			(fill yes)
			(layer "F.SilkS")
		)
		(fp_line
			(start 2.549906 2.549906)
			(end 2.549906 -2.549906)
			(stroke
				(width 0.1)
				(type default)
			)
			(layer "F.Fab")
		)
		(fp_line
			(start 2.549906 -2.549906)
			(end -2.549906 -2.549906)
			(stroke
				(width 0.1)
				(type default)
			)
			(layer "F.Fab")
		)
		(fp_line
			(start -2.549906 2.549906)
			(end 2.549906 2.549906)
			(stroke
				(width 0.1)
				(type default)
			)
			(layer "F.Fab")
		)
		(fp_line
			(start -2.549906 -2.549906)
			(end -2.549906 2.549906)
			(stroke
				(width 0.1)
				(type default)
			)
			(layer "F.Fab")
		)
		(fp_poly
			(pts
				(xy -3.806698 -2.25806) (xy -3.806698 -1.24206) (xy -2.790698 -1.75006)
			)
			(stroke
				(width 0)
				(type default)
			)
			(fill yes)
			(layer "F.Fab")
		)
		(pad "1" smd rect
			(at -2.250186 -1.75006 270)
			(size 0.254 0.3556)
			(layers "F.Cu" "F.Mask" "F.Paste")
			(net "P12V_AUX")
		)
		(pad "2" smd rect
			(at -2.237486 -1.249934 270)
			(size 0.254 0.381)
			(layers "F.Cu" "F.Mask" "F.Paste")
			(net "P12V_AUX")
		)
		(pad "3" smd rect
			(at -2.237486 -0.750062 270)
			(size 0.254 0.381)
			(layers "F.Cu" "F.Mask" "F.Paste")
			(net "HSC_D_OC_2")
		)
		(pad "4" smd rect
			(at -2.237486 -0.249936 270)
			(size 0.254 0.381)
			(layers "F.Cu" "F.Mask" "F.Paste")
			(net "HSC_ON")
		)
		(pad "5" smd rect
			(at -2.237486 0.249936 270)
			(size 0.254 0.381)
			(layers "F.Cu" "F.Mask" "F.Paste")
			(net "HSC_FAULT_N_2")
		)
		(pad "6" smd rect
			(at -2.237486 0.750062 270)
			(size 0.254 0.381)
			(layers "F.Cu" "F.Mask" "F.Paste")
			(net "HSC_FLT_TYPE_2")
		)
		(pad "7" smd rect
			(at -2.237486 1.249934 270)
			(size 0.254 0.381)
			(layers "F.Cu" "F.Mask" "F.Paste")
			(net "Net_9083")
		)
		(pad "8" smd rect
			(at -2.250186 1.75006 270)
			(size 0.254 0.3556)
			(layers "F.Cu" "F.Mask" "F.Paste")
			(net "HSC_MODE_2")
		)
		(pad "9" smd rect
			(at -1.75006 2.250186 180)
			(size 0.254 0.3556)
			(layers "F.Cu" "F.Mask" "F.Paste")
			(net "P12V_STBY")
		)
		(pad "10" smd rect
			(at -1.249934 2.237486 180)
			(size 0.254 0.381)
			(layers "F.Cu" "F.Mask" "F.Paste")
			(net "P12V_STBY")
		)
		(pad "11" smd rect
			(at -0.750062 2.237486 180)
			(size 0.254 0.381)
			(layers "F.Cu" "F.Mask" "F.Paste")
			(net "P12V_STBY")
		)
		(pad "12" smd rect
			(at -0.249936 2.237486 180)
			(size 0.254 0.381)
			(layers "F.Cu" "F.Mask" "F.Paste")
			(net "P12V_STBY")
		)
		(pad "13" smd rect
			(at 0.249936 2.237486 180)
			(size 0.254 0.381)
			(layers "F.Cu" "F.Mask" "F.Paste")
			(net "P12V_STBY")
		)
		(pad "14" smd rect
			(at 0.750062 2.237486 180)
			(size 0.254 0.381)
			(layers "F.Cu" "F.Mask" "F.Paste")
			(net "P12V_STBY")
		)
		(pad "15" smd rect
			(at 1.249934 2.237486 180)
			(size 0.254 0.381)
			(layers "F.Cu" "F.Mask" "F.Paste")
			(net "P12V_STBY")
		)
		(pad "16" smd rect
			(at 1.75006 2.250186 180)
			(size 0.254 0.3556)
			(layers "F.Cu" "F.Mask" "F.Paste")
			(net "P12V_STBY")
		)
		(pad "17" smd rect
			(at 2.250186 1.75006 270)
			(size 0.254 0.3556)
			(layers "F.Cu" "F.Mask" "F.Paste")
			(net "HSC_SCREF_2")
		)
		(pad "18" smd rect
			(at 2.237486 1.249934 270)
			(size 0.254 0.381)
			(layers "F.Cu" "F.Mask" "F.Paste")
			(net "HSC_VTEMP")
		)
		(pad "19" smd rect
			(at 2.237486 0.750062 270)
			(size 0.254 0.381)
			(layers "F.Cu" "F.Mask" "F.Paste")
			(net "HSC_SS")
		)
		(pad "20" smd rect
			(at 2.237486 0.249936 270)
			(size 0.254 0.381)
			(layers "F.Cu" "F.Mask" "F.Paste")
			(net "AGND_HSC")
		)
		(pad "21" smd rect
			(at 2.237486 -0.249936 270)
			(size 0.254 0.381)
			(layers "F.Cu" "F.Mask" "F.Paste")
			(net "HSC_VDD_2")
		)
		(pad "22" smd rect
			(at 2.237486 -0.750062 270)
			(size 0.254 0.381)
			(layers "F.Cu" "F.Mask" "F.Paste")
			(net "HSC_IMON")
		)
		(pad "23" smd rect
			(at 2.237486 -1.249934 270)
			(size 0.254 0.381)
			(layers "F.Cu" "F.Mask" "F.Paste")
			(net "HSC_CS_2")
		)
		(pad "24" smd rect
			(at 2.250186 -1.75006 270)
			(size 0.254 0.3556)
			(layers "F.Cu" "F.Mask" "F.Paste")
			(net "HSC_OCREF")
		)
		(pad "25" smd rect
			(at 1.75006 -2.250186 180)
			(size 0.254 0.3556)
			(layers "F.Cu" "F.Mask" "F.Paste")
			(net "P12V_AUX")
		)
		(pad "26" smd rect
			(at 1.249934 -2.237486 180)
			(size 0.254 0.381)
			(layers "F.Cu" "F.Mask" "F.Paste")
			(net "P12V_AUX")
		)
		(pad "27" smd rect
			(at 0.750062 -2.237486 180)
			(size 0.254 0.381)
			(layers "F.Cu" "F.Mask" "F.Paste")
			(net "P12V_AUX")
		)
		(pad "28" smd rect
			(at 0.249936 -2.237486 180)
			(size 0.254 0.381)
			(layers "F.Cu" "F.Mask" "F.Paste")
			(net "P12V_AUX")
		)
		(pad "29" smd rect
			(at -0.249936 -2.237486 180)
			(size 0.254 0.381)
			(layers "F.Cu" "F.Mask" "F.Paste")
			(net "P12V_AUX")
		)
		(pad "30" smd rect
			(at -0.750062 -2.237486 180)
			(size 0.254 0.381)
			(layers "F.Cu" "F.Mask" "F.Paste")
			(net "P12V_AUX")
		)
		(pad "31" smd rect
			(at -1.249934 -2.237486 180)
			(size 0.254 0.381)
			(layers "F.Cu" "F.Mask" "F.Paste")
			(net "P12V_AUX")
		)
		(pad "32" smd rect
			(at -1.75006 -2.250186 180)
			(size 0.254 0.3556)
			(layers "F.Cu" "F.Mask" "F.Paste")
			(net "P12V_AUX")
		)
		(pad "33" smd rect
			(at 0 0 180)
			(size 3.4036 3.4036)
			(layers "F.Cu" "F.Mask" "F.Paste")
			(net "P12V_STBY")
		)
	)
	(footprint ""
		(layer "F.Cu")
		(at 358.037892 -207.183482 180)
		(property "Reference" "R6422"
			(at 0 0 180)
			(layer "F.SilkS")
			(hide yes)
			(effects
				(font
					(size 1.27 1.27)
				)
			)
		)
		(property "Value" ""
			(at 0 0 180)
			(layer "F.Fab")
			(effects
				(font
					(size 1.27 1.27)
				)
			)
		)
		(duplicate_pad_numbers_are_jumpers no)
		(fp_line
			(start 0.7874 0.4064)
			(end -0.7874 0.4064)
			(stroke
				(width 0.1524)
				(type default)
			)
			(layer "F.SilkS")
		)
		(fp_line
			(start 0.7874 -0.4064)
			(end 0.7874 0.4064)
			(stroke
				(width 0.1524)
				(type default)
			)
			(layer "F.SilkS")
		)
		(fp_line
			(start -0.7874 0.4064)
			(end -0.7874 -0.4064)
			(stroke
				(width 0.1524)
				(type default)
			)
			(layer "F.SilkS")
		)
		(fp_line
			(start -0.7874 -0.4064)
			(end 0.7874 -0.4064)
			(stroke
				(width 0.1524)
				(type default)
			)
			(layer "F.SilkS")
		)
		(fp_line
			(start 0.67945 0.3048)
			(end 0.120396 0.3048)
			(stroke
				(width 0.1)
				(type default)
			)
			(layer "F.Fab")
		)
		(fp_line
			(start 0.67945 -0.3048)
			(end 0.67945 0.3048)
			(stroke
				(width 0.1)
				(type default)
			)
			(layer "F.Fab")
		)
		(fp_line
			(start 0.12065 -0.2794)
			(end 0.12065 -0.3048)
			(stroke
				(width 0.1)
				(type default)
			)
			(layer "F.Fab")
		)
		(fp_line
			(start 0.12065 -0.3048)
			(end 0.67945 -0.3048)
			(stroke
				(width 0.1)
				(type default)
			)
			(layer "F.Fab")
		)
		(fp_line
			(start 0.120396 0.3048)
			(end 0.120396 0.2794)
			(stroke
				(width 0.1)
				(type default)
			)
			(layer "F.Fab")
		)
		(fp_line
			(start 0.120396 0.2794)
			(end -0.12065 0.2794)
			(stroke
				(width 0.1)
				(type default)
			)
			(layer "F.Fab")
		)
		(fp_line
			(start -0.12065 0.3048)
			(end -0.67945 0.3048)
			(stroke
				(width 0.1)
				(type default)
			)
			(layer "F.Fab")
		)
		(fp_line
			(start -0.12065 0.2794)
			(end -0.12065 0.3048)
			(stroke
				(width 0.1)
				(type default)
			)
			(layer "F.Fab")
		)
		(fp_line
			(start -0.12065 -0.2794)
			(end 0.12065 -0.2794)
			(stroke
				(width 0.1)
				(type default)
			)
			(layer "F.Fab")
		)
		(fp_line
			(start -0.12065 -0.305054)
			(end -0.12065 -0.2794)
			(stroke
				(width 0.1)
				(type default)
			)
			(layer "F.Fab")
		)
		(fp_line
			(start -0.67945 0.3048)
			(end -0.67945 -0.305054)
			(stroke
				(width 0.1)
				(type default)
			)
			(layer "F.Fab")
		)
		(fp_line
			(start -0.67945 -0.305054)
			(end -0.12065 -0.305054)
			(stroke
				(width 0.1)
				(type default)
			)
			(layer "F.Fab")
		)
		(pad "1" smd circle
			(at -0.40005 0 180)
			(size 0 0)
			(layers "F.Cu" "F.Mask" "F.Paste")
			(net "FPGA_PEX3_MODE_SEL2_R")
		)
		(pad "2" smd circle
			(at 0.40005 0 180)
			(size 0 0)
			(layers "F.Cu" "F.Mask" "F.Paste")
			(net "FPGA_PEX3_MODE_SEL2")
		)
	)
	(footprint ""
		(layer "F.Cu")
		(at 214.757 -198.12)
		(property "Reference" "U121"
			(at -1.397 -2.13233 0)
			(unlocked yes)
			(layer "F.SilkS")
			(effects
				(font
					(size 0.7874 0.5842)
					(thickness 0.1524)
				)
				(justify left)
			)
		)
		(property "Value" ""
			(at 0 0 0)
			(layer "F.Fab")
			(effects
				(font
					(size 1.27 1.27)
				)
			)
		)
		(duplicate_pad_numbers_are_jumpers no)
		(fp_line
			(start -1.3208 -1.525016)
			(end -0.508 -1.525016)
			(stroke
				(width 0.1524)
				(type default)
			)
			(layer "F.SilkS")
		)
		(fp_line
			(start -1.3208 1.525016)
			(end -1.3208 -1.525016)
			(stroke
				(width 0.1524)
				(type default)
			)
			(layer "F.SilkS")
		)
		(fp_line
			(start -0.508 -1.525016)
			(end 0 -0.999998)
			(stroke
				(width 0.1524)
				(type default)
			)
			(layer "F.SilkS")
		)
		(fp_line
			(start 0 -0.999998)
			(end 0.508 -1.525016)
			(stroke
				(width 0.1524)
				(type default)
			)
			(layer "F.SilkS")
		)
		(fp_line
			(start 0.508 -1.525016)
			(end 1.3208 -1.525016)
			(stroke
				(width 0.1524)
				(type default)
			)
			(layer "F.SilkS")
		)
		(fp_line
			(start 1.3208 -1.525016)
			(end 1.3208 1.525016)
			(stroke
				(width 0.1524)
				(type default)
			)
			(layer "F.SilkS")
		)
		(fp_line
			(start 1.3208 1.525016)
			(end -1.3208 1.525016)
			(stroke
				(width 0.1524)
				(type default)
			)
			(layer "F.SilkS")
		)
		(fp_poly
			(pts
				(xy -2.897886 -1.428496) (xy -3.706114 -1.697736) (xy -3.167126 -2.236724)
			)
			(stroke
				(width 0)
				(type default)
			)
			(fill yes)
			(layer "F.SilkS")
		)
		(fp_line
			(start -3.037078 -1.20777)
			(end -1.524 -1.20777)
			(stroke
				(width 0.1)
				(type default)
			)
			(layer "F.Fab")
		)
		(fp_line
			(start -3.037078 1.203706)
			(end -3.037078 -1.20777)
			(stroke
				(width 0.1)
				(type default)
			)
			(layer "F.Fab")
		)
		(fp_line
			(start -1.5494 1.203706)
			(end -3.037078 1.203706)
			(stroke
				(width 0.1)
				(type default)
			)
			(layer "F.Fab")
		)
		(fp_line
			(start -1.5494 1.5494)
			(end -1.5494 1.203706)
			(stroke
				(width 0.1)
				(type default)
			)
			(layer "F.Fab")
		)
		(fp_line
			(start -1.524 -1.524)
			(end 1.524 -1.524)
			(stroke
				(width 0.1)
				(type default)
			)
			(layer "F.Fab")
		)
		(fp_line
			(start -1.524 -1.20777)
			(end -1.524 -1.524)
			(stroke
				(width 0.1)
				(type default)
			)
			(layer "F.Fab")
		)
		(fp_line
			(start 1.524 -1.524)
			(end 1.524 -1.20777)
			(stroke
				(width 0.1)
				(type default)
			)
			(layer "F.Fab")
		)
		(fp_line
			(start 1.524 -1.20777)
			(end 3.0353 -1.20777)
			(stroke
				(width 0.1)
				(type default)
			)
			(layer "F.Fab")
		)
		(fp_line
			(start 1.524 1.208786)
			(end 1.524 1.5494)
			(stroke
				(width 0.1)
				(type default)
			)
			(layer "F.Fab")
		)
		(fp_line
			(start 1.524 1.5494)
			(end -1.5494 1.5494)
			(stroke
				(width 0.1)
				(type default)
			)
			(layer "F.Fab")
		)
		(fp_line
			(start 3.0353 -1.20777)
			(end 3.0353 1.208786)
			(stroke
				(width 0.1)
				(type default)
			)
			(layer "F.Fab")
		)
		(fp_line
			(start 3.0353 1.208786)
			(end 1.524 1.208786)
			(stroke
				(width 0.1)
				(type default)
			)
			(layer "F.Fab")
		)
		(fp_poly
			(pts
				(xy -3.175 -1.016) (xy -3.937 -0.635) (xy -3.937 -1.397)
			)
			(stroke
				(width 0)
				(type default)
			)
			(fill yes)
			(layer "F.Fab")
		)
		(pad "1" smd rect
			(at -2.234946 -0.975106 270)
			(size 0.3556 1.4986)
			(layers "F.Cu" "F.Mask" "F.Paste")
			(net "P1V2_AUX")
		)
		(pad "2" smd rect
			(at -2.234946 -0.32512 270)
			(size 0.3556 1.4986)
			(layers "F.Cu" "F.Mask" "F.Paste")
			(net "SMB_NIC6_R_SDA")
		)
		(pad "3" smd rect
			(at -2.234946 0.32512 270)
			(size 0.3556 1.4986)
			(layers "F.Cu" "F.Mask" "F.Paste")
			(net "SMB_NIC6_R_SCL")
		)
		(pad "4" smd rect
			(at -2.234946 0.975106 270)
			(size 0.3556 1.4986)
			(layers "F.Cu" "F.Mask" "F.Paste")
			(net "GND")
		)
		(pad "5" smd rect
			(at 2.234946 0.975106 270)
			(size 0.3556 1.4986)
			(layers "F.Cu" "F.Mask" "F.Paste")
			(net "SMB_NIC6_LS_EN")
		)
		(pad "6" smd rect
			(at 2.234946 0.32512 270)
			(size 0.3556 1.4986)
			(layers "F.Cu" "F.Mask" "F.Paste")
			(net "SMB_NIC6_LS_R_SCL")
		)
		(pad "7" smd rect
			(at 2.234946 -0.32512 270)
			(size 0.3556 1.4986)
			(layers "F.Cu" "F.Mask" "F.Paste")
			(net "SMB_NIC6_LS_R_SDA")
		)
		(pad "8" smd rect
			(at 2.234946 -0.975106 270)
			(size 0.3556 1.4986)
			(layers "F.Cu" "F.Mask" "F.Paste")
			(net "P3V3_NIC6")
		)
	)
	(footprint ""
		(layer "F.Cu")
		(at 239.754918 -312.316114 180)
		(property "Reference" "PC244"
			(at 0 0 180)
			(layer "F.SilkS")
			(hide yes)
			(effects
				(font
					(size 1.27 1.27)
				)
			)
		)
		(property "Value" ""
			(at 0 0 180)
			(layer "F.Fab")
			(effects
				(font
					(size 1.27 1.27)
				)
			)
		)
		(duplicate_pad_numbers_are_jumpers no)
		(fp_line
			(start 1.524 0.762)
			(end -1.524 0.762)
			(stroke
				(width 0.1524)
				(type default)
			)
			(layer "F.SilkS")
		)
		(fp_line
			(start 1.524 -0.762)
			(end 1.524 0.762)
			(stroke
				(width 0.1524)
				(type default)
			)
			(layer "F.SilkS")
		)
		(fp_line
			(start -1.524 0.762)
			(end -1.524 -0.762)
			(stroke
				(width 0.1524)
				(type default)
			)
			(layer "F.SilkS")
		)
		(fp_line
			(start -1.524 -0.762)
			(end 1.524 -0.762)
			(stroke
				(width 0.1524)
				(type default)
			)
			(layer "F.SilkS")
		)
		(fp_line
			(start 1.1049 0.724916)
			(end 1.1049 -0.724916)
			(stroke
				(width 0.1)
				(type default)
			)
			(layer "F.Fab")
		)
		(fp_line
			(start 1.1049 -0.724916)
			(end -1.1049 -0.724916)
			(stroke
				(width 0.1)
				(type default)
			)
			(layer "F.Fab")
		)
		(fp_line
			(start -1.1049 0.724916)
			(end 1.1049 0.724916)
			(stroke
				(width 0.1)
				(type default)
			)
			(layer "F.Fab")
		)
		(fp_line
			(start -1.1049 -0.724916)
			(end -1.1049 0.724916)
			(stroke
				(width 0.1)
				(type default)
			)
			(layer "F.Fab")
		)
		(pad "1" smd rect
			(at -0.889 0)
			(size 1.016 1.27)
			(layers "F.Cu" "F.Mask" "F.Paste")
			(net "SW_P12V_P1V25_PEX2_FLT")
		)
		(pad "2" smd rect
			(at 0.889 0)
			(size 1.016 1.27)
			(layers "F.Cu" "F.Mask" "F.Paste")
			(net "GND")
		)
	)
	(footprint ""
		(layer "F.Cu")
		(at 31.007304 -260.639814 -90)
		(property "Reference" "C3034"
			(at 0 0 270)
			(layer "F.SilkS")
			(hide yes)
			(effects
				(font
					(size 1.27 1.27)
				)
			)
		)
		(property "Value" ""
			(at 0 0 270)
			(layer "F.Fab")
			(effects
				(font
					(size 1.27 1.27)
				)
			)
		)
		(duplicate_pad_numbers_are_jumpers no)
		(fp_line
			(start -0.299974 0.150114)
			(end -0.299974 -0.150114)
			(stroke
				(width 0.1)
				(type default)
			)
			(layer "F.Fab")
		)
		(fp_line
			(start 0.299974 0.150114)
			(end -0.299974 0.150114)
			(stroke
				(width 0.1)
				(type default)
			)
			(layer "F.Fab")
		)
		(fp_line
			(start -0.299974 -0.150114)
			(end 0.299974 -0.150114)
			(stroke
				(width 0.1)
				(type default)
			)
			(layer "F.Fab")
		)
		(fp_line
			(start 0.299974 -0.150114)
			(end 0.299974 0.150114)
			(stroke
				(width 0.1)
				(type default)
			)
			(layer "F.Fab")
		)
		(pad "1" smd rect
			(at -0.2667 0 270)
			(size 0.3048 0.381)
			(layers "F.Cu" "F.Mask" "F.Paste")
			(net "P1V8_PLL0_PEX0")
		)
		(pad "2" smd rect
			(at 0.2667 0 270)
			(size 0.3048 0.381)
			(layers "F.Cu" "F.Mask" "F.Paste")
			(net "GND")
		)
	)
	(footprint ""
		(layer "F.Cu")
		(at 17.333214 -265.719052)
		(property "Reference" "C4224"
			(at 0 0 0)
			(layer "F.SilkS")
			(hide yes)
			(effects
				(font
					(size 1.27 1.27)
				)
			)
		)
		(property "Value" ""
			(at 0 0 0)
			(layer "F.Fab")
			(effects
				(font
					(size 1.27 1.27)
				)
			)
		)
		(duplicate_pad_numbers_are_jumpers no)
		(fp_line
			(start -0.299974 -0.150114)
			(end 0.299974 -0.150114)
			(stroke
				(width 0.1)
				(type default)
			)
			(layer "F.Fab")
		)
		(fp_line
			(start -0.299974 0.150114)
			(end -0.299974 -0.150114)
			(stroke
				(width 0.1)
				(type default)
			)
			(layer "F.Fab")
		)
		(fp_line
			(start 0.299974 -0.150114)
			(end 0.299974 0.150114)
			(stroke
				(width 0.1)
				(type default)
			)
			(layer "F.Fab")
		)
		(fp_line
			(start 0.299974 0.150114)
			(end -0.299974 0.150114)
			(stroke
				(width 0.1)
				(type default)
			)
			(layer "F.Fab")
		)
		(pad "1" smd rect
			(at -0.2667 0)
			(size 0.3048 0.381)
			(layers "F.Cu" "F.Mask" "F.Paste")
			(net "P1V25_SERDES_VDDPLL_PEX0")
		)
		(pad "2" smd rect
			(at 0.2667 0)
			(size 0.3048 0.381)
			(layers "F.Cu" "F.Mask" "F.Paste")
			(net "GND")
		)
	)
	(footprint ""
		(layer "F.Cu")
		(at 320.354452 -220.849698 180)
		(property "Reference" "D17"
			(at 3.743452 0.103632 0)
			(unlocked yes)
			(layer "F.SilkS")
			(effects
				(font
					(size 0.7874 0.5842)
					(thickness 0.1524)
				)
				(justify left)
			)
		)
		(property "Value" ""
			(at 0 0 180)
			(layer "F.Fab")
			(effects
				(font
					(size 1.27 1.27)
				)
			)
		)
		(duplicate_pad_numbers_are_jumpers no)
		(fp_line
			(start 1.16078 0.4826)
			(end -0.64008 0.4826)
			(stroke
				(width 0.1524)
				(type default)
			)
			(layer "F.SilkS")
		)
		(fp_line
			(start 1.16078 -0.4826)
			(end 1.16078 0.4826)
			(stroke
				(width 0.1524)
				(type default)
			)
			(layer "F.SilkS")
		)
		(fp_line
			(start 1.03378 0.4826)
			(end -0.79248 0.4826)
			(stroke
				(width 0.1524)
				(type default)
			)
			(layer "F.SilkS")
		)
		(fp_line
			(start 1.03378 -0.4826)
			(end 1.03378 0.4826)
			(stroke
				(width 0.1524)
				(type default)
			)
			(layer "F.SilkS")
		)
		(fp_line
			(start 0.90678 0.4826)
			(end -0.90678 0.4826)
			(stroke
				(width 0.1524)
				(type default)
			)
			(layer "F.SilkS")
		)
		(fp_line
			(start 0.90678 -0.4826)
			(end 0.90678 0.4826)
			(stroke
				(width 0.1524)
				(type default)
			)
			(layer "F.SilkS")
		)
		(fp_line
			(start -0.64008 -0.4826)
			(end 1.16078 -0.4826)
			(stroke
				(width 0.1524)
				(type default)
			)
			(layer "F.SilkS")
		)
		(fp_line
			(start -0.79248 -0.4826)
			(end 1.03378 -0.4826)
			(stroke
				(width 0.1524)
				(type default)
			)
			(layer "F.SilkS")
		)
		(fp_line
			(start -0.89408 -0.4826)
			(end 0.90678 -0.4826)
			(stroke
				(width 0.1524)
				(type default)
			)
			(layer "F.SilkS")
		)
		(fp_line
			(start -0.90678 0.4826)
			(end -0.90678 -0.4699)
			(stroke
				(width 0.1524)
				(type default)
			)
			(layer "F.SilkS")
		)
		(fp_line
			(start 0.499872 0.249936)
			(end -0.499872 0.249936)
			(stroke
				(width 0.1)
				(type default)
			)
			(layer "F.Fab")
		)
		(fp_line
			(start 0.499872 -0.249936)
			(end 0.499872 0.249936)
			(stroke
				(width 0.1)
				(type default)
			)
			(layer "F.Fab")
		)
		(fp_line
			(start -0.499872 0.249936)
			(end -0.499872 -0.249936)
			(stroke
				(width 0.1)
				(type default)
			)
			(layer "F.Fab")
		)
		(fp_line
			(start -0.499872 -0.249936)
			(end 0.499872 -0.249936)
			(stroke
				(width 0.1)
				(type default)
			)
			(layer "F.Fab")
		)
		(pad "A" smd rect
			(at -0.47498 0 180)
			(size 0.6096 0.7112)
			(layers "F.Cu" "F.Mask" "F.Paste")
			(net "LED_POSTCODE_R_4")
		)
		(pad "C" smd rect
			(at 0.47498 0 180)
			(size 0.6096 0.7112)
			(layers "F.Cu" "F.Mask" "F.Paste")
			(net "FPGA_DEBUG_LED_R_N")
		)
	)
	(footprint ""
		(layer "F.Cu")
		(at 247.67159 -211.276946)
		(property "Reference" "C4458"
			(at 0 0 0)
			(layer "F.SilkS")
			(hide yes)
			(effects
				(font
					(size 1.27 1.27)
				)
			)
		)
		(property "Value" ""
			(at 0 0 0)
			(layer "F.Fab")
			(effects
				(font
					(size 1.27 1.27)
				)
			)
		)
		(duplicate_pad_numbers_are_jumpers no)
		(fp_line
			(start -0.7874 -0.4064)
			(end 0.7874 -0.4064)
			(stroke
				(width 0.1524)
				(type default)
			)
			(layer "F.SilkS")
		)
		(fp_line
			(start -0.7874 0.4064)
			(end -0.7874 -0.4064)
			(stroke
				(width 0.1524)
				(type default)
			)
			(layer "F.SilkS")
		)
		(fp_line
			(start 0.7874 -0.4064)
			(end 0.7874 0.4064)
			(stroke
				(width 0.1524)
				(type default)
			)
			(layer "F.SilkS")
		)
		(fp_line
			(start 0.7874 0.4064)
			(end -0.7874 0.4064)
			(stroke
				(width 0.1524)
				(type default)
			)
			(layer "F.SilkS")
		)
		(fp_line
			(start -0.67945 -0.305054)
			(end -0.12065 -0.305054)
			(stroke
				(width 0.1)
				(type default)
			)
			(layer "F.Fab")
		)
		(fp_line
			(start -0.67945 0.3048)
			(end -0.67945 -0.305054)
			(stroke
				(width 0.1)
				(type default)
			)
			(layer "F.Fab")
		)
		(fp_line
			(start -0.12065 -0.305054)
			(end -0.12065 -0.2794)
			(stroke
				(width 0.1)
				(type default)
			)
			(layer "F.Fab")
		)
		(fp_line
			(start -0.12065 -0.2794)
			(end 0.12065 -0.2794)
			(stroke
				(width 0.1)
				(type default)
			)
			(layer "F.Fab")
		)
		(fp_line
			(start -0.12065 0.2794)
			(end -0.12065 0.3048)
			(stroke
				(width 0.1)
				(type default)
			)
			(layer "F.Fab")
		)
		(fp_line
			(start -0.12065 0.3048)
			(end -0.67945 0.3048)
			(stroke
				(width 0.1)
				(type default)
			)
			(layer "F.Fab")
		)
		(fp_line
			(start 0.120396 0.2794)
			(end -0.12065 0.2794)
			(stroke
				(width 0.1)
				(type default)
			)
			(layer "F.Fab")
		)
		(fp_line
			(start 0.120396 0.3048)
			(end 0.120396 0.2794)
			(stroke
				(width 0.1)
				(type default)
			)
			(layer "F.Fab")
		)
		(fp_line
			(start 0.12065 -0.3048)
			(end 0.67945 -0.3048)
			(stroke
				(width 0.1)
				(type default)
			)
			(layer "F.Fab")
		)
		(fp_line
			(start 0.12065 -0.2794)
			(end 0.12065 -0.3048)
			(stroke
				(width 0.1)
				(type default)
			)
			(layer "F.Fab")
		)
		(fp_line
			(start 0.67945 -0.3048)
			(end 0.67945 0.3048)
			(stroke
				(width 0.1)
				(type default)
			)
			(layer "F.Fab")
		)
		(fp_line
			(start 0.67945 0.3048)
			(end 0.120396 0.3048)
			(stroke
				(width 0.1)
				(type default)
			)
			(layer "F.Fab")
		)
		(pad "1" smd circle
			(at -0.40005 0)
			(size 0 0)
			(layers "F.Cu" "F.Mask" "F.Paste")
			(net "HSC_TYPE_ADC_R")
		)
		(pad "2" smd circle
			(at 0.40005 0)
			(size 0 0)
			(layers "F.Cu" "F.Mask" "F.Paste")
			(net "GND")
		)
	)
	(footprint ""
		(layer "F.Cu")
		(at 334.240124 -356.244906 90)
		(property "Reference" "C527"
			(at 0 0 90)
			(layer "F.SilkS")
			(hide yes)
			(effects
				(font
					(size 1.27 1.27)
				)
			)
		)
		(property "Value" ""
			(at 0 0 90)
			(layer "F.Fab")
			(effects
				(font
					(size 1.27 1.27)
				)
			)
		)
		(duplicate_pad_numbers_are_jumpers no)
		(fp_line
			(start 0.299974 -0.150114)
			(end 0.299974 0.150114)
			(stroke
				(width 0.1)
				(type default)
			)
			(layer "F.Fab")
		)
		(fp_line
			(start -0.299974 -0.150114)
			(end 0.299974 -0.150114)
			(stroke
				(width 0.1)
				(type default)
			)
			(layer "F.Fab")
		)
		(fp_line
			(start 0.299974 0.150114)
			(end -0.299974 0.150114)
			(stroke
				(width 0.1)
				(type default)
			)
			(layer "F.Fab")
		)
		(fp_line
			(start -0.299974 0.150114)
			(end -0.299974 -0.150114)
			(stroke
				(width 0.1)
				(type default)
			)
			(layer "F.Fab")
		)
		(pad "1" smd rect
			(at -0.2667 0 90)
			(size 0.3048 0.381)
			(layers "F.Cu" "F.Mask" "F.Paste")
			(net "P5E_PEX2_STN5_TX_DP<91>")
		)
		(pad "2" smd rect
			(at 0.2667 0 90)
			(size 0.3048 0.381)
			(layers "F.Cu" "F.Mask" "F.Paste")
			(net "P5E_PEX2_STN5_TX_C_DP<91>")
		)
	)
	(footprint ""
		(layer "F.Cu")
		(at 407.800048 -407.960068 180)
		(property "Reference" "J62"
			(at -2.6289 -11.325352 0)
			(unlocked yes)
			(layer "F.SilkS")
			(effects
				(font
					(size 0.7874 0.5842)
					(thickness 0.1524)
				)
			)
		)
		(property "Value" ""
			(at 0 0 180)
			(layer "F.Fab")
			(effects
				(font
					(size 1.27 1.27)
				)
			)
		)
		(duplicate_pad_numbers_are_jumpers no)
		(fp_line
			(start 3.525012 21.310092)
			(end 3.525012 -10.489946)
			(stroke
				(width 0.1524)
				(type default)
			)
			(layer "F.SilkS")
		)
		(fp_line
			(start 3.525012 -10.489946)
			(end -3.525012 -10.489946)
			(stroke
				(width 0.1524)
				(type default)
			)
			(layer "F.SilkS")
		)
		(fp_line
			(start -3.525012 21.310092)
			(end 3.525012 21.310092)
			(stroke
				(width 0.1524)
				(type default)
			)
			(layer "F.SilkS")
		)
		(fp_line
			(start -3.525012 10.6299)
			(end 3.525012 10.6299)
			(stroke
				(width 0.1524)
				(type default)
			)
			(layer "F.SilkS")
		)
		(fp_line
			(start -3.525012 -10.489946)
			(end -3.525012 21.310092)
			(stroke
				(width 0.1524)
				(type default)
			)
			(layer "F.SilkS")
		)
		(fp_line
			(start 3.525012 21.310092)
			(end 3.525012 -10.489946)
			(stroke
				(width 0.1)
				(type default)
			)
			(layer "F.Fab")
		)
		(fp_line
			(start 3.525012 -10.489946)
			(end -3.525012 -10.489946)
			(stroke
				(width 0.1)
				(type default)
			)
			(layer "F.Fab")
		)
		(fp_line
			(start -3.525012 21.310092)
			(end 3.525012 21.310092)
			(stroke
				(width 0.1)
				(type default)
			)
			(layer "F.Fab")
		)
		(fp_line
			(start -3.525012 -10.489946)
			(end -3.525012 21.310092)
			(stroke
				(width 0.1)
				(type default)
			)
			(layer "F.Fab")
		)
		(pad "" np_thru_hole circle
			(at 0 -6.620002 180)
			(size 3.175 3.175)
			(drill 3.175)
			(layers "*.Cu" "*.Mask")
			(clearance 0.381)
			(thermal_gap 0.381)
		)
		(pad "" np_thru_hole circle
			(at 0 0 180)
			(size 0 0)
			(drill 3.175)
			(layers "*.Cu" "*.Mask")
			(clearance 0)
		)
		(pad "" np_thru_hole circle
			(at 0 5.130038 180)
			(size 3.175 3.175)
			(drill 3.175)
			(layers "*.Cu" "*.Mask")
			(clearance 0.381)
			(thermal_gap 0.381)
		)
		(zone
			(layers "F.Cu" "B.Cu" "In1.Cu" "In2.Cu" "In3.Cu" "In4.Cu" "In5.Cu" "In6.Cu"
				"In7.Cu" "In8.Cu" "In9.Cu" "In10.Cu" "In11.Cu" "In12.Cu" "In13.Cu" "In14.Cu"
				"In15.Cu" "In16.Cu"
			)
			(hatch none 0.5)
			(connect_pads
				(clearance 0)
			)
			(min_thickness 0.25)
			(keepout
				(tracks not_allowed)
				(vias allowed)
				(pads allowed)
				(copperpour not_allowed)
				(footprints allowed)
			)
			(placement
				(enabled no)
				(sheetname "")
			)
			(fill
				(thermal_gap 0.5)
				(thermal_bridge_width 0.5)
				(island_removal_mode 0)
			)
			(polygon
				(pts
					(arc
						(start 409.895548 -413.090106)
						(mid 405.704548 -413.090106)
						(end 409.895548 -413.090106)
					)
				)
			)
		)
		(zone
			(layers "F.Cu" "B.Cu" "In1.Cu" "In2.Cu" "In3.Cu" "In4.Cu" "In5.Cu" "In6.Cu"
				"In7.Cu" "In8.Cu" "In9.Cu" "In10.Cu" "In11.Cu" "In12.Cu" "In13.Cu" "In14.Cu"
				"In15.Cu" "In16.Cu"
			)
			(hatch none 0.5)
			(connect_pads
				(clearance 0)
			)
			(min_thickness 0.25)
			(keepout
				(tracks not_allowed)
				(vias allowed)
				(pads allowed)
				(copperpour not_allowed)
				(footprints allowed)
			)
			(placement
				(enabled no)
				(sheetname "")
			)
			(fill
				(thermal_gap 0.5)
				(thermal_bridge_width 0.5)
				(island_removal_mode 0)
			)
			(polygon
				(pts
					(arc
						(start 409.895548 -401.340066)
						(mid 405.704548 -401.340066)
						(end 409.895548 -401.340066)
					)
				)
			)
		)
		(zone
			(layers "F.Cu" "B.Cu" "In1.Cu" "In2.Cu" "In3.Cu" "In4.Cu" "In5.Cu" "In6.Cu"
				"In7.Cu" "In8.Cu" "In9.Cu" "In10.Cu" "In11.Cu" "In12.Cu" "In13.Cu" "In14.Cu"
				"In15.Cu" "In16.Cu"
			)
			(hatch none 0.5)
			(connect_pads
				(clearance 0)
			)
			(min_thickness 0.25)
			(keepout
				(tracks not_allowed)
				(vias allowed)
				(pads allowed)
				(copperpour not_allowed)
				(footprints allowed)
			)
			(placement
				(enabled no)
				(sheetname "")
			)
			(fill
				(thermal_gap 0.5)
				(thermal_bridge_width 0.5)
				(island_removal_mode 0)
			)
			(polygon
				(pts
					(arc
						(start 411.419548 -407.960068)
						(mid 404.180548 -407.960068)
						(end 411.419548 -407.960068)
					)
				)
			)
		)
	)
	(footprint ""
		(layer "F.Cu")
		(at 447.275712 -121.509028)
		(property "Reference" "PR254"
			(at 0 0 0)
			(layer "F.SilkS")
			(hide yes)
			(effects
				(font
					(size 1.27 1.27)
				)
			)
		)
		(property "Value" ""
			(at 0 0 0)
			(layer "F.Fab")
			(effects
				(font
					(size 1.27 1.27)
				)
			)
		)
		(duplicate_pad_numbers_are_jumpers no)
		(fp_line
			(start -0.7874 -0.4064)
			(end 0.7874 -0.4064)
			(stroke
				(width 0.1524)
				(type default)
			)
			(layer "F.SilkS")
		)
		(fp_line
			(start -0.7874 0.4064)
			(end -0.7874 -0.4064)
			(stroke
				(width 0.1524)
				(type default)
			)
			(layer "F.SilkS")
		)
		(fp_line
			(start 0.7874 -0.4064)
			(end 0.7874 0.4064)
			(stroke
				(width 0.1524)
				(type default)
			)
			(layer "F.SilkS")
		)
		(fp_line
			(start 0.7874 0.4064)
			(end -0.7874 0.4064)
			(stroke
				(width 0.1524)
				(type default)
			)
			(layer "F.SilkS")
		)
		(fp_line
			(start -0.67945 -0.305054)
			(end -0.12065 -0.305054)
			(stroke
				(width 0.1)
				(type default)
			)
			(layer "F.Fab")
		)
		(fp_line
			(start -0.67945 0.3048)
			(end -0.67945 -0.305054)
			(stroke
				(width 0.1)
				(type default)
			)
			(layer "F.Fab")
		)
		(fp_line
			(start -0.12065 -0.305054)
			(end -0.12065 -0.2794)
			(stroke
				(width 0.1)
				(type default)
			)
			(layer "F.Fab")
		)
		(fp_line
			(start -0.12065 -0.2794)
			(end 0.12065 -0.2794)
			(stroke
				(width 0.1)
				(type default)
			)
			(layer "F.Fab")
		)
		(fp_line
			(start -0.12065 0.2794)
			(end -0.12065 0.3048)
			(stroke
				(width 0.1)
				(type default)
			)
			(layer "F.Fab")
		)
		(fp_line
			(start -0.12065 0.3048)
			(end -0.67945 0.3048)
			(stroke
				(width 0.1)
				(type default)
			)
			(layer "F.Fab")
		)
		(fp_line
			(start 0.120396 0.2794)
			(end -0.12065 0.2794)
			(stroke
				(width 0.1)
				(type default)
			)
			(layer "F.Fab")
		)
		(fp_line
			(start 0.120396 0.3048)
			(end 0.120396 0.2794)
			(stroke
				(width 0.1)
				(type default)
			)
			(layer "F.Fab")
		)
		(fp_line
			(start 0.12065 -0.3048)
			(end 0.67945 -0.3048)
			(stroke
				(width 0.1)
				(type default)
			)
			(layer "F.Fab")
		)
		(fp_line
			(start 0.12065 -0.2794)
			(end 0.12065 -0.3048)
			(stroke
				(width 0.1)
				(type default)
			)
			(layer "F.Fab")
		)
		(fp_line
			(start 0.67945 -0.3048)
			(end 0.67945 0.3048)
			(stroke
				(width 0.1)
				(type default)
			)
			(layer "F.Fab")
		)
		(fp_line
			(start 0.67945 0.3048)
			(end 0.120396 0.3048)
			(stroke
				(width 0.1)
				(type default)
			)
			(layer "F.Fab")
		)
		(pad "1" smd circle
			(at -0.40005 0)
			(size 0 0)
			(layers "F.Cu" "F.Mask" "F.Paste")
			(net "P3V3_NIC7_OCP")
		)
		(pad "2" smd circle
			(at 0.40005 0)
			(size 0 0)
			(layers "F.Cu" "F.Mask" "F.Paste")
			(net "GND")
		)
	)
	(footprint ""
		(layer "F.Cu")
		(at 102.273862 -26.31186 -90)
		(property "Reference" "U401"
			(at -0.05334 -2.324608 90)
			(unlocked yes)
			(layer "F.SilkS")
			(effects
				(font
					(size 0.7874 0.5842)
					(thickness 0.1524)
				)
			)
		)
		(property "Value" ""
			(at 0 0 270)
			(layer "F.Fab")
			(effects
				(font
					(size 1.27 1.27)
				)
			)
		)
		(duplicate_pad_numbers_are_jumpers no)
		(fp_line
			(start -1.949958 1.610106)
			(end -1.949958 -1.610106)
			(stroke
				(width 0.1524)
				(type default)
			)
			(layer "F.SilkS")
		)
		(fp_line
			(start 1.949958 1.610106)
			(end -1.949958 1.610106)
			(stroke
				(width 0.1524)
				(type default)
			)
			(layer "F.SilkS")
		)
		(fp_line
			(start 1.949958 -1.560068)
			(end 1.949958 1.610106)
			(stroke
				(width 0.1524)
				(type default)
			)
			(layer "F.SilkS")
		)
		(fp_line
			(start -1.949958 -1.610106)
			(end 1.949958 -1.610106)
			(stroke
				(width 0.1524)
				(type default)
			)
			(layer "F.SilkS")
		)
		(fp_line
			(start -0.750062 1.560068)
			(end -0.750062 -1.560068)
			(stroke
				(width 0.1)
				(type default)
			)
			(layer "F.Fab")
		)
		(fp_line
			(start 0.750062 1.560068)
			(end -0.750062 1.560068)
			(stroke
				(width 0.1)
				(type default)
			)
			(layer "F.Fab")
		)
		(fp_line
			(start -0.750062 -1.560068)
			(end 0.750062 -1.560068)
			(stroke
				(width 0.1)
				(type default)
			)
			(layer "F.Fab")
		)
		(fp_line
			(start 0.750062 -1.560068)
			(end 0.750062 1.560068)
			(stroke
				(width 0.1)
				(type default)
			)
			(layer "F.Fab")
		)
		(pad "D" smd rect
			(at 1.100074 0 180)
			(size 1.016 1.4224)
			(layers "F.Cu" "F.Mask" "F.Paste")
			(net "SSD3_LED_ISO_N")
		)
		(pad "G" smd rect
			(at -1.100074 -0.94996 180)
			(size 1.016 1.4224)
			(layers "F.Cu" "F.Mask" "F.Paste")
			(net "SSD3_LED_R")
		)
		(pad "S" smd rect
			(at -1.100074 0.94996 180)
			(size 1.016 1.4224)
			(layers "F.Cu" "F.Mask" "F.Paste")
			(net "GND")
		)
	)
	(footprint ""
		(layer "F.Cu")
		(at 278.634444 -30.94609 180)
		(property "Reference" "C499"
			(at 0 0 180)
			(layer "F.SilkS")
			(hide yes)
			(effects
				(font
					(size 1.27 1.27)
				)
			)
		)
		(property "Value" ""
			(at 0 0 180)
			(layer "F.Fab")
			(effects
				(font
					(size 1.27 1.27)
				)
			)
		)
		(duplicate_pad_numbers_are_jumpers no)
		(fp_line
			(start 0.299974 0.150114)
			(end -0.299974 0.150114)
			(stroke
				(width 0.1)
				(type default)
			)
			(layer "F.Fab")
		)
		(fp_line
			(start 0.299974 -0.150114)
			(end 0.299974 0.150114)
			(stroke
				(width 0.1)
				(type default)
			)
			(layer "F.Fab")
		)
		(fp_line
			(start -0.299974 0.150114)
			(end -0.299974 -0.150114)
			(stroke
				(width 0.1)
				(type default)
			)
			(layer "F.Fab")
		)
		(fp_line
			(start -0.299974 -0.150114)
			(end 0.299974 -0.150114)
			(stroke
				(width 0.1)
				(type default)
			)
			(layer "F.Fab")
		)
		(pad "1" smd rect
			(at -0.2667 0 180)
			(size 0.3048 0.381)
			(layers "F.Cu" "F.Mask" "F.Paste")
			(net "P5E_PEX2_STN2_TX_DP<41>")
		)
		(pad "2" smd rect
			(at 0.2667 0 180)
			(size 0.3048 0.381)
			(layers "F.Cu" "F.Mask" "F.Paste")
			(net "P5E_PEX2_STN2_TX_C_DP<41>")
		)
	)
	(footprint ""
		(layer "F.Cu")
		(at 222.011494 -181.14518)
		(property "Reference" "Q58"
			(at -0.472694 1.82245 0)
			(unlocked yes)
			(layer "F.SilkS")
			(effects
				(font
					(size 0.7874 0.5842)
					(thickness 0.1524)
				)
				(justify left)
			)
		)
		(property "Value" ""
			(at 0 0 0)
			(layer "F.Fab")
			(effects
				(font
					(size 1.27 1.27)
				)
			)
		)
		(duplicate_pad_numbers_are_jumpers no)
		(fp_line
			(start -1.38176 -1.100074)
			(end -1.38176 1.100074)
			(stroke
				(width 0.1524)
				(type default)
			)
			(layer "F.SilkS")
		)
		(fp_line
			(start -1.38176 1.100074)
			(end 1.38176 1.100074)
			(stroke
				(width 0.1524)
				(type default)
			)
			(layer "F.SilkS")
		)
		(fp_line
			(start -0.592074 -1.100074)
			(end -1.38176 -1.100074)
			(stroke
				(width 0.1524)
				(type default)
			)
			(layer "F.SilkS")
		)
		(fp_line
			(start 0 -0.508)
			(end -0.592074 -1.100074)
			(stroke
				(width 0.1524)
				(type default)
			)
			(layer "F.SilkS")
		)
		(fp_line
			(start 0.592074 -1.100074)
			(end 0 -0.508)
			(stroke
				(width 0.1524)
				(type default)
			)
			(layer "F.SilkS")
		)
		(fp_line
			(start 1.38176 -1.100074)
			(end 0.592074 -1.100074)
			(stroke
				(width 0.1524)
				(type default)
			)
			(layer "F.SilkS")
		)
		(fp_line
			(start 1.38176 1.100074)
			(end 1.38176 -1.100074)
			(stroke
				(width 0.1524)
				(type default)
			)
			(layer "F.SilkS")
		)
		(fp_poly
			(pts
				(xy -1.9431 -0.870204) (xy -1.50241 -0.649986) (xy -1.9431 -0.429768)
			)
			(stroke
				(width 0)
				(type default)
			)
			(fill yes)
			(layer "F.SilkS")
		)
		(fp_line
			(start -0.674878 -1.100074)
			(end -0.674878 1.100074)
			(stroke
				(width 0.1)
				(type default)
			)
			(layer "F.Fab")
		)
		(fp_line
			(start -0.674878 1.100074)
			(end 0.674878 1.100074)
			(stroke
				(width 0.1)
				(type default)
			)
			(layer "F.Fab")
		)
		(fp_line
			(start 0.674878 -1.100074)
			(end -0.674878 -1.100074)
			(stroke
				(width 0.1)
				(type default)
			)
			(layer "F.Fab")
		)
		(fp_line
			(start 0.674878 1.100074)
			(end 0.674878 -1.100074)
			(stroke
				(width 0.1)
				(type default)
			)
			(layer "F.Fab")
		)
		(fp_poly
			(pts
				(xy -1.9431 -0.870204) (xy -1.50241 -0.649986) (xy -1.9431 -0.429768)
			)
			(stroke
				(width 0)
				(type default)
			)
			(fill yes)
			(layer "F.Fab")
		)
		(pad "1" smd rect
			(at -0.94996 -0.649986 270)
			(size 0.4318 0.6096)
			(layers "F.Cu" "F.Mask" "F.Paste")
			(net "GND")
		)
		(pad "2" smd rect
			(at -0.94996 0 270)
			(size 0.4318 0.6096)
			(layers "F.Cu" "F.Mask" "F.Paste")
			(net "RST_FW_BIC_PLTRST_C")
		)
		(pad "3" smd rect
			(at -0.94996 0.649986 270)
			(size 0.4318 0.6096)
			(layers "F.Cu" "F.Mask" "F.Paste")
			(net "RST_FW_BIC_PLTRST")
		)
		(pad "4" smd rect
			(at 0.94996 0.649986 270)
			(size 0.4318 0.6096)
			(layers "F.Cu" "F.Mask" "F.Paste")
			(net "GND")
		)
		(pad "5" smd rect
			(at 0.94996 0 270)
			(size 0.4318 0.6096)
			(layers "F.Cu" "F.Mask" "F.Paste")
			(net "RST_FW_BIC_PLTRST_N")
		)
		(pad "6" smd rect
			(at 0.94996 -0.649986 270)
			(size 0.4318 0.6096)
			(layers "F.Cu" "F.Mask" "F.Paste")
			(net "RST_BIC_BUF_RSMRST_N_BUF")
		)
	)
	(footprint ""
		(layer "F.Cu")
		(at 405.003 -383.667 -90)
		(property "Reference" "R6281"
			(at 0 0 270)
			(layer "F.SilkS")
			(hide yes)
			(effects
				(font
					(size 1.27 1.27)
				)
			)
		)
		(property "Value" ""
			(at 0 0 270)
			(layer "F.Fab")
			(effects
				(font
					(size 1.27 1.27)
				)
			)
		)
		(duplicate_pad_numbers_are_jumpers no)
		(fp_line
			(start -0.7874 0.4064)
			(end -0.7874 -0.4064)
			(stroke
				(width 0.1524)
				(type default)
			)
			(layer "F.SilkS")
		)
		(fp_line
			(start 0.7874 0.4064)
			(end -0.7874 0.4064)
			(stroke
				(width 0.1524)
				(type default)
			)
			(layer "F.SilkS")
		)
		(fp_line
			(start -0.7874 -0.4064)
			(end 0.7874 -0.4064)
			(stroke
				(width 0.1524)
				(type default)
			)
			(layer "F.SilkS")
		)
		(fp_line
			(start 0.7874 -0.4064)
			(end 0.7874 0.4064)
			(stroke
				(width 0.1524)
				(type default)
			)
			(layer "F.SilkS")
		)
		(fp_line
			(start -0.67945 0.3048)
			(end -0.67945 -0.305054)
			(stroke
				(width 0.1)
				(type default)
			)
			(layer "F.Fab")
		)
		(fp_line
			(start -0.12065 0.3048)
			(end -0.67945 0.3048)
			(stroke
				(width 0.1)
				(type default)
			)
			(layer "F.Fab")
		)
		(fp_line
			(start 0.120396 0.3048)
			(end 0.120396 0.2794)
			(stroke
				(width 0.1)
				(type default)
			)
			(layer "F.Fab")
		)
		(fp_line
			(start 0.67945 0.3048)
			(end 0.120396 0.3048)
			(stroke
				(width 0.1)
				(type default)
			)
			(layer "F.Fab")
		)
		(fp_line
			(start -0.12065 0.2794)
			(end -0.12065 0.3048)
			(stroke
				(width 0.1)
				(type default)
			)
			(layer "F.Fab")
		)
		(fp_line
			(start 0.120396 0.2794)
			(end -0.12065 0.2794)
			(stroke
				(width 0.1)
				(type default)
			)
			(layer "F.Fab")
		)
		(fp_line
			(start -0.12065 -0.2794)
			(end 0.12065 -0.2794)
			(stroke
				(width 0.1)
				(type default)
			)
			(layer "F.Fab")
		)
		(fp_line
			(start 0.12065 -0.2794)
			(end 0.12065 -0.3048)
			(stroke
				(width 0.1)
				(type default)
			)
			(layer "F.Fab")
		)
		(fp_line
			(start 0.12065 -0.3048)
			(end 0.67945 -0.3048)
			(stroke
				(width 0.1)
				(type default)
			)
			(layer "F.Fab")
		)
		(fp_line
			(start 0.67945 -0.3048)
			(end 0.67945 0.3048)
			(stroke
				(width 0.1)
				(type default)
			)
			(layer "F.Fab")
		)
		(fp_line
			(start -0.67945 -0.305054)
			(end -0.12065 -0.305054)
			(stroke
				(width 0.1)
				(type default)
			)
			(layer "F.Fab")
		)
		(fp_line
			(start -0.12065 -0.305054)
			(end -0.12065 -0.2794)
			(stroke
				(width 0.1)
				(type default)
			)
			(layer "F.Fab")
		)
		(pad "1" smd circle
			(at -0.40005 0 270)
			(size 0 0)
			(layers "F.Cu" "F.Mask" "F.Paste")
			(net "P3V3_AUX")
		)
		(pad "2" smd circle
			(at 0.40005 0 270)
			(size 0 0)
			(layers "F.Cu" "F.Mask" "F.Paste")
			(net "I3C_MB_BMC_R_SCL")
		)
	)
	(footprint ""
		(layer "F.Cu")
		(at 176.210468 -63.652146 180)
		(property "Reference" "R5986"
			(at 0 0 180)
			(layer "F.SilkS")
			(hide yes)
			(effects
				(font
					(size 1.27 1.27)
				)
			)
		)
		(property "Value" ""
			(at 0 0 180)
			(layer "F.Fab")
			(effects
				(font
					(size 1.27 1.27)
				)
			)
		)
		(duplicate_pad_numbers_are_jumpers no)
		(fp_line
			(start 0.7874 0.4064)
			(end -0.7874 0.4064)
			(stroke
				(width 0.1524)
				(type default)
			)
			(layer "F.SilkS")
		)
		(fp_line
			(start 0.7874 -0.4064)
			(end 0.7874 0.4064)
			(stroke
				(width 0.1524)
				(type default)
			)
			(layer "F.SilkS")
		)
		(fp_line
			(start -0.7874 0.4064)
			(end -0.7874 -0.4064)
			(stroke
				(width 0.1524)
				(type default)
			)
			(layer "F.SilkS")
		)
		(fp_line
			(start -0.7874 -0.4064)
			(end 0.7874 -0.4064)
			(stroke
				(width 0.1524)
				(type default)
			)
			(layer "F.SilkS")
		)
		(fp_line
			(start 0.67945 0.3048)
			(end 0.120396 0.3048)
			(stroke
				(width 0.1)
				(type default)
			)
			(layer "F.Fab")
		)
		(fp_line
			(start 0.67945 -0.3048)
			(end 0.67945 0.3048)
			(stroke
				(width 0.1)
				(type default)
			)
			(layer "F.Fab")
		)
		(fp_line
			(start 0.12065 -0.2794)
			(end 0.12065 -0.3048)
			(stroke
				(width 0.1)
				(type default)
			)
			(layer "F.Fab")
		)
		(fp_line
			(start 0.12065 -0.3048)
			(end 0.67945 -0.3048)
			(stroke
				(width 0.1)
				(type default)
			)
			(layer "F.Fab")
		)
		(fp_line
			(start 0.120396 0.3048)
			(end 0.120396 0.2794)
			(stroke
				(width 0.1)
				(type default)
			)
			(layer "F.Fab")
		)
		(fp_line
			(start 0.120396 0.2794)
			(end -0.12065 0.2794)
			(stroke
				(width 0.1)
				(type default)
			)
			(layer "F.Fab")
		)
		(fp_line
			(start -0.12065 0.3048)
			(end -0.67945 0.3048)
			(stroke
				(width 0.1)
				(type default)
			)
			(layer "F.Fab")
		)
		(fp_line
			(start -0.12065 0.2794)
			(end -0.12065 0.3048)
			(stroke
				(width 0.1)
				(type default)
			)
			(layer "F.Fab")
		)
		(fp_line
			(start -0.12065 -0.2794)
			(end 0.12065 -0.2794)
			(stroke
				(width 0.1)
				(type default)
			)
			(layer "F.Fab")
		)
		(fp_line
			(start -0.12065 -0.305054)
			(end -0.12065 -0.2794)
			(stroke
				(width 0.1)
				(type default)
			)
			(layer "F.Fab")
		)
		(fp_line
			(start -0.67945 0.3048)
			(end -0.67945 -0.305054)
			(stroke
				(width 0.1)
				(type default)
			)
			(layer "F.Fab")
		)
		(fp_line
			(start -0.67945 -0.305054)
			(end -0.12065 -0.305054)
			(stroke
				(width 0.1)
				(type default)
			)
			(layer "F.Fab")
		)
		(pad "1" smd circle
			(at -0.40005 0 180)
			(size 0 0)
			(layers "F.Cu" "F.Mask" "F.Paste")
			(net "P5V_AUX")
		)
		(pad "2" smd circle
			(at 0.40005 0 180)
			(size 0 0)
			(layers "F.Cu" "F.Mask" "F.Paste")
			(net "P12V_SSD6_PG_G2")
		)
	)
	(footprint ""
		(layer "F.Cu")
		(at 29.155136 -53.468524 90)
		(property "Reference" "PC509"
			(at 0 0 90)
			(layer "F.SilkS")
			(hide yes)
			(effects
				(font
					(size 1.27 1.27)
				)
			)
		)
		(property "Value" ""
			(at 0 0 90)
			(layer "F.Fab")
			(effects
				(font
					(size 1.27 1.27)
				)
			)
		)
		(duplicate_pad_numbers_are_jumpers no)
		(fp_line
			(start 1.524 -0.762)
			(end 1.524 0.762)
			(stroke
				(width 0.1524)
				(type default)
			)
			(layer "F.SilkS")
		)
		(fp_line
			(start -1.524 -0.762)
			(end 1.524 -0.762)
			(stroke
				(width 0.1524)
				(type default)
			)
			(layer "F.SilkS")
		)
		(fp_line
			(start 1.524 0.762)
			(end -1.524 0.762)
			(stroke
				(width 0.1524)
				(type default)
			)
			(layer "F.SilkS")
		)
		(fp_line
			(start -1.524 0.762)
			(end -1.524 -0.762)
			(stroke
				(width 0.1524)
				(type default)
			)
			(layer "F.SilkS")
		)
		(fp_line
			(start 1.1049 -0.724916)
			(end -1.1049 -0.724916)
			(stroke
				(width 0.1)
				(type default)
			)
			(layer "F.Fab")
		)
		(fp_line
			(start -1.1049 -0.724916)
			(end -1.1049 0.724916)
			(stroke
				(width 0.1)
				(type default)
			)
			(layer "F.Fab")
		)
		(fp_line
			(start 1.1049 0.724916)
			(end 1.1049 -0.724916)
			(stroke
				(width 0.1)
				(type default)
			)
			(layer "F.Fab")
		)
		(fp_line
			(start -1.1049 0.724916)
			(end 1.1049 0.724916)
			(stroke
				(width 0.1)
				(type default)
			)
			(layer "F.Fab")
		)
		(pad "1" smd rect
			(at -0.889 0 270)
			(size 1.016 1.27)
			(layers "F.Cu" "F.Mask" "F.Paste")
			(net "GND")
		)
		(pad "2" smd rect
			(at 0.889 0 270)
			(size 1.016 1.27)
			(layers "F.Cu" "F.Mask" "F.Paste")
			(net "P3V3_AUX")
		)
	)
	(footprint ""
		(layer "F.Cu")
		(at 287.355026 -53.468524 90)
		(property "Reference" "PC545"
			(at 0 0 90)
			(layer "F.SilkS")
			(hide yes)
			(effects
				(font
					(size 1.27 1.27)
				)
			)
		)
		(property "Value" ""
			(at 0 0 90)
			(layer "F.Fab")
			(effects
				(font
					(size 1.27 1.27)
				)
			)
		)
		(duplicate_pad_numbers_are_jumpers no)
		(fp_line
			(start 1.524 -0.762)
			(end 1.524 0.762)
			(stroke
				(width 0.1524)
				(type default)
			)
			(layer "F.SilkS")
		)
		(fp_line
			(start -1.524 -0.762)
			(end 1.524 -0.762)
			(stroke
				(width 0.1524)
				(type default)
			)
			(layer "F.SilkS")
		)
		(fp_line
			(start 1.524 0.762)
			(end -1.524 0.762)
			(stroke
				(width 0.1524)
				(type default)
			)
			(layer "F.SilkS")
		)
		(fp_line
			(start -1.524 0.762)
			(end -1.524 -0.762)
			(stroke
				(width 0.1524)
				(type default)
			)
			(layer "F.SilkS")
		)
		(fp_line
			(start 1.1049 -0.724916)
			(end -1.1049 -0.724916)
			(stroke
				(width 0.1)
				(type default)
			)
			(layer "F.Fab")
		)
		(fp_line
			(start -1.1049 -0.724916)
			(end -1.1049 0.724916)
			(stroke
				(width 0.1)
				(type default)
			)
			(layer "F.Fab")
		)
		(fp_line
			(start 1.1049 0.724916)
			(end 1.1049 -0.724916)
			(stroke
				(width 0.1)
				(type default)
			)
			(layer "F.Fab")
		)
		(fp_line
			(start -1.1049 0.724916)
			(end 1.1049 0.724916)
			(stroke
				(width 0.1)
				(type default)
			)
			(layer "F.Fab")
		)
		(pad "1" smd rect
			(at -0.889 0 270)
			(size 1.016 1.27)
			(layers "F.Cu" "F.Mask" "F.Paste")
			(net "GND")
		)
		(pad "2" smd rect
			(at 0.889 0 270)
			(size 1.016 1.27)
			(layers "F.Cu" "F.Mask" "F.Paste")
			(net "P3V3_AUX")
		)
	)
	(footprint ""
		(layer "F.Cu")
		(at 112.198404 -164.52342)
		(property "Reference" "PC29"
			(at 0 0 0)
			(layer "F.SilkS")
			(hide yes)
			(effects
				(font
					(size 1.27 1.27)
				)
			)
		)
		(property "Value" ""
			(at 0 0 0)
			(layer "F.Fab")
			(effects
				(font
					(size 1.27 1.27)
				)
			)
		)
		(duplicate_pad_numbers_are_jumpers no)
		(fp_line
			(start -1.524 -0.762)
			(end 1.524 -0.762)
			(stroke
				(width 0.1524)
				(type default)
			)
			(layer "F.SilkS")
		)
		(fp_line
			(start -1.524 0.762)
			(end -1.524 -0.762)
			(stroke
				(width 0.1524)
				(type default)
			)
			(layer "F.SilkS")
		)
		(fp_line
			(start 1.524 -0.762)
			(end 1.524 0.762)
			(stroke
				(width 0.1524)
				(type default)
			)
			(layer "F.SilkS")
		)
		(fp_line
			(start 1.524 0.762)
			(end -1.524 0.762)
			(stroke
				(width 0.1524)
				(type default)
			)
			(layer "F.SilkS")
		)
		(fp_line
			(start -1.1049 -0.724916)
			(end -1.1049 0.724916)
			(stroke
				(width 0.1)
				(type default)
			)
			(layer "F.Fab")
		)
		(fp_line
			(start -1.1049 0.724916)
			(end 1.1049 0.724916)
			(stroke
				(width 0.1)
				(type default)
			)
			(layer "F.Fab")
		)
		(fp_line
			(start 1.1049 -0.724916)
			(end -1.1049 -0.724916)
			(stroke
				(width 0.1)
				(type default)
			)
			(layer "F.Fab")
		)
		(fp_line
			(start 1.1049 0.724916)
			(end 1.1049 -0.724916)
			(stroke
				(width 0.1)
				(type default)
			)
			(layer "F.Fab")
		)
		(pad "1" smd rect
			(at -0.889 0 180)
			(size 1.016 1.27)
			(layers "F.Cu" "F.Mask" "F.Paste")
			(net "SW_P12V_P3V3_AUX_FLT")
		)
		(pad "2" smd rect
			(at 0.889 0 180)
			(size 1.016 1.27)
			(layers "F.Cu" "F.Mask" "F.Paste")
			(net "GND")
		)
	)
	(footprint ""
		(layer "F.Cu")
		(at 238.385604 -185.17235 -90)
		(property "Reference" "C3645"
			(at 0 0 270)
			(layer "F.SilkS")
			(hide yes)
			(effects
				(font
					(size 1.27 1.27)
				)
			)
		)
		(property "Value" ""
			(at 0 0 270)
			(layer "F.Fab")
			(effects
				(font
					(size 1.27 1.27)
				)
			)
		)
		(duplicate_pad_numbers_are_jumpers no)
		(fp_line
			(start -0.7874 0.4064)
			(end -0.7874 -0.4064)
			(stroke
				(width 0.1524)
				(type default)
			)
			(layer "F.SilkS")
		)
		(fp_line
			(start 0.7874 0.4064)
			(end -0.7874 0.4064)
			(stroke
				(width 0.1524)
				(type default)
			)
			(layer "F.SilkS")
		)
		(fp_line
			(start -0.7874 -0.4064)
			(end 0.7874 -0.4064)
			(stroke
				(width 0.1524)
				(type default)
			)
			(layer "F.SilkS")
		)
		(fp_line
			(start 0.7874 -0.4064)
			(end 0.7874 0.4064)
			(stroke
				(width 0.1524)
				(type default)
			)
			(layer "F.SilkS")
		)
		(fp_line
			(start -0.67945 0.3048)
			(end -0.67945 -0.305054)
			(stroke
				(width 0.1)
				(type default)
			)
			(layer "F.Fab")
		)
		(fp_line
			(start -0.12065 0.3048)
			(end -0.67945 0.3048)
			(stroke
				(width 0.1)
				(type default)
			)
			(layer "F.Fab")
		)
		(fp_line
			(start 0.120396 0.3048)
			(end 0.120396 0.2794)
			(stroke
				(width 0.1)
				(type default)
			)
			(layer "F.Fab")
		)
		(fp_line
			(start 0.67945 0.3048)
			(end 0.120396 0.3048)
			(stroke
				(width 0.1)
				(type default)
			)
			(layer "F.Fab")
		)
		(fp_line
			(start -0.12065 0.2794)
			(end -0.12065 0.3048)
			(stroke
				(width 0.1)
				(type default)
			)
			(layer "F.Fab")
		)
		(fp_line
			(start 0.120396 0.2794)
			(end -0.12065 0.2794)
			(stroke
				(width 0.1)
				(type default)
			)
			(layer "F.Fab")
		)
		(fp_line
			(start -0.12065 -0.2794)
			(end 0.12065 -0.2794)
			(stroke
				(width 0.1)
				(type default)
			)
			(layer "F.Fab")
		)
		(fp_line
			(start 0.12065 -0.2794)
			(end 0.12065 -0.3048)
			(stroke
				(width 0.1)
				(type default)
			)
			(layer "F.Fab")
		)
		(fp_line
			(start 0.12065 -0.3048)
			(end 0.67945 -0.3048)
			(stroke
				(width 0.1)
				(type default)
			)
			(layer "F.Fab")
		)
		(fp_line
			(start 0.67945 -0.3048)
			(end 0.67945 0.3048)
			(stroke
				(width 0.1)
				(type default)
			)
			(layer "F.Fab")
		)
		(fp_line
			(start -0.67945 -0.305054)
			(end -0.12065 -0.305054)
			(stroke
				(width 0.1)
				(type default)
			)
			(layer "F.Fab")
		)
		(fp_line
			(start -0.12065 -0.305054)
			(end -0.12065 -0.2794)
			(stroke
				(width 0.1)
				(type default)
			)
			(layer "F.Fab")
		)
		(pad "1" smd circle
			(at -0.40005 0 270)
			(size 0 0)
			(layers "F.Cu" "F.Mask" "F.Paste")
			(net "GND")
		)
		(pad "2" smd circle
			(at 0.40005 0 270)
			(size 0 0)
			(layers "F.Cu" "F.Mask" "F.Paste")
			(net "P3V3_AUX")
		)
	)
	(footprint ""
		(layer "F.Cu")
		(at 230.4542 -231.4194 -90)
		(property "Reference" "R4537"
			(at 0 0 270)
			(layer "F.SilkS")
			(hide yes)
			(effects
				(font
					(size 1.27 1.27)
				)
			)
		)
		(property "Value" ""
			(at 0 0 270)
			(layer "F.Fab")
			(effects
				(font
					(size 1.27 1.27)
				)
			)
		)
		(duplicate_pad_numbers_are_jumpers no)
		(fp_line
			(start -0.7874 0.4064)
			(end -0.7874 -0.4064)
			(stroke
				(width 0.1524)
				(type default)
			)
			(layer "F.SilkS")
		)
		(fp_line
			(start 0.7874 0.4064)
			(end -0.7874 0.4064)
			(stroke
				(width 0.1524)
				(type default)
			)
			(layer "F.SilkS")
		)
		(fp_line
			(start -0.7874 -0.4064)
			(end 0.7874 -0.4064)
			(stroke
				(width 0.1524)
				(type default)
			)
			(layer "F.SilkS")
		)
		(fp_line
			(start 0.7874 -0.4064)
			(end 0.7874 0.4064)
			(stroke
				(width 0.1524)
				(type default)
			)
			(layer "F.SilkS")
		)
		(fp_line
			(start -0.67945 0.3048)
			(end -0.67945 -0.305054)
			(stroke
				(width 0.1)
				(type default)
			)
			(layer "F.Fab")
		)
		(fp_line
			(start -0.12065 0.3048)
			(end -0.67945 0.3048)
			(stroke
				(width 0.1)
				(type default)
			)
			(layer "F.Fab")
		)
		(fp_line
			(start 0.120396 0.3048)
			(end 0.120396 0.2794)
			(stroke
				(width 0.1)
				(type default)
			)
			(layer "F.Fab")
		)
		(fp_line
			(start 0.67945 0.3048)
			(end 0.120396 0.3048)
			(stroke
				(width 0.1)
				(type default)
			)
			(layer "F.Fab")
		)
		(fp_line
			(start -0.12065 0.2794)
			(end -0.12065 0.3048)
			(stroke
				(width 0.1)
				(type default)
			)
			(layer "F.Fab")
		)
		(fp_line
			(start 0.120396 0.2794)
			(end -0.12065 0.2794)
			(stroke
				(width 0.1)
				(type default)
			)
			(layer "F.Fab")
		)
		(fp_line
			(start -0.12065 -0.2794)
			(end 0.12065 -0.2794)
			(stroke
				(width 0.1)
				(type default)
			)
			(layer "F.Fab")
		)
		(fp_line
			(start 0.12065 -0.2794)
			(end 0.12065 -0.3048)
			(stroke
				(width 0.1)
				(type default)
			)
			(layer "F.Fab")
		)
		(fp_line
			(start 0.12065 -0.3048)
			(end 0.67945 -0.3048)
			(stroke
				(width 0.1)
				(type default)
			)
			(layer "F.Fab")
		)
		(fp_line
			(start 0.67945 -0.3048)
			(end 0.67945 0.3048)
			(stroke
				(width 0.1)
				(type default)
			)
			(layer "F.Fab")
		)
		(fp_line
			(start -0.67945 -0.305054)
			(end -0.12065 -0.305054)
			(stroke
				(width 0.1)
				(type default)
			)
			(layer "F.Fab")
		)
		(fp_line
			(start -0.12065 -0.305054)
			(end -0.12065 -0.2794)
			(stroke
				(width 0.1)
				(type default)
			)
			(layer "F.Fab")
		)
		(pad "1" smd circle
			(at -0.40005 0 270)
			(size 0 0)
			(layers "F.Cu" "F.Mask" "F.Paste")
			(net "NIC1_MAIN_PWR_BIC_EN_R")
		)
		(pad "2" smd circle
			(at 0.40005 0 270)
			(size 0 0)
			(layers "F.Cu" "F.Mask" "F.Paste")
			(net "NIC1_MAIN_PWR_BIC_EN")
		)
	)
	(footprint ""
		(layer "F.Cu")
		(at 149.586442 -250.070874 -90)
		(property "Reference" "R1266"
			(at 0 0 270)
			(layer "F.SilkS")
			(hide yes)
			(effects
				(font
					(size 1.27 1.27)
				)
			)
		)
		(property "Value" ""
			(at 0 0 270)
			(layer "F.Fab")
			(effects
				(font
					(size 1.27 1.27)
				)
			)
		)
		(duplicate_pad_numbers_are_jumpers no)
		(fp_line
			(start -0.7874 0.4064)
			(end -0.7874 -0.4064)
			(stroke
				(width 0.1524)
				(type default)
			)
			(layer "F.SilkS")
		)
		(fp_line
			(start 0.7874 0.4064)
			(end -0.7874 0.4064)
			(stroke
				(width 0.1524)
				(type default)
			)
			(layer "F.SilkS")
		)
		(fp_line
			(start -0.7874 -0.4064)
			(end 0.7874 -0.4064)
			(stroke
				(width 0.1524)
				(type default)
			)
			(layer "F.SilkS")
		)
		(fp_line
			(start 0.7874 -0.4064)
			(end 0.7874 0.4064)
			(stroke
				(width 0.1524)
				(type default)
			)
			(layer "F.SilkS")
		)
		(fp_line
			(start -0.67945 0.3048)
			(end -0.67945 -0.305054)
			(stroke
				(width 0.1)
				(type default)
			)
			(layer "F.Fab")
		)
		(fp_line
			(start -0.12065 0.3048)
			(end -0.67945 0.3048)
			(stroke
				(width 0.1)
				(type default)
			)
			(layer "F.Fab")
		)
		(fp_line
			(start 0.120396 0.3048)
			(end 0.120396 0.2794)
			(stroke
				(width 0.1)
				(type default)
			)
			(layer "F.Fab")
		)
		(fp_line
			(start 0.67945 0.3048)
			(end 0.120396 0.3048)
			(stroke
				(width 0.1)
				(type default)
			)
			(layer "F.Fab")
		)
		(fp_line
			(start -0.12065 0.2794)
			(end -0.12065 0.3048)
			(stroke
				(width 0.1)
				(type default)
			)
			(layer "F.Fab")
		)
		(fp_line
			(start 0.120396 0.2794)
			(end -0.12065 0.2794)
			(stroke
				(width 0.1)
				(type default)
			)
			(layer "F.Fab")
		)
		(fp_line
			(start -0.12065 -0.2794)
			(end 0.12065 -0.2794)
			(stroke
				(width 0.1)
				(type default)
			)
			(layer "F.Fab")
		)
		(fp_line
			(start 0.12065 -0.2794)
			(end 0.12065 -0.3048)
			(stroke
				(width 0.1)
				(type default)
			)
			(layer "F.Fab")
		)
		(fp_line
			(start 0.12065 -0.3048)
			(end 0.67945 -0.3048)
			(stroke
				(width 0.1)
				(type default)
			)
			(layer "F.Fab")
		)
		(fp_line
			(start 0.67945 -0.3048)
			(end 0.67945 0.3048)
			(stroke
				(width 0.1)
				(type default)
			)
			(layer "F.Fab")
		)
		(fp_line
			(start -0.67945 -0.305054)
			(end -0.12065 -0.305054)
			(stroke
				(width 0.1)
				(type default)
			)
			(layer "F.Fab")
		)
		(fp_line
			(start -0.12065 -0.305054)
			(end -0.12065 -0.2794)
			(stroke
				(width 0.1)
				(type default)
			)
			(layer "F.Fab")
		)
		(pad "1" smd circle
			(at -0.40005 0 270)
			(size 0 0)
			(layers "F.Cu" "F.Mask" "F.Paste")
			(net "PEX1_DBG_MODE2")
		)
		(pad "2" smd circle
			(at 0.40005 0 270)
			(size 0 0)
			(layers "F.Cu" "F.Mask" "F.Paste")
			(net "P1V8_PEX")
		)
	)
	(footprint ""
		(layer "F.Cu")
		(at 235.557822 -27.006296 -90)
		(property "Reference" "PR7115"
			(at 0 0 270)
			(layer "F.SilkS")
			(hide yes)
			(effects
				(font
					(size 1.27 1.27)
				)
			)
		)
		(property "Value" ""
			(at 0 0 270)
			(layer "F.Fab")
			(effects
				(font
					(size 1.27 1.27)
				)
			)
		)
		(duplicate_pad_numbers_are_jumpers no)
		(fp_line
			(start -0.7874 0.4064)
			(end -0.7874 -0.4064)
			(stroke
				(width 0.1524)
				(type default)
			)
			(layer "F.SilkS")
		)
		(fp_line
			(start 0.7874 0.4064)
			(end -0.7874 0.4064)
			(stroke
				(width 0.1524)
				(type default)
			)
			(layer "F.SilkS")
		)
		(fp_line
			(start -0.7874 -0.4064)
			(end 0.7874 -0.4064)
			(stroke
				(width 0.1524)
				(type default)
			)
			(layer "F.SilkS")
		)
		(fp_line
			(start 0.7874 -0.4064)
			(end 0.7874 0.4064)
			(stroke
				(width 0.1524)
				(type default)
			)
			(layer "F.SilkS")
		)
		(fp_line
			(start -0.67945 0.3048)
			(end -0.67945 -0.305054)
			(stroke
				(width 0.1)
				(type default)
			)
			(layer "F.Fab")
		)
		(fp_line
			(start -0.12065 0.3048)
			(end -0.67945 0.3048)
			(stroke
				(width 0.1)
				(type default)
			)
			(layer "F.Fab")
		)
		(fp_line
			(start 0.120396 0.3048)
			(end 0.120396 0.2794)
			(stroke
				(width 0.1)
				(type default)
			)
			(layer "F.Fab")
		)
		(fp_line
			(start 0.67945 0.3048)
			(end 0.120396 0.3048)
			(stroke
				(width 0.1)
				(type default)
			)
			(layer "F.Fab")
		)
		(fp_line
			(start -0.12065 0.2794)
			(end -0.12065 0.3048)
			(stroke
				(width 0.1)
				(type default)
			)
			(layer "F.Fab")
		)
		(fp_line
			(start 0.120396 0.2794)
			(end -0.12065 0.2794)
			(stroke
				(width 0.1)
				(type default)
			)
			(layer "F.Fab")
		)
		(fp_line
			(start -0.12065 -0.2794)
			(end 0.12065 -0.2794)
			(stroke
				(width 0.1)
				(type default)
			)
			(layer "F.Fab")
		)
		(fp_line
			(start 0.12065 -0.2794)
			(end 0.12065 -0.3048)
			(stroke
				(width 0.1)
				(type default)
			)
			(layer "F.Fab")
		)
		(fp_line
			(start 0.12065 -0.3048)
			(end 0.67945 -0.3048)
			(stroke
				(width 0.1)
				(type default)
			)
			(layer "F.Fab")
		)
		(fp_line
			(start 0.67945 -0.3048)
			(end 0.67945 0.3048)
			(stroke
				(width 0.1)
				(type default)
			)
			(layer "F.Fab")
		)
		(fp_line
			(start -0.67945 -0.305054)
			(end -0.12065 -0.305054)
			(stroke
				(width 0.1)
				(type default)
			)
			(layer "F.Fab")
		)
		(fp_line
			(start -0.12065 -0.305054)
			(end -0.12065 -0.2794)
			(stroke
				(width 0.1)
				(type default)
			)
			(layer "F.Fab")
		)
		(pad "1" smd circle
			(at -0.40005 0 270)
			(size 0 0)
			(layers "F.Cu" "F.Mask" "F.Paste")
			(net "P3V3_SSD8_CO_MODE")
		)
		(pad "2" smd circle
			(at 0.40005 0 270)
			(size 0 0)
			(layers "F.Cu" "F.Mask" "F.Paste")
			(net "GND")
		)
	)
	(footprint ""
		(layer "F.Cu")
		(at 380.711456 -286.844232 -90)
		(property "Reference" "R4594"
			(at 0 0 270)
			(layer "F.SilkS")
			(hide yes)
			(effects
				(font
					(size 1.27 1.27)
				)
			)
		)
		(property "Value" ""
			(at 0 0 270)
			(layer "F.Fab")
			(effects
				(font
					(size 1.27 1.27)
				)
			)
		)
		(duplicate_pad_numbers_are_jumpers no)
		(fp_line
			(start -0.7874 0.4064)
			(end -0.7874 -0.4064)
			(stroke
				(width 0.1524)
				(type default)
			)
			(layer "F.SilkS")
		)
		(fp_line
			(start 0.7874 0.4064)
			(end -0.7874 0.4064)
			(stroke
				(width 0.1524)
				(type default)
			)
			(layer "F.SilkS")
		)
		(fp_line
			(start -0.7874 -0.4064)
			(end 0.7874 -0.4064)
			(stroke
				(width 0.1524)
				(type default)
			)
			(layer "F.SilkS")
		)
		(fp_line
			(start 0.7874 -0.4064)
			(end 0.7874 0.4064)
			(stroke
				(width 0.1524)
				(type default)
			)
			(layer "F.SilkS")
		)
		(fp_line
			(start -0.67945 0.3048)
			(end -0.67945 -0.305054)
			(stroke
				(width 0.1)
				(type default)
			)
			(layer "F.Fab")
		)
		(fp_line
			(start -0.12065 0.3048)
			(end -0.67945 0.3048)
			(stroke
				(width 0.1)
				(type default)
			)
			(layer "F.Fab")
		)
		(fp_line
			(start 0.120396 0.3048)
			(end 0.120396 0.2794)
			(stroke
				(width 0.1)
				(type default)
			)
			(layer "F.Fab")
		)
		(fp_line
			(start 0.67945 0.3048)
			(end 0.120396 0.3048)
			(stroke
				(width 0.1)
				(type default)
			)
			(layer "F.Fab")
		)
		(fp_line
			(start -0.12065 0.2794)
			(end -0.12065 0.3048)
			(stroke
				(width 0.1)
				(type default)
			)
			(layer "F.Fab")
		)
		(fp_line
			(start 0.120396 0.2794)
			(end -0.12065 0.2794)
			(stroke
				(width 0.1)
				(type default)
			)
			(layer "F.Fab")
		)
		(fp_line
			(start -0.12065 -0.2794)
			(end 0.12065 -0.2794)
			(stroke
				(width 0.1)
				(type default)
			)
			(layer "F.Fab")
		)
		(fp_line
			(start 0.12065 -0.2794)
			(end 0.12065 -0.3048)
			(stroke
				(width 0.1)
				(type default)
			)
			(layer "F.Fab")
		)
		(fp_line
			(start 0.12065 -0.3048)
			(end 0.67945 -0.3048)
			(stroke
				(width 0.1)
				(type default)
			)
			(layer "F.Fab")
		)
		(fp_line
			(start 0.67945 -0.3048)
			(end 0.67945 0.3048)
			(stroke
				(width 0.1)
				(type default)
			)
			(layer "F.Fab")
		)
		(fp_line
			(start -0.67945 -0.305054)
			(end -0.12065 -0.305054)
			(stroke
				(width 0.1)
				(type default)
			)
			(layer "F.Fab")
		)
		(fp_line
			(start -0.12065 -0.305054)
			(end -0.12065 -0.2794)
			(stroke
				(width 0.1)
				(type default)
			)
			(layer "F.Fab")
		)
		(pad "1" smd circle
			(at -0.40005 0 270)
			(size 0 0)
			(layers "F.Cu" "F.Mask" "F.Paste")
			(net "PCEPLL6_VDDA18_PEX3")
		)
		(pad "2" smd circle
			(at 0.40005 0 270)
			(size 0 0)
			(layers "F.Cu" "F.Mask" "F.Paste")
			(net "PCEPLL6_VDDA18_PEX3_R")
		)
	)
	(footprint ""
		(layer "F.Cu")
		(at 210.054698 -235.76407 -90)
		(property "Reference" "R6319"
			(at 0 0 270)
			(layer "F.SilkS")
			(hide yes)
			(effects
				(font
					(size 1.27 1.27)
				)
			)
		)
		(property "Value" ""
			(at 0 0 270)
			(layer "F.Fab")
			(effects
				(font
					(size 1.27 1.27)
				)
			)
		)
		(duplicate_pad_numbers_are_jumpers no)
		(fp_line
			(start -0.7874 0.4064)
			(end -0.7874 -0.4064)
			(stroke
				(width 0.1524)
				(type default)
			)
			(layer "F.SilkS")
		)
		(fp_line
			(start 0.7874 0.4064)
			(end -0.7874 0.4064)
			(stroke
				(width 0.1524)
				(type default)
			)
			(layer "F.SilkS")
		)
		(fp_line
			(start -0.7874 -0.4064)
			(end 0.7874 -0.4064)
			(stroke
				(width 0.1524)
				(type default)
			)
			(layer "F.SilkS")
		)
		(fp_line
			(start 0.7874 -0.4064)
			(end 0.7874 0.4064)
			(stroke
				(width 0.1524)
				(type default)
			)
			(layer "F.SilkS")
		)
		(fp_line
			(start -0.67945 0.3048)
			(end -0.67945 -0.305054)
			(stroke
				(width 0.1)
				(type default)
			)
			(layer "F.Fab")
		)
		(fp_line
			(start -0.12065 0.3048)
			(end -0.67945 0.3048)
			(stroke
				(width 0.1)
				(type default)
			)
			(layer "F.Fab")
		)
		(fp_line
			(start 0.120396 0.3048)
			(end 0.120396 0.2794)
			(stroke
				(width 0.1)
				(type default)
			)
			(layer "F.Fab")
		)
		(fp_line
			(start 0.67945 0.3048)
			(end 0.120396 0.3048)
			(stroke
				(width 0.1)
				(type default)
			)
			(layer "F.Fab")
		)
		(fp_line
			(start -0.12065 0.2794)
			(end -0.12065 0.3048)
			(stroke
				(width 0.1)
				(type default)
			)
			(layer "F.Fab")
		)
		(fp_line
			(start 0.120396 0.2794)
			(end -0.12065 0.2794)
			(stroke
				(width 0.1)
				(type default)
			)
			(layer "F.Fab")
		)
		(fp_line
			(start -0.12065 -0.2794)
			(end 0.12065 -0.2794)
			(stroke
				(width 0.1)
				(type default)
			)
			(layer "F.Fab")
		)
		(fp_line
			(start 0.12065 -0.2794)
			(end 0.12065 -0.3048)
			(stroke
				(width 0.1)
				(type default)
			)
			(layer "F.Fab")
		)
		(fp_line
			(start 0.12065 -0.3048)
			(end 0.67945 -0.3048)
			(stroke
				(width 0.1)
				(type default)
			)
			(layer "F.Fab")
		)
		(fp_line
			(start 0.67945 -0.3048)
			(end 0.67945 0.3048)
			(stroke
				(width 0.1)
				(type default)
			)
			(layer "F.Fab")
		)
		(fp_line
			(start -0.67945 -0.305054)
			(end -0.12065 -0.305054)
			(stroke
				(width 0.1)
				(type default)
			)
			(layer "F.Fab")
		)
		(fp_line
			(start -0.12065 -0.305054)
			(end -0.12065 -0.2794)
			(stroke
				(width 0.1)
				(type default)
			)
			(layer "F.Fab")
		)
		(pad "1" smd circle
			(at -0.40005 0 270)
			(size 0 0)
			(layers "F.Cu" "F.Mask" "F.Paste")
			(net "SMB_PEX_LS_SCL")
		)
		(pad "2" smd circle
			(at 0.40005 0 270)
			(size 0 0)
			(layers "F.Cu" "F.Mask" "F.Paste")
			(net "SMB_PEX_MUX_SCL")
		)
	)
	(footprint ""
		(layer "F.Cu")
		(at 145.972276 -32.848042 90)
		(property "Reference" "PC922"
			(at 0 0 90)
			(layer "F.SilkS")
			(hide yes)
			(effects
				(font
					(size 1.27 1.27)
				)
			)
		)
		(property "Value" ""
			(at 0 0 90)
			(layer "F.Fab")
			(effects
				(font
					(size 1.27 1.27)
				)
			)
		)
		(duplicate_pad_numbers_are_jumpers no)
		(fp_line
			(start 0.7874 -0.4064)
			(end 0.7874 0.4064)
			(stroke
				(width 0.1524)
				(type default)
			)
			(layer "F.SilkS")
		)
		(fp_line
			(start -0.7874 -0.4064)
			(end 0.7874 -0.4064)
			(stroke
				(width 0.1524)
				(type default)
			)
			(layer "F.SilkS")
		)
		(fp_line
			(start 0.7874 0.4064)
			(end -0.7874 0.4064)
			(stroke
				(width 0.1524)
				(type default)
			)
			(layer "F.SilkS")
		)
		(fp_line
			(start -0.7874 0.4064)
			(end -0.7874 -0.4064)
			(stroke
				(width 0.1524)
				(type default)
			)
			(layer "F.SilkS")
		)
		(fp_line
			(start -0.12065 -0.305054)
			(end -0.12065 -0.2794)
			(stroke
				(width 0.1)
				(type default)
			)
			(layer "F.Fab")
		)
		(fp_line
			(start -0.67945 -0.305054)
			(end -0.12065 -0.305054)
			(stroke
				(width 0.1)
				(type default)
			)
			(layer "F.Fab")
		)
		(fp_line
			(start 0.67945 -0.3048)
			(end 0.67945 0.3048)
			(stroke
				(width 0.1)
				(type default)
			)
			(layer "F.Fab")
		)
		(fp_line
			(start 0.12065 -0.3048)
			(end 0.67945 -0.3048)
			(stroke
				(width 0.1)
				(type default)
			)
			(layer "F.Fab")
		)
		(fp_line
			(start 0.12065 -0.2794)
			(end 0.12065 -0.3048)
			(stroke
				(width 0.1)
				(type default)
			)
			(layer "F.Fab")
		)
		(fp_line
			(start -0.12065 -0.2794)
			(end 0.12065 -0.2794)
			(stroke
				(width 0.1)
				(type default)
			)
			(layer "F.Fab")
		)
		(fp_line
			(start 0.120396 0.2794)
			(end -0.12065 0.2794)
			(stroke
				(width 0.1)
				(type default)
			)
			(layer "F.Fab")
		)
		(fp_line
			(start -0.12065 0.2794)
			(end -0.12065 0.3048)
			(stroke
				(width 0.1)
				(type default)
			)
			(layer "F.Fab")
		)
		(fp_line
			(start 0.67945 0.3048)
			(end 0.120396 0.3048)
			(stroke
				(width 0.1)
				(type default)
			)
			(layer "F.Fab")
		)
		(fp_line
			(start 0.120396 0.3048)
			(end 0.120396 0.2794)
			(stroke
				(width 0.1)
				(type default)
			)
			(layer "F.Fab")
		)
		(fp_line
			(start -0.12065 0.3048)
			(end -0.67945 0.3048)
			(stroke
				(width 0.1)
				(type default)
			)
			(layer "F.Fab")
		)
		(fp_line
			(start -0.67945 0.3048)
			(end -0.67945 -0.305054)
			(stroke
				(width 0.1)
				(type default)
			)
			(layer "F.Fab")
		)
		(pad "1" smd circle
			(at -0.40005 0 90)
			(size 0 0)
			(layers "F.Cu" "F.Mask" "F.Paste")
			(net "P3V3_SSD5_CO_GATE")
		)
		(pad "2" smd circle
			(at 0.40005 0 90)
			(size 0 0)
			(layers "F.Cu" "F.Mask" "F.Paste")
			(net "GND")
		)
	)
	(footprint ""
		(layer "F.Cu")
		(at 376.34926 -284.195012 -90)
		(property "Reference" "C3560"
			(at 0 0 270)
			(layer "F.SilkS")
			(hide yes)
			(effects
				(font
					(size 1.27 1.27)
				)
			)
		)
		(property "Value" ""
			(at 0 0 270)
			(layer "F.Fab")
			(effects
				(font
					(size 1.27 1.27)
				)
			)
		)
		(duplicate_pad_numbers_are_jumpers no)
		(fp_line
			(start -0.299974 0.150114)
			(end -0.299974 -0.150114)
			(stroke
				(width 0.1)
				(type default)
			)
			(layer "F.Fab")
		)
		(fp_line
			(start 0.299974 0.150114)
			(end -0.299974 0.150114)
			(stroke
				(width 0.1)
				(type default)
			)
			(layer "F.Fab")
		)
		(fp_line
			(start -0.299974 -0.150114)
			(end 0.299974 -0.150114)
			(stroke
				(width 0.1)
				(type default)
			)
			(layer "F.Fab")
		)
		(fp_line
			(start 0.299974 -0.150114)
			(end 0.299974 0.150114)
			(stroke
				(width 0.1)
				(type default)
			)
			(layer "F.Fab")
		)
		(pad "1" smd rect
			(at -0.2667 0 270)
			(size 0.3048 0.381)
			(layers "F.Cu" "F.Mask" "F.Paste")
			(net "P1V8_PLL0_PEX3")
		)
		(pad "2" smd rect
			(at 0.2667 0 270)
			(size 0.3048 0.381)
			(layers "F.Cu" "F.Mask" "F.Paste")
			(net "GND")
		)
	)
	(footprint ""
		(layer "F.Cu")
		(at 87.132922 -350.098614 90)
		(property "Reference" "C104"
			(at 0 0 90)
			(layer "F.SilkS")
			(hide yes)
			(effects
				(font
					(size 1.27 1.27)
				)
			)
		)
		(property "Value" ""
			(at 0 0 90)
			(layer "F.Fab")
			(effects
				(font
					(size 1.27 1.27)
				)
			)
		)
		(duplicate_pad_numbers_are_jumpers no)
		(fp_line
			(start 0.299974 -0.150114)
			(end 0.299974 0.150114)
			(stroke
				(width 0.1)
				(type default)
			)
			(layer "F.Fab")
		)
		(fp_line
			(start -0.299974 -0.150114)
			(end 0.299974 -0.150114)
			(stroke
				(width 0.1)
				(type default)
			)
			(layer "F.Fab")
		)
		(fp_line
			(start 0.299974 0.150114)
			(end -0.299974 0.150114)
			(stroke
				(width 0.1)
				(type default)
			)
			(layer "F.Fab")
		)
		(fp_line
			(start -0.299974 0.150114)
			(end -0.299974 -0.150114)
			(stroke
				(width 0.1)
				(type default)
			)
			(layer "F.Fab")
		)
		(pad "1" smd rect
			(at -0.2667 0 90)
			(size 0.3048 0.381)
			(layers "F.Cu" "F.Mask" "F.Paste")
			(net "P5E_PEX0_STN5_TX_DN<92>")
		)
		(pad "2" smd rect
			(at 0.2667 0 90)
			(size 0.3048 0.381)
			(layers "F.Cu" "F.Mask" "F.Paste")
			(net "P5E_PEX0_STN5_TX_C_DN<92>")
		)
	)
	(footprint ""
		(layer "F.Cu")
		(at 152.738328 -108.29544)
		(property "Reference" "C264"
			(at 0 0 0)
			(layer "F.SilkS")
			(hide yes)
			(effects
				(font
					(size 1.27 1.27)
				)
			)
		)
		(property "Value" ""
			(at 0 0 0)
			(layer "F.Fab")
			(effects
				(font
					(size 1.27 1.27)
				)
			)
		)
		(duplicate_pad_numbers_are_jumpers no)
		(fp_line
			(start -0.299974 -0.150114)
			(end 0.299974 -0.150114)
			(stroke
				(width 0.1)
				(type default)
			)
			(layer "F.Fab")
		)
		(fp_line
			(start -0.299974 0.150114)
			(end -0.299974 -0.150114)
			(stroke
				(width 0.1)
				(type default)
			)
			(layer "F.Fab")
		)
		(fp_line
			(start 0.299974 -0.150114)
			(end 0.299974 0.150114)
			(stroke
				(width 0.1)
				(type default)
			)
			(layer "F.Fab")
		)
		(fp_line
			(start 0.299974 0.150114)
			(end -0.299974 0.150114)
			(stroke
				(width 0.1)
				(type default)
			)
			(layer "F.Fab")
		)
		(pad "1" smd rect
			(at -0.2667 0)
			(size 0.3048 0.381)
			(layers "F.Cu" "F.Mask" "F.Paste")
			(net "P5E_PEX1_STN1_TX_DN<21>")
		)
		(pad "2" smd rect
			(at 0.2667 0)
			(size 0.3048 0.381)
			(layers "F.Cu" "F.Mask" "F.Paste")
			(net "P5E_PEX1_STN1_TX_C_DN<21>")
		)
	)
	(footprint ""
		(layer "F.Cu")
		(at 231.954832 -155.960826 -90)
		(property "Reference" "R1208"
			(at 0 0 270)
			(layer "F.SilkS")
			(hide yes)
			(effects
				(font
					(size 1.27 1.27)
				)
			)
		)
		(property "Value" ""
			(at 0 0 270)
			(layer "F.Fab")
			(effects
				(font
					(size 1.27 1.27)
				)
			)
		)
		(duplicate_pad_numbers_are_jumpers no)
		(fp_line
			(start -0.7874 -0.4064)
			(end 0.7874 -0.4064)
			(stroke
				(width 0.1524)
				(type default)
			)
			(layer "F.SilkS")
		)
		(fp_line
			(start -0.67945 0.3048)
			(end -0.67945 -0.305054)
			(stroke
				(width 0.1)
				(type default)
			)
			(layer "F.Fab")
		)
		(fp_line
			(start -0.12065 0.3048)
			(end -0.67945 0.3048)
			(stroke
				(width 0.1)
				(type default)
			)
			(layer "F.Fab")
		)
		(fp_line
			(start 0.120396 0.3048)
			(end 0.120396 0.2794)
			(stroke
				(width 0.1)
				(type default)
			)
			(layer "F.Fab")
		)
		(fp_line
			(start 0.67945 0.3048)
			(end 0.120396 0.3048)
			(stroke
				(width 0.1)
				(type default)
			)
			(layer "F.Fab")
		)
		(fp_line
			(start -0.12065 0.2794)
			(end -0.12065 0.3048)
			(stroke
				(width 0.1)
				(type default)
			)
			(layer "F.Fab")
		)
		(fp_line
			(start 0.120396 0.2794)
			(end -0.12065 0.2794)
			(stroke
				(width 0.1)
				(type default)
			)
			(layer "F.Fab")
		)
		(fp_line
			(start -0.12065 -0.2794)
			(end 0.12065 -0.2794)
			(stroke
				(width 0.1)
				(type default)
			)
			(layer "F.Fab")
		)
		(fp_line
			(start 0.12065 -0.2794)
			(end 0.12065 -0.3048)
			(stroke
				(width 0.1)
				(type default)
			)
			(layer "F.Fab")
		)
		(fp_line
			(start 0.12065 -0.3048)
			(end 0.67945 -0.3048)
			(stroke
				(width 0.1)
				(type default)
			)
			(layer "F.Fab")
		)
		(fp_line
			(start 0.67945 -0.3048)
			(end 0.67945 0.3048)
			(stroke
				(width 0.1)
				(type default)
			)
			(layer "F.Fab")
		)
		(fp_line
			(start -0.67945 -0.305054)
			(end -0.12065 -0.305054)
			(stroke
				(width 0.1)
				(type default)
			)
			(layer "F.Fab")
		)
		(fp_line
			(start -0.12065 -0.305054)
			(end -0.12065 -0.2794)
			(stroke
				(width 0.1)
				(type default)
			)
			(layer "F.Fab")
		)
		(pad "1" smd circle
			(at -0.40005 0 270)
			(size 0 0)
			(layers "F.Cu" "F.Mask" "F.Paste")
			(net "CLK_100M_PEX1_REF_R_DN")
		)
		(pad "2" smd circle
			(at 0.40005 0 270)
			(size 0 0)
			(layers "F.Cu" "F.Mask" "F.Paste")
			(net "CLK_100M_PEX1_REF_DN")
		)
	)
	(footprint ""
		(layer "F.Cu")
		(at 39.582344 -252.356874 -90)
		(property "Reference" "R3954"
			(at 0 0 270)
			(layer "F.SilkS")
			(hide yes)
			(effects
				(font
					(size 1.27 1.27)
				)
			)
		)
		(property "Value" ""
			(at 0 0 270)
			(layer "F.Fab")
			(effects
				(font
					(size 1.27 1.27)
				)
			)
		)
		(duplicate_pad_numbers_are_jumpers no)
		(fp_line
			(start -0.7874 0.4064)
			(end -0.7874 -0.4064)
			(stroke
				(width 0.1524)
				(type default)
			)
			(layer "F.SilkS")
		)
		(fp_line
			(start 0.7874 0.4064)
			(end -0.7874 0.4064)
			(stroke
				(width 0.1524)
				(type default)
			)
			(layer "F.SilkS")
		)
		(fp_line
			(start -0.7874 -0.4064)
			(end 0.7874 -0.4064)
			(stroke
				(width 0.1524)
				(type default)
			)
			(layer "F.SilkS")
		)
		(fp_line
			(start 0.7874 -0.4064)
			(end 0.7874 0.4064)
			(stroke
				(width 0.1524)
				(type default)
			)
			(layer "F.SilkS")
		)
		(fp_line
			(start -0.67945 0.3048)
			(end -0.67945 -0.305054)
			(stroke
				(width 0.1)
				(type default)
			)
			(layer "F.Fab")
		)
		(fp_line
			(start -0.12065 0.3048)
			(end -0.67945 0.3048)
			(stroke
				(width 0.1)
				(type default)
			)
			(layer "F.Fab")
		)
		(fp_line
			(start 0.120396 0.3048)
			(end 0.120396 0.2794)
			(stroke
				(width 0.1)
				(type default)
			)
			(layer "F.Fab")
		)
		(fp_line
			(start 0.67945 0.3048)
			(end 0.120396 0.3048)
			(stroke
				(width 0.1)
				(type default)
			)
			(layer "F.Fab")
		)
		(fp_line
			(start -0.12065 0.2794)
			(end -0.12065 0.3048)
			(stroke
				(width 0.1)
				(type default)
			)
			(layer "F.Fab")
		)
		(fp_line
			(start 0.120396 0.2794)
			(end -0.12065 0.2794)
			(stroke
				(width 0.1)
				(type default)
			)
			(layer "F.Fab")
		)
		(fp_line
			(start -0.12065 -0.2794)
			(end 0.12065 -0.2794)
			(stroke
				(width 0.1)
				(type default)
			)
			(layer "F.Fab")
		)
		(fp_line
			(start 0.12065 -0.2794)
			(end 0.12065 -0.3048)
			(stroke
				(width 0.1)
				(type default)
			)
			(layer "F.Fab")
		)
		(fp_line
			(start 0.12065 -0.3048)
			(end 0.67945 -0.3048)
			(stroke
				(width 0.1)
				(type default)
			)
			(layer "F.Fab")
		)
		(fp_line
			(start 0.67945 -0.3048)
			(end 0.67945 0.3048)
			(stroke
				(width 0.1)
				(type default)
			)
			(layer "F.Fab")
		)
		(fp_line
			(start -0.67945 -0.305054)
			(end -0.12065 -0.305054)
			(stroke
				(width 0.1)
				(type default)
			)
			(layer "F.Fab")
		)
		(fp_line
			(start -0.12065 -0.305054)
			(end -0.12065 -0.2794)
			(stroke
				(width 0.1)
				(type default)
			)
			(layer "F.Fab")
		)
		(pad "1" smd circle
			(at -0.40005 0 270)
			(size 0 0)
			(layers "F.Cu" "F.Mask" "F.Paste")
			(net "PEX0_PCA9555_INT_R_N")
		)
		(pad "2" smd circle
			(at 0.40005 0 270)
			(size 0 0)
			(layers "F.Cu" "F.Mask" "F.Paste")
			(net "P1V8_PEX")
		)
	)
	(footprint ""
		(layer "F.Cu")
		(at 248.094754 -277.535386)
		(property "Reference" "R795"
			(at 0 0 0)
			(layer "F.SilkS")
			(hide yes)
			(effects
				(font
					(size 1.27 1.27)
				)
			)
		)
		(property "Value" ""
			(at 0 0 0)
			(layer "F.Fab")
			(effects
				(font
					(size 1.27 1.27)
				)
			)
		)
		(duplicate_pad_numbers_are_jumpers no)
		(fp_line
			(start -0.7874 -0.4064)
			(end 0.7874 -0.4064)
			(stroke
				(width 0.1524)
				(type default)
			)
			(layer "F.SilkS")
		)
		(fp_line
			(start -0.7874 0.4064)
			(end -0.7874 -0.4064)
			(stroke
				(width 0.1524)
				(type default)
			)
			(layer "F.SilkS")
		)
		(fp_line
			(start 0.7874 -0.4064)
			(end 0.7874 0.4064)
			(stroke
				(width 0.1524)
				(type default)
			)
			(layer "F.SilkS")
		)
		(fp_line
			(start 0.7874 0.4064)
			(end -0.7874 0.4064)
			(stroke
				(width 0.1524)
				(type default)
			)
			(layer "F.SilkS")
		)
		(fp_line
			(start -0.67945 -0.305054)
			(end -0.12065 -0.305054)
			(stroke
				(width 0.1)
				(type default)
			)
			(layer "F.Fab")
		)
		(fp_line
			(start -0.67945 0.3048)
			(end -0.67945 -0.305054)
			(stroke
				(width 0.1)
				(type default)
			)
			(layer "F.Fab")
		)
		(fp_line
			(start -0.12065 -0.305054)
			(end -0.12065 -0.2794)
			(stroke
				(width 0.1)
				(type default)
			)
			(layer "F.Fab")
		)
		(fp_line
			(start -0.12065 -0.2794)
			(end 0.12065 -0.2794)
			(stroke
				(width 0.1)
				(type default)
			)
			(layer "F.Fab")
		)
		(fp_line
			(start -0.12065 0.2794)
			(end -0.12065 0.3048)
			(stroke
				(width 0.1)
				(type default)
			)
			(layer "F.Fab")
		)
		(fp_line
			(start -0.12065 0.3048)
			(end -0.67945 0.3048)
			(stroke
				(width 0.1)
				(type default)
			)
			(layer "F.Fab")
		)
		(fp_line
			(start 0.120396 0.2794)
			(end -0.12065 0.2794)
			(stroke
				(width 0.1)
				(type default)
			)
			(layer "F.Fab")
		)
		(fp_line
			(start 0.120396 0.3048)
			(end 0.120396 0.2794)
			(stroke
				(width 0.1)
				(type default)
			)
			(layer "F.Fab")
		)
		(fp_line
			(start 0.12065 -0.3048)
			(end 0.67945 -0.3048)
			(stroke
				(width 0.1)
				(type default)
			)
			(layer "F.Fab")
		)
		(fp_line
			(start 0.12065 -0.2794)
			(end 0.12065 -0.3048)
			(stroke
				(width 0.1)
				(type default)
			)
			(layer "F.Fab")
		)
		(fp_line
			(start 0.67945 -0.3048)
			(end 0.67945 0.3048)
			(stroke
				(width 0.1)
				(type default)
			)
			(layer "F.Fab")
		)
		(fp_line
			(start 0.67945 0.3048)
			(end 0.120396 0.3048)
			(stroke
				(width 0.1)
				(type default)
			)
			(layer "F.Fab")
		)
		(pad "1" smd circle
			(at -0.40005 0)
			(size 0 0)
			(layers "F.Cu" "F.Mask" "F.Paste")
			(net "PEX2_P1V25_ADC_ALERT_N")
		)
		(pad "2" smd circle
			(at 0.40005 0)
			(size 0 0)
			(layers "F.Cu" "F.Mask" "F.Paste")
			(net "PEX_ADC_ALERT_N")
		)
	)
	(footprint ""
		(layer "F.Cu")
		(at 21.771864 -259.346192)
		(property "Reference" "R1255"
			(at 0 0 0)
			(layer "F.SilkS")
			(hide yes)
			(effects
				(font
					(size 1.27 1.27)
				)
			)
		)
		(property "Value" ""
			(at 0 0 0)
			(layer "F.Fab")
			(effects
				(font
					(size 1.27 1.27)
				)
			)
		)
		(duplicate_pad_numbers_are_jumpers no)
		(fp_line
			(start -0.7874 -0.4064)
			(end 0.7874 -0.4064)
			(stroke
				(width 0.1524)
				(type default)
			)
			(layer "F.SilkS")
		)
		(fp_line
			(start -0.7874 0.4064)
			(end -0.7874 -0.4064)
			(stroke
				(width 0.1524)
				(type default)
			)
			(layer "F.SilkS")
		)
		(fp_line
			(start 0.7874 -0.4064)
			(end 0.7874 0.4064)
			(stroke
				(width 0.1524)
				(type default)
			)
			(layer "F.SilkS")
		)
		(fp_line
			(start 0.7874 0.4064)
			(end -0.7874 0.4064)
			(stroke
				(width 0.1524)
				(type default)
			)
			(layer "F.SilkS")
		)
		(fp_line
			(start -0.67945 -0.305054)
			(end -0.12065 -0.305054)
			(stroke
				(width 0.1)
				(type default)
			)
			(layer "F.Fab")
		)
		(fp_line
			(start -0.67945 0.3048)
			(end -0.67945 -0.305054)
			(stroke
				(width 0.1)
				(type default)
			)
			(layer "F.Fab")
		)
		(fp_line
			(start -0.12065 -0.305054)
			(end -0.12065 -0.2794)
			(stroke
				(width 0.1)
				(type default)
			)
			(layer "F.Fab")
		)
		(fp_line
			(start -0.12065 -0.2794)
			(end 0.12065 -0.2794)
			(stroke
				(width 0.1)
				(type default)
			)
			(layer "F.Fab")
		)
		(fp_line
			(start -0.12065 0.2794)
			(end -0.12065 0.3048)
			(stroke
				(width 0.1)
				(type default)
			)
			(layer "F.Fab")
		)
		(fp_line
			(start -0.12065 0.3048)
			(end -0.67945 0.3048)
			(stroke
				(width 0.1)
				(type default)
			)
			(layer "F.Fab")
		)
		(fp_line
			(start 0.120396 0.2794)
			(end -0.12065 0.2794)
			(stroke
				(width 0.1)
				(type default)
			)
			(layer "F.Fab")
		)
		(fp_line
			(start 0.120396 0.3048)
			(end 0.120396 0.2794)
			(stroke
				(width 0.1)
				(type default)
			)
			(layer "F.Fab")
		)
		(fp_line
			(start 0.12065 -0.3048)
			(end 0.67945 -0.3048)
			(stroke
				(width 0.1)
				(type default)
			)
			(layer "F.Fab")
		)
		(fp_line
			(start 0.12065 -0.2794)
			(end 0.12065 -0.3048)
			(stroke
				(width 0.1)
				(type default)
			)
			(layer "F.Fab")
		)
		(fp_line
			(start 0.67945 -0.3048)
			(end 0.67945 0.3048)
			(stroke
				(width 0.1)
				(type default)
			)
			(layer "F.Fab")
		)
		(fp_line
			(start 0.67945 0.3048)
			(end 0.120396 0.3048)
			(stroke
				(width 0.1)
				(type default)
			)
			(layer "F.Fab")
		)
		(pad "1" smd circle
			(at -0.40005 0)
			(size 0 0)
			(layers "F.Cu" "F.Mask" "F.Paste")
			(net "PEX0_SYS_ERR_N")
		)
		(pad "2" smd circle
			(at 0.40005 0)
			(size 0 0)
			(layers "F.Cu" "F.Mask" "F.Paste")
			(net "PEX0_SYS_ERR_R_N")
		)
	)
	(footprint ""
		(layer "F.Cu")
		(at 366.955578 -84.927694 180)
		(property "Reference" "R1622"
			(at 0 0 180)
			(layer "F.SilkS")
			(hide yes)
			(effects
				(font
					(size 1.27 1.27)
				)
			)
		)
		(property "Value" ""
			(at 0 0 180)
			(layer "F.Fab")
			(effects
				(font
					(size 1.27 1.27)
				)
			)
		)
		(duplicate_pad_numbers_are_jumpers no)
		(fp_line
			(start 0.7874 0.4064)
			(end -0.7874 0.4064)
			(stroke
				(width 0.1524)
				(type default)
			)
			(layer "F.SilkS")
		)
		(fp_line
			(start 0.7874 -0.4064)
			(end 0.7874 0.4064)
			(stroke
				(width 0.1524)
				(type default)
			)
			(layer "F.SilkS")
		)
		(fp_line
			(start -0.7874 0.4064)
			(end -0.7874 -0.4064)
			(stroke
				(width 0.1524)
				(type default)
			)
			(layer "F.SilkS")
		)
		(fp_line
			(start -0.7874 -0.4064)
			(end 0.7874 -0.4064)
			(stroke
				(width 0.1524)
				(type default)
			)
			(layer "F.SilkS")
		)
		(fp_line
			(start 0.67945 0.3048)
			(end 0.120396 0.3048)
			(stroke
				(width 0.1)
				(type default)
			)
			(layer "F.Fab")
		)
		(fp_line
			(start 0.67945 -0.3048)
			(end 0.67945 0.3048)
			(stroke
				(width 0.1)
				(type default)
			)
			(layer "F.Fab")
		)
		(fp_line
			(start 0.12065 -0.2794)
			(end 0.12065 -0.3048)
			(stroke
				(width 0.1)
				(type default)
			)
			(layer "F.Fab")
		)
		(fp_line
			(start 0.12065 -0.3048)
			(end 0.67945 -0.3048)
			(stroke
				(width 0.1)
				(type default)
			)
			(layer "F.Fab")
		)
		(fp_line
			(start 0.120396 0.3048)
			(end 0.120396 0.2794)
			(stroke
				(width 0.1)
				(type default)
			)
			(layer "F.Fab")
		)
		(fp_line
			(start 0.120396 0.2794)
			(end -0.12065 0.2794)
			(stroke
				(width 0.1)
				(type default)
			)
			(layer "F.Fab")
		)
		(fp_line
			(start -0.12065 0.3048)
			(end -0.67945 0.3048)
			(stroke
				(width 0.1)
				(type default)
			)
			(layer "F.Fab")
		)
		(fp_line
			(start -0.12065 0.2794)
			(end -0.12065 0.3048)
			(stroke
				(width 0.1)
				(type default)
			)
			(layer "F.Fab")
		)
		(fp_line
			(start -0.12065 -0.2794)
			(end 0.12065 -0.2794)
			(stroke
				(width 0.1)
				(type default)
			)
			(layer "F.Fab")
		)
		(fp_line
			(start -0.12065 -0.305054)
			(end -0.12065 -0.2794)
			(stroke
				(width 0.1)
				(type default)
			)
			(layer "F.Fab")
		)
		(fp_line
			(start -0.67945 0.3048)
			(end -0.67945 -0.305054)
			(stroke
				(width 0.1)
				(type default)
			)
			(layer "F.Fab")
		)
		(fp_line
			(start -0.67945 -0.305054)
			(end -0.12065 -0.305054)
			(stroke
				(width 0.1)
				(type default)
			)
			(layer "F.Fab")
		)
		(pad "1" smd circle
			(at -0.40005 0 180)
			(size 0 0)
			(layers "F.Cu" "F.Mask" "F.Paste")
			(net "SMB_BIC_I2C9_MUX1_SSD13_R_SCL")
		)
		(pad "2" smd circle
			(at 0.40005 0 180)
			(size 0 0)
			(layers "F.Cu" "F.Mask" "F.Paste")
			(net "SMB_BIC_I2C9_MUX1_SSD13_SCL")
		)
	)
	(footprint ""
		(layer "F.Cu")
		(at 361.264962 -26.785062 180)
		(property "Reference" "J42"
			(at 3.984498 -11.185652 90)
			(unlocked yes)
			(layer "F.SilkS")
			(effects
				(font
					(size 0.7874 0.5842)
					(thickness 0.1524)
				)
			)
		)
		(property "Value" ""
			(at 0 0 180)
			(layer "F.Fab")
			(effects
				(font
					(size 1.27 1.27)
				)
			)
		)
		(duplicate_pad_numbers_are_jumpers no)
		(fp_line
			(start 3.150108 12.115038)
			(end 1.529334 12.115038)
			(stroke
				(width 0.1524)
				(type default)
			)
			(layer "F.SilkS")
		)
		(fp_line
			(start 3.074924 12.014962)
			(end 1.632204 12.014962)
			(stroke
				(width 0.1524)
				(type default)
			)
			(layer "F.SilkS")
		)
		(fp_line
			(start 1.632204 -12.014962)
			(end 3.074924 -12.014962)
			(stroke
				(width 0.1524)
				(type default)
			)
			(layer "F.SilkS")
		)
		(fp_line
			(start 1.529334 -12.115038)
			(end 3.150108 -12.115038)
			(stroke
				(width 0.1524)
				(type default)
			)
			(layer "F.SilkS")
		)
		(fp_line
			(start -1.529334 12.115038)
			(end -3.150108 12.115038)
			(stroke
				(width 0.1524)
				(type default)
			)
			(layer "F.SilkS")
		)
		(fp_line
			(start -1.632204 12.014962)
			(end -3.074924 12.014962)
			(stroke
				(width 0.1524)
				(type default)
			)
			(layer "F.SilkS")
		)
		(fp_line
			(start -3.074924 -12.014962)
			(end -1.632204 -12.014962)
			(stroke
				(width 0.1524)
				(type default)
			)
			(layer "F.SilkS")
		)
		(fp_line
			(start -3.150108 -12.115038)
			(end -1.529334 -12.115038)
			(stroke
				(width 0.1524)
				(type default)
			)
			(layer "F.SilkS")
		)
		(fp_poly
			(pts
				(xy 3.463036 -8.736076) (xy 3.885438 -10.00379) (xy 4.730496 -9.158732)
			)
			(stroke
				(width 0)
				(type default)
			)
			(fill yes)
			(layer "F.SilkS")
		)
		(fp_line
			(start 3.074924 12.014962)
			(end -3.074924 12.014962)
			(stroke
				(width 0.1)
				(type default)
			)
			(layer "F.Fab")
		)
		(fp_line
			(start 3.074924 -12.014962)
			(end 3.074924 12.014962)
			(stroke
				(width 0.1)
				(type default)
			)
			(layer "F.Fab")
		)
		(fp_line
			(start -3.074924 12.014962)
			(end -3.074924 -12.014962)
			(stroke
				(width 0.1)
				(type default)
			)
			(layer "F.Fab")
		)
		(fp_line
			(start -3.074924 -12.014962)
			(end 3.074924 -12.014962)
			(stroke
				(width 0.1)
				(type default)
			)
			(layer "F.Fab")
		)
		(fp_poly
			(pts
				(xy 3.348736 -7.994904) (xy 4.543806 -8.592566) (xy 4.543806 -7.397496)
			)
			(stroke
				(width 0)
				(type default)
			)
			(fill yes)
			(layer "F.Fab")
		)
		(pad "" np_thru_hole circle
			(at -1.75006 -9.815068 90)
			(size 1.1176 1.1176)
			(drill 1.1176)
			(layers "*.Cu" "*.Mask")
			(clearance 0.381)
			(thermal_gap 0.381)
		)
		(pad "" np_thru_hole circle
			(at 0 9.815068 90)
			(size 1.1176 1.1176)
			(drill 1.1176)
			(layers "*.Cu" "*.Mask")
			(clearance 0.381)
			(thermal_gap 0.381)
		)
		(pad "A1" smd rect
			(at 2.29997 -7.994904 90)
			(size 0.381 1.27)
			(layers "F.Cu" "F.Mask" "F.Paste")
			(net "GND")
		)
		(pad "A2" smd rect
			(at 2.29997 -7.394956 90)
			(size 0.381 1.27)
			(layers "F.Cu" "F.Mask" "F.Paste")
			(net "GND")
		)
		(pad "A3" smd rect
			(at 2.29997 -6.795008 90)
			(size 0.381 1.27)
			(layers "F.Cu" "F.Mask" "F.Paste")
			(net "GND")
		)
		(pad "A4" smd rect
			(at 2.29997 -6.19506 90)
			(size 0.381 1.27)
			(layers "F.Cu" "F.Mask" "F.Paste")
			(net "GND")
		)
		(pad "A5" smd rect
			(at 2.29997 -5.595112 90)
			(size 0.381 1.27)
			(layers "F.Cu" "F.Mask" "F.Paste")
			(net "GND")
		)
		(pad "A6" smd rect
			(at 2.29997 -4.99491 90)
			(size 0.381 1.27)
			(layers "F.Cu" "F.Mask" "F.Paste")
			(net "GND")
		)
		(pad "A7" smd rect
			(at 2.29997 -4.394962 90)
			(size 0.381 1.27)
			(layers "F.Cu" "F.Mask" "F.Paste")
			(net "SMB_ISO_SSD12_R_SCL")
		)
		(pad "A8" smd rect
			(at 2.29997 -3.795014 90)
			(size 0.381 1.27)
			(layers "F.Cu" "F.Mask" "F.Paste")
			(net "SMB_ISO_SSD12_R_SDA")
		)
		(pad "A9" smd rect
			(at 2.29997 -3.195066 90)
			(size 0.381 1.27)
			(layers "F.Cu" "F.Mask" "F.Paste")
			(net "RST_SMB_SSD12_ISO_R_N")
		)
		(pad "A10" smd rect
			(at 2.29997 -2.595118 90)
			(size 0.381 1.27)
			(layers "F.Cu" "F.Mask" "F.Paste")
			(net "SSD12_LED_ISO_R_N")
		)
		(pad "A11" smd rect
			(at 2.29997 -1.994916 90)
			(size 0.381 1.27)
			(layers "F.Cu" "F.Mask" "F.Paste")
			(net "PU_CLKREQ12")
		)
		(pad "A12" smd rect
			(at 2.29997 -1.394968 90)
			(size 0.381 1.27)
			(layers "F.Cu" "F.Mask" "F.Paste")
			(net "PRSNT_SSD12_N")
		)
		(pad "A13" smd rect
			(at 2.29997 -0.79502 90)
			(size 0.381 1.27)
			(layers "F.Cu" "F.Mask" "F.Paste")
			(net "GND")
		)
		(pad "A14" smd rect
			(at 2.29997 -0.195072 90)
			(size 0.381 1.27)
			(layers "F.Cu" "F.Mask" "F.Paste")
			(net "Net_8477")
		)
		(pad "A15" smd rect
			(at 2.29997 0.404876 90)
			(size 0.381 1.27)
			(layers "F.Cu" "F.Mask" "F.Paste")
			(net "Net_8476")
		)
		(pad "A16" smd rect
			(at 2.29997 1.005078 90)
			(size 0.381 1.27)
			(layers "F.Cu" "F.Mask" "F.Paste")
			(net "GND")
		)
		(pad "A17" smd rect
			(at 2.29997 1.605026 90)
			(size 0.381 1.27)
			(layers "F.Cu" "F.Mask" "F.Paste")
			(net "P5E_PEX3_STN2_RX_DN<44>")
		)
		(pad "A18" smd rect
			(at 2.29997 2.204974 90)
			(size 0.381 1.27)
			(layers "F.Cu" "F.Mask" "F.Paste")
			(net "P5E_PEX3_STN2_RX_DP<44>")
		)
		(pad "A19" smd rect
			(at 2.29997 2.804922 90)
			(size 0.381 1.27)
			(layers "F.Cu" "F.Mask" "F.Paste")
			(net "GND")
		)
		(pad "A20" smd rect
			(at 2.29997 3.405124 90)
			(size 0.381 1.27)
			(layers "F.Cu" "F.Mask" "F.Paste")
			(net "P5E_PEX3_STN2_RX_DN<45>")
		)
		(pad "A21" smd rect
			(at 2.29997 4.005072 90)
			(size 0.381 1.27)
			(layers "F.Cu" "F.Mask" "F.Paste")
			(net "P5E_PEX3_STN2_RX_DP<45>")
		)
		(pad "A22" smd rect
			(at 2.29997 4.60502 90)
			(size 0.381 1.27)
			(layers "F.Cu" "F.Mask" "F.Paste")
			(net "GND")
		)
		(pad "A23" smd rect
			(at 2.29997 5.204968 90)
			(size 0.381 1.27)
			(layers "F.Cu" "F.Mask" "F.Paste")
			(net "P5E_PEX3_STN2_RX_DN<46>")
		)
		(pad "A24" smd rect
			(at 2.29997 5.804916 90)
			(size 0.381 1.27)
			(layers "F.Cu" "F.Mask" "F.Paste")
			(net "P5E_PEX3_STN2_RX_DP<46>")
		)
		(pad "A25" smd rect
			(at 2.29997 6.405118 90)
			(size 0.381 1.27)
			(layers "F.Cu" "F.Mask" "F.Paste")
			(net "GND")
		)
		(pad "A26" smd rect
			(at 2.29997 7.005066 90)
			(size 0.381 1.27)
			(layers "F.Cu" "F.Mask" "F.Paste")
			(net "P5E_PEX3_STN2_RX_DN<47>")
		)
		(pad "A27" smd rect
			(at 2.29997 7.605014 90)
			(size 0.381 1.27)
			(layers "F.Cu" "F.Mask" "F.Paste")
			(net "P5E_PEX3_STN2_RX_DP<47>")
		)
		(pad "A28" smd rect
			(at 2.29997 8.204962 90)
			(size 0.381 1.27)
			(layers "F.Cu" "F.Mask" "F.Paste")
			(net "GND")
		)
		(pad "B1" smd rect
			(at -2.29997 -7.994904 90)
			(size 0.381 1.27)
			(layers "F.Cu" "F.Mask" "F.Paste")
			(net "P12V_SSD12")
		)
		(pad "B2" smd rect
			(at -2.29997 -7.394956 90)
			(size 0.381 1.27)
			(layers "F.Cu" "F.Mask" "F.Paste")
			(net "P12V_SSD12")
		)
		(pad "B3" smd rect
			(at -2.29997 -6.795008 90)
			(size 0.381 1.27)
			(layers "F.Cu" "F.Mask" "F.Paste")
			(net "P12V_SSD12")
		)
		(pad "B4" smd rect
			(at -2.29997 -6.19506 90)
			(size 0.381 1.27)
			(layers "F.Cu" "F.Mask" "F.Paste")
			(net "P12V_SSD12")
		)
		(pad "B5" smd rect
			(at -2.29997 -5.595112 90)
			(size 0.381 1.27)
			(layers "F.Cu" "F.Mask" "F.Paste")
			(net "P12V_SSD12")
		)
		(pad "B6" smd rect
			(at -2.29997 -4.99491 90)
			(size 0.381 1.27)
			(layers "F.Cu" "F.Mask" "F.Paste")
			(net "P12V_SSD12")
		)
		(pad "B7" smd rect
			(at -2.29997 -4.394962 90)
			(size 0.381 1.27)
			(layers "F.Cu" "F.Mask" "F.Paste")
			(net "Net_8478")
		)
		(pad "B8" smd rect
			(at -2.29997 -3.795014 90)
			(size 0.381 1.27)
			(layers "F.Cu" "F.Mask" "F.Paste")
			(net "Net_8475")
		)
		(pad "B9" smd rect
			(at -2.29997 -3.195066 90)
			(size 0.381 1.27)
			(layers "F.Cu" "F.Mask" "F.Paste")
			(net "DUALPORT_N_SSD12")
		)
		(pad "B10" smd rect
			(at -2.29997 -2.595118 90)
			(size 0.381 1.27)
			(layers "F.Cu" "F.Mask" "F.Paste")
			(net "RST_SSD12_PERST_R_N")
		)
		(pad "B11" smd rect
			(at -2.29997 -1.994916 90)
			(size 0.381 1.27)
			(layers "F.Cu" "F.Mask" "F.Paste")
			(net "P3V3_SSD12")
		)
		(pad "B12" smd rect
			(at -2.29997 -1.394968 90)
			(size 0.381 1.27)
			(layers "F.Cu" "F.Mask" "F.Paste")
			(net "SSD12_PWRDIS_R")
		)
		(pad "B13" smd rect
			(at -2.29997 -0.79502 90)
			(size 0.381 1.27)
			(layers "F.Cu" "F.Mask" "F.Paste")
			(net "GND")
		)
		(pad "B14" smd rect
			(at -2.29997 -0.195072 90)
			(size 0.381 1.27)
			(layers "F.Cu" "F.Mask" "F.Paste")
			(net "CLK_100M_DB800ZL_SSD12_R_DN")
		)
		(pad "B15" smd rect
			(at -2.29997 0.404876 90)
			(size 0.381 1.27)
			(layers "F.Cu" "F.Mask" "F.Paste")
			(net "CLK_100M_DB800ZL_SSD12_R_DP")
		)
		(pad "B16" smd rect
			(at -2.29997 1.005078 90)
			(size 0.381 1.27)
			(layers "F.Cu" "F.Mask" "F.Paste")
			(net "GND")
		)
		(pad "B17" smd rect
			(at -2.29997 1.605026 90)
			(size 0.381 1.27)
			(layers "F.Cu" "F.Mask" "F.Paste")
			(net "P5E_PEX3_STN2_TX_C_DN<44>")
		)
		(pad "B18" smd rect
			(at -2.29997 2.204974 90)
			(size 0.381 1.27)
			(layers "F.Cu" "F.Mask" "F.Paste")
			(net "P5E_PEX3_STN2_TX_C_DP<44>")
		)
		(pad "B19" smd rect
			(at -2.29997 2.804922 90)
			(size 0.381 1.27)
			(layers "F.Cu" "F.Mask" "F.Paste")
			(net "GND")
		)
		(pad "B20" smd rect
			(at -2.29997 3.405124 90)
			(size 0.381 1.27)
			(layers "F.Cu" "F.Mask" "F.Paste")
			(net "P5E_PEX3_STN2_TX_C_DN<45>")
		)
		(pad "B21" smd rect
			(at -2.29997 4.005072 90)
			(size 0.381 1.27)
			(layers "F.Cu" "F.Mask" "F.Paste")
			(net "P5E_PEX3_STN2_TX_C_DP<45>")
		)
		(pad "B22" smd rect
			(at -2.29997 4.60502 90)
			(size 0.381 1.27)
			(layers "F.Cu" "F.Mask" "F.Paste")
			(net "GND")
		)
		(pad "B23" smd rect
			(at -2.29997 5.204968 90)
			(size 0.381 1.27)
			(layers "F.Cu" "F.Mask" "F.Paste")
			(net "P5E_PEX3_STN2_TX_C_DN<46>")
		)
		(pad "B24" smd rect
			(at -2.29997 5.804916 90)
			(size 0.381 1.27)
			(layers "F.Cu" "F.Mask" "F.Paste")
			(net "P5E_PEX3_STN2_TX_C_DP<46>")
		)
		(pad "B25" smd rect
			(at -2.29997 6.405118 90)
			(size 0.381 1.27)
			(layers "F.Cu" "F.Mask" "F.Paste")
			(net "GND")
		)
		(pad "B26" smd rect
			(at -2.29997 7.005066 90)
			(size 0.381 1.27)
			(layers "F.Cu" "F.Mask" "F.Paste")
			(net "P5E_PEX3_STN2_TX_C_DN<47>")
		)
		(pad "B27" smd rect
			(at -2.29997 7.605014 90)
			(size 0.381 1.27)
			(layers "F.Cu" "F.Mask" "F.Paste")
			(net "P5E_PEX3_STN2_TX_C_DP<47>")
		)
		(pad "B28" smd rect
			(at -2.29997 8.204962 90)
			(size 0.381 1.27)
			(layers "F.Cu" "F.Mask" "F.Paste")
			(net "GND")
		)
		(pad "G1" thru_hole oval
			(at 0 -11.364976 90)
			(size 1.6256 3.4798)
			(drill oval 1.1176 2.4638)
			(layers "*.Cu" "*.Mask")
			(remove_unused_layers no)
			(net "GND")
			(clearance 0.127)
			(thermal_gap 0.127)
		)
		(pad "G2" thru_hole oval
			(at 0 11.364976 90)
			(size 1.6256 3.4798)
			(drill oval 1.1176 2.4638)
			(layers "*.Cu" "*.Mask")
			(remove_unused_layers no)
			(net "GND")
			(clearance 0.127)
			(thermal_gap 0.127)
		)
		(zone
			(layer "F.Cu")
			(hatch none 0.5)
			(connect_pads
				(clearance 0)
			)
			(min_thickness 0.25)
			(keepout
				(tracks not_allowed)
				(vias allowed)
				(pads allowed)
				(copperpour not_allowed)
				(footprints allowed)
			)
			(placement
				(enabled no)
				(sheetname "")
			)
			(fill
				(thermal_gap 0.5)
				(thermal_bridge_width 0.5)
				(island_removal_mode 0)
			)
			(polygon
				(pts
					(xy 362.644944 -38.850062) (xy 359.894886 -38.850062) (xy 359.894886 -35.900106) (xy 362.644944 -35.900106)
				)
			)
		)
		(zone
			(layer "F.Cu")
			(hatch none 0.5)
			(connect_pads
				(clearance 0)
			)
			(min_thickness 0.25)
			(keepout
				(tracks not_allowed)
				(vias allowed)
				(pads allowed)
				(copperpour not_allowed)
				(footprints allowed)
			)
			(placement
				(enabled no)
				(sheetname "")
			)
			(fill
				(thermal_gap 0.5)
				(thermal_bridge_width 0.5)
				(island_removal_mode 0)
			)
			(polygon
				(pts
					(xy 363.715046 -17.670018) (xy 359.88498 -17.670018) (xy 359.88498 -14.720062) (xy 363.715046 -14.720062)
				)
			)
		)
		(zone
			(layers "F.Cu" "B.Cu" "In1.Cu" "In2.Cu" "In3.Cu" "In4.Cu" "In5.Cu" "In6.Cu"
				"In7.Cu" "In8.Cu" "In9.Cu" "In10.Cu" "In11.Cu" "In12.Cu" "In13.Cu" "In14.Cu"
				"In15.Cu" "In16.Cu"
			)
			(hatch none 0.5)
			(connect_pads
				(clearance 0)
			)
			(min_thickness 0.25)
			(keepout
				(tracks not_allowed)
				(vias allowed)
				(pads allowed)
				(copperpour not_allowed)
				(footprints allowed)
			)
			(placement
				(enabled no)
				(sheetname "")
			)
			(fill
				(thermal_gap 0.5)
				(thermal_bridge_width 0.5)
				(island_removal_mode 0)
			)
			(polygon
				(pts
					(arc
						(start 362.230162 -36.60013)
						(mid 360.299762 -36.60013)
						(end 362.230162 -36.60013)
					)
				)
			)
		)
		(zone
			(layers "F.Cu" "B.Cu" "In1.Cu" "In2.Cu" "In3.Cu" "In4.Cu" "In5.Cu" "In6.Cu"
				"In7.Cu" "In8.Cu" "In9.Cu" "In10.Cu" "In11.Cu" "In12.Cu" "In13.Cu" "In14.Cu"
				"In15.Cu" "In16.Cu"
			)
			(hatch none 0.5)
			(connect_pads
				(clearance 0)
			)
			(min_thickness 0.25)
			(keepout
				(tracks not_allowed)
				(vias allowed)
				(pads allowed)
				(copperpour not_allowed)
				(footprints allowed)
			)
			(placement
				(enabled no)
				(sheetname "")
			)
			(fill
				(thermal_gap 0.5)
				(thermal_bridge_width 0.5)
				(island_removal_mode 0)
			)
			(polygon
				(pts
					(arc
						(start 363.980222 -16.969994)
						(mid 362.049822 -16.969994)
						(end 363.980222 -16.969994)
					)
				)
			)
		)
	)
	(footprint ""
		(layer "F.Cu")
		(at 390.73074 -356.244906 90)
		(property "Reference" "C743"
			(at 0 0 90)
			(layer "F.SilkS")
			(hide yes)
			(effects
				(font
					(size 1.27 1.27)
				)
			)
		)
		(property "Value" ""
			(at 0 0 90)
			(layer "F.Fab")
			(effects
				(font
					(size 1.27 1.27)
				)
			)
		)
		(duplicate_pad_numbers_are_jumpers no)
		(fp_line
			(start 0.299974 -0.150114)
			(end 0.299974 0.150114)
			(stroke
				(width 0.1)
				(type default)
			)
			(layer "F.Fab")
		)
		(fp_line
			(start -0.299974 -0.150114)
			(end 0.299974 -0.150114)
			(stroke
				(width 0.1)
				(type default)
			)
			(layer "F.Fab")
		)
		(fp_line
			(start 0.299974 0.150114)
			(end -0.299974 0.150114)
			(stroke
				(width 0.1)
				(type default)
			)
			(layer "F.Fab")
		)
		(fp_line
			(start -0.299974 0.150114)
			(end -0.299974 -0.150114)
			(stroke
				(width 0.1)
				(type default)
			)
			(layer "F.Fab")
		)
		(pad "1" smd rect
			(at -0.2667 0 90)
			(size 0.3048 0.381)
			(layers "F.Cu" "F.Mask" "F.Paste")
			(net "P5E_PEX3_STN5_TX_DN<89>")
		)
		(pad "2" smd rect
			(at 0.2667 0 90)
			(size 0.3048 0.381)
			(layers "F.Cu" "F.Mask" "F.Paste")
			(net "P5E_PEX3_STN5_TX_C_DN<89>")
		)
	)
	(footprint ""
		(layer "F.Cu")
		(at 367.77168 -25.342342 -90)
		(property "Reference" "R445"
			(at 0 0 270)
			(layer "F.SilkS")
			(hide yes)
			(effects
				(font
					(size 1.27 1.27)
				)
			)
		)
		(property "Value" ""
			(at 0 0 270)
			(layer "F.Fab")
			(effects
				(font
					(size 1.27 1.27)
				)
			)
		)
		(duplicate_pad_numbers_are_jumpers no)
		(fp_line
			(start -0.7874 0.4064)
			(end -0.7874 -0.4064)
			(stroke
				(width 0.1524)
				(type default)
			)
			(layer "F.SilkS")
		)
		(fp_line
			(start 0.7874 0.4064)
			(end -0.7874 0.4064)
			(stroke
				(width 0.1524)
				(type default)
			)
			(layer "F.SilkS")
		)
		(fp_line
			(start -0.7874 -0.4064)
			(end 0.7874 -0.4064)
			(stroke
				(width 0.1524)
				(type default)
			)
			(layer "F.SilkS")
		)
		(fp_line
			(start 0.7874 -0.4064)
			(end 0.7874 0.4064)
			(stroke
				(width 0.1524)
				(type default)
			)
			(layer "F.SilkS")
		)
		(fp_line
			(start -0.67945 0.3048)
			(end -0.67945 -0.305054)
			(stroke
				(width 0.1)
				(type default)
			)
			(layer "F.Fab")
		)
		(fp_line
			(start -0.12065 0.3048)
			(end -0.67945 0.3048)
			(stroke
				(width 0.1)
				(type default)
			)
			(layer "F.Fab")
		)
		(fp_line
			(start 0.120396 0.3048)
			(end 0.120396 0.2794)
			(stroke
				(width 0.1)
				(type default)
			)
			(layer "F.Fab")
		)
		(fp_line
			(start 0.67945 0.3048)
			(end 0.120396 0.3048)
			(stroke
				(width 0.1)
				(type default)
			)
			(layer "F.Fab")
		)
		(fp_line
			(start -0.12065 0.2794)
			(end -0.12065 0.3048)
			(stroke
				(width 0.1)
				(type default)
			)
			(layer "F.Fab")
		)
		(fp_line
			(start 0.120396 0.2794)
			(end -0.12065 0.2794)
			(stroke
				(width 0.1)
				(type default)
			)
			(layer "F.Fab")
		)
		(fp_line
			(start -0.12065 -0.2794)
			(end 0.12065 -0.2794)
			(stroke
				(width 0.1)
				(type default)
			)
			(layer "F.Fab")
		)
		(fp_line
			(start 0.12065 -0.2794)
			(end 0.12065 -0.3048)
			(stroke
				(width 0.1)
				(type default)
			)
			(layer "F.Fab")
		)
		(fp_line
			(start 0.12065 -0.3048)
			(end 0.67945 -0.3048)
			(stroke
				(width 0.1)
				(type default)
			)
			(layer "F.Fab")
		)
		(fp_line
			(start 0.67945 -0.3048)
			(end 0.67945 0.3048)
			(stroke
				(width 0.1)
				(type default)
			)
			(layer "F.Fab")
		)
		(fp_line
			(start -0.67945 -0.305054)
			(end -0.12065 -0.305054)
			(stroke
				(width 0.1)
				(type default)
			)
			(layer "F.Fab")
		)
		(fp_line
			(start -0.12065 -0.305054)
			(end -0.12065 -0.2794)
			(stroke
				(width 0.1)
				(type default)
			)
			(layer "F.Fab")
		)
		(pad "1" smd circle
			(at -0.40005 0 270)
			(size 0 0)
			(layers "F.Cu" "F.Mask" "F.Paste")
			(net "P3V3_SSD12")
		)
		(pad "2" smd circle
			(at 0.40005 0 270)
			(size 0 0)
			(layers "F.Cu" "F.Mask" "F.Paste")
			(net "DUALPORT_N_SSD12")
		)
	)
	(footprint ""
		(layer "F.Cu")
		(at 178.731926 -169.040302 -90)
		(property "Reference" "U22"
			(at -0.17907 -3.529584 0)
			(unlocked yes)
			(layer "F.SilkS")
			(effects
				(font
					(size 0.7874 0.5842)
					(thickness 0.1524)
				)
			)
		)
		(property "Value" ""
			(at 0 0 270)
			(layer "F.Fab")
			(effects
				(font
					(size 1.27 1.27)
				)
			)
		)
		(duplicate_pad_numbers_are_jumpers no)
		(fp_line
			(start -1.905 1.651)
			(end -1.905 -1.651)
			(stroke
				(width 0.1524)
				(type default)
			)
			(layer "F.SilkS")
		)
		(fp_line
			(start 1.905 1.651)
			(end -1.905 1.651)
			(stroke
				(width 0.1524)
				(type default)
			)
			(layer "F.SilkS")
		)
		(fp_line
			(start -1.905 -1.651)
			(end 1.905 -1.651)
			(stroke
				(width 0.1524)
				(type default)
			)
			(layer "F.SilkS")
		)
		(fp_line
			(start 1.905 -1.651)
			(end 1.905 1.651)
			(stroke
				(width 0.1524)
				(type default)
			)
			(layer "F.SilkS")
		)
		(fp_line
			(start -0.649986 1.524)
			(end -0.649986 1.169924)
			(stroke
				(width 0.1)
				(type default)
			)
			(layer "F.Fab")
		)
		(fp_line
			(start 0.6985 1.524)
			(end -0.649986 1.524)
			(stroke
				(width 0.1)
				(type default)
			)
			(layer "F.Fab")
		)
		(fp_line
			(start -1.249934 1.169924)
			(end -1.249934 0.729996)
			(stroke
				(width 0.1)
				(type default)
			)
			(layer "F.Fab")
		)
		(fp_line
			(start -0.649986 1.169924)
			(end -1.249934 1.169924)
			(stroke
				(width 0.1)
				(type default)
			)
			(layer "F.Fab")
		)
		(fp_line
			(start -1.249934 0.729996)
			(end -0.6985 0.729996)
			(stroke
				(width 0.1)
				(type default)
			)
			(layer "F.Fab")
		)
		(fp_line
			(start -0.6985 0.729996)
			(end -0.6985 -0.729996)
			(stroke
				(width 0.1)
				(type default)
			)
			(layer "F.Fab")
		)
		(fp_line
			(start 0.6985 0.219964)
			(end 0.6985 1.524)
			(stroke
				(width 0.1)
				(type default)
			)
			(layer "F.Fab")
		)
		(fp_line
			(start 1.249934 0.219964)
			(end 0.6985 0.219964)
			(stroke
				(width 0.1)
				(type default)
			)
			(layer "F.Fab")
		)
		(fp_line
			(start 0.6985 -0.219964)
			(end 1.249934 -0.219964)
			(stroke
				(width 0.1)
				(type default)
			)
			(layer "F.Fab")
		)
		(fp_line
			(start 1.249934 -0.219964)
			(end 1.249934 0.219964)
			(stroke
				(width 0.1)
				(type default)
			)
			(layer "F.Fab")
		)
		(fp_line
			(start -1.249934 -0.729996)
			(end -1.249934 -1.169924)
			(stroke
				(width 0.1)
				(type default)
			)
			(layer "F.Fab")
		)
		(fp_line
			(start -0.6985 -0.729996)
			(end -1.249934 -0.729996)
			(stroke
				(width 0.1)
				(type default)
			)
			(layer "F.Fab")
		)
		(fp_line
			(start -1.249934 -1.169924)
			(end -0.649986 -1.169924)
			(stroke
				(width 0.1)
				(type default)
			)
			(layer "F.Fab")
		)
		(fp_line
			(start -0.649986 -1.169924)
			(end -0.649986 -1.524)
			(stroke
				(width 0.1)
				(type default)
			)
			(layer "F.Fab")
		)
		(fp_line
			(start -0.649986 -1.524)
			(end 0.6985 -1.524)
			(stroke
				(width 0.1)
				(type default)
			)
			(layer "F.Fab")
		)
		(fp_line
			(start 0.6985 -1.524)
			(end 0.6985 -0.219964)
			(stroke
				(width 0.1)
				(type default)
			)
			(layer "F.Fab")
		)
		(pad "1" smd rect
			(at -1.1176 -1.016 180)
			(size 1.016 1.27)
			(layers "F.Cu" "F.Mask" "F.Paste")
			(net "HP_NIC2_PWRGD")
		)
		(pad "2" smd rect
			(at -1.1176 1.016 180)
			(size 1.016 1.27)
			(layers "F.Cu" "F.Mask" "F.Paste")
			(net "P3V3_NIC2")
		)
		(pad "3" smd rect
			(at 1.1176 0 180)
			(size 1.016 1.27)
			(layers "F.Cu" "F.Mask" "F.Paste")
			(net "GND")
		)
	)
	(footprint ""
		(layer "F.Cu")
		(at 381.254 -210.566)
		(property "Reference" "R4608"
			(at 0 0 0)
			(layer "F.SilkS")
			(hide yes)
			(effects
				(font
					(size 1.27 1.27)
				)
			)
		)
		(property "Value" ""
			(at 0 0 0)
			(layer "F.Fab")
			(effects
				(font
					(size 1.27 1.27)
				)
			)
		)
		(duplicate_pad_numbers_are_jumpers no)
		(fp_line
			(start -0.7874 -0.4064)
			(end 0.7874 -0.4064)
			(stroke
				(width 0.1524)
				(type default)
			)
			(layer "F.SilkS")
		)
		(fp_line
			(start -0.7874 0.4064)
			(end -0.7874 -0.4064)
			(stroke
				(width 0.1524)
				(type default)
			)
			(layer "F.SilkS")
		)
		(fp_line
			(start 0.7874 -0.4064)
			(end 0.7874 0.4064)
			(stroke
				(width 0.1524)
				(type default)
			)
			(layer "F.SilkS")
		)
		(fp_line
			(start 0.7874 0.4064)
			(end -0.7874 0.4064)
			(stroke
				(width 0.1524)
				(type default)
			)
			(layer "F.SilkS")
		)
		(fp_line
			(start -0.67945 -0.305054)
			(end -0.12065 -0.305054)
			(stroke
				(width 0.1)
				(type default)
			)
			(layer "F.Fab")
		)
		(fp_line
			(start -0.67945 0.3048)
			(end -0.67945 -0.305054)
			(stroke
				(width 0.1)
				(type default)
			)
			(layer "F.Fab")
		)
		(fp_line
			(start -0.12065 -0.305054)
			(end -0.12065 -0.2794)
			(stroke
				(width 0.1)
				(type default)
			)
			(layer "F.Fab")
		)
		(fp_line
			(start -0.12065 -0.2794)
			(end 0.12065 -0.2794)
			(stroke
				(width 0.1)
				(type default)
			)
			(layer "F.Fab")
		)
		(fp_line
			(start -0.12065 0.2794)
			(end -0.12065 0.3048)
			(stroke
				(width 0.1)
				(type default)
			)
			(layer "F.Fab")
		)
		(fp_line
			(start -0.12065 0.3048)
			(end -0.67945 0.3048)
			(stroke
				(width 0.1)
				(type default)
			)
			(layer "F.Fab")
		)
		(fp_line
			(start 0.120396 0.2794)
			(end -0.12065 0.2794)
			(stroke
				(width 0.1)
				(type default)
			)
			(layer "F.Fab")
		)
		(fp_line
			(start 0.120396 0.3048)
			(end 0.120396 0.2794)
			(stroke
				(width 0.1)
				(type default)
			)
			(layer "F.Fab")
		)
		(fp_line
			(start 0.12065 -0.3048)
			(end 0.67945 -0.3048)
			(stroke
				(width 0.1)
				(type default)
			)
			(layer "F.Fab")
		)
		(fp_line
			(start 0.12065 -0.2794)
			(end 0.12065 -0.3048)
			(stroke
				(width 0.1)
				(type default)
			)
			(layer "F.Fab")
		)
		(fp_line
			(start 0.67945 -0.3048)
			(end 0.67945 0.3048)
			(stroke
				(width 0.1)
				(type default)
			)
			(layer "F.Fab")
		)
		(fp_line
			(start 0.67945 0.3048)
			(end 0.120396 0.3048)
			(stroke
				(width 0.1)
				(type default)
			)
			(layer "F.Fab")
		)
		(pad "1" smd circle
			(at -0.40005 0)
			(size 0 0)
			(layers "F.Cu" "F.Mask" "F.Paste")
			(net "P3V3_AUX")
		)
		(pad "2" smd circle
			(at 0.40005 0)
			(size 0 0)
			(layers "F.Cu" "F.Mask" "F.Paste")
			(net "RST_PEX_NIC0_PERST_R_N")
		)
	)
	(footprint ""
		(layer "F.Cu")
		(at 262.564626 -240.851944 90)
		(property "Reference" "R6580"
			(at 0 0 90)
			(layer "F.SilkS")
			(hide yes)
			(effects
				(font
					(size 1.27 1.27)
				)
			)
		)
		(property "Value" ""
			(at 0 0 90)
			(layer "F.Fab")
			(effects
				(font
					(size 1.27 1.27)
				)
			)
		)
		(duplicate_pad_numbers_are_jumpers no)
		(fp_line
			(start 0.7874 -0.4064)
			(end 0.7874 0.4064)
			(stroke
				(width 0.1524)
				(type default)
			)
			(layer "F.SilkS")
		)
		(fp_line
			(start -0.7874 -0.4064)
			(end 0.7874 -0.4064)
			(stroke
				(width 0.1524)
				(type default)
			)
			(layer "F.SilkS")
		)
		(fp_line
			(start 0.7874 0.4064)
			(end -0.7874 0.4064)
			(stroke
				(width 0.1524)
				(type default)
			)
			(layer "F.SilkS")
		)
		(fp_line
			(start -0.7874 0.4064)
			(end -0.7874 -0.4064)
			(stroke
				(width 0.1524)
				(type default)
			)
			(layer "F.SilkS")
		)
		(fp_line
			(start -0.12065 -0.305054)
			(end -0.12065 -0.2794)
			(stroke
				(width 0.1)
				(type default)
			)
			(layer "F.Fab")
		)
		(fp_line
			(start -0.67945 -0.305054)
			(end -0.12065 -0.305054)
			(stroke
				(width 0.1)
				(type default)
			)
			(layer "F.Fab")
		)
		(fp_line
			(start 0.67945 -0.3048)
			(end 0.67945 0.3048)
			(stroke
				(width 0.1)
				(type default)
			)
			(layer "F.Fab")
		)
		(fp_line
			(start 0.12065 -0.3048)
			(end 0.67945 -0.3048)
			(stroke
				(width 0.1)
				(type default)
			)
			(layer "F.Fab")
		)
		(fp_line
			(start 0.12065 -0.2794)
			(end 0.12065 -0.3048)
			(stroke
				(width 0.1)
				(type default)
			)
			(layer "F.Fab")
		)
		(fp_line
			(start -0.12065 -0.2794)
			(end 0.12065 -0.2794)
			(stroke
				(width 0.1)
				(type default)
			)
			(layer "F.Fab")
		)
		(fp_line
			(start 0.120396 0.2794)
			(end -0.12065 0.2794)
			(stroke
				(width 0.1)
				(type default)
			)
			(layer "F.Fab")
		)
		(fp_line
			(start -0.12065 0.2794)
			(end -0.12065 0.3048)
			(stroke
				(width 0.1)
				(type default)
			)
			(layer "F.Fab")
		)
		(fp_line
			(start 0.67945 0.3048)
			(end 0.120396 0.3048)
			(stroke
				(width 0.1)
				(type default)
			)
			(layer "F.Fab")
		)
		(fp_line
			(start 0.120396 0.3048)
			(end 0.120396 0.2794)
			(stroke
				(width 0.1)
				(type default)
			)
			(layer "F.Fab")
		)
		(fp_line
			(start -0.12065 0.3048)
			(end -0.67945 0.3048)
			(stroke
				(width 0.1)
				(type default)
			)
			(layer "F.Fab")
		)
		(fp_line
			(start -0.67945 0.3048)
			(end -0.67945 -0.305054)
			(stroke
				(width 0.1)
				(type default)
			)
			(layer "F.Fab")
		)
		(pad "1" smd circle
			(at -0.40005 0 90)
			(size 0 0)
			(layers "F.Cu" "F.Mask" "F.Paste")
			(net "P1V8_PLL_PEX2_ADJ")
		)
		(pad "2" smd circle
			(at 0.40005 0 90)
			(size 0 0)
			(layers "F.Cu" "F.Mask" "F.Paste")
			(net "GND")
		)
	)
	(footprint ""
		(layer "F.Cu")
		(at 327.533 -208.153 180)
		(property "Reference" "R5911"
			(at 0 0 180)
			(layer "F.SilkS")
			(hide yes)
			(effects
				(font
					(size 1.27 1.27)
				)
			)
		)
		(property "Value" ""
			(at 0 0 180)
			(layer "F.Fab")
			(effects
				(font
					(size 1.27 1.27)
				)
			)
		)
		(duplicate_pad_numbers_are_jumpers no)
		(fp_line
			(start 0.7874 0.4064)
			(end -0.7874 0.4064)
			(stroke
				(width 0.1524)
				(type default)
			)
			(layer "F.SilkS")
		)
		(fp_line
			(start 0.7874 -0.4064)
			(end 0.7874 0.4064)
			(stroke
				(width 0.1524)
				(type default)
			)
			(layer "F.SilkS")
		)
		(fp_line
			(start -0.7874 0.4064)
			(end -0.7874 -0.4064)
			(stroke
				(width 0.1524)
				(type default)
			)
			(layer "F.SilkS")
		)
		(fp_line
			(start -0.7874 -0.4064)
			(end 0.7874 -0.4064)
			(stroke
				(width 0.1524)
				(type default)
			)
			(layer "F.SilkS")
		)
		(fp_line
			(start 0.67945 0.3048)
			(end 0.120396 0.3048)
			(stroke
				(width 0.1)
				(type default)
			)
			(layer "F.Fab")
		)
		(fp_line
			(start 0.67945 -0.3048)
			(end 0.67945 0.3048)
			(stroke
				(width 0.1)
				(type default)
			)
			(layer "F.Fab")
		)
		(fp_line
			(start 0.12065 -0.2794)
			(end 0.12065 -0.3048)
			(stroke
				(width 0.1)
				(type default)
			)
			(layer "F.Fab")
		)
		(fp_line
			(start 0.12065 -0.3048)
			(end 0.67945 -0.3048)
			(stroke
				(width 0.1)
				(type default)
			)
			(layer "F.Fab")
		)
		(fp_line
			(start 0.120396 0.3048)
			(end 0.120396 0.2794)
			(stroke
				(width 0.1)
				(type default)
			)
			(layer "F.Fab")
		)
		(fp_line
			(start 0.120396 0.2794)
			(end -0.12065 0.2794)
			(stroke
				(width 0.1)
				(type default)
			)
			(layer "F.Fab")
		)
		(fp_line
			(start -0.12065 0.3048)
			(end -0.67945 0.3048)
			(stroke
				(width 0.1)
				(type default)
			)
			(layer "F.Fab")
		)
		(fp_line
			(start -0.12065 0.2794)
			(end -0.12065 0.3048)
			(stroke
				(width 0.1)
				(type default)
			)
			(layer "F.Fab")
		)
		(fp_line
			(start -0.12065 -0.2794)
			(end 0.12065 -0.2794)
			(stroke
				(width 0.1)
				(type default)
			)
			(layer "F.Fab")
		)
		(fp_line
			(start -0.12065 -0.305054)
			(end -0.12065 -0.2794)
			(stroke
				(width 0.1)
				(type default)
			)
			(layer "F.Fab")
		)
		(fp_line
			(start -0.67945 0.3048)
			(end -0.67945 -0.305054)
			(stroke
				(width 0.1)
				(type default)
			)
			(layer "F.Fab")
		)
		(fp_line
			(start -0.67945 -0.305054)
			(end -0.12065 -0.305054)
			(stroke
				(width 0.1)
				(type default)
			)
			(layer "F.Fab")
		)
		(pad "1" smd circle
			(at -0.40005 0 180)
			(size 0 0)
			(layers "F.Cu" "F.Mask" "F.Paste")
			(net "HSC_TIMER_R_N")
		)
		(pad "2" smd circle
			(at 0.40005 0 180)
			(size 0 0)
			(layers "F.Cu" "F.Mask" "F.Paste")
			(net "P3V3_AUX")
		)
	)
	(footprint ""
		(layer "F.Cu")
		(at 126.221236 -176.023524)
		(property "Reference" "R1088"
			(at 0 0 0)
			(layer "F.SilkS")
			(hide yes)
			(effects
				(font
					(size 1.27 1.27)
				)
			)
		)
		(property "Value" ""
			(at 0 0 0)
			(layer "F.Fab")
			(effects
				(font
					(size 1.27 1.27)
				)
			)
		)
		(duplicate_pad_numbers_are_jumpers no)
		(fp_line
			(start 0.7874 0.4064)
			(end -0.7874 0.4064)
			(stroke
				(width 0.1524)
				(type default)
			)
			(layer "F.SilkS")
		)
		(fp_line
			(start -0.67945 -0.305054)
			(end -0.12065 -0.305054)
			(stroke
				(width 0.1)
				(type default)
			)
			(layer "F.Fab")
		)
		(fp_line
			(start -0.67945 0.3048)
			(end -0.67945 -0.305054)
			(stroke
				(width 0.1)
				(type default)
			)
			(layer "F.Fab")
		)
		(fp_line
			(start -0.12065 -0.305054)
			(end -0.12065 -0.2794)
			(stroke
				(width 0.1)
				(type default)
			)
			(layer "F.Fab")
		)
		(fp_line
			(start -0.12065 -0.2794)
			(end 0.12065 -0.2794)
			(stroke
				(width 0.1)
				(type default)
			)
			(layer "F.Fab")
		)
		(fp_line
			(start -0.12065 0.2794)
			(end -0.12065 0.3048)
			(stroke
				(width 0.1)
				(type default)
			)
			(layer "F.Fab")
		)
		(fp_line
			(start -0.12065 0.3048)
			(end -0.67945 0.3048)
			(stroke
				(width 0.1)
				(type default)
			)
			(layer "F.Fab")
		)
		(fp_line
			(start 0.120396 0.2794)
			(end -0.12065 0.2794)
			(stroke
				(width 0.1)
				(type default)
			)
			(layer "F.Fab")
		)
		(fp_line
			(start 0.120396 0.3048)
			(end 0.120396 0.2794)
			(stroke
				(width 0.1)
				(type default)
			)
			(layer "F.Fab")
		)
		(fp_line
			(start 0.12065 -0.3048)
			(end 0.67945 -0.3048)
			(stroke
				(width 0.1)
				(type default)
			)
			(layer "F.Fab")
		)
		(fp_line
			(start 0.12065 -0.2794)
			(end 0.12065 -0.3048)
			(stroke
				(width 0.1)
				(type default)
			)
			(layer "F.Fab")
		)
		(fp_line
			(start 0.67945 -0.3048)
			(end 0.67945 0.3048)
			(stroke
				(width 0.1)
				(type default)
			)
			(layer "F.Fab")
		)
		(fp_line
			(start 0.67945 0.3048)
			(end 0.120396 0.3048)
			(stroke
				(width 0.1)
				(type default)
			)
			(layer "F.Fab")
		)
		(pad "1" smd circle
			(at -0.40005 0)
			(size 0 0)
			(layers "F.Cu" "F.Mask" "F.Paste")
			(net "CLK_100M_DB2000QL_PEX0_S1_R_DN")
		)
		(pad "2" smd circle
			(at 0.40005 0)
			(size 0 0)
			(layers "F.Cu" "F.Mask" "F.Paste")
			(net "CLK_100M_DB2000QL_PEX0_S1_DN")
		)
	)
	(footprint ""
		(layer "F.Cu")
		(at 128.201166 -118.343426 -90)
		(property "Reference" "R5962"
			(at 0 0 270)
			(layer "F.SilkS")
			(hide yes)
			(effects
				(font
					(size 1.27 1.27)
				)
			)
		)
		(property "Value" ""
			(at 0 0 270)
			(layer "F.Fab")
			(effects
				(font
					(size 1.27 1.27)
				)
			)
		)
		(duplicate_pad_numbers_are_jumpers no)
		(fp_line
			(start -0.7874 0.4064)
			(end -0.7874 -0.4064)
			(stroke
				(width 0.1524)
				(type default)
			)
			(layer "F.SilkS")
		)
		(fp_line
			(start 0.7874 0.4064)
			(end -0.7874 0.4064)
			(stroke
				(width 0.1524)
				(type default)
			)
			(layer "F.SilkS")
		)
		(fp_line
			(start -0.7874 -0.4064)
			(end 0.7874 -0.4064)
			(stroke
				(width 0.1524)
				(type default)
			)
			(layer "F.SilkS")
		)
		(fp_line
			(start 0.7874 -0.4064)
			(end 0.7874 0.4064)
			(stroke
				(width 0.1524)
				(type default)
			)
			(layer "F.SilkS")
		)
		(fp_line
			(start -0.67945 0.3048)
			(end -0.67945 -0.305054)
			(stroke
				(width 0.1)
				(type default)
			)
			(layer "F.Fab")
		)
		(fp_line
			(start -0.12065 0.3048)
			(end -0.67945 0.3048)
			(stroke
				(width 0.1)
				(type default)
			)
			(layer "F.Fab")
		)
		(fp_line
			(start 0.120396 0.3048)
			(end 0.120396 0.2794)
			(stroke
				(width 0.1)
				(type default)
			)
			(layer "F.Fab")
		)
		(fp_line
			(start 0.67945 0.3048)
			(end 0.120396 0.3048)
			(stroke
				(width 0.1)
				(type default)
			)
			(layer "F.Fab")
		)
		(fp_line
			(start -0.12065 0.2794)
			(end -0.12065 0.3048)
			(stroke
				(width 0.1)
				(type default)
			)
			(layer "F.Fab")
		)
		(fp_line
			(start 0.120396 0.2794)
			(end -0.12065 0.2794)
			(stroke
				(width 0.1)
				(type default)
			)
			(layer "F.Fab")
		)
		(fp_line
			(start -0.12065 -0.2794)
			(end 0.12065 -0.2794)
			(stroke
				(width 0.1)
				(type default)
			)
			(layer "F.Fab")
		)
		(fp_line
			(start 0.12065 -0.2794)
			(end 0.12065 -0.3048)
			(stroke
				(width 0.1)
				(type default)
			)
			(layer "F.Fab")
		)
		(fp_line
			(start 0.12065 -0.3048)
			(end 0.67945 -0.3048)
			(stroke
				(width 0.1)
				(type default)
			)
			(layer "F.Fab")
		)
		(fp_line
			(start 0.67945 -0.3048)
			(end 0.67945 0.3048)
			(stroke
				(width 0.1)
				(type default)
			)
			(layer "F.Fab")
		)
		(fp_line
			(start -0.67945 -0.305054)
			(end -0.12065 -0.305054)
			(stroke
				(width 0.1)
				(type default)
			)
			(layer "F.Fab")
		)
		(fp_line
			(start -0.12065 -0.305054)
			(end -0.12065 -0.2794)
			(stroke
				(width 0.1)
				(type default)
			)
			(layer "F.Fab")
		)
		(pad "1" smd circle
			(at -0.40005 0 270)
			(size 0 0)
			(layers "F.Cu" "F.Mask" "F.Paste")
			(net "P3V3_NIC2")
		)
		(pad "2" smd circle
			(at 0.40005 0 270)
			(size 0 0)
			(layers "F.Cu" "F.Mask" "F.Paste")
			(net "P3V3_NIC2_PG_G1")
		)
	)
	(footprint ""
		(layer "F.Cu")
		(at 115.720114 -260.290564)
		(property "Reference" "PR80"
			(at 0 0 0)
			(layer "F.SilkS")
			(hide yes)
			(effects
				(font
					(size 1.27 1.27)
				)
			)
		)
		(property "Value" ""
			(at 0 0 0)
			(layer "F.Fab")
			(effects
				(font
					(size 1.27 1.27)
				)
			)
		)
		(duplicate_pad_numbers_are_jumpers no)
		(fp_line
			(start -0.7874 -0.4064)
			(end 0.7874 -0.4064)
			(stroke
				(width 0.1524)
				(type default)
			)
			(layer "F.SilkS")
		)
		(fp_line
			(start -0.7874 0.4064)
			(end -0.7874 -0.4064)
			(stroke
				(width 0.1524)
				(type default)
			)
			(layer "F.SilkS")
		)
		(fp_line
			(start 0.7874 -0.4064)
			(end 0.7874 0.4064)
			(stroke
				(width 0.1524)
				(type default)
			)
			(layer "F.SilkS")
		)
		(fp_line
			(start 0.7874 0.4064)
			(end -0.7874 0.4064)
			(stroke
				(width 0.1524)
				(type default)
			)
			(layer "F.SilkS")
		)
		(fp_line
			(start -0.67945 -0.305054)
			(end -0.12065 -0.305054)
			(stroke
				(width 0.1)
				(type default)
			)
			(layer "F.Fab")
		)
		(fp_line
			(start -0.67945 0.3048)
			(end -0.67945 -0.305054)
			(stroke
				(width 0.1)
				(type default)
			)
			(layer "F.Fab")
		)
		(fp_line
			(start -0.12065 -0.305054)
			(end -0.12065 -0.2794)
			(stroke
				(width 0.1)
				(type default)
			)
			(layer "F.Fab")
		)
		(fp_line
			(start -0.12065 -0.2794)
			(end 0.12065 -0.2794)
			(stroke
				(width 0.1)
				(type default)
			)
			(layer "F.Fab")
		)
		(fp_line
			(start -0.12065 0.2794)
			(end -0.12065 0.3048)
			(stroke
				(width 0.1)
				(type default)
			)
			(layer "F.Fab")
		)
		(fp_line
			(start -0.12065 0.3048)
			(end -0.67945 0.3048)
			(stroke
				(width 0.1)
				(type default)
			)
			(layer "F.Fab")
		)
		(fp_line
			(start 0.120396 0.2794)
			(end -0.12065 0.2794)
			(stroke
				(width 0.1)
				(type default)
			)
			(layer "F.Fab")
		)
		(fp_line
			(start 0.120396 0.3048)
			(end 0.120396 0.2794)
			(stroke
				(width 0.1)
				(type default)
			)
			(layer "F.Fab")
		)
		(fp_line
			(start 0.12065 -0.3048)
			(end 0.67945 -0.3048)
			(stroke
				(width 0.1)
				(type default)
			)
			(layer "F.Fab")
		)
		(fp_line
			(start 0.12065 -0.2794)
			(end 0.12065 -0.3048)
			(stroke
				(width 0.1)
				(type default)
			)
			(layer "F.Fab")
		)
		(fp_line
			(start 0.67945 -0.3048)
			(end 0.67945 0.3048)
			(stroke
				(width 0.1)
				(type default)
			)
			(layer "F.Fab")
		)
		(fp_line
			(start 0.67945 0.3048)
			(end 0.120396 0.3048)
			(stroke
				(width 0.1)
				(type default)
			)
			(layer "F.Fab")
		)
		(pad "1" smd circle
			(at -0.40005 0)
			(size 0 0)
			(layers "F.Cu" "F.Mask" "F.Paste")
			(net "SH_P0V8_PEX1_VSEN1_R")
		)
		(pad "2" smd circle
			(at 0.40005 0)
			(size 0 0)
			(layers "F.Cu" "F.Mask" "F.Paste")
			(net "P0V8_PEX1_VSEN1")
		)
	)
	(footprint ""
		(layer "F.Cu")
		(at 210.439 -197.231 180)
		(property "Reference" "R1526"
			(at 0 0 180)
			(layer "F.SilkS")
			(hide yes)
			(effects
				(font
					(size 1.27 1.27)
				)
			)
		)
		(property "Value" ""
			(at 0 0 180)
			(layer "F.Fab")
			(effects
				(font
					(size 1.27 1.27)
				)
			)
		)
		(duplicate_pad_numbers_are_jumpers no)
		(fp_line
			(start 0.7874 0.4064)
			(end -0.7874 0.4064)
			(stroke
				(width 0.1524)
				(type default)
			)
			(layer "F.SilkS")
		)
		(fp_line
			(start 0.7874 -0.4064)
			(end 0.7874 0.4064)
			(stroke
				(width 0.1524)
				(type default)
			)
			(layer "F.SilkS")
		)
		(fp_line
			(start -0.7874 0.4064)
			(end -0.7874 -0.4064)
			(stroke
				(width 0.1524)
				(type default)
			)
			(layer "F.SilkS")
		)
		(fp_line
			(start -0.7874 -0.4064)
			(end 0.7874 -0.4064)
			(stroke
				(width 0.1524)
				(type default)
			)
			(layer "F.SilkS")
		)
		(fp_line
			(start 0.67945 0.3048)
			(end 0.120396 0.3048)
			(stroke
				(width 0.1)
				(type default)
			)
			(layer "F.Fab")
		)
		(fp_line
			(start 0.67945 -0.3048)
			(end 0.67945 0.3048)
			(stroke
				(width 0.1)
				(type default)
			)
			(layer "F.Fab")
		)
		(fp_line
			(start 0.12065 -0.2794)
			(end 0.12065 -0.3048)
			(stroke
				(width 0.1)
				(type default)
			)
			(layer "F.Fab")
		)
		(fp_line
			(start 0.12065 -0.3048)
			(end 0.67945 -0.3048)
			(stroke
				(width 0.1)
				(type default)
			)
			(layer "F.Fab")
		)
		(fp_line
			(start 0.120396 0.3048)
			(end 0.120396 0.2794)
			(stroke
				(width 0.1)
				(type default)
			)
			(layer "F.Fab")
		)
		(fp_line
			(start 0.120396 0.2794)
			(end -0.12065 0.2794)
			(stroke
				(width 0.1)
				(type default)
			)
			(layer "F.Fab")
		)
		(fp_line
			(start -0.12065 0.3048)
			(end -0.67945 0.3048)
			(stroke
				(width 0.1)
				(type default)
			)
			(layer "F.Fab")
		)
		(fp_line
			(start -0.12065 0.2794)
			(end -0.12065 0.3048)
			(stroke
				(width 0.1)
				(type default)
			)
			(layer "F.Fab")
		)
		(fp_line
			(start -0.12065 -0.2794)
			(end 0.12065 -0.2794)
			(stroke
				(width 0.1)
				(type default)
			)
			(layer "F.Fab")
		)
		(fp_line
			(start -0.12065 -0.305054)
			(end -0.12065 -0.2794)
			(stroke
				(width 0.1)
				(type default)
			)
			(layer "F.Fab")
		)
		(fp_line
			(start -0.67945 0.3048)
			(end -0.67945 -0.305054)
			(stroke
				(width 0.1)
				(type default)
			)
			(layer "F.Fab")
		)
		(fp_line
			(start -0.67945 -0.305054)
			(end -0.12065 -0.305054)
			(stroke
				(width 0.1)
				(type default)
			)
			(layer "F.Fab")
		)
		(pad "1" smd circle
			(at -0.40005 0 180)
			(size 0 0)
			(layers "F.Cu" "F.Mask" "F.Paste")
			(net "SMB_NIC6_R_SCL")
		)
		(pad "2" smd circle
			(at 0.40005 0 180)
			(size 0 0)
			(layers "F.Cu" "F.Mask" "F.Paste")
			(net "P1V2_AUX")
		)
	)
	(footprint ""
		(layer "F.Cu")
		(at 230.724964 -64.200024 180)
		(property "Reference" "J2"
			(at -5.4356 -8.346948 180)
			(unlocked yes)
			(layer "F.SilkS")
			(effects
				(font
					(size 0.7874 0.5842)
					(thickness 0.1524)
				)
				(justify left)
			)
		)
		(property "Value" ""
			(at 0 0 180)
			(layer "F.Fab")
			(effects
				(font
					(size 1.27 1.27)
				)
			)
		)
		(duplicate_pad_numbers_are_jumpers no)
		(fp_line
			(start 4.872482 7.649972)
			(end 4.872482 -7.649972)
			(stroke
				(width 0.1524)
				(type default)
			)
			(layer "F.SilkS")
		)
		(fp_line
			(start 4.872482 -7.649972)
			(end -5.377434 -7.649972)
			(stroke
				(width 0.1524)
				(type default)
			)
			(layer "F.SilkS")
		)
		(fp_line
			(start 3.927602 6.83006)
			(end 3.4544 6.83006)
			(stroke
				(width 0.1524)
				(type default)
			)
			(layer "F.SilkS")
		)
		(fp_line
			(start 3.927602 6.5024)
			(end 3.927602 6.83006)
			(stroke
				(width 0.1524)
				(type default)
			)
			(layer "F.SilkS")
		)
		(fp_line
			(start 3.927602 -5.6896)
			(end 3.927602 5.715)
			(stroke
				(width 0.1524)
				(type default)
			)
			(layer "F.SilkS")
		)
		(fp_line
			(start 3.927602 -6.83006)
			(end 3.927602 -6.5024)
			(stroke
				(width 0.1524)
				(type default)
			)
			(layer "F.SilkS")
		)
		(fp_line
			(start 3.4544 -6.83006)
			(end 3.927602 -6.83006)
			(stroke
				(width 0.1524)
				(type default)
			)
			(layer "F.SilkS")
		)
		(fp_line
			(start 3.1877 6.83006)
			(end -3.0988 6.83006)
			(stroke
				(width 0.1524)
				(type default)
			)
			(layer "F.SilkS")
		)
		(fp_line
			(start -3.0988 -6.83006)
			(end 3.1496 -6.83006)
			(stroke
				(width 0.1524)
				(type default)
			)
			(layer "F.SilkS")
		)
		(fp_line
			(start -3.927602 5.8674)
			(end -3.927602 -5.8674)
			(stroke
				(width 0.1524)
				(type default)
			)
			(layer "F.SilkS")
		)
		(fp_line
			(start -5.377434 7.649972)
			(end 4.872482 7.649972)
			(stroke
				(width 0.1524)
				(type default)
			)
			(layer "F.SilkS")
		)
		(fp_line
			(start -5.377434 -7.649972)
			(end -5.377434 7.649972)
			(stroke
				(width 0.1524)
				(type default)
			)
			(layer "F.SilkS")
		)
		(fp_poly
			(pts
				(xy -6.475476 -5.90804) (xy -6.475476 -4.89204) (xy -5.459476 -5.40004)
			)
			(stroke
				(width 0)
				(type default)
			)
			(fill yes)
			(layer "F.SilkS")
		)
		(fp_line
			(start 3.927602 6.83006)
			(end -3.927602 6.83006)
			(stroke
				(width 0.1)
				(type default)
			)
			(layer "F.Fab")
		)
		(fp_line
			(start 3.927602 -6.83006)
			(end 3.927602 6.83006)
			(stroke
				(width 0.1)
				(type default)
			)
			(layer "F.Fab")
		)
		(fp_line
			(start -3.927602 6.83006)
			(end -3.927602 -6.83006)
			(stroke
				(width 0.1)
				(type default)
			)
			(layer "F.Fab")
		)
		(fp_line
			(start -3.927602 -6.83006)
			(end 3.927602 -6.83006)
			(stroke
				(width 0.1)
				(type default)
			)
			(layer "F.Fab")
		)
		(fp_poly
			(pts
				(xy -6.475476 -5.90804) (xy -6.475476 -4.89204) (xy -5.459476 -5.40004)
			)
			(stroke
				(width 0)
				(type default)
			)
			(fill yes)
			(layer "F.Fab")
		)
		(pad "" np_thru_hole circle
			(at -0.252476 -5.5499 90)
			(size 1.3208 1.3208)
			(drill 1.3208)
			(layers "*.Cu" "*.Mask")
			(clearance 0.381)
			(thermal_gap 0.381)
		)
		(pad "" np_thru_hole circle
			(at -0.252476 5.5499 90)
			(size 1.3208 1.3208)
			(drill 1.3208)
			(layers "*.Cu" "*.Mask")
			(clearance 0.381)
			(thermal_gap 0.381)
		)
		(pad "A1" smd rect
			(at -1.792478 -5.40004 90)
			(size 0.381 1.3462)
			(layers "F.Cu" "F.Mask" "F.Paste")
			(net "GND")
		)
		(pad "A2" smd rect
			(at -1.792478 -4.800092 90)
			(size 0.381 1.3462)
			(layers "F.Cu" "F.Mask" "F.Paste")
			(net "GND")
		)
		(pad "A3" smd rect
			(at -1.792478 -4.19989 90)
			(size 0.381 1.3462)
			(layers "F.Cu" "F.Mask" "F.Paste")
			(net "GND")
		)
		(pad "A4" smd rect
			(at -1.792478 -3.599942 90)
			(size 0.381 1.3462)
			(layers "F.Cu" "F.Mask" "F.Paste")
			(net "GND")
		)
		(pad "A5" smd rect
			(at -1.792478 -2.999994 90)
			(size 0.381 1.3462)
			(layers "F.Cu" "F.Mask" "F.Paste")
			(net "P5V_AUX")
		)
		(pad "A6" smd rect
			(at -1.792478 -2.400046 90)
			(size 0.381 1.3462)
			(layers "F.Cu" "F.Mask" "F.Paste")
			(net "P5V_AUX")
		)
		(pad "A7" smd rect
			(at -1.792478 -1.800098 90)
			(size 0.381 1.3462)
			(layers "F.Cu" "F.Mask" "F.Paste")
			(net "GND")
		)
		(pad "A8" smd rect
			(at -1.792478 -1.199896 90)
			(size 0.381 1.3462)
			(layers "F.Cu" "F.Mask" "F.Paste")
			(net "P5V_AUX")
		)
		(pad "A9" smd rect
			(at -1.792478 -0.599948 90)
			(size 0.381 1.3462)
			(layers "F.Cu" "F.Mask" "F.Paste")
			(net "P5V_AUX")
		)
		(pad "A10" smd rect
			(at -1.792478 0 90)
			(size 0.381 1.3462)
			(layers "F.Cu" "F.Mask" "F.Paste")
			(net "GND")
		)
		(pad "A11" smd rect
			(at -1.792478 0.599948 90)
			(size 0.381 1.3462)
			(layers "F.Cu" "F.Mask" "F.Paste")
			(net "GND")
		)
		(pad "A12" smd rect
			(at -1.792478 1.199896 90)
			(size 0.381 1.3462)
			(layers "F.Cu" "F.Mask" "F.Paste")
			(net "GND")
		)
		(pad "A13" smd rect
			(at -1.792478 1.800098 90)
			(size 0.381 1.3462)
			(layers "F.Cu" "F.Mask" "F.Paste")
			(net "GND")
		)
		(pad "A14" smd rect
			(at -1.792478 2.400046 90)
			(size 0.381 1.3462)
			(layers "F.Cu" "F.Mask" "F.Paste")
			(net "P5V_AUX")
		)
		(pad "A15" smd rect
			(at -1.792478 2.999994 90)
			(size 0.381 1.3462)
			(layers "F.Cu" "F.Mask" "F.Paste")
			(net "P5V_AUX")
		)
		(pad "A16" smd rect
			(at -1.792478 3.599942 90)
			(size 0.381 1.3462)
			(layers "F.Cu" "F.Mask" "F.Paste")
			(net "GND")
		)
		(pad "A17" smd rect
			(at -1.792478 4.19989 90)
			(size 0.381 1.3462)
			(layers "F.Cu" "F.Mask" "F.Paste")
			(net "P5V_AUX")
		)
		(pad "A18" smd rect
			(at -1.792478 4.800092 90)
			(size 0.381 1.3462)
			(layers "F.Cu" "F.Mask" "F.Paste")
			(net "P5V_AUX")
		)
		(pad "A19" smd rect
			(at -1.792478 5.40004 90)
			(size 0.381 1.3462)
			(layers "F.Cu" "F.Mask" "F.Paste")
			(net "GND")
		)
		(pad "B1" smd rect
			(at 1.287526 -5.40004 90)
			(size 0.381 1.3462)
			(layers "F.Cu" "F.Mask" "F.Paste")
			(net "GND")
		)
		(pad "B2" smd rect
			(at 1.287526 -4.800092 90)
			(size 0.381 1.3462)
			(layers "F.Cu" "F.Mask" "F.Paste")
			(net "USB2_FIO_DP")
		)
		(pad "B3" smd rect
			(at 1.287526 -4.19989 90)
			(size 0.381 1.3462)
			(layers "F.Cu" "F.Mask" "F.Paste")
			(net "USB2_FIO_DN")
		)
		(pad "B4" smd rect
			(at 1.287526 -3.599942 90)
			(size 0.381 1.3462)
			(layers "F.Cu" "F.Mask" "F.Paste")
			(net "GND")
		)
		(pad "B5" smd rect
			(at 1.287526 -2.999994 90)
			(size 0.381 1.3462)
			(layers "F.Cu" "F.Mask" "F.Paste")
			(net "FM_PFR_LED_AMBER_R")
		)
		(pad "B6" smd rect
			(at 1.287526 -2.400046 90)
			(size 0.381 1.3462)
			(layers "F.Cu" "F.Mask" "F.Paste")
			(net "FM_PFR_LED_BLUE_R")
		)
		(pad "B7" smd rect
			(at 1.287526 -1.800098 90)
			(size 0.381 1.3462)
			(layers "F.Cu" "F.Mask" "F.Paste")
			(net "GND")
		)
		(pad "B8" smd rect
			(at 1.287526 -1.199896 90)
			(size 0.381 1.3462)
			(layers "F.Cu" "F.Mask" "F.Paste")
			(net "RST_SMB_FIO_R_N")
		)
		(pad "B9" smd rect
			(at 1.287526 -0.599948 90)
			(size 0.381 1.3462)
			(layers "F.Cu" "F.Mask" "F.Paste")
			(net "PRSNT_DBV2_SLIMSAS")
		)
		(pad "B10" smd rect
			(at 1.287526 0 90)
			(size 0.381 1.3462)
			(layers "F.Cu" "F.Mask" "F.Paste")
			(net "GND")
		)
		(pad "B11" smd rect
			(at 1.287526 0.599948 90)
			(size 0.381 1.3462)
			(layers "F.Cu" "F.Mask" "F.Paste")
			(net "SMB_FIO_R2_SCL")
		)
		(pad "B12" smd rect
			(at 1.287526 1.199896 90)
			(size 0.381 1.3462)
			(layers "F.Cu" "F.Mask" "F.Paste")
			(net "SMB_FIO_R2_SDA")
		)
		(pad "B13" smd rect
			(at 1.287526 1.800098 90)
			(size 0.381 1.3462)
			(layers "F.Cu" "F.Mask" "F.Paste")
			(net "GND")
		)
		(pad "B14" smd rect
			(at 1.287526 2.400046 90)
			(size 0.381 1.3462)
			(layers "F.Cu" "F.Mask" "F.Paste")
			(net "UART_FIO_DEBUG_R_TX")
		)
		(pad "B15" smd rect
			(at 1.287526 2.999994 90)
			(size 0.381 1.3462)
			(layers "F.Cu" "F.Mask" "F.Paste")
			(net "UART_FIO_DEBUG_R_RX")
		)
		(pad "B16" smd rect
			(at 1.287526 3.599942 90)
			(size 0.381 1.3462)
			(layers "F.Cu" "F.Mask" "F.Paste")
			(net "GND")
		)
		(pad "B17" smd rect
			(at 1.287526 4.19989 90)
			(size 0.381 1.3462)
			(layers "F.Cu" "F.Mask" "F.Paste")
			(net "P3V3_AUX")
		)
		(pad "B18" smd rect
			(at 1.287526 4.800092 90)
			(size 0.381 1.3462)
			(layers "F.Cu" "F.Mask" "F.Paste")
			(net "P5V_AUX")
		)
		(pad "B19" smd rect
			(at 1.287526 5.40004 90)
			(size 0.381 1.3462)
			(layers "F.Cu" "F.Mask" "F.Paste")
			(net "GND")
		)
		(pad "G1" thru_hole circle
			(at -3.80238 -6.599936 90)
			(size 1.2192 1.2192)
			(drill 0.8128)
			(layers "*.Cu" "*.Mask")
			(remove_unused_layers no)
			(net "GND")
			(clearance 0.0508)
			(thermal_gap 0.0508)
		)
		(pad "G2" thru_hole circle
			(at -3.80238 6.599936 90)
			(size 1.2192 1.2192)
			(drill 0.8128)
			(layers "*.Cu" "*.Mask")
			(remove_unused_layers no)
			(net "GND")
			(clearance 0.0508)
			(thermal_gap 0.0508)
		)
		(pad "G3" thru_hole circle
			(at 3.297428 -6.100064 90)
			(size 1.2192 1.2192)
			(drill 0.8128)
			(layers "*.Cu" "*.Mask")
			(remove_unused_layers no)
			(net "GND")
			(clearance 0.0508)
			(thermal_gap 0.0508)
		)
		(pad "G4" thru_hole circle
			(at 3.297428 6.100064 90)
			(size 1.2192 1.2192)
			(drill 0.8128)
			(layers "*.Cu" "*.Mask")
			(remove_unused_layers no)
			(net "GND")
			(clearance 0.0508)
			(thermal_gap 0.0508)
		)
		(zone
			(layer "F.Cu")
			(hatch none 0.5)
			(connect_pads
				(clearance 0)
			)
			(min_thickness 0.25)
			(keepout
				(tracks not_allowed)
				(vias allowed)
				(pads allowed)
				(copperpour not_allowed)
				(footprints allowed)
			)
			(placement
				(enabled no)
				(sheetname "")
			)
			(fill
				(thermal_gap 0.5)
				(thermal_bridge_width 0.5)
				(island_removal_mode 0)
			)
			(polygon
				(pts
					(xy 230.377492 -70.600062) (xy 228.27742 -70.600062) (xy 228.27742 -70.000114) (xy 230.377492 -70.000114)
				)
			)
		)
		(zone
			(layer "F.Cu")
			(hatch none 0.5)
			(connect_pads
				(clearance 0)
			)
			(min_thickness 0.25)
			(keepout
				(tracks not_allowed)
				(vias allowed)
				(pads allowed)
				(copperpour not_allowed)
				(footprints allowed)
			)
			(placement
				(enabled no)
				(sheetname "")
			)
			(fill
				(thermal_gap 0.5)
				(thermal_bridge_width 0.5)
				(island_removal_mode 0)
			)
			(polygon
				(pts
					(xy 230.377492 -58.399934) (xy 228.27742 -58.399934) (xy 228.27742 -57.799986) (xy 230.377492 -57.799986)
				)
			)
		)
		(zone
			(layer "F.Cu")
			(hatch none 0.5)
			(connect_pads
				(clearance 0)
			)
			(min_thickness 0.25)
			(keepout
				(tracks not_allowed)
				(vias allowed)
				(pads allowed)
				(copperpour not_allowed)
				(footprints allowed)
			)
			(placement
				(enabled no)
				(sheetname "")
			)
			(fill
				(thermal_gap 0.5)
				(thermal_bridge_width 0.5)
				(island_removal_mode 0)
			)
			(polygon
				(pts
					(xy 233.67746 -70.600062) (xy 231.577388 -70.600062) (xy 231.577388 -70.000114) (xy 233.67746 -70.000114)
				)
			)
		)
		(zone
			(layer "F.Cu")
			(hatch none 0.5)
			(connect_pads
				(clearance 0)
			)
			(min_thickness 0.25)
			(keepout
				(tracks not_allowed)
				(vias allowed)
				(pads allowed)
				(copperpour not_allowed)
				(footprints allowed)
			)
			(placement
				(enabled no)
				(sheetname "")
			)
			(fill
				(thermal_gap 0.5)
				(thermal_bridge_width 0.5)
				(island_removal_mode 0)
			)
			(polygon
				(pts
					(xy 233.67746 -58.399934) (xy 231.577388 -58.399934) (xy 231.577388 -57.799986) (xy 233.67746 -57.799986)
				)
			)
		)
		(zone
			(layer "F.Cu")
			(hatch none 0.5)
			(connect_pads
				(clearance 0)
			)
			(min_thickness 0.25)
			(keepout
				(tracks not_allowed)
				(vias allowed)
				(pads allowed)
				(copperpour not_allowed)
				(footprints allowed)
			)
			(placement
				(enabled no)
				(sheetname "")
			)
			(fill
				(thermal_gap 0.5)
				(thermal_bridge_width 0.5)
				(island_removal_mode 0)
			)
			(polygon
				(pts
					(arc
						(start 227.177346 -57.488836)
						(mid 227.427418 -57.439606)
						(end 227.677472 -57.488836)
					)
					(xy 227.677472 -57.250076) (xy 227.177346 -57.250076)
				)
			)
		)
		(zone
			(layer "F.Cu")
			(hatch none 0.5)
			(connect_pads
				(clearance 0)
			)
			(min_thickness 0.25)
			(keepout
				(tracks not_allowed)
				(vias allowed)
				(pads allowed)
				(copperpour not_allowed)
				(footprints allowed)
			)
			(placement
				(enabled no)
				(sheetname "")
			)
			(fill
				(thermal_gap 0.5)
				(thermal_bridge_width 0.5)
				(island_removal_mode 0)
			)
			(polygon
				(pts
					(arc
						(start 227.677472 -70.911212)
						(mid 227.427418 -70.960346)
						(end 227.177346 -70.911212)
					)
					(xy 227.177346 -71.149972) (xy 227.677472 -71.149972)
				)
			)
		)
		(zone
			(layer "F.Cu")
			(hatch none 0.5)
			(connect_pads
				(clearance 0)
			)
			(min_thickness 0.25)
			(keepout
				(tracks not_allowed)
				(vias allowed)
				(pads allowed)
				(copperpour not_allowed)
				(footprints allowed)
			)
			(placement
				(enabled no)
				(sheetname "")
			)
			(fill
				(thermal_gap 0.5)
				(thermal_bridge_width 0.5)
				(island_removal_mode 0)
			)
			(polygon
				(pts
					(arc
						(start 234.277408 -70.188836)
						(mid 234.52748 -70.139606)
						(end 234.777534 -70.188836)
					)
					(xy 234.777534 -69.950076) (xy 234.277408 -69.950076)
				)
			)
		)
		(zone
			(layer "F.Cu")
			(hatch none 0.5)
			(connect_pads
				(clearance 0)
			)
			(min_thickness 0.25)
			(keepout
				(tracks not_allowed)
				(vias allowed)
				(pads allowed)
				(copperpour not_allowed)
				(footprints allowed)
			)
			(placement
				(enabled no)
				(sheetname "")
			)
			(fill
				(thermal_gap 0.5)
				(thermal_bridge_width 0.5)
				(island_removal_mode 0)
			)
			(polygon
				(pts
					(arc
						(start 234.777534 -58.211212)
						(mid 234.52748 -58.260346)
						(end 234.277408 -58.211212)
					)
					(xy 234.277408 -58.449972) (xy 234.777534 -58.449972)
				)
			)
		)
		(zone
			(layers "F.Cu" "B.Cu" "In1.Cu" "In2.Cu" "In3.Cu" "In4.Cu" "In5.Cu" "In6.Cu"
				"In7.Cu" "In8.Cu" "In9.Cu" "In10.Cu" "In11.Cu" "In12.Cu" "In13.Cu" "In14.Cu"
				"In15.Cu" "In16.Cu"
			)
			(hatch none 0.5)
			(connect_pads
				(clearance 0)
			)
			(min_thickness 0.25)
			(keepout
				(tracks not_allowed)
				(vias allowed)
				(pads allowed)
				(copperpour not_allowed)
				(footprints allowed)
			)
			(placement
				(enabled no)
				(sheetname "")
			)
			(fill
				(thermal_gap 0.5)
				(thermal_bridge_width 0.5)
				(island_removal_mode 0)
			)
			(polygon
				(pts
					(arc
						(start 232.14584 -69.749924)
						(mid 229.80904 -69.749924)
						(end 232.14584 -69.749924)
					)
				)
			)
		)
		(zone
			(layers "F.Cu" "B.Cu" "In1.Cu" "In2.Cu" "In3.Cu" "In4.Cu" "In5.Cu" "In6.Cu"
				"In7.Cu" "In8.Cu" "In9.Cu" "In10.Cu" "In11.Cu" "In12.Cu" "In13.Cu" "In14.Cu"
				"In15.Cu" "In16.Cu"
			)
			(hatch none 0.5)
			(connect_pads
				(clearance 0)
			)
			(min_thickness 0.25)
			(keepout
				(tracks not_allowed)
				(vias allowed)
				(pads allowed)
				(copperpour not_allowed)
				(footprints allowed)
			)
			(placement
				(enabled no)
				(sheetname "")
			)
			(fill
				(thermal_gap 0.5)
				(thermal_bridge_width 0.5)
				(island_removal_mode 0)
			)
			(polygon
				(pts
					(arc
						(start 232.14584 -58.650124)
						(mid 229.80904 -58.650124)
						(end 232.14584 -58.650124)
					)
				)
			)
		)
	)
	(footprint ""
		(layer "F.Cu")
		(at 237.963964 -254.18542 -90)
		(property "Reference" "C4340"
			(at 0 0 270)
			(layer "F.SilkS")
			(hide yes)
			(effects
				(font
					(size 1.27 1.27)
				)
			)
		)
		(property "Value" ""
			(at 0 0 270)
			(layer "F.Fab")
			(effects
				(font
					(size 1.27 1.27)
				)
			)
		)
		(duplicate_pad_numbers_are_jumpers no)
		(fp_line
			(start -1.2954 0.5842)
			(end -1.2954 -0.5842)
			(stroke
				(width 0.1524)
				(type default)
			)
			(layer "F.SilkS")
		)
		(fp_line
			(start 1.2954 0.5842)
			(end -1.2954 0.5842)
			(stroke
				(width 0.1524)
				(type default)
			)
			(layer "F.SilkS")
		)
		(fp_line
			(start -1.2954 -0.5842)
			(end 1.2954 -0.5842)
			(stroke
				(width 0.1524)
				(type default)
			)
			(layer "F.SilkS")
		)
		(fp_line
			(start 1.2954 -0.5842)
			(end 1.2954 0.5842)
			(stroke
				(width 0.1524)
				(type default)
			)
			(layer "F.SilkS")
		)
		(fp_line
			(start -0.8636 0.4572)
			(end -0.8636 0.4064)
			(stroke
				(width 0.1)
				(type default)
			)
			(layer "F.Fab")
		)
		(fp_line
			(start 0.8636 0.4572)
			(end -0.8636 0.4572)
			(stroke
				(width 0.1)
				(type default)
			)
			(layer "F.Fab")
		)
		(fp_line
			(start -1.1938 0.4064)
			(end -1.1938 -0.4064)
			(stroke
				(width 0.1)
				(type default)
			)
			(layer "F.Fab")
		)
		(fp_line
			(start -0.8636 0.4064)
			(end -1.1938 0.4064)
			(stroke
				(width 0.1)
				(type default)
			)
			(layer "F.Fab")
		)
		(fp_line
			(start 0.8636 0.4064)
			(end 0.8636 0.4572)
			(stroke
				(width 0.1)
				(type default)
			)
			(layer "F.Fab")
		)
		(fp_line
			(start 1.1938 0.4064)
			(end 0.8636 0.4064)
			(stroke
				(width 0.1)
				(type default)
			)
			(layer "F.Fab")
		)
		(fp_line
			(start -1.1938 -0.4064)
			(end -0.8636 -0.4064)
			(stroke
				(width 0.1)
				(type default)
			)
			(layer "F.Fab")
		)
		(fp_line
			(start -0.8636 -0.4064)
			(end -0.8636 -0.4572)
			(stroke
				(width 0.1)
				(type default)
			)
			(layer "F.Fab")
		)
		(fp_line
			(start 0.8636 -0.4064)
			(end 1.1938 -0.4064)
			(stroke
				(width 0.1)
				(type default)
			)
			(layer "F.Fab")
		)
		(fp_line
			(start 1.1938 -0.4064)
			(end 1.1938 0.4064)
			(stroke
				(width 0.1)
				(type default)
			)
			(layer "F.Fab")
		)
		(fp_line
			(start -0.8636 -0.4572)
			(end 0.8636 -0.4572)
			(stroke
				(width 0.1)
				(type default)
			)
			(layer "F.Fab")
		)
		(fp_line
			(start 0.8636 -0.4572)
			(end 0.8636 -0.4064)
			(stroke
				(width 0.1)
				(type default)
			)
			(layer "F.Fab")
		)
		(pad "1" smd rect
			(at -0.7366 0 180)
			(size 0.7112 0.8128)
			(layers "F.Cu" "F.Mask" "F.Paste")
			(net "P1V25_SERDES_VDDPLL_PEX2_C2")
		)
		(pad "2" smd rect
			(at 0.7366 0 180)
			(size 0.7112 0.8128)
			(layers "F.Cu" "F.Mask" "F.Paste")
			(net "GND")
		)
	)
	(footprint ""
		(layer "F.Cu")
		(at 384.938524 -123.71324)
		(property "Reference" "C677"
			(at 0 0 0)
			(layer "F.SilkS")
			(hide yes)
			(effects
				(font
					(size 1.27 1.27)
				)
			)
		)
		(property "Value" ""
			(at 0 0 0)
			(layer "F.Fab")
			(effects
				(font
					(size 1.27 1.27)
				)
			)
		)
		(duplicate_pad_numbers_are_jumpers no)
		(fp_line
			(start -0.299974 -0.150114)
			(end 0.299974 -0.150114)
			(stroke
				(width 0.1)
				(type default)
			)
			(layer "F.Fab")
		)
		(fp_line
			(start -0.299974 0.150114)
			(end -0.299974 -0.150114)
			(stroke
				(width 0.1)
				(type default)
			)
			(layer "F.Fab")
		)
		(fp_line
			(start 0.299974 -0.150114)
			(end 0.299974 0.150114)
			(stroke
				(width 0.1)
				(type default)
			)
			(layer "F.Fab")
		)
		(fp_line
			(start 0.299974 0.150114)
			(end -0.299974 0.150114)
			(stroke
				(width 0.1)
				(type default)
			)
			(layer "F.Fab")
		)
		(pad "1" smd rect
			(at -0.2667 0)
			(size 0.3048 0.381)
			(layers "F.Cu" "F.Mask" "F.Paste")
			(net "P5E_PEX3_STN1_TX_DN<26>")
		)
		(pad "2" smd rect
			(at 0.2667 0)
			(size 0.3048 0.381)
			(layers "F.Cu" "F.Mask" "F.Paste")
			(net "P5E_PEX3_STN1_TX_C_DN<26>")
		)
	)
	(footprint ""
		(layer "F.Cu")
		(at 187.346844 -38.49116 180)
		(property "Reference" "R6077"
			(at 0 0 180)
			(layer "F.SilkS")
			(hide yes)
			(effects
				(font
					(size 1.27 1.27)
				)
			)
		)
		(property "Value" ""
			(at 0 0 180)
			(layer "F.Fab")
			(effects
				(font
					(size 1.27 1.27)
				)
			)
		)
		(duplicate_pad_numbers_are_jumpers no)
		(fp_line
			(start 0.7874 0.4064)
			(end -0.7874 0.4064)
			(stroke
				(width 0.1524)
				(type default)
			)
			(layer "F.SilkS")
		)
		(fp_line
			(start 0.7874 -0.4064)
			(end 0.7874 0.4064)
			(stroke
				(width 0.1524)
				(type default)
			)
			(layer "F.SilkS")
		)
		(fp_line
			(start -0.7874 0.4064)
			(end -0.7874 -0.4064)
			(stroke
				(width 0.1524)
				(type default)
			)
			(layer "F.SilkS")
		)
		(fp_line
			(start -0.7874 -0.4064)
			(end 0.7874 -0.4064)
			(stroke
				(width 0.1524)
				(type default)
			)
			(layer "F.SilkS")
		)
		(fp_line
			(start 0.67945 0.3048)
			(end 0.120396 0.3048)
			(stroke
				(width 0.1)
				(type default)
			)
			(layer "F.Fab")
		)
		(fp_line
			(start 0.67945 -0.3048)
			(end 0.67945 0.3048)
			(stroke
				(width 0.1)
				(type default)
			)
			(layer "F.Fab")
		)
		(fp_line
			(start 0.12065 -0.2794)
			(end 0.12065 -0.3048)
			(stroke
				(width 0.1)
				(type default)
			)
			(layer "F.Fab")
		)
		(fp_line
			(start 0.12065 -0.3048)
			(end 0.67945 -0.3048)
			(stroke
				(width 0.1)
				(type default)
			)
			(layer "F.Fab")
		)
		(fp_line
			(start 0.120396 0.3048)
			(end 0.120396 0.2794)
			(stroke
				(width 0.1)
				(type default)
			)
			(layer "F.Fab")
		)
		(fp_line
			(start 0.120396 0.2794)
			(end -0.12065 0.2794)
			(stroke
				(width 0.1)
				(type default)
			)
			(layer "F.Fab")
		)
		(fp_line
			(start -0.12065 0.3048)
			(end -0.67945 0.3048)
			(stroke
				(width 0.1)
				(type default)
			)
			(layer "F.Fab")
		)
		(fp_line
			(start -0.12065 0.2794)
			(end -0.12065 0.3048)
			(stroke
				(width 0.1)
				(type default)
			)
			(layer "F.Fab")
		)
		(fp_line
			(start -0.12065 -0.2794)
			(end 0.12065 -0.2794)
			(stroke
				(width 0.1)
				(type default)
			)
			(layer "F.Fab")
		)
		(fp_line
			(start -0.12065 -0.305054)
			(end -0.12065 -0.2794)
			(stroke
				(width 0.1)
				(type default)
			)
			(layer "F.Fab")
		)
		(fp_line
			(start -0.67945 0.3048)
			(end -0.67945 -0.305054)
			(stroke
				(width 0.1)
				(type default)
			)
			(layer "F.Fab")
		)
		(fp_line
			(start -0.67945 -0.305054)
			(end -0.12065 -0.305054)
			(stroke
				(width 0.1)
				(type default)
			)
			(layer "F.Fab")
		)
		(pad "1" smd circle
			(at -0.40005 0 180)
			(size 0 0)
			(layers "F.Cu" "F.Mask" "F.Paste")
			(net "P3V3_SSD7_PG_G1")
		)
		(pad "2" smd circle
			(at 0.40005 0 180)
			(size 0 0)
			(layers "F.Cu" "F.Mask" "F.Paste")
			(net "GND")
		)
	)
	(footprint ""
		(layer "F.Cu")
		(at 238.891064 -227.73767 -90)
		(property "Reference" "R6593"
			(at 0 0 270)
			(layer "F.SilkS")
			(hide yes)
			(effects
				(font
					(size 1.27 1.27)
				)
			)
		)
		(property "Value" ""
			(at 0 0 270)
			(layer "F.Fab")
			(effects
				(font
					(size 1.27 1.27)
				)
			)
		)
		(duplicate_pad_numbers_are_jumpers no)
		(fp_line
			(start -0.7874 0.4064)
			(end -0.7874 -0.4064)
			(stroke
				(width 0.1524)
				(type default)
			)
			(layer "F.SilkS")
		)
		(fp_line
			(start 0.7874 0.4064)
			(end -0.7874 0.4064)
			(stroke
				(width 0.1524)
				(type default)
			)
			(layer "F.SilkS")
		)
		(fp_line
			(start -0.7874 -0.4064)
			(end 0.7874 -0.4064)
			(stroke
				(width 0.1524)
				(type default)
			)
			(layer "F.SilkS")
		)
		(fp_line
			(start 0.7874 -0.4064)
			(end 0.7874 0.4064)
			(stroke
				(width 0.1524)
				(type default)
			)
			(layer "F.SilkS")
		)
		(fp_line
			(start -0.67945 0.3048)
			(end -0.67945 -0.305054)
			(stroke
				(width 0.1)
				(type default)
			)
			(layer "F.Fab")
		)
		(fp_line
			(start -0.12065 0.3048)
			(end -0.67945 0.3048)
			(stroke
				(width 0.1)
				(type default)
			)
			(layer "F.Fab")
		)
		(fp_line
			(start 0.120396 0.3048)
			(end 0.120396 0.2794)
			(stroke
				(width 0.1)
				(type default)
			)
			(layer "F.Fab")
		)
		(fp_line
			(start 0.67945 0.3048)
			(end 0.120396 0.3048)
			(stroke
				(width 0.1)
				(type default)
			)
			(layer "F.Fab")
		)
		(fp_line
			(start -0.12065 0.2794)
			(end -0.12065 0.3048)
			(stroke
				(width 0.1)
				(type default)
			)
			(layer "F.Fab")
		)
		(fp_line
			(start 0.120396 0.2794)
			(end -0.12065 0.2794)
			(stroke
				(width 0.1)
				(type default)
			)
			(layer "F.Fab")
		)
		(fp_line
			(start -0.12065 -0.2794)
			(end 0.12065 -0.2794)
			(stroke
				(width 0.1)
				(type default)
			)
			(layer "F.Fab")
		)
		(fp_line
			(start 0.12065 -0.2794)
			(end 0.12065 -0.3048)
			(stroke
				(width 0.1)
				(type default)
			)
			(layer "F.Fab")
		)
		(fp_line
			(start 0.12065 -0.3048)
			(end 0.67945 -0.3048)
			(stroke
				(width 0.1)
				(type default)
			)
			(layer "F.Fab")
		)
		(fp_line
			(start 0.67945 -0.3048)
			(end 0.67945 0.3048)
			(stroke
				(width 0.1)
				(type default)
			)
			(layer "F.Fab")
		)
		(fp_line
			(start -0.67945 -0.305054)
			(end -0.12065 -0.305054)
			(stroke
				(width 0.1)
				(type default)
			)
			(layer "F.Fab")
		)
		(fp_line
			(start -0.12065 -0.305054)
			(end -0.12065 -0.2794)
			(stroke
				(width 0.1)
				(type default)
			)
			(layer "F.Fab")
		)
		(pad "1" smd circle
			(at -0.40005 0 270)
			(size 0 0)
			(layers "F.Cu" "F.Mask" "F.Paste")
			(net "P1V8_PLL0_PEX2")
		)
		(pad "2" smd circle
			(at 0.40005 0 270)
			(size 0 0)
			(layers "F.Cu" "F.Mask" "F.Paste")
			(net "P1V8_PLL0_PEX2_SCALED")
		)
	)
	(footprint ""
		(layer "F.Cu")
		(at 344.784172 -277.644352)
		(property "Reference" "PC142"
			(at 0 0 0)
			(layer "F.SilkS")
			(hide yes)
			(effects
				(font
					(size 1.27 1.27)
				)
			)
		)
		(property "Value" ""
			(at 0 0 0)
			(layer "F.Fab")
			(effects
				(font
					(size 1.27 1.27)
				)
			)
		)
		(duplicate_pad_numbers_are_jumpers no)
		(fp_line
			(start -1.524 -0.762)
			(end 1.524 -0.762)
			(stroke
				(width 0.1524)
				(type default)
			)
			(layer "F.SilkS")
		)
		(fp_line
			(start -1.524 0.762)
			(end -1.524 -0.762)
			(stroke
				(width 0.1524)
				(type default)
			)
			(layer "F.SilkS")
		)
		(fp_line
			(start 1.524 -0.762)
			(end 1.524 0.762)
			(stroke
				(width 0.1524)
				(type default)
			)
			(layer "F.SilkS")
		)
		(fp_line
			(start 1.524 0.762)
			(end -1.524 0.762)
			(stroke
				(width 0.1524)
				(type default)
			)
			(layer "F.SilkS")
		)
		(fp_line
			(start -1.1049 -0.724916)
			(end -1.1049 0.724916)
			(stroke
				(width 0.1)
				(type default)
			)
			(layer "F.Fab")
		)
		(fp_line
			(start -1.1049 0.724916)
			(end 1.1049 0.724916)
			(stroke
				(width 0.1)
				(type default)
			)
			(layer "F.Fab")
		)
		(fp_line
			(start 1.1049 -0.724916)
			(end -1.1049 -0.724916)
			(stroke
				(width 0.1)
				(type default)
			)
			(layer "F.Fab")
		)
		(fp_line
			(start 1.1049 0.724916)
			(end 1.1049 -0.724916)
			(stroke
				(width 0.1)
				(type default)
			)
			(layer "F.Fab")
		)
		(pad "1" smd rect
			(at -0.889 0 180)
			(size 1.016 1.27)
			(layers "F.Cu" "F.Mask" "F.Paste")
			(net "SW_P12V_P0V8_PEX2_FLT")
		)
		(pad "2" smd rect
			(at 0.889 0 180)
			(size 1.016 1.27)
			(layers "F.Cu" "F.Mask" "F.Paste")
			(net "GND")
		)
	)
	(footprint ""
		(layer "F.Cu")
		(at 428.79518 -35.48253)
		(property "Reference" "U396"
			(at -2.53111 0.73533 90)
			(unlocked yes)
			(layer "F.SilkS")
			(effects
				(font
					(size 0.7874 0.5842)
					(thickness 0.1524)
				)
				(justify left)
			)
		)
		(property "Value" ""
			(at 0 0 0)
			(layer "F.Fab")
			(effects
				(font
					(size 1.27 1.27)
				)
			)
		)
		(duplicate_pad_numbers_are_jumpers no)
		(fp_line
			(start -1.3462 -1.1938)
			(end -1.3462 1.1684)
			(stroke
				(width 0.1524)
				(type default)
			)
			(layer "F.SilkS")
		)
		(fp_line
			(start -1.3462 1.1938)
			(end 1.3462 1.1938)
			(stroke
				(width 0.1524)
				(type default)
			)
			(layer "F.SilkS")
		)
		(fp_line
			(start 1.3462 -1.1938)
			(end -1.3462 -1.1938)
			(stroke
				(width 0.1524)
				(type default)
			)
			(layer "F.SilkS")
		)
		(fp_line
			(start 1.3462 1.1938)
			(end 1.3462 -1.1938)
			(stroke
				(width 0.1524)
				(type default)
			)
			(layer "F.SilkS")
		)
		(fp_poly
			(pts
				(xy -1.447038 -0.760476) (xy -2.052066 -0.457962) (xy -2.052066 -1.06299)
			)
			(stroke
				(width 0)
				(type default)
			)
			(fill yes)
			(layer "F.SilkS")
		)
		(fp_line
			(start -0.674878 -1.124966)
			(end -0.674878 1.124966)
			(stroke
				(width 0.1)
				(type default)
			)
			(layer "F.Fab")
		)
		(fp_line
			(start -0.674878 1.124966)
			(end 0.674878 1.124966)
			(stroke
				(width 0.1)
				(type default)
			)
			(layer "F.Fab")
		)
		(fp_line
			(start 0.674878 -1.124966)
			(end -0.674878 -1.124966)
			(stroke
				(width 0.1)
				(type default)
			)
			(layer "F.Fab")
		)
		(fp_line
			(start 0.674878 1.124966)
			(end 0.674878 -1.124966)
			(stroke
				(width 0.1)
				(type default)
			)
			(layer "F.Fab")
		)
		(fp_poly
			(pts
				(xy -1.447038 -0.760476) (xy -2.052066 -0.457962) (xy -2.052066 -1.06299)
			)
			(stroke
				(width 0)
				(type default)
			)
			(fill yes)
			(layer "F.Fab")
		)
		(pad "1" smd rect
			(at -0.899922 -0.750062)
			(size 0.6096 0.6096)
			(layers "F.Cu" "F.Mask" "F.Paste")
			(net "PWRGD_P3V3_SSD15_R")
		)
		(pad "2" smd rect
			(at -0.899922 0 90)
			(size 0.4064 0.6096)
			(layers "F.Cu" "F.Mask" "F.Paste")
			(net "RST_SMB_SSD15_N")
		)
		(pad "3" smd rect
			(at -0.899922 0.750062)
			(size 0.6096 0.6096)
			(layers "F.Cu" "F.Mask" "F.Paste")
			(net "GND")
		)
		(pad "4" smd rect
			(at 0.899922 0.750062)
			(size 0.6096 0.6096)
			(layers "F.Cu" "F.Mask" "F.Paste")
			(net "RST_SMB_SSD15_ISO_N")
		)
		(pad "5" smd rect
			(at 0.899922 -0.750062)
			(size 0.6096 0.6096)
			(layers "F.Cu" "F.Mask" "F.Paste")
			(net "P3V3_AUX")
		)
	)
	(footprint ""
		(layer "F.Cu")
		(at 227.773484 -309.211218 90)
		(property "Reference" "PR173"
			(at 0 0 90)
			(layer "F.SilkS")
			(hide yes)
			(effects
				(font
					(size 1.27 1.27)
				)
			)
		)
		(property "Value" ""
			(at 0 0 90)
			(layer "F.Fab")
			(effects
				(font
					(size 1.27 1.27)
				)
			)
		)
		(duplicate_pad_numbers_are_jumpers no)
		(fp_line
			(start 0.7874 -0.4064)
			(end 0.7874 0.4064)
			(stroke
				(width 0.1524)
				(type default)
			)
			(layer "F.SilkS")
		)
		(fp_line
			(start -0.7874 -0.4064)
			(end 0.7874 -0.4064)
			(stroke
				(width 0.1524)
				(type default)
			)
			(layer "F.SilkS")
		)
		(fp_line
			(start 0.7874 0.4064)
			(end -0.7874 0.4064)
			(stroke
				(width 0.1524)
				(type default)
			)
			(layer "F.SilkS")
		)
		(fp_line
			(start -0.7874 0.4064)
			(end -0.7874 -0.4064)
			(stroke
				(width 0.1524)
				(type default)
			)
			(layer "F.SilkS")
		)
		(fp_line
			(start -0.12065 -0.305054)
			(end -0.12065 -0.2794)
			(stroke
				(width 0.1)
				(type default)
			)
			(layer "F.Fab")
		)
		(fp_line
			(start -0.67945 -0.305054)
			(end -0.12065 -0.305054)
			(stroke
				(width 0.1)
				(type default)
			)
			(layer "F.Fab")
		)
		(fp_line
			(start 0.67945 -0.3048)
			(end 0.67945 0.3048)
			(stroke
				(width 0.1)
				(type default)
			)
			(layer "F.Fab")
		)
		(fp_line
			(start 0.12065 -0.3048)
			(end 0.67945 -0.3048)
			(stroke
				(width 0.1)
				(type default)
			)
			(layer "F.Fab")
		)
		(fp_line
			(start 0.12065 -0.2794)
			(end 0.12065 -0.3048)
			(stroke
				(width 0.1)
				(type default)
			)
			(layer "F.Fab")
		)
		(fp_line
			(start -0.12065 -0.2794)
			(end 0.12065 -0.2794)
			(stroke
				(width 0.1)
				(type default)
			)
			(layer "F.Fab")
		)
		(fp_line
			(start 0.120396 0.2794)
			(end -0.12065 0.2794)
			(stroke
				(width 0.1)
				(type default)
			)
			(layer "F.Fab")
		)
		(fp_line
			(start -0.12065 0.2794)
			(end -0.12065 0.3048)
			(stroke
				(width 0.1)
				(type default)
			)
			(layer "F.Fab")
		)
		(fp_line
			(start 0.67945 0.3048)
			(end 0.120396 0.3048)
			(stroke
				(width 0.1)
				(type default)
			)
			(layer "F.Fab")
		)
		(fp_line
			(start 0.120396 0.3048)
			(end 0.120396 0.2794)
			(stroke
				(width 0.1)
				(type default)
			)
			(layer "F.Fab")
		)
		(fp_line
			(start -0.12065 0.3048)
			(end -0.67945 0.3048)
			(stroke
				(width 0.1)
				(type default)
			)
			(layer "F.Fab")
		)
		(fp_line
			(start -0.67945 0.3048)
			(end -0.67945 -0.305054)
			(stroke
				(width 0.1)
				(type default)
			)
			(layer "F.Fab")
		)
		(pad "1" smd circle
			(at -0.40005 0 90)
			(size 0 0)
			(layers "F.Cu" "F.Mask" "F.Paste")
			(net "SH_P1V25_PEX1_FB_N")
		)
		(pad "2" smd circle
			(at 0.40005 0 90)
			(size 0 0)
			(layers "F.Cu" "F.Mask" "F.Paste")
			(net "P1V25_PEX1_FB")
		)
	)
	(footprint ""
		(layer "F.Cu")
		(at 2.099056 -40.01262 -90)
		(property "Reference" "PC668"
			(at 0 0 270)
			(layer "F.SilkS")
			(hide yes)
			(effects
				(font
					(size 1.27 1.27)
				)
			)
		)
		(property "Value" ""
			(at 0 0 270)
			(layer "F.Fab")
			(effects
				(font
					(size 1.27 1.27)
				)
			)
		)
		(duplicate_pad_numbers_are_jumpers no)
		(fp_line
			(start -0.7874 0.4064)
			(end -0.7874 -0.4064)
			(stroke
				(width 0.1524)
				(type default)
			)
			(layer "F.SilkS")
		)
		(fp_line
			(start 0.7874 0.4064)
			(end -0.7874 0.4064)
			(stroke
				(width 0.1524)
				(type default)
			)
			(layer "F.SilkS")
		)
		(fp_line
			(start -0.7874 -0.4064)
			(end 0.7874 -0.4064)
			(stroke
				(width 0.1524)
				(type default)
			)
			(layer "F.SilkS")
		)
		(fp_line
			(start 0.7874 -0.4064)
			(end 0.7874 0.4064)
			(stroke
				(width 0.1524)
				(type default)
			)
			(layer "F.SilkS")
		)
		(fp_line
			(start -0.67945 0.3048)
			(end -0.67945 -0.305054)
			(stroke
				(width 0.1)
				(type default)
			)
			(layer "F.Fab")
		)
		(fp_line
			(start -0.12065 0.3048)
			(end -0.67945 0.3048)
			(stroke
				(width 0.1)
				(type default)
			)
			(layer "F.Fab")
		)
		(fp_line
			(start 0.120396 0.3048)
			(end 0.120396 0.2794)
			(stroke
				(width 0.1)
				(type default)
			)
			(layer "F.Fab")
		)
		(fp_line
			(start 0.67945 0.3048)
			(end 0.120396 0.3048)
			(stroke
				(width 0.1)
				(type default)
			)
			(layer "F.Fab")
		)
		(fp_line
			(start -0.12065 0.2794)
			(end -0.12065 0.3048)
			(stroke
				(width 0.1)
				(type default)
			)
			(layer "F.Fab")
		)
		(fp_line
			(start 0.120396 0.2794)
			(end -0.12065 0.2794)
			(stroke
				(width 0.1)
				(type default)
			)
			(layer "F.Fab")
		)
		(fp_line
			(start -0.12065 -0.2794)
			(end 0.12065 -0.2794)
			(stroke
				(width 0.1)
				(type default)
			)
			(layer "F.Fab")
		)
		(fp_line
			(start 0.12065 -0.2794)
			(end 0.12065 -0.3048)
			(stroke
				(width 0.1)
				(type default)
			)
			(layer "F.Fab")
		)
		(fp_line
			(start 0.12065 -0.3048)
			(end 0.67945 -0.3048)
			(stroke
				(width 0.1)
				(type default)
			)
			(layer "F.Fab")
		)
		(fp_line
			(start 0.67945 -0.3048)
			(end 0.67945 0.3048)
			(stroke
				(width 0.1)
				(type default)
			)
			(layer "F.Fab")
		)
		(fp_line
			(start -0.67945 -0.305054)
			(end -0.12065 -0.305054)
			(stroke
				(width 0.1)
				(type default)
			)
			(layer "F.Fab")
		)
		(fp_line
			(start -0.12065 -0.305054)
			(end -0.12065 -0.2794)
			(stroke
				(width 0.1)
				(type default)
			)
			(layer "F.Fab")
		)
		(pad "1" smd circle
			(at -0.40005 0 270)
			(size 0 0)
			(layers "F.Cu" "F.Mask" "F.Paste")
			(net "P3V3_AUX")
		)
		(pad "2" smd circle
			(at 0.40005 0 270)
			(size 0 0)
			(layers "F.Cu" "F.Mask" "F.Paste")
			(net "GND")
		)
	)
	(footprint ""
		(layer "F.Cu")
		(at 2.232152 -251.312426 -90)
		(property "Reference" "C4240"
			(at 0 0 270)
			(layer "F.SilkS")
			(hide yes)
			(effects
				(font
					(size 1.27 1.27)
				)
			)
		)
		(property "Value" ""
			(at 0 0 270)
			(layer "F.Fab")
			(effects
				(font
					(size 1.27 1.27)
				)
			)
		)
		(duplicate_pad_numbers_are_jumpers no)
		(fp_line
			(start -1.2954 0.5842)
			(end -1.2954 -0.5842)
			(stroke
				(width 0.1524)
				(type default)
			)
			(layer "F.SilkS")
		)
		(fp_line
			(start 1.2954 0.5842)
			(end -1.2954 0.5842)
			(stroke
				(width 0.1524)
				(type default)
			)
			(layer "F.SilkS")
		)
		(fp_line
			(start -1.2954 -0.5842)
			(end 1.2954 -0.5842)
			(stroke
				(width 0.1524)
				(type default)
			)
			(layer "F.SilkS")
		)
		(fp_line
			(start 1.2954 -0.5842)
			(end 1.2954 0.5842)
			(stroke
				(width 0.1524)
				(type default)
			)
			(layer "F.SilkS")
		)
		(fp_line
			(start -0.8636 0.4572)
			(end -0.8636 0.4064)
			(stroke
				(width 0.1)
				(type default)
			)
			(layer "F.Fab")
		)
		(fp_line
			(start 0.8636 0.4572)
			(end -0.8636 0.4572)
			(stroke
				(width 0.1)
				(type default)
			)
			(layer "F.Fab")
		)
		(fp_line
			(start -1.1938 0.4064)
			(end -1.1938 -0.4064)
			(stroke
				(width 0.1)
				(type default)
			)
			(layer "F.Fab")
		)
		(fp_line
			(start -0.8636 0.4064)
			(end -1.1938 0.4064)
			(stroke
				(width 0.1)
				(type default)
			)
			(layer "F.Fab")
		)
		(fp_line
			(start 0.8636 0.4064)
			(end 0.8636 0.4572)
			(stroke
				(width 0.1)
				(type default)
			)
			(layer "F.Fab")
		)
		(fp_line
			(start 1.1938 0.4064)
			(end 0.8636 0.4064)
			(stroke
				(width 0.1)
				(type default)
			)
			(layer "F.Fab")
		)
		(fp_line
			(start -1.1938 -0.4064)
			(end -0.8636 -0.4064)
			(stroke
				(width 0.1)
				(type default)
			)
			(layer "F.Fab")
		)
		(fp_line
			(start -0.8636 -0.4064)
			(end -0.8636 -0.4572)
			(stroke
				(width 0.1)
				(type default)
			)
			(layer "F.Fab")
		)
		(fp_line
			(start 0.8636 -0.4064)
			(end 1.1938 -0.4064)
			(stroke
				(width 0.1)
				(type default)
			)
			(layer "F.Fab")
		)
		(fp_line
			(start 1.1938 -0.4064)
			(end 1.1938 0.4064)
			(stroke
				(width 0.1)
				(type default)
			)
			(layer "F.Fab")
		)
		(fp_line
			(start -0.8636 -0.4572)
			(end 0.8636 -0.4572)
			(stroke
				(width 0.1)
				(type default)
			)
			(layer "F.Fab")
		)
		(fp_line
			(start 0.8636 -0.4572)
			(end 0.8636 -0.4064)
			(stroke
				(width 0.1)
				(type default)
			)
			(layer "F.Fab")
		)
		(pad "1" smd rect
			(at -0.7366 0 180)
			(size 0.7112 0.8128)
			(layers "F.Cu" "F.Mask" "F.Paste")
			(net "P1V25_SERDES_VDDPLL_PEX0_C6")
		)
		(pad "2" smd rect
			(at 0.7366 0 180)
			(size 0.7112 0.8128)
			(layers "F.Cu" "F.Mask" "F.Paste")
			(net "GND")
		)
	)
	(footprint ""
		(layer "F.Cu")
		(at 444.908432 -224.700846)
		(property "Reference" "R6606"
			(at 0 0 0)
			(layer "F.SilkS")
			(hide yes)
			(effects
				(font
					(size 1.27 1.27)
				)
			)
		)
		(property "Value" ""
			(at 0 0 0)
			(layer "F.Fab")
			(effects
				(font
					(size 1.27 1.27)
				)
			)
		)
		(duplicate_pad_numbers_are_jumpers no)
		(fp_line
			(start -0.7874 -0.4064)
			(end 0.7874 -0.4064)
			(stroke
				(width 0.1524)
				(type default)
			)
			(layer "F.SilkS")
		)
		(fp_line
			(start -0.7874 0.4064)
			(end -0.7874 -0.4064)
			(stroke
				(width 0.1524)
				(type default)
			)
			(layer "F.SilkS")
		)
		(fp_line
			(start 0.7874 -0.4064)
			(end 0.7874 0.4064)
			(stroke
				(width 0.1524)
				(type default)
			)
			(layer "F.SilkS")
		)
		(fp_line
			(start 0.7874 0.4064)
			(end -0.7874 0.4064)
			(stroke
				(width 0.1524)
				(type default)
			)
			(layer "F.SilkS")
		)
		(fp_line
			(start -0.67945 -0.305054)
			(end -0.12065 -0.305054)
			(stroke
				(width 0.1)
				(type default)
			)
			(layer "F.Fab")
		)
		(fp_line
			(start -0.67945 0.3048)
			(end -0.67945 -0.305054)
			(stroke
				(width 0.1)
				(type default)
			)
			(layer "F.Fab")
		)
		(fp_line
			(start -0.12065 -0.305054)
			(end -0.12065 -0.2794)
			(stroke
				(width 0.1)
				(type default)
			)
			(layer "F.Fab")
		)
		(fp_line
			(start -0.12065 -0.2794)
			(end 0.12065 -0.2794)
			(stroke
				(width 0.1)
				(type default)
			)
			(layer "F.Fab")
		)
		(fp_line
			(start -0.12065 0.2794)
			(end -0.12065 0.3048)
			(stroke
				(width 0.1)
				(type default)
			)
			(layer "F.Fab")
		)
		(fp_line
			(start -0.12065 0.3048)
			(end -0.67945 0.3048)
			(stroke
				(width 0.1)
				(type default)
			)
			(layer "F.Fab")
		)
		(fp_line
			(start 0.120396 0.2794)
			(end -0.12065 0.2794)
			(stroke
				(width 0.1)
				(type default)
			)
			(layer "F.Fab")
		)
		(fp_line
			(start 0.120396 0.3048)
			(end 0.120396 0.2794)
			(stroke
				(width 0.1)
				(type default)
			)
			(layer "F.Fab")
		)
		(fp_line
			(start 0.12065 -0.3048)
			(end 0.67945 -0.3048)
			(stroke
				(width 0.1)
				(type default)
			)
			(layer "F.Fab")
		)
		(fp_line
			(start 0.12065 -0.2794)
			(end 0.12065 -0.3048)
			(stroke
				(width 0.1)
				(type default)
			)
			(layer "F.Fab")
		)
		(fp_line
			(start 0.67945 -0.3048)
			(end 0.67945 0.3048)
			(stroke
				(width 0.1)
				(type default)
			)
			(layer "F.Fab")
		)
		(fp_line
			(start 0.67945 0.3048)
			(end 0.120396 0.3048)
			(stroke
				(width 0.1)
				(type default)
			)
			(layer "F.Fab")
		)
		(pad "1" smd circle
			(at -0.40005 0)
			(size 0 0)
			(layers "F.Cu" "F.Mask" "F.Paste")
			(net "UART_PEX2_SDB_BUF_R_TX")
		)
		(pad "2" smd circle
			(at 0.40005 0)
			(size 0 0)
			(layers "F.Cu" "F.Mask" "F.Paste")
			(net "UART_PEX2_SDB_CP2108_TX")
		)
	)
	(footprint ""
		(layer "F.Cu")
		(at 104.267762 -52.035456 180)
		(property "Reference" "R867"
			(at 0 0 180)
			(layer "F.SilkS")
			(hide yes)
			(effects
				(font
					(size 1.27 1.27)
				)
			)
		)
		(property "Value" ""
			(at 0 0 180)
			(layer "F.Fab")
			(effects
				(font
					(size 1.27 1.27)
				)
			)
		)
		(duplicate_pad_numbers_are_jumpers no)
		(fp_line
			(start 0.7874 0.4064)
			(end -0.7874 0.4064)
			(stroke
				(width 0.1524)
				(type default)
			)
			(layer "F.SilkS")
		)
		(fp_line
			(start 0.7874 -0.4064)
			(end 0.7874 0.4064)
			(stroke
				(width 0.1524)
				(type default)
			)
			(layer "F.SilkS")
		)
		(fp_line
			(start -0.7874 0.4064)
			(end -0.7874 -0.4064)
			(stroke
				(width 0.1524)
				(type default)
			)
			(layer "F.SilkS")
		)
		(fp_line
			(start -0.7874 -0.4064)
			(end 0.7874 -0.4064)
			(stroke
				(width 0.1524)
				(type default)
			)
			(layer "F.SilkS")
		)
		(fp_line
			(start 0.67945 0.3048)
			(end 0.120396 0.3048)
			(stroke
				(width 0.1)
				(type default)
			)
			(layer "F.Fab")
		)
		(fp_line
			(start 0.67945 -0.3048)
			(end 0.67945 0.3048)
			(stroke
				(width 0.1)
				(type default)
			)
			(layer "F.Fab")
		)
		(fp_line
			(start 0.12065 -0.2794)
			(end 0.12065 -0.3048)
			(stroke
				(width 0.1)
				(type default)
			)
			(layer "F.Fab")
		)
		(fp_line
			(start 0.12065 -0.3048)
			(end 0.67945 -0.3048)
			(stroke
				(width 0.1)
				(type default)
			)
			(layer "F.Fab")
		)
		(fp_line
			(start 0.120396 0.3048)
			(end 0.120396 0.2794)
			(stroke
				(width 0.1)
				(type default)
			)
			(layer "F.Fab")
		)
		(fp_line
			(start 0.120396 0.2794)
			(end -0.12065 0.2794)
			(stroke
				(width 0.1)
				(type default)
			)
			(layer "F.Fab")
		)
		(fp_line
			(start -0.12065 0.3048)
			(end -0.67945 0.3048)
			(stroke
				(width 0.1)
				(type default)
			)
			(layer "F.Fab")
		)
		(fp_line
			(start -0.12065 0.2794)
			(end -0.12065 0.3048)
			(stroke
				(width 0.1)
				(type default)
			)
			(layer "F.Fab")
		)
		(fp_line
			(start -0.12065 -0.2794)
			(end 0.12065 -0.2794)
			(stroke
				(width 0.1)
				(type default)
			)
			(layer "F.Fab")
		)
		(fp_line
			(start -0.12065 -0.305054)
			(end -0.12065 -0.2794)
			(stroke
				(width 0.1)
				(type default)
			)
			(layer "F.Fab")
		)
		(fp_line
			(start -0.67945 0.3048)
			(end -0.67945 -0.305054)
			(stroke
				(width 0.1)
				(type default)
			)
			(layer "F.Fab")
		)
		(fp_line
			(start -0.67945 -0.305054)
			(end -0.12065 -0.305054)
			(stroke
				(width 0.1)
				(type default)
			)
			(layer "F.Fab")
		)
		(pad "1" smd circle
			(at -0.40005 0 180)
			(size 0 0)
			(layers "F.Cu" "F.Mask" "F.Paste")
			(net "P3V3_AUX")
		)
		(pad "2" smd circle
			(at 0.40005 0 180)
			(size 0 0)
			(layers "F.Cu" "F.Mask" "F.Paste")
			(net "PWRGD_P12V_SSD3")
		)
	)
	(footprint ""
		(layer "F.Cu")
		(at 72.947276 -21.37156)
		(property "Reference" "C3889"
			(at 0 0 0)
			(layer "F.SilkS")
			(hide yes)
			(effects
				(font
					(size 1.27 1.27)
				)
			)
		)
		(property "Value" ""
			(at 0 0 0)
			(layer "F.Fab")
			(effects
				(font
					(size 1.27 1.27)
				)
			)
		)
		(duplicate_pad_numbers_are_jumpers no)
		(fp_line
			(start -0.7874 -0.4064)
			(end 0.7874 -0.4064)
			(stroke
				(width 0.1524)
				(type default)
			)
			(layer "F.SilkS")
		)
		(fp_line
			(start -0.7874 0.4064)
			(end -0.7874 -0.4064)
			(stroke
				(width 0.1524)
				(type default)
			)
			(layer "F.SilkS")
		)
		(fp_line
			(start 0.7874 -0.4064)
			(end 0.7874 0.4064)
			(stroke
				(width 0.1524)
				(type default)
			)
			(layer "F.SilkS")
		)
		(fp_line
			(start 0.7874 0.4064)
			(end -0.7874 0.4064)
			(stroke
				(width 0.1524)
				(type default)
			)
			(layer "F.SilkS")
		)
		(fp_line
			(start -0.67945 -0.305054)
			(end -0.12065 -0.305054)
			(stroke
				(width 0.1)
				(type default)
			)
			(layer "F.Fab")
		)
		(fp_line
			(start -0.67945 0.3048)
			(end -0.67945 -0.305054)
			(stroke
				(width 0.1)
				(type default)
			)
			(layer "F.Fab")
		)
		(fp_line
			(start -0.12065 -0.305054)
			(end -0.12065 -0.2794)
			(stroke
				(width 0.1)
				(type default)
			)
			(layer "F.Fab")
		)
		(fp_line
			(start -0.12065 -0.2794)
			(end 0.12065 -0.2794)
			(stroke
				(width 0.1)
				(type default)
			)
			(layer "F.Fab")
		)
		(fp_line
			(start -0.12065 0.2794)
			(end -0.12065 0.3048)
			(stroke
				(width 0.1)
				(type default)
			)
			(layer "F.Fab")
		)
		(fp_line
			(start -0.12065 0.3048)
			(end -0.67945 0.3048)
			(stroke
				(width 0.1)
				(type default)
			)
			(layer "F.Fab")
		)
		(fp_line
			(start 0.120396 0.2794)
			(end -0.12065 0.2794)
			(stroke
				(width 0.1)
				(type default)
			)
			(layer "F.Fab")
		)
		(fp_line
			(start 0.120396 0.3048)
			(end 0.120396 0.2794)
			(stroke
				(width 0.1)
				(type default)
			)
			(layer "F.Fab")
		)
		(fp_line
			(start 0.12065 -0.3048)
			(end 0.67945 -0.3048)
			(stroke
				(width 0.1)
				(type default)
			)
			(layer "F.Fab")
		)
		(fp_line
			(start 0.12065 -0.2794)
			(end 0.12065 -0.3048)
			(stroke
				(width 0.1)
				(type default)
			)
			(layer "F.Fab")
		)
		(fp_line
			(start 0.67945 -0.3048)
			(end 0.67945 0.3048)
			(stroke
				(width 0.1)
				(type default)
			)
			(layer "F.Fab")
		)
		(fp_line
			(start 0.67945 0.3048)
			(end 0.120396 0.3048)
			(stroke
				(width 0.1)
				(type default)
			)
			(layer "F.Fab")
		)
		(pad "1" smd circle
			(at -0.40005 0)
			(size 0 0)
			(layers "F.Cu" "F.Mask" "F.Paste")
			(net "P12V_SSD2")
		)
		(pad "2" smd circle
			(at 0.40005 0)
			(size 0 0)
			(layers "F.Cu" "F.Mask" "F.Paste")
			(net "GND")
		)
	)
	(footprint ""
		(layer "F.Cu")
		(at 366.211866 -146.263614 180)
		(property "Reference" "C620"
			(at 0 0 180)
			(layer "F.SilkS")
			(hide yes)
			(effects
				(font
					(size 1.27 1.27)
				)
			)
		)
		(property "Value" ""
			(at 0 0 180)
			(layer "F.Fab")
			(effects
				(font
					(size 1.27 1.27)
				)
			)
		)
		(duplicate_pad_numbers_are_jumpers no)
		(fp_line
			(start 0.7874 0.4064)
			(end -0.7874 0.4064)
			(stroke
				(width 0.1524)
				(type default)
			)
			(layer "F.SilkS")
		)
		(fp_line
			(start 0.7874 -0.4064)
			(end 0.7874 0.4064)
			(stroke
				(width 0.1524)
				(type default)
			)
			(layer "F.SilkS")
		)
		(fp_line
			(start -0.7874 0.4064)
			(end -0.7874 -0.4064)
			(stroke
				(width 0.1524)
				(type default)
			)
			(layer "F.SilkS")
		)
		(fp_line
			(start -0.7874 -0.4064)
			(end 0.7874 -0.4064)
			(stroke
				(width 0.1524)
				(type default)
			)
			(layer "F.SilkS")
		)
		(fp_line
			(start 0.67945 0.3048)
			(end 0.120396 0.3048)
			(stroke
				(width 0.1)
				(type default)
			)
			(layer "F.Fab")
		)
		(fp_line
			(start 0.67945 -0.3048)
			(end 0.67945 0.3048)
			(stroke
				(width 0.1)
				(type default)
			)
			(layer "F.Fab")
		)
		(fp_line
			(start 0.12065 -0.2794)
			(end 0.12065 -0.3048)
			(stroke
				(width 0.1)
				(type default)
			)
			(layer "F.Fab")
		)
		(fp_line
			(start 0.12065 -0.3048)
			(end 0.67945 -0.3048)
			(stroke
				(width 0.1)
				(type default)
			)
			(layer "F.Fab")
		)
		(fp_line
			(start 0.120396 0.3048)
			(end 0.120396 0.2794)
			(stroke
				(width 0.1)
				(type default)
			)
			(layer "F.Fab")
		)
		(fp_line
			(start 0.120396 0.2794)
			(end -0.12065 0.2794)
			(stroke
				(width 0.1)
				(type default)
			)
			(layer "F.Fab")
		)
		(fp_line
			(start -0.12065 0.3048)
			(end -0.67945 0.3048)
			(stroke
				(width 0.1)
				(type default)
			)
			(layer "F.Fab")
		)
		(fp_line
			(start -0.12065 0.2794)
			(end -0.12065 0.3048)
			(stroke
				(width 0.1)
				(type default)
			)
			(layer "F.Fab")
		)
		(fp_line
			(start -0.12065 -0.2794)
			(end 0.12065 -0.2794)
			(stroke
				(width 0.1)
				(type default)
			)
			(layer "F.Fab")
		)
		(fp_line
			(start -0.12065 -0.305054)
			(end -0.12065 -0.2794)
			(stroke
				(width 0.1)
				(type default)
			)
			(layer "F.Fab")
		)
		(fp_line
			(start -0.67945 0.3048)
			(end -0.67945 -0.305054)
			(stroke
				(width 0.1)
				(type default)
			)
			(layer "F.Fab")
		)
		(fp_line
			(start -0.67945 -0.305054)
			(end -0.12065 -0.305054)
			(stroke
				(width 0.1)
				(type default)
			)
			(layer "F.Fab")
		)
		(pad "1" smd circle
			(at -0.40005 0 180)
			(size 0 0)
			(layers "F.Cu" "F.Mask" "F.Paste")
			(net "P12V_NIC6_R")
		)
		(pad "2" smd circle
			(at 0.40005 0 180)
			(size 0 0)
			(layers "F.Cu" "F.Mask" "F.Paste")
			(net "GND")
		)
	)
	(footprint ""
		(layer "F.Cu")
		(at 352.975926 -258.394962 90)
		(property "Reference" "PU11"
			(at -2.542794 -6.725158 90)
			(unlocked yes)
			(layer "F.SilkS")
			(effects
				(font
					(size 0.7874 0.5842)
					(thickness 0.1524)
				)
				(justify left)
			)
		)
		(property "Value" ""
			(at 0 0 90)
			(layer "F.Fab")
			(effects
				(font
					(size 1.27 1.27)
				)
			)
		)
		(duplicate_pad_numbers_are_jumpers no)
		(fp_line
			(start 0.1778 -3.2385)
			(end 0.1778 -2.8575)
			(stroke
				(width 0.1524)
				(type default)
			)
			(layer "F.SilkS")
		)
		(fp_line
			(start -1.8034 -2.8702)
			(end -1.8034 -3.6322)
			(stroke
				(width 0.1524)
				(type default)
			)
			(layer "F.SilkS")
		)
		(fp_line
			(start 2.500122 -2.500122)
			(end 2.500122 -2.015998)
			(stroke
				(width 0.1524)
				(type default)
			)
			(layer "F.SilkS")
		)
		(fp_line
			(start 2.015998 -2.500122)
			(end 2.500122 -2.500122)
			(stroke
				(width 0.1524)
				(type default)
			)
			(layer "F.SilkS")
		)
		(fp_line
			(start -2.500122 -2.500122)
			(end -2.015998 -2.500122)
			(stroke
				(width 0.1524)
				(type default)
			)
			(layer "F.SilkS")
		)
		(fp_line
			(start -2.500122 -2.015998)
			(end -2.500122 -2.500122)
			(stroke
				(width 0.1524)
				(type default)
			)
			(layer "F.SilkS")
		)
		(fp_line
			(start 2.8702 -1.778)
			(end 3.6322 -1.778)
			(stroke
				(width 0.1524)
				(type default)
			)
			(layer "F.SilkS")
		)
		(fp_line
			(start -3.2639 -0.1778)
			(end -2.8829 -0.1778)
			(stroke
				(width 0.1524)
				(type default)
			)
			(layer "F.SilkS")
		)
		(fp_line
			(start 2.8829 0.2032)
			(end 3.2639 0.2032)
			(stroke
				(width 0.1524)
				(type default)
			)
			(layer "F.SilkS")
		)
		(fp_line
			(start -3.6576 1.8034)
			(end -2.8956 1.8034)
			(stroke
				(width 0.1524)
				(type default)
			)
			(layer "F.SilkS")
		)
		(fp_line
			(start 2.500122 2.015998)
			(end 2.500122 2.500122)
			(stroke
				(width 0.1524)
				(type default)
			)
			(layer "F.SilkS")
		)
		(fp_line
			(start 2.500122 2.500122)
			(end 2.015998 2.500122)
			(stroke
				(width 0.1524)
				(type default)
			)
			(layer "F.SilkS")
		)
		(fp_line
			(start -2.015998 2.500122)
			(end -2.500122 2.500122)
			(stroke
				(width 0.1524)
				(type default)
			)
			(layer "F.SilkS")
		)
		(fp_line
			(start -2.500122 2.500122)
			(end -2.500122 2.018538)
			(stroke
				(width 0.1524)
				(type default)
			)
			(layer "F.SilkS")
		)
		(fp_line
			(start -0.2032 2.8829)
			(end -0.2032 3.2639)
			(stroke
				(width 0.1524)
				(type default)
			)
			(layer "F.SilkS")
		)
		(fp_line
			(start 1.778 3.6322)
			(end 1.778 2.8702)
			(stroke
				(width 0.1524)
				(type default)
			)
			(layer "F.SilkS")
		)
		(fp_poly
			(pts
				(xy -2.921 -1.800098) (xy -3.504184 -1.508506) (xy -3.504184 -2.09169)
			)
			(stroke
				(width 0)
				(type default)
			)
			(fill yes)
			(layer "F.SilkS")
		)
		(fp_line
			(start 0.1778 -3.2385)
			(end 0.1778 -2.8575)
			(stroke
				(width 0.1)
				(type default)
			)
			(layer "F.Fab")
		)
		(fp_line
			(start -1.8034 -2.8702)
			(end -1.8034 -3.6322)
			(stroke
				(width 0.1)
				(type default)
			)
			(layer "F.Fab")
		)
		(fp_line
			(start 2.500122 -2.500122)
			(end 2.500122 2.500122)
			(stroke
				(width 0.1)
				(type default)
			)
			(layer "F.Fab")
		)
		(fp_line
			(start -2.500122 -2.500122)
			(end 2.500122 -2.500122)
			(stroke
				(width 0.1)
				(type default)
			)
			(layer "F.Fab")
		)
		(fp_line
			(start 2.8702 -1.778)
			(end 3.6322 -1.778)
			(stroke
				(width 0.1)
				(type default)
			)
			(layer "F.Fab")
		)
		(fp_line
			(start -3.2639 -0.1778)
			(end -2.8829 -0.1778)
			(stroke
				(width 0.1)
				(type default)
			)
			(layer "F.Fab")
		)
		(fp_line
			(start 2.8829 0.2032)
			(end 3.2639 0.2032)
			(stroke
				(width 0.1)
				(type default)
			)
			(layer "F.Fab")
		)
		(fp_line
			(start -3.6576 1.8034)
			(end -2.8956 1.8034)
			(stroke
				(width 0.1)
				(type default)
			)
			(layer "F.Fab")
		)
		(fp_line
			(start 2.500122 2.500122)
			(end -2.500122 2.500122)
			(stroke
				(width 0.1)
				(type default)
			)
			(layer "F.Fab")
		)
		(fp_line
			(start -2.500122 2.500122)
			(end -2.500122 -2.500122)
			(stroke
				(width 0.1)
				(type default)
			)
			(layer "F.Fab")
		)
		(fp_line
			(start -0.2032 2.8829)
			(end -0.2032 3.2639)
			(stroke
				(width 0.1)
				(type default)
			)
			(layer "F.Fab")
		)
		(fp_line
			(start 1.778 3.6322)
			(end 1.778 2.8702)
			(stroke
				(width 0.1)
				(type default)
			)
			(layer "F.Fab")
		)
		(fp_poly
			(pts
				(xy -2.921 -1.800098) (xy -3.504184 -1.508506) (xy -3.504184 -2.09169)
			)
			(stroke
				(width 0)
				(type default)
			)
			(fill yes)
			(layer "F.Fab")
		)
		(fp_text user "31"
			(at 0.4318 -3.336036 90)
			(unlocked yes)
			(layer "F.SilkS")
			(effects
				(font
					(size 0.635 0.4064)
					(thickness 0.1524)
				)
				(justify left)
			)
		)
		(fp_text user "30"
			(at 3.223768 -3.0988 0)
			(unlocked yes)
			(layer "F.SilkS")
			(effects
				(font
					(size 0.635 0.4064)
					(thickness 0.1524)
				)
				(justify left)
			)
		)
		(fp_text user "40"
			(at -3.2004 -3.096768 90)
			(unlocked yes)
			(layer "F.SilkS")
			(effects
				(font
					(size 0.635 0.4064)
					(thickness 0.1524)
				)
				(justify left)
			)
		)
		(fp_text user "21"
			(at 3.208782 0.362712 0)
			(unlocked yes)
			(layer "F.SilkS")
			(effects
				(font
					(size 0.635 0.4064)
					(thickness 0.1524)
				)
				(justify left)
			)
		)
		(fp_text user "10"
			(at -3.253232 2.1336 0)
			(unlocked yes)
			(layer "F.SilkS")
			(effects
				(font
					(size 0.635 0.4064)
					(thickness 0.1524)
				)
				(justify left)
			)
		)
		(fp_text user "11"
			(at -2.51206 3.269234 90)
			(unlocked yes)
			(layer "F.SilkS")
			(effects
				(font
					(size 0.635 0.4064)
					(thickness 0.1524)
				)
				(justify left)
			)
		)
		(fp_text user "20"
			(at 0.911352 5.261102 90)
			(unlocked yes)
			(layer "F.SilkS")
			(effects
				(font
					(size 0.635 0.4064)
					(thickness 0.1524)
				)
				(justify left)
			)
		)
		(fp_text user "31"
			(at 1.8542 -3.172968 90)
			(unlocked yes)
			(layer "F.Fab")
			(effects
				(font
					(size 0.635 0.4064)
					(thickness 0.1524)
				)
				(justify left)
			)
		)
		(fp_text user "30"
			(at 3.223768 -3.0988 0)
			(unlocked yes)
			(layer "F.Fab")
			(effects
				(font
					(size 0.635 0.4064)
					(thickness 0.1524)
				)
				(justify left)
			)
		)
		(fp_text user "40"
			(at -3.2004 -3.096768 90)
			(unlocked yes)
			(layer "F.Fab")
			(effects
				(font
					(size 0.635 0.4064)
					(thickness 0.1524)
				)
				(justify left)
			)
		)
		(fp_text user "21"
			(at 3.274568 1.8796 0)
			(unlocked yes)
			(layer "F.Fab")
			(effects
				(font
					(size 0.635 0.4064)
					(thickness 0.1524)
				)
				(justify left)
			)
		)
		(fp_text user "10"
			(at -3.253232 2.1336 0)
			(unlocked yes)
			(layer "F.Fab")
			(effects
				(font
					(size 0.635 0.4064)
					(thickness 0.1524)
				)
				(justify left)
			)
		)
		(fp_text user "20"
			(at 2.0828 3.253232 90)
			(unlocked yes)
			(layer "F.Fab")
			(effects
				(font
					(size 0.635 0.4064)
					(thickness 0.1524)
				)
				(justify left)
			)
		)
		(fp_text user "11"
			(at -2.8702 3.278632 90)
			(unlocked yes)
			(layer "F.Fab")
			(effects
				(font
					(size 0.635 0.4064)
					(thickness 0.1524)
				)
				(justify left)
			)
		)
		(pad "1" smd rect
			(at -2.400046 -1.800098)
			(size 0.1778 0.6096)
			(layers "F.Cu" "F.Mask" "F.Paste")
			(net "P0V8_PEX3_PWM1")
		)
		(pad "2" smd rect
			(at -2.400046 -1.400048)
			(size 0.1778 0.6096)
			(layers "F.Cu" "F.Mask" "F.Paste")
			(net "P0V8_PEX3_PWM2")
		)
		(pad "3" smd rect
			(at -2.400046 -0.999998)
			(size 0.1778 0.6096)
			(layers "F.Cu" "F.Mask" "F.Paste")
			(net "NC_P0V8_PEX2_PWM3")
		)
		(pad "4" smd rect
			(at -2.400046 -0.599948)
			(size 0.1778 0.6096)
			(layers "F.Cu" "F.Mask" "F.Paste")
			(net "NC_P0V8_PEX2_PWM4")
		)
		(pad "5" smd rect
			(at -2.400046 -0.199898)
			(size 0.1778 0.6096)
			(layers "F.Cu" "F.Mask" "F.Paste")
			(net "NC_P0V8_PEX2_PWM5")
		)
		(pad "6" smd rect
			(at -2.400046 0.199898)
			(size 0.1778 0.6096)
			(layers "F.Cu" "F.Mask" "F.Paste")
			(net "NC_P0V8_PEX2_PWM6")
		)
		(pad "7" smd rect
			(at -2.400046 0.599948)
			(size 0.1778 0.6096)
			(layers "F.Cu" "F.Mask" "F.Paste")
			(net "P0V8_PEX2_PWM2")
		)
		(pad "8" smd rect
			(at -2.400046 0.999998)
			(size 0.1778 0.6096)
			(layers "F.Cu" "F.Mask" "F.Paste")
			(net "P0V8_PEX2_PWM1")
		)
		(pad "9" smd rect
			(at -2.400046 1.400048)
			(size 0.1778 0.6096)
			(layers "F.Cu" "F.Mask" "F.Paste")
			(net "SMB_VR_P0V8_PEX2_SDA")
		)
		(pad "10" smd rect
			(at -2.400046 1.800098)
			(size 0.1778 0.6096)
			(layers "F.Cu" "F.Mask" "F.Paste")
			(net "SMB_VR_P0V8_PEX2_SCL")
		)
		(pad "11" smd rect
			(at -1.800098 2.400046 90)
			(size 0.1778 0.6096)
			(layers "F.Cu" "F.Mask" "F.Paste")
			(net "P0V8_PEX2_SMBALERT")
		)
		(pad "12" smd rect
			(at -1.400048 2.400046 90)
			(size 0.1778 0.6096)
			(layers "F.Cu" "F.Mask" "F.Paste")
			(net "P0V8_PEX2_AVRRDY")
		)
		(pad "13" smd rect
			(at -0.999998 2.400046 90)
			(size 0.1778 0.6096)
			(layers "F.Cu" "F.Mask" "F.Paste")
			(net "FM_P0V8_PEX2_EN_R")
		)
		(pad "14" smd rect
			(at -0.599948 2.400046 90)
			(size 0.1778 0.6096)
			(layers "F.Cu" "F.Mask" "F.Paste")
			(net "P0V8_PEX2_VRHOT_R")
		)
		(pad "15" smd rect
			(at -0.199898 2.400046 90)
			(size 0.1778 0.6096)
			(layers "F.Cu" "F.Mask" "F.Paste")
			(net "P0V8_PEX2_PINALRT")
		)
		(pad "16" smd rect
			(at 0.199898 2.400046 90)
			(size 0.1778 0.6096)
			(layers "F.Cu" "F.Mask" "F.Paste")
			(net "P0V8_PEX3_BVRRDY")
		)
		(pad "17" smd rect
			(at 0.599948 2.400046 90)
			(size 0.1778 0.6096)
			(layers "F.Cu" "F.Mask" "F.Paste")
			(net "P0V8_PEX2_SVID")
		)
		(pad "18" smd rect
			(at 0.999998 2.400046 90)
			(size 0.1778 0.6096)
			(layers "F.Cu" "F.Mask" "F.Paste")
			(net "P0V8_PEX2_SVID")
		)
		(pad "19" smd rect
			(at 1.400048 2.400046 90)
			(size 0.1778 0.6096)
			(layers "F.Cu" "F.Mask" "F.Paste")
			(net "NC_P0V8_PEX2_SVID_ALERT_N_R")
		)
		(pad "20" smd rect
			(at 1.800098 2.400046 90)
			(size 0.1778 0.6096)
			(layers "F.Cu" "F.Mask" "F.Paste")
			(net "FM_P0V8_PEX3_EN_R")
		)
		(pad "21" smd rect
			(at 2.400046 1.800098)
			(size 0.1778 0.6096)
			(layers "F.Cu" "F.Mask" "F.Paste")
			(net "P0V8_PEX2_VSEN2")
		)
		(pad "22" smd rect
			(at 2.400046 1.400048)
			(size 0.1778 0.6096)
			(layers "F.Cu" "F.Mask" "F.Paste")
			(net "SH_P0V8_PEX2_RGND2")
		)
		(pad "23" smd rect
			(at 2.400046 0.999998)
			(size 0.1778 0.6096)
			(layers "F.Cu" "F.Mask" "F.Paste")
			(net "P0V8_PEX2_ISEN1")
		)
		(pad "24" smd rect
			(at 2.400046 0.599948)
			(size 0.1778 0.6096)
			(layers "F.Cu" "F.Mask" "F.Paste")
			(net "P0V8_PEX2_ISEN2")
		)
		(pad "25" smd rect
			(at 2.400046 0.199898)
			(size 0.1778 0.6096)
			(layers "F.Cu" "F.Mask" "F.Paste")
			(net "NC_P0V8_PEX2_ISEN6")
		)
		(pad "26" smd rect
			(at 2.400046 -0.199898)
			(size 0.1778 0.6096)
			(layers "F.Cu" "F.Mask" "F.Paste")
			(net "NC_P0V8_PEX2_ISEN5")
		)
		(pad "27" smd rect
			(at 2.400046 -0.599948)
			(size 0.1778 0.6096)
			(layers "F.Cu" "F.Mask" "F.Paste")
			(net "NC_P0V8_PEX2_ISEN4")
		)
		(pad "28" smd rect
			(at 2.400046 -0.999998)
			(size 0.1778 0.6096)
			(layers "F.Cu" "F.Mask" "F.Paste")
			(net "NC_P0V8_PEX2_ISEN3")
		)
		(pad "29" smd rect
			(at 2.400046 -1.400048)
			(size 0.1778 0.6096)
			(layers "F.Cu" "F.Mask" "F.Paste")
			(net "P0V8_PEX3_ISEN2")
		)
		(pad "30" smd rect
			(at 2.400046 -1.800098)
			(size 0.1778 0.6096)
			(layers "F.Cu" "F.Mask" "F.Paste")
			(net "P0V8_PEX3_ISEN1")
		)
		(pad "31" smd rect
			(at 1.800098 -2.400046 90)
			(size 0.1778 0.6096)
			(layers "F.Cu" "F.Mask" "F.Paste")
			(net "SH_P0V8_PEX3_RGND3")
		)
		(pad "32" smd rect
			(at 1.400048 -2.400046 90)
			(size 0.1778 0.6096)
			(layers "F.Cu" "F.Mask" "F.Paste")
			(net "P0V8_PEX3_VSEN3")
		)
		(pad "33" smd rect
			(at 0.999998 -2.400046 90)
			(size 0.1778 0.6096)
			(layers "F.Cu" "F.Mask" "F.Paste")
			(net "P0V8_PEX2_VR_CONFIG")
		)
		(pad "34" smd rect
			(at 0.599948 -2.400046 90)
			(size 0.1778 0.6096)
			(layers "F.Cu" "F.Mask" "F.Paste")
			(net "P0V8_PEX2_ADDR")
		)
		(pad "35" smd rect
			(at 0.199898 -2.400046 90)
			(size 0.1778 0.6096)
			(layers "F.Cu" "F.Mask" "F.Paste")
			(net "P0V8_PEX2_TSEN_R")
		)
		(pad "36" smd rect
			(at -0.199898 -2.400046 90)
			(size 0.1778 0.6096)
			(layers "F.Cu" "F.Mask" "F.Paste")
			(net "P0V8_PEX3_TSEN_R")
		)
		(pad "37" smd rect
			(at -0.599948 -2.400046 90)
			(size 0.1778 0.6096)
			(layers "F.Cu" "F.Mask" "F.Paste")
			(net "P0V8_PEX2_IINSEN")
		)
		(pad "38" smd rect
			(at -0.999998 -2.400046 90)
			(size 0.1778 0.6096)
			(layers "F.Cu" "F.Mask" "F.Paste")
			(net "P0V8_PEX2_VINSEN")
		)
		(pad "39" smd rect
			(at -1.400048 -2.400046 90)
			(size 0.1778 0.6096)
			(layers "F.Cu" "F.Mask" "F.Paste")
			(net "P0V8_PEX2_VDD")
		)
		(pad "40" smd rect
			(at -1.800098 -2.400046 90)
			(size 0.1778 0.6096)
			(layers "F.Cu" "F.Mask" "F.Paste")
			(net "P0V8_PEX2_VREF")
		)
		(pad "TH" smd rect
			(at 0 0 90)
			(size 3.6576 3.6576)
			(layers "F.Cu" "F.Mask" "F.Paste")
			(net "GND")
		)
		(zone
			(layer "F.Cu")
			(hatch none 0.5)
			(connect_pads
				(clearance 0)
			)
			(min_thickness 0.25)
			(keepout
				(tracks not_allowed)
				(vias allowed)
				(pads allowed)
				(copperpour not_allowed)
				(footprints allowed)
			)
			(placement
				(enabled no)
				(sheetname "")
			)
			(fill
				(thermal_gap 0.5)
				(thermal_bridge_width 0.5)
				(island_removal_mode 0)
			)
			(polygon
				(pts
					(xy 350.943926 -256.362962) (xy 350.943926 -260.426962) (xy 355.007926 -260.426962) (xy 355.007926 -256.362962)
					(xy 351.121726 -256.362962) (xy 351.121726 -256.515362) (xy 354.855526 -256.515362) (xy 354.855526 -260.274562)
					(xy 351.096326 -260.274562) (xy 351.096326 -256.362962)
				)
			)
		)
	)
	(footprint ""
		(layer "F.Cu")
		(at 29.541978 -305.648106 -135)
		(property "Reference" "R1241"
			(at 0 0 225)
			(layer "F.SilkS")
			(hide yes)
			(effects
				(font
					(size 1.27 1.27)
				)
			)
		)
		(property "Value" ""
			(at 0 0 225)
			(layer "F.Fab")
			(effects
				(font
					(size 1.27 1.27)
				)
			)
		)
		(duplicate_pad_numbers_are_jumpers no)
		(fp_line
			(start 0.787389 0.406267)
			(end -0.787389 0.406267)
			(stroke
				(width 0.1524)
				(type default)
			)
			(layer "F.SilkS")
		)
		(fp_line
			(start 0.787389 -0.406267)
			(end 0.787389 0.406267)
			(stroke
				(width 0.1524)
				(type default)
			)
			(layer "F.SilkS")
		)
		(fp_line
			(start -0.787389 0.406267)
			(end -0.787389 -0.406267)
			(stroke
				(width 0.1524)
				(type default)
			)
			(layer "F.SilkS")
		)
		(fp_line
			(start -0.787389 -0.406267)
			(end 0.787389 -0.406267)
			(stroke
				(width 0.1524)
				(type default)
			)
			(layer "F.SilkS")
		)
		(fp_line
			(start 0.679446 0.30479)
			(end 0.120515 0.30479)
			(stroke
				(width 0.1)
				(type default)
			)
			(layer "F.Fab")
		)
		(fp_line
			(start 0.120515 0.30479)
			(end 0.120335 0.279466)
			(stroke
				(width 0.1)
				(type default)
			)
			(layer "F.Fab")
		)
		(fp_line
			(start 0.120335 0.279466)
			(end -0.120695 0.279466)
			(stroke
				(width 0.1)
				(type default)
			)
			(layer "F.Fab")
		)
		(fp_line
			(start 0.679446 -0.30479)
			(end 0.679446 0.30479)
			(stroke
				(width 0.1)
				(type default)
			)
			(layer "F.Fab")
		)
		(fp_line
			(start -0.120515 0.30479)
			(end -0.679446 0.30479)
			(stroke
				(width 0.1)
				(type default)
			)
			(layer "F.Fab")
		)
		(fp_line
			(start -0.120695 0.279466)
			(end -0.120515 0.30479)
			(stroke
				(width 0.1)
				(type default)
			)
			(layer "F.Fab")
		)
		(fp_line
			(start 0.120695 -0.279466)
			(end 0.120515 -0.30479)
			(stroke
				(width 0.1)
				(type default)
			)
			(layer "F.Fab")
		)
		(fp_line
			(start 0.120515 -0.30479)
			(end 0.679446 -0.30479)
			(stroke
				(width 0.1)
				(type default)
			)
			(layer "F.Fab")
		)
		(fp_line
			(start -0.679446 0.30479)
			(end -0.679446 -0.305149)
			(stroke
				(width 0.1)
				(type default)
			)
			(layer "F.Fab")
		)
		(fp_line
			(start -0.120695 -0.279466)
			(end 0.120695 -0.279466)
			(stroke
				(width 0.1)
				(type default)
			)
			(layer "F.Fab")
		)
		(fp_line
			(start -0.120695 -0.304969)
			(end -0.120695 -0.279466)
			(stroke
				(width 0.1)
				(type default)
			)
			(layer "F.Fab")
		)
		(fp_line
			(start -0.679446 -0.305149)
			(end -0.120695 -0.304969)
			(stroke
				(width 0.1)
				(type default)
			)
			(layer "F.Fab")
		)
		(pad "1" smd circle
			(at -0.40005 0 225)
			(size 0 0)
			(layers "F.Cu" "F.Mask" "F.Paste")
			(net "PEX0_DFT_IDDT")
		)
		(pad "2" smd circle
			(at 0.40005 0 225)
			(size 0 0)
			(layers "F.Cu" "F.Mask" "F.Paste")
			(net "P1V8_PEX")
		)
	)
	(footprint ""
		(layer "F.Cu")
		(at 139.756642 -17.419574 180)
		(property "Reference" "R1660"
			(at 0 0 180)
			(layer "F.SilkS")
			(hide yes)
			(effects
				(font
					(size 1.27 1.27)
				)
			)
		)
		(property "Value" ""
			(at 0 0 180)
			(layer "F.Fab")
			(effects
				(font
					(size 1.27 1.27)
				)
			)
		)
		(duplicate_pad_numbers_are_jumpers no)
		(fp_line
			(start 0.7874 0.4064)
			(end -0.7874 0.4064)
			(stroke
				(width 0.1524)
				(type default)
			)
			(layer "F.SilkS")
		)
		(fp_line
			(start 0.7874 -0.4064)
			(end 0.7874 0.4064)
			(stroke
				(width 0.1524)
				(type default)
			)
			(layer "F.SilkS")
		)
		(fp_line
			(start -0.7874 0.4064)
			(end -0.7874 -0.4064)
			(stroke
				(width 0.1524)
				(type default)
			)
			(layer "F.SilkS")
		)
		(fp_line
			(start -0.7874 -0.4064)
			(end 0.7874 -0.4064)
			(stroke
				(width 0.1524)
				(type default)
			)
			(layer "F.SilkS")
		)
		(fp_line
			(start 0.67945 0.3048)
			(end 0.120396 0.3048)
			(stroke
				(width 0.1)
				(type default)
			)
			(layer "F.Fab")
		)
		(fp_line
			(start 0.67945 -0.3048)
			(end 0.67945 0.3048)
			(stroke
				(width 0.1)
				(type default)
			)
			(layer "F.Fab")
		)
		(fp_line
			(start 0.12065 -0.2794)
			(end 0.12065 -0.3048)
			(stroke
				(width 0.1)
				(type default)
			)
			(layer "F.Fab")
		)
		(fp_line
			(start 0.12065 -0.3048)
			(end 0.67945 -0.3048)
			(stroke
				(width 0.1)
				(type default)
			)
			(layer "F.Fab")
		)
		(fp_line
			(start 0.120396 0.3048)
			(end 0.120396 0.2794)
			(stroke
				(width 0.1)
				(type default)
			)
			(layer "F.Fab")
		)
		(fp_line
			(start 0.120396 0.2794)
			(end -0.12065 0.2794)
			(stroke
				(width 0.1)
				(type default)
			)
			(layer "F.Fab")
		)
		(fp_line
			(start -0.12065 0.3048)
			(end -0.67945 0.3048)
			(stroke
				(width 0.1)
				(type default)
			)
			(layer "F.Fab")
		)
		(fp_line
			(start -0.12065 0.2794)
			(end -0.12065 0.3048)
			(stroke
				(width 0.1)
				(type default)
			)
			(layer "F.Fab")
		)
		(fp_line
			(start -0.12065 -0.2794)
			(end 0.12065 -0.2794)
			(stroke
				(width 0.1)
				(type default)
			)
			(layer "F.Fab")
		)
		(fp_line
			(start -0.12065 -0.305054)
			(end -0.12065 -0.2794)
			(stroke
				(width 0.1)
				(type default)
			)
			(layer "F.Fab")
		)
		(fp_line
			(start -0.67945 0.3048)
			(end -0.67945 -0.305054)
			(stroke
				(width 0.1)
				(type default)
			)
			(layer "F.Fab")
		)
		(fp_line
			(start -0.67945 -0.305054)
			(end -0.12065 -0.305054)
			(stroke
				(width 0.1)
				(type default)
			)
			(layer "F.Fab")
		)
		(pad "1" smd circle
			(at -0.40005 0 180)
			(size 0 0)
			(layers "F.Cu" "F.Mask" "F.Paste")
			(net "P3V3_SSD4")
		)
		(pad "2" smd circle
			(at 0.40005 0 180)
			(size 0 0)
			(layers "F.Cu" "F.Mask" "F.Paste")
			(net "SMB_ISO_SSD4_SCL")
		)
	)
	(footprint ""
		(layer "F.Cu")
		(at 326.517 -233.553 180)
		(property "Reference" "R4386"
			(at 0 0 180)
			(layer "F.SilkS")
			(hide yes)
			(effects
				(font
					(size 1.27 1.27)
				)
			)
		)
		(property "Value" ""
			(at 0 0 180)
			(layer "F.Fab")
			(effects
				(font
					(size 1.27 1.27)
				)
			)
		)
		(duplicate_pad_numbers_are_jumpers no)
		(fp_line
			(start 0.7874 0.4064)
			(end -0.7874 0.4064)
			(stroke
				(width 0.1524)
				(type default)
			)
			(layer "F.SilkS")
		)
		(fp_line
			(start 0.7874 -0.4064)
			(end 0.7874 0.4064)
			(stroke
				(width 0.1524)
				(type default)
			)
			(layer "F.SilkS")
		)
		(fp_line
			(start -0.7874 0.4064)
			(end -0.7874 -0.4064)
			(stroke
				(width 0.1524)
				(type default)
			)
			(layer "F.SilkS")
		)
		(fp_line
			(start -0.7874 -0.4064)
			(end 0.7874 -0.4064)
			(stroke
				(width 0.1524)
				(type default)
			)
			(layer "F.SilkS")
		)
		(fp_line
			(start 0.67945 0.3048)
			(end 0.120396 0.3048)
			(stroke
				(width 0.1)
				(type default)
			)
			(layer "F.Fab")
		)
		(fp_line
			(start 0.67945 -0.3048)
			(end 0.67945 0.3048)
			(stroke
				(width 0.1)
				(type default)
			)
			(layer "F.Fab")
		)
		(fp_line
			(start 0.12065 -0.2794)
			(end 0.12065 -0.3048)
			(stroke
				(width 0.1)
				(type default)
			)
			(layer "F.Fab")
		)
		(fp_line
			(start 0.12065 -0.3048)
			(end 0.67945 -0.3048)
			(stroke
				(width 0.1)
				(type default)
			)
			(layer "F.Fab")
		)
		(fp_line
			(start 0.120396 0.3048)
			(end 0.120396 0.2794)
			(stroke
				(width 0.1)
				(type default)
			)
			(layer "F.Fab")
		)
		(fp_line
			(start 0.120396 0.2794)
			(end -0.12065 0.2794)
			(stroke
				(width 0.1)
				(type default)
			)
			(layer "F.Fab")
		)
		(fp_line
			(start -0.12065 0.3048)
			(end -0.67945 0.3048)
			(stroke
				(width 0.1)
				(type default)
			)
			(layer "F.Fab")
		)
		(fp_line
			(start -0.12065 0.2794)
			(end -0.12065 0.3048)
			(stroke
				(width 0.1)
				(type default)
			)
			(layer "F.Fab")
		)
		(fp_line
			(start -0.12065 -0.2794)
			(end 0.12065 -0.2794)
			(stroke
				(width 0.1)
				(type default)
			)
			(layer "F.Fab")
		)
		(fp_line
			(start -0.12065 -0.305054)
			(end -0.12065 -0.2794)
			(stroke
				(width 0.1)
				(type default)
			)
			(layer "F.Fab")
		)
		(fp_line
			(start -0.67945 0.3048)
			(end -0.67945 -0.305054)
			(stroke
				(width 0.1)
				(type default)
			)
			(layer "F.Fab")
		)
		(fp_line
			(start -0.67945 -0.305054)
			(end -0.12065 -0.305054)
			(stroke
				(width 0.1)
				(type default)
			)
			(layer "F.Fab")
		)
		(pad "1" smd circle
			(at -0.40005 0 180)
			(size 0 0)
			(layers "F.Cu" "F.Mask" "F.Paste")
			(net "RST_PEX_SYS_BUF_N")
		)
		(pad "2" smd circle
			(at 0.40005 0 180)
			(size 0 0)
			(layers "F.Cu" "F.Mask" "F.Paste")
			(net "RST_PEX_SYS_BUF_R_N")
		)
	)
	(footprint ""
		(layer "F.Cu")
		(at 137.047478 -20.35556)
		(property "Reference" "C3906"
			(at 0 0 0)
			(layer "F.SilkS")
			(hide yes)
			(effects
				(font
					(size 1.27 1.27)
				)
			)
		)
		(property "Value" ""
			(at 0 0 0)
			(layer "F.Fab")
			(effects
				(font
					(size 1.27 1.27)
				)
			)
		)
		(duplicate_pad_numbers_are_jumpers no)
		(fp_line
			(start -0.7874 -0.4064)
			(end 0.7874 -0.4064)
			(stroke
				(width 0.1524)
				(type default)
			)
			(layer "F.SilkS")
		)
		(fp_line
			(start -0.7874 0.4064)
			(end -0.7874 -0.4064)
			(stroke
				(width 0.1524)
				(type default)
			)
			(layer "F.SilkS")
		)
		(fp_line
			(start 0.7874 -0.4064)
			(end 0.7874 0.4064)
			(stroke
				(width 0.1524)
				(type default)
			)
			(layer "F.SilkS")
		)
		(fp_line
			(start 0.7874 0.4064)
			(end -0.7874 0.4064)
			(stroke
				(width 0.1524)
				(type default)
			)
			(layer "F.SilkS")
		)
		(fp_line
			(start -0.67945 -0.305054)
			(end -0.12065 -0.305054)
			(stroke
				(width 0.1)
				(type default)
			)
			(layer "F.Fab")
		)
		(fp_line
			(start -0.67945 0.3048)
			(end -0.67945 -0.305054)
			(stroke
				(width 0.1)
				(type default)
			)
			(layer "F.Fab")
		)
		(fp_line
			(start -0.12065 -0.305054)
			(end -0.12065 -0.2794)
			(stroke
				(width 0.1)
				(type default)
			)
			(layer "F.Fab")
		)
		(fp_line
			(start -0.12065 -0.2794)
			(end 0.12065 -0.2794)
			(stroke
				(width 0.1)
				(type default)
			)
			(layer "F.Fab")
		)
		(fp_line
			(start -0.12065 0.2794)
			(end -0.12065 0.3048)
			(stroke
				(width 0.1)
				(type default)
			)
			(layer "F.Fab")
		)
		(fp_line
			(start -0.12065 0.3048)
			(end -0.67945 0.3048)
			(stroke
				(width 0.1)
				(type default)
			)
			(layer "F.Fab")
		)
		(fp_line
			(start 0.120396 0.2794)
			(end -0.12065 0.2794)
			(stroke
				(width 0.1)
				(type default)
			)
			(layer "F.Fab")
		)
		(fp_line
			(start 0.120396 0.3048)
			(end 0.120396 0.2794)
			(stroke
				(width 0.1)
				(type default)
			)
			(layer "F.Fab")
		)
		(fp_line
			(start 0.12065 -0.3048)
			(end 0.67945 -0.3048)
			(stroke
				(width 0.1)
				(type default)
			)
			(layer "F.Fab")
		)
		(fp_line
			(start 0.12065 -0.2794)
			(end 0.12065 -0.3048)
			(stroke
				(width 0.1)
				(type default)
			)
			(layer "F.Fab")
		)
		(fp_line
			(start 0.67945 -0.3048)
			(end 0.67945 0.3048)
			(stroke
				(width 0.1)
				(type default)
			)
			(layer "F.Fab")
		)
		(fp_line
			(start 0.67945 0.3048)
			(end 0.120396 0.3048)
			(stroke
				(width 0.1)
				(type default)
			)
			(layer "F.Fab")
		)
		(pad "1" smd circle
			(at -0.40005 0)
			(size 0 0)
			(layers "F.Cu" "F.Mask" "F.Paste")
			(net "P12V_SSD4")
		)
		(pad "2" smd circle
			(at 0.40005 0)
			(size 0 0)
			(layers "F.Cu" "F.Mask" "F.Paste")
			(net "GND")
		)
	)
	(footprint ""
		(layer "F.Cu")
		(at 379.59411 -35.264852)
		(property "Reference" "R5700"
			(at 0 0 0)
			(layer "F.SilkS")
			(hide yes)
			(effects
				(font
					(size 1.27 1.27)
				)
			)
		)
		(property "Value" ""
			(at 0 0 0)
			(layer "F.Fab")
			(effects
				(font
					(size 1.27 1.27)
				)
			)
		)
		(duplicate_pad_numbers_are_jumpers no)
		(fp_line
			(start -0.7874 -0.4064)
			(end 0.7874 -0.4064)
			(stroke
				(width 0.1524)
				(type default)
			)
			(layer "F.SilkS")
		)
		(fp_line
			(start -0.7874 0.4064)
			(end -0.7874 -0.4064)
			(stroke
				(width 0.1524)
				(type default)
			)
			(layer "F.SilkS")
		)
		(fp_line
			(start 0.7874 -0.4064)
			(end 0.7874 0.4064)
			(stroke
				(width 0.1524)
				(type default)
			)
			(layer "F.SilkS")
		)
		(fp_line
			(start 0.7874 0.4064)
			(end -0.7874 0.4064)
			(stroke
				(width 0.1524)
				(type default)
			)
			(layer "F.SilkS")
		)
		(fp_line
			(start -0.67945 -0.305054)
			(end -0.12065 -0.305054)
			(stroke
				(width 0.1)
				(type default)
			)
			(layer "F.Fab")
		)
		(fp_line
			(start -0.67945 0.3048)
			(end -0.67945 -0.305054)
			(stroke
				(width 0.1)
				(type default)
			)
			(layer "F.Fab")
		)
		(fp_line
			(start -0.12065 -0.305054)
			(end -0.12065 -0.2794)
			(stroke
				(width 0.1)
				(type default)
			)
			(layer "F.Fab")
		)
		(fp_line
			(start -0.12065 -0.2794)
			(end 0.12065 -0.2794)
			(stroke
				(width 0.1)
				(type default)
			)
			(layer "F.Fab")
		)
		(fp_line
			(start -0.12065 0.2794)
			(end -0.12065 0.3048)
			(stroke
				(width 0.1)
				(type default)
			)
			(layer "F.Fab")
		)
		(fp_line
			(start -0.12065 0.3048)
			(end -0.67945 0.3048)
			(stroke
				(width 0.1)
				(type default)
			)
			(layer "F.Fab")
		)
		(fp_line
			(start 0.120396 0.2794)
			(end -0.12065 0.2794)
			(stroke
				(width 0.1)
				(type default)
			)
			(layer "F.Fab")
		)
		(fp_line
			(start 0.120396 0.3048)
			(end 0.120396 0.2794)
			(stroke
				(width 0.1)
				(type default)
			)
			(layer "F.Fab")
		)
		(fp_line
			(start 0.12065 -0.3048)
			(end 0.67945 -0.3048)
			(stroke
				(width 0.1)
				(type default)
			)
			(layer "F.Fab")
		)
		(fp_line
			(start 0.12065 -0.2794)
			(end 0.12065 -0.3048)
			(stroke
				(width 0.1)
				(type default)
			)
			(layer "F.Fab")
		)
		(fp_line
			(start 0.67945 -0.3048)
			(end 0.67945 0.3048)
			(stroke
				(width 0.1)
				(type default)
			)
			(layer "F.Fab")
		)
		(fp_line
			(start 0.67945 0.3048)
			(end 0.120396 0.3048)
			(stroke
				(width 0.1)
				(type default)
			)
			(layer "F.Fab")
		)
		(pad "1" smd circle
			(at -0.40005 0)
			(size 0 0)
			(layers "F.Cu" "F.Mask" "F.Paste")
			(net "RST_SMB_SSD13_ISO_N")
		)
		(pad "2" smd circle
			(at 0.40005 0)
			(size 0 0)
			(layers "F.Cu" "F.Mask" "F.Paste")
			(net "GND")
		)
	)
	(footprint ""
		(layer "F.Cu")
		(at 484.109776 -522.077696 180)
		(property "Reference" "SCREW_SSD7_2"
			(at -5.207 -1.402334 0)
			(unlocked yes)
			(layer "B.SilkS")
			(effects
				(font
					(size 0.7874 0.5842)
					(thickness 0.1524)
				)
				(justify mirror)
			)
		)
		(property "Value" ""
			(at 0 0 180)
			(layer "F.Fab")
			(effects
				(font
					(size 1.27 1.27)
				)
			)
		)
		(duplicate_pad_numbers_are_jumpers no)
		(pad "1" thru_hole circle
			(at 0 0 180)
			(size 0.4572 0.4572)
			(drill 0.2032)
			(layers "*.Cu" "*.Mask")
			(remove_unused_layers no)
			(net "Net_9129")
			(clearance 0.127)
			(thermal_gap 0.127)
			(padstack
				(mode front_inner_back)
				(layer "Inner"
					(shape circle)
					(size 0.4572 0.4572)
					(clearance 0.127)
				)
				(layer "B.Cu"
					(shape circle)
					(size 0.508 0.508)
					(clearance 0.1016)
				)
			)
		)
	)
	(footprint ""
		(layer "F.Cu")
		(at 349.907098 -285.088584 90)
		(property "Reference" "PC154"
			(at 0 0 90)
			(layer "F.SilkS")
			(hide yes)
			(effects
				(font
					(size 1.27 1.27)
				)
			)
		)
		(property "Value" ""
			(at 0 0 90)
			(layer "F.Fab")
			(effects
				(font
					(size 1.27 1.27)
				)
			)
		)
		(duplicate_pad_numbers_are_jumpers no)
		(fp_line
			(start 0.7874 -0.4064)
			(end 0.7874 0.4064)
			(stroke
				(width 0.1524)
				(type default)
			)
			(layer "F.SilkS")
		)
		(fp_line
			(start -0.7874 -0.4064)
			(end 0.7874 -0.4064)
			(stroke
				(width 0.1524)
				(type default)
			)
			(layer "F.SilkS")
		)
		(fp_line
			(start 0.7874 0.4064)
			(end -0.7874 0.4064)
			(stroke
				(width 0.1524)
				(type default)
			)
			(layer "F.SilkS")
		)
		(fp_line
			(start -0.7874 0.4064)
			(end -0.7874 -0.4064)
			(stroke
				(width 0.1524)
				(type default)
			)
			(layer "F.SilkS")
		)
		(fp_line
			(start -0.12065 -0.305054)
			(end -0.12065 -0.2794)
			(stroke
				(width 0.1)
				(type default)
			)
			(layer "F.Fab")
		)
		(fp_line
			(start -0.67945 -0.305054)
			(end -0.12065 -0.305054)
			(stroke
				(width 0.1)
				(type default)
			)
			(layer "F.Fab")
		)
		(fp_line
			(start 0.67945 -0.3048)
			(end 0.67945 0.3048)
			(stroke
				(width 0.1)
				(type default)
			)
			(layer "F.Fab")
		)
		(fp_line
			(start 0.12065 -0.3048)
			(end 0.67945 -0.3048)
			(stroke
				(width 0.1)
				(type default)
			)
			(layer "F.Fab")
		)
		(fp_line
			(start 0.12065 -0.2794)
			(end 0.12065 -0.3048)
			(stroke
				(width 0.1)
				(type default)
			)
			(layer "F.Fab")
		)
		(fp_line
			(start -0.12065 -0.2794)
			(end 0.12065 -0.2794)
			(stroke
				(width 0.1)
				(type default)
			)
			(layer "F.Fab")
		)
		(fp_line
			(start 0.120396 0.2794)
			(end -0.12065 0.2794)
			(stroke
				(width 0.1)
				(type default)
			)
			(layer "F.Fab")
		)
		(fp_line
			(start -0.12065 0.2794)
			(end -0.12065 0.3048)
			(stroke
				(width 0.1)
				(type default)
			)
			(layer "F.Fab")
		)
		(fp_line
			(start 0.67945 0.3048)
			(end 0.120396 0.3048)
			(stroke
				(width 0.1)
				(type default)
			)
			(layer "F.Fab")
		)
		(fp_line
			(start 0.120396 0.3048)
			(end 0.120396 0.2794)
			(stroke
				(width 0.1)
				(type default)
			)
			(layer "F.Fab")
		)
		(fp_line
			(start -0.12065 0.3048)
			(end -0.67945 0.3048)
			(stroke
				(width 0.1)
				(type default)
			)
			(layer "F.Fab")
		)
		(fp_line
			(start -0.67945 0.3048)
			(end -0.67945 -0.305054)
			(stroke
				(width 0.1)
				(type default)
			)
			(layer "F.Fab")
		)
		(pad "1" smd circle
			(at -0.40005 0 90)
			(size 0 0)
			(layers "F.Cu" "F.Mask" "F.Paste")
			(net "P0V8_PEX2_PVCC")
		)
		(pad "2" smd circle
			(at 0.40005 0 90)
			(size 0 0)
			(layers "F.Cu" "F.Mask" "F.Paste")
			(net "GND")
		)
	)
	(footprint ""
		(layer "F.Cu")
		(at 168.343834 -43.85691)
		(property "Reference" "R563"
			(at 0 0 0)
			(layer "F.SilkS")
			(hide yes)
			(effects
				(font
					(size 1.27 1.27)
				)
			)
		)
		(property "Value" ""
			(at 0 0 0)
			(layer "F.Fab")
			(effects
				(font
					(size 1.27 1.27)
				)
			)
		)
		(duplicate_pad_numbers_are_jumpers no)
		(fp_line
			(start -0.7874 -0.4064)
			(end 0.7874 -0.4064)
			(stroke
				(width 0.1524)
				(type default)
			)
			(layer "F.SilkS")
		)
		(fp_line
			(start -0.7874 0.4064)
			(end -0.7874 -0.4064)
			(stroke
				(width 0.1524)
				(type default)
			)
			(layer "F.SilkS")
		)
		(fp_line
			(start 0.7874 -0.4064)
			(end 0.7874 0.4064)
			(stroke
				(width 0.1524)
				(type default)
			)
			(layer "F.SilkS")
		)
		(fp_line
			(start 0.7874 0.4064)
			(end -0.7874 0.4064)
			(stroke
				(width 0.1524)
				(type default)
			)
			(layer "F.SilkS")
		)
		(fp_line
			(start -0.67945 -0.305054)
			(end -0.12065 -0.305054)
			(stroke
				(width 0.1)
				(type default)
			)
			(layer "F.Fab")
		)
		(fp_line
			(start -0.67945 0.3048)
			(end -0.67945 -0.305054)
			(stroke
				(width 0.1)
				(type default)
			)
			(layer "F.Fab")
		)
		(fp_line
			(start -0.12065 -0.305054)
			(end -0.12065 -0.2794)
			(stroke
				(width 0.1)
				(type default)
			)
			(layer "F.Fab")
		)
		(fp_line
			(start -0.12065 -0.2794)
			(end 0.12065 -0.2794)
			(stroke
				(width 0.1)
				(type default)
			)
			(layer "F.Fab")
		)
		(fp_line
			(start -0.12065 0.2794)
			(end -0.12065 0.3048)
			(stroke
				(width 0.1)
				(type default)
			)
			(layer "F.Fab")
		)
		(fp_line
			(start -0.12065 0.3048)
			(end -0.67945 0.3048)
			(stroke
				(width 0.1)
				(type default)
			)
			(layer "F.Fab")
		)
		(fp_line
			(start 0.120396 0.2794)
			(end -0.12065 0.2794)
			(stroke
				(width 0.1)
				(type default)
			)
			(layer "F.Fab")
		)
		(fp_line
			(start 0.120396 0.3048)
			(end 0.120396 0.2794)
			(stroke
				(width 0.1)
				(type default)
			)
			(layer "F.Fab")
		)
		(fp_line
			(start 0.12065 -0.3048)
			(end 0.67945 -0.3048)
			(stroke
				(width 0.1)
				(type default)
			)
			(layer "F.Fab")
		)
		(fp_line
			(start 0.12065 -0.2794)
			(end 0.12065 -0.3048)
			(stroke
				(width 0.1)
				(type default)
			)
			(layer "F.Fab")
		)
		(fp_line
			(start 0.67945 -0.3048)
			(end 0.67945 0.3048)
			(stroke
				(width 0.1)
				(type default)
			)
			(layer "F.Fab")
		)
		(fp_line
			(start 0.67945 0.3048)
			(end 0.120396 0.3048)
			(stroke
				(width 0.1)
				(type default)
			)
			(layer "F.Fab")
		)
		(pad "1" smd circle
			(at -0.40005 0)
			(size 0 0)
			(layers "F.Cu" "F.Mask" "F.Paste")
			(net "SSD5_ADC_A1")
		)
		(pad "2" smd circle
			(at 0.40005 0)
			(size 0 0)
			(layers "F.Cu" "F.Mask" "F.Paste")
			(net "GND")
		)
	)
	(footprint ""
		(layer "F.Cu")
		(at 119.061484 -284.834838 90)
		(property "Reference" "PC92"
			(at 0 0 90)
			(layer "F.SilkS")
			(hide yes)
			(effects
				(font
					(size 1.27 1.27)
				)
			)
		)
		(property "Value" ""
			(at 0 0 90)
			(layer "F.Fab")
			(effects
				(font
					(size 1.27 1.27)
				)
			)
		)
		(duplicate_pad_numbers_are_jumpers no)
		(fp_line
			(start 0.7874 -0.4064)
			(end 0.7874 0.4064)
			(stroke
				(width 0.1524)
				(type default)
			)
			(layer "F.SilkS")
		)
		(fp_line
			(start -0.7874 -0.4064)
			(end 0.7874 -0.4064)
			(stroke
				(width 0.1524)
				(type default)
			)
			(layer "F.SilkS")
		)
		(fp_line
			(start 0.7874 0.4064)
			(end -0.7874 0.4064)
			(stroke
				(width 0.1524)
				(type default)
			)
			(layer "F.SilkS")
		)
		(fp_line
			(start -0.7874 0.4064)
			(end -0.7874 -0.4064)
			(stroke
				(width 0.1524)
				(type default)
			)
			(layer "F.SilkS")
		)
		(fp_line
			(start -0.12065 -0.305054)
			(end -0.12065 -0.2794)
			(stroke
				(width 0.1)
				(type default)
			)
			(layer "F.Fab")
		)
		(fp_line
			(start -0.67945 -0.305054)
			(end -0.12065 -0.305054)
			(stroke
				(width 0.1)
				(type default)
			)
			(layer "F.Fab")
		)
		(fp_line
			(start 0.67945 -0.3048)
			(end 0.67945 0.3048)
			(stroke
				(width 0.1)
				(type default)
			)
			(layer "F.Fab")
		)
		(fp_line
			(start 0.12065 -0.3048)
			(end 0.67945 -0.3048)
			(stroke
				(width 0.1)
				(type default)
			)
			(layer "F.Fab")
		)
		(fp_line
			(start 0.12065 -0.2794)
			(end 0.12065 -0.3048)
			(stroke
				(width 0.1)
				(type default)
			)
			(layer "F.Fab")
		)
		(fp_line
			(start -0.12065 -0.2794)
			(end 0.12065 -0.2794)
			(stroke
				(width 0.1)
				(type default)
			)
			(layer "F.Fab")
		)
		(fp_line
			(start 0.120396 0.2794)
			(end -0.12065 0.2794)
			(stroke
				(width 0.1)
				(type default)
			)
			(layer "F.Fab")
		)
		(fp_line
			(start -0.12065 0.2794)
			(end -0.12065 0.3048)
			(stroke
				(width 0.1)
				(type default)
			)
			(layer "F.Fab")
		)
		(fp_line
			(start 0.67945 0.3048)
			(end 0.120396 0.3048)
			(stroke
				(width 0.1)
				(type default)
			)
			(layer "F.Fab")
		)
		(fp_line
			(start 0.120396 0.3048)
			(end 0.120396 0.2794)
			(stroke
				(width 0.1)
				(type default)
			)
			(layer "F.Fab")
		)
		(fp_line
			(start -0.12065 0.3048)
			(end -0.67945 0.3048)
			(stroke
				(width 0.1)
				(type default)
			)
			(layer "F.Fab")
		)
		(fp_line
			(start -0.67945 0.3048)
			(end -0.67945 -0.305054)
			(stroke
				(width 0.1)
				(type default)
			)
			(layer "F.Fab")
		)
		(pad "1" smd circle
			(at -0.40005 0 90)
			(size 0 0)
			(layers "F.Cu" "F.Mask" "F.Paste")
			(net "SW_P12V_P0V8_PEX1_FLT")
		)
		(pad "2" smd circle
			(at 0.40005 0 90)
			(size 0 0)
			(layers "F.Cu" "F.Mask" "F.Paste")
			(net "GND")
		)
	)
	(footprint ""
		(layer "F.Cu")
		(at 452.543672 -44.87291)
		(property "Reference" "R672"
			(at 0 0 0)
			(layer "F.SilkS")
			(hide yes)
			(effects
				(font
					(size 1.27 1.27)
				)
			)
		)
		(property "Value" ""
			(at 0 0 0)
			(layer "F.Fab")
			(effects
				(font
					(size 1.27 1.27)
				)
			)
		)
		(duplicate_pad_numbers_are_jumpers no)
		(fp_line
			(start -0.7874 -0.4064)
			(end 0.7874 -0.4064)
			(stroke
				(width 0.1524)
				(type default)
			)
			(layer "F.SilkS")
		)
		(fp_line
			(start -0.7874 0.4064)
			(end -0.7874 -0.4064)
			(stroke
				(width 0.1524)
				(type default)
			)
			(layer "F.SilkS")
		)
		(fp_line
			(start 0.7874 -0.4064)
			(end 0.7874 0.4064)
			(stroke
				(width 0.1524)
				(type default)
			)
			(layer "F.SilkS")
		)
		(fp_line
			(start 0.7874 0.4064)
			(end -0.7874 0.4064)
			(stroke
				(width 0.1524)
				(type default)
			)
			(layer "F.SilkS")
		)
		(fp_line
			(start -0.67945 -0.305054)
			(end -0.12065 -0.305054)
			(stroke
				(width 0.1)
				(type default)
			)
			(layer "F.Fab")
		)
		(fp_line
			(start -0.67945 0.3048)
			(end -0.67945 -0.305054)
			(stroke
				(width 0.1)
				(type default)
			)
			(layer "F.Fab")
		)
		(fp_line
			(start -0.12065 -0.305054)
			(end -0.12065 -0.2794)
			(stroke
				(width 0.1)
				(type default)
			)
			(layer "F.Fab")
		)
		(fp_line
			(start -0.12065 -0.2794)
			(end 0.12065 -0.2794)
			(stroke
				(width 0.1)
				(type default)
			)
			(layer "F.Fab")
		)
		(fp_line
			(start -0.12065 0.2794)
			(end -0.12065 0.3048)
			(stroke
				(width 0.1)
				(type default)
			)
			(layer "F.Fab")
		)
		(fp_line
			(start -0.12065 0.3048)
			(end -0.67945 0.3048)
			(stroke
				(width 0.1)
				(type default)
			)
			(layer "F.Fab")
		)
		(fp_line
			(start 0.120396 0.2794)
			(end -0.12065 0.2794)
			(stroke
				(width 0.1)
				(type default)
			)
			(layer "F.Fab")
		)
		(fp_line
			(start 0.120396 0.3048)
			(end 0.120396 0.2794)
			(stroke
				(width 0.1)
				(type default)
			)
			(layer "F.Fab")
		)
		(fp_line
			(start 0.12065 -0.3048)
			(end 0.67945 -0.3048)
			(stroke
				(width 0.1)
				(type default)
			)
			(layer "F.Fab")
		)
		(fp_line
			(start 0.12065 -0.2794)
			(end 0.12065 -0.3048)
			(stroke
				(width 0.1)
				(type default)
			)
			(layer "F.Fab")
		)
		(fp_line
			(start 0.67945 -0.3048)
			(end 0.67945 0.3048)
			(stroke
				(width 0.1)
				(type default)
			)
			(layer "F.Fab")
		)
		(fp_line
			(start 0.67945 0.3048)
			(end 0.120396 0.3048)
			(stroke
				(width 0.1)
				(type default)
			)
			(layer "F.Fab")
		)
		(pad "1" smd circle
			(at -0.40005 0)
			(size 0 0)
			(layers "F.Cu" "F.Mask" "F.Paste")
			(net "SSD15_ADC_A0")
		)
		(pad "2" smd circle
			(at 0.40005 0)
			(size 0 0)
			(layers "F.Cu" "F.Mask" "F.Paste")
			(net "P3V3_AUX")
		)
	)
	(footprint ""
		(layer "F.Cu")
		(at 268.512036 -137.2489 -90)
		(property "Reference" "C915"
			(at 0 0 270)
			(layer "F.SilkS")
			(hide yes)
			(effects
				(font
					(size 1.27 1.27)
				)
			)
		)
		(property "Value" ""
			(at 0 0 270)
			(layer "F.Fab")
			(effects
				(font
					(size 1.27 1.27)
				)
			)
		)
		(duplicate_pad_numbers_are_jumpers no)
		(fp_line
			(start -0.7874 0.4064)
			(end -0.7874 -0.4064)
			(stroke
				(width 0.1524)
				(type default)
			)
			(layer "F.SilkS")
		)
		(fp_line
			(start 0.7874 0.4064)
			(end -0.7874 0.4064)
			(stroke
				(width 0.1524)
				(type default)
			)
			(layer "F.SilkS")
		)
		(fp_line
			(start -0.7874 -0.4064)
			(end 0.7874 -0.4064)
			(stroke
				(width 0.1524)
				(type default)
			)
			(layer "F.SilkS")
		)
		(fp_line
			(start 0.7874 -0.4064)
			(end 0.7874 0.4064)
			(stroke
				(width 0.1524)
				(type default)
			)
			(layer "F.SilkS")
		)
		(fp_line
			(start -0.67945 0.3048)
			(end -0.67945 -0.305054)
			(stroke
				(width 0.1)
				(type default)
			)
			(layer "F.Fab")
		)
		(fp_line
			(start -0.12065 0.3048)
			(end -0.67945 0.3048)
			(stroke
				(width 0.1)
				(type default)
			)
			(layer "F.Fab")
		)
		(fp_line
			(start 0.120396 0.3048)
			(end 0.120396 0.2794)
			(stroke
				(width 0.1)
				(type default)
			)
			(layer "F.Fab")
		)
		(fp_line
			(start 0.67945 0.3048)
			(end 0.120396 0.3048)
			(stroke
				(width 0.1)
				(type default)
			)
			(layer "F.Fab")
		)
		(fp_line
			(start -0.12065 0.2794)
			(end -0.12065 0.3048)
			(stroke
				(width 0.1)
				(type default)
			)
			(layer "F.Fab")
		)
		(fp_line
			(start 0.120396 0.2794)
			(end -0.12065 0.2794)
			(stroke
				(width 0.1)
				(type default)
			)
			(layer "F.Fab")
		)
		(fp_line
			(start -0.12065 -0.2794)
			(end 0.12065 -0.2794)
			(stroke
				(width 0.1)
				(type default)
			)
			(layer "F.Fab")
		)
		(fp_line
			(start 0.12065 -0.2794)
			(end 0.12065 -0.3048)
			(stroke
				(width 0.1)
				(type default)
			)
			(layer "F.Fab")
		)
		(fp_line
			(start 0.12065 -0.3048)
			(end 0.67945 -0.3048)
			(stroke
				(width 0.1)
				(type default)
			)
			(layer "F.Fab")
		)
		(fp_line
			(start 0.67945 -0.3048)
			(end 0.67945 0.3048)
			(stroke
				(width 0.1)
				(type default)
			)
			(layer "F.Fab")
		)
		(fp_line
			(start -0.67945 -0.305054)
			(end -0.12065 -0.305054)
			(stroke
				(width 0.1)
				(type default)
			)
			(layer "F.Fab")
		)
		(fp_line
			(start -0.12065 -0.305054)
			(end -0.12065 -0.2794)
			(stroke
				(width 0.1)
				(type default)
			)
			(layer "F.Fab")
		)
		(pad "1" smd circle
			(at -0.40005 0 270)
			(size 0 0)
			(layers "F.Cu" "F.Mask" "F.Paste")
			(net "P3V3_NIC4")
		)
		(pad "2" smd circle
			(at 0.40005 0 270)
			(size 0 0)
			(layers "F.Cu" "F.Mask" "F.Paste")
			(net "GND")
		)
	)
	(footprint ""
		(layer "F.Cu")
		(at 327.992232 -32.739584 180)
		(property "Reference" "C513"
			(at 0 0 180)
			(layer "F.SilkS")
			(hide yes)
			(effects
				(font
					(size 1.27 1.27)
				)
			)
		)
		(property "Value" ""
			(at 0 0 180)
			(layer "F.Fab")
			(effects
				(font
					(size 1.27 1.27)
				)
			)
		)
		(duplicate_pad_numbers_are_jumpers no)
		(fp_line
			(start 0.299974 0.150114)
			(end -0.299974 0.150114)
			(stroke
				(width 0.1)
				(type default)
			)
			(layer "F.Fab")
		)
		(fp_line
			(start 0.299974 -0.150114)
			(end 0.299974 0.150114)
			(stroke
				(width 0.1)
				(type default)
			)
			(layer "F.Fab")
		)
		(fp_line
			(start -0.299974 0.150114)
			(end -0.299974 -0.150114)
			(stroke
				(width 0.1)
				(type default)
			)
			(layer "F.Fab")
		)
		(fp_line
			(start -0.299974 -0.150114)
			(end 0.299974 -0.150114)
			(stroke
				(width 0.1)
				(type default)
			)
			(layer "F.Fab")
		)
		(pad "1" smd rect
			(at -0.2667 0 180)
			(size 0.3048 0.381)
			(layers "F.Cu" "F.Mask" "F.Paste")
			(net "P5E_PEX2_STN2_TX_DP<34>")
		)
		(pad "2" smd rect
			(at 0.2667 0 180)
			(size 0.3048 0.381)
			(layers "F.Cu" "F.Mask" "F.Paste")
			(net "P5E_PEX2_STN2_TX_C_DP<34>")
		)
	)
	(footprint ""
		(layer "F.Cu")
		(at 258.54533 -197.097396)
		(property "Reference" "R4900"
			(at 0 0 0)
			(layer "F.SilkS")
			(hide yes)
			(effects
				(font
					(size 1.27 1.27)
				)
			)
		)
		(property "Value" ""
			(at 0 0 0)
			(layer "F.Fab")
			(effects
				(font
					(size 1.27 1.27)
				)
			)
		)
		(duplicate_pad_numbers_are_jumpers no)
		(fp_line
			(start -0.7874 -0.4064)
			(end 0.7874 -0.4064)
			(stroke
				(width 0.1524)
				(type default)
			)
			(layer "F.SilkS")
		)
		(fp_line
			(start -0.7874 0.4064)
			(end -0.7874 -0.4064)
			(stroke
				(width 0.1524)
				(type default)
			)
			(layer "F.SilkS")
		)
		(fp_line
			(start 0.7874 -0.4064)
			(end 0.7874 0.4064)
			(stroke
				(width 0.1524)
				(type default)
			)
			(layer "F.SilkS")
		)
		(fp_line
			(start 0.7874 0.4064)
			(end -0.7874 0.4064)
			(stroke
				(width 0.1524)
				(type default)
			)
			(layer "F.SilkS")
		)
		(fp_line
			(start -0.67945 -0.305054)
			(end -0.12065 -0.305054)
			(stroke
				(width 0.1)
				(type default)
			)
			(layer "F.Fab")
		)
		(fp_line
			(start -0.67945 0.3048)
			(end -0.67945 -0.305054)
			(stroke
				(width 0.1)
				(type default)
			)
			(layer "F.Fab")
		)
		(fp_line
			(start -0.12065 -0.305054)
			(end -0.12065 -0.2794)
			(stroke
				(width 0.1)
				(type default)
			)
			(layer "F.Fab")
		)
		(fp_line
			(start -0.12065 -0.2794)
			(end 0.12065 -0.2794)
			(stroke
				(width 0.1)
				(type default)
			)
			(layer "F.Fab")
		)
		(fp_line
			(start -0.12065 0.2794)
			(end -0.12065 0.3048)
			(stroke
				(width 0.1)
				(type default)
			)
			(layer "F.Fab")
		)
		(fp_line
			(start -0.12065 0.3048)
			(end -0.67945 0.3048)
			(stroke
				(width 0.1)
				(type default)
			)
			(layer "F.Fab")
		)
		(fp_line
			(start 0.120396 0.2794)
			(end -0.12065 0.2794)
			(stroke
				(width 0.1)
				(type default)
			)
			(layer "F.Fab")
		)
		(fp_line
			(start 0.120396 0.3048)
			(end 0.120396 0.2794)
			(stroke
				(width 0.1)
				(type default)
			)
			(layer "F.Fab")
		)
		(fp_line
			(start 0.12065 -0.3048)
			(end 0.67945 -0.3048)
			(stroke
				(width 0.1)
				(type default)
			)
			(layer "F.Fab")
		)
		(fp_line
			(start 0.12065 -0.2794)
			(end 0.12065 -0.3048)
			(stroke
				(width 0.1)
				(type default)
			)
			(layer "F.Fab")
		)
		(fp_line
			(start 0.67945 -0.3048)
			(end 0.67945 0.3048)
			(stroke
				(width 0.1)
				(type default)
			)
			(layer "F.Fab")
		)
		(fp_line
			(start 0.67945 0.3048)
			(end 0.120396 0.3048)
			(stroke
				(width 0.1)
				(type default)
			)
			(layer "F.Fab")
		)
		(pad "1" smd circle
			(at -0.40005 0)
			(size 0 0)
			(layers "F.Cu" "F.Mask" "F.Paste")
			(net "JTAG_FPGA_TMS")
		)
		(pad "2" smd circle
			(at 0.40005 0)
			(size 0 0)
			(layers "F.Cu" "F.Mask" "F.Paste")
			(net "JTAG_CONN_TMS")
		)
	)
	(footprint ""
		(layer "F.Cu")
		(at 44.722542 -44.341542 90)
		(property "Reference" "R525"
			(at 0 0 90)
			(layer "F.SilkS")
			(hide yes)
			(effects
				(font
					(size 1.27 1.27)
				)
			)
		)
		(property "Value" ""
			(at 0 0 90)
			(layer "F.Fab")
			(effects
				(font
					(size 1.27 1.27)
				)
			)
		)
		(duplicate_pad_numbers_are_jumpers no)
		(fp_line
			(start 0.7874 -0.4064)
			(end 0.7874 0.4064)
			(stroke
				(width 0.1524)
				(type default)
			)
			(layer "F.SilkS")
		)
		(fp_line
			(start -0.7874 -0.4064)
			(end 0.7874 -0.4064)
			(stroke
				(width 0.1524)
				(type default)
			)
			(layer "F.SilkS")
		)
		(fp_line
			(start 0.7874 0.4064)
			(end -0.7874 0.4064)
			(stroke
				(width 0.1524)
				(type default)
			)
			(layer "F.SilkS")
		)
		(fp_line
			(start -0.7874 0.4064)
			(end -0.7874 -0.4064)
			(stroke
				(width 0.1524)
				(type default)
			)
			(layer "F.SilkS")
		)
		(fp_line
			(start -0.12065 -0.305054)
			(end -0.12065 -0.2794)
			(stroke
				(width 0.1)
				(type default)
			)
			(layer "F.Fab")
		)
		(fp_line
			(start -0.67945 -0.305054)
			(end -0.12065 -0.305054)
			(stroke
				(width 0.1)
				(type default)
			)
			(layer "F.Fab")
		)
		(fp_line
			(start 0.67945 -0.3048)
			(end 0.67945 0.3048)
			(stroke
				(width 0.1)
				(type default)
			)
			(layer "F.Fab")
		)
		(fp_line
			(start 0.12065 -0.3048)
			(end 0.67945 -0.3048)
			(stroke
				(width 0.1)
				(type default)
			)
			(layer "F.Fab")
		)
		(fp_line
			(start 0.12065 -0.2794)
			(end 0.12065 -0.3048)
			(stroke
				(width 0.1)
				(type default)
			)
			(layer "F.Fab")
		)
		(fp_line
			(start -0.12065 -0.2794)
			(end 0.12065 -0.2794)
			(stroke
				(width 0.1)
				(type default)
			)
			(layer "F.Fab")
		)
		(fp_line
			(start 0.120396 0.2794)
			(end -0.12065 0.2794)
			(stroke
				(width 0.1)
				(type default)
			)
			(layer "F.Fab")
		)
		(fp_line
			(start -0.12065 0.2794)
			(end -0.12065 0.3048)
			(stroke
				(width 0.1)
				(type default)
			)
			(layer "F.Fab")
		)
		(fp_line
			(start 0.67945 0.3048)
			(end 0.120396 0.3048)
			(stroke
				(width 0.1)
				(type default)
			)
			(layer "F.Fab")
		)
		(fp_line
			(start 0.120396 0.3048)
			(end 0.120396 0.2794)
			(stroke
				(width 0.1)
				(type default)
			)
			(layer "F.Fab")
		)
		(fp_line
			(start -0.12065 0.3048)
			(end -0.67945 0.3048)
			(stroke
				(width 0.1)
				(type default)
			)
			(layer "F.Fab")
		)
		(fp_line
			(start -0.67945 0.3048)
			(end -0.67945 -0.305054)
			(stroke
				(width 0.1)
				(type default)
			)
			(layer "F.Fab")
		)
		(pad "1" smd circle
			(at -0.40005 0 90)
			(size 0 0)
			(layers "F.Cu" "F.Mask" "F.Paste")
			(net "P12V_SSD1")
		)
		(pad "2" smd circle
			(at 0.40005 0 90)
			(size 0 0)
			(layers "F.Cu" "F.Mask" "F.Paste")
			(net "P12V_SSD1_VIN_N")
		)
	)
	(footprint ""
		(layer "F.Cu")
		(at 174.80915 -27.04973 180)
		(property "Reference" "C2769"
			(at 0 0 180)
			(layer "F.SilkS")
			(hide yes)
			(effects
				(font
					(size 1.27 1.27)
				)
			)
		)
		(property "Value" ""
			(at 0 0 180)
			(layer "F.Fab")
			(effects
				(font
					(size 1.27 1.27)
				)
			)
		)
		(duplicate_pad_numbers_are_jumpers no)
		(fp_line
			(start 0.7874 0.4064)
			(end -0.7874 0.4064)
			(stroke
				(width 0.1524)
				(type default)
			)
			(layer "F.SilkS")
		)
		(fp_line
			(start 0.7874 -0.4064)
			(end 0.7874 0.4064)
			(stroke
				(width 0.1524)
				(type default)
			)
			(layer "F.SilkS")
		)
		(fp_line
			(start -0.7874 0.4064)
			(end -0.7874 -0.4064)
			(stroke
				(width 0.1524)
				(type default)
			)
			(layer "F.SilkS")
		)
		(fp_line
			(start -0.7874 -0.4064)
			(end 0.7874 -0.4064)
			(stroke
				(width 0.1524)
				(type default)
			)
			(layer "F.SilkS")
		)
		(fp_line
			(start 0.67945 0.3048)
			(end 0.120396 0.3048)
			(stroke
				(width 0.1)
				(type default)
			)
			(layer "F.Fab")
		)
		(fp_line
			(start 0.67945 -0.3048)
			(end 0.67945 0.3048)
			(stroke
				(width 0.1)
				(type default)
			)
			(layer "F.Fab")
		)
		(fp_line
			(start 0.12065 -0.2794)
			(end 0.12065 -0.3048)
			(stroke
				(width 0.1)
				(type default)
			)
			(layer "F.Fab")
		)
		(fp_line
			(start 0.12065 -0.3048)
			(end 0.67945 -0.3048)
			(stroke
				(width 0.1)
				(type default)
			)
			(layer "F.Fab")
		)
		(fp_line
			(start 0.120396 0.3048)
			(end 0.120396 0.2794)
			(stroke
				(width 0.1)
				(type default)
			)
			(layer "F.Fab")
		)
		(fp_line
			(start 0.120396 0.2794)
			(end -0.12065 0.2794)
			(stroke
				(width 0.1)
				(type default)
			)
			(layer "F.Fab")
		)
		(fp_line
			(start -0.12065 0.3048)
			(end -0.67945 0.3048)
			(stroke
				(width 0.1)
				(type default)
			)
			(layer "F.Fab")
		)
		(fp_line
			(start -0.12065 0.2794)
			(end -0.12065 0.3048)
			(stroke
				(width 0.1)
				(type default)
			)
			(layer "F.Fab")
		)
		(fp_line
			(start -0.12065 -0.2794)
			(end 0.12065 -0.2794)
			(stroke
				(width 0.1)
				(type default)
			)
			(layer "F.Fab")
		)
		(fp_line
			(start -0.12065 -0.305054)
			(end -0.12065 -0.2794)
			(stroke
				(width 0.1)
				(type default)
			)
			(layer "F.Fab")
		)
		(fp_line
			(start -0.67945 0.3048)
			(end -0.67945 -0.305054)
			(stroke
				(width 0.1)
				(type default)
			)
			(layer "F.Fab")
		)
		(fp_line
			(start -0.67945 -0.305054)
			(end -0.12065 -0.305054)
			(stroke
				(width 0.1)
				(type default)
			)
			(layer "F.Fab")
		)
		(pad "1" smd circle
			(at -0.40005 0 180)
			(size 0 0)
			(layers "F.Cu" "F.Mask" "F.Paste")
			(net "PRSNT_SSD6_R_N")
		)
		(pad "2" smd circle
			(at 0.40005 0 180)
			(size 0 0)
			(layers "F.Cu" "F.Mask" "F.Paste")
			(net "GND")
		)
	)
	(footprint ""
		(layer "F.Cu")
		(at 399.91157 -71.458074 -90)
		(property "Reference" "PD117"
			(at 4.300474 -2.7813 90)
			(unlocked yes)
			(layer "F.SilkS")
			(effects
				(font
					(size 0.7874 0.5842)
					(thickness 0.1524)
				)
				(justify left)
			)
		)
		(property "Value" ""
			(at 0 0 270)
			(layer "F.Fab")
			(effects
				(font
					(size 1.27 1.27)
				)
			)
		)
		(duplicate_pad_numbers_are_jumpers no)
		(fp_line
			(start -3.656584 1.970024)
			(end 4.240784 1.970024)
			(stroke
				(width 0.1524)
				(type default)
			)
			(layer "F.SilkS")
		)
		(fp_line
			(start 4.240784 1.970024)
			(end 4.240784 -1.970024)
			(stroke
				(width 0.1524)
				(type default)
			)
			(layer "F.SilkS")
		)
		(fp_line
			(start -3.656584 -1.970024)
			(end -3.656584 1.970024)
			(stroke
				(width 0.1524)
				(type default)
			)
			(layer "F.SilkS")
		)
		(fp_line
			(start 4.240784 -1.970024)
			(end -3.656584 -1.970024)
			(stroke
				(width 0.1524)
				(type default)
			)
			(layer "F.SilkS")
		)
		(fp_poly
			(pts
				(xy 3.580384 1.970024) (xy 3.580384 -1.970024) (xy 4.240784 -1.970024) (xy 4.240784 1.970024)
			)
			(stroke
				(width 0)
				(type default)
			)
			(fill yes)
			(layer "F.SilkS")
		)
		(fp_line
			(start -2.3749 1.970024)
			(end 2.3749 1.970024)
			(stroke
				(width 0.1)
				(type default)
			)
			(layer "F.Fab")
		)
		(fp_line
			(start 2.3749 1.970024)
			(end 2.3749 -1.970024)
			(stroke
				(width 0.1)
				(type default)
			)
			(layer "F.Fab")
		)
		(fp_line
			(start -2.3749 -1.970024)
			(end -2.3749 1.970024)
			(stroke
				(width 0.1)
				(type default)
			)
			(layer "F.Fab")
		)
		(fp_line
			(start 2.3749 -1.970024)
			(end -2.3749 -1.970024)
			(stroke
				(width 0.1)
				(type default)
			)
			(layer "F.Fab")
		)
		(fp_text user "+"
			(at -4.9784 -0.23495 270)
			(unlocked yes)
			(layer "F.Fab")
			(effects
				(font
					(size 1.905 1.4224)
					(thickness 0.1524)
				)
				(justify left)
			)
		)
		(fp_text user "-"
			(at 4.1656 -0.23495 270)
			(unlocked yes)
			(layer "F.Fab")
			(effects
				(font
					(size 1.905 1.4224)
					(thickness 0.1524)
				)
				(justify left)
			)
		)
		(pad "A" smd rect
			(at -2.450084 0 270)
			(size 2.159 2.2606)
			(layers "F.Cu" "F.Mask" "F.Paste")
			(net "GND")
		)
		(pad "C" smd rect
			(at 2.450084 0 270)
			(size 2.159 2.2606)
			(layers "F.Cu" "F.Mask" "F.Paste")
			(net "P12V_AUX")
		)
	)
	(footprint ""
		(layer "F.Cu")
		(at 456.957938 -275.725636 135)
		(property "Reference" "C828"
			(at 0 0 135)
			(layer "F.SilkS")
			(hide yes)
			(effects
				(font
					(size 1.27 1.27)
				)
			)
		)
		(property "Value" ""
			(at 0 0 135)
			(layer "F.Fab")
			(effects
				(font
					(size 1.27 1.27)
				)
			)
		)
		(duplicate_pad_numbers_are_jumpers no)
		(fp_line
			(start 0.787389 -0.406267)
			(end 0.787389 0.406267)
			(stroke
				(width 0.1524)
				(type default)
			)
			(layer "F.SilkS")
		)
		(fp_line
			(start 0.787389 0.406267)
			(end -0.787389 0.406267)
			(stroke
				(width 0.1524)
				(type default)
			)
			(layer "F.SilkS")
		)
		(fp_line
			(start -0.787389 -0.406267)
			(end 0.787389 -0.406267)
			(stroke
				(width 0.1524)
				(type default)
			)
			(layer "F.SilkS")
		)
		(fp_line
			(start -0.787389 0.406267)
			(end -0.787389 -0.406267)
			(stroke
				(width 0.1524)
				(type default)
			)
			(layer "F.SilkS")
		)
		(fp_line
			(start 0.679446 -0.30479)
			(end 0.679446 0.30479)
			(stroke
				(width 0.1)
				(type default)
			)
			(layer "F.Fab")
		)
		(fp_line
			(start 0.120515 -0.30479)
			(end 0.679446 -0.30479)
			(stroke
				(width 0.1)
				(type default)
			)
			(layer "F.Fab")
		)
		(fp_line
			(start 0.120695 -0.279466)
			(end 0.120515 -0.30479)
			(stroke
				(width 0.1)
				(type default)
			)
			(layer "F.Fab")
		)
		(fp_line
			(start 0.679446 0.30479)
			(end 0.120515 0.30479)
			(stroke
				(width 0.1)
				(type default)
			)
			(layer "F.Fab")
		)
		(fp_line
			(start -0.120695 -0.304969)
			(end -0.120695 -0.279466)
			(stroke
				(width 0.1)
				(type default)
			)
			(layer "F.Fab")
		)
		(fp_line
			(start -0.120695 -0.279466)
			(end 0.120695 -0.279466)
			(stroke
				(width 0.1)
				(type default)
			)
			(layer "F.Fab")
		)
		(fp_line
			(start 0.120335 0.279466)
			(end -0.120695 0.279466)
			(stroke
				(width 0.1)
				(type default)
			)
			(layer "F.Fab")
		)
		(fp_line
			(start 0.120515 0.30479)
			(end 0.120335 0.279466)
			(stroke
				(width 0.1)
				(type default)
			)
			(layer "F.Fab")
		)
		(fp_line
			(start -0.679446 -0.305149)
			(end -0.120695 -0.304969)
			(stroke
				(width 0.1)
				(type default)
			)
			(layer "F.Fab")
		)
		(fp_line
			(start -0.120695 0.279466)
			(end -0.120515 0.30479)
			(stroke
				(width 0.1)
				(type default)
			)
			(layer "F.Fab")
		)
		(fp_line
			(start -0.120515 0.30479)
			(end -0.679446 0.30479)
			(stroke
				(width 0.1)
				(type default)
			)
			(layer "F.Fab")
		)
		(fp_line
			(start -0.679446 0.30479)
			(end -0.679446 -0.305149)
			(stroke
				(width 0.1)
				(type default)
			)
			(layer "F.Fab")
		)
		(pad "1" smd circle
			(at -0.40005 0 135)
			(size 0 0)
			(layers "F.Cu" "F.Mask" "F.Paste")
			(net "P12V_PEX3_P1V25_VIN_P")
		)
		(pad "2" smd circle
			(at 0.40005 0 135)
			(size 0 0)
			(layers "F.Cu" "F.Mask" "F.Paste")
			(net "P12V_PEX3_P1V25_VIN_N")
		)
	)
	(footprint ""
		(layer "F.Cu")
		(at 365.506 -200.787 180)
		(property "Reference" "R4686"
			(at 0 0 180)
			(layer "F.SilkS")
			(hide yes)
			(effects
				(font
					(size 1.27 1.27)
				)
			)
		)
		(property "Value" ""
			(at 0 0 180)
			(layer "F.Fab")
			(effects
				(font
					(size 1.27 1.27)
				)
			)
		)
		(duplicate_pad_numbers_are_jumpers no)
		(fp_line
			(start 0.7874 0.4064)
			(end -0.7874 0.4064)
			(stroke
				(width 0.1524)
				(type default)
			)
			(layer "F.SilkS")
		)
		(fp_line
			(start 0.7874 -0.4064)
			(end 0.7874 0.4064)
			(stroke
				(width 0.1524)
				(type default)
			)
			(layer "F.SilkS")
		)
		(fp_line
			(start -0.7874 0.4064)
			(end -0.7874 -0.4064)
			(stroke
				(width 0.1524)
				(type default)
			)
			(layer "F.SilkS")
		)
		(fp_line
			(start -0.7874 -0.4064)
			(end 0.7874 -0.4064)
			(stroke
				(width 0.1524)
				(type default)
			)
			(layer "F.SilkS")
		)
		(fp_line
			(start 0.67945 0.3048)
			(end 0.120396 0.3048)
			(stroke
				(width 0.1)
				(type default)
			)
			(layer "F.Fab")
		)
		(fp_line
			(start 0.67945 -0.3048)
			(end 0.67945 0.3048)
			(stroke
				(width 0.1)
				(type default)
			)
			(layer "F.Fab")
		)
		(fp_line
			(start 0.12065 -0.2794)
			(end 0.12065 -0.3048)
			(stroke
				(width 0.1)
				(type default)
			)
			(layer "F.Fab")
		)
		(fp_line
			(start 0.12065 -0.3048)
			(end 0.67945 -0.3048)
			(stroke
				(width 0.1)
				(type default)
			)
			(layer "F.Fab")
		)
		(fp_line
			(start 0.120396 0.3048)
			(end 0.120396 0.2794)
			(stroke
				(width 0.1)
				(type default)
			)
			(layer "F.Fab")
		)
		(fp_line
			(start 0.120396 0.2794)
			(end -0.12065 0.2794)
			(stroke
				(width 0.1)
				(type default)
			)
			(layer "F.Fab")
		)
		(fp_line
			(start -0.12065 0.3048)
			(end -0.67945 0.3048)
			(stroke
				(width 0.1)
				(type default)
			)
			(layer "F.Fab")
		)
		(fp_line
			(start -0.12065 0.2794)
			(end -0.12065 0.3048)
			(stroke
				(width 0.1)
				(type default)
			)
			(layer "F.Fab")
		)
		(fp_line
			(start -0.12065 -0.2794)
			(end 0.12065 -0.2794)
			(stroke
				(width 0.1)
				(type default)
			)
			(layer "F.Fab")
		)
		(fp_line
			(start -0.12065 -0.305054)
			(end -0.12065 -0.2794)
			(stroke
				(width 0.1)
				(type default)
			)
			(layer "F.Fab")
		)
		(fp_line
			(start -0.67945 0.3048)
			(end -0.67945 -0.305054)
			(stroke
				(width 0.1)
				(type default)
			)
			(layer "F.Fab")
		)
		(fp_line
			(start -0.67945 -0.305054)
			(end -0.12065 -0.305054)
			(stroke
				(width 0.1)
				(type default)
			)
			(layer "F.Fab")
		)
		(pad "1" smd circle
			(at -0.40005 0 180)
			(size 0 0)
			(layers "F.Cu" "F.Mask" "F.Paste")
			(net "PRSNT_SSD4_FPGA_PCA9555_N")
		)
		(pad "2" smd circle
			(at 0.40005 0 180)
			(size 0 0)
			(layers "F.Cu" "F.Mask" "F.Paste")
			(net "PRSNT_SSD4_FPGA_R_N")
		)
	)
	(footprint ""
		(layer "F.Cu")
		(at 220.366844 -98.806 90)
		(property "Reference" "R721"
			(at 0 0 90)
			(layer "F.SilkS")
			(hide yes)
			(effects
				(font
					(size 1.27 1.27)
				)
			)
		)
		(property "Value" ""
			(at 0 0 90)
			(layer "F.Fab")
			(effects
				(font
					(size 1.27 1.27)
				)
			)
		)
		(duplicate_pad_numbers_are_jumpers no)
		(fp_line
			(start 0.7874 -0.4064)
			(end 0.7874 0.4064)
			(stroke
				(width 0.1524)
				(type default)
			)
			(layer "F.SilkS")
		)
		(fp_line
			(start -0.7874 -0.4064)
			(end 0.7874 -0.4064)
			(stroke
				(width 0.1524)
				(type default)
			)
			(layer "F.SilkS")
		)
		(fp_line
			(start 0.7874 0.4064)
			(end -0.7874 0.4064)
			(stroke
				(width 0.1524)
				(type default)
			)
			(layer "F.SilkS")
		)
		(fp_line
			(start -0.7874 0.4064)
			(end -0.7874 -0.4064)
			(stroke
				(width 0.1524)
				(type default)
			)
			(layer "F.SilkS")
		)
		(fp_line
			(start -0.12065 -0.305054)
			(end -0.12065 -0.2794)
			(stroke
				(width 0.1)
				(type default)
			)
			(layer "F.Fab")
		)
		(fp_line
			(start -0.67945 -0.305054)
			(end -0.12065 -0.305054)
			(stroke
				(width 0.1)
				(type default)
			)
			(layer "F.Fab")
		)
		(fp_line
			(start 0.67945 -0.3048)
			(end 0.67945 0.3048)
			(stroke
				(width 0.1)
				(type default)
			)
			(layer "F.Fab")
		)
		(fp_line
			(start 0.12065 -0.3048)
			(end 0.67945 -0.3048)
			(stroke
				(width 0.1)
				(type default)
			)
			(layer "F.Fab")
		)
		(fp_line
			(start 0.12065 -0.2794)
			(end 0.12065 -0.3048)
			(stroke
				(width 0.1)
				(type default)
			)
			(layer "F.Fab")
		)
		(fp_line
			(start -0.12065 -0.2794)
			(end 0.12065 -0.2794)
			(stroke
				(width 0.1)
				(type default)
			)
			(layer "F.Fab")
		)
		(fp_line
			(start 0.120396 0.2794)
			(end -0.12065 0.2794)
			(stroke
				(width 0.1)
				(type default)
			)
			(layer "F.Fab")
		)
		(fp_line
			(start -0.12065 0.2794)
			(end -0.12065 0.3048)
			(stroke
				(width 0.1)
				(type default)
			)
			(layer "F.Fab")
		)
		(fp_line
			(start 0.67945 0.3048)
			(end 0.120396 0.3048)
			(stroke
				(width 0.1)
				(type default)
			)
			(layer "F.Fab")
		)
		(fp_line
			(start 0.120396 0.3048)
			(end 0.120396 0.2794)
			(stroke
				(width 0.1)
				(type default)
			)
			(layer "F.Fab")
		)
		(fp_line
			(start -0.12065 0.3048)
			(end -0.67945 0.3048)
			(stroke
				(width 0.1)
				(type default)
			)
			(layer "F.Fab")
		)
		(fp_line
			(start -0.67945 0.3048)
			(end -0.67945 -0.305054)
			(stroke
				(width 0.1)
				(type default)
			)
			(layer "F.Fab")
		)
		(pad "1" smd circle
			(at -0.40005 0 90)
			(size 0 0)
			(layers "F.Cu" "F.Mask" "F.Paste")
			(net "SMB_BIC_I2C6_MUX_NIC_ADC_R_SDA")
		)
		(pad "2" smd circle
			(at 0.40005 0 90)
			(size 0 0)
			(layers "F.Cu" "F.Mask" "F.Paste")
			(net "SMB_NIC3_ADC_SDA")
		)
	)
	(footprint ""
		(layer "F.Cu")
		(at 257.811524 -71.458074 -90)
		(property "Reference" "PD36"
			(at 4.300474 -2.742946 90)
			(unlocked yes)
			(layer "F.SilkS")
			(effects
				(font
					(size 0.7874 0.5842)
					(thickness 0.1524)
				)
				(justify left)
			)
		)
		(property "Value" ""
			(at 0 0 270)
			(layer "F.Fab")
			(effects
				(font
					(size 1.27 1.27)
				)
			)
		)
		(duplicate_pad_numbers_are_jumpers no)
		(fp_line
			(start -3.656584 1.970024)
			(end 4.240784 1.970024)
			(stroke
				(width 0.1524)
				(type default)
			)
			(layer "F.SilkS")
		)
		(fp_line
			(start 4.240784 1.970024)
			(end 4.240784 -1.970024)
			(stroke
				(width 0.1524)
				(type default)
			)
			(layer "F.SilkS")
		)
		(fp_line
			(start -3.656584 -1.970024)
			(end -3.656584 1.970024)
			(stroke
				(width 0.1524)
				(type default)
			)
			(layer "F.SilkS")
		)
		(fp_line
			(start 4.240784 -1.970024)
			(end -3.656584 -1.970024)
			(stroke
				(width 0.1524)
				(type default)
			)
			(layer "F.SilkS")
		)
		(fp_poly
			(pts
				(xy 3.580384 1.970024) (xy 3.580384 -1.970024) (xy 4.240784 -1.970024) (xy 4.240784 1.970024)
			)
			(stroke
				(width 0)
				(type default)
			)
			(fill yes)
			(layer "F.SilkS")
		)
		(fp_line
			(start -2.3749 1.970024)
			(end 2.3749 1.970024)
			(stroke
				(width 0.1)
				(type default)
			)
			(layer "F.Fab")
		)
		(fp_line
			(start 2.3749 1.970024)
			(end 2.3749 -1.970024)
			(stroke
				(width 0.1)
				(type default)
			)
			(layer "F.Fab")
		)
		(fp_line
			(start -2.3749 -1.970024)
			(end -2.3749 1.970024)
			(stroke
				(width 0.1)
				(type default)
			)
			(layer "F.Fab")
		)
		(fp_line
			(start 2.3749 -1.970024)
			(end -2.3749 -1.970024)
			(stroke
				(width 0.1)
				(type default)
			)
			(layer "F.Fab")
		)
		(fp_text user "+"
			(at -4.9784 -0.23495 270)
			(unlocked yes)
			(layer "F.Fab")
			(effects
				(font
					(size 1.905 1.4224)
					(thickness 0.1524)
				)
				(justify left)
			)
		)
		(fp_text user "-"
			(at 4.1656 -0.23495 270)
			(unlocked yes)
			(layer "F.Fab")
			(effects
				(font
					(size 1.905 1.4224)
					(thickness 0.1524)
				)
				(justify left)
			)
		)
		(pad "A" smd rect
			(at -2.450084 0 270)
			(size 2.159 2.2606)
			(layers "F.Cu" "F.Mask" "F.Paste")
			(net "GND")
		)
		(pad "C" smd rect
			(at 2.450084 0 270)
			(size 2.159 2.2606)
			(layers "F.Cu" "F.Mask" "F.Paste")
			(net "P12V_AUX")
		)
	)
	(footprint ""
		(layer "F.Cu")
		(at 424.814492 -350.098614 90)
		(property "Reference" "C810"
			(at 0 0 90)
			(layer "F.SilkS")
			(hide yes)
			(effects
				(font
					(size 1.27 1.27)
				)
			)
		)
		(property "Value" ""
			(at 0 0 90)
			(layer "F.Fab")
			(effects
				(font
					(size 1.27 1.27)
				)
			)
		)
		(duplicate_pad_numbers_are_jumpers no)
		(fp_line
			(start 0.299974 -0.150114)
			(end 0.299974 0.150114)
			(stroke
				(width 0.1)
				(type default)
			)
			(layer "F.Fab")
		)
		(fp_line
			(start -0.299974 -0.150114)
			(end 0.299974 -0.150114)
			(stroke
				(width 0.1)
				(type default)
			)
			(layer "F.Fab")
		)
		(fp_line
			(start 0.299974 0.150114)
			(end -0.299974 0.150114)
			(stroke
				(width 0.1)
				(type default)
			)
			(layer "F.Fab")
		)
		(fp_line
			(start -0.299974 0.150114)
			(end -0.299974 -0.150114)
			(stroke
				(width 0.1)
				(type default)
			)
			(layer "F.Fab")
		)
		(pad "1" smd rect
			(at -0.2667 0 90)
			(size 0.3048 0.381)
			(layers "F.Cu" "F.Mask" "F.Paste")
			(net "P5E_PEX3_STN7_TX_DP<119>")
		)
		(pad "2" smd rect
			(at 0.2667 0 90)
			(size 0.3048 0.381)
			(layers "F.Cu" "F.Mask" "F.Paste")
			(net "P5E_PEX3_STN7_TX_C_DP<119>")
		)
	)
	(footprint ""
		(layer "F.Cu")
		(at 364.259876 -254.385826)
		(property "Reference" "R3059"
			(at 0 0 0)
			(layer "F.SilkS")
			(hide yes)
			(effects
				(font
					(size 1.27 1.27)
				)
			)
		)
		(property "Value" ""
			(at 0 0 0)
			(layer "F.Fab")
			(effects
				(font
					(size 1.27 1.27)
				)
			)
		)
		(duplicate_pad_numbers_are_jumpers no)
		(fp_line
			(start -0.7874 -0.4064)
			(end 0.7874 -0.4064)
			(stroke
				(width 0.1524)
				(type default)
			)
			(layer "F.SilkS")
		)
		(fp_line
			(start -0.7874 0.4064)
			(end -0.7874 -0.4064)
			(stroke
				(width 0.1524)
				(type default)
			)
			(layer "F.SilkS")
		)
		(fp_line
			(start 0.7874 -0.4064)
			(end 0.7874 0.4064)
			(stroke
				(width 0.1524)
				(type default)
			)
			(layer "F.SilkS")
		)
		(fp_line
			(start 0.7874 0.4064)
			(end -0.7874 0.4064)
			(stroke
				(width 0.1524)
				(type default)
			)
			(layer "F.SilkS")
		)
		(fp_line
			(start -0.67945 -0.305054)
			(end -0.12065 -0.305054)
			(stroke
				(width 0.1)
				(type default)
			)
			(layer "F.Fab")
		)
		(fp_line
			(start -0.67945 0.3048)
			(end -0.67945 -0.305054)
			(stroke
				(width 0.1)
				(type default)
			)
			(layer "F.Fab")
		)
		(fp_line
			(start -0.12065 -0.305054)
			(end -0.12065 -0.2794)
			(stroke
				(width 0.1)
				(type default)
			)
			(layer "F.Fab")
		)
		(fp_line
			(start -0.12065 -0.2794)
			(end 0.12065 -0.2794)
			(stroke
				(width 0.1)
				(type default)
			)
			(layer "F.Fab")
		)
		(fp_line
			(start -0.12065 0.2794)
			(end -0.12065 0.3048)
			(stroke
				(width 0.1)
				(type default)
			)
			(layer "F.Fab")
		)
		(fp_line
			(start -0.12065 0.3048)
			(end -0.67945 0.3048)
			(stroke
				(width 0.1)
				(type default)
			)
			(layer "F.Fab")
		)
		(fp_line
			(start 0.120396 0.2794)
			(end -0.12065 0.2794)
			(stroke
				(width 0.1)
				(type default)
			)
			(layer "F.Fab")
		)
		(fp_line
			(start 0.120396 0.3048)
			(end 0.120396 0.2794)
			(stroke
				(width 0.1)
				(type default)
			)
			(layer "F.Fab")
		)
		(fp_line
			(start 0.12065 -0.3048)
			(end 0.67945 -0.3048)
			(stroke
				(width 0.1)
				(type default)
			)
			(layer "F.Fab")
		)
		(fp_line
			(start 0.12065 -0.2794)
			(end 0.12065 -0.3048)
			(stroke
				(width 0.1)
				(type default)
			)
			(layer "F.Fab")
		)
		(fp_line
			(start 0.67945 -0.3048)
			(end 0.67945 0.3048)
			(stroke
				(width 0.1)
				(type default)
			)
			(layer "F.Fab")
		)
		(fp_line
			(start 0.67945 0.3048)
			(end 0.120396 0.3048)
			(stroke
				(width 0.1)
				(type default)
			)
			(layer "F.Fab")
		)
		(pad "1" smd circle
			(at -0.40005 0)
			(size 0 0)
			(layers "F.Cu" "F.Mask" "F.Paste")
			(net "PWR_EN_PEX_R")
		)
		(pad "2" smd circle
			(at 0.40005 0)
			(size 0 0)
			(layers "F.Cu" "F.Mask" "F.Paste")
			(net "PWR_EN_PEX")
		)
	)
	(footprint ""
		(layer "F.Cu")
		(at 238.28375 -59.751976 -90)
		(property "Reference" "PR7079"
			(at 0 0 270)
			(layer "F.SilkS")
			(hide yes)
			(effects
				(font
					(size 1.27 1.27)
				)
			)
		)
		(property "Value" ""
			(at 0 0 270)
			(layer "F.Fab")
			(effects
				(font
					(size 1.27 1.27)
				)
			)
		)
		(duplicate_pad_numbers_are_jumpers no)
		(fp_line
			(start -0.7874 0.4064)
			(end -0.7874 -0.4064)
			(stroke
				(width 0.1524)
				(type default)
			)
			(layer "F.SilkS")
		)
		(fp_line
			(start 0.7874 0.4064)
			(end -0.7874 0.4064)
			(stroke
				(width 0.1524)
				(type default)
			)
			(layer "F.SilkS")
		)
		(fp_line
			(start -0.7874 -0.4064)
			(end 0.7874 -0.4064)
			(stroke
				(width 0.1524)
				(type default)
			)
			(layer "F.SilkS")
		)
		(fp_line
			(start 0.7874 -0.4064)
			(end 0.7874 0.4064)
			(stroke
				(width 0.1524)
				(type default)
			)
			(layer "F.SilkS")
		)
		(fp_line
			(start -0.67945 0.3048)
			(end -0.67945 -0.305054)
			(stroke
				(width 0.1)
				(type default)
			)
			(layer "F.Fab")
		)
		(fp_line
			(start -0.12065 0.3048)
			(end -0.67945 0.3048)
			(stroke
				(width 0.1)
				(type default)
			)
			(layer "F.Fab")
		)
		(fp_line
			(start 0.120396 0.3048)
			(end 0.120396 0.2794)
			(stroke
				(width 0.1)
				(type default)
			)
			(layer "F.Fab")
		)
		(fp_line
			(start 0.67945 0.3048)
			(end 0.120396 0.3048)
			(stroke
				(width 0.1)
				(type default)
			)
			(layer "F.Fab")
		)
		(fp_line
			(start -0.12065 0.2794)
			(end -0.12065 0.3048)
			(stroke
				(width 0.1)
				(type default)
			)
			(layer "F.Fab")
		)
		(fp_line
			(start 0.120396 0.2794)
			(end -0.12065 0.2794)
			(stroke
				(width 0.1)
				(type default)
			)
			(layer "F.Fab")
		)
		(fp_line
			(start -0.12065 -0.2794)
			(end 0.12065 -0.2794)
			(stroke
				(width 0.1)
				(type default)
			)
			(layer "F.Fab")
		)
		(fp_line
			(start 0.12065 -0.2794)
			(end 0.12065 -0.3048)
			(stroke
				(width 0.1)
				(type default)
			)
			(layer "F.Fab")
		)
		(fp_line
			(start 0.12065 -0.3048)
			(end 0.67945 -0.3048)
			(stroke
				(width 0.1)
				(type default)
			)
			(layer "F.Fab")
		)
		(fp_line
			(start 0.67945 -0.3048)
			(end 0.67945 0.3048)
			(stroke
				(width 0.1)
				(type default)
			)
			(layer "F.Fab")
		)
		(fp_line
			(start -0.67945 -0.305054)
			(end -0.12065 -0.305054)
			(stroke
				(width 0.1)
				(type default)
			)
			(layer "F.Fab")
		)
		(fp_line
			(start -0.12065 -0.305054)
			(end -0.12065 -0.2794)
			(stroke
				(width 0.1)
				(type default)
			)
			(layer "F.Fab")
		)
		(pad "1" smd circle
			(at -0.40005 0 270)
			(size 0 0)
			(layers "F.Cu" "F.Mask" "F.Paste")
			(net "P12V_SSD8_PG_G1")
		)
		(pad "2" smd circle
			(at 0.40005 0 270)
			(size 0 0)
			(layers "F.Cu" "F.Mask" "F.Paste")
			(net "GND")
		)
	)
	(footprint ""
		(layer "F.Cu")
		(at 265.311382 -258.234434)
		(property "Reference" "L125"
			(at 0 0 0)
			(layer "F.SilkS")
			(hide yes)
			(effects
				(font
					(size 1.27 1.27)
				)
			)
		)
		(property "Value" ""
			(at 0 0 0)
			(layer "F.Fab")
			(effects
				(font
					(size 1.27 1.27)
				)
			)
		)
		(duplicate_pad_numbers_are_jumpers no)
		(fp_line
			(start -1.63576 -0.8128)
			(end -1.63576 0.8128)
			(stroke
				(width 0.1524)
				(type default)
			)
			(layer "F.SilkS")
		)
		(fp_line
			(start -1.63576 -0.8128)
			(end 1.63576 -0.8128)
			(stroke
				(width 0.1524)
				(type default)
			)
			(layer "F.SilkS")
		)
		(fp_line
			(start 1.63576 -0.8128)
			(end 1.63576 0.8128)
			(stroke
				(width 0.1524)
				(type default)
			)
			(layer "F.SilkS")
		)
		(fp_line
			(start 1.63576 0.8128)
			(end -1.63576 0.8128)
			(stroke
				(width 0.1524)
				(type default)
			)
			(layer "F.SilkS")
		)
		(fp_line
			(start -1.56083 -0.738632)
			(end -1.56083 0.7366)
			(stroke
				(width 0.1)
				(type default)
			)
			(layer "F.Fab")
		)
		(fp_line
			(start -1.56083 0.7366)
			(end -1.524 0.7366)
			(stroke
				(width 0.1)
				(type default)
			)
			(layer "F.Fab")
		)
		(fp_line
			(start -1.524 0.7366)
			(end 1.524 0.7366)
			(stroke
				(width 0.1)
				(type default)
			)
			(layer "F.Fab")
		)
		(fp_line
			(start 1.524 0.7366)
			(end 1.560576 0.7366)
			(stroke
				(width 0.1)
				(type default)
			)
			(layer "F.Fab")
		)
		(fp_line
			(start 1.560576 -0.738632)
			(end -1.56083 -0.738632)
			(stroke
				(width 0.1)
				(type default)
			)
			(layer "F.Fab")
		)
		(fp_line
			(start 1.560576 0.7366)
			(end 1.560576 -0.738632)
			(stroke
				(width 0.1)
				(type default)
			)
			(layer "F.Fab")
		)
		(pad "1" smd rect
			(at -0.94996 0 180)
			(size 1.1176 1.3716)
			(layers "F.Cu" "F.Mask" "F.Paste")
			(net "P1V8_PLL0_PEX2")
		)
		(pad "2" smd rect
			(at 0.94996 0 180)
			(size 1.1176 1.3716)
			(layers "F.Cu" "F.Mask" "F.Paste")
			(net "PCEPLL5_VDDA18_PEX2")
		)
	)
	(footprint ""
		(layer "F.Cu")
		(at 394.734542 -30.03169 180)
		(property "Reference" "C711"
			(at 0 0 180)
			(layer "F.SilkS")
			(hide yes)
			(effects
				(font
					(size 1.27 1.27)
				)
			)
		)
		(property "Value" ""
			(at 0 0 180)
			(layer "F.Fab")
			(effects
				(font
					(size 1.27 1.27)
				)
			)
		)
		(duplicate_pad_numbers_are_jumpers no)
		(fp_line
			(start 0.299974 0.150114)
			(end -0.299974 0.150114)
			(stroke
				(width 0.1)
				(type default)
			)
			(layer "F.Fab")
		)
		(fp_line
			(start 0.299974 -0.150114)
			(end 0.299974 0.150114)
			(stroke
				(width 0.1)
				(type default)
			)
			(layer "F.Fab")
		)
		(fp_line
			(start -0.299974 0.150114)
			(end -0.299974 -0.150114)
			(stroke
				(width 0.1)
				(type default)
			)
			(layer "F.Fab")
		)
		(fp_line
			(start -0.299974 -0.150114)
			(end 0.299974 -0.150114)
			(stroke
				(width 0.1)
				(type default)
			)
			(layer "F.Fab")
		)
		(pad "1" smd rect
			(at -0.2667 0 180)
			(size 0.3048 0.381)
			(layers "F.Cu" "F.Mask" "F.Paste")
			(net "P5E_PEX3_STN2_TX_DN<41>")
		)
		(pad "2" smd rect
			(at 0.2667 0 180)
			(size 0.3048 0.381)
			(layers "F.Cu" "F.Mask" "F.Paste")
			(net "P5E_PEX3_STN2_TX_C_DN<41>")
		)
	)
	(footprint ""
		(layer "F.Cu")
		(at 78.912974 -8.891778 180)
		(property "Reference" "C3870"
			(at 0 0 180)
			(layer "F.SilkS")
			(hide yes)
			(effects
				(font
					(size 1.27 1.27)
				)
			)
		)
		(property "Value" ""
			(at 0 0 180)
			(layer "F.Fab")
			(effects
				(font
					(size 1.27 1.27)
				)
			)
		)
		(duplicate_pad_numbers_are_jumpers no)
		(fp_line
			(start 0.7874 0.4064)
			(end -0.7874 0.4064)
			(stroke
				(width 0.1524)
				(type default)
			)
			(layer "F.SilkS")
		)
		(fp_line
			(start 0.7874 -0.4064)
			(end 0.7874 0.4064)
			(stroke
				(width 0.1524)
				(type default)
			)
			(layer "F.SilkS")
		)
		(fp_line
			(start -0.7874 0.4064)
			(end -0.7874 -0.4064)
			(stroke
				(width 0.1524)
				(type default)
			)
			(layer "F.SilkS")
		)
		(fp_line
			(start -0.7874 -0.4064)
			(end 0.7874 -0.4064)
			(stroke
				(width 0.1524)
				(type default)
			)
			(layer "F.SilkS")
		)
		(fp_line
			(start 0.67945 0.3048)
			(end 0.120396 0.3048)
			(stroke
				(width 0.1)
				(type default)
			)
			(layer "F.Fab")
		)
		(fp_line
			(start 0.67945 -0.3048)
			(end 0.67945 0.3048)
			(stroke
				(width 0.1)
				(type default)
			)
			(layer "F.Fab")
		)
		(fp_line
			(start 0.12065 -0.2794)
			(end 0.12065 -0.3048)
			(stroke
				(width 0.1)
				(type default)
			)
			(layer "F.Fab")
		)
		(fp_line
			(start 0.12065 -0.3048)
			(end 0.67945 -0.3048)
			(stroke
				(width 0.1)
				(type default)
			)
			(layer "F.Fab")
		)
		(fp_line
			(start 0.120396 0.3048)
			(end 0.120396 0.2794)
			(stroke
				(width 0.1)
				(type default)
			)
			(layer "F.Fab")
		)
		(fp_line
			(start 0.120396 0.2794)
			(end -0.12065 0.2794)
			(stroke
				(width 0.1)
				(type default)
			)
			(layer "F.Fab")
		)
		(fp_line
			(start -0.12065 0.3048)
			(end -0.67945 0.3048)
			(stroke
				(width 0.1)
				(type default)
			)
			(layer "F.Fab")
		)
		(fp_line
			(start -0.12065 0.2794)
			(end -0.12065 0.3048)
			(stroke
				(width 0.1)
				(type default)
			)
			(layer "F.Fab")
		)
		(fp_line
			(start -0.12065 -0.2794)
			(end 0.12065 -0.2794)
			(stroke
				(width 0.1)
				(type default)
			)
			(layer "F.Fab")
		)
		(fp_line
			(start -0.12065 -0.305054)
			(end -0.12065 -0.2794)
			(stroke
				(width 0.1)
				(type default)
			)
			(layer "F.Fab")
		)
		(fp_line
			(start -0.67945 0.3048)
			(end -0.67945 -0.305054)
			(stroke
				(width 0.1)
				(type default)
			)
			(layer "F.Fab")
		)
		(fp_line
			(start -0.67945 -0.305054)
			(end -0.12065 -0.305054)
			(stroke
				(width 0.1)
				(type default)
			)
			(layer "F.Fab")
		)
		(pad "1" smd circle
			(at -0.40005 0 180)
			(size 0 0)
			(layers "F.Cu" "F.Mask" "F.Paste")
			(net "P3V3_AUX")
		)
		(pad "2" smd circle
			(at 0.40005 0 180)
			(size 0 0)
			(layers "F.Cu" "F.Mask" "F.Paste")
			(net "GND")
		)
	)
	(footprint ""
		(layer "F.Cu")
		(at 62.96279 -382.538732 180)
		(property "Reference" "C4030"
			(at 0 0 180)
			(layer "F.SilkS")
			(hide yes)
			(effects
				(font
					(size 1.27 1.27)
				)
			)
		)
		(property "Value" ""
			(at 0 0 180)
			(layer "F.Fab")
			(effects
				(font
					(size 1.27 1.27)
				)
			)
		)
		(duplicate_pad_numbers_are_jumpers no)
		(fp_line
			(start 0.7874 0.4064)
			(end -0.7874 0.4064)
			(stroke
				(width 0.1524)
				(type default)
			)
			(layer "F.SilkS")
		)
		(fp_line
			(start 0.7874 -0.4064)
			(end 0.7874 0.4064)
			(stroke
				(width 0.1524)
				(type default)
			)
			(layer "F.SilkS")
		)
		(fp_line
			(start -0.7874 0.4064)
			(end -0.7874 -0.4064)
			(stroke
				(width 0.1524)
				(type default)
			)
			(layer "F.SilkS")
		)
		(fp_line
			(start -0.7874 -0.4064)
			(end 0.7874 -0.4064)
			(stroke
				(width 0.1524)
				(type default)
			)
			(layer "F.SilkS")
		)
		(fp_line
			(start 0.67945 0.3048)
			(end 0.120396 0.3048)
			(stroke
				(width 0.1)
				(type default)
			)
			(layer "F.Fab")
		)
		(fp_line
			(start 0.67945 -0.3048)
			(end 0.67945 0.3048)
			(stroke
				(width 0.1)
				(type default)
			)
			(layer "F.Fab")
		)
		(fp_line
			(start 0.12065 -0.2794)
			(end 0.12065 -0.3048)
			(stroke
				(width 0.1)
				(type default)
			)
			(layer "F.Fab")
		)
		(fp_line
			(start 0.12065 -0.3048)
			(end 0.67945 -0.3048)
			(stroke
				(width 0.1)
				(type default)
			)
			(layer "F.Fab")
		)
		(fp_line
			(start 0.120396 0.3048)
			(end 0.120396 0.2794)
			(stroke
				(width 0.1)
				(type default)
			)
			(layer "F.Fab")
		)
		(fp_line
			(start 0.120396 0.2794)
			(end -0.12065 0.2794)
			(stroke
				(width 0.1)
				(type default)
			)
			(layer "F.Fab")
		)
		(fp_line
			(start -0.12065 0.3048)
			(end -0.67945 0.3048)
			(stroke
				(width 0.1)
				(type default)
			)
			(layer "F.Fab")
		)
		(fp_line
			(start -0.12065 0.2794)
			(end -0.12065 0.3048)
			(stroke
				(width 0.1)
				(type default)
			)
			(layer "F.Fab")
		)
		(fp_line
			(start -0.12065 -0.2794)
			(end 0.12065 -0.2794)
			(stroke
				(width 0.1)
				(type default)
			)
			(layer "F.Fab")
		)
		(fp_line
			(start -0.12065 -0.305054)
			(end -0.12065 -0.2794)
			(stroke
				(width 0.1)
				(type default)
			)
			(layer "F.Fab")
		)
		(fp_line
			(start -0.67945 0.3048)
			(end -0.67945 -0.305054)
			(stroke
				(width 0.1)
				(type default)
			)
			(layer "F.Fab")
		)
		(fp_line
			(start -0.67945 -0.305054)
			(end -0.12065 -0.305054)
			(stroke
				(width 0.1)
				(type default)
			)
			(layer "F.Fab")
		)
		(pad "1" smd circle
			(at -0.40005 0 180)
			(size 0 0)
			(layers "F.Cu" "F.Mask" "F.Paste")
			(net "GND")
		)
		(pad "2" smd circle
			(at 0.40005 0 180)
			(size 0 0)
			(layers "F.Cu" "F.Mask" "F.Paste")
			(net "RST_MB_PERST_2_N")
		)
	)
	(footprint ""
		(layer "F.Cu")
		(at 82.90179 -32.849312 90)
		(property "Reference" "R5658"
			(at 0 0 90)
			(layer "F.SilkS")
			(hide yes)
			(effects
				(font
					(size 1.27 1.27)
				)
			)
		)
		(property "Value" ""
			(at 0 0 90)
			(layer "F.Fab")
			(effects
				(font
					(size 1.27 1.27)
				)
			)
		)
		(duplicate_pad_numbers_are_jumpers no)
		(fp_line
			(start 0.7874 -0.4064)
			(end 0.7874 0.4064)
			(stroke
				(width 0.1524)
				(type default)
			)
			(layer "F.SilkS")
		)
		(fp_line
			(start -0.7874 -0.4064)
			(end 0.7874 -0.4064)
			(stroke
				(width 0.1524)
				(type default)
			)
			(layer "F.SilkS")
		)
		(fp_line
			(start 0.7874 0.4064)
			(end -0.7874 0.4064)
			(stroke
				(width 0.1524)
				(type default)
			)
			(layer "F.SilkS")
		)
		(fp_line
			(start -0.7874 0.4064)
			(end -0.7874 -0.4064)
			(stroke
				(width 0.1524)
				(type default)
			)
			(layer "F.SilkS")
		)
		(fp_line
			(start -0.12065 -0.305054)
			(end -0.12065 -0.2794)
			(stroke
				(width 0.1)
				(type default)
			)
			(layer "F.Fab")
		)
		(fp_line
			(start -0.67945 -0.305054)
			(end -0.12065 -0.305054)
			(stroke
				(width 0.1)
				(type default)
			)
			(layer "F.Fab")
		)
		(fp_line
			(start 0.67945 -0.3048)
			(end 0.67945 0.3048)
			(stroke
				(width 0.1)
				(type default)
			)
			(layer "F.Fab")
		)
		(fp_line
			(start 0.12065 -0.3048)
			(end 0.67945 -0.3048)
			(stroke
				(width 0.1)
				(type default)
			)
			(layer "F.Fab")
		)
		(fp_line
			(start 0.12065 -0.2794)
			(end 0.12065 -0.3048)
			(stroke
				(width 0.1)
				(type default)
			)
			(layer "F.Fab")
		)
		(fp_line
			(start -0.12065 -0.2794)
			(end 0.12065 -0.2794)
			(stroke
				(width 0.1)
				(type default)
			)
			(layer "F.Fab")
		)
		(fp_line
			(start 0.120396 0.2794)
			(end -0.12065 0.2794)
			(stroke
				(width 0.1)
				(type default)
			)
			(layer "F.Fab")
		)
		(fp_line
			(start -0.12065 0.2794)
			(end -0.12065 0.3048)
			(stroke
				(width 0.1)
				(type default)
			)
			(layer "F.Fab")
		)
		(fp_line
			(start 0.67945 0.3048)
			(end 0.120396 0.3048)
			(stroke
				(width 0.1)
				(type default)
			)
			(layer "F.Fab")
		)
		(fp_line
			(start 0.120396 0.3048)
			(end 0.120396 0.2794)
			(stroke
				(width 0.1)
				(type default)
			)
			(layer "F.Fab")
		)
		(fp_line
			(start -0.12065 0.3048)
			(end -0.67945 0.3048)
			(stroke
				(width 0.1)
				(type default)
			)
			(layer "F.Fab")
		)
		(fp_line
			(start -0.67945 0.3048)
			(end -0.67945 -0.305054)
			(stroke
				(width 0.1)
				(type default)
			)
			(layer "F.Fab")
		)
		(pad "1" smd circle
			(at -0.40005 0 90)
			(size 0 0)
			(layers "F.Cu" "F.Mask" "F.Paste")
			(net "RST_SMB_SSD3_ISO_R_N")
		)
		(pad "2" smd circle
			(at 0.40005 0 90)
			(size 0 0)
			(layers "F.Cu" "F.Mask" "F.Paste")
			(net "RST_SMB_SSD3_ISO_N")
		)
	)
	(footprint ""
		(layer "F.Cu")
		(at 194.367912 -54.067456)
		(property "Reference" "PR218"
			(at 0 0 0)
			(layer "F.SilkS")
			(hide yes)
			(effects
				(font
					(size 1.27 1.27)
				)
			)
		)
		(property "Value" ""
			(at 0 0 0)
			(layer "F.Fab")
			(effects
				(font
					(size 1.27 1.27)
				)
			)
		)
		(duplicate_pad_numbers_are_jumpers no)
		(fp_line
			(start -0.7874 -0.4064)
			(end 0.7874 -0.4064)
			(stroke
				(width 0.1524)
				(type default)
			)
			(layer "F.SilkS")
		)
		(fp_line
			(start -0.7874 0.4064)
			(end -0.7874 -0.4064)
			(stroke
				(width 0.1524)
				(type default)
			)
			(layer "F.SilkS")
		)
		(fp_line
			(start 0.7874 -0.4064)
			(end 0.7874 0.4064)
			(stroke
				(width 0.1524)
				(type default)
			)
			(layer "F.SilkS")
		)
		(fp_line
			(start 0.7874 0.4064)
			(end -0.7874 0.4064)
			(stroke
				(width 0.1524)
				(type default)
			)
			(layer "F.SilkS")
		)
		(fp_line
			(start -0.67945 -0.305054)
			(end -0.12065 -0.305054)
			(stroke
				(width 0.1)
				(type default)
			)
			(layer "F.Fab")
		)
		(fp_line
			(start -0.67945 0.3048)
			(end -0.67945 -0.305054)
			(stroke
				(width 0.1)
				(type default)
			)
			(layer "F.Fab")
		)
		(fp_line
			(start -0.12065 -0.305054)
			(end -0.12065 -0.2794)
			(stroke
				(width 0.1)
				(type default)
			)
			(layer "F.Fab")
		)
		(fp_line
			(start -0.12065 -0.2794)
			(end 0.12065 -0.2794)
			(stroke
				(width 0.1)
				(type default)
			)
			(layer "F.Fab")
		)
		(fp_line
			(start -0.12065 0.2794)
			(end -0.12065 0.3048)
			(stroke
				(width 0.1)
				(type default)
			)
			(layer "F.Fab")
		)
		(fp_line
			(start -0.12065 0.3048)
			(end -0.67945 0.3048)
			(stroke
				(width 0.1)
				(type default)
			)
			(layer "F.Fab")
		)
		(fp_line
			(start 0.120396 0.2794)
			(end -0.12065 0.2794)
			(stroke
				(width 0.1)
				(type default)
			)
			(layer "F.Fab")
		)
		(fp_line
			(start 0.120396 0.3048)
			(end 0.120396 0.2794)
			(stroke
				(width 0.1)
				(type default)
			)
			(layer "F.Fab")
		)
		(fp_line
			(start 0.12065 -0.3048)
			(end 0.67945 -0.3048)
			(stroke
				(width 0.1)
				(type default)
			)
			(layer "F.Fab")
		)
		(fp_line
			(start 0.12065 -0.2794)
			(end 0.12065 -0.3048)
			(stroke
				(width 0.1)
				(type default)
			)
			(layer "F.Fab")
		)
		(fp_line
			(start 0.67945 -0.3048)
			(end 0.67945 0.3048)
			(stroke
				(width 0.1)
				(type default)
			)
			(layer "F.Fab")
		)
		(fp_line
			(start 0.67945 0.3048)
			(end 0.120396 0.3048)
			(stroke
				(width 0.1)
				(type default)
			)
			(layer "F.Fab")
		)
		(pad "1" smd circle
			(at -0.40005 0)
			(size 0 0)
			(layers "F.Cu" "F.Mask" "F.Paste")
			(net "P12V_SSD6_OCP")
		)
		(pad "2" smd circle
			(at 0.40005 0)
			(size 0 0)
			(layers "F.Cu" "F.Mask" "F.Paste")
			(net "GND")
		)
	)
	(footprint ""
		(layer "F.Cu")
		(at 461.614012 -550.105834 180)
		(property "Reference" "SCREW_SSD13_1"
			(at -5.6007 -1.402334 0)
			(unlocked yes)
			(layer "B.SilkS")
			(effects
				(font
					(size 0.7874 0.5842)
					(thickness 0.1524)
				)
				(justify mirror)
			)
		)
		(property "Value" ""
			(at 0 0 180)
			(layer "F.Fab")
			(effects
				(font
					(size 1.27 1.27)
				)
			)
		)
		(duplicate_pad_numbers_are_jumpers no)
		(pad "1" thru_hole circle
			(at 0 0 180)
			(size 0.4572 0.4572)
			(drill 0.2032)
			(layers "*.Cu" "*.Mask")
			(remove_unused_layers no)
			(net "Net_9148")
			(clearance 0.127)
			(thermal_gap 0.127)
			(padstack
				(mode front_inner_back)
				(layer "Inner"
					(shape circle)
					(size 0.4572 0.4572)
					(clearance 0.127)
				)
				(layer "B.Cu"
					(shape circle)
					(size 0.508 0.508)
					(clearance 0.1016)
				)
			)
		)
	)
	(footprint ""
		(layer "F.Cu")
		(at 460.31531 -258.331208 -90)
		(property "Reference" "R6563"
			(at 0 0 270)
			(layer "F.SilkS")
			(hide yes)
			(effects
				(font
					(size 1.27 1.27)
				)
			)
		)
		(property "Value" ""
			(at 0 0 270)
			(layer "F.Fab")
			(effects
				(font
					(size 1.27 1.27)
				)
			)
		)
		(duplicate_pad_numbers_are_jumpers no)
		(fp_line
			(start -0.7874 0.4064)
			(end -0.7874 -0.4064)
			(stroke
				(width 0.1524)
				(type default)
			)
			(layer "F.SilkS")
		)
		(fp_line
			(start 0.7874 0.4064)
			(end -0.7874 0.4064)
			(stroke
				(width 0.1524)
				(type default)
			)
			(layer "F.SilkS")
		)
		(fp_line
			(start -0.7874 -0.4064)
			(end 0.7874 -0.4064)
			(stroke
				(width 0.1524)
				(type default)
			)
			(layer "F.SilkS")
		)
		(fp_line
			(start 0.7874 -0.4064)
			(end 0.7874 0.4064)
			(stroke
				(width 0.1524)
				(type default)
			)
			(layer "F.SilkS")
		)
		(fp_line
			(start -0.67945 0.3048)
			(end -0.67945 -0.305054)
			(stroke
				(width 0.1)
				(type default)
			)
			(layer "F.Fab")
		)
		(fp_line
			(start -0.12065 0.3048)
			(end -0.67945 0.3048)
			(stroke
				(width 0.1)
				(type default)
			)
			(layer "F.Fab")
		)
		(fp_line
			(start 0.120396 0.3048)
			(end 0.120396 0.2794)
			(stroke
				(width 0.1)
				(type default)
			)
			(layer "F.Fab")
		)
		(fp_line
			(start 0.67945 0.3048)
			(end 0.120396 0.3048)
			(stroke
				(width 0.1)
				(type default)
			)
			(layer "F.Fab")
		)
		(fp_line
			(start -0.12065 0.2794)
			(end -0.12065 0.3048)
			(stroke
				(width 0.1)
				(type default)
			)
			(layer "F.Fab")
		)
		(fp_line
			(start 0.120396 0.2794)
			(end -0.12065 0.2794)
			(stroke
				(width 0.1)
				(type default)
			)
			(layer "F.Fab")
		)
		(fp_line
			(start -0.12065 -0.2794)
			(end 0.12065 -0.2794)
			(stroke
				(width 0.1)
				(type default)
			)
			(layer "F.Fab")
		)
		(fp_line
			(start 0.12065 -0.2794)
			(end 0.12065 -0.3048)
			(stroke
				(width 0.1)
				(type default)
			)
			(layer "F.Fab")
		)
		(fp_line
			(start 0.12065 -0.3048)
			(end 0.67945 -0.3048)
			(stroke
				(width 0.1)
				(type default)
			)
			(layer "F.Fab")
		)
		(fp_line
			(start 0.67945 -0.3048)
			(end 0.67945 0.3048)
			(stroke
				(width 0.1)
				(type default)
			)
			(layer "F.Fab")
		)
		(fp_line
			(start -0.67945 -0.305054)
			(end -0.12065 -0.305054)
			(stroke
				(width 0.1)
				(type default)
			)
			(layer "F.Fab")
		)
		(fp_line
			(start -0.12065 -0.305054)
			(end -0.12065 -0.2794)
			(stroke
				(width 0.1)
				(type default)
			)
			(layer "F.Fab")
		)
		(pad "1" smd circle
			(at -0.40005 0 270)
			(size 0 0)
			(layers "F.Cu" "F.Mask" "F.Paste")
			(net "P1V25_SERDES_VDDPLL_PEX3")
		)
		(pad "2" smd circle
			(at 0.40005 0 270)
			(size 0 0)
			(layers "F.Cu" "F.Mask" "F.Paste")
			(net "P1V25_SERDES_VDDPLL_PEX3_C10")
		)
	)
	(footprint ""
		(layer "F.Cu")
		(at 168.367964 -55.083456)
		(property "Reference" "PC396"
			(at 0 0 0)
			(layer "F.SilkS")
			(hide yes)
			(effects
				(font
					(size 1.27 1.27)
				)
			)
		)
		(property "Value" ""
			(at 0 0 0)
			(layer "F.Fab")
			(effects
				(font
					(size 1.27 1.27)
				)
			)
		)
		(duplicate_pad_numbers_are_jumpers no)
		(fp_line
			(start -0.7874 -0.4064)
			(end 0.7874 -0.4064)
			(stroke
				(width 0.1524)
				(type default)
			)
			(layer "F.SilkS")
		)
		(fp_line
			(start -0.7874 0.4064)
			(end -0.7874 -0.4064)
			(stroke
				(width 0.1524)
				(type default)
			)
			(layer "F.SilkS")
		)
		(fp_line
			(start 0.7874 -0.4064)
			(end 0.7874 0.4064)
			(stroke
				(width 0.1524)
				(type default)
			)
			(layer "F.SilkS")
		)
		(fp_line
			(start 0.7874 0.4064)
			(end -0.7874 0.4064)
			(stroke
				(width 0.1524)
				(type default)
			)
			(layer "F.SilkS")
		)
		(fp_line
			(start -0.67945 -0.305054)
			(end -0.12065 -0.305054)
			(stroke
				(width 0.1)
				(type default)
			)
			(layer "F.Fab")
		)
		(fp_line
			(start -0.67945 0.3048)
			(end -0.67945 -0.305054)
			(stroke
				(width 0.1)
				(type default)
			)
			(layer "F.Fab")
		)
		(fp_line
			(start -0.12065 -0.305054)
			(end -0.12065 -0.2794)
			(stroke
				(width 0.1)
				(type default)
			)
			(layer "F.Fab")
		)
		(fp_line
			(start -0.12065 -0.2794)
			(end 0.12065 -0.2794)
			(stroke
				(width 0.1)
				(type default)
			)
			(layer "F.Fab")
		)
		(fp_line
			(start -0.12065 0.2794)
			(end -0.12065 0.3048)
			(stroke
				(width 0.1)
				(type default)
			)
			(layer "F.Fab")
		)
		(fp_line
			(start -0.12065 0.3048)
			(end -0.67945 0.3048)
			(stroke
				(width 0.1)
				(type default)
			)
			(layer "F.Fab")
		)
		(fp_line
			(start 0.120396 0.2794)
			(end -0.12065 0.2794)
			(stroke
				(width 0.1)
				(type default)
			)
			(layer "F.Fab")
		)
		(fp_line
			(start 0.120396 0.3048)
			(end 0.120396 0.2794)
			(stroke
				(width 0.1)
				(type default)
			)
			(layer "F.Fab")
		)
		(fp_line
			(start 0.12065 -0.3048)
			(end 0.67945 -0.3048)
			(stroke
				(width 0.1)
				(type default)
			)
			(layer "F.Fab")
		)
		(fp_line
			(start 0.12065 -0.2794)
			(end 0.12065 -0.3048)
			(stroke
				(width 0.1)
				(type default)
			)
			(layer "F.Fab")
		)
		(fp_line
			(start 0.67945 -0.3048)
			(end 0.67945 0.3048)
			(stroke
				(width 0.1)
				(type default)
			)
			(layer "F.Fab")
		)
		(fp_line
			(start 0.67945 0.3048)
			(end 0.120396 0.3048)
			(stroke
				(width 0.1)
				(type default)
			)
			(layer "F.Fab")
		)
		(pad "1" smd circle
			(at -0.40005 0)
			(size 0 0)
			(layers "F.Cu" "F.Mask" "F.Paste")
			(net "P5V_AUX")
		)
		(pad "2" smd circle
			(at 0.40005 0)
			(size 0 0)
			(layers "F.Cu" "F.Mask" "F.Paste")
			(net "GND")
		)
	)
	(footprint ""
		(layer "F.Cu")
		(at 83.293966 -34.248852)
		(property "Reference" "R5656"
			(at 0 0 0)
			(layer "F.SilkS")
			(hide yes)
			(effects
				(font
					(size 1.27 1.27)
				)
			)
		)
		(property "Value" ""
			(at 0 0 0)
			(layer "F.Fab")
			(effects
				(font
					(size 1.27 1.27)
				)
			)
		)
		(duplicate_pad_numbers_are_jumpers no)
		(fp_line
			(start -0.7874 -0.4064)
			(end 0.7874 -0.4064)
			(stroke
				(width 0.1524)
				(type default)
			)
			(layer "F.SilkS")
		)
		(fp_line
			(start -0.7874 0.4064)
			(end -0.7874 -0.4064)
			(stroke
				(width 0.1524)
				(type default)
			)
			(layer "F.SilkS")
		)
		(fp_line
			(start 0.7874 -0.4064)
			(end 0.7874 0.4064)
			(stroke
				(width 0.1524)
				(type default)
			)
			(layer "F.SilkS")
		)
		(fp_line
			(start 0.7874 0.4064)
			(end -0.7874 0.4064)
			(stroke
				(width 0.1524)
				(type default)
			)
			(layer "F.SilkS")
		)
		(fp_line
			(start -0.67945 -0.305054)
			(end -0.12065 -0.305054)
			(stroke
				(width 0.1)
				(type default)
			)
			(layer "F.Fab")
		)
		(fp_line
			(start -0.67945 0.3048)
			(end -0.67945 -0.305054)
			(stroke
				(width 0.1)
				(type default)
			)
			(layer "F.Fab")
		)
		(fp_line
			(start -0.12065 -0.305054)
			(end -0.12065 -0.2794)
			(stroke
				(width 0.1)
				(type default)
			)
			(layer "F.Fab")
		)
		(fp_line
			(start -0.12065 -0.2794)
			(end 0.12065 -0.2794)
			(stroke
				(width 0.1)
				(type default)
			)
			(layer "F.Fab")
		)
		(fp_line
			(start -0.12065 0.2794)
			(end -0.12065 0.3048)
			(stroke
				(width 0.1)
				(type default)
			)
			(layer "F.Fab")
		)
		(fp_line
			(start -0.12065 0.3048)
			(end -0.67945 0.3048)
			(stroke
				(width 0.1)
				(type default)
			)
			(layer "F.Fab")
		)
		(fp_line
			(start 0.120396 0.2794)
			(end -0.12065 0.2794)
			(stroke
				(width 0.1)
				(type default)
			)
			(layer "F.Fab")
		)
		(fp_line
			(start 0.120396 0.3048)
			(end 0.120396 0.2794)
			(stroke
				(width 0.1)
				(type default)
			)
			(layer "F.Fab")
		)
		(fp_line
			(start 0.12065 -0.3048)
			(end 0.67945 -0.3048)
			(stroke
				(width 0.1)
				(type default)
			)
			(layer "F.Fab")
		)
		(fp_line
			(start 0.12065 -0.2794)
			(end 0.12065 -0.3048)
			(stroke
				(width 0.1)
				(type default)
			)
			(layer "F.Fab")
		)
		(fp_line
			(start 0.67945 -0.3048)
			(end 0.67945 0.3048)
			(stroke
				(width 0.1)
				(type default)
			)
			(layer "F.Fab")
		)
		(fp_line
			(start 0.67945 0.3048)
			(end 0.120396 0.3048)
			(stroke
				(width 0.1)
				(type default)
			)
			(layer "F.Fab")
		)
		(pad "1" smd circle
			(at -0.40005 0)
			(size 0 0)
			(layers "F.Cu" "F.Mask" "F.Paste")
			(net "RST_SMB_SSD3_ISO_N")
		)
		(pad "2" smd circle
			(at 0.40005 0)
			(size 0 0)
			(layers "F.Cu" "F.Mask" "F.Paste")
			(net "P3V3_SSD3")
		)
	)
	(footprint ""
		(layer "F.Cu")
		(at 20.771104 -146.205956 180)
		(property "Reference" "C411"
			(at 0 0 180)
			(layer "F.SilkS")
			(hide yes)
			(effects
				(font
					(size 1.27 1.27)
				)
			)
		)
		(property "Value" ""
			(at 0 0 180)
			(layer "F.Fab")
			(effects
				(font
					(size 1.27 1.27)
				)
			)
		)
		(duplicate_pad_numbers_are_jumpers no)
		(fp_line
			(start 0.7874 0.4064)
			(end -0.7874 0.4064)
			(stroke
				(width 0.1524)
				(type default)
			)
			(layer "F.SilkS")
		)
		(fp_line
			(start 0.7874 -0.4064)
			(end 0.7874 0.4064)
			(stroke
				(width 0.1524)
				(type default)
			)
			(layer "F.SilkS")
		)
		(fp_line
			(start -0.7874 0.4064)
			(end -0.7874 -0.4064)
			(stroke
				(width 0.1524)
				(type default)
			)
			(layer "F.SilkS")
		)
		(fp_line
			(start -0.7874 -0.4064)
			(end 0.7874 -0.4064)
			(stroke
				(width 0.1524)
				(type default)
			)
			(layer "F.SilkS")
		)
		(fp_line
			(start 0.67945 0.3048)
			(end 0.120396 0.3048)
			(stroke
				(width 0.1)
				(type default)
			)
			(layer "F.Fab")
		)
		(fp_line
			(start 0.67945 -0.3048)
			(end 0.67945 0.3048)
			(stroke
				(width 0.1)
				(type default)
			)
			(layer "F.Fab")
		)
		(fp_line
			(start 0.12065 -0.2794)
			(end 0.12065 -0.3048)
			(stroke
				(width 0.1)
				(type default)
			)
			(layer "F.Fab")
		)
		(fp_line
			(start 0.12065 -0.3048)
			(end 0.67945 -0.3048)
			(stroke
				(width 0.1)
				(type default)
			)
			(layer "F.Fab")
		)
		(fp_line
			(start 0.120396 0.3048)
			(end 0.120396 0.2794)
			(stroke
				(width 0.1)
				(type default)
			)
			(layer "F.Fab")
		)
		(fp_line
			(start 0.120396 0.2794)
			(end -0.12065 0.2794)
			(stroke
				(width 0.1)
				(type default)
			)
			(layer "F.Fab")
		)
		(fp_line
			(start -0.12065 0.3048)
			(end -0.67945 0.3048)
			(stroke
				(width 0.1)
				(type default)
			)
			(layer "F.Fab")
		)
		(fp_line
			(start -0.12065 0.2794)
			(end -0.12065 0.3048)
			(stroke
				(width 0.1)
				(type default)
			)
			(layer "F.Fab")
		)
		(fp_line
			(start -0.12065 -0.2794)
			(end 0.12065 -0.2794)
			(stroke
				(width 0.1)
				(type default)
			)
			(layer "F.Fab")
		)
		(fp_line
			(start -0.12065 -0.305054)
			(end -0.12065 -0.2794)
			(stroke
				(width 0.1)
				(type default)
			)
			(layer "F.Fab")
		)
		(fp_line
			(start -0.67945 0.3048)
			(end -0.67945 -0.305054)
			(stroke
				(width 0.1)
				(type default)
			)
			(layer "F.Fab")
		)
		(fp_line
			(start -0.67945 -0.305054)
			(end -0.12065 -0.305054)
			(stroke
				(width 0.1)
				(type default)
			)
			(layer "F.Fab")
		)
		(pad "1" smd circle
			(at -0.40005 0 180)
			(size 0 0)
			(layers "F.Cu" "F.Mask" "F.Paste")
			(net "P12V_NIC0_VIN_P")
		)
		(pad "2" smd circle
			(at 0.40005 0 180)
			(size 0 0)
			(layers "F.Cu" "F.Mask" "F.Paste")
			(net "P12V_NIC0_VIN_N")
		)
	)
	(footprint ""
		(layer "F.Cu")
		(at 118.572534 -119.511826 90)
		(property "Reference" "PU70"
			(at -1.657096 3.245866 0)
			(unlocked yes)
			(layer "F.SilkS")
			(effects
				(font
					(size 0.7874 0.5842)
					(thickness 0.1524)
				)
			)
		)
		(property "Value" ""
			(at 0 0 90)
			(layer "F.Fab")
			(effects
				(font
					(size 1.27 1.27)
				)
			)
		)
		(duplicate_pad_numbers_are_jumpers no)
		(fp_line
			(start 1.239774 -1.495298)
			(end 1.239774 1.495298)
			(stroke
				(width 0.1524)
				(type default)
			)
			(layer "F.SilkS")
		)
		(fp_line
			(start -1.239774 -1.495298)
			(end 1.239774 -1.495298)
			(stroke
				(width 0.1524)
				(type default)
			)
			(layer "F.SilkS")
		)
		(fp_line
			(start 1.239774 1.495298)
			(end -1.239774 1.495298)
			(stroke
				(width 0.1524)
				(type default)
			)
			(layer "F.SilkS")
		)
		(fp_line
			(start -1.239774 1.495298)
			(end -1.239774 -1.495298)
			(stroke
				(width 0.1524)
				(type default)
			)
			(layer "F.SilkS")
		)
		(fp_poly
			(pts
				(xy -1.858264 -1.248918) (xy -2.576576 -0.530606) (xy -1.499108 -0.17145)
			)
			(stroke
				(width 0)
				(type default)
			)
			(fill yes)
			(layer "F.SilkS")
		)
		(fp_line
			(start 0.8001 -1.050036)
			(end 0.8001 1.050036)
			(stroke
				(width 0.1)
				(type default)
			)
			(layer "F.Fab")
		)
		(fp_line
			(start -0.8001 -1.050036)
			(end 0.8001 -1.050036)
			(stroke
				(width 0.1)
				(type default)
			)
			(layer "F.Fab")
		)
		(fp_line
			(start 0.8001 1.050036)
			(end -0.8001 1.050036)
			(stroke
				(width 0.1)
				(type default)
			)
			(layer "F.Fab")
		)
		(fp_line
			(start -0.8001 1.050036)
			(end -0.8001 -1.050036)
			(stroke
				(width 0.1)
				(type default)
			)
			(layer "F.Fab")
		)
		(fp_poly
			(pts
				(xy -2.458974 -0.508) (xy -2.458974 0.508) (xy -1.442974 0)
			)
			(stroke
				(width 0)
				(type default)
			)
			(fill yes)
			(layer "F.Fab")
		)
		(pad "1_2" smd circle
			(at -0.374904 0 180)
			(size 0 0)
			(layers "F.Cu" "F.Mask" "F.Paste")
			(net "P3V3_AUX")
		)
		(pad "3" smd rect
			(at -0.499872 0.999998 90)
			(size 0.254 0.7112)
			(layers "F.Cu" "F.Mask" "F.Paste")
			(net "GND")
		)
		(pad "4" smd rect
			(at 0 0.999998 90)
			(size 0.254 0.7112)
			(layers "F.Cu" "F.Mask" "F.Paste")
			(net "P3V3_CO_ILIMIT")
		)
		(pad "5" smd rect
			(at 0.499872 0.999998 90)
			(size 0.254 0.7112)
			(layers "F.Cu" "F.Mask" "F.Paste")
			(net "P3V3_CO_MODE")
		)
		(pad "6_7" smd circle
			(at 0.374904 0)
			(size 0 0)
			(layers "F.Cu" "F.Mask" "F.Paste")
			(net "P3V3")
		)
		(pad "8" smd rect
			(at 0.499872 -0.999998 90)
			(size 0.254 0.7112)
			(layers "F.Cu" "F.Mask" "F.Paste")
			(net "P3V3_CO_GATE")
		)
		(pad "9" smd rect
			(at 0 -0.999998 90)
			(size 0.254 0.7112)
			(layers "F.Cu" "F.Mask" "F.Paste")
			(net "P3V3_CO_EN")
		)
		(pad "10" smd rect
			(at -0.499872 -0.999998 90)
			(size 0.254 0.7112)
			(layers "F.Cu" "F.Mask" "F.Paste")
			(net "P3V3_CO_DV_DT")
		)
	)
	(footprint ""
		(layer "F.Cu")
		(at 320.354452 -219.579698 180)
		(property "Reference" "D18"
			(at 3.743452 -0.023368 0)
			(unlocked yes)
			(layer "F.SilkS")
			(effects
				(font
					(size 0.7874 0.5842)
					(thickness 0.1524)
				)
				(justify left)
			)
		)
		(property "Value" ""
			(at 0 0 180)
			(layer "F.Fab")
			(effects
				(font
					(size 1.27 1.27)
				)
			)
		)
		(duplicate_pad_numbers_are_jumpers no)
		(fp_line
			(start 1.16078 0.4826)
			(end -0.64008 0.4826)
			(stroke
				(width 0.1524)
				(type default)
			)
			(layer "F.SilkS")
		)
		(fp_line
			(start 1.16078 -0.4826)
			(end 1.16078 0.4826)
			(stroke
				(width 0.1524)
				(type default)
			)
			(layer "F.SilkS")
		)
		(fp_line
			(start 1.03378 0.4826)
			(end -0.79248 0.4826)
			(stroke
				(width 0.1524)
				(type default)
			)
			(layer "F.SilkS")
		)
		(fp_line
			(start 1.03378 -0.4826)
			(end 1.03378 0.4826)
			(stroke
				(width 0.1524)
				(type default)
			)
			(layer "F.SilkS")
		)
		(fp_line
			(start 0.90678 0.4826)
			(end -0.90678 0.4826)
			(stroke
				(width 0.1524)
				(type default)
			)
			(layer "F.SilkS")
		)
		(fp_line
			(start 0.90678 -0.4826)
			(end 0.90678 0.4826)
			(stroke
				(width 0.1524)
				(type default)
			)
			(layer "F.SilkS")
		)
		(fp_line
			(start -0.64008 -0.4826)
			(end 1.16078 -0.4826)
			(stroke
				(width 0.1524)
				(type default)
			)
			(layer "F.SilkS")
		)
		(fp_line
			(start -0.79248 -0.4826)
			(end 1.03378 -0.4826)
			(stroke
				(width 0.1524)
				(type default)
			)
			(layer "F.SilkS")
		)
		(fp_line
			(start -0.89408 -0.4826)
			(end 0.90678 -0.4826)
			(stroke
				(width 0.1524)
				(type default)
			)
			(layer "F.SilkS")
		)
		(fp_line
			(start -0.90678 0.4826)
			(end -0.90678 -0.4699)
			(stroke
				(width 0.1524)
				(type default)
			)
			(layer "F.SilkS")
		)
		(fp_line
			(start 0.499872 0.249936)
			(end -0.499872 0.249936)
			(stroke
				(width 0.1)
				(type default)
			)
			(layer "F.Fab")
		)
		(fp_line
			(start 0.499872 -0.249936)
			(end 0.499872 0.249936)
			(stroke
				(width 0.1)
				(type default)
			)
			(layer "F.Fab")
		)
		(fp_line
			(start -0.499872 0.249936)
			(end -0.499872 -0.249936)
			(stroke
				(width 0.1)
				(type default)
			)
			(layer "F.Fab")
		)
		(fp_line
			(start -0.499872 -0.249936)
			(end 0.499872 -0.249936)
			(stroke
				(width 0.1)
				(type default)
			)
			(layer "F.Fab")
		)
		(pad "A" smd rect
			(at -0.47498 0 180)
			(size 0.6096 0.7112)
			(layers "F.Cu" "F.Mask" "F.Paste")
			(net "LED_POSTCODE_R_5")
		)
		(pad "C" smd rect
			(at 0.47498 0 180)
			(size 0.6096 0.7112)
			(layers "F.Cu" "F.Mask" "F.Paste")
			(net "FPGA_DEBUG_LED_R_N")
		)
	)
	(footprint ""
		(layer "F.Cu")
		(at 219.202 -194.056)
		(property "Reference" "R1529"
			(at 0 0 0)
			(layer "F.SilkS")
			(hide yes)
			(effects
				(font
					(size 1.27 1.27)
				)
			)
		)
		(property "Value" ""
			(at 0 0 0)
			(layer "F.Fab")
			(effects
				(font
					(size 1.27 1.27)
				)
			)
		)
		(duplicate_pad_numbers_are_jumpers no)
		(fp_line
			(start -0.7874 -0.4064)
			(end 0.7874 -0.4064)
			(stroke
				(width 0.1524)
				(type default)
			)
			(layer "F.SilkS")
		)
		(fp_line
			(start -0.7874 0.4064)
			(end -0.7874 -0.4064)
			(stroke
				(width 0.1524)
				(type default)
			)
			(layer "F.SilkS")
		)
		(fp_line
			(start 0.7874 -0.4064)
			(end 0.7874 0.4064)
			(stroke
				(width 0.1524)
				(type default)
			)
			(layer "F.SilkS")
		)
		(fp_line
			(start 0.7874 0.4064)
			(end -0.7874 0.4064)
			(stroke
				(width 0.1524)
				(type default)
			)
			(layer "F.SilkS")
		)
		(fp_line
			(start -0.67945 -0.305054)
			(end -0.12065 -0.305054)
			(stroke
				(width 0.1)
				(type default)
			)
			(layer "F.Fab")
		)
		(fp_line
			(start -0.67945 0.3048)
			(end -0.67945 -0.305054)
			(stroke
				(width 0.1)
				(type default)
			)
			(layer "F.Fab")
		)
		(fp_line
			(start -0.12065 -0.305054)
			(end -0.12065 -0.2794)
			(stroke
				(width 0.1)
				(type default)
			)
			(layer "F.Fab")
		)
		(fp_line
			(start -0.12065 -0.2794)
			(end 0.12065 -0.2794)
			(stroke
				(width 0.1)
				(type default)
			)
			(layer "F.Fab")
		)
		(fp_line
			(start -0.12065 0.2794)
			(end -0.12065 0.3048)
			(stroke
				(width 0.1)
				(type default)
			)
			(layer "F.Fab")
		)
		(fp_line
			(start -0.12065 0.3048)
			(end -0.67945 0.3048)
			(stroke
				(width 0.1)
				(type default)
			)
			(layer "F.Fab")
		)
		(fp_line
			(start 0.120396 0.2794)
			(end -0.12065 0.2794)
			(stroke
				(width 0.1)
				(type default)
			)
			(layer "F.Fab")
		)
		(fp_line
			(start 0.120396 0.3048)
			(end 0.120396 0.2794)
			(stroke
				(width 0.1)
				(type default)
			)
			(layer "F.Fab")
		)
		(fp_line
			(start 0.12065 -0.3048)
			(end 0.67945 -0.3048)
			(stroke
				(width 0.1)
				(type default)
			)
			(layer "F.Fab")
		)
		(fp_line
			(start 0.12065 -0.2794)
			(end 0.12065 -0.3048)
			(stroke
				(width 0.1)
				(type default)
			)
			(layer "F.Fab")
		)
		(fp_line
			(start 0.67945 -0.3048)
			(end 0.67945 0.3048)
			(stroke
				(width 0.1)
				(type default)
			)
			(layer "F.Fab")
		)
		(fp_line
			(start 0.67945 0.3048)
			(end 0.120396 0.3048)
			(stroke
				(width 0.1)
				(type default)
			)
			(layer "F.Fab")
		)
		(pad "1" smd circle
			(at -0.40005 0)
			(size 0 0)
			(layers "F.Cu" "F.Mask" "F.Paste")
			(net "SMB_NIC7_LS_R_SDA")
		)
		(pad "2" smd circle
			(at 0.40005 0)
			(size 0 0)
			(layers "F.Cu" "F.Mask" "F.Paste")
			(net "P3V3_NIC7")
		)
	)
	(footprint ""
		(layer "F.Cu")
		(at 106.7816 -202.466956 90)
		(property "Reference" "R6630"
			(at 0 0 90)
			(layer "F.SilkS")
			(hide yes)
			(effects
				(font
					(size 1.27 1.27)
				)
			)
		)
		(property "Value" ""
			(at 0 0 90)
			(layer "F.Fab")
			(effects
				(font
					(size 1.27 1.27)
				)
			)
		)
		(duplicate_pad_numbers_are_jumpers no)
		(fp_line
			(start 0.7874 -0.4064)
			(end 0.7874 0.4064)
			(stroke
				(width 0.1524)
				(type default)
			)
			(layer "F.SilkS")
		)
		(fp_line
			(start -0.7874 -0.4064)
			(end 0.7874 -0.4064)
			(stroke
				(width 0.1524)
				(type default)
			)
			(layer "F.SilkS")
		)
		(fp_line
			(start 0.7874 0.4064)
			(end -0.7874 0.4064)
			(stroke
				(width 0.1524)
				(type default)
			)
			(layer "F.SilkS")
		)
		(fp_line
			(start -0.7874 0.4064)
			(end -0.7874 -0.4064)
			(stroke
				(width 0.1524)
				(type default)
			)
			(layer "F.SilkS")
		)
		(fp_line
			(start -0.12065 -0.305054)
			(end -0.12065 -0.2794)
			(stroke
				(width 0.1)
				(type default)
			)
			(layer "F.Fab")
		)
		(fp_line
			(start -0.67945 -0.305054)
			(end -0.12065 -0.305054)
			(stroke
				(width 0.1)
				(type default)
			)
			(layer "F.Fab")
		)
		(fp_line
			(start 0.67945 -0.3048)
			(end 0.67945 0.3048)
			(stroke
				(width 0.1)
				(type default)
			)
			(layer "F.Fab")
		)
		(fp_line
			(start 0.12065 -0.3048)
			(end 0.67945 -0.3048)
			(stroke
				(width 0.1)
				(type default)
			)
			(layer "F.Fab")
		)
		(fp_line
			(start 0.12065 -0.2794)
			(end 0.12065 -0.3048)
			(stroke
				(width 0.1)
				(type default)
			)
			(layer "F.Fab")
		)
		(fp_line
			(start -0.12065 -0.2794)
			(end 0.12065 -0.2794)
			(stroke
				(width 0.1)
				(type default)
			)
			(layer "F.Fab")
		)
		(fp_line
			(start 0.120396 0.2794)
			(end -0.12065 0.2794)
			(stroke
				(width 0.1)
				(type default)
			)
			(layer "F.Fab")
		)
		(fp_line
			(start -0.12065 0.2794)
			(end -0.12065 0.3048)
			(stroke
				(width 0.1)
				(type default)
			)
			(layer "F.Fab")
		)
		(fp_line
			(start 0.67945 0.3048)
			(end 0.120396 0.3048)
			(stroke
				(width 0.1)
				(type default)
			)
			(layer "F.Fab")
		)
		(fp_line
			(start 0.120396 0.3048)
			(end 0.120396 0.2794)
			(stroke
				(width 0.1)
				(type default)
			)
			(layer "F.Fab")
		)
		(fp_line
			(start -0.12065 0.3048)
			(end -0.67945 0.3048)
			(stroke
				(width 0.1)
				(type default)
			)
			(layer "F.Fab")
		)
		(fp_line
			(start -0.67945 0.3048)
			(end -0.67945 -0.305054)
			(stroke
				(width 0.1)
				(type default)
			)
			(layer "F.Fab")
		)
		(pad "1" smd circle
			(at -0.40005 0 90)
			(size 0 0)
			(layers "F.Cu" "F.Mask" "F.Paste")
			(net "UART_PEX1_CLI_CP2108_RX")
		)
		(pad "2" smd circle
			(at 0.40005 0 90)
			(size 0 0)
			(layers "F.Cu" "F.Mask" "F.Paste")
			(net "UART_PEX1_CLI_R_RX")
		)
	)
	(footprint ""
		(layer "F.Cu")
		(at 38.875208 -350.098614 90)
		(property "Reference" "C173"
			(at 0 0 90)
			(layer "F.SilkS")
			(hide yes)
			(effects
				(font
					(size 1.27 1.27)
				)
			)
		)
		(property "Value" ""
			(at 0 0 90)
			(layer "F.Fab")
			(effects
				(font
					(size 1.27 1.27)
				)
			)
		)
		(duplicate_pad_numbers_are_jumpers no)
		(fp_line
			(start 0.299974 -0.150114)
			(end 0.299974 0.150114)
			(stroke
				(width 0.1)
				(type default)
			)
			(layer "F.Fab")
		)
		(fp_line
			(start -0.299974 -0.150114)
			(end 0.299974 -0.150114)
			(stroke
				(width 0.1)
				(type default)
			)
			(layer "F.Fab")
		)
		(fp_line
			(start 0.299974 0.150114)
			(end -0.299974 0.150114)
			(stroke
				(width 0.1)
				(type default)
			)
			(layer "F.Fab")
		)
		(fp_line
			(start -0.299974 0.150114)
			(end -0.299974 -0.150114)
			(stroke
				(width 0.1)
				(type default)
			)
			(layer "F.Fab")
		)
		(pad "1" smd rect
			(at -0.2667 0 90)
			(size 0.3048 0.381)
			(layers "F.Cu" "F.Mask" "F.Paste")
			(net "P5E_PEX0_STN7_TX_DP<121>")
		)
		(pad "2" smd rect
			(at 0.2667 0 90)
			(size 0.3048 0.381)
			(layers "F.Cu" "F.Mask" "F.Paste")
			(net "P5E_PEX0_STN7_TX_C_DP<121>")
		)
	)
	(footprint ""
		(layer "F.Cu")
		(at 207.724502 -114.311176 90)
		(property "Reference" "PU102"
			(at 1.765554 -3.457702 0)
			(unlocked yes)
			(layer "F.SilkS")
			(effects
				(font
					(size 0.7874 0.5842)
					(thickness 0.1524)
				)
			)
		)
		(property "Value" ""
			(at 0 0 90)
			(layer "F.Fab")
			(effects
				(font
					(size 1.27 1.27)
				)
			)
		)
		(duplicate_pad_numbers_are_jumpers no)
		(fp_line
			(start 1.239774 -1.495298)
			(end 1.239774 1.495298)
			(stroke
				(width 0.1524)
				(type default)
			)
			(layer "F.SilkS")
		)
		(fp_line
			(start -1.239774 -1.495298)
			(end 1.239774 -1.495298)
			(stroke
				(width 0.1524)
				(type default)
			)
			(layer "F.SilkS")
		)
		(fp_line
			(start 1.239774 1.495298)
			(end -1.239774 1.495298)
			(stroke
				(width 0.1524)
				(type default)
			)
			(layer "F.SilkS")
		)
		(fp_line
			(start -1.239774 1.495298)
			(end -1.239774 -1.495298)
			(stroke
				(width 0.1524)
				(type default)
			)
			(layer "F.SilkS")
		)
		(fp_poly
			(pts
				(xy -1.82118 -1.277112) (xy -2.539492 -0.558546) (xy -1.462024 -0.19939)
			)
			(stroke
				(width 0)
				(type default)
			)
			(fill yes)
			(layer "F.SilkS")
		)
		(fp_line
			(start 0.8001 -1.050036)
			(end 0.8001 1.050036)
			(stroke
				(width 0.1)
				(type default)
			)
			(layer "F.Fab")
		)
		(fp_line
			(start -0.8001 -1.050036)
			(end 0.8001 -1.050036)
			(stroke
				(width 0.1)
				(type default)
			)
			(layer "F.Fab")
		)
		(fp_line
			(start 0.8001 1.050036)
			(end -0.8001 1.050036)
			(stroke
				(width 0.1)
				(type default)
			)
			(layer "F.Fab")
		)
		(fp_line
			(start -0.8001 1.050036)
			(end -0.8001 -1.050036)
			(stroke
				(width 0.1)
				(type default)
			)
			(layer "F.Fab")
		)
		(fp_poly
			(pts
				(xy -2.458974 -0.508) (xy -2.458974 0.508) (xy -1.442974 0)
			)
			(stroke
				(width 0)
				(type default)
			)
			(fill yes)
			(layer "F.Fab")
		)
		(pad "1_2" smd circle
			(at -0.374904 0 180)
			(size 0 0)
			(layers "F.Cu" "F.Mask" "F.Paste")
			(net "P3V3_AUX")
		)
		(pad "3" smd rect
			(at -0.499872 0.999998 90)
			(size 0.254 0.7112)
			(layers "F.Cu" "F.Mask" "F.Paste")
			(net "GND")
		)
		(pad "4" smd rect
			(at 0 0.999998 90)
			(size 0.254 0.7112)
			(layers "F.Cu" "F.Mask" "F.Paste")
			(net "P3V3_NIC3_CO_ILIMIT")
		)
		(pad "5" smd rect
			(at 0.499872 0.999998 90)
			(size 0.254 0.7112)
			(layers "F.Cu" "F.Mask" "F.Paste")
			(net "P3V3_NIC3_CO_MODE")
		)
		(pad "6_7" smd circle
			(at 0.374904 0)
			(size 0 0)
			(layers "F.Cu" "F.Mask" "F.Paste")
			(net "P3V3_NIC3")
		)
		(pad "8" smd rect
			(at 0.499872 -0.999998 90)
			(size 0.254 0.7112)
			(layers "F.Cu" "F.Mask" "F.Paste")
			(net "P3V3_NIC3_CO_GATE")
		)
		(pad "9" smd rect
			(at 0 -0.999998 90)
			(size 0.254 0.7112)
			(layers "F.Cu" "F.Mask" "F.Paste")
			(net "P3V3_NIC3_CO_EN")
		)
		(pad "10" smd rect
			(at -0.499872 -0.999998 90)
			(size 0.254 0.7112)
			(layers "F.Cu" "F.Mask" "F.Paste")
			(net "P3V3_NIC3_CO_DV_DT")
		)
	)
	(footprint ""
		(layer "F.Cu")
		(at 123.648978 -88.39073)
		(property "Reference" "R1589"
			(at 0 0 0)
			(layer "F.SilkS")
			(hide yes)
			(effects
				(font
					(size 1.27 1.27)
				)
			)
		)
		(property "Value" ""
			(at 0 0 0)
			(layer "F.Fab")
			(effects
				(font
					(size 1.27 1.27)
				)
			)
		)
		(duplicate_pad_numbers_are_jumpers no)
		(fp_line
			(start -0.7874 -0.4064)
			(end 0.7874 -0.4064)
			(stroke
				(width 0.1524)
				(type default)
			)
			(layer "F.SilkS")
		)
		(fp_line
			(start -0.7874 0.4064)
			(end -0.7874 -0.4064)
			(stroke
				(width 0.1524)
				(type default)
			)
			(layer "F.SilkS")
		)
		(fp_line
			(start 0.7874 -0.4064)
			(end 0.7874 0.4064)
			(stroke
				(width 0.1524)
				(type default)
			)
			(layer "F.SilkS")
		)
		(fp_line
			(start 0.7874 0.4064)
			(end -0.7874 0.4064)
			(stroke
				(width 0.1524)
				(type default)
			)
			(layer "F.SilkS")
		)
		(fp_line
			(start -0.67945 -0.305054)
			(end -0.12065 -0.305054)
			(stroke
				(width 0.1)
				(type default)
			)
			(layer "F.Fab")
		)
		(fp_line
			(start -0.67945 0.3048)
			(end -0.67945 -0.305054)
			(stroke
				(width 0.1)
				(type default)
			)
			(layer "F.Fab")
		)
		(fp_line
			(start -0.12065 -0.305054)
			(end -0.12065 -0.2794)
			(stroke
				(width 0.1)
				(type default)
			)
			(layer "F.Fab")
		)
		(fp_line
			(start -0.12065 -0.2794)
			(end 0.12065 -0.2794)
			(stroke
				(width 0.1)
				(type default)
			)
			(layer "F.Fab")
		)
		(fp_line
			(start -0.12065 0.2794)
			(end -0.12065 0.3048)
			(stroke
				(width 0.1)
				(type default)
			)
			(layer "F.Fab")
		)
		(fp_line
			(start -0.12065 0.3048)
			(end -0.67945 0.3048)
			(stroke
				(width 0.1)
				(type default)
			)
			(layer "F.Fab")
		)
		(fp_line
			(start 0.120396 0.2794)
			(end -0.12065 0.2794)
			(stroke
				(width 0.1)
				(type default)
			)
			(layer "F.Fab")
		)
		(fp_line
			(start 0.120396 0.3048)
			(end 0.120396 0.2794)
			(stroke
				(width 0.1)
				(type default)
			)
			(layer "F.Fab")
		)
		(fp_line
			(start 0.12065 -0.3048)
			(end 0.67945 -0.3048)
			(stroke
				(width 0.1)
				(type default)
			)
			(layer "F.Fab")
		)
		(fp_line
			(start 0.12065 -0.2794)
			(end 0.12065 -0.3048)
			(stroke
				(width 0.1)
				(type default)
			)
			(layer "F.Fab")
		)
		(fp_line
			(start 0.67945 -0.3048)
			(end 0.67945 0.3048)
			(stroke
				(width 0.1)
				(type default)
			)
			(layer "F.Fab")
		)
		(fp_line
			(start 0.67945 0.3048)
			(end 0.120396 0.3048)
			(stroke
				(width 0.1)
				(type default)
			)
			(layer "F.Fab")
		)
		(pad "1" smd circle
			(at -0.40005 0)
			(size 0 0)
			(layers "F.Cu" "F.Mask" "F.Paste")
			(net "SMB_BIC_I2C9_MUX0_SSD3_R_SCL")
		)
		(pad "2" smd circle
			(at 0.40005 0)
			(size 0 0)
			(layers "F.Cu" "F.Mask" "F.Paste")
			(net "SMB_BIC_I2C9_MUX0_SSD3_SCL")
		)
	)
	(footprint ""
		(layer "F.Cu")
		(at 444.938658 -22.867366 90)
		(property "Reference" "C3978"
			(at 0 0 90)
			(layer "F.SilkS")
			(hide yes)
			(effects
				(font
					(size 1.27 1.27)
				)
			)
		)
		(property "Value" ""
			(at 0 0 90)
			(layer "F.Fab")
			(effects
				(font
					(size 1.27 1.27)
				)
			)
		)
		(duplicate_pad_numbers_are_jumpers no)
		(fp_line
			(start 0.7874 -0.4064)
			(end 0.7874 0.4064)
			(stroke
				(width 0.1524)
				(type default)
			)
			(layer "F.SilkS")
		)
		(fp_line
			(start -0.7874 -0.4064)
			(end 0.7874 -0.4064)
			(stroke
				(width 0.1524)
				(type default)
			)
			(layer "F.SilkS")
		)
		(fp_line
			(start 0.7874 0.4064)
			(end -0.7874 0.4064)
			(stroke
				(width 0.1524)
				(type default)
			)
			(layer "F.SilkS")
		)
		(fp_line
			(start -0.7874 0.4064)
			(end -0.7874 -0.4064)
			(stroke
				(width 0.1524)
				(type default)
			)
			(layer "F.SilkS")
		)
		(fp_line
			(start -0.12065 -0.305054)
			(end -0.12065 -0.2794)
			(stroke
				(width 0.1)
				(type default)
			)
			(layer "F.Fab")
		)
		(fp_line
			(start -0.67945 -0.305054)
			(end -0.12065 -0.305054)
			(stroke
				(width 0.1)
				(type default)
			)
			(layer "F.Fab")
		)
		(fp_line
			(start 0.67945 -0.3048)
			(end 0.67945 0.3048)
			(stroke
				(width 0.1)
				(type default)
			)
			(layer "F.Fab")
		)
		(fp_line
			(start 0.12065 -0.3048)
			(end 0.67945 -0.3048)
			(stroke
				(width 0.1)
				(type default)
			)
			(layer "F.Fab")
		)
		(fp_line
			(start 0.12065 -0.2794)
			(end 0.12065 -0.3048)
			(stroke
				(width 0.1)
				(type default)
			)
			(layer "F.Fab")
		)
		(fp_line
			(start -0.12065 -0.2794)
			(end 0.12065 -0.2794)
			(stroke
				(width 0.1)
				(type default)
			)
			(layer "F.Fab")
		)
		(fp_line
			(start 0.120396 0.2794)
			(end -0.12065 0.2794)
			(stroke
				(width 0.1)
				(type default)
			)
			(layer "F.Fab")
		)
		(fp_line
			(start -0.12065 0.2794)
			(end -0.12065 0.3048)
			(stroke
				(width 0.1)
				(type default)
			)
			(layer "F.Fab")
		)
		(fp_line
			(start 0.67945 0.3048)
			(end 0.120396 0.3048)
			(stroke
				(width 0.1)
				(type default)
			)
			(layer "F.Fab")
		)
		(fp_line
			(start 0.120396 0.3048)
			(end 0.120396 0.2794)
			(stroke
				(width 0.1)
				(type default)
			)
			(layer "F.Fab")
		)
		(fp_line
			(start -0.12065 0.3048)
			(end -0.67945 0.3048)
			(stroke
				(width 0.1)
				(type default)
			)
			(layer "F.Fab")
		)
		(fp_line
			(start -0.67945 0.3048)
			(end -0.67945 -0.305054)
			(stroke
				(width 0.1)
				(type default)
			)
			(layer "F.Fab")
		)
		(pad "1" smd circle
			(at -0.40005 0 90)
			(size 0 0)
			(layers "F.Cu" "F.Mask" "F.Paste")
			(net "P12V_SSD15")
		)
		(pad "2" smd circle
			(at 0.40005 0 90)
			(size 0 0)
			(layers "F.Cu" "F.Mask" "F.Paste")
			(net "GND")
		)
	)
	(footprint ""
		(layer "F.Cu")
		(at 46.67504 -56.977534 180)
		(property "Reference" "PC402"
			(at 0 0 180)
			(layer "F.SilkS")
			(hide yes)
			(effects
				(font
					(size 1.27 1.27)
				)
			)
		)
		(property "Value" ""
			(at 0 0 180)
			(layer "F.Fab")
			(effects
				(font
					(size 1.27 1.27)
				)
			)
		)
		(duplicate_pad_numbers_are_jumpers no)
		(fp_line
			(start 0.7874 0.4064)
			(end -0.7874 0.4064)
			(stroke
				(width 0.1524)
				(type default)
			)
			(layer "F.SilkS")
		)
		(fp_line
			(start 0.7874 -0.4064)
			(end 0.7874 0.4064)
			(stroke
				(width 0.1524)
				(type default)
			)
			(layer "F.SilkS")
		)
		(fp_line
			(start -0.7874 0.4064)
			(end -0.7874 -0.4064)
			(stroke
				(width 0.1524)
				(type default)
			)
			(layer "F.SilkS")
		)
		(fp_line
			(start -0.7874 -0.4064)
			(end 0.7874 -0.4064)
			(stroke
				(width 0.1524)
				(type default)
			)
			(layer "F.SilkS")
		)
		(fp_line
			(start 0.67945 0.3048)
			(end 0.120396 0.3048)
			(stroke
				(width 0.1)
				(type default)
			)
			(layer "F.Fab")
		)
		(fp_line
			(start 0.67945 -0.3048)
			(end 0.67945 0.3048)
			(stroke
				(width 0.1)
				(type default)
			)
			(layer "F.Fab")
		)
		(fp_line
			(start 0.12065 -0.2794)
			(end 0.12065 -0.3048)
			(stroke
				(width 0.1)
				(type default)
			)
			(layer "F.Fab")
		)
		(fp_line
			(start 0.12065 -0.3048)
			(end 0.67945 -0.3048)
			(stroke
				(width 0.1)
				(type default)
			)
			(layer "F.Fab")
		)
		(fp_line
			(start 0.120396 0.3048)
			(end 0.120396 0.2794)
			(stroke
				(width 0.1)
				(type default)
			)
			(layer "F.Fab")
		)
		(fp_line
			(start 0.120396 0.2794)
			(end -0.12065 0.2794)
			(stroke
				(width 0.1)
				(type default)
			)
			(layer "F.Fab")
		)
		(fp_line
			(start -0.12065 0.3048)
			(end -0.67945 0.3048)
			(stroke
				(width 0.1)
				(type default)
			)
			(layer "F.Fab")
		)
		(fp_line
			(start -0.12065 0.2794)
			(end -0.12065 0.3048)
			(stroke
				(width 0.1)
				(type default)
			)
			(layer "F.Fab")
		)
		(fp_line
			(start -0.12065 -0.2794)
			(end 0.12065 -0.2794)
			(stroke
				(width 0.1)
				(type default)
			)
			(layer "F.Fab")
		)
		(fp_line
			(start -0.12065 -0.305054)
			(end -0.12065 -0.2794)
			(stroke
				(width 0.1)
				(type default)
			)
			(layer "F.Fab")
		)
		(fp_line
			(start -0.67945 0.3048)
			(end -0.67945 -0.305054)
			(stroke
				(width 0.1)
				(type default)
			)
			(layer "F.Fab")
		)
		(fp_line
			(start -0.67945 -0.305054)
			(end -0.12065 -0.305054)
			(stroke
				(width 0.1)
				(type default)
			)
			(layer "F.Fab")
		)
		(pad "1" smd circle
			(at -0.40005 0 180)
			(size 0 0)
			(layers "F.Cu" "F.Mask" "F.Paste")
			(net "P12V_AUX")
		)
		(pad "2" smd circle
			(at 0.40005 0 180)
			(size 0 0)
			(layers "F.Cu" "F.Mask" "F.Paste")
			(net "GND")
		)
	)
	(footprint ""
		(layer "F.Cu")
		(at 233.800142 -194.359784)
		(property "Reference" "H69"
			(at -4.338828 -4.989322 0)
			(unlocked yes)
			(layer "F.SilkS")
			(effects
				(font
					(size 0.7874 0.5842)
					(thickness 0.1524)
				)
				(justify left)
			)
		)
		(property "Value" ""
			(at 0 0 0)
			(layer "F.Fab")
			(effects
				(font
					(size 1.27 1.27)
				)
			)
		)
		(duplicate_pad_numbers_are_jumpers no)
		(pad "1" thru_hole circle
			(at 0 0)
			(size 10.0076 10.0076)
			(drill 5.6134)
			(layers "*.Cu" "*.Mask")
			(remove_unused_layers no)
			(net "GND")
			(clearance -1.9431)
		)
	)
	(footprint ""
		(layer "F.Cu")
		(at 322.21805 -306.074572 90)
		(property "Reference" "R1371"
			(at 0 0 90)
			(layer "F.SilkS")
			(hide yes)
			(effects
				(font
					(size 1.27 1.27)
				)
			)
		)
		(property "Value" ""
			(at 0 0 90)
			(layer "F.Fab")
			(effects
				(font
					(size 1.27 1.27)
				)
			)
		)
		(duplicate_pad_numbers_are_jumpers no)
		(fp_line
			(start 0.7874 -0.4064)
			(end 0.7874 0.4064)
			(stroke
				(width 0.1524)
				(type default)
			)
			(layer "F.SilkS")
		)
		(fp_line
			(start -0.7874 -0.4064)
			(end 0.7874 -0.4064)
			(stroke
				(width 0.1524)
				(type default)
			)
			(layer "F.SilkS")
		)
		(fp_line
			(start 0.7874 0.4064)
			(end -0.7874 0.4064)
			(stroke
				(width 0.1524)
				(type default)
			)
			(layer "F.SilkS")
		)
		(fp_line
			(start -0.7874 0.4064)
			(end -0.7874 -0.4064)
			(stroke
				(width 0.1524)
				(type default)
			)
			(layer "F.SilkS")
		)
		(fp_line
			(start -0.12065 -0.305054)
			(end -0.12065 -0.2794)
			(stroke
				(width 0.1)
				(type default)
			)
			(layer "F.Fab")
		)
		(fp_line
			(start -0.67945 -0.305054)
			(end -0.12065 -0.305054)
			(stroke
				(width 0.1)
				(type default)
			)
			(layer "F.Fab")
		)
		(fp_line
			(start 0.67945 -0.3048)
			(end 0.67945 0.3048)
			(stroke
				(width 0.1)
				(type default)
			)
			(layer "F.Fab")
		)
		(fp_line
			(start 0.12065 -0.3048)
			(end 0.67945 -0.3048)
			(stroke
				(width 0.1)
				(type default)
			)
			(layer "F.Fab")
		)
		(fp_line
			(start 0.12065 -0.2794)
			(end 0.12065 -0.3048)
			(stroke
				(width 0.1)
				(type default)
			)
			(layer "F.Fab")
		)
		(fp_line
			(start -0.12065 -0.2794)
			(end 0.12065 -0.2794)
			(stroke
				(width 0.1)
				(type default)
			)
			(layer "F.Fab")
		)
		(fp_line
			(start 0.120396 0.2794)
			(end -0.12065 0.2794)
			(stroke
				(width 0.1)
				(type default)
			)
			(layer "F.Fab")
		)
		(fp_line
			(start -0.12065 0.2794)
			(end -0.12065 0.3048)
			(stroke
				(width 0.1)
				(type default)
			)
			(layer "F.Fab")
		)
		(fp_line
			(start 0.67945 0.3048)
			(end 0.120396 0.3048)
			(stroke
				(width 0.1)
				(type default)
			)
			(layer "F.Fab")
		)
		(fp_line
			(start 0.120396 0.3048)
			(end 0.120396 0.2794)
			(stroke
				(width 0.1)
				(type default)
			)
			(layer "F.Fab")
		)
		(fp_line
			(start -0.12065 0.3048)
			(end -0.67945 0.3048)
			(stroke
				(width 0.1)
				(type default)
			)
			(layer "F.Fab")
		)
		(fp_line
			(start -0.67945 0.3048)
			(end -0.67945 -0.305054)
			(stroke
				(width 0.1)
				(type default)
			)
			(layer "F.Fab")
		)
		(pad "1" smd circle
			(at -0.40005 0 90)
			(size 0 0)
			(layers "F.Cu" "F.Mask" "F.Paste")
			(net "PEX2_SPARE3")
		)
		(pad "2" smd circle
			(at 0.40005 0 90)
			(size 0 0)
			(layers "F.Cu" "F.Mask" "F.Paste")
			(net "P1V8_PEX")
		)
	)
	(footprint ""
		(layer "F.Cu")
		(at 346.950792 -240.691162 90)
		(property "Reference" "R3525"
			(at 0 0 90)
			(layer "F.SilkS")
			(hide yes)
			(effects
				(font
					(size 1.27 1.27)
				)
			)
		)
		(property "Value" ""
			(at 0 0 90)
			(layer "F.Fab")
			(effects
				(font
					(size 1.27 1.27)
				)
			)
		)
		(duplicate_pad_numbers_are_jumpers no)
		(fp_line
			(start 0.7874 -0.4064)
			(end 0.7874 0.4064)
			(stroke
				(width 0.1524)
				(type default)
			)
			(layer "F.SilkS")
		)
		(fp_line
			(start -0.7874 -0.4064)
			(end 0.7874 -0.4064)
			(stroke
				(width 0.1524)
				(type default)
			)
			(layer "F.SilkS")
		)
		(fp_line
			(start 0.7874 0.4064)
			(end -0.7874 0.4064)
			(stroke
				(width 0.1524)
				(type default)
			)
			(layer "F.SilkS")
		)
		(fp_line
			(start -0.7874 0.4064)
			(end -0.7874 -0.4064)
			(stroke
				(width 0.1524)
				(type default)
			)
			(layer "F.SilkS")
		)
		(fp_line
			(start -0.12065 -0.305054)
			(end -0.12065 -0.2794)
			(stroke
				(width 0.1)
				(type default)
			)
			(layer "F.Fab")
		)
		(fp_line
			(start -0.67945 -0.305054)
			(end -0.12065 -0.305054)
			(stroke
				(width 0.1)
				(type default)
			)
			(layer "F.Fab")
		)
		(fp_line
			(start 0.67945 -0.3048)
			(end 0.67945 0.3048)
			(stroke
				(width 0.1)
				(type default)
			)
			(layer "F.Fab")
		)
		(fp_line
			(start 0.12065 -0.3048)
			(end 0.67945 -0.3048)
			(stroke
				(width 0.1)
				(type default)
			)
			(layer "F.Fab")
		)
		(fp_line
			(start 0.12065 -0.2794)
			(end 0.12065 -0.3048)
			(stroke
				(width 0.1)
				(type default)
			)
			(layer "F.Fab")
		)
		(fp_line
			(start -0.12065 -0.2794)
			(end 0.12065 -0.2794)
			(stroke
				(width 0.1)
				(type default)
			)
			(layer "F.Fab")
		)
		(fp_line
			(start 0.120396 0.2794)
			(end -0.12065 0.2794)
			(stroke
				(width 0.1)
				(type default)
			)
			(layer "F.Fab")
		)
		(fp_line
			(start -0.12065 0.2794)
			(end -0.12065 0.3048)
			(stroke
				(width 0.1)
				(type default)
			)
			(layer "F.Fab")
		)
		(fp_line
			(start 0.67945 0.3048)
			(end 0.120396 0.3048)
			(stroke
				(width 0.1)
				(type default)
			)
			(layer "F.Fab")
		)
		(fp_line
			(start 0.120396 0.3048)
			(end 0.120396 0.2794)
			(stroke
				(width 0.1)
				(type default)
			)
			(layer "F.Fab")
		)
		(fp_line
			(start -0.12065 0.3048)
			(end -0.67945 0.3048)
			(stroke
				(width 0.1)
				(type default)
			)
			(layer "F.Fab")
		)
		(fp_line
			(start -0.67945 0.3048)
			(end -0.67945 -0.305054)
			(stroke
				(width 0.1)
				(type default)
			)
			(layer "F.Fab")
		)
		(pad "1" smd circle
			(at -0.40005 0 90)
			(size 0 0)
			(layers "F.Cu" "F.Mask" "F.Paste")
			(net "RST_SSD2_PERST_N")
		)
		(pad "2" smd circle
			(at 0.40005 0 90)
			(size 0 0)
			(layers "F.Cu" "F.Mask" "F.Paste")
			(net "RST_SSD2_PERST_R_N")
		)
	)
	(footprint ""
		(layer "F.Cu")
		(at 115.847114 -262.322564 -90)
		(property "Reference" "PJ6"
			(at 0 0 270)
			(layer "F.SilkS")
			(hide yes)
			(effects
				(font
					(size 1.27 1.27)
				)
			)
		)
		(property "Value" ""
			(at 0 0 270)
			(layer "F.Fab")
			(effects
				(font
					(size 1.27 1.27)
				)
			)
		)
		(duplicate_pad_numbers_are_jumpers no)
		(pad "1" smd circle
			(at -0.7493 0)
			(size 0 0)
			(layers "F.Cu" "F.Mask" "F.Paste")
			(net "SH_P0V8_PEX1_VSEN1_L")
		)
		(pad "2" smd rect
			(at 0.7493 0 180)
			(size 0.7112 0.8128)
			(layers "F.Cu" "F.Mask" "F.Paste")
			(net "SH_P0V8_PEX1_VSEN1_R")
		)
		(zone
			(layer "F.Cu")
			(hatch none 0.5)
			(connect_pads
				(clearance 0)
			)
			(min_thickness 0.25)
			(keepout
				(tracks allowed)
				(vias not_allowed)
				(pads allowed)
				(copperpour not_allowed)
				(footprints allowed)
			)
			(placement
				(enabled no)
				(sheetname "")
			)
			(fill
				(thermal_gap 0.5)
				(thermal_bridge_width 0.5)
				(island_removal_mode 0)
			)
			(polygon
				(pts
					(xy 115.435888 -261.116064) (xy 116.253514 -261.116064) (xy 116.253514 -263.503664) (xy 115.435888 -263.503664)
				)
			)
		)
	)
	(footprint ""
		(layer "F.Cu")
		(at 273.115024 18.035524)
		(property "Reference" "DE03F_2"
			(at -3.6068 -2.962148 0)
			(unlocked yes)
			(layer "F.SilkS")
			(effects
				(font
					(size 0.7874 0.5842)
					(thickness 0.1524)
				)
				(justify left)
			)
		)
		(property "Value" ""
			(at 0 0 0)
			(layer "F.Fab")
			(effects
				(font
					(size 1.27 1.27)
				)
			)
		)
		(duplicate_pad_numbers_are_jumpers no)
		(fp_line
			(start -1.2192 -2.1082)
			(end 1.2192 -2.1082)
			(stroke
				(width 0.1524)
				(type default)
			)
			(layer "F.SilkS")
		)
		(fp_line
			(start -1.2192 2.1082)
			(end -1.2192 -2.1082)
			(stroke
				(width 0.1524)
				(type default)
			)
			(layer "F.SilkS")
		)
		(fp_line
			(start 1.2192 -2.1082)
			(end 1.2192 2.1082)
			(stroke
				(width 0.1524)
				(type default)
			)
			(layer "F.SilkS")
		)
		(fp_line
			(start 1.2192 2.1082)
			(end -1.2192 2.1082)
			(stroke
				(width 0.1524)
				(type default)
			)
			(layer "F.SilkS")
		)
		(pad "" np_thru_hole circle
			(at -2.8829 -1.27 270)
			(size 1.0414 1.0414)
			(drill 1.0414)
			(layers "*.Cu" "*.Mask")
			(clearance 0.381)
			(thermal_gap 0.381)
		)
		(pad "" np_thru_hole circle
			(at -2.8829 1.27 270)
			(size 1.0414 1.0414)
			(drill 1.0414)
			(layers "*.Cu" "*.Mask")
			(clearance 0.381)
			(thermal_gap 0.381)
		)
		(pad "" np_thru_hole circle
			(at 3.4671 -1.27 270)
			(size 1.0414 1.0414)
			(drill 1.0414)
			(layers "*.Cu" "*.Mask")
			(clearance 0.381)
			(thermal_gap 0.381)
		)
		(pad "" np_thru_hole circle
			(at 3.4671 1.27 270)
			(size 1.0414 1.0414)
			(drill 1.0414)
			(layers "*.Cu" "*.Mask")
			(clearance 0.381)
			(thermal_gap 0.381)
		)
		(pad "1" smd rect
			(at 0.8255 -0.249936 270)
			(size 0.3048 0.508)
			(layers "F.Cu" "F.Mask" "F.Paste")
			(net "85_5INCH_IN1_DP")
		)
		(pad "2" smd rect
			(at 0.8255 0.249936 270)
			(size 0.3048 0.508)
			(layers "F.Cu" "F.Mask" "F.Paste")
			(net "85_5INCH_IN1_DN")
		)
		(pad "3" smd circle
			(at 0 0)
			(size 0 0)
			(layers "F.Cu" "F.Mask" "F.Paste")
			(net "COUPON_GND2")
		)
		(zone
			(layer "F.Cu")
			(hatch none 0.5)
			(connect_pads
				(clearance 0)
			)
			(min_thickness 0.25)
			(keepout
				(tracks not_allowed)
				(vias allowed)
				(pads allowed)
				(copperpour not_allowed)
				(footprints allowed)
			)
			(placement
				(enabled no)
				(sheetname "")
			)
			(fill
				(thermal_gap 0.5)
				(thermal_bridge_width 0.5)
				(island_removal_mode 0)
			)
			(polygon
				(pts
					(xy 274.232624 17.486884) (xy 274.232624 17.582388) (xy 273.635724 17.582388) (xy 273.635724 17.988788)
					(xy 274.232624 17.988788) (xy 274.232624 18.08226) (xy 273.635724 18.08226) (xy 273.635724 18.48866)
					(xy 274.232624 18.48866) (xy 274.232624 18.584164) (xy 273.534124 18.584164) (xy 273.534124 17.486884)
				)
			)
		)
		(zone
			(layers "F.Cu" "B.Cu" "In1.Cu" "In2.Cu" "In3.Cu" "In4.Cu" "In5.Cu" "In6.Cu"
				"In7.Cu" "In8.Cu" "In9.Cu" "In10.Cu" "In11.Cu" "In12.Cu" "In13.Cu" "In14.Cu"
				"In15.Cu" "In16.Cu"
			)
			(hatch none 0.5)
			(connect_pads
				(clearance 0)
			)
			(min_thickness 0.25)
			(keepout
				(tracks not_allowed)
				(vias allowed)
				(pads allowed)
				(copperpour not_allowed)
				(footprints allowed)
			)
			(placement
				(enabled no)
				(sheetname "")
			)
			(fill
				(thermal_gap 0.5)
				(thermal_bridge_width 0.5)
				(island_removal_mode 0)
			)
			(polygon
				(pts
					(arc
						(start 271.159224 16.765524)
						(mid 269.305024 16.765524)
						(end 271.159224 16.765524)
					)
				)
			)
		)
		(zone
			(layers "F.Cu" "B.Cu" "In1.Cu" "In2.Cu" "In3.Cu" "In4.Cu" "In5.Cu" "In6.Cu"
				"In7.Cu" "In8.Cu" "In9.Cu" "In10.Cu" "In11.Cu" "In12.Cu" "In13.Cu" "In14.Cu"
				"In15.Cu" "In16.Cu"
			)
			(hatch none 0.5)
			(connect_pads
				(clearance 0)
			)
			(min_thickness 0.25)
			(keepout
				(tracks not_allowed)
				(vias allowed)
				(pads allowed)
				(copperpour not_allowed)
				(footprints allowed)
			)
			(placement
				(enabled no)
				(sheetname "")
			)
			(fill
				(thermal_gap 0.5)
				(thermal_bridge_width 0.5)
				(island_removal_mode 0)
			)
			(polygon
				(pts
					(arc
						(start 271.159224 19.305524)
						(mid 269.305024 19.305524)
						(end 271.159224 19.305524)
					)
				)
			)
		)
		(zone
			(layers "F.Cu" "B.Cu" "In1.Cu" "In2.Cu" "In3.Cu" "In4.Cu" "In5.Cu" "In6.Cu"
				"In7.Cu" "In8.Cu" "In9.Cu" "In10.Cu" "In11.Cu" "In12.Cu" "In13.Cu" "In14.Cu"
				"In15.Cu" "In16.Cu"
			)
			(hatch none 0.5)
			(connect_pads
				(clearance 0)
			)
			(min_thickness 0.25)
			(keepout
				(tracks not_allowed)
				(vias allowed)
				(pads allowed)
				(copperpour not_allowed)
				(footprints allowed)
			)
			(placement
				(enabled no)
				(sheetname "")
			)
			(fill
				(thermal_gap 0.5)
				(thermal_bridge_width 0.5)
				(island_removal_mode 0)
			)
			(polygon
				(pts
					(arc
						(start 277.509224 16.765524)
						(mid 275.655024 16.765524)
						(end 277.509224 16.765524)
					)
				)
			)
		)
		(zone
			(layers "F.Cu" "B.Cu" "In1.Cu" "In2.Cu" "In3.Cu" "In4.Cu" "In5.Cu" "In6.Cu"
				"In7.Cu" "In8.Cu" "In9.Cu" "In10.Cu" "In11.Cu" "In12.Cu" "In13.Cu" "In14.Cu"
				"In15.Cu" "In16.Cu"
			)
			(hatch none 0.5)
			(connect_pads
				(clearance 0)
			)
			(min_thickness 0.25)
			(keepout
				(tracks not_allowed)
				(vias allowed)
				(pads allowed)
				(copperpour not_allowed)
				(footprints allowed)
			)
			(placement
				(enabled no)
				(sheetname "")
			)
			(fill
				(thermal_gap 0.5)
				(thermal_bridge_width 0.5)
				(island_removal_mode 0)
			)
			(polygon
				(pts
					(arc
						(start 277.509224 19.305524)
						(mid 275.655024 19.305524)
						(end 277.509224 19.305524)
					)
				)
			)
		)
	)
	(footprint ""
		(layer "F.Cu")
		(at 386.90804 -158.3944 180)
		(property "Reference" "R317"
			(at 0 0 180)
			(layer "F.SilkS")
			(hide yes)
			(effects
				(font
					(size 1.27 1.27)
				)
			)
		)
		(property "Value" ""
			(at 0 0 180)
			(layer "F.Fab")
			(effects
				(font
					(size 1.27 1.27)
				)
			)
		)
		(duplicate_pad_numbers_are_jumpers no)
		(fp_line
			(start 0.7874 0.4064)
			(end -0.7874 0.4064)
			(stroke
				(width 0.1524)
				(type default)
			)
			(layer "F.SilkS")
		)
		(fp_line
			(start 0.7874 -0.4064)
			(end 0.7874 0.4064)
			(stroke
				(width 0.1524)
				(type default)
			)
			(layer "F.SilkS")
		)
		(fp_line
			(start -0.7874 0.4064)
			(end -0.7874 -0.4064)
			(stroke
				(width 0.1524)
				(type default)
			)
			(layer "F.SilkS")
		)
		(fp_line
			(start -0.7874 -0.4064)
			(end 0.7874 -0.4064)
			(stroke
				(width 0.1524)
				(type default)
			)
			(layer "F.SilkS")
		)
		(fp_line
			(start 0.67945 0.3048)
			(end 0.120396 0.3048)
			(stroke
				(width 0.1)
				(type default)
			)
			(layer "F.Fab")
		)
		(fp_line
			(start 0.67945 -0.3048)
			(end 0.67945 0.3048)
			(stroke
				(width 0.1)
				(type default)
			)
			(layer "F.Fab")
		)
		(fp_line
			(start 0.12065 -0.2794)
			(end 0.12065 -0.3048)
			(stroke
				(width 0.1)
				(type default)
			)
			(layer "F.Fab")
		)
		(fp_line
			(start 0.12065 -0.3048)
			(end 0.67945 -0.3048)
			(stroke
				(width 0.1)
				(type default)
			)
			(layer "F.Fab")
		)
		(fp_line
			(start 0.120396 0.3048)
			(end 0.120396 0.2794)
			(stroke
				(width 0.1)
				(type default)
			)
			(layer "F.Fab")
		)
		(fp_line
			(start 0.120396 0.2794)
			(end -0.12065 0.2794)
			(stroke
				(width 0.1)
				(type default)
			)
			(layer "F.Fab")
		)
		(fp_line
			(start -0.12065 0.3048)
			(end -0.67945 0.3048)
			(stroke
				(width 0.1)
				(type default)
			)
			(layer "F.Fab")
		)
		(fp_line
			(start -0.12065 0.2794)
			(end -0.12065 0.3048)
			(stroke
				(width 0.1)
				(type default)
			)
			(layer "F.Fab")
		)
		(fp_line
			(start -0.12065 -0.2794)
			(end 0.12065 -0.2794)
			(stroke
				(width 0.1)
				(type default)
			)
			(layer "F.Fab")
		)
		(fp_line
			(start -0.12065 -0.305054)
			(end -0.12065 -0.2794)
			(stroke
				(width 0.1)
				(type default)
			)
			(layer "F.Fab")
		)
		(fp_line
			(start -0.67945 0.3048)
			(end -0.67945 -0.305054)
			(stroke
				(width 0.1)
				(type default)
			)
			(layer "F.Fab")
		)
		(fp_line
			(start -0.67945 -0.305054)
			(end -0.12065 -0.305054)
			(stroke
				(width 0.1)
				(type default)
			)
			(layer "F.Fab")
		)
		(pad "1" smd circle
			(at -0.40005 0 180)
			(size 0 0)
			(layers "F.Cu" "F.Mask" "F.Paste")
			(net "NIC6_LD_N")
		)
		(pad "2" smd circle
			(at 0.40005 0 180)
			(size 0 0)
			(layers "F.Cu" "F.Mask" "F.Paste")
			(net "P3V3_NIC6")
		)
	)
	(footprint ""
		(layer "F.Cu")
		(at 350.380554 -88.359234)
		(property "Reference" "R1592"
			(at 0 0 0)
			(layer "F.SilkS")
			(hide yes)
			(effects
				(font
					(size 1.27 1.27)
				)
			)
		)
		(property "Value" ""
			(at 0 0 0)
			(layer "F.Fab")
			(effects
				(font
					(size 1.27 1.27)
				)
			)
		)
		(duplicate_pad_numbers_are_jumpers no)
		(fp_line
			(start -0.7874 -0.4064)
			(end 0.7874 -0.4064)
			(stroke
				(width 0.1524)
				(type default)
			)
			(layer "F.SilkS")
		)
		(fp_line
			(start -0.7874 0.4064)
			(end -0.7874 -0.4064)
			(stroke
				(width 0.1524)
				(type default)
			)
			(layer "F.SilkS")
		)
		(fp_line
			(start 0.7874 -0.4064)
			(end 0.7874 0.4064)
			(stroke
				(width 0.1524)
				(type default)
			)
			(layer "F.SilkS")
		)
		(fp_line
			(start 0.7874 0.4064)
			(end -0.7874 0.4064)
			(stroke
				(width 0.1524)
				(type default)
			)
			(layer "F.SilkS")
		)
		(fp_line
			(start -0.67945 -0.305054)
			(end -0.12065 -0.305054)
			(stroke
				(width 0.1)
				(type default)
			)
			(layer "F.Fab")
		)
		(fp_line
			(start -0.67945 0.3048)
			(end -0.67945 -0.305054)
			(stroke
				(width 0.1)
				(type default)
			)
			(layer "F.Fab")
		)
		(fp_line
			(start -0.12065 -0.305054)
			(end -0.12065 -0.2794)
			(stroke
				(width 0.1)
				(type default)
			)
			(layer "F.Fab")
		)
		(fp_line
			(start -0.12065 -0.2794)
			(end 0.12065 -0.2794)
			(stroke
				(width 0.1)
				(type default)
			)
			(layer "F.Fab")
		)
		(fp_line
			(start -0.12065 0.2794)
			(end -0.12065 0.3048)
			(stroke
				(width 0.1)
				(type default)
			)
			(layer "F.Fab")
		)
		(fp_line
			(start -0.12065 0.3048)
			(end -0.67945 0.3048)
			(stroke
				(width 0.1)
				(type default)
			)
			(layer "F.Fab")
		)
		(fp_line
			(start 0.120396 0.2794)
			(end -0.12065 0.2794)
			(stroke
				(width 0.1)
				(type default)
			)
			(layer "F.Fab")
		)
		(fp_line
			(start 0.120396 0.3048)
			(end 0.120396 0.2794)
			(stroke
				(width 0.1)
				(type default)
			)
			(layer "F.Fab")
		)
		(fp_line
			(start 0.12065 -0.3048)
			(end 0.67945 -0.3048)
			(stroke
				(width 0.1)
				(type default)
			)
			(layer "F.Fab")
		)
		(fp_line
			(start 0.12065 -0.2794)
			(end 0.12065 -0.3048)
			(stroke
				(width 0.1)
				(type default)
			)
			(layer "F.Fab")
		)
		(fp_line
			(start 0.67945 -0.3048)
			(end 0.67945 0.3048)
			(stroke
				(width 0.1)
				(type default)
			)
			(layer "F.Fab")
		)
		(fp_line
			(start 0.67945 0.3048)
			(end 0.120396 0.3048)
			(stroke
				(width 0.1)
				(type default)
			)
			(layer "F.Fab")
		)
		(pad "1" smd circle
			(at -0.40005 0)
			(size 0 0)
			(layers "F.Cu" "F.Mask" "F.Paste")
			(net "P3V3_AUX")
		)
		(pad "2" smd circle
			(at 0.40005 0)
			(size 0 0)
			(layers "F.Cu" "F.Mask" "F.Paste")
			(net "SMB_BIC_I2C9_MUX1_SSD8_R_SCL")
		)
	)
	(footprint ""
		(layer "F.Cu")
		(at 127.658114 -254.194564)
		(property "Reference" "C199"
			(at 0 0 0)
			(layer "F.SilkS")
			(hide yes)
			(effects
				(font
					(size 1.27 1.27)
				)
			)
		)
		(property "Value" ""
			(at 0 0 0)
			(layer "F.Fab")
			(effects
				(font
					(size 1.27 1.27)
				)
			)
		)
		(duplicate_pad_numbers_are_jumpers no)
		(fp_line
			(start -0.7874 -0.4064)
			(end 0.7874 -0.4064)
			(stroke
				(width 0.1524)
				(type default)
			)
			(layer "F.SilkS")
		)
		(fp_line
			(start -0.7874 0.4064)
			(end -0.7874 -0.4064)
			(stroke
				(width 0.1524)
				(type default)
			)
			(layer "F.SilkS")
		)
		(fp_line
			(start 0.7874 -0.4064)
			(end 0.7874 0.4064)
			(stroke
				(width 0.1524)
				(type default)
			)
			(layer "F.SilkS")
		)
		(fp_line
			(start 0.7874 0.4064)
			(end -0.7874 0.4064)
			(stroke
				(width 0.1524)
				(type default)
			)
			(layer "F.SilkS")
		)
		(fp_line
			(start -0.67945 -0.305054)
			(end -0.12065 -0.305054)
			(stroke
				(width 0.1)
				(type default)
			)
			(layer "F.Fab")
		)
		(fp_line
			(start -0.67945 0.3048)
			(end -0.67945 -0.305054)
			(stroke
				(width 0.1)
				(type default)
			)
			(layer "F.Fab")
		)
		(fp_line
			(start -0.12065 -0.305054)
			(end -0.12065 -0.2794)
			(stroke
				(width 0.1)
				(type default)
			)
			(layer "F.Fab")
		)
		(fp_line
			(start -0.12065 -0.2794)
			(end 0.12065 -0.2794)
			(stroke
				(width 0.1)
				(type default)
			)
			(layer "F.Fab")
		)
		(fp_line
			(start -0.12065 0.2794)
			(end -0.12065 0.3048)
			(stroke
				(width 0.1)
				(type default)
			)
			(layer "F.Fab")
		)
		(fp_line
			(start -0.12065 0.3048)
			(end -0.67945 0.3048)
			(stroke
				(width 0.1)
				(type default)
			)
			(layer "F.Fab")
		)
		(fp_line
			(start 0.120396 0.2794)
			(end -0.12065 0.2794)
			(stroke
				(width 0.1)
				(type default)
			)
			(layer "F.Fab")
		)
		(fp_line
			(start 0.120396 0.3048)
			(end 0.120396 0.2794)
			(stroke
				(width 0.1)
				(type default)
			)
			(layer "F.Fab")
		)
		(fp_line
			(start 0.12065 -0.3048)
			(end 0.67945 -0.3048)
			(stroke
				(width 0.1)
				(type default)
			)
			(layer "F.Fab")
		)
		(fp_line
			(start 0.12065 -0.2794)
			(end 0.12065 -0.3048)
			(stroke
				(width 0.1)
				(type default)
			)
			(layer "F.Fab")
		)
		(fp_line
			(start 0.67945 -0.3048)
			(end 0.67945 0.3048)
			(stroke
				(width 0.1)
				(type default)
			)
			(layer "F.Fab")
		)
		(fp_line
			(start 0.67945 0.3048)
			(end 0.120396 0.3048)
			(stroke
				(width 0.1)
				(type default)
			)
			(layer "F.Fab")
		)
		(pad "1" smd circle
			(at -0.40005 0)
			(size 0 0)
			(layers "F.Cu" "F.Mask" "F.Paste")
			(net "P0V8_PEX0_AVRRDY")
		)
		(pad "2" smd circle
			(at 0.40005 0)
			(size 0 0)
			(layers "F.Cu" "F.Mask" "F.Paste")
			(net "GND")
		)
	)
	(footprint ""
		(layer "F.Cu")
		(at 395.247368 -21.37156)
		(property "Reference" "C3965"
			(at 0 0 0)
			(layer "F.SilkS")
			(hide yes)
			(effects
				(font
					(size 1.27 1.27)
				)
			)
		)
		(property "Value" ""
			(at 0 0 0)
			(layer "F.Fab")
			(effects
				(font
					(size 1.27 1.27)
				)
			)
		)
		(duplicate_pad_numbers_are_jumpers no)
		(fp_line
			(start -0.7874 -0.4064)
			(end 0.7874 -0.4064)
			(stroke
				(width 0.1524)
				(type default)
			)
			(layer "F.SilkS")
		)
		(fp_line
			(start -0.7874 0.4064)
			(end -0.7874 -0.4064)
			(stroke
				(width 0.1524)
				(type default)
			)
			(layer "F.SilkS")
		)
		(fp_line
			(start 0.7874 -0.4064)
			(end 0.7874 0.4064)
			(stroke
				(width 0.1524)
				(type default)
			)
			(layer "F.SilkS")
		)
		(fp_line
			(start 0.7874 0.4064)
			(end -0.7874 0.4064)
			(stroke
				(width 0.1524)
				(type default)
			)
			(layer "F.SilkS")
		)
		(fp_line
			(start -0.67945 -0.305054)
			(end -0.12065 -0.305054)
			(stroke
				(width 0.1)
				(type default)
			)
			(layer "F.Fab")
		)
		(fp_line
			(start -0.67945 0.3048)
			(end -0.67945 -0.305054)
			(stroke
				(width 0.1)
				(type default)
			)
			(layer "F.Fab")
		)
		(fp_line
			(start -0.12065 -0.305054)
			(end -0.12065 -0.2794)
			(stroke
				(width 0.1)
				(type default)
			)
			(layer "F.Fab")
		)
		(fp_line
			(start -0.12065 -0.2794)
			(end 0.12065 -0.2794)
			(stroke
				(width 0.1)
				(type default)
			)
			(layer "F.Fab")
		)
		(fp_line
			(start -0.12065 0.2794)
			(end -0.12065 0.3048)
			(stroke
				(width 0.1)
				(type default)
			)
			(layer "F.Fab")
		)
		(fp_line
			(start -0.12065 0.3048)
			(end -0.67945 0.3048)
			(stroke
				(width 0.1)
				(type default)
			)
			(layer "F.Fab")
		)
		(fp_line
			(start 0.120396 0.2794)
			(end -0.12065 0.2794)
			(stroke
				(width 0.1)
				(type default)
			)
			(layer "F.Fab")
		)
		(fp_line
			(start 0.120396 0.3048)
			(end 0.120396 0.2794)
			(stroke
				(width 0.1)
				(type default)
			)
			(layer "F.Fab")
		)
		(fp_line
			(start 0.12065 -0.3048)
			(end 0.67945 -0.3048)
			(stroke
				(width 0.1)
				(type default)
			)
			(layer "F.Fab")
		)
		(fp_line
			(start 0.12065 -0.2794)
			(end 0.12065 -0.3048)
			(stroke
				(width 0.1)
				(type default)
			)
			(layer "F.Fab")
		)
		(fp_line
			(start 0.67945 -0.3048)
			(end 0.67945 0.3048)
			(stroke
				(width 0.1)
				(type default)
			)
			(layer "F.Fab")
		)
		(fp_line
			(start 0.67945 0.3048)
			(end 0.120396 0.3048)
			(stroke
				(width 0.1)
				(type default)
			)
			(layer "F.Fab")
		)
		(pad "1" smd circle
			(at -0.40005 0)
			(size 0 0)
			(layers "F.Cu" "F.Mask" "F.Paste")
			(net "P12V_SSD13")
		)
		(pad "2" smd circle
			(at 0.40005 0)
			(size 0 0)
			(layers "F.Cu" "F.Mask" "F.Paste")
			(net "GND")
		)
	)
	(footprint ""
		(layer "F.Cu")
		(at 74.697082 -356.244906 90)
		(property "Reference" "C142"
			(at 0 0 90)
			(layer "F.SilkS")
			(hide yes)
			(effects
				(font
					(size 1.27 1.27)
				)
			)
		)
		(property "Value" ""
			(at 0 0 90)
			(layer "F.Fab")
			(effects
				(font
					(size 1.27 1.27)
				)
			)
		)
		(duplicate_pad_numbers_are_jumpers no)
		(fp_line
			(start 0.299974 -0.150114)
			(end 0.299974 0.150114)
			(stroke
				(width 0.1)
				(type default)
			)
			(layer "F.Fab")
		)
		(fp_line
			(start -0.299974 -0.150114)
			(end 0.299974 -0.150114)
			(stroke
				(width 0.1)
				(type default)
			)
			(layer "F.Fab")
		)
		(fp_line
			(start 0.299974 0.150114)
			(end -0.299974 0.150114)
			(stroke
				(width 0.1)
				(type default)
			)
			(layer "F.Fab")
		)
		(fp_line
			(start -0.299974 0.150114)
			(end -0.299974 -0.150114)
			(stroke
				(width 0.1)
				(type default)
			)
			(layer "F.Fab")
		)
		(pad "1" smd rect
			(at -0.2667 0 90)
			(size 0.3048 0.381)
			(layers "F.Cu" "F.Mask" "F.Paste")
			(net "P5E_PEX0_STN6_TX_DN<105>")
		)
		(pad "2" smd rect
			(at 0.2667 0 90)
			(size 0.3048 0.381)
			(layers "F.Cu" "F.Mask" "F.Paste")
			(net "P5E_PEX0_STN6_TX_C_DN<105>")
		)
	)
	(footprint ""
		(layer "F.Cu")
		(at 420.474902 -48.753014 180)
		(property "Reference" "C336"
			(at 0 0 180)
			(layer "F.SilkS")
			(hide yes)
			(effects
				(font
					(size 1.27 1.27)
				)
			)
		)
		(property "Value" ""
			(at 0 0 180)
			(layer "F.Fab")
			(effects
				(font
					(size 1.27 1.27)
				)
			)
		)
		(duplicate_pad_numbers_are_jumpers no)
		(fp_line
			(start 0.7874 0.4064)
			(end -0.7874 0.4064)
			(stroke
				(width 0.1524)
				(type default)
			)
			(layer "F.SilkS")
		)
		(fp_line
			(start 0.7874 -0.4064)
			(end 0.7874 0.4064)
			(stroke
				(width 0.1524)
				(type default)
			)
			(layer "F.SilkS")
		)
		(fp_line
			(start -0.7874 0.4064)
			(end -0.7874 -0.4064)
			(stroke
				(width 0.1524)
				(type default)
			)
			(layer "F.SilkS")
		)
		(fp_line
			(start -0.7874 -0.4064)
			(end 0.7874 -0.4064)
			(stroke
				(width 0.1524)
				(type default)
			)
			(layer "F.SilkS")
		)
		(fp_line
			(start 0.67945 0.3048)
			(end 0.120396 0.3048)
			(stroke
				(width 0.1)
				(type default)
			)
			(layer "F.Fab")
		)
		(fp_line
			(start 0.67945 -0.3048)
			(end 0.67945 0.3048)
			(stroke
				(width 0.1)
				(type default)
			)
			(layer "F.Fab")
		)
		(fp_line
			(start 0.12065 -0.2794)
			(end 0.12065 -0.3048)
			(stroke
				(width 0.1)
				(type default)
			)
			(layer "F.Fab")
		)
		(fp_line
			(start 0.12065 -0.3048)
			(end 0.67945 -0.3048)
			(stroke
				(width 0.1)
				(type default)
			)
			(layer "F.Fab")
		)
		(fp_line
			(start 0.120396 0.3048)
			(end 0.120396 0.2794)
			(stroke
				(width 0.1)
				(type default)
			)
			(layer "F.Fab")
		)
		(fp_line
			(start 0.120396 0.2794)
			(end -0.12065 0.2794)
			(stroke
				(width 0.1)
				(type default)
			)
			(layer "F.Fab")
		)
		(fp_line
			(start -0.12065 0.3048)
			(end -0.67945 0.3048)
			(stroke
				(width 0.1)
				(type default)
			)
			(layer "F.Fab")
		)
		(fp_line
			(start -0.12065 0.2794)
			(end -0.12065 0.3048)
			(stroke
				(width 0.1)
				(type default)
			)
			(layer "F.Fab")
		)
		(fp_line
			(start -0.12065 -0.2794)
			(end 0.12065 -0.2794)
			(stroke
				(width 0.1)
				(type default)
			)
			(layer "F.Fab")
		)
		(fp_line
			(start -0.12065 -0.305054)
			(end -0.12065 -0.2794)
			(stroke
				(width 0.1)
				(type default)
			)
			(layer "F.Fab")
		)
		(fp_line
			(start -0.67945 0.3048)
			(end -0.67945 -0.305054)
			(stroke
				(width 0.1)
				(type default)
			)
			(layer "F.Fab")
		)
		(fp_line
			(start -0.67945 -0.305054)
			(end -0.12065 -0.305054)
			(stroke
				(width 0.1)
				(type default)
			)
			(layer "F.Fab")
		)
		(pad "1" smd circle
			(at -0.40005 0 180)
			(size 0 0)
			(layers "F.Cu" "F.Mask" "F.Paste")
			(net "P3V3_AUX")
		)
		(pad "2" smd circle
			(at 0.40005 0 180)
			(size 0 0)
			(layers "F.Cu" "F.Mask" "F.Paste")
			(net "GND")
		)
	)
	(footprint ""
		(layer "F.Cu")
		(at 290.264342 -141.6558 180)
		(property "Reference" "R239"
			(at 0 0 180)
			(layer "F.SilkS")
			(hide yes)
			(effects
				(font
					(size 1.27 1.27)
				)
			)
		)
		(property "Value" ""
			(at 0 0 180)
			(layer "F.Fab")
			(effects
				(font
					(size 1.27 1.27)
				)
			)
		)
		(duplicate_pad_numbers_are_jumpers no)
		(fp_line
			(start 0.7874 0.4064)
			(end -0.7874 0.4064)
			(stroke
				(width 0.1524)
				(type default)
			)
			(layer "F.SilkS")
		)
		(fp_line
			(start 0.7874 -0.4064)
			(end 0.7874 0.4064)
			(stroke
				(width 0.1524)
				(type default)
			)
			(layer "F.SilkS")
		)
		(fp_line
			(start -0.7874 0.4064)
			(end -0.7874 -0.4064)
			(stroke
				(width 0.1524)
				(type default)
			)
			(layer "F.SilkS")
		)
		(fp_line
			(start -0.7874 -0.4064)
			(end 0.7874 -0.4064)
			(stroke
				(width 0.1524)
				(type default)
			)
			(layer "F.SilkS")
		)
		(fp_line
			(start 0.67945 0.3048)
			(end 0.120396 0.3048)
			(stroke
				(width 0.1)
				(type default)
			)
			(layer "F.Fab")
		)
		(fp_line
			(start 0.67945 -0.3048)
			(end 0.67945 0.3048)
			(stroke
				(width 0.1)
				(type default)
			)
			(layer "F.Fab")
		)
		(fp_line
			(start 0.12065 -0.2794)
			(end 0.12065 -0.3048)
			(stroke
				(width 0.1)
				(type default)
			)
			(layer "F.Fab")
		)
		(fp_line
			(start 0.12065 -0.3048)
			(end 0.67945 -0.3048)
			(stroke
				(width 0.1)
				(type default)
			)
			(layer "F.Fab")
		)
		(fp_line
			(start 0.120396 0.3048)
			(end 0.120396 0.2794)
			(stroke
				(width 0.1)
				(type default)
			)
			(layer "F.Fab")
		)
		(fp_line
			(start 0.120396 0.2794)
			(end -0.12065 0.2794)
			(stroke
				(width 0.1)
				(type default)
			)
			(layer "F.Fab")
		)
		(fp_line
			(start -0.12065 0.3048)
			(end -0.67945 0.3048)
			(stroke
				(width 0.1)
				(type default)
			)
			(layer "F.Fab")
		)
		(fp_line
			(start -0.12065 0.2794)
			(end -0.12065 0.3048)
			(stroke
				(width 0.1)
				(type default)
			)
			(layer "F.Fab")
		)
		(fp_line
			(start -0.12065 -0.2794)
			(end 0.12065 -0.2794)
			(stroke
				(width 0.1)
				(type default)
			)
			(layer "F.Fab")
		)
		(fp_line
			(start -0.12065 -0.305054)
			(end -0.12065 -0.2794)
			(stroke
				(width 0.1)
				(type default)
			)
			(layer "F.Fab")
		)
		(fp_line
			(start -0.67945 0.3048)
			(end -0.67945 -0.305054)
			(stroke
				(width 0.1)
				(type default)
			)
			(layer "F.Fab")
		)
		(fp_line
			(start -0.67945 -0.305054)
			(end -0.12065 -0.305054)
			(stroke
				(width 0.1)
				(type default)
			)
			(layer "F.Fab")
		)
		(pad "1" smd circle
			(at -0.40005 0 180)
			(size 0 0)
			(layers "F.Cu" "F.Mask" "F.Paste")
			(net "RST_SMB_NIC4_MUX_ISO_N")
		)
		(pad "2" smd circle
			(at 0.40005 0 180)
			(size 0 0)
			(layers "F.Cu" "F.Mask" "F.Paste")
			(net "P3V3_NIC4")
		)
	)
	(footprint ""
		(layer "F.Cu")
		(at 338.074 -180.975 180)
		(property "Reference" "R4751"
			(at 0 0 180)
			(layer "F.SilkS")
			(hide yes)
			(effects
				(font
					(size 1.27 1.27)
				)
			)
		)
		(property "Value" ""
			(at 0 0 180)
			(layer "F.Fab")
			(effects
				(font
					(size 1.27 1.27)
				)
			)
		)
		(duplicate_pad_numbers_are_jumpers no)
		(fp_line
			(start 0.7874 0.4064)
			(end -0.7874 0.4064)
			(stroke
				(width 0.1524)
				(type default)
			)
			(layer "F.SilkS")
		)
		(fp_line
			(start 0.7874 -0.4064)
			(end 0.7874 0.4064)
			(stroke
				(width 0.1524)
				(type default)
			)
			(layer "F.SilkS")
		)
		(fp_line
			(start -0.7874 0.4064)
			(end -0.7874 -0.4064)
			(stroke
				(width 0.1524)
				(type default)
			)
			(layer "F.SilkS")
		)
		(fp_line
			(start -0.7874 -0.4064)
			(end 0.7874 -0.4064)
			(stroke
				(width 0.1524)
				(type default)
			)
			(layer "F.SilkS")
		)
		(fp_line
			(start 0.67945 0.3048)
			(end 0.120396 0.3048)
			(stroke
				(width 0.1)
				(type default)
			)
			(layer "F.Fab")
		)
		(fp_line
			(start 0.67945 -0.3048)
			(end 0.67945 0.3048)
			(stroke
				(width 0.1)
				(type default)
			)
			(layer "F.Fab")
		)
		(fp_line
			(start 0.12065 -0.2794)
			(end 0.12065 -0.3048)
			(stroke
				(width 0.1)
				(type default)
			)
			(layer "F.Fab")
		)
		(fp_line
			(start 0.12065 -0.3048)
			(end 0.67945 -0.3048)
			(stroke
				(width 0.1)
				(type default)
			)
			(layer "F.Fab")
		)
		(fp_line
			(start 0.120396 0.3048)
			(end 0.120396 0.2794)
			(stroke
				(width 0.1)
				(type default)
			)
			(layer "F.Fab")
		)
		(fp_line
			(start 0.120396 0.2794)
			(end -0.12065 0.2794)
			(stroke
				(width 0.1)
				(type default)
			)
			(layer "F.Fab")
		)
		(fp_line
			(start -0.12065 0.3048)
			(end -0.67945 0.3048)
			(stroke
				(width 0.1)
				(type default)
			)
			(layer "F.Fab")
		)
		(fp_line
			(start -0.12065 0.2794)
			(end -0.12065 0.3048)
			(stroke
				(width 0.1)
				(type default)
			)
			(layer "F.Fab")
		)
		(fp_line
			(start -0.12065 -0.2794)
			(end 0.12065 -0.2794)
			(stroke
				(width 0.1)
				(type default)
			)
			(layer "F.Fab")
		)
		(fp_line
			(start -0.12065 -0.305054)
			(end -0.12065 -0.2794)
			(stroke
				(width 0.1)
				(type default)
			)
			(layer "F.Fab")
		)
		(fp_line
			(start -0.67945 0.3048)
			(end -0.67945 -0.305054)
			(stroke
				(width 0.1)
				(type default)
			)
			(layer "F.Fab")
		)
		(fp_line
			(start -0.67945 -0.305054)
			(end -0.12065 -0.305054)
			(stroke
				(width 0.1)
				(type default)
			)
			(layer "F.Fab")
		)
		(pad "1" smd circle
			(at -0.40005 0 180)
			(size 0 0)
			(layers "F.Cu" "F.Mask" "F.Paste")
			(net "RST_PEX_SSD8_PERST_N")
		)
		(pad "2" smd circle
			(at 0.40005 0 180)
			(size 0 0)
			(layers "F.Cu" "F.Mask" "F.Paste")
			(net "RST_PEX_SSD8_PERST_R_N")
		)
	)
	(footprint ""
		(layer "F.Cu")
		(at 26.267918 -53.051456)
		(property "Reference" "R4458"
			(at 0 0 0)
			(layer "F.SilkS")
			(hide yes)
			(effects
				(font
					(size 1.27 1.27)
				)
			)
		)
		(property "Value" ""
			(at 0 0 0)
			(layer "F.Fab")
			(effects
				(font
					(size 1.27 1.27)
				)
			)
		)
		(duplicate_pad_numbers_are_jumpers no)
		(fp_line
			(start -0.7874 -0.4064)
			(end 0.7874 -0.4064)
			(stroke
				(width 0.1524)
				(type default)
			)
			(layer "F.SilkS")
		)
		(fp_line
			(start -0.7874 0.4064)
			(end -0.7874 -0.4064)
			(stroke
				(width 0.1524)
				(type default)
			)
			(layer "F.SilkS")
		)
		(fp_line
			(start 0.7874 -0.4064)
			(end 0.7874 0.4064)
			(stroke
				(width 0.1524)
				(type default)
			)
			(layer "F.SilkS")
		)
		(fp_line
			(start 0.7874 0.4064)
			(end -0.7874 0.4064)
			(stroke
				(width 0.1524)
				(type default)
			)
			(layer "F.SilkS")
		)
		(fp_line
			(start -0.67945 -0.305054)
			(end -0.12065 -0.305054)
			(stroke
				(width 0.1)
				(type default)
			)
			(layer "F.Fab")
		)
		(fp_line
			(start -0.67945 0.3048)
			(end -0.67945 -0.305054)
			(stroke
				(width 0.1)
				(type default)
			)
			(layer "F.Fab")
		)
		(fp_line
			(start -0.12065 -0.305054)
			(end -0.12065 -0.2794)
			(stroke
				(width 0.1)
				(type default)
			)
			(layer "F.Fab")
		)
		(fp_line
			(start -0.12065 -0.2794)
			(end 0.12065 -0.2794)
			(stroke
				(width 0.1)
				(type default)
			)
			(layer "F.Fab")
		)
		(fp_line
			(start -0.12065 0.2794)
			(end -0.12065 0.3048)
			(stroke
				(width 0.1)
				(type default)
			)
			(layer "F.Fab")
		)
		(fp_line
			(start -0.12065 0.3048)
			(end -0.67945 0.3048)
			(stroke
				(width 0.1)
				(type default)
			)
			(layer "F.Fab")
		)
		(fp_line
			(start 0.120396 0.2794)
			(end -0.12065 0.2794)
			(stroke
				(width 0.1)
				(type default)
			)
			(layer "F.Fab")
		)
		(fp_line
			(start 0.120396 0.3048)
			(end 0.120396 0.2794)
			(stroke
				(width 0.1)
				(type default)
			)
			(layer "F.Fab")
		)
		(fp_line
			(start 0.12065 -0.3048)
			(end 0.67945 -0.3048)
			(stroke
				(width 0.1)
				(type default)
			)
			(layer "F.Fab")
		)
		(fp_line
			(start 0.12065 -0.2794)
			(end 0.12065 -0.3048)
			(stroke
				(width 0.1)
				(type default)
			)
			(layer "F.Fab")
		)
		(fp_line
			(start 0.67945 -0.3048)
			(end 0.67945 0.3048)
			(stroke
				(width 0.1)
				(type default)
			)
			(layer "F.Fab")
		)
		(fp_line
			(start 0.67945 0.3048)
			(end 0.120396 0.3048)
			(stroke
				(width 0.1)
				(type default)
			)
			(layer "F.Fab")
		)
		(pad "1" smd circle
			(at -0.40005 0)
			(size 0 0)
			(layers "F.Cu" "F.Mask" "F.Paste")
			(net "PWRGD_P12V_SSD0")
		)
		(pad "2" smd circle
			(at 0.40005 0)
			(size 0 0)
			(layers "F.Cu" "F.Mask" "F.Paste")
			(net "PWRGD_P12V_SSD0_R")
		)
	)
	(footprint ""
		(layer "F.Cu")
		(at 98.873818 -103.668068)
		(property "Reference" "PC321"
			(at 0 0 0)
			(layer "F.SilkS")
			(hide yes)
			(effects
				(font
					(size 1.27 1.27)
				)
			)
		)
		(property "Value" ""
			(at 0 0 0)
			(layer "F.Fab")
			(effects
				(font
					(size 1.27 1.27)
				)
			)
		)
		(duplicate_pad_numbers_are_jumpers no)
		(fp_line
			(start -1.524 -0.762)
			(end 1.524 -0.762)
			(stroke
				(width 0.1524)
				(type default)
			)
			(layer "F.SilkS")
		)
		(fp_line
			(start -1.524 0.762)
			(end -1.524 -0.762)
			(stroke
				(width 0.1524)
				(type default)
			)
			(layer "F.SilkS")
		)
		(fp_line
			(start 1.524 -0.762)
			(end 1.524 0.762)
			(stroke
				(width 0.1524)
				(type default)
			)
			(layer "F.SilkS")
		)
		(fp_line
			(start 1.524 0.762)
			(end -1.524 0.762)
			(stroke
				(width 0.1524)
				(type default)
			)
			(layer "F.SilkS")
		)
		(fp_line
			(start -1.1049 -0.724916)
			(end -1.1049 0.724916)
			(stroke
				(width 0.1)
				(type default)
			)
			(layer "F.Fab")
		)
		(fp_line
			(start -1.1049 0.724916)
			(end 1.1049 0.724916)
			(stroke
				(width 0.1)
				(type default)
			)
			(layer "F.Fab")
		)
		(fp_line
			(start 1.1049 -0.724916)
			(end -1.1049 -0.724916)
			(stroke
				(width 0.1)
				(type default)
			)
			(layer "F.Fab")
		)
		(fp_line
			(start 1.1049 0.724916)
			(end 1.1049 -0.724916)
			(stroke
				(width 0.1)
				(type default)
			)
			(layer "F.Fab")
		)
		(pad "1" smd rect
			(at -0.889 0 180)
			(size 1.016 1.27)
			(layers "F.Cu" "F.Mask" "F.Paste")
			(net "P12V_NIC1_R")
		)
		(pad "2" smd rect
			(at 0.889 0 180)
			(size 1.016 1.27)
			(layers "F.Cu" "F.Mask" "F.Paste")
			(net "GND")
		)
	)
	(footprint ""
		(layer "F.Cu")
		(at 21.530564 -66.32194 -90)
		(property "Reference" "PC646"
			(at 0 0 270)
			(layer "F.SilkS")
			(hide yes)
			(effects
				(font
					(size 1.27 1.27)
				)
			)
		)
		(property "Value" ""
			(at 0 0 270)
			(layer "F.Fab")
			(effects
				(font
					(size 1.27 1.27)
				)
			)
		)
		(duplicate_pad_numbers_are_jumpers no)
		(fp_line
			(start -0.7874 0.4064)
			(end -0.7874 -0.4064)
			(stroke
				(width 0.1524)
				(type default)
			)
			(layer "F.SilkS")
		)
		(fp_line
			(start 0.7874 0.4064)
			(end -0.7874 0.4064)
			(stroke
				(width 0.1524)
				(type default)
			)
			(layer "F.SilkS")
		)
		(fp_line
			(start -0.7874 -0.4064)
			(end 0.7874 -0.4064)
			(stroke
				(width 0.1524)
				(type default)
			)
			(layer "F.SilkS")
		)
		(fp_line
			(start 0.7874 -0.4064)
			(end 0.7874 0.4064)
			(stroke
				(width 0.1524)
				(type default)
			)
			(layer "F.SilkS")
		)
		(fp_line
			(start -0.67945 0.3048)
			(end -0.67945 -0.305054)
			(stroke
				(width 0.1)
				(type default)
			)
			(layer "F.Fab")
		)
		(fp_line
			(start -0.12065 0.3048)
			(end -0.67945 0.3048)
			(stroke
				(width 0.1)
				(type default)
			)
			(layer "F.Fab")
		)
		(fp_line
			(start 0.120396 0.3048)
			(end 0.120396 0.2794)
			(stroke
				(width 0.1)
				(type default)
			)
			(layer "F.Fab")
		)
		(fp_line
			(start 0.67945 0.3048)
			(end 0.120396 0.3048)
			(stroke
				(width 0.1)
				(type default)
			)
			(layer "F.Fab")
		)
		(fp_line
			(start -0.12065 0.2794)
			(end -0.12065 0.3048)
			(stroke
				(width 0.1)
				(type default)
			)
			(layer "F.Fab")
		)
		(fp_line
			(start 0.120396 0.2794)
			(end -0.12065 0.2794)
			(stroke
				(width 0.1)
				(type default)
			)
			(layer "F.Fab")
		)
		(fp_line
			(start -0.12065 -0.2794)
			(end 0.12065 -0.2794)
			(stroke
				(width 0.1)
				(type default)
			)
			(layer "F.Fab")
		)
		(fp_line
			(start 0.12065 -0.2794)
			(end 0.12065 -0.3048)
			(stroke
				(width 0.1)
				(type default)
			)
			(layer "F.Fab")
		)
		(fp_line
			(start 0.12065 -0.3048)
			(end 0.67945 -0.3048)
			(stroke
				(width 0.1)
				(type default)
			)
			(layer "F.Fab")
		)
		(fp_line
			(start 0.67945 -0.3048)
			(end 0.67945 0.3048)
			(stroke
				(width 0.1)
				(type default)
			)
			(layer "F.Fab")
		)
		(fp_line
			(start -0.67945 -0.305054)
			(end -0.12065 -0.305054)
			(stroke
				(width 0.1)
				(type default)
			)
			(layer "F.Fab")
		)
		(fp_line
			(start -0.12065 -0.305054)
			(end -0.12065 -0.2794)
			(stroke
				(width 0.1)
				(type default)
			)
			(layer "F.Fab")
		)
		(pad "1" smd circle
			(at -0.40005 0 270)
			(size 0 0)
			(layers "F.Cu" "F.Mask" "F.Paste")
			(net "P12V_SSD0_CO_DV_DT")
		)
		(pad "2" smd circle
			(at 0.40005 0 270)
			(size 0 0)
			(layers "F.Cu" "F.Mask" "F.Paste")
			(net "GND")
		)
	)
	(footprint ""
		(layer "F.Cu")
		(at 451.211188 -415.621216 90)
		(property "Reference" "R5607"
			(at 0 0 90)
			(layer "F.SilkS")
			(hide yes)
			(effects
				(font
					(size 1.27 1.27)
				)
			)
		)
		(property "Value" ""
			(at 0 0 90)
			(layer "F.Fab")
			(effects
				(font
					(size 1.27 1.27)
				)
			)
		)
		(duplicate_pad_numbers_are_jumpers no)
		(fp_line
			(start 0.7874 -0.4064)
			(end 0.7874 0.4064)
			(stroke
				(width 0.1524)
				(type default)
			)
			(layer "F.SilkS")
		)
		(fp_line
			(start -0.7874 -0.4064)
			(end 0.7874 -0.4064)
			(stroke
				(width 0.1524)
				(type default)
			)
			(layer "F.SilkS")
		)
		(fp_line
			(start 0.7874 0.4064)
			(end -0.7874 0.4064)
			(stroke
				(width 0.1524)
				(type default)
			)
			(layer "F.SilkS")
		)
		(fp_line
			(start -0.7874 0.4064)
			(end -0.7874 -0.4064)
			(stroke
				(width 0.1524)
				(type default)
			)
			(layer "F.SilkS")
		)
		(fp_line
			(start -0.12065 -0.305054)
			(end -0.12065 -0.2794)
			(stroke
				(width 0.1)
				(type default)
			)
			(layer "F.Fab")
		)
		(fp_line
			(start -0.67945 -0.305054)
			(end -0.12065 -0.305054)
			(stroke
				(width 0.1)
				(type default)
			)
			(layer "F.Fab")
		)
		(fp_line
			(start 0.67945 -0.3048)
			(end 0.67945 0.3048)
			(stroke
				(width 0.1)
				(type default)
			)
			(layer "F.Fab")
		)
		(fp_line
			(start 0.12065 -0.3048)
			(end 0.67945 -0.3048)
			(stroke
				(width 0.1)
				(type default)
			)
			(layer "F.Fab")
		)
		(fp_line
			(start 0.12065 -0.2794)
			(end 0.12065 -0.3048)
			(stroke
				(width 0.1)
				(type default)
			)
			(layer "F.Fab")
		)
		(fp_line
			(start -0.12065 -0.2794)
			(end 0.12065 -0.2794)
			(stroke
				(width 0.1)
				(type default)
			)
			(layer "F.Fab")
		)
		(fp_line
			(start 0.120396 0.2794)
			(end -0.12065 0.2794)
			(stroke
				(width 0.1)
				(type default)
			)
			(layer "F.Fab")
		)
		(fp_line
			(start -0.12065 0.2794)
			(end -0.12065 0.3048)
			(stroke
				(width 0.1)
				(type default)
			)
			(layer "F.Fab")
		)
		(fp_line
			(start 0.67945 0.3048)
			(end 0.120396 0.3048)
			(stroke
				(width 0.1)
				(type default)
			)
			(layer "F.Fab")
		)
		(fp_line
			(start 0.120396 0.3048)
			(end 0.120396 0.2794)
			(stroke
				(width 0.1)
				(type default)
			)
			(layer "F.Fab")
		)
		(fp_line
			(start -0.12065 0.3048)
			(end -0.67945 0.3048)
			(stroke
				(width 0.1)
				(type default)
			)
			(layer "F.Fab")
		)
		(fp_line
			(start -0.67945 0.3048)
			(end -0.67945 -0.305054)
			(stroke
				(width 0.1)
				(type default)
			)
			(layer "F.Fab")
		)
		(pad "1" smd circle
			(at -0.40005 0 90)
			(size 0 0)
			(layers "F.Cu" "F.Mask" "F.Paste")
			(net "LM75_1_A2")
		)
		(pad "2" smd circle
			(at 0.40005 0 90)
			(size 0 0)
			(layers "F.Cu" "F.Mask" "F.Paste")
			(net "GND")
		)
	)
	(footprint ""
		(layer "F.Cu")
		(at 293.394892 -59.577986 90)
		(property "Reference" "PC578"
			(at 0 0 90)
			(layer "F.SilkS")
			(hide yes)
			(effects
				(font
					(size 1.27 1.27)
				)
			)
		)
		(property "Value" ""
			(at 0 0 90)
			(layer "F.Fab")
			(effects
				(font
					(size 1.27 1.27)
				)
			)
		)
		(duplicate_pad_numbers_are_jumpers no)
		(fp_line
			(start 0.7874 -0.4064)
			(end 0.7874 0.4064)
			(stroke
				(width 0.1524)
				(type default)
			)
			(layer "F.SilkS")
		)
		(fp_line
			(start -0.7874 -0.4064)
			(end 0.7874 -0.4064)
			(stroke
				(width 0.1524)
				(type default)
			)
			(layer "F.SilkS")
		)
		(fp_line
			(start 0.7874 0.4064)
			(end -0.7874 0.4064)
			(stroke
				(width 0.1524)
				(type default)
			)
			(layer "F.SilkS")
		)
		(fp_line
			(start -0.7874 0.4064)
			(end -0.7874 -0.4064)
			(stroke
				(width 0.1524)
				(type default)
			)
			(layer "F.SilkS")
		)
		(fp_line
			(start -0.12065 -0.305054)
			(end -0.12065 -0.2794)
			(stroke
				(width 0.1)
				(type default)
			)
			(layer "F.Fab")
		)
		(fp_line
			(start -0.67945 -0.305054)
			(end -0.12065 -0.305054)
			(stroke
				(width 0.1)
				(type default)
			)
			(layer "F.Fab")
		)
		(fp_line
			(start 0.67945 -0.3048)
			(end 0.67945 0.3048)
			(stroke
				(width 0.1)
				(type default)
			)
			(layer "F.Fab")
		)
		(fp_line
			(start 0.12065 -0.3048)
			(end 0.67945 -0.3048)
			(stroke
				(width 0.1)
				(type default)
			)
			(layer "F.Fab")
		)
		(fp_line
			(start 0.12065 -0.2794)
			(end 0.12065 -0.3048)
			(stroke
				(width 0.1)
				(type default)
			)
			(layer "F.Fab")
		)
		(fp_line
			(start -0.12065 -0.2794)
			(end 0.12065 -0.2794)
			(stroke
				(width 0.1)
				(type default)
			)
			(layer "F.Fab")
		)
		(fp_line
			(start 0.120396 0.2794)
			(end -0.12065 0.2794)
			(stroke
				(width 0.1)
				(type default)
			)
			(layer "F.Fab")
		)
		(fp_line
			(start -0.12065 0.2794)
			(end -0.12065 0.3048)
			(stroke
				(width 0.1)
				(type default)
			)
			(layer "F.Fab")
		)
		(fp_line
			(start 0.67945 0.3048)
			(end 0.120396 0.3048)
			(stroke
				(width 0.1)
				(type default)
			)
			(layer "F.Fab")
		)
		(fp_line
			(start 0.120396 0.3048)
			(end 0.120396 0.2794)
			(stroke
				(width 0.1)
				(type default)
			)
			(layer "F.Fab")
		)
		(fp_line
			(start -0.12065 0.3048)
			(end -0.67945 0.3048)
			(stroke
				(width 0.1)
				(type default)
			)
			(layer "F.Fab")
		)
		(fp_line
			(start -0.67945 0.3048)
			(end -0.67945 -0.305054)
			(stroke
				(width 0.1)
				(type default)
			)
			(layer "F.Fab")
		)
		(pad "1" smd circle
			(at -0.40005 0 90)
			(size 0 0)
			(layers "F.Cu" "F.Mask" "F.Paste")
			(net "P3V3_SSD10_SS")
		)
		(pad "2" smd circle
			(at 0.40005 0 90)
			(size 0 0)
			(layers "F.Cu" "F.Mask" "F.Paste")
			(net "GND")
		)
	)
	(footprint ""
		(layer "F.Cu")
		(at 32.411416 -286.844232 -90)
		(property "Reference" "R4564"
			(at 0 0 270)
			(layer "F.SilkS")
			(hide yes)
			(effects
				(font
					(size 1.27 1.27)
				)
			)
		)
		(property "Value" ""
			(at 0 0 270)
			(layer "F.Fab")
			(effects
				(font
					(size 1.27 1.27)
				)
			)
		)
		(duplicate_pad_numbers_are_jumpers no)
		(fp_line
			(start -0.7874 0.4064)
			(end -0.7874 -0.4064)
			(stroke
				(width 0.1524)
				(type default)
			)
			(layer "F.SilkS")
		)
		(fp_line
			(start 0.7874 0.4064)
			(end -0.7874 0.4064)
			(stroke
				(width 0.1524)
				(type default)
			)
			(layer "F.SilkS")
		)
		(fp_line
			(start -0.7874 -0.4064)
			(end 0.7874 -0.4064)
			(stroke
				(width 0.1524)
				(type default)
			)
			(layer "F.SilkS")
		)
		(fp_line
			(start 0.7874 -0.4064)
			(end 0.7874 0.4064)
			(stroke
				(width 0.1524)
				(type default)
			)
			(layer "F.SilkS")
		)
		(fp_line
			(start -0.67945 0.3048)
			(end -0.67945 -0.305054)
			(stroke
				(width 0.1)
				(type default)
			)
			(layer "F.Fab")
		)
		(fp_line
			(start -0.12065 0.3048)
			(end -0.67945 0.3048)
			(stroke
				(width 0.1)
				(type default)
			)
			(layer "F.Fab")
		)
		(fp_line
			(start 0.120396 0.3048)
			(end 0.120396 0.2794)
			(stroke
				(width 0.1)
				(type default)
			)
			(layer "F.Fab")
		)
		(fp_line
			(start 0.67945 0.3048)
			(end 0.120396 0.3048)
			(stroke
				(width 0.1)
				(type default)
			)
			(layer "F.Fab")
		)
		(fp_line
			(start -0.12065 0.2794)
			(end -0.12065 0.3048)
			(stroke
				(width 0.1)
				(type default)
			)
			(layer "F.Fab")
		)
		(fp_line
			(start 0.120396 0.2794)
			(end -0.12065 0.2794)
			(stroke
				(width 0.1)
				(type default)
			)
			(layer "F.Fab")
		)
		(fp_line
			(start -0.12065 -0.2794)
			(end 0.12065 -0.2794)
			(stroke
				(width 0.1)
				(type default)
			)
			(layer "F.Fab")
		)
		(fp_line
			(start 0.12065 -0.2794)
			(end 0.12065 -0.3048)
			(stroke
				(width 0.1)
				(type default)
			)
			(layer "F.Fab")
		)
		(fp_line
			(start 0.12065 -0.3048)
			(end 0.67945 -0.3048)
			(stroke
				(width 0.1)
				(type default)
			)
			(layer "F.Fab")
		)
		(fp_line
			(start 0.67945 -0.3048)
			(end 0.67945 0.3048)
			(stroke
				(width 0.1)
				(type default)
			)
			(layer "F.Fab")
		)
		(fp_line
			(start -0.67945 -0.305054)
			(end -0.12065 -0.305054)
			(stroke
				(width 0.1)
				(type default)
			)
			(layer "F.Fab")
		)
		(fp_line
			(start -0.12065 -0.305054)
			(end -0.12065 -0.2794)
			(stroke
				(width 0.1)
				(type default)
			)
			(layer "F.Fab")
		)
		(pad "1" smd circle
			(at -0.40005 0 270)
			(size 0 0)
			(layers "F.Cu" "F.Mask" "F.Paste")
			(net "PCEPLL6_VDDA18_PEX0")
		)
		(pad "2" smd circle
			(at 0.40005 0 270)
			(size 0 0)
			(layers "F.Cu" "F.Mask" "F.Paste")
			(net "PCEPLL6_VDDA18_PEX0_R")
		)
	)
	(footprint ""
		(layer "F.Cu")
		(at 13.0175 -312.137552)
		(property "Reference" "PC206"
			(at 0 0 0)
			(layer "F.SilkS")
			(hide yes)
			(effects
				(font
					(size 1.27 1.27)
				)
			)
		)
		(property "Value" ""
			(at 0 0 0)
			(layer "F.Fab")
			(effects
				(font
					(size 1.27 1.27)
				)
			)
		)
		(duplicate_pad_numbers_are_jumpers no)
		(fp_line
			(start -1.524 -0.762)
			(end 1.524 -0.762)
			(stroke
				(width 0.1524)
				(type default)
			)
			(layer "F.SilkS")
		)
		(fp_line
			(start -1.524 0.762)
			(end -1.524 -0.762)
			(stroke
				(width 0.1524)
				(type default)
			)
			(layer "F.SilkS")
		)
		(fp_line
			(start 1.524 -0.762)
			(end 1.524 0.762)
			(stroke
				(width 0.1524)
				(type default)
			)
			(layer "F.SilkS")
		)
		(fp_line
			(start 1.524 0.762)
			(end -1.524 0.762)
			(stroke
				(width 0.1524)
				(type default)
			)
			(layer "F.SilkS")
		)
		(fp_line
			(start -1.1049 -0.724916)
			(end -1.1049 0.724916)
			(stroke
				(width 0.1)
				(type default)
			)
			(layer "F.Fab")
		)
		(fp_line
			(start -1.1049 0.724916)
			(end 1.1049 0.724916)
			(stroke
				(width 0.1)
				(type default)
			)
			(layer "F.Fab")
		)
		(fp_line
			(start 1.1049 -0.724916)
			(end -1.1049 -0.724916)
			(stroke
				(width 0.1)
				(type default)
			)
			(layer "F.Fab")
		)
		(fp_line
			(start 1.1049 0.724916)
			(end 1.1049 -0.724916)
			(stroke
				(width 0.1)
				(type default)
			)
			(layer "F.Fab")
		)
		(pad "1" smd rect
			(at -0.889 0 180)
			(size 1.016 1.27)
			(layers "F.Cu" "F.Mask" "F.Paste")
			(net "SW_P12V_P1V25_PEX0_FLT")
		)
		(pad "2" smd rect
			(at 0.889 0 180)
			(size 1.016 1.27)
			(layers "F.Cu" "F.Mask" "F.Paste")
			(net "GND")
		)
	)
	(footprint ""
		(layer "F.Cu")
		(at 258.44373 -45.88891)
		(property "Reference" "R598"
			(at 0 0 0)
			(layer "F.SilkS")
			(hide yes)
			(effects
				(font
					(size 1.27 1.27)
				)
			)
		)
		(property "Value" ""
			(at 0 0 0)
			(layer "F.Fab")
			(effects
				(font
					(size 1.27 1.27)
				)
			)
		)
		(duplicate_pad_numbers_are_jumpers no)
		(fp_line
			(start -0.7874 -0.4064)
			(end 0.7874 -0.4064)
			(stroke
				(width 0.1524)
				(type default)
			)
			(layer "F.SilkS")
		)
		(fp_line
			(start -0.7874 0.4064)
			(end -0.7874 -0.4064)
			(stroke
				(width 0.1524)
				(type default)
			)
			(layer "F.SilkS")
		)
		(fp_line
			(start 0.7874 -0.4064)
			(end 0.7874 0.4064)
			(stroke
				(width 0.1524)
				(type default)
			)
			(layer "F.SilkS")
		)
		(fp_line
			(start 0.7874 0.4064)
			(end -0.7874 0.4064)
			(stroke
				(width 0.1524)
				(type default)
			)
			(layer "F.SilkS")
		)
		(fp_line
			(start -0.67945 -0.305054)
			(end -0.12065 -0.305054)
			(stroke
				(width 0.1)
				(type default)
			)
			(layer "F.Fab")
		)
		(fp_line
			(start -0.67945 0.3048)
			(end -0.67945 -0.305054)
			(stroke
				(width 0.1)
				(type default)
			)
			(layer "F.Fab")
		)
		(fp_line
			(start -0.12065 -0.305054)
			(end -0.12065 -0.2794)
			(stroke
				(width 0.1)
				(type default)
			)
			(layer "F.Fab")
		)
		(fp_line
			(start -0.12065 -0.2794)
			(end 0.12065 -0.2794)
			(stroke
				(width 0.1)
				(type default)
			)
			(layer "F.Fab")
		)
		(fp_line
			(start -0.12065 0.2794)
			(end -0.12065 0.3048)
			(stroke
				(width 0.1)
				(type default)
			)
			(layer "F.Fab")
		)
		(fp_line
			(start -0.12065 0.3048)
			(end -0.67945 0.3048)
			(stroke
				(width 0.1)
				(type default)
			)
			(layer "F.Fab")
		)
		(fp_line
			(start 0.120396 0.2794)
			(end -0.12065 0.2794)
			(stroke
				(width 0.1)
				(type default)
			)
			(layer "F.Fab")
		)
		(fp_line
			(start 0.120396 0.3048)
			(end 0.120396 0.2794)
			(stroke
				(width 0.1)
				(type default)
			)
			(layer "F.Fab")
		)
		(fp_line
			(start 0.12065 -0.3048)
			(end 0.67945 -0.3048)
			(stroke
				(width 0.1)
				(type default)
			)
			(layer "F.Fab")
		)
		(fp_line
			(start 0.12065 -0.2794)
			(end 0.12065 -0.3048)
			(stroke
				(width 0.1)
				(type default)
			)
			(layer "F.Fab")
		)
		(fp_line
			(start 0.67945 -0.3048)
			(end 0.67945 0.3048)
			(stroke
				(width 0.1)
				(type default)
			)
			(layer "F.Fab")
		)
		(fp_line
			(start 0.67945 0.3048)
			(end 0.120396 0.3048)
			(stroke
				(width 0.1)
				(type default)
			)
			(layer "F.Fab")
		)
		(pad "1" smd circle
			(at -0.40005 0)
			(size 0 0)
			(layers "F.Cu" "F.Mask" "F.Paste")
			(net "SSD8_ADC_A0")
		)
		(pad "2" smd circle
			(at 0.40005 0)
			(size 0 0)
			(layers "F.Cu" "F.Mask" "F.Paste")
			(net "GND")
		)
	)
	(footprint ""
		(layer "F.Cu")
		(at 84.023962 -343.952322 90)
		(property "Reference" "C108"
			(at 0 0 90)
			(layer "F.SilkS")
			(hide yes)
			(effects
				(font
					(size 1.27 1.27)
				)
			)
		)
		(property "Value" ""
			(at 0 0 90)
			(layer "F.Fab")
			(effects
				(font
					(size 1.27 1.27)
				)
			)
		)
		(duplicate_pad_numbers_are_jumpers no)
		(fp_line
			(start 0.299974 -0.150114)
			(end 0.299974 0.150114)
			(stroke
				(width 0.1)
				(type default)
			)
			(layer "F.Fab")
		)
		(fp_line
			(start -0.299974 -0.150114)
			(end 0.299974 -0.150114)
			(stroke
				(width 0.1)
				(type default)
			)
			(layer "F.Fab")
		)
		(fp_line
			(start 0.299974 0.150114)
			(end -0.299974 0.150114)
			(stroke
				(width 0.1)
				(type default)
			)
			(layer "F.Fab")
		)
		(fp_line
			(start -0.299974 0.150114)
			(end -0.299974 -0.150114)
			(stroke
				(width 0.1)
				(type default)
			)
			(layer "F.Fab")
		)
		(pad "1" smd rect
			(at -0.2667 0 90)
			(size 0.3048 0.381)
			(layers "F.Cu" "F.Mask" "F.Paste")
			(net "P5E_PEX0_STN5_TX_DN<90>")
		)
		(pad "2" smd rect
			(at 0.2667 0 90)
			(size 0.3048 0.381)
			(layers "F.Cu" "F.Mask" "F.Paste")
			(net "P5E_PEX0_STN5_TX_C_DN<90>")
		)
	)
	(footprint ""
		(layer "F.Cu")
		(at 358.41051 -125.979428)
		(property "Reference" "R883"
			(at 0 0 0)
			(layer "F.SilkS")
			(hide yes)
			(effects
				(font
					(size 1.27 1.27)
				)
			)
		)
		(property "Value" ""
			(at 0 0 0)
			(layer "F.Fab")
			(effects
				(font
					(size 1.27 1.27)
				)
			)
		)
		(duplicate_pad_numbers_are_jumpers no)
		(fp_line
			(start -0.7874 -0.4064)
			(end 0.7874 -0.4064)
			(stroke
				(width 0.1524)
				(type default)
			)
			(layer "F.SilkS")
		)
		(fp_line
			(start -0.7874 0.4064)
			(end -0.7874 -0.4064)
			(stroke
				(width 0.1524)
				(type default)
			)
			(layer "F.SilkS")
		)
		(fp_line
			(start 0.7874 -0.4064)
			(end 0.7874 0.4064)
			(stroke
				(width 0.1524)
				(type default)
			)
			(layer "F.SilkS")
		)
		(fp_line
			(start 0.7874 0.4064)
			(end -0.7874 0.4064)
			(stroke
				(width 0.1524)
				(type default)
			)
			(layer "F.SilkS")
		)
		(fp_line
			(start -0.67945 -0.305054)
			(end -0.12065 -0.305054)
			(stroke
				(width 0.1)
				(type default)
			)
			(layer "F.Fab")
		)
		(fp_line
			(start -0.67945 0.3048)
			(end -0.67945 -0.305054)
			(stroke
				(width 0.1)
				(type default)
			)
			(layer "F.Fab")
		)
		(fp_line
			(start -0.12065 -0.305054)
			(end -0.12065 -0.2794)
			(stroke
				(width 0.1)
				(type default)
			)
			(layer "F.Fab")
		)
		(fp_line
			(start -0.12065 -0.2794)
			(end 0.12065 -0.2794)
			(stroke
				(width 0.1)
				(type default)
			)
			(layer "F.Fab")
		)
		(fp_line
			(start -0.12065 0.2794)
			(end -0.12065 0.3048)
			(stroke
				(width 0.1)
				(type default)
			)
			(layer "F.Fab")
		)
		(fp_line
			(start -0.12065 0.3048)
			(end -0.67945 0.3048)
			(stroke
				(width 0.1)
				(type default)
			)
			(layer "F.Fab")
		)
		(fp_line
			(start 0.120396 0.2794)
			(end -0.12065 0.2794)
			(stroke
				(width 0.1)
				(type default)
			)
			(layer "F.Fab")
		)
		(fp_line
			(start 0.120396 0.3048)
			(end 0.120396 0.2794)
			(stroke
				(width 0.1)
				(type default)
			)
			(layer "F.Fab")
		)
		(fp_line
			(start 0.12065 -0.3048)
			(end 0.67945 -0.3048)
			(stroke
				(width 0.1)
				(type default)
			)
			(layer "F.Fab")
		)
		(fp_line
			(start 0.12065 -0.2794)
			(end 0.12065 -0.3048)
			(stroke
				(width 0.1)
				(type default)
			)
			(layer "F.Fab")
		)
		(fp_line
			(start 0.67945 -0.3048)
			(end 0.67945 0.3048)
			(stroke
				(width 0.1)
				(type default)
			)
			(layer "F.Fab")
		)
		(fp_line
			(start 0.67945 0.3048)
			(end 0.120396 0.3048)
			(stroke
				(width 0.1)
				(type default)
			)
			(layer "F.Fab")
		)
		(pad "1" smd circle
			(at -0.40005 0)
			(size 0 0)
			(layers "F.Cu" "F.Mask" "F.Paste")
			(net "P3V3_NIC6")
		)
		(pad "2" smd circle
			(at 0.40005 0)
			(size 0 0)
			(layers "F.Cu" "F.Mask" "F.Paste")
			(net "PWRGD_P3V3_NIC6")
		)
	)
	(footprint ""
		(layer "F.Cu")
		(at 55.88 -139.6492)
		(property "Reference" "R7"
			(at 0 0 0)
			(layer "F.SilkS")
			(hide yes)
			(effects
				(font
					(size 1.27 1.27)
				)
			)
		)
		(property "Value" ""
			(at 0 0 0)
			(layer "F.Fab")
			(effects
				(font
					(size 1.27 1.27)
				)
			)
		)
		(duplicate_pad_numbers_are_jumpers no)
		(fp_line
			(start -0.7874 -0.4064)
			(end 0.7874 -0.4064)
			(stroke
				(width 0.1524)
				(type default)
			)
			(layer "F.SilkS")
		)
		(fp_line
			(start -0.7874 0.4064)
			(end -0.7874 -0.4064)
			(stroke
				(width 0.1524)
				(type default)
			)
			(layer "F.SilkS")
		)
		(fp_line
			(start 0.7874 -0.4064)
			(end 0.7874 0.4064)
			(stroke
				(width 0.1524)
				(type default)
			)
			(layer "F.SilkS")
		)
		(fp_line
			(start 0.7874 0.4064)
			(end -0.7874 0.4064)
			(stroke
				(width 0.1524)
				(type default)
			)
			(layer "F.SilkS")
		)
		(fp_line
			(start -0.67945 -0.305054)
			(end -0.12065 -0.305054)
			(stroke
				(width 0.1)
				(type default)
			)
			(layer "F.Fab")
		)
		(fp_line
			(start -0.67945 0.3048)
			(end -0.67945 -0.305054)
			(stroke
				(width 0.1)
				(type default)
			)
			(layer "F.Fab")
		)
		(fp_line
			(start -0.12065 -0.305054)
			(end -0.12065 -0.2794)
			(stroke
				(width 0.1)
				(type default)
			)
			(layer "F.Fab")
		)
		(fp_line
			(start -0.12065 -0.2794)
			(end 0.12065 -0.2794)
			(stroke
				(width 0.1)
				(type default)
			)
			(layer "F.Fab")
		)
		(fp_line
			(start -0.12065 0.2794)
			(end -0.12065 0.3048)
			(stroke
				(width 0.1)
				(type default)
			)
			(layer "F.Fab")
		)
		(fp_line
			(start -0.12065 0.3048)
			(end -0.67945 0.3048)
			(stroke
				(width 0.1)
				(type default)
			)
			(layer "F.Fab")
		)
		(fp_line
			(start 0.120396 0.2794)
			(end -0.12065 0.2794)
			(stroke
				(width 0.1)
				(type default)
			)
			(layer "F.Fab")
		)
		(fp_line
			(start 0.120396 0.3048)
			(end 0.120396 0.2794)
			(stroke
				(width 0.1)
				(type default)
			)
			(layer "F.Fab")
		)
		(fp_line
			(start 0.12065 -0.3048)
			(end 0.67945 -0.3048)
			(stroke
				(width 0.1)
				(type default)
			)
			(layer "F.Fab")
		)
		(fp_line
			(start 0.12065 -0.2794)
			(end 0.12065 -0.3048)
			(stroke
				(width 0.1)
				(type default)
			)
			(layer "F.Fab")
		)
		(fp_line
			(start 0.67945 -0.3048)
			(end 0.67945 0.3048)
			(stroke
				(width 0.1)
				(type default)
			)
			(layer "F.Fab")
		)
		(fp_line
			(start 0.67945 0.3048)
			(end 0.120396 0.3048)
			(stroke
				(width 0.1)
				(type default)
			)
			(layer "F.Fab")
		)
		(pad "1" smd circle
			(at -0.40005 0)
			(size 0 0)
			(layers "F.Cu" "F.Mask" "F.Paste")
			(net "PRSNTB2_NIC0_N")
		)
		(pad "2" smd circle
			(at 0.40005 0)
			(size 0 0)
			(layers "F.Cu" "F.Mask" "F.Paste")
			(net "P3V3_AUX")
		)
	)
	(footprint ""
		(layer "F.Cu")
		(at 144.149318 -300.197012 -90)
		(property "Reference" "C3212"
			(at 0 0 270)
			(layer "F.SilkS")
			(hide yes)
			(effects
				(font
					(size 1.27 1.27)
				)
			)
		)
		(property "Value" ""
			(at 0 0 270)
			(layer "F.Fab")
			(effects
				(font
					(size 1.27 1.27)
				)
			)
		)
		(duplicate_pad_numbers_are_jumpers no)
		(fp_line
			(start -0.299974 0.150114)
			(end -0.299974 -0.150114)
			(stroke
				(width 0.1)
				(type default)
			)
			(layer "F.Fab")
		)
		(fp_line
			(start 0.299974 0.150114)
			(end -0.299974 0.150114)
			(stroke
				(width 0.1)
				(type default)
			)
			(layer "F.Fab")
		)
		(fp_line
			(start -0.299974 -0.150114)
			(end 0.299974 -0.150114)
			(stroke
				(width 0.1)
				(type default)
			)
			(layer "F.Fab")
		)
		(fp_line
			(start 0.299974 -0.150114)
			(end 0.299974 0.150114)
			(stroke
				(width 0.1)
				(type default)
			)
			(layer "F.Fab")
		)
		(pad "1" smd rect
			(at -0.2667 0 270)
			(size 0.3048 0.381)
			(layers "F.Cu" "F.Mask" "F.Paste")
			(net "P1V8_PLL0_PEX1")
		)
		(pad "2" smd rect
			(at 0.2667 0 270)
			(size 0.3048 0.381)
			(layers "F.Cu" "F.Mask" "F.Paste")
			(net "GND")
		)
	)
	(footprint ""
		(layer "F.Cu")
		(at 414.197292 -183.078882)
		(property "Reference" "Q239"
			(at -3.857244 -1.611122 0)
			(unlocked yes)
			(layer "F.SilkS")
			(effects
				(font
					(size 0.7874 0.5842)
					(thickness 0.1524)
				)
			)
		)
		(property "Value" ""
			(at 0 0 0)
			(layer "F.Fab")
			(effects
				(font
					(size 1.27 1.27)
				)
			)
		)
		(duplicate_pad_numbers_are_jumpers no)
		(fp_line
			(start -1.376172 -1.199896)
			(end -0.508 -1.199896)
			(stroke
				(width 0.1524)
				(type default)
			)
			(layer "F.SilkS")
		)
		(fp_line
			(start -1.376172 1.199896)
			(end -1.376172 -1.199896)
			(stroke
				(width 0.1524)
				(type default)
			)
			(layer "F.SilkS")
		)
		(fp_line
			(start -0.508 -1.199896)
			(end 0 -0.762)
			(stroke
				(width 0.1524)
				(type default)
			)
			(layer "F.SilkS")
		)
		(fp_line
			(start 0 -0.762)
			(end 0.508 -1.199896)
			(stroke
				(width 0.1524)
				(type default)
			)
			(layer "F.SilkS")
		)
		(fp_line
			(start 0.508 -1.199896)
			(end 1.376172 -1.199896)
			(stroke
				(width 0.1524)
				(type default)
			)
			(layer "F.SilkS")
		)
		(fp_line
			(start 1.376172 -1.199896)
			(end 1.376172 1.199896)
			(stroke
				(width 0.1524)
				(type default)
			)
			(layer "F.SilkS")
		)
		(fp_line
			(start 1.376172 1.199896)
			(end -1.376172 1.199896)
			(stroke
				(width 0.1524)
				(type default)
			)
			(layer "F.SilkS")
		)
		(fp_poly
			(pts
				(xy -1.4605 -0.7493) (xy -2.2225 -1.1303) (xy -2.2225 -0.3683)
			)
			(stroke
				(width 0)
				(type default)
			)
			(fill yes)
			(layer "F.SilkS")
		)
		(fp_line
			(start -0.674878 -1.100074)
			(end 0.674878 -1.100074)
			(stroke
				(width 0.1)
				(type default)
			)
			(layer "F.Fab")
		)
		(fp_line
			(start -0.674878 1.100074)
			(end -0.674878 -1.100074)
			(stroke
				(width 0.1)
				(type default)
			)
			(layer "F.Fab")
		)
		(fp_line
			(start 0.674878 -1.100074)
			(end 0.674878 1.100074)
			(stroke
				(width 0.1)
				(type default)
			)
			(layer "F.Fab")
		)
		(fp_line
			(start 0.674878 1.100074)
			(end -0.674878 1.100074)
			(stroke
				(width 0.1)
				(type default)
			)
			(layer "F.Fab")
		)
		(fp_poly
			(pts
				(xy -1.4605 -0.7493) (xy -2.2225 -1.1303) (xy -2.2225 -0.3683)
			)
			(stroke
				(width 0)
				(type default)
			)
			(fill yes)
			(layer "F.Fab")
		)
		(pad "1" smd rect
			(at -0.899922 -0.750062 270)
			(size 0.6096 0.6096)
			(layers "F.Cu" "F.Mask" "F.Paste")
			(net "GND")
		)
		(pad "2" smd rect
			(at -0.899922 0 270)
			(size 0.4064 0.6096)
			(layers "F.Cu" "F.Mask" "F.Paste")
			(net "FPGA_PEX3_MODE_SEL2_R")
		)
		(pad "3" smd rect
			(at -0.899922 0.750062 270)
			(size 0.6096 0.6096)
			(layers "F.Cu" "F.Mask" "F.Paste")
			(net "FPGA_PEX3_MODE_SEL2_ISO")
		)
		(pad "4" smd rect
			(at 0.899922 0.750062 270)
			(size 0.6096 0.6096)
			(layers "F.Cu" "F.Mask" "F.Paste")
			(net "GND")
		)
		(pad "5" smd rect
			(at 0.899922 0 270)
			(size 0.4064 0.6096)
			(layers "F.Cu" "F.Mask" "F.Paste")
			(net "FPGA_PEX3_MODE_SEL2_D_N")
		)
		(pad "6" smd rect
			(at 0.899922 -0.750062 270)
			(size 0.6096 0.6096)
			(layers "F.Cu" "F.Mask" "F.Paste")
			(net "FPGA_PEX3_MODE_SEL2_D_N")
		)
	)
	(footprint ""
		(layer "F.Cu")
		(at 212.44687 -218.945968 -90)
		(property "Reference" "R4875"
			(at 0 0 270)
			(layer "F.SilkS")
			(hide yes)
			(effects
				(font
					(size 1.27 1.27)
				)
			)
		)
		(property "Value" ""
			(at 0 0 270)
			(layer "F.Fab")
			(effects
				(font
					(size 1.27 1.27)
				)
			)
		)
		(duplicate_pad_numbers_are_jumpers no)
		(fp_line
			(start -0.7874 0.4064)
			(end -0.7874 -0.4064)
			(stroke
				(width 0.1524)
				(type default)
			)
			(layer "F.SilkS")
		)
		(fp_line
			(start 0.7874 0.4064)
			(end -0.7874 0.4064)
			(stroke
				(width 0.1524)
				(type default)
			)
			(layer "F.SilkS")
		)
		(fp_line
			(start -0.7874 -0.4064)
			(end 0.7874 -0.4064)
			(stroke
				(width 0.1524)
				(type default)
			)
			(layer "F.SilkS")
		)
		(fp_line
			(start 0.7874 -0.4064)
			(end 0.7874 0.4064)
			(stroke
				(width 0.1524)
				(type default)
			)
			(layer "F.SilkS")
		)
		(fp_line
			(start -0.67945 0.3048)
			(end -0.67945 -0.305054)
			(stroke
				(width 0.1)
				(type default)
			)
			(layer "F.Fab")
		)
		(fp_line
			(start -0.12065 0.3048)
			(end -0.67945 0.3048)
			(stroke
				(width 0.1)
				(type default)
			)
			(layer "F.Fab")
		)
		(fp_line
			(start 0.120396 0.3048)
			(end 0.120396 0.2794)
			(stroke
				(width 0.1)
				(type default)
			)
			(layer "F.Fab")
		)
		(fp_line
			(start 0.67945 0.3048)
			(end 0.120396 0.3048)
			(stroke
				(width 0.1)
				(type default)
			)
			(layer "F.Fab")
		)
		(fp_line
			(start -0.12065 0.2794)
			(end -0.12065 0.3048)
			(stroke
				(width 0.1)
				(type default)
			)
			(layer "F.Fab")
		)
		(fp_line
			(start 0.120396 0.2794)
			(end -0.12065 0.2794)
			(stroke
				(width 0.1)
				(type default)
			)
			(layer "F.Fab")
		)
		(fp_line
			(start -0.12065 -0.2794)
			(end 0.12065 -0.2794)
			(stroke
				(width 0.1)
				(type default)
			)
			(layer "F.Fab")
		)
		(fp_line
			(start 0.12065 -0.2794)
			(end 0.12065 -0.3048)
			(stroke
				(width 0.1)
				(type default)
			)
			(layer "F.Fab")
		)
		(fp_line
			(start 0.12065 -0.3048)
			(end 0.67945 -0.3048)
			(stroke
				(width 0.1)
				(type default)
			)
			(layer "F.Fab")
		)
		(fp_line
			(start 0.67945 -0.3048)
			(end 0.67945 0.3048)
			(stroke
				(width 0.1)
				(type default)
			)
			(layer "F.Fab")
		)
		(fp_line
			(start -0.67945 -0.305054)
			(end -0.12065 -0.305054)
			(stroke
				(width 0.1)
				(type default)
			)
			(layer "F.Fab")
		)
		(fp_line
			(start -0.12065 -0.305054)
			(end -0.12065 -0.2794)
			(stroke
				(width 0.1)
				(type default)
			)
			(layer "F.Fab")
		)
		(pad "1" smd circle
			(at -0.40005 0 270)
			(size 0 0)
			(layers "F.Cu" "F.Mask" "F.Paste")
			(net "P1V2_AUX")
		)
		(pad "2" smd circle
			(at 0.40005 0 270)
			(size 0 0)
			(layers "F.Cu" "F.Mask" "F.Paste")
			(net "SMB_NIC5_SCL")
		)
	)
	(footprint ""
		(layer "F.Cu")
		(at 36.638484 -130.408934)
		(property "Reference" "C39"
			(at 0 0 0)
			(layer "F.SilkS")
			(hide yes)
			(effects
				(font
					(size 1.27 1.27)
				)
			)
		)
		(property "Value" ""
			(at 0 0 0)
			(layer "F.Fab")
			(effects
				(font
					(size 1.27 1.27)
				)
			)
		)
		(duplicate_pad_numbers_are_jumpers no)
		(fp_line
			(start -0.299974 -0.150114)
			(end 0.299974 -0.150114)
			(stroke
				(width 0.1)
				(type default)
			)
			(layer "F.Fab")
		)
		(fp_line
			(start -0.299974 0.150114)
			(end -0.299974 -0.150114)
			(stroke
				(width 0.1)
				(type default)
			)
			(layer "F.Fab")
		)
		(fp_line
			(start 0.299974 -0.150114)
			(end 0.299974 0.150114)
			(stroke
				(width 0.1)
				(type default)
			)
			(layer "F.Fab")
		)
		(fp_line
			(start 0.299974 0.150114)
			(end -0.299974 0.150114)
			(stroke
				(width 0.1)
				(type default)
			)
			(layer "F.Fab")
		)
		(pad "1" smd rect
			(at -0.2667 0)
			(size 0.3048 0.381)
			(layers "F.Cu" "F.Mask" "F.Paste")
			(net "P5E_PEX0_STN1_TX_DP<28>")
		)
		(pad "2" smd rect
			(at 0.2667 0)
			(size 0.3048 0.381)
			(layers "F.Cu" "F.Mask" "F.Paste")
			(net "P5E_PEX0_STN1_TX_C_DP<28>")
		)
	)
	(footprint ""
		(layer "F.Cu")
		(at 269.25397 -147.969224 90)
		(property "Reference" "C905"
			(at 0 0 90)
			(layer "F.SilkS")
			(hide yes)
			(effects
				(font
					(size 1.27 1.27)
				)
			)
		)
		(property "Value" ""
			(at 0 0 90)
			(layer "F.Fab")
			(effects
				(font
					(size 1.27 1.27)
				)
			)
		)
		(duplicate_pad_numbers_are_jumpers no)
		(fp_line
			(start 1.524 -0.762)
			(end 1.524 0.762)
			(stroke
				(width 0.1524)
				(type default)
			)
			(layer "F.SilkS")
		)
		(fp_line
			(start -1.524 -0.762)
			(end 1.524 -0.762)
			(stroke
				(width 0.1524)
				(type default)
			)
			(layer "F.SilkS")
		)
		(fp_line
			(start 1.524 0.762)
			(end -1.524 0.762)
			(stroke
				(width 0.1524)
				(type default)
			)
			(layer "F.SilkS")
		)
		(fp_line
			(start -1.524 0.762)
			(end -1.524 -0.762)
			(stroke
				(width 0.1524)
				(type default)
			)
			(layer "F.SilkS")
		)
		(fp_line
			(start 1.1049 -0.724916)
			(end -1.1049 -0.724916)
			(stroke
				(width 0.1)
				(type default)
			)
			(layer "F.Fab")
		)
		(fp_line
			(start -1.1049 -0.724916)
			(end -1.1049 0.724916)
			(stroke
				(width 0.1)
				(type default)
			)
			(layer "F.Fab")
		)
		(fp_line
			(start 1.1049 0.724916)
			(end 1.1049 -0.724916)
			(stroke
				(width 0.1)
				(type default)
			)
			(layer "F.Fab")
		)
		(fp_line
			(start -1.1049 0.724916)
			(end 1.1049 0.724916)
			(stroke
				(width 0.1)
				(type default)
			)
			(layer "F.Fab")
		)
		(pad "1" smd rect
			(at -0.889 0 270)
			(size 1.016 1.27)
			(layers "F.Cu" "F.Mask" "F.Paste")
			(net "P12V_NIC4")
		)
		(pad "2" smd rect
			(at 0.889 0 270)
			(size 1.016 1.27)
			(layers "F.Cu" "F.Mask" "F.Paste")
			(net "GND")
		)
	)
	(footprint ""
		(layer "F.Cu")
		(at 323.917818 -224.659698 180)
		(property "Reference" "R2979"
			(at 0 0 180)
			(layer "F.SilkS")
			(hide yes)
			(effects
				(font
					(size 1.27 1.27)
				)
			)
		)
		(property "Value" ""
			(at 0 0 180)
			(layer "F.Fab")
			(effects
				(font
					(size 1.27 1.27)
				)
			)
		)
		(duplicate_pad_numbers_are_jumpers no)
		(fp_line
			(start 0.7874 0.4064)
			(end -0.7874 0.4064)
			(stroke
				(width 0.1524)
				(type default)
			)
			(layer "F.SilkS")
		)
		(fp_line
			(start 0.7874 -0.4064)
			(end 0.7874 0.4064)
			(stroke
				(width 0.1524)
				(type default)
			)
			(layer "F.SilkS")
		)
		(fp_line
			(start -0.7874 0.4064)
			(end -0.7874 -0.4064)
			(stroke
				(width 0.1524)
				(type default)
			)
			(layer "F.SilkS")
		)
		(fp_line
			(start -0.7874 -0.4064)
			(end 0.7874 -0.4064)
			(stroke
				(width 0.1524)
				(type default)
			)
			(layer "F.SilkS")
		)
		(fp_line
			(start 0.67945 0.3048)
			(end 0.120396 0.3048)
			(stroke
				(width 0.1)
				(type default)
			)
			(layer "F.Fab")
		)
		(fp_line
			(start 0.67945 -0.3048)
			(end 0.67945 0.3048)
			(stroke
				(width 0.1)
				(type default)
			)
			(layer "F.Fab")
		)
		(fp_line
			(start 0.12065 -0.2794)
			(end 0.12065 -0.3048)
			(stroke
				(width 0.1)
				(type default)
			)
			(layer "F.Fab")
		)
		(fp_line
			(start 0.12065 -0.3048)
			(end 0.67945 -0.3048)
			(stroke
				(width 0.1)
				(type default)
			)
			(layer "F.Fab")
		)
		(fp_line
			(start 0.120396 0.3048)
			(end 0.120396 0.2794)
			(stroke
				(width 0.1)
				(type default)
			)
			(layer "F.Fab")
		)
		(fp_line
			(start 0.120396 0.2794)
			(end -0.12065 0.2794)
			(stroke
				(width 0.1)
				(type default)
			)
			(layer "F.Fab")
		)
		(fp_line
			(start -0.12065 0.3048)
			(end -0.67945 0.3048)
			(stroke
				(width 0.1)
				(type default)
			)
			(layer "F.Fab")
		)
		(fp_line
			(start -0.12065 0.2794)
			(end -0.12065 0.3048)
			(stroke
				(width 0.1)
				(type default)
			)
			(layer "F.Fab")
		)
		(fp_line
			(start -0.12065 -0.2794)
			(end 0.12065 -0.2794)
			(stroke
				(width 0.1)
				(type default)
			)
			(layer "F.Fab")
		)
		(fp_line
			(start -0.12065 -0.305054)
			(end -0.12065 -0.2794)
			(stroke
				(width 0.1)
				(type default)
			)
			(layer "F.Fab")
		)
		(fp_line
			(start -0.67945 0.3048)
			(end -0.67945 -0.305054)
			(stroke
				(width 0.1)
				(type default)
			)
			(layer "F.Fab")
		)
		(fp_line
			(start -0.67945 -0.305054)
			(end -0.12065 -0.305054)
			(stroke
				(width 0.1)
				(type default)
			)
			(layer "F.Fab")
		)
		(pad "1" smd circle
			(at -0.40005 0 180)
			(size 0 0)
			(layers "F.Cu" "F.Mask" "F.Paste")
			(net "LED_POSTCODE_1")
		)
		(pad "2" smd circle
			(at 0.40005 0 180)
			(size 0 0)
			(layers "F.Cu" "F.Mask" "F.Paste")
			(net "LED_POSTCODE_R_1")
		)
	)
	(footprint ""
		(layer "F.Cu")
		(at 56.373776 -27.006296 -90)
		(property "Reference" "PC684"
			(at 0 0 270)
			(layer "F.SilkS")
			(hide yes)
			(effects
				(font
					(size 1.27 1.27)
				)
			)
		)
		(property "Value" ""
			(at 0 0 270)
			(layer "F.Fab")
			(effects
				(font
					(size 1.27 1.27)
				)
			)
		)
		(duplicate_pad_numbers_are_jumpers no)
		(fp_line
			(start -0.7874 0.4064)
			(end -0.7874 -0.4064)
			(stroke
				(width 0.1524)
				(type default)
			)
			(layer "F.SilkS")
		)
		(fp_line
			(start 0.7874 0.4064)
			(end -0.7874 0.4064)
			(stroke
				(width 0.1524)
				(type default)
			)
			(layer "F.SilkS")
		)
		(fp_line
			(start -0.7874 -0.4064)
			(end 0.7874 -0.4064)
			(stroke
				(width 0.1524)
				(type default)
			)
			(layer "F.SilkS")
		)
		(fp_line
			(start 0.7874 -0.4064)
			(end 0.7874 0.4064)
			(stroke
				(width 0.1524)
				(type default)
			)
			(layer "F.SilkS")
		)
		(fp_line
			(start -0.67945 0.3048)
			(end -0.67945 -0.305054)
			(stroke
				(width 0.1)
				(type default)
			)
			(layer "F.Fab")
		)
		(fp_line
			(start -0.12065 0.3048)
			(end -0.67945 0.3048)
			(stroke
				(width 0.1)
				(type default)
			)
			(layer "F.Fab")
		)
		(fp_line
			(start 0.120396 0.3048)
			(end 0.120396 0.2794)
			(stroke
				(width 0.1)
				(type default)
			)
			(layer "F.Fab")
		)
		(fp_line
			(start 0.67945 0.3048)
			(end 0.120396 0.3048)
			(stroke
				(width 0.1)
				(type default)
			)
			(layer "F.Fab")
		)
		(fp_line
			(start -0.12065 0.2794)
			(end -0.12065 0.3048)
			(stroke
				(width 0.1)
				(type default)
			)
			(layer "F.Fab")
		)
		(fp_line
			(start 0.120396 0.2794)
			(end -0.12065 0.2794)
			(stroke
				(width 0.1)
				(type default)
			)
			(layer "F.Fab")
		)
		(fp_line
			(start -0.12065 -0.2794)
			(end 0.12065 -0.2794)
			(stroke
				(width 0.1)
				(type default)
			)
			(layer "F.Fab")
		)
		(fp_line
			(start 0.12065 -0.2794)
			(end 0.12065 -0.3048)
			(stroke
				(width 0.1)
				(type default)
			)
			(layer "F.Fab")
		)
		(fp_line
			(start 0.12065 -0.3048)
			(end 0.67945 -0.3048)
			(stroke
				(width 0.1)
				(type default)
			)
			(layer "F.Fab")
		)
		(fp_line
			(start 0.67945 -0.3048)
			(end 0.67945 0.3048)
			(stroke
				(width 0.1)
				(type default)
			)
			(layer "F.Fab")
		)
		(fp_line
			(start -0.67945 -0.305054)
			(end -0.12065 -0.305054)
			(stroke
				(width 0.1)
				(type default)
			)
			(layer "F.Fab")
		)
		(fp_line
			(start -0.12065 -0.305054)
			(end -0.12065 -0.2794)
			(stroke
				(width 0.1)
				(type default)
			)
			(layer "F.Fab")
		)
		(pad "1" smd circle
			(at -0.40005 0 270)
			(size 0 0)
			(layers "F.Cu" "F.Mask" "F.Paste")
			(net "P3V3_SSD2_CO_MODE")
		)
		(pad "2" smd circle
			(at 0.40005 0 270)
			(size 0 0)
			(layers "F.Cu" "F.Mask" "F.Paste")
			(net "GND")
		)
	)
	(footprint ""
		(layer "F.Cu")
		(at 115.600226 -119.077486)
		(property "Reference" "R5824"
			(at 0 0 0)
			(layer "F.SilkS")
			(hide yes)
			(effects
				(font
					(size 1.27 1.27)
				)
			)
		)
		(property "Value" ""
			(at 0 0 0)
			(layer "F.Fab")
			(effects
				(font
					(size 1.27 1.27)
				)
			)
		)
		(duplicate_pad_numbers_are_jumpers no)
		(fp_line
			(start -0.7874 -0.4064)
			(end 0.7874 -0.4064)
			(stroke
				(width 0.1524)
				(type default)
			)
			(layer "F.SilkS")
		)
		(fp_line
			(start -0.7874 0.4064)
			(end -0.7874 -0.4064)
			(stroke
				(width 0.1524)
				(type default)
			)
			(layer "F.SilkS")
		)
		(fp_line
			(start 0.7874 -0.4064)
			(end 0.7874 0.4064)
			(stroke
				(width 0.1524)
				(type default)
			)
			(layer "F.SilkS")
		)
		(fp_line
			(start 0.7874 0.4064)
			(end -0.7874 0.4064)
			(stroke
				(width 0.1524)
				(type default)
			)
			(layer "F.SilkS")
		)
		(fp_line
			(start -0.67945 -0.305054)
			(end -0.12065 -0.305054)
			(stroke
				(width 0.1)
				(type default)
			)
			(layer "F.Fab")
		)
		(fp_line
			(start -0.67945 0.3048)
			(end -0.67945 -0.305054)
			(stroke
				(width 0.1)
				(type default)
			)
			(layer "F.Fab")
		)
		(fp_line
			(start -0.12065 -0.305054)
			(end -0.12065 -0.2794)
			(stroke
				(width 0.1)
				(type default)
			)
			(layer "F.Fab")
		)
		(fp_line
			(start -0.12065 -0.2794)
			(end 0.12065 -0.2794)
			(stroke
				(width 0.1)
				(type default)
			)
			(layer "F.Fab")
		)
		(fp_line
			(start -0.12065 0.2794)
			(end -0.12065 0.3048)
			(stroke
				(width 0.1)
				(type default)
			)
			(layer "F.Fab")
		)
		(fp_line
			(start -0.12065 0.3048)
			(end -0.67945 0.3048)
			(stroke
				(width 0.1)
				(type default)
			)
			(layer "F.Fab")
		)
		(fp_line
			(start 0.120396 0.2794)
			(end -0.12065 0.2794)
			(stroke
				(width 0.1)
				(type default)
			)
			(layer "F.Fab")
		)
		(fp_line
			(start 0.120396 0.3048)
			(end 0.120396 0.2794)
			(stroke
				(width 0.1)
				(type default)
			)
			(layer "F.Fab")
		)
		(fp_line
			(start 0.12065 -0.3048)
			(end 0.67945 -0.3048)
			(stroke
				(width 0.1)
				(type default)
			)
			(layer "F.Fab")
		)
		(fp_line
			(start 0.12065 -0.2794)
			(end 0.12065 -0.3048)
			(stroke
				(width 0.1)
				(type default)
			)
			(layer "F.Fab")
		)
		(fp_line
			(start 0.67945 -0.3048)
			(end 0.67945 0.3048)
			(stroke
				(width 0.1)
				(type default)
			)
			(layer "F.Fab")
		)
		(fp_line
			(start 0.67945 0.3048)
			(end 0.120396 0.3048)
			(stroke
				(width 0.1)
				(type default)
			)
			(layer "F.Fab")
		)
		(pad "1" smd circle
			(at -0.40005 0)
			(size 0 0)
			(layers "F.Cu" "F.Mask" "F.Paste")
			(net "PWR_EN_P3V3_R")
		)
		(pad "2" smd circle
			(at 0.40005 0)
			(size 0 0)
			(layers "F.Cu" "F.Mask" "F.Paste")
			(net "P3V3_CO_EN")
		)
	)
	(footprint ""
		(layer "F.Cu")
		(at 193.745104 -413.45485 -90)
		(property "Reference" "U443"
			(at -2.551938 -3.27787 0)
			(unlocked yes)
			(layer "F.SilkS")
			(effects
				(font
					(size 0.7874 0.5842)
					(thickness 0.1524)
				)
			)
		)
		(property "Value" ""
			(at 0 0 270)
			(layer "F.Fab")
			(effects
				(font
					(size 1.27 1.27)
				)
			)
		)
		(duplicate_pad_numbers_are_jumpers no)
		(fp_line
			(start -2.032 1.549908)
			(end -2.032 -1.549908)
			(stroke
				(width 0.1524)
				(type default)
			)
			(layer "F.SilkS")
		)
		(fp_line
			(start 2.032 1.549908)
			(end -2.032 1.549908)
			(stroke
				(width 0.1524)
				(type default)
			)
			(layer "F.SilkS")
		)
		(fp_line
			(start 0 -0.762)
			(end 0.508 -1.549908)
			(stroke
				(width 0.1524)
				(type default)
			)
			(layer "F.SilkS")
		)
		(fp_line
			(start -2.032 -1.549908)
			(end -0.508 -1.549908)
			(stroke
				(width 0.1524)
				(type default)
			)
			(layer "F.SilkS")
		)
		(fp_line
			(start -0.508 -1.549908)
			(end 0 -0.762)
			(stroke
				(width 0.1524)
				(type default)
			)
			(layer "F.SilkS")
		)
		(fp_line
			(start 0.508 -1.549908)
			(end 2.032 -1.549908)
			(stroke
				(width 0.1524)
				(type default)
			)
			(layer "F.SilkS")
		)
		(fp_line
			(start 2.032 -1.549908)
			(end 2.032 1.549908)
			(stroke
				(width 0.1524)
				(type default)
			)
			(layer "F.SilkS")
		)
		(fp_poly
			(pts
				(xy -3.2004 -1.45796) (xy -3.2004 -0.44196) (xy -2.1844 -0.94996)
			)
			(stroke
				(width 0)
				(type default)
			)
			(fill yes)
			(layer "F.SilkS")
		)
		(fp_line
			(start -0.849884 1.549908)
			(end -0.849884 -1.549908)
			(stroke
				(width 0.1)
				(type default)
			)
			(layer "F.Fab")
		)
		(fp_line
			(start 0.849884 1.549908)
			(end -0.849884 1.549908)
			(stroke
				(width 0.1)
				(type default)
			)
			(layer "F.Fab")
		)
		(fp_line
			(start -0.849884 -1.549908)
			(end 0.849884 -1.549908)
			(stroke
				(width 0.1)
				(type default)
			)
			(layer "F.Fab")
		)
		(fp_line
			(start 0.849884 -1.549908)
			(end 0.849884 1.549908)
			(stroke
				(width 0.1)
				(type default)
			)
			(layer "F.Fab")
		)
		(fp_poly
			(pts
				(xy -3.2004 -1.45796) (xy -3.2004 -0.44196) (xy -2.1844 -0.94996)
			)
			(stroke
				(width 0)
				(type default)
			)
			(fill yes)
			(layer "F.Fab")
		)
		(pad "1" smd rect
			(at -1.35001 -0.94996 180)
			(size 0.6096 1.0668)
			(layers "F.Cu" "F.Mask" "F.Paste")
			(net "UV_P2V5_COMP")
		)
		(pad "2" smd rect
			(at -1.35001 0 180)
			(size 0.6096 1.0668)
			(layers "F.Cu" "F.Mask" "F.Paste")
			(net "GND")
		)
		(pad "3" smd rect
			(at -1.35001 0.94996 180)
			(size 0.6096 1.0668)
			(layers "F.Cu" "F.Mask" "F.Paste")
			(net "P12V_AUX_FP_TRIGGER")
		)
		(pad "4" smd rect
			(at 1.35001 0.94996 180)
			(size 0.6096 1.0668)
			(layers "F.Cu" "F.Mask" "F.Paste")
			(net "HSC_UV_R2_N")
		)
		(pad "5" smd rect
			(at 1.35001 -0.94996 180)
			(size 0.6096 1.0668)
			(layers "F.Cu" "F.Mask" "F.Paste")
			(net "P12V_AUX")
		)
	)
	(footprint ""
		(layer "F.Cu")
		(at 452.543672 -47.92091)
		(property "Reference" "R669"
			(at 0 0 0)
			(layer "F.SilkS")
			(hide yes)
			(effects
				(font
					(size 1.27 1.27)
				)
			)
		)
		(property "Value" ""
			(at 0 0 0)
			(layer "F.Fab")
			(effects
				(font
					(size 1.27 1.27)
				)
			)
		)
		(duplicate_pad_numbers_are_jumpers no)
		(fp_line
			(start -0.7874 -0.4064)
			(end 0.7874 -0.4064)
			(stroke
				(width 0.1524)
				(type default)
			)
			(layer "F.SilkS")
		)
		(fp_line
			(start -0.7874 0.4064)
			(end -0.7874 -0.4064)
			(stroke
				(width 0.1524)
				(type default)
			)
			(layer "F.SilkS")
		)
		(fp_line
			(start 0.7874 -0.4064)
			(end 0.7874 0.4064)
			(stroke
				(width 0.1524)
				(type default)
			)
			(layer "F.SilkS")
		)
		(fp_line
			(start 0.7874 0.4064)
			(end -0.7874 0.4064)
			(stroke
				(width 0.1524)
				(type default)
			)
			(layer "F.SilkS")
		)
		(fp_line
			(start -0.67945 -0.305054)
			(end -0.12065 -0.305054)
			(stroke
				(width 0.1)
				(type default)
			)
			(layer "F.Fab")
		)
		(fp_line
			(start -0.67945 0.3048)
			(end -0.67945 -0.305054)
			(stroke
				(width 0.1)
				(type default)
			)
			(layer "F.Fab")
		)
		(fp_line
			(start -0.12065 -0.305054)
			(end -0.12065 -0.2794)
			(stroke
				(width 0.1)
				(type default)
			)
			(layer "F.Fab")
		)
		(fp_line
			(start -0.12065 -0.2794)
			(end 0.12065 -0.2794)
			(stroke
				(width 0.1)
				(type default)
			)
			(layer "F.Fab")
		)
		(fp_line
			(start -0.12065 0.2794)
			(end -0.12065 0.3048)
			(stroke
				(width 0.1)
				(type default)
			)
			(layer "F.Fab")
		)
		(fp_line
			(start -0.12065 0.3048)
			(end -0.67945 0.3048)
			(stroke
				(width 0.1)
				(type default)
			)
			(layer "F.Fab")
		)
		(fp_line
			(start 0.120396 0.2794)
			(end -0.12065 0.2794)
			(stroke
				(width 0.1)
				(type default)
			)
			(layer "F.Fab")
		)
		(fp_line
			(start 0.120396 0.3048)
			(end 0.120396 0.2794)
			(stroke
				(width 0.1)
				(type default)
			)
			(layer "F.Fab")
		)
		(fp_line
			(start 0.12065 -0.3048)
			(end 0.67945 -0.3048)
			(stroke
				(width 0.1)
				(type default)
			)
			(layer "F.Fab")
		)
		(fp_line
			(start 0.12065 -0.2794)
			(end 0.12065 -0.3048)
			(stroke
				(width 0.1)
				(type default)
			)
			(layer "F.Fab")
		)
		(fp_line
			(start 0.67945 -0.3048)
			(end 0.67945 0.3048)
			(stroke
				(width 0.1)
				(type default)
			)
			(layer "F.Fab")
		)
		(fp_line
			(start 0.67945 0.3048)
			(end 0.120396 0.3048)
			(stroke
				(width 0.1)
				(type default)
			)
			(layer "F.Fab")
		)
		(pad "1" smd circle
			(at -0.40005 0)
			(size 0 0)
			(layers "F.Cu" "F.Mask" "F.Paste")
			(net "P3V3_AUX")
		)
		(pad "2" smd circle
			(at 0.40005 0)
			(size 0 0)
			(layers "F.Cu" "F.Mask" "F.Paste")
			(net "SSD_8_15_ADC_ALERT_N")
		)
	)
	(footprint ""
		(layer "F.Cu")
		(at 224.722944 -98.36912 -90)
		(property "Reference" "PR205"
			(at 0 0 270)
			(layer "F.SilkS")
			(hide yes)
			(effects
				(font
					(size 1.27 1.27)
				)
			)
		)
		(property "Value" ""
			(at 0 0 270)
			(layer "F.Fab")
			(effects
				(font
					(size 1.27 1.27)
				)
			)
		)
		(duplicate_pad_numbers_are_jumpers no)
		(fp_line
			(start -0.7874 0.4064)
			(end -0.7874 -0.4064)
			(stroke
				(width 0.1524)
				(type default)
			)
			(layer "F.SilkS")
		)
		(fp_line
			(start 0.7874 0.4064)
			(end -0.7874 0.4064)
			(stroke
				(width 0.1524)
				(type default)
			)
			(layer "F.SilkS")
		)
		(fp_line
			(start -0.7874 -0.4064)
			(end 0.7874 -0.4064)
			(stroke
				(width 0.1524)
				(type default)
			)
			(layer "F.SilkS")
		)
		(fp_line
			(start 0.7874 -0.4064)
			(end 0.7874 0.4064)
			(stroke
				(width 0.1524)
				(type default)
			)
			(layer "F.SilkS")
		)
		(fp_line
			(start -0.67945 0.3048)
			(end -0.67945 -0.305054)
			(stroke
				(width 0.1)
				(type default)
			)
			(layer "F.Fab")
		)
		(fp_line
			(start -0.12065 0.3048)
			(end -0.67945 0.3048)
			(stroke
				(width 0.1)
				(type default)
			)
			(layer "F.Fab")
		)
		(fp_line
			(start 0.120396 0.3048)
			(end 0.120396 0.2794)
			(stroke
				(width 0.1)
				(type default)
			)
			(layer "F.Fab")
		)
		(fp_line
			(start 0.67945 0.3048)
			(end 0.120396 0.3048)
			(stroke
				(width 0.1)
				(type default)
			)
			(layer "F.Fab")
		)
		(fp_line
			(start -0.12065 0.2794)
			(end -0.12065 0.3048)
			(stroke
				(width 0.1)
				(type default)
			)
			(layer "F.Fab")
		)
		(fp_line
			(start 0.120396 0.2794)
			(end -0.12065 0.2794)
			(stroke
				(width 0.1)
				(type default)
			)
			(layer "F.Fab")
		)
		(fp_line
			(start -0.12065 -0.2794)
			(end 0.12065 -0.2794)
			(stroke
				(width 0.1)
				(type default)
			)
			(layer "F.Fab")
		)
		(fp_line
			(start 0.12065 -0.2794)
			(end 0.12065 -0.3048)
			(stroke
				(width 0.1)
				(type default)
			)
			(layer "F.Fab")
		)
		(fp_line
			(start 0.12065 -0.3048)
			(end 0.67945 -0.3048)
			(stroke
				(width 0.1)
				(type default)
			)
			(layer "F.Fab")
		)
		(fp_line
			(start 0.67945 -0.3048)
			(end 0.67945 0.3048)
			(stroke
				(width 0.1)
				(type default)
			)
			(layer "F.Fab")
		)
		(fp_line
			(start -0.67945 -0.305054)
			(end -0.12065 -0.305054)
			(stroke
				(width 0.1)
				(type default)
			)
			(layer "F.Fab")
		)
		(fp_line
			(start -0.12065 -0.305054)
			(end -0.12065 -0.2794)
			(stroke
				(width 0.1)
				(type default)
			)
			(layer "F.Fab")
		)
		(pad "1" smd circle
			(at -0.40005 0 270)
			(size 0 0)
			(layers "F.Cu" "F.Mask" "F.Paste")
			(net "P12V_NIC3_OCP")
		)
		(pad "2" smd circle
			(at 0.40005 0 270)
			(size 0 0)
			(layers "F.Cu" "F.Mask" "F.Paste")
			(net "GND")
		)
	)
	(footprint ""
		(layer "F.Cu")
		(at 146.253454 -294.591232)
		(property "Reference" "L106"
			(at 0 0 0)
			(layer "F.SilkS")
			(hide yes)
			(effects
				(font
					(size 1.27 1.27)
				)
			)
		)
		(property "Value" ""
			(at 0 0 0)
			(layer "F.Fab")
			(effects
				(font
					(size 1.27 1.27)
				)
			)
		)
		(duplicate_pad_numbers_are_jumpers no)
		(fp_line
			(start -1.63576 -0.8128)
			(end -1.63576 0.8128)
			(stroke
				(width 0.1524)
				(type default)
			)
			(layer "F.SilkS")
		)
		(fp_line
			(start -1.63576 -0.8128)
			(end 1.63576 -0.8128)
			(stroke
				(width 0.1524)
				(type default)
			)
			(layer "F.SilkS")
		)
		(fp_line
			(start 1.63576 -0.8128)
			(end 1.63576 0.8128)
			(stroke
				(width 0.1524)
				(type default)
			)
			(layer "F.SilkS")
		)
		(fp_line
			(start 1.63576 0.8128)
			(end -1.63576 0.8128)
			(stroke
				(width 0.1524)
				(type default)
			)
			(layer "F.SilkS")
		)
		(fp_line
			(start -1.56083 -0.738632)
			(end -1.56083 0.7366)
			(stroke
				(width 0.1)
				(type default)
			)
			(layer "F.Fab")
		)
		(fp_line
			(start -1.56083 0.7366)
			(end -1.524 0.7366)
			(stroke
				(width 0.1)
				(type default)
			)
			(layer "F.Fab")
		)
		(fp_line
			(start -1.524 0.7366)
			(end 1.524 0.7366)
			(stroke
				(width 0.1)
				(type default)
			)
			(layer "F.Fab")
		)
		(fp_line
			(start 1.524 0.7366)
			(end 1.560576 0.7366)
			(stroke
				(width 0.1)
				(type default)
			)
			(layer "F.Fab")
		)
		(fp_line
			(start 1.560576 -0.738632)
			(end -1.56083 -0.738632)
			(stroke
				(width 0.1)
				(type default)
			)
			(layer "F.Fab")
		)
		(fp_line
			(start 1.560576 0.7366)
			(end 1.560576 -0.738632)
			(stroke
				(width 0.1)
				(type default)
			)
			(layer "F.Fab")
		)
		(pad "1" smd rect
			(at -0.94996 0 180)
			(size 1.1176 1.3716)
			(layers "F.Cu" "F.Mask" "F.Paste")
			(net "P1V8_PLL0_PEX1")
		)
		(pad "2" smd rect
			(at 0.94996 0 180)
			(size 1.1176 1.3716)
			(layers "F.Cu" "F.Mask" "F.Paste")
			(net "PCEPLL2_VDDA18_PEX1")
		)
	)
	(footprint ""
		(layer "F.Cu")
		(at 92.997782 -296.365168 90)
		(property "Reference" "C2781"
			(at 0 0 90)
			(layer "F.SilkS")
			(hide yes)
			(effects
				(font
					(size 1.27 1.27)
				)
			)
		)
		(property "Value" ""
			(at 0 0 90)
			(layer "F.Fab")
			(effects
				(font
					(size 1.27 1.27)
				)
			)
		)
		(duplicate_pad_numbers_are_jumpers no)
		(fp_line
			(start 0.7874 -0.4064)
			(end 0.7874 0.4064)
			(stroke
				(width 0.1524)
				(type default)
			)
			(layer "F.SilkS")
		)
		(fp_line
			(start -0.7874 -0.4064)
			(end 0.7874 -0.4064)
			(stroke
				(width 0.1524)
				(type default)
			)
			(layer "F.SilkS")
		)
		(fp_line
			(start 0.7874 0.4064)
			(end -0.7874 0.4064)
			(stroke
				(width 0.1524)
				(type default)
			)
			(layer "F.SilkS")
		)
		(fp_line
			(start -0.7874 0.4064)
			(end -0.7874 -0.4064)
			(stroke
				(width 0.1524)
				(type default)
			)
			(layer "F.SilkS")
		)
		(fp_line
			(start -0.12065 -0.305054)
			(end -0.12065 -0.2794)
			(stroke
				(width 0.1)
				(type default)
			)
			(layer "F.Fab")
		)
		(fp_line
			(start -0.67945 -0.305054)
			(end -0.12065 -0.305054)
			(stroke
				(width 0.1)
				(type default)
			)
			(layer "F.Fab")
		)
		(fp_line
			(start 0.67945 -0.3048)
			(end 0.67945 0.3048)
			(stroke
				(width 0.1)
				(type default)
			)
			(layer "F.Fab")
		)
		(fp_line
			(start 0.12065 -0.3048)
			(end 0.67945 -0.3048)
			(stroke
				(width 0.1)
				(type default)
			)
			(layer "F.Fab")
		)
		(fp_line
			(start 0.12065 -0.2794)
			(end 0.12065 -0.3048)
			(stroke
				(width 0.1)
				(type default)
			)
			(layer "F.Fab")
		)
		(fp_line
			(start -0.12065 -0.2794)
			(end 0.12065 -0.2794)
			(stroke
				(width 0.1)
				(type default)
			)
			(layer "F.Fab")
		)
		(fp_line
			(start 0.120396 0.2794)
			(end -0.12065 0.2794)
			(stroke
				(width 0.1)
				(type default)
			)
			(layer "F.Fab")
		)
		(fp_line
			(start -0.12065 0.2794)
			(end -0.12065 0.3048)
			(stroke
				(width 0.1)
				(type default)
			)
			(layer "F.Fab")
		)
		(fp_line
			(start 0.67945 0.3048)
			(end 0.120396 0.3048)
			(stroke
				(width 0.1)
				(type default)
			)
			(layer "F.Fab")
		)
		(fp_line
			(start 0.120396 0.3048)
			(end 0.120396 0.2794)
			(stroke
				(width 0.1)
				(type default)
			)
			(layer "F.Fab")
		)
		(fp_line
			(start -0.12065 0.3048)
			(end -0.67945 0.3048)
			(stroke
				(width 0.1)
				(type default)
			)
			(layer "F.Fab")
		)
		(fp_line
			(start -0.67945 0.3048)
			(end -0.67945 -0.305054)
			(stroke
				(width 0.1)
				(type default)
			)
			(layer "F.Fab")
		)
		(pad "1" smd circle
			(at -0.40005 0 90)
			(size 0 0)
			(layers "F.Cu" "F.Mask" "F.Paste")
			(net "GND")
		)
		(pad "2" smd circle
			(at 0.40005 0 90)
			(size 0 0)
			(layers "F.Cu" "F.Mask" "F.Paste")
			(net "P1V8_PEX")
		)
	)
	(footprint ""
		(layer "F.Cu")
		(at 336.443574 -43.85691)
		(property "Reference" "R630"
			(at 0 0 0)
			(layer "F.SilkS")
			(hide yes)
			(effects
				(font
					(size 1.27 1.27)
				)
			)
		)
		(property "Value" ""
			(at 0 0 0)
			(layer "F.Fab")
			(effects
				(font
					(size 1.27 1.27)
				)
			)
		)
		(duplicate_pad_numbers_are_jumpers no)
		(fp_line
			(start -0.7874 -0.4064)
			(end 0.7874 -0.4064)
			(stroke
				(width 0.1524)
				(type default)
			)
			(layer "F.SilkS")
		)
		(fp_line
			(start -0.7874 0.4064)
			(end -0.7874 -0.4064)
			(stroke
				(width 0.1524)
				(type default)
			)
			(layer "F.SilkS")
		)
		(fp_line
			(start 0.7874 -0.4064)
			(end 0.7874 0.4064)
			(stroke
				(width 0.1524)
				(type default)
			)
			(layer "F.SilkS")
		)
		(fp_line
			(start 0.7874 0.4064)
			(end -0.7874 0.4064)
			(stroke
				(width 0.1524)
				(type default)
			)
			(layer "F.SilkS")
		)
		(fp_line
			(start -0.67945 -0.305054)
			(end -0.12065 -0.305054)
			(stroke
				(width 0.1)
				(type default)
			)
			(layer "F.Fab")
		)
		(fp_line
			(start -0.67945 0.3048)
			(end -0.67945 -0.305054)
			(stroke
				(width 0.1)
				(type default)
			)
			(layer "F.Fab")
		)
		(fp_line
			(start -0.12065 -0.305054)
			(end -0.12065 -0.2794)
			(stroke
				(width 0.1)
				(type default)
			)
			(layer "F.Fab")
		)
		(fp_line
			(start -0.12065 -0.2794)
			(end 0.12065 -0.2794)
			(stroke
				(width 0.1)
				(type default)
			)
			(layer "F.Fab")
		)
		(fp_line
			(start -0.12065 0.2794)
			(end -0.12065 0.3048)
			(stroke
				(width 0.1)
				(type default)
			)
			(layer "F.Fab")
		)
		(fp_line
			(start -0.12065 0.3048)
			(end -0.67945 0.3048)
			(stroke
				(width 0.1)
				(type default)
			)
			(layer "F.Fab")
		)
		(fp_line
			(start 0.120396 0.2794)
			(end -0.12065 0.2794)
			(stroke
				(width 0.1)
				(type default)
			)
			(layer "F.Fab")
		)
		(fp_line
			(start 0.120396 0.3048)
			(end 0.120396 0.2794)
			(stroke
				(width 0.1)
				(type default)
			)
			(layer "F.Fab")
		)
		(fp_line
			(start 0.12065 -0.3048)
			(end 0.67945 -0.3048)
			(stroke
				(width 0.1)
				(type default)
			)
			(layer "F.Fab")
		)
		(fp_line
			(start 0.12065 -0.2794)
			(end 0.12065 -0.3048)
			(stroke
				(width 0.1)
				(type default)
			)
			(layer "F.Fab")
		)
		(fp_line
			(start 0.67945 -0.3048)
			(end 0.67945 0.3048)
			(stroke
				(width 0.1)
				(type default)
			)
			(layer "F.Fab")
		)
		(fp_line
			(start 0.67945 0.3048)
			(end 0.120396 0.3048)
			(stroke
				(width 0.1)
				(type default)
			)
			(layer "F.Fab")
		)
		(pad "1" smd circle
			(at -0.40005 0)
			(size 0 0)
			(layers "F.Cu" "F.Mask" "F.Paste")
			(net "SSD11_ADC_A1")
		)
		(pad "2" smd circle
			(at 0.40005 0)
			(size 0 0)
			(layers "F.Cu" "F.Mask" "F.Paste")
			(net "GND")
		)
	)
	(footprint ""
		(layer "F.Cu")
		(at 195.562474 -22.937216 90)
		(property "Reference" "R1683"
			(at 0 0 90)
			(layer "F.SilkS")
			(hide yes)
			(effects
				(font
					(size 1.27 1.27)
				)
			)
		)
		(property "Value" ""
			(at 0 0 90)
			(layer "F.Fab")
			(effects
				(font
					(size 1.27 1.27)
				)
			)
		)
		(duplicate_pad_numbers_are_jumpers no)
		(fp_line
			(start 0.7874 -0.4064)
			(end 0.7874 0.4064)
			(stroke
				(width 0.1524)
				(type default)
			)
			(layer "F.SilkS")
		)
		(fp_line
			(start -0.7874 -0.4064)
			(end 0.7874 -0.4064)
			(stroke
				(width 0.1524)
				(type default)
			)
			(layer "F.SilkS")
		)
		(fp_line
			(start 0.7874 0.4064)
			(end -0.7874 0.4064)
			(stroke
				(width 0.1524)
				(type default)
			)
			(layer "F.SilkS")
		)
		(fp_line
			(start -0.7874 0.4064)
			(end -0.7874 -0.4064)
			(stroke
				(width 0.1524)
				(type default)
			)
			(layer "F.SilkS")
		)
		(fp_line
			(start -0.12065 -0.305054)
			(end -0.12065 -0.2794)
			(stroke
				(width 0.1)
				(type default)
			)
			(layer "F.Fab")
		)
		(fp_line
			(start -0.67945 -0.305054)
			(end -0.12065 -0.305054)
			(stroke
				(width 0.1)
				(type default)
			)
			(layer "F.Fab")
		)
		(fp_line
			(start 0.67945 -0.3048)
			(end 0.67945 0.3048)
			(stroke
				(width 0.1)
				(type default)
			)
			(layer "F.Fab")
		)
		(fp_line
			(start 0.12065 -0.3048)
			(end 0.67945 -0.3048)
			(stroke
				(width 0.1)
				(type default)
			)
			(layer "F.Fab")
		)
		(fp_line
			(start 0.12065 -0.2794)
			(end 0.12065 -0.3048)
			(stroke
				(width 0.1)
				(type default)
			)
			(layer "F.Fab")
		)
		(fp_line
			(start -0.12065 -0.2794)
			(end 0.12065 -0.2794)
			(stroke
				(width 0.1)
				(type default)
			)
			(layer "F.Fab")
		)
		(fp_line
			(start 0.120396 0.2794)
			(end -0.12065 0.2794)
			(stroke
				(width 0.1)
				(type default)
			)
			(layer "F.Fab")
		)
		(fp_line
			(start -0.12065 0.2794)
			(end -0.12065 0.3048)
			(stroke
				(width 0.1)
				(type default)
			)
			(layer "F.Fab")
		)
		(fp_line
			(start 0.67945 0.3048)
			(end 0.120396 0.3048)
			(stroke
				(width 0.1)
				(type default)
			)
			(layer "F.Fab")
		)
		(fp_line
			(start 0.120396 0.3048)
			(end 0.120396 0.2794)
			(stroke
				(width 0.1)
				(type default)
			)
			(layer "F.Fab")
		)
		(fp_line
			(start -0.12065 0.3048)
			(end -0.67945 0.3048)
			(stroke
				(width 0.1)
				(type default)
			)
			(layer "F.Fab")
		)
		(fp_line
			(start -0.67945 0.3048)
			(end -0.67945 -0.305054)
			(stroke
				(width 0.1)
				(type default)
			)
			(layer "F.Fab")
		)
		(pad "1" smd circle
			(at -0.40005 0 90)
			(size 0 0)
			(layers "F.Cu" "F.Mask" "F.Paste")
			(net "SMB_BIC_I2C9_MUX0_SSD6_R_SDA")
		)
		(pad "2" smd circle
			(at 0.40005 0 90)
			(size 0 0)
			(layers "F.Cu" "F.Mask" "F.Paste")
			(net "SMB_ISO_SSD6_SDA")
		)
	)
	(footprint ""
		(layer "F.Cu")
		(at 322.839334 -293.47287 -90)
		(property "Reference" "U315"
			(at -0.516382 -4.855972 90)
			(unlocked yes)
			(layer "F.SilkS")
			(effects
				(font
					(size 0.7874 0.5842)
					(thickness 0.1524)
				)
			)
		)
		(property "Value" ""
			(at 0 0 270)
			(layer "F.Fab")
			(effects
				(font
					(size 1.27 1.27)
				)
			)
		)
		(duplicate_pad_numbers_are_jumpers no)
		(fp_line
			(start -1.463548 1.549908)
			(end -1.463548 -1.549908)
			(stroke
				(width 0.1524)
				(type default)
			)
			(layer "F.SilkS")
		)
		(fp_line
			(start 1.463548 1.549908)
			(end -1.463548 1.549908)
			(stroke
				(width 0.1524)
				(type default)
			)
			(layer "F.SilkS")
		)
		(fp_line
			(start 0 -0.762)
			(end 0.762 -1.549908)
			(stroke
				(width 0.1524)
				(type default)
			)
			(layer "F.SilkS")
		)
		(fp_line
			(start -1.463548 -1.549908)
			(end -0.787908 -1.549908)
			(stroke
				(width 0.1524)
				(type default)
			)
			(layer "F.SilkS")
		)
		(fp_line
			(start -0.787908 -1.549908)
			(end 0 -0.762)
			(stroke
				(width 0.1524)
				(type default)
			)
			(layer "F.SilkS")
		)
		(fp_line
			(start 0.762 -1.549908)
			(end 1.463548 -1.549908)
			(stroke
				(width 0.1524)
				(type default)
			)
			(layer "F.SilkS")
		)
		(fp_line
			(start 1.463548 -1.549908)
			(end 1.463548 1.549908)
			(stroke
				(width 0.1524)
				(type default)
			)
			(layer "F.SilkS")
		)
		(fp_poly
			(pts
				(xy -3.4798 -1.359916) (xy -2.86004 -1.050036) (xy -3.4798 -0.740156)
			)
			(stroke
				(width 0)
				(type default)
			)
			(fill yes)
			(layer "F.SilkS")
		)
		(fp_line
			(start -1.549908 1.549908)
			(end -1.549908 -1.549908)
			(stroke
				(width 0.1)
				(type default)
			)
			(layer "F.Fab")
		)
		(fp_line
			(start 1.549908 1.549908)
			(end -1.549908 1.549908)
			(stroke
				(width 0.1)
				(type default)
			)
			(layer "F.Fab")
		)
		(fp_line
			(start -1.549908 -1.549908)
			(end 1.549908 -1.549908)
			(stroke
				(width 0.1)
				(type default)
			)
			(layer "F.Fab")
		)
		(fp_line
			(start 1.549908 -1.549908)
			(end 1.549908 1.549908)
			(stroke
				(width 0.1)
				(type default)
			)
			(layer "F.Fab")
		)
		(fp_poly
			(pts
				(xy -3.4798 -1.359916) (xy -2.86004 -1.050036) (xy -3.4798 -0.740156)
			)
			(stroke
				(width 0)
				(type default)
			)
			(fill yes)
			(layer "F.Fab")
		)
		(pad "1" smd rect
			(at -2.175002 -1.050036)
			(size 0.6096 1.1684)
			(layers "F.Cu" "F.Mask" "F.Paste")
			(net "P1V8_PEX")
		)
		(pad "2" smd rect
			(at -2.175002 -0.32512)
			(size 0.4318 1.1684)
			(layers "F.Cu" "F.Mask" "F.Paste")
			(net "I2C_PEX2_HOST_R_SCL")
		)
		(pad "3" smd rect
			(at -2.175002 0.32512)
			(size 0.4318 1.1684)
			(layers "F.Cu" "F.Mask" "F.Paste")
			(net "I2C_PEX2_HOST_R_SDA")
		)
		(pad "4" smd rect
			(at -2.175002 1.050036)
			(size 0.6096 1.1684)
			(layers "F.Cu" "F.Mask" "F.Paste")
			(net "GND")
		)
		(pad "5" smd rect
			(at 2.175002 1.050036)
			(size 0.6096 1.1684)
			(layers "F.Cu" "F.Mask" "F.Paste")
			(net "PWRGD_P1V8_PEX2_R")
		)
		(pad "6" smd rect
			(at 2.175002 0.32512)
			(size 0.4318 1.1684)
			(layers "F.Cu" "F.Mask" "F.Paste")
			(net "SMB_PEX2_HOST_LS_SDA")
		)
		(pad "7" smd rect
			(at 2.175002 -0.32512)
			(size 0.4318 1.1684)
			(layers "F.Cu" "F.Mask" "F.Paste")
			(net "SMB_PEX2_HOST_LS_SCL")
		)
		(pad "8" smd rect
			(at 2.175002 -1.050036)
			(size 0.6096 1.1684)
			(layers "F.Cu" "F.Mask" "F.Paste")
			(net "P3V3_AUX")
		)
	)
	(footprint ""
		(layer "F.Cu")
		(at 383.66954 -256.888234 -90)
		(property "Reference" "R4593"
			(at 0 0 270)
			(layer "F.SilkS")
			(hide yes)
			(effects
				(font
					(size 1.27 1.27)
				)
			)
		)
		(property "Value" ""
			(at 0 0 270)
			(layer "F.Fab")
			(effects
				(font
					(size 1.27 1.27)
				)
			)
		)
		(duplicate_pad_numbers_are_jumpers no)
		(fp_line
			(start -0.7874 0.4064)
			(end -0.7874 -0.4064)
			(stroke
				(width 0.1524)
				(type default)
			)
			(layer "F.SilkS")
		)
		(fp_line
			(start 0.7874 0.4064)
			(end -0.7874 0.4064)
			(stroke
				(width 0.1524)
				(type default)
			)
			(layer "F.SilkS")
		)
		(fp_line
			(start -0.7874 -0.4064)
			(end 0.7874 -0.4064)
			(stroke
				(width 0.1524)
				(type default)
			)
			(layer "F.SilkS")
		)
		(fp_line
			(start 0.7874 -0.4064)
			(end 0.7874 0.4064)
			(stroke
				(width 0.1524)
				(type default)
			)
			(layer "F.SilkS")
		)
		(fp_line
			(start -0.67945 0.3048)
			(end -0.67945 -0.305054)
			(stroke
				(width 0.1)
				(type default)
			)
			(layer "F.Fab")
		)
		(fp_line
			(start -0.12065 0.3048)
			(end -0.67945 0.3048)
			(stroke
				(width 0.1)
				(type default)
			)
			(layer "F.Fab")
		)
		(fp_line
			(start 0.120396 0.3048)
			(end 0.120396 0.2794)
			(stroke
				(width 0.1)
				(type default)
			)
			(layer "F.Fab")
		)
		(fp_line
			(start 0.67945 0.3048)
			(end 0.120396 0.3048)
			(stroke
				(width 0.1)
				(type default)
			)
			(layer "F.Fab")
		)
		(fp_line
			(start -0.12065 0.2794)
			(end -0.12065 0.3048)
			(stroke
				(width 0.1)
				(type default)
			)
			(layer "F.Fab")
		)
		(fp_line
			(start 0.120396 0.2794)
			(end -0.12065 0.2794)
			(stroke
				(width 0.1)
				(type default)
			)
			(layer "F.Fab")
		)
		(fp_line
			(start -0.12065 -0.2794)
			(end 0.12065 -0.2794)
			(stroke
				(width 0.1)
				(type default)
			)
			(layer "F.Fab")
		)
		(fp_line
			(start 0.12065 -0.2794)
			(end 0.12065 -0.3048)
			(stroke
				(width 0.1)
				(type default)
			)
			(layer "F.Fab")
		)
		(fp_line
			(start 0.12065 -0.3048)
			(end 0.67945 -0.3048)
			(stroke
				(width 0.1)
				(type default)
			)
			(layer "F.Fab")
		)
		(fp_line
			(start 0.67945 -0.3048)
			(end 0.67945 0.3048)
			(stroke
				(width 0.1)
				(type default)
			)
			(layer "F.Fab")
		)
		(fp_line
			(start -0.67945 -0.305054)
			(end -0.12065 -0.305054)
			(stroke
				(width 0.1)
				(type default)
			)
			(layer "F.Fab")
		)
		(fp_line
			(start -0.12065 -0.305054)
			(end -0.12065 -0.2794)
			(stroke
				(width 0.1)
				(type default)
			)
			(layer "F.Fab")
		)
		(pad "1" smd circle
			(at -0.40005 0 270)
			(size 0 0)
			(layers "F.Cu" "F.Mask" "F.Paste")
			(net "PCEPLL5_VDDA18_PEX3")
		)
		(pad "2" smd circle
			(at 0.40005 0 270)
			(size 0 0)
			(layers "F.Cu" "F.Mask" "F.Paste")
			(net "PCEPLL5_VDDA18_PEX3_R")
		)
	)
	(footprint ""
		(layer "F.Cu")
		(at 87.819992 -289.230816 -90)
		(property "Reference" "R3878"
			(at 0 0 270)
			(layer "F.SilkS")
			(hide yes)
			(effects
				(font
					(size 1.27 1.27)
				)
			)
		)
		(property "Value" ""
			(at 0 0 270)
			(layer "F.Fab")
			(effects
				(font
					(size 1.27 1.27)
				)
			)
		)
		(duplicate_pad_numbers_are_jumpers no)
		(fp_line
			(start -0.7874 0.4064)
			(end -0.7874 -0.4064)
			(stroke
				(width 0.1524)
				(type default)
			)
			(layer "F.SilkS")
		)
		(fp_line
			(start 0.7874 0.4064)
			(end -0.7874 0.4064)
			(stroke
				(width 0.1524)
				(type default)
			)
			(layer "F.SilkS")
		)
		(fp_line
			(start -0.7874 -0.4064)
			(end 0.7874 -0.4064)
			(stroke
				(width 0.1524)
				(type default)
			)
			(layer "F.SilkS")
		)
		(fp_line
			(start 0.7874 -0.4064)
			(end 0.7874 0.4064)
			(stroke
				(width 0.1524)
				(type default)
			)
			(layer "F.SilkS")
		)
		(fp_line
			(start -0.67945 0.3048)
			(end -0.67945 -0.305054)
			(stroke
				(width 0.1)
				(type default)
			)
			(layer "F.Fab")
		)
		(fp_line
			(start -0.12065 0.3048)
			(end -0.67945 0.3048)
			(stroke
				(width 0.1)
				(type default)
			)
			(layer "F.Fab")
		)
		(fp_line
			(start 0.120396 0.3048)
			(end 0.120396 0.2794)
			(stroke
				(width 0.1)
				(type default)
			)
			(layer "F.Fab")
		)
		(fp_line
			(start 0.67945 0.3048)
			(end 0.120396 0.3048)
			(stroke
				(width 0.1)
				(type default)
			)
			(layer "F.Fab")
		)
		(fp_line
			(start -0.12065 0.2794)
			(end -0.12065 0.3048)
			(stroke
				(width 0.1)
				(type default)
			)
			(layer "F.Fab")
		)
		(fp_line
			(start 0.120396 0.2794)
			(end -0.12065 0.2794)
			(stroke
				(width 0.1)
				(type default)
			)
			(layer "F.Fab")
		)
		(fp_line
			(start -0.12065 -0.2794)
			(end 0.12065 -0.2794)
			(stroke
				(width 0.1)
				(type default)
			)
			(layer "F.Fab")
		)
		(fp_line
			(start 0.12065 -0.2794)
			(end 0.12065 -0.3048)
			(stroke
				(width 0.1)
				(type default)
			)
			(layer "F.Fab")
		)
		(fp_line
			(start 0.12065 -0.3048)
			(end 0.67945 -0.3048)
			(stroke
				(width 0.1)
				(type default)
			)
			(layer "F.Fab")
		)
		(fp_line
			(start 0.67945 -0.3048)
			(end 0.67945 0.3048)
			(stroke
				(width 0.1)
				(type default)
			)
			(layer "F.Fab")
		)
		(fp_line
			(start -0.67945 -0.305054)
			(end -0.12065 -0.305054)
			(stroke
				(width 0.1)
				(type default)
			)
			(layer "F.Fab")
		)
		(fp_line
			(start -0.12065 -0.305054)
			(end -0.12065 -0.2794)
			(stroke
				(width 0.1)
				(type default)
			)
			(layer "F.Fab")
		)
		(pad "1" smd circle
			(at -0.40005 0 270)
			(size 0 0)
			(layers "F.Cu" "F.Mask" "F.Paste")
			(net "SMB_PEX0_HOST_LS_SDA")
		)
		(pad "2" smd circle
			(at 0.40005 0 270)
			(size 0 0)
			(layers "F.Cu" "F.Mask" "F.Paste")
			(net "P3V3_AUX")
		)
	)
	(footprint ""
		(layer "F.Cu")
		(at 225.026474 -136.669272 -90)
		(property "Reference" "R4218"
			(at 0 0 270)
			(layer "F.SilkS")
			(hide yes)
			(effects
				(font
					(size 1.27 1.27)
				)
			)
		)
		(property "Value" ""
			(at 0 0 270)
			(layer "F.Fab")
			(effects
				(font
					(size 1.27 1.27)
				)
			)
		)
		(duplicate_pad_numbers_are_jumpers no)
		(fp_line
			(start -0.7874 0.4064)
			(end -0.7874 -0.4064)
			(stroke
				(width 0.1524)
				(type default)
			)
			(layer "F.SilkS")
		)
		(fp_line
			(start 0.7874 0.4064)
			(end -0.7874 0.4064)
			(stroke
				(width 0.1524)
				(type default)
			)
			(layer "F.SilkS")
		)
		(fp_line
			(start -0.7874 -0.4064)
			(end 0.7874 -0.4064)
			(stroke
				(width 0.1524)
				(type default)
			)
			(layer "F.SilkS")
		)
		(fp_line
			(start 0.7874 -0.4064)
			(end 0.7874 0.4064)
			(stroke
				(width 0.1524)
				(type default)
			)
			(layer "F.SilkS")
		)
		(fp_line
			(start -0.67945 0.3048)
			(end -0.67945 -0.305054)
			(stroke
				(width 0.1)
				(type default)
			)
			(layer "F.Fab")
		)
		(fp_line
			(start -0.12065 0.3048)
			(end -0.67945 0.3048)
			(stroke
				(width 0.1)
				(type default)
			)
			(layer "F.Fab")
		)
		(fp_line
			(start 0.120396 0.3048)
			(end 0.120396 0.2794)
			(stroke
				(width 0.1)
				(type default)
			)
			(layer "F.Fab")
		)
		(fp_line
			(start 0.67945 0.3048)
			(end 0.120396 0.3048)
			(stroke
				(width 0.1)
				(type default)
			)
			(layer "F.Fab")
		)
		(fp_line
			(start -0.12065 0.2794)
			(end -0.12065 0.3048)
			(stroke
				(width 0.1)
				(type default)
			)
			(layer "F.Fab")
		)
		(fp_line
			(start 0.120396 0.2794)
			(end -0.12065 0.2794)
			(stroke
				(width 0.1)
				(type default)
			)
			(layer "F.Fab")
		)
		(fp_line
			(start -0.12065 -0.2794)
			(end 0.12065 -0.2794)
			(stroke
				(width 0.1)
				(type default)
			)
			(layer "F.Fab")
		)
		(fp_line
			(start 0.12065 -0.2794)
			(end 0.12065 -0.3048)
			(stroke
				(width 0.1)
				(type default)
			)
			(layer "F.Fab")
		)
		(fp_line
			(start 0.12065 -0.3048)
			(end 0.67945 -0.3048)
			(stroke
				(width 0.1)
				(type default)
			)
			(layer "F.Fab")
		)
		(fp_line
			(start 0.67945 -0.3048)
			(end 0.67945 0.3048)
			(stroke
				(width 0.1)
				(type default)
			)
			(layer "F.Fab")
		)
		(fp_line
			(start -0.67945 -0.305054)
			(end -0.12065 -0.305054)
			(stroke
				(width 0.1)
				(type default)
			)
			(layer "F.Fab")
		)
		(fp_line
			(start -0.12065 -0.305054)
			(end -0.12065 -0.2794)
			(stroke
				(width 0.1)
				(type default)
			)
			(layer "F.Fab")
		)
		(pad "1" smd circle
			(at -0.40005 0 270)
			(size 0 0)
			(layers "F.Cu" "F.Mask" "F.Paste")
			(net "SMB_CK440_PEX_CLK_SDA")
		)
		(pad "2" smd circle
			(at 0.40005 0 270)
			(size 0 0)
			(layers "F.Cu" "F.Mask" "F.Paste")
			(net "SMB_CLK_ISO_R_SDA")
		)
	)
	(footprint ""
		(layer "F.Cu")
		(at 334.240124 -350.098614 90)
		(property "Reference" "C571"
			(at 0 0 90)
			(layer "F.SilkS")
			(hide yes)
			(effects
				(font
					(size 1.27 1.27)
				)
			)
		)
		(property "Value" ""
			(at 0 0 90)
			(layer "F.Fab")
			(effects
				(font
					(size 1.27 1.27)
				)
			)
		)
		(duplicate_pad_numbers_are_jumpers no)
		(fp_line
			(start 0.299974 -0.150114)
			(end 0.299974 0.150114)
			(stroke
				(width 0.1)
				(type default)
			)
			(layer "F.Fab")
		)
		(fp_line
			(start -0.299974 -0.150114)
			(end 0.299974 -0.150114)
			(stroke
				(width 0.1)
				(type default)
			)
			(layer "F.Fab")
		)
		(fp_line
			(start 0.299974 0.150114)
			(end -0.299974 0.150114)
			(stroke
				(width 0.1)
				(type default)
			)
			(layer "F.Fab")
		)
		(fp_line
			(start -0.299974 0.150114)
			(end -0.299974 -0.150114)
			(stroke
				(width 0.1)
				(type default)
			)
			(layer "F.Fab")
		)
		(pad "1" smd rect
			(at -0.2667 0 90)
			(size 0.3048 0.381)
			(layers "F.Cu" "F.Mask" "F.Paste")
			(net "P5E_PEX2_STN6_TX_DP<101>")
		)
		(pad "2" smd rect
			(at 0.2667 0 90)
			(size 0.3048 0.381)
			(layers "F.Cu" "F.Mask" "F.Paste")
			(net "P5E_PEX2_STN6_TX_C_DP<101>")
		)
	)
	(footprint ""
		(layer "F.Cu")
		(at 296.024554 -158.080202 90)
		(property "Reference" "R2476"
			(at 0 0 90)
			(layer "F.SilkS")
			(hide yes)
			(effects
				(font
					(size 1.27 1.27)
				)
			)
		)
		(property "Value" ""
			(at 0 0 90)
			(layer "F.Fab")
			(effects
				(font
					(size 1.27 1.27)
				)
			)
		)
		(duplicate_pad_numbers_are_jumpers no)
		(fp_line
			(start 0.7874 -0.4064)
			(end 0.7874 0.4064)
			(stroke
				(width 0.1524)
				(type default)
			)
			(layer "F.SilkS")
		)
		(fp_line
			(start -0.7874 -0.4064)
			(end 0.7874 -0.4064)
			(stroke
				(width 0.1524)
				(type default)
			)
			(layer "F.SilkS")
		)
		(fp_line
			(start 0.7874 0.4064)
			(end -0.7874 0.4064)
			(stroke
				(width 0.1524)
				(type default)
			)
			(layer "F.SilkS")
		)
		(fp_line
			(start -0.7874 0.4064)
			(end -0.7874 -0.4064)
			(stroke
				(width 0.1524)
				(type default)
			)
			(layer "F.SilkS")
		)
		(fp_line
			(start -0.12065 -0.305054)
			(end -0.12065 -0.2794)
			(stroke
				(width 0.1)
				(type default)
			)
			(layer "F.Fab")
		)
		(fp_line
			(start -0.67945 -0.305054)
			(end -0.12065 -0.305054)
			(stroke
				(width 0.1)
				(type default)
			)
			(layer "F.Fab")
		)
		(fp_line
			(start 0.67945 -0.3048)
			(end 0.67945 0.3048)
			(stroke
				(width 0.1)
				(type default)
			)
			(layer "F.Fab")
		)
		(fp_line
			(start 0.12065 -0.3048)
			(end 0.67945 -0.3048)
			(stroke
				(width 0.1)
				(type default)
			)
			(layer "F.Fab")
		)
		(fp_line
			(start 0.12065 -0.2794)
			(end 0.12065 -0.3048)
			(stroke
				(width 0.1)
				(type default)
			)
			(layer "F.Fab")
		)
		(fp_line
			(start -0.12065 -0.2794)
			(end 0.12065 -0.2794)
			(stroke
				(width 0.1)
				(type default)
			)
			(layer "F.Fab")
		)
		(fp_line
			(start 0.120396 0.2794)
			(end -0.12065 0.2794)
			(stroke
				(width 0.1)
				(type default)
			)
			(layer "F.Fab")
		)
		(fp_line
			(start -0.12065 0.2794)
			(end -0.12065 0.3048)
			(stroke
				(width 0.1)
				(type default)
			)
			(layer "F.Fab")
		)
		(fp_line
			(start 0.67945 0.3048)
			(end 0.120396 0.3048)
			(stroke
				(width 0.1)
				(type default)
			)
			(layer "F.Fab")
		)
		(fp_line
			(start 0.120396 0.3048)
			(end 0.120396 0.2794)
			(stroke
				(width 0.1)
				(type default)
			)
			(layer "F.Fab")
		)
		(fp_line
			(start -0.12065 0.3048)
			(end -0.67945 0.3048)
			(stroke
				(width 0.1)
				(type default)
			)
			(layer "F.Fab")
		)
		(fp_line
			(start -0.67945 0.3048)
			(end -0.67945 -0.305054)
			(stroke
				(width 0.1)
				(type default)
			)
			(layer "F.Fab")
		)
		(pad "1" smd circle
			(at -0.40005 0 90)
			(size 0 0)
			(layers "F.Cu" "F.Mask" "F.Paste")
			(net "NIC5_PWRBRK_R_N")
		)
		(pad "2" smd circle
			(at 0.40005 0 90)
			(size 0 0)
			(layers "F.Cu" "F.Mask" "F.Paste")
			(net "NIC5_PWRBRK_N")
		)
	)
	(footprint ""
		(layer "F.Cu")
		(at 324.01764 -87.42934 -90)
		(property "Reference" "R6384"
			(at 0 0 270)
			(layer "F.SilkS")
			(hide yes)
			(effects
				(font
					(size 1.27 1.27)
				)
			)
		)
		(property "Value" ""
			(at 0 0 270)
			(layer "F.Fab")
			(effects
				(font
					(size 1.27 1.27)
				)
			)
		)
		(duplicate_pad_numbers_are_jumpers no)
		(fp_line
			(start -0.7874 0.4064)
			(end -0.7874 -0.4064)
			(stroke
				(width 0.1524)
				(type default)
			)
			(layer "F.SilkS")
		)
		(fp_line
			(start 0.7874 0.4064)
			(end -0.7874 0.4064)
			(stroke
				(width 0.1524)
				(type default)
			)
			(layer "F.SilkS")
		)
		(fp_line
			(start -0.7874 -0.4064)
			(end 0.7874 -0.4064)
			(stroke
				(width 0.1524)
				(type default)
			)
			(layer "F.SilkS")
		)
		(fp_line
			(start 0.7874 -0.4064)
			(end 0.7874 0.4064)
			(stroke
				(width 0.1524)
				(type default)
			)
			(layer "F.SilkS")
		)
		(fp_line
			(start -0.67945 0.3048)
			(end -0.67945 -0.305054)
			(stroke
				(width 0.1)
				(type default)
			)
			(layer "F.Fab")
		)
		(fp_line
			(start -0.12065 0.3048)
			(end -0.67945 0.3048)
			(stroke
				(width 0.1)
				(type default)
			)
			(layer "F.Fab")
		)
		(fp_line
			(start 0.120396 0.3048)
			(end 0.120396 0.2794)
			(stroke
				(width 0.1)
				(type default)
			)
			(layer "F.Fab")
		)
		(fp_line
			(start 0.67945 0.3048)
			(end 0.120396 0.3048)
			(stroke
				(width 0.1)
				(type default)
			)
			(layer "F.Fab")
		)
		(fp_line
			(start -0.12065 0.2794)
			(end -0.12065 0.3048)
			(stroke
				(width 0.1)
				(type default)
			)
			(layer "F.Fab")
		)
		(fp_line
			(start 0.120396 0.2794)
			(end -0.12065 0.2794)
			(stroke
				(width 0.1)
				(type default)
			)
			(layer "F.Fab")
		)
		(fp_line
			(start -0.12065 -0.2794)
			(end 0.12065 -0.2794)
			(stroke
				(width 0.1)
				(type default)
			)
			(layer "F.Fab")
		)
		(fp_line
			(start 0.12065 -0.2794)
			(end 0.12065 -0.3048)
			(stroke
				(width 0.1)
				(type default)
			)
			(layer "F.Fab")
		)
		(fp_line
			(start 0.12065 -0.3048)
			(end 0.67945 -0.3048)
			(stroke
				(width 0.1)
				(type default)
			)
			(layer "F.Fab")
		)
		(fp_line
			(start 0.67945 -0.3048)
			(end 0.67945 0.3048)
			(stroke
				(width 0.1)
				(type default)
			)
			(layer "F.Fab")
		)
		(fp_line
			(start -0.67945 -0.305054)
			(end -0.12065 -0.305054)
			(stroke
				(width 0.1)
				(type default)
			)
			(layer "F.Fab")
		)
		(fp_line
			(start -0.12065 -0.305054)
			(end -0.12065 -0.2794)
			(stroke
				(width 0.1)
				(type default)
			)
			(layer "F.Fab")
		)
		(pad "1" smd circle
			(at -0.40005 0 270)
			(size 0 0)
			(layers "F.Cu" "F.Mask" "F.Paste")
			(net "SMB_BMC_9FGL0451E_S3_SCL")
		)
		(pad "2" smd circle
			(at 0.40005 0 270)
			(size 0 0)
			(layers "F.Cu" "F.Mask" "F.Paste")
			(net "SMB_ISO_CB_SCL")
		)
	)
	(footprint ""
		(layer "F.Cu")
		(at 296.766742 -343.952322 90)
		(property "Reference" "C588"
			(at 0 0 90)
			(layer "F.SilkS")
			(hide yes)
			(effects
				(font
					(size 1.27 1.27)
				)
			)
		)
		(property "Value" ""
			(at 0 0 90)
			(layer "F.Fab")
			(effects
				(font
					(size 1.27 1.27)
				)
			)
		)
		(duplicate_pad_numbers_are_jumpers no)
		(fp_line
			(start 0.299974 -0.150114)
			(end 0.299974 0.150114)
			(stroke
				(width 0.1)
				(type default)
			)
			(layer "F.Fab")
		)
		(fp_line
			(start -0.299974 -0.150114)
			(end 0.299974 -0.150114)
			(stroke
				(width 0.1)
				(type default)
			)
			(layer "F.Fab")
		)
		(fp_line
			(start 0.299974 0.150114)
			(end -0.299974 0.150114)
			(stroke
				(width 0.1)
				(type default)
			)
			(layer "F.Fab")
		)
		(fp_line
			(start -0.299974 0.150114)
			(end -0.299974 -0.150114)
			(stroke
				(width 0.1)
				(type default)
			)
			(layer "F.Fab")
		)
		(pad "1" smd rect
			(at -0.2667 0 90)
			(size 0.3048 0.381)
			(layers "F.Cu" "F.Mask" "F.Paste")
			(net "P5E_PEX2_STN7_TX_DN<125>")
		)
		(pad "2" smd rect
			(at 0.2667 0 90)
			(size 0.3048 0.381)
			(layers "F.Cu" "F.Mask" "F.Paste")
			(net "P5E_PEX2_STN7_TX_C_DN<125>")
		)
	)
	(footprint ""
		(layer "F.Cu")
		(at 35.518344 -252.356874 -90)
		(property "Reference" "R1234"
			(at 0 0 270)
			(layer "F.SilkS")
			(hide yes)
			(effects
				(font
					(size 1.27 1.27)
				)
			)
		)
		(property "Value" ""
			(at 0 0 270)
			(layer "F.Fab")
			(effects
				(font
					(size 1.27 1.27)
				)
			)
		)
		(duplicate_pad_numbers_are_jumpers no)
		(fp_line
			(start -0.7874 0.4064)
			(end -0.7874 -0.4064)
			(stroke
				(width 0.1524)
				(type default)
			)
			(layer "F.SilkS")
		)
		(fp_line
			(start 0.7874 0.4064)
			(end -0.7874 0.4064)
			(stroke
				(width 0.1524)
				(type default)
			)
			(layer "F.SilkS")
		)
		(fp_line
			(start -0.7874 -0.4064)
			(end 0.7874 -0.4064)
			(stroke
				(width 0.1524)
				(type default)
			)
			(layer "F.SilkS")
		)
		(fp_line
			(start 0.7874 -0.4064)
			(end 0.7874 0.4064)
			(stroke
				(width 0.1524)
				(type default)
			)
			(layer "F.SilkS")
		)
		(fp_line
			(start -0.67945 0.3048)
			(end -0.67945 -0.305054)
			(stroke
				(width 0.1)
				(type default)
			)
			(layer "F.Fab")
		)
		(fp_line
			(start -0.12065 0.3048)
			(end -0.67945 0.3048)
			(stroke
				(width 0.1)
				(type default)
			)
			(layer "F.Fab")
		)
		(fp_line
			(start 0.120396 0.3048)
			(end 0.120396 0.2794)
			(stroke
				(width 0.1)
				(type default)
			)
			(layer "F.Fab")
		)
		(fp_line
			(start 0.67945 0.3048)
			(end 0.120396 0.3048)
			(stroke
				(width 0.1)
				(type default)
			)
			(layer "F.Fab")
		)
		(fp_line
			(start -0.12065 0.2794)
			(end -0.12065 0.3048)
			(stroke
				(width 0.1)
				(type default)
			)
			(layer "F.Fab")
		)
		(fp_line
			(start 0.120396 0.2794)
			(end -0.12065 0.2794)
			(stroke
				(width 0.1)
				(type default)
			)
			(layer "F.Fab")
		)
		(fp_line
			(start -0.12065 -0.2794)
			(end 0.12065 -0.2794)
			(stroke
				(width 0.1)
				(type default)
			)
			(layer "F.Fab")
		)
		(fp_line
			(start 0.12065 -0.2794)
			(end 0.12065 -0.3048)
			(stroke
				(width 0.1)
				(type default)
			)
			(layer "F.Fab")
		)
		(fp_line
			(start 0.12065 -0.3048)
			(end 0.67945 -0.3048)
			(stroke
				(width 0.1)
				(type default)
			)
			(layer "F.Fab")
		)
		(fp_line
			(start 0.67945 -0.3048)
			(end 0.67945 0.3048)
			(stroke
				(width 0.1)
				(type default)
			)
			(layer "F.Fab")
		)
		(fp_line
			(start -0.67945 -0.305054)
			(end -0.12065 -0.305054)
			(stroke
				(width 0.1)
				(type default)
			)
			(layer "F.Fab")
		)
		(fp_line
			(start -0.12065 -0.305054)
			(end -0.12065 -0.2794)
			(stroke
				(width 0.1)
				(type default)
			)
			(layer "F.Fab")
		)
		(pad "1" smd circle
			(at -0.40005 0 270)
			(size 0 0)
			(layers "F.Cu" "F.Mask" "F.Paste")
			(net "GND")
		)
		(pad "2" smd circle
			(at 0.40005 0 270)
			(size 0 0)
			(layers "F.Cu" "F.Mask" "F.Paste")
			(net "PEX0_MODE_SEL12")
		)
	)
	(footprint ""
		(layer "F.Cu")
		(at 85.320124 -20.72005)
		(property "Reference" "H107"
			(at -1.43637 -2.878836 0)
			(unlocked yes)
			(layer "B.SilkS")
			(effects
				(font
					(size 0.7874 0.5842)
					(thickness 0.1524)
				)
				(justify left mirror)
			)
		)
		(property "Value" ""
			(at 0 0 0)
			(layer "F.Fab")
			(effects
				(font
					(size 1.27 1.27)
				)
			)
		)
		(duplicate_pad_numbers_are_jumpers no)
		(pad "1" thru_hole rect
			(at 0 0)
			(size 4.2164 5.0038)
			(drill 2.0066
				(offset 0.099822 0)
			)
			(layers "*.Cu" "*.Mask")
			(remove_unused_layers no)
			(net "Net_8556")
			(clearance -0.8509)
			(padstack
				(mode front_inner_back)
				(layer "Inner"
					(shape circle)
					(size 4.0132 4.0132)
					(clearance -0.7493)
				)
				(layer "B.Cu"
					(shape circle)
					(size 4.0132 4.0132)
					(clearance -0.7493)
				)
			)
		)
	)
	(footprint ""
		(layer "F.Cu")
		(at 448.163188 -415.621216 90)
		(property "Reference" "R5606"
			(at 0 0 90)
			(layer "F.SilkS")
			(hide yes)
			(effects
				(font
					(size 1.27 1.27)
				)
			)
		)
		(property "Value" ""
			(at 0 0 90)
			(layer "F.Fab")
			(effects
				(font
					(size 1.27 1.27)
				)
			)
		)
		(duplicate_pad_numbers_are_jumpers no)
		(fp_line
			(start 0.7874 -0.4064)
			(end 0.7874 0.4064)
			(stroke
				(width 0.1524)
				(type default)
			)
			(layer "F.SilkS")
		)
		(fp_line
			(start -0.7874 -0.4064)
			(end 0.7874 -0.4064)
			(stroke
				(width 0.1524)
				(type default)
			)
			(layer "F.SilkS")
		)
		(fp_line
			(start 0.7874 0.4064)
			(end -0.7874 0.4064)
			(stroke
				(width 0.1524)
				(type default)
			)
			(layer "F.SilkS")
		)
		(fp_line
			(start -0.7874 0.4064)
			(end -0.7874 -0.4064)
			(stroke
				(width 0.1524)
				(type default)
			)
			(layer "F.SilkS")
		)
		(fp_line
			(start -0.12065 -0.305054)
			(end -0.12065 -0.2794)
			(stroke
				(width 0.1)
				(type default)
			)
			(layer "F.Fab")
		)
		(fp_line
			(start -0.67945 -0.305054)
			(end -0.12065 -0.305054)
			(stroke
				(width 0.1)
				(type default)
			)
			(layer "F.Fab")
		)
		(fp_line
			(start 0.67945 -0.3048)
			(end 0.67945 0.3048)
			(stroke
				(width 0.1)
				(type default)
			)
			(layer "F.Fab")
		)
		(fp_line
			(start 0.12065 -0.3048)
			(end 0.67945 -0.3048)
			(stroke
				(width 0.1)
				(type default)
			)
			(layer "F.Fab")
		)
		(fp_line
			(start 0.12065 -0.2794)
			(end 0.12065 -0.3048)
			(stroke
				(width 0.1)
				(type default)
			)
			(layer "F.Fab")
		)
		(fp_line
			(start -0.12065 -0.2794)
			(end 0.12065 -0.2794)
			(stroke
				(width 0.1)
				(type default)
			)
			(layer "F.Fab")
		)
		(fp_line
			(start 0.120396 0.2794)
			(end -0.12065 0.2794)
			(stroke
				(width 0.1)
				(type default)
			)
			(layer "F.Fab")
		)
		(fp_line
			(start -0.12065 0.2794)
			(end -0.12065 0.3048)
			(stroke
				(width 0.1)
				(type default)
			)
			(layer "F.Fab")
		)
		(fp_line
			(start 0.67945 0.3048)
			(end 0.120396 0.3048)
			(stroke
				(width 0.1)
				(type default)
			)
			(layer "F.Fab")
		)
		(fp_line
			(start 0.120396 0.3048)
			(end 0.120396 0.2794)
			(stroke
				(width 0.1)
				(type default)
			)
			(layer "F.Fab")
		)
		(fp_line
			(start -0.12065 0.3048)
			(end -0.67945 0.3048)
			(stroke
				(width 0.1)
				(type default)
			)
			(layer "F.Fab")
		)
		(fp_line
			(start -0.67945 0.3048)
			(end -0.67945 -0.305054)
			(stroke
				(width 0.1)
				(type default)
			)
			(layer "F.Fab")
		)
		(pad "1" smd circle
			(at -0.40005 0 90)
			(size 0 0)
			(layers "F.Cu" "F.Mask" "F.Paste")
			(net "LM75_1_A1")
		)
		(pad "2" smd circle
			(at 0.40005 0 90)
			(size 0 0)
			(layers "F.Cu" "F.Mask" "F.Paste")
			(net "GND")
		)
	)
	(footprint ""
		(layer "F.Cu")
		(at 105.021126 -303.698402 90)
		(property "Reference" "PC88"
			(at 0 0 90)
			(layer "F.SilkS")
			(hide yes)
			(effects
				(font
					(size 1.27 1.27)
				)
			)
		)
		(property "Value" ""
			(at 0 0 90)
			(layer "F.Fab")
			(effects
				(font
					(size 1.27 1.27)
				)
			)
		)
		(duplicate_pad_numbers_are_jumpers no)
		(fp_line
			(start -4.53898 -2.150618)
			(end -4.539742 2.152142)
			(stroke
				(width 0.1524)
				(type default)
			)
			(layer "F.SilkS")
		)
		(fp_line
			(start -4.69138 -2.150618)
			(end -4.692396 2.161032)
			(stroke
				(width 0.1524)
				(type default)
			)
			(layer "F.SilkS")
		)
		(fp_line
			(start -4.84378 -2.150618)
			(end -4.53898 -2.150618)
			(stroke
				(width 0.1524)
				(type default)
			)
			(layer "F.SilkS")
		)
		(fp_line
			(start -4.84378 -2.150618)
			(end -4.842256 2.163064)
			(stroke
				(width 0.1524)
				(type default)
			)
			(layer "F.SilkS")
		)
		(fp_line
			(start 4.53898 -2.15011)
			(end 4.53898 2.15011)
			(stroke
				(width 0.1524)
				(type default)
			)
			(layer "F.SilkS")
		)
		(fp_line
			(start -4.53898 -2.15011)
			(end 4.53898 -2.15011)
			(stroke
				(width 0.1524)
				(type default)
			)
			(layer "F.SilkS")
		)
		(fp_line
			(start 4.53898 2.15011)
			(end -4.53898 2.15011)
			(stroke
				(width 0.1524)
				(type default)
			)
			(layer "F.SilkS")
		)
		(fp_line
			(start -4.53898 2.15011)
			(end -4.53898 -2.15011)
			(stroke
				(width 0.1524)
				(type default)
			)
			(layer "F.SilkS")
		)
		(fp_line
			(start -4.83108 2.150364)
			(end -4.447794 2.149348)
			(stroke
				(width 0.1524)
				(type default)
			)
			(layer "F.SilkS")
		)
		(fp_line
			(start 3.64998 -2.15011)
			(end 3.64998 2.15011)
			(stroke
				(width 0.1)
				(type default)
			)
			(layer "F.Fab")
		)
		(fp_line
			(start -3.64998 -2.15011)
			(end 3.64998 -2.15011)
			(stroke
				(width 0.1)
				(type default)
			)
			(layer "F.Fab")
		)
		(fp_line
			(start 3.64998 2.15011)
			(end -3.64998 2.15011)
			(stroke
				(width 0.1)
				(type default)
			)
			(layer "F.Fab")
		)
		(fp_line
			(start -3.64998 2.15011)
			(end -3.64998 -2.15011)
			(stroke
				(width 0.1)
				(type default)
			)
			(layer "F.Fab")
		)
		(fp_text user "+"
			(at -5.12191 -3.164078 90)
			(unlocked yes)
			(layer "F.SilkS")
			(effects
				(font
					(size 1.905 1.4224)
					(thickness 0.1524)
				)
				(justify left)
			)
		)
		(fp_text user "-"
			(at 4.685284 -0.437134 90)
			(unlocked yes)
			(layer "F.SilkS")
			(effects
				(font
					(size 1.905 1.4224)
					(thickness 0.1524)
				)
				(justify left)
			)
		)
		(fp_text user "+"
			(at -6.214872 -0.337058 90)
			(unlocked yes)
			(layer "F.Fab")
			(effects
				(font
					(size 1.905 1.4224)
					(thickness 0.1524)
				)
				(justify left)
			)
		)
		(fp_text user "-"
			(at 4.313174 -0.094488 90)
			(unlocked yes)
			(layer "F.Fab")
			(effects
				(font
					(size 1.905 1.4224)
					(thickness 0.1524)
				)
				(justify left)
			)
		)
		(pad "1" smd rect
			(at -3.199892 0 90)
			(size 2.413 2.8194)
			(layers "F.Cu" "F.Mask" "F.Paste")
			(net "P0V8_PEX0")
		)
		(pad "2" smd rect
			(at 3.199892 0 90)
			(size 2.413 2.8194)
			(layers "F.Cu" "F.Mask" "F.Paste")
			(net "GND")
		)
	)
	(footprint ""
		(layer "F.Cu")
		(at 289.856164 -61.487812 180)
		(property "Reference" "R6002"
			(at 0 0 180)
			(layer "F.SilkS")
			(hide yes)
			(effects
				(font
					(size 1.27 1.27)
				)
			)
		)
		(property "Value" ""
			(at 0 0 180)
			(layer "F.Fab")
			(effects
				(font
					(size 1.27 1.27)
				)
			)
		)
		(duplicate_pad_numbers_are_jumpers no)
		(fp_line
			(start 0.7874 0.4064)
			(end -0.7874 0.4064)
			(stroke
				(width 0.1524)
				(type default)
			)
			(layer "F.SilkS")
		)
		(fp_line
			(start 0.7874 -0.4064)
			(end 0.7874 0.4064)
			(stroke
				(width 0.1524)
				(type default)
			)
			(layer "F.SilkS")
		)
		(fp_line
			(start -0.7874 0.4064)
			(end -0.7874 -0.4064)
			(stroke
				(width 0.1524)
				(type default)
			)
			(layer "F.SilkS")
		)
		(fp_line
			(start -0.7874 -0.4064)
			(end 0.7874 -0.4064)
			(stroke
				(width 0.1524)
				(type default)
			)
			(layer "F.SilkS")
		)
		(fp_line
			(start 0.67945 0.3048)
			(end 0.120396 0.3048)
			(stroke
				(width 0.1)
				(type default)
			)
			(layer "F.Fab")
		)
		(fp_line
			(start 0.67945 -0.3048)
			(end 0.67945 0.3048)
			(stroke
				(width 0.1)
				(type default)
			)
			(layer "F.Fab")
		)
		(fp_line
			(start 0.12065 -0.2794)
			(end 0.12065 -0.3048)
			(stroke
				(width 0.1)
				(type default)
			)
			(layer "F.Fab")
		)
		(fp_line
			(start 0.12065 -0.3048)
			(end 0.67945 -0.3048)
			(stroke
				(width 0.1)
				(type default)
			)
			(layer "F.Fab")
		)
		(fp_line
			(start 0.120396 0.3048)
			(end 0.120396 0.2794)
			(stroke
				(width 0.1)
				(type default)
			)
			(layer "F.Fab")
		)
		(fp_line
			(start 0.120396 0.2794)
			(end -0.12065 0.2794)
			(stroke
				(width 0.1)
				(type default)
			)
			(layer "F.Fab")
		)
		(fp_line
			(start -0.12065 0.3048)
			(end -0.67945 0.3048)
			(stroke
				(width 0.1)
				(type default)
			)
			(layer "F.Fab")
		)
		(fp_line
			(start -0.12065 0.2794)
			(end -0.12065 0.3048)
			(stroke
				(width 0.1)
				(type default)
			)
			(layer "F.Fab")
		)
		(fp_line
			(start -0.12065 -0.2794)
			(end 0.12065 -0.2794)
			(stroke
				(width 0.1)
				(type default)
			)
			(layer "F.Fab")
		)
		(fp_line
			(start -0.12065 -0.305054)
			(end -0.12065 -0.2794)
			(stroke
				(width 0.1)
				(type default)
			)
			(layer "F.Fab")
		)
		(fp_line
			(start -0.67945 0.3048)
			(end -0.67945 -0.305054)
			(stroke
				(width 0.1)
				(type default)
			)
			(layer "F.Fab")
		)
		(fp_line
			(start -0.67945 -0.305054)
			(end -0.12065 -0.305054)
			(stroke
				(width 0.1)
				(type default)
			)
			(layer "F.Fab")
		)
		(pad "1" smd circle
			(at -0.40005 0 180)
			(size 0 0)
			(layers "F.Cu" "F.Mask" "F.Paste")
			(net "P3V3_AUX")
		)
		(pad "2" smd circle
			(at 0.40005 0 180)
			(size 0 0)
			(layers "F.Cu" "F.Mask" "F.Paste")
			(net "PWRGD_P12V_SSD10_D")
		)
	)
	(footprint ""
		(layer "F.Cu")
		(at 72.7202 -229.289356 90)
		(property "Reference" "R6638"
			(at 0 0 90)
			(layer "F.SilkS")
			(hide yes)
			(effects
				(font
					(size 1.27 1.27)
				)
			)
		)
		(property "Value" ""
			(at 0 0 90)
			(layer "F.Fab")
			(effects
				(font
					(size 1.27 1.27)
				)
			)
		)
		(duplicate_pad_numbers_are_jumpers no)
		(fp_line
			(start 0.7874 -0.4064)
			(end 0.7874 0.4064)
			(stroke
				(width 0.1524)
				(type default)
			)
			(layer "F.SilkS")
		)
		(fp_line
			(start -0.7874 -0.4064)
			(end 0.7874 -0.4064)
			(stroke
				(width 0.1524)
				(type default)
			)
			(layer "F.SilkS")
		)
		(fp_line
			(start 0.7874 0.4064)
			(end -0.7874 0.4064)
			(stroke
				(width 0.1524)
				(type default)
			)
			(layer "F.SilkS")
		)
		(fp_line
			(start -0.7874 0.4064)
			(end -0.7874 -0.4064)
			(stroke
				(width 0.1524)
				(type default)
			)
			(layer "F.SilkS")
		)
		(fp_line
			(start -0.12065 -0.305054)
			(end -0.12065 -0.2794)
			(stroke
				(width 0.1)
				(type default)
			)
			(layer "F.Fab")
		)
		(fp_line
			(start -0.67945 -0.305054)
			(end -0.12065 -0.305054)
			(stroke
				(width 0.1)
				(type default)
			)
			(layer "F.Fab")
		)
		(fp_line
			(start 0.67945 -0.3048)
			(end 0.67945 0.3048)
			(stroke
				(width 0.1)
				(type default)
			)
			(layer "F.Fab")
		)
		(fp_line
			(start 0.12065 -0.3048)
			(end 0.67945 -0.3048)
			(stroke
				(width 0.1)
				(type default)
			)
			(layer "F.Fab")
		)
		(fp_line
			(start 0.12065 -0.2794)
			(end 0.12065 -0.3048)
			(stroke
				(width 0.1)
				(type default)
			)
			(layer "F.Fab")
		)
		(fp_line
			(start -0.12065 -0.2794)
			(end 0.12065 -0.2794)
			(stroke
				(width 0.1)
				(type default)
			)
			(layer "F.Fab")
		)
		(fp_line
			(start 0.120396 0.2794)
			(end -0.12065 0.2794)
			(stroke
				(width 0.1)
				(type default)
			)
			(layer "F.Fab")
		)
		(fp_line
			(start -0.12065 0.2794)
			(end -0.12065 0.3048)
			(stroke
				(width 0.1)
				(type default)
			)
			(layer "F.Fab")
		)
		(fp_line
			(start 0.67945 0.3048)
			(end 0.120396 0.3048)
			(stroke
				(width 0.1)
				(type default)
			)
			(layer "F.Fab")
		)
		(fp_line
			(start 0.120396 0.3048)
			(end 0.120396 0.2794)
			(stroke
				(width 0.1)
				(type default)
			)
			(layer "F.Fab")
		)
		(fp_line
			(start -0.12065 0.3048)
			(end -0.67945 0.3048)
			(stroke
				(width 0.1)
				(type default)
			)
			(layer "F.Fab")
		)
		(fp_line
			(start -0.67945 0.3048)
			(end -0.67945 -0.305054)
			(stroke
				(width 0.1)
				(type default)
			)
			(layer "F.Fab")
		)
		(pad "1" smd circle
			(at -0.40005 0 90)
			(size 0 0)
			(layers "F.Cu" "F.Mask" "F.Paste")
			(net "UART_PEX1_CLI_BUF_R_TX")
		)
		(pad "2" smd circle
			(at 0.40005 0 90)
			(size 0 0)
			(layers "F.Cu" "F.Mask" "F.Paste")
			(net "UART_PEX1_CLI_BUF_R1_TX")
		)
	)
	(footprint ""
		(layer "F.Cu")
		(at 351.65792 -27.006296 -90)
		(property "Reference" "PR7123"
			(at 0 0 270)
			(layer "F.SilkS")
			(hide yes)
			(effects
				(font
					(size 1.27 1.27)
				)
			)
		)
		(property "Value" ""
			(at 0 0 270)
			(layer "F.Fab")
			(effects
				(font
					(size 1.27 1.27)
				)
			)
		)
		(duplicate_pad_numbers_are_jumpers no)
		(fp_line
			(start -0.7874 0.4064)
			(end -0.7874 -0.4064)
			(stroke
				(width 0.1524)
				(type default)
			)
			(layer "F.SilkS")
		)
		(fp_line
			(start 0.7874 0.4064)
			(end -0.7874 0.4064)
			(stroke
				(width 0.1524)
				(type default)
			)
			(layer "F.SilkS")
		)
		(fp_line
			(start -0.7874 -0.4064)
			(end 0.7874 -0.4064)
			(stroke
				(width 0.1524)
				(type default)
			)
			(layer "F.SilkS")
		)
		(fp_line
			(start 0.7874 -0.4064)
			(end 0.7874 0.4064)
			(stroke
				(width 0.1524)
				(type default)
			)
			(layer "F.SilkS")
		)
		(fp_line
			(start -0.67945 0.3048)
			(end -0.67945 -0.305054)
			(stroke
				(width 0.1)
				(type default)
			)
			(layer "F.Fab")
		)
		(fp_line
			(start -0.12065 0.3048)
			(end -0.67945 0.3048)
			(stroke
				(width 0.1)
				(type default)
			)
			(layer "F.Fab")
		)
		(fp_line
			(start 0.120396 0.3048)
			(end 0.120396 0.2794)
			(stroke
				(width 0.1)
				(type default)
			)
			(layer "F.Fab")
		)
		(fp_line
			(start 0.67945 0.3048)
			(end 0.120396 0.3048)
			(stroke
				(width 0.1)
				(type default)
			)
			(layer "F.Fab")
		)
		(fp_line
			(start -0.12065 0.2794)
			(end -0.12065 0.3048)
			(stroke
				(width 0.1)
				(type default)
			)
			(layer "F.Fab")
		)
		(fp_line
			(start 0.120396 0.2794)
			(end -0.12065 0.2794)
			(stroke
				(width 0.1)
				(type default)
			)
			(layer "F.Fab")
		)
		(fp_line
			(start -0.12065 -0.2794)
			(end 0.12065 -0.2794)
			(stroke
				(width 0.1)
				(type default)
			)
			(layer "F.Fab")
		)
		(fp_line
			(start 0.12065 -0.2794)
			(end 0.12065 -0.3048)
			(stroke
				(width 0.1)
				(type default)
			)
			(layer "F.Fab")
		)
		(fp_line
			(start 0.12065 -0.3048)
			(end 0.67945 -0.3048)
			(stroke
				(width 0.1)
				(type default)
			)
			(layer "F.Fab")
		)
		(fp_line
			(start 0.67945 -0.3048)
			(end 0.67945 0.3048)
			(stroke
				(width 0.1)
				(type default)
			)
			(layer "F.Fab")
		)
		(fp_line
			(start -0.67945 -0.305054)
			(end -0.12065 -0.305054)
			(stroke
				(width 0.1)
				(type default)
			)
			(layer "F.Fab")
		)
		(fp_line
			(start -0.12065 -0.305054)
			(end -0.12065 -0.2794)
			(stroke
				(width 0.1)
				(type default)
			)
			(layer "F.Fab")
		)
		(pad "1" smd circle
			(at -0.40005 0 270)
			(size 0 0)
			(layers "F.Cu" "F.Mask" "F.Paste")
			(net "P3V3_SSD12_CO_MODE")
		)
		(pad "2" smd circle
			(at 0.40005 0 270)
			(size 0 0)
			(layers "F.Cu" "F.Mask" "F.Paste")
			(net "GND")
		)
	)
	(footprint ""
		(layer "F.Cu")
		(at 407.295096 -98.734372)
		(property "Reference" "R358"
			(at 0 0 0)
			(layer "F.SilkS")
			(hide yes)
			(effects
				(font
					(size 1.27 1.27)
				)
			)
		)
		(property "Value" ""
			(at 0 0 0)
			(layer "F.Fab")
			(effects
				(font
					(size 1.27 1.27)
				)
			)
		)
		(duplicate_pad_numbers_are_jumpers no)
		(fp_line
			(start -0.7874 -0.4064)
			(end 0.7874 -0.4064)
			(stroke
				(width 0.1524)
				(type default)
			)
			(layer "F.SilkS")
		)
		(fp_line
			(start -0.7874 0.4064)
			(end -0.7874 -0.4064)
			(stroke
				(width 0.1524)
				(type default)
			)
			(layer "F.SilkS")
		)
		(fp_line
			(start 0.7874 -0.4064)
			(end 0.7874 0.4064)
			(stroke
				(width 0.1524)
				(type default)
			)
			(layer "F.SilkS")
		)
		(fp_line
			(start 0.7874 0.4064)
			(end -0.7874 0.4064)
			(stroke
				(width 0.1524)
				(type default)
			)
			(layer "F.SilkS")
		)
		(fp_line
			(start -0.67945 -0.305054)
			(end -0.12065 -0.305054)
			(stroke
				(width 0.1)
				(type default)
			)
			(layer "F.Fab")
		)
		(fp_line
			(start -0.67945 0.3048)
			(end -0.67945 -0.305054)
			(stroke
				(width 0.1)
				(type default)
			)
			(layer "F.Fab")
		)
		(fp_line
			(start -0.12065 -0.305054)
			(end -0.12065 -0.2794)
			(stroke
				(width 0.1)
				(type default)
			)
			(layer "F.Fab")
		)
		(fp_line
			(start -0.12065 -0.2794)
			(end 0.12065 -0.2794)
			(stroke
				(width 0.1)
				(type default)
			)
			(layer "F.Fab")
		)
		(fp_line
			(start -0.12065 0.2794)
			(end -0.12065 0.3048)
			(stroke
				(width 0.1)
				(type default)
			)
			(layer "F.Fab")
		)
		(fp_line
			(start -0.12065 0.3048)
			(end -0.67945 0.3048)
			(stroke
				(width 0.1)
				(type default)
			)
			(layer "F.Fab")
		)
		(fp_line
			(start 0.120396 0.2794)
			(end -0.12065 0.2794)
			(stroke
				(width 0.1)
				(type default)
			)
			(layer "F.Fab")
		)
		(fp_line
			(start 0.120396 0.3048)
			(end 0.120396 0.2794)
			(stroke
				(width 0.1)
				(type default)
			)
			(layer "F.Fab")
		)
		(fp_line
			(start 0.12065 -0.3048)
			(end 0.67945 -0.3048)
			(stroke
				(width 0.1)
				(type default)
			)
			(layer "F.Fab")
		)
		(fp_line
			(start 0.12065 -0.2794)
			(end 0.12065 -0.3048)
			(stroke
				(width 0.1)
				(type default)
			)
			(layer "F.Fab")
		)
		(fp_line
			(start 0.67945 -0.3048)
			(end 0.67945 0.3048)
			(stroke
				(width 0.1)
				(type default)
			)
			(layer "F.Fab")
		)
		(fp_line
			(start 0.67945 0.3048)
			(end 0.120396 0.3048)
			(stroke
				(width 0.1)
				(type default)
			)
			(layer "F.Fab")
		)
		(pad "1" smd circle
			(at -0.40005 0)
			(size 0 0)
			(layers "F.Cu" "F.Mask" "F.Paste")
			(net "NIC7_RBT_ARB_OUT")
		)
		(pad "2" smd circle
			(at 0.40005 0)
			(size 0 0)
			(layers "F.Cu" "F.Mask" "F.Paste")
			(net "NIC7_RBT_ARB_IN")
		)
	)
	(footprint ""
		(layer "F.Cu")
		(at 254.177292 -77.279754 -90)
		(property "Reference" "R1056"
			(at 0 0 270)
			(layer "F.SilkS")
			(hide yes)
			(effects
				(font
					(size 1.27 1.27)
				)
			)
		)
		(property "Value" ""
			(at 0 0 270)
			(layer "F.Fab")
			(effects
				(font
					(size 1.27 1.27)
				)
			)
		)
		(duplicate_pad_numbers_are_jumpers no)
		(fp_line
			(start -0.7874 0.4064)
			(end -0.7874 -0.4064)
			(stroke
				(width 0.1524)
				(type default)
			)
			(layer "F.SilkS")
		)
		(fp_line
			(start 0.7874 0.4064)
			(end -0.7874 0.4064)
			(stroke
				(width 0.1524)
				(type default)
			)
			(layer "F.SilkS")
		)
		(fp_line
			(start -0.7874 -0.4064)
			(end 0.7874 -0.4064)
			(stroke
				(width 0.1524)
				(type default)
			)
			(layer "F.SilkS")
		)
		(fp_line
			(start 0.7874 -0.4064)
			(end 0.7874 0.4064)
			(stroke
				(width 0.1524)
				(type default)
			)
			(layer "F.SilkS")
		)
		(fp_line
			(start -0.67945 0.3048)
			(end -0.67945 -0.305054)
			(stroke
				(width 0.1)
				(type default)
			)
			(layer "F.Fab")
		)
		(fp_line
			(start -0.12065 0.3048)
			(end -0.67945 0.3048)
			(stroke
				(width 0.1)
				(type default)
			)
			(layer "F.Fab")
		)
		(fp_line
			(start 0.120396 0.3048)
			(end 0.120396 0.2794)
			(stroke
				(width 0.1)
				(type default)
			)
			(layer "F.Fab")
		)
		(fp_line
			(start 0.67945 0.3048)
			(end 0.120396 0.3048)
			(stroke
				(width 0.1)
				(type default)
			)
			(layer "F.Fab")
		)
		(fp_line
			(start -0.12065 0.2794)
			(end -0.12065 0.3048)
			(stroke
				(width 0.1)
				(type default)
			)
			(layer "F.Fab")
		)
		(fp_line
			(start 0.120396 0.2794)
			(end -0.12065 0.2794)
			(stroke
				(width 0.1)
				(type default)
			)
			(layer "F.Fab")
		)
		(fp_line
			(start -0.12065 -0.2794)
			(end 0.12065 -0.2794)
			(stroke
				(width 0.1)
				(type default)
			)
			(layer "F.Fab")
		)
		(fp_line
			(start 0.12065 -0.2794)
			(end 0.12065 -0.3048)
			(stroke
				(width 0.1)
				(type default)
			)
			(layer "F.Fab")
		)
		(fp_line
			(start 0.12065 -0.3048)
			(end 0.67945 -0.3048)
			(stroke
				(width 0.1)
				(type default)
			)
			(layer "F.Fab")
		)
		(fp_line
			(start 0.67945 -0.3048)
			(end 0.67945 0.3048)
			(stroke
				(width 0.1)
				(type default)
			)
			(layer "F.Fab")
		)
		(fp_line
			(start -0.67945 -0.305054)
			(end -0.12065 -0.305054)
			(stroke
				(width 0.1)
				(type default)
			)
			(layer "F.Fab")
		)
		(fp_line
			(start -0.12065 -0.305054)
			(end -0.12065 -0.2794)
			(stroke
				(width 0.1)
				(type default)
			)
			(layer "F.Fab")
		)
		(pad "1" smd circle
			(at -0.40005 0 270)
			(size 0 0)
			(layers "F.Cu" "F.Mask" "F.Paste")
			(net "FM_CLK_CK440_SS_EN")
		)
		(pad "2" smd circle
			(at 0.40005 0 270)
			(size 0 0)
			(layers "F.Cu" "F.Mask" "F.Paste")
			(net "P3V3")
		)
	)
	(footprint ""
		(layer "F.Cu")
		(at 432.418998 -59.574684 90)
		(property "Reference" "PC433"
			(at 0 0 90)
			(layer "F.SilkS")
			(hide yes)
			(effects
				(font
					(size 1.27 1.27)
				)
			)
		)
		(property "Value" ""
			(at 0 0 90)
			(layer "F.Fab")
			(effects
				(font
					(size 1.27 1.27)
				)
			)
		)
		(duplicate_pad_numbers_are_jumpers no)
		(fp_line
			(start 0.7874 -0.4064)
			(end 0.7874 0.4064)
			(stroke
				(width 0.1524)
				(type default)
			)
			(layer "F.SilkS")
		)
		(fp_line
			(start -0.7874 -0.4064)
			(end 0.7874 -0.4064)
			(stroke
				(width 0.1524)
				(type default)
			)
			(layer "F.SilkS")
		)
		(fp_line
			(start 0.7874 0.4064)
			(end -0.7874 0.4064)
			(stroke
				(width 0.1524)
				(type default)
			)
			(layer "F.SilkS")
		)
		(fp_line
			(start -0.7874 0.4064)
			(end -0.7874 -0.4064)
			(stroke
				(width 0.1524)
				(type default)
			)
			(layer "F.SilkS")
		)
		(fp_line
			(start -0.12065 -0.305054)
			(end -0.12065 -0.2794)
			(stroke
				(width 0.1)
				(type default)
			)
			(layer "F.Fab")
		)
		(fp_line
			(start -0.67945 -0.305054)
			(end -0.12065 -0.305054)
			(stroke
				(width 0.1)
				(type default)
			)
			(layer "F.Fab")
		)
		(fp_line
			(start 0.67945 -0.3048)
			(end 0.67945 0.3048)
			(stroke
				(width 0.1)
				(type default)
			)
			(layer "F.Fab")
		)
		(fp_line
			(start 0.12065 -0.3048)
			(end 0.67945 -0.3048)
			(stroke
				(width 0.1)
				(type default)
			)
			(layer "F.Fab")
		)
		(fp_line
			(start 0.12065 -0.2794)
			(end 0.12065 -0.3048)
			(stroke
				(width 0.1)
				(type default)
			)
			(layer "F.Fab")
		)
		(fp_line
			(start -0.12065 -0.2794)
			(end 0.12065 -0.2794)
			(stroke
				(width 0.1)
				(type default)
			)
			(layer "F.Fab")
		)
		(fp_line
			(start 0.120396 0.2794)
			(end -0.12065 0.2794)
			(stroke
				(width 0.1)
				(type default)
			)
			(layer "F.Fab")
		)
		(fp_line
			(start -0.12065 0.2794)
			(end -0.12065 0.3048)
			(stroke
				(width 0.1)
				(type default)
			)
			(layer "F.Fab")
		)
		(fp_line
			(start 0.67945 0.3048)
			(end 0.120396 0.3048)
			(stroke
				(width 0.1)
				(type default)
			)
			(layer "F.Fab")
		)
		(fp_line
			(start 0.120396 0.3048)
			(end 0.120396 0.2794)
			(stroke
				(width 0.1)
				(type default)
			)
			(layer "F.Fab")
		)
		(fp_line
			(start -0.12065 0.3048)
			(end -0.67945 0.3048)
			(stroke
				(width 0.1)
				(type default)
			)
			(layer "F.Fab")
		)
		(fp_line
			(start -0.67945 0.3048)
			(end -0.67945 -0.305054)
			(stroke
				(width 0.1)
				(type default)
			)
			(layer "F.Fab")
		)
		(pad "1" smd circle
			(at -0.40005 0 90)
			(size 0 0)
			(layers "F.Cu" "F.Mask" "F.Paste")
			(net "P5V_AUX")
		)
		(pad "2" smd circle
			(at 0.40005 0 90)
			(size 0 0)
			(layers "F.Cu" "F.Mask" "F.Paste")
			(net "GND")
		)
	)
	(footprint ""
		(layer "F.Cu")
		(at 331.147166 -21.37156)
		(property "Reference" "C3950"
			(at 0 0 0)
			(layer "F.SilkS")
			(hide yes)
			(effects
				(font
					(size 1.27 1.27)
				)
			)
		)
		(property "Value" ""
			(at 0 0 0)
			(layer "F.Fab")
			(effects
				(font
					(size 1.27 1.27)
				)
			)
		)
		(duplicate_pad_numbers_are_jumpers no)
		(fp_line
			(start -0.7874 -0.4064)
			(end 0.7874 -0.4064)
			(stroke
				(width 0.1524)
				(type default)
			)
			(layer "F.SilkS")
		)
		(fp_line
			(start -0.7874 0.4064)
			(end -0.7874 -0.4064)
			(stroke
				(width 0.1524)
				(type default)
			)
			(layer "F.SilkS")
		)
		(fp_line
			(start 0.7874 -0.4064)
			(end 0.7874 0.4064)
			(stroke
				(width 0.1524)
				(type default)
			)
			(layer "F.SilkS")
		)
		(fp_line
			(start 0.7874 0.4064)
			(end -0.7874 0.4064)
			(stroke
				(width 0.1524)
				(type default)
			)
			(layer "F.SilkS")
		)
		(fp_line
			(start -0.67945 -0.305054)
			(end -0.12065 -0.305054)
			(stroke
				(width 0.1)
				(type default)
			)
			(layer "F.Fab")
		)
		(fp_line
			(start -0.67945 0.3048)
			(end -0.67945 -0.305054)
			(stroke
				(width 0.1)
				(type default)
			)
			(layer "F.Fab")
		)
		(fp_line
			(start -0.12065 -0.305054)
			(end -0.12065 -0.2794)
			(stroke
				(width 0.1)
				(type default)
			)
			(layer "F.Fab")
		)
		(fp_line
			(start -0.12065 -0.2794)
			(end 0.12065 -0.2794)
			(stroke
				(width 0.1)
				(type default)
			)
			(layer "F.Fab")
		)
		(fp_line
			(start -0.12065 0.2794)
			(end -0.12065 0.3048)
			(stroke
				(width 0.1)
				(type default)
			)
			(layer "F.Fab")
		)
		(fp_line
			(start -0.12065 0.3048)
			(end -0.67945 0.3048)
			(stroke
				(width 0.1)
				(type default)
			)
			(layer "F.Fab")
		)
		(fp_line
			(start 0.120396 0.2794)
			(end -0.12065 0.2794)
			(stroke
				(width 0.1)
				(type default)
			)
			(layer "F.Fab")
		)
		(fp_line
			(start 0.120396 0.3048)
			(end 0.120396 0.2794)
			(stroke
				(width 0.1)
				(type default)
			)
			(layer "F.Fab")
		)
		(fp_line
			(start 0.12065 -0.3048)
			(end 0.67945 -0.3048)
			(stroke
				(width 0.1)
				(type default)
			)
			(layer "F.Fab")
		)
		(fp_line
			(start 0.12065 -0.2794)
			(end 0.12065 -0.3048)
			(stroke
				(width 0.1)
				(type default)
			)
			(layer "F.Fab")
		)
		(fp_line
			(start 0.67945 -0.3048)
			(end 0.67945 0.3048)
			(stroke
				(width 0.1)
				(type default)
			)
			(layer "F.Fab")
		)
		(fp_line
			(start 0.67945 0.3048)
			(end 0.120396 0.3048)
			(stroke
				(width 0.1)
				(type default)
			)
			(layer "F.Fab")
		)
		(pad "1" smd circle
			(at -0.40005 0)
			(size 0 0)
			(layers "F.Cu" "F.Mask" "F.Paste")
			(net "P12V_SSD11")
		)
		(pad "2" smd circle
			(at 0.40005 0)
			(size 0 0)
			(layers "F.Cu" "F.Mask" "F.Paste")
			(net "GND")
		)
	)
	(footprint ""
		(layer "F.Cu")
		(at 82.661506 -120.476772 180)
		(property "Reference" "C30"
			(at 0 0 180)
			(layer "F.SilkS")
			(hide yes)
			(effects
				(font
					(size 1.27 1.27)
				)
			)
		)
		(property "Value" ""
			(at 0 0 180)
			(layer "F.Fab")
			(effects
				(font
					(size 1.27 1.27)
				)
			)
		)
		(duplicate_pad_numbers_are_jumpers no)
		(fp_line
			(start 0.299974 0.150114)
			(end -0.299974 0.150114)
			(stroke
				(width 0.1)
				(type default)
			)
			(layer "F.Fab")
		)
		(fp_line
			(start 0.299974 -0.150114)
			(end 0.299974 0.150114)
			(stroke
				(width 0.1)
				(type default)
			)
			(layer "F.Fab")
		)
		(fp_line
			(start -0.299974 0.150114)
			(end -0.299974 -0.150114)
			(stroke
				(width 0.1)
				(type default)
			)
			(layer "F.Fab")
		)
		(fp_line
			(start -0.299974 -0.150114)
			(end 0.299974 -0.150114)
			(stroke
				(width 0.1)
				(type default)
			)
			(layer "F.Fab")
		)
		(pad "1" smd rect
			(at -0.2667 0 180)
			(size 0.3048 0.381)
			(layers "F.Cu" "F.Mask" "F.Paste")
			(net "P5E_PEX0_STN0_TX_DN<1>")
		)
		(pad "2" smd rect
			(at 0.2667 0 180)
			(size 0.3048 0.381)
			(layers "F.Cu" "F.Mask" "F.Paste")
			(net "P5E_PEX0_STN0_TX_C_DN<1>")
		)
	)
	(footprint ""
		(layer "F.Cu")
		(at 139.556744 -206.213964 90)
		(property "Reference" "U98"
			(at -5.860034 -6.613144 0)
			(unlocked yes)
			(layer "F.SilkS")
			(effects
				(font
					(size 0.7874 0.5842)
					(thickness 0.1524)
				)
				(justify left)
			)
		)
		(property "Value" ""
			(at 0 0 90)
			(layer "F.Fab")
			(effects
				(font
					(size 1.27 1.27)
				)
			)
		)
		(duplicate_pad_numbers_are_jumpers no)
		(fp_line
			(start 5.050028 -5.050028)
			(end 4.0386 -5.050028)
			(stroke
				(width 0.1524)
				(type default)
			)
			(layer "F.SilkS")
		)
		(fp_line
			(start -4.0386 -5.050028)
			(end -5.050028 -5.050028)
			(stroke
				(width 0.1524)
				(type default)
			)
			(layer "F.SilkS")
		)
		(fp_line
			(start -5.050028 -5.050028)
			(end -5.050028 -4.0386)
			(stroke
				(width 0.1524)
				(type default)
			)
			(layer "F.SilkS")
		)
		(fp_line
			(start 5.050028 -4.0386)
			(end 5.050028 -5.050028)
			(stroke
				(width 0.1524)
				(type default)
			)
			(layer "F.SilkS")
		)
		(fp_line
			(start -5.050028 4.0386)
			(end -5.050028 5.050028)
			(stroke
				(width 0.1524)
				(type default)
			)
			(layer "F.SilkS")
		)
		(fp_line
			(start 5.050028 5.050028)
			(end 5.050028 4.0386)
			(stroke
				(width 0.1524)
				(type default)
			)
			(layer "F.SilkS")
		)
		(fp_line
			(start 4.0386 5.050028)
			(end 5.050028 5.050028)
			(stroke
				(width 0.1524)
				(type default)
			)
			(layer "F.SilkS")
		)
		(fp_line
			(start -5.050028 5.050028)
			(end -4.0386 5.050028)
			(stroke
				(width 0.1524)
				(type default)
			)
			(layer "F.SilkS")
		)
		(fp_poly
			(pts
				(xy -6.706362 -5.238242) (xy -7.424928 -4.519676) (xy -6.347206 -4.16052)
			)
			(stroke
				(width 0)
				(type default)
			)
			(fill yes)
			(layer "F.SilkS")
		)
		(fp_line
			(start 5.050028 -5.050028)
			(end -5.050028 -5.050028)
			(stroke
				(width 0.1)
				(type default)
			)
			(layer "F.Fab")
		)
		(fp_line
			(start -5.050028 -5.050028)
			(end -5.050028 5.050028)
			(stroke
				(width 0.1)
				(type default)
			)
			(layer "F.Fab")
		)
		(fp_line
			(start 5.050028 5.050028)
			(end 5.050028 -5.050028)
			(stroke
				(width 0.1)
				(type default)
			)
			(layer "F.Fab")
		)
		(fp_line
			(start -5.050028 5.050028)
			(end 5.050028 5.050028)
			(stroke
				(width 0.1)
				(type default)
			)
			(layer "F.Fab")
		)
		(fp_poly
			(pts
				(xy -7.62 -4.258056) (xy -7.62 -3.242056) (xy -6.604 -3.750056)
			)
			(stroke
				(width 0)
				(type default)
			)
			(fill yes)
			(layer "F.Fab")
		)
		(pad "1" smd rect
			(at -5.724906 -3.750056)
			(size 0.2794 1.3716)
			(layers "F.Cu" "F.Mask" "F.Paste")
			(net "GND")
		)
		(pad "2" smd rect
			(at -5.724906 -3.24993)
			(size 0.2794 1.3716)
			(layers "F.Cu" "F.Mask" "F.Paste")
			(net "OSC_CLI_IN")
		)
		(pad "3" smd rect
			(at -5.724906 -2.750058)
			(size 0.2794 1.3716)
			(layers "F.Cu" "F.Mask" "F.Paste")
			(net "OSC_CLI_OUT")
		)
		(pad "4" smd rect
			(at -5.724906 -2.249932)
			(size 0.2794 1.3716)
			(layers "F.Cu" "F.Mask" "F.Paste")
			(net "P3V3_CLI_VPHY")
		)
		(pad "5" smd rect
			(at -5.724906 -1.75006)
			(size 0.2794 1.3716)
			(layers "F.Cu" "F.Mask" "F.Paste")
			(net "GND")
		)
		(pad "6" smd rect
			(at -5.724906 -1.249934)
			(size 0.2794 1.3716)
			(layers "F.Cu" "F.Mask" "F.Paste")
			(net "FT4232_CLI_REF")
		)
		(pad "7" smd rect
			(at -5.724906 -0.750062)
			(size 0.2794 1.3716)
			(layers "F.Cu" "F.Mask" "F.Paste")
			(net "USB2_FT4232_CLI_DN")
		)
		(pad "8" smd rect
			(at -5.724906 -0.249936)
			(size 0.2794 1.3716)
			(layers "F.Cu" "F.Mask" "F.Paste")
			(net "USB2_FT4232_CLI_DP")
		)
		(pad "9" smd rect
			(at -5.724906 0.249936)
			(size 0.2794 1.3716)
			(layers "F.Cu" "F.Mask" "F.Paste")
			(net "P3V3_CLI_VPLL")
		)
		(pad "10" smd rect
			(at -5.724906 0.750062)
			(size 0.2794 1.3716)
			(layers "F.Cu" "F.Mask" "F.Paste")
			(net "GND")
		)
		(pad "11" smd rect
			(at -5.724906 1.249934)
			(size 0.2794 1.3716)
			(layers "F.Cu" "F.Mask" "F.Paste")
			(net "GND")
		)
		(pad "12" smd rect
			(at -5.724906 1.75006)
			(size 0.2794 1.3716)
			(layers "F.Cu" "F.Mask" "F.Paste")
			(net "P1V8_CLI_VCORE")
		)
		(pad "13" smd rect
			(at -5.724906 2.249932)
			(size 0.2794 1.3716)
			(layers "F.Cu" "F.Mask" "F.Paste")
			(net "GND")
		)
		(pad "14" smd rect
			(at -5.724906 2.750058)
			(size 0.2794 1.3716)
			(layers "F.Cu" "F.Mask" "F.Paste")
			(net "RST_FT4232_CLI_R_N")
		)
		(pad "15" smd rect
			(at -5.724906 3.24993)
			(size 0.2794 1.3716)
			(layers "F.Cu" "F.Mask" "F.Paste")
			(net "GND")
		)
		(pad "16" smd rect
			(at -5.724906 3.750056)
			(size 0.2794 1.3716)
			(layers "F.Cu" "F.Mask" "F.Paste")
			(net "UART_PEX0_CLI_RX")
		)
		(pad "17" smd rect
			(at -3.750056 5.724906 90)
			(size 0.2794 1.3716)
			(layers "F.Cu" "F.Mask" "F.Paste")
			(net "UART_PEX0_CLI_BUF_TX")
		)
		(pad "18" smd rect
			(at -3.24993 5.724906 90)
			(size 0.2794 1.3716)
			(layers "F.Cu" "F.Mask" "F.Paste")
			(net "Net_8932")
		)
		(pad "19" smd rect
			(at -2.750058 5.724906 90)
			(size 0.2794 1.3716)
			(layers "F.Cu" "F.Mask" "F.Paste")
			(net "Net_8931")
		)
		(pad "20" smd rect
			(at -2.249932 5.724906 90)
			(size 0.2794 1.3716)
			(layers "F.Cu" "F.Mask" "F.Paste")
			(net "P3V3_AUX")
		)
		(pad "21" smd rect
			(at -1.75006 5.724906 90)
			(size 0.2794 1.3716)
			(layers "F.Cu" "F.Mask" "F.Paste")
			(net "Net_8930")
		)
		(pad "22" smd rect
			(at -1.249934 5.724906 90)
			(size 0.2794 1.3716)
			(layers "F.Cu" "F.Mask" "F.Paste")
			(net "Net_8929")
		)
		(pad "23" smd rect
			(at -0.750062 5.724906 90)
			(size 0.2794 1.3716)
			(layers "F.Cu" "F.Mask" "F.Paste")
			(net "Net_8928")
		)
		(pad "24" smd rect
			(at -0.249936 5.724906 90)
			(size 0.2794 1.3716)
			(layers "F.Cu" "F.Mask" "F.Paste")
			(net "Net_8927")
		)
		(pad "25" smd rect
			(at 0.249936 5.724906 90)
			(size 0.2794 1.3716)
			(layers "F.Cu" "F.Mask" "F.Paste")
			(net "GND")
		)
		(pad "26" smd rect
			(at 0.750062 5.724906 90)
			(size 0.2794 1.3716)
			(layers "F.Cu" "F.Mask" "F.Paste")
			(net "UART_PEX1_CLI_RX")
		)
		(pad "27" smd rect
			(at 1.249934 5.724906 90)
			(size 0.2794 1.3716)
			(layers "F.Cu" "F.Mask" "F.Paste")
			(net "UART_PEX1_CLI_BUF_TX")
		)
		(pad "28" smd rect
			(at 1.75006 5.724906 90)
			(size 0.2794 1.3716)
			(layers "F.Cu" "F.Mask" "F.Paste")
			(net "Net_8926")
		)
		(pad "29" smd rect
			(at 2.249932 5.724906 90)
			(size 0.2794 1.3716)
			(layers "F.Cu" "F.Mask" "F.Paste")
			(net "Net_8925")
		)
		(pad "30" smd rect
			(at 2.750058 5.724906 90)
			(size 0.2794 1.3716)
			(layers "F.Cu" "F.Mask" "F.Paste")
			(net "Net_8924")
		)
		(pad "31" smd rect
			(at 3.24993 5.724906 90)
			(size 0.2794 1.3716)
			(layers "F.Cu" "F.Mask" "F.Paste")
			(net "P3V3_AUX")
		)
		(pad "32" smd rect
			(at 3.750056 5.724906 90)
			(size 0.2794 1.3716)
			(layers "F.Cu" "F.Mask" "F.Paste")
			(net "Net_8923")
		)
		(pad "33" smd rect
			(at 5.724906 3.750056)
			(size 0.2794 1.3716)
			(layers "F.Cu" "F.Mask" "F.Paste")
			(net "Net_8922")
		)
		(pad "34" smd rect
			(at 5.724906 3.24993)
			(size 0.2794 1.3716)
			(layers "F.Cu" "F.Mask" "F.Paste")
			(net "Net_8921")
		)
		(pad "35" smd rect
			(at 5.724906 2.750058)
			(size 0.2794 1.3716)
			(layers "F.Cu" "F.Mask" "F.Paste")
			(net "GND")
		)
		(pad "36" smd rect
			(at 5.724906 2.249932)
			(size 0.2794 1.3716)
			(layers "F.Cu" "F.Mask" "F.Paste")
			(net "Net_8907")
		)
		(pad "37" smd rect
			(at 5.724906 1.75006)
			(size 0.2794 1.3716)
			(layers "F.Cu" "F.Mask" "F.Paste")
			(net "P1V8_CLI_VCORE")
		)
		(pad "38" smd rect
			(at 5.724906 1.249934)
			(size 0.2794 1.3716)
			(layers "F.Cu" "F.Mask" "F.Paste")
			(net "UART_PEX2_CLI_RX")
		)
		(pad "39" smd rect
			(at 5.724906 0.750062)
			(size 0.2794 1.3716)
			(layers "F.Cu" "F.Mask" "F.Paste")
			(net "UART_PEX2_CLI_BUF_TX")
		)
		(pad "40" smd rect
			(at 5.724906 0.249936)
			(size 0.2794 1.3716)
			(layers "F.Cu" "F.Mask" "F.Paste")
			(net "Net_8920")
		)
		(pad "41" smd rect
			(at 5.724906 -0.249936)
			(size 0.2794 1.3716)
			(layers "F.Cu" "F.Mask" "F.Paste")
			(net "Net_8919")
		)
		(pad "42" smd rect
			(at 5.724906 -0.750062)
			(size 0.2794 1.3716)
			(layers "F.Cu" "F.Mask" "F.Paste")
			(net "P3V3_AUX")
		)
		(pad "43" smd rect
			(at 5.724906 -1.249934)
			(size 0.2794 1.3716)
			(layers "F.Cu" "F.Mask" "F.Paste")
			(net "Net_8918")
		)
		(pad "44" smd rect
			(at 5.724906 -1.75006)
			(size 0.2794 1.3716)
			(layers "F.Cu" "F.Mask" "F.Paste")
			(net "Net_8917")
		)
		(pad "45" smd rect
			(at 5.724906 -2.249932)
			(size 0.2794 1.3716)
			(layers "F.Cu" "F.Mask" "F.Paste")
			(net "Net_8916")
		)
		(pad "46" smd rect
			(at 5.724906 -2.750058)
			(size 0.2794 1.3716)
			(layers "F.Cu" "F.Mask" "F.Paste")
			(net "Net_8915")
		)
		(pad "47" smd rect
			(at 5.724906 -3.24993)
			(size 0.2794 1.3716)
			(layers "F.Cu" "F.Mask" "F.Paste")
			(net "GND")
		)
		(pad "48" smd rect
			(at 5.724906 -3.750056)
			(size 0.2794 1.3716)
			(layers "F.Cu" "F.Mask" "F.Paste")
			(net "UART_PEX3_CLI_RX")
		)
		(pad "49" smd rect
			(at 3.750056 -5.724906 90)
			(size 0.2794 1.3716)
			(layers "F.Cu" "F.Mask" "F.Paste")
			(net "P1V8_CLI_VCORE")
		)
		(pad "50" smd rect
			(at 3.24993 -5.724906 90)
			(size 0.2794 1.3716)
			(layers "F.Cu" "F.Mask" "F.Paste")
			(net "P3V3_AUX")
		)
		(pad "51" smd rect
			(at 2.750058 -5.724906 90)
			(size 0.2794 1.3716)
			(layers "F.Cu" "F.Mask" "F.Paste")
			(net "GND")
		)
		(pad "52" smd rect
			(at 2.249932 -5.724906 90)
			(size 0.2794 1.3716)
			(layers "F.Cu" "F.Mask" "F.Paste")
			(net "UART_PEX3_CLI_BUF_TX")
		)
		(pad "53" smd rect
			(at 1.75006 -5.724906 90)
			(size 0.2794 1.3716)
			(layers "F.Cu" "F.Mask" "F.Paste")
			(net "Net_8914")
		)
		(pad "54" smd rect
			(at 1.249934 -5.724906 90)
			(size 0.2794 1.3716)
			(layers "F.Cu" "F.Mask" "F.Paste")
			(net "Net_8913")
		)
		(pad "55" smd rect
			(at 0.750062 -5.724906 90)
			(size 0.2794 1.3716)
			(layers "F.Cu" "F.Mask" "F.Paste")
			(net "Net_8912")
		)
		(pad "56" smd rect
			(at 0.249936 -5.724906 90)
			(size 0.2794 1.3716)
			(layers "F.Cu" "F.Mask" "F.Paste")
			(net "P3V3_AUX")
		)
		(pad "57" smd rect
			(at -0.249936 -5.724906 90)
			(size 0.2794 1.3716)
			(layers "F.Cu" "F.Mask" "F.Paste")
			(net "Net_8911")
		)
		(pad "58" smd rect
			(at -0.750062 -5.724906 90)
			(size 0.2794 1.3716)
			(layers "F.Cu" "F.Mask" "F.Paste")
			(net "Net_8910")
		)
		(pad "59" smd rect
			(at -1.249934 -5.724906 90)
			(size 0.2794 1.3716)
			(layers "F.Cu" "F.Mask" "F.Paste")
			(net "Net_8909")
		)
		(pad "60" smd rect
			(at -1.75006 -5.724906 90)
			(size 0.2794 1.3716)
			(layers "F.Cu" "F.Mask" "F.Paste")
			(net "Net_8908")
		)
		(pad "61" smd rect
			(at -2.249932 -5.724906 90)
			(size 0.2794 1.3716)
			(layers "F.Cu" "F.Mask" "F.Paste")
			(net "FT4232_CLI_EEPROM_SDA")
		)
		(pad "62" smd rect
			(at -2.750058 -5.724906 90)
			(size 0.2794 1.3716)
			(layers "F.Cu" "F.Mask" "F.Paste")
			(net "FT4232_CLI_EEPROM_SCL")
		)
		(pad "63" smd rect
			(at -3.24993 -5.724906 90)
			(size 0.2794 1.3716)
			(layers "F.Cu" "F.Mask" "F.Paste")
			(net "FT4232_CLI_EEPROM_CS")
		)
		(pad "64" smd rect
			(at -3.750056 -5.724906 90)
			(size 0.2794 1.3716)
			(layers "F.Cu" "F.Mask" "F.Paste")
			(net "P1V8_CLI_VCORE")
		)
	)
	(footprint ""
		(layer "F.Cu")
		(at 247.401334 -55.78475 -90)
		(property "Reference" "PD111"
			(at 4.07035 2.188464 90)
			(unlocked yes)
			(layer "F.SilkS")
			(effects
				(font
					(size 0.7874 0.5842)
					(thickness 0.1524)
				)
				(justify left)
			)
		)
		(property "Value" ""
			(at 0 0 270)
			(layer "F.Fab")
			(effects
				(font
					(size 1.27 1.27)
				)
			)
		)
		(duplicate_pad_numbers_are_jumpers no)
		(fp_line
			(start -3.400044 1.459992)
			(end -3.400044 -1.459992)
			(stroke
				(width 0.1524)
				(type default)
			)
			(layer "F.SilkS")
		)
		(fp_line
			(start 4.107942 1.459992)
			(end -3.400044 1.459992)
			(stroke
				(width 0.1524)
				(type default)
			)
			(layer "F.SilkS")
		)
		(fp_line
			(start -3.400044 -1.459992)
			(end 4.107942 -1.459992)
			(stroke
				(width 0.1524)
				(type default)
			)
			(layer "F.SilkS")
		)
		(fp_line
			(start 4.107942 -1.459992)
			(end 4.107942 1.459992)
			(stroke
				(width 0.1524)
				(type default)
			)
			(layer "F.SilkS")
		)
		(fp_poly
			(pts
				(xy 4.107942 -1.459992) (xy 4.107942 1.459992) (xy 3.308096 1.459992) (xy 3.308096 -1.459992)
			)
			(stroke
				(width 0)
				(type default)
			)
			(fill yes)
			(layer "F.SilkS")
		)
		(fp_line
			(start -2.29997 1.459992)
			(end -2.29997 -1.459992)
			(stroke
				(width 0.1)
				(type default)
			)
			(layer "F.Fab")
		)
		(fp_line
			(start 2.29997 1.459992)
			(end -2.29997 1.459992)
			(stroke
				(width 0.1)
				(type default)
			)
			(layer "F.Fab")
		)
		(fp_line
			(start -2.29997 -1.459992)
			(end 2.29997 -1.459992)
			(stroke
				(width 0.1)
				(type default)
			)
			(layer "F.Fab")
		)
		(fp_line
			(start 2.29997 -1.459992)
			(end 2.29997 1.459992)
			(stroke
				(width 0.1)
				(type default)
			)
			(layer "F.Fab")
		)
		(fp_text user "-"
			(at 5.4102 0.29845 90)
			(unlocked yes)
			(layer "F.SilkS")
			(effects
				(font
					(size 1.905 1.4224)
					(thickness 0.1524)
				)
				(justify left)
			)
		)
		(fp_text user "+"
			(at -4.7752 -0.12065 270)
			(unlocked yes)
			(layer "F.SilkS")
			(effects
				(font
					(size 1.905 1.4224)
					(thickness 0.1524)
				)
				(justify left)
			)
		)
		(fp_text user "-"
			(at 5.4102 0.29845 90)
			(unlocked yes)
			(layer "F.Fab")
			(effects
				(font
					(size 1.905 1.4224)
					(thickness 0.1524)
				)
				(justify left)
			)
		)
		(fp_text user "+"
			(at -4.7752 -0.12065 270)
			(unlocked yes)
			(layer "F.Fab")
			(effects
				(font
					(size 1.905 1.4224)
					(thickness 0.1524)
				)
				(justify left)
			)
		)
		(pad "A" smd rect
			(at -1.999996 0)
			(size 1.7018 2.5146)
			(layers "F.Cu" "F.Mask" "F.Paste")
			(net "GND")
		)
		(pad "C" smd rect
			(at 1.999996 0)
			(size 1.7018 2.5146)
			(layers "F.Cu" "F.Mask" "F.Paste")
			(net "P12V_SSD8_R")
		)
	)
	(footprint ""
		(layer "F.Cu")
		(at 6.652768 -156.288994 -90)
		(property "Reference" "PR6862"
			(at 0 0 270)
			(layer "F.SilkS")
			(hide yes)
			(effects
				(font
					(size 1.27 1.27)
				)
			)
		)
		(property "Value" ""
			(at 0 0 270)
			(layer "F.Fab")
			(effects
				(font
					(size 1.27 1.27)
				)
			)
		)
		(duplicate_pad_numbers_are_jumpers no)
		(fp_line
			(start -0.7874 0.4064)
			(end -0.7874 -0.4064)
			(stroke
				(width 0.1524)
				(type default)
			)
			(layer "F.SilkS")
		)
		(fp_line
			(start 0.7874 0.4064)
			(end -0.7874 0.4064)
			(stroke
				(width 0.1524)
				(type default)
			)
			(layer "F.SilkS")
		)
		(fp_line
			(start -0.7874 -0.4064)
			(end 0.7874 -0.4064)
			(stroke
				(width 0.1524)
				(type default)
			)
			(layer "F.SilkS")
		)
		(fp_line
			(start 0.7874 -0.4064)
			(end 0.7874 0.4064)
			(stroke
				(width 0.1524)
				(type default)
			)
			(layer "F.SilkS")
		)
		(fp_line
			(start -0.67945 0.3048)
			(end -0.67945 -0.305054)
			(stroke
				(width 0.1)
				(type default)
			)
			(layer "F.Fab")
		)
		(fp_line
			(start -0.12065 0.3048)
			(end -0.67945 0.3048)
			(stroke
				(width 0.1)
				(type default)
			)
			(layer "F.Fab")
		)
		(fp_line
			(start 0.120396 0.3048)
			(end 0.120396 0.2794)
			(stroke
				(width 0.1)
				(type default)
			)
			(layer "F.Fab")
		)
		(fp_line
			(start 0.67945 0.3048)
			(end 0.120396 0.3048)
			(stroke
				(width 0.1)
				(type default)
			)
			(layer "F.Fab")
		)
		(fp_line
			(start -0.12065 0.2794)
			(end -0.12065 0.3048)
			(stroke
				(width 0.1)
				(type default)
			)
			(layer "F.Fab")
		)
		(fp_line
			(start 0.120396 0.2794)
			(end -0.12065 0.2794)
			(stroke
				(width 0.1)
				(type default)
			)
			(layer "F.Fab")
		)
		(fp_line
			(start -0.12065 -0.2794)
			(end 0.12065 -0.2794)
			(stroke
				(width 0.1)
				(type default)
			)
			(layer "F.Fab")
		)
		(fp_line
			(start 0.12065 -0.2794)
			(end 0.12065 -0.3048)
			(stroke
				(width 0.1)
				(type default)
			)
			(layer "F.Fab")
		)
		(fp_line
			(start 0.12065 -0.3048)
			(end 0.67945 -0.3048)
			(stroke
				(width 0.1)
				(type default)
			)
			(layer "F.Fab")
		)
		(fp_line
			(start 0.67945 -0.3048)
			(end 0.67945 0.3048)
			(stroke
				(width 0.1)
				(type default)
			)
			(layer "F.Fab")
		)
		(fp_line
			(start -0.67945 -0.305054)
			(end -0.12065 -0.305054)
			(stroke
				(width 0.1)
				(type default)
			)
			(layer "F.Fab")
		)
		(fp_line
			(start -0.12065 -0.305054)
			(end -0.12065 -0.2794)
			(stroke
				(width 0.1)
				(type default)
			)
			(layer "F.Fab")
		)
		(pad "1" smd circle
			(at -0.40005 0 270)
			(size 0 0)
			(layers "F.Cu" "F.Mask" "F.Paste")
			(net "P12V_NIC0_CO_OV_FB")
		)
		(pad "2" smd circle
			(at 0.40005 0 270)
			(size 0 0)
			(layers "F.Cu" "F.Mask" "F.Paste")
			(net "P12V_NIC0_R")
		)
	)
	(footprint ""
		(layer "F.Cu")
		(at 378.852684 -86.5378)
		(property "Reference" "R1769"
			(at 0 0 0)
			(layer "F.SilkS")
			(hide yes)
			(effects
				(font
					(size 1.27 1.27)
				)
			)
		)
		(property "Value" ""
			(at 0 0 0)
			(layer "F.Fab")
			(effects
				(font
					(size 1.27 1.27)
				)
			)
		)
		(duplicate_pad_numbers_are_jumpers no)
		(fp_line
			(start -0.7874 -0.4064)
			(end 0.7874 -0.4064)
			(stroke
				(width 0.1524)
				(type default)
			)
			(layer "F.SilkS")
		)
		(fp_line
			(start -0.7874 0.4064)
			(end -0.7874 -0.4064)
			(stroke
				(width 0.1524)
				(type default)
			)
			(layer "F.SilkS")
		)
		(fp_line
			(start 0.7874 -0.4064)
			(end 0.7874 0.4064)
			(stroke
				(width 0.1524)
				(type default)
			)
			(layer "F.SilkS")
		)
		(fp_line
			(start 0.7874 0.4064)
			(end -0.7874 0.4064)
			(stroke
				(width 0.1524)
				(type default)
			)
			(layer "F.SilkS")
		)
		(fp_line
			(start -0.67945 -0.305054)
			(end -0.12065 -0.305054)
			(stroke
				(width 0.1)
				(type default)
			)
			(layer "F.Fab")
		)
		(fp_line
			(start -0.67945 0.3048)
			(end -0.67945 -0.305054)
			(stroke
				(width 0.1)
				(type default)
			)
			(layer "F.Fab")
		)
		(fp_line
			(start -0.12065 -0.305054)
			(end -0.12065 -0.2794)
			(stroke
				(width 0.1)
				(type default)
			)
			(layer "F.Fab")
		)
		(fp_line
			(start -0.12065 -0.2794)
			(end 0.12065 -0.2794)
			(stroke
				(width 0.1)
				(type default)
			)
			(layer "F.Fab")
		)
		(fp_line
			(start -0.12065 0.2794)
			(end -0.12065 0.3048)
			(stroke
				(width 0.1)
				(type default)
			)
			(layer "F.Fab")
		)
		(fp_line
			(start -0.12065 0.3048)
			(end -0.67945 0.3048)
			(stroke
				(width 0.1)
				(type default)
			)
			(layer "F.Fab")
		)
		(fp_line
			(start 0.120396 0.2794)
			(end -0.12065 0.2794)
			(stroke
				(width 0.1)
				(type default)
			)
			(layer "F.Fab")
		)
		(fp_line
			(start 0.120396 0.3048)
			(end 0.120396 0.2794)
			(stroke
				(width 0.1)
				(type default)
			)
			(layer "F.Fab")
		)
		(fp_line
			(start 0.12065 -0.3048)
			(end 0.67945 -0.3048)
			(stroke
				(width 0.1)
				(type default)
			)
			(layer "F.Fab")
		)
		(fp_line
			(start 0.12065 -0.2794)
			(end 0.12065 -0.3048)
			(stroke
				(width 0.1)
				(type default)
			)
			(layer "F.Fab")
		)
		(fp_line
			(start 0.67945 -0.3048)
			(end 0.67945 0.3048)
			(stroke
				(width 0.1)
				(type default)
			)
			(layer "F.Fab")
		)
		(fp_line
			(start 0.67945 0.3048)
			(end 0.120396 0.3048)
			(stroke
				(width 0.1)
				(type default)
			)
			(layer "F.Fab")
		)
		(pad "1" smd circle
			(at -0.40005 0)
			(size 0 0)
			(layers "F.Cu" "F.Mask" "F.Paste")
			(net "SMB_BIC_I2C6_MUX_PEX_ADC_R_SDA")
		)
		(pad "2" smd circle
			(at 0.40005 0)
			(size 0 0)
			(layers "F.Cu" "F.Mask" "F.Paste")
			(net "SMB_BIC_I2C6_MUX_PEX_ADC_SDA")
		)
	)
	(footprint ""
		(layer "F.Cu")
		(at 163.047426 -21.37156)
		(property "Reference" "C3909"
			(at 0 0 0)
			(layer "F.SilkS")
			(hide yes)
			(effects
				(font
					(size 1.27 1.27)
				)
			)
		)
		(property "Value" ""
			(at 0 0 0)
			(layer "F.Fab")
			(effects
				(font
					(size 1.27 1.27)
				)
			)
		)
		(duplicate_pad_numbers_are_jumpers no)
		(fp_line
			(start -0.7874 -0.4064)
			(end 0.7874 -0.4064)
			(stroke
				(width 0.1524)
				(type default)
			)
			(layer "F.SilkS")
		)
		(fp_line
			(start -0.7874 0.4064)
			(end -0.7874 -0.4064)
			(stroke
				(width 0.1524)
				(type default)
			)
			(layer "F.SilkS")
		)
		(fp_line
			(start 0.7874 -0.4064)
			(end 0.7874 0.4064)
			(stroke
				(width 0.1524)
				(type default)
			)
			(layer "F.SilkS")
		)
		(fp_line
			(start 0.7874 0.4064)
			(end -0.7874 0.4064)
			(stroke
				(width 0.1524)
				(type default)
			)
			(layer "F.SilkS")
		)
		(fp_line
			(start -0.67945 -0.305054)
			(end -0.12065 -0.305054)
			(stroke
				(width 0.1)
				(type default)
			)
			(layer "F.Fab")
		)
		(fp_line
			(start -0.67945 0.3048)
			(end -0.67945 -0.305054)
			(stroke
				(width 0.1)
				(type default)
			)
			(layer "F.Fab")
		)
		(fp_line
			(start -0.12065 -0.305054)
			(end -0.12065 -0.2794)
			(stroke
				(width 0.1)
				(type default)
			)
			(layer "F.Fab")
		)
		(fp_line
			(start -0.12065 -0.2794)
			(end 0.12065 -0.2794)
			(stroke
				(width 0.1)
				(type default)
			)
			(layer "F.Fab")
		)
		(fp_line
			(start -0.12065 0.2794)
			(end -0.12065 0.3048)
			(stroke
				(width 0.1)
				(type default)
			)
			(layer "F.Fab")
		)
		(fp_line
			(start -0.12065 0.3048)
			(end -0.67945 0.3048)
			(stroke
				(width 0.1)
				(type default)
			)
			(layer "F.Fab")
		)
		(fp_line
			(start 0.120396 0.2794)
			(end -0.12065 0.2794)
			(stroke
				(width 0.1)
				(type default)
			)
			(layer "F.Fab")
		)
		(fp_line
			(start 0.120396 0.3048)
			(end 0.120396 0.2794)
			(stroke
				(width 0.1)
				(type default)
			)
			(layer "F.Fab")
		)
		(fp_line
			(start 0.12065 -0.3048)
			(end 0.67945 -0.3048)
			(stroke
				(width 0.1)
				(type default)
			)
			(layer "F.Fab")
		)
		(fp_line
			(start 0.12065 -0.2794)
			(end 0.12065 -0.3048)
			(stroke
				(width 0.1)
				(type default)
			)
			(layer "F.Fab")
		)
		(fp_line
			(start 0.67945 -0.3048)
			(end 0.67945 0.3048)
			(stroke
				(width 0.1)
				(type default)
			)
			(layer "F.Fab")
		)
		(fp_line
			(start 0.67945 0.3048)
			(end 0.120396 0.3048)
			(stroke
				(width 0.1)
				(type default)
			)
			(layer "F.Fab")
		)
		(pad "1" smd circle
			(at -0.40005 0)
			(size 0 0)
			(layers "F.Cu" "F.Mask" "F.Paste")
			(net "P12V_SSD5")
		)
		(pad "2" smd circle
			(at 0.40005 0)
			(size 0 0)
			(layers "F.Cu" "F.Mask" "F.Paste")
			(net "GND")
		)
	)
	(footprint ""
		(layer "F.Cu")
		(at 69.947028 -55.63489 90)
		(property "Reference" "PC650"
			(at 0 0 90)
			(layer "F.SilkS")
			(hide yes)
			(effects
				(font
					(size 1.27 1.27)
				)
			)
		)
		(property "Value" ""
			(at 0 0 90)
			(layer "F.Fab")
			(effects
				(font
					(size 1.27 1.27)
				)
			)
		)
		(duplicate_pad_numbers_are_jumpers no)
		(fp_line
			(start 1.524 -0.762)
			(end 1.524 0.762)
			(stroke
				(width 0.1524)
				(type default)
			)
			(layer "F.SilkS")
		)
		(fp_line
			(start -1.524 -0.762)
			(end 1.524 -0.762)
			(stroke
				(width 0.1524)
				(type default)
			)
			(layer "F.SilkS")
		)
		(fp_line
			(start 1.524 0.762)
			(end -1.524 0.762)
			(stroke
				(width 0.1524)
				(type default)
			)
			(layer "F.SilkS")
		)
		(fp_line
			(start -1.524 0.762)
			(end -1.524 -0.762)
			(stroke
				(width 0.1524)
				(type default)
			)
			(layer "F.SilkS")
		)
		(fp_line
			(start 1.1049 -0.724916)
			(end -1.1049 -0.724916)
			(stroke
				(width 0.1)
				(type default)
			)
			(layer "F.Fab")
		)
		(fp_line
			(start -1.1049 -0.724916)
			(end -1.1049 0.724916)
			(stroke
				(width 0.1)
				(type default)
			)
			(layer "F.Fab")
		)
		(fp_line
			(start 1.1049 0.724916)
			(end 1.1049 -0.724916)
			(stroke
				(width 0.1)
				(type default)
			)
			(layer "F.Fab")
		)
		(fp_line
			(start -1.1049 0.724916)
			(end 1.1049 0.724916)
			(stroke
				(width 0.1)
				(type default)
			)
			(layer "F.Fab")
		)
		(pad "1" smd rect
			(at -0.889 0 270)
			(size 1.016 1.27)
			(layers "F.Cu" "F.Mask" "F.Paste")
			(net "P12V_SSD2_R")
		)
		(pad "2" smd rect
			(at 0.889 0 270)
			(size 1.016 1.27)
			(layers "F.Cu" "F.Mask" "F.Paste")
			(net "GND")
		)
	)
	(footprint ""
		(layer "F.Cu")
		(at 151.469598 -260.088634 -90)
		(property "Reference" "R4571"
			(at 0 0 270)
			(layer "F.SilkS")
			(hide yes)
			(effects
				(font
					(size 1.27 1.27)
				)
			)
		)
		(property "Value" ""
			(at 0 0 270)
			(layer "F.Fab")
			(effects
				(font
					(size 1.27 1.27)
				)
			)
		)
		(duplicate_pad_numbers_are_jumpers no)
		(fp_line
			(start -0.7874 0.4064)
			(end -0.7874 -0.4064)
			(stroke
				(width 0.1524)
				(type default)
			)
			(layer "F.SilkS")
		)
		(fp_line
			(start 0.7874 0.4064)
			(end -0.7874 0.4064)
			(stroke
				(width 0.1524)
				(type default)
			)
			(layer "F.SilkS")
		)
		(fp_line
			(start -0.7874 -0.4064)
			(end 0.7874 -0.4064)
			(stroke
				(width 0.1524)
				(type default)
			)
			(layer "F.SilkS")
		)
		(fp_line
			(start 0.7874 -0.4064)
			(end 0.7874 0.4064)
			(stroke
				(width 0.1524)
				(type default)
			)
			(layer "F.SilkS")
		)
		(fp_line
			(start -0.67945 0.3048)
			(end -0.67945 -0.305054)
			(stroke
				(width 0.1)
				(type default)
			)
			(layer "F.Fab")
		)
		(fp_line
			(start -0.12065 0.3048)
			(end -0.67945 0.3048)
			(stroke
				(width 0.1)
				(type default)
			)
			(layer "F.Fab")
		)
		(fp_line
			(start 0.120396 0.3048)
			(end 0.120396 0.2794)
			(stroke
				(width 0.1)
				(type default)
			)
			(layer "F.Fab")
		)
		(fp_line
			(start 0.67945 0.3048)
			(end 0.120396 0.3048)
			(stroke
				(width 0.1)
				(type default)
			)
			(layer "F.Fab")
		)
		(fp_line
			(start -0.12065 0.2794)
			(end -0.12065 0.3048)
			(stroke
				(width 0.1)
				(type default)
			)
			(layer "F.Fab")
		)
		(fp_line
			(start 0.120396 0.2794)
			(end -0.12065 0.2794)
			(stroke
				(width 0.1)
				(type default)
			)
			(layer "F.Fab")
		)
		(fp_line
			(start -0.12065 -0.2794)
			(end 0.12065 -0.2794)
			(stroke
				(width 0.1)
				(type default)
			)
			(layer "F.Fab")
		)
		(fp_line
			(start 0.12065 -0.2794)
			(end 0.12065 -0.3048)
			(stroke
				(width 0.1)
				(type default)
			)
			(layer "F.Fab")
		)
		(fp_line
			(start 0.12065 -0.3048)
			(end 0.67945 -0.3048)
			(stroke
				(width 0.1)
				(type default)
			)
			(layer "F.Fab")
		)
		(fp_line
			(start 0.67945 -0.3048)
			(end 0.67945 0.3048)
			(stroke
				(width 0.1)
				(type default)
			)
			(layer "F.Fab")
		)
		(fp_line
			(start -0.67945 -0.305054)
			(end -0.12065 -0.305054)
			(stroke
				(width 0.1)
				(type default)
			)
			(layer "F.Fab")
		)
		(fp_line
			(start -0.12065 -0.305054)
			(end -0.12065 -0.2794)
			(stroke
				(width 0.1)
				(type default)
			)
			(layer "F.Fab")
		)
		(pad "1" smd circle
			(at -0.40005 0 270)
			(size 0 0)
			(layers "F.Cu" "F.Mask" "F.Paste")
			(net "PCEPLL3_VDDA18_PEX1")
		)
		(pad "2" smd circle
			(at 0.40005 0 270)
			(size 0 0)
			(layers "F.Cu" "F.Mask" "F.Paste")
			(net "PCEPLL3_VDDA18_PEX1_R")
		)
	)
	(footprint ""
		(layer "F.Cu")
		(at 185.89244 -32.739584 180)
		(property "Reference" "C294"
			(at 0 0 180)
			(layer "F.SilkS")
			(hide yes)
			(effects
				(font
					(size 1.27 1.27)
				)
			)
		)
		(property "Value" ""
			(at 0 0 180)
			(layer "F.Fab")
			(effects
				(font
					(size 1.27 1.27)
				)
			)
		)
		(duplicate_pad_numbers_are_jumpers no)
		(fp_line
			(start 0.299974 0.150114)
			(end -0.299974 0.150114)
			(stroke
				(width 0.1)
				(type default)
			)
			(layer "F.Fab")
		)
		(fp_line
			(start 0.299974 -0.150114)
			(end 0.299974 0.150114)
			(stroke
				(width 0.1)
				(type default)
			)
			(layer "F.Fab")
		)
		(fp_line
			(start -0.299974 0.150114)
			(end -0.299974 -0.150114)
			(stroke
				(width 0.1)
				(type default)
			)
			(layer "F.Fab")
		)
		(fp_line
			(start -0.299974 -0.150114)
			(end 0.299974 -0.150114)
			(stroke
				(width 0.1)
				(type default)
			)
			(layer "F.Fab")
		)
		(pad "1" smd rect
			(at -0.2667 0 180)
			(size 0.3048 0.381)
			(layers "F.Cu" "F.Mask" "F.Paste")
			(net "P5E_PEX1_STN2_TX_DP<38>")
		)
		(pad "2" smd rect
			(at 0.2667 0 180)
			(size 0.3048 0.381)
			(layers "F.Cu" "F.Mask" "F.Paste")
			(net "P5E_PEX1_STN2_TX_C_DP<38>")
		)
	)
	(footprint ""
		(layer "F.Cu")
		(at 315.856112 -61.487812 180)
		(property "Reference" "R6003"
			(at 0 0 180)
			(layer "F.SilkS")
			(hide yes)
			(effects
				(font
					(size 1.27 1.27)
				)
			)
		)
		(property "Value" ""
			(at 0 0 180)
			(layer "F.Fab")
			(effects
				(font
					(size 1.27 1.27)
				)
			)
		)
		(duplicate_pad_numbers_are_jumpers no)
		(fp_line
			(start 0.7874 0.4064)
			(end -0.7874 0.4064)
			(stroke
				(width 0.1524)
				(type default)
			)
			(layer "F.SilkS")
		)
		(fp_line
			(start 0.7874 -0.4064)
			(end 0.7874 0.4064)
			(stroke
				(width 0.1524)
				(type default)
			)
			(layer "F.SilkS")
		)
		(fp_line
			(start -0.7874 0.4064)
			(end -0.7874 -0.4064)
			(stroke
				(width 0.1524)
				(type default)
			)
			(layer "F.SilkS")
		)
		(fp_line
			(start -0.7874 -0.4064)
			(end 0.7874 -0.4064)
			(stroke
				(width 0.1524)
				(type default)
			)
			(layer "F.SilkS")
		)
		(fp_line
			(start 0.67945 0.3048)
			(end 0.120396 0.3048)
			(stroke
				(width 0.1)
				(type default)
			)
			(layer "F.Fab")
		)
		(fp_line
			(start 0.67945 -0.3048)
			(end 0.67945 0.3048)
			(stroke
				(width 0.1)
				(type default)
			)
			(layer "F.Fab")
		)
		(fp_line
			(start 0.12065 -0.2794)
			(end 0.12065 -0.3048)
			(stroke
				(width 0.1)
				(type default)
			)
			(layer "F.Fab")
		)
		(fp_line
			(start 0.12065 -0.3048)
			(end 0.67945 -0.3048)
			(stroke
				(width 0.1)
				(type default)
			)
			(layer "F.Fab")
		)
		(fp_line
			(start 0.120396 0.3048)
			(end 0.120396 0.2794)
			(stroke
				(width 0.1)
				(type default)
			)
			(layer "F.Fab")
		)
		(fp_line
			(start 0.120396 0.2794)
			(end -0.12065 0.2794)
			(stroke
				(width 0.1)
				(type default)
			)
			(layer "F.Fab")
		)
		(fp_line
			(start -0.12065 0.3048)
			(end -0.67945 0.3048)
			(stroke
				(width 0.1)
				(type default)
			)
			(layer "F.Fab")
		)
		(fp_line
			(start -0.12065 0.2794)
			(end -0.12065 0.3048)
			(stroke
				(width 0.1)
				(type default)
			)
			(layer "F.Fab")
		)
		(fp_line
			(start -0.12065 -0.2794)
			(end 0.12065 -0.2794)
			(stroke
				(width 0.1)
				(type default)
			)
			(layer "F.Fab")
		)
		(fp_line
			(start -0.12065 -0.305054)
			(end -0.12065 -0.2794)
			(stroke
				(width 0.1)
				(type default)
			)
			(layer "F.Fab")
		)
		(fp_line
			(start -0.67945 0.3048)
			(end -0.67945 -0.305054)
			(stroke
				(width 0.1)
				(type default)
			)
			(layer "F.Fab")
		)
		(fp_line
			(start -0.67945 -0.305054)
			(end -0.12065 -0.305054)
			(stroke
				(width 0.1)
				(type default)
			)
			(layer "F.Fab")
		)
		(pad "1" smd circle
			(at -0.40005 0 180)
			(size 0 0)
			(layers "F.Cu" "F.Mask" "F.Paste")
			(net "P3V3_AUX")
		)
		(pad "2" smd circle
			(at 0.40005 0 180)
			(size 0 0)
			(layers "F.Cu" "F.Mask" "F.Paste")
			(net "PWRGD_P12V_SSD11_D")
		)
	)
	(footprint ""
		(layer "F.Cu")
		(at 252.439678 -152.71115 90)
		(property "Reference" "R726"
			(at 0 0 90)
			(layer "F.SilkS")
			(hide yes)
			(effects
				(font
					(size 1.27 1.27)
				)
			)
		)
		(property "Value" ""
			(at 0 0 90)
			(layer "F.Fab")
			(effects
				(font
					(size 1.27 1.27)
				)
			)
		)
		(duplicate_pad_numbers_are_jumpers no)
		(fp_line
			(start 0.7874 -0.4064)
			(end 0.7874 0.4064)
			(stroke
				(width 0.1524)
				(type default)
			)
			(layer "F.SilkS")
		)
		(fp_line
			(start -0.7874 -0.4064)
			(end 0.7874 -0.4064)
			(stroke
				(width 0.1524)
				(type default)
			)
			(layer "F.SilkS")
		)
		(fp_line
			(start 0.7874 0.4064)
			(end -0.7874 0.4064)
			(stroke
				(width 0.1524)
				(type default)
			)
			(layer "F.SilkS")
		)
		(fp_line
			(start -0.7874 0.4064)
			(end -0.7874 -0.4064)
			(stroke
				(width 0.1524)
				(type default)
			)
			(layer "F.SilkS")
		)
		(fp_line
			(start -0.12065 -0.305054)
			(end -0.12065 -0.2794)
			(stroke
				(width 0.1)
				(type default)
			)
			(layer "F.Fab")
		)
		(fp_line
			(start -0.67945 -0.305054)
			(end -0.12065 -0.305054)
			(stroke
				(width 0.1)
				(type default)
			)
			(layer "F.Fab")
		)
		(fp_line
			(start 0.67945 -0.3048)
			(end 0.67945 0.3048)
			(stroke
				(width 0.1)
				(type default)
			)
			(layer "F.Fab")
		)
		(fp_line
			(start 0.12065 -0.3048)
			(end 0.67945 -0.3048)
			(stroke
				(width 0.1)
				(type default)
			)
			(layer "F.Fab")
		)
		(fp_line
			(start 0.12065 -0.2794)
			(end 0.12065 -0.3048)
			(stroke
				(width 0.1)
				(type default)
			)
			(layer "F.Fab")
		)
		(fp_line
			(start -0.12065 -0.2794)
			(end 0.12065 -0.2794)
			(stroke
				(width 0.1)
				(type default)
			)
			(layer "F.Fab")
		)
		(fp_line
			(start 0.120396 0.2794)
			(end -0.12065 0.2794)
			(stroke
				(width 0.1)
				(type default)
			)
			(layer "F.Fab")
		)
		(fp_line
			(start -0.12065 0.2794)
			(end -0.12065 0.3048)
			(stroke
				(width 0.1)
				(type default)
			)
			(layer "F.Fab")
		)
		(fp_line
			(start 0.67945 0.3048)
			(end 0.120396 0.3048)
			(stroke
				(width 0.1)
				(type default)
			)
			(layer "F.Fab")
		)
		(fp_line
			(start 0.120396 0.3048)
			(end 0.120396 0.2794)
			(stroke
				(width 0.1)
				(type default)
			)
			(layer "F.Fab")
		)
		(fp_line
			(start -0.12065 0.3048)
			(end -0.67945 0.3048)
			(stroke
				(width 0.1)
				(type default)
			)
			(layer "F.Fab")
		)
		(fp_line
			(start -0.67945 0.3048)
			(end -0.67945 -0.305054)
			(stroke
				(width 0.1)
				(type default)
			)
			(layer "F.Fab")
		)
		(pad "1" smd circle
			(at -0.40005 0 90)
			(size 0 0)
			(layers "F.Cu" "F.Mask" "F.Paste")
			(net "NIC4_ADC_A0")
		)
		(pad "2" smd circle
			(at 0.40005 0 90)
			(size 0 0)
			(layers "F.Cu" "F.Mask" "F.Paste")
			(net "P3V3_AUX")
		)
	)
	(footprint ""
		(layer "F.Cu")
		(at 61.792612 -158.080202 90)
		(property "Reference" "R3304"
			(at 0 0 90)
			(layer "F.SilkS")
			(hide yes)
			(effects
				(font
					(size 1.27 1.27)
				)
			)
		)
		(property "Value" ""
			(at 0 0 90)
			(layer "F.Fab")
			(effects
				(font
					(size 1.27 1.27)
				)
			)
		)
		(duplicate_pad_numbers_are_jumpers no)
		(fp_line
			(start 0.7874 -0.4064)
			(end 0.7874 0.4064)
			(stroke
				(width 0.1524)
				(type default)
			)
			(layer "F.SilkS")
		)
		(fp_line
			(start -0.7874 -0.4064)
			(end 0.7874 -0.4064)
			(stroke
				(width 0.1524)
				(type default)
			)
			(layer "F.SilkS")
		)
		(fp_line
			(start 0.7874 0.4064)
			(end -0.7874 0.4064)
			(stroke
				(width 0.1524)
				(type default)
			)
			(layer "F.SilkS")
		)
		(fp_line
			(start -0.7874 0.4064)
			(end -0.7874 -0.4064)
			(stroke
				(width 0.1524)
				(type default)
			)
			(layer "F.SilkS")
		)
		(fp_line
			(start -0.12065 -0.305054)
			(end -0.12065 -0.2794)
			(stroke
				(width 0.1)
				(type default)
			)
			(layer "F.Fab")
		)
		(fp_line
			(start -0.67945 -0.305054)
			(end -0.12065 -0.305054)
			(stroke
				(width 0.1)
				(type default)
			)
			(layer "F.Fab")
		)
		(fp_line
			(start 0.67945 -0.3048)
			(end 0.67945 0.3048)
			(stroke
				(width 0.1)
				(type default)
			)
			(layer "F.Fab")
		)
		(fp_line
			(start 0.12065 -0.3048)
			(end 0.67945 -0.3048)
			(stroke
				(width 0.1)
				(type default)
			)
			(layer "F.Fab")
		)
		(fp_line
			(start 0.12065 -0.2794)
			(end 0.12065 -0.3048)
			(stroke
				(width 0.1)
				(type default)
			)
			(layer "F.Fab")
		)
		(fp_line
			(start -0.12065 -0.2794)
			(end 0.12065 -0.2794)
			(stroke
				(width 0.1)
				(type default)
			)
			(layer "F.Fab")
		)
		(fp_line
			(start 0.120396 0.2794)
			(end -0.12065 0.2794)
			(stroke
				(width 0.1)
				(type default)
			)
			(layer "F.Fab")
		)
		(fp_line
			(start -0.12065 0.2794)
			(end -0.12065 0.3048)
			(stroke
				(width 0.1)
				(type default)
			)
			(layer "F.Fab")
		)
		(fp_line
			(start 0.67945 0.3048)
			(end 0.120396 0.3048)
			(stroke
				(width 0.1)
				(type default)
			)
			(layer "F.Fab")
		)
		(fp_line
			(start 0.120396 0.3048)
			(end 0.120396 0.2794)
			(stroke
				(width 0.1)
				(type default)
			)
			(layer "F.Fab")
		)
		(fp_line
			(start -0.12065 0.3048)
			(end -0.67945 0.3048)
			(stroke
				(width 0.1)
				(type default)
			)
			(layer "F.Fab")
		)
		(fp_line
			(start -0.67945 0.3048)
			(end -0.67945 -0.305054)
			(stroke
				(width 0.1)
				(type default)
			)
			(layer "F.Fab")
		)
		(pad "1" smd circle
			(at -0.40005 0 90)
			(size 0 0)
			(layers "F.Cu" "F.Mask" "F.Paste")
			(net "FM_SYS_THROTTLE_R")
		)
		(pad "2" smd circle
			(at 0.40005 0 90)
			(size 0 0)
			(layers "F.Cu" "F.Mask" "F.Paste")
			(net "FM_SYS_THROTTLE_NIC0")
		)
	)
	(footprint ""
		(layer "F.Cu")
		(at 90.197178 -309.0418 135)
		(property "Reference" "R1249"
			(at 0 0 135)
			(layer "F.SilkS")
			(hide yes)
			(effects
				(font
					(size 1.27 1.27)
				)
			)
		)
		(property "Value" ""
			(at 0 0 135)
			(layer "F.Fab")
			(effects
				(font
					(size 1.27 1.27)
				)
			)
		)
		(duplicate_pad_numbers_are_jumpers no)
		(fp_line
			(start 0.787389 -0.406267)
			(end 0.787389 0.406267)
			(stroke
				(width 0.1524)
				(type default)
			)
			(layer "F.SilkS")
		)
		(fp_line
			(start 0.787389 0.406267)
			(end -0.787389 0.406267)
			(stroke
				(width 0.1524)
				(type default)
			)
			(layer "F.SilkS")
		)
		(fp_line
			(start -0.787389 -0.406267)
			(end 0.787389 -0.406267)
			(stroke
				(width 0.1524)
				(type default)
			)
			(layer "F.SilkS")
		)
		(fp_line
			(start -0.787389 0.406267)
			(end -0.787389 -0.406267)
			(stroke
				(width 0.1524)
				(type default)
			)
			(layer "F.SilkS")
		)
		(fp_line
			(start 0.679446 -0.30479)
			(end 0.679446 0.30479)
			(stroke
				(width 0.1)
				(type default)
			)
			(layer "F.Fab")
		)
		(fp_line
			(start 0.120515 -0.30479)
			(end 0.679446 -0.30479)
			(stroke
				(width 0.1)
				(type default)
			)
			(layer "F.Fab")
		)
		(fp_line
			(start 0.120695 -0.279466)
			(end 0.120515 -0.30479)
			(stroke
				(width 0.1)
				(type default)
			)
			(layer "F.Fab")
		)
		(fp_line
			(start 0.679446 0.30479)
			(end 0.120515 0.30479)
			(stroke
				(width 0.1)
				(type default)
			)
			(layer "F.Fab")
		)
		(fp_line
			(start -0.120695 -0.304969)
			(end -0.120695 -0.279466)
			(stroke
				(width 0.1)
				(type default)
			)
			(layer "F.Fab")
		)
		(fp_line
			(start -0.120695 -0.279466)
			(end 0.120695 -0.279466)
			(stroke
				(width 0.1)
				(type default)
			)
			(layer "F.Fab")
		)
		(fp_line
			(start 0.120335 0.279466)
			(end -0.120695 0.279466)
			(stroke
				(width 0.1)
				(type default)
			)
			(layer "F.Fab")
		)
		(fp_line
			(start 0.120515 0.30479)
			(end 0.120335 0.279466)
			(stroke
				(width 0.1)
				(type default)
			)
			(layer "F.Fab")
		)
		(fp_line
			(start -0.679446 -0.305149)
			(end -0.120695 -0.304969)
			(stroke
				(width 0.1)
				(type default)
			)
			(layer "F.Fab")
		)
		(fp_line
			(start -0.120695 0.279466)
			(end -0.120515 0.30479)
			(stroke
				(width 0.1)
				(type default)
			)
			(layer "F.Fab")
		)
		(fp_line
			(start -0.120515 0.30479)
			(end -0.679446 0.30479)
			(stroke
				(width 0.1)
				(type default)
			)
			(layer "F.Fab")
		)
		(fp_line
			(start -0.679446 0.30479)
			(end -0.679446 -0.305149)
			(stroke
				(width 0.1)
				(type default)
			)
			(layer "F.Fab")
		)
		(pad "1" smd circle
			(at -0.40005 0 135)
			(size 0 0)
			(layers "F.Cu" "F.Mask" "F.Paste")
			(net "GND")
		)
		(pad "2" smd circle
			(at 0.40005 0 135)
			(size 0 0)
			(layers "F.Cu" "F.Mask" "F.Paste")
			(net "PEX0_SPARE2")
		)
	)
	(footprint ""
		(layer "F.Cu")
		(at 352.920554 -84.930234)
		(property "Reference" "R1623"
			(at 0 0 0)
			(layer "F.SilkS")
			(hide yes)
			(effects
				(font
					(size 1.27 1.27)
				)
			)
		)
		(property "Value" ""
			(at 0 0 0)
			(layer "F.Fab")
			(effects
				(font
					(size 1.27 1.27)
				)
			)
		)
		(duplicate_pad_numbers_are_jumpers no)
		(fp_line
			(start -0.7874 -0.4064)
			(end 0.7874 -0.4064)
			(stroke
				(width 0.1524)
				(type default)
			)
			(layer "F.SilkS")
		)
		(fp_line
			(start -0.7874 0.4064)
			(end -0.7874 -0.4064)
			(stroke
				(width 0.1524)
				(type default)
			)
			(layer "F.SilkS")
		)
		(fp_line
			(start 0.7874 -0.4064)
			(end 0.7874 0.4064)
			(stroke
				(width 0.1524)
				(type default)
			)
			(layer "F.SilkS")
		)
		(fp_line
			(start 0.7874 0.4064)
			(end -0.7874 0.4064)
			(stroke
				(width 0.1524)
				(type default)
			)
			(layer "F.SilkS")
		)
		(fp_line
			(start -0.67945 -0.305054)
			(end -0.12065 -0.305054)
			(stroke
				(width 0.1)
				(type default)
			)
			(layer "F.Fab")
		)
		(fp_line
			(start -0.67945 0.3048)
			(end -0.67945 -0.305054)
			(stroke
				(width 0.1)
				(type default)
			)
			(layer "F.Fab")
		)
		(fp_line
			(start -0.12065 -0.305054)
			(end -0.12065 -0.2794)
			(stroke
				(width 0.1)
				(type default)
			)
			(layer "F.Fab")
		)
		(fp_line
			(start -0.12065 -0.2794)
			(end 0.12065 -0.2794)
			(stroke
				(width 0.1)
				(type default)
			)
			(layer "F.Fab")
		)
		(fp_line
			(start -0.12065 0.2794)
			(end -0.12065 0.3048)
			(stroke
				(width 0.1)
				(type default)
			)
			(layer "F.Fab")
		)
		(fp_line
			(start -0.12065 0.3048)
			(end -0.67945 0.3048)
			(stroke
				(width 0.1)
				(type default)
			)
			(layer "F.Fab")
		)
		(fp_line
			(start 0.120396 0.2794)
			(end -0.12065 0.2794)
			(stroke
				(width 0.1)
				(type default)
			)
			(layer "F.Fab")
		)
		(fp_line
			(start 0.120396 0.3048)
			(end 0.120396 0.2794)
			(stroke
				(width 0.1)
				(type default)
			)
			(layer "F.Fab")
		)
		(fp_line
			(start 0.12065 -0.3048)
			(end 0.67945 -0.3048)
			(stroke
				(width 0.1)
				(type default)
			)
			(layer "F.Fab")
		)
		(fp_line
			(start 0.12065 -0.2794)
			(end 0.12065 -0.3048)
			(stroke
				(width 0.1)
				(type default)
			)
			(layer "F.Fab")
		)
		(fp_line
			(start 0.67945 -0.3048)
			(end 0.67945 0.3048)
			(stroke
				(width 0.1)
				(type default)
			)
			(layer "F.Fab")
		)
		(fp_line
			(start 0.67945 0.3048)
			(end 0.120396 0.3048)
			(stroke
				(width 0.1)
				(type default)
			)
			(layer "F.Fab")
		)
		(pad "1" smd circle
			(at -0.40005 0)
			(size 0 0)
			(layers "F.Cu" "F.Mask" "F.Paste")
			(net "SMB_BIC_I2C9_MUX1_SSD10_R_SDA")
		)
		(pad "2" smd circle
			(at 0.40005 0)
			(size 0 0)
			(layers "F.Cu" "F.Mask" "F.Paste")
			(net "SMB_BIC_I2C9_MUX1_SSD10_SDA")
		)
	)
	(footprint ""
		(layer "F.Cu")
		(at 361.417362 -118.343426 90)
		(property "Reference" "R6052"
			(at 0 0 90)
			(layer "F.SilkS")
			(hide yes)
			(effects
				(font
					(size 1.27 1.27)
				)
			)
		)
		(property "Value" ""
			(at 0 0 90)
			(layer "F.Fab")
			(effects
				(font
					(size 1.27 1.27)
				)
			)
		)
		(duplicate_pad_numbers_are_jumpers no)
		(fp_line
			(start 0.7874 -0.4064)
			(end 0.7874 0.4064)
			(stroke
				(width 0.1524)
				(type default)
			)
			(layer "F.SilkS")
		)
		(fp_line
			(start -0.7874 -0.4064)
			(end 0.7874 -0.4064)
			(stroke
				(width 0.1524)
				(type default)
			)
			(layer "F.SilkS")
		)
		(fp_line
			(start 0.7874 0.4064)
			(end -0.7874 0.4064)
			(stroke
				(width 0.1524)
				(type default)
			)
			(layer "F.SilkS")
		)
		(fp_line
			(start -0.7874 0.4064)
			(end -0.7874 -0.4064)
			(stroke
				(width 0.1524)
				(type default)
			)
			(layer "F.SilkS")
		)
		(fp_line
			(start -0.12065 -0.305054)
			(end -0.12065 -0.2794)
			(stroke
				(width 0.1)
				(type default)
			)
			(layer "F.Fab")
		)
		(fp_line
			(start -0.67945 -0.305054)
			(end -0.12065 -0.305054)
			(stroke
				(width 0.1)
				(type default)
			)
			(layer "F.Fab")
		)
		(fp_line
			(start 0.67945 -0.3048)
			(end 0.67945 0.3048)
			(stroke
				(width 0.1)
				(type default)
			)
			(layer "F.Fab")
		)
		(fp_line
			(start 0.12065 -0.3048)
			(end 0.67945 -0.3048)
			(stroke
				(width 0.1)
				(type default)
			)
			(layer "F.Fab")
		)
		(fp_line
			(start 0.12065 -0.2794)
			(end 0.12065 -0.3048)
			(stroke
				(width 0.1)
				(type default)
			)
			(layer "F.Fab")
		)
		(fp_line
			(start -0.12065 -0.2794)
			(end 0.12065 -0.2794)
			(stroke
				(width 0.1)
				(type default)
			)
			(layer "F.Fab")
		)
		(fp_line
			(start 0.120396 0.2794)
			(end -0.12065 0.2794)
			(stroke
				(width 0.1)
				(type default)
			)
			(layer "F.Fab")
		)
		(fp_line
			(start -0.12065 0.2794)
			(end -0.12065 0.3048)
			(stroke
				(width 0.1)
				(type default)
			)
			(layer "F.Fab")
		)
		(fp_line
			(start 0.67945 0.3048)
			(end 0.120396 0.3048)
			(stroke
				(width 0.1)
				(type default)
			)
			(layer "F.Fab")
		)
		(fp_line
			(start 0.120396 0.3048)
			(end 0.120396 0.2794)
			(stroke
				(width 0.1)
				(type default)
			)
			(layer "F.Fab")
		)
		(fp_line
			(start -0.12065 0.3048)
			(end -0.67945 0.3048)
			(stroke
				(width 0.1)
				(type default)
			)
			(layer "F.Fab")
		)
		(fp_line
			(start -0.67945 0.3048)
			(end -0.67945 -0.305054)
			(stroke
				(width 0.1)
				(type default)
			)
			(layer "F.Fab")
		)
		(pad "1" smd circle
			(at -0.40005 0 90)
			(size 0 0)
			(layers "F.Cu" "F.Mask" "F.Paste")
			(net "P3V3_NIC6_PG_G1")
		)
		(pad "2" smd circle
			(at 0.40005 0 90)
			(size 0 0)
			(layers "F.Cu" "F.Mask" "F.Paste")
			(net "GND")
		)
	)
	(footprint ""
		(layer "F.Cu")
		(at 365.506 -209.931 180)
		(property "Reference" "R4625"
			(at 0 0 180)
			(layer "F.SilkS")
			(hide yes)
			(effects
				(font
					(size 1.27 1.27)
				)
			)
		)
		(property "Value" ""
			(at 0 0 180)
			(layer "F.Fab")
			(effects
				(font
					(size 1.27 1.27)
				)
			)
		)
		(duplicate_pad_numbers_are_jumpers no)
		(fp_line
			(start 0.7874 0.4064)
			(end -0.7874 0.4064)
			(stroke
				(width 0.1524)
				(type default)
			)
			(layer "F.SilkS")
		)
		(fp_line
			(start 0.7874 -0.4064)
			(end 0.7874 0.4064)
			(stroke
				(width 0.1524)
				(type default)
			)
			(layer "F.SilkS")
		)
		(fp_line
			(start -0.7874 0.4064)
			(end -0.7874 -0.4064)
			(stroke
				(width 0.1524)
				(type default)
			)
			(layer "F.SilkS")
		)
		(fp_line
			(start -0.7874 -0.4064)
			(end 0.7874 -0.4064)
			(stroke
				(width 0.1524)
				(type default)
			)
			(layer "F.SilkS")
		)
		(fp_line
			(start 0.67945 0.3048)
			(end 0.120396 0.3048)
			(stroke
				(width 0.1)
				(type default)
			)
			(layer "F.Fab")
		)
		(fp_line
			(start 0.67945 -0.3048)
			(end 0.67945 0.3048)
			(stroke
				(width 0.1)
				(type default)
			)
			(layer "F.Fab")
		)
		(fp_line
			(start 0.12065 -0.2794)
			(end 0.12065 -0.3048)
			(stroke
				(width 0.1)
				(type default)
			)
			(layer "F.Fab")
		)
		(fp_line
			(start 0.12065 -0.3048)
			(end 0.67945 -0.3048)
			(stroke
				(width 0.1)
				(type default)
			)
			(layer "F.Fab")
		)
		(fp_line
			(start 0.120396 0.3048)
			(end 0.120396 0.2794)
			(stroke
				(width 0.1)
				(type default)
			)
			(layer "F.Fab")
		)
		(fp_line
			(start 0.120396 0.2794)
			(end -0.12065 0.2794)
			(stroke
				(width 0.1)
				(type default)
			)
			(layer "F.Fab")
		)
		(fp_line
			(start -0.12065 0.3048)
			(end -0.67945 0.3048)
			(stroke
				(width 0.1)
				(type default)
			)
			(layer "F.Fab")
		)
		(fp_line
			(start -0.12065 0.2794)
			(end -0.12065 0.3048)
			(stroke
				(width 0.1)
				(type default)
			)
			(layer "F.Fab")
		)
		(fp_line
			(start -0.12065 -0.2794)
			(end 0.12065 -0.2794)
			(stroke
				(width 0.1)
				(type default)
			)
			(layer "F.Fab")
		)
		(fp_line
			(start -0.12065 -0.305054)
			(end -0.12065 -0.2794)
			(stroke
				(width 0.1)
				(type default)
			)
			(layer "F.Fab")
		)
		(fp_line
			(start -0.67945 0.3048)
			(end -0.67945 -0.305054)
			(stroke
				(width 0.1)
				(type default)
			)
			(layer "F.Fab")
		)
		(fp_line
			(start -0.67945 -0.305054)
			(end -0.12065 -0.305054)
			(stroke
				(width 0.1)
				(type default)
			)
			(layer "F.Fab")
		)
		(pad "1" smd circle
			(at -0.40005 0 180)
			(size 0 0)
			(layers "F.Cu" "F.Mask" "F.Paste")
			(net "RST_PEX_SSD0_PERST_N")
		)
		(pad "2" smd circle
			(at 0.40005 0 180)
			(size 0 0)
			(layers "F.Cu" "F.Mask" "F.Paste")
			(net "RST_PEX_SSD0_PERST_R_N")
		)
	)
	(footprint ""
		(layer "F.Cu")
		(at 307.867812 -18.437098)
		(property "Reference" "R1707"
			(at 0 0 0)
			(layer "F.SilkS")
			(hide yes)
			(effects
				(font
					(size 1.27 1.27)
				)
			)
		)
		(property "Value" ""
			(at 0 0 0)
			(layer "F.Fab")
			(effects
				(font
					(size 1.27 1.27)
				)
			)
		)
		(duplicate_pad_numbers_are_jumpers no)
		(fp_line
			(start -0.7874 -0.4064)
			(end 0.7874 -0.4064)
			(stroke
				(width 0.1524)
				(type default)
			)
			(layer "F.SilkS")
		)
		(fp_line
			(start -0.7874 0.4064)
			(end -0.7874 -0.4064)
			(stroke
				(width 0.1524)
				(type default)
			)
			(layer "F.SilkS")
		)
		(fp_line
			(start 0.7874 -0.4064)
			(end 0.7874 0.4064)
			(stroke
				(width 0.1524)
				(type default)
			)
			(layer "F.SilkS")
		)
		(fp_line
			(start 0.7874 0.4064)
			(end -0.7874 0.4064)
			(stroke
				(width 0.1524)
				(type default)
			)
			(layer "F.SilkS")
		)
		(fp_line
			(start -0.67945 -0.305054)
			(end -0.12065 -0.305054)
			(stroke
				(width 0.1)
				(type default)
			)
			(layer "F.Fab")
		)
		(fp_line
			(start -0.67945 0.3048)
			(end -0.67945 -0.305054)
			(stroke
				(width 0.1)
				(type default)
			)
			(layer "F.Fab")
		)
		(fp_line
			(start -0.12065 -0.305054)
			(end -0.12065 -0.2794)
			(stroke
				(width 0.1)
				(type default)
			)
			(layer "F.Fab")
		)
		(fp_line
			(start -0.12065 -0.2794)
			(end 0.12065 -0.2794)
			(stroke
				(width 0.1)
				(type default)
			)
			(layer "F.Fab")
		)
		(fp_line
			(start -0.12065 0.2794)
			(end -0.12065 0.3048)
			(stroke
				(width 0.1)
				(type default)
			)
			(layer "F.Fab")
		)
		(fp_line
			(start -0.12065 0.3048)
			(end -0.67945 0.3048)
			(stroke
				(width 0.1)
				(type default)
			)
			(layer "F.Fab")
		)
		(fp_line
			(start 0.120396 0.2794)
			(end -0.12065 0.2794)
			(stroke
				(width 0.1)
				(type default)
			)
			(layer "F.Fab")
		)
		(fp_line
			(start 0.120396 0.3048)
			(end 0.120396 0.2794)
			(stroke
				(width 0.1)
				(type default)
			)
			(layer "F.Fab")
		)
		(fp_line
			(start 0.12065 -0.3048)
			(end 0.67945 -0.3048)
			(stroke
				(width 0.1)
				(type default)
			)
			(layer "F.Fab")
		)
		(fp_line
			(start 0.12065 -0.2794)
			(end 0.12065 -0.3048)
			(stroke
				(width 0.1)
				(type default)
			)
			(layer "F.Fab")
		)
		(fp_line
			(start 0.67945 -0.3048)
			(end 0.67945 0.3048)
			(stroke
				(width 0.1)
				(type default)
			)
			(layer "F.Fab")
		)
		(fp_line
			(start 0.67945 0.3048)
			(end 0.120396 0.3048)
			(stroke
				(width 0.1)
				(type default)
			)
			(layer "F.Fab")
		)
		(pad "1" smd circle
			(at -0.40005 0)
			(size 0 0)
			(layers "F.Cu" "F.Mask" "F.Paste")
			(net "SMB_ISO_SSD10_R_SCL")
		)
		(pad "2" smd circle
			(at 0.40005 0)
			(size 0 0)
			(layers "F.Cu" "F.Mask" "F.Paste")
			(net "SMB_ISO_SSD10_SCL")
		)
	)
	(footprint ""
		(layer "F.Cu")
		(at 446.974976 -56.977534 180)
		(property "Reference" "PC438"
			(at 0 0 180)
			(layer "F.SilkS")
			(hide yes)
			(effects
				(font
					(size 1.27 1.27)
				)
			)
		)
		(property "Value" ""
			(at 0 0 180)
			(layer "F.Fab")
			(effects
				(font
					(size 1.27 1.27)
				)
			)
		)
		(duplicate_pad_numbers_are_jumpers no)
		(fp_line
			(start 0.7874 0.4064)
			(end -0.7874 0.4064)
			(stroke
				(width 0.1524)
				(type default)
			)
			(layer "F.SilkS")
		)
		(fp_line
			(start 0.7874 -0.4064)
			(end 0.7874 0.4064)
			(stroke
				(width 0.1524)
				(type default)
			)
			(layer "F.SilkS")
		)
		(fp_line
			(start -0.7874 0.4064)
			(end -0.7874 -0.4064)
			(stroke
				(width 0.1524)
				(type default)
			)
			(layer "F.SilkS")
		)
		(fp_line
			(start -0.7874 -0.4064)
			(end 0.7874 -0.4064)
			(stroke
				(width 0.1524)
				(type default)
			)
			(layer "F.SilkS")
		)
		(fp_line
			(start 0.67945 0.3048)
			(end 0.120396 0.3048)
			(stroke
				(width 0.1)
				(type default)
			)
			(layer "F.Fab")
		)
		(fp_line
			(start 0.67945 -0.3048)
			(end 0.67945 0.3048)
			(stroke
				(width 0.1)
				(type default)
			)
			(layer "F.Fab")
		)
		(fp_line
			(start 0.12065 -0.2794)
			(end 0.12065 -0.3048)
			(stroke
				(width 0.1)
				(type default)
			)
			(layer "F.Fab")
		)
		(fp_line
			(start 0.12065 -0.3048)
			(end 0.67945 -0.3048)
			(stroke
				(width 0.1)
				(type default)
			)
			(layer "F.Fab")
		)
		(fp_line
			(start 0.120396 0.3048)
			(end 0.120396 0.2794)
			(stroke
				(width 0.1)
				(type default)
			)
			(layer "F.Fab")
		)
		(fp_line
			(start 0.120396 0.2794)
			(end -0.12065 0.2794)
			(stroke
				(width 0.1)
				(type default)
			)
			(layer "F.Fab")
		)
		(fp_line
			(start -0.12065 0.3048)
			(end -0.67945 0.3048)
			(stroke
				(width 0.1)
				(type default)
			)
			(layer "F.Fab")
		)
		(fp_line
			(start -0.12065 0.2794)
			(end -0.12065 0.3048)
			(stroke
				(width 0.1)
				(type default)
			)
			(layer "F.Fab")
		)
		(fp_line
			(start -0.12065 -0.2794)
			(end 0.12065 -0.2794)
			(stroke
				(width 0.1)
				(type default)
			)
			(layer "F.Fab")
		)
		(fp_line
			(start -0.12065 -0.305054)
			(end -0.12065 -0.2794)
			(stroke
				(width 0.1)
				(type default)
			)
			(layer "F.Fab")
		)
		(fp_line
			(start -0.67945 0.3048)
			(end -0.67945 -0.305054)
			(stroke
				(width 0.1)
				(type default)
			)
			(layer "F.Fab")
		)
		(fp_line
			(start -0.67945 -0.305054)
			(end -0.12065 -0.305054)
			(stroke
				(width 0.1)
				(type default)
			)
			(layer "F.Fab")
		)
		(pad "1" smd circle
			(at -0.40005 0 180)
			(size 0 0)
			(layers "F.Cu" "F.Mask" "F.Paste")
			(net "P12V_AUX")
		)
		(pad "2" smd circle
			(at 0.40005 0 180)
			(size 0 0)
			(layers "F.Cu" "F.Mask" "F.Paste")
			(net "GND")
		)
	)
	(footprint ""
		(layer "F.Cu")
		(at 449.452238 -95.264224 90)
		(property "Reference" "R4457"
			(at 0 0 90)
			(layer "F.SilkS")
			(hide yes)
			(effects
				(font
					(size 1.27 1.27)
				)
			)
		)
		(property "Value" ""
			(at 0 0 90)
			(layer "F.Fab")
			(effects
				(font
					(size 1.27 1.27)
				)
			)
		)
		(duplicate_pad_numbers_are_jumpers no)
		(fp_line
			(start 0.7874 -0.4064)
			(end 0.7874 0.4064)
			(stroke
				(width 0.1524)
				(type default)
			)
			(layer "F.SilkS")
		)
		(fp_line
			(start -0.7874 -0.4064)
			(end 0.7874 -0.4064)
			(stroke
				(width 0.1524)
				(type default)
			)
			(layer "F.SilkS")
		)
		(fp_line
			(start 0.7874 0.4064)
			(end -0.7874 0.4064)
			(stroke
				(width 0.1524)
				(type default)
			)
			(layer "F.SilkS")
		)
		(fp_line
			(start -0.7874 0.4064)
			(end -0.7874 -0.4064)
			(stroke
				(width 0.1524)
				(type default)
			)
			(layer "F.SilkS")
		)
		(fp_line
			(start -0.12065 -0.305054)
			(end -0.12065 -0.2794)
			(stroke
				(width 0.1)
				(type default)
			)
			(layer "F.Fab")
		)
		(fp_line
			(start -0.67945 -0.305054)
			(end -0.12065 -0.305054)
			(stroke
				(width 0.1)
				(type default)
			)
			(layer "F.Fab")
		)
		(fp_line
			(start 0.67945 -0.3048)
			(end 0.67945 0.3048)
			(stroke
				(width 0.1)
				(type default)
			)
			(layer "F.Fab")
		)
		(fp_line
			(start 0.12065 -0.3048)
			(end 0.67945 -0.3048)
			(stroke
				(width 0.1)
				(type default)
			)
			(layer "F.Fab")
		)
		(fp_line
			(start 0.12065 -0.2794)
			(end 0.12065 -0.3048)
			(stroke
				(width 0.1)
				(type default)
			)
			(layer "F.Fab")
		)
		(fp_line
			(start -0.12065 -0.2794)
			(end 0.12065 -0.2794)
			(stroke
				(width 0.1)
				(type default)
			)
			(layer "F.Fab")
		)
		(fp_line
			(start 0.120396 0.2794)
			(end -0.12065 0.2794)
			(stroke
				(width 0.1)
				(type default)
			)
			(layer "F.Fab")
		)
		(fp_line
			(start -0.12065 0.2794)
			(end -0.12065 0.3048)
			(stroke
				(width 0.1)
				(type default)
			)
			(layer "F.Fab")
		)
		(fp_line
			(start 0.67945 0.3048)
			(end 0.120396 0.3048)
			(stroke
				(width 0.1)
				(type default)
			)
			(layer "F.Fab")
		)
		(fp_line
			(start 0.120396 0.3048)
			(end 0.120396 0.2794)
			(stroke
				(width 0.1)
				(type default)
			)
			(layer "F.Fab")
		)
		(fp_line
			(start -0.12065 0.3048)
			(end -0.67945 0.3048)
			(stroke
				(width 0.1)
				(type default)
			)
			(layer "F.Fab")
		)
		(fp_line
			(start -0.67945 0.3048)
			(end -0.67945 -0.305054)
			(stroke
				(width 0.1)
				(type default)
			)
			(layer "F.Fab")
		)
		(pad "1" smd circle
			(at -0.40005 0 90)
			(size 0 0)
			(layers "F.Cu" "F.Mask" "F.Paste")
			(net "HP_NIC7_EN")
		)
		(pad "2" smd circle
			(at 0.40005 0 90)
			(size 0 0)
			(layers "F.Cu" "F.Mask" "F.Paste")
			(net "P12V_NIC7_EN_R")
		)
	)
	(footprint ""
		(layer "F.Cu")
		(at 426.567854 -55.083456)
		(property "Reference" "PC420"
			(at 0 0 0)
			(layer "F.SilkS")
			(hide yes)
			(effects
				(font
					(size 1.27 1.27)
				)
			)
		)
		(property "Value" ""
			(at 0 0 0)
			(layer "F.Fab")
			(effects
				(font
					(size 1.27 1.27)
				)
			)
		)
		(duplicate_pad_numbers_are_jumpers no)
		(fp_line
			(start -0.7874 -0.4064)
			(end 0.7874 -0.4064)
			(stroke
				(width 0.1524)
				(type default)
			)
			(layer "F.SilkS")
		)
		(fp_line
			(start -0.7874 0.4064)
			(end -0.7874 -0.4064)
			(stroke
				(width 0.1524)
				(type default)
			)
			(layer "F.SilkS")
		)
		(fp_line
			(start 0.7874 -0.4064)
			(end 0.7874 0.4064)
			(stroke
				(width 0.1524)
				(type default)
			)
			(layer "F.SilkS")
		)
		(fp_line
			(start 0.7874 0.4064)
			(end -0.7874 0.4064)
			(stroke
				(width 0.1524)
				(type default)
			)
			(layer "F.SilkS")
		)
		(fp_line
			(start -0.67945 -0.305054)
			(end -0.12065 -0.305054)
			(stroke
				(width 0.1)
				(type default)
			)
			(layer "F.Fab")
		)
		(fp_line
			(start -0.67945 0.3048)
			(end -0.67945 -0.305054)
			(stroke
				(width 0.1)
				(type default)
			)
			(layer "F.Fab")
		)
		(fp_line
			(start -0.12065 -0.305054)
			(end -0.12065 -0.2794)
			(stroke
				(width 0.1)
				(type default)
			)
			(layer "F.Fab")
		)
		(fp_line
			(start -0.12065 -0.2794)
			(end 0.12065 -0.2794)
			(stroke
				(width 0.1)
				(type default)
			)
			(layer "F.Fab")
		)
		(fp_line
			(start -0.12065 0.2794)
			(end -0.12065 0.3048)
			(stroke
				(width 0.1)
				(type default)
			)
			(layer "F.Fab")
		)
		(fp_line
			(start -0.12065 0.3048)
			(end -0.67945 0.3048)
			(stroke
				(width 0.1)
				(type default)
			)
			(layer "F.Fab")
		)
		(fp_line
			(start 0.120396 0.2794)
			(end -0.12065 0.2794)
			(stroke
				(width 0.1)
				(type default)
			)
			(layer "F.Fab")
		)
		(fp_line
			(start 0.120396 0.3048)
			(end 0.120396 0.2794)
			(stroke
				(width 0.1)
				(type default)
			)
			(layer "F.Fab")
		)
		(fp_line
			(start 0.12065 -0.3048)
			(end 0.67945 -0.3048)
			(stroke
				(width 0.1)
				(type default)
			)
			(layer "F.Fab")
		)
		(fp_line
			(start 0.12065 -0.2794)
			(end 0.12065 -0.3048)
			(stroke
				(width 0.1)
				(type default)
			)
			(layer "F.Fab")
		)
		(fp_line
			(start 0.67945 -0.3048)
			(end 0.67945 0.3048)
			(stroke
				(width 0.1)
				(type default)
			)
			(layer "F.Fab")
		)
		(fp_line
			(start 0.67945 0.3048)
			(end 0.120396 0.3048)
			(stroke
				(width 0.1)
				(type default)
			)
			(layer "F.Fab")
		)
		(pad "1" smd circle
			(at -0.40005 0)
			(size 0 0)
			(layers "F.Cu" "F.Mask" "F.Paste")
			(net "P5V_AUX")
		)
		(pad "2" smd circle
			(at 0.40005 0)
			(size 0 0)
			(layers "F.Cu" "F.Mask" "F.Paste")
			(net "GND")
		)
	)
	(footprint ""
		(layer "F.Cu")
		(at 3.65125 -393.464542 -90)
		(property "Reference" "R6736"
			(at 0 0 270)
			(layer "F.SilkS")
			(hide yes)
			(effects
				(font
					(size 1.27 1.27)
				)
			)
		)
		(property "Value" ""
			(at 0 0 270)
			(layer "F.Fab")
			(effects
				(font
					(size 1.27 1.27)
				)
			)
		)
		(duplicate_pad_numbers_are_jumpers no)
		(fp_line
			(start -0.7874 0.4064)
			(end -0.7874 -0.4064)
			(stroke
				(width 0.1524)
				(type default)
			)
			(layer "F.SilkS")
		)
		(fp_line
			(start 0.7874 0.4064)
			(end -0.7874 0.4064)
			(stroke
				(width 0.1524)
				(type default)
			)
			(layer "F.SilkS")
		)
		(fp_line
			(start -0.7874 -0.4064)
			(end 0.7874 -0.4064)
			(stroke
				(width 0.1524)
				(type default)
			)
			(layer "F.SilkS")
		)
		(fp_line
			(start 0.7874 -0.4064)
			(end 0.7874 0.4064)
			(stroke
				(width 0.1524)
				(type default)
			)
			(layer "F.SilkS")
		)
		(fp_line
			(start -0.67945 0.3048)
			(end -0.67945 -0.305054)
			(stroke
				(width 0.1)
				(type default)
			)
			(layer "F.Fab")
		)
		(fp_line
			(start -0.12065 0.3048)
			(end -0.67945 0.3048)
			(stroke
				(width 0.1)
				(type default)
			)
			(layer "F.Fab")
		)
		(fp_line
			(start 0.120396 0.3048)
			(end 0.120396 0.2794)
			(stroke
				(width 0.1)
				(type default)
			)
			(layer "F.Fab")
		)
		(fp_line
			(start 0.67945 0.3048)
			(end 0.120396 0.3048)
			(stroke
				(width 0.1)
				(type default)
			)
			(layer "F.Fab")
		)
		(fp_line
			(start -0.12065 0.2794)
			(end -0.12065 0.3048)
			(stroke
				(width 0.1)
				(type default)
			)
			(layer "F.Fab")
		)
		(fp_line
			(start 0.120396 0.2794)
			(end -0.12065 0.2794)
			(stroke
				(width 0.1)
				(type default)
			)
			(layer "F.Fab")
		)
		(fp_line
			(start -0.12065 -0.2794)
			(end 0.12065 -0.2794)
			(stroke
				(width 0.1)
				(type default)
			)
			(layer "F.Fab")
		)
		(fp_line
			(start 0.12065 -0.2794)
			(end 0.12065 -0.3048)
			(stroke
				(width 0.1)
				(type default)
			)
			(layer "F.Fab")
		)
		(fp_line
			(start 0.12065 -0.3048)
			(end 0.67945 -0.3048)
			(stroke
				(width 0.1)
				(type default)
			)
			(layer "F.Fab")
		)
		(fp_line
			(start 0.67945 -0.3048)
			(end 0.67945 0.3048)
			(stroke
				(width 0.1)
				(type default)
			)
			(layer "F.Fab")
		)
		(fp_line
			(start -0.67945 -0.305054)
			(end -0.12065 -0.305054)
			(stroke
				(width 0.1)
				(type default)
			)
			(layer "F.Fab")
		)
		(fp_line
			(start -0.12065 -0.305054)
			(end -0.12065 -0.2794)
			(stroke
				(width 0.1)
				(type default)
			)
			(layer "F.Fab")
		)
		(pad "1" smd circle
			(at -0.40005 0 270)
			(size 0 0)
			(layers "F.Cu" "F.Mask" "F.Paste")
			(net "GND")
		)
		(pad "2" smd circle
			(at 0.40005 0 270)
			(size 0 0)
			(layers "F.Cu" "F.Mask" "F.Paste")
			(net "BIC_USB_8042_HUB_TEST")
		)
	)
	(footprint ""
		(layer "F.Cu")
		(at 28.633928 -350.098614 90)
		(property "Reference" "C2160"
			(at 0 0 90)
			(layer "F.SilkS")
			(hide yes)
			(effects
				(font
					(size 1.27 1.27)
				)
			)
		)
		(property "Value" ""
			(at 0 0 90)
			(layer "F.Fab")
			(effects
				(font
					(size 1.27 1.27)
				)
			)
		)
		(duplicate_pad_numbers_are_jumpers no)
		(fp_line
			(start 0.299974 -0.150114)
			(end 0.299974 0.150114)
			(stroke
				(width 0.1)
				(type default)
			)
			(layer "F.Fab")
		)
		(fp_line
			(start -0.299974 -0.150114)
			(end 0.299974 -0.150114)
			(stroke
				(width 0.1)
				(type default)
			)
			(layer "F.Fab")
		)
		(fp_line
			(start 0.299974 0.150114)
			(end -0.299974 0.150114)
			(stroke
				(width 0.1)
				(type default)
			)
			(layer "F.Fab")
		)
		(fp_line
			(start -0.299974 0.150114)
			(end -0.299974 -0.150114)
			(stroke
				(width 0.1)
				(type default)
			)
			(layer "F.Fab")
		)
		(pad "1" smd rect
			(at -0.2667 0 90)
			(size 0.3048 0.381)
			(layers "F.Cu" "F.Mask" "F.Paste")
			(net "P5E_PEX0_STN4_TX_DP<75>")
		)
		(pad "2" smd rect
			(at 0.2667 0 90)
			(size 0.3048 0.381)
			(layers "F.Cu" "F.Mask" "F.Paste")
			(net "P5E_PEX0_STN4_TX_C_DP<75>")
		)
	)
	(footprint ""
		(layer "F.Cu")
		(at 49.656492 -20.467574 180)
		(property "Reference" "R1636"
			(at 0 0 180)
			(layer "F.SilkS")
			(hide yes)
			(effects
				(font
					(size 1.27 1.27)
				)
			)
		)
		(property "Value" ""
			(at 0 0 180)
			(layer "F.Fab")
			(effects
				(font
					(size 1.27 1.27)
				)
			)
		)
		(duplicate_pad_numbers_are_jumpers no)
		(fp_line
			(start 0.7874 0.4064)
			(end -0.7874 0.4064)
			(stroke
				(width 0.1524)
				(type default)
			)
			(layer "F.SilkS")
		)
		(fp_line
			(start 0.7874 -0.4064)
			(end 0.7874 0.4064)
			(stroke
				(width 0.1524)
				(type default)
			)
			(layer "F.SilkS")
		)
		(fp_line
			(start -0.7874 0.4064)
			(end -0.7874 -0.4064)
			(stroke
				(width 0.1524)
				(type default)
			)
			(layer "F.SilkS")
		)
		(fp_line
			(start -0.7874 -0.4064)
			(end 0.7874 -0.4064)
			(stroke
				(width 0.1524)
				(type default)
			)
			(layer "F.SilkS")
		)
		(fp_line
			(start 0.67945 0.3048)
			(end 0.120396 0.3048)
			(stroke
				(width 0.1)
				(type default)
			)
			(layer "F.Fab")
		)
		(fp_line
			(start 0.67945 -0.3048)
			(end 0.67945 0.3048)
			(stroke
				(width 0.1)
				(type default)
			)
			(layer "F.Fab")
		)
		(fp_line
			(start 0.12065 -0.2794)
			(end 0.12065 -0.3048)
			(stroke
				(width 0.1)
				(type default)
			)
			(layer "F.Fab")
		)
		(fp_line
			(start 0.12065 -0.3048)
			(end 0.67945 -0.3048)
			(stroke
				(width 0.1)
				(type default)
			)
			(layer "F.Fab")
		)
		(fp_line
			(start 0.120396 0.3048)
			(end 0.120396 0.2794)
			(stroke
				(width 0.1)
				(type default)
			)
			(layer "F.Fab")
		)
		(fp_line
			(start 0.120396 0.2794)
			(end -0.12065 0.2794)
			(stroke
				(width 0.1)
				(type default)
			)
			(layer "F.Fab")
		)
		(fp_line
			(start -0.12065 0.3048)
			(end -0.67945 0.3048)
			(stroke
				(width 0.1)
				(type default)
			)
			(layer "F.Fab")
		)
		(fp_line
			(start -0.12065 0.2794)
			(end -0.12065 0.3048)
			(stroke
				(width 0.1)
				(type default)
			)
			(layer "F.Fab")
		)
		(fp_line
			(start -0.12065 -0.2794)
			(end 0.12065 -0.2794)
			(stroke
				(width 0.1)
				(type default)
			)
			(layer "F.Fab")
		)
		(fp_line
			(start -0.12065 -0.305054)
			(end -0.12065 -0.2794)
			(stroke
				(width 0.1)
				(type default)
			)
			(layer "F.Fab")
		)
		(fp_line
			(start -0.67945 0.3048)
			(end -0.67945 -0.305054)
			(stroke
				(width 0.1)
				(type default)
			)
			(layer "F.Fab")
		)
		(fp_line
			(start -0.67945 -0.305054)
			(end -0.12065 -0.305054)
			(stroke
				(width 0.1)
				(type default)
			)
			(layer "F.Fab")
		)
		(pad "1" smd circle
			(at -0.40005 0 180)
			(size 0 0)
			(layers "F.Cu" "F.Mask" "F.Paste")
			(net "P3V3_SSD1")
		)
		(pad "2" smd circle
			(at 0.40005 0 180)
			(size 0 0)
			(layers "F.Cu" "F.Mask" "F.Paste")
			(net "SMB_ISO_SSD1_SDA")
		)
	)
	(footprint ""
		(layer "F.Cu")
		(at 258.54533 -196.081396)
		(property "Reference" "R2619"
			(at 0 0 0)
			(layer "F.SilkS")
			(hide yes)
			(effects
				(font
					(size 1.27 1.27)
				)
			)
		)
		(property "Value" ""
			(at 0 0 0)
			(layer "F.Fab")
			(effects
				(font
					(size 1.27 1.27)
				)
			)
		)
		(duplicate_pad_numbers_are_jumpers no)
		(fp_line
			(start -0.7874 -0.4064)
			(end 0.7874 -0.4064)
			(stroke
				(width 0.1524)
				(type default)
			)
			(layer "F.SilkS")
		)
		(fp_line
			(start -0.7874 0.4064)
			(end -0.7874 -0.4064)
			(stroke
				(width 0.1524)
				(type default)
			)
			(layer "F.SilkS")
		)
		(fp_line
			(start 0.7874 -0.4064)
			(end 0.7874 0.4064)
			(stroke
				(width 0.1524)
				(type default)
			)
			(layer "F.SilkS")
		)
		(fp_line
			(start 0.7874 0.4064)
			(end -0.7874 0.4064)
			(stroke
				(width 0.1524)
				(type default)
			)
			(layer "F.SilkS")
		)
		(fp_line
			(start -0.67945 -0.305054)
			(end -0.12065 -0.305054)
			(stroke
				(width 0.1)
				(type default)
			)
			(layer "F.Fab")
		)
		(fp_line
			(start -0.67945 0.3048)
			(end -0.67945 -0.305054)
			(stroke
				(width 0.1)
				(type default)
			)
			(layer "F.Fab")
		)
		(fp_line
			(start -0.12065 -0.305054)
			(end -0.12065 -0.2794)
			(stroke
				(width 0.1)
				(type default)
			)
			(layer "F.Fab")
		)
		(fp_line
			(start -0.12065 -0.2794)
			(end 0.12065 -0.2794)
			(stroke
				(width 0.1)
				(type default)
			)
			(layer "F.Fab")
		)
		(fp_line
			(start -0.12065 0.2794)
			(end -0.12065 0.3048)
			(stroke
				(width 0.1)
				(type default)
			)
			(layer "F.Fab")
		)
		(fp_line
			(start -0.12065 0.3048)
			(end -0.67945 0.3048)
			(stroke
				(width 0.1)
				(type default)
			)
			(layer "F.Fab")
		)
		(fp_line
			(start 0.120396 0.2794)
			(end -0.12065 0.2794)
			(stroke
				(width 0.1)
				(type default)
			)
			(layer "F.Fab")
		)
		(fp_line
			(start 0.120396 0.3048)
			(end 0.120396 0.2794)
			(stroke
				(width 0.1)
				(type default)
			)
			(layer "F.Fab")
		)
		(fp_line
			(start 0.12065 -0.3048)
			(end 0.67945 -0.3048)
			(stroke
				(width 0.1)
				(type default)
			)
			(layer "F.Fab")
		)
		(fp_line
			(start 0.12065 -0.2794)
			(end 0.12065 -0.3048)
			(stroke
				(width 0.1)
				(type default)
			)
			(layer "F.Fab")
		)
		(fp_line
			(start 0.67945 -0.3048)
			(end 0.67945 0.3048)
			(stroke
				(width 0.1)
				(type default)
			)
			(layer "F.Fab")
		)
		(fp_line
			(start 0.67945 0.3048)
			(end 0.120396 0.3048)
			(stroke
				(width 0.1)
				(type default)
			)
			(layer "F.Fab")
		)
		(pad "1" smd circle
			(at -0.40005 0)
			(size 0 0)
			(layers "F.Cu" "F.Mask" "F.Paste")
			(net "JTAG_FPGA_TMS")
		)
		(pad "2" smd circle
			(at 0.40005 0)
			(size 0 0)
			(layers "F.Cu" "F.Mask" "F.Paste")
			(net "GND")
		)
	)
	(footprint ""
		(layer "F.Cu")
		(at 216.567512 -231.416606 90)
		(property "Reference" "R4552"
			(at 0 0 90)
			(layer "F.SilkS")
			(hide yes)
			(effects
				(font
					(size 1.27 1.27)
				)
			)
		)
		(property "Value" ""
			(at 0 0 90)
			(layer "F.Fab")
			(effects
				(font
					(size 1.27 1.27)
				)
			)
		)
		(duplicate_pad_numbers_are_jumpers no)
		(fp_line
			(start 0.7874 -0.4064)
			(end 0.7874 0.4064)
			(stroke
				(width 0.1524)
				(type default)
			)
			(layer "F.SilkS")
		)
		(fp_line
			(start -0.7874 -0.4064)
			(end 0.7874 -0.4064)
			(stroke
				(width 0.1524)
				(type default)
			)
			(layer "F.SilkS")
		)
		(fp_line
			(start 0.7874 0.4064)
			(end -0.7874 0.4064)
			(stroke
				(width 0.1524)
				(type default)
			)
			(layer "F.SilkS")
		)
		(fp_line
			(start -0.7874 0.4064)
			(end -0.7874 -0.4064)
			(stroke
				(width 0.1524)
				(type default)
			)
			(layer "F.SilkS")
		)
		(fp_line
			(start -0.12065 -0.305054)
			(end -0.12065 -0.2794)
			(stroke
				(width 0.1)
				(type default)
			)
			(layer "F.Fab")
		)
		(fp_line
			(start -0.67945 -0.305054)
			(end -0.12065 -0.305054)
			(stroke
				(width 0.1)
				(type default)
			)
			(layer "F.Fab")
		)
		(fp_line
			(start 0.67945 -0.3048)
			(end 0.67945 0.3048)
			(stroke
				(width 0.1)
				(type default)
			)
			(layer "F.Fab")
		)
		(fp_line
			(start 0.12065 -0.3048)
			(end 0.67945 -0.3048)
			(stroke
				(width 0.1)
				(type default)
			)
			(layer "F.Fab")
		)
		(fp_line
			(start 0.12065 -0.2794)
			(end 0.12065 -0.3048)
			(stroke
				(width 0.1)
				(type default)
			)
			(layer "F.Fab")
		)
		(fp_line
			(start -0.12065 -0.2794)
			(end 0.12065 -0.2794)
			(stroke
				(width 0.1)
				(type default)
			)
			(layer "F.Fab")
		)
		(fp_line
			(start 0.120396 0.2794)
			(end -0.12065 0.2794)
			(stroke
				(width 0.1)
				(type default)
			)
			(layer "F.Fab")
		)
		(fp_line
			(start -0.12065 0.2794)
			(end -0.12065 0.3048)
			(stroke
				(width 0.1)
				(type default)
			)
			(layer "F.Fab")
		)
		(fp_line
			(start 0.67945 0.3048)
			(end 0.120396 0.3048)
			(stroke
				(width 0.1)
				(type default)
			)
			(layer "F.Fab")
		)
		(fp_line
			(start 0.120396 0.3048)
			(end 0.120396 0.2794)
			(stroke
				(width 0.1)
				(type default)
			)
			(layer "F.Fab")
		)
		(fp_line
			(start -0.12065 0.3048)
			(end -0.67945 0.3048)
			(stroke
				(width 0.1)
				(type default)
			)
			(layer "F.Fab")
		)
		(fp_line
			(start -0.67945 0.3048)
			(end -0.67945 -0.305054)
			(stroke
				(width 0.1)
				(type default)
			)
			(layer "F.Fab")
		)
		(pad "1" smd circle
			(at -0.40005 0 90)
			(size 0 0)
			(layers "F.Cu" "F.Mask" "F.Paste")
			(net "BOARD_ID2")
		)
		(pad "2" smd circle
			(at 0.40005 0 90)
			(size 0 0)
			(layers "F.Cu" "F.Mask" "F.Paste")
			(net "P3V3_AUX")
		)
	)
	(footprint ""
		(layer "F.Cu")
		(at 11.593322 -119.105426 -90)
		(property "Reference" "R5856"
			(at 0 0 270)
			(layer "F.SilkS")
			(hide yes)
			(effects
				(font
					(size 1.27 1.27)
				)
			)
		)
		(property "Value" ""
			(at 0 0 270)
			(layer "F.Fab")
			(effects
				(font
					(size 1.27 1.27)
				)
			)
		)
		(duplicate_pad_numbers_are_jumpers no)
		(fp_line
			(start -0.7874 0.4064)
			(end -0.7874 -0.4064)
			(stroke
				(width 0.1524)
				(type default)
			)
			(layer "F.SilkS")
		)
		(fp_line
			(start 0.7874 0.4064)
			(end -0.7874 0.4064)
			(stroke
				(width 0.1524)
				(type default)
			)
			(layer "F.SilkS")
		)
		(fp_line
			(start -0.7874 -0.4064)
			(end 0.7874 -0.4064)
			(stroke
				(width 0.1524)
				(type default)
			)
			(layer "F.SilkS")
		)
		(fp_line
			(start 0.7874 -0.4064)
			(end 0.7874 0.4064)
			(stroke
				(width 0.1524)
				(type default)
			)
			(layer "F.SilkS")
		)
		(fp_line
			(start -0.67945 0.3048)
			(end -0.67945 -0.305054)
			(stroke
				(width 0.1)
				(type default)
			)
			(layer "F.Fab")
		)
		(fp_line
			(start -0.12065 0.3048)
			(end -0.67945 0.3048)
			(stroke
				(width 0.1)
				(type default)
			)
			(layer "F.Fab")
		)
		(fp_line
			(start 0.120396 0.3048)
			(end 0.120396 0.2794)
			(stroke
				(width 0.1)
				(type default)
			)
			(layer "F.Fab")
		)
		(fp_line
			(start 0.67945 0.3048)
			(end 0.120396 0.3048)
			(stroke
				(width 0.1)
				(type default)
			)
			(layer "F.Fab")
		)
		(fp_line
			(start -0.12065 0.2794)
			(end -0.12065 0.3048)
			(stroke
				(width 0.1)
				(type default)
			)
			(layer "F.Fab")
		)
		(fp_line
			(start 0.120396 0.2794)
			(end -0.12065 0.2794)
			(stroke
				(width 0.1)
				(type default)
			)
			(layer "F.Fab")
		)
		(fp_line
			(start -0.12065 -0.2794)
			(end 0.12065 -0.2794)
			(stroke
				(width 0.1)
				(type default)
			)
			(layer "F.Fab")
		)
		(fp_line
			(start 0.12065 -0.2794)
			(end 0.12065 -0.3048)
			(stroke
				(width 0.1)
				(type default)
			)
			(layer "F.Fab")
		)
		(fp_line
			(start 0.12065 -0.3048)
			(end 0.67945 -0.3048)
			(stroke
				(width 0.1)
				(type default)
			)
			(layer "F.Fab")
		)
		(fp_line
			(start 0.67945 -0.3048)
			(end 0.67945 0.3048)
			(stroke
				(width 0.1)
				(type default)
			)
			(layer "F.Fab")
		)
		(fp_line
			(start -0.67945 -0.305054)
			(end -0.12065 -0.305054)
			(stroke
				(width 0.1)
				(type default)
			)
			(layer "F.Fab")
		)
		(fp_line
			(start -0.12065 -0.305054)
			(end -0.12065 -0.2794)
			(stroke
				(width 0.1)
				(type default)
			)
			(layer "F.Fab")
		)
		(pad "1" smd circle
			(at -0.40005 0 270)
			(size 0 0)
			(layers "F.Cu" "F.Mask" "F.Paste")
			(net "P3V3_AUX")
		)
		(pad "2" smd circle
			(at 0.40005 0 270)
			(size 0 0)
			(layers "F.Cu" "F.Mask" "F.Paste")
			(net "PWRGD_P3V3_NIC0_D")
		)
	)
	(footprint ""
		(layer "F.Cu")
		(at 436.95239 -114.384836 180)
		(property "Reference" "PC917"
			(at 0 0 180)
			(layer "F.SilkS")
			(hide yes)
			(effects
				(font
					(size 1.27 1.27)
				)
			)
		)
		(property "Value" ""
			(at 0 0 180)
			(layer "F.Fab")
			(effects
				(font
					(size 1.27 1.27)
				)
			)
		)
		(duplicate_pad_numbers_are_jumpers no)
		(fp_line
			(start 0.7874 0.4064)
			(end -0.7874 0.4064)
			(stroke
				(width 0.1524)
				(type default)
			)
			(layer "F.SilkS")
		)
		(fp_line
			(start 0.7874 -0.4064)
			(end 0.7874 0.4064)
			(stroke
				(width 0.1524)
				(type default)
			)
			(layer "F.SilkS")
		)
		(fp_line
			(start -0.7874 0.4064)
			(end -0.7874 -0.4064)
			(stroke
				(width 0.1524)
				(type default)
			)
			(layer "F.SilkS")
		)
		(fp_line
			(start -0.7874 -0.4064)
			(end 0.7874 -0.4064)
			(stroke
				(width 0.1524)
				(type default)
			)
			(layer "F.SilkS")
		)
		(fp_line
			(start 0.67945 0.3048)
			(end 0.120396 0.3048)
			(stroke
				(width 0.1)
				(type default)
			)
			(layer "F.Fab")
		)
		(fp_line
			(start 0.67945 -0.3048)
			(end 0.67945 0.3048)
			(stroke
				(width 0.1)
				(type default)
			)
			(layer "F.Fab")
		)
		(fp_line
			(start 0.12065 -0.2794)
			(end 0.12065 -0.3048)
			(stroke
				(width 0.1)
				(type default)
			)
			(layer "F.Fab")
		)
		(fp_line
			(start 0.12065 -0.3048)
			(end 0.67945 -0.3048)
			(stroke
				(width 0.1)
				(type default)
			)
			(layer "F.Fab")
		)
		(fp_line
			(start 0.120396 0.3048)
			(end 0.120396 0.2794)
			(stroke
				(width 0.1)
				(type default)
			)
			(layer "F.Fab")
		)
		(fp_line
			(start 0.120396 0.2794)
			(end -0.12065 0.2794)
			(stroke
				(width 0.1)
				(type default)
			)
			(layer "F.Fab")
		)
		(fp_line
			(start -0.12065 0.3048)
			(end -0.67945 0.3048)
			(stroke
				(width 0.1)
				(type default)
			)
			(layer "F.Fab")
		)
		(fp_line
			(start -0.12065 0.2794)
			(end -0.12065 0.3048)
			(stroke
				(width 0.1)
				(type default)
			)
			(layer "F.Fab")
		)
		(fp_line
			(start -0.12065 -0.2794)
			(end 0.12065 -0.2794)
			(stroke
				(width 0.1)
				(type default)
			)
			(layer "F.Fab")
		)
		(fp_line
			(start -0.12065 -0.305054)
			(end -0.12065 -0.2794)
			(stroke
				(width 0.1)
				(type default)
			)
			(layer "F.Fab")
		)
		(fp_line
			(start -0.67945 0.3048)
			(end -0.67945 -0.305054)
			(stroke
				(width 0.1)
				(type default)
			)
			(layer "F.Fab")
		)
		(fp_line
			(start -0.67945 -0.305054)
			(end -0.12065 -0.305054)
			(stroke
				(width 0.1)
				(type default)
			)
			(layer "F.Fab")
		)
		(pad "1" smd circle
			(at -0.40005 0 180)
			(size 0 0)
			(layers "F.Cu" "F.Mask" "F.Paste")
			(net "P3V3_NIC7_CO_DV_DT")
		)
		(pad "2" smd circle
			(at 0.40005 0 180)
			(size 0 0)
			(layers "F.Cu" "F.Mask" "F.Paste")
			(net "GND")
		)
	)
	(footprint ""
		(layer "F.Cu")
		(at 244.588792 -284.252162)
		(property "Reference" "PC259"
			(at 0 0 0)
			(layer "F.SilkS")
			(hide yes)
			(effects
				(font
					(size 1.27 1.27)
				)
			)
		)
		(property "Value" ""
			(at 0 0 0)
			(layer "F.Fab")
			(effects
				(font
					(size 1.27 1.27)
				)
			)
		)
		(duplicate_pad_numbers_are_jumpers no)
		(fp_line
			(start -2.750058 -1.988058)
			(end -2.750058 -0.9398)
			(stroke
				(width 0.1524)
				(type default)
			)
			(layer "F.SilkS")
		)
		(fp_line
			(start -2.750058 0.9398)
			(end -2.750058 1.988058)
			(stroke
				(width 0.1524)
				(type default)
			)
			(layer "F.SilkS")
		)
		(fp_line
			(start -2.750058 1.988058)
			(end -1.988058 2.750058)
			(stroke
				(width 0.1524)
				(type default)
			)
			(layer "F.SilkS")
		)
		(fp_line
			(start -1.988058 -2.750058)
			(end -2.750058 -1.988058)
			(stroke
				(width 0.1524)
				(type default)
			)
			(layer "F.SilkS")
		)
		(fp_line
			(start -1.988058 2.750058)
			(end 2.750058 2.750058)
			(stroke
				(width 0.1524)
				(type default)
			)
			(layer "F.SilkS")
		)
		(fp_line
			(start 2.750058 -2.750058)
			(end -1.988058 -2.750058)
			(stroke
				(width 0.1524)
				(type default)
			)
			(layer "F.SilkS")
		)
		(fp_line
			(start 2.750058 -0.9398)
			(end 2.750058 -2.750058)
			(stroke
				(width 0.1524)
				(type default)
			)
			(layer "F.SilkS")
		)
		(fp_line
			(start 2.750058 2.750058)
			(end 2.750058 0.9398)
			(stroke
				(width 0.1524)
				(type default)
			)
			(layer "F.SilkS")
		)
		(fp_line
			(start -2.750058 -2.750058)
			(end -2.750058 2.750058)
			(stroke
				(width 0.1)
				(type default)
			)
			(layer "F.Fab")
		)
		(fp_line
			(start -2.750058 2.750058)
			(end 2.750058 2.750058)
			(stroke
				(width 0.1)
				(type default)
			)
			(layer "F.Fab")
		)
		(fp_line
			(start 2.750058 -2.750058)
			(end -2.750058 -2.750058)
			(stroke
				(width 0.1)
				(type default)
			)
			(layer "F.Fab")
		)
		(fp_line
			(start 2.750058 2.750058)
			(end 2.750058 -2.750058)
			(stroke
				(width 0.1)
				(type default)
			)
			(layer "F.Fab")
		)
		(pad "1" smd rect
			(at -2.199894 0 90)
			(size 1.6002 3.0226)
			(layers "F.Cu" "F.Mask" "F.Paste")
			(net "P1V25_PEX2_R")
		)
		(pad "2" smd rect
			(at 2.199894 0 90)
			(size 1.6002 3.0226)
			(layers "F.Cu" "F.Mask" "F.Paste")
			(net "GND")
		)
	)
	(footprint ""
		(layer "F.Cu")
		(at 484.9495 -548.246554 180)
		(property "Reference" "SCREW_SSD3_2"
			(at -5.207 -1.402334 0)
			(unlocked yes)
			(layer "B.SilkS")
			(effects
				(font
					(size 0.7874 0.5842)
					(thickness 0.1524)
				)
				(justify mirror)
			)
		)
		(property "Value" ""
			(at 0 0 180)
			(layer "F.Fab")
			(effects
				(font
					(size 1.27 1.27)
				)
			)
		)
		(duplicate_pad_numbers_are_jumpers no)
		(pad "1" thru_hole circle
			(at 0 0 180)
			(size 0.4572 0.4572)
			(drill 0.2032)
			(layers "*.Cu" "*.Mask")
			(remove_unused_layers no)
			(net "Net_9137")
			(clearance 0.127)
			(thermal_gap 0.127)
			(padstack
				(mode front_inner_back)
				(layer "Inner"
					(shape circle)
					(size 0.4572 0.4572)
					(clearance 0.127)
				)
				(layer "B.Cu"
					(shape circle)
					(size 0.508 0.508)
					(clearance 0.1016)
				)
			)
		)
	)
	(footprint ""
		(layer "F.Cu")
		(at 315.586364 -356.244906 90)
		(property "Reference" "C545"
			(at 0 0 90)
			(layer "F.SilkS")
			(hide yes)
			(effects
				(font
					(size 1.27 1.27)
				)
			)
		)
		(property "Value" ""
			(at 0 0 90)
			(layer "F.Fab")
			(effects
				(font
					(size 1.27 1.27)
				)
			)
		)
		(duplicate_pad_numbers_are_jumpers no)
		(fp_line
			(start 0.299974 -0.150114)
			(end 0.299974 0.150114)
			(stroke
				(width 0.1)
				(type default)
			)
			(layer "F.Fab")
		)
		(fp_line
			(start -0.299974 -0.150114)
			(end 0.299974 -0.150114)
			(stroke
				(width 0.1)
				(type default)
			)
			(layer "F.Fab")
		)
		(fp_line
			(start 0.299974 0.150114)
			(end -0.299974 0.150114)
			(stroke
				(width 0.1)
				(type default)
			)
			(layer "F.Fab")
		)
		(fp_line
			(start -0.299974 0.150114)
			(end -0.299974 -0.150114)
			(stroke
				(width 0.1)
				(type default)
			)
			(layer "F.Fab")
		)
		(pad "1" smd rect
			(at -0.2667 0 90)
			(size 0.3048 0.381)
			(layers "F.Cu" "F.Mask" "F.Paste")
			(net "P5E_PEX2_STN5_TX_DP<82>")
		)
		(pad "2" smd rect
			(at 0.2667 0 90)
			(size 0.3048 0.381)
			(layers "F.Cu" "F.Mask" "F.Paste")
			(net "P5E_PEX2_STN5_TX_C_DP<82>")
		)
	)
	(footprint ""
		(layer "F.Cu")
		(at 393.669266 -87.214202 180)
		(property "Reference" "R1778"
			(at 0 0 180)
			(layer "F.SilkS")
			(hide yes)
			(effects
				(font
					(size 1.27 1.27)
				)
			)
		)
		(property "Value" ""
			(at 0 0 180)
			(layer "F.Fab")
			(effects
				(font
					(size 1.27 1.27)
				)
			)
		)
		(duplicate_pad_numbers_are_jumpers no)
		(fp_line
			(start 0.7874 0.4064)
			(end -0.7874 0.4064)
			(stroke
				(width 0.1524)
				(type default)
			)
			(layer "F.SilkS")
		)
		(fp_line
			(start 0.7874 -0.4064)
			(end 0.7874 0.4064)
			(stroke
				(width 0.1524)
				(type default)
			)
			(layer "F.SilkS")
		)
		(fp_line
			(start -0.7874 0.4064)
			(end -0.7874 -0.4064)
			(stroke
				(width 0.1524)
				(type default)
			)
			(layer "F.SilkS")
		)
		(fp_line
			(start -0.7874 -0.4064)
			(end 0.7874 -0.4064)
			(stroke
				(width 0.1524)
				(type default)
			)
			(layer "F.SilkS")
		)
		(fp_line
			(start 0.67945 0.3048)
			(end 0.120396 0.3048)
			(stroke
				(width 0.1)
				(type default)
			)
			(layer "F.Fab")
		)
		(fp_line
			(start 0.67945 -0.3048)
			(end 0.67945 0.3048)
			(stroke
				(width 0.1)
				(type default)
			)
			(layer "F.Fab")
		)
		(fp_line
			(start 0.12065 -0.2794)
			(end 0.12065 -0.3048)
			(stroke
				(width 0.1)
				(type default)
			)
			(layer "F.Fab")
		)
		(fp_line
			(start 0.12065 -0.3048)
			(end 0.67945 -0.3048)
			(stroke
				(width 0.1)
				(type default)
			)
			(layer "F.Fab")
		)
		(fp_line
			(start 0.120396 0.3048)
			(end 0.120396 0.2794)
			(stroke
				(width 0.1)
				(type default)
			)
			(layer "F.Fab")
		)
		(fp_line
			(start 0.120396 0.2794)
			(end -0.12065 0.2794)
			(stroke
				(width 0.1)
				(type default)
			)
			(layer "F.Fab")
		)
		(fp_line
			(start -0.12065 0.3048)
			(end -0.67945 0.3048)
			(stroke
				(width 0.1)
				(type default)
			)
			(layer "F.Fab")
		)
		(fp_line
			(start -0.12065 0.2794)
			(end -0.12065 0.3048)
			(stroke
				(width 0.1)
				(type default)
			)
			(layer "F.Fab")
		)
		(fp_line
			(start -0.12065 -0.2794)
			(end 0.12065 -0.2794)
			(stroke
				(width 0.1)
				(type default)
			)
			(layer "F.Fab")
		)
		(fp_line
			(start -0.12065 -0.305054)
			(end -0.12065 -0.2794)
			(stroke
				(width 0.1)
				(type default)
			)
			(layer "F.Fab")
		)
		(fp_line
			(start -0.67945 0.3048)
			(end -0.67945 -0.305054)
			(stroke
				(width 0.1)
				(type default)
			)
			(layer "F.Fab")
		)
		(fp_line
			(start -0.67945 -0.305054)
			(end -0.12065 -0.305054)
			(stroke
				(width 0.1)
				(type default)
			)
			(layer "F.Fab")
		)
		(pad "1" smd circle
			(at -0.40005 0 180)
			(size 0 0)
			(layers "F.Cu" "F.Mask" "F.Paste")
			(net "SMB_BIC_I2C6_MUX_FRU_R_SDA")
		)
		(pad "2" smd circle
			(at 0.40005 0 180)
			(size 0 0)
			(layers "F.Cu" "F.Mask" "F.Paste")
			(net "SMB_BIC_I2C6_MUX_FRU_SDA")
		)
	)
	(footprint ""
		(layer "F.Cu")
		(at 70.673722 -343.952322 90)
		(property "Reference" "C119"
			(at 0 0 90)
			(layer "F.SilkS")
			(hide yes)
			(effects
				(font
					(size 1.27 1.27)
				)
			)
		)
		(property "Value" ""
			(at 0 0 90)
			(layer "F.Fab")
			(effects
				(font
					(size 1.27 1.27)
				)
			)
		)
		(duplicate_pad_numbers_are_jumpers no)
		(fp_line
			(start 0.299974 -0.150114)
			(end 0.299974 0.150114)
			(stroke
				(width 0.1)
				(type default)
			)
			(layer "F.Fab")
		)
		(fp_line
			(start -0.299974 -0.150114)
			(end 0.299974 -0.150114)
			(stroke
				(width 0.1)
				(type default)
			)
			(layer "F.Fab")
		)
		(fp_line
			(start 0.299974 0.150114)
			(end -0.299974 0.150114)
			(stroke
				(width 0.1)
				(type default)
			)
			(layer "F.Fab")
		)
		(fp_line
			(start -0.299974 0.150114)
			(end -0.299974 -0.150114)
			(stroke
				(width 0.1)
				(type default)
			)
			(layer "F.Fab")
		)
		(pad "1" smd rect
			(at -0.2667 0 90)
			(size 0.3048 0.381)
			(layers "F.Cu" "F.Mask" "F.Paste")
			(net "P5E_PEX0_STN5_TX_DP<84>")
		)
		(pad "2" smd rect
			(at 0.2667 0 90)
			(size 0.3048 0.381)
			(layers "F.Cu" "F.Mask" "F.Paste")
			(net "P5E_PEX0_STN5_TX_C_DP<84>")
		)
	)
	(footprint ""
		(layer "F.Cu")
		(at 152.738328 -134.923276)
		(property "Reference" "C247"
			(at 0 0 0)
			(layer "F.SilkS")
			(hide yes)
			(effects
				(font
					(size 1.27 1.27)
				)
			)
		)
		(property "Value" ""
			(at 0 0 0)
			(layer "F.Fab")
			(effects
				(font
					(size 1.27 1.27)
				)
			)
		)
		(duplicate_pad_numbers_are_jumpers no)
		(fp_line
			(start -0.299974 -0.150114)
			(end 0.299974 -0.150114)
			(stroke
				(width 0.1)
				(type default)
			)
			(layer "F.Fab")
		)
		(fp_line
			(start -0.299974 0.150114)
			(end -0.299974 -0.150114)
			(stroke
				(width 0.1)
				(type default)
			)
			(layer "F.Fab")
		)
		(fp_line
			(start 0.299974 -0.150114)
			(end 0.299974 0.150114)
			(stroke
				(width 0.1)
				(type default)
			)
			(layer "F.Fab")
		)
		(fp_line
			(start 0.299974 0.150114)
			(end -0.299974 0.150114)
			(stroke
				(width 0.1)
				(type default)
			)
			(layer "F.Fab")
		)
		(pad "1" smd rect
			(at -0.2667 0)
			(size 0.3048 0.381)
			(layers "F.Cu" "F.Mask" "F.Paste")
			(net "P5E_PEX1_STN1_TX_DN<30>")
		)
		(pad "2" smd rect
			(at 0.2667 0)
			(size 0.3048 0.381)
			(layers "F.Cu" "F.Mask" "F.Paste")
			(net "P5E_PEX1_STN1_TX_C_DN<30>")
		)
	)
	(footprint ""
		(layer "F.Cu")
		(at 80.019398 -118.670324 180)
		(property "Reference" "C32"
			(at 0 0 180)
			(layer "F.SilkS")
			(hide yes)
			(effects
				(font
					(size 1.27 1.27)
				)
			)
		)
		(property "Value" ""
			(at 0 0 180)
			(layer "F.Fab")
			(effects
				(font
					(size 1.27 1.27)
				)
			)
		)
		(duplicate_pad_numbers_are_jumpers no)
		(fp_line
			(start 0.299974 0.150114)
			(end -0.299974 0.150114)
			(stroke
				(width 0.1)
				(type default)
			)
			(layer "F.Fab")
		)
		(fp_line
			(start 0.299974 -0.150114)
			(end 0.299974 0.150114)
			(stroke
				(width 0.1)
				(type default)
			)
			(layer "F.Fab")
		)
		(fp_line
			(start -0.299974 0.150114)
			(end -0.299974 -0.150114)
			(stroke
				(width 0.1)
				(type default)
			)
			(layer "F.Fab")
		)
		(fp_line
			(start -0.299974 -0.150114)
			(end 0.299974 -0.150114)
			(stroke
				(width 0.1)
				(type default)
			)
			(layer "F.Fab")
		)
		(pad "1" smd rect
			(at -0.2667 0 180)
			(size 0.3048 0.381)
			(layers "F.Cu" "F.Mask" "F.Paste")
			(net "P5E_PEX0_STN0_TX_DN<0>")
		)
		(pad "2" smd rect
			(at 0.2667 0 180)
			(size 0.3048 0.381)
			(layers "F.Cu" "F.Mask" "F.Paste")
			(net "P5E_PEX0_STN0_TX_C_DN<0>")
		)
	)
	(footprint ""
		(layer "F.Cu")
		(at 88.65235 -116.416836 180)
		(property "Reference" "PC662"
			(at 0 0 180)
			(layer "F.SilkS")
			(hide yes)
			(effects
				(font
					(size 1.27 1.27)
				)
			)
		)
		(property "Value" ""
			(at 0 0 180)
			(layer "F.Fab")
			(effects
				(font
					(size 1.27 1.27)
				)
			)
		)
		(duplicate_pad_numbers_are_jumpers no)
		(fp_line
			(start 0.7874 0.4064)
			(end -0.7874 0.4064)
			(stroke
				(width 0.1524)
				(type default)
			)
			(layer "F.SilkS")
		)
		(fp_line
			(start 0.7874 -0.4064)
			(end 0.7874 0.4064)
			(stroke
				(width 0.1524)
				(type default)
			)
			(layer "F.SilkS")
		)
		(fp_line
			(start -0.7874 0.4064)
			(end -0.7874 -0.4064)
			(stroke
				(width 0.1524)
				(type default)
			)
			(layer "F.SilkS")
		)
		(fp_line
			(start -0.7874 -0.4064)
			(end 0.7874 -0.4064)
			(stroke
				(width 0.1524)
				(type default)
			)
			(layer "F.SilkS")
		)
		(fp_line
			(start 0.67945 0.3048)
			(end 0.120396 0.3048)
			(stroke
				(width 0.1)
				(type default)
			)
			(layer "F.Fab")
		)
		(fp_line
			(start 0.67945 -0.3048)
			(end 0.67945 0.3048)
			(stroke
				(width 0.1)
				(type default)
			)
			(layer "F.Fab")
		)
		(fp_line
			(start 0.12065 -0.2794)
			(end 0.12065 -0.3048)
			(stroke
				(width 0.1)
				(type default)
			)
			(layer "F.Fab")
		)
		(fp_line
			(start 0.12065 -0.3048)
			(end 0.67945 -0.3048)
			(stroke
				(width 0.1)
				(type default)
			)
			(layer "F.Fab")
		)
		(fp_line
			(start 0.120396 0.3048)
			(end 0.120396 0.2794)
			(stroke
				(width 0.1)
				(type default)
			)
			(layer "F.Fab")
		)
		(fp_line
			(start 0.120396 0.2794)
			(end -0.12065 0.2794)
			(stroke
				(width 0.1)
				(type default)
			)
			(layer "F.Fab")
		)
		(fp_line
			(start -0.12065 0.3048)
			(end -0.67945 0.3048)
			(stroke
				(width 0.1)
				(type default)
			)
			(layer "F.Fab")
		)
		(fp_line
			(start -0.12065 0.2794)
			(end -0.12065 0.3048)
			(stroke
				(width 0.1)
				(type default)
			)
			(layer "F.Fab")
		)
		(fp_line
			(start -0.12065 -0.2794)
			(end 0.12065 -0.2794)
			(stroke
				(width 0.1)
				(type default)
			)
			(layer "F.Fab")
		)
		(fp_line
			(start -0.12065 -0.305054)
			(end -0.12065 -0.2794)
			(stroke
				(width 0.1)
				(type default)
			)
			(layer "F.Fab")
		)
		(fp_line
			(start -0.67945 0.3048)
			(end -0.67945 -0.305054)
			(stroke
				(width 0.1)
				(type default)
			)
			(layer "F.Fab")
		)
		(fp_line
			(start -0.67945 -0.305054)
			(end -0.12065 -0.305054)
			(stroke
				(width 0.1)
				(type default)
			)
			(layer "F.Fab")
		)
		(pad "1" smd circle
			(at -0.40005 0 180)
			(size 0 0)
			(layers "F.Cu" "F.Mask" "F.Paste")
			(net "P3V3_NIC1_CO_GATE")
		)
		(pad "2" smd circle
			(at 0.40005 0 180)
			(size 0 0)
			(layers "F.Cu" "F.Mask" "F.Paste")
			(net "GND")
		)
	)
	(footprint ""
		(layer "F.Cu")
		(at 263.179814 -310.28894 -135)
		(property "Reference" "R1331"
			(at 0 0 225)
			(layer "F.SilkS")
			(hide yes)
			(effects
				(font
					(size 1.27 1.27)
				)
			)
		)
		(property "Value" ""
			(at 0 0 225)
			(layer "F.Fab")
			(effects
				(font
					(size 1.27 1.27)
				)
			)
		)
		(duplicate_pad_numbers_are_jumpers no)
		(fp_line
			(start 0.787389 0.406267)
			(end -0.787389 0.406267)
			(stroke
				(width 0.1524)
				(type default)
			)
			(layer "F.SilkS")
		)
		(fp_line
			(start 0.787389 -0.406267)
			(end 0.787389 0.406267)
			(stroke
				(width 0.1524)
				(type default)
			)
			(layer "F.SilkS")
		)
		(fp_line
			(start -0.787389 0.406267)
			(end -0.787389 -0.406267)
			(stroke
				(width 0.1524)
				(type default)
			)
			(layer "F.SilkS")
		)
		(fp_line
			(start -0.787389 -0.406267)
			(end 0.787389 -0.406267)
			(stroke
				(width 0.1524)
				(type default)
			)
			(layer "F.SilkS")
		)
		(fp_line
			(start 0.679446 0.30479)
			(end 0.120515 0.30479)
			(stroke
				(width 0.1)
				(type default)
			)
			(layer "F.Fab")
		)
		(fp_line
			(start 0.120515 0.30479)
			(end 0.120335 0.279466)
			(stroke
				(width 0.1)
				(type default)
			)
			(layer "F.Fab")
		)
		(fp_line
			(start 0.120335 0.279466)
			(end -0.120695 0.279466)
			(stroke
				(width 0.1)
				(type default)
			)
			(layer "F.Fab")
		)
		(fp_line
			(start 0.679446 -0.30479)
			(end 0.679446 0.30479)
			(stroke
				(width 0.1)
				(type default)
			)
			(layer "F.Fab")
		)
		(fp_line
			(start -0.120515 0.30479)
			(end -0.679446 0.30479)
			(stroke
				(width 0.1)
				(type default)
			)
			(layer "F.Fab")
		)
		(fp_line
			(start -0.120695 0.279466)
			(end -0.120515 0.30479)
			(stroke
				(width 0.1)
				(type default)
			)
			(layer "F.Fab")
		)
		(fp_line
			(start 0.120695 -0.279466)
			(end 0.120515 -0.30479)
			(stroke
				(width 0.1)
				(type default)
			)
			(layer "F.Fab")
		)
		(fp_line
			(start 0.120515 -0.30479)
			(end 0.679446 -0.30479)
			(stroke
				(width 0.1)
				(type default)
			)
			(layer "F.Fab")
		)
		(fp_line
			(start -0.679446 0.30479)
			(end -0.679446 -0.305149)
			(stroke
				(width 0.1)
				(type default)
			)
			(layer "F.Fab")
		)
		(fp_line
			(start -0.120695 -0.279466)
			(end 0.120695 -0.279466)
			(stroke
				(width 0.1)
				(type default)
			)
			(layer "F.Fab")
		)
		(fp_line
			(start -0.120695 -0.304969)
			(end -0.120695 -0.279466)
			(stroke
				(width 0.1)
				(type default)
			)
			(layer "F.Fab")
		)
		(fp_line
			(start -0.679446 -0.305149)
			(end -0.120695 -0.304969)
			(stroke
				(width 0.1)
				(type default)
			)
			(layer "F.Fab")
		)
		(pad "1" smd circle
			(at -0.40005 0 225)
			(size 0 0)
			(layers "F.Cu" "F.Mask" "F.Paste")
			(net "PEX2_DBG_MODE0")
		)
		(pad "2" smd circle
			(at 0.40005 0 225)
			(size 0 0)
			(layers "F.Cu" "F.Mask" "F.Paste")
			(net "P1V8_PEX")
		)
	)
	(footprint ""
		(layer "F.Cu")
		(at 128.848612 -162.003994 90)
		(property "Reference" "PR6899"
			(at 0 0 90)
			(layer "F.SilkS")
			(hide yes)
			(effects
				(font
					(size 1.27 1.27)
				)
			)
		)
		(property "Value" ""
			(at 0 0 90)
			(layer "F.Fab")
			(effects
				(font
					(size 1.27 1.27)
				)
			)
		)
		(duplicate_pad_numbers_are_jumpers no)
		(fp_line
			(start 0.7874 -0.4064)
			(end 0.7874 0.4064)
			(stroke
				(width 0.1524)
				(type default)
			)
			(layer "F.SilkS")
		)
		(fp_line
			(start -0.7874 -0.4064)
			(end 0.7874 -0.4064)
			(stroke
				(width 0.1524)
				(type default)
			)
			(layer "F.SilkS")
		)
		(fp_line
			(start 0.7874 0.4064)
			(end -0.7874 0.4064)
			(stroke
				(width 0.1524)
				(type default)
			)
			(layer "F.SilkS")
		)
		(fp_line
			(start -0.7874 0.4064)
			(end -0.7874 -0.4064)
			(stroke
				(width 0.1524)
				(type default)
			)
			(layer "F.SilkS")
		)
		(fp_line
			(start -0.12065 -0.305054)
			(end -0.12065 -0.2794)
			(stroke
				(width 0.1)
				(type default)
			)
			(layer "F.Fab")
		)
		(fp_line
			(start -0.67945 -0.305054)
			(end -0.12065 -0.305054)
			(stroke
				(width 0.1)
				(type default)
			)
			(layer "F.Fab")
		)
		(fp_line
			(start 0.67945 -0.3048)
			(end 0.67945 0.3048)
			(stroke
				(width 0.1)
				(type default)
			)
			(layer "F.Fab")
		)
		(fp_line
			(start 0.12065 -0.3048)
			(end 0.67945 -0.3048)
			(stroke
				(width 0.1)
				(type default)
			)
			(layer "F.Fab")
		)
		(fp_line
			(start 0.12065 -0.2794)
			(end 0.12065 -0.3048)
			(stroke
				(width 0.1)
				(type default)
			)
			(layer "F.Fab")
		)
		(fp_line
			(start -0.12065 -0.2794)
			(end 0.12065 -0.2794)
			(stroke
				(width 0.1)
				(type default)
			)
			(layer "F.Fab")
		)
		(fp_line
			(start 0.120396 0.2794)
			(end -0.12065 0.2794)
			(stroke
				(width 0.1)
				(type default)
			)
			(layer "F.Fab")
		)
		(fp_line
			(start -0.12065 0.2794)
			(end -0.12065 0.3048)
			(stroke
				(width 0.1)
				(type default)
			)
			(layer "F.Fab")
		)
		(fp_line
			(start 0.67945 0.3048)
			(end 0.120396 0.3048)
			(stroke
				(width 0.1)
				(type default)
			)
			(layer "F.Fab")
		)
		(fp_line
			(start 0.120396 0.3048)
			(end 0.120396 0.2794)
			(stroke
				(width 0.1)
				(type default)
			)
			(layer "F.Fab")
		)
		(fp_line
			(start -0.12065 0.3048)
			(end -0.67945 0.3048)
			(stroke
				(width 0.1)
				(type default)
			)
			(layer "F.Fab")
		)
		(fp_line
			(start -0.67945 0.3048)
			(end -0.67945 -0.305054)
			(stroke
				(width 0.1)
				(type default)
			)
			(layer "F.Fab")
		)
		(pad "1" smd circle
			(at -0.40005 0 90)
			(size 0 0)
			(layers "F.Cu" "F.Mask" "F.Paste")
			(net "P12V_NIC2_CO_ISET")
		)
		(pad "2" smd circle
			(at 0.40005 0 90)
			(size 0 0)
			(layers "F.Cu" "F.Mask" "F.Paste")
			(net "GND")
		)
	)
	(footprint ""
		(layer "F.Cu")
		(at 26.930096 -281.203908 -90)
		(property "Reference" "C3037"
			(at 0 0 270)
			(layer "F.SilkS")
			(hide yes)
			(effects
				(font
					(size 1.27 1.27)
				)
			)
		)
		(property "Value" ""
			(at 0 0 270)
			(layer "F.Fab")
			(effects
				(font
					(size 1.27 1.27)
				)
			)
		)
		(duplicate_pad_numbers_are_jumpers no)
		(fp_line
			(start -1.2954 0.5842)
			(end -1.2954 -0.5842)
			(stroke
				(width 0.1524)
				(type default)
			)
			(layer "F.SilkS")
		)
		(fp_line
			(start 1.2954 0.5842)
			(end -1.2954 0.5842)
			(stroke
				(width 0.1524)
				(type default)
			)
			(layer "F.SilkS")
		)
		(fp_line
			(start -1.2954 -0.5842)
			(end 1.2954 -0.5842)
			(stroke
				(width 0.1524)
				(type default)
			)
			(layer "F.SilkS")
		)
		(fp_line
			(start 1.2954 -0.5842)
			(end 1.2954 0.5842)
			(stroke
				(width 0.1524)
				(type default)
			)
			(layer "F.SilkS")
		)
		(fp_line
			(start -0.8636 0.4572)
			(end -0.8636 0.4064)
			(stroke
				(width 0.1)
				(type default)
			)
			(layer "F.Fab")
		)
		(fp_line
			(start 0.8636 0.4572)
			(end -0.8636 0.4572)
			(stroke
				(width 0.1)
				(type default)
			)
			(layer "F.Fab")
		)
		(fp_line
			(start -1.1938 0.4064)
			(end -1.1938 -0.4064)
			(stroke
				(width 0.1)
				(type default)
			)
			(layer "F.Fab")
		)
		(fp_line
			(start -0.8636 0.4064)
			(end -1.1938 0.4064)
			(stroke
				(width 0.1)
				(type default)
			)
			(layer "F.Fab")
		)
		(fp_line
			(start 0.8636 0.4064)
			(end 0.8636 0.4572)
			(stroke
				(width 0.1)
				(type default)
			)
			(layer "F.Fab")
		)
		(fp_line
			(start 1.1938 0.4064)
			(end 0.8636 0.4064)
			(stroke
				(width 0.1)
				(type default)
			)
			(layer "F.Fab")
		)
		(fp_line
			(start -1.1938 -0.4064)
			(end -0.8636 -0.4064)
			(stroke
				(width 0.1)
				(type default)
			)
			(layer "F.Fab")
		)
		(fp_line
			(start -0.8636 -0.4064)
			(end -0.8636 -0.4572)
			(stroke
				(width 0.1)
				(type default)
			)
			(layer "F.Fab")
		)
		(fp_line
			(start 0.8636 -0.4064)
			(end 1.1938 -0.4064)
			(stroke
				(width 0.1)
				(type default)
			)
			(layer "F.Fab")
		)
		(fp_line
			(start 1.1938 -0.4064)
			(end 1.1938 0.4064)
			(stroke
				(width 0.1)
				(type default)
			)
			(layer "F.Fab")
		)
		(fp_line
			(start -0.8636 -0.4572)
			(end 0.8636 -0.4572)
			(stroke
				(width 0.1)
				(type default)
			)
			(layer "F.Fab")
		)
		(fp_line
			(start 0.8636 -0.4572)
			(end 0.8636 -0.4064)
			(stroke
				(width 0.1)
				(type default)
			)
			(layer "F.Fab")
		)
		(pad "1" smd rect
			(at -0.7366 0 180)
			(size 0.7112 0.8128)
			(layers "F.Cu" "F.Mask" "F.Paste")
			(net "P1V8_PLL0_PEX0")
		)
		(pad "2" smd rect
			(at 0.7366 0 180)
			(size 0.7112 0.8128)
			(layers "F.Cu" "F.Mask" "F.Paste")
			(net "GND")
		)
	)
	(footprint ""
		(layer "F.Cu")
		(at 86.943692 -302.873664 -90)
		(property "Reference" "R6806"
			(at 0 0 270)
			(layer "F.SilkS")
			(hide yes)
			(effects
				(font
					(size 1.27 1.27)
				)
			)
		)
		(property "Value" ""
			(at 0 0 270)
			(layer "F.Fab")
			(effects
				(font
					(size 1.27 1.27)
				)
			)
		)
		(duplicate_pad_numbers_are_jumpers no)
		(fp_line
			(start -0.7874 0.4064)
			(end -0.7874 -0.4064)
			(stroke
				(width 0.1524)
				(type default)
			)
			(layer "F.SilkS")
		)
		(fp_line
			(start 0.7874 0.4064)
			(end -0.7874 0.4064)
			(stroke
				(width 0.1524)
				(type default)
			)
			(layer "F.SilkS")
		)
		(fp_line
			(start -0.7874 -0.4064)
			(end 0.7874 -0.4064)
			(stroke
				(width 0.1524)
				(type default)
			)
			(layer "F.SilkS")
		)
		(fp_line
			(start 0.7874 -0.4064)
			(end 0.7874 0.4064)
			(stroke
				(width 0.1524)
				(type default)
			)
			(layer "F.SilkS")
		)
		(fp_line
			(start -0.67945 0.3048)
			(end -0.67945 -0.305054)
			(stroke
				(width 0.1)
				(type default)
			)
			(layer "F.Fab")
		)
		(fp_line
			(start -0.12065 0.3048)
			(end -0.67945 0.3048)
			(stroke
				(width 0.1)
				(type default)
			)
			(layer "F.Fab")
		)
		(fp_line
			(start 0.120396 0.3048)
			(end 0.120396 0.2794)
			(stroke
				(width 0.1)
				(type default)
			)
			(layer "F.Fab")
		)
		(fp_line
			(start 0.67945 0.3048)
			(end 0.120396 0.3048)
			(stroke
				(width 0.1)
				(type default)
			)
			(layer "F.Fab")
		)
		(fp_line
			(start -0.12065 0.2794)
			(end -0.12065 0.3048)
			(stroke
				(width 0.1)
				(type default)
			)
			(layer "F.Fab")
		)
		(fp_line
			(start 0.120396 0.2794)
			(end -0.12065 0.2794)
			(stroke
				(width 0.1)
				(type default)
			)
			(layer "F.Fab")
		)
		(fp_line
			(start -0.12065 -0.2794)
			(end 0.12065 -0.2794)
			(stroke
				(width 0.1)
				(type default)
			)
			(layer "F.Fab")
		)
		(fp_line
			(start 0.12065 -0.2794)
			(end 0.12065 -0.3048)
			(stroke
				(width 0.1)
				(type default)
			)
			(layer "F.Fab")
		)
		(fp_line
			(start 0.12065 -0.3048)
			(end 0.67945 -0.3048)
			(stroke
				(width 0.1)
				(type default)
			)
			(layer "F.Fab")
		)
		(fp_line
			(start 0.67945 -0.3048)
			(end 0.67945 0.3048)
			(stroke
				(width 0.1)
				(type default)
			)
			(layer "F.Fab")
		)
		(fp_line
			(start -0.67945 -0.305054)
			(end -0.12065 -0.305054)
			(stroke
				(width 0.1)
				(type default)
			)
			(layer "F.Fab")
		)
		(fp_line
			(start -0.12065 -0.305054)
			(end -0.12065 -0.2794)
			(stroke
				(width 0.1)
				(type default)
			)
			(layer "F.Fab")
		)
		(pad "1" smd circle
			(at -0.40005 0 270)
			(size 0 0)
			(layers "F.Cu" "F.Mask" "F.Paste")
			(net "SMB_PEX0_R_SCL")
		)
		(pad "2" smd circle
			(at 0.40005 0 270)
			(size 0 0)
			(layers "F.Cu" "F.Mask" "F.Paste")
			(net "SMB_PEX0_SCL")
		)
	)
	(footprint ""
		(layer "F.Cu")
		(at 268.838426 -108.29544)
		(property "Reference" "C475"
			(at 0 0 0)
			(layer "F.SilkS")
			(hide yes)
			(effects
				(font
					(size 1.27 1.27)
				)
			)
		)
		(property "Value" ""
			(at 0 0 0)
			(layer "F.Fab")
			(effects
				(font
					(size 1.27 1.27)
				)
			)
		)
		(duplicate_pad_numbers_are_jumpers no)
		(fp_line
			(start -0.299974 -0.150114)
			(end 0.299974 -0.150114)
			(stroke
				(width 0.1)
				(type default)
			)
			(layer "F.Fab")
		)
		(fp_line
			(start -0.299974 0.150114)
			(end -0.299974 -0.150114)
			(stroke
				(width 0.1)
				(type default)
			)
			(layer "F.Fab")
		)
		(fp_line
			(start 0.299974 -0.150114)
			(end 0.299974 0.150114)
			(stroke
				(width 0.1)
				(type default)
			)
			(layer "F.Fab")
		)
		(fp_line
			(start 0.299974 0.150114)
			(end -0.299974 0.150114)
			(stroke
				(width 0.1)
				(type default)
			)
			(layer "F.Fab")
		)
		(pad "1" smd rect
			(at -0.2667 0)
			(size 0.3048 0.381)
			(layers "F.Cu" "F.Mask" "F.Paste")
			(net "P5E_PEX2_STN1_TX_DN<21>")
		)
		(pad "2" smd rect
			(at 0.2667 0)
			(size 0.3048 0.381)
			(layers "F.Cu" "F.Mask" "F.Paste")
			(net "P5E_PEX2_STN1_TX_C_DN<21>")
		)
	)
	(footprint ""
		(layer "F.Cu")
		(at 450.230494 -121.80824 180)
		(property "Reference" "R6053"
			(at 0 0 180)
			(layer "F.SilkS")
			(hide yes)
			(effects
				(font
					(size 1.27 1.27)
				)
			)
		)
		(property "Value" ""
			(at 0 0 180)
			(layer "F.Fab")
			(effects
				(font
					(size 1.27 1.27)
				)
			)
		)
		(duplicate_pad_numbers_are_jumpers no)
		(fp_line
			(start 0.7874 0.4064)
			(end -0.7874 0.4064)
			(stroke
				(width 0.1524)
				(type default)
			)
			(layer "F.SilkS")
		)
		(fp_line
			(start 0.7874 -0.4064)
			(end 0.7874 0.4064)
			(stroke
				(width 0.1524)
				(type default)
			)
			(layer "F.SilkS")
		)
		(fp_line
			(start -0.7874 0.4064)
			(end -0.7874 -0.4064)
			(stroke
				(width 0.1524)
				(type default)
			)
			(layer "F.SilkS")
		)
		(fp_line
			(start -0.7874 -0.4064)
			(end 0.7874 -0.4064)
			(stroke
				(width 0.1524)
				(type default)
			)
			(layer "F.SilkS")
		)
		(fp_line
			(start 0.67945 0.3048)
			(end 0.120396 0.3048)
			(stroke
				(width 0.1)
				(type default)
			)
			(layer "F.Fab")
		)
		(fp_line
			(start 0.67945 -0.3048)
			(end 0.67945 0.3048)
			(stroke
				(width 0.1)
				(type default)
			)
			(layer "F.Fab")
		)
		(fp_line
			(start 0.12065 -0.2794)
			(end 0.12065 -0.3048)
			(stroke
				(width 0.1)
				(type default)
			)
			(layer "F.Fab")
		)
		(fp_line
			(start 0.12065 -0.3048)
			(end 0.67945 -0.3048)
			(stroke
				(width 0.1)
				(type default)
			)
			(layer "F.Fab")
		)
		(fp_line
			(start 0.120396 0.3048)
			(end 0.120396 0.2794)
			(stroke
				(width 0.1)
				(type default)
			)
			(layer "F.Fab")
		)
		(fp_line
			(start 0.120396 0.2794)
			(end -0.12065 0.2794)
			(stroke
				(width 0.1)
				(type default)
			)
			(layer "F.Fab")
		)
		(fp_line
			(start -0.12065 0.3048)
			(end -0.67945 0.3048)
			(stroke
				(width 0.1)
				(type default)
			)
			(layer "F.Fab")
		)
		(fp_line
			(start -0.12065 0.2794)
			(end -0.12065 0.3048)
			(stroke
				(width 0.1)
				(type default)
			)
			(layer "F.Fab")
		)
		(fp_line
			(start -0.12065 -0.2794)
			(end 0.12065 -0.2794)
			(stroke
				(width 0.1)
				(type default)
			)
			(layer "F.Fab")
		)
		(fp_line
			(start -0.12065 -0.305054)
			(end -0.12065 -0.2794)
			(stroke
				(width 0.1)
				(type default)
			)
			(layer "F.Fab")
		)
		(fp_line
			(start -0.67945 0.3048)
			(end -0.67945 -0.305054)
			(stroke
				(width 0.1)
				(type default)
			)
			(layer "F.Fab")
		)
		(fp_line
			(start -0.67945 -0.305054)
			(end -0.12065 -0.305054)
			(stroke
				(width 0.1)
				(type default)
			)
			(layer "F.Fab")
		)
		(pad "1" smd circle
			(at -0.40005 0 180)
			(size 0 0)
			(layers "F.Cu" "F.Mask" "F.Paste")
			(net "P3V3_NIC7_PG_G1")
		)
		(pad "2" smd circle
			(at 0.40005 0 180)
			(size 0 0)
			(layers "F.Cu" "F.Mask" "F.Paste")
			(net "GND")
		)
	)
	(footprint ""
		(layer "F.Cu")
		(at 203.00442 -306.077874 -90)
		(property "Reference" "R6807"
			(at 0 0 270)
			(layer "F.SilkS")
			(hide yes)
			(effects
				(font
					(size 1.27 1.27)
				)
			)
		)
		(property "Value" ""
			(at 0 0 270)
			(layer "F.Fab")
			(effects
				(font
					(size 1.27 1.27)
				)
			)
		)
		(duplicate_pad_numbers_are_jumpers no)
		(fp_line
			(start -0.7874 0.4064)
			(end -0.7874 -0.4064)
			(stroke
				(width 0.1524)
				(type default)
			)
			(layer "F.SilkS")
		)
		(fp_line
			(start 0.7874 0.4064)
			(end -0.7874 0.4064)
			(stroke
				(width 0.1524)
				(type default)
			)
			(layer "F.SilkS")
		)
		(fp_line
			(start -0.7874 -0.4064)
			(end 0.7874 -0.4064)
			(stroke
				(width 0.1524)
				(type default)
			)
			(layer "F.SilkS")
		)
		(fp_line
			(start 0.7874 -0.4064)
			(end 0.7874 0.4064)
			(stroke
				(width 0.1524)
				(type default)
			)
			(layer "F.SilkS")
		)
		(fp_line
			(start -0.67945 0.3048)
			(end -0.67945 -0.305054)
			(stroke
				(width 0.1)
				(type default)
			)
			(layer "F.Fab")
		)
		(fp_line
			(start -0.12065 0.3048)
			(end -0.67945 0.3048)
			(stroke
				(width 0.1)
				(type default)
			)
			(layer "F.Fab")
		)
		(fp_line
			(start 0.120396 0.3048)
			(end 0.120396 0.2794)
			(stroke
				(width 0.1)
				(type default)
			)
			(layer "F.Fab")
		)
		(fp_line
			(start 0.67945 0.3048)
			(end 0.120396 0.3048)
			(stroke
				(width 0.1)
				(type default)
			)
			(layer "F.Fab")
		)
		(fp_line
			(start -0.12065 0.2794)
			(end -0.12065 0.3048)
			(stroke
				(width 0.1)
				(type default)
			)
			(layer "F.Fab")
		)
		(fp_line
			(start 0.120396 0.2794)
			(end -0.12065 0.2794)
			(stroke
				(width 0.1)
				(type default)
			)
			(layer "F.Fab")
		)
		(fp_line
			(start -0.12065 -0.2794)
			(end 0.12065 -0.2794)
			(stroke
				(width 0.1)
				(type default)
			)
			(layer "F.Fab")
		)
		(fp_line
			(start 0.12065 -0.2794)
			(end 0.12065 -0.3048)
			(stroke
				(width 0.1)
				(type default)
			)
			(layer "F.Fab")
		)
		(fp_line
			(start 0.12065 -0.3048)
			(end 0.67945 -0.3048)
			(stroke
				(width 0.1)
				(type default)
			)
			(layer "F.Fab")
		)
		(fp_line
			(start 0.67945 -0.3048)
			(end 0.67945 0.3048)
			(stroke
				(width 0.1)
				(type default)
			)
			(layer "F.Fab")
		)
		(fp_line
			(start -0.67945 -0.305054)
			(end -0.12065 -0.305054)
			(stroke
				(width 0.1)
				(type default)
			)
			(layer "F.Fab")
		)
		(fp_line
			(start -0.12065 -0.305054)
			(end -0.12065 -0.2794)
			(stroke
				(width 0.1)
				(type default)
			)
			(layer "F.Fab")
		)
		(pad "1" smd circle
			(at -0.40005 0 270)
			(size 0 0)
			(layers "F.Cu" "F.Mask" "F.Paste")
			(net "SMB_PEX1_R_SDA")
		)
		(pad "2" smd circle
			(at 0.40005 0 270)
			(size 0 0)
			(layers "F.Cu" "F.Mask" "F.Paste")
			(net "SMB_PEX1_SDA")
		)
	)
	(footprint ""
		(layer "F.Cu")
		(at 406.054306 -48.21809)
		(property "Reference" "PD73"
			(at -3.362706 2.24536 0)
			(unlocked yes)
			(layer "F.SilkS")
			(effects
				(font
					(size 0.7874 0.5842)
					(thickness 0.1524)
				)
				(justify left)
			)
		)
		(property "Value" ""
			(at 0 0 0)
			(layer "F.Fab")
			(effects
				(font
					(size 1.27 1.27)
				)
			)
		)
		(duplicate_pad_numbers_are_jumpers no)
		(fp_line
			(start -3.400044 -1.459992)
			(end 4.107942 -1.459992)
			(stroke
				(width 0.1524)
				(type default)
			)
			(layer "F.SilkS")
		)
		(fp_line
			(start -3.400044 1.459992)
			(end -3.400044 -1.459992)
			(stroke
				(width 0.1524)
				(type default)
			)
			(layer "F.SilkS")
		)
		(fp_line
			(start 4.107942 -1.459992)
			(end 4.107942 1.459992)
			(stroke
				(width 0.1524)
				(type default)
			)
			(layer "F.SilkS")
		)
		(fp_line
			(start 4.107942 1.459992)
			(end -3.400044 1.459992)
			(stroke
				(width 0.1524)
				(type default)
			)
			(layer "F.SilkS")
		)
		(fp_poly
			(pts
				(xy 4.107942 -1.459992) (xy 4.107942 1.459992) (xy 3.308096 1.459992) (xy 3.308096 -1.459992)
			)
			(stroke
				(width 0)
				(type default)
			)
			(fill yes)
			(layer "F.SilkS")
		)
		(fp_line
			(start -2.29997 -1.459992)
			(end 2.29997 -1.459992)
			(stroke
				(width 0.1)
				(type default)
			)
			(layer "F.Fab")
		)
		(fp_line
			(start -2.29997 1.459992)
			(end -2.29997 -1.459992)
			(stroke
				(width 0.1)
				(type default)
			)
			(layer "F.Fab")
		)
		(fp_line
			(start 2.29997 -1.459992)
			(end 2.29997 1.459992)
			(stroke
				(width 0.1)
				(type default)
			)
			(layer "F.Fab")
		)
		(fp_line
			(start 2.29997 1.459992)
			(end -2.29997 1.459992)
			(stroke
				(width 0.1)
				(type default)
			)
			(layer "F.Fab")
		)
		(fp_text user "+"
			(at -4.7752 -0.12065 0)
			(unlocked yes)
			(layer "F.SilkS")
			(effects
				(font
					(size 1.905 1.4224)
					(thickness 0.1524)
				)
				(justify left)
			)
		)
		(fp_text user "-"
			(at 5.4102 0.29845 180)
			(unlocked yes)
			(layer "F.SilkS")
			(effects
				(font
					(size 1.905 1.4224)
					(thickness 0.1524)
				)
				(justify left)
			)
		)
		(fp_text user "+"
			(at -4.7752 -0.12065 0)
			(unlocked yes)
			(layer "F.Fab")
			(effects
				(font
					(size 1.905 1.4224)
					(thickness 0.1524)
				)
				(justify left)
			)
		)
		(fp_text user "-"
			(at 5.4102 0.29845 180)
			(unlocked yes)
			(layer "F.Fab")
			(effects
				(font
					(size 1.905 1.4224)
					(thickness 0.1524)
				)
				(justify left)
			)
		)
		(pad "A" smd rect
			(at -1.999996 0 90)
			(size 1.7018 2.5146)
			(layers "F.Cu" "F.Mask" "F.Paste")
			(net "GND")
		)
		(pad "C" smd rect
			(at 1.999996 0 90)
			(size 1.7018 2.5146)
			(layers "F.Cu" "F.Mask" "F.Paste")
			(net "P3V3_SSD14")
		)
	)
	(footprint ""
		(layer "F.Cu")
		(at 117.958362 -130.217926)
		(property "Reference" "C2852"
			(at 0 0 0)
			(layer "F.SilkS")
			(hide yes)
			(effects
				(font
					(size 1.27 1.27)
				)
			)
		)
		(property "Value" ""
			(at 0 0 0)
			(layer "F.Fab")
			(effects
				(font
					(size 1.27 1.27)
				)
			)
		)
		(duplicate_pad_numbers_are_jumpers no)
		(fp_line
			(start -0.7874 -0.4064)
			(end 0.7874 -0.4064)
			(stroke
				(width 0.1524)
				(type default)
			)
			(layer "F.SilkS")
		)
		(fp_line
			(start -0.7874 0.4064)
			(end -0.7874 -0.4064)
			(stroke
				(width 0.1524)
				(type default)
			)
			(layer "F.SilkS")
		)
		(fp_line
			(start 0.7874 -0.4064)
			(end 0.7874 0.4064)
			(stroke
				(width 0.1524)
				(type default)
			)
			(layer "F.SilkS")
		)
		(fp_line
			(start 0.7874 0.4064)
			(end -0.7874 0.4064)
			(stroke
				(width 0.1524)
				(type default)
			)
			(layer "F.SilkS")
		)
		(fp_line
			(start -0.67945 -0.305054)
			(end -0.12065 -0.305054)
			(stroke
				(width 0.1)
				(type default)
			)
			(layer "F.Fab")
		)
		(fp_line
			(start -0.67945 0.3048)
			(end -0.67945 -0.305054)
			(stroke
				(width 0.1)
				(type default)
			)
			(layer "F.Fab")
		)
		(fp_line
			(start -0.12065 -0.305054)
			(end -0.12065 -0.2794)
			(stroke
				(width 0.1)
				(type default)
			)
			(layer "F.Fab")
		)
		(fp_line
			(start -0.12065 -0.2794)
			(end 0.12065 -0.2794)
			(stroke
				(width 0.1)
				(type default)
			)
			(layer "F.Fab")
		)
		(fp_line
			(start -0.12065 0.2794)
			(end -0.12065 0.3048)
			(stroke
				(width 0.1)
				(type default)
			)
			(layer "F.Fab")
		)
		(fp_line
			(start -0.12065 0.3048)
			(end -0.67945 0.3048)
			(stroke
				(width 0.1)
				(type default)
			)
			(layer "F.Fab")
		)
		(fp_line
			(start 0.120396 0.2794)
			(end -0.12065 0.2794)
			(stroke
				(width 0.1)
				(type default)
			)
			(layer "F.Fab")
		)
		(fp_line
			(start 0.120396 0.3048)
			(end 0.120396 0.2794)
			(stroke
				(width 0.1)
				(type default)
			)
			(layer "F.Fab")
		)
		(fp_line
			(start 0.12065 -0.3048)
			(end 0.67945 -0.3048)
			(stroke
				(width 0.1)
				(type default)
			)
			(layer "F.Fab")
		)
		(fp_line
			(start 0.12065 -0.2794)
			(end 0.12065 -0.3048)
			(stroke
				(width 0.1)
				(type default)
			)
			(layer "F.Fab")
		)
		(fp_line
			(start 0.67945 -0.3048)
			(end 0.67945 0.3048)
			(stroke
				(width 0.1)
				(type default)
			)
			(layer "F.Fab")
		)
		(fp_line
			(start 0.67945 0.3048)
			(end 0.120396 0.3048)
			(stroke
				(width 0.1)
				(type default)
			)
			(layer "F.Fab")
		)
		(pad "1" smd circle
			(at -0.40005 0)
			(size 0 0)
			(layers "F.Cu" "F.Mask" "F.Paste")
			(net "PWR_EN_P3V3_R")
		)
		(pad "2" smd circle
			(at 0.40005 0)
			(size 0 0)
			(layers "F.Cu" "F.Mask" "F.Paste")
			(net "GND")
		)
	)
	(footprint ""
		(layer "F.Cu")
		(at 280.085546 -27.092148 -90)
		(property "Reference" "R5761"
			(at 0 0 270)
			(layer "F.SilkS")
			(hide yes)
			(effects
				(font
					(size 1.27 1.27)
				)
			)
		)
		(property "Value" ""
			(at 0 0 270)
			(layer "F.Fab")
			(effects
				(font
					(size 1.27 1.27)
				)
			)
		)
		(duplicate_pad_numbers_are_jumpers no)
		(fp_line
			(start -0.7874 0.4064)
			(end -0.7874 -0.4064)
			(stroke
				(width 0.1524)
				(type default)
			)
			(layer "F.SilkS")
		)
		(fp_line
			(start 0.7874 0.4064)
			(end -0.7874 0.4064)
			(stroke
				(width 0.1524)
				(type default)
			)
			(layer "F.SilkS")
		)
		(fp_line
			(start -0.7874 -0.4064)
			(end 0.7874 -0.4064)
			(stroke
				(width 0.1524)
				(type default)
			)
			(layer "F.SilkS")
		)
		(fp_line
			(start 0.7874 -0.4064)
			(end 0.7874 0.4064)
			(stroke
				(width 0.1524)
				(type default)
			)
			(layer "F.SilkS")
		)
		(fp_line
			(start -0.67945 0.3048)
			(end -0.67945 -0.305054)
			(stroke
				(width 0.1)
				(type default)
			)
			(layer "F.Fab")
		)
		(fp_line
			(start -0.12065 0.3048)
			(end -0.67945 0.3048)
			(stroke
				(width 0.1)
				(type default)
			)
			(layer "F.Fab")
		)
		(fp_line
			(start 0.120396 0.3048)
			(end 0.120396 0.2794)
			(stroke
				(width 0.1)
				(type default)
			)
			(layer "F.Fab")
		)
		(fp_line
			(start 0.67945 0.3048)
			(end 0.120396 0.3048)
			(stroke
				(width 0.1)
				(type default)
			)
			(layer "F.Fab")
		)
		(fp_line
			(start -0.12065 0.2794)
			(end -0.12065 0.3048)
			(stroke
				(width 0.1)
				(type default)
			)
			(layer "F.Fab")
		)
		(fp_line
			(start 0.120396 0.2794)
			(end -0.12065 0.2794)
			(stroke
				(width 0.1)
				(type default)
			)
			(layer "F.Fab")
		)
		(fp_line
			(start -0.12065 -0.2794)
			(end 0.12065 -0.2794)
			(stroke
				(width 0.1)
				(type default)
			)
			(layer "F.Fab")
		)
		(fp_line
			(start 0.12065 -0.2794)
			(end 0.12065 -0.3048)
			(stroke
				(width 0.1)
				(type default)
			)
			(layer "F.Fab")
		)
		(fp_line
			(start 0.12065 -0.3048)
			(end 0.67945 -0.3048)
			(stroke
				(width 0.1)
				(type default)
			)
			(layer "F.Fab")
		)
		(fp_line
			(start 0.67945 -0.3048)
			(end 0.67945 0.3048)
			(stroke
				(width 0.1)
				(type default)
			)
			(layer "F.Fab")
		)
		(fp_line
			(start -0.67945 -0.305054)
			(end -0.12065 -0.305054)
			(stroke
				(width 0.1)
				(type default)
			)
			(layer "F.Fab")
		)
		(fp_line
			(start -0.12065 -0.305054)
			(end -0.12065 -0.2794)
			(stroke
				(width 0.1)
				(type default)
			)
			(layer "F.Fab")
		)
		(pad "1" smd circle
			(at -0.40005 0 270)
			(size 0 0)
			(layers "F.Cu" "F.Mask" "F.Paste")
			(net "P3V3_SSD9")
		)
		(pad "2" smd circle
			(at 0.40005 0 270)
			(size 0 0)
			(layers "F.Cu" "F.Mask" "F.Paste")
			(net "SSD9_LED_ISO_N")
		)
	)
	(footprint ""
		(layer "F.Cu")
		(at 71.246746 -38.49116 180)
		(property "Reference" "R5889"
			(at 0 0 180)
			(layer "F.SilkS")
			(hide yes)
			(effects
				(font
					(size 1.27 1.27)
				)
			)
		)
		(property "Value" ""
			(at 0 0 180)
			(layer "F.Fab")
			(effects
				(font
					(size 1.27 1.27)
				)
			)
		)
		(duplicate_pad_numbers_are_jumpers no)
		(fp_line
			(start 0.7874 0.4064)
			(end -0.7874 0.4064)
			(stroke
				(width 0.1524)
				(type default)
			)
			(layer "F.SilkS")
		)
		(fp_line
			(start 0.7874 -0.4064)
			(end 0.7874 0.4064)
			(stroke
				(width 0.1524)
				(type default)
			)
			(layer "F.SilkS")
		)
		(fp_line
			(start -0.7874 0.4064)
			(end -0.7874 -0.4064)
			(stroke
				(width 0.1524)
				(type default)
			)
			(layer "F.SilkS")
		)
		(fp_line
			(start -0.7874 -0.4064)
			(end 0.7874 -0.4064)
			(stroke
				(width 0.1524)
				(type default)
			)
			(layer "F.SilkS")
		)
		(fp_line
			(start 0.67945 0.3048)
			(end 0.120396 0.3048)
			(stroke
				(width 0.1)
				(type default)
			)
			(layer "F.Fab")
		)
		(fp_line
			(start 0.67945 -0.3048)
			(end 0.67945 0.3048)
			(stroke
				(width 0.1)
				(type default)
			)
			(layer "F.Fab")
		)
		(fp_line
			(start 0.12065 -0.2794)
			(end 0.12065 -0.3048)
			(stroke
				(width 0.1)
				(type default)
			)
			(layer "F.Fab")
		)
		(fp_line
			(start 0.12065 -0.3048)
			(end 0.67945 -0.3048)
			(stroke
				(width 0.1)
				(type default)
			)
			(layer "F.Fab")
		)
		(fp_line
			(start 0.120396 0.3048)
			(end 0.120396 0.2794)
			(stroke
				(width 0.1)
				(type default)
			)
			(layer "F.Fab")
		)
		(fp_line
			(start 0.120396 0.2794)
			(end -0.12065 0.2794)
			(stroke
				(width 0.1)
				(type default)
			)
			(layer "F.Fab")
		)
		(fp_line
			(start -0.12065 0.3048)
			(end -0.67945 0.3048)
			(stroke
				(width 0.1)
				(type default)
			)
			(layer "F.Fab")
		)
		(fp_line
			(start -0.12065 0.2794)
			(end -0.12065 0.3048)
			(stroke
				(width 0.1)
				(type default)
			)
			(layer "F.Fab")
		)
		(fp_line
			(start -0.12065 -0.2794)
			(end 0.12065 -0.2794)
			(stroke
				(width 0.1)
				(type default)
			)
			(layer "F.Fab")
		)
		(fp_line
			(start -0.12065 -0.305054)
			(end -0.12065 -0.2794)
			(stroke
				(width 0.1)
				(type default)
			)
			(layer "F.Fab")
		)
		(fp_line
			(start -0.67945 0.3048)
			(end -0.67945 -0.305054)
			(stroke
				(width 0.1)
				(type default)
			)
			(layer "F.Fab")
		)
		(fp_line
			(start -0.67945 -0.305054)
			(end -0.12065 -0.305054)
			(stroke
				(width 0.1)
				(type default)
			)
			(layer "F.Fab")
		)
		(pad "1" smd circle
			(at -0.40005 0 180)
			(size 0 0)
			(layers "F.Cu" "F.Mask" "F.Paste")
			(net "P3V3_SSD3_PG_G1")
		)
		(pad "2" smd circle
			(at 0.40005 0 180)
			(size 0 0)
			(layers "F.Cu" "F.Mask" "F.Paste")
			(net "GND")
		)
	)
	(footprint ""
		(layer "F.Cu")
		(at 188.587634 -25.342342 -90)
		(property "Reference" "R428"
			(at 0 0 270)
			(layer "F.SilkS")
			(hide yes)
			(effects
				(font
					(size 1.27 1.27)
				)
			)
		)
		(property "Value" ""
			(at 0 0 270)
			(layer "F.Fab")
			(effects
				(font
					(size 1.27 1.27)
				)
			)
		)
		(duplicate_pad_numbers_are_jumpers no)
		(fp_line
			(start -0.7874 0.4064)
			(end -0.7874 -0.4064)
			(stroke
				(width 0.1524)
				(type default)
			)
			(layer "F.SilkS")
		)
		(fp_line
			(start 0.7874 0.4064)
			(end -0.7874 0.4064)
			(stroke
				(width 0.1524)
				(type default)
			)
			(layer "F.SilkS")
		)
		(fp_line
			(start -0.7874 -0.4064)
			(end 0.7874 -0.4064)
			(stroke
				(width 0.1524)
				(type default)
			)
			(layer "F.SilkS")
		)
		(fp_line
			(start 0.7874 -0.4064)
			(end 0.7874 0.4064)
			(stroke
				(width 0.1524)
				(type default)
			)
			(layer "F.SilkS")
		)
		(fp_line
			(start -0.67945 0.3048)
			(end -0.67945 -0.305054)
			(stroke
				(width 0.1)
				(type default)
			)
			(layer "F.Fab")
		)
		(fp_line
			(start -0.12065 0.3048)
			(end -0.67945 0.3048)
			(stroke
				(width 0.1)
				(type default)
			)
			(layer "F.Fab")
		)
		(fp_line
			(start 0.120396 0.3048)
			(end 0.120396 0.2794)
			(stroke
				(width 0.1)
				(type default)
			)
			(layer "F.Fab")
		)
		(fp_line
			(start 0.67945 0.3048)
			(end 0.120396 0.3048)
			(stroke
				(width 0.1)
				(type default)
			)
			(layer "F.Fab")
		)
		(fp_line
			(start -0.12065 0.2794)
			(end -0.12065 0.3048)
			(stroke
				(width 0.1)
				(type default)
			)
			(layer "F.Fab")
		)
		(fp_line
			(start 0.120396 0.2794)
			(end -0.12065 0.2794)
			(stroke
				(width 0.1)
				(type default)
			)
			(layer "F.Fab")
		)
		(fp_line
			(start -0.12065 -0.2794)
			(end 0.12065 -0.2794)
			(stroke
				(width 0.1)
				(type default)
			)
			(layer "F.Fab")
		)
		(fp_line
			(start 0.12065 -0.2794)
			(end 0.12065 -0.3048)
			(stroke
				(width 0.1)
				(type default)
			)
			(layer "F.Fab")
		)
		(fp_line
			(start 0.12065 -0.3048)
			(end 0.67945 -0.3048)
			(stroke
				(width 0.1)
				(type default)
			)
			(layer "F.Fab")
		)
		(fp_line
			(start 0.67945 -0.3048)
			(end 0.67945 0.3048)
			(stroke
				(width 0.1)
				(type default)
			)
			(layer "F.Fab")
		)
		(fp_line
			(start -0.67945 -0.305054)
			(end -0.12065 -0.305054)
			(stroke
				(width 0.1)
				(type default)
			)
			(layer "F.Fab")
		)
		(fp_line
			(start -0.12065 -0.305054)
			(end -0.12065 -0.2794)
			(stroke
				(width 0.1)
				(type default)
			)
			(layer "F.Fab")
		)
		(pad "1" smd circle
			(at -0.40005 0 270)
			(size 0 0)
			(layers "F.Cu" "F.Mask" "F.Paste")
			(net "GND")
		)
		(pad "2" smd circle
			(at 0.40005 0 270)
			(size 0 0)
			(layers "F.Cu" "F.Mask" "F.Paste")
			(net "DUALPORT_N_SSD6")
		)
	)
	(footprint ""
		(layer "F.Cu")
		(at 27.890216 -260.949694)
		(property "Reference" "R4567"
			(at 0 0 0)
			(layer "F.SilkS")
			(hide yes)
			(effects
				(font
					(size 1.27 1.27)
				)
			)
		)
		(property "Value" ""
			(at 0 0 0)
			(layer "F.Fab")
			(effects
				(font
					(size 1.27 1.27)
				)
			)
		)
		(duplicate_pad_numbers_are_jumpers no)
		(fp_line
			(start -0.7874 -0.4064)
			(end 0.7874 -0.4064)
			(stroke
				(width 0.1524)
				(type default)
			)
			(layer "F.SilkS")
		)
		(fp_line
			(start -0.7874 0.4064)
			(end -0.7874 -0.4064)
			(stroke
				(width 0.1524)
				(type default)
			)
			(layer "F.SilkS")
		)
		(fp_line
			(start 0.7874 -0.4064)
			(end 0.7874 0.4064)
			(stroke
				(width 0.1524)
				(type default)
			)
			(layer "F.SilkS")
		)
		(fp_line
			(start 0.7874 0.4064)
			(end -0.7874 0.4064)
			(stroke
				(width 0.1524)
				(type default)
			)
			(layer "F.SilkS")
		)
		(fp_line
			(start -0.67945 -0.305054)
			(end -0.12065 -0.305054)
			(stroke
				(width 0.1)
				(type default)
			)
			(layer "F.Fab")
		)
		(fp_line
			(start -0.67945 0.3048)
			(end -0.67945 -0.305054)
			(stroke
				(width 0.1)
				(type default)
			)
			(layer "F.Fab")
		)
		(fp_line
			(start -0.12065 -0.305054)
			(end -0.12065 -0.2794)
			(stroke
				(width 0.1)
				(type default)
			)
			(layer "F.Fab")
		)
		(fp_line
			(start -0.12065 -0.2794)
			(end 0.12065 -0.2794)
			(stroke
				(width 0.1)
				(type default)
			)
			(layer "F.Fab")
		)
		(fp_line
			(start -0.12065 0.2794)
			(end -0.12065 0.3048)
			(stroke
				(width 0.1)
				(type default)
			)
			(layer "F.Fab")
		)
		(fp_line
			(start -0.12065 0.3048)
			(end -0.67945 0.3048)
			(stroke
				(width 0.1)
				(type default)
			)
			(layer "F.Fab")
		)
		(fp_line
			(start 0.120396 0.2794)
			(end -0.12065 0.2794)
			(stroke
				(width 0.1)
				(type default)
			)
			(layer "F.Fab")
		)
		(fp_line
			(start 0.120396 0.3048)
			(end 0.120396 0.2794)
			(stroke
				(width 0.1)
				(type default)
			)
			(layer "F.Fab")
		)
		(fp_line
			(start 0.12065 -0.3048)
			(end 0.67945 -0.3048)
			(stroke
				(width 0.1)
				(type default)
			)
			(layer "F.Fab")
		)
		(fp_line
			(start 0.12065 -0.2794)
			(end 0.12065 -0.3048)
			(stroke
				(width 0.1)
				(type default)
			)
			(layer "F.Fab")
		)
		(fp_line
			(start 0.67945 -0.3048)
			(end 0.67945 0.3048)
			(stroke
				(width 0.1)
				(type default)
			)
			(layer "F.Fab")
		)
		(fp_line
			(start 0.67945 0.3048)
			(end 0.120396 0.3048)
			(stroke
				(width 0.1)
				(type default)
			)
			(layer "F.Fab")
		)
		(pad "1" smd circle
			(at -0.40005 0)
			(size 0 0)
			(layers "F.Cu" "F.Mask" "F.Paste")
			(net "P1V8_VDDA_PEX0")
		)
		(pad "2" smd circle
			(at 0.40005 0)
			(size 0 0)
			(layers "F.Cu" "F.Mask" "F.Paste")
			(net "P1V8_VDDA_PEX0_R")
		)
	)
	(footprint ""
		(layer "F.Cu")
		(at 36.638484 -123.71324)
		(property "Reference" "C44"
			(at 0 0 0)
			(layer "F.SilkS")
			(hide yes)
			(effects
				(font
					(size 1.27 1.27)
				)
			)
		)
		(property "Value" ""
			(at 0 0 0)
			(layer "F.Fab")
			(effects
				(font
					(size 1.27 1.27)
				)
			)
		)
		(duplicate_pad_numbers_are_jumpers no)
		(fp_line
			(start -0.299974 -0.150114)
			(end 0.299974 -0.150114)
			(stroke
				(width 0.1)
				(type default)
			)
			(layer "F.Fab")
		)
		(fp_line
			(start -0.299974 0.150114)
			(end -0.299974 -0.150114)
			(stroke
				(width 0.1)
				(type default)
			)
			(layer "F.Fab")
		)
		(fp_line
			(start 0.299974 -0.150114)
			(end 0.299974 0.150114)
			(stroke
				(width 0.1)
				(type default)
			)
			(layer "F.Fab")
		)
		(fp_line
			(start 0.299974 0.150114)
			(end -0.299974 0.150114)
			(stroke
				(width 0.1)
				(type default)
			)
			(layer "F.Fab")
		)
		(pad "1" smd rect
			(at -0.2667 0)
			(size 0.3048 0.381)
			(layers "F.Cu" "F.Mask" "F.Paste")
			(net "P5E_PEX0_STN1_TX_DN<26>")
		)
		(pad "2" smd rect
			(at 0.2667 0)
			(size 0.3048 0.381)
			(layers "F.Cu" "F.Mask" "F.Paste")
			(net "P5E_PEX0_STN1_TX_C_DN<26>")
		)
	)
	(footprint ""
		(layer "F.Cu")
		(at 270.980662 -350.098614 90)
		(property "Reference" "C2343"
			(at 0 0 90)
			(layer "F.SilkS")
			(hide yes)
			(effects
				(font
					(size 1.27 1.27)
				)
			)
		)
		(property "Value" ""
			(at 0 0 90)
			(layer "F.Fab")
			(effects
				(font
					(size 1.27 1.27)
				)
			)
		)
		(duplicate_pad_numbers_are_jumpers no)
		(fp_line
			(start 0.299974 -0.150114)
			(end 0.299974 0.150114)
			(stroke
				(width 0.1)
				(type default)
			)
			(layer "F.Fab")
		)
		(fp_line
			(start -0.299974 -0.150114)
			(end 0.299974 -0.150114)
			(stroke
				(width 0.1)
				(type default)
			)
			(layer "F.Fab")
		)
		(fp_line
			(start 0.299974 0.150114)
			(end -0.299974 0.150114)
			(stroke
				(width 0.1)
				(type default)
			)
			(layer "F.Fab")
		)
		(fp_line
			(start -0.299974 0.150114)
			(end -0.299974 -0.150114)
			(stroke
				(width 0.1)
				(type default)
			)
			(layer "F.Fab")
		)
		(pad "1" smd rect
			(at -0.2667 0 90)
			(size 0.3048 0.381)
			(layers "F.Cu" "F.Mask" "F.Paste")
			(net "P5E_PEX2_STN4_TX_DP<78>")
		)
		(pad "2" smd rect
			(at 0.2667 0 90)
			(size 0.3048 0.381)
			(layers "F.Cu" "F.Mask" "F.Paste")
			(net "P5E_PEX2_STN4_TX_C_DP<78>")
		)
	)
	(footprint ""
		(layer "F.Cu")
		(at 376.809 -174.15002 180)
		(property "Reference" "R4679"
			(at 0 0 180)
			(layer "F.SilkS")
			(hide yes)
			(effects
				(font
					(size 1.27 1.27)
				)
			)
		)
		(property "Value" ""
			(at 0 0 180)
			(layer "F.Fab")
			(effects
				(font
					(size 1.27 1.27)
				)
			)
		)
		(duplicate_pad_numbers_are_jumpers no)
		(fp_line
			(start 0.7874 0.4064)
			(end -0.7874 0.4064)
			(stroke
				(width 0.1524)
				(type default)
			)
			(layer "F.SilkS")
		)
		(fp_line
			(start 0.7874 -0.4064)
			(end 0.7874 0.4064)
			(stroke
				(width 0.1524)
				(type default)
			)
			(layer "F.SilkS")
		)
		(fp_line
			(start -0.7874 0.4064)
			(end -0.7874 -0.4064)
			(stroke
				(width 0.1524)
				(type default)
			)
			(layer "F.SilkS")
		)
		(fp_line
			(start -0.7874 -0.4064)
			(end 0.7874 -0.4064)
			(stroke
				(width 0.1524)
				(type default)
			)
			(layer "F.SilkS")
		)
		(fp_line
			(start 0.67945 0.3048)
			(end 0.120396 0.3048)
			(stroke
				(width 0.1)
				(type default)
			)
			(layer "F.Fab")
		)
		(fp_line
			(start 0.67945 -0.3048)
			(end 0.67945 0.3048)
			(stroke
				(width 0.1)
				(type default)
			)
			(layer "F.Fab")
		)
		(fp_line
			(start 0.12065 -0.2794)
			(end 0.12065 -0.3048)
			(stroke
				(width 0.1)
				(type default)
			)
			(layer "F.Fab")
		)
		(fp_line
			(start 0.12065 -0.3048)
			(end 0.67945 -0.3048)
			(stroke
				(width 0.1)
				(type default)
			)
			(layer "F.Fab")
		)
		(fp_line
			(start 0.120396 0.3048)
			(end 0.120396 0.2794)
			(stroke
				(width 0.1)
				(type default)
			)
			(layer "F.Fab")
		)
		(fp_line
			(start 0.120396 0.2794)
			(end -0.12065 0.2794)
			(stroke
				(width 0.1)
				(type default)
			)
			(layer "F.Fab")
		)
		(fp_line
			(start -0.12065 0.3048)
			(end -0.67945 0.3048)
			(stroke
				(width 0.1)
				(type default)
			)
			(layer "F.Fab")
		)
		(fp_line
			(start -0.12065 0.2794)
			(end -0.12065 0.3048)
			(stroke
				(width 0.1)
				(type default)
			)
			(layer "F.Fab")
		)
		(fp_line
			(start -0.12065 -0.2794)
			(end 0.12065 -0.2794)
			(stroke
				(width 0.1)
				(type default)
			)
			(layer "F.Fab")
		)
		(fp_line
			(start -0.12065 -0.305054)
			(end -0.12065 -0.2794)
			(stroke
				(width 0.1)
				(type default)
			)
			(layer "F.Fab")
		)
		(fp_line
			(start -0.67945 0.3048)
			(end -0.67945 -0.305054)
			(stroke
				(width 0.1)
				(type default)
			)
			(layer "F.Fab")
		)
		(fp_line
			(start -0.67945 -0.305054)
			(end -0.12065 -0.305054)
			(stroke
				(width 0.1)
				(type default)
			)
			(layer "F.Fab")
		)
		(pad "1" smd circle
			(at -0.40005 0 180)
			(size 0 0)
			(layers "F.Cu" "F.Mask" "F.Paste")
			(net "NIC3_PEX_PWR_EN_R")
		)
		(pad "2" smd circle
			(at 0.40005 0 180)
			(size 0 0)
			(layers "F.Cu" "F.Mask" "F.Paste")
			(net "GND")
		)
	)
	(footprint ""
		(layer "F.Cu")
		(at 446.150238 -95.263716 -90)
		(property "Reference" "PR206"
			(at 0 0 270)
			(layer "F.SilkS")
			(hide yes)
			(effects
				(font
					(size 1.27 1.27)
				)
			)
		)
		(property "Value" ""
			(at 0 0 270)
			(layer "F.Fab")
			(effects
				(font
					(size 1.27 1.27)
				)
			)
		)
		(duplicate_pad_numbers_are_jumpers no)
		(fp_line
			(start -0.7874 0.4064)
			(end -0.7874 -0.4064)
			(stroke
				(width 0.1524)
				(type default)
			)
			(layer "F.SilkS")
		)
		(fp_line
			(start 0.7874 0.4064)
			(end -0.7874 0.4064)
			(stroke
				(width 0.1524)
				(type default)
			)
			(layer "F.SilkS")
		)
		(fp_line
			(start -0.7874 -0.4064)
			(end 0.7874 -0.4064)
			(stroke
				(width 0.1524)
				(type default)
			)
			(layer "F.SilkS")
		)
		(fp_line
			(start 0.7874 -0.4064)
			(end 0.7874 0.4064)
			(stroke
				(width 0.1524)
				(type default)
			)
			(layer "F.SilkS")
		)
		(fp_line
			(start -0.67945 0.3048)
			(end -0.67945 -0.305054)
			(stroke
				(width 0.1)
				(type default)
			)
			(layer "F.Fab")
		)
		(fp_line
			(start -0.12065 0.3048)
			(end -0.67945 0.3048)
			(stroke
				(width 0.1)
				(type default)
			)
			(layer "F.Fab")
		)
		(fp_line
			(start 0.120396 0.3048)
			(end 0.120396 0.2794)
			(stroke
				(width 0.1)
				(type default)
			)
			(layer "F.Fab")
		)
		(fp_line
			(start 0.67945 0.3048)
			(end 0.120396 0.3048)
			(stroke
				(width 0.1)
				(type default)
			)
			(layer "F.Fab")
		)
		(fp_line
			(start -0.12065 0.2794)
			(end -0.12065 0.3048)
			(stroke
				(width 0.1)
				(type default)
			)
			(layer "F.Fab")
		)
		(fp_line
			(start 0.120396 0.2794)
			(end -0.12065 0.2794)
			(stroke
				(width 0.1)
				(type default)
			)
			(layer "F.Fab")
		)
		(fp_line
			(start -0.12065 -0.2794)
			(end 0.12065 -0.2794)
			(stroke
				(width 0.1)
				(type default)
			)
			(layer "F.Fab")
		)
		(fp_line
			(start 0.12065 -0.2794)
			(end 0.12065 -0.3048)
			(stroke
				(width 0.1)
				(type default)
			)
			(layer "F.Fab")
		)
		(fp_line
			(start 0.12065 -0.3048)
			(end 0.67945 -0.3048)
			(stroke
				(width 0.1)
				(type default)
			)
			(layer "F.Fab")
		)
		(fp_line
			(start 0.67945 -0.3048)
			(end 0.67945 0.3048)
			(stroke
				(width 0.1)
				(type default)
			)
			(layer "F.Fab")
		)
		(fp_line
			(start -0.67945 -0.305054)
			(end -0.12065 -0.305054)
			(stroke
				(width 0.1)
				(type default)
			)
			(layer "F.Fab")
		)
		(fp_line
			(start -0.12065 -0.305054)
			(end -0.12065 -0.2794)
			(stroke
				(width 0.1)
				(type default)
			)
			(layer "F.Fab")
		)
		(pad "1" smd circle
			(at -0.40005 0 270)
			(size 0 0)
			(layers "F.Cu" "F.Mask" "F.Paste")
			(net "P12V_NIC7_OCP")
		)
		(pad "2" smd circle
			(at 0.40005 0 270)
			(size 0 0)
			(layers "F.Cu" "F.Mask" "F.Paste")
			(net "GND")
		)
	)
	(footprint ""
		(layer "F.Cu")
		(at 265.5951 -77.279754 -90)
		(property "Reference" "R1049"
			(at 0 0 270)
			(layer "F.SilkS")
			(hide yes)
			(effects
				(font
					(size 1.27 1.27)
				)
			)
		)
		(property "Value" ""
			(at 0 0 270)
			(layer "F.Fab")
			(effects
				(font
					(size 1.27 1.27)
				)
			)
		)
		(duplicate_pad_numbers_are_jumpers no)
		(fp_line
			(start -0.7874 0.4064)
			(end -0.7874 -0.4064)
			(stroke
				(width 0.1524)
				(type default)
			)
			(layer "F.SilkS")
		)
		(fp_line
			(start 0.7874 0.4064)
			(end -0.7874 0.4064)
			(stroke
				(width 0.1524)
				(type default)
			)
			(layer "F.SilkS")
		)
		(fp_line
			(start -0.7874 -0.4064)
			(end 0.7874 -0.4064)
			(stroke
				(width 0.1524)
				(type default)
			)
			(layer "F.SilkS")
		)
		(fp_line
			(start 0.7874 -0.4064)
			(end 0.7874 0.4064)
			(stroke
				(width 0.1524)
				(type default)
			)
			(layer "F.SilkS")
		)
		(fp_line
			(start -0.67945 0.3048)
			(end -0.67945 -0.305054)
			(stroke
				(width 0.1)
				(type default)
			)
			(layer "F.Fab")
		)
		(fp_line
			(start -0.12065 0.3048)
			(end -0.67945 0.3048)
			(stroke
				(width 0.1)
				(type default)
			)
			(layer "F.Fab")
		)
		(fp_line
			(start 0.120396 0.3048)
			(end 0.120396 0.2794)
			(stroke
				(width 0.1)
				(type default)
			)
			(layer "F.Fab")
		)
		(fp_line
			(start 0.67945 0.3048)
			(end 0.120396 0.3048)
			(stroke
				(width 0.1)
				(type default)
			)
			(layer "F.Fab")
		)
		(fp_line
			(start -0.12065 0.2794)
			(end -0.12065 0.3048)
			(stroke
				(width 0.1)
				(type default)
			)
			(layer "F.Fab")
		)
		(fp_line
			(start 0.120396 0.2794)
			(end -0.12065 0.2794)
			(stroke
				(width 0.1)
				(type default)
			)
			(layer "F.Fab")
		)
		(fp_line
			(start -0.12065 -0.2794)
			(end 0.12065 -0.2794)
			(stroke
				(width 0.1)
				(type default)
			)
			(layer "F.Fab")
		)
		(fp_line
			(start 0.12065 -0.2794)
			(end 0.12065 -0.3048)
			(stroke
				(width 0.1)
				(type default)
			)
			(layer "F.Fab")
		)
		(fp_line
			(start 0.12065 -0.3048)
			(end 0.67945 -0.3048)
			(stroke
				(width 0.1)
				(type default)
			)
			(layer "F.Fab")
		)
		(fp_line
			(start 0.67945 -0.3048)
			(end 0.67945 0.3048)
			(stroke
				(width 0.1)
				(type default)
			)
			(layer "F.Fab")
		)
		(fp_line
			(start -0.67945 -0.305054)
			(end -0.12065 -0.305054)
			(stroke
				(width 0.1)
				(type default)
			)
			(layer "F.Fab")
		)
		(fp_line
			(start -0.12065 -0.305054)
			(end -0.12065 -0.2794)
			(stroke
				(width 0.1)
				(type default)
			)
			(layer "F.Fab")
		)
		(pad "1" smd circle
			(at -0.40005 0 270)
			(size 0 0)
			(layers "F.Cu" "F.Mask" "F.Paste")
			(net "CLK_BUFFER_9ZXL0851E_8_15_OE2_N")
		)
		(pad "2" smd circle
			(at 0.40005 0 270)
			(size 0 0)
			(layers "F.Cu" "F.Mask" "F.Paste")
			(net "P3V3")
		)
	)
	(footprint ""
		(layer "F.Cu")
		(at 372.913656 -239.647984)
		(property "Reference" "R6402"
			(at 0 0 0)
			(layer "F.SilkS")
			(hide yes)
			(effects
				(font
					(size 1.27 1.27)
				)
			)
		)
		(property "Value" ""
			(at 0 0 0)
			(layer "F.Fab")
			(effects
				(font
					(size 1.27 1.27)
				)
			)
		)
		(duplicate_pad_numbers_are_jumpers no)
		(fp_line
			(start -0.7874 -0.4064)
			(end 0.7874 -0.4064)
			(stroke
				(width 0.1524)
				(type default)
			)
			(layer "F.SilkS")
		)
		(fp_line
			(start -0.7874 0.4064)
			(end -0.7874 -0.4064)
			(stroke
				(width 0.1524)
				(type default)
			)
			(layer "F.SilkS")
		)
		(fp_line
			(start 0.7874 -0.4064)
			(end 0.7874 0.4064)
			(stroke
				(width 0.1524)
				(type default)
			)
			(layer "F.SilkS")
		)
		(fp_line
			(start 0.7874 0.4064)
			(end -0.7874 0.4064)
			(stroke
				(width 0.1524)
				(type default)
			)
			(layer "F.SilkS")
		)
		(fp_line
			(start -0.67945 -0.305054)
			(end -0.12065 -0.305054)
			(stroke
				(width 0.1)
				(type default)
			)
			(layer "F.Fab")
		)
		(fp_line
			(start -0.67945 0.3048)
			(end -0.67945 -0.305054)
			(stroke
				(width 0.1)
				(type default)
			)
			(layer "F.Fab")
		)
		(fp_line
			(start -0.12065 -0.305054)
			(end -0.12065 -0.2794)
			(stroke
				(width 0.1)
				(type default)
			)
			(layer "F.Fab")
		)
		(fp_line
			(start -0.12065 -0.2794)
			(end 0.12065 -0.2794)
			(stroke
				(width 0.1)
				(type default)
			)
			(layer "F.Fab")
		)
		(fp_line
			(start -0.12065 0.2794)
			(end -0.12065 0.3048)
			(stroke
				(width 0.1)
				(type default)
			)
			(layer "F.Fab")
		)
		(fp_line
			(start -0.12065 0.3048)
			(end -0.67945 0.3048)
			(stroke
				(width 0.1)
				(type default)
			)
			(layer "F.Fab")
		)
		(fp_line
			(start 0.120396 0.2794)
			(end -0.12065 0.2794)
			(stroke
				(width 0.1)
				(type default)
			)
			(layer "F.Fab")
		)
		(fp_line
			(start 0.120396 0.3048)
			(end 0.120396 0.2794)
			(stroke
				(width 0.1)
				(type default)
			)
			(layer "F.Fab")
		)
		(fp_line
			(start 0.12065 -0.3048)
			(end 0.67945 -0.3048)
			(stroke
				(width 0.1)
				(type default)
			)
			(layer "F.Fab")
		)
		(fp_line
			(start 0.12065 -0.2794)
			(end 0.12065 -0.3048)
			(stroke
				(width 0.1)
				(type default)
			)
			(layer "F.Fab")
		)
		(fp_line
			(start 0.67945 -0.3048)
			(end 0.67945 0.3048)
			(stroke
				(width 0.1)
				(type default)
			)
			(layer "F.Fab")
		)
		(fp_line
			(start 0.67945 0.3048)
			(end 0.120396 0.3048)
			(stroke
				(width 0.1)
				(type default)
			)
			(layer "F.Fab")
		)
		(pad "1" smd circle
			(at -0.40005 0)
			(size 0 0)
			(layers "F.Cu" "F.Mask" "F.Paste")
			(net "PWRGD_P12V_AUX_BUF")
		)
		(pad "2" smd circle
			(at 0.40005 0)
			(size 0 0)
			(layers "F.Cu" "F.Mask" "F.Paste")
			(net "PWRGD_P12V_AUX_BUF_R")
		)
	)
	(footprint ""
		(layer "B.Cu")
		(at 397.85544 -154.0256)
		(property "Reference" "R327"
			(at 0 0 0)
			(layer "B.SilkS")
			(hide yes)
			(effects
				(font
					(size 1.27 1.27)
				)
				(justify mirror)
			)
		)
		(property "Value" ""
			(at 0 0 0)
			(layer "B.Fab")
			(effects
				(font
					(size 1.27 1.27)
				)
				(justify mirror)
			)
		)
		(duplicate_pad_numbers_are_jumpers no)
		(fp_line
			(start -0.7874 -0.4064)
			(end -0.7874 0.4064)
			(stroke
				(width 0.1524)
				(type default)
			)
			(layer "B.SilkS")
		)
		(fp_line
			(start -0.7874 0.4064)
			(end 0.7874 0.4064)
			(stroke
				(width 0.1524)
				(type default)
			)
			(layer "B.SilkS")
		)
		(fp_line
			(start 0.7874 -0.4064)
			(end -0.7874 -0.4064)
			(stroke
				(width 0.1524)
				(type default)
			)
			(layer "B.SilkS")
		)
		(fp_line
			(start 0.7874 0.4064)
			(end 0.7874 -0.4064)
			(stroke
				(width 0.1524)
				(type default)
			)
			(layer "B.SilkS")
		)
		(fp_line
			(start -0.67945 -0.3048)
			(end -0.67945 0.3048)
			(stroke
				(width 0.1)
				(type default)
			)
			(layer "B.Fab")
		)
		(fp_line
			(start -0.67945 0.3048)
			(end -0.120396 0.3048)
			(stroke
				(width 0.1)
				(type default)
			)
			(layer "B.Fab")
		)
		(fp_line
			(start -0.12065 -0.3048)
			(end -0.67945 -0.3048)
			(stroke
				(width 0.1)
				(type default)
			)
			(layer "B.Fab")
		)
		(fp_line
			(start -0.12065 -0.2794)
			(end -0.12065 -0.3048)
			(stroke
				(width 0.1)
				(type default)
			)
			(layer "B.Fab")
		)
		(fp_line
			(start -0.120396 0.2794)
			(end 0.12065 0.2794)
			(stroke
				(width 0.1)
				(type default)
			)
			(layer "B.Fab")
		)
		(fp_line
			(start -0.120396 0.3048)
			(end -0.120396 0.2794)
			(stroke
				(width 0.1)
				(type default)
			)
			(layer "B.Fab")
		)
		(fp_line
			(start 0.12065 -0.305054)
			(end 0.12065 -0.2794)
			(stroke
				(width 0.1)
				(type default)
			)
			(layer "B.Fab")
		)
		(fp_line
			(start 0.12065 -0.2794)
			(end -0.12065 -0.2794)
			(stroke
				(width 0.1)
				(type default)
			)
			(layer "B.Fab")
		)
		(fp_line
			(start 0.12065 0.2794)
			(end 0.12065 0.3048)
			(stroke
				(width 0.1)
				(type default)
			)
			(layer "B.Fab")
		)
		(fp_line
			(start 0.12065 0.3048)
			(end 0.67945 0.3048)
			(stroke
				(width 0.1)
				(type default)
			)
			(layer "B.Fab")
		)
		(fp_line
			(start 0.67945 -0.305054)
			(end 0.12065 -0.305054)
			(stroke
				(width 0.1)
				(type default)
			)
			(layer "B.Fab")
		)
		(fp_line
			(start 0.67945 0.3048)
			(end 0.67945 -0.305054)
			(stroke
				(width 0.1)
				(type default)
			)
			(layer "B.Fab")
		)
		(pad "1" smd circle
			(at 0.40005 0 180)
			(size 0 0)
			(layers "B.Cu" "B.Mask" "B.Paste")
			(net "NCSI_NIC6_TX_EN")
		)
		(pad "2" smd circle
			(at -0.40005 0 180)
			(size 0 0)
			(layers "B.Cu" "B.Mask" "B.Paste")
			(net "GND")
		)
	)
	(footprint ""
		(layer "B.Cu")
		(at 338.266024 20.575524 180)
		(property "Reference" "DE06F_1"
			(at -2.195576 -3.047746 0)
			(unlocked yes)
			(layer "B.SilkS")
			(effects
				(font
					(size 0.7874 0.5842)
					(thickness 0.1524)
				)
				(justify left mirror)
			)
		)
		(property "Value" ""
			(at 0 0 0)
			(layer "B.Fab")
			(effects
				(font
					(size 1.27 1.27)
				)
				(justify mirror)
			)
		)
		(duplicate_pad_numbers_are_jumpers no)
		(fp_line
			(start 1.2192 2.1082)
			(end 1.2192 -2.1082)
			(stroke
				(width 0.1524)
				(type default)
			)
			(layer "B.SilkS")
		)
		(fp_line
			(start 1.2192 -2.1082)
			(end -1.2192 -2.1082)
			(stroke
				(width 0.1524)
				(type default)
			)
			(layer "B.SilkS")
		)
		(fp_line
			(start -1.2192 2.1082)
			(end 1.2192 2.1082)
			(stroke
				(width 0.1524)
				(type default)
			)
			(layer "B.SilkS")
		)
		(fp_line
			(start -1.2192 -2.1082)
			(end -1.2192 2.1082)
			(stroke
				(width 0.1524)
				(type default)
			)
			(layer "B.SilkS")
		)
		(pad "" np_thru_hole circle
			(at -3.4671 -1.27 90)
			(size 1.0414 1.0414)
			(drill 1.0414)
			(layers "*.Cu" "*.Mask")
			(clearance 0.381)
			(thermal_gap 0.381)
		)
		(pad "" np_thru_hole circle
			(at -3.4671 1.27 90)
			(size 1.0414 1.0414)
			(drill 1.0414)
			(layers "*.Cu" "*.Mask")
			(clearance 0.381)
			(thermal_gap 0.381)
		)
		(pad "" np_thru_hole circle
			(at 2.8829 -1.27 90)
			(size 1.0414 1.0414)
			(drill 1.0414)
			(layers "*.Cu" "*.Mask")
			(clearance 0.381)
			(thermal_gap 0.381)
		)
		(pad "" np_thru_hole circle
			(at 2.8829 1.27 90)
			(size 1.0414 1.0414)
			(drill 1.0414)
			(layers "*.Cu" "*.Mask")
			(clearance 0.381)
			(thermal_gap 0.381)
		)
		(pad "1" smd rect
			(at -0.8255 -0.249936 90)
			(size 0.3048 0.508)
			(layers "B.Cu" "B.Mask" "B.Paste")
			(net "85_5INCH_IN4_DP")
		)
		(pad "2" smd rect
			(at -0.8255 0.249936 90)
			(size 0.3048 0.508)
			(layers "B.Cu" "B.Mask" "B.Paste")
			(net "85_5INCH_IN4_DN")
		)
		(pad "3" smd circle
			(at 0 0)
			(size 0 0)
			(layers "B.Cu" "B.Mask" "B.Paste")
			(net "COUPON_GND2")
		)
		(zone
			(layers "F.Cu" "B.Cu" "In1.Cu" "In2.Cu" "In3.Cu" "In4.Cu" "In5.Cu" "In6.Cu"
				"In7.Cu" "In8.Cu" "In9.Cu" "In10.Cu" "In11.Cu" "In12.Cu" "In13.Cu" "In14.Cu"
				"In15.Cu" "In16.Cu"
			)
			(hatch none 0.5)
			(connect_pads
				(clearance 0)
			)
			(min_thickness 0.25)
			(keepout
				(tracks not_allowed)
				(vias allowed)
				(pads allowed)
				(copperpour not_allowed)
				(footprints allowed)
			)
			(placement
				(enabled no)
				(sheetname "")
			)
			(fill
				(thermal_gap 0.5)
				(thermal_bridge_width 0.5)
				(island_removal_mode 0)
			)
			(polygon
				(pts
					(arc
						(start 336.310224 19.305524)
						(mid 334.456024 19.305524)
						(end 336.310224 19.305524)
					)
				)
			)
		)
		(zone
			(layers "F.Cu" "B.Cu" "In1.Cu" "In2.Cu" "In3.Cu" "In4.Cu" "In5.Cu" "In6.Cu"
				"In7.Cu" "In8.Cu" "In9.Cu" "In10.Cu" "In11.Cu" "In12.Cu" "In13.Cu" "In14.Cu"
				"In15.Cu" "In16.Cu"
			)
			(hatch none 0.5)
			(connect_pads
				(clearance 0)
			)
			(min_thickness 0.25)
			(keepout
				(tracks not_allowed)
				(vias allowed)
				(pads allowed)
				(copperpour not_allowed)
				(footprints allowed)
			)
			(placement
				(enabled no)
				(sheetname "")
			)
			(fill
				(thermal_gap 0.5)
				(thermal_bridge_width 0.5)
				(island_removal_mode 0)
			)
			(polygon
				(pts
					(arc
						(start 336.310224 21.845524)
						(mid 334.456024 21.845524)
						(end 336.310224 21.845524)
					)
				)
			)
		)
		(zone
			(layers "F.Cu" "B.Cu" "In1.Cu" "In2.Cu" "In3.Cu" "In4.Cu" "In5.Cu" "In6.Cu"
				"In7.Cu" "In8.Cu" "In9.Cu" "In10.Cu" "In11.Cu" "In12.Cu" "In13.Cu" "In14.Cu"
				"In15.Cu" "In16.Cu"
			)
			(hatch none 0.5)
			(connect_pads
				(clearance 0)
			)
			(min_thickness 0.25)
			(keepout
				(tracks not_allowed)
				(vias allowed)
				(pads allowed)
				(copperpour not_allowed)
				(footprints allowed)
			)
			(placement
				(enabled no)
				(sheetname "")
			)
			(fill
				(thermal_gap 0.5)
				(thermal_bridge_width 0.5)
				(island_removal_mode 0)
			)
			(polygon
				(pts
					(arc
						(start 342.660224 19.305524)
						(mid 340.806024 19.305524)
						(end 342.660224 19.305524)
					)
				)
			)
		)
		(zone
			(layers "F.Cu" "B.Cu" "In1.Cu" "In2.Cu" "In3.Cu" "In4.Cu" "In5.Cu" "In6.Cu"
				"In7.Cu" "In8.Cu" "In9.Cu" "In10.Cu" "In11.Cu" "In12.Cu" "In13.Cu" "In14.Cu"
				"In15.Cu" "In16.Cu"
			)
			(hatch none 0.5)
			(connect_pads
				(clearance 0)
			)
			(min_thickness 0.25)
			(keepout
				(tracks not_allowed)
				(vias allowed)
				(pads allowed)
				(copperpour not_allowed)
				(footprints allowed)
			)
			(placement
				(enabled no)
				(sheetname "")
			)
			(fill
				(thermal_gap 0.5)
				(thermal_bridge_width 0.5)
				(island_removal_mode 0)
			)
			(polygon
				(pts
					(arc
						(start 342.660224 21.845524)
						(mid 340.806024 21.845524)
						(end 342.660224 21.845524)
					)
				)
			)
		)
		(zone
			(layer "B.Cu")
			(hatch none 0.5)
			(connect_pads
				(clearance 0)
			)
			(min_thickness 0.25)
			(keepout
				(tracks not_allowed)
				(vias allowed)
				(pads allowed)
				(copperpour not_allowed)
				(footprints allowed)
			)
			(placement
				(enabled no)
				(sheetname "")
			)
			(fill
				(thermal_gap 0.5)
				(thermal_bridge_width 0.5)
				(island_removal_mode 0)
			)
			(polygon
				(pts
					(xy 339.383624 21.124164) (xy 339.383624 21.02866) (xy 338.786724 21.02866) (xy 338.786724 20.62226)
					(xy 339.383624 20.62226) (xy 339.383624 20.528788) (xy 338.786724 20.528788) (xy 338.786724 20.122388)
					(xy 339.383624 20.122388) (xy 339.383624 20.026884) (xy 338.685124 20.026884) (xy 338.685124 21.124164)
				)
			)
		)
	)
	(footprint ""
		(layer "B.Cu")
		(at 59.649868 -290.199826 90)
		(property "Reference" "C1212"
			(at 0 0 90)
			(layer "B.SilkS")
			(hide yes)
			(effects
				(font
					(size 1.27 1.27)
				)
				(justify mirror)
			)
		)
		(property "Value" ""
			(at 0 0 90)
			(layer "B.Fab")
			(effects
				(font
					(size 1.27 1.27)
				)
				(justify mirror)
			)
		)
		(duplicate_pad_numbers_are_jumpers no)
		(fp_line
			(start 0.299974 -0.150114)
			(end -0.299974 -0.150114)
			(stroke
				(width 0.1)
				(type default)
			)
			(layer "B.Fab")
		)
		(fp_line
			(start -0.299974 -0.150114)
			(end -0.299974 0.150114)
			(stroke
				(width 0.1)
				(type default)
			)
			(layer "B.Fab")
		)
		(fp_line
			(start 0.299974 0.150114)
			(end 0.299974 -0.150114)
			(stroke
				(width 0.1)
				(type default)
			)
			(layer "B.Fab")
		)
		(fp_line
			(start -0.299974 0.150114)
			(end 0.299974 0.150114)
			(stroke
				(width 0.1)
				(type default)
			)
			(layer "B.Fab")
		)
		(pad "1" smd rect
			(at 0.2667 0 270)
			(size 0.3048 0.381)
			(layers "B.Cu" "B.Mask" "B.Paste")
			(net "P0V8_SERDES_VDDA_PEX0")
		)
		(pad "2" smd rect
			(at -0.2667 0 270)
			(size 0.3048 0.381)
			(layers "B.Cu" "B.Mask" "B.Paste")
			(net "GND")
		)
	)
	(footprint ""
		(layer "B.Cu")
		(at 127.0762 -325.61149 -90)
		(property "Reference" "C4256"
			(at 0 0 90)
			(layer "B.SilkS")
			(hide yes)
			(effects
				(font
					(size 1.27 1.27)
				)
				(justify mirror)
			)
		)
		(property "Value" ""
			(at 0 0 90)
			(layer "B.Fab")
			(effects
				(font
					(size 1.27 1.27)
				)
				(justify mirror)
			)
		)
		(duplicate_pad_numbers_are_jumpers no)
		(fp_line
			(start -1.2954 0.5842)
			(end 1.2954 0.5842)
			(stroke
				(width 0.1524)
				(type default)
			)
			(layer "B.SilkS")
		)
		(fp_line
			(start 1.2954 0.5842)
			(end 1.2954 -0.5842)
			(stroke
				(width 0.1524)
				(type default)
			)
			(layer "B.SilkS")
		)
		(fp_line
			(start -1.2954 -0.5842)
			(end -1.2954 0.5842)
			(stroke
				(width 0.1524)
				(type default)
			)
			(layer "B.SilkS")
		)
		(fp_line
			(start 1.2954 -0.5842)
			(end -1.2954 -0.5842)
			(stroke
				(width 0.1524)
				(type default)
			)
			(layer "B.SilkS")
		)
		(fp_line
			(start -0.8636 0.4572)
			(end 0.8636 0.4572)
			(stroke
				(width 0.1)
				(type default)
			)
			(layer "B.Fab")
		)
		(fp_line
			(start 0.8636 0.4572)
			(end 0.8636 0.4064)
			(stroke
				(width 0.1)
				(type default)
			)
			(layer "B.Fab")
		)
		(fp_line
			(start -1.1938 0.4064)
			(end -0.8636 0.4064)
			(stroke
				(width 0.1)
				(type default)
			)
			(layer "B.Fab")
		)
		(fp_line
			(start -0.8636 0.4064)
			(end -0.8636 0.4572)
			(stroke
				(width 0.1)
				(type default)
			)
			(layer "B.Fab")
		)
		(fp_line
			(start 0.8636 0.4064)
			(end 1.1938 0.4064)
			(stroke
				(width 0.1)
				(type default)
			)
			(layer "B.Fab")
		)
		(fp_line
			(start 1.1938 0.4064)
			(end 1.1938 -0.4064)
			(stroke
				(width 0.1)
				(type default)
			)
			(layer "B.Fab")
		)
		(fp_line
			(start -1.1938 -0.4064)
			(end -1.1938 0.4064)
			(stroke
				(width 0.1)
				(type default)
			)
			(layer "B.Fab")
		)
		(fp_line
			(start -0.8636 -0.4064)
			(end -1.1938 -0.4064)
			(stroke
				(width 0.1)
				(type default)
			)
			(layer "B.Fab")
		)
		(fp_line
			(start 0.8636 -0.4064)
			(end 0.8636 -0.4572)
			(stroke
				(width 0.1)
				(type default)
			)
			(layer "B.Fab")
		)
		(fp_line
			(start 1.1938 -0.4064)
			(end 0.8636 -0.4064)
			(stroke
				(width 0.1)
				(type default)
			)
			(layer "B.Fab")
		)
		(fp_line
			(start -0.8636 -0.4572)
			(end -0.8636 -0.4064)
			(stroke
				(width 0.1)
				(type default)
			)
			(layer "B.Fab")
		)
		(fp_line
			(start 0.8636 -0.4572)
			(end -0.8636 -0.4572)
			(stroke
				(width 0.1)
				(type default)
			)
			(layer "B.Fab")
		)
		(pad "1" smd rect
			(at 0.7366 0 180)
			(size 0.7112 0.8128)
			(layers "B.Cu" "B.Mask" "B.Paste")
			(net "P0V8_SERDES_VDDA_PEX1_C2")
		)
		(pad "2" smd rect
			(at -0.7366 0 180)
			(size 0.7112 0.8128)
			(layers "B.Cu" "B.Mask" "B.Paste")
			(net "GND")
		)
	)
	(footprint ""
		(layer "B.Cu")
		(at 236.415072 -217.104214 -90)
		(property "Reference" "C2022"
			(at 0 0 90)
			(layer "B.SilkS")
			(hide yes)
			(effects
				(font
					(size 1.27 1.27)
				)
				(justify mirror)
			)
		)
		(property "Value" ""
			(at 0 0 90)
			(layer "B.Fab")
			(effects
				(font
					(size 1.27 1.27)
				)
				(justify mirror)
			)
		)
		(duplicate_pad_numbers_are_jumpers no)
		(fp_line
			(start -0.69215 0.2921)
			(end 0.69215 0.2921)
			(stroke
				(width 0.1524)
				(type default)
			)
			(layer "B.SilkS")
		)
		(fp_line
			(start 0.69215 0.2921)
			(end 0.69215 -0.2921)
			(stroke
				(width 0.1524)
				(type default)
			)
			(layer "B.SilkS")
		)
		(fp_line
			(start -0.69215 -0.2921)
			(end -0.69215 0.2921)
			(stroke
				(width 0.1524)
				(type default)
			)
			(layer "B.SilkS")
		)
		(fp_line
			(start 0.69215 -0.2921)
			(end -0.69215 -0.2921)
			(stroke
				(width 0.1524)
				(type default)
			)
			(layer "B.SilkS")
		)
		(fp_line
			(start -0.51435 0.2794)
			(end 0.51435 0.2794)
			(stroke
				(width 0.1)
				(type default)
			)
			(layer "B.Fab")
		)
		(fp_line
			(start 0.51435 0.2794)
			(end 0.51435 -0.2794)
			(stroke
				(width 0.1)
				(type default)
			)
			(layer "B.Fab")
		)
		(fp_line
			(start -0.51435 -0.2794)
			(end -0.51435 0.2794)
			(stroke
				(width 0.1)
				(type default)
			)
			(layer "B.Fab")
		)
		(fp_line
			(start 0.51435 -0.2794)
			(end -0.51435 -0.2794)
			(stroke
				(width 0.1)
				(type default)
			)
			(layer "B.Fab")
		)
		(pad "1" smd circle
			(at 0.40005 0 90)
			(size 0 0)
			(layers "B.Cu" "B.Mask" "B.Paste")
			(net "P1V2_BIC_PLL")
		)
		(pad "2" smd circle
			(at -0.40005 0 90)
			(size 0 0)
			(layers "B.Cu" "B.Mask" "B.Paste")
			(net "GND")
		)
		(zone
			(layer "B.Cu")
			(hatch none 0.5)
			(connect_pads
				(clearance 0)
			)
			(min_thickness 0.25)
			(keepout
				(tracks not_allowed)
				(vias allowed)
				(pads allowed)
				(copperpour not_allowed)
				(footprints allowed)
			)
			(placement
				(enabled no)
				(sheetname "")
			)
			(fill
				(thermal_gap 0.5)
				(thermal_bridge_width 0.5)
				(island_removal_mode 0)
			)
			(polygon
				(pts
					(xy 236.327442 -216.913714) (xy 236.269276 -217.005154) (xy 236.269276 -217.204544) (xy 236.327442 -217.294714)
					(xy 236.502702 -217.294714) (xy 236.561122 -217.204544) (xy 236.561122 -217.005154) (xy 236.502956 -216.913714)
				)
			)
		)
	)
	(footprint ""
		(layer "B.Cu")
		(at 343.323672 -326.945498 -90)
		(property "Reference" "C4315"
			(at 0 0 90)
			(layer "B.SilkS")
			(hide yes)
			(effects
				(font
					(size 1.27 1.27)
				)
				(justify mirror)
			)
		)
		(property "Value" ""
			(at 0 0 90)
			(layer "B.Fab")
			(effects
				(font
					(size 1.27 1.27)
				)
				(justify mirror)
			)
		)
		(duplicate_pad_numbers_are_jumpers no)
		(fp_line
			(start -1.2954 0.5842)
			(end 1.2954 0.5842)
			(stroke
				(width 0.1524)
				(type default)
			)
			(layer "B.SilkS")
		)
		(fp_line
			(start 1.2954 0.5842)
			(end 1.2954 -0.5842)
			(stroke
				(width 0.1524)
				(type default)
			)
			(layer "B.SilkS")
		)
		(fp_line
			(start -1.2954 -0.5842)
			(end -1.2954 0.5842)
			(stroke
				(width 0.1524)
				(type default)
			)
			(layer "B.SilkS")
		)
		(fp_line
			(start 1.2954 -0.5842)
			(end -1.2954 -0.5842)
			(stroke
				(width 0.1524)
				(type default)
			)
			(layer "B.SilkS")
		)
		(fp_line
			(start -0.8636 0.4572)
			(end 0.8636 0.4572)
			(stroke
				(width 0.1)
				(type default)
			)
			(layer "B.Fab")
		)
		(fp_line
			(start 0.8636 0.4572)
			(end 0.8636 0.4064)
			(stroke
				(width 0.1)
				(type default)
			)
			(layer "B.Fab")
		)
		(fp_line
			(start -1.1938 0.4064)
			(end -0.8636 0.4064)
			(stroke
				(width 0.1)
				(type default)
			)
			(layer "B.Fab")
		)
		(fp_line
			(start -0.8636 0.4064)
			(end -0.8636 0.4572)
			(stroke
				(width 0.1)
				(type default)
			)
			(layer "B.Fab")
		)
		(fp_line
			(start 0.8636 0.4064)
			(end 1.1938 0.4064)
			(stroke
				(width 0.1)
				(type default)
			)
			(layer "B.Fab")
		)
		(fp_line
			(start 1.1938 0.4064)
			(end 1.1938 -0.4064)
			(stroke
				(width 0.1)
				(type default)
			)
			(layer "B.Fab")
		)
		(fp_line
			(start -1.1938 -0.4064)
			(end -1.1938 0.4064)
			(stroke
				(width 0.1)
				(type default)
			)
			(layer "B.Fab")
		)
		(fp_line
			(start -0.8636 -0.4064)
			(end -1.1938 -0.4064)
			(stroke
				(width 0.1)
				(type default)
			)
			(layer "B.Fab")
		)
		(fp_line
			(start 0.8636 -0.4064)
			(end 0.8636 -0.4572)
			(stroke
				(width 0.1)
				(type default)
			)
			(layer "B.Fab")
		)
		(fp_line
			(start 1.1938 -0.4064)
			(end 0.8636 -0.4064)
			(stroke
				(width 0.1)
				(type default)
			)
			(layer "B.Fab")
		)
		(fp_line
			(start -0.8636 -0.4572)
			(end -0.8636 -0.4064)
			(stroke
				(width 0.1)
				(type default)
			)
			(layer "B.Fab")
		)
		(fp_line
			(start 0.8636 -0.4572)
			(end -0.8636 -0.4572)
			(stroke
				(width 0.1)
				(type default)
			)
			(layer "B.Fab")
		)
		(pad "1" smd rect
			(at 0.7366 0 180)
			(size 0.7112 0.8128)
			(layers "B.Cu" "B.Mask" "B.Paste")
			(net "P0V8_SERDES_VDDA_PEX2_C5")
		)
		(pad "2" smd rect
			(at -0.7366 0 180)
			(size 0.7112 0.8128)
			(layers "B.Cu" "B.Mask" "B.Paste")
			(net "GND")
		)
	)
	(footprint ""
		(layer "B.Cu")
		(at 165.774878 -293.99992 -90)
		(property "Reference" "C1381"
			(at 0 0 90)
			(layer "B.SilkS")
			(hide yes)
			(effects
				(font
					(size 1.27 1.27)
				)
				(justify mirror)
			)
		)
		(property "Value" ""
			(at 0 0 90)
			(layer "B.Fab")
			(effects
				(font
					(size 1.27 1.27)
				)
				(justify mirror)
			)
		)
		(duplicate_pad_numbers_are_jumpers no)
		(fp_line
			(start -0.299974 0.150114)
			(end 0.299974 0.150114)
			(stroke
				(width 0.1)
				(type default)
			)
			(layer "B.Fab")
		)
		(fp_line
			(start 0.299974 0.150114)
			(end 0.299974 -0.150114)
			(stroke
				(width 0.1)
				(type default)
			)
			(layer "B.Fab")
		)
		(fp_line
			(start -0.299974 -0.150114)
			(end -0.299974 0.150114)
			(stroke
				(width 0.1)
				(type default)
			)
			(layer "B.Fab")
		)
		(fp_line
			(start 0.299974 -0.150114)
			(end -0.299974 -0.150114)
			(stroke
				(width 0.1)
				(type default)
			)
			(layer "B.Fab")
		)
		(pad "1" smd rect
			(at 0.2667 0 90)
			(size 0.3048 0.381)
			(layers "B.Cu" "B.Mask" "B.Paste")
			(net "P0V8_PEX1")
		)
		(pad "2" smd rect
			(at -0.2667 0 90)
			(size 0.3048 0.381)
			(layers "B.Cu" "B.Mask" "B.Paste")
			(net "GND")
		)
	)
	(footprint ""
		(layer "B.Cu")
		(at 121.642378 -260.509258 90)
		(property "Reference" "PR7135"
			(at 0 0 90)
			(layer "B.SilkS")
			(hide yes)
			(effects
				(font
					(size 1.27 1.27)
				)
				(justify mirror)
			)
		)
		(property "Value" ""
			(at 0 0 90)
			(layer "B.Fab")
			(effects
				(font
					(size 1.27 1.27)
				)
				(justify mirror)
			)
		)
		(duplicate_pad_numbers_are_jumpers no)
		(fp_line
			(start 0.7874 -0.4064)
			(end -0.7874 -0.4064)
			(stroke
				(width 0.1524)
				(type default)
			)
			(layer "B.SilkS")
		)
		(fp_line
			(start -0.7874 -0.4064)
			(end -0.7874 0.4064)
			(stroke
				(width 0.1524)
				(type default)
			)
			(layer "B.SilkS")
		)
		(fp_line
			(start 0.7874 0.4064)
			(end 0.7874 -0.4064)
			(stroke
				(width 0.1524)
				(type default)
			)
			(layer "B.SilkS")
		)
		(fp_line
			(start -0.7874 0.4064)
			(end 0.7874 0.4064)
			(stroke
				(width 0.1524)
				(type default)
			)
			(layer "B.SilkS")
		)
		(fp_line
			(start 0.67945 -0.305054)
			(end 0.12065 -0.305054)
			(stroke
				(width 0.1)
				(type default)
			)
			(layer "B.Fab")
		)
		(fp_line
			(start 0.12065 -0.305054)
			(end 0.12065 -0.2794)
			(stroke
				(width 0.1)
				(type default)
			)
			(layer "B.Fab")
		)
		(fp_line
			(start -0.12065 -0.3048)
			(end -0.67945 -0.3048)
			(stroke
				(width 0.1)
				(type default)
			)
			(layer "B.Fab")
		)
		(fp_line
			(start -0.67945 -0.3048)
			(end -0.67945 0.3048)
			(stroke
				(width 0.1)
				(type default)
			)
			(layer "B.Fab")
		)
		(fp_line
			(start 0.12065 -0.2794)
			(end -0.12065 -0.2794)
			(stroke
				(width 0.1)
				(type default)
			)
			(layer "B.Fab")
		)
		(fp_line
			(start -0.12065 -0.2794)
			(end -0.12065 -0.3048)
			(stroke
				(width 0.1)
				(type default)
			)
			(layer "B.Fab")
		)
		(fp_line
			(start 0.12065 0.2794)
			(end 0.12065 0.3048)
			(stroke
				(width 0.1)
				(type default)
			)
			(layer "B.Fab")
		)
		(fp_line
			(start -0.120396 0.2794)
			(end 0.12065 0.2794)
			(stroke
				(width 0.1)
				(type default)
			)
			(layer "B.Fab")
		)
		(fp_line
			(start 0.67945 0.3048)
			(end 0.67945 -0.305054)
			(stroke
				(width 0.1)
				(type default)
			)
			(layer "B.Fab")
		)
		(fp_line
			(start 0.12065 0.3048)
			(end 0.67945 0.3048)
			(stroke
				(width 0.1)
				(type default)
			)
			(layer "B.Fab")
		)
		(fp_line
			(start -0.120396 0.3048)
			(end -0.120396 0.2794)
			(stroke
				(width 0.1)
				(type default)
			)
			(layer "B.Fab")
		)
		(fp_line
			(start -0.67945 0.3048)
			(end -0.120396 0.3048)
			(stroke
				(width 0.1)
				(type default)
			)
			(layer "B.Fab")
		)
		(pad "1" smd circle
			(at 0.40005 0 270)
			(size 0 0)
			(layers "B.Cu" "B.Mask" "B.Paste")
			(net "NC_P0V8_PEX0_ISEN2")
		)
		(pad "2" smd circle
			(at -0.40005 0 270)
			(size 0 0)
			(layers "B.Cu" "B.Mask" "B.Paste")
			(net "GND")
		)
	)
	(footprint ""
		(layer "B.Cu")
		(at 121.050558 -308.580028 90)
		(property "Reference" "C1412"
			(at 0 0 90)
			(layer "B.SilkS")
			(hide yes)
			(effects
				(font
					(size 1.27 1.27)
				)
				(justify mirror)
			)
		)
		(property "Value" ""
			(at 0 0 90)
			(layer "B.Fab")
			(effects
				(font
					(size 1.27 1.27)
				)
				(justify mirror)
			)
		)
		(duplicate_pad_numbers_are_jumpers no)
		(fp_line
			(start 1.2954 -0.5842)
			(end -1.2954 -0.5842)
			(stroke
				(width 0.1524)
				(type default)
			)
			(layer "B.SilkS")
		)
		(fp_line
			(start -1.2954 -0.5842)
			(end -1.2954 0.5842)
			(stroke
				(width 0.1524)
				(type default)
			)
			(layer "B.SilkS")
		)
		(fp_line
			(start 1.2954 0.5842)
			(end 1.2954 -0.5842)
			(stroke
				(width 0.1524)
				(type default)
			)
			(layer "B.SilkS")
		)
		(fp_line
			(start -1.2954 0.5842)
			(end 1.2954 0.5842)
			(stroke
				(width 0.1524)
				(type default)
			)
			(layer "B.SilkS")
		)
		(fp_line
			(start 0.8636 -0.4572)
			(end -0.8636 -0.4572)
			(stroke
				(width 0.1)
				(type default)
			)
			(layer "B.Fab")
		)
		(fp_line
			(start -0.8636 -0.4572)
			(end -0.8636 -0.4064)
			(stroke
				(width 0.1)
				(type default)
			)
			(layer "B.Fab")
		)
		(fp_line
			(start 1.1938 -0.4064)
			(end 0.8636 -0.4064)
			(stroke
				(width 0.1)
				(type default)
			)
			(layer "B.Fab")
		)
		(fp_line
			(start 0.8636 -0.4064)
			(end 0.8636 -0.4572)
			(stroke
				(width 0.1)
				(type default)
			)
			(layer "B.Fab")
		)
		(fp_line
			(start -0.8636 -0.4064)
			(end -1.1938 -0.4064)
			(stroke
				(width 0.1)
				(type default)
			)
			(layer "B.Fab")
		)
		(fp_line
			(start -1.1938 -0.4064)
			(end -1.1938 0.4064)
			(stroke
				(width 0.1)
				(type default)
			)
			(layer "B.Fab")
		)
		(fp_line
			(start 1.1938 0.4064)
			(end 1.1938 -0.4064)
			(stroke
				(width 0.1)
				(type default)
			)
			(layer "B.Fab")
		)
		(fp_line
			(start 0.8636 0.4064)
			(end 1.1938 0.4064)
			(stroke
				(width 0.1)
				(type default)
			)
			(layer "B.Fab")
		)
		(fp_line
			(start -0.8636 0.4064)
			(end -0.8636 0.4572)
			(stroke
				(width 0.1)
				(type default)
			)
			(layer "B.Fab")
		)
		(fp_line
			(start -1.1938 0.4064)
			(end -0.8636 0.4064)
			(stroke
				(width 0.1)
				(type default)
			)
			(layer "B.Fab")
		)
		(fp_line
			(start 0.8636 0.4572)
			(end 0.8636 0.4064)
			(stroke
				(width 0.1)
				(type default)
			)
			(layer "B.Fab")
		)
		(fp_line
			(start -0.8636 0.4572)
			(end 0.8636 0.4572)
			(stroke
				(width 0.1)
				(type default)
			)
			(layer "B.Fab")
		)
		(pad "1" smd rect
			(at 0.7366 0)
			(size 0.7112 0.8128)
			(layers "B.Cu" "B.Mask" "B.Paste")
			(net "P0V8_SERDES_VDDA_PEX1")
		)
		(pad "2" smd rect
			(at -0.7366 0)
			(size 0.7112 0.8128)
			(layers "B.Cu" "B.Mask" "B.Paste")
			(net "GND")
		)
	)
	(footprint ""
		(layer "B.Cu")
		(at 418.40404 -98.552)
		(property "Reference" "R380"
			(at 0 0 0)
			(layer "B.SilkS")
			(hide yes)
			(effects
				(font
					(size 1.27 1.27)
				)
				(justify mirror)
			)
		)
		(property "Value" ""
			(at 0 0 0)
			(layer "B.Fab")
			(effects
				(font
					(size 1.27 1.27)
				)
				(justify mirror)
			)
		)
		(duplicate_pad_numbers_are_jumpers no)
		(fp_line
			(start -0.7874 -0.4064)
			(end -0.7874 0.4064)
			(stroke
				(width 0.1524)
				(type default)
			)
			(layer "B.SilkS")
		)
		(fp_line
			(start -0.7874 0.4064)
			(end 0.7874 0.4064)
			(stroke
				(width 0.1524)
				(type default)
			)
			(layer "B.SilkS")
		)
		(fp_line
			(start 0.7874 -0.4064)
			(end -0.7874 -0.4064)
			(stroke
				(width 0.1524)
				(type default)
			)
			(layer "B.SilkS")
		)
		(fp_line
			(start 0.7874 0.4064)
			(end 0.7874 -0.4064)
			(stroke
				(width 0.1524)
				(type default)
			)
			(layer "B.SilkS")
		)
		(fp_line
			(start -0.67945 -0.3048)
			(end -0.67945 0.3048)
			(stroke
				(width 0.1)
				(type default)
			)
			(layer "B.Fab")
		)
		(fp_line
			(start -0.67945 0.3048)
			(end -0.120396 0.3048)
			(stroke
				(width 0.1)
				(type default)
			)
			(layer "B.Fab")
		)
		(fp_line
			(start -0.12065 -0.3048)
			(end -0.67945 -0.3048)
			(stroke
				(width 0.1)
				(type default)
			)
			(layer "B.Fab")
		)
		(fp_line
			(start -0.12065 -0.2794)
			(end -0.12065 -0.3048)
			(stroke
				(width 0.1)
				(type default)
			)
			(layer "B.Fab")
		)
		(fp_line
			(start -0.120396 0.2794)
			(end 0.12065 0.2794)
			(stroke
				(width 0.1)
				(type default)
			)
			(layer "B.Fab")
		)
		(fp_line
			(start -0.120396 0.3048)
			(end -0.120396 0.2794)
			(stroke
				(width 0.1)
				(type default)
			)
			(layer "B.Fab")
		)
		(fp_line
			(start 0.12065 -0.305054)
			(end 0.12065 -0.2794)
			(stroke
				(width 0.1)
				(type default)
			)
			(layer "B.Fab")
		)
		(fp_line
			(start 0.12065 -0.2794)
			(end -0.12065 -0.2794)
			(stroke
				(width 0.1)
				(type default)
			)
			(layer "B.Fab")
		)
		(fp_line
			(start 0.12065 0.2794)
			(end 0.12065 0.3048)
			(stroke
				(width 0.1)
				(type default)
			)
			(layer "B.Fab")
		)
		(fp_line
			(start 0.12065 0.3048)
			(end 0.67945 0.3048)
			(stroke
				(width 0.1)
				(type default)
			)
			(layer "B.Fab")
		)
		(fp_line
			(start 0.67945 -0.305054)
			(end 0.12065 -0.305054)
			(stroke
				(width 0.1)
				(type default)
			)
			(layer "B.Fab")
		)
		(fp_line
			(start 0.67945 0.3048)
			(end 0.67945 -0.305054)
			(stroke
				(width 0.1)
				(type default)
			)
			(layer "B.Fab")
		)
		(pad "1" smd circle
			(at 0.40005 0 180)
			(size 0 0)
			(layers "B.Cu" "B.Mask" "B.Paste")
			(net "NIC7_MAIN_PWR_EN")
		)
		(pad "2" smd circle
			(at -0.40005 0 180)
			(size 0 0)
			(layers "B.Cu" "B.Mask" "B.Paste")
			(net "GND")
		)
	)
	(footprint ""
		(layer "B.Cu")
		(at 75.716892 -295.42486)
		(property "Reference" "C2902"
			(at 0 0 0)
			(layer "B.SilkS")
			(hide yes)
			(effects
				(font
					(size 1.27 1.27)
				)
				(justify mirror)
			)
		)
		(property "Value" ""
			(at 0 0 0)
			(layer "B.Fab")
			(effects
				(font
					(size 1.27 1.27)
				)
				(justify mirror)
			)
		)
		(duplicate_pad_numbers_are_jumpers no)
		(fp_line
			(start -1.2954 -0.5842)
			(end -1.2954 0.5842)
			(stroke
				(width 0.1524)
				(type default)
			)
			(layer "B.SilkS")
		)
		(fp_line
			(start -1.2954 0.5842)
			(end 1.2954 0.5842)
			(stroke
				(width 0.1524)
				(type default)
			)
			(layer "B.SilkS")
		)
		(fp_line
			(start 1.2954 -0.5842)
			(end -1.2954 -0.5842)
			(stroke
				(width 0.1524)
				(type default)
			)
			(layer "B.SilkS")
		)
		(fp_line
			(start 1.2954 0.5842)
			(end 1.2954 -0.5842)
			(stroke
				(width 0.1524)
				(type default)
			)
			(layer "B.SilkS")
		)
		(fp_line
			(start -1.1938 -0.4064)
			(end -1.1938 0.4064)
			(stroke
				(width 0.1)
				(type default)
			)
			(layer "B.Fab")
		)
		(fp_line
			(start -1.1938 0.4064)
			(end -0.8636 0.4064)
			(stroke
				(width 0.1)
				(type default)
			)
			(layer "B.Fab")
		)
		(fp_line
			(start -0.8636 -0.4572)
			(end -0.8636 -0.4064)
			(stroke
				(width 0.1)
				(type default)
			)
			(layer "B.Fab")
		)
		(fp_line
			(start -0.8636 -0.4064)
			(end -1.1938 -0.4064)
			(stroke
				(width 0.1)
				(type default)
			)
			(layer "B.Fab")
		)
		(fp_line
			(start -0.8636 0.4064)
			(end -0.8636 0.4572)
			(stroke
				(width 0.1)
				(type default)
			)
			(layer "B.Fab")
		)
		(fp_line
			(start -0.8636 0.4572)
			(end 0.8636 0.4572)
			(stroke
				(width 0.1)
				(type default)
			)
			(layer "B.Fab")
		)
		(fp_line
			(start 0.8636 -0.4572)
			(end -0.8636 -0.4572)
			(stroke
				(width 0.1)
				(type default)
			)
			(layer "B.Fab")
		)
		(fp_line
			(start 0.8636 -0.4064)
			(end 0.8636 -0.4572)
			(stroke
				(width 0.1)
				(type default)
			)
			(layer "B.Fab")
		)
		(fp_line
			(start 0.8636 0.4064)
			(end 1.1938 0.4064)
			(stroke
				(width 0.1)
				(type default)
			)
			(layer "B.Fab")
		)
		(fp_line
			(start 0.8636 0.4572)
			(end 0.8636 0.4064)
			(stroke
				(width 0.1)
				(type default)
			)
			(layer "B.Fab")
		)
		(fp_line
			(start 1.1938 -0.4064)
			(end 0.8636 -0.4064)
			(stroke
				(width 0.1)
				(type default)
			)
			(layer "B.Fab")
		)
		(fp_line
			(start 1.1938 0.4064)
			(end 1.1938 -0.4064)
			(stroke
				(width 0.1)
				(type default)
			)
			(layer "B.Fab")
		)
		(pad "1" smd rect
			(at 0.7366 0 270)
			(size 0.7112 0.8128)
			(layers "B.Cu" "B.Mask" "B.Paste")
			(net "P1V25_PEX0")
		)
		(pad "2" smd rect
			(at -0.7366 0 270)
			(size 0.7112 0.8128)
			(layers "B.Cu" "B.Mask" "B.Paste")
			(net "GND")
		)
	)
	(footprint ""
		(layer "B.Cu")
		(at 279.977342 -299.5422 90)
		(property "Reference" "C3371"
			(at 0 0 90)
			(layer "B.SilkS")
			(hide yes)
			(effects
				(font
					(size 1.27 1.27)
				)
				(justify mirror)
			)
		)
		(property "Value" ""
			(at 0 0 90)
			(layer "B.Fab")
			(effects
				(font
					(size 1.27 1.27)
				)
				(justify mirror)
			)
		)
		(duplicate_pad_numbers_are_jumpers no)
		(fp_line
			(start 0.299974 -0.150114)
			(end -0.299974 -0.150114)
			(stroke
				(width 0.1)
				(type default)
			)
			(layer "B.Fab")
		)
		(fp_line
			(start -0.299974 -0.150114)
			(end -0.299974 0.150114)
			(stroke
				(width 0.1)
				(type default)
			)
			(layer "B.Fab")
		)
		(fp_line
			(start 0.299974 0.150114)
			(end 0.299974 -0.150114)
			(stroke
				(width 0.1)
				(type default)
			)
			(layer "B.Fab")
		)
		(fp_line
			(start -0.299974 0.150114)
			(end 0.299974 0.150114)
			(stroke
				(width 0.1)
				(type default)
			)
			(layer "B.Fab")
		)
		(pad "1" smd rect
			(at 0.2667 0 270)
			(size 0.3048 0.381)
			(layers "B.Cu" "B.Mask" "B.Paste")
			(net "PCEPLL0_VDDA18_PEX2")
		)
		(pad "2" smd rect
			(at -0.2667 0 270)
			(size 0.3048 0.381)
			(layers "B.Cu" "B.Mask" "B.Paste")
			(net "GND")
		)
	)
	(footprint ""
		(layer "B.Cu")
		(at 363.710474 -282.244038 180)
		(property "Reference" "PR7174"
			(at 0 0 0)
			(layer "B.SilkS")
			(hide yes)
			(effects
				(font
					(size 1.27 1.27)
				)
				(justify mirror)
			)
		)
		(property "Value" ""
			(at 0 0 0)
			(layer "B.Fab")
			(effects
				(font
					(size 1.27 1.27)
				)
				(justify mirror)
			)
		)
		(duplicate_pad_numbers_are_jumpers no)
		(fp_line
			(start 0.7874 0.4064)
			(end 0.7874 -0.4064)
			(stroke
				(width 0.1524)
				(type default)
			)
			(layer "B.SilkS")
		)
		(fp_line
			(start 0.7874 -0.4064)
			(end -0.7874 -0.4064)
			(stroke
				(width 0.1524)
				(type default)
			)
			(layer "B.SilkS")
		)
		(fp_line
			(start -0.7874 0.4064)
			(end 0.7874 0.4064)
			(stroke
				(width 0.1524)
				(type default)
			)
			(layer "B.SilkS")
		)
		(fp_line
			(start -0.7874 -0.4064)
			(end -0.7874 0.4064)
			(stroke
				(width 0.1524)
				(type default)
			)
			(layer "B.SilkS")
		)
		(fp_line
			(start 0.67945 0.3048)
			(end 0.67945 -0.305054)
			(stroke
				(width 0.1)
				(type default)
			)
			(layer "B.Fab")
		)
		(fp_line
			(start 0.67945 -0.305054)
			(end 0.12065 -0.305054)
			(stroke
				(width 0.1)
				(type default)
			)
			(layer "B.Fab")
		)
		(fp_line
			(start 0.12065 0.3048)
			(end 0.67945 0.3048)
			(stroke
				(width 0.1)
				(type default)
			)
			(layer "B.Fab")
		)
		(fp_line
			(start 0.12065 0.2794)
			(end 0.12065 0.3048)
			(stroke
				(width 0.1)
				(type default)
			)
			(layer "B.Fab")
		)
		(fp_line
			(start 0.12065 -0.2794)
			(end -0.12065 -0.2794)
			(stroke
				(width 0.1)
				(type default)
			)
			(layer "B.Fab")
		)
		(fp_line
			(start 0.12065 -0.305054)
			(end 0.12065 -0.2794)
			(stroke
				(width 0.1)
				(type default)
			)
			(layer "B.Fab")
		)
		(fp_line
			(start -0.120396 0.3048)
			(end -0.120396 0.2794)
			(stroke
				(width 0.1)
				(type default)
			)
			(layer "B.Fab")
		)
		(fp_line
			(start -0.120396 0.2794)
			(end 0.12065 0.2794)
			(stroke
				(width 0.1)
				(type default)
			)
			(layer "B.Fab")
		)
		(fp_line
			(start -0.12065 -0.2794)
			(end -0.12065 -0.3048)
			(stroke
				(width 0.1)
				(type default)
			)
			(layer "B.Fab")
		)
		(fp_line
			(start -0.12065 -0.3048)
			(end -0.67945 -0.3048)
			(stroke
				(width 0.1)
				(type default)
			)
			(layer "B.Fab")
		)
		(fp_line
			(start -0.67945 0.3048)
			(end -0.120396 0.3048)
			(stroke
				(width 0.1)
				(type default)
			)
			(layer "B.Fab")
		)
		(fp_line
			(start -0.67945 -0.3048)
			(end -0.67945 0.3048)
			(stroke
				(width 0.1)
				(type default)
			)
			(layer "B.Fab")
		)
		(pad "1" smd circle
			(at 0.40005 0)
			(size 0 0)
			(layers "B.Cu" "B.Mask" "B.Paste")
			(net "P0V8_PEX2_EN4")
		)
		(pad "2" smd circle
			(at -0.40005 0)
			(size 0 0)
			(layers "B.Cu" "B.Mask" "B.Paste")
			(net "P0V8_PEX3_VCC2")
		)
	)
	(footprint ""
		(layer "B.Cu")
		(at 222.212154 -193.759836 90)
		(property "Reference" "R467"
			(at 0 0 90)
			(layer "B.SilkS")
			(hide yes)
			(effects
				(font
					(size 1.27 1.27)
				)
				(justify mirror)
			)
		)
		(property "Value" ""
			(at 0 0 90)
			(layer "B.Fab")
			(effects
				(font
					(size 1.27 1.27)
				)
				(justify mirror)
			)
		)
		(duplicate_pad_numbers_are_jumpers no)
		(fp_line
			(start 0.7874 -0.4064)
			(end -0.7874 -0.4064)
			(stroke
				(width 0.1524)
				(type default)
			)
			(layer "B.SilkS")
		)
		(fp_line
			(start -0.7874 -0.4064)
			(end -0.7874 0.4064)
			(stroke
				(width 0.1524)
				(type default)
			)
			(layer "B.SilkS")
		)
		(fp_line
			(start 0.7874 0.4064)
			(end 0.7874 -0.4064)
			(stroke
				(width 0.1524)
				(type default)
			)
			(layer "B.SilkS")
		)
		(fp_line
			(start -0.7874 0.4064)
			(end 0.7874 0.4064)
			(stroke
				(width 0.1524)
				(type default)
			)
			(layer "B.SilkS")
		)
		(fp_line
			(start 0.67945 -0.305054)
			(end 0.12065 -0.305054)
			(stroke
				(width 0.1)
				(type default)
			)
			(layer "B.Fab")
		)
		(fp_line
			(start 0.12065 -0.305054)
			(end 0.12065 -0.2794)
			(stroke
				(width 0.1)
				(type default)
			)
			(layer "B.Fab")
		)
		(fp_line
			(start -0.12065 -0.3048)
			(end -0.67945 -0.3048)
			(stroke
				(width 0.1)
				(type default)
			)
			(layer "B.Fab")
		)
		(fp_line
			(start -0.67945 -0.3048)
			(end -0.67945 0.3048)
			(stroke
				(width 0.1)
				(type default)
			)
			(layer "B.Fab")
		)
		(fp_line
			(start 0.12065 -0.2794)
			(end -0.12065 -0.2794)
			(stroke
				(width 0.1)
				(type default)
			)
			(layer "B.Fab")
		)
		(fp_line
			(start -0.12065 -0.2794)
			(end -0.12065 -0.3048)
			(stroke
				(width 0.1)
				(type default)
			)
			(layer "B.Fab")
		)
		(fp_line
			(start 0.12065 0.2794)
			(end 0.12065 0.3048)
			(stroke
				(width 0.1)
				(type default)
			)
			(layer "B.Fab")
		)
		(fp_line
			(start -0.120396 0.2794)
			(end 0.12065 0.2794)
			(stroke
				(width 0.1)
				(type default)
			)
			(layer "B.Fab")
		)
		(fp_line
			(start 0.67945 0.3048)
			(end 0.67945 -0.305054)
			(stroke
				(width 0.1)
				(type default)
			)
			(layer "B.Fab")
		)
		(fp_line
			(start 0.12065 0.3048)
			(end 0.67945 0.3048)
			(stroke
				(width 0.1)
				(type default)
			)
			(layer "B.Fab")
		)
		(fp_line
			(start -0.120396 0.3048)
			(end -0.120396 0.2794)
			(stroke
				(width 0.1)
				(type default)
			)
			(layer "B.Fab")
		)
		(fp_line
			(start -0.67945 0.3048)
			(end -0.120396 0.3048)
			(stroke
				(width 0.1)
				(type default)
			)
			(layer "B.Fab")
		)
		(pad "1" smd circle
			(at 0.40005 0 270)
			(size 0 0)
			(layers "B.Cu" "B.Mask" "B.Paste")
			(net "SPI_BIC1_MOSI_R1")
		)
		(pad "2" smd circle
			(at -0.40005 0 270)
			(size 0 0)
			(layers "B.Cu" "B.Mask" "B.Paste")
			(net "SPI_BIC1_MOSI_R2")
		)
	)
	(footprint ""
		(layer "B.Cu")
		(at 354.588318 -249.945398 180)
		(property "Reference" "R6715"
			(at 0 0 0)
			(layer "B.SilkS")
			(hide yes)
			(effects
				(font
					(size 1.27 1.27)
				)
				(justify mirror)
			)
		)
		(property "Value" ""
			(at 0 0 0)
			(layer "B.Fab")
			(effects
				(font
					(size 1.27 1.27)
				)
				(justify mirror)
			)
		)
		(duplicate_pad_numbers_are_jumpers no)
		(fp_line
			(start 0.7874 0.4064)
			(end 0.7874 -0.4064)
			(stroke
				(width 0.1524)
				(type default)
			)
			(layer "B.SilkS")
		)
		(fp_line
			(start 0.7874 -0.4064)
			(end -0.7874 -0.4064)
			(stroke
				(width 0.1524)
				(type default)
			)
			(layer "B.SilkS")
		)
		(fp_line
			(start -0.7874 0.4064)
			(end 0.7874 0.4064)
			(stroke
				(width 0.1524)
				(type default)
			)
			(layer "B.SilkS")
		)
		(fp_line
			(start -0.7874 -0.4064)
			(end -0.7874 0.4064)
			(stroke
				(width 0.1524)
				(type default)
			)
			(layer "B.SilkS")
		)
		(fp_line
			(start 0.67945 0.3048)
			(end 0.67945 -0.305054)
			(stroke
				(width 0.1)
				(type default)
			)
			(layer "B.Fab")
		)
		(fp_line
			(start 0.67945 -0.305054)
			(end 0.12065 -0.305054)
			(stroke
				(width 0.1)
				(type default)
			)
			(layer "B.Fab")
		)
		(fp_line
			(start 0.12065 0.3048)
			(end 0.67945 0.3048)
			(stroke
				(width 0.1)
				(type default)
			)
			(layer "B.Fab")
		)
		(fp_line
			(start 0.12065 0.2794)
			(end 0.12065 0.3048)
			(stroke
				(width 0.1)
				(type default)
			)
			(layer "B.Fab")
		)
		(fp_line
			(start 0.12065 -0.2794)
			(end -0.12065 -0.2794)
			(stroke
				(width 0.1)
				(type default)
			)
			(layer "B.Fab")
		)
		(fp_line
			(start 0.12065 -0.305054)
			(end 0.12065 -0.2794)
			(stroke
				(width 0.1)
				(type default)
			)
			(layer "B.Fab")
		)
		(fp_line
			(start -0.120396 0.3048)
			(end -0.120396 0.2794)
			(stroke
				(width 0.1)
				(type default)
			)
			(layer "B.Fab")
		)
		(fp_line
			(start -0.120396 0.2794)
			(end 0.12065 0.2794)
			(stroke
				(width 0.1)
				(type default)
			)
			(layer "B.Fab")
		)
		(fp_line
			(start -0.12065 -0.2794)
			(end -0.12065 -0.3048)
			(stroke
				(width 0.1)
				(type default)
			)
			(layer "B.Fab")
		)
		(fp_line
			(start -0.12065 -0.3048)
			(end -0.67945 -0.3048)
			(stroke
				(width 0.1)
				(type default)
			)
			(layer "B.Fab")
		)
		(fp_line
			(start -0.67945 0.3048)
			(end -0.120396 0.3048)
			(stroke
				(width 0.1)
				(type default)
			)
			(layer "B.Fab")
		)
		(fp_line
			(start -0.67945 -0.3048)
			(end -0.67945 0.3048)
			(stroke
				(width 0.1)
				(type default)
			)
			(layer "B.Fab")
		)
		(pad "1" smd circle
			(at 0.40005 0)
			(size 0 0)
			(layers "B.Cu" "B.Mask" "B.Paste")
			(net "SMB_SML1_PMBUS_HSC_SDA")
		)
		(pad "2" smd circle
			(at -0.40005 0)
			(size 0 0)
			(layers "B.Cu" "B.Mask" "B.Paste")
			(net "SMB_BIC_I2C6_MUX_VR_R_SDA")
		)
	)
	(footprint ""
		(layer "B.Cu")
		(at 403.674834 -293.99992 -90)
		(property "Reference" "C1918"
			(at 0 0 90)
			(layer "B.SilkS")
			(hide yes)
			(effects
				(font
					(size 1.27 1.27)
				)
				(justify mirror)
			)
		)
		(property "Value" ""
			(at 0 0 90)
			(layer "B.Fab")
			(effects
				(font
					(size 1.27 1.27)
				)
				(justify mirror)
			)
		)
		(duplicate_pad_numbers_are_jumpers no)
		(fp_line
			(start -0.299974 0.150114)
			(end 0.299974 0.150114)
			(stroke
				(width 0.1)
				(type default)
			)
			(layer "B.Fab")
		)
		(fp_line
			(start 0.299974 0.150114)
			(end 0.299974 -0.150114)
			(stroke
				(width 0.1)
				(type default)
			)
			(layer "B.Fab")
		)
		(fp_line
			(start -0.299974 -0.150114)
			(end -0.299974 0.150114)
			(stroke
				(width 0.1)
				(type default)
			)
			(layer "B.Fab")
		)
		(fp_line
			(start 0.299974 -0.150114)
			(end -0.299974 -0.150114)
			(stroke
				(width 0.1)
				(type default)
			)
			(layer "B.Fab")
		)
		(pad "1" smd rect
			(at 0.2667 0 90)
			(size 0.3048 0.381)
			(layers "B.Cu" "B.Mask" "B.Paste")
			(net "P0V8_PEX3")
		)
		(pad "2" smd rect
			(at -0.2667 0 90)
			(size 0.3048 0.381)
			(layers "B.Cu" "B.Mask" "B.Paste")
			(net "GND")
		)
	)
	(footprint ""
		(layer "B.Cu")
		(at 287.099756 -290.199826 90)
		(property "Reference" "C1746"
			(at 0 0 90)
			(layer "B.SilkS")
			(hide yes)
			(effects
				(font
					(size 1.27 1.27)
				)
				(justify mirror)
			)
		)
		(property "Value" ""
			(at 0 0 90)
			(layer "B.Fab")
			(effects
				(font
					(size 1.27 1.27)
				)
				(justify mirror)
			)
		)
		(duplicate_pad_numbers_are_jumpers no)
		(fp_line
			(start 0.299974 -0.150114)
			(end -0.299974 -0.150114)
			(stroke
				(width 0.1)
				(type default)
			)
			(layer "B.Fab")
		)
		(fp_line
			(start -0.299974 -0.150114)
			(end -0.299974 0.150114)
			(stroke
				(width 0.1)
				(type default)
			)
			(layer "B.Fab")
		)
		(fp_line
			(start 0.299974 0.150114)
			(end 0.299974 -0.150114)
			(stroke
				(width 0.1)
				(type default)
			)
			(layer "B.Fab")
		)
		(fp_line
			(start -0.299974 0.150114)
			(end 0.299974 0.150114)
			(stroke
				(width 0.1)
				(type default)
			)
			(layer "B.Fab")
		)
		(pad "1" smd rect
			(at 0.2667 0 270)
			(size 0.3048 0.381)
			(layers "B.Cu" "B.Mask" "B.Paste")
			(net "P0V8_SERDES_VDDA_PEX2")
		)
		(pad "2" smd rect
			(at -0.2667 0 270)
			(size 0.3048 0.381)
			(layers "B.Cu" "B.Mask" "B.Paste")
			(net "GND")
		)
	)
	(footprint ""
		(layer "B.Cu")
		(at 100.358194 -379.090174 -90)
		(property "Reference" "R1836"
			(at 0 0 90)
			(layer "B.SilkS")
			(hide yes)
			(effects
				(font
					(size 1.27 1.27)
				)
				(justify mirror)
			)
		)
		(property "Value" ""
			(at 0 0 90)
			(layer "B.Fab")
			(effects
				(font
					(size 1.27 1.27)
				)
				(justify mirror)
			)
		)
		(duplicate_pad_numbers_are_jumpers no)
		(fp_line
			(start -0.7874 0.4064)
			(end 0.7874 0.4064)
			(stroke
				(width 0.1524)
				(type default)
			)
			(layer "B.SilkS")
		)
		(fp_line
			(start 0.7874 0.4064)
			(end 0.7874 -0.4064)
			(stroke
				(width 0.1524)
				(type default)
			)
			(layer "B.SilkS")
		)
		(fp_line
			(start -0.7874 -0.4064)
			(end -0.7874 0.4064)
			(stroke
				(width 0.1524)
				(type default)
			)
			(layer "B.SilkS")
		)
		(fp_line
			(start 0.7874 -0.4064)
			(end -0.7874 -0.4064)
			(stroke
				(width 0.1524)
				(type default)
			)
			(layer "B.SilkS")
		)
		(fp_line
			(start -0.67945 0.3048)
			(end -0.120396 0.3048)
			(stroke
				(width 0.1)
				(type default)
			)
			(layer "B.Fab")
		)
		(fp_line
			(start -0.120396 0.3048)
			(end -0.120396 0.2794)
			(stroke
				(width 0.1)
				(type default)
			)
			(layer "B.Fab")
		)
		(fp_line
			(start 0.12065 0.3048)
			(end 0.67945 0.3048)
			(stroke
				(width 0.1)
				(type default)
			)
			(layer "B.Fab")
		)
		(fp_line
			(start 0.67945 0.3048)
			(end 0.67945 -0.305054)
			(stroke
				(width 0.1)
				(type default)
			)
			(layer "B.Fab")
		)
		(fp_line
			(start -0.120396 0.2794)
			(end 0.12065 0.2794)
			(stroke
				(width 0.1)
				(type default)
			)
			(layer "B.Fab")
		)
		(fp_line
			(start 0.12065 0.2794)
			(end 0.12065 0.3048)
			(stroke
				(width 0.1)
				(type default)
			)
			(layer "B.Fab")
		)
		(fp_line
			(start -0.12065 -0.2794)
			(end -0.12065 -0.3048)
			(stroke
				(width 0.1)
				(type default)
			)
			(layer "B.Fab")
		)
		(fp_line
			(start 0.12065 -0.2794)
			(end -0.12065 -0.2794)
			(stroke
				(width 0.1)
				(type default)
			)
			(layer "B.Fab")
		)
		(fp_line
			(start -0.67945 -0.3048)
			(end -0.67945 0.3048)
			(stroke
				(width 0.1)
				(type default)
			)
			(layer "B.Fab")
		)
		(fp_line
			(start -0.12065 -0.3048)
			(end -0.67945 -0.3048)
			(stroke
				(width 0.1)
				(type default)
			)
			(layer "B.Fab")
		)
		(fp_line
			(start 0.12065 -0.305054)
			(end 0.12065 -0.2794)
			(stroke
				(width 0.1)
				(type default)
			)
			(layer "B.Fab")
		)
		(fp_line
			(start 0.67945 -0.305054)
			(end 0.12065 -0.305054)
			(stroke
				(width 0.1)
				(type default)
			)
			(layer "B.Fab")
		)
		(pad "1" smd circle
			(at 0.40005 0 90)
			(size 0 0)
			(layers "B.Cu" "B.Mask" "B.Paste")
			(net "SMB_GPU_1_R_SDA")
		)
		(pad "2" smd circle
			(at -0.40005 0 90)
			(size 0 0)
			(layers "B.Cu" "B.Mask" "B.Paste")
			(net "SMB_GPU_1_SDA")
		)
	)
	(footprint ""
		(layer "B.Cu")
		(at 47.77486 -298.00804 90)
		(property "Reference" "C3068"
			(at 0 0 90)
			(layer "B.SilkS")
			(hide yes)
			(effects
				(font
					(size 1.27 1.27)
				)
				(justify mirror)
			)
		)
		(property "Value" ""
			(at 0 0 90)
			(layer "B.Fab")
			(effects
				(font
					(size 1.27 1.27)
				)
				(justify mirror)
			)
		)
		(duplicate_pad_numbers_are_jumpers no)
		(fp_line
			(start 0.299974 -0.150114)
			(end -0.299974 -0.150114)
			(stroke
				(width 0.1)
				(type default)
			)
			(layer "B.Fab")
		)
		(fp_line
			(start -0.299974 -0.150114)
			(end -0.299974 0.150114)
			(stroke
				(width 0.1)
				(type default)
			)
			(layer "B.Fab")
		)
		(fp_line
			(start 0.299974 0.150114)
			(end 0.299974 -0.150114)
			(stroke
				(width 0.1)
				(type default)
			)
			(layer "B.Fab")
		)
		(fp_line
			(start -0.299974 0.150114)
			(end 0.299974 0.150114)
			(stroke
				(width 0.1)
				(type default)
			)
			(layer "B.Fab")
		)
		(pad "1" smd rect
			(at 0.2667 0 270)
			(size 0.3048 0.381)
			(layers "B.Cu" "B.Mask" "B.Paste")
			(net "SYSPLL_VDDA18_PEX0")
		)
		(pad "2" smd rect
			(at -0.2667 0 270)
			(size 0.3048 0.381)
			(layers "B.Cu" "B.Mask" "B.Paste")
			(net "GND")
		)
	)
	(footprint ""
		(layer "B.Cu")
		(at 294.69969 -303.499774 -90)
		(property "Reference" "C3254"
			(at 0 0 90)
			(layer "B.SilkS")
			(hide yes)
			(effects
				(font
					(size 1.27 1.27)
				)
				(justify mirror)
			)
		)
		(property "Value" ""
			(at 0 0 90)
			(layer "B.Fab")
			(effects
				(font
					(size 1.27 1.27)
				)
				(justify mirror)
			)
		)
		(duplicate_pad_numbers_are_jumpers no)
		(fp_line
			(start -0.299974 0.150114)
			(end 0.299974 0.150114)
			(stroke
				(width 0.1)
				(type default)
			)
			(layer "B.Fab")
		)
		(fp_line
			(start 0.299974 0.150114)
			(end 0.299974 -0.150114)
			(stroke
				(width 0.1)
				(type default)
			)
			(layer "B.Fab")
		)
		(fp_line
			(start -0.299974 -0.150114)
			(end -0.299974 0.150114)
			(stroke
				(width 0.1)
				(type default)
			)
			(layer "B.Fab")
		)
		(fp_line
			(start 0.299974 -0.150114)
			(end -0.299974 -0.150114)
			(stroke
				(width 0.1)
				(type default)
			)
			(layer "B.Fab")
		)
		(pad "1" smd rect
			(at 0.2667 0 90)
			(size 0.3048 0.381)
			(layers "B.Cu" "B.Mask" "B.Paste")
			(net "P1V25_PEX2")
		)
		(pad "2" smd rect
			(at -0.2667 0 90)
			(size 0.3048 0.381)
			(layers "B.Cu" "B.Mask" "B.Paste")
			(net "GND")
		)
	)
	(footprint ""
		(layer "B.Cu")
		(at 406.999948 -288.299906 90)
		(property "Reference" "C3457"
			(at 0 0 90)
			(layer "B.SilkS")
			(hide yes)
			(effects
				(font
					(size 1.27 1.27)
				)
				(justify mirror)
			)
		)
		(property "Value" ""
			(at 0 0 90)
			(layer "B.Fab")
			(effects
				(font
					(size 1.27 1.27)
				)
				(justify mirror)
			)
		)
		(duplicate_pad_numbers_are_jumpers no)
		(fp_line
			(start 0.299974 -0.150114)
			(end -0.299974 -0.150114)
			(stroke
				(width 0.1)
				(type default)
			)
			(layer "B.Fab")
		)
		(fp_line
			(start -0.299974 -0.150114)
			(end -0.299974 0.150114)
			(stroke
				(width 0.1)
				(type default)
			)
			(layer "B.Fab")
		)
		(fp_line
			(start 0.299974 0.150114)
			(end 0.299974 -0.150114)
			(stroke
				(width 0.1)
				(type default)
			)
			(layer "B.Fab")
		)
		(fp_line
			(start -0.299974 0.150114)
			(end 0.299974 0.150114)
			(stroke
				(width 0.1)
				(type default)
			)
			(layer "B.Fab")
		)
		(pad "1" smd rect
			(at 0.2667 0 270)
			(size 0.3048 0.381)
			(layers "B.Cu" "B.Mask" "B.Paste")
			(net "P1V25_PEX3")
		)
		(pad "2" smd rect
			(at -0.2667 0 270)
			(size 0.3048 0.381)
			(layers "B.Cu" "B.Mask" "B.Paste")
			(net "GND")
		)
	)
	(footprint ""
		(layer "B.Cu")
		(at 335.82737 -85.75421 180)
		(property "Reference" "C2675"
			(at 0 0 0)
			(layer "B.SilkS")
			(hide yes)
			(effects
				(font
					(size 1.27 1.27)
				)
				(justify mirror)
			)
		)
		(property "Value" ""
			(at 0 0 0)
			(layer "B.Fab")
			(effects
				(font
					(size 1.27 1.27)
				)
				(justify mirror)
			)
		)
		(duplicate_pad_numbers_are_jumpers no)
		(fp_line
			(start 0.7874 0.4064)
			(end 0.7874 -0.4064)
			(stroke
				(width 0.1524)
				(type default)
			)
			(layer "B.SilkS")
		)
		(fp_line
			(start 0.7874 -0.4064)
			(end -0.7874 -0.4064)
			(stroke
				(width 0.1524)
				(type default)
			)
			(layer "B.SilkS")
		)
		(fp_line
			(start -0.7874 0.4064)
			(end 0.7874 0.4064)
			(stroke
				(width 0.1524)
				(type default)
			)
			(layer "B.SilkS")
		)
		(fp_line
			(start -0.7874 -0.4064)
			(end -0.7874 0.4064)
			(stroke
				(width 0.1524)
				(type default)
			)
			(layer "B.SilkS")
		)
		(fp_line
			(start 0.67945 0.3048)
			(end 0.67945 -0.305054)
			(stroke
				(width 0.1)
				(type default)
			)
			(layer "B.Fab")
		)
		(fp_line
			(start 0.67945 -0.305054)
			(end 0.12065 -0.305054)
			(stroke
				(width 0.1)
				(type default)
			)
			(layer "B.Fab")
		)
		(fp_line
			(start 0.12065 0.3048)
			(end 0.67945 0.3048)
			(stroke
				(width 0.1)
				(type default)
			)
			(layer "B.Fab")
		)
		(fp_line
			(start 0.12065 0.2794)
			(end 0.12065 0.3048)
			(stroke
				(width 0.1)
				(type default)
			)
			(layer "B.Fab")
		)
		(fp_line
			(start 0.12065 -0.2794)
			(end -0.12065 -0.2794)
			(stroke
				(width 0.1)
				(type default)
			)
			(layer "B.Fab")
		)
		(fp_line
			(start 0.12065 -0.305054)
			(end 0.12065 -0.2794)
			(stroke
				(width 0.1)
				(type default)
			)
			(layer "B.Fab")
		)
		(fp_line
			(start -0.120396 0.3048)
			(end -0.120396 0.2794)
			(stroke
				(width 0.1)
				(type default)
			)
			(layer "B.Fab")
		)
		(fp_line
			(start -0.120396 0.2794)
			(end 0.12065 0.2794)
			(stroke
				(width 0.1)
				(type default)
			)
			(layer "B.Fab")
		)
		(fp_line
			(start -0.12065 -0.2794)
			(end -0.12065 -0.3048)
			(stroke
				(width 0.1)
				(type default)
			)
			(layer "B.Fab")
		)
		(fp_line
			(start -0.12065 -0.3048)
			(end -0.67945 -0.3048)
			(stroke
				(width 0.1)
				(type default)
			)
			(layer "B.Fab")
		)
		(fp_line
			(start -0.67945 0.3048)
			(end -0.120396 0.3048)
			(stroke
				(width 0.1)
				(type default)
			)
			(layer "B.Fab")
		)
		(fp_line
			(start -0.67945 -0.3048)
			(end -0.67945 0.3048)
			(stroke
				(width 0.1)
				(type default)
			)
			(layer "B.Fab")
		)
		(pad "1" smd circle
			(at 0.40005 0)
			(size 0 0)
			(layers "B.Cu" "B.Mask" "B.Paste")
			(net "P3V3_VDD_9ZXL0851_8_15")
		)
		(pad "2" smd circle
			(at -0.40005 0)
			(size 0 0)
			(layers "B.Cu" "B.Mask" "B.Paste")
			(net "GND")
		)
	)
	(footprint ""
		(layer "B.Cu")
		(at 288.206942 -136.652 -90)
		(property "Reference" "R240"
			(at 0 0 90)
			(layer "B.SilkS")
			(hide yes)
			(effects
				(font
					(size 1.27 1.27)
				)
				(justify mirror)
			)
		)
		(property "Value" ""
			(at 0 0 90)
			(layer "B.Fab")
			(effects
				(font
					(size 1.27 1.27)
				)
				(justify mirror)
			)
		)
		(duplicate_pad_numbers_are_jumpers no)
		(fp_line
			(start -0.7874 0.4064)
			(end 0.7874 0.4064)
			(stroke
				(width 0.1524)
				(type default)
			)
			(layer "B.SilkS")
		)
		(fp_line
			(start 0.7874 0.4064)
			(end 0.7874 -0.4064)
			(stroke
				(width 0.1524)
				(type default)
			)
			(layer "B.SilkS")
		)
		(fp_line
			(start -0.7874 -0.4064)
			(end -0.7874 0.4064)
			(stroke
				(width 0.1524)
				(type default)
			)
			(layer "B.SilkS")
		)
		(fp_line
			(start 0.7874 -0.4064)
			(end -0.7874 -0.4064)
			(stroke
				(width 0.1524)
				(type default)
			)
			(layer "B.SilkS")
		)
		(fp_line
			(start -0.67945 0.3048)
			(end -0.120396 0.3048)
			(stroke
				(width 0.1)
				(type default)
			)
			(layer "B.Fab")
		)
		(fp_line
			(start -0.120396 0.3048)
			(end -0.120396 0.2794)
			(stroke
				(width 0.1)
				(type default)
			)
			(layer "B.Fab")
		)
		(fp_line
			(start 0.12065 0.3048)
			(end 0.67945 0.3048)
			(stroke
				(width 0.1)
				(type default)
			)
			(layer "B.Fab")
		)
		(fp_line
			(start 0.67945 0.3048)
			(end 0.67945 -0.305054)
			(stroke
				(width 0.1)
				(type default)
			)
			(layer "B.Fab")
		)
		(fp_line
			(start -0.120396 0.2794)
			(end 0.12065 0.2794)
			(stroke
				(width 0.1)
				(type default)
			)
			(layer "B.Fab")
		)
		(fp_line
			(start 0.12065 0.2794)
			(end 0.12065 0.3048)
			(stroke
				(width 0.1)
				(type default)
			)
			(layer "B.Fab")
		)
		(fp_line
			(start -0.12065 -0.2794)
			(end -0.12065 -0.3048)
			(stroke
				(width 0.1)
				(type default)
			)
			(layer "B.Fab")
		)
		(fp_line
			(start 0.12065 -0.2794)
			(end -0.12065 -0.2794)
			(stroke
				(width 0.1)
				(type default)
			)
			(layer "B.Fab")
		)
		(fp_line
			(start -0.67945 -0.3048)
			(end -0.67945 0.3048)
			(stroke
				(width 0.1)
				(type default)
			)
			(layer "B.Fab")
		)
		(fp_line
			(start -0.12065 -0.3048)
			(end -0.67945 -0.3048)
			(stroke
				(width 0.1)
				(type default)
			)
			(layer "B.Fab")
		)
		(fp_line
			(start 0.12065 -0.305054)
			(end 0.12065 -0.2794)
			(stroke
				(width 0.1)
				(type default)
			)
			(layer "B.Fab")
		)
		(fp_line
			(start 0.67945 -0.305054)
			(end 0.12065 -0.305054)
			(stroke
				(width 0.1)
				(type default)
			)
			(layer "B.Fab")
		)
		(pad "1" smd circle
			(at 0.40005 0 90)
			(size 0 0)
			(layers "B.Cu" "B.Mask" "B.Paste")
			(net "RST_SMB_NIC_MUX_R_N")
		)
		(pad "2" smd circle
			(at -0.40005 0 90)
			(size 0 0)
			(layers "B.Cu" "B.Mask" "B.Paste")
			(net "RST_SMB_NIC4_MUX_N")
		)
	)
	(footprint ""
		(layer "B.Cu")
		(at 222.212154 -197.791832 -90)
		(property "Reference" "R1024"
			(at 0 0 90)
			(layer "B.SilkS")
			(hide yes)
			(effects
				(font
					(size 1.27 1.27)
				)
				(justify mirror)
			)
		)
		(property "Value" ""
			(at 0 0 90)
			(layer "B.Fab")
			(effects
				(font
					(size 1.27 1.27)
				)
				(justify mirror)
			)
		)
		(duplicate_pad_numbers_are_jumpers no)
		(fp_line
			(start -0.7874 0.4064)
			(end 0.7874 0.4064)
			(stroke
				(width 0.1524)
				(type default)
			)
			(layer "B.SilkS")
		)
		(fp_line
			(start 0.7874 0.4064)
			(end 0.7874 -0.4064)
			(stroke
				(width 0.1524)
				(type default)
			)
			(layer "B.SilkS")
		)
		(fp_line
			(start -0.7874 -0.4064)
			(end -0.7874 0.4064)
			(stroke
				(width 0.1524)
				(type default)
			)
			(layer "B.SilkS")
		)
		(fp_line
			(start 0.7874 -0.4064)
			(end -0.7874 -0.4064)
			(stroke
				(width 0.1524)
				(type default)
			)
			(layer "B.SilkS")
		)
		(fp_line
			(start -0.67945 0.3048)
			(end -0.120396 0.3048)
			(stroke
				(width 0.1)
				(type default)
			)
			(layer "B.Fab")
		)
		(fp_line
			(start -0.120396 0.3048)
			(end -0.120396 0.2794)
			(stroke
				(width 0.1)
				(type default)
			)
			(layer "B.Fab")
		)
		(fp_line
			(start 0.12065 0.3048)
			(end 0.67945 0.3048)
			(stroke
				(width 0.1)
				(type default)
			)
			(layer "B.Fab")
		)
		(fp_line
			(start 0.67945 0.3048)
			(end 0.67945 -0.305054)
			(stroke
				(width 0.1)
				(type default)
			)
			(layer "B.Fab")
		)
		(fp_line
			(start -0.120396 0.2794)
			(end 0.12065 0.2794)
			(stroke
				(width 0.1)
				(type default)
			)
			(layer "B.Fab")
		)
		(fp_line
			(start 0.12065 0.2794)
			(end 0.12065 0.3048)
			(stroke
				(width 0.1)
				(type default)
			)
			(layer "B.Fab")
		)
		(fp_line
			(start -0.12065 -0.2794)
			(end -0.12065 -0.3048)
			(stroke
				(width 0.1)
				(type default)
			)
			(layer "B.Fab")
		)
		(fp_line
			(start 0.12065 -0.2794)
			(end -0.12065 -0.2794)
			(stroke
				(width 0.1)
				(type default)
			)
			(layer "B.Fab")
		)
		(fp_line
			(start -0.67945 -0.3048)
			(end -0.67945 0.3048)
			(stroke
				(width 0.1)
				(type default)
			)
			(layer "B.Fab")
		)
		(fp_line
			(start -0.12065 -0.3048)
			(end -0.67945 -0.3048)
			(stroke
				(width 0.1)
				(type default)
			)
			(layer "B.Fab")
		)
		(fp_line
			(start 0.12065 -0.305054)
			(end 0.12065 -0.2794)
			(stroke
				(width 0.1)
				(type default)
			)
			(layer "B.Fab")
		)
		(fp_line
			(start 0.67945 -0.305054)
			(end 0.12065 -0.305054)
			(stroke
				(width 0.1)
				(type default)
			)
			(layer "B.Fab")
		)
		(pad "1" smd circle
			(at 0.40005 0 90)
			(size 0 0)
			(layers "B.Cu" "B.Mask" "B.Paste")
			(net "SPI_BIC1_MOSI_R")
		)
		(pad "2" smd circle
			(at -0.40005 0 90)
			(size 0 0)
			(layers "B.Cu" "B.Mask" "B.Paste")
			(net "SPI_BIC1_MOSI_R5")
		)
	)
	(footprint ""
		(layer "B.Cu")
		(at 354.78212 -228.348794 90)
		(property "Reference" "R5636"
			(at 0 0 90)
			(layer "B.SilkS")
			(hide yes)
			(effects
				(font
					(size 1.27 1.27)
				)
				(justify mirror)
			)
		)
		(property "Value" ""
			(at 0 0 90)
			(layer "B.Fab")
			(effects
				(font
					(size 1.27 1.27)
				)
				(justify mirror)
			)
		)
		(duplicate_pad_numbers_are_jumpers no)
		(fp_line
			(start 1.2954 -0.5842)
			(end -1.2954 -0.5842)
			(stroke
				(width 0.1524)
				(type default)
			)
			(layer "B.SilkS")
		)
		(fp_line
			(start -1.2954 -0.5842)
			(end -1.2954 0.5842)
			(stroke
				(width 0.1524)
				(type default)
			)
			(layer "B.SilkS")
		)
		(fp_line
			(start 1.2954 0.5842)
			(end 1.2954 -0.5842)
			(stroke
				(width 0.1524)
				(type default)
			)
			(layer "B.SilkS")
		)
		(fp_line
			(start -1.2954 0.5842)
			(end 1.2954 0.5842)
			(stroke
				(width 0.1524)
				(type default)
			)
			(layer "B.SilkS")
		)
		(fp_line
			(start 0.8636 -0.4572)
			(end -0.8636 -0.4572)
			(stroke
				(width 0.1)
				(type default)
			)
			(layer "B.Fab")
		)
		(fp_line
			(start -0.8636 -0.4572)
			(end -0.8636 -0.406654)
			(stroke
				(width 0.1)
				(type default)
			)
			(layer "B.Fab")
		)
		(fp_line
			(start 1.1938 -0.406654)
			(end 0.8636 -0.406654)
			(stroke
				(width 0.1)
				(type default)
			)
			(layer "B.Fab")
		)
		(fp_line
			(start 0.8636 -0.406654)
			(end 0.8636 -0.4572)
			(stroke
				(width 0.1)
				(type default)
			)
			(layer "B.Fab")
		)
		(fp_line
			(start -0.8636 -0.406654)
			(end -1.1938 -0.406654)
			(stroke
				(width 0.1)
				(type default)
			)
			(layer "B.Fab")
		)
		(fp_line
			(start -1.1938 -0.406654)
			(end -1.1938 0.4064)
			(stroke
				(width 0.1)
				(type default)
			)
			(layer "B.Fab")
		)
		(fp_line
			(start 1.1938 0.4064)
			(end 1.1938 -0.406654)
			(stroke
				(width 0.1)
				(type default)
			)
			(layer "B.Fab")
		)
		(fp_line
			(start 0.8636 0.4064)
			(end 1.1938 0.4064)
			(stroke
				(width 0.1)
				(type default)
			)
			(layer "B.Fab")
		)
		(fp_line
			(start -0.8636 0.4064)
			(end -0.8636 0.4572)
			(stroke
				(width 0.1)
				(type default)
			)
			(layer "B.Fab")
		)
		(fp_line
			(start -1.1938 0.4064)
			(end -0.8636 0.4064)
			(stroke
				(width 0.1)
				(type default)
			)
			(layer "B.Fab")
		)
		(fp_line
			(start 0.8636 0.4318)
			(end 0.8636 0.4064)
			(stroke
				(width 0.1)
				(type default)
			)
			(layer "B.Fab")
		)
		(fp_line
			(start 0.8636 0.4572)
			(end 0.8636 0.4318)
			(stroke
				(width 0.1)
				(type default)
			)
			(layer "B.Fab")
		)
		(fp_line
			(start -0.8636 0.4572)
			(end 0.8636 0.4572)
			(stroke
				(width 0.1)
				(type default)
			)
			(layer "B.Fab")
		)
		(pad "1" smd rect
			(at 0.7366 0)
			(size 0.7112 0.8128)
			(layers "B.Cu" "B.Mask" "B.Paste")
			(net "P3V3_AUX")
		)
		(pad "2" smd rect
			(at -0.7366 0)
			(size 0.7112 0.8128)
			(layers "B.Cu" "B.Mask" "B.Paste")
			(net "P3V3_FPGA_VCCIO0")
		)
	)
	(footprint ""
		(layer "B.Cu")
		(at 351.547684 -303.141634)
		(property "Reference" "PR128"
			(at 0 0 0)
			(layer "B.SilkS")
			(hide yes)
			(effects
				(font
					(size 1.27 1.27)
				)
				(justify mirror)
			)
		)
		(property "Value" ""
			(at 0 0 0)
			(layer "B.Fab")
			(effects
				(font
					(size 1.27 1.27)
				)
				(justify mirror)
			)
		)
		(duplicate_pad_numbers_are_jumpers no)
		(fp_line
			(start -0.7874 -0.4064)
			(end -0.7874 0.4064)
			(stroke
				(width 0.1524)
				(type default)
			)
			(layer "B.SilkS")
		)
		(fp_line
			(start -0.7874 0.4064)
			(end 0.7874 0.4064)
			(stroke
				(width 0.1524)
				(type default)
			)
			(layer "B.SilkS")
		)
		(fp_line
			(start 0.7874 -0.4064)
			(end -0.7874 -0.4064)
			(stroke
				(width 0.1524)
				(type default)
			)
			(layer "B.SilkS")
		)
		(fp_line
			(start 0.7874 0.4064)
			(end 0.7874 -0.4064)
			(stroke
				(width 0.1524)
				(type default)
			)
			(layer "B.SilkS")
		)
		(fp_line
			(start -0.67945 -0.3048)
			(end -0.67945 0.3048)
			(stroke
				(width 0.1)
				(type default)
			)
			(layer "B.Fab")
		)
		(fp_line
			(start -0.67945 0.3048)
			(end -0.120396 0.3048)
			(stroke
				(width 0.1)
				(type default)
			)
			(layer "B.Fab")
		)
		(fp_line
			(start -0.12065 -0.3048)
			(end -0.67945 -0.3048)
			(stroke
				(width 0.1)
				(type default)
			)
			(layer "B.Fab")
		)
		(fp_line
			(start -0.12065 -0.2794)
			(end -0.12065 -0.3048)
			(stroke
				(width 0.1)
				(type default)
			)
			(layer "B.Fab")
		)
		(fp_line
			(start -0.120396 0.2794)
			(end 0.12065 0.2794)
			(stroke
				(width 0.1)
				(type default)
			)
			(layer "B.Fab")
		)
		(fp_line
			(start -0.120396 0.3048)
			(end -0.120396 0.2794)
			(stroke
				(width 0.1)
				(type default)
			)
			(layer "B.Fab")
		)
		(fp_line
			(start 0.12065 -0.305054)
			(end 0.12065 -0.2794)
			(stroke
				(width 0.1)
				(type default)
			)
			(layer "B.Fab")
		)
		(fp_line
			(start 0.12065 -0.2794)
			(end -0.12065 -0.2794)
			(stroke
				(width 0.1)
				(type default)
			)
			(layer "B.Fab")
		)
		(fp_line
			(start 0.12065 0.2794)
			(end 0.12065 0.3048)
			(stroke
				(width 0.1)
				(type default)
			)
			(layer "B.Fab")
		)
		(fp_line
			(start 0.12065 0.3048)
			(end 0.67945 0.3048)
			(stroke
				(width 0.1)
				(type default)
			)
			(layer "B.Fab")
		)
		(fp_line
			(start 0.67945 -0.305054)
			(end 0.12065 -0.305054)
			(stroke
				(width 0.1)
				(type default)
			)
			(layer "B.Fab")
		)
		(fp_line
			(start 0.67945 0.3048)
			(end 0.67945 -0.305054)
			(stroke
				(width 0.1)
				(type default)
			)
			(layer "B.Fab")
		)
		(pad "1" smd circle
			(at 0.40005 0 180)
			(size 0 0)
			(layers "B.Cu" "B.Mask" "B.Paste")
			(net "P0V8_PEX3")
		)
		(pad "2" smd circle
			(at -0.40005 0 180)
			(size 0 0)
			(layers "B.Cu" "B.Mask" "B.Paste")
			(net "SH_P0V8_PEX3_VSEN3_L")
		)
	)
	(footprint ""
		(layer "B.Cu")
		(at 397.49984 -291.624766)
		(property "Reference" "C1870"
			(at 0 0 0)
			(layer "B.SilkS")
			(hide yes)
			(effects
				(font
					(size 1.27 1.27)
				)
				(justify mirror)
			)
		)
		(property "Value" ""
			(at 0 0 0)
			(layer "B.Fab")
			(effects
				(font
					(size 1.27 1.27)
				)
				(justify mirror)
			)
		)
		(duplicate_pad_numbers_are_jumpers no)
		(fp_line
			(start -0.299974 -0.150114)
			(end -0.299974 0.150114)
			(stroke
				(width 0.1)
				(type default)
			)
			(layer "B.Fab")
		)
		(fp_line
			(start -0.299974 0.150114)
			(end 0.299974 0.150114)
			(stroke
				(width 0.1)
				(type default)
			)
			(layer "B.Fab")
		)
		(fp_line
			(start 0.299974 -0.150114)
			(end -0.299974 -0.150114)
			(stroke
				(width 0.1)
				(type default)
			)
			(layer "B.Fab")
		)
		(fp_line
			(start 0.299974 0.150114)
			(end 0.299974 -0.150114)
			(stroke
				(width 0.1)
				(type default)
			)
			(layer "B.Fab")
		)
		(pad "1" smd rect
			(at 0.2667 0 180)
			(size 0.3048 0.381)
			(layers "B.Cu" "B.Mask" "B.Paste")
			(net "P0V8_PEX3")
		)
		(pad "2" smd rect
			(at -0.2667 0 180)
			(size 0.3048 0.381)
			(layers "B.Cu" "B.Mask" "B.Paste")
			(net "GND")
		)
	)
	(footprint ""
		(layer "B.Cu")
		(at 412.699962 -292.099746 90)
		(property "Reference" "C1991"
			(at 0 0 90)
			(layer "B.SilkS")
			(hide yes)
			(effects
				(font
					(size 1.27 1.27)
				)
				(justify mirror)
			)
		)
		(property "Value" ""
			(at 0 0 90)
			(layer "B.Fab")
			(effects
				(font
					(size 1.27 1.27)
				)
				(justify mirror)
			)
		)
		(duplicate_pad_numbers_are_jumpers no)
		(fp_line
			(start 0.299974 -0.150114)
			(end -0.299974 -0.150114)
			(stroke
				(width 0.1)
				(type default)
			)
			(layer "B.Fab")
		)
		(fp_line
			(start -0.299974 -0.150114)
			(end -0.299974 0.150114)
			(stroke
				(width 0.1)
				(type default)
			)
			(layer "B.Fab")
		)
		(fp_line
			(start 0.299974 0.150114)
			(end 0.299974 -0.150114)
			(stroke
				(width 0.1)
				(type default)
			)
			(layer "B.Fab")
		)
		(fp_line
			(start -0.299974 0.150114)
			(end 0.299974 0.150114)
			(stroke
				(width 0.1)
				(type default)
			)
			(layer "B.Fab")
		)
		(pad "1" smd rect
			(at 0.2667 0 270)
			(size 0.3048 0.381)
			(layers "B.Cu" "B.Mask" "B.Paste")
			(net "P0V8_SERDES_VDDA_PEX3")
		)
		(pad "2" smd rect
			(at -0.2667 0 270)
			(size 0.3048 0.381)
			(layers "B.Cu" "B.Mask" "B.Paste")
			(net "GND")
		)
	)
	(footprint ""
		(layer "B.Cu")
		(at 400.349974 -301.599854 -90)
		(property "Reference" "C1932"
			(at 0 0 90)
			(layer "B.SilkS")
			(hide yes)
			(effects
				(font
					(size 1.27 1.27)
				)
				(justify mirror)
			)
		)
		(property "Value" ""
			(at 0 0 90)
			(layer "B.Fab")
			(effects
				(font
					(size 1.27 1.27)
				)
				(justify mirror)
			)
		)
		(duplicate_pad_numbers_are_jumpers no)
		(fp_line
			(start -0.299974 0.150114)
			(end 0.299974 0.150114)
			(stroke
				(width 0.1)
				(type default)
			)
			(layer "B.Fab")
		)
		(fp_line
			(start 0.299974 0.150114)
			(end 0.299974 -0.150114)
			(stroke
				(width 0.1)
				(type default)
			)
			(layer "B.Fab")
		)
		(fp_line
			(start -0.299974 -0.150114)
			(end -0.299974 0.150114)
			(stroke
				(width 0.1)
				(type default)
			)
			(layer "B.Fab")
		)
		(fp_line
			(start 0.299974 -0.150114)
			(end -0.299974 -0.150114)
			(stroke
				(width 0.1)
				(type default)
			)
			(layer "B.Fab")
		)
		(pad "1" smd rect
			(at 0.2667 0 90)
			(size 0.3048 0.381)
			(layers "B.Cu" "B.Mask" "B.Paste")
			(net "P0V8_SERDES_VDDA_PEX3")
		)
		(pad "2" smd rect
			(at -0.2667 0 90)
			(size 0.3048 0.381)
			(layers "B.Cu" "B.Mask" "B.Paste")
			(net "GND")
		)
	)
	(footprint ""
		(layer "B.Cu")
		(at 337.488022 -319.545462 -90)
		(property "Reference" "L64"
			(at 0 0 90)
			(layer "B.SilkS")
			(hide yes)
			(effects
				(font
					(size 1.27 1.27)
				)
				(justify mirror)
			)
		)
		(property "Value" ""
			(at 0 0 90)
			(layer "B.Fab")
			(effects
				(font
					(size 1.27 1.27)
				)
				(justify mirror)
			)
		)
		(duplicate_pad_numbers_are_jumpers no)
		(fp_line
			(start -2.248154 4.9911)
			(end -2.248154 1.980692)
			(stroke
				(width 0.1524)
				(type default)
			)
			(layer "B.SilkS")
		)
		(fp_line
			(start 2.248154 4.9911)
			(end -2.248154 4.9911)
			(stroke
				(width 0.1524)
				(type default)
			)
			(layer "B.SilkS")
		)
		(fp_line
			(start 2.248154 1.980692)
			(end 2.248154 4.9911)
			(stroke
				(width 0.1524)
				(type default)
			)
			(layer "B.SilkS")
		)
		(fp_line
			(start -2.248154 -2.210816)
			(end -2.248154 -4.9911)
			(stroke
				(width 0.1524)
				(type default)
			)
			(layer "B.SilkS")
		)
		(fp_line
			(start -2.248154 -4.9911)
			(end 2.248154 -4.9911)
			(stroke
				(width 0.1524)
				(type default)
			)
			(layer "B.SilkS")
		)
		(fp_line
			(start 2.248154 -4.9911)
			(end 2.248154 -2.210816)
			(stroke
				(width 0.1524)
				(type default)
			)
			(layer "B.SilkS")
		)
		(fp_line
			(start -1.700022 0.899922)
			(end -1.700022 -0.899922)
			(stroke
				(width 0.1)
				(type default)
			)
			(layer "B.Fab")
		)
		(fp_line
			(start 1.700022 0.899922)
			(end -1.700022 0.899922)
			(stroke
				(width 0.1)
				(type default)
			)
			(layer "B.Fab")
		)
		(fp_line
			(start -1.700022 -0.899922)
			(end 1.700022 -0.899922)
			(stroke
				(width 0.1)
				(type default)
			)
			(layer "B.Fab")
		)
		(fp_line
			(start 1.700022 -0.899922)
			(end 1.700022 0.899922)
			(stroke
				(width 0.1)
				(type default)
			)
			(layer "B.Fab")
		)
		(pad "1" smd rect
			(at 1.575054 0 90)
			(size 1.1684 9.8044)
			(layers "B.Cu" "B.Mask" "B.Paste")
			(net "P0V8_PEX2")
		)
		(pad "2" smd rect
			(at -1.575054 0 90)
			(size 1.1684 9.8044)
			(layers "B.Cu" "B.Mask" "B.Paste")
			(net "P0V8_SERDES_VDDA_PEX2")
		)
	)
	(footprint ""
		(layer "B.Cu")
		(at 260.456426 -237.190788)
		(property "Reference" "C4427"
			(at 0 0 0)
			(layer "B.SilkS")
			(hide yes)
			(effects
				(font
					(size 1.27 1.27)
				)
				(justify mirror)
			)
		)
		(property "Value" ""
			(at 0 0 0)
			(layer "B.Fab")
			(effects
				(font
					(size 1.27 1.27)
				)
				(justify mirror)
			)
		)
		(duplicate_pad_numbers_are_jumpers no)
		(fp_line
			(start -0.7874 -0.4064)
			(end -0.7874 0.4064)
			(stroke
				(width 0.1524)
				(type default)
			)
			(layer "B.SilkS")
		)
		(fp_line
			(start -0.7874 0.4064)
			(end 0.7874 0.4064)
			(stroke
				(width 0.1524)
				(type default)
			)
			(layer "B.SilkS")
		)
		(fp_line
			(start 0.7874 -0.4064)
			(end -0.7874 -0.4064)
			(stroke
				(width 0.1524)
				(type default)
			)
			(layer "B.SilkS")
		)
		(fp_line
			(start 0.7874 0.4064)
			(end 0.7874 -0.4064)
			(stroke
				(width 0.1524)
				(type default)
			)
			(layer "B.SilkS")
		)
		(fp_line
			(start -0.67945 -0.3048)
			(end -0.67945 0.3048)
			(stroke
				(width 0.1)
				(type default)
			)
			(layer "B.Fab")
		)
		(fp_line
			(start -0.67945 0.3048)
			(end -0.120396 0.3048)
			(stroke
				(width 0.1)
				(type default)
			)
			(layer "B.Fab")
		)
		(fp_line
			(start -0.12065 -0.3048)
			(end -0.67945 -0.3048)
			(stroke
				(width 0.1)
				(type default)
			)
			(layer "B.Fab")
		)
		(fp_line
			(start -0.12065 -0.2794)
			(end -0.12065 -0.3048)
			(stroke
				(width 0.1)
				(type default)
			)
			(layer "B.Fab")
		)
		(fp_line
			(start -0.120396 0.2794)
			(end 0.12065 0.2794)
			(stroke
				(width 0.1)
				(type default)
			)
			(layer "B.Fab")
		)
		(fp_line
			(start -0.120396 0.3048)
			(end -0.120396 0.2794)
			(stroke
				(width 0.1)
				(type default)
			)
			(layer "B.Fab")
		)
		(fp_line
			(start 0.12065 -0.305054)
			(end 0.12065 -0.2794)
			(stroke
				(width 0.1)
				(type default)
			)
			(layer "B.Fab")
		)
		(fp_line
			(start 0.12065 -0.2794)
			(end -0.12065 -0.2794)
			(stroke
				(width 0.1)
				(type default)
			)
			(layer "B.Fab")
		)
		(fp_line
			(start 0.12065 0.2794)
			(end 0.12065 0.3048)
			(stroke
				(width 0.1)
				(type default)
			)
			(layer "B.Fab")
		)
		(fp_line
			(start 0.12065 0.3048)
			(end 0.67945 0.3048)
			(stroke
				(width 0.1)
				(type default)
			)
			(layer "B.Fab")
		)
		(fp_line
			(start 0.67945 -0.305054)
			(end 0.12065 -0.305054)
			(stroke
				(width 0.1)
				(type default)
			)
			(layer "B.Fab")
		)
		(fp_line
			(start 0.67945 0.3048)
			(end 0.67945 -0.305054)
			(stroke
				(width 0.1)
				(type default)
			)
			(layer "B.Fab")
		)
		(pad "1" smd circle
			(at 0.40005 0 180)
			(size 0 0)
			(layers "B.Cu" "B.Mask" "B.Paste")
			(net "P1V8_PLL0_PEX2")
		)
		(pad "2" smd circle
			(at -0.40005 0 180)
			(size 0 0)
			(layers "B.Cu" "B.Mask" "B.Paste")
			(net "GND")
		)
	)
	(footprint ""
		(layer "B.Cu")
		(at 244.901212 -291.888926 180)
		(property "Reference" "PC995"
			(at 0 0 0)
			(layer "B.SilkS")
			(hide yes)
			(effects
				(font
					(size 1.27 1.27)
				)
				(justify mirror)
			)
		)
		(property "Value" ""
			(at 0 0 0)
			(layer "B.Fab")
			(effects
				(font
					(size 1.27 1.27)
				)
				(justify mirror)
			)
		)
		(duplicate_pad_numbers_are_jumpers no)
		(fp_line
			(start 1.524 0.762)
			(end 1.524 -0.762)
			(stroke
				(width 0.1524)
				(type default)
			)
			(layer "B.SilkS")
		)
		(fp_line
			(start 1.524 -0.762)
			(end -1.524 -0.762)
			(stroke
				(width 0.1524)
				(type default)
			)
			(layer "B.SilkS")
		)
		(fp_line
			(start -1.524 0.762)
			(end 1.524 0.762)
			(stroke
				(width 0.1524)
				(type default)
			)
			(layer "B.SilkS")
		)
		(fp_line
			(start -1.524 -0.762)
			(end -1.524 0.762)
			(stroke
				(width 0.1524)
				(type default)
			)
			(layer "B.SilkS")
		)
		(fp_line
			(start 1.1049 0.724916)
			(end -1.1049 0.724916)
			(stroke
				(width 0.1)
				(type default)
			)
			(layer "B.Fab")
		)
		(fp_line
			(start 1.1049 -0.724916)
			(end 1.1049 0.724916)
			(stroke
				(width 0.1)
				(type default)
			)
			(layer "B.Fab")
		)
		(fp_line
			(start -1.1049 0.724916)
			(end -1.1049 -0.724916)
			(stroke
				(width 0.1)
				(type default)
			)
			(layer "B.Fab")
		)
		(fp_line
			(start -1.1049 -0.724916)
			(end 1.1049 -0.724916)
			(stroke
				(width 0.1)
				(type default)
			)
			(layer "B.Fab")
		)
		(pad "1" smd rect
			(at 0.889 0 180)
			(size 1.016 1.27)
			(layers "B.Cu" "B.Mask" "B.Paste")
			(net "P1V25_PEX2_R")
		)
		(pad "2" smd rect
			(at -0.889 0 180)
			(size 1.016 1.27)
			(layers "B.Cu" "B.Mask" "B.Paste")
			(net "GND")
		)
	)
	(footprint ""
		(layer "B.Cu")
		(at 397.49984 -299.2755 180)
		(property "Reference" "C1893"
			(at 0 0 0)
			(layer "B.SilkS")
			(hide yes)
			(effects
				(font
					(size 1.27 1.27)
				)
				(justify mirror)
			)
		)
		(property "Value" ""
			(at 0 0 0)
			(layer "B.Fab")
			(effects
				(font
					(size 1.27 1.27)
				)
				(justify mirror)
			)
		)
		(duplicate_pad_numbers_are_jumpers no)
		(fp_line
			(start 0.299974 0.150114)
			(end 0.299974 -0.150114)
			(stroke
				(width 0.1)
				(type default)
			)
			(layer "B.Fab")
		)
		(fp_line
			(start 0.299974 -0.150114)
			(end -0.299974 -0.150114)
			(stroke
				(width 0.1)
				(type default)
			)
			(layer "B.Fab")
		)
		(fp_line
			(start -0.299974 0.150114)
			(end 0.299974 0.150114)
			(stroke
				(width 0.1)
				(type default)
			)
			(layer "B.Fab")
		)
		(fp_line
			(start -0.299974 -0.150114)
			(end -0.299974 0.150114)
			(stroke
				(width 0.1)
				(type default)
			)
			(layer "B.Fab")
		)
		(pad "1" smd rect
			(at 0.2667 0)
			(size 0.3048 0.381)
			(layers "B.Cu" "B.Mask" "B.Paste")
			(net "P0V8_PEX3")
		)
		(pad "2" smd rect
			(at -0.2667 0)
			(size 0.3048 0.381)
			(layers "B.Cu" "B.Mask" "B.Paste")
			(net "GND")
		)
	)
	(footprint ""
		(layer "B.Cu")
		(at 227.067618 -218.30411 180)
		(property "Reference" "C2013"
			(at 0 0 0)
			(layer "B.SilkS")
			(hide yes)
			(effects
				(font
					(size 1.27 1.27)
				)
				(justify mirror)
			)
		)
		(property "Value" ""
			(at 0 0 0)
			(layer "B.Fab")
			(effects
				(font
					(size 1.27 1.27)
				)
				(justify mirror)
			)
		)
		(duplicate_pad_numbers_are_jumpers no)
		(fp_line
			(start 0.69215 0.2921)
			(end 0.69215 -0.2921)
			(stroke
				(width 0.1524)
				(type default)
			)
			(layer "B.SilkS")
		)
		(fp_line
			(start 0.69215 -0.2921)
			(end -0.69215 -0.2921)
			(stroke
				(width 0.1524)
				(type default)
			)
			(layer "B.SilkS")
		)
		(fp_line
			(start -0.69215 0.2921)
			(end 0.69215 0.2921)
			(stroke
				(width 0.1524)
				(type default)
			)
			(layer "B.SilkS")
		)
		(fp_line
			(start -0.69215 -0.2921)
			(end -0.69215 0.2921)
			(stroke
				(width 0.1524)
				(type default)
			)
			(layer "B.SilkS")
		)
		(fp_line
			(start 0.51435 0.2794)
			(end 0.51435 -0.2794)
			(stroke
				(width 0.1)
				(type default)
			)
			(layer "B.Fab")
		)
		(fp_line
			(start 0.51435 -0.2794)
			(end -0.51435 -0.2794)
			(stroke
				(width 0.1)
				(type default)
			)
			(layer "B.Fab")
		)
		(fp_line
			(start -0.51435 0.2794)
			(end 0.51435 0.2794)
			(stroke
				(width 0.1)
				(type default)
			)
			(layer "B.Fab")
		)
		(fp_line
			(start -0.51435 -0.2794)
			(end -0.51435 0.2794)
			(stroke
				(width 0.1)
				(type default)
			)
			(layer "B.Fab")
		)
		(pad "1" smd circle
			(at 0.40005 0)
			(size 0 0)
			(layers "B.Cu" "B.Mask" "B.Paste")
			(net "P1V2_AUX")
		)
		(pad "2" smd circle
			(at -0.40005 0)
			(size 0 0)
			(layers "B.Cu" "B.Mask" "B.Paste")
			(net "GND")
		)
		(zone
			(layer "B.Cu")
			(hatch none 0.5)
			(connect_pads
				(clearance 0)
			)
			(min_thickness 0.25)
			(keepout
				(tracks not_allowed)
				(vias allowed)
				(pads allowed)
				(copperpour not_allowed)
				(footprints allowed)
			)
			(placement
				(enabled no)
				(sheetname "")
			)
			(fill
				(thermal_gap 0.5)
				(thermal_bridge_width 0.5)
				(island_removal_mode 0)
			)
			(polygon
				(pts
					(xy 226.877118 -218.39174) (xy 226.968558 -218.449906) (xy 227.167948 -218.449906) (xy 227.258118 -218.39174)
					(xy 227.258118 -218.21648) (xy 227.167948 -218.15806) (xy 226.968558 -218.15806) (xy 226.877118 -218.216226)
				)
			)
		)
	)
	(footprint ""
		(layer "B.Cu")
		(at 399.400014 -288.299906 90)
		(property "Reference" "C3456"
			(at 0 0 90)
			(layer "B.SilkS")
			(hide yes)
			(effects
				(font
					(size 1.27 1.27)
				)
				(justify mirror)
			)
		)
		(property "Value" ""
			(at 0 0 90)
			(layer "B.Fab")
			(effects
				(font
					(size 1.27 1.27)
				)
				(justify mirror)
			)
		)
		(duplicate_pad_numbers_are_jumpers no)
		(fp_line
			(start 0.299974 -0.150114)
			(end -0.299974 -0.150114)
			(stroke
				(width 0.1)
				(type default)
			)
			(layer "B.Fab")
		)
		(fp_line
			(start -0.299974 -0.150114)
			(end -0.299974 0.150114)
			(stroke
				(width 0.1)
				(type default)
			)
			(layer "B.Fab")
		)
		(fp_line
			(start 0.299974 0.150114)
			(end 0.299974 -0.150114)
			(stroke
				(width 0.1)
				(type default)
			)
			(layer "B.Fab")
		)
		(fp_line
			(start -0.299974 0.150114)
			(end 0.299974 0.150114)
			(stroke
				(width 0.1)
				(type default)
			)
			(layer "B.Fab")
		)
		(pad "1" smd rect
			(at 0.2667 0 270)
			(size 0.3048 0.381)
			(layers "B.Cu" "B.Mask" "B.Paste")
			(net "P1V25_PEX3")
		)
		(pad "2" smd rect
			(at -0.2667 0 270)
			(size 0.3048 0.381)
			(layers "B.Cu" "B.Mask" "B.Paste")
			(net "GND")
		)
	)
	(footprint ""
		(layer "B.Cu")
		(at 116.935758 -260.400546 -90)
		(property "Reference" "PC55"
			(at 0 0 90)
			(layer "B.SilkS")
			(hide yes)
			(effects
				(font
					(size 1.27 1.27)
				)
				(justify mirror)
			)
		)
		(property "Value" ""
			(at 0 0 90)
			(layer "B.Fab")
			(effects
				(font
					(size 1.27 1.27)
				)
				(justify mirror)
			)
		)
		(duplicate_pad_numbers_are_jumpers no)
		(fp_line
			(start -0.7874 0.4064)
			(end 0.7874 0.4064)
			(stroke
				(width 0.1524)
				(type default)
			)
			(layer "B.SilkS")
		)
		(fp_line
			(start 0.7874 0.4064)
			(end 0.7874 -0.4064)
			(stroke
				(width 0.1524)
				(type default)
			)
			(layer "B.SilkS")
		)
		(fp_line
			(start -0.7874 -0.4064)
			(end -0.7874 0.4064)
			(stroke
				(width 0.1524)
				(type default)
			)
			(layer "B.SilkS")
		)
		(fp_line
			(start 0.7874 -0.4064)
			(end -0.7874 -0.4064)
			(stroke
				(width 0.1524)
				(type default)
			)
			(layer "B.SilkS")
		)
		(fp_line
			(start -0.67945 0.3048)
			(end -0.120396 0.3048)
			(stroke
				(width 0.1)
				(type default)
			)
			(layer "B.Fab")
		)
		(fp_line
			(start -0.120396 0.3048)
			(end -0.120396 0.2794)
			(stroke
				(width 0.1)
				(type default)
			)
			(layer "B.Fab")
		)
		(fp_line
			(start 0.12065 0.3048)
			(end 0.67945 0.3048)
			(stroke
				(width 0.1)
				(type default)
			)
			(layer "B.Fab")
		)
		(fp_line
			(start 0.67945 0.3048)
			(end 0.67945 -0.305054)
			(stroke
				(width 0.1)
				(type default)
			)
			(layer "B.Fab")
		)
		(fp_line
			(start -0.120396 0.2794)
			(end 0.12065 0.2794)
			(stroke
				(width 0.1)
				(type default)
			)
			(layer "B.Fab")
		)
		(fp_line
			(start 0.12065 0.2794)
			(end 0.12065 0.3048)
			(stroke
				(width 0.1)
				(type default)
			)
			(layer "B.Fab")
		)
		(fp_line
			(start -0.12065 -0.2794)
			(end -0.12065 -0.3048)
			(stroke
				(width 0.1)
				(type default)
			)
			(layer "B.Fab")
		)
		(fp_line
			(start 0.12065 -0.2794)
			(end -0.12065 -0.2794)
			(stroke
				(width 0.1)
				(type default)
			)
			(layer "B.Fab")
		)
		(fp_line
			(start -0.67945 -0.3048)
			(end -0.67945 0.3048)
			(stroke
				(width 0.1)
				(type default)
			)
			(layer "B.Fab")
		)
		(fp_line
			(start -0.12065 -0.3048)
			(end -0.67945 -0.3048)
			(stroke
				(width 0.1)
				(type default)
			)
			(layer "B.Fab")
		)
		(fp_line
			(start 0.12065 -0.305054)
			(end 0.12065 -0.2794)
			(stroke
				(width 0.1)
				(type default)
			)
			(layer "B.Fab")
		)
		(fp_line
			(start 0.67945 -0.305054)
			(end 0.12065 -0.305054)
			(stroke
				(width 0.1)
				(type default)
			)
			(layer "B.Fab")
		)
		(pad "1" smd circle
			(at 0.40005 0 90)
			(size 0 0)
			(layers "B.Cu" "B.Mask" "B.Paste")
			(net "P0V8_PEX0_TSEN_R")
		)
		(pad "2" smd circle
			(at -0.40005 0 90)
			(size 0 0)
			(layers "B.Cu" "B.Mask" "B.Paste")
			(net "GND")
		)
	)
	(footprint ""
		(layer "B.Cu")
		(at 77.541882 -95.989648 180)
		(property "Reference" "R62"
			(at 0 0 0)
			(layer "B.SilkS")
			(hide yes)
			(effects
				(font
					(size 1.27 1.27)
				)
				(justify mirror)
			)
		)
		(property "Value" ""
			(at 0 0 0)
			(layer "B.Fab")
			(effects
				(font
					(size 1.27 1.27)
				)
				(justify mirror)
			)
		)
		(duplicate_pad_numbers_are_jumpers no)
		(fp_line
			(start 0.7874 0.4064)
			(end 0.7874 -0.4064)
			(stroke
				(width 0.1524)
				(type default)
			)
			(layer "B.SilkS")
		)
		(fp_line
			(start 0.7874 -0.4064)
			(end -0.7874 -0.4064)
			(stroke
				(width 0.1524)
				(type default)
			)
			(layer "B.SilkS")
		)
		(fp_line
			(start -0.7874 0.4064)
			(end 0.7874 0.4064)
			(stroke
				(width 0.1524)
				(type default)
			)
			(layer "B.SilkS")
		)
		(fp_line
			(start -0.7874 -0.4064)
			(end -0.7874 0.4064)
			(stroke
				(width 0.1524)
				(type default)
			)
			(layer "B.SilkS")
		)
		(fp_line
			(start 0.67945 0.3048)
			(end 0.67945 -0.305054)
			(stroke
				(width 0.1)
				(type default)
			)
			(layer "B.Fab")
		)
		(fp_line
			(start 0.67945 -0.305054)
			(end 0.12065 -0.305054)
			(stroke
				(width 0.1)
				(type default)
			)
			(layer "B.Fab")
		)
		(fp_line
			(start 0.12065 0.3048)
			(end 0.67945 0.3048)
			(stroke
				(width 0.1)
				(type default)
			)
			(layer "B.Fab")
		)
		(fp_line
			(start 0.12065 0.2794)
			(end 0.12065 0.3048)
			(stroke
				(width 0.1)
				(type default)
			)
			(layer "B.Fab")
		)
		(fp_line
			(start 0.12065 -0.2794)
			(end -0.12065 -0.2794)
			(stroke
				(width 0.1)
				(type default)
			)
			(layer "B.Fab")
		)
		(fp_line
			(start 0.12065 -0.305054)
			(end 0.12065 -0.2794)
			(stroke
				(width 0.1)
				(type default)
			)
			(layer "B.Fab")
		)
		(fp_line
			(start -0.120396 0.3048)
			(end -0.120396 0.2794)
			(stroke
				(width 0.1)
				(type default)
			)
			(layer "B.Fab")
		)
		(fp_line
			(start -0.120396 0.2794)
			(end 0.12065 0.2794)
			(stroke
				(width 0.1)
				(type default)
			)
			(layer "B.Fab")
		)
		(fp_line
			(start -0.12065 -0.2794)
			(end -0.12065 -0.3048)
			(stroke
				(width 0.1)
				(type default)
			)
			(layer "B.Fab")
		)
		(fp_line
			(start -0.12065 -0.3048)
			(end -0.67945 -0.3048)
			(stroke
				(width 0.1)
				(type default)
			)
			(layer "B.Fab")
		)
		(fp_line
			(start -0.67945 0.3048)
			(end -0.120396 0.3048)
			(stroke
				(width 0.1)
				(type default)
			)
			(layer "B.Fab")
		)
		(fp_line
			(start -0.67945 -0.3048)
			(end -0.67945 0.3048)
			(stroke
				(width 0.1)
				(type default)
			)
			(layer "B.Fab")
		)
		(pad "1" smd circle
			(at 0.40005 0)
			(size 0 0)
			(layers "B.Cu" "B.Mask" "B.Paste")
			(net "NIC1_LD_N")
		)
		(pad "2" smd circle
			(at -0.40005 0)
			(size 0 0)
			(layers "B.Cu" "B.Mask" "B.Paste")
			(net "P3V3_NIC1")
		)
	)
	(footprint ""
		(layer "B.Cu")
		(at 401.774914 -286.399732 90)
		(property "Reference" "C3500"
			(at 0 0 90)
			(layer "B.SilkS")
			(hide yes)
			(effects
				(font
					(size 1.27 1.27)
				)
				(justify mirror)
			)
		)
		(property "Value" ""
			(at 0 0 90)
			(layer "B.Fab")
			(effects
				(font
					(size 1.27 1.27)
				)
				(justify mirror)
			)
		)
		(duplicate_pad_numbers_are_jumpers no)
		(fp_line
			(start 0.299974 -0.150114)
			(end -0.299974 -0.150114)
			(stroke
				(width 0.1)
				(type default)
			)
			(layer "B.Fab")
		)
		(fp_line
			(start -0.299974 -0.150114)
			(end -0.299974 0.150114)
			(stroke
				(width 0.1)
				(type default)
			)
			(layer "B.Fab")
		)
		(fp_line
			(start 0.299974 0.150114)
			(end 0.299974 -0.150114)
			(stroke
				(width 0.1)
				(type default)
			)
			(layer "B.Fab")
		)
		(fp_line
			(start -0.299974 0.150114)
			(end 0.299974 0.150114)
			(stroke
				(width 0.1)
				(type default)
			)
			(layer "B.Fab")
		)
		(pad "1" smd rect
			(at 0.2667 0 270)
			(size 0.3048 0.381)
			(layers "B.Cu" "B.Mask" "B.Paste")
			(net "P1V25_SERDES_VDDPLL_PEX3")
		)
		(pad "2" smd rect
			(at -0.2667 0 270)
			(size 0.3048 0.381)
			(layers "B.Cu" "B.Mask" "B.Paste")
			(net "GND")
		)
	)
	(footprint ""
		(layer "B.Cu")
		(at 62.499748 -288.299906 90)
		(property "Reference" "C2919"
			(at 0 0 90)
			(layer "B.SilkS")
			(hide yes)
			(effects
				(font
					(size 1.27 1.27)
				)
				(justify mirror)
			)
		)
		(property "Value" ""
			(at 0 0 90)
			(layer "B.Fab")
			(effects
				(font
					(size 1.27 1.27)
				)
				(justify mirror)
			)
		)
		(duplicate_pad_numbers_are_jumpers no)
		(fp_line
			(start 0.299974 -0.150114)
			(end -0.299974 -0.150114)
			(stroke
				(width 0.1)
				(type default)
			)
			(layer "B.Fab")
		)
		(fp_line
			(start -0.299974 -0.150114)
			(end -0.299974 0.150114)
			(stroke
				(width 0.1)
				(type default)
			)
			(layer "B.Fab")
		)
		(fp_line
			(start 0.299974 0.150114)
			(end 0.299974 -0.150114)
			(stroke
				(width 0.1)
				(type default)
			)
			(layer "B.Fab")
		)
		(fp_line
			(start -0.299974 0.150114)
			(end 0.299974 0.150114)
			(stroke
				(width 0.1)
				(type default)
			)
			(layer "B.Fab")
		)
		(pad "1" smd rect
			(at 0.2667 0 270)
			(size 0.3048 0.381)
			(layers "B.Cu" "B.Mask" "B.Paste")
			(net "P1V25_PEX0")
		)
		(pad "2" smd rect
			(at -0.2667 0 270)
			(size 0.3048 0.381)
			(layers "B.Cu" "B.Mask" "B.Paste")
			(net "GND")
		)
	)
	(footprint ""
		(layer "B.Cu")
		(at 408.899868 -292.099746 90)
		(property "Reference" "C2001"
			(at 0 0 90)
			(layer "B.SilkS")
			(hide yes)
			(effects
				(font
					(size 1.27 1.27)
				)
				(justify mirror)
			)
		)
		(property "Value" ""
			(at 0 0 90)
			(layer "B.Fab")
			(effects
				(font
					(size 1.27 1.27)
				)
				(justify mirror)
			)
		)
		(duplicate_pad_numbers_are_jumpers no)
		(fp_line
			(start 0.299974 -0.150114)
			(end -0.299974 -0.150114)
			(stroke
				(width 0.1)
				(type default)
			)
			(layer "B.Fab")
		)
		(fp_line
			(start -0.299974 -0.150114)
			(end -0.299974 0.150114)
			(stroke
				(width 0.1)
				(type default)
			)
			(layer "B.Fab")
		)
		(fp_line
			(start 0.299974 0.150114)
			(end 0.299974 -0.150114)
			(stroke
				(width 0.1)
				(type default)
			)
			(layer "B.Fab")
		)
		(fp_line
			(start -0.299974 0.150114)
			(end 0.299974 0.150114)
			(stroke
				(width 0.1)
				(type default)
			)
			(layer "B.Fab")
		)
		(pad "1" smd rect
			(at 0.2667 0 270)
			(size 0.3048 0.381)
			(layers "B.Cu" "B.Mask" "B.Paste")
			(net "P0V8_SERDES_VDDA_PEX3")
		)
		(pad "2" smd rect
			(at -0.2667 0 270)
			(size 0.3048 0.381)
			(layers "B.Cu" "B.Mask" "B.Paste")
			(net "GND")
		)
	)
	(footprint ""
		(layer "B.Cu")
		(at 340.093808 -223.187006)
		(property "Reference" "C2031"
			(at 0 0 0)
			(layer "B.SilkS")
			(hide yes)
			(effects
				(font
					(size 1.27 1.27)
				)
				(justify mirror)
			)
		)
		(property "Value" ""
			(at 0 0 0)
			(layer "B.Fab")
			(effects
				(font
					(size 1.27 1.27)
				)
				(justify mirror)
			)
		)
		(duplicate_pad_numbers_are_jumpers no)
		(fp_line
			(start -0.69215 -0.2921)
			(end -0.69215 0.2921)
			(stroke
				(width 0.1524)
				(type default)
			)
			(layer "B.SilkS")
		)
		(fp_line
			(start -0.69215 0.2921)
			(end 0.69215 0.2921)
			(stroke
				(width 0.1524)
				(type default)
			)
			(layer "B.SilkS")
		)
		(fp_line
			(start 0.69215 -0.2921)
			(end -0.69215 -0.2921)
			(stroke
				(width 0.1524)
				(type default)
			)
			(layer "B.SilkS")
		)
		(fp_line
			(start 0.69215 0.2921)
			(end 0.69215 -0.2921)
			(stroke
				(width 0.1524)
				(type default)
			)
			(layer "B.SilkS")
		)
		(fp_line
			(start -0.51435 -0.2794)
			(end -0.51435 0.2794)
			(stroke
				(width 0.1)
				(type default)
			)
			(layer "B.Fab")
		)
		(fp_line
			(start -0.51435 0.2794)
			(end 0.51435 0.2794)
			(stroke
				(width 0.1)
				(type default)
			)
			(layer "B.Fab")
		)
		(fp_line
			(start 0.51435 -0.2794)
			(end -0.51435 -0.2794)
			(stroke
				(width 0.1)
				(type default)
			)
			(layer "B.Fab")
		)
		(fp_line
			(start 0.51435 0.2794)
			(end 0.51435 -0.2794)
			(stroke
				(width 0.1)
				(type default)
			)
			(layer "B.Fab")
		)
		(pad "1" smd circle
			(at 0.40005 0 180)
			(size 0 0)
			(layers "B.Cu" "B.Mask" "B.Paste")
			(net "P3V3_FPGA_VCCIO0")
		)
		(pad "2" smd circle
			(at -0.40005 0 180)
			(size 0 0)
			(layers "B.Cu" "B.Mask" "B.Paste")
			(net "GND")
		)
		(zone
			(layer "B.Cu")
			(hatch none 0.5)
			(connect_pads
				(clearance 0)
			)
			(min_thickness 0.25)
			(keepout
				(tracks not_allowed)
				(vias allowed)
				(pads allowed)
				(copperpour not_allowed)
				(footprints allowed)
			)
			(placement
				(enabled no)
				(sheetname "")
			)
			(fill
				(thermal_gap 0.5)
				(thermal_bridge_width 0.5)
				(island_removal_mode 0)
			)
			(polygon
				(pts
					(xy 340.284308 -223.099376) (xy 340.192868 -223.04121) (xy 339.993478 -223.04121) (xy 339.903308 -223.099376)
					(xy 339.903308 -223.274636) (xy 339.993478 -223.333056) (xy 340.192868 -223.333056) (xy 340.284308 -223.27489)
				)
			)
		)
	)
	(footprint ""
		(layer "B.Cu")
		(at 297.549824 -292.099746 90)
		(property "Reference" "C1680"
			(at 0 0 90)
			(layer "B.SilkS")
			(hide yes)
			(effects
				(font
					(size 1.27 1.27)
				)
				(justify mirror)
			)
		)
		(property "Value" ""
			(at 0 0 90)
			(layer "B.Fab")
			(effects
				(font
					(size 1.27 1.27)
				)
				(justify mirror)
			)
		)
		(duplicate_pad_numbers_are_jumpers no)
		(fp_line
			(start 0.299974 -0.150114)
			(end -0.299974 -0.150114)
			(stroke
				(width 0.1)
				(type default)
			)
			(layer "B.Fab")
		)
		(fp_line
			(start -0.299974 -0.150114)
			(end -0.299974 0.150114)
			(stroke
				(width 0.1)
				(type default)
			)
			(layer "B.Fab")
		)
		(fp_line
			(start 0.299974 0.150114)
			(end 0.299974 -0.150114)
			(stroke
				(width 0.1)
				(type default)
			)
			(layer "B.Fab")
		)
		(fp_line
			(start -0.299974 0.150114)
			(end 0.299974 0.150114)
			(stroke
				(width 0.1)
				(type default)
			)
			(layer "B.Fab")
		)
		(pad "1" smd rect
			(at 0.2667 0 270)
			(size 0.3048 0.381)
			(layers "B.Cu" "B.Mask" "B.Paste")
			(net "P0V8_SERDES_VDDA_PEX2")
		)
		(pad "2" smd rect
			(at -0.2667 0 270)
			(size 0.3048 0.381)
			(layers "B.Cu" "B.Mask" "B.Paste")
			(net "GND")
		)
	)
	(footprint ""
		(layer "B.Cu")
		(at 262.96239 -85.784944)
		(property "Reference" "C2648"
			(at 0 0 0)
			(layer "B.SilkS")
			(hide yes)
			(effects
				(font
					(size 1.27 1.27)
				)
				(justify mirror)
			)
		)
		(property "Value" ""
			(at 0 0 0)
			(layer "B.Fab")
			(effects
				(font
					(size 1.27 1.27)
				)
				(justify mirror)
			)
		)
		(duplicate_pad_numbers_are_jumpers no)
		(fp_line
			(start -0.7874 -0.4064)
			(end -0.7874 0.4064)
			(stroke
				(width 0.1524)
				(type default)
			)
			(layer "B.SilkS")
		)
		(fp_line
			(start -0.7874 0.4064)
			(end 0.7874 0.4064)
			(stroke
				(width 0.1524)
				(type default)
			)
			(layer "B.SilkS")
		)
		(fp_line
			(start 0.7874 -0.4064)
			(end -0.7874 -0.4064)
			(stroke
				(width 0.1524)
				(type default)
			)
			(layer "B.SilkS")
		)
		(fp_line
			(start 0.7874 0.4064)
			(end 0.7874 -0.4064)
			(stroke
				(width 0.1524)
				(type default)
			)
			(layer "B.SilkS")
		)
		(fp_line
			(start -0.67945 -0.3048)
			(end -0.67945 0.3048)
			(stroke
				(width 0.1)
				(type default)
			)
			(layer "B.Fab")
		)
		(fp_line
			(start -0.67945 0.3048)
			(end -0.120396 0.3048)
			(stroke
				(width 0.1)
				(type default)
			)
			(layer "B.Fab")
		)
		(fp_line
			(start -0.12065 -0.3048)
			(end -0.67945 -0.3048)
			(stroke
				(width 0.1)
				(type default)
			)
			(layer "B.Fab")
		)
		(fp_line
			(start -0.12065 -0.2794)
			(end -0.12065 -0.3048)
			(stroke
				(width 0.1)
				(type default)
			)
			(layer "B.Fab")
		)
		(fp_line
			(start -0.120396 0.2794)
			(end 0.12065 0.2794)
			(stroke
				(width 0.1)
				(type default)
			)
			(layer "B.Fab")
		)
		(fp_line
			(start -0.120396 0.3048)
			(end -0.120396 0.2794)
			(stroke
				(width 0.1)
				(type default)
			)
			(layer "B.Fab")
		)
		(fp_line
			(start 0.12065 -0.305054)
			(end 0.12065 -0.2794)
			(stroke
				(width 0.1)
				(type default)
			)
			(layer "B.Fab")
		)
		(fp_line
			(start 0.12065 -0.2794)
			(end -0.12065 -0.2794)
			(stroke
				(width 0.1)
				(type default)
			)
			(layer "B.Fab")
		)
		(fp_line
			(start 0.12065 0.2794)
			(end 0.12065 0.3048)
			(stroke
				(width 0.1)
				(type default)
			)
			(layer "B.Fab")
		)
		(fp_line
			(start 0.12065 0.3048)
			(end 0.67945 0.3048)
			(stroke
				(width 0.1)
				(type default)
			)
			(layer "B.Fab")
		)
		(fp_line
			(start 0.67945 -0.305054)
			(end 0.12065 -0.305054)
			(stroke
				(width 0.1)
				(type default)
			)
			(layer "B.Fab")
		)
		(fp_line
			(start 0.67945 0.3048)
			(end 0.67945 -0.305054)
			(stroke
				(width 0.1)
				(type default)
			)
			(layer "B.Fab")
		)
		(pad "1" smd circle
			(at 0.40005 0 180)
			(size 0 0)
			(layers "B.Cu" "B.Mask" "B.Paste")
			(net "P3V3_CLK_GEN_VDDMXCK_CK440")
		)
		(pad "2" smd circle
			(at -0.40005 0 180)
			(size 0 0)
			(layers "B.Cu" "B.Mask" "B.Paste")
			(net "GND")
		)
	)
	(footprint ""
		(layer "B.Cu")
		(at 160.549844 -299.699934)
		(property "Reference" "C3183"
			(at 0 0 0)
			(layer "B.SilkS")
			(hide yes)
			(effects
				(font
					(size 1.27 1.27)
				)
				(justify mirror)
			)
		)
		(property "Value" ""
			(at 0 0 0)
			(layer "B.Fab")
			(effects
				(font
					(size 1.27 1.27)
				)
				(justify mirror)
			)
		)
		(duplicate_pad_numbers_are_jumpers no)
		(fp_line
			(start -0.299974 -0.150114)
			(end -0.299974 0.150114)
			(stroke
				(width 0.1)
				(type default)
			)
			(layer "B.Fab")
		)
		(fp_line
			(start -0.299974 0.150114)
			(end 0.299974 0.150114)
			(stroke
				(width 0.1)
				(type default)
			)
			(layer "B.Fab")
		)
		(fp_line
			(start 0.299974 -0.150114)
			(end -0.299974 -0.150114)
			(stroke
				(width 0.1)
				(type default)
			)
			(layer "B.Fab")
		)
		(fp_line
			(start 0.299974 0.150114)
			(end 0.299974 -0.150114)
			(stroke
				(width 0.1)
				(type default)
			)
			(layer "B.Fab")
		)
		(pad "1" smd rect
			(at 0.2667 0 180)
			(size 0.3048 0.381)
			(layers "B.Cu" "B.Mask" "B.Paste")
			(net "P1V8_VDDA_PEX1")
		)
		(pad "2" smd rect
			(at -0.2667 0 180)
			(size 0.3048 0.381)
			(layers "B.Cu" "B.Mask" "B.Paste")
			(net "GND")
		)
	)
	(footprint ""
		(layer "B.Cu")
		(at 363.275118 -221.640908 90)
		(property "Reference" "R3503"
			(at 0 0 90)
			(layer "B.SilkS")
			(hide yes)
			(effects
				(font
					(size 1.27 1.27)
				)
				(justify mirror)
			)
		)
		(property "Value" ""
			(at 0 0 90)
			(layer "B.Fab")
			(effects
				(font
					(size 1.27 1.27)
				)
				(justify mirror)
			)
		)
		(duplicate_pad_numbers_are_jumpers no)
		(fp_line
			(start 0.7874 -0.4064)
			(end -0.7874 -0.4064)
			(stroke
				(width 0.1524)
				(type default)
			)
			(layer "B.SilkS")
		)
		(fp_line
			(start -0.7874 -0.4064)
			(end -0.7874 0.4064)
			(stroke
				(width 0.1524)
				(type default)
			)
			(layer "B.SilkS")
		)
		(fp_line
			(start 0.7874 0.4064)
			(end 0.7874 -0.4064)
			(stroke
				(width 0.1524)
				(type default)
			)
			(layer "B.SilkS")
		)
		(fp_line
			(start -0.7874 0.4064)
			(end 0.7874 0.4064)
			(stroke
				(width 0.1524)
				(type default)
			)
			(layer "B.SilkS")
		)
		(fp_line
			(start 0.67945 -0.305054)
			(end 0.12065 -0.305054)
			(stroke
				(width 0.1)
				(type default)
			)
			(layer "B.Fab")
		)
		(fp_line
			(start 0.12065 -0.305054)
			(end 0.12065 -0.2794)
			(stroke
				(width 0.1)
				(type default)
			)
			(layer "B.Fab")
		)
		(fp_line
			(start -0.12065 -0.3048)
			(end -0.67945 -0.3048)
			(stroke
				(width 0.1)
				(type default)
			)
			(layer "B.Fab")
		)
		(fp_line
			(start -0.67945 -0.3048)
			(end -0.67945 0.3048)
			(stroke
				(width 0.1)
				(type default)
			)
			(layer "B.Fab")
		)
		(fp_line
			(start 0.12065 -0.2794)
			(end -0.12065 -0.2794)
			(stroke
				(width 0.1)
				(type default)
			)
			(layer "B.Fab")
		)
		(fp_line
			(start -0.12065 -0.2794)
			(end -0.12065 -0.3048)
			(stroke
				(width 0.1)
				(type default)
			)
			(layer "B.Fab")
		)
		(fp_line
			(start 0.12065 0.2794)
			(end 0.12065 0.3048)
			(stroke
				(width 0.1)
				(type default)
			)
			(layer "B.Fab")
		)
		(fp_line
			(start -0.120396 0.2794)
			(end 0.12065 0.2794)
			(stroke
				(width 0.1)
				(type default)
			)
			(layer "B.Fab")
		)
		(fp_line
			(start 0.67945 0.3048)
			(end 0.67945 -0.305054)
			(stroke
				(width 0.1)
				(type default)
			)
			(layer "B.Fab")
		)
		(fp_line
			(start 0.12065 0.3048)
			(end 0.67945 0.3048)
			(stroke
				(width 0.1)
				(type default)
			)
			(layer "B.Fab")
		)
		(fp_line
			(start -0.120396 0.3048)
			(end -0.120396 0.2794)
			(stroke
				(width 0.1)
				(type default)
			)
			(layer "B.Fab")
		)
		(fp_line
			(start -0.67945 0.3048)
			(end -0.120396 0.3048)
			(stroke
				(width 0.1)
				(type default)
			)
			(layer "B.Fab")
		)
		(pad "1" smd circle
			(at 0.40005 0 270)
			(size 0 0)
			(layers "B.Cu" "B.Mask" "B.Paste")
			(net "SPI_PEX3_CLK_MUX")
		)
		(pad "2" smd circle
			(at -0.40005 0 270)
			(size 0 0)
			(layers "B.Cu" "B.Mask" "B.Paste")
			(net "SPI_PEX3_CLK_MUX_R")
		)
	)
	(footprint ""
		(layer "B.Cu")
		(at 65.370202 -296.37482)
		(property "Reference" "C1127"
			(at 0 0 0)
			(layer "B.SilkS")
			(hide yes)
			(effects
				(font
					(size 1.27 1.27)
				)
				(justify mirror)
			)
		)
		(property "Value" ""
			(at 0 0 0)
			(layer "B.Fab")
			(effects
				(font
					(size 1.27 1.27)
				)
				(justify mirror)
			)
		)
		(duplicate_pad_numbers_are_jumpers no)
		(fp_line
			(start -0.299974 -0.150114)
			(end -0.299974 0.150114)
			(stroke
				(width 0.1)
				(type default)
			)
			(layer "B.Fab")
		)
		(fp_line
			(start -0.299974 0.150114)
			(end 0.299974 0.150114)
			(stroke
				(width 0.1)
				(type default)
			)
			(layer "B.Fab")
		)
		(fp_line
			(start 0.299974 -0.150114)
			(end -0.299974 -0.150114)
			(stroke
				(width 0.1)
				(type default)
			)
			(layer "B.Fab")
		)
		(fp_line
			(start 0.299974 0.150114)
			(end 0.299974 -0.150114)
			(stroke
				(width 0.1)
				(type default)
			)
			(layer "B.Fab")
		)
		(pad "1" smd rect
			(at 0.2667 0 180)
			(size 0.3048 0.381)
			(layers "B.Cu" "B.Mask" "B.Paste")
			(net "P0V8_PEX0")
		)
		(pad "2" smd rect
			(at -0.2667 0 180)
			(size 0.3048 0.381)
			(layers "B.Cu" "B.Mask" "B.Paste")
			(net "GND")
		)
	)
	(footprint ""
		(layer "B.Cu")
		(at 414.151318 -305.399948 -90)
		(property "Reference" "C3483"
			(at 0 0 90)
			(layer "B.SilkS")
			(hide yes)
			(effects
				(font
					(size 1.27 1.27)
				)
				(justify mirror)
			)
		)
		(property "Value" ""
			(at 0 0 90)
			(layer "B.Fab")
			(effects
				(font
					(size 1.27 1.27)
				)
				(justify mirror)
			)
		)
		(duplicate_pad_numbers_are_jumpers no)
		(fp_line
			(start -0.299974 0.150114)
			(end 0.299974 0.150114)
			(stroke
				(width 0.1)
				(type default)
			)
			(layer "B.Fab")
		)
		(fp_line
			(start 0.299974 0.150114)
			(end 0.299974 -0.150114)
			(stroke
				(width 0.1)
				(type default)
			)
			(layer "B.Fab")
		)
		(fp_line
			(start -0.299974 -0.150114)
			(end -0.299974 0.150114)
			(stroke
				(width 0.1)
				(type default)
			)
			(layer "B.Fab")
		)
		(fp_line
			(start 0.299974 -0.150114)
			(end -0.299974 -0.150114)
			(stroke
				(width 0.1)
				(type default)
			)
			(layer "B.Fab")
		)
		(pad "1" smd rect
			(at 0.2667 0 90)
			(size 0.3048 0.381)
			(layers "B.Cu" "B.Mask" "B.Paste")
			(net "P1V25_SERDES_VDDPLL_PEX3")
		)
		(pad "2" smd rect
			(at -0.2667 0 90)
			(size 0.3048 0.381)
			(layers "B.Cu" "B.Mask" "B.Paste")
			(net "GND")
		)
	)
	(footprint ""
		(layer "B.Cu")
		(at 389.899906 -288.774886 90)
		(property "Reference" "R6160"
			(at 0 0 90)
			(layer "B.SilkS")
			(hide yes)
			(effects
				(font
					(size 1.27 1.27)
				)
				(justify mirror)
			)
		)
		(property "Value" ""
			(at 0 0 90)
			(layer "B.Fab")
			(effects
				(font
					(size 1.27 1.27)
				)
				(justify mirror)
			)
		)
		(duplicate_pad_numbers_are_jumpers no)
		(fp_line
			(start 0.7874 -0.4064)
			(end -0.7874 -0.4064)
			(stroke
				(width 0.1524)
				(type default)
			)
			(layer "B.SilkS")
		)
		(fp_line
			(start -0.7874 -0.4064)
			(end -0.7874 0.4064)
			(stroke
				(width 0.1524)
				(type default)
			)
			(layer "B.SilkS")
		)
		(fp_line
			(start 0.7874 0.4064)
			(end 0.7874 -0.4064)
			(stroke
				(width 0.1524)
				(type default)
			)
			(layer "B.SilkS")
		)
		(fp_line
			(start -0.7874 0.4064)
			(end 0.7874 0.4064)
			(stroke
				(width 0.1524)
				(type default)
			)
			(layer "B.SilkS")
		)
		(fp_line
			(start 0.67945 -0.305054)
			(end 0.12065 -0.305054)
			(stroke
				(width 0.1)
				(type default)
			)
			(layer "B.Fab")
		)
		(fp_line
			(start 0.12065 -0.305054)
			(end 0.12065 -0.2794)
			(stroke
				(width 0.1)
				(type default)
			)
			(layer "B.Fab")
		)
		(fp_line
			(start -0.12065 -0.3048)
			(end -0.67945 -0.3048)
			(stroke
				(width 0.1)
				(type default)
			)
			(layer "B.Fab")
		)
		(fp_line
			(start -0.67945 -0.3048)
			(end -0.67945 0.3048)
			(stroke
				(width 0.1)
				(type default)
			)
			(layer "B.Fab")
		)
		(fp_line
			(start 0.12065 -0.2794)
			(end -0.12065 -0.2794)
			(stroke
				(width 0.1)
				(type default)
			)
			(layer "B.Fab")
		)
		(fp_line
			(start -0.12065 -0.2794)
			(end -0.12065 -0.3048)
			(stroke
				(width 0.1)
				(type default)
			)
			(layer "B.Fab")
		)
		(fp_line
			(start 0.12065 0.2794)
			(end 0.12065 0.3048)
			(stroke
				(width 0.1)
				(type default)
			)
			(layer "B.Fab")
		)
		(fp_line
			(start -0.120396 0.2794)
			(end 0.12065 0.2794)
			(stroke
				(width 0.1)
				(type default)
			)
			(layer "B.Fab")
		)
		(fp_line
			(start 0.67945 0.3048)
			(end 0.67945 -0.305054)
			(stroke
				(width 0.1)
				(type default)
			)
			(layer "B.Fab")
		)
		(fp_line
			(start 0.12065 0.3048)
			(end 0.67945 0.3048)
			(stroke
				(width 0.1)
				(type default)
			)
			(layer "B.Fab")
		)
		(fp_line
			(start -0.120396 0.3048)
			(end -0.120396 0.2794)
			(stroke
				(width 0.1)
				(type default)
			)
			(layer "B.Fab")
		)
		(fp_line
			(start -0.67945 0.3048)
			(end -0.120396 0.3048)
			(stroke
				(width 0.1)
				(type default)
			)
			(layer "B.Fab")
		)
		(pad "1" smd circle
			(at 0.40005 0 270)
			(size 0 0)
			(layers "B.Cu" "B.Mask" "B.Paste")
			(net "SPI_PEX3_CS_N")
		)
		(pad "2" smd circle
			(at -0.40005 0 270)
			(size 0 0)
			(layers "B.Cu" "B.Mask" "B.Paste")
			(net "P1V8_PEX")
		)
	)
	(footprint ""
		(layer "B.Cu")
		(at 5.617718 -264.586466)
		(property "Reference" "L83"
			(at 0 0 0)
			(layer "B.SilkS")
			(hide yes)
			(effects
				(font
					(size 1.27 1.27)
				)
				(justify mirror)
			)
		)
		(property "Value" ""
			(at 0 0 0)
			(layer "B.Fab")
			(effects
				(font
					(size 1.27 1.27)
				)
				(justify mirror)
			)
		)
		(duplicate_pad_numbers_are_jumpers no)
		(fp_line
			(start -2.248154 -4.9911)
			(end 2.248154 -4.9911)
			(stroke
				(width 0.1524)
				(type default)
			)
			(layer "B.SilkS")
		)
		(fp_line
			(start -2.248154 -2.077974)
			(end -2.248154 -4.9911)
			(stroke
				(width 0.1524)
				(type default)
			)
			(layer "B.SilkS")
		)
		(fp_line
			(start -2.248154 4.9911)
			(end -2.248154 2.20472)
			(stroke
				(width 0.1524)
				(type default)
			)
			(layer "B.SilkS")
		)
		(fp_line
			(start 2.248154 -4.9911)
			(end 2.248154 -2.077974)
			(stroke
				(width 0.1524)
				(type default)
			)
			(layer "B.SilkS")
		)
		(fp_line
			(start 2.248154 2.20472)
			(end 2.248154 4.9911)
			(stroke
				(width 0.1524)
				(type default)
			)
			(layer "B.SilkS")
		)
		(fp_line
			(start 2.248154 4.9911)
			(end -2.248154 4.9911)
			(stroke
				(width 0.1524)
				(type default)
			)
			(layer "B.SilkS")
		)
		(fp_line
			(start -1.700022 -0.899922)
			(end 1.700022 -0.899922)
			(stroke
				(width 0.1)
				(type default)
			)
			(layer "B.Fab")
		)
		(fp_line
			(start -1.700022 0.899922)
			(end -1.700022 -0.899922)
			(stroke
				(width 0.1)
				(type default)
			)
			(layer "B.Fab")
		)
		(fp_line
			(start 1.700022 -0.899922)
			(end 1.700022 0.899922)
			(stroke
				(width 0.1)
				(type default)
			)
			(layer "B.Fab")
		)
		(fp_line
			(start 1.700022 0.899922)
			(end -1.700022 0.899922)
			(stroke
				(width 0.1)
				(type default)
			)
			(layer "B.Fab")
		)
		(pad "1" smd rect
			(at 1.575054 0 180)
			(size 1.1684 9.8044)
			(layers "B.Cu" "B.Mask" "B.Paste")
			(net "P1V25_PEX0")
		)
		(pad "2" smd rect
			(at -1.575054 0 180)
			(size 1.1684 9.8044)
			(layers "B.Cu" "B.Mask" "B.Paste")
			(net "P1V25_SERDES_VDDPLL_PEX0")
		)
	)
	(footprint ""
		(layer "B.Cu")
		(at 110.884208 -88.81745)
		(property "Reference" "C2668"
			(at 0 0 0)
			(layer "B.SilkS")
			(hide yes)
			(effects
				(font
					(size 1.27 1.27)
				)
				(justify mirror)
			)
		)
		(property "Value" ""
			(at 0 0 0)
			(layer "B.Fab")
			(effects
				(font
					(size 1.27 1.27)
				)
				(justify mirror)
			)
		)
		(duplicate_pad_numbers_are_jumpers no)
		(fp_line
			(start -0.7874 -0.4064)
			(end -0.7874 0.4064)
			(stroke
				(width 0.1524)
				(type default)
			)
			(layer "B.SilkS")
		)
		(fp_line
			(start -0.7874 0.4064)
			(end 0.7874 0.4064)
			(stroke
				(width 0.1524)
				(type default)
			)
			(layer "B.SilkS")
		)
		(fp_line
			(start 0.7874 -0.4064)
			(end -0.7874 -0.4064)
			(stroke
				(width 0.1524)
				(type default)
			)
			(layer "B.SilkS")
		)
		(fp_line
			(start 0.7874 0.4064)
			(end 0.7874 -0.4064)
			(stroke
				(width 0.1524)
				(type default)
			)
			(layer "B.SilkS")
		)
		(fp_line
			(start -0.67945 -0.3048)
			(end -0.67945 0.3048)
			(stroke
				(width 0.1)
				(type default)
			)
			(layer "B.Fab")
		)
		(fp_line
			(start -0.67945 0.3048)
			(end -0.120396 0.3048)
			(stroke
				(width 0.1)
				(type default)
			)
			(layer "B.Fab")
		)
		(fp_line
			(start -0.12065 -0.3048)
			(end -0.67945 -0.3048)
			(stroke
				(width 0.1)
				(type default)
			)
			(layer "B.Fab")
		)
		(fp_line
			(start -0.12065 -0.2794)
			(end -0.12065 -0.3048)
			(stroke
				(width 0.1)
				(type default)
			)
			(layer "B.Fab")
		)
		(fp_line
			(start -0.120396 0.2794)
			(end 0.12065 0.2794)
			(stroke
				(width 0.1)
				(type default)
			)
			(layer "B.Fab")
		)
		(fp_line
			(start -0.120396 0.3048)
			(end -0.120396 0.2794)
			(stroke
				(width 0.1)
				(type default)
			)
			(layer "B.Fab")
		)
		(fp_line
			(start 0.12065 -0.305054)
			(end 0.12065 -0.2794)
			(stroke
				(width 0.1)
				(type default)
			)
			(layer "B.Fab")
		)
		(fp_line
			(start 0.12065 -0.2794)
			(end -0.12065 -0.2794)
			(stroke
				(width 0.1)
				(type default)
			)
			(layer "B.Fab")
		)
		(fp_line
			(start 0.12065 0.2794)
			(end 0.12065 0.3048)
			(stroke
				(width 0.1)
				(type default)
			)
			(layer "B.Fab")
		)
		(fp_line
			(start 0.12065 0.3048)
			(end 0.67945 0.3048)
			(stroke
				(width 0.1)
				(type default)
			)
			(layer "B.Fab")
		)
		(fp_line
			(start 0.67945 -0.305054)
			(end 0.12065 -0.305054)
			(stroke
				(width 0.1)
				(type default)
			)
			(layer "B.Fab")
		)
		(fp_line
			(start 0.67945 0.3048)
			(end 0.67945 -0.305054)
			(stroke
				(width 0.1)
				(type default)
			)
			(layer "B.Fab")
		)
		(pad "1" smd circle
			(at 0.40005 0 180)
			(size 0 0)
			(layers "B.Cu" "B.Mask" "B.Paste")
			(net "P3V3_VDD_9ZXL0851_0_7")
		)
		(pad "2" smd circle
			(at -0.40005 0 180)
			(size 0 0)
			(layers "B.Cu" "B.Mask" "B.Paste")
			(net "GND")
		)
	)
	(footprint ""
		(layer "B.Cu")
		(at 137.689336 -173.827186 90)
		(property "Reference" "C2657"
			(at 0 0 90)
			(layer "B.SilkS")
			(hide yes)
			(effects
				(font
					(size 1.27 1.27)
				)
				(justify mirror)
			)
		)
		(property "Value" ""
			(at 0 0 90)
			(layer "B.Fab")
			(effects
				(font
					(size 1.27 1.27)
				)
				(justify mirror)
			)
		)
		(duplicate_pad_numbers_are_jumpers no)
		(fp_line
			(start 1.2954 -0.5842)
			(end -1.2954 -0.5842)
			(stroke
				(width 0.1524)
				(type default)
			)
			(layer "B.SilkS")
		)
		(fp_line
			(start -1.2954 -0.5842)
			(end -1.2954 0.5842)
			(stroke
				(width 0.1524)
				(type default)
			)
			(layer "B.SilkS")
		)
		(fp_line
			(start 1.2954 0.5842)
			(end 1.2954 -0.5842)
			(stroke
				(width 0.1524)
				(type default)
			)
			(layer "B.SilkS")
		)
		(fp_line
			(start -1.2954 0.5842)
			(end 1.2954 0.5842)
			(stroke
				(width 0.1524)
				(type default)
			)
			(layer "B.SilkS")
		)
		(fp_line
			(start 0.8636 -0.4572)
			(end -0.8636 -0.4572)
			(stroke
				(width 0.1)
				(type default)
			)
			(layer "B.Fab")
		)
		(fp_line
			(start -0.8636 -0.4572)
			(end -0.8636 -0.4064)
			(stroke
				(width 0.1)
				(type default)
			)
			(layer "B.Fab")
		)
		(fp_line
			(start 1.1938 -0.4064)
			(end 0.8636 -0.4064)
			(stroke
				(width 0.1)
				(type default)
			)
			(layer "B.Fab")
		)
		(fp_line
			(start 0.8636 -0.4064)
			(end 0.8636 -0.4572)
			(stroke
				(width 0.1)
				(type default)
			)
			(layer "B.Fab")
		)
		(fp_line
			(start -0.8636 -0.4064)
			(end -1.1938 -0.4064)
			(stroke
				(width 0.1)
				(type default)
			)
			(layer "B.Fab")
		)
		(fp_line
			(start -1.1938 -0.4064)
			(end -1.1938 0.4064)
			(stroke
				(width 0.1)
				(type default)
			)
			(layer "B.Fab")
		)
		(fp_line
			(start 1.1938 0.4064)
			(end 1.1938 -0.4064)
			(stroke
				(width 0.1)
				(type default)
			)
			(layer "B.Fab")
		)
		(fp_line
			(start 0.8636 0.4064)
			(end 1.1938 0.4064)
			(stroke
				(width 0.1)
				(type default)
			)
			(layer "B.Fab")
		)
		(fp_line
			(start -0.8636 0.4064)
			(end -0.8636 0.4572)
			(stroke
				(width 0.1)
				(type default)
			)
			(layer "B.Fab")
		)
		(fp_line
			(start -1.1938 0.4064)
			(end -0.8636 0.4064)
			(stroke
				(width 0.1)
				(type default)
			)
			(layer "B.Fab")
		)
		(fp_line
			(start 0.8636 0.4572)
			(end 0.8636 0.4064)
			(stroke
				(width 0.1)
				(type default)
			)
			(layer "B.Fab")
		)
		(fp_line
			(start -0.8636 0.4572)
			(end 0.8636 0.4572)
			(stroke
				(width 0.1)
				(type default)
			)
			(layer "B.Fab")
		)
		(pad "1" smd rect
			(at 0.7366 0)
			(size 0.7112 0.8128)
			(layers "B.Cu" "B.Mask" "B.Paste")
			(net "P3V3_DB2000QL_VDD")
		)
		(pad "2" smd rect
			(at -0.7366 0)
			(size 0.7112 0.8128)
			(layers "B.Cu" "B.Mask" "B.Paste")
			(net "GND")
		)
	)
	(footprint ""
		(layer "B.Cu")
		(at 304.093626 -239.976406 90)
		(property "Reference" "R4101"
			(at 0 0 90)
			(layer "B.SilkS")
			(hide yes)
			(effects
				(font
					(size 1.27 1.27)
				)
				(justify mirror)
			)
		)
		(property "Value" ""
			(at 0 0 90)
			(layer "B.Fab")
			(effects
				(font
					(size 1.27 1.27)
				)
				(justify mirror)
			)
		)
		(duplicate_pad_numbers_are_jumpers no)
		(fp_line
			(start 0.7874 -0.4064)
			(end -0.7874 -0.4064)
			(stroke
				(width 0.1524)
				(type default)
			)
			(layer "B.SilkS")
		)
		(fp_line
			(start -0.7874 -0.4064)
			(end -0.7874 0.4064)
			(stroke
				(width 0.1524)
				(type default)
			)
			(layer "B.SilkS")
		)
		(fp_line
			(start 0.7874 0.4064)
			(end 0.7874 -0.4064)
			(stroke
				(width 0.1524)
				(type default)
			)
			(layer "B.SilkS")
		)
		(fp_line
			(start -0.7874 0.4064)
			(end 0.7874 0.4064)
			(stroke
				(width 0.1524)
				(type default)
			)
			(layer "B.SilkS")
		)
		(fp_line
			(start 0.67945 -0.305054)
			(end 0.12065 -0.305054)
			(stroke
				(width 0.1)
				(type default)
			)
			(layer "B.Fab")
		)
		(fp_line
			(start 0.12065 -0.305054)
			(end 0.12065 -0.2794)
			(stroke
				(width 0.1)
				(type default)
			)
			(layer "B.Fab")
		)
		(fp_line
			(start -0.12065 -0.3048)
			(end -0.67945 -0.3048)
			(stroke
				(width 0.1)
				(type default)
			)
			(layer "B.Fab")
		)
		(fp_line
			(start -0.67945 -0.3048)
			(end -0.67945 0.3048)
			(stroke
				(width 0.1)
				(type default)
			)
			(layer "B.Fab")
		)
		(fp_line
			(start 0.12065 -0.2794)
			(end -0.12065 -0.2794)
			(stroke
				(width 0.1)
				(type default)
			)
			(layer "B.Fab")
		)
		(fp_line
			(start -0.12065 -0.2794)
			(end -0.12065 -0.3048)
			(stroke
				(width 0.1)
				(type default)
			)
			(layer "B.Fab")
		)
		(fp_line
			(start 0.12065 0.2794)
			(end 0.12065 0.3048)
			(stroke
				(width 0.1)
				(type default)
			)
			(layer "B.Fab")
		)
		(fp_line
			(start -0.120396 0.2794)
			(end 0.12065 0.2794)
			(stroke
				(width 0.1)
				(type default)
			)
			(layer "B.Fab")
		)
		(fp_line
			(start 0.67945 0.3048)
			(end 0.67945 -0.305054)
			(stroke
				(width 0.1)
				(type default)
			)
			(layer "B.Fab")
		)
		(fp_line
			(start 0.12065 0.3048)
			(end 0.67945 0.3048)
			(stroke
				(width 0.1)
				(type default)
			)
			(layer "B.Fab")
		)
		(fp_line
			(start -0.120396 0.3048)
			(end -0.120396 0.2794)
			(stroke
				(width 0.1)
				(type default)
			)
			(layer "B.Fab")
		)
		(fp_line
			(start -0.67945 0.3048)
			(end -0.120396 0.3048)
			(stroke
				(width 0.1)
				(type default)
			)
			(layer "B.Fab")
		)
		(pad "1" smd circle
			(at 0.40005 0 270)
			(size 0 0)
			(layers "B.Cu" "B.Mask" "B.Paste")
			(net "SMB_MB_BMC_ISO_SCL")
		)
		(pad "2" smd circle
			(at -0.40005 0 270)
			(size 0 0)
			(layers "B.Cu" "B.Mask" "B.Paste")
			(net "P3V3_AUX")
		)
	)
	(footprint ""
		(layer "B.Cu")
		(at 180.02504 -297.79976 90)
		(property "Reference" "C1384"
			(at 0 0 90)
			(layer "B.SilkS")
			(hide yes)
			(effects
				(font
					(size 1.27 1.27)
				)
				(justify mirror)
			)
		)
		(property "Value" ""
			(at 0 0 90)
			(layer "B.Fab")
			(effects
				(font
					(size 1.27 1.27)
				)
				(justify mirror)
			)
		)
		(duplicate_pad_numbers_are_jumpers no)
		(fp_line
			(start 0.299974 -0.150114)
			(end -0.299974 -0.150114)
			(stroke
				(width 0.1)
				(type default)
			)
			(layer "B.Fab")
		)
		(fp_line
			(start -0.299974 -0.150114)
			(end -0.299974 0.150114)
			(stroke
				(width 0.1)
				(type default)
			)
			(layer "B.Fab")
		)
		(fp_line
			(start 0.299974 0.150114)
			(end 0.299974 -0.150114)
			(stroke
				(width 0.1)
				(type default)
			)
			(layer "B.Fab")
		)
		(fp_line
			(start -0.299974 0.150114)
			(end 0.299974 0.150114)
			(stroke
				(width 0.1)
				(type default)
			)
			(layer "B.Fab")
		)
		(pad "1" smd rect
			(at 0.2667 0 270)
			(size 0.3048 0.381)
			(layers "B.Cu" "B.Mask" "B.Paste")
			(net "P0V8_PEX1")
		)
		(pad "2" smd rect
			(at -0.2667 0 270)
			(size 0.3048 0.381)
			(layers "B.Cu" "B.Mask" "B.Paste")
			(net "GND")
		)
	)
	(footprint ""
		(layer "B.Cu")
		(at 217.235786 -223.382586)
		(property "Reference" "R1496"
			(at 0 0 0)
			(layer "B.SilkS")
			(hide yes)
			(effects
				(font
					(size 1.27 1.27)
				)
				(justify mirror)
			)
		)
		(property "Value" ""
			(at 0 0 0)
			(layer "B.Fab")
			(effects
				(font
					(size 1.27 1.27)
				)
				(justify mirror)
			)
		)
		(duplicate_pad_numbers_are_jumpers no)
		(fp_line
			(start -0.7874 -0.4064)
			(end -0.7874 0.4064)
			(stroke
				(width 0.1524)
				(type default)
			)
			(layer "B.SilkS")
		)
		(fp_line
			(start -0.7874 0.4064)
			(end 0.7874 0.4064)
			(stroke
				(width 0.1524)
				(type default)
			)
			(layer "B.SilkS")
		)
		(fp_line
			(start 0.7874 -0.4064)
			(end -0.7874 -0.4064)
			(stroke
				(width 0.1524)
				(type default)
			)
			(layer "B.SilkS")
		)
		(fp_line
			(start 0.7874 0.4064)
			(end 0.7874 -0.4064)
			(stroke
				(width 0.1524)
				(type default)
			)
			(layer "B.SilkS")
		)
		(fp_line
			(start -0.67945 -0.3048)
			(end -0.67945 0.3048)
			(stroke
				(width 0.1)
				(type default)
			)
			(layer "B.Fab")
		)
		(fp_line
			(start -0.67945 0.3048)
			(end -0.120396 0.3048)
			(stroke
				(width 0.1)
				(type default)
			)
			(layer "B.Fab")
		)
		(fp_line
			(start -0.12065 -0.3048)
			(end -0.67945 -0.3048)
			(stroke
				(width 0.1)
				(type default)
			)
			(layer "B.Fab")
		)
		(fp_line
			(start -0.12065 -0.2794)
			(end -0.12065 -0.3048)
			(stroke
				(width 0.1)
				(type default)
			)
			(layer "B.Fab")
		)
		(fp_line
			(start -0.120396 0.2794)
			(end 0.12065 0.2794)
			(stroke
				(width 0.1)
				(type default)
			)
			(layer "B.Fab")
		)
		(fp_line
			(start -0.120396 0.3048)
			(end -0.120396 0.2794)
			(stroke
				(width 0.1)
				(type default)
			)
			(layer "B.Fab")
		)
		(fp_line
			(start 0.12065 -0.305054)
			(end 0.12065 -0.2794)
			(stroke
				(width 0.1)
				(type default)
			)
			(layer "B.Fab")
		)
		(fp_line
			(start 0.12065 -0.2794)
			(end -0.12065 -0.2794)
			(stroke
				(width 0.1)
				(type default)
			)
			(layer "B.Fab")
		)
		(fp_line
			(start 0.12065 0.2794)
			(end 0.12065 0.3048)
			(stroke
				(width 0.1)
				(type default)
			)
			(layer "B.Fab")
		)
		(fp_line
			(start 0.12065 0.3048)
			(end 0.67945 0.3048)
			(stroke
				(width 0.1)
				(type default)
			)
			(layer "B.Fab")
		)
		(fp_line
			(start 0.67945 -0.305054)
			(end 0.12065 -0.305054)
			(stroke
				(width 0.1)
				(type default)
			)
			(layer "B.Fab")
		)
		(fp_line
			(start 0.67945 0.3048)
			(end 0.67945 -0.305054)
			(stroke
				(width 0.1)
				(type default)
			)
			(layer "B.Fab")
		)
		(pad "1" smd circle
			(at 0.40005 0 180)
			(size 0 0)
			(layers "B.Cu" "B.Mask" "B.Paste")
			(net "SMB_BIC_I2C6_SDA")
		)
		(pad "2" smd circle
			(at -0.40005 0 180)
			(size 0 0)
			(layers "B.Cu" "B.Mask" "B.Paste")
			(net "SMB_BIC_I2C6_R_SDA")
		)
	)
	(footprint ""
		(layer "B.Cu")
		(at 387.223 -239.522 180)
		(property "Reference" "R939"
			(at 0 0 0)
			(layer "B.SilkS")
			(hide yes)
			(effects
				(font
					(size 1.27 1.27)
				)
				(justify mirror)
			)
		)
		(property "Value" ""
			(at 0 0 0)
			(layer "B.Fab")
			(effects
				(font
					(size 1.27 1.27)
				)
				(justify mirror)
			)
		)
		(duplicate_pad_numbers_are_jumpers no)
		(fp_line
			(start 0.7874 0.4064)
			(end 0.7874 -0.4064)
			(stroke
				(width 0.1524)
				(type default)
			)
			(layer "B.SilkS")
		)
		(fp_line
			(start 0.7874 -0.4064)
			(end -0.7874 -0.4064)
			(stroke
				(width 0.1524)
				(type default)
			)
			(layer "B.SilkS")
		)
		(fp_line
			(start -0.7874 0.4064)
			(end 0.7874 0.4064)
			(stroke
				(width 0.1524)
				(type default)
			)
			(layer "B.SilkS")
		)
		(fp_line
			(start -0.7874 -0.4064)
			(end -0.7874 0.4064)
			(stroke
				(width 0.1524)
				(type default)
			)
			(layer "B.SilkS")
		)
		(fp_line
			(start 0.67945 0.3048)
			(end 0.67945 -0.305054)
			(stroke
				(width 0.1)
				(type default)
			)
			(layer "B.Fab")
		)
		(fp_line
			(start 0.67945 -0.305054)
			(end 0.12065 -0.305054)
			(stroke
				(width 0.1)
				(type default)
			)
			(layer "B.Fab")
		)
		(fp_line
			(start 0.12065 0.3048)
			(end 0.67945 0.3048)
			(stroke
				(width 0.1)
				(type default)
			)
			(layer "B.Fab")
		)
		(fp_line
			(start 0.12065 0.2794)
			(end 0.12065 0.3048)
			(stroke
				(width 0.1)
				(type default)
			)
			(layer "B.Fab")
		)
		(fp_line
			(start 0.12065 -0.2794)
			(end -0.12065 -0.2794)
			(stroke
				(width 0.1)
				(type default)
			)
			(layer "B.Fab")
		)
		(fp_line
			(start 0.12065 -0.305054)
			(end 0.12065 -0.2794)
			(stroke
				(width 0.1)
				(type default)
			)
			(layer "B.Fab")
		)
		(fp_line
			(start -0.120396 0.3048)
			(end -0.120396 0.2794)
			(stroke
				(width 0.1)
				(type default)
			)
			(layer "B.Fab")
		)
		(fp_line
			(start -0.120396 0.2794)
			(end 0.12065 0.2794)
			(stroke
				(width 0.1)
				(type default)
			)
			(layer "B.Fab")
		)
		(fp_line
			(start -0.12065 -0.2794)
			(end -0.12065 -0.3048)
			(stroke
				(width 0.1)
				(type default)
			)
			(layer "B.Fab")
		)
		(fp_line
			(start -0.12065 -0.3048)
			(end -0.67945 -0.3048)
			(stroke
				(width 0.1)
				(type default)
			)
			(layer "B.Fab")
		)
		(fp_line
			(start -0.67945 0.3048)
			(end -0.120396 0.3048)
			(stroke
				(width 0.1)
				(type default)
			)
			(layer "B.Fab")
		)
		(fp_line
			(start -0.67945 -0.3048)
			(end -0.67945 0.3048)
			(stroke
				(width 0.1)
				(type default)
			)
			(layer "B.Fab")
		)
		(pad "1" smd circle
			(at 0.40005 0)
			(size 0 0)
			(layers "B.Cu" "B.Mask" "B.Paste")
			(net "UART_PEX2_SDB_RX")
		)
		(pad "2" smd circle
			(at -0.40005 0)
			(size 0 0)
			(layers "B.Cu" "B.Mask" "B.Paste")
			(net "UART_PEX2_SDB_R_RX")
		)
	)
	(footprint ""
		(layer "B.Cu")
		(at 78.345792 -450.581014 180)
		(property "Reference" "X65"
			(at 0.1778 -1.92913 180)
			(unlocked yes)
			(layer "B.SilkS")
			(effects
				(font
					(size 0.7874 0.5842)
					(thickness 0.1524)
				)
				(justify left mirror)
			)
		)
		(property "Value" ""
			(at 0 0 0)
			(layer "B.Fab")
			(effects
				(font
					(size 1.27 1.27)
				)
				(justify mirror)
			)
		)
		(property "Device Type" "TP_TDR_4P_FTS_MPKT4_H025P0200_IO_TP15_TP_TDR_4P_DIP"
			(at -1.30175 1.27 90)
			(unlocked yes)
			(layer "B.Fab")
			(hide yes)
			(effects
				(font
					(size 0.635 0.4064)
					(thickness 0.1524)
				)
				(justify mirror)
			)
		)
		(property "User Part Number" "TP15"
			(at -1.30175 1.27 90)
			(unlocked yes)
			(layer "Cmts.User")
			(hide yes)
			(effects
				(font
					(size 0.635 0.4064)
					(thickness 0.1524)
				)
				(justify mirror)
			)
		)
		(duplicate_pad_numbers_are_jumpers no)
		(fp_line
			(start 0 3.81)
			(end -2.54 3.81)
			(stroke
				(width 0.1524)
				(type default)
			)
			(layer "B.SilkS")
		)
		(fp_line
			(start 0 3.175)
			(end 0 3.81)
			(stroke
				(width 0.1524)
				(type default)
			)
			(layer "B.SilkS")
		)
		(fp_line
			(start 0 0.635)
			(end 0 1.905)
			(stroke
				(width 0.1524)
				(type default)
			)
			(layer "B.SilkS")
		)
		(fp_line
			(start 0 -1.27)
			(end 0 -0.635)
			(stroke
				(width 0.1524)
				(type default)
			)
			(layer "B.SilkS")
		)
		(fp_line
			(start -2.54 3.81)
			(end -2.54 3.6703)
			(stroke
				(width 0.1524)
				(type default)
			)
			(layer "B.SilkS")
		)
		(fp_line
			(start -2.54 1.4097)
			(end -2.54 1.1303)
			(stroke
				(width 0.1524)
				(type default)
			)
			(layer "B.SilkS")
		)
		(fp_line
			(start -2.54 -1.1303)
			(end -2.54 -1.27)
			(stroke
				(width 0.1524)
				(type default)
			)
			(layer "B.SilkS")
		)
		(fp_line
			(start -2.54 -1.27)
			(end 0 -1.27)
			(stroke
				(width 0.1524)
				(type default)
			)
			(layer "B.SilkS")
		)
		(fp_poly
			(pts
				(xy 0.761746 0) (xy 2.285746 -0.762) (xy 2.285746 0.762)
			)
			(stroke
				(width 0)
				(type default)
			)
			(fill yes)
			(layer "B.SilkS")
		)
		(fp_line
			(start 0 3.81)
			(end -2.54 3.81)
			(stroke
				(width 0.1)
				(type default)
			)
			(layer "B.Fab")
		)
		(fp_line
			(start 0 -1.27)
			(end 0 3.81)
			(stroke
				(width 0.1)
				(type default)
			)
			(layer "B.Fab")
		)
		(fp_line
			(start -2.54 3.81)
			(end -2.54 -1.27)
			(stroke
				(width 0.1)
				(type default)
			)
			(layer "B.Fab")
		)
		(fp_line
			(start -2.54 -1.27)
			(end 0 -1.27)
			(stroke
				(width 0.1)
				(type default)
			)
			(layer "B.Fab")
		)
		(fp_poly
			(pts
				(xy 0.761746 0) (xy 2.285746 -0.762) (xy 2.285746 0.762)
			)
			(stroke
				(width 0)
				(type default)
			)
			(fill yes)
			(layer "B.Fab")
		)
		(pad "1" thru_hole circle
			(at 0 0)
			(size 1.0033 1.0033)
			(drill 0.249936)
			(layers "*.Cu" "*.Mask")
			(remove_unused_layers no)
			(net "TDR_DIFF_85_IN6_DIN")
			(clearance 0.10795)
			(padstack
				(mode front_inner_back)
				(layer "Inner"
					(shape circle)
					(size 0.8001 0.8001)
					(clearance 0.1524)
				)
				(layer "B.Cu"
					(shape circle)
					(size 1.0033 1.0033)
					(thermal_gap 0.10795)
					(clearance 0.10795)
				)
			)
		)
		(pad "2" thru_hole circle
			(at -2.54 0)
			(size 1.9939 1.9939)
			(drill 0.249936)
			(layers "*.Cu" "*.Mask")
			(remove_unused_layers no)
			(net "COUPON_GND1")
			(clearance 0.10795)
			(padstack
				(mode front_inner_back)
				(layer "Inner"
					(shape circle)
					(size 0.8001 0.8001)
					(clearance 0.1524)
				)
				(layer "B.Cu"
					(shape circle)
					(size 1.9939 1.9939)
					(thermal_gap 0.10795)
					(clearance 0.10795)
				)
			)
		)
		(pad "3" thru_hole circle
			(at -2.54 2.54)
			(size 1.9939 1.9939)
			(drill 0.249936)
			(layers "*.Cu" "*.Mask")
			(remove_unused_layers no)
			(net "COUPON_GND1")
			(clearance 0.10795)
			(padstack
				(mode front_inner_back)
				(layer "Inner"
					(shape circle)
					(size 0.8001 0.8001)
					(clearance 0.1524)
				)
				(layer "B.Cu"
					(shape circle)
					(size 1.9939 1.9939)
					(thermal_gap 0.10795)
					(clearance 0.10795)
				)
			)
		)
		(pad "4" thru_hole circle
			(at 0 2.54)
			(size 1.0033 1.0033)
			(drill 0.249936)
			(layers "*.Cu" "*.Mask")
			(remove_unused_layers no)
			(net "TDR_DIFF_85_IN6_DIP")
			(clearance 0.10795)
			(padstack
				(mode front_inner_back)
				(layer "Inner"
					(shape circle)
					(size 0.8001 0.8001)
					(clearance 0.1524)
				)
				(layer "B.Cu"
					(shape circle)
					(size 1.0033 1.0033)
					(thermal_gap 0.10795)
					(clearance 0.10795)
				)
			)
		)
	)
	(footprint ""
		(layer "B.Cu")
		(at 301.349918 -301.124874)
		(property "Reference" "C3339"
			(at 0 0 0)
			(layer "B.SilkS")
			(hide yes)
			(effects
				(font
					(size 1.27 1.27)
				)
				(justify mirror)
			)
		)
		(property "Value" ""
			(at 0 0 0)
			(layer "B.Fab")
			(effects
				(font
					(size 1.27 1.27)
				)
				(justify mirror)
			)
		)
		(duplicate_pad_numbers_are_jumpers no)
		(fp_line
			(start -0.299974 -0.150114)
			(end -0.299974 0.150114)
			(stroke
				(width 0.1)
				(type default)
			)
			(layer "B.Fab")
		)
		(fp_line
			(start -0.299974 0.150114)
			(end 0.299974 0.150114)
			(stroke
				(width 0.1)
				(type default)
			)
			(layer "B.Fab")
		)
		(fp_line
			(start 0.299974 -0.150114)
			(end -0.299974 -0.150114)
			(stroke
				(width 0.1)
				(type default)
			)
			(layer "B.Fab")
		)
		(fp_line
			(start 0.299974 0.150114)
			(end 0.299974 -0.150114)
			(stroke
				(width 0.1)
				(type default)
			)
			(layer "B.Fab")
		)
		(pad "1" smd rect
			(at 0.2667 0 180)
			(size 0.3048 0.381)
			(layers "B.Cu" "B.Mask" "B.Paste")
			(net "P1V8_PEX")
		)
		(pad "2" smd rect
			(at -0.2667 0 180)
			(size 0.3048 0.381)
			(layers "B.Cu" "B.Mask" "B.Paste")
			(net "GND")
		)
	)
	(footprint ""
		(layer "B.Cu")
		(at 385.445 -239.522 180)
		(property "Reference" "R940"
			(at 0 0 0)
			(layer "B.SilkS")
			(hide yes)
			(effects
				(font
					(size 1.27 1.27)
				)
				(justify mirror)
			)
		)
		(property "Value" ""
			(at 0 0 0)
			(layer "B.Fab")
			(effects
				(font
					(size 1.27 1.27)
				)
				(justify mirror)
			)
		)
		(duplicate_pad_numbers_are_jumpers no)
		(fp_line
			(start 0.7874 0.4064)
			(end 0.7874 -0.4064)
			(stroke
				(width 0.1524)
				(type default)
			)
			(layer "B.SilkS")
		)
		(fp_line
			(start 0.7874 -0.4064)
			(end -0.7874 -0.4064)
			(stroke
				(width 0.1524)
				(type default)
			)
			(layer "B.SilkS")
		)
		(fp_line
			(start -0.7874 0.4064)
			(end 0.7874 0.4064)
			(stroke
				(width 0.1524)
				(type default)
			)
			(layer "B.SilkS")
		)
		(fp_line
			(start -0.7874 -0.4064)
			(end -0.7874 0.4064)
			(stroke
				(width 0.1524)
				(type default)
			)
			(layer "B.SilkS")
		)
		(fp_line
			(start 0.67945 0.3048)
			(end 0.67945 -0.305054)
			(stroke
				(width 0.1)
				(type default)
			)
			(layer "B.Fab")
		)
		(fp_line
			(start 0.67945 -0.305054)
			(end 0.12065 -0.305054)
			(stroke
				(width 0.1)
				(type default)
			)
			(layer "B.Fab")
		)
		(fp_line
			(start 0.12065 0.3048)
			(end 0.67945 0.3048)
			(stroke
				(width 0.1)
				(type default)
			)
			(layer "B.Fab")
		)
		(fp_line
			(start 0.12065 0.2794)
			(end 0.12065 0.3048)
			(stroke
				(width 0.1)
				(type default)
			)
			(layer "B.Fab")
		)
		(fp_line
			(start 0.12065 -0.2794)
			(end -0.12065 -0.2794)
			(stroke
				(width 0.1)
				(type default)
			)
			(layer "B.Fab")
		)
		(fp_line
			(start 0.12065 -0.305054)
			(end 0.12065 -0.2794)
			(stroke
				(width 0.1)
				(type default)
			)
			(layer "B.Fab")
		)
		(fp_line
			(start -0.120396 0.3048)
			(end -0.120396 0.2794)
			(stroke
				(width 0.1)
				(type default)
			)
			(layer "B.Fab")
		)
		(fp_line
			(start -0.120396 0.2794)
			(end 0.12065 0.2794)
			(stroke
				(width 0.1)
				(type default)
			)
			(layer "B.Fab")
		)
		(fp_line
			(start -0.12065 -0.2794)
			(end -0.12065 -0.3048)
			(stroke
				(width 0.1)
				(type default)
			)
			(layer "B.Fab")
		)
		(fp_line
			(start -0.12065 -0.3048)
			(end -0.67945 -0.3048)
			(stroke
				(width 0.1)
				(type default)
			)
			(layer "B.Fab")
		)
		(fp_line
			(start -0.67945 0.3048)
			(end -0.120396 0.3048)
			(stroke
				(width 0.1)
				(type default)
			)
			(layer "B.Fab")
		)
		(fp_line
			(start -0.67945 -0.3048)
			(end -0.67945 0.3048)
			(stroke
				(width 0.1)
				(type default)
			)
			(layer "B.Fab")
		)
		(pad "1" smd circle
			(at 0.40005 0)
			(size 0 0)
			(layers "B.Cu" "B.Mask" "B.Paste")
			(net "UART_PEX3_SDB_RX")
		)
		(pad "2" smd circle
			(at -0.40005 0)
			(size 0 0)
			(layers "B.Cu" "B.Mask" "B.Paste")
			(net "UART_PEX3_SDB_R_RX")
		)
	)
	(footprint ""
		(layer "B.Cu")
		(at 290.89985 -292.099746 90)
		(property "Reference" "C1671"
			(at 0 0 90)
			(layer "B.SilkS")
			(hide yes)
			(effects
				(font
					(size 1.27 1.27)
				)
				(justify mirror)
			)
		)
		(property "Value" ""
			(at 0 0 90)
			(layer "B.Fab")
			(effects
				(font
					(size 1.27 1.27)
				)
				(justify mirror)
			)
		)
		(duplicate_pad_numbers_are_jumpers no)
		(fp_line
			(start 0.299974 -0.150114)
			(end -0.299974 -0.150114)
			(stroke
				(width 0.1)
				(type default)
			)
			(layer "B.Fab")
		)
		(fp_line
			(start -0.299974 -0.150114)
			(end -0.299974 0.150114)
			(stroke
				(width 0.1)
				(type default)
			)
			(layer "B.Fab")
		)
		(fp_line
			(start 0.299974 0.150114)
			(end 0.299974 -0.150114)
			(stroke
				(width 0.1)
				(type default)
			)
			(layer "B.Fab")
		)
		(fp_line
			(start -0.299974 0.150114)
			(end 0.299974 0.150114)
			(stroke
				(width 0.1)
				(type default)
			)
			(layer "B.Fab")
		)
		(pad "1" smd rect
			(at 0.2667 0 270)
			(size 0.3048 0.381)
			(layers "B.Cu" "B.Mask" "B.Paste")
			(net "P0V8_SERDES_VDDA_PEX2")
		)
		(pad "2" smd rect
			(at -0.2667 0 270)
			(size 0.3048 0.381)
			(layers "B.Cu" "B.Mask" "B.Paste")
			(net "GND")
		)
	)
	(footprint ""
		(layer "B.Cu")
		(at 324.612 -84.963 180)
		(property "Reference" "R6263"
			(at 0 0 0)
			(layer "B.SilkS")
			(hide yes)
			(effects
				(font
					(size 1.27 1.27)
				)
				(justify mirror)
			)
		)
		(property "Value" ""
			(at 0 0 0)
			(layer "B.Fab")
			(effects
				(font
					(size 1.27 1.27)
				)
				(justify mirror)
			)
		)
		(duplicate_pad_numbers_are_jumpers no)
		(fp_line
			(start 0.7874 0.4064)
			(end 0.7874 -0.4064)
			(stroke
				(width 0.1524)
				(type default)
			)
			(layer "B.SilkS")
		)
		(fp_line
			(start 0.7874 -0.4064)
			(end -0.7874 -0.4064)
			(stroke
				(width 0.1524)
				(type default)
			)
			(layer "B.SilkS")
		)
		(fp_line
			(start -0.7874 0.4064)
			(end 0.7874 0.4064)
			(stroke
				(width 0.1524)
				(type default)
			)
			(layer "B.SilkS")
		)
		(fp_line
			(start -0.7874 -0.4064)
			(end -0.7874 0.4064)
			(stroke
				(width 0.1524)
				(type default)
			)
			(layer "B.SilkS")
		)
		(fp_line
			(start 0.67945 0.3048)
			(end 0.67945 -0.305054)
			(stroke
				(width 0.1)
				(type default)
			)
			(layer "B.Fab")
		)
		(fp_line
			(start 0.67945 -0.305054)
			(end 0.12065 -0.305054)
			(stroke
				(width 0.1)
				(type default)
			)
			(layer "B.Fab")
		)
		(fp_line
			(start 0.12065 0.3048)
			(end 0.67945 0.3048)
			(stroke
				(width 0.1)
				(type default)
			)
			(layer "B.Fab")
		)
		(fp_line
			(start 0.12065 0.2794)
			(end 0.12065 0.3048)
			(stroke
				(width 0.1)
				(type default)
			)
			(layer "B.Fab")
		)
		(fp_line
			(start 0.12065 -0.2794)
			(end -0.12065 -0.2794)
			(stroke
				(width 0.1)
				(type default)
			)
			(layer "B.Fab")
		)
		(fp_line
			(start 0.12065 -0.305054)
			(end 0.12065 -0.2794)
			(stroke
				(width 0.1)
				(type default)
			)
			(layer "B.Fab")
		)
		(fp_line
			(start -0.120396 0.3048)
			(end -0.120396 0.2794)
			(stroke
				(width 0.1)
				(type default)
			)
			(layer "B.Fab")
		)
		(fp_line
			(start -0.120396 0.2794)
			(end 0.12065 0.2794)
			(stroke
				(width 0.1)
				(type default)
			)
			(layer "B.Fab")
		)
		(fp_line
			(start -0.12065 -0.2794)
			(end -0.12065 -0.3048)
			(stroke
				(width 0.1)
				(type default)
			)
			(layer "B.Fab")
		)
		(fp_line
			(start -0.12065 -0.3048)
			(end -0.67945 -0.3048)
			(stroke
				(width 0.1)
				(type default)
			)
			(layer "B.Fab")
		)
		(fp_line
			(start -0.67945 0.3048)
			(end -0.120396 0.3048)
			(stroke
				(width 0.1)
				(type default)
			)
			(layer "B.Fab")
		)
		(fp_line
			(start -0.67945 -0.3048)
			(end -0.67945 0.3048)
			(stroke
				(width 0.1)
				(type default)
			)
			(layer "B.Fab")
		)
		(pad "1" smd circle
			(at 0.40005 0)
			(size 0 0)
			(layers "B.Cu" "B.Mask" "B.Paste")
			(net "SMB_BIC_I2C6_MUX_FRU_R_SDA")
		)
		(pad "2" smd circle
			(at -0.40005 0)
			(size 0 0)
			(layers "B.Cu" "B.Mask" "B.Paste")
			(net "SMB_ISO_CB_SDA")
		)
	)
	(footprint ""
		(layer "B.Cu")
		(at 401.345654 -296.37482)
		(property "Reference" "C1895"
			(at 0 0 0)
			(layer "B.SilkS")
			(hide yes)
			(effects
				(font
					(size 1.27 1.27)
				)
				(justify mirror)
			)
		)
		(property "Value" ""
			(at 0 0 0)
			(layer "B.Fab")
			(effects
				(font
					(size 1.27 1.27)
				)
				(justify mirror)
			)
		)
		(duplicate_pad_numbers_are_jumpers no)
		(fp_line
			(start -0.299974 -0.150114)
			(end -0.299974 0.150114)
			(stroke
				(width 0.1)
				(type default)
			)
			(layer "B.Fab")
		)
		(fp_line
			(start -0.299974 0.150114)
			(end 0.299974 0.150114)
			(stroke
				(width 0.1)
				(type default)
			)
			(layer "B.Fab")
		)
		(fp_line
			(start 0.299974 -0.150114)
			(end -0.299974 -0.150114)
			(stroke
				(width 0.1)
				(type default)
			)
			(layer "B.Fab")
		)
		(fp_line
			(start 0.299974 0.150114)
			(end 0.299974 -0.150114)
			(stroke
				(width 0.1)
				(type default)
			)
			(layer "B.Fab")
		)
		(pad "1" smd rect
			(at 0.2667 0 180)
			(size 0.3048 0.381)
			(layers "B.Cu" "B.Mask" "B.Paste")
			(net "P0V8_PEX3")
		)
		(pad "2" smd rect
			(at -0.2667 0 180)
			(size 0.3048 0.381)
			(layers "B.Cu" "B.Mask" "B.Paste")
			(net "GND")
		)
	)
	(footprint ""
		(layer "B.Cu")
		(at 217.235786 -224.398586)
		(property "Reference" "R1494"
			(at 0 0 0)
			(layer "B.SilkS")
			(hide yes)
			(effects
				(font
					(size 1.27 1.27)
				)
				(justify mirror)
			)
		)
		(property "Value" ""
			(at 0 0 0)
			(layer "B.Fab")
			(effects
				(font
					(size 1.27 1.27)
				)
				(justify mirror)
			)
		)
		(duplicate_pad_numbers_are_jumpers no)
		(fp_line
			(start -0.7874 -0.4064)
			(end -0.7874 0.4064)
			(stroke
				(width 0.1524)
				(type default)
			)
			(layer "B.SilkS")
		)
		(fp_line
			(start -0.7874 0.4064)
			(end 0.7874 0.4064)
			(stroke
				(width 0.1524)
				(type default)
			)
			(layer "B.SilkS")
		)
		(fp_line
			(start 0.7874 -0.4064)
			(end -0.7874 -0.4064)
			(stroke
				(width 0.1524)
				(type default)
			)
			(layer "B.SilkS")
		)
		(fp_line
			(start 0.7874 0.4064)
			(end 0.7874 -0.4064)
			(stroke
				(width 0.1524)
				(type default)
			)
			(layer "B.SilkS")
		)
		(fp_line
			(start -0.67945 -0.3048)
			(end -0.67945 0.3048)
			(stroke
				(width 0.1)
				(type default)
			)
			(layer "B.Fab")
		)
		(fp_line
			(start -0.67945 0.3048)
			(end -0.120396 0.3048)
			(stroke
				(width 0.1)
				(type default)
			)
			(layer "B.Fab")
		)
		(fp_line
			(start -0.12065 -0.3048)
			(end -0.67945 -0.3048)
			(stroke
				(width 0.1)
				(type default)
			)
			(layer "B.Fab")
		)
		(fp_line
			(start -0.12065 -0.2794)
			(end -0.12065 -0.3048)
			(stroke
				(width 0.1)
				(type default)
			)
			(layer "B.Fab")
		)
		(fp_line
			(start -0.120396 0.2794)
			(end 0.12065 0.2794)
			(stroke
				(width 0.1)
				(type default)
			)
			(layer "B.Fab")
		)
		(fp_line
			(start -0.120396 0.3048)
			(end -0.120396 0.2794)
			(stroke
				(width 0.1)
				(type default)
			)
			(layer "B.Fab")
		)
		(fp_line
			(start 0.12065 -0.305054)
			(end 0.12065 -0.2794)
			(stroke
				(width 0.1)
				(type default)
			)
			(layer "B.Fab")
		)
		(fp_line
			(start 0.12065 -0.2794)
			(end -0.12065 -0.2794)
			(stroke
				(width 0.1)
				(type default)
			)
			(layer "B.Fab")
		)
		(fp_line
			(start 0.12065 0.2794)
			(end 0.12065 0.3048)
			(stroke
				(width 0.1)
				(type default)
			)
			(layer "B.Fab")
		)
		(fp_line
			(start 0.12065 0.3048)
			(end 0.67945 0.3048)
			(stroke
				(width 0.1)
				(type default)
			)
			(layer "B.Fab")
		)
		(fp_line
			(start 0.67945 -0.305054)
			(end 0.12065 -0.305054)
			(stroke
				(width 0.1)
				(type default)
			)
			(layer "B.Fab")
		)
		(fp_line
			(start 0.67945 0.3048)
			(end 0.67945 -0.305054)
			(stroke
				(width 0.1)
				(type default)
			)
			(layer "B.Fab")
		)
		(pad "1" smd circle
			(at 0.40005 0 180)
			(size 0 0)
			(layers "B.Cu" "B.Mask" "B.Paste")
			(net "SMB_BIC_I2C6_SCL")
		)
		(pad "2" smd circle
			(at -0.40005 0 180)
			(size 0 0)
			(layers "B.Cu" "B.Mask" "B.Paste")
			(net "SMB_BIC_I2C6_R_SCL")
		)
	)
	(footprint ""
		(layer "B.Cu")
		(at 231.86771 -218.30411)
		(property "Reference" "C2019"
			(at 0 0 0)
			(layer "B.SilkS")
			(hide yes)
			(effects
				(font
					(size 1.27 1.27)
				)
				(justify mirror)
			)
		)
		(property "Value" ""
			(at 0 0 0)
			(layer "B.Fab")
			(effects
				(font
					(size 1.27 1.27)
				)
				(justify mirror)
			)
		)
		(duplicate_pad_numbers_are_jumpers no)
		(fp_line
			(start -0.69215 -0.2921)
			(end -0.69215 0.2921)
			(stroke
				(width 0.1524)
				(type default)
			)
			(layer "B.SilkS")
		)
		(fp_line
			(start -0.69215 0.2921)
			(end 0.69215 0.2921)
			(stroke
				(width 0.1524)
				(type default)
			)
			(layer "B.SilkS")
		)
		(fp_line
			(start 0.69215 -0.2921)
			(end -0.69215 -0.2921)
			(stroke
				(width 0.1524)
				(type default)
			)
			(layer "B.SilkS")
		)
		(fp_line
			(start 0.69215 0.2921)
			(end 0.69215 -0.2921)
			(stroke
				(width 0.1524)
				(type default)
			)
			(layer "B.SilkS")
		)
		(fp_line
			(start -0.51435 -0.2794)
			(end -0.51435 0.2794)
			(stroke
				(width 0.1)
				(type default)
			)
			(layer "B.Fab")
		)
		(fp_line
			(start -0.51435 0.2794)
			(end 0.51435 0.2794)
			(stroke
				(width 0.1)
				(type default)
			)
			(layer "B.Fab")
		)
		(fp_line
			(start 0.51435 -0.2794)
			(end -0.51435 -0.2794)
			(stroke
				(width 0.1)
				(type default)
			)
			(layer "B.Fab")
		)
		(fp_line
			(start 0.51435 0.2794)
			(end 0.51435 -0.2794)
			(stroke
				(width 0.1)
				(type default)
			)
			(layer "B.Fab")
		)
		(pad "1" smd circle
			(at 0.40005 0 180)
			(size 0 0)
			(layers "B.Cu" "B.Mask" "B.Paste")
			(net "P1V2_AUX")
		)
		(pad "2" smd circle
			(at -0.40005 0 180)
			(size 0 0)
			(layers "B.Cu" "B.Mask" "B.Paste")
			(net "GND")
		)
		(zone
			(layer "B.Cu")
			(hatch none 0.5)
			(connect_pads
				(clearance 0)
			)
			(min_thickness 0.25)
			(keepout
				(tracks not_allowed)
				(vias allowed)
				(pads allowed)
				(copperpour not_allowed)
				(footprints allowed)
			)
			(placement
				(enabled no)
				(sheetname "")
			)
			(fill
				(thermal_gap 0.5)
				(thermal_bridge_width 0.5)
				(island_removal_mode 0)
			)
			(polygon
				(pts
					(xy 232.05821 -218.21648) (xy 231.96677 -218.158314) (xy 231.76738 -218.158314) (xy 231.67721 -218.21648)
					(xy 231.67721 -218.39174) (xy 231.76738 -218.45016) (xy 231.96677 -218.45016) (xy 232.05821 -218.391994)
				)
			)
		)
	)
	(footprint ""
		(layer "B.Cu")
		(at 55.849774 -301.599854 -90)
		(property "Reference" "C1202"
			(at 0 0 90)
			(layer "B.SilkS")
			(hide yes)
			(effects
				(font
					(size 1.27 1.27)
				)
				(justify mirror)
			)
		)
		(property "Value" ""
			(at 0 0 90)
			(layer "B.Fab")
			(effects
				(font
					(size 1.27 1.27)
				)
				(justify mirror)
			)
		)
		(duplicate_pad_numbers_are_jumpers no)
		(fp_line
			(start -0.299974 0.150114)
			(end 0.299974 0.150114)
			(stroke
				(width 0.1)
				(type default)
			)
			(layer "B.Fab")
		)
		(fp_line
			(start 0.299974 0.150114)
			(end 0.299974 -0.150114)
			(stroke
				(width 0.1)
				(type default)
			)
			(layer "B.Fab")
		)
		(fp_line
			(start -0.299974 -0.150114)
			(end -0.299974 0.150114)
			(stroke
				(width 0.1)
				(type default)
			)
			(layer "B.Fab")
		)
		(fp_line
			(start 0.299974 -0.150114)
			(end -0.299974 -0.150114)
			(stroke
				(width 0.1)
				(type default)
			)
			(layer "B.Fab")
		)
		(pad "1" smd rect
			(at 0.2667 0 90)
			(size 0.3048 0.381)
			(layers "B.Cu" "B.Mask" "B.Paste")
			(net "P0V8_SERDES_VDDA_PEX0")
		)
		(pad "2" smd rect
			(at -0.2667 0 90)
			(size 0.3048 0.381)
			(layers "B.Cu" "B.Mask" "B.Paste")
			(net "GND")
		)
	)
	(footprint ""
		(layer "B.Cu")
		(at 250.032266 -222.658432)
		(property "Reference" "C2405"
			(at 0 0 0)
			(layer "B.SilkS")
			(hide yes)
			(effects
				(font
					(size 1.27 1.27)
				)
				(justify mirror)
			)
		)
		(property "Value" ""
			(at 0 0 0)
			(layer "B.Fab")
			(effects
				(font
					(size 1.27 1.27)
				)
				(justify mirror)
			)
		)
		(duplicate_pad_numbers_are_jumpers no)
		(fp_line
			(start -0.7874 -0.4064)
			(end -0.7874 0.4064)
			(stroke
				(width 0.1524)
				(type default)
			)
			(layer "B.SilkS")
		)
		(fp_line
			(start -0.7874 0.4064)
			(end 0.7874 0.4064)
			(stroke
				(width 0.1524)
				(type default)
			)
			(layer "B.SilkS")
		)
		(fp_line
			(start 0.7874 -0.4064)
			(end -0.7874 -0.4064)
			(stroke
				(width 0.1524)
				(type default)
			)
			(layer "B.SilkS")
		)
		(fp_line
			(start 0.7874 0.4064)
			(end 0.7874 -0.4064)
			(stroke
				(width 0.1524)
				(type default)
			)
			(layer "B.SilkS")
		)
		(fp_line
			(start -0.67945 -0.3048)
			(end -0.67945 0.3048)
			(stroke
				(width 0.1)
				(type default)
			)
			(layer "B.Fab")
		)
		(fp_line
			(start -0.67945 0.3048)
			(end -0.120396 0.3048)
			(stroke
				(width 0.1)
				(type default)
			)
			(layer "B.Fab")
		)
		(fp_line
			(start -0.12065 -0.3048)
			(end -0.67945 -0.3048)
			(stroke
				(width 0.1)
				(type default)
			)
			(layer "B.Fab")
		)
		(fp_line
			(start -0.12065 -0.2794)
			(end -0.12065 -0.3048)
			(stroke
				(width 0.1)
				(type default)
			)
			(layer "B.Fab")
		)
		(fp_line
			(start -0.120396 0.2794)
			(end 0.12065 0.2794)
			(stroke
				(width 0.1)
				(type default)
			)
			(layer "B.Fab")
		)
		(fp_line
			(start -0.120396 0.3048)
			(end -0.120396 0.2794)
			(stroke
				(width 0.1)
				(type default)
			)
			(layer "B.Fab")
		)
		(fp_line
			(start 0.12065 -0.305054)
			(end 0.12065 -0.2794)
			(stroke
				(width 0.1)
				(type default)
			)
			(layer "B.Fab")
		)
		(fp_line
			(start 0.12065 -0.2794)
			(end -0.12065 -0.2794)
			(stroke
				(width 0.1)
				(type default)
			)
			(layer "B.Fab")
		)
		(fp_line
			(start 0.12065 0.2794)
			(end 0.12065 0.3048)
			(stroke
				(width 0.1)
				(type default)
			)
			(layer "B.Fab")
		)
		(fp_line
			(start 0.12065 0.3048)
			(end 0.67945 0.3048)
			(stroke
				(width 0.1)
				(type default)
			)
			(layer "B.Fab")
		)
		(fp_line
			(start 0.67945 -0.305054)
			(end 0.12065 -0.305054)
			(stroke
				(width 0.1)
				(type default)
			)
			(layer "B.Fab")
		)
		(fp_line
			(start 0.67945 0.3048)
			(end 0.67945 -0.305054)
			(stroke
				(width 0.1)
				(type default)
			)
			(layer "B.Fab")
		)
		(pad "1" smd circle
			(at 0.40005 0 180)
			(size 0 0)
			(layers "B.Cu" "B.Mask" "B.Paste")
			(net "GND")
		)
		(pad "2" smd circle
			(at -0.40005 0 180)
			(size 0 0)
			(layers "B.Cu" "B.Mask" "B.Paste")
			(net "P3V3_AUX")
		)
	)
	(footprint ""
		(layer "B.Cu")
		(at 372.974108 -222.299276 180)
		(property "Reference" "C2784"
			(at 0 0 0)
			(layer "B.SilkS")
			(hide yes)
			(effects
				(font
					(size 1.27 1.27)
				)
				(justify mirror)
			)
		)
		(property "Value" ""
			(at 0 0 0)
			(layer "B.Fab")
			(effects
				(font
					(size 1.27 1.27)
				)
				(justify mirror)
			)
		)
		(duplicate_pad_numbers_are_jumpers no)
		(fp_line
			(start 0.7874 0.4064)
			(end 0.7874 -0.4064)
			(stroke
				(width 0.1524)
				(type default)
			)
			(layer "B.SilkS")
		)
		(fp_line
			(start 0.7874 -0.4064)
			(end -0.7874 -0.4064)
			(stroke
				(width 0.1524)
				(type default)
			)
			(layer "B.SilkS")
		)
		(fp_line
			(start -0.7874 0.4064)
			(end 0.7874 0.4064)
			(stroke
				(width 0.1524)
				(type default)
			)
			(layer "B.SilkS")
		)
		(fp_line
			(start -0.7874 -0.4064)
			(end -0.7874 0.4064)
			(stroke
				(width 0.1524)
				(type default)
			)
			(layer "B.SilkS")
		)
		(fp_line
			(start 0.67945 0.3048)
			(end 0.67945 -0.305054)
			(stroke
				(width 0.1)
				(type default)
			)
			(layer "B.Fab")
		)
		(fp_line
			(start 0.67945 -0.305054)
			(end 0.12065 -0.305054)
			(stroke
				(width 0.1)
				(type default)
			)
			(layer "B.Fab")
		)
		(fp_line
			(start 0.12065 0.3048)
			(end 0.67945 0.3048)
			(stroke
				(width 0.1)
				(type default)
			)
			(layer "B.Fab")
		)
		(fp_line
			(start 0.12065 0.2794)
			(end 0.12065 0.3048)
			(stroke
				(width 0.1)
				(type default)
			)
			(layer "B.Fab")
		)
		(fp_line
			(start 0.12065 -0.2794)
			(end -0.12065 -0.2794)
			(stroke
				(width 0.1)
				(type default)
			)
			(layer "B.Fab")
		)
		(fp_line
			(start 0.12065 -0.305054)
			(end 0.12065 -0.2794)
			(stroke
				(width 0.1)
				(type default)
			)
			(layer "B.Fab")
		)
		(fp_line
			(start -0.120396 0.3048)
			(end -0.120396 0.2794)
			(stroke
				(width 0.1)
				(type default)
			)
			(layer "B.Fab")
		)
		(fp_line
			(start -0.120396 0.2794)
			(end 0.12065 0.2794)
			(stroke
				(width 0.1)
				(type default)
			)
			(layer "B.Fab")
		)
		(fp_line
			(start -0.12065 -0.2794)
			(end -0.12065 -0.3048)
			(stroke
				(width 0.1)
				(type default)
			)
			(layer "B.Fab")
		)
		(fp_line
			(start -0.12065 -0.3048)
			(end -0.67945 -0.3048)
			(stroke
				(width 0.1)
				(type default)
			)
			(layer "B.Fab")
		)
		(fp_line
			(start -0.67945 0.3048)
			(end -0.120396 0.3048)
			(stroke
				(width 0.1)
				(type default)
			)
			(layer "B.Fab")
		)
		(fp_line
			(start -0.67945 -0.3048)
			(end -0.67945 0.3048)
			(stroke
				(width 0.1)
				(type default)
			)
			(layer "B.Fab")
		)
		(pad "1" smd circle
			(at 0.40005 0)
			(size 0 0)
			(layers "B.Cu" "B.Mask" "B.Paste")
			(net "GND")
		)
		(pad "2" smd circle
			(at -0.40005 0)
			(size 0 0)
			(layers "B.Cu" "B.Mask" "B.Paste")
			(net "P1V8_PEX")
		)
	)
	(footprint ""
		(layer "B.Cu")
		(at 298.024804 -297.79976 90)
		(property "Reference" "C1629"
			(at 0 0 90)
			(layer "B.SilkS")
			(hide yes)
			(effects
				(font
					(size 1.27 1.27)
				)
				(justify mirror)
			)
		)
		(property "Value" ""
			(at 0 0 90)
			(layer "B.Fab")
			(effects
				(font
					(size 1.27 1.27)
				)
				(justify mirror)
			)
		)
		(duplicate_pad_numbers_are_jumpers no)
		(fp_line
			(start 0.299974 -0.150114)
			(end -0.299974 -0.150114)
			(stroke
				(width 0.1)
				(type default)
			)
			(layer "B.Fab")
		)
		(fp_line
			(start -0.299974 -0.150114)
			(end -0.299974 0.150114)
			(stroke
				(width 0.1)
				(type default)
			)
			(layer "B.Fab")
		)
		(fp_line
			(start 0.299974 0.150114)
			(end 0.299974 -0.150114)
			(stroke
				(width 0.1)
				(type default)
			)
			(layer "B.Fab")
		)
		(fp_line
			(start -0.299974 0.150114)
			(end 0.299974 0.150114)
			(stroke
				(width 0.1)
				(type default)
			)
			(layer "B.Fab")
		)
		(pad "1" smd rect
			(at 0.2667 0 270)
			(size 0.3048 0.381)
			(layers "B.Cu" "B.Mask" "B.Paste")
			(net "P0V8_PEX2")
		)
		(pad "2" smd rect
			(at -0.2667 0 270)
			(size 0.3048 0.381)
			(layers "B.Cu" "B.Mask" "B.Paste")
			(net "GND")
		)
	)
	(footprint ""
		(layer "B.Cu")
		(at 276.649688 -293.04996)
		(property "Reference" "C3354"
			(at 0 0 0)
			(layer "B.SilkS")
			(hide yes)
			(effects
				(font
					(size 1.27 1.27)
				)
				(justify mirror)
			)
		)
		(property "Value" ""
			(at 0 0 0)
			(layer "B.Fab")
			(effects
				(font
					(size 1.27 1.27)
				)
				(justify mirror)
			)
		)
		(duplicate_pad_numbers_are_jumpers no)
		(fp_line
			(start -0.299974 -0.150114)
			(end -0.299974 0.150114)
			(stroke
				(width 0.1)
				(type default)
			)
			(layer "B.Fab")
		)
		(fp_line
			(start -0.299974 0.150114)
			(end 0.299974 0.150114)
			(stroke
				(width 0.1)
				(type default)
			)
			(layer "B.Fab")
		)
		(fp_line
			(start 0.299974 -0.150114)
			(end -0.299974 -0.150114)
			(stroke
				(width 0.1)
				(type default)
			)
			(layer "B.Fab")
		)
		(fp_line
			(start 0.299974 0.150114)
			(end 0.299974 -0.150114)
			(stroke
				(width 0.1)
				(type default)
			)
			(layer "B.Fab")
		)
		(pad "1" smd rect
			(at 0.2667 0 180)
			(size 0.3048 0.381)
			(layers "B.Cu" "B.Mask" "B.Paste")
			(net "P1V8_PEX")
		)
		(pad "2" smd rect
			(at -0.2667 0 180)
			(size 0.3048 0.381)
			(layers "B.Cu" "B.Mask" "B.Paste")
			(net "GND")
		)
	)
	(footprint ""
		(layer "B.Cu")
		(at 63.924942 -297.79976 90)
		(property "Reference" "C1116"
			(at 0 0 90)
			(layer "B.SilkS")
			(hide yes)
			(effects
				(font
					(size 1.27 1.27)
				)
				(justify mirror)
			)
		)
		(property "Value" ""
			(at 0 0 90)
			(layer "B.Fab")
			(effects
				(font
					(size 1.27 1.27)
				)
				(justify mirror)
			)
		)
		(duplicate_pad_numbers_are_jumpers no)
		(fp_line
			(start 0.299974 -0.150114)
			(end -0.299974 -0.150114)
			(stroke
				(width 0.1)
				(type default)
			)
			(layer "B.Fab")
		)
		(fp_line
			(start -0.299974 -0.150114)
			(end -0.299974 0.150114)
			(stroke
				(width 0.1)
				(type default)
			)
			(layer "B.Fab")
		)
		(fp_line
			(start 0.299974 0.150114)
			(end 0.299974 -0.150114)
			(stroke
				(width 0.1)
				(type default)
			)
			(layer "B.Fab")
		)
		(fp_line
			(start -0.299974 0.150114)
			(end 0.299974 0.150114)
			(stroke
				(width 0.1)
				(type default)
			)
			(layer "B.Fab")
		)
		(pad "1" smd rect
			(at 0.2667 0 270)
			(size 0.3048 0.381)
			(layers "B.Cu" "B.Mask" "B.Paste")
			(net "P0V8_PEX0")
		)
		(pad "2" smd rect
			(at -0.2667 0 270)
			(size 0.3048 0.381)
			(layers "B.Cu" "B.Mask" "B.Paste")
			(net "GND")
		)
	)
	(footprint ""
		(layer "B.Cu")
		(at 397.85544 -156.0576)
		(property "Reference" "R334"
			(at 0 0 0)
			(layer "B.SilkS")
			(hide yes)
			(effects
				(font
					(size 1.27 1.27)
				)
				(justify mirror)
			)
		)
		(property "Value" ""
			(at 0 0 0)
			(layer "B.Fab")
			(effects
				(font
					(size 1.27 1.27)
				)
				(justify mirror)
			)
		)
		(duplicate_pad_numbers_are_jumpers no)
		(fp_line
			(start -0.7874 -0.4064)
			(end -0.7874 0.4064)
			(stroke
				(width 0.1524)
				(type default)
			)
			(layer "B.SilkS")
		)
		(fp_line
			(start -0.7874 0.4064)
			(end 0.7874 0.4064)
			(stroke
				(width 0.1524)
				(type default)
			)
			(layer "B.SilkS")
		)
		(fp_line
			(start 0.7874 -0.4064)
			(end -0.7874 -0.4064)
			(stroke
				(width 0.1524)
				(type default)
			)
			(layer "B.SilkS")
		)
		(fp_line
			(start 0.7874 0.4064)
			(end 0.7874 -0.4064)
			(stroke
				(width 0.1524)
				(type default)
			)
			(layer "B.SilkS")
		)
		(fp_line
			(start -0.67945 -0.3048)
			(end -0.67945 0.3048)
			(stroke
				(width 0.1)
				(type default)
			)
			(layer "B.Fab")
		)
		(fp_line
			(start -0.67945 0.3048)
			(end -0.120396 0.3048)
			(stroke
				(width 0.1)
				(type default)
			)
			(layer "B.Fab")
		)
		(fp_line
			(start -0.12065 -0.3048)
			(end -0.67945 -0.3048)
			(stroke
				(width 0.1)
				(type default)
			)
			(layer "B.Fab")
		)
		(fp_line
			(start -0.12065 -0.2794)
			(end -0.12065 -0.3048)
			(stroke
				(width 0.1)
				(type default)
			)
			(layer "B.Fab")
		)
		(fp_line
			(start -0.120396 0.2794)
			(end 0.12065 0.2794)
			(stroke
				(width 0.1)
				(type default)
			)
			(layer "B.Fab")
		)
		(fp_line
			(start -0.120396 0.3048)
			(end -0.120396 0.2794)
			(stroke
				(width 0.1)
				(type default)
			)
			(layer "B.Fab")
		)
		(fp_line
			(start 0.12065 -0.305054)
			(end 0.12065 -0.2794)
			(stroke
				(width 0.1)
				(type default)
			)
			(layer "B.Fab")
		)
		(fp_line
			(start 0.12065 -0.2794)
			(end -0.12065 -0.2794)
			(stroke
				(width 0.1)
				(type default)
			)
			(layer "B.Fab")
		)
		(fp_line
			(start 0.12065 0.2794)
			(end 0.12065 0.3048)
			(stroke
				(width 0.1)
				(type default)
			)
			(layer "B.Fab")
		)
		(fp_line
			(start 0.12065 0.3048)
			(end 0.67945 0.3048)
			(stroke
				(width 0.1)
				(type default)
			)
			(layer "B.Fab")
		)
		(fp_line
			(start 0.67945 -0.305054)
			(end 0.12065 -0.305054)
			(stroke
				(width 0.1)
				(type default)
			)
			(layer "B.Fab")
		)
		(fp_line
			(start 0.67945 0.3048)
			(end 0.67945 -0.305054)
			(stroke
				(width 0.1)
				(type default)
			)
			(layer "B.Fab")
		)
		(pad "1" smd circle
			(at 0.40005 0 180)
			(size 0 0)
			(layers "B.Cu" "B.Mask" "B.Paste")
			(net "NIC6_SLOT_ID1")
		)
		(pad "2" smd circle
			(at -0.40005 0 180)
			(size 0 0)
			(layers "B.Cu" "B.Mask" "B.Paste")
			(net "GND")
		)
	)
	(footprint ""
		(layer "B.Cu")
		(at 223.533716 -197.789292 -90)
		(property "Reference" "R1025"
			(at 0 0 90)
			(layer "B.SilkS")
			(hide yes)
			(effects
				(font
					(size 1.27 1.27)
				)
				(justify mirror)
			)
		)
		(property "Value" ""
			(at 0 0 90)
			(layer "B.Fab")
			(effects
				(font
					(size 1.27 1.27)
				)
				(justify mirror)
			)
		)
		(duplicate_pad_numbers_are_jumpers no)
		(fp_line
			(start -0.7874 0.4064)
			(end 0.7874 0.4064)
			(stroke
				(width 0.1524)
				(type default)
			)
			(layer "B.SilkS")
		)
		(fp_line
			(start 0.7874 0.4064)
			(end 0.7874 -0.4064)
			(stroke
				(width 0.1524)
				(type default)
			)
			(layer "B.SilkS")
		)
		(fp_line
			(start -0.7874 -0.4064)
			(end -0.7874 0.4064)
			(stroke
				(width 0.1524)
				(type default)
			)
			(layer "B.SilkS")
		)
		(fp_line
			(start 0.7874 -0.4064)
			(end -0.7874 -0.4064)
			(stroke
				(width 0.1524)
				(type default)
			)
			(layer "B.SilkS")
		)
		(fp_line
			(start -0.67945 0.3048)
			(end -0.120396 0.3048)
			(stroke
				(width 0.1)
				(type default)
			)
			(layer "B.Fab")
		)
		(fp_line
			(start -0.120396 0.3048)
			(end -0.120396 0.2794)
			(stroke
				(width 0.1)
				(type default)
			)
			(layer "B.Fab")
		)
		(fp_line
			(start 0.12065 0.3048)
			(end 0.67945 0.3048)
			(stroke
				(width 0.1)
				(type default)
			)
			(layer "B.Fab")
		)
		(fp_line
			(start 0.67945 0.3048)
			(end 0.67945 -0.305054)
			(stroke
				(width 0.1)
				(type default)
			)
			(layer "B.Fab")
		)
		(fp_line
			(start -0.120396 0.2794)
			(end 0.12065 0.2794)
			(stroke
				(width 0.1)
				(type default)
			)
			(layer "B.Fab")
		)
		(fp_line
			(start 0.12065 0.2794)
			(end 0.12065 0.3048)
			(stroke
				(width 0.1)
				(type default)
			)
			(layer "B.Fab")
		)
		(fp_line
			(start -0.12065 -0.2794)
			(end -0.12065 -0.3048)
			(stroke
				(width 0.1)
				(type default)
			)
			(layer "B.Fab")
		)
		(fp_line
			(start 0.12065 -0.2794)
			(end -0.12065 -0.2794)
			(stroke
				(width 0.1)
				(type default)
			)
			(layer "B.Fab")
		)
		(fp_line
			(start -0.67945 -0.3048)
			(end -0.67945 0.3048)
			(stroke
				(width 0.1)
				(type default)
			)
			(layer "B.Fab")
		)
		(fp_line
			(start -0.12065 -0.3048)
			(end -0.67945 -0.3048)
			(stroke
				(width 0.1)
				(type default)
			)
			(layer "B.Fab")
		)
		(fp_line
			(start 0.12065 -0.305054)
			(end 0.12065 -0.2794)
			(stroke
				(width 0.1)
				(type default)
			)
			(layer "B.Fab")
		)
		(fp_line
			(start 0.67945 -0.305054)
			(end 0.12065 -0.305054)
			(stroke
				(width 0.1)
				(type default)
			)
			(layer "B.Fab")
		)
		(pad "1" smd circle
			(at 0.40005 0 90)
			(size 0 0)
			(layers "B.Cu" "B.Mask" "B.Paste")
			(net "SPI_BIC1_MISO_R")
		)
		(pad "2" smd circle
			(at -0.40005 0 90)
			(size 0 0)
			(layers "B.Cu" "B.Mask" "B.Paste")
			(net "SPI_BIC1_MISO_R5")
		)
	)
	(footprint ""
		(layer "B.Cu")
		(at 179.55006 -303.499774 -90)
		(property "Reference" "C3092"
			(at 0 0 90)
			(layer "B.SilkS")
			(hide yes)
			(effects
				(font
					(size 1.27 1.27)
				)
				(justify mirror)
			)
		)
		(property "Value" ""
			(at 0 0 90)
			(layer "B.Fab")
			(effects
				(font
					(size 1.27 1.27)
				)
				(justify mirror)
			)
		)
		(duplicate_pad_numbers_are_jumpers no)
		(fp_line
			(start -0.299974 0.150114)
			(end 0.299974 0.150114)
			(stroke
				(width 0.1)
				(type default)
			)
			(layer "B.Fab")
		)
		(fp_line
			(start 0.299974 0.150114)
			(end 0.299974 -0.150114)
			(stroke
				(width 0.1)
				(type default)
			)
			(layer "B.Fab")
		)
		(fp_line
			(start -0.299974 -0.150114)
			(end -0.299974 0.150114)
			(stroke
				(width 0.1)
				(type default)
			)
			(layer "B.Fab")
		)
		(fp_line
			(start 0.299974 -0.150114)
			(end -0.299974 -0.150114)
			(stroke
				(width 0.1)
				(type default)
			)
			(layer "B.Fab")
		)
		(pad "1" smd rect
			(at 0.2667 0 90)
			(size 0.3048 0.381)
			(layers "B.Cu" "B.Mask" "B.Paste")
			(net "P1V25_PEX1")
		)
		(pad "2" smd rect
			(at -0.2667 0 90)
			(size 0.3048 0.381)
			(layers "B.Cu" "B.Mask" "B.Paste")
			(net "GND")
		)
	)
	(footprint ""
		(layer "B.Cu")
		(at 298.024804 -293.99992 -90)
		(property "Reference" "C1659"
			(at 0 0 90)
			(layer "B.SilkS")
			(hide yes)
			(effects
				(font
					(size 1.27 1.27)
				)
				(justify mirror)
			)
		)
		(property "Value" ""
			(at 0 0 90)
			(layer "B.Fab")
			(effects
				(font
					(size 1.27 1.27)
				)
				(justify mirror)
			)
		)
		(duplicate_pad_numbers_are_jumpers no)
		(fp_line
			(start -0.299974 0.150114)
			(end 0.299974 0.150114)
			(stroke
				(width 0.1)
				(type default)
			)
			(layer "B.Fab")
		)
		(fp_line
			(start 0.299974 0.150114)
			(end 0.299974 -0.150114)
			(stroke
				(width 0.1)
				(type default)
			)
			(layer "B.Fab")
		)
		(fp_line
			(start -0.299974 -0.150114)
			(end -0.299974 0.150114)
			(stroke
				(width 0.1)
				(type default)
			)
			(layer "B.Fab")
		)
		(fp_line
			(start 0.299974 -0.150114)
			(end -0.299974 -0.150114)
			(stroke
				(width 0.1)
				(type default)
			)
			(layer "B.Fab")
		)
		(pad "1" smd rect
			(at 0.2667 0 90)
			(size 0.3048 0.381)
			(layers "B.Cu" "B.Mask" "B.Paste")
			(net "P0V8_PEX2")
		)
		(pad "2" smd rect
			(at -0.2667 0 90)
			(size 0.3048 0.381)
			(layers "B.Cu" "B.Mask" "B.Paste")
			(net "GND")
		)
	)
	(footprint ""
		(layer "B.Cu")
		(at 167.200072 -303.499774 -90)
		(property "Reference" "C3079"
			(at 0 0 90)
			(layer "B.SilkS")
			(hide yes)
			(effects
				(font
					(size 1.27 1.27)
				)
				(justify mirror)
			)
		)
		(property "Value" ""
			(at 0 0 90)
			(layer "B.Fab")
			(effects
				(font
					(size 1.27 1.27)
				)
				(justify mirror)
			)
		)
		(duplicate_pad_numbers_are_jumpers no)
		(fp_line
			(start -0.299974 0.150114)
			(end 0.299974 0.150114)
			(stroke
				(width 0.1)
				(type default)
			)
			(layer "B.Fab")
		)
		(fp_line
			(start 0.299974 0.150114)
			(end 0.299974 -0.150114)
			(stroke
				(width 0.1)
				(type default)
			)
			(layer "B.Fab")
		)
		(fp_line
			(start -0.299974 -0.150114)
			(end -0.299974 0.150114)
			(stroke
				(width 0.1)
				(type default)
			)
			(layer "B.Fab")
		)
		(fp_line
			(start 0.299974 -0.150114)
			(end -0.299974 -0.150114)
			(stroke
				(width 0.1)
				(type default)
			)
			(layer "B.Fab")
		)
		(pad "1" smd rect
			(at 0.2667 0 90)
			(size 0.3048 0.381)
			(layers "B.Cu" "B.Mask" "B.Paste")
			(net "P1V25_PEX1")
		)
		(pad "2" smd rect
			(at -0.2667 0 90)
			(size 0.3048 0.381)
			(layers "B.Cu" "B.Mask" "B.Paste")
			(net "GND")
		)
	)
	(footprint ""
		(layer "B.Cu")
		(at 411.770322 -296.37482)
		(property "Reference" "C1888"
			(at 0 0 0)
			(layer "B.SilkS")
			(hide yes)
			(effects
				(font
					(size 1.27 1.27)
				)
				(justify mirror)
			)
		)
		(property "Value" ""
			(at 0 0 0)
			(layer "B.Fab")
			(effects
				(font
					(size 1.27 1.27)
				)
				(justify mirror)
			)
		)
		(duplicate_pad_numbers_are_jumpers no)
		(fp_line
			(start -0.299974 -0.150114)
			(end -0.299974 0.150114)
			(stroke
				(width 0.1)
				(type default)
			)
			(layer "B.Fab")
		)
		(fp_line
			(start -0.299974 0.150114)
			(end 0.299974 0.150114)
			(stroke
				(width 0.1)
				(type default)
			)
			(layer "B.Fab")
		)
		(fp_line
			(start 0.299974 -0.150114)
			(end -0.299974 -0.150114)
			(stroke
				(width 0.1)
				(type default)
			)
			(layer "B.Fab")
		)
		(fp_line
			(start 0.299974 0.150114)
			(end 0.299974 -0.150114)
			(stroke
				(width 0.1)
				(type default)
			)
			(layer "B.Fab")
		)
		(pad "1" smd rect
			(at 0.2667 0 180)
			(size 0.3048 0.381)
			(layers "B.Cu" "B.Mask" "B.Paste")
			(net "P0V8_PEX3")
		)
		(pad "2" smd rect
			(at -0.2667 0 180)
			(size 0.3048 0.381)
			(layers "B.Cu" "B.Mask" "B.Paste")
			(net "GND")
		)
	)
	(footprint ""
		(layer "B.Cu")
		(at 329.692 -222.4532 180)
		(property "Reference" "R4174"
			(at 0 0 0)
			(layer "B.SilkS")
			(hide yes)
			(effects
				(font
					(size 1.27 1.27)
				)
				(justify mirror)
			)
		)
		(property "Value" ""
			(at 0 0 0)
			(layer "B.Fab")
			(effects
				(font
					(size 1.27 1.27)
				)
				(justify mirror)
			)
		)
		(duplicate_pad_numbers_are_jumpers no)
		(fp_line
			(start 0.7874 0.4064)
			(end 0.7874 -0.4064)
			(stroke
				(width 0.1524)
				(type default)
			)
			(layer "B.SilkS")
		)
		(fp_line
			(start 0.7874 -0.4064)
			(end -0.7874 -0.4064)
			(stroke
				(width 0.1524)
				(type default)
			)
			(layer "B.SilkS")
		)
		(fp_line
			(start -0.7874 0.4064)
			(end 0.7874 0.4064)
			(stroke
				(width 0.1524)
				(type default)
			)
			(layer "B.SilkS")
		)
		(fp_line
			(start -0.7874 -0.4064)
			(end -0.7874 0.4064)
			(stroke
				(width 0.1524)
				(type default)
			)
			(layer "B.SilkS")
		)
		(fp_line
			(start 0.67945 0.3048)
			(end 0.67945 -0.305054)
			(stroke
				(width 0.1)
				(type default)
			)
			(layer "B.Fab")
		)
		(fp_line
			(start 0.67945 -0.305054)
			(end 0.12065 -0.305054)
			(stroke
				(width 0.1)
				(type default)
			)
			(layer "B.Fab")
		)
		(fp_line
			(start 0.12065 0.3048)
			(end 0.67945 0.3048)
			(stroke
				(width 0.1)
				(type default)
			)
			(layer "B.Fab")
		)
		(fp_line
			(start 0.12065 0.2794)
			(end 0.12065 0.3048)
			(stroke
				(width 0.1)
				(type default)
			)
			(layer "B.Fab")
		)
		(fp_line
			(start 0.12065 -0.2794)
			(end -0.12065 -0.2794)
			(stroke
				(width 0.1)
				(type default)
			)
			(layer "B.Fab")
		)
		(fp_line
			(start 0.12065 -0.305054)
			(end 0.12065 -0.2794)
			(stroke
				(width 0.1)
				(type default)
			)
			(layer "B.Fab")
		)
		(fp_line
			(start -0.120396 0.3048)
			(end -0.120396 0.2794)
			(stroke
				(width 0.1)
				(type default)
			)
			(layer "B.Fab")
		)
		(fp_line
			(start -0.120396 0.2794)
			(end 0.12065 0.2794)
			(stroke
				(width 0.1)
				(type default)
			)
			(layer "B.Fab")
		)
		(fp_line
			(start -0.12065 -0.2794)
			(end -0.12065 -0.3048)
			(stroke
				(width 0.1)
				(type default)
			)
			(layer "B.Fab")
		)
		(fp_line
			(start -0.12065 -0.3048)
			(end -0.67945 -0.3048)
			(stroke
				(width 0.1)
				(type default)
			)
			(layer "B.Fab")
		)
		(fp_line
			(start -0.67945 0.3048)
			(end -0.120396 0.3048)
			(stroke
				(width 0.1)
				(type default)
			)
			(layer "B.Fab")
		)
		(fp_line
			(start -0.67945 -0.3048)
			(end -0.67945 0.3048)
			(stroke
				(width 0.1)
				(type default)
			)
			(layer "B.Fab")
		)
		(pad "1" smd circle
			(at 0.40005 0)
			(size 0 0)
			(layers "B.Cu" "B.Mask" "B.Paste")
			(net "RST_PEX3_PERST_R_N")
		)
		(pad "2" smd circle
			(at -0.40005 0)
			(size 0 0)
			(layers "B.Cu" "B.Mask" "B.Paste")
			(net "RST_PEX3_PERST_N")
		)
	)
	(footprint ""
		(layer "B.Cu")
		(at 401.72005 -305.399948 -90)
		(property "Reference" "C3489"
			(at 0 0 90)
			(layer "B.SilkS")
			(hide yes)
			(effects
				(font
					(size 1.27 1.27)
				)
				(justify mirror)
			)
		)
		(property "Value" ""
			(at 0 0 90)
			(layer "B.Fab")
			(effects
				(font
					(size 1.27 1.27)
				)
				(justify mirror)
			)
		)
		(duplicate_pad_numbers_are_jumpers no)
		(fp_line
			(start -0.299974 0.150114)
			(end 0.299974 0.150114)
			(stroke
				(width 0.1)
				(type default)
			)
			(layer "B.Fab")
		)
		(fp_line
			(start 0.299974 0.150114)
			(end 0.299974 -0.150114)
			(stroke
				(width 0.1)
				(type default)
			)
			(layer "B.Fab")
		)
		(fp_line
			(start -0.299974 -0.150114)
			(end -0.299974 0.150114)
			(stroke
				(width 0.1)
				(type default)
			)
			(layer "B.Fab")
		)
		(fp_line
			(start 0.299974 -0.150114)
			(end -0.299974 -0.150114)
			(stroke
				(width 0.1)
				(type default)
			)
			(layer "B.Fab")
		)
		(pad "1" smd rect
			(at 0.2667 0 90)
			(size 0.3048 0.381)
			(layers "B.Cu" "B.Mask" "B.Paste")
			(net "P1V25_SERDES_VDDPLL_PEX3")
		)
		(pad "2" smd rect
			(at -0.2667 0 90)
			(size 0.3048 0.381)
			(layers "B.Cu" "B.Mask" "B.Paste")
			(net "GND")
		)
	)
	(footprint ""
		(layer "B.Cu")
		(at 331.30363 -217.125296)
		(property "Reference" "C2078"
			(at 0 0 0)
			(layer "B.SilkS")
			(hide yes)
			(effects
				(font
					(size 1.27 1.27)
				)
				(justify mirror)
			)
		)
		(property "Value" ""
			(at 0 0 0)
			(layer "B.Fab")
			(effects
				(font
					(size 1.27 1.27)
				)
				(justify mirror)
			)
		)
		(duplicate_pad_numbers_are_jumpers no)
		(fp_line
			(start -0.69215 -0.2921)
			(end -0.69215 0.2921)
			(stroke
				(width 0.1524)
				(type default)
			)
			(layer "B.SilkS")
		)
		(fp_line
			(start -0.69215 0.2921)
			(end 0.69215 0.2921)
			(stroke
				(width 0.1524)
				(type default)
			)
			(layer "B.SilkS")
		)
		(fp_line
			(start 0.69215 -0.2921)
			(end -0.69215 -0.2921)
			(stroke
				(width 0.1524)
				(type default)
			)
			(layer "B.SilkS")
		)
		(fp_line
			(start 0.69215 0.2921)
			(end 0.69215 -0.2921)
			(stroke
				(width 0.1524)
				(type default)
			)
			(layer "B.SilkS")
		)
		(fp_line
			(start -0.51435 -0.2794)
			(end -0.51435 0.2794)
			(stroke
				(width 0.1)
				(type default)
			)
			(layer "B.Fab")
		)
		(fp_line
			(start -0.51435 0.2794)
			(end 0.51435 0.2794)
			(stroke
				(width 0.1)
				(type default)
			)
			(layer "B.Fab")
		)
		(fp_line
			(start 0.51435 -0.2794)
			(end -0.51435 -0.2794)
			(stroke
				(width 0.1)
				(type default)
			)
			(layer "B.Fab")
		)
		(fp_line
			(start 0.51435 0.2794)
			(end 0.51435 -0.2794)
			(stroke
				(width 0.1)
				(type default)
			)
			(layer "B.Fab")
		)
		(pad "1" smd circle
			(at 0.40005 0 180)
			(size 0 0)
			(layers "B.Cu" "B.Mask" "B.Paste")
			(net "P3V3_FPGA_VCCIO3")
		)
		(pad "2" smd circle
			(at -0.40005 0 180)
			(size 0 0)
			(layers "B.Cu" "B.Mask" "B.Paste")
			(net "GND")
		)
		(zone
			(layer "B.Cu")
			(hatch none 0.5)
			(connect_pads
				(clearance 0)
			)
			(min_thickness 0.25)
			(keepout
				(tracks not_allowed)
				(vias allowed)
				(pads allowed)
				(copperpour not_allowed)
				(footprints allowed)
			)
			(placement
				(enabled no)
				(sheetname "")
			)
			(fill
				(thermal_gap 0.5)
				(thermal_bridge_width 0.5)
				(island_removal_mode 0)
			)
			(polygon
				(pts
					(xy 331.49413 -217.037666) (xy 331.40269 -216.9795) (xy 331.2033 -216.9795) (xy 331.11313 -217.037666)
					(xy 331.11313 -217.212926) (xy 331.2033 -217.271346) (xy 331.40269 -217.271346) (xy 331.49413 -217.21318)
				)
			)
		)
	)
	(footprint ""
		(layer "B.Cu")
		(at 183.3499 -290.199826 90)
		(property "Reference" "C1437"
			(at 0 0 90)
			(layer "B.SilkS")
			(hide yes)
			(effects
				(font
					(size 1.27 1.27)
				)
				(justify mirror)
			)
		)
		(property "Value" ""
			(at 0 0 90)
			(layer "B.Fab")
			(effects
				(font
					(size 1.27 1.27)
				)
				(justify mirror)
			)
		)
		(duplicate_pad_numbers_are_jumpers no)
		(fp_line
			(start 0.299974 -0.150114)
			(end -0.299974 -0.150114)
			(stroke
				(width 0.1)
				(type default)
			)
			(layer "B.Fab")
		)
		(fp_line
			(start -0.299974 -0.150114)
			(end -0.299974 0.150114)
			(stroke
				(width 0.1)
				(type default)
			)
			(layer "B.Fab")
		)
		(fp_line
			(start 0.299974 0.150114)
			(end 0.299974 -0.150114)
			(stroke
				(width 0.1)
				(type default)
			)
			(layer "B.Fab")
		)
		(fp_line
			(start -0.299974 0.150114)
			(end 0.299974 0.150114)
			(stroke
				(width 0.1)
				(type default)
			)
			(layer "B.Fab")
		)
		(pad "1" smd rect
			(at 0.2667 0 270)
			(size 0.3048 0.381)
			(layers "B.Cu" "B.Mask" "B.Paste")
			(net "P0V8_SERDES_VDDA_PEX1")
		)
		(pad "2" smd rect
			(at -0.2667 0 270)
			(size 0.3048 0.381)
			(layers "B.Cu" "B.Mask" "B.Paste")
			(net "GND")
		)
	)
	(footprint ""
		(layer "B.Cu")
		(at 135.818372 -227.084382 90)
		(property "Reference" "U66"
			(at -1.970278 3.25374 270)
			(unlocked yes)
			(layer "B.SilkS")
			(effects
				(font
					(size 0.7874 0.5842)
					(thickness 0.1524)
				)
				(justify mirror)
			)
		)
		(property "Value" ""
			(at 0 0 90)
			(layer "B.Fab")
			(effects
				(font
					(size 1.27 1.27)
				)
				(justify mirror)
			)
		)
		(duplicate_pad_numbers_are_jumpers no)
		(fp_line
			(start 1.8288 -2.4892)
			(end 0.5588 -2.4892)
			(stroke
				(width 0.1524)
				(type default)
			)
			(layer "B.SilkS")
		)
		(fp_line
			(start 0.5588 -2.4892)
			(end 0 -1.9304)
			(stroke
				(width 0.1524)
				(type default)
			)
			(layer "B.SilkS")
		)
		(fp_line
			(start -0.5588 -2.4892)
			(end -1.8288 -2.4892)
			(stroke
				(width 0.1524)
				(type default)
			)
			(layer "B.SilkS")
		)
		(fp_line
			(start -1.8288 -2.4892)
			(end -1.8161 2.4892)
			(stroke
				(width 0.1524)
				(type default)
			)
			(layer "B.SilkS")
		)
		(fp_line
			(start 0 -1.9304)
			(end -0.5588 -2.4892)
			(stroke
				(width 0.1524)
				(type default)
			)
			(layer "B.SilkS")
		)
		(fp_line
			(start 1.8288 2.4892)
			(end 1.8288 -2.4892)
			(stroke
				(width 0.1524)
				(type default)
			)
			(layer "B.SilkS")
		)
		(fp_line
			(start -1.8161 2.4892)
			(end 1.8288 2.4892)
			(stroke
				(width 0.1524)
				(type default)
			)
			(layer "B.SilkS")
		)
		(fp_poly
			(pts
				(xy 4.23672 -1.989328) (xy 4.23672 -2.614168) (xy 3.683 -2.286)
			)
			(stroke
				(width 0)
				(type default)
			)
			(fill yes)
			(layer "B.SilkS")
		)
		(fp_line
			(start 1.9939 -2.4892)
			(end -1.9939 -2.4892)
			(stroke
				(width 0.1)
				(type default)
			)
			(layer "B.Fab")
		)
		(fp_line
			(start -1.9939 -2.4892)
			(end -1.9939 -2.3876)
			(stroke
				(width 0.1)
				(type default)
			)
			(layer "B.Fab")
		)
		(fp_line
			(start 3.0988 -2.3876)
			(end 1.9939 -2.3876)
			(stroke
				(width 0.1)
				(type default)
			)
			(layer "B.Fab")
		)
		(fp_line
			(start 1.9939 -2.3876)
			(end 1.9939 -2.4892)
			(stroke
				(width 0.1)
				(type default)
			)
			(layer "B.Fab")
		)
		(fp_line
			(start 1.9939 -2.3876)
			(end 1.9812 -2.3876)
			(stroke
				(width 0.1)
				(type default)
			)
			(layer "B.Fab")
		)
		(fp_line
			(start -1.9939 -2.3876)
			(end -3.0988 -2.3876)
			(stroke
				(width 0.1)
				(type default)
			)
			(layer "B.Fab")
		)
		(fp_line
			(start -1.9939 -2.3876)
			(end -1.9939 2.3876)
			(stroke
				(width 0.1)
				(type default)
			)
			(layer "B.Fab")
		)
		(fp_line
			(start -3.0988 -2.3876)
			(end -3.0988 2.3876)
			(stroke
				(width 0.1)
				(type default)
			)
			(layer "B.Fab")
		)
		(fp_line
			(start -3.0988 -2.3876)
			(end -3.0988 2.3876)
			(stroke
				(width 0.1)
				(type default)
			)
			(layer "B.Fab")
		)
		(fp_line
			(start 3.0988 2.3876)
			(end 3.0988 -2.3876)
			(stroke
				(width 0.1)
				(type default)
			)
			(layer "B.Fab")
		)
		(fp_line
			(start 3.0988 2.3876)
			(end 3.0988 -2.3876)
			(stroke
				(width 0.1)
				(type default)
			)
			(layer "B.Fab")
		)
		(fp_line
			(start 1.9939 2.3876)
			(end 1.9939 -2.3876)
			(stroke
				(width 0.1)
				(type default)
			)
			(layer "B.Fab")
		)
		(fp_line
			(start 1.9939 2.3876)
			(end 3.0988 2.3876)
			(stroke
				(width 0.1)
				(type default)
			)
			(layer "B.Fab")
		)
		(fp_line
			(start -1.9939 2.3876)
			(end -1.9939 2.4892)
			(stroke
				(width 0.1)
				(type default)
			)
			(layer "B.Fab")
		)
		(fp_line
			(start -3.0988 2.3876)
			(end -1.9939 2.3876)
			(stroke
				(width 0.1)
				(type default)
			)
			(layer "B.Fab")
		)
		(fp_line
			(start 1.9939 2.4892)
			(end 1.9939 2.3876)
			(stroke
				(width 0.1)
				(type default)
			)
			(layer "B.Fab")
		)
		(fp_line
			(start -1.9939 2.4892)
			(end 1.9939 2.4892)
			(stroke
				(width 0.1)
				(type default)
			)
			(layer "B.Fab")
		)
		(fp_line
			(start -1.9939 2.4892)
			(end -2.0066 2.4892)
			(stroke
				(width 0.1)
				(type default)
			)
			(layer "B.Fab")
		)
		(fp_line
			(start -1.9939 2.5019)
			(end -1.9939 2.4892)
			(stroke
				(width 0.1)
				(type default)
			)
			(layer "B.Fab")
		)
		(fp_poly
			(pts
				(xy 4.23672 -1.989328) (xy 4.23672 -2.614168) (xy 3.683 -2.286)
			)
			(stroke
				(width 0)
				(type default)
			)
			(fill yes)
			(layer "B.Fab")
		)
		(pad "1" smd rect
			(at 2.7432 -2.2225)
			(size 0.3556 1.5494)
			(layers "B.Cu" "B.Mask" "B.Paste")
			(net "SEL_FLASH_PEX1_BUF_R")
		)
		(pad "2" smd rect
			(at 2.7432 -1.5875)
			(size 0.3556 1.5494)
			(layers "B.Cu" "B.Mask" "B.Paste")
			(net "SPI_PEX1_CS_R_N")
		)
		(pad "3" smd rect
			(at 2.7432 -0.9525)
			(size 0.3556 1.5494)
			(layers "B.Cu" "B.Mask" "B.Paste")
			(net "SPI_BIC1_CS0_LS01_R2_N")
		)
		(pad "4" smd rect
			(at 2.7432 -0.3175)
			(size 0.3556 1.5494)
			(layers "B.Cu" "B.Mask" "B.Paste")
			(net "SPI_PEX1_CS_MUX_N")
		)
		(pad "5" smd rect
			(at 2.7432 0.3175)
			(size 0.3556 1.5494)
			(layers "B.Cu" "B.Mask" "B.Paste")
			(net "SPI_PEX1_CLK_R")
		)
		(pad "6" smd rect
			(at 2.7432 0.9525)
			(size 0.3556 1.5494)
			(layers "B.Cu" "B.Mask" "B.Paste")
			(net "SPI_BIC1_CLK_LS01_R2")
		)
		(pad "7" smd rect
			(at 2.7432 1.5875)
			(size 0.3556 1.5494)
			(layers "B.Cu" "B.Mask" "B.Paste")
			(net "SPI_PEX1_CLK_MUX")
		)
		(pad "8" smd rect
			(at 2.7432 2.2225)
			(size 0.3556 1.5494)
			(layers "B.Cu" "B.Mask" "B.Paste")
			(net "GND")
		)
		(pad "9" smd rect
			(at -2.7432 2.2225)
			(size 0.3556 1.5494)
			(layers "B.Cu" "B.Mask" "B.Paste")
			(net "SPI_PEX1_SDIO0_MUX")
		)
		(pad "10" smd rect
			(at -2.7432 1.5875)
			(size 0.3556 1.5494)
			(layers "B.Cu" "B.Mask" "B.Paste")
			(net "SPI_BIC1_MOSI_LS01_R2")
		)
		(pad "11" smd rect
			(at -2.7432 0.9525)
			(size 0.3556 1.5494)
			(layers "B.Cu" "B.Mask" "B.Paste")
			(net "SPI_PEX1_SDIO0_R")
		)
		(pad "12" smd rect
			(at -2.7432 0.3175)
			(size 0.3556 1.5494)
			(layers "B.Cu" "B.Mask" "B.Paste")
			(net "SPI_PEX1_SDIO1_MUX")
		)
		(pad "13" smd rect
			(at -2.7432 -0.3175)
			(size 0.3556 1.5494)
			(layers "B.Cu" "B.Mask" "B.Paste")
			(net "SPI_BIC1_MISO_LS01_R2")
		)
		(pad "14" smd rect
			(at -2.7432 -0.9525)
			(size 0.3556 1.5494)
			(layers "B.Cu" "B.Mask" "B.Paste")
			(net "SPI_PEX1_SDIO1_R")
		)
		(pad "15" smd rect
			(at -2.7432 -1.5875)
			(size 0.3556 1.5494)
			(layers "B.Cu" "B.Mask" "B.Paste")
			(net "SPI_MUX_PEX1_EN_N")
		)
		(pad "16" smd rect
			(at -2.7432 -2.2225)
			(size 0.3556 1.5494)
			(layers "B.Cu" "B.Mask" "B.Paste")
			(net "P3V3_AUX")
		)
	)
	(footprint ""
		(layer "B.Cu")
		(at 336.296 -207.772 90)
		(property "Reference" "R4130"
			(at 0 0 90)
			(layer "B.SilkS")
			(hide yes)
			(effects
				(font
					(size 1.27 1.27)
				)
				(justify mirror)
			)
		)
		(property "Value" ""
			(at 0 0 90)
			(layer "B.Fab")
			(effects
				(font
					(size 1.27 1.27)
				)
				(justify mirror)
			)
		)
		(duplicate_pad_numbers_are_jumpers no)
		(fp_line
			(start 0.7874 -0.4064)
			(end -0.7874 -0.4064)
			(stroke
				(width 0.1524)
				(type default)
			)
			(layer "B.SilkS")
		)
		(fp_line
			(start -0.7874 -0.4064)
			(end -0.7874 0.4064)
			(stroke
				(width 0.1524)
				(type default)
			)
			(layer "B.SilkS")
		)
		(fp_line
			(start 0.7874 0.4064)
			(end 0.7874 -0.4064)
			(stroke
				(width 0.1524)
				(type default)
			)
			(layer "B.SilkS")
		)
		(fp_line
			(start -0.7874 0.4064)
			(end 0.7874 0.4064)
			(stroke
				(width 0.1524)
				(type default)
			)
			(layer "B.SilkS")
		)
		(fp_line
			(start 0.67945 -0.305054)
			(end 0.12065 -0.305054)
			(stroke
				(width 0.1)
				(type default)
			)
			(layer "B.Fab")
		)
		(fp_line
			(start 0.12065 -0.305054)
			(end 0.12065 -0.2794)
			(stroke
				(width 0.1)
				(type default)
			)
			(layer "B.Fab")
		)
		(fp_line
			(start -0.12065 -0.3048)
			(end -0.67945 -0.3048)
			(stroke
				(width 0.1)
				(type default)
			)
			(layer "B.Fab")
		)
		(fp_line
			(start -0.67945 -0.3048)
			(end -0.67945 0.3048)
			(stroke
				(width 0.1)
				(type default)
			)
			(layer "B.Fab")
		)
		(fp_line
			(start 0.12065 -0.2794)
			(end -0.12065 -0.2794)
			(stroke
				(width 0.1)
				(type default)
			)
			(layer "B.Fab")
		)
		(fp_line
			(start -0.12065 -0.2794)
			(end -0.12065 -0.3048)
			(stroke
				(width 0.1)
				(type default)
			)
			(layer "B.Fab")
		)
		(fp_line
			(start 0.12065 0.2794)
			(end 0.12065 0.3048)
			(stroke
				(width 0.1)
				(type default)
			)
			(layer "B.Fab")
		)
		(fp_line
			(start -0.120396 0.2794)
			(end 0.12065 0.2794)
			(stroke
				(width 0.1)
				(type default)
			)
			(layer "B.Fab")
		)
		(fp_line
			(start 0.67945 0.3048)
			(end 0.67945 -0.305054)
			(stroke
				(width 0.1)
				(type default)
			)
			(layer "B.Fab")
		)
		(fp_line
			(start 0.12065 0.3048)
			(end 0.67945 0.3048)
			(stroke
				(width 0.1)
				(type default)
			)
			(layer "B.Fab")
		)
		(fp_line
			(start -0.120396 0.3048)
			(end -0.120396 0.2794)
			(stroke
				(width 0.1)
				(type default)
			)
			(layer "B.Fab")
		)
		(fp_line
			(start -0.67945 0.3048)
			(end -0.120396 0.3048)
			(stroke
				(width 0.1)
				(type default)
			)
			(layer "B.Fab")
		)
		(pad "1" smd circle
			(at 0.40005 0 270)
			(size 0 0)
			(layers "B.Cu" "B.Mask" "B.Paste")
			(net "SSD11_CLK_EN_N")
		)
		(pad "2" smd circle
			(at -0.40005 0 270)
			(size 0 0)
			(layers "B.Cu" "B.Mask" "B.Paste")
			(net "SSD11_CLK_EN_R_N")
		)
	)
	(footprint ""
		(layer "B.Cu")
		(at 105.754678 -355.714046 -90)
		(property "Reference" "R6368"
			(at 0 0 90)
			(layer "B.SilkS")
			(hide yes)
			(effects
				(font
					(size 1.27 1.27)
				)
				(justify mirror)
			)
		)
		(property "Value" ""
			(at 0 0 90)
			(layer "B.Fab")
			(effects
				(font
					(size 1.27 1.27)
				)
				(justify mirror)
			)
		)
		(duplicate_pad_numbers_are_jumpers no)
		(fp_line
			(start -0.7874 0.4064)
			(end 0.7874 0.4064)
			(stroke
				(width 0.1524)
				(type default)
			)
			(layer "B.SilkS")
		)
		(fp_line
			(start 0.7874 0.4064)
			(end 0.7874 -0.4064)
			(stroke
				(width 0.1524)
				(type default)
			)
			(layer "B.SilkS")
		)
		(fp_line
			(start -0.7874 -0.4064)
			(end -0.7874 0.4064)
			(stroke
				(width 0.1524)
				(type default)
			)
			(layer "B.SilkS")
		)
		(fp_line
			(start 0.7874 -0.4064)
			(end -0.7874 -0.4064)
			(stroke
				(width 0.1524)
				(type default)
			)
			(layer "B.SilkS")
		)
		(fp_line
			(start -0.67945 0.3048)
			(end -0.120396 0.3048)
			(stroke
				(width 0.1)
				(type default)
			)
			(layer "B.Fab")
		)
		(fp_line
			(start -0.120396 0.3048)
			(end -0.120396 0.2794)
			(stroke
				(width 0.1)
				(type default)
			)
			(layer "B.Fab")
		)
		(fp_line
			(start 0.12065 0.3048)
			(end 0.67945 0.3048)
			(stroke
				(width 0.1)
				(type default)
			)
			(layer "B.Fab")
		)
		(fp_line
			(start 0.67945 0.3048)
			(end 0.67945 -0.305054)
			(stroke
				(width 0.1)
				(type default)
			)
			(layer "B.Fab")
		)
		(fp_line
			(start -0.120396 0.2794)
			(end 0.12065 0.2794)
			(stroke
				(width 0.1)
				(type default)
			)
			(layer "B.Fab")
		)
		(fp_line
			(start 0.12065 0.2794)
			(end 0.12065 0.3048)
			(stroke
				(width 0.1)
				(type default)
			)
			(layer "B.Fab")
		)
		(fp_line
			(start -0.12065 -0.2794)
			(end -0.12065 -0.3048)
			(stroke
				(width 0.1)
				(type default)
			)
			(layer "B.Fab")
		)
		(fp_line
			(start 0.12065 -0.2794)
			(end -0.12065 -0.2794)
			(stroke
				(width 0.1)
				(type default)
			)
			(layer "B.Fab")
		)
		(fp_line
			(start -0.67945 -0.3048)
			(end -0.67945 0.3048)
			(stroke
				(width 0.1)
				(type default)
			)
			(layer "B.Fab")
		)
		(fp_line
			(start -0.12065 -0.3048)
			(end -0.67945 -0.3048)
			(stroke
				(width 0.1)
				(type default)
			)
			(layer "B.Fab")
		)
		(fp_line
			(start 0.12065 -0.305054)
			(end 0.12065 -0.2794)
			(stroke
				(width 0.1)
				(type default)
			)
			(layer "B.Fab")
		)
		(fp_line
			(start 0.67945 -0.305054)
			(end 0.12065 -0.305054)
			(stroke
				(width 0.1)
				(type default)
			)
			(layer "B.Fab")
		)
		(pad "1" smd circle
			(at 0.40005 0 90)
			(size 0 0)
			(layers "B.Cu" "B.Mask" "B.Paste")
			(net "PEX_S3_REF_CLK_BUFFER_EN_N")
		)
		(pad "2" smd circle
			(at -0.40005 0 90)
			(size 0 0)
			(layers "B.Cu" "B.Mask" "B.Paste")
			(net "P3V3")
		)
	)
	(footprint ""
		(layer "B.Cu")
		(at 53.949854 -288.299906 90)
		(property "Reference" "C2934"
			(at 0 0 90)
			(layer "B.SilkS")
			(hide yes)
			(effects
				(font
					(size 1.27 1.27)
				)
				(justify mirror)
			)
		)
		(property "Value" ""
			(at 0 0 90)
			(layer "B.Fab")
			(effects
				(font
					(size 1.27 1.27)
				)
				(justify mirror)
			)
		)
		(duplicate_pad_numbers_are_jumpers no)
		(fp_line
			(start 0.299974 -0.150114)
			(end -0.299974 -0.150114)
			(stroke
				(width 0.1)
				(type default)
			)
			(layer "B.Fab")
		)
		(fp_line
			(start -0.299974 -0.150114)
			(end -0.299974 0.150114)
			(stroke
				(width 0.1)
				(type default)
			)
			(layer "B.Fab")
		)
		(fp_line
			(start 0.299974 0.150114)
			(end 0.299974 -0.150114)
			(stroke
				(width 0.1)
				(type default)
			)
			(layer "B.Fab")
		)
		(fp_line
			(start -0.299974 0.150114)
			(end 0.299974 0.150114)
			(stroke
				(width 0.1)
				(type default)
			)
			(layer "B.Fab")
		)
		(pad "1" smd rect
			(at 0.2667 0 270)
			(size 0.3048 0.381)
			(layers "B.Cu" "B.Mask" "B.Paste")
			(net "P1V25_PEX0")
		)
		(pad "2" smd rect
			(at -0.2667 0 270)
			(size 0.3048 0.381)
			(layers "B.Cu" "B.Mask" "B.Paste")
			(net "GND")
		)
	)
	(footprint ""
		(layer "B.Cu")
		(at 148.285962 -237.948978)
		(property "Reference" "C4422"
			(at 0 0 0)
			(layer "B.SilkS")
			(hide yes)
			(effects
				(font
					(size 1.27 1.27)
				)
				(justify mirror)
			)
		)
		(property "Value" ""
			(at 0 0 0)
			(layer "B.Fab")
			(effects
				(font
					(size 1.27 1.27)
				)
				(justify mirror)
			)
		)
		(duplicate_pad_numbers_are_jumpers no)
		(fp_line
			(start -0.7874 -0.4064)
			(end -0.7874 0.4064)
			(stroke
				(width 0.1524)
				(type default)
			)
			(layer "B.SilkS")
		)
		(fp_line
			(start -0.7874 0.4064)
			(end 0.7874 0.4064)
			(stroke
				(width 0.1524)
				(type default)
			)
			(layer "B.SilkS")
		)
		(fp_line
			(start 0.7874 -0.4064)
			(end -0.7874 -0.4064)
			(stroke
				(width 0.1524)
				(type default)
			)
			(layer "B.SilkS")
		)
		(fp_line
			(start 0.7874 0.4064)
			(end 0.7874 -0.4064)
			(stroke
				(width 0.1524)
				(type default)
			)
			(layer "B.SilkS")
		)
		(fp_line
			(start -0.67945 -0.3048)
			(end -0.67945 0.3048)
			(stroke
				(width 0.1)
				(type default)
			)
			(layer "B.Fab")
		)
		(fp_line
			(start -0.67945 0.3048)
			(end -0.120396 0.3048)
			(stroke
				(width 0.1)
				(type default)
			)
			(layer "B.Fab")
		)
		(fp_line
			(start -0.12065 -0.3048)
			(end -0.67945 -0.3048)
			(stroke
				(width 0.1)
				(type default)
			)
			(layer "B.Fab")
		)
		(fp_line
			(start -0.12065 -0.2794)
			(end -0.12065 -0.3048)
			(stroke
				(width 0.1)
				(type default)
			)
			(layer "B.Fab")
		)
		(fp_line
			(start -0.120396 0.2794)
			(end 0.12065 0.2794)
			(stroke
				(width 0.1)
				(type default)
			)
			(layer "B.Fab")
		)
		(fp_line
			(start -0.120396 0.3048)
			(end -0.120396 0.2794)
			(stroke
				(width 0.1)
				(type default)
			)
			(layer "B.Fab")
		)
		(fp_line
			(start 0.12065 -0.305054)
			(end 0.12065 -0.2794)
			(stroke
				(width 0.1)
				(type default)
			)
			(layer "B.Fab")
		)
		(fp_line
			(start 0.12065 -0.2794)
			(end -0.12065 -0.2794)
			(stroke
				(width 0.1)
				(type default)
			)
			(layer "B.Fab")
		)
		(fp_line
			(start 0.12065 0.2794)
			(end 0.12065 0.3048)
			(stroke
				(width 0.1)
				(type default)
			)
			(layer "B.Fab")
		)
		(fp_line
			(start 0.12065 0.3048)
			(end 0.67945 0.3048)
			(stroke
				(width 0.1)
				(type default)
			)
			(layer "B.Fab")
		)
		(fp_line
			(start 0.67945 -0.305054)
			(end 0.12065 -0.305054)
			(stroke
				(width 0.1)
				(type default)
			)
			(layer "B.Fab")
		)
		(fp_line
			(start 0.67945 0.3048)
			(end 0.67945 -0.305054)
			(stroke
				(width 0.1)
				(type default)
			)
			(layer "B.Fab")
		)
		(pad "1" smd circle
			(at 0.40005 0 180)
			(size 0 0)
			(layers "B.Cu" "B.Mask" "B.Paste")
			(net "P1V8_PLL0_PEX1")
		)
		(pad "2" smd circle
			(at -0.40005 0 180)
			(size 0 0)
			(layers "B.Cu" "B.Mask" "B.Paste")
			(net "GND")
		)
	)
	(footprint ""
		(layer "B.Cu")
		(at 252.0188 -347.7768 180)
		(property "Reference" "PR7161"
			(at 0 0 0)
			(layer "B.SilkS")
			(hide yes)
			(effects
				(font
					(size 1.27 1.27)
				)
				(justify mirror)
			)
		)
		(property "Value" ""
			(at 0 0 0)
			(layer "B.Fab")
			(effects
				(font
					(size 1.27 1.27)
				)
				(justify mirror)
			)
		)
		(duplicate_pad_numbers_are_jumpers no)
		(fp_line
			(start 0.7874 0.4064)
			(end 0.7874 -0.4064)
			(stroke
				(width 0.1524)
				(type default)
			)
			(layer "B.SilkS")
		)
		(fp_line
			(start 0.7874 -0.4064)
			(end -0.7874 -0.4064)
			(stroke
				(width 0.1524)
				(type default)
			)
			(layer "B.SilkS")
		)
		(fp_line
			(start -0.7874 0.4064)
			(end 0.7874 0.4064)
			(stroke
				(width 0.1524)
				(type default)
			)
			(layer "B.SilkS")
		)
		(fp_line
			(start -0.7874 -0.4064)
			(end -0.7874 0.4064)
			(stroke
				(width 0.1524)
				(type default)
			)
			(layer "B.SilkS")
		)
		(fp_line
			(start 0.67945 0.3048)
			(end 0.67945 -0.305054)
			(stroke
				(width 0.1)
				(type default)
			)
			(layer "B.Fab")
		)
		(fp_line
			(start 0.67945 -0.305054)
			(end 0.12065 -0.305054)
			(stroke
				(width 0.1)
				(type default)
			)
			(layer "B.Fab")
		)
		(fp_line
			(start 0.12065 0.3048)
			(end 0.67945 0.3048)
			(stroke
				(width 0.1)
				(type default)
			)
			(layer "B.Fab")
		)
		(fp_line
			(start 0.12065 0.2794)
			(end 0.12065 0.3048)
			(stroke
				(width 0.1)
				(type default)
			)
			(layer "B.Fab")
		)
		(fp_line
			(start 0.12065 -0.2794)
			(end -0.12065 -0.2794)
			(stroke
				(width 0.1)
				(type default)
			)
			(layer "B.Fab")
		)
		(fp_line
			(start 0.12065 -0.305054)
			(end 0.12065 -0.2794)
			(stroke
				(width 0.1)
				(type default)
			)
			(layer "B.Fab")
		)
		(fp_line
			(start -0.120396 0.3048)
			(end -0.120396 0.2794)
			(stroke
				(width 0.1)
				(type default)
			)
			(layer "B.Fab")
		)
		(fp_line
			(start -0.120396 0.2794)
			(end 0.12065 0.2794)
			(stroke
				(width 0.1)
				(type default)
			)
			(layer "B.Fab")
		)
		(fp_line
			(start -0.12065 -0.2794)
			(end -0.12065 -0.3048)
			(stroke
				(width 0.1)
				(type default)
			)
			(layer "B.Fab")
		)
		(fp_line
			(start -0.12065 -0.3048)
			(end -0.67945 -0.3048)
			(stroke
				(width 0.1)
				(type default)
			)
			(layer "B.Fab")
		)
		(fp_line
			(start -0.67945 0.3048)
			(end -0.120396 0.3048)
			(stroke
				(width 0.1)
				(type default)
			)
			(layer "B.Fab")
		)
		(fp_line
			(start -0.67945 -0.3048)
			(end -0.67945 0.3048)
			(stroke
				(width 0.1)
				(type default)
			)
			(layer "B.Fab")
		)
		(pad "1" smd circle
			(at 0.40005 0)
			(size 0 0)
			(layers "B.Cu" "B.Mask" "B.Paste")
			(net "IRQ_HSC_FAULT_R_N")
		)
		(pad "2" smd circle
			(at -0.40005 0)
			(size 0 0)
			(layers "B.Cu" "B.Mask" "B.Paste")
			(net "FM_HSC_FAULT_N")
		)
	)
	(footprint ""
		(layer "B.Cu")
		(at 222.212154 -196.991732 90)
		(property "Reference" "R463"
			(at 0 0 90)
			(layer "B.SilkS")
			(hide yes)
			(effects
				(font
					(size 1.27 1.27)
				)
				(justify mirror)
			)
		)
		(property "Value" ""
			(at 0 0 90)
			(layer "B.Fab")
			(effects
				(font
					(size 1.27 1.27)
				)
				(justify mirror)
			)
		)
		(duplicate_pad_numbers_are_jumpers no)
		(fp_line
			(start 0.7874 -0.4064)
			(end -0.7874 -0.4064)
			(stroke
				(width 0.1524)
				(type default)
			)
			(layer "B.SilkS")
		)
		(fp_line
			(start -0.7874 -0.4064)
			(end -0.7874 0.4064)
			(stroke
				(width 0.1524)
				(type default)
			)
			(layer "B.SilkS")
		)
		(fp_line
			(start 0.7874 0.4064)
			(end 0.7874 -0.4064)
			(stroke
				(width 0.1524)
				(type default)
			)
			(layer "B.SilkS")
		)
		(fp_line
			(start -0.7874 0.4064)
			(end 0.7874 0.4064)
			(stroke
				(width 0.1524)
				(type default)
			)
			(layer "B.SilkS")
		)
		(fp_line
			(start 0.67945 -0.305054)
			(end 0.12065 -0.305054)
			(stroke
				(width 0.1)
				(type default)
			)
			(layer "B.Fab")
		)
		(fp_line
			(start 0.12065 -0.305054)
			(end 0.12065 -0.2794)
			(stroke
				(width 0.1)
				(type default)
			)
			(layer "B.Fab")
		)
		(fp_line
			(start -0.12065 -0.3048)
			(end -0.67945 -0.3048)
			(stroke
				(width 0.1)
				(type default)
			)
			(layer "B.Fab")
		)
		(fp_line
			(start -0.67945 -0.3048)
			(end -0.67945 0.3048)
			(stroke
				(width 0.1)
				(type default)
			)
			(layer "B.Fab")
		)
		(fp_line
			(start 0.12065 -0.2794)
			(end -0.12065 -0.2794)
			(stroke
				(width 0.1)
				(type default)
			)
			(layer "B.Fab")
		)
		(fp_line
			(start -0.12065 -0.2794)
			(end -0.12065 -0.3048)
			(stroke
				(width 0.1)
				(type default)
			)
			(layer "B.Fab")
		)
		(fp_line
			(start 0.12065 0.2794)
			(end 0.12065 0.3048)
			(stroke
				(width 0.1)
				(type default)
			)
			(layer "B.Fab")
		)
		(fp_line
			(start -0.120396 0.2794)
			(end 0.12065 0.2794)
			(stroke
				(width 0.1)
				(type default)
			)
			(layer "B.Fab")
		)
		(fp_line
			(start 0.67945 0.3048)
			(end 0.67945 -0.305054)
			(stroke
				(width 0.1)
				(type default)
			)
			(layer "B.Fab")
		)
		(fp_line
			(start 0.12065 0.3048)
			(end 0.67945 0.3048)
			(stroke
				(width 0.1)
				(type default)
			)
			(layer "B.Fab")
		)
		(fp_line
			(start -0.120396 0.3048)
			(end -0.120396 0.2794)
			(stroke
				(width 0.1)
				(type default)
			)
			(layer "B.Fab")
		)
		(fp_line
			(start -0.67945 0.3048)
			(end -0.120396 0.3048)
			(stroke
				(width 0.1)
				(type default)
			)
			(layer "B.Fab")
		)
		(pad "1" smd circle
			(at 0.40005 0 270)
			(size 0 0)
			(layers "B.Cu" "B.Mask" "B.Paste")
			(net "SPI_BIC1_MOSI_R")
		)
		(pad "2" smd circle
			(at -0.40005 0 270)
			(size 0 0)
			(layers "B.Cu" "B.Mask" "B.Paste")
			(net "SPI_BIC1_MOSI_R1")
		)
	)
	(footprint ""
		(layer "B.Cu")
		(at 329.692 -223.4692)
		(property "Reference" "R4170"
			(at 0 0 0)
			(layer "B.SilkS")
			(hide yes)
			(effects
				(font
					(size 1.27 1.27)
				)
				(justify mirror)
			)
		)
		(property "Value" ""
			(at 0 0 0)
			(layer "B.Fab")
			(effects
				(font
					(size 1.27 1.27)
				)
				(justify mirror)
			)
		)
		(duplicate_pad_numbers_are_jumpers no)
		(fp_line
			(start -0.7874 -0.4064)
			(end -0.7874 0.4064)
			(stroke
				(width 0.1524)
				(type default)
			)
			(layer "B.SilkS")
		)
		(fp_line
			(start -0.7874 0.4064)
			(end 0.7874 0.4064)
			(stroke
				(width 0.1524)
				(type default)
			)
			(layer "B.SilkS")
		)
		(fp_line
			(start 0.7874 -0.4064)
			(end -0.7874 -0.4064)
			(stroke
				(width 0.1524)
				(type default)
			)
			(layer "B.SilkS")
		)
		(fp_line
			(start 0.7874 0.4064)
			(end 0.7874 -0.4064)
			(stroke
				(width 0.1524)
				(type default)
			)
			(layer "B.SilkS")
		)
		(fp_line
			(start -0.67945 -0.3048)
			(end -0.67945 0.3048)
			(stroke
				(width 0.1)
				(type default)
			)
			(layer "B.Fab")
		)
		(fp_line
			(start -0.67945 0.3048)
			(end -0.120396 0.3048)
			(stroke
				(width 0.1)
				(type default)
			)
			(layer "B.Fab")
		)
		(fp_line
			(start -0.12065 -0.3048)
			(end -0.67945 -0.3048)
			(stroke
				(width 0.1)
				(type default)
			)
			(layer "B.Fab")
		)
		(fp_line
			(start -0.12065 -0.2794)
			(end -0.12065 -0.3048)
			(stroke
				(width 0.1)
				(type default)
			)
			(layer "B.Fab")
		)
		(fp_line
			(start -0.120396 0.2794)
			(end 0.12065 0.2794)
			(stroke
				(width 0.1)
				(type default)
			)
			(layer "B.Fab")
		)
		(fp_line
			(start -0.120396 0.3048)
			(end -0.120396 0.2794)
			(stroke
				(width 0.1)
				(type default)
			)
			(layer "B.Fab")
		)
		(fp_line
			(start 0.12065 -0.305054)
			(end 0.12065 -0.2794)
			(stroke
				(width 0.1)
				(type default)
			)
			(layer "B.Fab")
		)
		(fp_line
			(start 0.12065 -0.2794)
			(end -0.12065 -0.2794)
			(stroke
				(width 0.1)
				(type default)
			)
			(layer "B.Fab")
		)
		(fp_line
			(start 0.12065 0.2794)
			(end 0.12065 0.3048)
			(stroke
				(width 0.1)
				(type default)
			)
			(layer "B.Fab")
		)
		(fp_line
			(start 0.12065 0.3048)
			(end 0.67945 0.3048)
			(stroke
				(width 0.1)
				(type default)
			)
			(layer "B.Fab")
		)
		(fp_line
			(start 0.67945 -0.305054)
			(end 0.12065 -0.305054)
			(stroke
				(width 0.1)
				(type default)
			)
			(layer "B.Fab")
		)
		(fp_line
			(start 0.67945 0.3048)
			(end 0.67945 -0.305054)
			(stroke
				(width 0.1)
				(type default)
			)
			(layer "B.Fab")
		)
		(pad "1" smd circle
			(at 0.40005 0 180)
			(size 0 0)
			(layers "B.Cu" "B.Mask" "B.Paste")
			(net "FM_SYS_THROTTLE")
		)
		(pad "2" smd circle
			(at -0.40005 0 180)
			(size 0 0)
			(layers "B.Cu" "B.Mask" "B.Paste")
			(net "FM_SYS_THROTTLE_R")
		)
	)
	(footprint ""
		(layer "B.Cu")
		(at 348.98838 -316.868048 180)
		(property "Reference" "C4322"
			(at 0 0 0)
			(layer "B.SilkS")
			(hide yes)
			(effects
				(font
					(size 1.27 1.27)
				)
				(justify mirror)
			)
		)
		(property "Value" ""
			(at 0 0 0)
			(layer "B.Fab")
			(effects
				(font
					(size 1.27 1.27)
				)
				(justify mirror)
			)
		)
		(duplicate_pad_numbers_are_jumpers no)
		(fp_line
			(start 0.299974 0.150114)
			(end 0.299974 -0.150114)
			(stroke
				(width 0.1)
				(type default)
			)
			(layer "B.Fab")
		)
		(fp_line
			(start 0.299974 -0.150114)
			(end -0.299974 -0.150114)
			(stroke
				(width 0.1)
				(type default)
			)
			(layer "B.Fab")
		)
		(fp_line
			(start -0.299974 0.150114)
			(end 0.299974 0.150114)
			(stroke
				(width 0.1)
				(type default)
			)
			(layer "B.Fab")
		)
		(fp_line
			(start -0.299974 -0.150114)
			(end -0.299974 0.150114)
			(stroke
				(width 0.1)
				(type default)
			)
			(layer "B.Fab")
		)
		(pad "1" smd rect
			(at 0.2667 0)
			(size 0.3048 0.381)
			(layers "B.Cu" "B.Mask" "B.Paste")
			(net "P0V8_SERDES_VDDA_PEX2")
		)
		(pad "2" smd rect
			(at -0.2667 0)
			(size 0.3048 0.381)
			(layers "B.Cu" "B.Mask" "B.Paste")
			(net "GND")
		)
	)
	(footprint ""
		(layer "B.Cu")
		(at 337.221322 -303.649634 -90)
		(property "Reference" "PC168"
			(at 0 0 90)
			(layer "B.SilkS")
			(hide yes)
			(effects
				(font
					(size 1.27 1.27)
				)
				(justify mirror)
			)
		)
		(property "Value" ""
			(at 0 0 90)
			(layer "B.Fab")
			(effects
				(font
					(size 1.27 1.27)
				)
				(justify mirror)
			)
		)
		(duplicate_pad_numbers_are_jumpers no)
		(fp_line
			(start -1.524 0.762)
			(end 1.524 0.762)
			(stroke
				(width 0.1524)
				(type default)
			)
			(layer "B.SilkS")
		)
		(fp_line
			(start 1.524 0.762)
			(end 1.524 -0.762)
			(stroke
				(width 0.1524)
				(type default)
			)
			(layer "B.SilkS")
		)
		(fp_line
			(start -1.524 -0.762)
			(end -1.524 0.762)
			(stroke
				(width 0.1524)
				(type default)
			)
			(layer "B.SilkS")
		)
		(fp_line
			(start 1.524 -0.762)
			(end -1.524 -0.762)
			(stroke
				(width 0.1524)
				(type default)
			)
			(layer "B.SilkS")
		)
		(fp_line
			(start -1.1049 0.724916)
			(end -1.1049 -0.724916)
			(stroke
				(width 0.1)
				(type default)
			)
			(layer "B.Fab")
		)
		(fp_line
			(start 1.1049 0.724916)
			(end -1.1049 0.724916)
			(stroke
				(width 0.1)
				(type default)
			)
			(layer "B.Fab")
		)
		(fp_line
			(start -1.1049 -0.724916)
			(end 1.1049 -0.724916)
			(stroke
				(width 0.1)
				(type default)
			)
			(layer "B.Fab")
		)
		(fp_line
			(start 1.1049 -0.724916)
			(end 1.1049 0.724916)
			(stroke
				(width 0.1)
				(type default)
			)
			(layer "B.Fab")
		)
		(pad "1" smd rect
			(at 0.889 0 270)
			(size 1.016 1.27)
			(layers "B.Cu" "B.Mask" "B.Paste")
			(net "P0V8_PEX2")
		)
		(pad "2" smd rect
			(at -0.889 0 270)
			(size 1.016 1.27)
			(layers "B.Cu" "B.Mask" "B.Paste")
			(net "GND")
		)
	)
	(footprint ""
		(layer "B.Cu")
		(at 290.89985 -303.499774 -90)
		(property "Reference" "C3280"
			(at 0 0 90)
			(layer "B.SilkS")
			(hide yes)
			(effects
				(font
					(size 1.27 1.27)
				)
				(justify mirror)
			)
		)
		(property "Value" ""
			(at 0 0 90)
			(layer "B.Fab")
			(effects
				(font
					(size 1.27 1.27)
				)
				(justify mirror)
			)
		)
		(duplicate_pad_numbers_are_jumpers no)
		(fp_line
			(start -0.299974 0.150114)
			(end 0.299974 0.150114)
			(stroke
				(width 0.1)
				(type default)
			)
			(layer "B.Fab")
		)
		(fp_line
			(start 0.299974 0.150114)
			(end 0.299974 -0.150114)
			(stroke
				(width 0.1)
				(type default)
			)
			(layer "B.Fab")
		)
		(fp_line
			(start -0.299974 -0.150114)
			(end -0.299974 0.150114)
			(stroke
				(width 0.1)
				(type default)
			)
			(layer "B.Fab")
		)
		(fp_line
			(start 0.299974 -0.150114)
			(end -0.299974 -0.150114)
			(stroke
				(width 0.1)
				(type default)
			)
			(layer "B.Fab")
		)
		(pad "1" smd rect
			(at 0.2667 0 90)
			(size 0.3048 0.381)
			(layers "B.Cu" "B.Mask" "B.Paste")
			(net "P1V25_PEX2")
		)
		(pad "2" smd rect
			(at -0.2667 0 90)
			(size 0.3048 0.381)
			(layers "B.Cu" "B.Mask" "B.Paste")
			(net "GND")
		)
	)
	(footprint ""
		(layer "B.Cu")
		(at 458.540866 -272.91792 180)
		(property "Reference" "C4403"
			(at 0 0 0)
			(layer "B.SilkS")
			(hide yes)
			(effects
				(font
					(size 1.27 1.27)
				)
				(justify mirror)
			)
		)
		(property "Value" ""
			(at 0 0 0)
			(layer "B.Fab")
			(effects
				(font
					(size 1.27 1.27)
				)
				(justify mirror)
			)
		)
		(duplicate_pad_numbers_are_jumpers no)
		(fp_line
			(start 1.2954 0.5842)
			(end 1.2954 -0.5842)
			(stroke
				(width 0.1524)
				(type default)
			)
			(layer "B.SilkS")
		)
		(fp_line
			(start 1.2954 -0.5842)
			(end -1.2954 -0.5842)
			(stroke
				(width 0.1524)
				(type default)
			)
			(layer "B.SilkS")
		)
		(fp_line
			(start -1.2954 0.5842)
			(end 1.2954 0.5842)
			(stroke
				(width 0.1524)
				(type default)
			)
			(layer "B.SilkS")
		)
		(fp_line
			(start -1.2954 -0.5842)
			(end -1.2954 0.5842)
			(stroke
				(width 0.1524)
				(type default)
			)
			(layer "B.SilkS")
		)
		(fp_line
			(start 1.1938 0.4064)
			(end 1.1938 -0.4064)
			(stroke
				(width 0.1)
				(type default)
			)
			(layer "B.Fab")
		)
		(fp_line
			(start 1.1938 -0.4064)
			(end 0.8636 -0.4064)
			(stroke
				(width 0.1)
				(type default)
			)
			(layer "B.Fab")
		)
		(fp_line
			(start 0.8636 0.4572)
			(end 0.8636 0.4064)
			(stroke
				(width 0.1)
				(type default)
			)
			(layer "B.Fab")
		)
		(fp_line
			(start 0.8636 0.4064)
			(end 1.1938 0.4064)
			(stroke
				(width 0.1)
				(type default)
			)
			(layer "B.Fab")
		)
		(fp_line
			(start 0.8636 -0.4064)
			(end 0.8636 -0.4572)
			(stroke
				(width 0.1)
				(type default)
			)
			(layer "B.Fab")
		)
		(fp_line
			(start 0.8636 -0.4572)
			(end -0.8636 -0.4572)
			(stroke
				(width 0.1)
				(type default)
			)
			(layer "B.Fab")
		)
		(fp_line
			(start -0.8636 0.4572)
			(end 0.8636 0.4572)
			(stroke
				(width 0.1)
				(type default)
			)
			(layer "B.Fab")
		)
		(fp_line
			(start -0.8636 0.4064)
			(end -0.8636 0.4572)
			(stroke
				(width 0.1)
				(type default)
			)
			(layer "B.Fab")
		)
		(fp_line
			(start -0.8636 -0.4064)
			(end -1.1938 -0.4064)
			(stroke
				(width 0.1)
				(type default)
			)
			(layer "B.Fab")
		)
		(fp_line
			(start -0.8636 -0.4572)
			(end -0.8636 -0.4064)
			(stroke
				(width 0.1)
				(type default)
			)
			(layer "B.Fab")
		)
		(fp_line
			(start -1.1938 0.4064)
			(end -0.8636 0.4064)
			(stroke
				(width 0.1)
				(type default)
			)
			(layer "B.Fab")
		)
		(fp_line
			(start -1.1938 -0.4064)
			(end -1.1938 0.4064)
			(stroke
				(width 0.1)
				(type default)
			)
			(layer "B.Fab")
		)
		(pad "1" smd rect
			(at 0.7366 0 90)
			(size 0.7112 0.8128)
			(layers "B.Cu" "B.Mask" "B.Paste")
			(net "P1V25_PEX3")
		)
		(pad "2" smd rect
			(at -0.7366 0 90)
			(size 0.7112 0.8128)
			(layers "B.Cu" "B.Mask" "B.Paste")
			(net "GND")
		)
	)
	(footprint ""
		(layer "B.Cu")
		(at 251.140722 -366.83696 180)
		(property "Reference" "PR6609"
			(at 0 0 0)
			(layer "B.SilkS")
			(hide yes)
			(effects
				(font
					(size 1.27 1.27)
				)
				(justify mirror)
			)
		)
		(property "Value" ""
			(at 0 0 0)
			(layer "B.Fab")
			(effects
				(font
					(size 1.27 1.27)
				)
				(justify mirror)
			)
		)
		(duplicate_pad_numbers_are_jumpers no)
		(fp_line
			(start 0.7874 0.4064)
			(end 0.7874 -0.4064)
			(stroke
				(width 0.1524)
				(type default)
			)
			(layer "B.SilkS")
		)
		(fp_line
			(start 0.7874 -0.4064)
			(end -0.7874 -0.4064)
			(stroke
				(width 0.1524)
				(type default)
			)
			(layer "B.SilkS")
		)
		(fp_line
			(start -0.7874 0.4064)
			(end 0.7874 0.4064)
			(stroke
				(width 0.1524)
				(type default)
			)
			(layer "B.SilkS")
		)
		(fp_line
			(start -0.7874 -0.4064)
			(end -0.7874 0.4064)
			(stroke
				(width 0.1524)
				(type default)
			)
			(layer "B.SilkS")
		)
		(fp_line
			(start 0.67945 0.3048)
			(end 0.67945 -0.305054)
			(stroke
				(width 0.1)
				(type default)
			)
			(layer "B.Fab")
		)
		(fp_line
			(start 0.67945 -0.305054)
			(end 0.12065 -0.305054)
			(stroke
				(width 0.1)
				(type default)
			)
			(layer "B.Fab")
		)
		(fp_line
			(start 0.12065 0.3048)
			(end 0.67945 0.3048)
			(stroke
				(width 0.1)
				(type default)
			)
			(layer "B.Fab")
		)
		(fp_line
			(start 0.12065 0.2794)
			(end 0.12065 0.3048)
			(stroke
				(width 0.1)
				(type default)
			)
			(layer "B.Fab")
		)
		(fp_line
			(start 0.12065 -0.2794)
			(end -0.12065 -0.2794)
			(stroke
				(width 0.1)
				(type default)
			)
			(layer "B.Fab")
		)
		(fp_line
			(start 0.12065 -0.305054)
			(end 0.12065 -0.2794)
			(stroke
				(width 0.1)
				(type default)
			)
			(layer "B.Fab")
		)
		(fp_line
			(start -0.120396 0.3048)
			(end -0.120396 0.2794)
			(stroke
				(width 0.1)
				(type default)
			)
			(layer "B.Fab")
		)
		(fp_line
			(start -0.120396 0.2794)
			(end 0.12065 0.2794)
			(stroke
				(width 0.1)
				(type default)
			)
			(layer "B.Fab")
		)
		(fp_line
			(start -0.12065 -0.2794)
			(end -0.12065 -0.3048)
			(stroke
				(width 0.1)
				(type default)
			)
			(layer "B.Fab")
		)
		(fp_line
			(start -0.12065 -0.3048)
			(end -0.67945 -0.3048)
			(stroke
				(width 0.1)
				(type default)
			)
			(layer "B.Fab")
		)
		(fp_line
			(start -0.67945 0.3048)
			(end -0.120396 0.3048)
			(stroke
				(width 0.1)
				(type default)
			)
			(layer "B.Fab")
		)
		(fp_line
			(start -0.67945 -0.3048)
			(end -0.67945 0.3048)
			(stroke
				(width 0.1)
				(type default)
			)
			(layer "B.Fab")
		)
		(pad "1" smd circle
			(at 0.40005 0)
			(size 0 0)
			(layers "B.Cu" "B.Mask" "B.Paste")
			(net "P12V_HSC_GATE2")
		)
		(pad "2" smd circle
			(at -0.40005 0)
			(size 0 0)
			(layers "B.Cu" "B.Mask" "B.Paste")
			(net "HS_GATE2_R_2")
		)
	)
	(footprint ""
		(layer "B.Cu")
		(at 171.949872 -292.099746 90)
		(property "Reference" "C1471"
			(at 0 0 90)
			(layer "B.SilkS")
			(hide yes)
			(effects
				(font
					(size 1.27 1.27)
				)
				(justify mirror)
			)
		)
		(property "Value" ""
			(at 0 0 90)
			(layer "B.Fab")
			(effects
				(font
					(size 1.27 1.27)
				)
				(justify mirror)
			)
		)
		(duplicate_pad_numbers_are_jumpers no)
		(fp_line
			(start 0.299974 -0.150114)
			(end -0.299974 -0.150114)
			(stroke
				(width 0.1)
				(type default)
			)
			(layer "B.Fab")
		)
		(fp_line
			(start -0.299974 -0.150114)
			(end -0.299974 0.150114)
			(stroke
				(width 0.1)
				(type default)
			)
			(layer "B.Fab")
		)
		(fp_line
			(start 0.299974 0.150114)
			(end 0.299974 -0.150114)
			(stroke
				(width 0.1)
				(type default)
			)
			(layer "B.Fab")
		)
		(fp_line
			(start -0.299974 0.150114)
			(end 0.299974 0.150114)
			(stroke
				(width 0.1)
				(type default)
			)
			(layer "B.Fab")
		)
		(pad "1" smd rect
			(at 0.2667 0 270)
			(size 0.3048 0.381)
			(layers "B.Cu" "B.Mask" "B.Paste")
			(net "P0V8_SERDES_VDDA_PEX1")
		)
		(pad "2" smd rect
			(at -0.2667 0 270)
			(size 0.3048 0.381)
			(layers "B.Cu" "B.Mask" "B.Paste")
			(net "GND")
		)
	)
	(footprint ""
		(layer "B.Cu")
		(at 217.235786 -221.350586)
		(property "Reference" "R1487"
			(at 0 0 0)
			(layer "B.SilkS")
			(hide yes)
			(effects
				(font
					(size 1.27 1.27)
				)
				(justify mirror)
			)
		)
		(property "Value" ""
			(at 0 0 0)
			(layer "B.Fab")
			(effects
				(font
					(size 1.27 1.27)
				)
				(justify mirror)
			)
		)
		(duplicate_pad_numbers_are_jumpers no)
		(fp_line
			(start -0.7874 -0.4064)
			(end -0.7874 0.4064)
			(stroke
				(width 0.1524)
				(type default)
			)
			(layer "B.SilkS")
		)
		(fp_line
			(start -0.7874 0.4064)
			(end 0.7874 0.4064)
			(stroke
				(width 0.1524)
				(type default)
			)
			(layer "B.SilkS")
		)
		(fp_line
			(start 0.7874 -0.4064)
			(end -0.7874 -0.4064)
			(stroke
				(width 0.1524)
				(type default)
			)
			(layer "B.SilkS")
		)
		(fp_line
			(start 0.7874 0.4064)
			(end 0.7874 -0.4064)
			(stroke
				(width 0.1524)
				(type default)
			)
			(layer "B.SilkS")
		)
		(fp_line
			(start -0.67945 -0.3048)
			(end -0.67945 0.3048)
			(stroke
				(width 0.1)
				(type default)
			)
			(layer "B.Fab")
		)
		(fp_line
			(start -0.67945 0.3048)
			(end -0.120396 0.3048)
			(stroke
				(width 0.1)
				(type default)
			)
			(layer "B.Fab")
		)
		(fp_line
			(start -0.12065 -0.3048)
			(end -0.67945 -0.3048)
			(stroke
				(width 0.1)
				(type default)
			)
			(layer "B.Fab")
		)
		(fp_line
			(start -0.12065 -0.2794)
			(end -0.12065 -0.3048)
			(stroke
				(width 0.1)
				(type default)
			)
			(layer "B.Fab")
		)
		(fp_line
			(start -0.120396 0.2794)
			(end 0.12065 0.2794)
			(stroke
				(width 0.1)
				(type default)
			)
			(layer "B.Fab")
		)
		(fp_line
			(start -0.120396 0.3048)
			(end -0.120396 0.2794)
			(stroke
				(width 0.1)
				(type default)
			)
			(layer "B.Fab")
		)
		(fp_line
			(start 0.12065 -0.305054)
			(end 0.12065 -0.2794)
			(stroke
				(width 0.1)
				(type default)
			)
			(layer "B.Fab")
		)
		(fp_line
			(start 0.12065 -0.2794)
			(end -0.12065 -0.2794)
			(stroke
				(width 0.1)
				(type default)
			)
			(layer "B.Fab")
		)
		(fp_line
			(start 0.12065 0.2794)
			(end 0.12065 0.3048)
			(stroke
				(width 0.1)
				(type default)
			)
			(layer "B.Fab")
		)
		(fp_line
			(start 0.12065 0.3048)
			(end 0.67945 0.3048)
			(stroke
				(width 0.1)
				(type default)
			)
			(layer "B.Fab")
		)
		(fp_line
			(start 0.67945 -0.305054)
			(end 0.12065 -0.305054)
			(stroke
				(width 0.1)
				(type default)
			)
			(layer "B.Fab")
		)
		(fp_line
			(start 0.67945 0.3048)
			(end 0.67945 -0.305054)
			(stroke
				(width 0.1)
				(type default)
			)
			(layer "B.Fab")
		)
		(pad "1" smd circle
			(at 0.40005 0 180)
			(size 0 0)
			(layers "B.Cu" "B.Mask" "B.Paste")
			(net "SMB_BIC_FPGA_SCL")
		)
		(pad "2" smd circle
			(at -0.40005 0 180)
			(size 0 0)
			(layers "B.Cu" "B.Mask" "B.Paste")
			(net "SMB_BIC_FPGA_R_SCL")
		)
	)
	(footprint ""
		(layer "B.Cu")
		(at 244.782086 -286.538162 180)
		(property "Reference" "PC252"
			(at 0 0 0)
			(layer "B.SilkS")
			(hide yes)
			(effects
				(font
					(size 1.27 1.27)
				)
				(justify mirror)
			)
		)
		(property "Value" ""
			(at 0 0 0)
			(layer "B.Fab")
			(effects
				(font
					(size 1.27 1.27)
				)
				(justify mirror)
			)
		)
		(duplicate_pad_numbers_are_jumpers no)
		(fp_line
			(start 1.524 0.762)
			(end 1.524 -0.762)
			(stroke
				(width 0.1524)
				(type default)
			)
			(layer "B.SilkS")
		)
		(fp_line
			(start 1.524 -0.762)
			(end -1.524 -0.762)
			(stroke
				(width 0.1524)
				(type default)
			)
			(layer "B.SilkS")
		)
		(fp_line
			(start -1.524 0.762)
			(end 1.524 0.762)
			(stroke
				(width 0.1524)
				(type default)
			)
			(layer "B.SilkS")
		)
		(fp_line
			(start -1.524 -0.762)
			(end -1.524 0.762)
			(stroke
				(width 0.1524)
				(type default)
			)
			(layer "B.SilkS")
		)
		(fp_line
			(start 1.1049 0.724916)
			(end -1.1049 0.724916)
			(stroke
				(width 0.1)
				(type default)
			)
			(layer "B.Fab")
		)
		(fp_line
			(start 1.1049 -0.724916)
			(end 1.1049 0.724916)
			(stroke
				(width 0.1)
				(type default)
			)
			(layer "B.Fab")
		)
		(fp_line
			(start -1.1049 0.724916)
			(end -1.1049 -0.724916)
			(stroke
				(width 0.1)
				(type default)
			)
			(layer "B.Fab")
		)
		(fp_line
			(start -1.1049 -0.724916)
			(end 1.1049 -0.724916)
			(stroke
				(width 0.1)
				(type default)
			)
			(layer "B.Fab")
		)
		(pad "1" smd rect
			(at 0.889 0 180)
			(size 1.016 1.27)
			(layers "B.Cu" "B.Mask" "B.Paste")
			(net "P1V25_PEX2_R")
		)
		(pad "2" smd rect
			(at -0.889 0 180)
			(size 1.016 1.27)
			(layers "B.Cu" "B.Mask" "B.Paste")
			(net "GND")
		)
	)
	(footprint ""
		(layer "B.Cu")
		(at 134.808214 -213.524846 180)
		(property "Reference" "R994"
			(at 0 0 0)
			(layer "B.SilkS")
			(hide yes)
			(effects
				(font
					(size 1.27 1.27)
				)
				(justify mirror)
			)
		)
		(property "Value" ""
			(at 0 0 0)
			(layer "B.Fab")
			(effects
				(font
					(size 1.27 1.27)
				)
				(justify mirror)
			)
		)
		(duplicate_pad_numbers_are_jumpers no)
		(fp_line
			(start 0.7874 0.4064)
			(end 0.7874 -0.4064)
			(stroke
				(width 0.1524)
				(type default)
			)
			(layer "B.SilkS")
		)
		(fp_line
			(start 0.7874 -0.4064)
			(end -0.7874 -0.4064)
			(stroke
				(width 0.1524)
				(type default)
			)
			(layer "B.SilkS")
		)
		(fp_line
			(start -0.7874 0.4064)
			(end 0.7874 0.4064)
			(stroke
				(width 0.1524)
				(type default)
			)
			(layer "B.SilkS")
		)
		(fp_line
			(start -0.7874 -0.4064)
			(end -0.7874 0.4064)
			(stroke
				(width 0.1524)
				(type default)
			)
			(layer "B.SilkS")
		)
		(fp_line
			(start 0.67945 0.3048)
			(end 0.67945 -0.305054)
			(stroke
				(width 0.1)
				(type default)
			)
			(layer "B.Fab")
		)
		(fp_line
			(start 0.67945 -0.305054)
			(end 0.12065 -0.305054)
			(stroke
				(width 0.1)
				(type default)
			)
			(layer "B.Fab")
		)
		(fp_line
			(start 0.12065 0.3048)
			(end 0.67945 0.3048)
			(stroke
				(width 0.1)
				(type default)
			)
			(layer "B.Fab")
		)
		(fp_line
			(start 0.12065 0.2794)
			(end 0.12065 0.3048)
			(stroke
				(width 0.1)
				(type default)
			)
			(layer "B.Fab")
		)
		(fp_line
			(start 0.12065 -0.2794)
			(end -0.12065 -0.2794)
			(stroke
				(width 0.1)
				(type default)
			)
			(layer "B.Fab")
		)
		(fp_line
			(start 0.12065 -0.305054)
			(end 0.12065 -0.2794)
			(stroke
				(width 0.1)
				(type default)
			)
			(layer "B.Fab")
		)
		(fp_line
			(start -0.120396 0.3048)
			(end -0.120396 0.2794)
			(stroke
				(width 0.1)
				(type default)
			)
			(layer "B.Fab")
		)
		(fp_line
			(start -0.120396 0.2794)
			(end 0.12065 0.2794)
			(stroke
				(width 0.1)
				(type default)
			)
			(layer "B.Fab")
		)
		(fp_line
			(start -0.12065 -0.2794)
			(end -0.12065 -0.3048)
			(stroke
				(width 0.1)
				(type default)
			)
			(layer "B.Fab")
		)
		(fp_line
			(start -0.12065 -0.3048)
			(end -0.67945 -0.3048)
			(stroke
				(width 0.1)
				(type default)
			)
			(layer "B.Fab")
		)
		(fp_line
			(start -0.67945 0.3048)
			(end -0.120396 0.3048)
			(stroke
				(width 0.1)
				(type default)
			)
			(layer "B.Fab")
		)
		(fp_line
			(start -0.67945 -0.3048)
			(end -0.67945 0.3048)
			(stroke
				(width 0.1)
				(type default)
			)
			(layer "B.Fab")
		)
		(pad "1" smd circle
			(at 0.40005 0)
			(size 0 0)
			(layers "B.Cu" "B.Mask" "B.Paste")
			(net "UART_PEX2_CLI_BUF_TX")
		)
		(pad "2" smd circle
			(at -0.40005 0)
			(size 0 0)
			(layers "B.Cu" "B.Mask" "B.Paste")
			(net "P3V3_AUX")
		)
	)
	(footprint ""
		(layer "B.Cu")
		(at 272.373598 -296.9514 180)
		(property "Reference" "R3474"
			(at 0 0 0)
			(layer "B.SilkS")
			(hide yes)
			(effects
				(font
					(size 1.27 1.27)
				)
				(justify mirror)
			)
		)
		(property "Value" ""
			(at 0 0 0)
			(layer "B.Fab")
			(effects
				(font
					(size 1.27 1.27)
				)
				(justify mirror)
			)
		)
		(duplicate_pad_numbers_are_jumpers no)
		(fp_line
			(start 0.7874 0.4064)
			(end 0.7874 -0.4064)
			(stroke
				(width 0.1524)
				(type default)
			)
			(layer "B.SilkS")
		)
		(fp_line
			(start 0.7874 -0.4064)
			(end -0.7874 -0.4064)
			(stroke
				(width 0.1524)
				(type default)
			)
			(layer "B.SilkS")
		)
		(fp_line
			(start -0.7874 0.4064)
			(end 0.7874 0.4064)
			(stroke
				(width 0.1524)
				(type default)
			)
			(layer "B.SilkS")
		)
		(fp_line
			(start -0.7874 -0.4064)
			(end -0.7874 0.4064)
			(stroke
				(width 0.1524)
				(type default)
			)
			(layer "B.SilkS")
		)
		(fp_line
			(start 0.67945 0.3048)
			(end 0.67945 -0.305054)
			(stroke
				(width 0.1)
				(type default)
			)
			(layer "B.Fab")
		)
		(fp_line
			(start 0.67945 -0.305054)
			(end 0.12065 -0.305054)
			(stroke
				(width 0.1)
				(type default)
			)
			(layer "B.Fab")
		)
		(fp_line
			(start 0.12065 0.3048)
			(end 0.67945 0.3048)
			(stroke
				(width 0.1)
				(type default)
			)
			(layer "B.Fab")
		)
		(fp_line
			(start 0.12065 0.2794)
			(end 0.12065 0.3048)
			(stroke
				(width 0.1)
				(type default)
			)
			(layer "B.Fab")
		)
		(fp_line
			(start 0.12065 -0.2794)
			(end -0.12065 -0.2794)
			(stroke
				(width 0.1)
				(type default)
			)
			(layer "B.Fab")
		)
		(fp_line
			(start 0.12065 -0.305054)
			(end 0.12065 -0.2794)
			(stroke
				(width 0.1)
				(type default)
			)
			(layer "B.Fab")
		)
		(fp_line
			(start -0.120396 0.3048)
			(end -0.120396 0.2794)
			(stroke
				(width 0.1)
				(type default)
			)
			(layer "B.Fab")
		)
		(fp_line
			(start -0.120396 0.2794)
			(end 0.12065 0.2794)
			(stroke
				(width 0.1)
				(type default)
			)
			(layer "B.Fab")
		)
		(fp_line
			(start -0.12065 -0.2794)
			(end -0.12065 -0.3048)
			(stroke
				(width 0.1)
				(type default)
			)
			(layer "B.Fab")
		)
		(fp_line
			(start -0.12065 -0.3048)
			(end -0.67945 -0.3048)
			(stroke
				(width 0.1)
				(type default)
			)
			(layer "B.Fab")
		)
		(fp_line
			(start -0.67945 0.3048)
			(end -0.120396 0.3048)
			(stroke
				(width 0.1)
				(type default)
			)
			(layer "B.Fab")
		)
		(fp_line
			(start -0.67945 -0.3048)
			(end -0.67945 0.3048)
			(stroke
				(width 0.1)
				(type default)
			)
			(layer "B.Fab")
		)
		(pad "1" smd circle
			(at 0.40005 0)
			(size 0 0)
			(layers "B.Cu" "B.Mask" "B.Paste")
			(net "SPI_PEX2_SDIO1_R")
		)
		(pad "2" smd circle
			(at -0.40005 0)
			(size 0 0)
			(layers "B.Cu" "B.Mask" "B.Paste")
			(net "SPI_PEX2_SDIO1")
		)
	)
	(footprint ""
		(layer "B.Cu")
		(at 235.871512 -234.728004 90)
		(property "Reference" "R6196"
			(at 0 0 90)
			(layer "B.SilkS")
			(hide yes)
			(effects
				(font
					(size 1.27 1.27)
				)
				(justify mirror)
			)
		)
		(property "Value" ""
			(at 0 0 90)
			(layer "B.Fab")
			(effects
				(font
					(size 1.27 1.27)
				)
				(justify mirror)
			)
		)
		(duplicate_pad_numbers_are_jumpers no)
		(fp_line
			(start 0.7874 -0.4064)
			(end -0.7874 -0.4064)
			(stroke
				(width 0.1524)
				(type default)
			)
			(layer "B.SilkS")
		)
		(fp_line
			(start -0.7874 -0.4064)
			(end -0.7874 0.4064)
			(stroke
				(width 0.1524)
				(type default)
			)
			(layer "B.SilkS")
		)
		(fp_line
			(start 0.7874 0.4064)
			(end 0.7874 -0.4064)
			(stroke
				(width 0.1524)
				(type default)
			)
			(layer "B.SilkS")
		)
		(fp_line
			(start -0.7874 0.4064)
			(end 0.7874 0.4064)
			(stroke
				(width 0.1524)
				(type default)
			)
			(layer "B.SilkS")
		)
		(fp_line
			(start 0.67945 -0.305054)
			(end 0.12065 -0.305054)
			(stroke
				(width 0.1)
				(type default)
			)
			(layer "B.Fab")
		)
		(fp_line
			(start 0.12065 -0.305054)
			(end 0.12065 -0.2794)
			(stroke
				(width 0.1)
				(type default)
			)
			(layer "B.Fab")
		)
		(fp_line
			(start -0.12065 -0.3048)
			(end -0.67945 -0.3048)
			(stroke
				(width 0.1)
				(type default)
			)
			(layer "B.Fab")
		)
		(fp_line
			(start -0.67945 -0.3048)
			(end -0.67945 0.3048)
			(stroke
				(width 0.1)
				(type default)
			)
			(layer "B.Fab")
		)
		(fp_line
			(start 0.12065 -0.2794)
			(end -0.12065 -0.2794)
			(stroke
				(width 0.1)
				(type default)
			)
			(layer "B.Fab")
		)
		(fp_line
			(start -0.12065 -0.2794)
			(end -0.12065 -0.3048)
			(stroke
				(width 0.1)
				(type default)
			)
			(layer "B.Fab")
		)
		(fp_line
			(start 0.12065 0.2794)
			(end 0.12065 0.3048)
			(stroke
				(width 0.1)
				(type default)
			)
			(layer "B.Fab")
		)
		(fp_line
			(start -0.120396 0.2794)
			(end 0.12065 0.2794)
			(stroke
				(width 0.1)
				(type default)
			)
			(layer "B.Fab")
		)
		(fp_line
			(start 0.67945 0.3048)
			(end 0.67945 -0.305054)
			(stroke
				(width 0.1)
				(type default)
			)
			(layer "B.Fab")
		)
		(fp_line
			(start 0.12065 0.3048)
			(end 0.67945 0.3048)
			(stroke
				(width 0.1)
				(type default)
			)
			(layer "B.Fab")
		)
		(fp_line
			(start -0.120396 0.3048)
			(end -0.120396 0.2794)
			(stroke
				(width 0.1)
				(type default)
			)
			(layer "B.Fab")
		)
		(fp_line
			(start -0.67945 0.3048)
			(end -0.120396 0.3048)
			(stroke
				(width 0.1)
				(type default)
			)
			(layer "B.Fab")
		)
		(pad "1" smd circle
			(at 0.40005 0 270)
			(size 0 0)
			(layers "B.Cu" "B.Mask" "B.Paste")
			(net "GND")
		)
		(pad "2" smd circle
			(at -0.40005 0 270)
			(size 0 0)
			(layers "B.Cu" "B.Mask" "B.Paste")
			(net "SSD14_PWRDIS_BIC_R")
		)
	)
	(footprint ""
		(layer "B.Cu")
		(at 4.880102 -285.910782)
		(property "Reference" "PC214"
			(at 0 0 0)
			(layer "B.SilkS")
			(hide yes)
			(effects
				(font
					(size 1.27 1.27)
				)
				(justify mirror)
			)
		)
		(property "Value" ""
			(at 0 0 0)
			(layer "B.Fab")
			(effects
				(font
					(size 1.27 1.27)
				)
				(justify mirror)
			)
		)
		(duplicate_pad_numbers_are_jumpers no)
		(fp_line
			(start -1.524 -0.762)
			(end -1.524 0.762)
			(stroke
				(width 0.1524)
				(type default)
			)
			(layer "B.SilkS")
		)
		(fp_line
			(start -1.524 0.762)
			(end 1.524 0.762)
			(stroke
				(width 0.1524)
				(type default)
			)
			(layer "B.SilkS")
		)
		(fp_line
			(start 1.524 -0.762)
			(end -1.524 -0.762)
			(stroke
				(width 0.1524)
				(type default)
			)
			(layer "B.SilkS")
		)
		(fp_line
			(start 1.524 0.762)
			(end 1.524 -0.762)
			(stroke
				(width 0.1524)
				(type default)
			)
			(layer "B.SilkS")
		)
		(fp_line
			(start -1.1049 -0.724916)
			(end 1.1049 -0.724916)
			(stroke
				(width 0.1)
				(type default)
			)
			(layer "B.Fab")
		)
		(fp_line
			(start -1.1049 0.724916)
			(end -1.1049 -0.724916)
			(stroke
				(width 0.1)
				(type default)
			)
			(layer "B.Fab")
		)
		(fp_line
			(start 1.1049 -0.724916)
			(end 1.1049 0.724916)
			(stroke
				(width 0.1)
				(type default)
			)
			(layer "B.Fab")
		)
		(fp_line
			(start 1.1049 0.724916)
			(end -1.1049 0.724916)
			(stroke
				(width 0.1)
				(type default)
			)
			(layer "B.Fab")
		)
		(pad "1" smd rect
			(at 0.889 0)
			(size 1.016 1.27)
			(layers "B.Cu" "B.Mask" "B.Paste")
			(net "P1V25_PEX0_R")
		)
		(pad "2" smd rect
			(at -0.889 0)
			(size 1.016 1.27)
			(layers "B.Cu" "B.Mask" "B.Paste")
			(net "GND")
		)
	)
	(footprint ""
		(layer "B.Cu")
		(at 134.808214 -212.381846 180)
		(property "Reference" "R983"
			(at 0 0 0)
			(layer "B.SilkS")
			(hide yes)
			(effects
				(font
					(size 1.27 1.27)
				)
				(justify mirror)
			)
		)
		(property "Value" ""
			(at 0 0 0)
			(layer "B.Fab")
			(effects
				(font
					(size 1.27 1.27)
				)
				(justify mirror)
			)
		)
		(duplicate_pad_numbers_are_jumpers no)
		(fp_line
			(start 0.7874 0.4064)
			(end 0.7874 -0.4064)
			(stroke
				(width 0.1524)
				(type default)
			)
			(layer "B.SilkS")
		)
		(fp_line
			(start 0.7874 -0.4064)
			(end -0.7874 -0.4064)
			(stroke
				(width 0.1524)
				(type default)
			)
			(layer "B.SilkS")
		)
		(fp_line
			(start -0.7874 0.4064)
			(end 0.7874 0.4064)
			(stroke
				(width 0.1524)
				(type default)
			)
			(layer "B.SilkS")
		)
		(fp_line
			(start -0.7874 -0.4064)
			(end -0.7874 0.4064)
			(stroke
				(width 0.1524)
				(type default)
			)
			(layer "B.SilkS")
		)
		(fp_line
			(start 0.67945 0.3048)
			(end 0.67945 -0.305054)
			(stroke
				(width 0.1)
				(type default)
			)
			(layer "B.Fab")
		)
		(fp_line
			(start 0.67945 -0.305054)
			(end 0.12065 -0.305054)
			(stroke
				(width 0.1)
				(type default)
			)
			(layer "B.Fab")
		)
		(fp_line
			(start 0.12065 0.3048)
			(end 0.67945 0.3048)
			(stroke
				(width 0.1)
				(type default)
			)
			(layer "B.Fab")
		)
		(fp_line
			(start 0.12065 0.2794)
			(end 0.12065 0.3048)
			(stroke
				(width 0.1)
				(type default)
			)
			(layer "B.Fab")
		)
		(fp_line
			(start 0.12065 -0.2794)
			(end -0.12065 -0.2794)
			(stroke
				(width 0.1)
				(type default)
			)
			(layer "B.Fab")
		)
		(fp_line
			(start 0.12065 -0.305054)
			(end 0.12065 -0.2794)
			(stroke
				(width 0.1)
				(type default)
			)
			(layer "B.Fab")
		)
		(fp_line
			(start -0.120396 0.3048)
			(end -0.120396 0.2794)
			(stroke
				(width 0.1)
				(type default)
			)
			(layer "B.Fab")
		)
		(fp_line
			(start -0.120396 0.2794)
			(end 0.12065 0.2794)
			(stroke
				(width 0.1)
				(type default)
			)
			(layer "B.Fab")
		)
		(fp_line
			(start -0.12065 -0.2794)
			(end -0.12065 -0.3048)
			(stroke
				(width 0.1)
				(type default)
			)
			(layer "B.Fab")
		)
		(fp_line
			(start -0.12065 -0.3048)
			(end -0.67945 -0.3048)
			(stroke
				(width 0.1)
				(type default)
			)
			(layer "B.Fab")
		)
		(fp_line
			(start -0.67945 0.3048)
			(end -0.120396 0.3048)
			(stroke
				(width 0.1)
				(type default)
			)
			(layer "B.Fab")
		)
		(fp_line
			(start -0.67945 -0.3048)
			(end -0.67945 0.3048)
			(stroke
				(width 0.1)
				(type default)
			)
			(layer "B.Fab")
		)
		(pad "1" smd circle
			(at 0.40005 0)
			(size 0 0)
			(layers "B.Cu" "B.Mask" "B.Paste")
			(net "UART_PEX1_CLI_BUF_TX")
		)
		(pad "2" smd circle
			(at -0.40005 0)
			(size 0 0)
			(layers "B.Cu" "B.Mask" "B.Paste")
			(net "P3V3_AUX")
		)
	)
	(footprint ""
		(layer "B.Cu")
		(at 296.599864 -290.199826 90)
		(property "Reference" "C1738"
			(at 0 0 90)
			(layer "B.SilkS")
			(hide yes)
			(effects
				(font
					(size 1.27 1.27)
				)
				(justify mirror)
			)
		)
		(property "Value" ""
			(at 0 0 90)
			(layer "B.Fab")
			(effects
				(font
					(size 1.27 1.27)
				)
				(justify mirror)
			)
		)
		(duplicate_pad_numbers_are_jumpers no)
		(fp_line
			(start 0.299974 -0.150114)
			(end -0.299974 -0.150114)
			(stroke
				(width 0.1)
				(type default)
			)
			(layer "B.Fab")
		)
		(fp_line
			(start -0.299974 -0.150114)
			(end -0.299974 0.150114)
			(stroke
				(width 0.1)
				(type default)
			)
			(layer "B.Fab")
		)
		(fp_line
			(start 0.299974 0.150114)
			(end 0.299974 -0.150114)
			(stroke
				(width 0.1)
				(type default)
			)
			(layer "B.Fab")
		)
		(fp_line
			(start -0.299974 0.150114)
			(end 0.299974 0.150114)
			(stroke
				(width 0.1)
				(type default)
			)
			(layer "B.Fab")
		)
		(pad "1" smd rect
			(at 0.2667 0 270)
			(size 0.3048 0.381)
			(layers "B.Cu" "B.Mask" "B.Paste")
			(net "P0V8_SERDES_VDDA_PEX2")
		)
		(pad "2" smd rect
			(at -0.2667 0 270)
			(size 0.3048 0.381)
			(layers "B.Cu" "B.Mask" "B.Paste")
			(net "GND")
		)
	)
	(footprint ""
		(layer "B.Cu")
		(at 128.41097 -176.08423)
		(property "Reference" "C2655"
			(at 0 0 0)
			(layer "B.SilkS")
			(hide yes)
			(effects
				(font
					(size 1.27 1.27)
				)
				(justify mirror)
			)
		)
		(property "Value" ""
			(at 0 0 0)
			(layer "B.Fab")
			(effects
				(font
					(size 1.27 1.27)
				)
				(justify mirror)
			)
		)
		(duplicate_pad_numbers_are_jumpers no)
		(fp_line
			(start -1.2954 -0.5842)
			(end -1.2954 0.5842)
			(stroke
				(width 0.1524)
				(type default)
			)
			(layer "B.SilkS")
		)
		(fp_line
			(start -1.2954 0.5842)
			(end 1.2954 0.5842)
			(stroke
				(width 0.1524)
				(type default)
			)
			(layer "B.SilkS")
		)
		(fp_line
			(start 1.2954 -0.5842)
			(end -1.2954 -0.5842)
			(stroke
				(width 0.1524)
				(type default)
			)
			(layer "B.SilkS")
		)
		(fp_line
			(start 1.2954 0.5842)
			(end 1.2954 -0.5842)
			(stroke
				(width 0.1524)
				(type default)
			)
			(layer "B.SilkS")
		)
		(fp_line
			(start -1.1938 -0.4064)
			(end -1.1938 0.4064)
			(stroke
				(width 0.1)
				(type default)
			)
			(layer "B.Fab")
		)
		(fp_line
			(start -1.1938 0.4064)
			(end -0.8636 0.4064)
			(stroke
				(width 0.1)
				(type default)
			)
			(layer "B.Fab")
		)
		(fp_line
			(start -0.8636 -0.4572)
			(end -0.8636 -0.4064)
			(stroke
				(width 0.1)
				(type default)
			)
			(layer "B.Fab")
		)
		(fp_line
			(start -0.8636 -0.4064)
			(end -1.1938 -0.4064)
			(stroke
				(width 0.1)
				(type default)
			)
			(layer "B.Fab")
		)
		(fp_line
			(start -0.8636 0.4064)
			(end -0.8636 0.4572)
			(stroke
				(width 0.1)
				(type default)
			)
			(layer "B.Fab")
		)
		(fp_line
			(start -0.8636 0.4572)
			(end 0.8636 0.4572)
			(stroke
				(width 0.1)
				(type default)
			)
			(layer "B.Fab")
		)
		(fp_line
			(start 0.8636 -0.4572)
			(end -0.8636 -0.4572)
			(stroke
				(width 0.1)
				(type default)
			)
			(layer "B.Fab")
		)
		(fp_line
			(start 0.8636 -0.4064)
			(end 0.8636 -0.4572)
			(stroke
				(width 0.1)
				(type default)
			)
			(layer "B.Fab")
		)
		(fp_line
			(start 0.8636 0.4064)
			(end 1.1938 0.4064)
			(stroke
				(width 0.1)
				(type default)
			)
			(layer "B.Fab")
		)
		(fp_line
			(start 0.8636 0.4572)
			(end 0.8636 0.4064)
			(stroke
				(width 0.1)
				(type default)
			)
			(layer "B.Fab")
		)
		(fp_line
			(start 1.1938 -0.4064)
			(end 0.8636 -0.4064)
			(stroke
				(width 0.1)
				(type default)
			)
			(layer "B.Fab")
		)
		(fp_line
			(start 1.1938 0.4064)
			(end 1.1938 -0.4064)
			(stroke
				(width 0.1)
				(type default)
			)
			(layer "B.Fab")
		)
		(pad "1" smd rect
			(at 0.7366 0 270)
			(size 0.7112 0.8128)
			(layers "B.Cu" "B.Mask" "B.Paste")
			(net "P3V3_DB2000QL_VDDR")
		)
		(pad "2" smd rect
			(at -0.7366 0 270)
			(size 0.7112 0.8128)
			(layers "B.Cu" "B.Mask" "B.Paste")
			(net "GND")
		)
	)
	(footprint ""
		(layer "B.Cu")
		(at 309.741824 -100.056696 180)
		(property "Reference" "R281"
			(at 0 0 0)
			(layer "B.SilkS")
			(hide yes)
			(effects
				(font
					(size 1.27 1.27)
				)
				(justify mirror)
			)
		)
		(property "Value" ""
			(at 0 0 0)
			(layer "B.Fab")
			(effects
				(font
					(size 1.27 1.27)
				)
				(justify mirror)
			)
		)
		(duplicate_pad_numbers_are_jumpers no)
		(fp_line
			(start 0.7874 0.4064)
			(end 0.7874 -0.4064)
			(stroke
				(width 0.1524)
				(type default)
			)
			(layer "B.SilkS")
		)
		(fp_line
			(start 0.7874 -0.4064)
			(end -0.7874 -0.4064)
			(stroke
				(width 0.1524)
				(type default)
			)
			(layer "B.SilkS")
		)
		(fp_line
			(start -0.7874 0.4064)
			(end 0.7874 0.4064)
			(stroke
				(width 0.1524)
				(type default)
			)
			(layer "B.SilkS")
		)
		(fp_line
			(start -0.7874 -0.4064)
			(end -0.7874 0.4064)
			(stroke
				(width 0.1524)
				(type default)
			)
			(layer "B.SilkS")
		)
		(fp_line
			(start 0.67945 0.3048)
			(end 0.67945 -0.305054)
			(stroke
				(width 0.1)
				(type default)
			)
			(layer "B.Fab")
		)
		(fp_line
			(start 0.67945 -0.305054)
			(end 0.12065 -0.305054)
			(stroke
				(width 0.1)
				(type default)
			)
			(layer "B.Fab")
		)
		(fp_line
			(start 0.12065 0.3048)
			(end 0.67945 0.3048)
			(stroke
				(width 0.1)
				(type default)
			)
			(layer "B.Fab")
		)
		(fp_line
			(start 0.12065 0.2794)
			(end 0.12065 0.3048)
			(stroke
				(width 0.1)
				(type default)
			)
			(layer "B.Fab")
		)
		(fp_line
			(start 0.12065 -0.2794)
			(end -0.12065 -0.2794)
			(stroke
				(width 0.1)
				(type default)
			)
			(layer "B.Fab")
		)
		(fp_line
			(start 0.12065 -0.305054)
			(end 0.12065 -0.2794)
			(stroke
				(width 0.1)
				(type default)
			)
			(layer "B.Fab")
		)
		(fp_line
			(start -0.120396 0.3048)
			(end -0.120396 0.2794)
			(stroke
				(width 0.1)
				(type default)
			)
			(layer "B.Fab")
		)
		(fp_line
			(start -0.120396 0.2794)
			(end 0.12065 0.2794)
			(stroke
				(width 0.1)
				(type default)
			)
			(layer "B.Fab")
		)
		(fp_line
			(start -0.12065 -0.2794)
			(end -0.12065 -0.3048)
			(stroke
				(width 0.1)
				(type default)
			)
			(layer "B.Fab")
		)
		(fp_line
			(start -0.12065 -0.3048)
			(end -0.67945 -0.3048)
			(stroke
				(width 0.1)
				(type default)
			)
			(layer "B.Fab")
		)
		(fp_line
			(start -0.67945 0.3048)
			(end -0.120396 0.3048)
			(stroke
				(width 0.1)
				(type default)
			)
			(layer "B.Fab")
		)
		(fp_line
			(start -0.67945 -0.3048)
			(end -0.67945 0.3048)
			(stroke
				(width 0.1)
				(type default)
			)
			(layer "B.Fab")
		)
		(pad "1" smd circle
			(at 0.40005 0)
			(size 0 0)
			(layers "B.Cu" "B.Mask" "B.Paste")
			(net "NIC5_SLOT_ID0")
		)
		(pad "2" smd circle
			(at -0.40005 0)
			(size 0 0)
			(layers "B.Cu" "B.Mask" "B.Paste")
			(net "GND")
		)
	)
	(footprint ""
		(layer "B.Cu")
		(at 52.999894 -290.199826 90)
		(property "Reference" "C1186"
			(at 0 0 90)
			(layer "B.SilkS")
			(hide yes)
			(effects
				(font
					(size 1.27 1.27)
				)
				(justify mirror)
			)
		)
		(property "Value" ""
			(at 0 0 90)
			(layer "B.Fab")
			(effects
				(font
					(size 1.27 1.27)
				)
				(justify mirror)
			)
		)
		(duplicate_pad_numbers_are_jumpers no)
		(fp_line
			(start 0.299974 -0.150114)
			(end -0.299974 -0.150114)
			(stroke
				(width 0.1)
				(type default)
			)
			(layer "B.Fab")
		)
		(fp_line
			(start -0.299974 -0.150114)
			(end -0.299974 0.150114)
			(stroke
				(width 0.1)
				(type default)
			)
			(layer "B.Fab")
		)
		(fp_line
			(start 0.299974 0.150114)
			(end 0.299974 -0.150114)
			(stroke
				(width 0.1)
				(type default)
			)
			(layer "B.Fab")
		)
		(fp_line
			(start -0.299974 0.150114)
			(end 0.299974 0.150114)
			(stroke
				(width 0.1)
				(type default)
			)
			(layer "B.Fab")
		)
		(pad "1" smd rect
			(at 0.2667 0 270)
			(size 0.3048 0.381)
			(layers "B.Cu" "B.Mask" "B.Paste")
			(net "P0V8_SERDES_VDDA_PEX0")
		)
		(pad "2" smd rect
			(at -0.2667 0 270)
			(size 0.3048 0.381)
			(layers "B.Cu" "B.Mask" "B.Paste")
			(net "GND")
		)
	)
	(footprint ""
		(layer "B.Cu")
		(at 385.943602 -235.89996 180)
		(property "Reference" "C2581"
			(at 0 0 0)
			(layer "B.SilkS")
			(hide yes)
			(effects
				(font
					(size 1.27 1.27)
				)
				(justify mirror)
			)
		)
		(property "Value" ""
			(at 0 0 0)
			(layer "B.Fab")
			(effects
				(font
					(size 1.27 1.27)
				)
				(justify mirror)
			)
		)
		(duplicate_pad_numbers_are_jumpers no)
		(fp_line
			(start 1.2954 0.5842)
			(end 1.2954 -0.5842)
			(stroke
				(width 0.1524)
				(type default)
			)
			(layer "B.SilkS")
		)
		(fp_line
			(start 1.2954 -0.5842)
			(end -1.2954 -0.5842)
			(stroke
				(width 0.1524)
				(type default)
			)
			(layer "B.SilkS")
		)
		(fp_line
			(start -1.2954 0.5842)
			(end 1.2954 0.5842)
			(stroke
				(width 0.1524)
				(type default)
			)
			(layer "B.SilkS")
		)
		(fp_line
			(start -1.2954 -0.5842)
			(end -1.2954 0.5842)
			(stroke
				(width 0.1524)
				(type default)
			)
			(layer "B.SilkS")
		)
		(fp_line
			(start 1.1938 0.4064)
			(end 1.1938 -0.4064)
			(stroke
				(width 0.1)
				(type default)
			)
			(layer "B.Fab")
		)
		(fp_line
			(start 1.1938 -0.4064)
			(end 0.8636 -0.4064)
			(stroke
				(width 0.1)
				(type default)
			)
			(layer "B.Fab")
		)
		(fp_line
			(start 0.8636 0.4572)
			(end 0.8636 0.4064)
			(stroke
				(width 0.1)
				(type default)
			)
			(layer "B.Fab")
		)
		(fp_line
			(start 0.8636 0.4064)
			(end 1.1938 0.4064)
			(stroke
				(width 0.1)
				(type default)
			)
			(layer "B.Fab")
		)
		(fp_line
			(start 0.8636 -0.4064)
			(end 0.8636 -0.4572)
			(stroke
				(width 0.1)
				(type default)
			)
			(layer "B.Fab")
		)
		(fp_line
			(start 0.8636 -0.4572)
			(end -0.8636 -0.4572)
			(stroke
				(width 0.1)
				(type default)
			)
			(layer "B.Fab")
		)
		(fp_line
			(start -0.8636 0.4572)
			(end 0.8636 0.4572)
			(stroke
				(width 0.1)
				(type default)
			)
			(layer "B.Fab")
		)
		(fp_line
			(start -0.8636 0.4064)
			(end -0.8636 0.4572)
			(stroke
				(width 0.1)
				(type default)
			)
			(layer "B.Fab")
		)
		(fp_line
			(start -0.8636 -0.4064)
			(end -1.1938 -0.4064)
			(stroke
				(width 0.1)
				(type default)
			)
			(layer "B.Fab")
		)
		(fp_line
			(start -0.8636 -0.4572)
			(end -0.8636 -0.4064)
			(stroke
				(width 0.1)
				(type default)
			)
			(layer "B.Fab")
		)
		(fp_line
			(start -1.1938 0.4064)
			(end -0.8636 0.4064)
			(stroke
				(width 0.1)
				(type default)
			)
			(layer "B.Fab")
		)
		(fp_line
			(start -1.1938 -0.4064)
			(end -1.1938 0.4064)
			(stroke
				(width 0.1)
				(type default)
			)
			(layer "B.Fab")
		)
		(pad "1" smd rect
			(at 0.7366 0 90)
			(size 0.7112 0.8128)
			(layers "B.Cu" "B.Mask" "B.Paste")
			(net "P3V3_SDB_VPLL")
		)
		(pad "2" smd rect
			(at -0.7366 0 90)
			(size 0.7112 0.8128)
			(layers "B.Cu" "B.Mask" "B.Paste")
			(net "GND")
		)
	)
	(footprint ""
		(layer "B.Cu")
		(at 132.826506 -321.834764 -90)
		(property "Reference" "R6487"
			(at 0 0 90)
			(layer "B.SilkS")
			(hide yes)
			(effects
				(font
					(size 1.27 1.27)
				)
				(justify mirror)
			)
		)
		(property "Value" ""
			(at 0 0 90)
			(layer "B.Fab")
			(effects
				(font
					(size 1.27 1.27)
				)
				(justify mirror)
			)
		)
		(duplicate_pad_numbers_are_jumpers no)
		(fp_line
			(start -0.7874 0.4064)
			(end 0.7874 0.4064)
			(stroke
				(width 0.1524)
				(type default)
			)
			(layer "B.SilkS")
		)
		(fp_line
			(start 0.7874 0.4064)
			(end 0.7874 -0.4064)
			(stroke
				(width 0.1524)
				(type default)
			)
			(layer "B.SilkS")
		)
		(fp_line
			(start -0.7874 -0.4064)
			(end -0.7874 0.4064)
			(stroke
				(width 0.1524)
				(type default)
			)
			(layer "B.SilkS")
		)
		(fp_line
			(start 0.7874 -0.4064)
			(end -0.7874 -0.4064)
			(stroke
				(width 0.1524)
				(type default)
			)
			(layer "B.SilkS")
		)
		(fp_line
			(start -0.67945 0.3048)
			(end -0.120396 0.3048)
			(stroke
				(width 0.1)
				(type default)
			)
			(layer "B.Fab")
		)
		(fp_line
			(start -0.120396 0.3048)
			(end -0.120396 0.2794)
			(stroke
				(width 0.1)
				(type default)
			)
			(layer "B.Fab")
		)
		(fp_line
			(start 0.12065 0.3048)
			(end 0.67945 0.3048)
			(stroke
				(width 0.1)
				(type default)
			)
			(layer "B.Fab")
		)
		(fp_line
			(start 0.67945 0.3048)
			(end 0.67945 -0.305054)
			(stroke
				(width 0.1)
				(type default)
			)
			(layer "B.Fab")
		)
		(fp_line
			(start -0.120396 0.2794)
			(end 0.12065 0.2794)
			(stroke
				(width 0.1)
				(type default)
			)
			(layer "B.Fab")
		)
		(fp_line
			(start 0.12065 0.2794)
			(end 0.12065 0.3048)
			(stroke
				(width 0.1)
				(type default)
			)
			(layer "B.Fab")
		)
		(fp_line
			(start -0.12065 -0.2794)
			(end -0.12065 -0.3048)
			(stroke
				(width 0.1)
				(type default)
			)
			(layer "B.Fab")
		)
		(fp_line
			(start 0.12065 -0.2794)
			(end -0.12065 -0.2794)
			(stroke
				(width 0.1)
				(type default)
			)
			(layer "B.Fab")
		)
		(fp_line
			(start -0.67945 -0.3048)
			(end -0.67945 0.3048)
			(stroke
				(width 0.1)
				(type default)
			)
			(layer "B.Fab")
		)
		(fp_line
			(start -0.12065 -0.3048)
			(end -0.67945 -0.3048)
			(stroke
				(width 0.1)
				(type default)
			)
			(layer "B.Fab")
		)
		(fp_line
			(start 0.12065 -0.305054)
			(end 0.12065 -0.2794)
			(stroke
				(width 0.1)
				(type default)
			)
			(layer "B.Fab")
		)
		(fp_line
			(start 0.67945 -0.305054)
			(end 0.12065 -0.305054)
			(stroke
				(width 0.1)
				(type default)
			)
			(layer "B.Fab")
		)
		(pad "1" smd circle
			(at 0.40005 0 90)
			(size 0 0)
			(layers "B.Cu" "B.Mask" "B.Paste")
			(net "P0V8_SERDES_VDDA_PEX1")
		)
		(pad "2" smd circle
			(at -0.40005 0 90)
			(size 0 0)
			(layers "B.Cu" "B.Mask" "B.Paste")
			(net "P0V8_SERDES_VDDA_PEX1_C10")
		)
	)
	(footprint ""
		(layer "B.Cu")
		(at 51.099974 -299.699934 -90)
		(property "Reference" "C1177"
			(at 0 0 90)
			(layer "B.SilkS")
			(hide yes)
			(effects
				(font
					(size 1.27 1.27)
				)
				(justify mirror)
			)
		)
		(property "Value" ""
			(at 0 0 90)
			(layer "B.Fab")
			(effects
				(font
					(size 1.27 1.27)
				)
				(justify mirror)
			)
		)
		(duplicate_pad_numbers_are_jumpers no)
		(fp_line
			(start -0.299974 0.150114)
			(end 0.299974 0.150114)
			(stroke
				(width 0.1)
				(type default)
			)
			(layer "B.Fab")
		)
		(fp_line
			(start 0.299974 0.150114)
			(end 0.299974 -0.150114)
			(stroke
				(width 0.1)
				(type default)
			)
			(layer "B.Fab")
		)
		(fp_line
			(start -0.299974 -0.150114)
			(end -0.299974 0.150114)
			(stroke
				(width 0.1)
				(type default)
			)
			(layer "B.Fab")
		)
		(fp_line
			(start 0.299974 -0.150114)
			(end -0.299974 -0.150114)
			(stroke
				(width 0.1)
				(type default)
			)
			(layer "B.Fab")
		)
		(pad "1" smd rect
			(at 0.2667 0 90)
			(size 0.3048 0.381)
			(layers "B.Cu" "B.Mask" "B.Paste")
			(net "P0V8_SERDES_VDDA_PEX0")
		)
		(pad "2" smd rect
			(at -0.2667 0 90)
			(size 0.3048 0.381)
			(layers "B.Cu" "B.Mask" "B.Paste")
			(net "GND")
		)
	)
	(footprint ""
		(layer "B.Cu")
		(at 15.748762 -385.723384 180)
		(property "Reference" "C4473"
			(at 0 0 0)
			(layer "B.SilkS")
			(hide yes)
			(effects
				(font
					(size 1.27 1.27)
				)
				(justify mirror)
			)
		)
		(property "Value" ""
			(at 0 0 0)
			(layer "B.Fab")
			(effects
				(font
					(size 1.27 1.27)
				)
				(justify mirror)
			)
		)
		(duplicate_pad_numbers_are_jumpers no)
		(fp_line
			(start 0.7874 0.4064)
			(end 0.7874 -0.4064)
			(stroke
				(width 0.1524)
				(type default)
			)
			(layer "B.SilkS")
		)
		(fp_line
			(start 0.7874 -0.4064)
			(end -0.7874 -0.4064)
			(stroke
				(width 0.1524)
				(type default)
			)
			(layer "B.SilkS")
		)
		(fp_line
			(start -0.7874 0.4064)
			(end 0.7874 0.4064)
			(stroke
				(width 0.1524)
				(type default)
			)
			(layer "B.SilkS")
		)
		(fp_line
			(start -0.7874 -0.4064)
			(end -0.7874 0.4064)
			(stroke
				(width 0.1524)
				(type default)
			)
			(layer "B.SilkS")
		)
		(fp_line
			(start 0.67945 0.3048)
			(end 0.67945 -0.305054)
			(stroke
				(width 0.1)
				(type default)
			)
			(layer "B.Fab")
		)
		(fp_line
			(start 0.67945 -0.305054)
			(end 0.12065 -0.305054)
			(stroke
				(width 0.1)
				(type default)
			)
			(layer "B.Fab")
		)
		(fp_line
			(start 0.12065 0.3048)
			(end 0.67945 0.3048)
			(stroke
				(width 0.1)
				(type default)
			)
			(layer "B.Fab")
		)
		(fp_line
			(start 0.12065 0.2794)
			(end 0.12065 0.3048)
			(stroke
				(width 0.1)
				(type default)
			)
			(layer "B.Fab")
		)
		(fp_line
			(start 0.12065 -0.2794)
			(end -0.12065 -0.2794)
			(stroke
				(width 0.1)
				(type default)
			)
			(layer "B.Fab")
		)
		(fp_line
			(start 0.12065 -0.305054)
			(end 0.12065 -0.2794)
			(stroke
				(width 0.1)
				(type default)
			)
			(layer "B.Fab")
		)
		(fp_line
			(start -0.120396 0.3048)
			(end -0.120396 0.2794)
			(stroke
				(width 0.1)
				(type default)
			)
			(layer "B.Fab")
		)
		(fp_line
			(start -0.120396 0.2794)
			(end 0.12065 0.2794)
			(stroke
				(width 0.1)
				(type default)
			)
			(layer "B.Fab")
		)
		(fp_line
			(start -0.12065 -0.2794)
			(end -0.12065 -0.3048)
			(stroke
				(width 0.1)
				(type default)
			)
			(layer "B.Fab")
		)
		(fp_line
			(start -0.12065 -0.3048)
			(end -0.67945 -0.3048)
			(stroke
				(width 0.1)
				(type default)
			)
			(layer "B.Fab")
		)
		(fp_line
			(start -0.67945 0.3048)
			(end -0.120396 0.3048)
			(stroke
				(width 0.1)
				(type default)
			)
			(layer "B.Fab")
		)
		(fp_line
			(start -0.67945 -0.3048)
			(end -0.67945 0.3048)
			(stroke
				(width 0.1)
				(type default)
			)
			(layer "B.Fab")
		)
		(pad "1" smd circle
			(at 0.40005 0)
			(size 0 0)
			(layers "B.Cu" "B.Mask" "B.Paste")
			(net "P1V2_USB_8042")
		)
		(pad "2" smd circle
			(at -0.40005 0)
			(size 0 0)
			(layers "B.Cu" "B.Mask" "B.Paste")
			(net "GND")
		)
	)
	(footprint ""
		(layer "B.Cu")
		(at 288.99993 -301.599854 -90)
		(property "Reference" "C1736"
			(at 0 0 90)
			(layer "B.SilkS")
			(hide yes)
			(effects
				(font
					(size 1.27 1.27)
				)
				(justify mirror)
			)
		)
		(property "Value" ""
			(at 0 0 90)
			(layer "B.Fab")
			(effects
				(font
					(size 1.27 1.27)
				)
				(justify mirror)
			)
		)
		(duplicate_pad_numbers_are_jumpers no)
		(fp_line
			(start -0.299974 0.150114)
			(end 0.299974 0.150114)
			(stroke
				(width 0.1)
				(type default)
			)
			(layer "B.Fab")
		)
		(fp_line
			(start 0.299974 0.150114)
			(end 0.299974 -0.150114)
			(stroke
				(width 0.1)
				(type default)
			)
			(layer "B.Fab")
		)
		(fp_line
			(start -0.299974 -0.150114)
			(end -0.299974 0.150114)
			(stroke
				(width 0.1)
				(type default)
			)
			(layer "B.Fab")
		)
		(fp_line
			(start 0.299974 -0.150114)
			(end -0.299974 -0.150114)
			(stroke
				(width 0.1)
				(type default)
			)
			(layer "B.Fab")
		)
		(pad "1" smd rect
			(at 0.2667 0 90)
			(size 0.3048 0.381)
			(layers "B.Cu" "B.Mask" "B.Paste")
			(net "P0V8_SERDES_VDDA_PEX2")
		)
		(pad "2" smd rect
			(at -0.2667 0 90)
			(size 0.3048 0.381)
			(layers "B.Cu" "B.Mask" "B.Paste")
			(net "GND")
		)
	)
	(footprint ""
		(layer "B.Cu")
		(at 227.190046 -153.000202 -90)
		(property "Reference" "C2803"
			(at 0 0 90)
			(layer "B.SilkS")
			(hide yes)
			(effects
				(font
					(size 1.27 1.27)
				)
				(justify mirror)
			)
		)
		(property "Value" ""
			(at 0 0 90)
			(layer "B.Fab")
			(effects
				(font
					(size 1.27 1.27)
				)
				(justify mirror)
			)
		)
		(duplicate_pad_numbers_are_jumpers no)
		(fp_line
			(start -0.7874 0.4064)
			(end 0.7874 0.4064)
			(stroke
				(width 0.1524)
				(type default)
			)
			(layer "B.SilkS")
		)
		(fp_line
			(start 0.7874 0.4064)
			(end 0.7874 -0.4064)
			(stroke
				(width 0.1524)
				(type default)
			)
			(layer "B.SilkS")
		)
		(fp_line
			(start -0.7874 -0.4064)
			(end -0.7874 0.4064)
			(stroke
				(width 0.1524)
				(type default)
			)
			(layer "B.SilkS")
		)
		(fp_line
			(start 0.7874 -0.4064)
			(end -0.7874 -0.4064)
			(stroke
				(width 0.1524)
				(type default)
			)
			(layer "B.SilkS")
		)
		(fp_line
			(start -0.67945 0.3048)
			(end -0.120396 0.3048)
			(stroke
				(width 0.1)
				(type default)
			)
			(layer "B.Fab")
		)
		(fp_line
			(start -0.120396 0.3048)
			(end -0.120396 0.2794)
			(stroke
				(width 0.1)
				(type default)
			)
			(layer "B.Fab")
		)
		(fp_line
			(start 0.12065 0.3048)
			(end 0.67945 0.3048)
			(stroke
				(width 0.1)
				(type default)
			)
			(layer "B.Fab")
		)
		(fp_line
			(start 0.67945 0.3048)
			(end 0.67945 -0.305054)
			(stroke
				(width 0.1)
				(type default)
			)
			(layer "B.Fab")
		)
		(fp_line
			(start -0.120396 0.2794)
			(end 0.12065 0.2794)
			(stroke
				(width 0.1)
				(type default)
			)
			(layer "B.Fab")
		)
		(fp_line
			(start 0.12065 0.2794)
			(end 0.12065 0.3048)
			(stroke
				(width 0.1)
				(type default)
			)
			(layer "B.Fab")
		)
		(fp_line
			(start -0.12065 -0.2794)
			(end -0.12065 -0.3048)
			(stroke
				(width 0.1)
				(type default)
			)
			(layer "B.Fab")
		)
		(fp_line
			(start 0.12065 -0.2794)
			(end -0.12065 -0.2794)
			(stroke
				(width 0.1)
				(type default)
			)
			(layer "B.Fab")
		)
		(fp_line
			(start -0.67945 -0.3048)
			(end -0.67945 0.3048)
			(stroke
				(width 0.1)
				(type default)
			)
			(layer "B.Fab")
		)
		(fp_line
			(start -0.12065 -0.3048)
			(end -0.67945 -0.3048)
			(stroke
				(width 0.1)
				(type default)
			)
			(layer "B.Fab")
		)
		(fp_line
			(start 0.12065 -0.305054)
			(end 0.12065 -0.2794)
			(stroke
				(width 0.1)
				(type default)
			)
			(layer "B.Fab")
		)
		(fp_line
			(start 0.67945 -0.305054)
			(end 0.12065 -0.305054)
			(stroke
				(width 0.1)
				(type default)
			)
			(layer "B.Fab")
		)
		(pad "1" smd circle
			(at 0.40005 0 90)
			(size 0 0)
			(layers "B.Cu" "B.Mask" "B.Paste")
			(net "P3V3_CLK_GEN_VDDMXCK_CK440_PEX")
		)
		(pad "2" smd circle
			(at -0.40005 0 90)
			(size 0 0)
			(layers "B.Cu" "B.Mask" "B.Paste")
			(net "GND")
		)
	)
	(footprint ""
		(layer "B.Cu")
		(at 333.073756 -329.008994 180)
		(property "Reference" "PJ23"
			(at 0 0 0)
			(layer "B.SilkS")
			(hide yes)
			(effects
				(font
					(size 1.27 1.27)
				)
				(justify mirror)
			)
		)
		(property "Value" ""
			(at 0 0 0)
			(layer "B.Fab")
			(effects
				(font
					(size 1.27 1.27)
				)
				(justify mirror)
			)
		)
		(duplicate_pad_numbers_are_jumpers no)
		(pad "1" smd circle
			(at 0.40005 0 270)
			(size 0 0)
			(layers "B.Cu" "B.Mask" "B.Paste")
			(net "VSENSE_P0V8_PEX2_SKT_VRTN")
		)
		(pad "2" smd rect
			(at -0.40005 0 180)
			(size 0.4572 0.508)
			(layers "B.Cu" "B.Mask" "B.Paste")
			(net "SH_P0V8_PEX2_RGND2")
		)
		(zone
			(layer "B.Cu")
			(hatch none 0.5)
			(connect_pads
				(clearance 0)
			)
			(min_thickness 0.25)
			(keepout
				(tracks allowed)
				(vias not_allowed)
				(pads allowed)
				(copperpour not_allowed)
				(footprints allowed)
			)
			(placement
				(enabled no)
				(sheetname "")
			)
			(fill
				(thermal_gap 0.5)
				(thermal_bridge_width 0.5)
				(island_removal_mode 0)
			)
			(polygon
				(pts
					(xy 333.759556 -329.313794) (xy 333.759556 -328.704194) (xy 332.387956 -328.704194) (xy 332.387956 -329.313794)
				)
			)
		)
	)
	(footprint ""
		(layer "B.Cu")
		(at 228.418644 -231.225598 -90)
		(property "Reference" "R4551"
			(at 0 0 90)
			(layer "B.SilkS")
			(hide yes)
			(effects
				(font
					(size 1.27 1.27)
				)
				(justify mirror)
			)
		)
		(property "Value" ""
			(at 0 0 90)
			(layer "B.Fab")
			(effects
				(font
					(size 1.27 1.27)
				)
				(justify mirror)
			)
		)
		(duplicate_pad_numbers_are_jumpers no)
		(fp_line
			(start -0.7874 0.4064)
			(end 0.7874 0.4064)
			(stroke
				(width 0.1524)
				(type default)
			)
			(layer "B.SilkS")
		)
		(fp_line
			(start 0.7874 0.4064)
			(end 0.7874 -0.4064)
			(stroke
				(width 0.1524)
				(type default)
			)
			(layer "B.SilkS")
		)
		(fp_line
			(start -0.7874 -0.4064)
			(end -0.7874 0.4064)
			(stroke
				(width 0.1524)
				(type default)
			)
			(layer "B.SilkS")
		)
		(fp_line
			(start 0.7874 -0.4064)
			(end -0.7874 -0.4064)
			(stroke
				(width 0.1524)
				(type default)
			)
			(layer "B.SilkS")
		)
		(fp_line
			(start -0.67945 0.3048)
			(end -0.120396 0.3048)
			(stroke
				(width 0.1)
				(type default)
			)
			(layer "B.Fab")
		)
		(fp_line
			(start -0.120396 0.3048)
			(end -0.120396 0.2794)
			(stroke
				(width 0.1)
				(type default)
			)
			(layer "B.Fab")
		)
		(fp_line
			(start 0.12065 0.3048)
			(end 0.67945 0.3048)
			(stroke
				(width 0.1)
				(type default)
			)
			(layer "B.Fab")
		)
		(fp_line
			(start 0.67945 0.3048)
			(end 0.67945 -0.305054)
			(stroke
				(width 0.1)
				(type default)
			)
			(layer "B.Fab")
		)
		(fp_line
			(start -0.120396 0.2794)
			(end 0.12065 0.2794)
			(stroke
				(width 0.1)
				(type default)
			)
			(layer "B.Fab")
		)
		(fp_line
			(start 0.12065 0.2794)
			(end 0.12065 0.3048)
			(stroke
				(width 0.1)
				(type default)
			)
			(layer "B.Fab")
		)
		(fp_line
			(start -0.12065 -0.2794)
			(end -0.12065 -0.3048)
			(stroke
				(width 0.1)
				(type default)
			)
			(layer "B.Fab")
		)
		(fp_line
			(start 0.12065 -0.2794)
			(end -0.12065 -0.2794)
			(stroke
				(width 0.1)
				(type default)
			)
			(layer "B.Fab")
		)
		(fp_line
			(start -0.67945 -0.3048)
			(end -0.67945 0.3048)
			(stroke
				(width 0.1)
				(type default)
			)
			(layer "B.Fab")
		)
		(fp_line
			(start -0.12065 -0.3048)
			(end -0.67945 -0.3048)
			(stroke
				(width 0.1)
				(type default)
			)
			(layer "B.Fab")
		)
		(fp_line
			(start 0.12065 -0.305054)
			(end 0.12065 -0.2794)
			(stroke
				(width 0.1)
				(type default)
			)
			(layer "B.Fab")
		)
		(fp_line
			(start 0.67945 -0.305054)
			(end 0.12065 -0.305054)
			(stroke
				(width 0.1)
				(type default)
			)
			(layer "B.Fab")
		)
		(pad "1" smd circle
			(at 0.40005 0 90)
			(size 0 0)
			(layers "B.Cu" "B.Mask" "B.Paste")
			(net "BOARD_ID1")
		)
		(pad "2" smd circle
			(at -0.40005 0 90)
			(size 0 0)
			(layers "B.Cu" "B.Mask" "B.Paste")
			(net "P3V3_AUX")
		)
	)
	(footprint ""
		(layer "B.Cu")
		(at 353.224338 -324.941946 -90)
		(property "Reference" "C4380"
			(at 0 0 90)
			(layer "B.SilkS")
			(hide yes)
			(effects
				(font
					(size 1.27 1.27)
				)
				(justify mirror)
			)
		)
		(property "Value" ""
			(at 0 0 90)
			(layer "B.Fab")
			(effects
				(font
					(size 1.27 1.27)
				)
				(justify mirror)
			)
		)
		(duplicate_pad_numbers_are_jumpers no)
		(fp_line
			(start -1.2954 0.5842)
			(end 1.2954 0.5842)
			(stroke
				(width 0.1524)
				(type default)
			)
			(layer "B.SilkS")
		)
		(fp_line
			(start 1.2954 0.5842)
			(end 1.2954 -0.5842)
			(stroke
				(width 0.1524)
				(type default)
			)
			(layer "B.SilkS")
		)
		(fp_line
			(start -1.2954 -0.5842)
			(end -1.2954 0.5842)
			(stroke
				(width 0.1524)
				(type default)
			)
			(layer "B.SilkS")
		)
		(fp_line
			(start 1.2954 -0.5842)
			(end -1.2954 -0.5842)
			(stroke
				(width 0.1524)
				(type default)
			)
			(layer "B.SilkS")
		)
		(fp_line
			(start -0.8636 0.4572)
			(end 0.8636 0.4572)
			(stroke
				(width 0.1)
				(type default)
			)
			(layer "B.Fab")
		)
		(fp_line
			(start 0.8636 0.4572)
			(end 0.8636 0.4064)
			(stroke
				(width 0.1)
				(type default)
			)
			(layer "B.Fab")
		)
		(fp_line
			(start -1.1938 0.4064)
			(end -0.8636 0.4064)
			(stroke
				(width 0.1)
				(type default)
			)
			(layer "B.Fab")
		)
		(fp_line
			(start -0.8636 0.4064)
			(end -0.8636 0.4572)
			(stroke
				(width 0.1)
				(type default)
			)
			(layer "B.Fab")
		)
		(fp_line
			(start 0.8636 0.4064)
			(end 1.1938 0.4064)
			(stroke
				(width 0.1)
				(type default)
			)
			(layer "B.Fab")
		)
		(fp_line
			(start 1.1938 0.4064)
			(end 1.1938 -0.4064)
			(stroke
				(width 0.1)
				(type default)
			)
			(layer "B.Fab")
		)
		(fp_line
			(start -1.1938 -0.4064)
			(end -1.1938 0.4064)
			(stroke
				(width 0.1)
				(type default)
			)
			(layer "B.Fab")
		)
		(fp_line
			(start -0.8636 -0.4064)
			(end -1.1938 -0.4064)
			(stroke
				(width 0.1)
				(type default)
			)
			(layer "B.Fab")
		)
		(fp_line
			(start 0.8636 -0.4064)
			(end 0.8636 -0.4572)
			(stroke
				(width 0.1)
				(type default)
			)
			(layer "B.Fab")
		)
		(fp_line
			(start 1.1938 -0.4064)
			(end 0.8636 -0.4064)
			(stroke
				(width 0.1)
				(type default)
			)
			(layer "B.Fab")
		)
		(fp_line
			(start -0.8636 -0.4572)
			(end -0.8636 -0.4064)
			(stroke
				(width 0.1)
				(type default)
			)
			(layer "B.Fab")
		)
		(fp_line
			(start 0.8636 -0.4572)
			(end -0.8636 -0.4572)
			(stroke
				(width 0.1)
				(type default)
			)
			(layer "B.Fab")
		)
		(pad "1" smd rect
			(at 0.7366 0 180)
			(size 0.7112 0.8128)
			(layers "B.Cu" "B.Mask" "B.Paste")
			(net "P0V8_SERDES_VDDA_PEX3_C6")
		)
		(pad "2" smd rect
			(at -0.7366 0 180)
			(size 0.7112 0.8128)
			(layers "B.Cu" "B.Mask" "B.Paste")
			(net "GND")
		)
	)
	(footprint ""
		(layer "B.Cu")
		(at 238.443008 -224.424494 90)
		(property "Reference" "R6818"
			(at 0 0 90)
			(layer "B.SilkS")
			(hide yes)
			(effects
				(font
					(size 1.27 1.27)
				)
				(justify mirror)
			)
		)
		(property "Value" ""
			(at 0 0 90)
			(layer "B.Fab")
			(effects
				(font
					(size 1.27 1.27)
				)
				(justify mirror)
			)
		)
		(duplicate_pad_numbers_are_jumpers no)
		(fp_line
			(start 0.7874 -0.4064)
			(end -0.7874 -0.4064)
			(stroke
				(width 0.1524)
				(type default)
			)
			(layer "B.SilkS")
		)
		(fp_line
			(start -0.7874 -0.4064)
			(end -0.7874 0.4064)
			(stroke
				(width 0.1524)
				(type default)
			)
			(layer "B.SilkS")
		)
		(fp_line
			(start 0.7874 0.4064)
			(end 0.7874 -0.4064)
			(stroke
				(width 0.1524)
				(type default)
			)
			(layer "B.SilkS")
		)
		(fp_line
			(start -0.7874 0.4064)
			(end 0.7874 0.4064)
			(stroke
				(width 0.1524)
				(type default)
			)
			(layer "B.SilkS")
		)
		(fp_line
			(start 0.67945 -0.305054)
			(end 0.12065 -0.305054)
			(stroke
				(width 0.1)
				(type default)
			)
			(layer "B.Fab")
		)
		(fp_line
			(start 0.12065 -0.305054)
			(end 0.12065 -0.2794)
			(stroke
				(width 0.1)
				(type default)
			)
			(layer "B.Fab")
		)
		(fp_line
			(start -0.12065 -0.3048)
			(end -0.67945 -0.3048)
			(stroke
				(width 0.1)
				(type default)
			)
			(layer "B.Fab")
		)
		(fp_line
			(start -0.67945 -0.3048)
			(end -0.67945 0.3048)
			(stroke
				(width 0.1)
				(type default)
			)
			(layer "B.Fab")
		)
		(fp_line
			(start 0.12065 -0.2794)
			(end -0.12065 -0.2794)
			(stroke
				(width 0.1)
				(type default)
			)
			(layer "B.Fab")
		)
		(fp_line
			(start -0.12065 -0.2794)
			(end -0.12065 -0.3048)
			(stroke
				(width 0.1)
				(type default)
			)
			(layer "B.Fab")
		)
		(fp_line
			(start 0.12065 0.2794)
			(end 0.12065 0.3048)
			(stroke
				(width 0.1)
				(type default)
			)
			(layer "B.Fab")
		)
		(fp_line
			(start -0.120396 0.2794)
			(end 0.12065 0.2794)
			(stroke
				(width 0.1)
				(type default)
			)
			(layer "B.Fab")
		)
		(fp_line
			(start 0.67945 0.3048)
			(end 0.67945 -0.305054)
			(stroke
				(width 0.1)
				(type default)
			)
			(layer "B.Fab")
		)
		(fp_line
			(start 0.12065 0.3048)
			(end 0.67945 0.3048)
			(stroke
				(width 0.1)
				(type default)
			)
			(layer "B.Fab")
		)
		(fp_line
			(start -0.120396 0.3048)
			(end -0.120396 0.2794)
			(stroke
				(width 0.1)
				(type default)
			)
			(layer "B.Fab")
		)
		(fp_line
			(start -0.67945 0.3048)
			(end -0.120396 0.3048)
			(stroke
				(width 0.1)
				(type default)
			)
			(layer "B.Fab")
		)
		(pad "1" smd circle
			(at 0.40005 0 270)
			(size 0 0)
			(layers "B.Cu" "B.Mask" "B.Paste")
			(net "GND")
		)
		(pad "2" smd circle
			(at -0.40005 0 270)
			(size 0 0)
			(layers "B.Cu" "B.Mask" "B.Paste")
			(net "VR_TYPE_ADC_R")
		)
	)
	(footprint ""
		(layer "B.Cu")
		(at 418.399976 -290.674806 180)
		(property "Reference" "C3514"
			(at 0 0 0)
			(layer "B.SilkS")
			(hide yes)
			(effects
				(font
					(size 1.27 1.27)
				)
				(justify mirror)
			)
		)
		(property "Value" ""
			(at 0 0 0)
			(layer "B.Fab")
			(effects
				(font
					(size 1.27 1.27)
				)
				(justify mirror)
			)
		)
		(duplicate_pad_numbers_are_jumpers no)
		(fp_line
			(start 0.299974 0.150114)
			(end 0.299974 -0.150114)
			(stroke
				(width 0.1)
				(type default)
			)
			(layer "B.Fab")
		)
		(fp_line
			(start 0.299974 -0.150114)
			(end -0.299974 -0.150114)
			(stroke
				(width 0.1)
				(type default)
			)
			(layer "B.Fab")
		)
		(fp_line
			(start -0.299974 0.150114)
			(end 0.299974 0.150114)
			(stroke
				(width 0.1)
				(type default)
			)
			(layer "B.Fab")
		)
		(fp_line
			(start -0.299974 -0.150114)
			(end -0.299974 0.150114)
			(stroke
				(width 0.1)
				(type default)
			)
			(layer "B.Fab")
		)
		(pad "1" smd rect
			(at 0.2667 0)
			(size 0.3048 0.381)
			(layers "B.Cu" "B.Mask" "B.Paste")
			(net "P1V8_PEX")
		)
		(pad "2" smd rect
			(at -0.2667 0)
			(size 0.3048 0.381)
			(layers "B.Cu" "B.Mask" "B.Paste")
			(net "GND")
		)
	)
	(footprint ""
		(layer "B.Cu")
		(at 115.775994 -308.580028 90)
		(property "Reference" "C1160"
			(at 0 0 90)
			(layer "B.SilkS")
			(hide yes)
			(effects
				(font
					(size 1.27 1.27)
				)
				(justify mirror)
			)
		)
		(property "Value" ""
			(at 0 0 90)
			(layer "B.Fab")
			(effects
				(font
					(size 1.27 1.27)
				)
				(justify mirror)
			)
		)
		(duplicate_pad_numbers_are_jumpers no)
		(fp_line
			(start 1.2954 -0.5842)
			(end -1.2954 -0.5842)
			(stroke
				(width 0.1524)
				(type default)
			)
			(layer "B.SilkS")
		)
		(fp_line
			(start -1.2954 -0.5842)
			(end -1.2954 0.5842)
			(stroke
				(width 0.1524)
				(type default)
			)
			(layer "B.SilkS")
		)
		(fp_line
			(start 1.2954 0.5842)
			(end 1.2954 -0.5842)
			(stroke
				(width 0.1524)
				(type default)
			)
			(layer "B.SilkS")
		)
		(fp_line
			(start -1.2954 0.5842)
			(end 1.2954 0.5842)
			(stroke
				(width 0.1524)
				(type default)
			)
			(layer "B.SilkS")
		)
		(fp_line
			(start 0.8636 -0.4572)
			(end -0.8636 -0.4572)
			(stroke
				(width 0.1)
				(type default)
			)
			(layer "B.Fab")
		)
		(fp_line
			(start -0.8636 -0.4572)
			(end -0.8636 -0.4064)
			(stroke
				(width 0.1)
				(type default)
			)
			(layer "B.Fab")
		)
		(fp_line
			(start 1.1938 -0.4064)
			(end 0.8636 -0.4064)
			(stroke
				(width 0.1)
				(type default)
			)
			(layer "B.Fab")
		)
		(fp_line
			(start 0.8636 -0.4064)
			(end 0.8636 -0.4572)
			(stroke
				(width 0.1)
				(type default)
			)
			(layer "B.Fab")
		)
		(fp_line
			(start -0.8636 -0.4064)
			(end -1.1938 -0.4064)
			(stroke
				(width 0.1)
				(type default)
			)
			(layer "B.Fab")
		)
		(fp_line
			(start -1.1938 -0.4064)
			(end -1.1938 0.4064)
			(stroke
				(width 0.1)
				(type default)
			)
			(layer "B.Fab")
		)
		(fp_line
			(start 1.1938 0.4064)
			(end 1.1938 -0.4064)
			(stroke
				(width 0.1)
				(type default)
			)
			(layer "B.Fab")
		)
		(fp_line
			(start 0.8636 0.4064)
			(end 1.1938 0.4064)
			(stroke
				(width 0.1)
				(type default)
			)
			(layer "B.Fab")
		)
		(fp_line
			(start -0.8636 0.4064)
			(end -0.8636 0.4572)
			(stroke
				(width 0.1)
				(type default)
			)
			(layer "B.Fab")
		)
		(fp_line
			(start -1.1938 0.4064)
			(end -0.8636 0.4064)
			(stroke
				(width 0.1)
				(type default)
			)
			(layer "B.Fab")
		)
		(fp_line
			(start 0.8636 0.4572)
			(end 0.8636 0.4064)
			(stroke
				(width 0.1)
				(type default)
			)
			(layer "B.Fab")
		)
		(fp_line
			(start -0.8636 0.4572)
			(end 0.8636 0.4572)
			(stroke
				(width 0.1)
				(type default)
			)
			(layer "B.Fab")
		)
		(pad "1" smd rect
			(at 0.7366 0)
			(size 0.7112 0.8128)
			(layers "B.Cu" "B.Mask" "B.Paste")
			(net "P0V8_SERDES_VDDA_PEX0")
		)
		(pad "2" smd rect
			(at -0.7366 0)
			(size 0.7112 0.8128)
			(layers "B.Cu" "B.Mask" "B.Paste")
			(net "GND")
		)
	)
	(footprint ""
		(layer "B.Cu")
		(at 51.099974 -290.199826 90)
		(property "Reference" "C1184"
			(at 0 0 90)
			(layer "B.SilkS")
			(hide yes)
			(effects
				(font
					(size 1.27 1.27)
				)
				(justify mirror)
			)
		)
		(property "Value" ""
			(at 0 0 90)
			(layer "B.Fab")
			(effects
				(font
					(size 1.27 1.27)
				)
				(justify mirror)
			)
		)
		(duplicate_pad_numbers_are_jumpers no)
		(fp_line
			(start 0.299974 -0.150114)
			(end -0.299974 -0.150114)
			(stroke
				(width 0.1)
				(type default)
			)
			(layer "B.Fab")
		)
		(fp_line
			(start -0.299974 -0.150114)
			(end -0.299974 0.150114)
			(stroke
				(width 0.1)
				(type default)
			)
			(layer "B.Fab")
		)
		(fp_line
			(start 0.299974 0.150114)
			(end 0.299974 -0.150114)
			(stroke
				(width 0.1)
				(type default)
			)
			(layer "B.Fab")
		)
		(fp_line
			(start -0.299974 0.150114)
			(end 0.299974 0.150114)
			(stroke
				(width 0.1)
				(type default)
			)
			(layer "B.Fab")
		)
		(pad "1" smd rect
			(at 0.2667 0 270)
			(size 0.3048 0.381)
			(layers "B.Cu" "B.Mask" "B.Paste")
			(net "P0V8_SERDES_VDDA_PEX0")
		)
		(pad "2" smd rect
			(at -0.2667 0 270)
			(size 0.3048 0.381)
			(layers "B.Cu" "B.Mask" "B.Paste")
			(net "GND")
		)
	)
	(footprint ""
		(layer "B.Cu")
		(at 192.923922 -114.35207 90)
		(property "Reference" "C897"
			(at 0 0 90)
			(layer "B.SilkS")
			(hide yes)
			(effects
				(font
					(size 1.27 1.27)
				)
				(justify mirror)
			)
		)
		(property "Value" ""
			(at 0 0 90)
			(layer "B.Fab")
			(effects
				(font
					(size 1.27 1.27)
				)
				(justify mirror)
			)
		)
		(duplicate_pad_numbers_are_jumpers no)
		(fp_line
			(start 0.7874 -0.4064)
			(end -0.7874 -0.4064)
			(stroke
				(width 0.1524)
				(type default)
			)
			(layer "B.SilkS")
		)
		(fp_line
			(start -0.7874 -0.4064)
			(end -0.7874 0.4064)
			(stroke
				(width 0.1524)
				(type default)
			)
			(layer "B.SilkS")
		)
		(fp_line
			(start 0.7874 0.4064)
			(end 0.7874 -0.4064)
			(stroke
				(width 0.1524)
				(type default)
			)
			(layer "B.SilkS")
		)
		(fp_line
			(start -0.7874 0.4064)
			(end 0.7874 0.4064)
			(stroke
				(width 0.1524)
				(type default)
			)
			(layer "B.SilkS")
		)
		(fp_line
			(start 0.67945 -0.305054)
			(end 0.12065 -0.305054)
			(stroke
				(width 0.1)
				(type default)
			)
			(layer "B.Fab")
		)
		(fp_line
			(start 0.12065 -0.305054)
			(end 0.12065 -0.2794)
			(stroke
				(width 0.1)
				(type default)
			)
			(layer "B.Fab")
		)
		(fp_line
			(start -0.12065 -0.3048)
			(end -0.67945 -0.3048)
			(stroke
				(width 0.1)
				(type default)
			)
			(layer "B.Fab")
		)
		(fp_line
			(start -0.67945 -0.3048)
			(end -0.67945 0.3048)
			(stroke
				(width 0.1)
				(type default)
			)
			(layer "B.Fab")
		)
		(fp_line
			(start 0.12065 -0.2794)
			(end -0.12065 -0.2794)
			(stroke
				(width 0.1)
				(type default)
			)
			(layer "B.Fab")
		)
		(fp_line
			(start -0.12065 -0.2794)
			(end -0.12065 -0.3048)
			(stroke
				(width 0.1)
				(type default)
			)
			(layer "B.Fab")
		)
		(fp_line
			(start 0.12065 0.2794)
			(end 0.12065 0.3048)
			(stroke
				(width 0.1)
				(type default)
			)
			(layer "B.Fab")
		)
		(fp_line
			(start -0.120396 0.2794)
			(end 0.12065 0.2794)
			(stroke
				(width 0.1)
				(type default)
			)
			(layer "B.Fab")
		)
		(fp_line
			(start 0.67945 0.3048)
			(end 0.67945 -0.305054)
			(stroke
				(width 0.1)
				(type default)
			)
			(layer "B.Fab")
		)
		(fp_line
			(start 0.12065 0.3048)
			(end 0.67945 0.3048)
			(stroke
				(width 0.1)
				(type default)
			)
			(layer "B.Fab")
		)
		(fp_line
			(start -0.120396 0.3048)
			(end -0.120396 0.2794)
			(stroke
				(width 0.1)
				(type default)
			)
			(layer "B.Fab")
		)
		(fp_line
			(start -0.67945 0.3048)
			(end -0.120396 0.3048)
			(stroke
				(width 0.1)
				(type default)
			)
			(layer "B.Fab")
		)
		(pad "1" smd circle
			(at 0.40005 0 270)
			(size 0 0)
			(layers "B.Cu" "B.Mask" "B.Paste")
			(net "P3V3_NIC3")
		)
		(pad "2" smd circle
			(at -0.40005 0 270)
			(size 0 0)
			(layers "B.Cu" "B.Mask" "B.Paste")
			(net "GND")
		)
	)
	(footprint ""
		(layer "B.Cu")
		(at 309.02402 -114.35207 90)
		(property "Reference" "C928"
			(at 0 0 90)
			(layer "B.SilkS")
			(hide yes)
			(effects
				(font
					(size 1.27 1.27)
				)
				(justify mirror)
			)
		)
		(property "Value" ""
			(at 0 0 90)
			(layer "B.Fab")
			(effects
				(font
					(size 1.27 1.27)
				)
				(justify mirror)
			)
		)
		(duplicate_pad_numbers_are_jumpers no)
		(fp_line
			(start 0.7874 -0.4064)
			(end -0.7874 -0.4064)
			(stroke
				(width 0.1524)
				(type default)
			)
			(layer "B.SilkS")
		)
		(fp_line
			(start -0.7874 -0.4064)
			(end -0.7874 0.4064)
			(stroke
				(width 0.1524)
				(type default)
			)
			(layer "B.SilkS")
		)
		(fp_line
			(start 0.7874 0.4064)
			(end 0.7874 -0.4064)
			(stroke
				(width 0.1524)
				(type default)
			)
			(layer "B.SilkS")
		)
		(fp_line
			(start -0.7874 0.4064)
			(end 0.7874 0.4064)
			(stroke
				(width 0.1524)
				(type default)
			)
			(layer "B.SilkS")
		)
		(fp_line
			(start 0.67945 -0.305054)
			(end 0.12065 -0.305054)
			(stroke
				(width 0.1)
				(type default)
			)
			(layer "B.Fab")
		)
		(fp_line
			(start 0.12065 -0.305054)
			(end 0.12065 -0.2794)
			(stroke
				(width 0.1)
				(type default)
			)
			(layer "B.Fab")
		)
		(fp_line
			(start -0.12065 -0.3048)
			(end -0.67945 -0.3048)
			(stroke
				(width 0.1)
				(type default)
			)
			(layer "B.Fab")
		)
		(fp_line
			(start -0.67945 -0.3048)
			(end -0.67945 0.3048)
			(stroke
				(width 0.1)
				(type default)
			)
			(layer "B.Fab")
		)
		(fp_line
			(start 0.12065 -0.2794)
			(end -0.12065 -0.2794)
			(stroke
				(width 0.1)
				(type default)
			)
			(layer "B.Fab")
		)
		(fp_line
			(start -0.12065 -0.2794)
			(end -0.12065 -0.3048)
			(stroke
				(width 0.1)
				(type default)
			)
			(layer "B.Fab")
		)
		(fp_line
			(start 0.12065 0.2794)
			(end 0.12065 0.3048)
			(stroke
				(width 0.1)
				(type default)
			)
			(layer "B.Fab")
		)
		(fp_line
			(start -0.120396 0.2794)
			(end 0.12065 0.2794)
			(stroke
				(width 0.1)
				(type default)
			)
			(layer "B.Fab")
		)
		(fp_line
			(start 0.67945 0.3048)
			(end 0.67945 -0.305054)
			(stroke
				(width 0.1)
				(type default)
			)
			(layer "B.Fab")
		)
		(fp_line
			(start 0.12065 0.3048)
			(end 0.67945 0.3048)
			(stroke
				(width 0.1)
				(type default)
			)
			(layer "B.Fab")
		)
		(fp_line
			(start -0.120396 0.3048)
			(end -0.120396 0.2794)
			(stroke
				(width 0.1)
				(type default)
			)
			(layer "B.Fab")
		)
		(fp_line
			(start -0.67945 0.3048)
			(end -0.120396 0.3048)
			(stroke
				(width 0.1)
				(type default)
			)
			(layer "B.Fab")
		)
		(pad "1" smd circle
			(at 0.40005 0 270)
			(size 0 0)
			(layers "B.Cu" "B.Mask" "B.Paste")
			(net "P3V3_NIC5")
		)
		(pad "2" smd circle
			(at -0.40005 0 270)
			(size 0 0)
			(layers "B.Cu" "B.Mask" "B.Paste")
			(net "GND")
		)
	)
	(footprint ""
		(layer "B.Cu")
		(at 397.97482 -297.79976 90)
		(property "Reference" "C1902"
			(at 0 0 90)
			(layer "B.SilkS")
			(hide yes)
			(effects
				(font
					(size 1.27 1.27)
				)
				(justify mirror)
			)
		)
		(property "Value" ""
			(at 0 0 90)
			(layer "B.Fab")
			(effects
				(font
					(size 1.27 1.27)
				)
				(justify mirror)
			)
		)
		(duplicate_pad_numbers_are_jumpers no)
		(fp_line
			(start 0.299974 -0.150114)
			(end -0.299974 -0.150114)
			(stroke
				(width 0.1)
				(type default)
			)
			(layer "B.Fab")
		)
		(fp_line
			(start -0.299974 -0.150114)
			(end -0.299974 0.150114)
			(stroke
				(width 0.1)
				(type default)
			)
			(layer "B.Fab")
		)
		(fp_line
			(start 0.299974 0.150114)
			(end 0.299974 -0.150114)
			(stroke
				(width 0.1)
				(type default)
			)
			(layer "B.Fab")
		)
		(fp_line
			(start -0.299974 0.150114)
			(end 0.299974 0.150114)
			(stroke
				(width 0.1)
				(type default)
			)
			(layer "B.Fab")
		)
		(pad "1" smd rect
			(at 0.2667 0 270)
			(size 0.3048 0.381)
			(layers "B.Cu" "B.Mask" "B.Paste")
			(net "P0V8_PEX3")
		)
		(pad "2" smd rect
			(at -0.2667 0 270)
			(size 0.3048 0.381)
			(layers "B.Cu" "B.Mask" "B.Paste")
			(net "GND")
		)
	)
	(footprint ""
		(layer "B.Cu")
		(at 133.731 -283.818584 90)
		(property "Reference" "PR111"
			(at 0 0 90)
			(layer "B.SilkS")
			(hide yes)
			(effects
				(font
					(size 1.27 1.27)
				)
				(justify mirror)
			)
		)
		(property "Value" ""
			(at 0 0 90)
			(layer "B.Fab")
			(effects
				(font
					(size 1.27 1.27)
				)
				(justify mirror)
			)
		)
		(duplicate_pad_numbers_are_jumpers no)
		(fp_line
			(start 0.7874 -0.4064)
			(end -0.7874 -0.4064)
			(stroke
				(width 0.1524)
				(type default)
			)
			(layer "B.SilkS")
		)
		(fp_line
			(start -0.7874 -0.4064)
			(end -0.7874 0.4064)
			(stroke
				(width 0.1524)
				(type default)
			)
			(layer "B.SilkS")
		)
		(fp_line
			(start 0.7874 0.4064)
			(end 0.7874 -0.4064)
			(stroke
				(width 0.1524)
				(type default)
			)
			(layer "B.SilkS")
		)
		(fp_line
			(start -0.7874 0.4064)
			(end 0.7874 0.4064)
			(stroke
				(width 0.1524)
				(type default)
			)
			(layer "B.SilkS")
		)
		(fp_line
			(start 0.67945 -0.305054)
			(end 0.12065 -0.305054)
			(stroke
				(width 0.1)
				(type default)
			)
			(layer "B.Fab")
		)
		(fp_line
			(start 0.12065 -0.305054)
			(end 0.12065 -0.2794)
			(stroke
				(width 0.1)
				(type default)
			)
			(layer "B.Fab")
		)
		(fp_line
			(start -0.12065 -0.3048)
			(end -0.67945 -0.3048)
			(stroke
				(width 0.1)
				(type default)
			)
			(layer "B.Fab")
		)
		(fp_line
			(start -0.67945 -0.3048)
			(end -0.67945 0.3048)
			(stroke
				(width 0.1)
				(type default)
			)
			(layer "B.Fab")
		)
		(fp_line
			(start 0.12065 -0.2794)
			(end -0.12065 -0.2794)
			(stroke
				(width 0.1)
				(type default)
			)
			(layer "B.Fab")
		)
		(fp_line
			(start -0.12065 -0.2794)
			(end -0.12065 -0.3048)
			(stroke
				(width 0.1)
				(type default)
			)
			(layer "B.Fab")
		)
		(fp_line
			(start 0.12065 0.2794)
			(end 0.12065 0.3048)
			(stroke
				(width 0.1)
				(type default)
			)
			(layer "B.Fab")
		)
		(fp_line
			(start -0.120396 0.2794)
			(end 0.12065 0.2794)
			(stroke
				(width 0.1)
				(type default)
			)
			(layer "B.Fab")
		)
		(fp_line
			(start 0.67945 0.3048)
			(end 0.67945 -0.305054)
			(stroke
				(width 0.1)
				(type default)
			)
			(layer "B.Fab")
		)
		(fp_line
			(start 0.12065 0.3048)
			(end 0.67945 0.3048)
			(stroke
				(width 0.1)
				(type default)
			)
			(layer "B.Fab")
		)
		(fp_line
			(start -0.120396 0.3048)
			(end -0.120396 0.2794)
			(stroke
				(width 0.1)
				(type default)
			)
			(layer "B.Fab")
		)
		(fp_line
			(start -0.67945 0.3048)
			(end -0.120396 0.3048)
			(stroke
				(width 0.1)
				(type default)
			)
			(layer "B.Fab")
		)
		(pad "1" smd circle
			(at 0.40005 0 270)
			(size 0 0)
			(layers "B.Cu" "B.Mask" "B.Paste")
			(net "P0V8_PEX1_PVCC")
		)
		(pad "2" smd circle
			(at -0.40005 0 270)
			(size 0 0)
			(layers "B.Cu" "B.Mask" "B.Paste")
			(net "P0V8_PEX1_VCC2")
		)
	)
	(footprint ""
		(layer "B.Cu")
		(at 57.274968 -293.99992 -90)
		(property "Reference" "C1149"
			(at 0 0 90)
			(layer "B.SilkS")
			(hide yes)
			(effects
				(font
					(size 1.27 1.27)
				)
				(justify mirror)
			)
		)
		(property "Value" ""
			(at 0 0 90)
			(layer "B.Fab")
			(effects
				(font
					(size 1.27 1.27)
				)
				(justify mirror)
			)
		)
		(duplicate_pad_numbers_are_jumpers no)
		(fp_line
			(start -0.299974 0.150114)
			(end 0.299974 0.150114)
			(stroke
				(width 0.1)
				(type default)
			)
			(layer "B.Fab")
		)
		(fp_line
			(start 0.299974 0.150114)
			(end 0.299974 -0.150114)
			(stroke
				(width 0.1)
				(type default)
			)
			(layer "B.Fab")
		)
		(fp_line
			(start -0.299974 -0.150114)
			(end -0.299974 0.150114)
			(stroke
				(width 0.1)
				(type default)
			)
			(layer "B.Fab")
		)
		(fp_line
			(start 0.299974 -0.150114)
			(end -0.299974 -0.150114)
			(stroke
				(width 0.1)
				(type default)
			)
			(layer "B.Fab")
		)
		(pad "1" smd rect
			(at 0.2667 0 90)
			(size 0.3048 0.381)
			(layers "B.Cu" "B.Mask" "B.Paste")
			(net "P0V8_PEX0")
		)
		(pad "2" smd rect
			(at -0.2667 0 90)
			(size 0.3048 0.381)
			(layers "B.Cu" "B.Mask" "B.Paste")
			(net "GND")
		)
	)
	(footprint ""
		(layer "B.Cu")
		(at 14.312392 -441.437014)
		(property "Reference" "X62"
			(at -0.9017 -2.08407 180)
			(unlocked yes)
			(layer "B.SilkS")
			(effects
				(font
					(size 0.7874 0.5842)
					(thickness 0.1524)
				)
				(justify mirror)
			)
		)
		(property "Value" ""
			(at 0 0 0)
			(layer "B.Fab")
			(effects
				(font
					(size 1.27 1.27)
				)
				(justify mirror)
			)
		)
		(property "Device Type" "TP_TDR_4P_FTS_MPKT4_H025P0200_IO_TP15_TP_TDR_4P_DIP"
			(at -1.30175 1.27 270)
			(unlocked yes)
			(layer "B.Fab")
			(hide yes)
			(effects
				(font
					(size 0.635 0.4064)
					(thickness 0.1524)
				)
				(justify mirror)
			)
		)
		(property "User Part Number" "TP15"
			(at -1.30175 1.27 270)
			(unlocked yes)
			(layer "Cmts.User")
			(hide yes)
			(effects
				(font
					(size 0.635 0.4064)
					(thickness 0.1524)
				)
				(justify mirror)
			)
		)
		(duplicate_pad_numbers_are_jumpers no)
		(fp_line
			(start -2.54 -1.27)
			(end 0 -1.27)
			(stroke
				(width 0.1524)
				(type default)
			)
			(layer "B.SilkS")
		)
		(fp_line
			(start -2.54 -1.1303)
			(end -2.54 -1.27)
			(stroke
				(width 0.1524)
				(type default)
			)
			(layer "B.SilkS")
		)
		(fp_line
			(start -2.54 1.4097)
			(end -2.54 1.1303)
			(stroke
				(width 0.1524)
				(type default)
			)
			(layer "B.SilkS")
		)
		(fp_line
			(start -2.54 3.81)
			(end -2.54 3.6703)
			(stroke
				(width 0.1524)
				(type default)
			)
			(layer "B.SilkS")
		)
		(fp_line
			(start 0 -1.27)
			(end 0 -0.635)
			(stroke
				(width 0.1524)
				(type default)
			)
			(layer "B.SilkS")
		)
		(fp_line
			(start 0 0.635)
			(end 0 1.905)
			(stroke
				(width 0.1524)
				(type default)
			)
			(layer "B.SilkS")
		)
		(fp_line
			(start 0 3.175)
			(end 0 3.81)
			(stroke
				(width 0.1524)
				(type default)
			)
			(layer "B.SilkS")
		)
		(fp_line
			(start 0 3.81)
			(end -2.54 3.81)
			(stroke
				(width 0.1524)
				(type default)
			)
			(layer "B.SilkS")
		)
		(fp_poly
			(pts
				(xy 0.761746 0) (xy 2.285746 -0.762) (xy 2.285746 0.762)
			)
			(stroke
				(width 0)
				(type default)
			)
			(fill yes)
			(layer "B.SilkS")
		)
		(fp_line
			(start -2.54 -1.27)
			(end 0 -1.27)
			(stroke
				(width 0.1)
				(type default)
			)
			(layer "B.Fab")
		)
		(fp_line
			(start -2.54 3.81)
			(end -2.54 -1.27)
			(stroke
				(width 0.1)
				(type default)
			)
			(layer "B.Fab")
		)
		(fp_line
			(start 0 -1.27)
			(end 0 3.81)
			(stroke
				(width 0.1)
				(type default)
			)
			(layer "B.Fab")
		)
		(fp_line
			(start 0 3.81)
			(end -2.54 3.81)
			(stroke
				(width 0.1)
				(type default)
			)
			(layer "B.Fab")
		)
		(fp_poly
			(pts
				(xy 0.761746 0) (xy 2.285746 -0.762) (xy 2.285746 0.762)
			)
			(stroke
				(width 0)
				(type default)
			)
			(fill yes)
			(layer "B.Fab")
		)
		(pad "1" thru_hole circle
			(at 0 0 180)
			(size 1.0033 1.0033)
			(drill 0.249936)
			(layers "*.Cu" "*.Mask")
			(remove_unused_layers no)
			(net "TDR_DIFF_85_IN5_DIP")
			(clearance 0.10795)
			(padstack
				(mode front_inner_back)
				(layer "Inner"
					(shape circle)
					(size 0.8001 0.8001)
					(clearance 0.1524)
				)
				(layer "B.Cu"
					(shape circle)
					(size 1.0033 1.0033)
					(thermal_gap 0.10795)
					(clearance 0.10795)
				)
			)
		)
		(pad "2" thru_hole circle
			(at -2.54 0 180)
			(size 1.9939 1.9939)
			(drill 0.249936)
			(layers "*.Cu" "*.Mask")
			(remove_unused_layers no)
			(net "COUPON_GND1")
			(clearance 0.10795)
			(padstack
				(mode front_inner_back)
				(layer "Inner"
					(shape circle)
					(size 0.8001 0.8001)
					(clearance 0.1524)
				)
				(layer "B.Cu"
					(shape circle)
					(size 1.9939 1.9939)
					(thermal_gap 0.10795)
					(clearance 0.10795)
				)
			)
		)
		(pad "3" thru_hole circle
			(at -2.54 2.54 180)
			(size 1.9939 1.9939)
			(drill 0.249936)
			(layers "*.Cu" "*.Mask")
			(remove_unused_layers no)
			(net "COUPON_GND1")
			(clearance 0.10795)
			(padstack
				(mode front_inner_back)
				(layer "Inner"
					(shape circle)
					(size 0.8001 0.8001)
					(clearance 0.1524)
				)
				(layer "B.Cu"
					(shape circle)
					(size 1.9939 1.9939)
					(thermal_gap 0.10795)
					(clearance 0.10795)
				)
			)
		)
		(pad "4" thru_hole circle
			(at 0 2.54 180)
			(size 1.0033 1.0033)
			(drill 0.249936)
			(layers "*.Cu" "*.Mask")
			(remove_unused_layers no)
			(net "TDR_DIFF_85_IN5_DIN")
			(clearance 0.10795)
			(padstack
				(mode front_inner_back)
				(layer "Inner"
					(shape circle)
					(size 0.8001 0.8001)
					(clearance 0.1524)
				)
				(layer "B.Cu"
					(shape circle)
					(size 1.0033 1.0033)
					(thermal_gap 0.10795)
					(clearance 0.10795)
				)
			)
		)
	)
	(footprint ""
		(layer "B.Cu")
		(at 284.669992 -305.399948 -90)
		(property "Reference" "C3333"
			(at 0 0 90)
			(layer "B.SilkS")
			(hide yes)
			(effects
				(font
					(size 1.27 1.27)
				)
				(justify mirror)
			)
		)
		(property "Value" ""
			(at 0 0 90)
			(layer "B.Fab")
			(effects
				(font
					(size 1.27 1.27)
				)
				(justify mirror)
			)
		)
		(duplicate_pad_numbers_are_jumpers no)
		(fp_line
			(start -0.299974 0.150114)
			(end 0.299974 0.150114)
			(stroke
				(width 0.1)
				(type default)
			)
			(layer "B.Fab")
		)
		(fp_line
			(start 0.299974 0.150114)
			(end 0.299974 -0.150114)
			(stroke
				(width 0.1)
				(type default)
			)
			(layer "B.Fab")
		)
		(fp_line
			(start -0.299974 -0.150114)
			(end -0.299974 0.150114)
			(stroke
				(width 0.1)
				(type default)
			)
			(layer "B.Fab")
		)
		(fp_line
			(start 0.299974 -0.150114)
			(end -0.299974 -0.150114)
			(stroke
				(width 0.1)
				(type default)
			)
			(layer "B.Fab")
		)
		(pad "1" smd rect
			(at 0.2667 0 90)
			(size 0.3048 0.381)
			(layers "B.Cu" "B.Mask" "B.Paste")
			(net "P1V25_SERDES_VDDPLL_PEX2")
		)
		(pad "2" smd rect
			(at -0.2667 0 90)
			(size 0.3048 0.381)
			(layers "B.Cu" "B.Mask" "B.Paste")
			(net "GND")
		)
	)
	(footprint ""
		(layer "B.Cu")
		(at 262.979408 -84.713826)
		(property "Reference" "C2647"
			(at 0 0 0)
			(layer "B.SilkS")
			(hide yes)
			(effects
				(font
					(size 1.27 1.27)
				)
				(justify mirror)
			)
		)
		(property "Value" ""
			(at 0 0 0)
			(layer "B.Fab")
			(effects
				(font
					(size 1.27 1.27)
				)
				(justify mirror)
			)
		)
		(duplicate_pad_numbers_are_jumpers no)
		(fp_line
			(start -0.7874 -0.4064)
			(end -0.7874 0.4064)
			(stroke
				(width 0.1524)
				(type default)
			)
			(layer "B.SilkS")
		)
		(fp_line
			(start -0.7874 0.4064)
			(end 0.7874 0.4064)
			(stroke
				(width 0.1524)
				(type default)
			)
			(layer "B.SilkS")
		)
		(fp_line
			(start 0.7874 -0.4064)
			(end -0.7874 -0.4064)
			(stroke
				(width 0.1524)
				(type default)
			)
			(layer "B.SilkS")
		)
		(fp_line
			(start 0.7874 0.4064)
			(end 0.7874 -0.4064)
			(stroke
				(width 0.1524)
				(type default)
			)
			(layer "B.SilkS")
		)
		(fp_line
			(start -0.67945 -0.3048)
			(end -0.67945 0.3048)
			(stroke
				(width 0.1)
				(type default)
			)
			(layer "B.Fab")
		)
		(fp_line
			(start -0.67945 0.3048)
			(end -0.120396 0.3048)
			(stroke
				(width 0.1)
				(type default)
			)
			(layer "B.Fab")
		)
		(fp_line
			(start -0.12065 -0.3048)
			(end -0.67945 -0.3048)
			(stroke
				(width 0.1)
				(type default)
			)
			(layer "B.Fab")
		)
		(fp_line
			(start -0.12065 -0.2794)
			(end -0.12065 -0.3048)
			(stroke
				(width 0.1)
				(type default)
			)
			(layer "B.Fab")
		)
		(fp_line
			(start -0.120396 0.2794)
			(end 0.12065 0.2794)
			(stroke
				(width 0.1)
				(type default)
			)
			(layer "B.Fab")
		)
		(fp_line
			(start -0.120396 0.3048)
			(end -0.120396 0.2794)
			(stroke
				(width 0.1)
				(type default)
			)
			(layer "B.Fab")
		)
		(fp_line
			(start 0.12065 -0.305054)
			(end 0.12065 -0.2794)
			(stroke
				(width 0.1)
				(type default)
			)
			(layer "B.Fab")
		)
		(fp_line
			(start 0.12065 -0.2794)
			(end -0.12065 -0.2794)
			(stroke
				(width 0.1)
				(type default)
			)
			(layer "B.Fab")
		)
		(fp_line
			(start 0.12065 0.2794)
			(end 0.12065 0.3048)
			(stroke
				(width 0.1)
				(type default)
			)
			(layer "B.Fab")
		)
		(fp_line
			(start 0.12065 0.3048)
			(end 0.67945 0.3048)
			(stroke
				(width 0.1)
				(type default)
			)
			(layer "B.Fab")
		)
		(fp_line
			(start 0.67945 -0.305054)
			(end 0.12065 -0.305054)
			(stroke
				(width 0.1)
				(type default)
			)
			(layer "B.Fab")
		)
		(fp_line
			(start 0.67945 0.3048)
			(end 0.67945 -0.305054)
			(stroke
				(width 0.1)
				(type default)
			)
			(layer "B.Fab")
		)
		(pad "1" smd circle
			(at 0.40005 0 180)
			(size 0 0)
			(layers "B.Cu" "B.Mask" "B.Paste")
			(net "P3V3_CLK_GEN_VDDMXCK_CK440")
		)
		(pad "2" smd circle
			(at -0.40005 0 180)
			(size 0 0)
			(layers "B.Cu" "B.Mask" "B.Paste")
			(net "GND")
		)
	)
	(footprint ""
		(layer "B.Cu")
		(at 247.099582 -227.965 180)
		(property "Reference" "R3488"
			(at 0 0 0)
			(layer "B.SilkS")
			(hide yes)
			(effects
				(font
					(size 1.27 1.27)
				)
				(justify mirror)
			)
		)
		(property "Value" ""
			(at 0 0 0)
			(layer "B.Fab")
			(effects
				(font
					(size 1.27 1.27)
				)
				(justify mirror)
			)
		)
		(duplicate_pad_numbers_are_jumpers no)
		(fp_line
			(start 0.7874 0.4064)
			(end 0.7874 -0.4064)
			(stroke
				(width 0.1524)
				(type default)
			)
			(layer "B.SilkS")
		)
		(fp_line
			(start 0.7874 -0.4064)
			(end -0.7874 -0.4064)
			(stroke
				(width 0.1524)
				(type default)
			)
			(layer "B.SilkS")
		)
		(fp_line
			(start -0.7874 0.4064)
			(end 0.7874 0.4064)
			(stroke
				(width 0.1524)
				(type default)
			)
			(layer "B.SilkS")
		)
		(fp_line
			(start -0.7874 -0.4064)
			(end -0.7874 0.4064)
			(stroke
				(width 0.1524)
				(type default)
			)
			(layer "B.SilkS")
		)
		(fp_line
			(start 0.67945 0.3048)
			(end 0.67945 -0.305054)
			(stroke
				(width 0.1)
				(type default)
			)
			(layer "B.Fab")
		)
		(fp_line
			(start 0.67945 -0.305054)
			(end 0.12065 -0.305054)
			(stroke
				(width 0.1)
				(type default)
			)
			(layer "B.Fab")
		)
		(fp_line
			(start 0.12065 0.3048)
			(end 0.67945 0.3048)
			(stroke
				(width 0.1)
				(type default)
			)
			(layer "B.Fab")
		)
		(fp_line
			(start 0.12065 0.2794)
			(end 0.12065 0.3048)
			(stroke
				(width 0.1)
				(type default)
			)
			(layer "B.Fab")
		)
		(fp_line
			(start 0.12065 -0.2794)
			(end -0.12065 -0.2794)
			(stroke
				(width 0.1)
				(type default)
			)
			(layer "B.Fab")
		)
		(fp_line
			(start 0.12065 -0.305054)
			(end 0.12065 -0.2794)
			(stroke
				(width 0.1)
				(type default)
			)
			(layer "B.Fab")
		)
		(fp_line
			(start -0.120396 0.3048)
			(end -0.120396 0.2794)
			(stroke
				(width 0.1)
				(type default)
			)
			(layer "B.Fab")
		)
		(fp_line
			(start -0.120396 0.2794)
			(end 0.12065 0.2794)
			(stroke
				(width 0.1)
				(type default)
			)
			(layer "B.Fab")
		)
		(fp_line
			(start -0.12065 -0.2794)
			(end -0.12065 -0.3048)
			(stroke
				(width 0.1)
				(type default)
			)
			(layer "B.Fab")
		)
		(fp_line
			(start -0.12065 -0.3048)
			(end -0.67945 -0.3048)
			(stroke
				(width 0.1)
				(type default)
			)
			(layer "B.Fab")
		)
		(fp_line
			(start -0.67945 0.3048)
			(end -0.120396 0.3048)
			(stroke
				(width 0.1)
				(type default)
			)
			(layer "B.Fab")
		)
		(fp_line
			(start -0.67945 -0.3048)
			(end -0.67945 0.3048)
			(stroke
				(width 0.1)
				(type default)
			)
			(layer "B.Fab")
		)
		(pad "1" smd circle
			(at 0.40005 0)
			(size 0 0)
			(layers "B.Cu" "B.Mask" "B.Paste")
			(net "SPI_PEX2_SDIO2_R1")
		)
		(pad "2" smd circle
			(at -0.40005 0)
			(size 0 0)
			(layers "B.Cu" "B.Mask" "B.Paste")
			(net "GND")
		)
	)
	(footprint ""
		(layer "B.Cu")
		(at 394.65504 -294.4749)
		(property "Reference" "C3566"
			(at 0 0 0)
			(layer "B.SilkS")
			(hide yes)
			(effects
				(font
					(size 1.27 1.27)
				)
				(justify mirror)
			)
		)
		(property "Value" ""
			(at 0 0 0)
			(layer "B.Fab")
			(effects
				(font
					(size 1.27 1.27)
				)
				(justify mirror)
			)
		)
		(duplicate_pad_numbers_are_jumpers no)
		(fp_line
			(start -0.299974 -0.150114)
			(end -0.299974 0.150114)
			(stroke
				(width 0.1)
				(type default)
			)
			(layer "B.Fab")
		)
		(fp_line
			(start -0.299974 0.150114)
			(end 0.299974 0.150114)
			(stroke
				(width 0.1)
				(type default)
			)
			(layer "B.Fab")
		)
		(fp_line
			(start 0.299974 -0.150114)
			(end -0.299974 -0.150114)
			(stroke
				(width 0.1)
				(type default)
			)
			(layer "B.Fab")
		)
		(fp_line
			(start 0.299974 0.150114)
			(end 0.299974 -0.150114)
			(stroke
				(width 0.1)
				(type default)
			)
			(layer "B.Fab")
		)
		(pad "1" smd rect
			(at 0.2667 0 180)
			(size 0.3048 0.381)
			(layers "B.Cu" "B.Mask" "B.Paste")
			(net "PCEPLL4_VDDA18_PEX3")
		)
		(pad "2" smd rect
			(at -0.2667 0 180)
			(size 0.3048 0.381)
			(layers "B.Cu" "B.Mask" "B.Paste")
			(net "GND")
		)
	)
	(footprint ""
		(layer "B.Cu")
		(at 174.800006 -288.299906 90)
		(property "Reference" "C3096"
			(at 0 0 90)
			(layer "B.SilkS")
			(hide yes)
			(effects
				(font
					(size 1.27 1.27)
				)
				(justify mirror)
			)
		)
		(property "Value" ""
			(at 0 0 90)
			(layer "B.Fab")
			(effects
				(font
					(size 1.27 1.27)
				)
				(justify mirror)
			)
		)
		(duplicate_pad_numbers_are_jumpers no)
		(fp_line
			(start 0.299974 -0.150114)
			(end -0.299974 -0.150114)
			(stroke
				(width 0.1)
				(type default)
			)
			(layer "B.Fab")
		)
		(fp_line
			(start -0.299974 -0.150114)
			(end -0.299974 0.150114)
			(stroke
				(width 0.1)
				(type default)
			)
			(layer "B.Fab")
		)
		(fp_line
			(start 0.299974 0.150114)
			(end 0.299974 -0.150114)
			(stroke
				(width 0.1)
				(type default)
			)
			(layer "B.Fab")
		)
		(fp_line
			(start -0.299974 0.150114)
			(end 0.299974 0.150114)
			(stroke
				(width 0.1)
				(type default)
			)
			(layer "B.Fab")
		)
		(pad "1" smd rect
			(at 0.2667 0 270)
			(size 0.3048 0.381)
			(layers "B.Cu" "B.Mask" "B.Paste")
			(net "P1V25_PEX1")
		)
		(pad "2" smd rect
			(at -0.2667 0 270)
			(size 0.3048 0.381)
			(layers "B.Cu" "B.Mask" "B.Paste")
			(net "GND")
		)
	)
	(footprint ""
		(layer "B.Cu")
		(at 404.30704 -136.652 -90)
		(property "Reference" "R342"
			(at 0 0 90)
			(layer "B.SilkS")
			(hide yes)
			(effects
				(font
					(size 1.27 1.27)
				)
				(justify mirror)
			)
		)
		(property "Value" ""
			(at 0 0 90)
			(layer "B.Fab")
			(effects
				(font
					(size 1.27 1.27)
				)
				(justify mirror)
			)
		)
		(duplicate_pad_numbers_are_jumpers no)
		(fp_line
			(start -0.7874 0.4064)
			(end 0.7874 0.4064)
			(stroke
				(width 0.1524)
				(type default)
			)
			(layer "B.SilkS")
		)
		(fp_line
			(start 0.7874 0.4064)
			(end 0.7874 -0.4064)
			(stroke
				(width 0.1524)
				(type default)
			)
			(layer "B.SilkS")
		)
		(fp_line
			(start -0.7874 -0.4064)
			(end -0.7874 0.4064)
			(stroke
				(width 0.1524)
				(type default)
			)
			(layer "B.SilkS")
		)
		(fp_line
			(start 0.7874 -0.4064)
			(end -0.7874 -0.4064)
			(stroke
				(width 0.1524)
				(type default)
			)
			(layer "B.SilkS")
		)
		(fp_line
			(start -0.67945 0.3048)
			(end -0.120396 0.3048)
			(stroke
				(width 0.1)
				(type default)
			)
			(layer "B.Fab")
		)
		(fp_line
			(start -0.120396 0.3048)
			(end -0.120396 0.2794)
			(stroke
				(width 0.1)
				(type default)
			)
			(layer "B.Fab")
		)
		(fp_line
			(start 0.12065 0.3048)
			(end 0.67945 0.3048)
			(stroke
				(width 0.1)
				(type default)
			)
			(layer "B.Fab")
		)
		(fp_line
			(start 0.67945 0.3048)
			(end 0.67945 -0.305054)
			(stroke
				(width 0.1)
				(type default)
			)
			(layer "B.Fab")
		)
		(fp_line
			(start -0.120396 0.2794)
			(end 0.12065 0.2794)
			(stroke
				(width 0.1)
				(type default)
			)
			(layer "B.Fab")
		)
		(fp_line
			(start 0.12065 0.2794)
			(end 0.12065 0.3048)
			(stroke
				(width 0.1)
				(type default)
			)
			(layer "B.Fab")
		)
		(fp_line
			(start -0.12065 -0.2794)
			(end -0.12065 -0.3048)
			(stroke
				(width 0.1)
				(type default)
			)
			(layer "B.Fab")
		)
		(fp_line
			(start 0.12065 -0.2794)
			(end -0.12065 -0.2794)
			(stroke
				(width 0.1)
				(type default)
			)
			(layer "B.Fab")
		)
		(fp_line
			(start -0.67945 -0.3048)
			(end -0.67945 0.3048)
			(stroke
				(width 0.1)
				(type default)
			)
			(layer "B.Fab")
		)
		(fp_line
			(start -0.12065 -0.3048)
			(end -0.67945 -0.3048)
			(stroke
				(width 0.1)
				(type default)
			)
			(layer "B.Fab")
		)
		(fp_line
			(start 0.12065 -0.305054)
			(end 0.12065 -0.2794)
			(stroke
				(width 0.1)
				(type default)
			)
			(layer "B.Fab")
		)
		(fp_line
			(start 0.67945 -0.305054)
			(end 0.12065 -0.305054)
			(stroke
				(width 0.1)
				(type default)
			)
			(layer "B.Fab")
		)
		(pad "1" smd circle
			(at 0.40005 0 90)
			(size 0 0)
			(layers "B.Cu" "B.Mask" "B.Paste")
			(net "RST_SMB_NIC_MUX_R_N")
		)
		(pad "2" smd circle
			(at -0.40005 0 90)
			(size 0 0)
			(layers "B.Cu" "B.Mask" "B.Paste")
			(net "RST_SMB_NIC6_MUX_N")
		)
	)
	(footprint ""
		(layer "B.Cu")
		(at 234.810046 -145.507202)
		(property "Reference" "R4186"
			(at 0 0 0)
			(layer "B.SilkS")
			(hide yes)
			(effects
				(font
					(size 1.27 1.27)
				)
				(justify mirror)
			)
		)
		(property "Value" ""
			(at 0 0 0)
			(layer "B.Fab")
			(effects
				(font
					(size 1.27 1.27)
				)
				(justify mirror)
			)
		)
		(duplicate_pad_numbers_are_jumpers no)
		(fp_line
			(start -1.2954 -0.5842)
			(end -1.2954 0.5842)
			(stroke
				(width 0.1524)
				(type default)
			)
			(layer "B.SilkS")
		)
		(fp_line
			(start -1.2954 0.5842)
			(end 1.2954 0.5842)
			(stroke
				(width 0.1524)
				(type default)
			)
			(layer "B.SilkS")
		)
		(fp_line
			(start 1.2954 -0.5842)
			(end -1.2954 -0.5842)
			(stroke
				(width 0.1524)
				(type default)
			)
			(layer "B.SilkS")
		)
		(fp_line
			(start 1.2954 0.5842)
			(end 1.2954 -0.5842)
			(stroke
				(width 0.1524)
				(type default)
			)
			(layer "B.SilkS")
		)
		(fp_line
			(start -1.1938 -0.406654)
			(end -1.1938 0.4064)
			(stroke
				(width 0.1)
				(type default)
			)
			(layer "B.Fab")
		)
		(fp_line
			(start -1.1938 0.4064)
			(end -0.8636 0.4064)
			(stroke
				(width 0.1)
				(type default)
			)
			(layer "B.Fab")
		)
		(fp_line
			(start -0.8636 -0.4572)
			(end -0.8636 -0.406654)
			(stroke
				(width 0.1)
				(type default)
			)
			(layer "B.Fab")
		)
		(fp_line
			(start -0.8636 -0.406654)
			(end -1.1938 -0.406654)
			(stroke
				(width 0.1)
				(type default)
			)
			(layer "B.Fab")
		)
		(fp_line
			(start -0.8636 0.4064)
			(end -0.8636 0.4572)
			(stroke
				(width 0.1)
				(type default)
			)
			(layer "B.Fab")
		)
		(fp_line
			(start -0.8636 0.4572)
			(end 0.8636 0.4572)
			(stroke
				(width 0.1)
				(type default)
			)
			(layer "B.Fab")
		)
		(fp_line
			(start 0.8636 -0.4572)
			(end -0.8636 -0.4572)
			(stroke
				(width 0.1)
				(type default)
			)
			(layer "B.Fab")
		)
		(fp_line
			(start 0.8636 -0.406654)
			(end 0.8636 -0.4572)
			(stroke
				(width 0.1)
				(type default)
			)
			(layer "B.Fab")
		)
		(fp_line
			(start 0.8636 0.4064)
			(end 1.1938 0.4064)
			(stroke
				(width 0.1)
				(type default)
			)
			(layer "B.Fab")
		)
		(fp_line
			(start 0.8636 0.4318)
			(end 0.8636 0.4064)
			(stroke
				(width 0.1)
				(type default)
			)
			(layer "B.Fab")
		)
		(fp_line
			(start 0.8636 0.4572)
			(end 0.8636 0.4318)
			(stroke
				(width 0.1)
				(type default)
			)
			(layer "B.Fab")
		)
		(fp_line
			(start 1.1938 -0.406654)
			(end 0.8636 -0.406654)
			(stroke
				(width 0.1)
				(type default)
			)
			(layer "B.Fab")
		)
		(fp_line
			(start 1.1938 0.4064)
			(end 1.1938 -0.406654)
			(stroke
				(width 0.1)
				(type default)
			)
			(layer "B.Fab")
		)
		(pad "1" smd rect
			(at 0.7366 0 270)
			(size 0.7112 0.8128)
			(layers "B.Cu" "B.Mask" "B.Paste")
			(net "P3V3_CLK_GEN_VDD_CK440_PEX")
		)
		(pad "2" smd rect
			(at -0.7366 0 270)
			(size 0.7112 0.8128)
			(layers "B.Cu" "B.Mask" "B.Paste")
			(net "P3V3_CLK_GEN_VDDA100M_CK440_PEX")
		)
	)
	(footprint ""
		(layer "B.Cu")
		(at 126.646178 -200.72985 180)
		(property "Reference" "R924"
			(at 0 0 0)
			(layer "B.SilkS")
			(hide yes)
			(effects
				(font
					(size 1.27 1.27)
				)
				(justify mirror)
			)
		)
		(property "Value" ""
			(at 0 0 0)
			(layer "B.Fab")
			(effects
				(font
					(size 1.27 1.27)
				)
				(justify mirror)
			)
		)
		(duplicate_pad_numbers_are_jumpers no)
		(fp_line
			(start 0.7874 0.4064)
			(end 0.7874 -0.4064)
			(stroke
				(width 0.1524)
				(type default)
			)
			(layer "B.SilkS")
		)
		(fp_line
			(start 0.7874 -0.4064)
			(end -0.7874 -0.4064)
			(stroke
				(width 0.1524)
				(type default)
			)
			(layer "B.SilkS")
		)
		(fp_line
			(start -0.7874 0.4064)
			(end 0.7874 0.4064)
			(stroke
				(width 0.1524)
				(type default)
			)
			(layer "B.SilkS")
		)
		(fp_line
			(start -0.7874 -0.4064)
			(end -0.7874 0.4064)
			(stroke
				(width 0.1524)
				(type default)
			)
			(layer "B.SilkS")
		)
		(fp_line
			(start 0.67945 0.3048)
			(end 0.67945 -0.305054)
			(stroke
				(width 0.1)
				(type default)
			)
			(layer "B.Fab")
		)
		(fp_line
			(start 0.67945 -0.305054)
			(end 0.12065 -0.305054)
			(stroke
				(width 0.1)
				(type default)
			)
			(layer "B.Fab")
		)
		(fp_line
			(start 0.12065 0.3048)
			(end 0.67945 0.3048)
			(stroke
				(width 0.1)
				(type default)
			)
			(layer "B.Fab")
		)
		(fp_line
			(start 0.12065 0.2794)
			(end 0.12065 0.3048)
			(stroke
				(width 0.1)
				(type default)
			)
			(layer "B.Fab")
		)
		(fp_line
			(start 0.12065 -0.2794)
			(end -0.12065 -0.2794)
			(stroke
				(width 0.1)
				(type default)
			)
			(layer "B.Fab")
		)
		(fp_line
			(start 0.12065 -0.305054)
			(end 0.12065 -0.2794)
			(stroke
				(width 0.1)
				(type default)
			)
			(layer "B.Fab")
		)
		(fp_line
			(start -0.120396 0.3048)
			(end -0.120396 0.2794)
			(stroke
				(width 0.1)
				(type default)
			)
			(layer "B.Fab")
		)
		(fp_line
			(start -0.120396 0.2794)
			(end 0.12065 0.2794)
			(stroke
				(width 0.1)
				(type default)
			)
			(layer "B.Fab")
		)
		(fp_line
			(start -0.12065 -0.2794)
			(end -0.12065 -0.3048)
			(stroke
				(width 0.1)
				(type default)
			)
			(layer "B.Fab")
		)
		(fp_line
			(start -0.12065 -0.3048)
			(end -0.67945 -0.3048)
			(stroke
				(width 0.1)
				(type default)
			)
			(layer "B.Fab")
		)
		(fp_line
			(start -0.67945 0.3048)
			(end -0.120396 0.3048)
			(stroke
				(width 0.1)
				(type default)
			)
			(layer "B.Fab")
		)
		(fp_line
			(start -0.67945 -0.3048)
			(end -0.67945 0.3048)
			(stroke
				(width 0.1)
				(type default)
			)
			(layer "B.Fab")
		)
		(pad "1" smd circle
			(at 0.40005 0)
			(size 0 0)
			(layers "B.Cu" "B.Mask" "B.Paste")
			(net "FT4232_CLI_EEPROM_R_SDA")
		)
		(pad "2" smd circle
			(at -0.40005 0)
			(size 0 0)
			(layers "B.Cu" "B.Mask" "B.Paste")
			(net "FT4232_CLI_EEPROM_SDA")
		)
	)
	(footprint ""
		(layer "B.Cu")
		(at 338.093812 -212.386926 90)
		(property "Reference" "C2052"
			(at 0 0 90)
			(layer "B.SilkS")
			(hide yes)
			(effects
				(font
					(size 1.27 1.27)
				)
				(justify mirror)
			)
		)
		(property "Value" ""
			(at 0 0 90)
			(layer "B.Fab")
			(effects
				(font
					(size 1.27 1.27)
				)
				(justify mirror)
			)
		)
		(duplicate_pad_numbers_are_jumpers no)
		(fp_line
			(start 0.69215 -0.2921)
			(end -0.69215 -0.2921)
			(stroke
				(width 0.1524)
				(type default)
			)
			(layer "B.SilkS")
		)
		(fp_line
			(start -0.69215 -0.2921)
			(end -0.69215 0.2921)
			(stroke
				(width 0.1524)
				(type default)
			)
			(layer "B.SilkS")
		)
		(fp_line
			(start 0.69215 0.2921)
			(end 0.69215 -0.2921)
			(stroke
				(width 0.1524)
				(type default)
			)
			(layer "B.SilkS")
		)
		(fp_line
			(start -0.69215 0.2921)
			(end 0.69215 0.2921)
			(stroke
				(width 0.1524)
				(type default)
			)
			(layer "B.SilkS")
		)
		(fp_line
			(start 0.51435 -0.2794)
			(end -0.51435 -0.2794)
			(stroke
				(width 0.1)
				(type default)
			)
			(layer "B.Fab")
		)
		(fp_line
			(start -0.51435 -0.2794)
			(end -0.51435 0.2794)
			(stroke
				(width 0.1)
				(type default)
			)
			(layer "B.Fab")
		)
		(fp_line
			(start 0.51435 0.2794)
			(end 0.51435 -0.2794)
			(stroke
				(width 0.1)
				(type default)
			)
			(layer "B.Fab")
		)
		(fp_line
			(start -0.51435 0.2794)
			(end 0.51435 0.2794)
			(stroke
				(width 0.1)
				(type default)
			)
			(layer "B.Fab")
		)
		(pad "1" smd circle
			(at 0.40005 0 270)
			(size 0 0)
			(layers "B.Cu" "B.Mask" "B.Paste")
			(net "P3V3_FPGA_VCCIO2")
		)
		(pad "2" smd circle
			(at -0.40005 0 270)
			(size 0 0)
			(layers "B.Cu" "B.Mask" "B.Paste")
			(net "GND")
		)
		(zone
			(layer "B.Cu")
			(hatch none 0.5)
			(connect_pads
				(clearance 0)
			)
			(min_thickness 0.25)
			(keepout
				(tracks not_allowed)
				(vias allowed)
				(pads allowed)
				(copperpour not_allowed)
				(footprints allowed)
			)
			(placement
				(enabled no)
				(sheetname "")
			)
			(fill
				(thermal_gap 0.5)
				(thermal_bridge_width 0.5)
				(island_removal_mode 0)
			)
			(polygon
				(pts
					(xy 338.181442 -212.577426) (xy 338.239608 -212.485986) (xy 338.239608 -212.286596) (xy 338.181442 -212.196426)
					(xy 338.006182 -212.196426) (xy 337.947762 -212.286596) (xy 337.947762 -212.485986) (xy 338.005928 -212.577426)
				)
			)
		)
	)
	(footprint ""
		(layer "B.Cu")
		(at 134.292594 -328.422)
		(property "Reference" "PJ20"
			(at 0 0 0)
			(layer "B.SilkS")
			(hide yes)
			(effects
				(font
					(size 1.27 1.27)
				)
				(justify mirror)
			)
		)
		(property "Value" ""
			(at 0 0 0)
			(layer "B.Fab")
			(effects
				(font
					(size 1.27 1.27)
				)
				(justify mirror)
			)
		)
		(duplicate_pad_numbers_are_jumpers no)
		(pad "1" smd circle
			(at 0.40005 0 90)
			(size 0 0)
			(layers "B.Cu" "B.Mask" "B.Paste")
			(net "VSENSE_P0V8_PEX1_SKT_VSEN")
		)
		(pad "2" smd rect
			(at -0.40005 0)
			(size 0.4572 0.508)
			(layers "B.Cu" "B.Mask" "B.Paste")
			(net "SH_P0V8_PEX1_VSEN1_L")
		)
		(zone
			(layer "B.Cu")
			(hatch none 0.5)
			(connect_pads
				(clearance 0)
			)
			(min_thickness 0.25)
			(keepout
				(tracks allowed)
				(vias not_allowed)
				(pads allowed)
				(copperpour not_allowed)
				(footprints allowed)
			)
			(placement
				(enabled no)
				(sheetname "")
			)
			(fill
				(thermal_gap 0.5)
				(thermal_bridge_width 0.5)
				(island_removal_mode 0)
			)
			(polygon
				(pts
					(xy 133.606794 -328.1172) (xy 133.606794 -328.7268) (xy 134.978394 -328.7268) (xy 134.978394 -328.1172)
				)
			)
		)
	)
	(footprint ""
		(layer "B.Cu")
		(at 281.399742 -291.624766)
		(property "Reference" "C1616"
			(at 0 0 0)
			(layer "B.SilkS")
			(hide yes)
			(effects
				(font
					(size 1.27 1.27)
				)
				(justify mirror)
			)
		)
		(property "Value" ""
			(at 0 0 0)
			(layer "B.Fab")
			(effects
				(font
					(size 1.27 1.27)
				)
				(justify mirror)
			)
		)
		(duplicate_pad_numbers_are_jumpers no)
		(fp_line
			(start -0.299974 -0.150114)
			(end -0.299974 0.150114)
			(stroke
				(width 0.1)
				(type default)
			)
			(layer "B.Fab")
		)
		(fp_line
			(start -0.299974 0.150114)
			(end 0.299974 0.150114)
			(stroke
				(width 0.1)
				(type default)
			)
			(layer "B.Fab")
		)
		(fp_line
			(start 0.299974 -0.150114)
			(end -0.299974 -0.150114)
			(stroke
				(width 0.1)
				(type default)
			)
			(layer "B.Fab")
		)
		(fp_line
			(start 0.299974 0.150114)
			(end 0.299974 -0.150114)
			(stroke
				(width 0.1)
				(type default)
			)
			(layer "B.Fab")
		)
		(pad "1" smd rect
			(at 0.2667 0 180)
			(size 0.3048 0.381)
			(layers "B.Cu" "B.Mask" "B.Paste")
			(net "P0V8_PEX2")
		)
		(pad "2" smd rect
			(at -0.2667 0 180)
			(size 0.3048 0.381)
			(layers "B.Cu" "B.Mask" "B.Paste")
			(net "GND")
		)
	)
	(footprint ""
		(layer "B.Cu")
		(at 102.156006 -357.923084 90)
		(property "Reference" "R6376"
			(at 0 0 90)
			(layer "B.SilkS")
			(hide yes)
			(effects
				(font
					(size 1.27 1.27)
				)
				(justify mirror)
			)
		)
		(property "Value" ""
			(at 0 0 90)
			(layer "B.Fab")
			(effects
				(font
					(size 1.27 1.27)
				)
				(justify mirror)
			)
		)
		(duplicate_pad_numbers_are_jumpers no)
		(fp_line
			(start 0.7874 -0.4064)
			(end -0.7874 -0.4064)
			(stroke
				(width 0.1524)
				(type default)
			)
			(layer "B.SilkS")
		)
		(fp_line
			(start -0.7874 -0.4064)
			(end -0.7874 0.4064)
			(stroke
				(width 0.1524)
				(type default)
			)
			(layer "B.SilkS")
		)
		(fp_line
			(start 0.7874 0.4064)
			(end 0.7874 -0.4064)
			(stroke
				(width 0.1524)
				(type default)
			)
			(layer "B.SilkS")
		)
		(fp_line
			(start -0.7874 0.4064)
			(end 0.7874 0.4064)
			(stroke
				(width 0.1524)
				(type default)
			)
			(layer "B.SilkS")
		)
		(fp_line
			(start 0.67945 -0.305054)
			(end 0.12065 -0.305054)
			(stroke
				(width 0.1)
				(type default)
			)
			(layer "B.Fab")
		)
		(fp_line
			(start 0.12065 -0.305054)
			(end 0.12065 -0.2794)
			(stroke
				(width 0.1)
				(type default)
			)
			(layer "B.Fab")
		)
		(fp_line
			(start -0.12065 -0.3048)
			(end -0.67945 -0.3048)
			(stroke
				(width 0.1)
				(type default)
			)
			(layer "B.Fab")
		)
		(fp_line
			(start -0.67945 -0.3048)
			(end -0.67945 0.3048)
			(stroke
				(width 0.1)
				(type default)
			)
			(layer "B.Fab")
		)
		(fp_line
			(start 0.12065 -0.2794)
			(end -0.12065 -0.2794)
			(stroke
				(width 0.1)
				(type default)
			)
			(layer "B.Fab")
		)
		(fp_line
			(start -0.12065 -0.2794)
			(end -0.12065 -0.3048)
			(stroke
				(width 0.1)
				(type default)
			)
			(layer "B.Fab")
		)
		(fp_line
			(start 0.12065 0.2794)
			(end 0.12065 0.3048)
			(stroke
				(width 0.1)
				(type default)
			)
			(layer "B.Fab")
		)
		(fp_line
			(start -0.120396 0.2794)
			(end 0.12065 0.2794)
			(stroke
				(width 0.1)
				(type default)
			)
			(layer "B.Fab")
		)
		(fp_line
			(start 0.67945 0.3048)
			(end 0.67945 -0.305054)
			(stroke
				(width 0.1)
				(type default)
			)
			(layer "B.Fab")
		)
		(fp_line
			(start 0.12065 0.3048)
			(end 0.67945 0.3048)
			(stroke
				(width 0.1)
				(type default)
			)
			(layer "B.Fab")
		)
		(fp_line
			(start -0.120396 0.3048)
			(end -0.120396 0.2794)
			(stroke
				(width 0.1)
				(type default)
			)
			(layer "B.Fab")
		)
		(fp_line
			(start -0.67945 0.3048)
			(end -0.120396 0.3048)
			(stroke
				(width 0.1)
				(type default)
			)
			(layer "B.Fab")
		)
		(pad "1" smd circle
			(at 0.40005 0 270)
			(size 0 0)
			(layers "B.Cu" "B.Mask" "B.Paste")
			(net "CLK_100M_DB800ZL_PEX1_S3_R_DP")
		)
		(pad "2" smd circle
			(at -0.40005 0 270)
			(size 0 0)
			(layers "B.Cu" "B.Mask" "B.Paste")
			(net "CLK_100M_DB800ZL_PEX1_S3_DP")
		)
	)
	(footprint ""
		(layer "B.Cu")
		(at 406.999948 -303.499774 -90)
		(property "Reference" "C3462"
			(at 0 0 90)
			(layer "B.SilkS")
			(hide yes)
			(effects
				(font
					(size 1.27 1.27)
				)
				(justify mirror)
			)
		)
		(property "Value" ""
			(at 0 0 90)
			(layer "B.Fab")
			(effects
				(font
					(size 1.27 1.27)
				)
				(justify mirror)
			)
		)
		(duplicate_pad_numbers_are_jumpers no)
		(fp_line
			(start -0.299974 0.150114)
			(end 0.299974 0.150114)
			(stroke
				(width 0.1)
				(type default)
			)
			(layer "B.Fab")
		)
		(fp_line
			(start 0.299974 0.150114)
			(end 0.299974 -0.150114)
			(stroke
				(width 0.1)
				(type default)
			)
			(layer "B.Fab")
		)
		(fp_line
			(start -0.299974 -0.150114)
			(end -0.299974 0.150114)
			(stroke
				(width 0.1)
				(type default)
			)
			(layer "B.Fab")
		)
		(fp_line
			(start 0.299974 -0.150114)
			(end -0.299974 -0.150114)
			(stroke
				(width 0.1)
				(type default)
			)
			(layer "B.Fab")
		)
		(pad "1" smd rect
			(at 0.2667 0 90)
			(size 0.3048 0.381)
			(layers "B.Cu" "B.Mask" "B.Paste")
			(net "P1V25_PEX3")
		)
		(pad "2" smd rect
			(at -0.2667 0 90)
			(size 0.3048 0.381)
			(layers "B.Cu" "B.Mask" "B.Paste")
			(net "GND")
		)
	)
	(footprint ""
		(layer "B.Cu")
		(at 312.759344 20.568412)
		(property "Reference" "DE06F_3"
			(at 2.911856 3.054858 0)
			(unlocked yes)
			(layer "B.SilkS")
			(effects
				(font
					(size 0.7874 0.5842)
					(thickness 0.1524)
				)
				(justify left mirror)
			)
		)
		(property "Value" ""
			(at 0 0 0)
			(layer "B.Fab")
			(effects
				(font
					(size 1.27 1.27)
				)
				(justify mirror)
			)
		)
		(duplicate_pad_numbers_are_jumpers no)
		(fp_line
			(start -1.2192 -2.1082)
			(end -1.2192 2.1082)
			(stroke
				(width 0.1524)
				(type default)
			)
			(layer "B.SilkS")
		)
		(fp_line
			(start -1.2192 2.1082)
			(end 1.2192 2.1082)
			(stroke
				(width 0.1524)
				(type default)
			)
			(layer "B.SilkS")
		)
		(fp_line
			(start 1.2192 -2.1082)
			(end -1.2192 -2.1082)
			(stroke
				(width 0.1524)
				(type default)
			)
			(layer "B.SilkS")
		)
		(fp_line
			(start 1.2192 2.1082)
			(end 1.2192 -2.1082)
			(stroke
				(width 0.1524)
				(type default)
			)
			(layer "B.SilkS")
		)
		(pad "" np_thru_hole circle
			(at -3.4671 -1.27 270)
			(size 1.0414 1.0414)
			(drill 1.0414)
			(layers "*.Cu" "*.Mask")
			(clearance 0.381)
			(thermal_gap 0.381)
		)
		(pad "" np_thru_hole circle
			(at -3.4671 1.27 270)
			(size 1.0414 1.0414)
			(drill 1.0414)
			(layers "*.Cu" "*.Mask")
			(clearance 0.381)
			(thermal_gap 0.381)
		)
		(pad "" np_thru_hole circle
			(at 2.8829 -1.27 270)
			(size 1.0414 1.0414)
			(drill 1.0414)
			(layers "*.Cu" "*.Mask")
			(clearance 0.381)
			(thermal_gap 0.381)
		)
		(pad "" np_thru_hole circle
			(at 2.8829 1.27 270)
			(size 1.0414 1.0414)
			(drill 1.0414)
			(layers "*.Cu" "*.Mask")
			(clearance 0.381)
			(thermal_gap 0.381)
		)
		(pad "1" smd rect
			(at -0.8255 -0.249936 270)
			(size 0.3048 0.508)
			(layers "B.Cu" "B.Mask" "B.Paste")
			(net "85_5INCH_IN6_DP")
		)
		(pad "2" smd rect
			(at -0.8255 0.249936 270)
			(size 0.3048 0.508)
			(layers "B.Cu" "B.Mask" "B.Paste")
			(net "85_5INCH_IN6_DN")
		)
		(pad "3" smd circle
			(at 0 0 180)
			(size 0 0)
			(layers "B.Cu" "B.Mask" "B.Paste")
			(net "COUPON_GND2")
		)
		(zone
			(layers "F.Cu" "B.Cu" "In1.Cu" "In2.Cu" "In3.Cu" "In4.Cu" "In5.Cu" "In6.Cu"
				"In7.Cu" "In8.Cu" "In9.Cu" "In10.Cu" "In11.Cu" "In12.Cu" "In13.Cu" "In14.Cu"
				"In15.Cu" "In16.Cu"
			)
			(hatch none 0.5)
			(connect_pads
				(clearance 0)
			)
			(min_thickness 0.25)
			(keepout
				(tracks not_allowed)
				(vias allowed)
				(pads allowed)
				(copperpour not_allowed)
				(footprints allowed)
			)
			(placement
				(enabled no)
				(sheetname "")
			)
			(fill
				(thermal_gap 0.5)
				(thermal_bridge_width 0.5)
				(island_removal_mode 0)
			)
			(polygon
				(pts
					(arc
						(start 310.219344 19.298412)
						(mid 308.365144 19.298412)
						(end 310.219344 19.298412)
					)
				)
			)
		)
		(zone
			(layers "F.Cu" "B.Cu" "In1.Cu" "In2.Cu" "In3.Cu" "In4.Cu" "In5.Cu" "In6.Cu"
				"In7.Cu" "In8.Cu" "In9.Cu" "In10.Cu" "In11.Cu" "In12.Cu" "In13.Cu" "In14.Cu"
				"In15.Cu" "In16.Cu"
			)
			(hatch none 0.5)
			(connect_pads
				(clearance 0)
			)
			(min_thickness 0.25)
			(keepout
				(tracks not_allowed)
				(vias allowed)
				(pads allowed)
				(copperpour not_allowed)
				(footprints allowed)
			)
			(placement
				(enabled no)
				(sheetname "")
			)
			(fill
				(thermal_gap 0.5)
				(thermal_bridge_width 0.5)
				(island_removal_mode 0)
			)
			(polygon
				(pts
					(arc
						(start 310.219344 21.838412)
						(mid 308.365144 21.838412)
						(end 310.219344 21.838412)
					)
				)
			)
		)
		(zone
			(layers "F.Cu" "B.Cu" "In1.Cu" "In2.Cu" "In3.Cu" "In4.Cu" "In5.Cu" "In6.Cu"
				"In7.Cu" "In8.Cu" "In9.Cu" "In10.Cu" "In11.Cu" "In12.Cu" "In13.Cu" "In14.Cu"
				"In15.Cu" "In16.Cu"
			)
			(hatch none 0.5)
			(connect_pads
				(clearance 0)
			)
			(min_thickness 0.25)
			(keepout
				(tracks not_allowed)
				(vias allowed)
				(pads allowed)
				(copperpour not_allowed)
				(footprints allowed)
			)
			(placement
				(enabled no)
				(sheetname "")
			)
			(fill
				(thermal_gap 0.5)
				(thermal_bridge_width 0.5)
				(island_removal_mode 0)
			)
			(polygon
				(pts
					(arc
						(start 316.569344 19.298412)
						(mid 314.715144 19.298412)
						(end 316.569344 19.298412)
					)
				)
			)
		)
		(zone
			(layers "F.Cu" "B.Cu" "In1.Cu" "In2.Cu" "In3.Cu" "In4.Cu" "In5.Cu" "In6.Cu"
				"In7.Cu" "In8.Cu" "In9.Cu" "In10.Cu" "In11.Cu" "In12.Cu" "In13.Cu" "In14.Cu"
				"In15.Cu" "In16.Cu"
			)
			(hatch none 0.5)
			(connect_pads
				(clearance 0)
			)
			(min_thickness 0.25)
			(keepout
				(tracks not_allowed)
				(vias allowed)
				(pads allowed)
				(copperpour not_allowed)
				(footprints allowed)
			)
			(placement
				(enabled no)
				(sheetname "")
			)
			(fill
				(thermal_gap 0.5)
				(thermal_bridge_width 0.5)
				(island_removal_mode 0)
			)
			(polygon
				(pts
					(arc
						(start 316.569344 21.838412)
						(mid 314.715144 21.838412)
						(end 316.569344 21.838412)
					)
				)
			)
		)
		(zone
			(layer "B.Cu")
			(hatch none 0.5)
			(connect_pads
				(clearance 0)
			)
			(min_thickness 0.25)
			(keepout
				(tracks not_allowed)
				(vias allowed)
				(pads allowed)
				(copperpour not_allowed)
				(footprints allowed)
			)
			(placement
				(enabled no)
				(sheetname "")
			)
			(fill
				(thermal_gap 0.5)
				(thermal_bridge_width 0.5)
				(island_removal_mode 0)
			)
			(polygon
				(pts
					(xy 311.641744 20.019772) (xy 311.641744 20.115276) (xy 312.238644 20.115276) (xy 312.238644 20.521676)
					(xy 311.641744 20.521676) (xy 311.641744 20.615148) (xy 312.238644 20.615148) (xy 312.238644 21.021548)
					(xy 311.641744 21.021548) (xy 311.641744 21.117052) (xy 312.340244 21.117052) (xy 312.340244 20.019772)
				)
			)
		)
	)
	(footprint ""
		(layer "B.Cu")
		(at 413.174942 -293.99992 90)
		(property "Reference" "C1899"
			(at 0 0 90)
			(layer "B.SilkS")
			(hide yes)
			(effects
				(font
					(size 1.27 1.27)
				)
				(justify mirror)
			)
		)
		(property "Value" ""
			(at 0 0 90)
			(layer "B.Fab")
			(effects
				(font
					(size 1.27 1.27)
				)
				(justify mirror)
			)
		)
		(duplicate_pad_numbers_are_jumpers no)
		(fp_line
			(start 0.299974 -0.150114)
			(end -0.299974 -0.150114)
			(stroke
				(width 0.1)
				(type default)
			)
			(layer "B.Fab")
		)
		(fp_line
			(start -0.299974 -0.150114)
			(end -0.299974 0.150114)
			(stroke
				(width 0.1)
				(type default)
			)
			(layer "B.Fab")
		)
		(fp_line
			(start 0.299974 0.150114)
			(end 0.299974 -0.150114)
			(stroke
				(width 0.1)
				(type default)
			)
			(layer "B.Fab")
		)
		(fp_line
			(start -0.299974 0.150114)
			(end 0.299974 0.150114)
			(stroke
				(width 0.1)
				(type default)
			)
			(layer "B.Fab")
		)
		(pad "1" smd rect
			(at 0.2667 0 270)
			(size 0.3048 0.381)
			(layers "B.Cu" "B.Mask" "B.Paste")
			(net "P0V8_PEX3")
		)
		(pad "2" smd rect
			(at -0.2667 0 270)
			(size 0.3048 0.381)
			(layers "B.Cu" "B.Mask" "B.Paste")
			(net "GND")
		)
	)
	(footprint ""
		(layer "B.Cu")
		(at 396.07744 -300.7995 -90)
		(property "Reference" "C3544"
			(at 0 0 90)
			(layer "B.SilkS")
			(hide yes)
			(effects
				(font
					(size 1.27 1.27)
				)
				(justify mirror)
			)
		)
		(property "Value" ""
			(at 0 0 90)
			(layer "B.Fab")
			(effects
				(font
					(size 1.27 1.27)
				)
				(justify mirror)
			)
		)
		(duplicate_pad_numbers_are_jumpers no)
		(fp_line
			(start -0.299974 0.150114)
			(end 0.299974 0.150114)
			(stroke
				(width 0.1)
				(type default)
			)
			(layer "B.Fab")
		)
		(fp_line
			(start 0.299974 0.150114)
			(end 0.299974 -0.150114)
			(stroke
				(width 0.1)
				(type default)
			)
			(layer "B.Fab")
		)
		(fp_line
			(start -0.299974 -0.150114)
			(end -0.299974 0.150114)
			(stroke
				(width 0.1)
				(type default)
			)
			(layer "B.Fab")
		)
		(fp_line
			(start 0.299974 -0.150114)
			(end -0.299974 -0.150114)
			(stroke
				(width 0.1)
				(type default)
			)
			(layer "B.Fab")
		)
		(pad "1" smd rect
			(at 0.2667 0 90)
			(size 0.3048 0.381)
			(layers "B.Cu" "B.Mask" "B.Paste")
			(net "PCEPLL0_VDDA18_PEX3")
		)
		(pad "2" smd rect
			(at -0.2667 0 90)
			(size 0.3048 0.381)
			(layers "B.Cu" "B.Mask" "B.Paste")
			(net "GND")
		)
	)
	(footprint ""
		(layer "B.Cu")
		(at 193.641726 -103.104696 180)
		(property "Reference" "R169"
			(at 0 0 0)
			(layer "B.SilkS")
			(hide yes)
			(effects
				(font
					(size 1.27 1.27)
				)
				(justify mirror)
			)
		)
		(property "Value" ""
			(at 0 0 0)
			(layer "B.Fab")
			(effects
				(font
					(size 1.27 1.27)
				)
				(justify mirror)
			)
		)
		(duplicate_pad_numbers_are_jumpers no)
		(fp_line
			(start 0.7874 0.4064)
			(end 0.7874 -0.4064)
			(stroke
				(width 0.1524)
				(type default)
			)
			(layer "B.SilkS")
		)
		(fp_line
			(start 0.7874 -0.4064)
			(end -0.7874 -0.4064)
			(stroke
				(width 0.1524)
				(type default)
			)
			(layer "B.SilkS")
		)
		(fp_line
			(start -0.7874 0.4064)
			(end 0.7874 0.4064)
			(stroke
				(width 0.1524)
				(type default)
			)
			(layer "B.SilkS")
		)
		(fp_line
			(start -0.7874 -0.4064)
			(end -0.7874 0.4064)
			(stroke
				(width 0.1524)
				(type default)
			)
			(layer "B.SilkS")
		)
		(fp_line
			(start 0.67945 0.3048)
			(end 0.67945 -0.305054)
			(stroke
				(width 0.1)
				(type default)
			)
			(layer "B.Fab")
		)
		(fp_line
			(start 0.67945 -0.305054)
			(end 0.12065 -0.305054)
			(stroke
				(width 0.1)
				(type default)
			)
			(layer "B.Fab")
		)
		(fp_line
			(start 0.12065 0.3048)
			(end 0.67945 0.3048)
			(stroke
				(width 0.1)
				(type default)
			)
			(layer "B.Fab")
		)
		(fp_line
			(start 0.12065 0.2794)
			(end 0.12065 0.3048)
			(stroke
				(width 0.1)
				(type default)
			)
			(layer "B.Fab")
		)
		(fp_line
			(start 0.12065 -0.2794)
			(end -0.12065 -0.2794)
			(stroke
				(width 0.1)
				(type default)
			)
			(layer "B.Fab")
		)
		(fp_line
			(start 0.12065 -0.305054)
			(end 0.12065 -0.2794)
			(stroke
				(width 0.1)
				(type default)
			)
			(layer "B.Fab")
		)
		(fp_line
			(start -0.120396 0.3048)
			(end -0.120396 0.2794)
			(stroke
				(width 0.1)
				(type default)
			)
			(layer "B.Fab")
		)
		(fp_line
			(start -0.120396 0.2794)
			(end 0.12065 0.2794)
			(stroke
				(width 0.1)
				(type default)
			)
			(layer "B.Fab")
		)
		(fp_line
			(start -0.12065 -0.2794)
			(end -0.12065 -0.3048)
			(stroke
				(width 0.1)
				(type default)
			)
			(layer "B.Fab")
		)
		(fp_line
			(start -0.12065 -0.3048)
			(end -0.67945 -0.3048)
			(stroke
				(width 0.1)
				(type default)
			)
			(layer "B.Fab")
		)
		(fp_line
			(start -0.67945 0.3048)
			(end -0.120396 0.3048)
			(stroke
				(width 0.1)
				(type default)
			)
			(layer "B.Fab")
		)
		(fp_line
			(start -0.67945 -0.3048)
			(end -0.67945 0.3048)
			(stroke
				(width 0.1)
				(type default)
			)
			(layer "B.Fab")
		)
		(pad "1" smd circle
			(at 0.40005 0)
			(size 0 0)
			(layers "B.Cu" "B.Mask" "B.Paste")
			(net "NCSI_NIC3_RXD0")
		)
		(pad "2" smd circle
			(at -0.40005 0)
			(size 0 0)
			(layers "B.Cu" "B.Mask" "B.Paste")
			(net "GND")
		)
	)
	(footprint ""
		(layer "B.Cu")
		(at 175.749966 -299.699934 -90)
		(property "Reference" "C1472"
			(at 0 0 90)
			(layer "B.SilkS")
			(hide yes)
			(effects
				(font
					(size 1.27 1.27)
				)
				(justify mirror)
			)
		)
		(property "Value" ""
			(at 0 0 90)
			(layer "B.Fab")
			(effects
				(font
					(size 1.27 1.27)
				)
				(justify mirror)
			)
		)
		(duplicate_pad_numbers_are_jumpers no)
		(fp_line
			(start -0.299974 0.150114)
			(end 0.299974 0.150114)
			(stroke
				(width 0.1)
				(type default)
			)
			(layer "B.Fab")
		)
		(fp_line
			(start 0.299974 0.150114)
			(end 0.299974 -0.150114)
			(stroke
				(width 0.1)
				(type default)
			)
			(layer "B.Fab")
		)
		(fp_line
			(start -0.299974 -0.150114)
			(end -0.299974 0.150114)
			(stroke
				(width 0.1)
				(type default)
			)
			(layer "B.Fab")
		)
		(fp_line
			(start 0.299974 -0.150114)
			(end -0.299974 -0.150114)
			(stroke
				(width 0.1)
				(type default)
			)
			(layer "B.Fab")
		)
		(pad "1" smd rect
			(at 0.2667 0 90)
			(size 0.3048 0.381)
			(layers "B.Cu" "B.Mask" "B.Paste")
			(net "P0V8_SERDES_VDDA_PEX1")
		)
		(pad "2" smd rect
			(at -0.2667 0 90)
			(size 0.3048 0.381)
			(layers "B.Cu" "B.Mask" "B.Paste")
			(net "GND")
		)
	)
	(footprint ""
		(layer "B.Cu")
		(at 255.016254 -203.57465 180)
		(property "Reference" "R4298"
			(at 0 0 0)
			(layer "B.SilkS")
			(hide yes)
			(effects
				(font
					(size 1.27 1.27)
				)
				(justify mirror)
			)
		)
		(property "Value" ""
			(at 0 0 0)
			(layer "B.Fab")
			(effects
				(font
					(size 1.27 1.27)
				)
				(justify mirror)
			)
		)
		(duplicate_pad_numbers_are_jumpers no)
		(fp_line
			(start 0.7874 0.4064)
			(end 0.7874 -0.4064)
			(stroke
				(width 0.1524)
				(type default)
			)
			(layer "B.SilkS")
		)
		(fp_line
			(start 0.7874 -0.4064)
			(end -0.7874 -0.4064)
			(stroke
				(width 0.1524)
				(type default)
			)
			(layer "B.SilkS")
		)
		(fp_line
			(start -0.7874 0.4064)
			(end 0.7874 0.4064)
			(stroke
				(width 0.1524)
				(type default)
			)
			(layer "B.SilkS")
		)
		(fp_line
			(start -0.7874 -0.4064)
			(end -0.7874 0.4064)
			(stroke
				(width 0.1524)
				(type default)
			)
			(layer "B.SilkS")
		)
		(fp_line
			(start 0.67945 0.3048)
			(end 0.67945 -0.305054)
			(stroke
				(width 0.1)
				(type default)
			)
			(layer "B.Fab")
		)
		(fp_line
			(start 0.67945 -0.305054)
			(end 0.12065 -0.305054)
			(stroke
				(width 0.1)
				(type default)
			)
			(layer "B.Fab")
		)
		(fp_line
			(start 0.12065 0.3048)
			(end 0.67945 0.3048)
			(stroke
				(width 0.1)
				(type default)
			)
			(layer "B.Fab")
		)
		(fp_line
			(start 0.12065 0.2794)
			(end 0.12065 0.3048)
			(stroke
				(width 0.1)
				(type default)
			)
			(layer "B.Fab")
		)
		(fp_line
			(start 0.12065 -0.2794)
			(end -0.12065 -0.2794)
			(stroke
				(width 0.1)
				(type default)
			)
			(layer "B.Fab")
		)
		(fp_line
			(start 0.12065 -0.305054)
			(end 0.12065 -0.2794)
			(stroke
				(width 0.1)
				(type default)
			)
			(layer "B.Fab")
		)
		(fp_line
			(start -0.120396 0.3048)
			(end -0.120396 0.2794)
			(stroke
				(width 0.1)
				(type default)
			)
			(layer "B.Fab")
		)
		(fp_line
			(start -0.120396 0.2794)
			(end 0.12065 0.2794)
			(stroke
				(width 0.1)
				(type default)
			)
			(layer "B.Fab")
		)
		(fp_line
			(start -0.12065 -0.2794)
			(end -0.12065 -0.3048)
			(stroke
				(width 0.1)
				(type default)
			)
			(layer "B.Fab")
		)
		(fp_line
			(start -0.12065 -0.3048)
			(end -0.67945 -0.3048)
			(stroke
				(width 0.1)
				(type default)
			)
			(layer "B.Fab")
		)
		(fp_line
			(start -0.67945 0.3048)
			(end -0.120396 0.3048)
			(stroke
				(width 0.1)
				(type default)
			)
			(layer "B.Fab")
		)
		(fp_line
			(start -0.67945 -0.3048)
			(end -0.67945 0.3048)
			(stroke
				(width 0.1)
				(type default)
			)
			(layer "B.Fab")
		)
		(pad "1" smd circle
			(at 0.40005 0)
			(size 0 0)
			(layers "B.Cu" "B.Mask" "B.Paste")
			(net "JTAG_PLD_TDO")
		)
		(pad "2" smd circle
			(at -0.40005 0)
			(size 0 0)
			(layers "B.Cu" "B.Mask" "B.Paste")
			(net "JTAG_FPGA_TDO")
		)
	)
	(footprint ""
		(layer "B.Cu")
		(at 141.22273 -220.924374 90)
		(property "Reference" "R3467"
			(at 0 0 90)
			(layer "B.SilkS")
			(hide yes)
			(effects
				(font
					(size 1.27 1.27)
				)
				(justify mirror)
			)
		)
		(property "Value" ""
			(at 0 0 90)
			(layer "B.Fab")
			(effects
				(font
					(size 1.27 1.27)
				)
				(justify mirror)
			)
		)
		(duplicate_pad_numbers_are_jumpers no)
		(fp_line
			(start 0.7874 -0.4064)
			(end -0.7874 -0.4064)
			(stroke
				(width 0.1524)
				(type default)
			)
			(layer "B.SilkS")
		)
		(fp_line
			(start -0.7874 -0.4064)
			(end -0.7874 0.4064)
			(stroke
				(width 0.1524)
				(type default)
			)
			(layer "B.SilkS")
		)
		(fp_line
			(start 0.7874 0.4064)
			(end 0.7874 -0.4064)
			(stroke
				(width 0.1524)
				(type default)
			)
			(layer "B.SilkS")
		)
		(fp_line
			(start -0.7874 0.4064)
			(end 0.7874 0.4064)
			(stroke
				(width 0.1524)
				(type default)
			)
			(layer "B.SilkS")
		)
		(fp_line
			(start 0.67945 -0.305054)
			(end 0.12065 -0.305054)
			(stroke
				(width 0.1)
				(type default)
			)
			(layer "B.Fab")
		)
		(fp_line
			(start 0.12065 -0.305054)
			(end 0.12065 -0.2794)
			(stroke
				(width 0.1)
				(type default)
			)
			(layer "B.Fab")
		)
		(fp_line
			(start -0.12065 -0.3048)
			(end -0.67945 -0.3048)
			(stroke
				(width 0.1)
				(type default)
			)
			(layer "B.Fab")
		)
		(fp_line
			(start -0.67945 -0.3048)
			(end -0.67945 0.3048)
			(stroke
				(width 0.1)
				(type default)
			)
			(layer "B.Fab")
		)
		(fp_line
			(start 0.12065 -0.2794)
			(end -0.12065 -0.2794)
			(stroke
				(width 0.1)
				(type default)
			)
			(layer "B.Fab")
		)
		(fp_line
			(start -0.12065 -0.2794)
			(end -0.12065 -0.3048)
			(stroke
				(width 0.1)
				(type default)
			)
			(layer "B.Fab")
		)
		(fp_line
			(start 0.12065 0.2794)
			(end 0.12065 0.3048)
			(stroke
				(width 0.1)
				(type default)
			)
			(layer "B.Fab")
		)
		(fp_line
			(start -0.120396 0.2794)
			(end 0.12065 0.2794)
			(stroke
				(width 0.1)
				(type default)
			)
			(layer "B.Fab")
		)
		(fp_line
			(start 0.67945 0.3048)
			(end 0.67945 -0.305054)
			(stroke
				(width 0.1)
				(type default)
			)
			(layer "B.Fab")
		)
		(fp_line
			(start 0.12065 0.3048)
			(end 0.67945 0.3048)
			(stroke
				(width 0.1)
				(type default)
			)
			(layer "B.Fab")
		)
		(fp_line
			(start -0.120396 0.3048)
			(end -0.120396 0.2794)
			(stroke
				(width 0.1)
				(type default)
			)
			(layer "B.Fab")
		)
		(fp_line
			(start -0.67945 0.3048)
			(end -0.120396 0.3048)
			(stroke
				(width 0.1)
				(type default)
			)
			(layer "B.Fab")
		)
		(pad "1" smd circle
			(at 0.40005 0 270)
			(size 0 0)
			(layers "B.Cu" "B.Mask" "B.Paste")
			(net "P1V8_PEX")
		)
		(pad "2" smd circle
			(at -0.40005 0 270)
			(size 0 0)
			(layers "B.Cu" "B.Mask" "B.Paste")
			(net "SPI_PEX1_SDIO3_R1")
		)
	)
	(footprint ""
		(layer "B.Cu")
		(at 214.454486 -213.222586 180)
		(property "Reference" "R5531"
			(at 0 0 0)
			(layer "B.SilkS")
			(hide yes)
			(effects
				(font
					(size 1.27 1.27)
				)
				(justify mirror)
			)
		)
		(property "Value" ""
			(at 0 0 0)
			(layer "B.Fab")
			(effects
				(font
					(size 1.27 1.27)
				)
				(justify mirror)
			)
		)
		(duplicate_pad_numbers_are_jumpers no)
		(fp_line
			(start 0.7874 0.4064)
			(end 0.7874 -0.4064)
			(stroke
				(width 0.1524)
				(type default)
			)
			(layer "B.SilkS")
		)
		(fp_line
			(start 0.7874 -0.4064)
			(end -0.7874 -0.4064)
			(stroke
				(width 0.1524)
				(type default)
			)
			(layer "B.SilkS")
		)
		(fp_line
			(start -0.7874 0.4064)
			(end 0.7874 0.4064)
			(stroke
				(width 0.1524)
				(type default)
			)
			(layer "B.SilkS")
		)
		(fp_line
			(start -0.7874 -0.4064)
			(end -0.7874 0.4064)
			(stroke
				(width 0.1524)
				(type default)
			)
			(layer "B.SilkS")
		)
		(fp_line
			(start 0.67945 0.3048)
			(end 0.67945 -0.305054)
			(stroke
				(width 0.1)
				(type default)
			)
			(layer "B.Fab")
		)
		(fp_line
			(start 0.67945 -0.305054)
			(end 0.12065 -0.305054)
			(stroke
				(width 0.1)
				(type default)
			)
			(layer "B.Fab")
		)
		(fp_line
			(start 0.12065 0.3048)
			(end 0.67945 0.3048)
			(stroke
				(width 0.1)
				(type default)
			)
			(layer "B.Fab")
		)
		(fp_line
			(start 0.12065 0.2794)
			(end 0.12065 0.3048)
			(stroke
				(width 0.1)
				(type default)
			)
			(layer "B.Fab")
		)
		(fp_line
			(start 0.12065 -0.2794)
			(end -0.12065 -0.2794)
			(stroke
				(width 0.1)
				(type default)
			)
			(layer "B.Fab")
		)
		(fp_line
			(start 0.12065 -0.305054)
			(end 0.12065 -0.2794)
			(stroke
				(width 0.1)
				(type default)
			)
			(layer "B.Fab")
		)
		(fp_line
			(start -0.120396 0.3048)
			(end -0.120396 0.2794)
			(stroke
				(width 0.1)
				(type default)
			)
			(layer "B.Fab")
		)
		(fp_line
			(start -0.120396 0.2794)
			(end 0.12065 0.2794)
			(stroke
				(width 0.1)
				(type default)
			)
			(layer "B.Fab")
		)
		(fp_line
			(start -0.12065 -0.2794)
			(end -0.12065 -0.3048)
			(stroke
				(width 0.1)
				(type default)
			)
			(layer "B.Fab")
		)
		(fp_line
			(start -0.12065 -0.3048)
			(end -0.67945 -0.3048)
			(stroke
				(width 0.1)
				(type default)
			)
			(layer "B.Fab")
		)
		(fp_line
			(start -0.67945 0.3048)
			(end -0.120396 0.3048)
			(stroke
				(width 0.1)
				(type default)
			)
			(layer "B.Fab")
		)
		(fp_line
			(start -0.67945 -0.3048)
			(end -0.67945 0.3048)
			(stroke
				(width 0.1)
				(type default)
			)
			(layer "B.Fab")
		)
		(pad "1" smd circle
			(at 0.40005 0)
			(size 0 0)
			(layers "B.Cu" "B.Mask" "B.Paste")
			(net "GND")
		)
		(pad "2" smd circle
			(at -0.40005 0)
			(size 0 0)
			(layers "B.Cu" "B.Mask" "B.Paste")
			(net "RST_BIC_USB_HUB_R_N")
		)
	)
	(footprint ""
		(layer "B.Cu")
		(at 405.183848 -308.724808 -90)
		(property "Reference" "R1459"
			(at 0 0 90)
			(layer "B.SilkS")
			(hide yes)
			(effects
				(font
					(size 1.27 1.27)
				)
				(justify mirror)
			)
		)
		(property "Value" ""
			(at 0 0 90)
			(layer "B.Fab")
			(effects
				(font
					(size 1.27 1.27)
				)
				(justify mirror)
			)
		)
		(duplicate_pad_numbers_are_jumpers no)
		(fp_line
			(start -0.7874 0.4064)
			(end 0.7874 0.4064)
			(stroke
				(width 0.1524)
				(type default)
			)
			(layer "B.SilkS")
		)
		(fp_line
			(start 0.7874 0.4064)
			(end 0.7874 -0.4064)
			(stroke
				(width 0.1524)
				(type default)
			)
			(layer "B.SilkS")
		)
		(fp_line
			(start -0.7874 -0.4064)
			(end -0.7874 0.4064)
			(stroke
				(width 0.1524)
				(type default)
			)
			(layer "B.SilkS")
		)
		(fp_line
			(start 0.7874 -0.4064)
			(end -0.7874 -0.4064)
			(stroke
				(width 0.1524)
				(type default)
			)
			(layer "B.SilkS")
		)
		(fp_line
			(start -0.67945 0.3048)
			(end -0.120396 0.3048)
			(stroke
				(width 0.1)
				(type default)
			)
			(layer "B.Fab")
		)
		(fp_line
			(start -0.120396 0.3048)
			(end -0.120396 0.2794)
			(stroke
				(width 0.1)
				(type default)
			)
			(layer "B.Fab")
		)
		(fp_line
			(start 0.12065 0.3048)
			(end 0.67945 0.3048)
			(stroke
				(width 0.1)
				(type default)
			)
			(layer "B.Fab")
		)
		(fp_line
			(start 0.67945 0.3048)
			(end 0.67945 -0.305054)
			(stroke
				(width 0.1)
				(type default)
			)
			(layer "B.Fab")
		)
		(fp_line
			(start -0.120396 0.2794)
			(end 0.12065 0.2794)
			(stroke
				(width 0.1)
				(type default)
			)
			(layer "B.Fab")
		)
		(fp_line
			(start 0.12065 0.2794)
			(end 0.12065 0.3048)
			(stroke
				(width 0.1)
				(type default)
			)
			(layer "B.Fab")
		)
		(fp_line
			(start -0.12065 -0.2794)
			(end -0.12065 -0.3048)
			(stroke
				(width 0.1)
				(type default)
			)
			(layer "B.Fab")
		)
		(fp_line
			(start 0.12065 -0.2794)
			(end -0.12065 -0.2794)
			(stroke
				(width 0.1)
				(type default)
			)
			(layer "B.Fab")
		)
		(fp_line
			(start -0.67945 -0.3048)
			(end -0.67945 0.3048)
			(stroke
				(width 0.1)
				(type default)
			)
			(layer "B.Fab")
		)
		(fp_line
			(start -0.12065 -0.3048)
			(end -0.67945 -0.3048)
			(stroke
				(width 0.1)
				(type default)
			)
			(layer "B.Fab")
		)
		(fp_line
			(start 0.12065 -0.305054)
			(end 0.12065 -0.2794)
			(stroke
				(width 0.1)
				(type default)
			)
			(layer "B.Fab")
		)
		(fp_line
			(start 0.67945 -0.305054)
			(end 0.12065 -0.305054)
			(stroke
				(width 0.1)
				(type default)
			)
			(layer "B.Fab")
		)
		(pad "1" smd circle
			(at 0.40005 0 90)
			(size 0 0)
			(layers "B.Cu" "B.Mask" "B.Paste")
			(net "TP_PEX3_TRST_L")
		)
		(pad "2" smd circle
			(at -0.40005 0 90)
			(size 0 0)
			(layers "B.Cu" "B.Mask" "B.Paste")
			(net "GND")
		)
	)
	(footprint ""
		(layer "B.Cu")
		(at 241.660934 -278.639778 -90)
		(property "Reference" "C4348"
			(at 0 0 90)
			(layer "B.SilkS")
			(hide yes)
			(effects
				(font
					(size 1.27 1.27)
				)
				(justify mirror)
			)
		)
		(property "Value" ""
			(at 0 0 90)
			(layer "B.Fab")
			(effects
				(font
					(size 1.27 1.27)
				)
				(justify mirror)
			)
		)
		(duplicate_pad_numbers_are_jumpers no)
		(fp_line
			(start -0.299974 0.150114)
			(end 0.299974 0.150114)
			(stroke
				(width 0.1)
				(type default)
			)
			(layer "B.Fab")
		)
		(fp_line
			(start 0.299974 0.150114)
			(end 0.299974 -0.150114)
			(stroke
				(width 0.1)
				(type default)
			)
			(layer "B.Fab")
		)
		(fp_line
			(start -0.299974 -0.150114)
			(end -0.299974 0.150114)
			(stroke
				(width 0.1)
				(type default)
			)
			(layer "B.Fab")
		)
		(fp_line
			(start 0.299974 -0.150114)
			(end -0.299974 -0.150114)
			(stroke
				(width 0.1)
				(type default)
			)
			(layer "B.Fab")
		)
		(pad "1" smd rect
			(at 0.2667 0 90)
			(size 0.3048 0.381)
			(layers "B.Cu" "B.Mask" "B.Paste")
			(net "P1V25_PEX2")
		)
		(pad "2" smd rect
			(at -0.2667 0 90)
			(size 0.3048 0.381)
			(layers "B.Cu" "B.Mask" "B.Paste")
			(net "GND")
		)
	)
	(footprint ""
		(layer "B.Cu")
		(at 182.87492 -293.99992 90)
		(property "Reference" "C1420"
			(at 0 0 90)
			(layer "B.SilkS")
			(hide yes)
			(effects
				(font
					(size 1.27 1.27)
				)
				(justify mirror)
			)
		)
		(property "Value" ""
			(at 0 0 90)
			(layer "B.Fab")
			(effects
				(font
					(size 1.27 1.27)
				)
				(justify mirror)
			)
		)
		(duplicate_pad_numbers_are_jumpers no)
		(fp_line
			(start 0.299974 -0.150114)
			(end -0.299974 -0.150114)
			(stroke
				(width 0.1)
				(type default)
			)
			(layer "B.Fab")
		)
		(fp_line
			(start -0.299974 -0.150114)
			(end -0.299974 0.150114)
			(stroke
				(width 0.1)
				(type default)
			)
			(layer "B.Fab")
		)
		(fp_line
			(start 0.299974 0.150114)
			(end 0.299974 -0.150114)
			(stroke
				(width 0.1)
				(type default)
			)
			(layer "B.Fab")
		)
		(fp_line
			(start -0.299974 0.150114)
			(end 0.299974 0.150114)
			(stroke
				(width 0.1)
				(type default)
			)
			(layer "B.Fab")
		)
		(pad "1" smd rect
			(at 0.2667 0 270)
			(size 0.3048 0.381)
			(layers "B.Cu" "B.Mask" "B.Paste")
			(net "P0V8_SERDES_VDDA_PEX1")
		)
		(pad "2" smd rect
			(at -0.2667 0 270)
			(size 0.3048 0.381)
			(layers "B.Cu" "B.Mask" "B.Paste")
			(net "GND")
		)
	)
	(footprint ""
		(layer "B.Cu")
		(at 87.175848 -459.136496)
		(property "Reference" "X26"
			(at 0.1778 -1.92913 0)
			(unlocked yes)
			(layer "B.SilkS")
			(effects
				(font
					(size 0.7874 0.5842)
					(thickness 0.1524)
				)
				(justify left mirror)
			)
		)
		(property "Value" ""
			(at 0 0 0)
			(layer "B.Fab")
			(effects
				(font
					(size 1.27 1.27)
				)
				(justify mirror)
			)
		)
		(property "Device Type" "TP_TDR_4P_FTS_MPKT4_H025P0200_IO_TP15_TP_TDR_4P_DIP"
			(at -1.30175 1.27 270)
			(unlocked yes)
			(layer "B.Fab")
			(hide yes)
			(effects
				(font
					(size 0.635 0.4064)
					(thickness 0.1524)
				)
				(justify mirror)
			)
		)
		(property "User Part Number" "TP15"
			(at -1.30175 1.27 270)
			(unlocked yes)
			(layer "Cmts.User")
			(hide yes)
			(effects
				(font
					(size 0.635 0.4064)
					(thickness 0.1524)
				)
				(justify mirror)
			)
		)
		(duplicate_pad_numbers_are_jumpers no)
		(fp_line
			(start -2.54 -1.27)
			(end 0 -1.27)
			(stroke
				(width 0.1524)
				(type default)
			)
			(layer "B.SilkS")
		)
		(fp_line
			(start -2.54 -1.1303)
			(end -2.54 -1.27)
			(stroke
				(width 0.1524)
				(type default)
			)
			(layer "B.SilkS")
		)
		(fp_line
			(start -2.54 1.4097)
			(end -2.54 1.1303)
			(stroke
				(width 0.1524)
				(type default)
			)
			(layer "B.SilkS")
		)
		(fp_line
			(start -2.54 3.81)
			(end -2.54 3.6703)
			(stroke
				(width 0.1524)
				(type default)
			)
			(layer "B.SilkS")
		)
		(fp_line
			(start 0 -1.27)
			(end 0 -0.635)
			(stroke
				(width 0.1524)
				(type default)
			)
			(layer "B.SilkS")
		)
		(fp_line
			(start 0 0.635)
			(end 0 1.905)
			(stroke
				(width 0.1524)
				(type default)
			)
			(layer "B.SilkS")
		)
		(fp_line
			(start 0 3.175)
			(end 0 3.81)
			(stroke
				(width 0.1524)
				(type default)
			)
			(layer "B.SilkS")
		)
		(fp_line
			(start 0 3.81)
			(end -2.54 3.81)
			(stroke
				(width 0.1524)
				(type default)
			)
			(layer "B.SilkS")
		)
		(fp_poly
			(pts
				(xy 0.761746 0) (xy 2.285746 -0.762) (xy 2.285746 0.762)
			)
			(stroke
				(width 0)
				(type default)
			)
			(fill yes)
			(layer "B.SilkS")
		)
		(fp_line
			(start -2.54 -1.27)
			(end 0 -1.27)
			(stroke
				(width 0.1)
				(type default)
			)
			(layer "B.Fab")
		)
		(fp_line
			(start -2.54 3.81)
			(end -2.54 -1.27)
			(stroke
				(width 0.1)
				(type default)
			)
			(layer "B.Fab")
		)
		(fp_line
			(start 0 -1.27)
			(end 0 3.81)
			(stroke
				(width 0.1)
				(type default)
			)
			(layer "B.Fab")
		)
		(fp_line
			(start 0 3.81)
			(end -2.54 3.81)
			(stroke
				(width 0.1)
				(type default)
			)
			(layer "B.Fab")
		)
		(fp_poly
			(pts
				(xy 0.761746 0) (xy 2.285746 -0.762) (xy 2.285746 0.762)
			)
			(stroke
				(width 0)
				(type default)
			)
			(fill yes)
			(layer "B.Fab")
		)
		(pad "1" thru_hole circle
			(at 0 0 180)
			(size 1.0033 1.0033)
			(drill 0.249936)
			(layers "*.Cu" "*.Mask")
			(remove_unused_layers no)
			(net "TDR_DIFF_85_IN4_DIP")
			(clearance 0.10795)
			(padstack
				(mode front_inner_back)
				(layer "Inner"
					(shape circle)
					(size 0.8001 0.8001)
					(clearance 0.1524)
				)
				(layer "B.Cu"
					(shape circle)
					(size 1.0033 1.0033)
					(thermal_gap 0.10795)
					(clearance 0.10795)
				)
			)
		)
		(pad "2" thru_hole circle
			(at -2.54 0 180)
			(size 1.9939 1.9939)
			(drill 0.249936)
			(layers "*.Cu" "*.Mask")
			(remove_unused_layers no)
			(net "COUPON_GND1")
			(clearance 0.10795)
			(padstack
				(mode front_inner_back)
				(layer "Inner"
					(shape circle)
					(size 0.8001 0.8001)
					(clearance 0.1524)
				)
				(layer "B.Cu"
					(shape circle)
					(size 1.9939 1.9939)
					(thermal_gap 0.10795)
					(clearance 0.10795)
				)
			)
		)
		(pad "3" thru_hole circle
			(at -2.54 2.54 180)
			(size 1.9939 1.9939)
			(drill 0.249936)
			(layers "*.Cu" "*.Mask")
			(remove_unused_layers no)
			(net "COUPON_GND1")
			(clearance 0.10795)
			(padstack
				(mode front_inner_back)
				(layer "Inner"
					(shape circle)
					(size 0.8001 0.8001)
					(clearance 0.1524)
				)
				(layer "B.Cu"
					(shape circle)
					(size 1.9939 1.9939)
					(thermal_gap 0.10795)
					(clearance 0.10795)
				)
			)
		)
		(pad "4" thru_hole circle
			(at 0 2.54 180)
			(size 1.0033 1.0033)
			(drill 0.249936)
			(layers "*.Cu" "*.Mask")
			(remove_unused_layers no)
			(net "TDR_DIFF_85_IN4_DIN")
			(clearance 0.10795)
			(padstack
				(mode front_inner_back)
				(layer "Inner"
					(shape circle)
					(size 0.8001 0.8001)
					(clearance 0.1524)
				)
				(layer "B.Cu"
					(shape circle)
					(size 1.0033 1.0033)
					(thermal_gap 0.10795)
					(clearance 0.10795)
				)
			)
		)
	)
	(footprint ""
		(layer "B.Cu")
		(at 129.243074 -277.644352 180)
		(property "Reference" "PC6612"
			(at 0 0 0)
			(layer "B.SilkS")
			(hide yes)
			(effects
				(font
					(size 1.27 1.27)
				)
				(justify mirror)
			)
		)
		(property "Value" ""
			(at 0 0 0)
			(layer "B.Fab")
			(effects
				(font
					(size 1.27 1.27)
				)
				(justify mirror)
			)
		)
		(duplicate_pad_numbers_are_jumpers no)
		(fp_line
			(start 1.524 0.762)
			(end 1.524 -0.762)
			(stroke
				(width 0.1524)
				(type default)
			)
			(layer "B.SilkS")
		)
		(fp_line
			(start 1.524 -0.762)
			(end -1.524 -0.762)
			(stroke
				(width 0.1524)
				(type default)
			)
			(layer "B.SilkS")
		)
		(fp_line
			(start -1.524 0.762)
			(end 1.524 0.762)
			(stroke
				(width 0.1524)
				(type default)
			)
			(layer "B.SilkS")
		)
		(fp_line
			(start -1.524 -0.762)
			(end -1.524 0.762)
			(stroke
				(width 0.1524)
				(type default)
			)
			(layer "B.SilkS")
		)
		(fp_line
			(start 1.1049 0.724916)
			(end -1.1049 0.724916)
			(stroke
				(width 0.1)
				(type default)
			)
			(layer "B.Fab")
		)
		(fp_line
			(start 1.1049 -0.724916)
			(end 1.1049 0.724916)
			(stroke
				(width 0.1)
				(type default)
			)
			(layer "B.Fab")
		)
		(fp_line
			(start -1.1049 0.724916)
			(end -1.1049 -0.724916)
			(stroke
				(width 0.1)
				(type default)
			)
			(layer "B.Fab")
		)
		(fp_line
			(start -1.1049 -0.724916)
			(end 1.1049 -0.724916)
			(stroke
				(width 0.1)
				(type default)
			)
			(layer "B.Fab")
		)
		(pad "1" smd rect
			(at 0.889 0 180)
			(size 1.016 1.27)
			(layers "B.Cu" "B.Mask" "B.Paste")
			(net "SW_P12V_P0V8_PEX1_FLT")
		)
		(pad "2" smd rect
			(at -0.889 0 180)
			(size 1.016 1.27)
			(layers "B.Cu" "B.Mask" "B.Paste")
			(net "GND")
		)
	)
	(footprint ""
		(layer "B.Cu")
		(at 55.374794 -297.79976 90)
		(property "Reference" "C1151"
			(at 0 0 90)
			(layer "B.SilkS")
			(hide yes)
			(effects
				(font
					(size 1.27 1.27)
				)
				(justify mirror)
			)
		)
		(property "Value" ""
			(at 0 0 90)
			(layer "B.Fab")
			(effects
				(font
					(size 1.27 1.27)
				)
				(justify mirror)
			)
		)
		(duplicate_pad_numbers_are_jumpers no)
		(fp_line
			(start 0.299974 -0.150114)
			(end -0.299974 -0.150114)
			(stroke
				(width 0.1)
				(type default)
			)
			(layer "B.Fab")
		)
		(fp_line
			(start -0.299974 -0.150114)
			(end -0.299974 0.150114)
			(stroke
				(width 0.1)
				(type default)
			)
			(layer "B.Fab")
		)
		(fp_line
			(start 0.299974 0.150114)
			(end 0.299974 -0.150114)
			(stroke
				(width 0.1)
				(type default)
			)
			(layer "B.Fab")
		)
		(fp_line
			(start -0.299974 0.150114)
			(end 0.299974 0.150114)
			(stroke
				(width 0.1)
				(type default)
			)
			(layer "B.Fab")
		)
		(pad "1" smd rect
			(at 0.2667 0 270)
			(size 0.3048 0.381)
			(layers "B.Cu" "B.Mask" "B.Paste")
			(net "P0V8_PEX0")
		)
		(pad "2" smd rect
			(at -0.2667 0 270)
			(size 0.3048 0.381)
			(layers "B.Cu" "B.Mask" "B.Paste")
			(net "GND")
		)
	)
	(footprint ""
		(layer "B.Cu")
		(at 101.223318 -392.9888 180)
		(property "Reference" "C3631"
			(at 0 0 0)
			(layer "B.SilkS")
			(hide yes)
			(effects
				(font
					(size 1.27 1.27)
				)
				(justify mirror)
			)
		)
		(property "Value" ""
			(at 0 0 0)
			(layer "B.Fab")
			(effects
				(font
					(size 1.27 1.27)
				)
				(justify mirror)
			)
		)
		(duplicate_pad_numbers_are_jumpers no)
		(fp_line
			(start 0.7874 0.4064)
			(end 0.7874 -0.4064)
			(stroke
				(width 0.1524)
				(type default)
			)
			(layer "B.SilkS")
		)
		(fp_line
			(start 0.7874 -0.4064)
			(end -0.7874 -0.4064)
			(stroke
				(width 0.1524)
				(type default)
			)
			(layer "B.SilkS")
		)
		(fp_line
			(start -0.7874 0.4064)
			(end 0.7874 0.4064)
			(stroke
				(width 0.1524)
				(type default)
			)
			(layer "B.SilkS")
		)
		(fp_line
			(start -0.7874 -0.4064)
			(end -0.7874 0.4064)
			(stroke
				(width 0.1524)
				(type default)
			)
			(layer "B.SilkS")
		)
		(fp_line
			(start 0.67945 0.3048)
			(end 0.67945 -0.305054)
			(stroke
				(width 0.1)
				(type default)
			)
			(layer "B.Fab")
		)
		(fp_line
			(start 0.67945 -0.305054)
			(end 0.12065 -0.305054)
			(stroke
				(width 0.1)
				(type default)
			)
			(layer "B.Fab")
		)
		(fp_line
			(start 0.12065 0.3048)
			(end 0.67945 0.3048)
			(stroke
				(width 0.1)
				(type default)
			)
			(layer "B.Fab")
		)
		(fp_line
			(start 0.12065 0.2794)
			(end 0.12065 0.3048)
			(stroke
				(width 0.1)
				(type default)
			)
			(layer "B.Fab")
		)
		(fp_line
			(start 0.12065 -0.2794)
			(end -0.12065 -0.2794)
			(stroke
				(width 0.1)
				(type default)
			)
			(layer "B.Fab")
		)
		(fp_line
			(start 0.12065 -0.305054)
			(end 0.12065 -0.2794)
			(stroke
				(width 0.1)
				(type default)
			)
			(layer "B.Fab")
		)
		(fp_line
			(start -0.120396 0.3048)
			(end -0.120396 0.2794)
			(stroke
				(width 0.1)
				(type default)
			)
			(layer "B.Fab")
		)
		(fp_line
			(start -0.120396 0.2794)
			(end 0.12065 0.2794)
			(stroke
				(width 0.1)
				(type default)
			)
			(layer "B.Fab")
		)
		(fp_line
			(start -0.12065 -0.2794)
			(end -0.12065 -0.3048)
			(stroke
				(width 0.1)
				(type default)
			)
			(layer "B.Fab")
		)
		(fp_line
			(start -0.12065 -0.3048)
			(end -0.67945 -0.3048)
			(stroke
				(width 0.1)
				(type default)
			)
			(layer "B.Fab")
		)
		(fp_line
			(start -0.67945 0.3048)
			(end -0.120396 0.3048)
			(stroke
				(width 0.1)
				(type default)
			)
			(layer "B.Fab")
		)
		(fp_line
			(start -0.67945 -0.3048)
			(end -0.67945 0.3048)
			(stroke
				(width 0.1)
				(type default)
			)
			(layer "B.Fab")
		)
		(pad "1" smd circle
			(at 0.40005 0)
			(size 0 0)
			(layers "B.Cu" "B.Mask" "B.Paste")
			(net "P3V3_BIC_USB_HUB")
		)
		(pad "2" smd circle
			(at -0.40005 0)
			(size 0 0)
			(layers "B.Cu" "B.Mask" "B.Paste")
			(net "GND")
		)
	)
	(footprint ""
		(layer "B.Cu")
		(at 419.590728 -118.711218 180)
		(property "Reference" "R381"
			(at 0 0 0)
			(layer "B.SilkS")
			(hide yes)
			(effects
				(font
					(size 1.27 1.27)
				)
				(justify mirror)
			)
		)
		(property "Value" ""
			(at 0 0 0)
			(layer "B.Fab")
			(effects
				(font
					(size 1.27 1.27)
				)
				(justify mirror)
			)
		)
		(duplicate_pad_numbers_are_jumpers no)
		(fp_line
			(start 0.7874 0.4064)
			(end 0.7874 -0.4064)
			(stroke
				(width 0.1524)
				(type default)
			)
			(layer "B.SilkS")
		)
		(fp_line
			(start 0.7874 -0.4064)
			(end -0.7874 -0.4064)
			(stroke
				(width 0.1524)
				(type default)
			)
			(layer "B.SilkS")
		)
		(fp_line
			(start -0.7874 0.4064)
			(end 0.7874 0.4064)
			(stroke
				(width 0.1524)
				(type default)
			)
			(layer "B.SilkS")
		)
		(fp_line
			(start -0.7874 -0.4064)
			(end -0.7874 0.4064)
			(stroke
				(width 0.1524)
				(type default)
			)
			(layer "B.SilkS")
		)
		(fp_line
			(start 0.67945 0.3048)
			(end 0.67945 -0.305054)
			(stroke
				(width 0.1)
				(type default)
			)
			(layer "B.Fab")
		)
		(fp_line
			(start 0.67945 -0.305054)
			(end 0.12065 -0.305054)
			(stroke
				(width 0.1)
				(type default)
			)
			(layer "B.Fab")
		)
		(fp_line
			(start 0.12065 0.3048)
			(end 0.67945 0.3048)
			(stroke
				(width 0.1)
				(type default)
			)
			(layer "B.Fab")
		)
		(fp_line
			(start 0.12065 0.2794)
			(end 0.12065 0.3048)
			(stroke
				(width 0.1)
				(type default)
			)
			(layer "B.Fab")
		)
		(fp_line
			(start 0.12065 -0.2794)
			(end -0.12065 -0.2794)
			(stroke
				(width 0.1)
				(type default)
			)
			(layer "B.Fab")
		)
		(fp_line
			(start 0.12065 -0.305054)
			(end 0.12065 -0.2794)
			(stroke
				(width 0.1)
				(type default)
			)
			(layer "B.Fab")
		)
		(fp_line
			(start -0.120396 0.3048)
			(end -0.120396 0.2794)
			(stroke
				(width 0.1)
				(type default)
			)
			(layer "B.Fab")
		)
		(fp_line
			(start -0.120396 0.2794)
			(end 0.12065 0.2794)
			(stroke
				(width 0.1)
				(type default)
			)
			(layer "B.Fab")
		)
		(fp_line
			(start -0.12065 -0.2794)
			(end -0.12065 -0.3048)
			(stroke
				(width 0.1)
				(type default)
			)
			(layer "B.Fab")
		)
		(fp_line
			(start -0.12065 -0.3048)
			(end -0.67945 -0.3048)
			(stroke
				(width 0.1)
				(type default)
			)
			(layer "B.Fab")
		)
		(fp_line
			(start -0.67945 0.3048)
			(end -0.120396 0.3048)
			(stroke
				(width 0.1)
				(type default)
			)
			(layer "B.Fab")
		)
		(fp_line
			(start -0.67945 -0.3048)
			(end -0.67945 0.3048)
			(stroke
				(width 0.1)
				(type default)
			)
			(layer "B.Fab")
		)
		(pad "1" smd circle
			(at 0.40005 0)
			(size 0 0)
			(layers "B.Cu" "B.Mask" "B.Paste")
			(net "NIC7_AUX_PWR_EN")
		)
		(pad "2" smd circle
			(at -0.40005 0)
			(size 0 0)
			(layers "B.Cu" "B.Mask" "B.Paste")
			(net "GND")
		)
	)
	(footprint ""
		(layer "B.Cu")
		(at 425.841922 -102.088696 180)
		(property "Reference" "R374"
			(at 0 0 0)
			(layer "B.SilkS")
			(hide yes)
			(effects
				(font
					(size 1.27 1.27)
				)
				(justify mirror)
			)
		)
		(property "Value" ""
			(at 0 0 0)
			(layer "B.Fab")
			(effects
				(font
					(size 1.27 1.27)
				)
				(justify mirror)
			)
		)
		(duplicate_pad_numbers_are_jumpers no)
		(fp_line
			(start 0.7874 0.4064)
			(end 0.7874 -0.4064)
			(stroke
				(width 0.1524)
				(type default)
			)
			(layer "B.SilkS")
		)
		(fp_line
			(start 0.7874 -0.4064)
			(end -0.7874 -0.4064)
			(stroke
				(width 0.1524)
				(type default)
			)
			(layer "B.SilkS")
		)
		(fp_line
			(start -0.7874 0.4064)
			(end 0.7874 0.4064)
			(stroke
				(width 0.1524)
				(type default)
			)
			(layer "B.SilkS")
		)
		(fp_line
			(start -0.7874 -0.4064)
			(end -0.7874 0.4064)
			(stroke
				(width 0.1524)
				(type default)
			)
			(layer "B.SilkS")
		)
		(fp_line
			(start 0.67945 0.3048)
			(end 0.67945 -0.305054)
			(stroke
				(width 0.1)
				(type default)
			)
			(layer "B.Fab")
		)
		(fp_line
			(start 0.67945 -0.305054)
			(end 0.12065 -0.305054)
			(stroke
				(width 0.1)
				(type default)
			)
			(layer "B.Fab")
		)
		(fp_line
			(start 0.12065 0.3048)
			(end 0.67945 0.3048)
			(stroke
				(width 0.1)
				(type default)
			)
			(layer "B.Fab")
		)
		(fp_line
			(start 0.12065 0.2794)
			(end 0.12065 0.3048)
			(stroke
				(width 0.1)
				(type default)
			)
			(layer "B.Fab")
		)
		(fp_line
			(start 0.12065 -0.2794)
			(end -0.12065 -0.2794)
			(stroke
				(width 0.1)
				(type default)
			)
			(layer "B.Fab")
		)
		(fp_line
			(start 0.12065 -0.305054)
			(end 0.12065 -0.2794)
			(stroke
				(width 0.1)
				(type default)
			)
			(layer "B.Fab")
		)
		(fp_line
			(start -0.120396 0.3048)
			(end -0.120396 0.2794)
			(stroke
				(width 0.1)
				(type default)
			)
			(layer "B.Fab")
		)
		(fp_line
			(start -0.120396 0.2794)
			(end 0.12065 0.2794)
			(stroke
				(width 0.1)
				(type default)
			)
			(layer "B.Fab")
		)
		(fp_line
			(start -0.12065 -0.2794)
			(end -0.12065 -0.3048)
			(stroke
				(width 0.1)
				(type default)
			)
			(layer "B.Fab")
		)
		(fp_line
			(start -0.12065 -0.3048)
			(end -0.67945 -0.3048)
			(stroke
				(width 0.1)
				(type default)
			)
			(layer "B.Fab")
		)
		(fp_line
			(start -0.67945 0.3048)
			(end -0.120396 0.3048)
			(stroke
				(width 0.1)
				(type default)
			)
			(layer "B.Fab")
		)
		(fp_line
			(start -0.67945 -0.3048)
			(end -0.67945 0.3048)
			(stroke
				(width 0.1)
				(type default)
			)
			(layer "B.Fab")
		)
		(pad "1" smd circle
			(at 0.40005 0)
			(size 0 0)
			(layers "B.Cu" "B.Mask" "B.Paste")
			(net "NCSI_NIC7_RXD1")
		)
		(pad "2" smd circle
			(at -0.40005 0)
			(size 0 0)
			(layers "B.Cu" "B.Mask" "B.Paste")
			(net "GND")
		)
	)
	(footprint ""
		(layer "B.Cu")
		(at 110.86719 -335.481676 90)
		(property "Reference" "R1220"
			(at 0 0 90)
			(layer "B.SilkS")
			(hide yes)
			(effects
				(font
					(size 1.27 1.27)
				)
				(justify mirror)
			)
		)
		(property "Value" ""
			(at 0 0 90)
			(layer "B.Fab")
			(effects
				(font
					(size 1.27 1.27)
				)
				(justify mirror)
			)
		)
		(duplicate_pad_numbers_are_jumpers no)
		(fp_line
			(start 0.7874 -0.4064)
			(end -0.7874 -0.4064)
			(stroke
				(width 0.1524)
				(type default)
			)
			(layer "B.SilkS")
		)
		(fp_line
			(start -0.7874 -0.4064)
			(end -0.7874 0.4064)
			(stroke
				(width 0.1524)
				(type default)
			)
			(layer "B.SilkS")
		)
		(fp_line
			(start 0.7874 0.4064)
			(end 0.7874 -0.4064)
			(stroke
				(width 0.1524)
				(type default)
			)
			(layer "B.SilkS")
		)
		(fp_line
			(start -0.7874 0.4064)
			(end 0.7874 0.4064)
			(stroke
				(width 0.1524)
				(type default)
			)
			(layer "B.SilkS")
		)
		(fp_line
			(start 0.67945 -0.305054)
			(end 0.12065 -0.305054)
			(stroke
				(width 0.1)
				(type default)
			)
			(layer "B.Fab")
		)
		(fp_line
			(start 0.12065 -0.305054)
			(end 0.12065 -0.2794)
			(stroke
				(width 0.1)
				(type default)
			)
			(layer "B.Fab")
		)
		(fp_line
			(start -0.12065 -0.3048)
			(end -0.67945 -0.3048)
			(stroke
				(width 0.1)
				(type default)
			)
			(layer "B.Fab")
		)
		(fp_line
			(start -0.67945 -0.3048)
			(end -0.67945 0.3048)
			(stroke
				(width 0.1)
				(type default)
			)
			(layer "B.Fab")
		)
		(fp_line
			(start 0.12065 -0.2794)
			(end -0.12065 -0.2794)
			(stroke
				(width 0.1)
				(type default)
			)
			(layer "B.Fab")
		)
		(fp_line
			(start -0.12065 -0.2794)
			(end -0.12065 -0.3048)
			(stroke
				(width 0.1)
				(type default)
			)
			(layer "B.Fab")
		)
		(fp_line
			(start 0.12065 0.2794)
			(end 0.12065 0.3048)
			(stroke
				(width 0.1)
				(type default)
			)
			(layer "B.Fab")
		)
		(fp_line
			(start -0.120396 0.2794)
			(end 0.12065 0.2794)
			(stroke
				(width 0.1)
				(type default)
			)
			(layer "B.Fab")
		)
		(fp_line
			(start 0.67945 0.3048)
			(end 0.67945 -0.305054)
			(stroke
				(width 0.1)
				(type default)
			)
			(layer "B.Fab")
		)
		(fp_line
			(start 0.12065 0.3048)
			(end 0.67945 0.3048)
			(stroke
				(width 0.1)
				(type default)
			)
			(layer "B.Fab")
		)
		(fp_line
			(start -0.120396 0.3048)
			(end -0.120396 0.2794)
			(stroke
				(width 0.1)
				(type default)
			)
			(layer "B.Fab")
		)
		(fp_line
			(start -0.67945 0.3048)
			(end -0.120396 0.3048)
			(stroke
				(width 0.1)
				(type default)
			)
			(layer "B.Fab")
		)
		(pad "1" smd circle
			(at 0.40005 0 270)
			(size 0 0)
			(layers "B.Cu" "B.Mask" "B.Paste")
			(net "P3V3")
		)
		(pad "2" smd circle
			(at -0.40005 0 270)
			(size 0 0)
			(layers "B.Cu" "B.Mask" "B.Paste")
			(net "PU_9ZXL0451E_HBW")
		)
	)
	(footprint ""
		(layer "B.Cu")
		(at 66.299842 -303.499774 -90)
		(property "Reference" "C2905"
			(at 0 0 90)
			(layer "B.SilkS")
			(hide yes)
			(effects
				(font
					(size 1.27 1.27)
				)
				(justify mirror)
			)
		)
		(property "Value" ""
			(at 0 0 90)
			(layer "B.Fab")
			(effects
				(font
					(size 1.27 1.27)
				)
				(justify mirror)
			)
		)
		(duplicate_pad_numbers_are_jumpers no)
		(fp_line
			(start -0.299974 0.150114)
			(end 0.299974 0.150114)
			(stroke
				(width 0.1)
				(type default)
			)
			(layer "B.Fab")
		)
		(fp_line
			(start 0.299974 0.150114)
			(end 0.299974 -0.150114)
			(stroke
				(width 0.1)
				(type default)
			)
			(layer "B.Fab")
		)
		(fp_line
			(start -0.299974 -0.150114)
			(end -0.299974 0.150114)
			(stroke
				(width 0.1)
				(type default)
			)
			(layer "B.Fab")
		)
		(fp_line
			(start 0.299974 -0.150114)
			(end -0.299974 -0.150114)
			(stroke
				(width 0.1)
				(type default)
			)
			(layer "B.Fab")
		)
		(pad "1" smd rect
			(at 0.2667 0 90)
			(size 0.3048 0.381)
			(layers "B.Cu" "B.Mask" "B.Paste")
			(net "P1V25_PEX0")
		)
		(pad "2" smd rect
			(at -0.2667 0 90)
			(size 0.3048 0.381)
			(layers "B.Cu" "B.Mask" "B.Paste")
			(net "GND")
		)
	)
	(footprint ""
		(layer "B.Cu")
		(at 213.106 -192.405 90)
		(property "Reference" "R6313"
			(at 0 0 90)
			(layer "B.SilkS")
			(hide yes)
			(effects
				(font
					(size 1.27 1.27)
				)
				(justify mirror)
			)
		)
		(property "Value" ""
			(at 0 0 90)
			(layer "B.Fab")
			(effects
				(font
					(size 1.27 1.27)
				)
				(justify mirror)
			)
		)
		(duplicate_pad_numbers_are_jumpers no)
		(fp_line
			(start 0.7874 -0.4064)
			(end -0.7874 -0.4064)
			(stroke
				(width 0.1524)
				(type default)
			)
			(layer "B.SilkS")
		)
		(fp_line
			(start -0.7874 -0.4064)
			(end -0.7874 0.4064)
			(stroke
				(width 0.1524)
				(type default)
			)
			(layer "B.SilkS")
		)
		(fp_line
			(start 0.7874 0.4064)
			(end 0.7874 -0.4064)
			(stroke
				(width 0.1524)
				(type default)
			)
			(layer "B.SilkS")
		)
		(fp_line
			(start -0.7874 0.4064)
			(end 0.7874 0.4064)
			(stroke
				(width 0.1524)
				(type default)
			)
			(layer "B.SilkS")
		)
		(fp_line
			(start 0.67945 -0.305054)
			(end 0.12065 -0.305054)
			(stroke
				(width 0.1)
				(type default)
			)
			(layer "B.Fab")
		)
		(fp_line
			(start 0.12065 -0.305054)
			(end 0.12065 -0.2794)
			(stroke
				(width 0.1)
				(type default)
			)
			(layer "B.Fab")
		)
		(fp_line
			(start -0.12065 -0.3048)
			(end -0.67945 -0.3048)
			(stroke
				(width 0.1)
				(type default)
			)
			(layer "B.Fab")
		)
		(fp_line
			(start -0.67945 -0.3048)
			(end -0.67945 0.3048)
			(stroke
				(width 0.1)
				(type default)
			)
			(layer "B.Fab")
		)
		(fp_line
			(start 0.12065 -0.2794)
			(end -0.12065 -0.2794)
			(stroke
				(width 0.1)
				(type default)
			)
			(layer "B.Fab")
		)
		(fp_line
			(start -0.12065 -0.2794)
			(end -0.12065 -0.3048)
			(stroke
				(width 0.1)
				(type default)
			)
			(layer "B.Fab")
		)
		(fp_line
			(start 0.12065 0.2794)
			(end 0.12065 0.3048)
			(stroke
				(width 0.1)
				(type default)
			)
			(layer "B.Fab")
		)
		(fp_line
			(start -0.120396 0.2794)
			(end 0.12065 0.2794)
			(stroke
				(width 0.1)
				(type default)
			)
			(layer "B.Fab")
		)
		(fp_line
			(start 0.67945 0.3048)
			(end 0.67945 -0.305054)
			(stroke
				(width 0.1)
				(type default)
			)
			(layer "B.Fab")
		)
		(fp_line
			(start 0.12065 0.3048)
			(end 0.67945 0.3048)
			(stroke
				(width 0.1)
				(type default)
			)
			(layer "B.Fab")
		)
		(fp_line
			(start -0.120396 0.3048)
			(end -0.120396 0.2794)
			(stroke
				(width 0.1)
				(type default)
			)
			(layer "B.Fab")
		)
		(fp_line
			(start -0.67945 0.3048)
			(end -0.120396 0.3048)
			(stroke
				(width 0.1)
				(type default)
			)
			(layer "B.Fab")
		)
		(pad "1" smd circle
			(at 0.40005 0 270)
			(size 0 0)
			(layers "B.Cu" "B.Mask" "B.Paste")
			(net "SMB_NIC7_LS_SCL")
		)
		(pad "2" smd circle
			(at -0.40005 0 270)
			(size 0 0)
			(layers "B.Cu" "B.Mask" "B.Paste")
			(net "SMB_NIC7_LS_R_SCL")
		)
	)
	(footprint ""
		(layer "B.Cu")
		(at 232.125774 -92.936822 180)
		(property "Reference" "C2615"
			(at 0 0 0)
			(layer "B.SilkS")
			(hide yes)
			(effects
				(font
					(size 1.27 1.27)
				)
				(justify mirror)
			)
		)
		(property "Value" ""
			(at 0 0 0)
			(layer "B.Fab")
			(effects
				(font
					(size 1.27 1.27)
				)
				(justify mirror)
			)
		)
		(duplicate_pad_numbers_are_jumpers no)
		(fp_line
			(start 0.7874 0.4064)
			(end 0.7874 -0.4064)
			(stroke
				(width 0.1524)
				(type default)
			)
			(layer "B.SilkS")
		)
		(fp_line
			(start 0.7874 -0.4064)
			(end -0.7874 -0.4064)
			(stroke
				(width 0.1524)
				(type default)
			)
			(layer "B.SilkS")
		)
		(fp_line
			(start -0.7874 0.4064)
			(end 0.7874 0.4064)
			(stroke
				(width 0.1524)
				(type default)
			)
			(layer "B.SilkS")
		)
		(fp_line
			(start -0.7874 -0.4064)
			(end -0.7874 0.4064)
			(stroke
				(width 0.1524)
				(type default)
			)
			(layer "B.SilkS")
		)
		(fp_line
			(start 0.67945 0.3048)
			(end 0.67945 -0.305054)
			(stroke
				(width 0.1)
				(type default)
			)
			(layer "B.Fab")
		)
		(fp_line
			(start 0.67945 -0.305054)
			(end 0.12065 -0.305054)
			(stroke
				(width 0.1)
				(type default)
			)
			(layer "B.Fab")
		)
		(fp_line
			(start 0.12065 0.3048)
			(end 0.67945 0.3048)
			(stroke
				(width 0.1)
				(type default)
			)
			(layer "B.Fab")
		)
		(fp_line
			(start 0.12065 0.2794)
			(end 0.12065 0.3048)
			(stroke
				(width 0.1)
				(type default)
			)
			(layer "B.Fab")
		)
		(fp_line
			(start 0.12065 -0.2794)
			(end -0.12065 -0.2794)
			(stroke
				(width 0.1)
				(type default)
			)
			(layer "B.Fab")
		)
		(fp_line
			(start 0.12065 -0.305054)
			(end 0.12065 -0.2794)
			(stroke
				(width 0.1)
				(type default)
			)
			(layer "B.Fab")
		)
		(fp_line
			(start -0.120396 0.3048)
			(end -0.120396 0.2794)
			(stroke
				(width 0.1)
				(type default)
			)
			(layer "B.Fab")
		)
		(fp_line
			(start -0.120396 0.2794)
			(end 0.12065 0.2794)
			(stroke
				(width 0.1)
				(type default)
			)
			(layer "B.Fab")
		)
		(fp_line
			(start -0.12065 -0.2794)
			(end -0.12065 -0.3048)
			(stroke
				(width 0.1)
				(type default)
			)
			(layer "B.Fab")
		)
		(fp_line
			(start -0.12065 -0.3048)
			(end -0.67945 -0.3048)
			(stroke
				(width 0.1)
				(type default)
			)
			(layer "B.Fab")
		)
		(fp_line
			(start -0.67945 0.3048)
			(end -0.120396 0.3048)
			(stroke
				(width 0.1)
				(type default)
			)
			(layer "B.Fab")
		)
		(fp_line
			(start -0.67945 -0.3048)
			(end -0.67945 0.3048)
			(stroke
				(width 0.1)
				(type default)
			)
			(layer "B.Fab")
		)
		(pad "1" smd circle
			(at 0.40005 0)
			(size 0 0)
			(layers "B.Cu" "B.Mask" "B.Paste")
			(net "P3V3_PEX_USB_HUB")
		)
		(pad "2" smd circle
			(at -0.40005 0)
			(size 0 0)
			(layers "B.Cu" "B.Mask" "B.Paste")
			(net "GND")
		)
	)
	(footprint ""
		(layer "B.Cu")
		(at 206.389986 -251.73051 90)
		(property "Reference" "U423"
			(at -1.153414 7.503668 0)
			(unlocked yes)
			(layer "B.SilkS")
			(effects
				(font
					(size 0.7874 0.5842)
					(thickness 0.1524)
				)
				(justify left mirror)
			)
		)
		(property "Value" ""
			(at 0 0 90)
			(layer "B.Fab")
			(effects
				(font
					(size 1.27 1.27)
				)
				(justify mirror)
			)
		)
		(duplicate_pad_numbers_are_jumpers no)
		(fp_line
			(start 1.8542 -3.949954)
			(end 1.8542 3.949954)
			(stroke
				(width 0.1524)
				(type default)
			)
			(layer "B.SilkS")
		)
		(fp_line
			(start 1.282954 -3.949954)
			(end 1.8542 -3.949954)
			(stroke
				(width 0.1524)
				(type default)
			)
			(layer "B.SilkS")
		)
		(fp_line
			(start -1.282954 -3.949954)
			(end 0 -2.667)
			(stroke
				(width 0.1524)
				(type default)
			)
			(layer "B.SilkS")
		)
		(fp_line
			(start -1.8542 -3.949954)
			(end -1.282954 -3.949954)
			(stroke
				(width 0.1524)
				(type default)
			)
			(layer "B.SilkS")
		)
		(fp_line
			(start 0 -2.667)
			(end 1.282954 -3.949954)
			(stroke
				(width 0.1524)
				(type default)
			)
			(layer "B.SilkS")
		)
		(fp_line
			(start 1.8542 3.949954)
			(end -1.8542 3.949954)
			(stroke
				(width 0.1524)
				(type default)
			)
			(layer "B.SilkS")
		)
		(fp_line
			(start -1.8542 3.949954)
			(end -1.8542 -3.949954)
			(stroke
				(width 0.1524)
				(type default)
			)
			(layer "B.SilkS")
		)
		(fp_poly
			(pts
				(xy 4.8006 -4.08305) (xy 4.8006 -3.06705) (xy 3.7846 -3.57505)
			)
			(stroke
				(width 0)
				(type default)
			)
			(fill yes)
			(layer "B.SilkS")
		)
		(fp_line
			(start 2.249932 -3.949954)
			(end 2.249932 3.949954)
			(stroke
				(width 0.1)
				(type default)
			)
			(layer "B.Fab")
		)
		(fp_line
			(start -2.249932 -3.949954)
			(end 2.249932 -3.949954)
			(stroke
				(width 0.1)
				(type default)
			)
			(layer "B.Fab")
		)
		(fp_line
			(start 2.249932 3.949954)
			(end -2.249932 3.949954)
			(stroke
				(width 0.1)
				(type default)
			)
			(layer "B.Fab")
		)
		(fp_line
			(start -2.249932 3.949954)
			(end -2.249932 -3.949954)
			(stroke
				(width 0.1)
				(type default)
			)
			(layer "B.Fab")
		)
		(fp_poly
			(pts
				(xy 4.8006 -4.08305) (xy 4.8006 -3.06705) (xy 3.7846 -3.57505)
			)
			(stroke
				(width 0)
				(type default)
			)
			(fill yes)
			(layer "B.Fab")
		)
		(pad "1" smd rect
			(at 2.800096 -3.57505)
			(size 0.3048 1.6002)
			(layers "B.Cu" "B.Mask" "B.Paste")
			(net "PEX_MUX_A0")
		)
		(pad "2" smd rect
			(at 2.800096 -2.925064)
			(size 0.3048 1.6002)
			(layers "B.Cu" "B.Mask" "B.Paste")
			(net "PEX_MUX_A1")
		)
		(pad "3" smd rect
			(at 2.800096 -2.275078)
			(size 0.3048 1.6002)
			(layers "B.Cu" "B.Mask" "B.Paste")
			(net "RST_PEX_MUX_R_N")
		)
		(pad "4" smd rect
			(at 2.800096 -1.625092)
			(size 0.3048 1.6002)
			(layers "B.Cu" "B.Mask" "B.Paste")
			(net "SMB_PEX0_MUX_SDA")
		)
		(pad "5" smd rect
			(at 2.800096 -0.975106)
			(size 0.3048 1.6002)
			(layers "B.Cu" "B.Mask" "B.Paste")
			(net "SMB_PEX0_MUX_SCL")
		)
		(pad "6" smd rect
			(at 2.800096 -0.32512)
			(size 0.3048 1.6002)
			(layers "B.Cu" "B.Mask" "B.Paste")
			(net "SMB_PEX1_MUX_SDA")
		)
		(pad "7" smd rect
			(at 2.800096 0.32512)
			(size 0.3048 1.6002)
			(layers "B.Cu" "B.Mask" "B.Paste")
			(net "SMB_PEX1_MUX_SCL")
		)
		(pad "8" smd rect
			(at 2.800096 0.975106)
			(size 0.3048 1.6002)
			(layers "B.Cu" "B.Mask" "B.Paste")
			(net "SMB_PEX2_MUX_SDA")
		)
		(pad "9" smd rect
			(at 2.800096 1.625092)
			(size 0.3048 1.6002)
			(layers "B.Cu" "B.Mask" "B.Paste")
			(net "SMB_PEX2_MUX_SCL")
		)
		(pad "10" smd rect
			(at 2.800096 2.275078)
			(size 0.3048 1.6002)
			(layers "B.Cu" "B.Mask" "B.Paste")
			(net "SMB_PEX3_MUX_SDA")
		)
		(pad "11" smd rect
			(at 2.800096 2.925064)
			(size 0.3048 1.6002)
			(layers "B.Cu" "B.Mask" "B.Paste")
			(net "SMB_PEX3_MUX_SCL")
		)
		(pad "12" smd rect
			(at 2.800096 3.57505)
			(size 0.3048 1.6002)
			(layers "B.Cu" "B.Mask" "B.Paste")
			(net "GND")
		)
		(pad "13" smd rect
			(at -2.800096 3.57505)
			(size 0.3048 1.6002)
			(layers "B.Cu" "B.Mask" "B.Paste")
			(net "Net_9184")
		)
		(pad "14" smd rect
			(at -2.800096 2.925064)
			(size 0.3048 1.6002)
			(layers "B.Cu" "B.Mask" "B.Paste")
			(net "Net_9188")
		)
		(pad "15" smd rect
			(at -2.800096 2.275078)
			(size 0.3048 1.6002)
			(layers "B.Cu" "B.Mask" "B.Paste")
			(net "Net_9183")
		)
		(pad "16" smd rect
			(at -2.800096 1.625092)
			(size 0.3048 1.6002)
			(layers "B.Cu" "B.Mask" "B.Paste")
			(net "Net_9187")
		)
		(pad "17" smd rect
			(at -2.800096 0.975106)
			(size 0.3048 1.6002)
			(layers "B.Cu" "B.Mask" "B.Paste")
			(net "Net_9182")
		)
		(pad "18" smd rect
			(at -2.800096 0.32512)
			(size 0.3048 1.6002)
			(layers "B.Cu" "B.Mask" "B.Paste")
			(net "Net_9186")
		)
		(pad "19" smd rect
			(at -2.800096 -0.32512)
			(size 0.3048 1.6002)
			(layers "B.Cu" "B.Mask" "B.Paste")
			(net "Net_9181")
		)
		(pad "20" smd rect
			(at -2.800096 -0.975106)
			(size 0.3048 1.6002)
			(layers "B.Cu" "B.Mask" "B.Paste")
			(net "Net_9185")
		)
		(pad "21" smd rect
			(at -2.800096 -1.625092)
			(size 0.3048 1.6002)
			(layers "B.Cu" "B.Mask" "B.Paste")
			(net "PEX_MUX_A2")
		)
		(pad "22" smd rect
			(at -2.800096 -2.275078)
			(size 0.3048 1.6002)
			(layers "B.Cu" "B.Mask" "B.Paste")
			(net "SMB_PEX_MUX_SCL")
		)
		(pad "23" smd rect
			(at -2.800096 -2.925064)
			(size 0.3048 1.6002)
			(layers "B.Cu" "B.Mask" "B.Paste")
			(net "SMB_PEX_MUX_SDA")
		)
		(pad "24" smd rect
			(at -2.800096 -3.57505)
			(size 0.3048 1.6002)
			(layers "B.Cu" "B.Mask" "B.Paste")
			(net "P1V8_PEX")
		)
	)
	(footprint ""
		(layer "B.Cu")
		(at 61.549788 -299.699934 -90)
		(property "Reference" "C1239"
			(at 0 0 90)
			(layer "B.SilkS")
			(hide yes)
			(effects
				(font
					(size 1.27 1.27)
				)
				(justify mirror)
			)
		)
		(property "Value" ""
			(at 0 0 90)
			(layer "B.Fab")
			(effects
				(font
					(size 1.27 1.27)
				)
				(justify mirror)
			)
		)
		(duplicate_pad_numbers_are_jumpers no)
		(fp_line
			(start -0.299974 0.150114)
			(end 0.299974 0.150114)
			(stroke
				(width 0.1)
				(type default)
			)
			(layer "B.Fab")
		)
		(fp_line
			(start 0.299974 0.150114)
			(end 0.299974 -0.150114)
			(stroke
				(width 0.1)
				(type default)
			)
			(layer "B.Fab")
		)
		(fp_line
			(start -0.299974 -0.150114)
			(end -0.299974 0.150114)
			(stroke
				(width 0.1)
				(type default)
			)
			(layer "B.Fab")
		)
		(fp_line
			(start 0.299974 -0.150114)
			(end -0.299974 -0.150114)
			(stroke
				(width 0.1)
				(type default)
			)
			(layer "B.Fab")
		)
		(pad "1" smd rect
			(at 0.2667 0 90)
			(size 0.3048 0.381)
			(layers "B.Cu" "B.Mask" "B.Paste")
			(net "P0V8_SERDES_VDDA_PEX0")
		)
		(pad "2" smd rect
			(at -0.2667 0 90)
			(size 0.3048 0.381)
			(layers "B.Cu" "B.Mask" "B.Paste")
			(net "GND")
		)
	)
	(footprint ""
		(layer "B.Cu")
		(at 294.69969 -292.099746 90)
		(property "Reference" "C1727"
			(at 0 0 90)
			(layer "B.SilkS")
			(hide yes)
			(effects
				(font
					(size 1.27 1.27)
				)
				(justify mirror)
			)
		)
		(property "Value" ""
			(at 0 0 90)
			(layer "B.Fab")
			(effects
				(font
					(size 1.27 1.27)
				)
				(justify mirror)
			)
		)
		(duplicate_pad_numbers_are_jumpers no)
		(fp_line
			(start 0.299974 -0.150114)
			(end -0.299974 -0.150114)
			(stroke
				(width 0.1)
				(type default)
			)
			(layer "B.Fab")
		)
		(fp_line
			(start -0.299974 -0.150114)
			(end -0.299974 0.150114)
			(stroke
				(width 0.1)
				(type default)
			)
			(layer "B.Fab")
		)
		(fp_line
			(start 0.299974 0.150114)
			(end 0.299974 -0.150114)
			(stroke
				(width 0.1)
				(type default)
			)
			(layer "B.Fab")
		)
		(fp_line
			(start -0.299974 0.150114)
			(end 0.299974 0.150114)
			(stroke
				(width 0.1)
				(type default)
			)
			(layer "B.Fab")
		)
		(pad "1" smd rect
			(at 0.2667 0 270)
			(size 0.3048 0.381)
			(layers "B.Cu" "B.Mask" "B.Paste")
			(net "P0V8_SERDES_VDDA_PEX2")
		)
		(pad "2" smd rect
			(at -0.2667 0 270)
			(size 0.3048 0.381)
			(layers "B.Cu" "B.Mask" "B.Paste")
			(net "GND")
		)
	)
	(footprint ""
		(layer "B.Cu")
		(at 58.699908 -290.199826 90)
		(property "Reference" "C1183"
			(at 0 0 90)
			(layer "B.SilkS")
			(hide yes)
			(effects
				(font
					(size 1.27 1.27)
				)
				(justify mirror)
			)
		)
		(property "Value" ""
			(at 0 0 90)
			(layer "B.Fab")
			(effects
				(font
					(size 1.27 1.27)
				)
				(justify mirror)
			)
		)
		(duplicate_pad_numbers_are_jumpers no)
		(fp_line
			(start 0.299974 -0.150114)
			(end -0.299974 -0.150114)
			(stroke
				(width 0.1)
				(type default)
			)
			(layer "B.Fab")
		)
		(fp_line
			(start -0.299974 -0.150114)
			(end -0.299974 0.150114)
			(stroke
				(width 0.1)
				(type default)
			)
			(layer "B.Fab")
		)
		(fp_line
			(start 0.299974 0.150114)
			(end 0.299974 -0.150114)
			(stroke
				(width 0.1)
				(type default)
			)
			(layer "B.Fab")
		)
		(fp_line
			(start -0.299974 0.150114)
			(end 0.299974 0.150114)
			(stroke
				(width 0.1)
				(type default)
			)
			(layer "B.Fab")
		)
		(pad "1" smd rect
			(at 0.2667 0 270)
			(size 0.3048 0.381)
			(layers "B.Cu" "B.Mask" "B.Paste")
			(net "P0V8_SERDES_VDDA_PEX0")
		)
		(pad "2" smd rect
			(at -0.2667 0 270)
			(size 0.3048 0.381)
			(layers "B.Cu" "B.Mask" "B.Paste")
			(net "GND")
		)
	)
	(footprint ""
		(layer "B.Cu")
		(at 107.697778 -327.366122 180)
		(property "Reference" "C2698"
			(at 0 0 0)
			(layer "B.SilkS")
			(hide yes)
			(effects
				(font
					(size 1.27 1.27)
				)
				(justify mirror)
			)
		)
		(property "Value" ""
			(at 0 0 0)
			(layer "B.Fab")
			(effects
				(font
					(size 1.27 1.27)
				)
				(justify mirror)
			)
		)
		(duplicate_pad_numbers_are_jumpers no)
		(fp_line
			(start 0.7874 0.4064)
			(end 0.7874 -0.4064)
			(stroke
				(width 0.1524)
				(type default)
			)
			(layer "B.SilkS")
		)
		(fp_line
			(start 0.7874 -0.4064)
			(end -0.7874 -0.4064)
			(stroke
				(width 0.1524)
				(type default)
			)
			(layer "B.SilkS")
		)
		(fp_line
			(start -0.7874 0.4064)
			(end 0.7874 0.4064)
			(stroke
				(width 0.1524)
				(type default)
			)
			(layer "B.SilkS")
		)
		(fp_line
			(start -0.7874 -0.4064)
			(end -0.7874 0.4064)
			(stroke
				(width 0.1524)
				(type default)
			)
			(layer "B.SilkS")
		)
		(fp_line
			(start 0.67945 0.3048)
			(end 0.67945 -0.305054)
			(stroke
				(width 0.1)
				(type default)
			)
			(layer "B.Fab")
		)
		(fp_line
			(start 0.67945 -0.305054)
			(end 0.12065 -0.305054)
			(stroke
				(width 0.1)
				(type default)
			)
			(layer "B.Fab")
		)
		(fp_line
			(start 0.12065 0.3048)
			(end 0.67945 0.3048)
			(stroke
				(width 0.1)
				(type default)
			)
			(layer "B.Fab")
		)
		(fp_line
			(start 0.12065 0.2794)
			(end 0.12065 0.3048)
			(stroke
				(width 0.1)
				(type default)
			)
			(layer "B.Fab")
		)
		(fp_line
			(start 0.12065 -0.2794)
			(end -0.12065 -0.2794)
			(stroke
				(width 0.1)
				(type default)
			)
			(layer "B.Fab")
		)
		(fp_line
			(start 0.12065 -0.305054)
			(end 0.12065 -0.2794)
			(stroke
				(width 0.1)
				(type default)
			)
			(layer "B.Fab")
		)
		(fp_line
			(start -0.120396 0.3048)
			(end -0.120396 0.2794)
			(stroke
				(width 0.1)
				(type default)
			)
			(layer "B.Fab")
		)
		(fp_line
			(start -0.120396 0.2794)
			(end 0.12065 0.2794)
			(stroke
				(width 0.1)
				(type default)
			)
			(layer "B.Fab")
		)
		(fp_line
			(start -0.12065 -0.2794)
			(end -0.12065 -0.3048)
			(stroke
				(width 0.1)
				(type default)
			)
			(layer "B.Fab")
		)
		(fp_line
			(start -0.12065 -0.3048)
			(end -0.67945 -0.3048)
			(stroke
				(width 0.1)
				(type default)
			)
			(layer "B.Fab")
		)
		(fp_line
			(start -0.67945 0.3048)
			(end -0.120396 0.3048)
			(stroke
				(width 0.1)
				(type default)
			)
			(layer "B.Fab")
		)
		(fp_line
			(start -0.67945 -0.3048)
			(end -0.67945 0.3048)
			(stroke
				(width 0.1)
				(type default)
			)
			(layer "B.Fab")
		)
		(pad "1" smd circle
			(at 0.40005 0)
			(size 0 0)
			(layers "B.Cu" "B.Mask" "B.Paste")
			(net "P3V3_CLK_BUFFER_9ZXL0451E_VZX3P3")
		)
		(pad "2" smd circle
			(at -0.40005 0)
			(size 0 0)
			(layers "B.Cu" "B.Mask" "B.Paste")
			(net "GND")
		)
	)
	(footprint ""
		(layer "B.Cu")
		(at 3.092704 -273.296888)
		(property "Reference" "C4232"
			(at 0 0 0)
			(layer "B.SilkS")
			(hide yes)
			(effects
				(font
					(size 1.27 1.27)
				)
				(justify mirror)
			)
		)
		(property "Value" ""
			(at 0 0 0)
			(layer "B.Fab")
			(effects
				(font
					(size 1.27 1.27)
				)
				(justify mirror)
			)
		)
		(duplicate_pad_numbers_are_jumpers no)
		(fp_line
			(start -1.2954 -0.5842)
			(end -1.2954 0.5842)
			(stroke
				(width 0.1524)
				(type default)
			)
			(layer "B.SilkS")
		)
		(fp_line
			(start -1.2954 0.5842)
			(end 1.2954 0.5842)
			(stroke
				(width 0.1524)
				(type default)
			)
			(layer "B.SilkS")
		)
		(fp_line
			(start 1.2954 -0.5842)
			(end -1.2954 -0.5842)
			(stroke
				(width 0.1524)
				(type default)
			)
			(layer "B.SilkS")
		)
		(fp_line
			(start 1.2954 0.5842)
			(end 1.2954 -0.5842)
			(stroke
				(width 0.1524)
				(type default)
			)
			(layer "B.SilkS")
		)
		(fp_line
			(start -1.1938 -0.4064)
			(end -1.1938 0.4064)
			(stroke
				(width 0.1)
				(type default)
			)
			(layer "B.Fab")
		)
		(fp_line
			(start -1.1938 0.4064)
			(end -0.8636 0.4064)
			(stroke
				(width 0.1)
				(type default)
			)
			(layer "B.Fab")
		)
		(fp_line
			(start -0.8636 -0.4572)
			(end -0.8636 -0.4064)
			(stroke
				(width 0.1)
				(type default)
			)
			(layer "B.Fab")
		)
		(fp_line
			(start -0.8636 -0.4064)
			(end -1.1938 -0.4064)
			(stroke
				(width 0.1)
				(type default)
			)
			(layer "B.Fab")
		)
		(fp_line
			(start -0.8636 0.4064)
			(end -0.8636 0.4572)
			(stroke
				(width 0.1)
				(type default)
			)
			(layer "B.Fab")
		)
		(fp_line
			(start -0.8636 0.4572)
			(end 0.8636 0.4572)
			(stroke
				(width 0.1)
				(type default)
			)
			(layer "B.Fab")
		)
		(fp_line
			(start 0.8636 -0.4572)
			(end -0.8636 -0.4572)
			(stroke
				(width 0.1)
				(type default)
			)
			(layer "B.Fab")
		)
		(fp_line
			(start 0.8636 -0.4064)
			(end 0.8636 -0.4572)
			(stroke
				(width 0.1)
				(type default)
			)
			(layer "B.Fab")
		)
		(fp_line
			(start 0.8636 0.4064)
			(end 1.1938 0.4064)
			(stroke
				(width 0.1)
				(type default)
			)
			(layer "B.Fab")
		)
		(fp_line
			(start 0.8636 0.4572)
			(end 0.8636 0.4064)
			(stroke
				(width 0.1)
				(type default)
			)
			(layer "B.Fab")
		)
		(fp_line
			(start 1.1938 -0.4064)
			(end 0.8636 -0.4064)
			(stroke
				(width 0.1)
				(type default)
			)
			(layer "B.Fab")
		)
		(fp_line
			(start 1.1938 0.4064)
			(end 1.1938 -0.4064)
			(stroke
				(width 0.1)
				(type default)
			)
			(layer "B.Fab")
		)
		(pad "1" smd rect
			(at 0.7366 0 270)
			(size 0.7112 0.8128)
			(layers "B.Cu" "B.Mask" "B.Paste")
			(net "P1V25_PEX0")
		)
		(pad "2" smd rect
			(at -0.7366 0 270)
			(size 0.7112 0.8128)
			(layers "B.Cu" "B.Mask" "B.Paste")
			(net "GND")
		)
	)
	(footprint ""
		(layer "B.Cu")
		(at 68.199762 -293.52494 180)
		(property "Reference" "C1105"
			(at 0 0 0)
			(layer "B.SilkS")
			(hide yes)
			(effects
				(font
					(size 1.27 1.27)
				)
				(justify mirror)
			)
		)
		(property "Value" ""
			(at 0 0 0)
			(layer "B.Fab")
			(effects
				(font
					(size 1.27 1.27)
				)
				(justify mirror)
			)
		)
		(duplicate_pad_numbers_are_jumpers no)
		(fp_line
			(start 0.299974 0.150114)
			(end 0.299974 -0.150114)
			(stroke
				(width 0.1)
				(type default)
			)
			(layer "B.Fab")
		)
		(fp_line
			(start 0.299974 -0.150114)
			(end -0.299974 -0.150114)
			(stroke
				(width 0.1)
				(type default)
			)
			(layer "B.Fab")
		)
		(fp_line
			(start -0.299974 0.150114)
			(end 0.299974 0.150114)
			(stroke
				(width 0.1)
				(type default)
			)
			(layer "B.Fab")
		)
		(fp_line
			(start -0.299974 -0.150114)
			(end -0.299974 0.150114)
			(stroke
				(width 0.1)
				(type default)
			)
			(layer "B.Fab")
		)
		(pad "1" smd rect
			(at 0.2667 0)
			(size 0.3048 0.381)
			(layers "B.Cu" "B.Mask" "B.Paste")
			(net "P0V8_PEX0")
		)
		(pad "2" smd rect
			(at -0.2667 0)
			(size 0.3048 0.381)
			(layers "B.Cu" "B.Mask" "B.Paste")
			(net "GND")
		)
	)
	(footprint ""
		(layer "B.Cu")
		(at 168.625012 -297.79976 -90)
		(property "Reference" "C1395"
			(at 0 0 90)
			(layer "B.SilkS")
			(hide yes)
			(effects
				(font
					(size 1.27 1.27)
				)
				(justify mirror)
			)
		)
		(property "Value" ""
			(at 0 0 90)
			(layer "B.Fab")
			(effects
				(font
					(size 1.27 1.27)
				)
				(justify mirror)
			)
		)
		(duplicate_pad_numbers_are_jumpers no)
		(fp_line
			(start -0.299974 0.150114)
			(end 0.299974 0.150114)
			(stroke
				(width 0.1)
				(type default)
			)
			(layer "B.Fab")
		)
		(fp_line
			(start 0.299974 0.150114)
			(end 0.299974 -0.150114)
			(stroke
				(width 0.1)
				(type default)
			)
			(layer "B.Fab")
		)
		(fp_line
			(start -0.299974 -0.150114)
			(end -0.299974 0.150114)
			(stroke
				(width 0.1)
				(type default)
			)
			(layer "B.Fab")
		)
		(fp_line
			(start 0.299974 -0.150114)
			(end -0.299974 -0.150114)
			(stroke
				(width 0.1)
				(type default)
			)
			(layer "B.Fab")
		)
		(pad "1" smd rect
			(at 0.2667 0 90)
			(size 0.3048 0.381)
			(layers "B.Cu" "B.Mask" "B.Paste")
			(net "P0V8_PEX1")
		)
		(pad "2" smd rect
			(at -0.2667 0 90)
			(size 0.3048 0.381)
			(layers "B.Cu" "B.Mask" "B.Paste")
			(net "GND")
		)
	)
	(footprint ""
		(layer "B.Cu")
		(at 286.149796 -299.699934 -90)
		(property "Reference" "C1710"
			(at 0 0 90)
			(layer "B.SilkS")
			(hide yes)
			(effects
				(font
					(size 1.27 1.27)
				)
				(justify mirror)
			)
		)
		(property "Value" ""
			(at 0 0 90)
			(layer "B.Fab")
			(effects
				(font
					(size 1.27 1.27)
				)
				(justify mirror)
			)
		)
		(duplicate_pad_numbers_are_jumpers no)
		(fp_line
			(start -0.299974 0.150114)
			(end 0.299974 0.150114)
			(stroke
				(width 0.1)
				(type default)
			)
			(layer "B.Fab")
		)
		(fp_line
			(start 0.299974 0.150114)
			(end 0.299974 -0.150114)
			(stroke
				(width 0.1)
				(type default)
			)
			(layer "B.Fab")
		)
		(fp_line
			(start -0.299974 -0.150114)
			(end -0.299974 0.150114)
			(stroke
				(width 0.1)
				(type default)
			)
			(layer "B.Fab")
		)
		(fp_line
			(start 0.299974 -0.150114)
			(end -0.299974 -0.150114)
			(stroke
				(width 0.1)
				(type default)
			)
			(layer "B.Fab")
		)
		(pad "1" smd rect
			(at 0.2667 0 90)
			(size 0.3048 0.381)
			(layers "B.Cu" "B.Mask" "B.Paste")
			(net "P0V8_SERDES_VDDA_PEX2")
		)
		(pad "2" smd rect
			(at -0.2667 0 90)
			(size 0.3048 0.381)
			(layers "B.Cu" "B.Mask" "B.Paste")
			(net "GND")
		)
	)
	(footprint ""
		(layer "B.Cu")
		(at 299.005244 -236.736636 90)
		(property "Reference" "R6174"
			(at 0 0 90)
			(layer "B.SilkS")
			(hide yes)
			(effects
				(font
					(size 1.27 1.27)
				)
				(justify mirror)
			)
		)
		(property "Value" ""
			(at 0 0 90)
			(layer "B.Fab")
			(effects
				(font
					(size 1.27 1.27)
				)
				(justify mirror)
			)
		)
		(duplicate_pad_numbers_are_jumpers no)
		(fp_line
			(start 0.7874 -0.4064)
			(end -0.7874 -0.4064)
			(stroke
				(width 0.1524)
				(type default)
			)
			(layer "B.SilkS")
		)
		(fp_line
			(start -0.7874 -0.4064)
			(end -0.7874 0.4064)
			(stroke
				(width 0.1524)
				(type default)
			)
			(layer "B.SilkS")
		)
		(fp_line
			(start 0.7874 0.4064)
			(end 0.7874 -0.4064)
			(stroke
				(width 0.1524)
				(type default)
			)
			(layer "B.SilkS")
		)
		(fp_line
			(start -0.7874 0.4064)
			(end 0.7874 0.4064)
			(stroke
				(width 0.1524)
				(type default)
			)
			(layer "B.SilkS")
		)
		(fp_line
			(start 0.67945 -0.305054)
			(end 0.12065 -0.305054)
			(stroke
				(width 0.1)
				(type default)
			)
			(layer "B.Fab")
		)
		(fp_line
			(start 0.12065 -0.305054)
			(end 0.12065 -0.2794)
			(stroke
				(width 0.1)
				(type default)
			)
			(layer "B.Fab")
		)
		(fp_line
			(start -0.12065 -0.3048)
			(end -0.67945 -0.3048)
			(stroke
				(width 0.1)
				(type default)
			)
			(layer "B.Fab")
		)
		(fp_line
			(start -0.67945 -0.3048)
			(end -0.67945 0.3048)
			(stroke
				(width 0.1)
				(type default)
			)
			(layer "B.Fab")
		)
		(fp_line
			(start 0.12065 -0.2794)
			(end -0.12065 -0.2794)
			(stroke
				(width 0.1)
				(type default)
			)
			(layer "B.Fab")
		)
		(fp_line
			(start -0.12065 -0.2794)
			(end -0.12065 -0.3048)
			(stroke
				(width 0.1)
				(type default)
			)
			(layer "B.Fab")
		)
		(fp_line
			(start 0.12065 0.2794)
			(end 0.12065 0.3048)
			(stroke
				(width 0.1)
				(type default)
			)
			(layer "B.Fab")
		)
		(fp_line
			(start -0.120396 0.2794)
			(end 0.12065 0.2794)
			(stroke
				(width 0.1)
				(type default)
			)
			(layer "B.Fab")
		)
		(fp_line
			(start 0.67945 0.3048)
			(end 0.67945 -0.305054)
			(stroke
				(width 0.1)
				(type default)
			)
			(layer "B.Fab")
		)
		(fp_line
			(start 0.12065 0.3048)
			(end 0.67945 0.3048)
			(stroke
				(width 0.1)
				(type default)
			)
			(layer "B.Fab")
		)
		(fp_line
			(start -0.120396 0.3048)
			(end -0.120396 0.2794)
			(stroke
				(width 0.1)
				(type default)
			)
			(layer "B.Fab")
		)
		(fp_line
			(start -0.67945 0.3048)
			(end -0.120396 0.3048)
			(stroke
				(width 0.1)
				(type default)
			)
			(layer "B.Fab")
		)
		(pad "1" smd circle
			(at 0.40005 0 270)
			(size 0 0)
			(layers "B.Cu" "B.Mask" "B.Paste")
			(net "GND")
		)
		(pad "2" smd circle
			(at -0.40005 0 270)
			(size 0 0)
			(layers "B.Cu" "B.Mask" "B.Paste")
			(net "RST_GPU_PERST_0_N")
		)
	)
	(footprint ""
		(layer "B.Cu")
		(at 66.299842 -301.599854 -90)
		(property "Reference" "C1196"
			(at 0 0 90)
			(layer "B.SilkS")
			(hide yes)
			(effects
				(font
					(size 1.27 1.27)
				)
				(justify mirror)
			)
		)
		(property "Value" ""
			(at 0 0 90)
			(layer "B.Fab")
			(effects
				(font
					(size 1.27 1.27)
				)
				(justify mirror)
			)
		)
		(duplicate_pad_numbers_are_jumpers no)
		(fp_line
			(start -0.299974 0.150114)
			(end 0.299974 0.150114)
			(stroke
				(width 0.1)
				(type default)
			)
			(layer "B.Fab")
		)
		(fp_line
			(start 0.299974 0.150114)
			(end 0.299974 -0.150114)
			(stroke
				(width 0.1)
				(type default)
			)
			(layer "B.Fab")
		)
		(fp_line
			(start -0.299974 -0.150114)
			(end -0.299974 0.150114)
			(stroke
				(width 0.1)
				(type default)
			)
			(layer "B.Fab")
		)
		(fp_line
			(start 0.299974 -0.150114)
			(end -0.299974 -0.150114)
			(stroke
				(width 0.1)
				(type default)
			)
			(layer "B.Fab")
		)
		(pad "1" smd rect
			(at 0.2667 0 90)
			(size 0.3048 0.381)
			(layers "B.Cu" "B.Mask" "B.Paste")
			(net "P0V8_SERDES_VDDA_PEX0")
		)
		(pad "2" smd rect
			(at -0.2667 0 90)
			(size 0.3048 0.381)
			(layers "B.Cu" "B.Mask" "B.Paste")
			(net "GND")
		)
	)
	(footprint ""
		(layer "B.Cu")
		(at 351.645982 -155.321 180)
		(property "Reference" "R4791"
			(at 0 0 0)
			(layer "B.SilkS")
			(hide yes)
			(effects
				(font
					(size 1.27 1.27)
				)
				(justify mirror)
			)
		)
		(property "Value" ""
			(at 0 0 0)
			(layer "B.Fab")
			(effects
				(font
					(size 1.27 1.27)
				)
				(justify mirror)
			)
		)
		(duplicate_pad_numbers_are_jumpers no)
		(fp_line
			(start 0.7874 0.4064)
			(end 0.7874 -0.4064)
			(stroke
				(width 0.1524)
				(type default)
			)
			(layer "B.SilkS")
		)
		(fp_line
			(start 0.7874 -0.4064)
			(end -0.7874 -0.4064)
			(stroke
				(width 0.1524)
				(type default)
			)
			(layer "B.SilkS")
		)
		(fp_line
			(start -0.7874 0.4064)
			(end 0.7874 0.4064)
			(stroke
				(width 0.1524)
				(type default)
			)
			(layer "B.SilkS")
		)
		(fp_line
			(start -0.7874 -0.4064)
			(end -0.7874 0.4064)
			(stroke
				(width 0.1524)
				(type default)
			)
			(layer "B.SilkS")
		)
		(fp_line
			(start 0.67945 0.3048)
			(end 0.67945 -0.305054)
			(stroke
				(width 0.1)
				(type default)
			)
			(layer "B.Fab")
		)
		(fp_line
			(start 0.67945 -0.305054)
			(end 0.12065 -0.305054)
			(stroke
				(width 0.1)
				(type default)
			)
			(layer "B.Fab")
		)
		(fp_line
			(start 0.12065 0.3048)
			(end 0.67945 0.3048)
			(stroke
				(width 0.1)
				(type default)
			)
			(layer "B.Fab")
		)
		(fp_line
			(start 0.12065 0.2794)
			(end 0.12065 0.3048)
			(stroke
				(width 0.1)
				(type default)
			)
			(layer "B.Fab")
		)
		(fp_line
			(start 0.12065 -0.2794)
			(end -0.12065 -0.2794)
			(stroke
				(width 0.1)
				(type default)
			)
			(layer "B.Fab")
		)
		(fp_line
			(start 0.12065 -0.305054)
			(end 0.12065 -0.2794)
			(stroke
				(width 0.1)
				(type default)
			)
			(layer "B.Fab")
		)
		(fp_line
			(start -0.120396 0.3048)
			(end -0.120396 0.2794)
			(stroke
				(width 0.1)
				(type default)
			)
			(layer "B.Fab")
		)
		(fp_line
			(start -0.120396 0.2794)
			(end 0.12065 0.2794)
			(stroke
				(width 0.1)
				(type default)
			)
			(layer "B.Fab")
		)
		(fp_line
			(start -0.12065 -0.2794)
			(end -0.12065 -0.3048)
			(stroke
				(width 0.1)
				(type default)
			)
			(layer "B.Fab")
		)
		(fp_line
			(start -0.12065 -0.3048)
			(end -0.67945 -0.3048)
			(stroke
				(width 0.1)
				(type default)
			)
			(layer "B.Fab")
		)
		(fp_line
			(start -0.67945 0.3048)
			(end -0.120396 0.3048)
			(stroke
				(width 0.1)
				(type default)
			)
			(layer "B.Fab")
		)
		(fp_line
			(start -0.67945 -0.3048)
			(end -0.67945 0.3048)
			(stroke
				(width 0.1)
				(type default)
			)
			(layer "B.Fab")
		)
		(pad "1" smd circle
			(at 0.40005 0)
			(size 0 0)
			(layers "B.Cu" "B.Mask" "B.Paste")
			(net "P3V3_AUX")
		)
		(pad "2" smd circle
			(at -0.40005 0)
			(size 0 0)
			(layers "B.Cu" "B.Mask" "B.Paste")
			(net "NIC6_PEX_PWR_EN_R")
		)
	)
	(footprint ""
		(layer "B.Cu")
		(at 305.6001 -110.978696)
		(property "Reference" "C926"
			(at 0 0 0)
			(layer "B.SilkS")
			(hide yes)
			(effects
				(font
					(size 1.27 1.27)
				)
				(justify mirror)
			)
		)
		(property "Value" ""
			(at 0 0 0)
			(layer "B.Fab")
			(effects
				(font
					(size 1.27 1.27)
				)
				(justify mirror)
			)
		)
		(duplicate_pad_numbers_are_jumpers no)
		(fp_line
			(start -0.299974 -0.150114)
			(end -0.299974 0.150114)
			(stroke
				(width 0.1)
				(type default)
			)
			(layer "B.Fab")
		)
		(fp_line
			(start -0.299974 0.150114)
			(end 0.299974 0.150114)
			(stroke
				(width 0.1)
				(type default)
			)
			(layer "B.Fab")
		)
		(fp_line
			(start 0.299974 -0.150114)
			(end -0.299974 -0.150114)
			(stroke
				(width 0.1)
				(type default)
			)
			(layer "B.Fab")
		)
		(fp_line
			(start 0.299974 0.150114)
			(end 0.299974 -0.150114)
			(stroke
				(width 0.1)
				(type default)
			)
			(layer "B.Fab")
		)
		(pad "1" smd rect
			(at 0.2667 0 180)
			(size 0.3048 0.381)
			(layers "B.Cu" "B.Mask" "B.Paste")
			(net "P12V_NIC5")
		)
		(pad "2" smd rect
			(at -0.2667 0 180)
			(size 0.3048 0.381)
			(layers "B.Cu" "B.Mask" "B.Paste")
			(net "GND")
		)
	)
	(footprint ""
		(layer "B.Cu")
		(at 412.224982 -293.99992 -90)
		(property "Reference" "C1911"
			(at 0 0 90)
			(layer "B.SilkS")
			(hide yes)
			(effects
				(font
					(size 1.27 1.27)
				)
				(justify mirror)
			)
		)
		(property "Value" ""
			(at 0 0 90)
			(layer "B.Fab")
			(effects
				(font
					(size 1.27 1.27)
				)
				(justify mirror)
			)
		)
		(duplicate_pad_numbers_are_jumpers no)
		(fp_line
			(start -0.299974 0.150114)
			(end 0.299974 0.150114)
			(stroke
				(width 0.1)
				(type default)
			)
			(layer "B.Fab")
		)
		(fp_line
			(start 0.299974 0.150114)
			(end 0.299974 -0.150114)
			(stroke
				(width 0.1)
				(type default)
			)
			(layer "B.Fab")
		)
		(fp_line
			(start -0.299974 -0.150114)
			(end -0.299974 0.150114)
			(stroke
				(width 0.1)
				(type default)
			)
			(layer "B.Fab")
		)
		(fp_line
			(start 0.299974 -0.150114)
			(end -0.299974 -0.150114)
			(stroke
				(width 0.1)
				(type default)
			)
			(layer "B.Fab")
		)
		(pad "1" smd rect
			(at 0.2667 0 90)
			(size 0.3048 0.381)
			(layers "B.Cu" "B.Mask" "B.Paste")
			(net "P0V8_PEX3")
		)
		(pad "2" smd rect
			(at -0.2667 0 90)
			(size 0.3048 0.381)
			(layers "B.Cu" "B.Mask" "B.Paste")
			(net "GND")
		)
	)
	(footprint ""
		(layer "B.Cu")
		(at 421.249856 -293.99992 180)
		(property "Reference" "C3471"
			(at 0 0 0)
			(layer "B.SilkS")
			(hide yes)
			(effects
				(font
					(size 1.27 1.27)
				)
				(justify mirror)
			)
		)
		(property "Value" ""
			(at 0 0 0)
			(layer "B.Fab")
			(effects
				(font
					(size 1.27 1.27)
				)
				(justify mirror)
			)
		)
		(duplicate_pad_numbers_are_jumpers no)
		(fp_line
			(start 0.299974 0.150114)
			(end 0.299974 -0.150114)
			(stroke
				(width 0.1)
				(type default)
			)
			(layer "B.Fab")
		)
		(fp_line
			(start 0.299974 -0.150114)
			(end -0.299974 -0.150114)
			(stroke
				(width 0.1)
				(type default)
			)
			(layer "B.Fab")
		)
		(fp_line
			(start -0.299974 0.150114)
			(end 0.299974 0.150114)
			(stroke
				(width 0.1)
				(type default)
			)
			(layer "B.Fab")
		)
		(fp_line
			(start -0.299974 -0.150114)
			(end -0.299974 0.150114)
			(stroke
				(width 0.1)
				(type default)
			)
			(layer "B.Fab")
		)
		(pad "1" smd rect
			(at 0.2667 0)
			(size 0.3048 0.381)
			(layers "B.Cu" "B.Mask" "B.Paste")
			(net "P1V25_SERDES_VDDPLL_PEX3")
		)
		(pad "2" smd rect
			(at -0.2667 0)
			(size 0.3048 0.381)
			(layers "B.Cu" "B.Mask" "B.Paste")
			(net "GND")
		)
	)
	(footprint ""
		(layer "B.Cu")
		(at 187.149994 -294.4749 180)
		(property "Reference" "C3114"
			(at 0 0 0)
			(layer "B.SilkS")
			(hide yes)
			(effects
				(font
					(size 1.27 1.27)
				)
				(justify mirror)
			)
		)
		(property "Value" ""
			(at 0 0 0)
			(layer "B.Fab")
			(effects
				(font
					(size 1.27 1.27)
				)
				(justify mirror)
			)
		)
		(duplicate_pad_numbers_are_jumpers no)
		(fp_line
			(start 0.299974 0.150114)
			(end 0.299974 -0.150114)
			(stroke
				(width 0.1)
				(type default)
			)
			(layer "B.Fab")
		)
		(fp_line
			(start 0.299974 -0.150114)
			(end -0.299974 -0.150114)
			(stroke
				(width 0.1)
				(type default)
			)
			(layer "B.Fab")
		)
		(fp_line
			(start -0.299974 0.150114)
			(end 0.299974 0.150114)
			(stroke
				(width 0.1)
				(type default)
			)
			(layer "B.Fab")
		)
		(fp_line
			(start -0.299974 -0.150114)
			(end -0.299974 0.150114)
			(stroke
				(width 0.1)
				(type default)
			)
			(layer "B.Fab")
		)
		(pad "1" smd rect
			(at 0.2667 0)
			(size 0.3048 0.381)
			(layers "B.Cu" "B.Mask" "B.Paste")
			(net "P1V25_PEX1")
		)
		(pad "2" smd rect
			(at -0.2667 0)
			(size 0.3048 0.381)
			(layers "B.Cu" "B.Mask" "B.Paste")
			(net "GND")
		)
	)
	(footprint ""
		(layer "B.Cu")
		(at 329.692 -221.4372 180)
		(property "Reference" "R4173"
			(at 0 0 0)
			(layer "B.SilkS")
			(hide yes)
			(effects
				(font
					(size 1.27 1.27)
				)
				(justify mirror)
			)
		)
		(property "Value" ""
			(at 0 0 0)
			(layer "B.Fab")
			(effects
				(font
					(size 1.27 1.27)
				)
				(justify mirror)
			)
		)
		(duplicate_pad_numbers_are_jumpers no)
		(fp_line
			(start 0.7874 0.4064)
			(end 0.7874 -0.4064)
			(stroke
				(width 0.1524)
				(type default)
			)
			(layer "B.SilkS")
		)
		(fp_line
			(start 0.7874 -0.4064)
			(end -0.7874 -0.4064)
			(stroke
				(width 0.1524)
				(type default)
			)
			(layer "B.SilkS")
		)
		(fp_line
			(start -0.7874 0.4064)
			(end 0.7874 0.4064)
			(stroke
				(width 0.1524)
				(type default)
			)
			(layer "B.SilkS")
		)
		(fp_line
			(start -0.7874 -0.4064)
			(end -0.7874 0.4064)
			(stroke
				(width 0.1524)
				(type default)
			)
			(layer "B.SilkS")
		)
		(fp_line
			(start 0.67945 0.3048)
			(end 0.67945 -0.305054)
			(stroke
				(width 0.1)
				(type default)
			)
			(layer "B.Fab")
		)
		(fp_line
			(start 0.67945 -0.305054)
			(end 0.12065 -0.305054)
			(stroke
				(width 0.1)
				(type default)
			)
			(layer "B.Fab")
		)
		(fp_line
			(start 0.12065 0.3048)
			(end 0.67945 0.3048)
			(stroke
				(width 0.1)
				(type default)
			)
			(layer "B.Fab")
		)
		(fp_line
			(start 0.12065 0.2794)
			(end 0.12065 0.3048)
			(stroke
				(width 0.1)
				(type default)
			)
			(layer "B.Fab")
		)
		(fp_line
			(start 0.12065 -0.2794)
			(end -0.12065 -0.2794)
			(stroke
				(width 0.1)
				(type default)
			)
			(layer "B.Fab")
		)
		(fp_line
			(start 0.12065 -0.305054)
			(end 0.12065 -0.2794)
			(stroke
				(width 0.1)
				(type default)
			)
			(layer "B.Fab")
		)
		(fp_line
			(start -0.120396 0.3048)
			(end -0.120396 0.2794)
			(stroke
				(width 0.1)
				(type default)
			)
			(layer "B.Fab")
		)
		(fp_line
			(start -0.120396 0.2794)
			(end 0.12065 0.2794)
			(stroke
				(width 0.1)
				(type default)
			)
			(layer "B.Fab")
		)
		(fp_line
			(start -0.12065 -0.2794)
			(end -0.12065 -0.3048)
			(stroke
				(width 0.1)
				(type default)
			)
			(layer "B.Fab")
		)
		(fp_line
			(start -0.12065 -0.3048)
			(end -0.67945 -0.3048)
			(stroke
				(width 0.1)
				(type default)
			)
			(layer "B.Fab")
		)
		(fp_line
			(start -0.67945 0.3048)
			(end -0.120396 0.3048)
			(stroke
				(width 0.1)
				(type default)
			)
			(layer "B.Fab")
		)
		(fp_line
			(start -0.67945 -0.3048)
			(end -0.67945 0.3048)
			(stroke
				(width 0.1)
				(type default)
			)
			(layer "B.Fab")
		)
		(pad "1" smd circle
			(at 0.40005 0)
			(size 0 0)
			(layers "B.Cu" "B.Mask" "B.Paste")
			(net "RST_PEX2_PERST_R_N")
		)
		(pad "2" smd circle
			(at -0.40005 0)
			(size 0 0)
			(layers "B.Cu" "B.Mask" "B.Paste")
			(net "RST_PEX2_PERST_N")
		)
	)
	(footprint ""
		(layer "B.Cu")
		(at 399.874994 -286.399732 90)
		(property "Reference" "C3502"
			(at 0 0 90)
			(layer "B.SilkS")
			(hide yes)
			(effects
				(font
					(size 1.27 1.27)
				)
				(justify mirror)
			)
		)
		(property "Value" ""
			(at 0 0 90)
			(layer "B.Fab")
			(effects
				(font
					(size 1.27 1.27)
				)
				(justify mirror)
			)
		)
		(duplicate_pad_numbers_are_jumpers no)
		(fp_line
			(start 0.299974 -0.150114)
			(end -0.299974 -0.150114)
			(stroke
				(width 0.1)
				(type default)
			)
			(layer "B.Fab")
		)
		(fp_line
			(start -0.299974 -0.150114)
			(end -0.299974 0.150114)
			(stroke
				(width 0.1)
				(type default)
			)
			(layer "B.Fab")
		)
		(fp_line
			(start 0.299974 0.150114)
			(end 0.299974 -0.150114)
			(stroke
				(width 0.1)
				(type default)
			)
			(layer "B.Fab")
		)
		(fp_line
			(start -0.299974 0.150114)
			(end 0.299974 0.150114)
			(stroke
				(width 0.1)
				(type default)
			)
			(layer "B.Fab")
		)
		(pad "1" smd rect
			(at 0.2667 0 270)
			(size 0.3048 0.381)
			(layers "B.Cu" "B.Mask" "B.Paste")
			(net "P1V25_SERDES_VDDPLL_PEX3")
		)
		(pad "2" smd rect
			(at -0.2667 0 270)
			(size 0.3048 0.381)
			(layers "B.Cu" "B.Mask" "B.Paste")
			(net "GND")
		)
	)
	(footprint ""
		(layer "B.Cu")
		(at 298.499784 -292.099746 90)
		(property "Reference" "C1699"
			(at 0 0 90)
			(layer "B.SilkS")
			(hide yes)
			(effects
				(font
					(size 1.27 1.27)
				)
				(justify mirror)
			)
		)
		(property "Value" ""
			(at 0 0 90)
			(layer "B.Fab")
			(effects
				(font
					(size 1.27 1.27)
				)
				(justify mirror)
			)
		)
		(duplicate_pad_numbers_are_jumpers no)
		(fp_line
			(start 0.299974 -0.150114)
			(end -0.299974 -0.150114)
			(stroke
				(width 0.1)
				(type default)
			)
			(layer "B.Fab")
		)
		(fp_line
			(start -0.299974 -0.150114)
			(end -0.299974 0.150114)
			(stroke
				(width 0.1)
				(type default)
			)
			(layer "B.Fab")
		)
		(fp_line
			(start 0.299974 0.150114)
			(end 0.299974 -0.150114)
			(stroke
				(width 0.1)
				(type default)
			)
			(layer "B.Fab")
		)
		(fp_line
			(start -0.299974 0.150114)
			(end 0.299974 0.150114)
			(stroke
				(width 0.1)
				(type default)
			)
			(layer "B.Fab")
		)
		(pad "1" smd rect
			(at 0.2667 0 270)
			(size 0.3048 0.381)
			(layers "B.Cu" "B.Mask" "B.Paste")
			(net "P0V8_SERDES_VDDA_PEX2")
		)
		(pad "2" smd rect
			(at -0.2667 0 270)
			(size 0.3048 0.381)
			(layers "B.Cu" "B.Mask" "B.Paste")
			(net "GND")
		)
	)
	(footprint ""
		(layer "B.Cu")
		(at 118.456964 -316.003686)
		(property "Reference" "C4266"
			(at 0 0 0)
			(layer "B.SilkS")
			(hide yes)
			(effects
				(font
					(size 1.27 1.27)
				)
				(justify mirror)
			)
		)
		(property "Value" ""
			(at 0 0 0)
			(layer "B.Fab")
			(effects
				(font
					(size 1.27 1.27)
				)
				(justify mirror)
			)
		)
		(duplicate_pad_numbers_are_jumpers no)
		(fp_line
			(start -0.299974 -0.150114)
			(end -0.299974 0.150114)
			(stroke
				(width 0.1)
				(type default)
			)
			(layer "B.Fab")
		)
		(fp_line
			(start -0.299974 0.150114)
			(end 0.299974 0.150114)
			(stroke
				(width 0.1)
				(type default)
			)
			(layer "B.Fab")
		)
		(fp_line
			(start 0.299974 -0.150114)
			(end -0.299974 -0.150114)
			(stroke
				(width 0.1)
				(type default)
			)
			(layer "B.Fab")
		)
		(fp_line
			(start 0.299974 0.150114)
			(end 0.299974 -0.150114)
			(stroke
				(width 0.1)
				(type default)
			)
			(layer "B.Fab")
		)
		(pad "1" smd rect
			(at 0.2667 0 180)
			(size 0.3048 0.381)
			(layers "B.Cu" "B.Mask" "B.Paste")
			(net "P0V8_SERDES_VDDA_PEX1")
		)
		(pad "2" smd rect
			(at -0.2667 0 180)
			(size 0.3048 0.381)
			(layers "B.Cu" "B.Mask" "B.Paste")
			(net "GND")
		)
	)
	(footprint ""
		(layer "B.Cu")
		(at 412.224982 -297.79976 90)
		(property "Reference" "C1913"
			(at 0 0 90)
			(layer "B.SilkS")
			(hide yes)
			(effects
				(font
					(size 1.27 1.27)
				)
				(justify mirror)
			)
		)
		(property "Value" ""
			(at 0 0 90)
			(layer "B.Fab")
			(effects
				(font
					(size 1.27 1.27)
				)
				(justify mirror)
			)
		)
		(duplicate_pad_numbers_are_jumpers no)
		(fp_line
			(start 0.299974 -0.150114)
			(end -0.299974 -0.150114)
			(stroke
				(width 0.1)
				(type default)
			)
			(layer "B.Fab")
		)
		(fp_line
			(start -0.299974 -0.150114)
			(end -0.299974 0.150114)
			(stroke
				(width 0.1)
				(type default)
			)
			(layer "B.Fab")
		)
		(fp_line
			(start 0.299974 0.150114)
			(end 0.299974 -0.150114)
			(stroke
				(width 0.1)
				(type default)
			)
			(layer "B.Fab")
		)
		(fp_line
			(start -0.299974 0.150114)
			(end 0.299974 0.150114)
			(stroke
				(width 0.1)
				(type default)
			)
			(layer "B.Fab")
		)
		(pad "1" smd rect
			(at 0.2667 0 270)
			(size 0.3048 0.381)
			(layers "B.Cu" "B.Mask" "B.Paste")
			(net "P0V8_PEX3")
		)
		(pad "2" smd rect
			(at -0.2667 0 270)
			(size 0.3048 0.381)
			(layers "B.Cu" "B.Mask" "B.Paste")
			(net "GND")
		)
	)
	(footprint ""
		(layer "B.Cu")
		(at 53.045614 -296.37482)
		(property "Reference" "C1111"
			(at 0 0 0)
			(layer "B.SilkS")
			(hide yes)
			(effects
				(font
					(size 1.27 1.27)
				)
				(justify mirror)
			)
		)
		(property "Value" ""
			(at 0 0 0)
			(layer "B.Fab")
			(effects
				(font
					(size 1.27 1.27)
				)
				(justify mirror)
			)
		)
		(duplicate_pad_numbers_are_jumpers no)
		(fp_line
			(start -0.299974 -0.150114)
			(end -0.299974 0.150114)
			(stroke
				(width 0.1)
				(type default)
			)
			(layer "B.Fab")
		)
		(fp_line
			(start -0.299974 0.150114)
			(end 0.299974 0.150114)
			(stroke
				(width 0.1)
				(type default)
			)
			(layer "B.Fab")
		)
		(fp_line
			(start 0.299974 -0.150114)
			(end -0.299974 -0.150114)
			(stroke
				(width 0.1)
				(type default)
			)
			(layer "B.Fab")
		)
		(fp_line
			(start 0.299974 0.150114)
			(end 0.299974 -0.150114)
			(stroke
				(width 0.1)
				(type default)
			)
			(layer "B.Fab")
		)
		(pad "1" smd rect
			(at 0.2667 0 180)
			(size 0.3048 0.381)
			(layers "B.Cu" "B.Mask" "B.Paste")
			(net "P0V8_PEX0")
		)
		(pad "2" smd rect
			(at -0.2667 0 180)
			(size 0.3048 0.381)
			(layers "B.Cu" "B.Mask" "B.Paste")
			(net "GND")
		)
	)
	(footprint ""
		(layer "B.Cu")
		(at 127.559308 -308.580028 90)
		(property "Reference" "C4262"
			(at 0 0 90)
			(layer "B.SilkS")
			(hide yes)
			(effects
				(font
					(size 1.27 1.27)
				)
				(justify mirror)
			)
		)
		(property "Value" ""
			(at 0 0 90)
			(layer "B.Fab")
			(effects
				(font
					(size 1.27 1.27)
				)
				(justify mirror)
			)
		)
		(duplicate_pad_numbers_are_jumpers no)
		(fp_line
			(start 1.2954 -0.5842)
			(end -1.2954 -0.5842)
			(stroke
				(width 0.1524)
				(type default)
			)
			(layer "B.SilkS")
		)
		(fp_line
			(start -1.2954 -0.5842)
			(end -1.2954 0.5842)
			(stroke
				(width 0.1524)
				(type default)
			)
			(layer "B.SilkS")
		)
		(fp_line
			(start 1.2954 0.5842)
			(end 1.2954 -0.5842)
			(stroke
				(width 0.1524)
				(type default)
			)
			(layer "B.SilkS")
		)
		(fp_line
			(start -1.2954 0.5842)
			(end 1.2954 0.5842)
			(stroke
				(width 0.1524)
				(type default)
			)
			(layer "B.SilkS")
		)
		(fp_line
			(start 0.8636 -0.4572)
			(end -0.8636 -0.4572)
			(stroke
				(width 0.1)
				(type default)
			)
			(layer "B.Fab")
		)
		(fp_line
			(start -0.8636 -0.4572)
			(end -0.8636 -0.4064)
			(stroke
				(width 0.1)
				(type default)
			)
			(layer "B.Fab")
		)
		(fp_line
			(start 1.1938 -0.4064)
			(end 0.8636 -0.4064)
			(stroke
				(width 0.1)
				(type default)
			)
			(layer "B.Fab")
		)
		(fp_line
			(start 0.8636 -0.4064)
			(end 0.8636 -0.4572)
			(stroke
				(width 0.1)
				(type default)
			)
			(layer "B.Fab")
		)
		(fp_line
			(start -0.8636 -0.4064)
			(end -1.1938 -0.4064)
			(stroke
				(width 0.1)
				(type default)
			)
			(layer "B.Fab")
		)
		(fp_line
			(start -1.1938 -0.4064)
			(end -1.1938 0.4064)
			(stroke
				(width 0.1)
				(type default)
			)
			(layer "B.Fab")
		)
		(fp_line
			(start 1.1938 0.4064)
			(end 1.1938 -0.4064)
			(stroke
				(width 0.1)
				(type default)
			)
			(layer "B.Fab")
		)
		(fp_line
			(start 0.8636 0.4064)
			(end 1.1938 0.4064)
			(stroke
				(width 0.1)
				(type default)
			)
			(layer "B.Fab")
		)
		(fp_line
			(start -0.8636 0.4064)
			(end -0.8636 0.4572)
			(stroke
				(width 0.1)
				(type default)
			)
			(layer "B.Fab")
		)
		(fp_line
			(start -1.1938 0.4064)
			(end -0.8636 0.4064)
			(stroke
				(width 0.1)
				(type default)
			)
			(layer "B.Fab")
		)
		(fp_line
			(start 0.8636 0.4572)
			(end 0.8636 0.4064)
			(stroke
				(width 0.1)
				(type default)
			)
			(layer "B.Fab")
		)
		(fp_line
			(start -0.8636 0.4572)
			(end 0.8636 0.4572)
			(stroke
				(width 0.1)
				(type default)
			)
			(layer "B.Fab")
		)
		(pad "1" smd rect
			(at 0.7366 0)
			(size 0.7112 0.8128)
			(layers "B.Cu" "B.Mask" "B.Paste")
			(net "P0V8_PEX1")
		)
		(pad "2" smd rect
			(at -0.7366 0)
			(size 0.7112 0.8128)
			(layers "B.Cu" "B.Mask" "B.Paste")
			(net "GND")
		)
	)
	(footprint ""
		(layer "B.Cu")
		(at 183.3499 -299.699934 -90)
		(property "Reference" "C1424"
			(at 0 0 90)
			(layer "B.SilkS")
			(hide yes)
			(effects
				(font
					(size 1.27 1.27)
				)
				(justify mirror)
			)
		)
		(property "Value" ""
			(at 0 0 90)
			(layer "B.Fab")
			(effects
				(font
					(size 1.27 1.27)
				)
				(justify mirror)
			)
		)
		(duplicate_pad_numbers_are_jumpers no)
		(fp_line
			(start -0.299974 0.150114)
			(end 0.299974 0.150114)
			(stroke
				(width 0.1)
				(type default)
			)
			(layer "B.Fab")
		)
		(fp_line
			(start 0.299974 0.150114)
			(end 0.299974 -0.150114)
			(stroke
				(width 0.1)
				(type default)
			)
			(layer "B.Fab")
		)
		(fp_line
			(start -0.299974 -0.150114)
			(end -0.299974 0.150114)
			(stroke
				(width 0.1)
				(type default)
			)
			(layer "B.Fab")
		)
		(fp_line
			(start 0.299974 -0.150114)
			(end -0.299974 -0.150114)
			(stroke
				(width 0.1)
				(type default)
			)
			(layer "B.Fab")
		)
		(pad "1" smd rect
			(at 0.2667 0 90)
			(size 0.3048 0.381)
			(layers "B.Cu" "B.Mask" "B.Paste")
			(net "P0V8_SERDES_VDDA_PEX1")
		)
		(pad "2" smd rect
			(at -0.2667 0 90)
			(size 0.3048 0.381)
			(layers "B.Cu" "B.Mask" "B.Paste")
			(net "GND")
		)
	)
	(footprint ""
		(layer "B.Cu")
		(at 252.0188 -352.8568 180)
		(property "Reference" "R6713"
			(at 0 0 0)
			(layer "B.SilkS")
			(hide yes)
			(effects
				(font
					(size 1.27 1.27)
				)
				(justify mirror)
			)
		)
		(property "Value" ""
			(at 0 0 0)
			(layer "B.Fab")
			(effects
				(font
					(size 1.27 1.27)
				)
				(justify mirror)
			)
		)
		(duplicate_pad_numbers_are_jumpers no)
		(fp_line
			(start 0.7874 0.4064)
			(end 0.7874 -0.4064)
			(stroke
				(width 0.1524)
				(type default)
			)
			(layer "B.SilkS")
		)
		(fp_line
			(start 0.7874 -0.4064)
			(end -0.7874 -0.4064)
			(stroke
				(width 0.1524)
				(type default)
			)
			(layer "B.SilkS")
		)
		(fp_line
			(start -0.7874 0.4064)
			(end 0.7874 0.4064)
			(stroke
				(width 0.1524)
				(type default)
			)
			(layer "B.SilkS")
		)
		(fp_line
			(start -0.7874 -0.4064)
			(end -0.7874 0.4064)
			(stroke
				(width 0.1524)
				(type default)
			)
			(layer "B.SilkS")
		)
		(fp_line
			(start 0.67945 0.3048)
			(end 0.67945 -0.305054)
			(stroke
				(width 0.1)
				(type default)
			)
			(layer "B.Fab")
		)
		(fp_line
			(start 0.67945 -0.305054)
			(end 0.12065 -0.305054)
			(stroke
				(width 0.1)
				(type default)
			)
			(layer "B.Fab")
		)
		(fp_line
			(start 0.12065 0.3048)
			(end 0.67945 0.3048)
			(stroke
				(width 0.1)
				(type default)
			)
			(layer "B.Fab")
		)
		(fp_line
			(start 0.12065 0.2794)
			(end 0.12065 0.3048)
			(stroke
				(width 0.1)
				(type default)
			)
			(layer "B.Fab")
		)
		(fp_line
			(start 0.12065 -0.2794)
			(end -0.12065 -0.2794)
			(stroke
				(width 0.1)
				(type default)
			)
			(layer "B.Fab")
		)
		(fp_line
			(start 0.12065 -0.305054)
			(end 0.12065 -0.2794)
			(stroke
				(width 0.1)
				(type default)
			)
			(layer "B.Fab")
		)
		(fp_line
			(start -0.120396 0.3048)
			(end -0.120396 0.2794)
			(stroke
				(width 0.1)
				(type default)
			)
			(layer "B.Fab")
		)
		(fp_line
			(start -0.120396 0.2794)
			(end 0.12065 0.2794)
			(stroke
				(width 0.1)
				(type default)
			)
			(layer "B.Fab")
		)
		(fp_line
			(start -0.12065 -0.2794)
			(end -0.12065 -0.3048)
			(stroke
				(width 0.1)
				(type default)
			)
			(layer "B.Fab")
		)
		(fp_line
			(start -0.12065 -0.3048)
			(end -0.67945 -0.3048)
			(stroke
				(width 0.1)
				(type default)
			)
			(layer "B.Fab")
		)
		(fp_line
			(start -0.67945 0.3048)
			(end -0.120396 0.3048)
			(stroke
				(width 0.1)
				(type default)
			)
			(layer "B.Fab")
		)
		(fp_line
			(start -0.67945 -0.3048)
			(end -0.67945 0.3048)
			(stroke
				(width 0.1)
				(type default)
			)
			(layer "B.Fab")
		)
		(pad "1" smd circle
			(at 0.40005 0)
			(size 0 0)
			(layers "B.Cu" "B.Mask" "B.Paste")
			(net "HSC_TYPE_ADC")
		)
		(pad "2" smd circle
			(at -0.40005 0)
			(size 0 0)
			(layers "B.Cu" "B.Mask" "B.Paste")
			(net "HSC_TYPE_ADC_R")
		)
	)
	(footprint ""
		(layer "B.Cu")
		(at 210.596734 -215.642444)
		(property "Reference" "R5478"
			(at 0 0 0)
			(layer "B.SilkS")
			(hide yes)
			(effects
				(font
					(size 1.27 1.27)
				)
				(justify mirror)
			)
		)
		(property "Value" ""
			(at 0 0 0)
			(layer "B.Fab")
			(effects
				(font
					(size 1.27 1.27)
				)
				(justify mirror)
			)
		)
		(duplicate_pad_numbers_are_jumpers no)
		(fp_line
			(start -0.7874 -0.4064)
			(end -0.7874 0.4064)
			(stroke
				(width 0.1524)
				(type default)
			)
			(layer "B.SilkS")
		)
		(fp_line
			(start -0.7874 0.4064)
			(end 0.7874 0.4064)
			(stroke
				(width 0.1524)
				(type default)
			)
			(layer "B.SilkS")
		)
		(fp_line
			(start 0.7874 -0.4064)
			(end -0.7874 -0.4064)
			(stroke
				(width 0.1524)
				(type default)
			)
			(layer "B.SilkS")
		)
		(fp_line
			(start 0.7874 0.4064)
			(end 0.7874 -0.4064)
			(stroke
				(width 0.1524)
				(type default)
			)
			(layer "B.SilkS")
		)
		(fp_line
			(start -0.67945 -0.3048)
			(end -0.67945 0.3048)
			(stroke
				(width 0.1)
				(type default)
			)
			(layer "B.Fab")
		)
		(fp_line
			(start -0.67945 0.3048)
			(end -0.120396 0.3048)
			(stroke
				(width 0.1)
				(type default)
			)
			(layer "B.Fab")
		)
		(fp_line
			(start -0.12065 -0.3048)
			(end -0.67945 -0.3048)
			(stroke
				(width 0.1)
				(type default)
			)
			(layer "B.Fab")
		)
		(fp_line
			(start -0.12065 -0.2794)
			(end -0.12065 -0.3048)
			(stroke
				(width 0.1)
				(type default)
			)
			(layer "B.Fab")
		)
		(fp_line
			(start -0.120396 0.2794)
			(end 0.12065 0.2794)
			(stroke
				(width 0.1)
				(type default)
			)
			(layer "B.Fab")
		)
		(fp_line
			(start -0.120396 0.3048)
			(end -0.120396 0.2794)
			(stroke
				(width 0.1)
				(type default)
			)
			(layer "B.Fab")
		)
		(fp_line
			(start 0.12065 -0.305054)
			(end 0.12065 -0.2794)
			(stroke
				(width 0.1)
				(type default)
			)
			(layer "B.Fab")
		)
		(fp_line
			(start 0.12065 -0.2794)
			(end -0.12065 -0.2794)
			(stroke
				(width 0.1)
				(type default)
			)
			(layer "B.Fab")
		)
		(fp_line
			(start 0.12065 0.2794)
			(end 0.12065 0.3048)
			(stroke
				(width 0.1)
				(type default)
			)
			(layer "B.Fab")
		)
		(fp_line
			(start 0.12065 0.3048)
			(end 0.67945 0.3048)
			(stroke
				(width 0.1)
				(type default)
			)
			(layer "B.Fab")
		)
		(fp_line
			(start 0.67945 -0.305054)
			(end 0.12065 -0.305054)
			(stroke
				(width 0.1)
				(type default)
			)
			(layer "B.Fab")
		)
		(fp_line
			(start 0.67945 0.3048)
			(end 0.67945 -0.305054)
			(stroke
				(width 0.1)
				(type default)
			)
			(layer "B.Fab")
		)
		(pad "1" smd circle
			(at 0.40005 0 180)
			(size 0 0)
			(layers "B.Cu" "B.Mask" "B.Paste")
			(net "USB_DEBUG_RST_BTN_N")
		)
		(pad "2" smd circle
			(at -0.40005 0 180)
			(size 0 0)
			(layers "B.Cu" "B.Mask" "B.Paste")
			(net "USB_DEBUG_RST_BTN_R_N")
		)
	)
	(footprint ""
		(layer "B.Cu")
		(at 202.633072 -364.80496)
		(property "Reference" "PR6"
			(at 0 0 0)
			(layer "B.SilkS")
			(hide yes)
			(effects
				(font
					(size 1.27 1.27)
				)
				(justify mirror)
			)
		)
		(property "Value" ""
			(at 0 0 0)
			(layer "B.Fab")
			(effects
				(font
					(size 1.27 1.27)
				)
				(justify mirror)
			)
		)
		(duplicate_pad_numbers_are_jumpers no)
		(fp_line
			(start -0.7874 -0.4064)
			(end -0.7874 0.4064)
			(stroke
				(width 0.1524)
				(type default)
			)
			(layer "B.SilkS")
		)
		(fp_line
			(start -0.7874 0.4064)
			(end 0.7874 0.4064)
			(stroke
				(width 0.1524)
				(type default)
			)
			(layer "B.SilkS")
		)
		(fp_line
			(start 0.7874 -0.4064)
			(end -0.7874 -0.4064)
			(stroke
				(width 0.1524)
				(type default)
			)
			(layer "B.SilkS")
		)
		(fp_line
			(start 0.7874 0.4064)
			(end 0.7874 -0.4064)
			(stroke
				(width 0.1524)
				(type default)
			)
			(layer "B.SilkS")
		)
		(fp_line
			(start -0.67945 -0.3048)
			(end -0.67945 0.3048)
			(stroke
				(width 0.1)
				(type default)
			)
			(layer "B.Fab")
		)
		(fp_line
			(start -0.67945 0.3048)
			(end -0.120396 0.3048)
			(stroke
				(width 0.1)
				(type default)
			)
			(layer "B.Fab")
		)
		(fp_line
			(start -0.12065 -0.3048)
			(end -0.67945 -0.3048)
			(stroke
				(width 0.1)
				(type default)
			)
			(layer "B.Fab")
		)
		(fp_line
			(start -0.12065 -0.2794)
			(end -0.12065 -0.3048)
			(stroke
				(width 0.1)
				(type default)
			)
			(layer "B.Fab")
		)
		(fp_line
			(start -0.120396 0.2794)
			(end 0.12065 0.2794)
			(stroke
				(width 0.1)
				(type default)
			)
			(layer "B.Fab")
		)
		(fp_line
			(start -0.120396 0.3048)
			(end -0.120396 0.2794)
			(stroke
				(width 0.1)
				(type default)
			)
			(layer "B.Fab")
		)
		(fp_line
			(start 0.12065 -0.305054)
			(end 0.12065 -0.2794)
			(stroke
				(width 0.1)
				(type default)
			)
			(layer "B.Fab")
		)
		(fp_line
			(start 0.12065 -0.2794)
			(end -0.12065 -0.2794)
			(stroke
				(width 0.1)
				(type default)
			)
			(layer "B.Fab")
		)
		(fp_line
			(start 0.12065 0.2794)
			(end 0.12065 0.3048)
			(stroke
				(width 0.1)
				(type default)
			)
			(layer "B.Fab")
		)
		(fp_line
			(start 0.12065 0.3048)
			(end 0.67945 0.3048)
			(stroke
				(width 0.1)
				(type default)
			)
			(layer "B.Fab")
		)
		(fp_line
			(start 0.67945 -0.305054)
			(end 0.12065 -0.305054)
			(stroke
				(width 0.1)
				(type default)
			)
			(layer "B.Fab")
		)
		(fp_line
			(start 0.67945 0.3048)
			(end 0.67945 -0.305054)
			(stroke
				(width 0.1)
				(type default)
			)
			(layer "B.Fab")
		)
		(pad "1" smd circle
			(at 0.40005 0 180)
			(size 0 0)
			(layers "B.Cu" "B.Mask" "B.Paste")
			(net "HSC_VOSEN")
		)
		(pad "2" smd circle
			(at -0.40005 0 180)
			(size 0 0)
			(layers "B.Cu" "B.Mask" "B.Paste")
			(net "AGND_HSC")
		)
	)
	(footprint ""
		(layer "B.Cu")
		(at 180.975 -286.399732 90)
		(property "Reference" "C3142"
			(at 0 0 90)
			(layer "B.SilkS")
			(hide yes)
			(effects
				(font
					(size 1.27 1.27)
				)
				(justify mirror)
			)
		)
		(property "Value" ""
			(at 0 0 90)
			(layer "B.Fab")
			(effects
				(font
					(size 1.27 1.27)
				)
				(justify mirror)
			)
		)
		(duplicate_pad_numbers_are_jumpers no)
		(fp_line
			(start 0.299974 -0.150114)
			(end -0.299974 -0.150114)
			(stroke
				(width 0.1)
				(type default)
			)
			(layer "B.Fab")
		)
		(fp_line
			(start -0.299974 -0.150114)
			(end -0.299974 0.150114)
			(stroke
				(width 0.1)
				(type default)
			)
			(layer "B.Fab")
		)
		(fp_line
			(start 0.299974 0.150114)
			(end 0.299974 -0.150114)
			(stroke
				(width 0.1)
				(type default)
			)
			(layer "B.Fab")
		)
		(fp_line
			(start -0.299974 0.150114)
			(end 0.299974 0.150114)
			(stroke
				(width 0.1)
				(type default)
			)
			(layer "B.Fab")
		)
		(pad "1" smd rect
			(at 0.2667 0 270)
			(size 0.3048 0.381)
			(layers "B.Cu" "B.Mask" "B.Paste")
			(net "P1V25_SERDES_VDDPLL_PEX1")
		)
		(pad "2" smd rect
			(at -0.2667 0 270)
			(size 0.3048 0.381)
			(layers "B.Cu" "B.Mask" "B.Paste")
			(net "GND")
		)
	)
	(footprint ""
		(layer "B.Cu")
		(at 217.235786 -220.334586)
		(property "Reference" "R1497"
			(at 0 0 0)
			(layer "B.SilkS")
			(hide yes)
			(effects
				(font
					(size 1.27 1.27)
				)
				(justify mirror)
			)
		)
		(property "Value" ""
			(at 0 0 0)
			(layer "B.Fab")
			(effects
				(font
					(size 1.27 1.27)
				)
				(justify mirror)
			)
		)
		(duplicate_pad_numbers_are_jumpers no)
		(fp_line
			(start -0.7874 -0.4064)
			(end -0.7874 0.4064)
			(stroke
				(width 0.1524)
				(type default)
			)
			(layer "B.SilkS")
		)
		(fp_line
			(start -0.7874 0.4064)
			(end 0.7874 0.4064)
			(stroke
				(width 0.1524)
				(type default)
			)
			(layer "B.SilkS")
		)
		(fp_line
			(start 0.7874 -0.4064)
			(end -0.7874 -0.4064)
			(stroke
				(width 0.1524)
				(type default)
			)
			(layer "B.SilkS")
		)
		(fp_line
			(start 0.7874 0.4064)
			(end 0.7874 -0.4064)
			(stroke
				(width 0.1524)
				(type default)
			)
			(layer "B.SilkS")
		)
		(fp_line
			(start -0.67945 -0.3048)
			(end -0.67945 0.3048)
			(stroke
				(width 0.1)
				(type default)
			)
			(layer "B.Fab")
		)
		(fp_line
			(start -0.67945 0.3048)
			(end -0.120396 0.3048)
			(stroke
				(width 0.1)
				(type default)
			)
			(layer "B.Fab")
		)
		(fp_line
			(start -0.12065 -0.3048)
			(end -0.67945 -0.3048)
			(stroke
				(width 0.1)
				(type default)
			)
			(layer "B.Fab")
		)
		(fp_line
			(start -0.12065 -0.2794)
			(end -0.12065 -0.3048)
			(stroke
				(width 0.1)
				(type default)
			)
			(layer "B.Fab")
		)
		(fp_line
			(start -0.120396 0.2794)
			(end 0.12065 0.2794)
			(stroke
				(width 0.1)
				(type default)
			)
			(layer "B.Fab")
		)
		(fp_line
			(start -0.120396 0.3048)
			(end -0.120396 0.2794)
			(stroke
				(width 0.1)
				(type default)
			)
			(layer "B.Fab")
		)
		(fp_line
			(start 0.12065 -0.305054)
			(end 0.12065 -0.2794)
			(stroke
				(width 0.1)
				(type default)
			)
			(layer "B.Fab")
		)
		(fp_line
			(start 0.12065 -0.2794)
			(end -0.12065 -0.2794)
			(stroke
				(width 0.1)
				(type default)
			)
			(layer "B.Fab")
		)
		(fp_line
			(start 0.12065 0.2794)
			(end 0.12065 0.3048)
			(stroke
				(width 0.1)
				(type default)
			)
			(layer "B.Fab")
		)
		(fp_line
			(start 0.12065 0.3048)
			(end 0.67945 0.3048)
			(stroke
				(width 0.1)
				(type default)
			)
			(layer "B.Fab")
		)
		(fp_line
			(start 0.67945 -0.305054)
			(end 0.12065 -0.305054)
			(stroke
				(width 0.1)
				(type default)
			)
			(layer "B.Fab")
		)
		(fp_line
			(start 0.67945 0.3048)
			(end 0.67945 -0.305054)
			(stroke
				(width 0.1)
				(type default)
			)
			(layer "B.Fab")
		)
		(pad "1" smd circle
			(at 0.40005 0 180)
			(size 0 0)
			(layers "B.Cu" "B.Mask" "B.Paste")
			(net "SMB_PEX_SDA")
		)
		(pad "2" smd circle
			(at -0.40005 0 180)
			(size 0 0)
			(layers "B.Cu" "B.Mask" "B.Paste")
			(net "SMB_PEX_R_SDA")
		)
	)
	(footprint ""
		(layer "B.Cu")
		(at 291.360606 -305.557936 -90)
		(property "Reference" "C3293"
			(at 0 0 90)
			(layer "B.SilkS")
			(hide yes)
			(effects
				(font
					(size 1.27 1.27)
				)
				(justify mirror)
			)
		)
		(property "Value" ""
			(at 0 0 90)
			(layer "B.Fab")
			(effects
				(font
					(size 1.27 1.27)
				)
				(justify mirror)
			)
		)
		(duplicate_pad_numbers_are_jumpers no)
		(fp_line
			(start -1.2954 0.5842)
			(end 1.2954 0.5842)
			(stroke
				(width 0.1524)
				(type default)
			)
			(layer "B.SilkS")
		)
		(fp_line
			(start 1.2954 0.5842)
			(end 1.2954 -0.5842)
			(stroke
				(width 0.1524)
				(type default)
			)
			(layer "B.SilkS")
		)
		(fp_line
			(start -1.2954 -0.5842)
			(end -1.2954 0.5842)
			(stroke
				(width 0.1524)
				(type default)
			)
			(layer "B.SilkS")
		)
		(fp_line
			(start 1.2954 -0.5842)
			(end -1.2954 -0.5842)
			(stroke
				(width 0.1524)
				(type default)
			)
			(layer "B.SilkS")
		)
		(fp_line
			(start -0.8636 0.4572)
			(end 0.8636 0.4572)
			(stroke
				(width 0.1)
				(type default)
			)
			(layer "B.Fab")
		)
		(fp_line
			(start 0.8636 0.4572)
			(end 0.8636 0.4064)
			(stroke
				(width 0.1)
				(type default)
			)
			(layer "B.Fab")
		)
		(fp_line
			(start -1.1938 0.4064)
			(end -0.8636 0.4064)
			(stroke
				(width 0.1)
				(type default)
			)
			(layer "B.Fab")
		)
		(fp_line
			(start -0.8636 0.4064)
			(end -0.8636 0.4572)
			(stroke
				(width 0.1)
				(type default)
			)
			(layer "B.Fab")
		)
		(fp_line
			(start 0.8636 0.4064)
			(end 1.1938 0.4064)
			(stroke
				(width 0.1)
				(type default)
			)
			(layer "B.Fab")
		)
		(fp_line
			(start 1.1938 0.4064)
			(end 1.1938 -0.4064)
			(stroke
				(width 0.1)
				(type default)
			)
			(layer "B.Fab")
		)
		(fp_line
			(start -1.1938 -0.4064)
			(end -1.1938 0.4064)
			(stroke
				(width 0.1)
				(type default)
			)
			(layer "B.Fab")
		)
		(fp_line
			(start -0.8636 -0.4064)
			(end -1.1938 -0.4064)
			(stroke
				(width 0.1)
				(type default)
			)
			(layer "B.Fab")
		)
		(fp_line
			(start 0.8636 -0.4064)
			(end 0.8636 -0.4572)
			(stroke
				(width 0.1)
				(type default)
			)
			(layer "B.Fab")
		)
		(fp_line
			(start 1.1938 -0.4064)
			(end 0.8636 -0.4064)
			(stroke
				(width 0.1)
				(type default)
			)
			(layer "B.Fab")
		)
		(fp_line
			(start -0.8636 -0.4572)
			(end -0.8636 -0.4064)
			(stroke
				(width 0.1)
				(type default)
			)
			(layer "B.Fab")
		)
		(fp_line
			(start 0.8636 -0.4572)
			(end -0.8636 -0.4572)
			(stroke
				(width 0.1)
				(type default)
			)
			(layer "B.Fab")
		)
		(pad "1" smd rect
			(at 0.7366 0 180)
			(size 0.7112 0.8128)
			(layers "B.Cu" "B.Mask" "B.Paste")
			(net "P1V25_SERDES_VDDPLL_PEX2")
		)
		(pad "2" smd rect
			(at -0.7366 0 180)
			(size 0.7112 0.8128)
			(layers "B.Cu" "B.Mask" "B.Paste")
			(net "GND")
		)
	)
	(footprint ""
		(layer "B.Cu")
		(at 410.480256 -295.221914)
		(property "Reference" "C1865"
			(at 0 0 0)
			(layer "B.SilkS")
			(hide yes)
			(effects
				(font
					(size 1.27 1.27)
				)
				(justify mirror)
			)
		)
		(property "Value" ""
			(at 0 0 0)
			(layer "B.Fab")
			(effects
				(font
					(size 1.27 1.27)
				)
				(justify mirror)
			)
		)
		(duplicate_pad_numbers_are_jumpers no)
		(fp_line
			(start -1.2954 -0.5842)
			(end -1.2954 0.5842)
			(stroke
				(width 0.1524)
				(type default)
			)
			(layer "B.SilkS")
		)
		(fp_line
			(start -1.2954 0.5842)
			(end 1.2954 0.5842)
			(stroke
				(width 0.1524)
				(type default)
			)
			(layer "B.SilkS")
		)
		(fp_line
			(start 1.2954 -0.5842)
			(end -1.2954 -0.5842)
			(stroke
				(width 0.1524)
				(type default)
			)
			(layer "B.SilkS")
		)
		(fp_line
			(start 1.2954 0.5842)
			(end 1.2954 -0.5842)
			(stroke
				(width 0.1524)
				(type default)
			)
			(layer "B.SilkS")
		)
		(fp_line
			(start -1.1938 -0.4064)
			(end -1.1938 0.4064)
			(stroke
				(width 0.1)
				(type default)
			)
			(layer "B.Fab")
		)
		(fp_line
			(start -1.1938 0.4064)
			(end -0.8636 0.4064)
			(stroke
				(width 0.1)
				(type default)
			)
			(layer "B.Fab")
		)
		(fp_line
			(start -0.8636 -0.4572)
			(end -0.8636 -0.4064)
			(stroke
				(width 0.1)
				(type default)
			)
			(layer "B.Fab")
		)
		(fp_line
			(start -0.8636 -0.4064)
			(end -1.1938 -0.4064)
			(stroke
				(width 0.1)
				(type default)
			)
			(layer "B.Fab")
		)
		(fp_line
			(start -0.8636 0.4064)
			(end -0.8636 0.4572)
			(stroke
				(width 0.1)
				(type default)
			)
			(layer "B.Fab")
		)
		(fp_line
			(start -0.8636 0.4572)
			(end 0.8636 0.4572)
			(stroke
				(width 0.1)
				(type default)
			)
			(layer "B.Fab")
		)
		(fp_line
			(start 0.8636 -0.4572)
			(end -0.8636 -0.4572)
			(stroke
				(width 0.1)
				(type default)
			)
			(layer "B.Fab")
		)
		(fp_line
			(start 0.8636 -0.4064)
			(end 0.8636 -0.4572)
			(stroke
				(width 0.1)
				(type default)
			)
			(layer "B.Fab")
		)
		(fp_line
			(start 0.8636 0.4064)
			(end 1.1938 0.4064)
			(stroke
				(width 0.1)
				(type default)
			)
			(layer "B.Fab")
		)
		(fp_line
			(start 0.8636 0.4572)
			(end 0.8636 0.4064)
			(stroke
				(width 0.1)
				(type default)
			)
			(layer "B.Fab")
		)
		(fp_line
			(start 1.1938 -0.4064)
			(end 0.8636 -0.4064)
			(stroke
				(width 0.1)
				(type default)
			)
			(layer "B.Fab")
		)
		(fp_line
			(start 1.1938 0.4064)
			(end 1.1938 -0.4064)
			(stroke
				(width 0.1)
				(type default)
			)
			(layer "B.Fab")
		)
		(pad "1" smd rect
			(at 0.7366 0 270)
			(size 0.7112 0.8128)
			(layers "B.Cu" "B.Mask" "B.Paste")
			(net "P0V8_PEX3")
		)
		(pad "2" smd rect
			(at -0.7366 0 270)
			(size 0.7112 0.8128)
			(layers "B.Cu" "B.Mask" "B.Paste")
			(net "GND")
		)
	)
	(footprint ""
		(layer "B.Cu")
		(at 337.6549 -308.613556 90)
		(property "Reference" "C4302"
			(at 0 0 90)
			(layer "B.SilkS")
			(hide yes)
			(effects
				(font
					(size 1.27 1.27)
				)
				(justify mirror)
			)
		)
		(property "Value" ""
			(at 0 0 90)
			(layer "B.Fab")
			(effects
				(font
					(size 1.27 1.27)
				)
				(justify mirror)
			)
		)
		(duplicate_pad_numbers_are_jumpers no)
		(fp_line
			(start 1.2954 -0.5842)
			(end -1.2954 -0.5842)
			(stroke
				(width 0.1524)
				(type default)
			)
			(layer "B.SilkS")
		)
		(fp_line
			(start -1.2954 -0.5842)
			(end -1.2954 0.5842)
			(stroke
				(width 0.1524)
				(type default)
			)
			(layer "B.SilkS")
		)
		(fp_line
			(start 1.2954 0.5842)
			(end 1.2954 -0.5842)
			(stroke
				(width 0.1524)
				(type default)
			)
			(layer "B.SilkS")
		)
		(fp_line
			(start -1.2954 0.5842)
			(end 1.2954 0.5842)
			(stroke
				(width 0.1524)
				(type default)
			)
			(layer "B.SilkS")
		)
		(fp_line
			(start 0.8636 -0.4572)
			(end -0.8636 -0.4572)
			(stroke
				(width 0.1)
				(type default)
			)
			(layer "B.Fab")
		)
		(fp_line
			(start -0.8636 -0.4572)
			(end -0.8636 -0.4064)
			(stroke
				(width 0.1)
				(type default)
			)
			(layer "B.Fab")
		)
		(fp_line
			(start 1.1938 -0.4064)
			(end 0.8636 -0.4064)
			(stroke
				(width 0.1)
				(type default)
			)
			(layer "B.Fab")
		)
		(fp_line
			(start 0.8636 -0.4064)
			(end 0.8636 -0.4572)
			(stroke
				(width 0.1)
				(type default)
			)
			(layer "B.Fab")
		)
		(fp_line
			(start -0.8636 -0.4064)
			(end -1.1938 -0.4064)
			(stroke
				(width 0.1)
				(type default)
			)
			(layer "B.Fab")
		)
		(fp_line
			(start -1.1938 -0.4064)
			(end -1.1938 0.4064)
			(stroke
				(width 0.1)
				(type default)
			)
			(layer "B.Fab")
		)
		(fp_line
			(start 1.1938 0.4064)
			(end 1.1938 -0.4064)
			(stroke
				(width 0.1)
				(type default)
			)
			(layer "B.Fab")
		)
		(fp_line
			(start 0.8636 0.4064)
			(end 1.1938 0.4064)
			(stroke
				(width 0.1)
				(type default)
			)
			(layer "B.Fab")
		)
		(fp_line
			(start -0.8636 0.4064)
			(end -0.8636 0.4572)
			(stroke
				(width 0.1)
				(type default)
			)
			(layer "B.Fab")
		)
		(fp_line
			(start -1.1938 0.4064)
			(end -0.8636 0.4064)
			(stroke
				(width 0.1)
				(type default)
			)
			(layer "B.Fab")
		)
		(fp_line
			(start 0.8636 0.4572)
			(end 0.8636 0.4064)
			(stroke
				(width 0.1)
				(type default)
			)
			(layer "B.Fab")
		)
		(fp_line
			(start -0.8636 0.4572)
			(end 0.8636 0.4572)
			(stroke
				(width 0.1)
				(type default)
			)
			(layer "B.Fab")
		)
		(pad "1" smd rect
			(at 0.7366 0)
			(size 0.7112 0.8128)
			(layers "B.Cu" "B.Mask" "B.Paste")
			(net "P0V8_PEX2")
		)
		(pad "2" smd rect
			(at -0.7366 0)
			(size 0.7112 0.8128)
			(layers "B.Cu" "B.Mask" "B.Paste")
			(net "GND")
		)
	)
	(footprint ""
		(layer "B.Cu")
		(at 257.052064 -80.364076)
		(property "Reference" "C2634"
			(at 0 0 0)
			(layer "B.SilkS")
			(hide yes)
			(effects
				(font
					(size 1.27 1.27)
				)
				(justify mirror)
			)
		)
		(property "Value" ""
			(at 0 0 0)
			(layer "B.Fab")
			(effects
				(font
					(size 1.27 1.27)
				)
				(justify mirror)
			)
		)
		(duplicate_pad_numbers_are_jumpers no)
		(fp_line
			(start -1.2954 -0.5842)
			(end -1.2954 0.5842)
			(stroke
				(width 0.1524)
				(type default)
			)
			(layer "B.SilkS")
		)
		(fp_line
			(start -1.2954 0.5842)
			(end 1.2954 0.5842)
			(stroke
				(width 0.1524)
				(type default)
			)
			(layer "B.SilkS")
		)
		(fp_line
			(start 1.2954 -0.5842)
			(end -1.2954 -0.5842)
			(stroke
				(width 0.1524)
				(type default)
			)
			(layer "B.SilkS")
		)
		(fp_line
			(start 1.2954 0.5842)
			(end 1.2954 -0.5842)
			(stroke
				(width 0.1524)
				(type default)
			)
			(layer "B.SilkS")
		)
		(fp_line
			(start -1.1938 -0.4064)
			(end -1.1938 0.4064)
			(stroke
				(width 0.1)
				(type default)
			)
			(layer "B.Fab")
		)
		(fp_line
			(start -1.1938 0.4064)
			(end -0.8636 0.4064)
			(stroke
				(width 0.1)
				(type default)
			)
			(layer "B.Fab")
		)
		(fp_line
			(start -0.8636 -0.4572)
			(end -0.8636 -0.4064)
			(stroke
				(width 0.1)
				(type default)
			)
			(layer "B.Fab")
		)
		(fp_line
			(start -0.8636 -0.4064)
			(end -1.1938 -0.4064)
			(stroke
				(width 0.1)
				(type default)
			)
			(layer "B.Fab")
		)
		(fp_line
			(start -0.8636 0.4064)
			(end -0.8636 0.4572)
			(stroke
				(width 0.1)
				(type default)
			)
			(layer "B.Fab")
		)
		(fp_line
			(start -0.8636 0.4572)
			(end 0.8636 0.4572)
			(stroke
				(width 0.1)
				(type default)
			)
			(layer "B.Fab")
		)
		(fp_line
			(start 0.8636 -0.4572)
			(end -0.8636 -0.4572)
			(stroke
				(width 0.1)
				(type default)
			)
			(layer "B.Fab")
		)
		(fp_line
			(start 0.8636 -0.4064)
			(end 0.8636 -0.4572)
			(stroke
				(width 0.1)
				(type default)
			)
			(layer "B.Fab")
		)
		(fp_line
			(start 0.8636 0.4064)
			(end 1.1938 0.4064)
			(stroke
				(width 0.1)
				(type default)
			)
			(layer "B.Fab")
		)
		(fp_line
			(start 0.8636 0.4572)
			(end 0.8636 0.4064)
			(stroke
				(width 0.1)
				(type default)
			)
			(layer "B.Fab")
		)
		(fp_line
			(start 1.1938 -0.4064)
			(end 0.8636 -0.4064)
			(stroke
				(width 0.1)
				(type default)
			)
			(layer "B.Fab")
		)
		(fp_line
			(start 1.1938 0.4064)
			(end 1.1938 -0.4064)
			(stroke
				(width 0.1)
				(type default)
			)
			(layer "B.Fab")
		)
		(pad "1" smd rect
			(at 0.7366 0 270)
			(size 0.7112 0.8128)
			(layers "B.Cu" "B.Mask" "B.Paste")
			(net "P3V3_CLK_GEN_VDDA100M_CK440")
		)
		(pad "2" smd rect
			(at -0.7366 0 270)
			(size 0.7112 0.8128)
			(layers "B.Cu" "B.Mask" "B.Paste")
			(net "GND")
		)
	)
	(footprint ""
		(layer "B.Cu")
		(at 217.247724 -216.388696 180)
		(property "Reference" "R4861"
			(at 0 0 0)
			(layer "B.SilkS")
			(hide yes)
			(effects
				(font
					(size 1.27 1.27)
				)
				(justify mirror)
			)
		)
		(property "Value" ""
			(at 0 0 0)
			(layer "B.Fab")
			(effects
				(font
					(size 1.27 1.27)
				)
				(justify mirror)
			)
		)
		(duplicate_pad_numbers_are_jumpers no)
		(fp_line
			(start 0.7874 0.4064)
			(end 0.7874 -0.4064)
			(stroke
				(width 0.1524)
				(type default)
			)
			(layer "B.SilkS")
		)
		(fp_line
			(start 0.7874 -0.4064)
			(end -0.7874 -0.4064)
			(stroke
				(width 0.1524)
				(type default)
			)
			(layer "B.SilkS")
		)
		(fp_line
			(start -0.7874 0.4064)
			(end 0.7874 0.4064)
			(stroke
				(width 0.1524)
				(type default)
			)
			(layer "B.SilkS")
		)
		(fp_line
			(start -0.7874 -0.4064)
			(end -0.7874 0.4064)
			(stroke
				(width 0.1524)
				(type default)
			)
			(layer "B.SilkS")
		)
		(fp_line
			(start 0.67945 0.3048)
			(end 0.67945 -0.305054)
			(stroke
				(width 0.1)
				(type default)
			)
			(layer "B.Fab")
		)
		(fp_line
			(start 0.67945 -0.305054)
			(end 0.12065 -0.305054)
			(stroke
				(width 0.1)
				(type default)
			)
			(layer "B.Fab")
		)
		(fp_line
			(start 0.12065 0.3048)
			(end 0.67945 0.3048)
			(stroke
				(width 0.1)
				(type default)
			)
			(layer "B.Fab")
		)
		(fp_line
			(start 0.12065 0.2794)
			(end 0.12065 0.3048)
			(stroke
				(width 0.1)
				(type default)
			)
			(layer "B.Fab")
		)
		(fp_line
			(start 0.12065 -0.2794)
			(end -0.12065 -0.2794)
			(stroke
				(width 0.1)
				(type default)
			)
			(layer "B.Fab")
		)
		(fp_line
			(start 0.12065 -0.305054)
			(end 0.12065 -0.2794)
			(stroke
				(width 0.1)
				(type default)
			)
			(layer "B.Fab")
		)
		(fp_line
			(start -0.120396 0.3048)
			(end -0.120396 0.2794)
			(stroke
				(width 0.1)
				(type default)
			)
			(layer "B.Fab")
		)
		(fp_line
			(start -0.120396 0.2794)
			(end 0.12065 0.2794)
			(stroke
				(width 0.1)
				(type default)
			)
			(layer "B.Fab")
		)
		(fp_line
			(start -0.12065 -0.2794)
			(end -0.12065 -0.3048)
			(stroke
				(width 0.1)
				(type default)
			)
			(layer "B.Fab")
		)
		(fp_line
			(start -0.12065 -0.3048)
			(end -0.67945 -0.3048)
			(stroke
				(width 0.1)
				(type default)
			)
			(layer "B.Fab")
		)
		(fp_line
			(start -0.67945 0.3048)
			(end -0.120396 0.3048)
			(stroke
				(width 0.1)
				(type default)
			)
			(layer "B.Fab")
		)
		(fp_line
			(start -0.67945 -0.3048)
			(end -0.67945 0.3048)
			(stroke
				(width 0.1)
				(type default)
			)
			(layer "B.Fab")
		)
		(pad "1" smd circle
			(at 0.40005 0)
			(size 0 0)
			(layers "B.Cu" "B.Mask" "B.Paste")
			(net "GND")
		)
		(pad "2" smd circle
			(at -0.40005 0)
			(size 0 0)
			(layers "B.Cu" "B.Mask" "B.Paste")
			(net "BIC_PECI")
		)
	)
	(footprint ""
		(layer "B.Cu")
		(at 265.66368 -89.142316)
		(property "Reference" "L10"
			(at 0 0 0)
			(layer "B.SilkS")
			(hide yes)
			(effects
				(font
					(size 1.27 1.27)
				)
				(justify mirror)
			)
		)
		(property "Value" ""
			(at 0 0 0)
			(layer "B.Fab")
			(effects
				(font
					(size 1.27 1.27)
				)
				(justify mirror)
			)
		)
		(duplicate_pad_numbers_are_jumpers no)
		(fp_line
			(start -1.63576 -0.8128)
			(end -1.63576 0.8128)
			(stroke
				(width 0.1524)
				(type default)
			)
			(layer "B.SilkS")
		)
		(fp_line
			(start -1.63576 0.8128)
			(end 1.63576 0.8128)
			(stroke
				(width 0.1524)
				(type default)
			)
			(layer "B.SilkS")
		)
		(fp_line
			(start 1.63576 -0.8128)
			(end -1.63576 -0.8128)
			(stroke
				(width 0.1524)
				(type default)
			)
			(layer "B.SilkS")
		)
		(fp_line
			(start 1.63576 -0.8128)
			(end 1.63576 0.8128)
			(stroke
				(width 0.1524)
				(type default)
			)
			(layer "B.SilkS")
		)
		(fp_line
			(start -1.560576 -0.738632)
			(end 1.56083 -0.738632)
			(stroke
				(width 0.1)
				(type default)
			)
			(layer "B.Fab")
		)
		(fp_line
			(start -1.560576 0.7366)
			(end -1.560576 -0.738632)
			(stroke
				(width 0.1)
				(type default)
			)
			(layer "B.Fab")
		)
		(fp_line
			(start -1.524 0.7366)
			(end -1.560576 0.7366)
			(stroke
				(width 0.1)
				(type default)
			)
			(layer "B.Fab")
		)
		(fp_line
			(start 1.524 0.7366)
			(end -1.524 0.7366)
			(stroke
				(width 0.1)
				(type default)
			)
			(layer "B.Fab")
		)
		(fp_line
			(start 1.56083 -0.738632)
			(end 1.56083 0.7366)
			(stroke
				(width 0.1)
				(type default)
			)
			(layer "B.Fab")
		)
		(fp_line
			(start 1.56083 0.7366)
			(end 1.524 0.7366)
			(stroke
				(width 0.1)
				(type default)
			)
			(layer "B.Fab")
		)
		(pad "1" smd rect
			(at 0.94996 0)
			(size 1.1176 1.3716)
			(layers "B.Cu" "B.Mask" "B.Paste")
			(net "P3V3")
		)
		(pad "2" smd rect
			(at -0.94996 0)
			(size 1.1176 1.3716)
			(layers "B.Cu" "B.Mask" "B.Paste")
			(net "P3V3_CLK_GEN_VDDMXCK_CK440")
		)
	)
	(footprint ""
		(layer "B.Cu")
		(at 13.513054 -288.972752 180)
		(property "Reference" "PC988"
			(at 0 0 0)
			(layer "B.SilkS")
			(hide yes)
			(effects
				(font
					(size 1.27 1.27)
				)
				(justify mirror)
			)
		)
		(property "Value" ""
			(at 0 0 0)
			(layer "B.Fab")
			(effects
				(font
					(size 1.27 1.27)
				)
				(justify mirror)
			)
		)
		(duplicate_pad_numbers_are_jumpers no)
		(fp_line
			(start 1.524 0.762)
			(end 1.524 -0.762)
			(stroke
				(width 0.1524)
				(type default)
			)
			(layer "B.SilkS")
		)
		(fp_line
			(start 1.524 -0.762)
			(end -1.524 -0.762)
			(stroke
				(width 0.1524)
				(type default)
			)
			(layer "B.SilkS")
		)
		(fp_line
			(start -1.524 0.762)
			(end 1.524 0.762)
			(stroke
				(width 0.1524)
				(type default)
			)
			(layer "B.SilkS")
		)
		(fp_line
			(start -1.524 -0.762)
			(end -1.524 0.762)
			(stroke
				(width 0.1524)
				(type default)
			)
			(layer "B.SilkS")
		)
		(fp_line
			(start 1.1049 0.724916)
			(end -1.1049 0.724916)
			(stroke
				(width 0.1)
				(type default)
			)
			(layer "B.Fab")
		)
		(fp_line
			(start 1.1049 -0.724916)
			(end 1.1049 0.724916)
			(stroke
				(width 0.1)
				(type default)
			)
			(layer "B.Fab")
		)
		(fp_line
			(start -1.1049 0.724916)
			(end -1.1049 -0.724916)
			(stroke
				(width 0.1)
				(type default)
			)
			(layer "B.Fab")
		)
		(fp_line
			(start -1.1049 -0.724916)
			(end 1.1049 -0.724916)
			(stroke
				(width 0.1)
				(type default)
			)
			(layer "B.Fab")
		)
		(pad "1" smd rect
			(at 0.889 0 180)
			(size 1.016 1.27)
			(layers "B.Cu" "B.Mask" "B.Paste")
			(net "P1V25_PEX0_R")
		)
		(pad "2" smd rect
			(at -0.889 0 180)
			(size 1.016 1.27)
			(layers "B.Cu" "B.Mask" "B.Paste")
			(net "GND")
		)
	)
	(footprint ""
		(layer "B.Cu")
		(at 54.864762 -140.931138 180)
		(property "Reference" "U8"
			(at -0.21971 1.912874 0)
			(unlocked yes)
			(layer "B.SilkS")
			(effects
				(font
					(size 0.7874 0.5842)
					(thickness 0.1524)
				)
				(justify mirror)
			)
		)
		(property "Value" ""
			(at 0 0 0)
			(layer "B.Fab")
			(effects
				(font
					(size 1.27 1.27)
				)
				(justify mirror)
			)
		)
		(duplicate_pad_numbers_are_jumpers no)
		(fp_line
			(start 1.3462 1.1938)
			(end -1.3462 1.1938)
			(stroke
				(width 0.1524)
				(type default)
			)
			(layer "B.SilkS")
		)
		(fp_line
			(start 1.3462 -1.1938)
			(end 1.3462 1.1684)
			(stroke
				(width 0.1524)
				(type default)
			)
			(layer "B.SilkS")
		)
		(fp_line
			(start -1.3462 1.1938)
			(end -1.3462 -1.1938)
			(stroke
				(width 0.1524)
				(type default)
			)
			(layer "B.SilkS")
		)
		(fp_line
			(start -1.3462 -1.1938)
			(end 1.3462 -1.1938)
			(stroke
				(width 0.1524)
				(type default)
			)
			(layer "B.SilkS")
		)
		(fp_poly
			(pts
				(xy 1.447038 -0.760476) (xy 2.052066 -0.457962) (xy 2.052066 -1.06299)
			)
			(stroke
				(width 0)
				(type default)
			)
			(fill yes)
			(layer "B.SilkS")
		)
		(fp_line
			(start 0.674878 1.124966)
			(end -0.674878 1.124966)
			(stroke
				(width 0.1)
				(type default)
			)
			(layer "B.Fab")
		)
		(fp_line
			(start 0.674878 -1.124966)
			(end 0.674878 1.124966)
			(stroke
				(width 0.1)
				(type default)
			)
			(layer "B.Fab")
		)
		(fp_line
			(start -0.674878 1.124966)
			(end -0.674878 -1.124966)
			(stroke
				(width 0.1)
				(type default)
			)
			(layer "B.Fab")
		)
		(fp_line
			(start -0.674878 -1.124966)
			(end 0.674878 -1.124966)
			(stroke
				(width 0.1)
				(type default)
			)
			(layer "B.Fab")
		)
		(fp_poly
			(pts
				(xy 1.447038 -0.760476) (xy 2.052066 -0.457962) (xy 2.052066 -1.06299)
			)
			(stroke
				(width 0)
				(type default)
			)
			(fill yes)
			(layer "B.Fab")
		)
		(pad "1" smd rect
			(at 0.899922 -0.750062)
			(size 0.6096 0.6096)
			(layers "B.Cu" "B.Mask" "B.Paste")
			(net "NIC0_AUX_PWR_EN_R")
		)
		(pad "2" smd rect
			(at 0.899922 0 270)
			(size 0.4064 0.6096)
			(layers "B.Cu" "B.Mask" "B.Paste")
			(net "RST_SMB_NIC0_MUX_N")
		)
		(pad "3" smd rect
			(at 0.899922 0.750062)
			(size 0.6096 0.6096)
			(layers "B.Cu" "B.Mask" "B.Paste")
			(net "GND")
		)
		(pad "4" smd rect
			(at -0.899922 0.750062)
			(size 0.6096 0.6096)
			(layers "B.Cu" "B.Mask" "B.Paste")
			(net "RST_SMB_NIC0_MUX_ISO_N")
		)
		(pad "5" smd rect
			(at -0.899922 -0.750062)
			(size 0.6096 0.6096)
			(layers "B.Cu" "B.Mask" "B.Paste")
			(net "P3V3_AUX")
		)
	)
	(footprint ""
		(layer "B.Cu")
		(at 386.316982 -232.858564 90)
		(property "Reference" "C2576"
			(at 0 0 90)
			(layer "B.SilkS")
			(hide yes)
			(effects
				(font
					(size 1.27 1.27)
				)
				(justify mirror)
			)
		)
		(property "Value" ""
			(at 0 0 90)
			(layer "B.Fab")
			(effects
				(font
					(size 1.27 1.27)
				)
				(justify mirror)
			)
		)
		(duplicate_pad_numbers_are_jumpers no)
		(fp_line
			(start 0.7874 -0.4064)
			(end -0.7874 -0.4064)
			(stroke
				(width 0.1524)
				(type default)
			)
			(layer "B.SilkS")
		)
		(fp_line
			(start -0.7874 -0.4064)
			(end -0.7874 0.4064)
			(stroke
				(width 0.1524)
				(type default)
			)
			(layer "B.SilkS")
		)
		(fp_line
			(start 0.7874 0.4064)
			(end 0.7874 -0.4064)
			(stroke
				(width 0.1524)
				(type default)
			)
			(layer "B.SilkS")
		)
		(fp_line
			(start -0.7874 0.4064)
			(end 0.7874 0.4064)
			(stroke
				(width 0.1524)
				(type default)
			)
			(layer "B.SilkS")
		)
		(fp_line
			(start 0.67945 -0.305054)
			(end 0.12065 -0.305054)
			(stroke
				(width 0.1)
				(type default)
			)
			(layer "B.Fab")
		)
		(fp_line
			(start 0.12065 -0.305054)
			(end 0.12065 -0.2794)
			(stroke
				(width 0.1)
				(type default)
			)
			(layer "B.Fab")
		)
		(fp_line
			(start -0.12065 -0.3048)
			(end -0.67945 -0.3048)
			(stroke
				(width 0.1)
				(type default)
			)
			(layer "B.Fab")
		)
		(fp_line
			(start -0.67945 -0.3048)
			(end -0.67945 0.3048)
			(stroke
				(width 0.1)
				(type default)
			)
			(layer "B.Fab")
		)
		(fp_line
			(start 0.12065 -0.2794)
			(end -0.12065 -0.2794)
			(stroke
				(width 0.1)
				(type default)
			)
			(layer "B.Fab")
		)
		(fp_line
			(start -0.12065 -0.2794)
			(end -0.12065 -0.3048)
			(stroke
				(width 0.1)
				(type default)
			)
			(layer "B.Fab")
		)
		(fp_line
			(start 0.12065 0.2794)
			(end 0.12065 0.3048)
			(stroke
				(width 0.1)
				(type default)
			)
			(layer "B.Fab")
		)
		(fp_line
			(start -0.120396 0.2794)
			(end 0.12065 0.2794)
			(stroke
				(width 0.1)
				(type default)
			)
			(layer "B.Fab")
		)
		(fp_line
			(start 0.67945 0.3048)
			(end 0.67945 -0.305054)
			(stroke
				(width 0.1)
				(type default)
			)
			(layer "B.Fab")
		)
		(fp_line
			(start 0.12065 0.3048)
			(end 0.67945 0.3048)
			(stroke
				(width 0.1)
				(type default)
			)
			(layer "B.Fab")
		)
		(fp_line
			(start -0.120396 0.3048)
			(end -0.120396 0.2794)
			(stroke
				(width 0.1)
				(type default)
			)
			(layer "B.Fab")
		)
		(fp_line
			(start -0.67945 0.3048)
			(end -0.120396 0.3048)
			(stroke
				(width 0.1)
				(type default)
			)
			(layer "B.Fab")
		)
		(pad "1" smd circle
			(at 0.40005 0 270)
			(size 0 0)
			(layers "B.Cu" "B.Mask" "B.Paste")
			(net "P1V8_SDB_VCORE")
		)
		(pad "2" smd circle
			(at -0.40005 0 270)
			(size 0 0)
			(layers "B.Cu" "B.Mask" "B.Paste")
			(net "GND")
		)
	)
	(footprint ""
		(layer "B.Cu")
		(at 366.492536 -327.3552)
		(property "Reference" "PJ25"
			(at 0 0 0)
			(layer "B.SilkS")
			(hide yes)
			(effects
				(font
					(size 1.27 1.27)
				)
				(justify mirror)
			)
		)
		(property "Value" ""
			(at 0 0 0)
			(layer "B.Fab")
			(effects
				(font
					(size 1.27 1.27)
				)
				(justify mirror)
			)
		)
		(duplicate_pad_numbers_are_jumpers no)
		(pad "1" smd circle
			(at 0.40005 0 90)
			(size 0 0)
			(layers "B.Cu" "B.Mask" "B.Paste")
			(net "VSENSE_P0V8_PEX3_SKT_VRTN")
		)
		(pad "2" smd rect
			(at -0.40005 0)
			(size 0.4572 0.508)
			(layers "B.Cu" "B.Mask" "B.Paste")
			(net "SH_P0V8_PEX3_RGND3")
		)
		(zone
			(layer "B.Cu")
			(hatch none 0.5)
			(connect_pads
				(clearance 0)
			)
			(min_thickness 0.25)
			(keepout
				(tracks allowed)
				(vias not_allowed)
				(pads allowed)
				(copperpour not_allowed)
				(footprints allowed)
			)
			(placement
				(enabled no)
				(sheetname "")
			)
			(fill
				(thermal_gap 0.5)
				(thermal_bridge_width 0.5)
				(island_removal_mode 0)
			)
			(polygon
				(pts
					(xy 365.806736 -327.0504) (xy 365.806736 -327.66) (xy 367.178336 -327.66) (xy 367.178336 -327.0504)
				)
			)
		)
	)
	(footprint ""
		(layer "B.Cu")
		(at 396.120366 -302.028606)
		(property "Reference" "C3510"
			(at 0 0 0)
			(layer "B.SilkS")
			(hide yes)
			(effects
				(font
					(size 1.27 1.27)
				)
				(justify mirror)
			)
		)
		(property "Value" ""
			(at 0 0 0)
			(layer "B.Fab")
			(effects
				(font
					(size 1.27 1.27)
				)
				(justify mirror)
			)
		)
		(duplicate_pad_numbers_are_jumpers no)
		(fp_line
			(start -1.2954 -0.5842)
			(end -1.2954 0.5842)
			(stroke
				(width 0.1524)
				(type default)
			)
			(layer "B.SilkS")
		)
		(fp_line
			(start -1.2954 0.5842)
			(end 1.2954 0.5842)
			(stroke
				(width 0.1524)
				(type default)
			)
			(layer "B.SilkS")
		)
		(fp_line
			(start 1.2954 -0.5842)
			(end -1.2954 -0.5842)
			(stroke
				(width 0.1524)
				(type default)
			)
			(layer "B.SilkS")
		)
		(fp_line
			(start 1.2954 0.5842)
			(end 1.2954 -0.5842)
			(stroke
				(width 0.1524)
				(type default)
			)
			(layer "B.SilkS")
		)
		(fp_line
			(start -1.1938 -0.4064)
			(end -1.1938 0.4064)
			(stroke
				(width 0.1)
				(type default)
			)
			(layer "B.Fab")
		)
		(fp_line
			(start -1.1938 0.4064)
			(end -0.8636 0.4064)
			(stroke
				(width 0.1)
				(type default)
			)
			(layer "B.Fab")
		)
		(fp_line
			(start -0.8636 -0.4572)
			(end -0.8636 -0.4064)
			(stroke
				(width 0.1)
				(type default)
			)
			(layer "B.Fab")
		)
		(fp_line
			(start -0.8636 -0.4064)
			(end -1.1938 -0.4064)
			(stroke
				(width 0.1)
				(type default)
			)
			(layer "B.Fab")
		)
		(fp_line
			(start -0.8636 0.4064)
			(end -0.8636 0.4572)
			(stroke
				(width 0.1)
				(type default)
			)
			(layer "B.Fab")
		)
		(fp_line
			(start -0.8636 0.4572)
			(end 0.8636 0.4572)
			(stroke
				(width 0.1)
				(type default)
			)
			(layer "B.Fab")
		)
		(fp_line
			(start 0.8636 -0.4572)
			(end -0.8636 -0.4572)
			(stroke
				(width 0.1)
				(type default)
			)
			(layer "B.Fab")
		)
		(fp_line
			(start 0.8636 -0.4064)
			(end 0.8636 -0.4572)
			(stroke
				(width 0.1)
				(type default)
			)
			(layer "B.Fab")
		)
		(fp_line
			(start 0.8636 0.4064)
			(end 1.1938 0.4064)
			(stroke
				(width 0.1)
				(type default)
			)
			(layer "B.Fab")
		)
		(fp_line
			(start 0.8636 0.4572)
			(end 0.8636 0.4064)
			(stroke
				(width 0.1)
				(type default)
			)
			(layer "B.Fab")
		)
		(fp_line
			(start 1.1938 -0.4064)
			(end 0.8636 -0.4064)
			(stroke
				(width 0.1)
				(type default)
			)
			(layer "B.Fab")
		)
		(fp_line
			(start 1.1938 0.4064)
			(end 1.1938 -0.4064)
			(stroke
				(width 0.1)
				(type default)
			)
			(layer "B.Fab")
		)
		(pad "1" smd rect
			(at 0.7366 0 270)
			(size 0.7112 0.8128)
			(layers "B.Cu" "B.Mask" "B.Paste")
			(net "P1V8_VDDA_PEX3")
		)
		(pad "2" smd rect
			(at -0.7366 0 270)
			(size 0.7112 0.8128)
			(layers "B.Cu" "B.Mask" "B.Paste")
			(net "GND")
		)
	)
	(footprint ""
		(layer "B.Cu")
		(at 59.160664 -305.557936 -90)
		(property "Reference" "C2945"
			(at 0 0 90)
			(layer "B.SilkS")
			(hide yes)
			(effects
				(font
					(size 1.27 1.27)
				)
				(justify mirror)
			)
		)
		(property "Value" ""
			(at 0 0 90)
			(layer "B.Fab")
			(effects
				(font
					(size 1.27 1.27)
				)
				(justify mirror)
			)
		)
		(duplicate_pad_numbers_are_jumpers no)
		(fp_line
			(start -1.2954 0.5842)
			(end 1.2954 0.5842)
			(stroke
				(width 0.1524)
				(type default)
			)
			(layer "B.SilkS")
		)
		(fp_line
			(start 1.2954 0.5842)
			(end 1.2954 -0.5842)
			(stroke
				(width 0.1524)
				(type default)
			)
			(layer "B.SilkS")
		)
		(fp_line
			(start -1.2954 -0.5842)
			(end -1.2954 0.5842)
			(stroke
				(width 0.1524)
				(type default)
			)
			(layer "B.SilkS")
		)
		(fp_line
			(start 1.2954 -0.5842)
			(end -1.2954 -0.5842)
			(stroke
				(width 0.1524)
				(type default)
			)
			(layer "B.SilkS")
		)
		(fp_line
			(start -0.8636 0.4572)
			(end 0.8636 0.4572)
			(stroke
				(width 0.1)
				(type default)
			)
			(layer "B.Fab")
		)
		(fp_line
			(start 0.8636 0.4572)
			(end 0.8636 0.4064)
			(stroke
				(width 0.1)
				(type default)
			)
			(layer "B.Fab")
		)
		(fp_line
			(start -1.1938 0.4064)
			(end -0.8636 0.4064)
			(stroke
				(width 0.1)
				(type default)
			)
			(layer "B.Fab")
		)
		(fp_line
			(start -0.8636 0.4064)
			(end -0.8636 0.4572)
			(stroke
				(width 0.1)
				(type default)
			)
			(layer "B.Fab")
		)
		(fp_line
			(start 0.8636 0.4064)
			(end 1.1938 0.4064)
			(stroke
				(width 0.1)
				(type default)
			)
			(layer "B.Fab")
		)
		(fp_line
			(start 1.1938 0.4064)
			(end 1.1938 -0.4064)
			(stroke
				(width 0.1)
				(type default)
			)
			(layer "B.Fab")
		)
		(fp_line
			(start -1.1938 -0.4064)
			(end -1.1938 0.4064)
			(stroke
				(width 0.1)
				(type default)
			)
			(layer "B.Fab")
		)
		(fp_line
			(start -0.8636 -0.4064)
			(end -1.1938 -0.4064)
			(stroke
				(width 0.1)
				(type default)
			)
			(layer "B.Fab")
		)
		(fp_line
			(start 0.8636 -0.4064)
			(end 0.8636 -0.4572)
			(stroke
				(width 0.1)
				(type default)
			)
			(layer "B.Fab")
		)
		(fp_line
			(start 1.1938 -0.4064)
			(end 0.8636 -0.4064)
			(stroke
				(width 0.1)
				(type default)
			)
			(layer "B.Fab")
		)
		(fp_line
			(start -0.8636 -0.4572)
			(end -0.8636 -0.4064)
			(stroke
				(width 0.1)
				(type default)
			)
			(layer "B.Fab")
		)
		(fp_line
			(start 0.8636 -0.4572)
			(end -0.8636 -0.4572)
			(stroke
				(width 0.1)
				(type default)
			)
			(layer "B.Fab")
		)
		(pad "1" smd rect
			(at 0.7366 0 180)
			(size 0.7112 0.8128)
			(layers "B.Cu" "B.Mask" "B.Paste")
			(net "P1V25_SERDES_VDDPLL_PEX0")
		)
		(pad "2" smd rect
			(at -0.7366 0 180)
			(size 0.7112 0.8128)
			(layers "B.Cu" "B.Mask" "B.Paste")
			(net "GND")
		)
	)
	(footprint ""
		(layer "B.Cu")
		(at 102.364032 -333.614522)
		(property "Reference" "R4228"
			(at 0 0 0)
			(layer "B.SilkS")
			(hide yes)
			(effects
				(font
					(size 1.27 1.27)
				)
				(justify mirror)
			)
		)
		(property "Value" ""
			(at 0 0 0)
			(layer "B.Fab")
			(effects
				(font
					(size 1.27 1.27)
				)
				(justify mirror)
			)
		)
		(duplicate_pad_numbers_are_jumpers no)
		(fp_line
			(start -0.7874 -0.4064)
			(end -0.7874 0.4064)
			(stroke
				(width 0.1524)
				(type default)
			)
			(layer "B.SilkS")
		)
		(fp_line
			(start -0.7874 0.4064)
			(end 0.7874 0.4064)
			(stroke
				(width 0.1524)
				(type default)
			)
			(layer "B.SilkS")
		)
		(fp_line
			(start 0.7874 -0.4064)
			(end -0.7874 -0.4064)
			(stroke
				(width 0.1524)
				(type default)
			)
			(layer "B.SilkS")
		)
		(fp_line
			(start 0.7874 0.4064)
			(end 0.7874 -0.4064)
			(stroke
				(width 0.1524)
				(type default)
			)
			(layer "B.SilkS")
		)
		(fp_line
			(start -0.67945 -0.3048)
			(end -0.67945 0.3048)
			(stroke
				(width 0.1)
				(type default)
			)
			(layer "B.Fab")
		)
		(fp_line
			(start -0.67945 0.3048)
			(end -0.120396 0.3048)
			(stroke
				(width 0.1)
				(type default)
			)
			(layer "B.Fab")
		)
		(fp_line
			(start -0.12065 -0.3048)
			(end -0.67945 -0.3048)
			(stroke
				(width 0.1)
				(type default)
			)
			(layer "B.Fab")
		)
		(fp_line
			(start -0.12065 -0.2794)
			(end -0.12065 -0.3048)
			(stroke
				(width 0.1)
				(type default)
			)
			(layer "B.Fab")
		)
		(fp_line
			(start -0.120396 0.2794)
			(end 0.12065 0.2794)
			(stroke
				(width 0.1)
				(type default)
			)
			(layer "B.Fab")
		)
		(fp_line
			(start -0.120396 0.3048)
			(end -0.120396 0.2794)
			(stroke
				(width 0.1)
				(type default)
			)
			(layer "B.Fab")
		)
		(fp_line
			(start 0.12065 -0.305054)
			(end 0.12065 -0.2794)
			(stroke
				(width 0.1)
				(type default)
			)
			(layer "B.Fab")
		)
		(fp_line
			(start 0.12065 -0.2794)
			(end -0.12065 -0.2794)
			(stroke
				(width 0.1)
				(type default)
			)
			(layer "B.Fab")
		)
		(fp_line
			(start 0.12065 0.2794)
			(end 0.12065 0.3048)
			(stroke
				(width 0.1)
				(type default)
			)
			(layer "B.Fab")
		)
		(fp_line
			(start 0.12065 0.3048)
			(end 0.67945 0.3048)
			(stroke
				(width 0.1)
				(type default)
			)
			(layer "B.Fab")
		)
		(fp_line
			(start 0.67945 -0.305054)
			(end 0.12065 -0.305054)
			(stroke
				(width 0.1)
				(type default)
			)
			(layer "B.Fab")
		)
		(fp_line
			(start 0.67945 0.3048)
			(end 0.67945 -0.305054)
			(stroke
				(width 0.1)
				(type default)
			)
			(layer "B.Fab")
		)
		(pad "1" smd circle
			(at 0.40005 0 180)
			(size 0 0)
			(layers "B.Cu" "B.Mask" "B.Paste")
			(net "PEX_REF_CLK_BUFFER_EN_N")
		)
		(pad "2" smd circle
			(at -0.40005 0 180)
			(size 0 0)
			(layers "B.Cu" "B.Mask" "B.Paste")
			(net "P3V3")
		)
	)
	(footprint ""
		(layer "B.Cu")
		(at 145.804382 -224.75063 180)
		(property "Reference" "R6167"
			(at 0 0 0)
			(layer "B.SilkS")
			(hide yes)
			(effects
				(font
					(size 1.27 1.27)
				)
				(justify mirror)
			)
		)
		(property "Value" ""
			(at 0 0 0)
			(layer "B.Fab")
			(effects
				(font
					(size 1.27 1.27)
				)
				(justify mirror)
			)
		)
		(duplicate_pad_numbers_are_jumpers no)
		(fp_line
			(start 0.7874 0.4064)
			(end 0.7874 -0.4064)
			(stroke
				(width 0.1524)
				(type default)
			)
			(layer "B.SilkS")
		)
		(fp_line
			(start 0.7874 -0.4064)
			(end -0.7874 -0.4064)
			(stroke
				(width 0.1524)
				(type default)
			)
			(layer "B.SilkS")
		)
		(fp_line
			(start -0.7874 0.4064)
			(end 0.7874 0.4064)
			(stroke
				(width 0.1524)
				(type default)
			)
			(layer "B.SilkS")
		)
		(fp_line
			(start -0.7874 -0.4064)
			(end -0.7874 0.4064)
			(stroke
				(width 0.1524)
				(type default)
			)
			(layer "B.SilkS")
		)
		(fp_line
			(start 0.67945 0.3048)
			(end 0.67945 -0.305054)
			(stroke
				(width 0.1)
				(type default)
			)
			(layer "B.Fab")
		)
		(fp_line
			(start 0.67945 -0.305054)
			(end 0.12065 -0.305054)
			(stroke
				(width 0.1)
				(type default)
			)
			(layer "B.Fab")
		)
		(fp_line
			(start 0.12065 0.3048)
			(end 0.67945 0.3048)
			(stroke
				(width 0.1)
				(type default)
			)
			(layer "B.Fab")
		)
		(fp_line
			(start 0.12065 0.2794)
			(end 0.12065 0.3048)
			(stroke
				(width 0.1)
				(type default)
			)
			(layer "B.Fab")
		)
		(fp_line
			(start 0.12065 -0.2794)
			(end -0.12065 -0.2794)
			(stroke
				(width 0.1)
				(type default)
			)
			(layer "B.Fab")
		)
		(fp_line
			(start 0.12065 -0.305054)
			(end 0.12065 -0.2794)
			(stroke
				(width 0.1)
				(type default)
			)
			(layer "B.Fab")
		)
		(fp_line
			(start -0.120396 0.3048)
			(end -0.120396 0.2794)
			(stroke
				(width 0.1)
				(type default)
			)
			(layer "B.Fab")
		)
		(fp_line
			(start -0.120396 0.2794)
			(end 0.12065 0.2794)
			(stroke
				(width 0.1)
				(type default)
			)
			(layer "B.Fab")
		)
		(fp_line
			(start -0.12065 -0.2794)
			(end -0.12065 -0.3048)
			(stroke
				(width 0.1)
				(type default)
			)
			(layer "B.Fab")
		)
		(fp_line
			(start -0.12065 -0.3048)
			(end -0.67945 -0.3048)
			(stroke
				(width 0.1)
				(type default)
			)
			(layer "B.Fab")
		)
		(fp_line
			(start -0.67945 0.3048)
			(end -0.120396 0.3048)
			(stroke
				(width 0.1)
				(type default)
			)
			(layer "B.Fab")
		)
		(fp_line
			(start -0.67945 -0.3048)
			(end -0.67945 0.3048)
			(stroke
				(width 0.1)
				(type default)
			)
			(layer "B.Fab")
		)
		(pad "1" smd circle
			(at 0.40005 0)
			(size 0 0)
			(layers "B.Cu" "B.Mask" "B.Paste")
			(net "SPI_PEX1_RST_R_N")
		)
		(pad "2" smd circle
			(at -0.40005 0)
			(size 0 0)
			(layers "B.Cu" "B.Mask" "B.Paste")
			(net "GND")
		)
	)
	(footprint ""
		(layer "B.Cu")
		(at 366.872774 -321.84594 -90)
		(property "Reference" "R6540"
			(at 0 0 90)
			(layer "B.SilkS")
			(hide yes)
			(effects
				(font
					(size 1.27 1.27)
				)
				(justify mirror)
			)
		)
		(property "Value" ""
			(at 0 0 90)
			(layer "B.Fab")
			(effects
				(font
					(size 1.27 1.27)
				)
				(justify mirror)
			)
		)
		(duplicate_pad_numbers_are_jumpers no)
		(fp_line
			(start -0.7874 0.4064)
			(end 0.7874 0.4064)
			(stroke
				(width 0.1524)
				(type default)
			)
			(layer "B.SilkS")
		)
		(fp_line
			(start 0.7874 0.4064)
			(end 0.7874 -0.4064)
			(stroke
				(width 0.1524)
				(type default)
			)
			(layer "B.SilkS")
		)
		(fp_line
			(start -0.7874 -0.4064)
			(end -0.7874 0.4064)
			(stroke
				(width 0.1524)
				(type default)
			)
			(layer "B.SilkS")
		)
		(fp_line
			(start 0.7874 -0.4064)
			(end -0.7874 -0.4064)
			(stroke
				(width 0.1524)
				(type default)
			)
			(layer "B.SilkS")
		)
		(fp_line
			(start -0.67945 0.3048)
			(end -0.120396 0.3048)
			(stroke
				(width 0.1)
				(type default)
			)
			(layer "B.Fab")
		)
		(fp_line
			(start -0.120396 0.3048)
			(end -0.120396 0.2794)
			(stroke
				(width 0.1)
				(type default)
			)
			(layer "B.Fab")
		)
		(fp_line
			(start 0.12065 0.3048)
			(end 0.67945 0.3048)
			(stroke
				(width 0.1)
				(type default)
			)
			(layer "B.Fab")
		)
		(fp_line
			(start 0.67945 0.3048)
			(end 0.67945 -0.305054)
			(stroke
				(width 0.1)
				(type default)
			)
			(layer "B.Fab")
		)
		(fp_line
			(start -0.120396 0.2794)
			(end 0.12065 0.2794)
			(stroke
				(width 0.1)
				(type default)
			)
			(layer "B.Fab")
		)
		(fp_line
			(start 0.12065 0.2794)
			(end 0.12065 0.3048)
			(stroke
				(width 0.1)
				(type default)
			)
			(layer "B.Fab")
		)
		(fp_line
			(start -0.12065 -0.2794)
			(end -0.12065 -0.3048)
			(stroke
				(width 0.1)
				(type default)
			)
			(layer "B.Fab")
		)
		(fp_line
			(start 0.12065 -0.2794)
			(end -0.12065 -0.2794)
			(stroke
				(width 0.1)
				(type default)
			)
			(layer "B.Fab")
		)
		(fp_line
			(start -0.67945 -0.3048)
			(end -0.67945 0.3048)
			(stroke
				(width 0.1)
				(type default)
			)
			(layer "B.Fab")
		)
		(fp_line
			(start -0.12065 -0.3048)
			(end -0.67945 -0.3048)
			(stroke
				(width 0.1)
				(type default)
			)
			(layer "B.Fab")
		)
		(fp_line
			(start 0.12065 -0.305054)
			(end 0.12065 -0.2794)
			(stroke
				(width 0.1)
				(type default)
			)
			(layer "B.Fab")
		)
		(fp_line
			(start 0.67945 -0.305054)
			(end 0.12065 -0.305054)
			(stroke
				(width 0.1)
				(type default)
			)
			(layer "B.Fab")
		)
		(pad "1" smd circle
			(at 0.40005 0 90)
			(size 0 0)
			(layers "B.Cu" "B.Mask" "B.Paste")
			(net "P0V8_SERDES_VDDA_PEX3")
		)
		(pad "2" smd circle
			(at -0.40005 0 90)
			(size 0 0)
			(layers "B.Cu" "B.Mask" "B.Paste")
			(net "P0V8_SERDES_VDDA_PEX3_C5")
		)
	)
	(footprint ""
		(layer "B.Cu")
		(at 187.149994 -298.27474 180)
		(property "Reference" "C3113"
			(at 0 0 0)
			(layer "B.SilkS")
			(hide yes)
			(effects
				(font
					(size 1.27 1.27)
				)
				(justify mirror)
			)
		)
		(property "Value" ""
			(at 0 0 0)
			(layer "B.Fab")
			(effects
				(font
					(size 1.27 1.27)
				)
				(justify mirror)
			)
		)
		(duplicate_pad_numbers_are_jumpers no)
		(fp_line
			(start 0.299974 0.150114)
			(end 0.299974 -0.150114)
			(stroke
				(width 0.1)
				(type default)
			)
			(layer "B.Fab")
		)
		(fp_line
			(start 0.299974 -0.150114)
			(end -0.299974 -0.150114)
			(stroke
				(width 0.1)
				(type default)
			)
			(layer "B.Fab")
		)
		(fp_line
			(start -0.299974 0.150114)
			(end 0.299974 0.150114)
			(stroke
				(width 0.1)
				(type default)
			)
			(layer "B.Fab")
		)
		(fp_line
			(start -0.299974 -0.150114)
			(end -0.299974 0.150114)
			(stroke
				(width 0.1)
				(type default)
			)
			(layer "B.Fab")
		)
		(pad "1" smd rect
			(at 0.2667 0)
			(size 0.3048 0.381)
			(layers "B.Cu" "B.Mask" "B.Paste")
			(net "P1V25_PEX1")
		)
		(pad "2" smd rect
			(at -0.2667 0)
			(size 0.3048 0.381)
			(layers "B.Cu" "B.Mask" "B.Paste")
			(net "GND")
		)
	)
	(footprint ""
		(layer "B.Cu")
		(at 237.304072 -217.104214 -90)
		(property "Reference" "C2023"
			(at 0 0 90)
			(layer "B.SilkS")
			(hide yes)
			(effects
				(font
					(size 1.27 1.27)
				)
				(justify mirror)
			)
		)
		(property "Value" ""
			(at 0 0 90)
			(layer "B.Fab")
			(effects
				(font
					(size 1.27 1.27)
				)
				(justify mirror)
			)
		)
		(duplicate_pad_numbers_are_jumpers no)
		(fp_line
			(start -0.69215 0.2921)
			(end 0.69215 0.2921)
			(stroke
				(width 0.1524)
				(type default)
			)
			(layer "B.SilkS")
		)
		(fp_line
			(start 0.69215 0.2921)
			(end 0.69215 -0.2921)
			(stroke
				(width 0.1524)
				(type default)
			)
			(layer "B.SilkS")
		)
		(fp_line
			(start -0.69215 -0.2921)
			(end -0.69215 0.2921)
			(stroke
				(width 0.1524)
				(type default)
			)
			(layer "B.SilkS")
		)
		(fp_line
			(start 0.69215 -0.2921)
			(end -0.69215 -0.2921)
			(stroke
				(width 0.1524)
				(type default)
			)
			(layer "B.SilkS")
		)
		(fp_line
			(start -0.51435 0.2794)
			(end 0.51435 0.2794)
			(stroke
				(width 0.1)
				(type default)
			)
			(layer "B.Fab")
		)
		(fp_line
			(start 0.51435 0.2794)
			(end 0.51435 -0.2794)
			(stroke
				(width 0.1)
				(type default)
			)
			(layer "B.Fab")
		)
		(fp_line
			(start -0.51435 -0.2794)
			(end -0.51435 0.2794)
			(stroke
				(width 0.1)
				(type default)
			)
			(layer "B.Fab")
		)
		(fp_line
			(start 0.51435 -0.2794)
			(end -0.51435 -0.2794)
			(stroke
				(width 0.1)
				(type default)
			)
			(layer "B.Fab")
		)
		(pad "1" smd circle
			(at 0.40005 0 90)
			(size 0 0)
			(layers "B.Cu" "B.Mask" "B.Paste")
			(net "P1V2_BIC_PLL")
		)
		(pad "2" smd circle
			(at -0.40005 0 90)
			(size 0 0)
			(layers "B.Cu" "B.Mask" "B.Paste")
			(net "GND")
		)
		(zone
			(layer "B.Cu")
			(hatch none 0.5)
			(connect_pads
				(clearance 0)
			)
			(min_thickness 0.25)
			(keepout
				(tracks not_allowed)
				(vias allowed)
				(pads allowed)
				(copperpour not_allowed)
				(footprints allowed)
			)
			(placement
				(enabled no)
				(sheetname "")
			)
			(fill
				(thermal_gap 0.5)
				(thermal_bridge_width 0.5)
				(island_removal_mode 0)
			)
			(polygon
				(pts
					(xy 237.216442 -216.913714) (xy 237.158276 -217.005154) (xy 237.158276 -217.204544) (xy 237.216442 -217.294714)
					(xy 237.391702 -217.294714) (xy 237.450122 -217.204544) (xy 237.450122 -217.005154) (xy 237.391956 -216.913714)
				)
			)
		)
	)
	(footprint ""
		(layer "B.Cu")
		(at 419.349936 -297.32478 180)
		(property "Reference" "C3440"
			(at 0 0 0)
			(layer "B.SilkS")
			(hide yes)
			(effects
				(font
					(size 1.27 1.27)
				)
				(justify mirror)
			)
		)
		(property "Value" ""
			(at 0 0 0)
			(layer "B.Fab")
			(effects
				(font
					(size 1.27 1.27)
				)
				(justify mirror)
			)
		)
		(duplicate_pad_numbers_are_jumpers no)
		(fp_line
			(start 0.299974 0.150114)
			(end 0.299974 -0.150114)
			(stroke
				(width 0.1)
				(type default)
			)
			(layer "B.Fab")
		)
		(fp_line
			(start 0.299974 -0.150114)
			(end -0.299974 -0.150114)
			(stroke
				(width 0.1)
				(type default)
			)
			(layer "B.Fab")
		)
		(fp_line
			(start -0.299974 0.150114)
			(end 0.299974 0.150114)
			(stroke
				(width 0.1)
				(type default)
			)
			(layer "B.Fab")
		)
		(fp_line
			(start -0.299974 -0.150114)
			(end -0.299974 0.150114)
			(stroke
				(width 0.1)
				(type default)
			)
			(layer "B.Fab")
		)
		(pad "1" smd rect
			(at 0.2667 0)
			(size 0.3048 0.381)
			(layers "B.Cu" "B.Mask" "B.Paste")
			(net "P1V25_PEX3")
		)
		(pad "2" smd rect
			(at -0.2667 0)
			(size 0.3048 0.381)
			(layers "B.Cu" "B.Mask" "B.Paste")
			(net "GND")
		)
	)
	(footprint ""
		(layer "B.Cu")
		(at 221.807278 -279.909524 -90)
		(property "Reference" "C4279"
			(at 0 0 90)
			(layer "B.SilkS")
			(hide yes)
			(effects
				(font
					(size 1.27 1.27)
				)
				(justify mirror)
			)
		)
		(property "Value" ""
			(at 0 0 90)
			(layer "B.Fab")
			(effects
				(font
					(size 1.27 1.27)
				)
				(justify mirror)
			)
		)
		(duplicate_pad_numbers_are_jumpers no)
		(fp_line
			(start -0.299974 0.150114)
			(end 0.299974 0.150114)
			(stroke
				(width 0.1)
				(type default)
			)
			(layer "B.Fab")
		)
		(fp_line
			(start 0.299974 0.150114)
			(end 0.299974 -0.150114)
			(stroke
				(width 0.1)
				(type default)
			)
			(layer "B.Fab")
		)
		(fp_line
			(start -0.299974 -0.150114)
			(end -0.299974 0.150114)
			(stroke
				(width 0.1)
				(type default)
			)
			(layer "B.Fab")
		)
		(fp_line
			(start 0.299974 -0.150114)
			(end -0.299974 -0.150114)
			(stroke
				(width 0.1)
				(type default)
			)
			(layer "B.Fab")
		)
		(pad "1" smd rect
			(at 0.2667 0 90)
			(size 0.3048 0.381)
			(layers "B.Cu" "B.Mask" "B.Paste")
			(net "P1V25_PEX1")
		)
		(pad "2" smd rect
			(at -0.2667 0 90)
			(size 0.3048 0.381)
			(layers "B.Cu" "B.Mask" "B.Paste")
			(net "GND")
		)
	)
	(footprint ""
		(layer "B.Cu")
		(at 345.321382 -284.796738 -90)
		(property "Reference" "PC143"
			(at 0 0 90)
			(layer "B.SilkS")
			(hide yes)
			(effects
				(font
					(size 1.27 1.27)
				)
				(justify mirror)
			)
		)
		(property "Value" ""
			(at 0 0 90)
			(layer "B.Fab")
			(effects
				(font
					(size 1.27 1.27)
				)
				(justify mirror)
			)
		)
		(duplicate_pad_numbers_are_jumpers no)
		(fp_line
			(start -1.524 0.762)
			(end 1.524 0.762)
			(stroke
				(width 0.1524)
				(type default)
			)
			(layer "B.SilkS")
		)
		(fp_line
			(start 1.524 0.762)
			(end 1.524 -0.762)
			(stroke
				(width 0.1524)
				(type default)
			)
			(layer "B.SilkS")
		)
		(fp_line
			(start -1.524 -0.762)
			(end -1.524 0.762)
			(stroke
				(width 0.1524)
				(type default)
			)
			(layer "B.SilkS")
		)
		(fp_line
			(start 1.524 -0.762)
			(end -1.524 -0.762)
			(stroke
				(width 0.1524)
				(type default)
			)
			(layer "B.SilkS")
		)
		(fp_line
			(start -1.1049 0.724916)
			(end -1.1049 -0.724916)
			(stroke
				(width 0.1)
				(type default)
			)
			(layer "B.Fab")
		)
		(fp_line
			(start 1.1049 0.724916)
			(end -1.1049 0.724916)
			(stroke
				(width 0.1)
				(type default)
			)
			(layer "B.Fab")
		)
		(fp_line
			(start -1.1049 -0.724916)
			(end 1.1049 -0.724916)
			(stroke
				(width 0.1)
				(type default)
			)
			(layer "B.Fab")
		)
		(fp_line
			(start 1.1049 -0.724916)
			(end 1.1049 0.724916)
			(stroke
				(width 0.1)
				(type default)
			)
			(layer "B.Fab")
		)
		(pad "1" smd rect
			(at 0.889 0 270)
			(size 1.016 1.27)
			(layers "B.Cu" "B.Mask" "B.Paste")
			(net "SW_P12V_P0V8_PEX2_FLT")
		)
		(pad "2" smd rect
			(at -0.889 0 270)
			(size 1.016 1.27)
			(layers "B.Cu" "B.Mask" "B.Paste")
			(net "GND")
		)
	)
	(footprint ""
		(layer "B.Cu")
		(at 358.22001 -252.186694 180)
		(property "Reference" "R6716"
			(at 0 0 0)
			(layer "B.SilkS")
			(hide yes)
			(effects
				(font
					(size 1.27 1.27)
				)
				(justify mirror)
			)
		)
		(property "Value" ""
			(at 0 0 0)
			(layer "B.Fab")
			(effects
				(font
					(size 1.27 1.27)
				)
				(justify mirror)
			)
		)
		(duplicate_pad_numbers_are_jumpers no)
		(fp_line
			(start 0.7874 0.4064)
			(end 0.7874 -0.4064)
			(stroke
				(width 0.1524)
				(type default)
			)
			(layer "B.SilkS")
		)
		(fp_line
			(start 0.7874 -0.4064)
			(end -0.7874 -0.4064)
			(stroke
				(width 0.1524)
				(type default)
			)
			(layer "B.SilkS")
		)
		(fp_line
			(start -0.7874 0.4064)
			(end 0.7874 0.4064)
			(stroke
				(width 0.1524)
				(type default)
			)
			(layer "B.SilkS")
		)
		(fp_line
			(start -0.7874 -0.4064)
			(end -0.7874 0.4064)
			(stroke
				(width 0.1524)
				(type default)
			)
			(layer "B.SilkS")
		)
		(fp_line
			(start 0.67945 0.3048)
			(end 0.67945 -0.305054)
			(stroke
				(width 0.1)
				(type default)
			)
			(layer "B.Fab")
		)
		(fp_line
			(start 0.67945 -0.305054)
			(end 0.12065 -0.305054)
			(stroke
				(width 0.1)
				(type default)
			)
			(layer "B.Fab")
		)
		(fp_line
			(start 0.12065 0.3048)
			(end 0.67945 0.3048)
			(stroke
				(width 0.1)
				(type default)
			)
			(layer "B.Fab")
		)
		(fp_line
			(start 0.12065 0.2794)
			(end 0.12065 0.3048)
			(stroke
				(width 0.1)
				(type default)
			)
			(layer "B.Fab")
		)
		(fp_line
			(start 0.12065 -0.2794)
			(end -0.12065 -0.2794)
			(stroke
				(width 0.1)
				(type default)
			)
			(layer "B.Fab")
		)
		(fp_line
			(start 0.12065 -0.305054)
			(end 0.12065 -0.2794)
			(stroke
				(width 0.1)
				(type default)
			)
			(layer "B.Fab")
		)
		(fp_line
			(start -0.120396 0.3048)
			(end -0.120396 0.2794)
			(stroke
				(width 0.1)
				(type default)
			)
			(layer "B.Fab")
		)
		(fp_line
			(start -0.120396 0.2794)
			(end 0.12065 0.2794)
			(stroke
				(width 0.1)
				(type default)
			)
			(layer "B.Fab")
		)
		(fp_line
			(start -0.12065 -0.2794)
			(end -0.12065 -0.3048)
			(stroke
				(width 0.1)
				(type default)
			)
			(layer "B.Fab")
		)
		(fp_line
			(start -0.12065 -0.3048)
			(end -0.67945 -0.3048)
			(stroke
				(width 0.1)
				(type default)
			)
			(layer "B.Fab")
		)
		(fp_line
			(start -0.67945 0.3048)
			(end -0.120396 0.3048)
			(stroke
				(width 0.1)
				(type default)
			)
			(layer "B.Fab")
		)
		(fp_line
			(start -0.67945 -0.3048)
			(end -0.67945 0.3048)
			(stroke
				(width 0.1)
				(type default)
			)
			(layer "B.Fab")
		)
		(pad "1" smd circle
			(at 0.40005 0)
			(size 0 0)
			(layers "B.Cu" "B.Mask" "B.Paste")
			(net "SMB_SML1_PMBUS_HSC_SCL")
		)
		(pad "2" smd circle
			(at -0.40005 0)
			(size 0 0)
			(layers "B.Cu" "B.Mask" "B.Paste")
			(net "SMB_BIC_I2C6_MUX_VR_R_SCL")
		)
	)
	(footprint ""
		(layer "B.Cu")
		(at 279.974802 -298.00804 90)
		(property "Reference" "C3417"
			(at 0 0 90)
			(layer "B.SilkS")
			(hide yes)
			(effects
				(font
					(size 1.27 1.27)
				)
				(justify mirror)
			)
		)
		(property "Value" ""
			(at 0 0 90)
			(layer "B.Fab")
			(effects
				(font
					(size 1.27 1.27)
				)
				(justify mirror)
			)
		)
		(duplicate_pad_numbers_are_jumpers no)
		(fp_line
			(start 0.299974 -0.150114)
			(end -0.299974 -0.150114)
			(stroke
				(width 0.1)
				(type default)
			)
			(layer "B.Fab")
		)
		(fp_line
			(start -0.299974 -0.150114)
			(end -0.299974 0.150114)
			(stroke
				(width 0.1)
				(type default)
			)
			(layer "B.Fab")
		)
		(fp_line
			(start 0.299974 0.150114)
			(end 0.299974 -0.150114)
			(stroke
				(width 0.1)
				(type default)
			)
			(layer "B.Fab")
		)
		(fp_line
			(start -0.299974 0.150114)
			(end 0.299974 0.150114)
			(stroke
				(width 0.1)
				(type default)
			)
			(layer "B.Fab")
		)
		(pad "1" smd rect
			(at 0.2667 0 270)
			(size 0.3048 0.381)
			(layers "B.Cu" "B.Mask" "B.Paste")
			(net "SYSPLL_VDDA18_PEX2")
		)
		(pad "2" smd rect
			(at -0.2667 0 270)
			(size 0.3048 0.381)
			(layers "B.Cu" "B.Mask" "B.Paste")
			(net "GND")
		)
	)
	(footprint ""
		(layer "B.Cu")
		(at 354.889562 -313.620404)
		(property "Reference" "L76"
			(at 0 0 0)
			(layer "B.SilkS")
			(hide yes)
			(effects
				(font
					(size 1.27 1.27)
				)
				(justify mirror)
			)
		)
		(property "Value" ""
			(at 0 0 0)
			(layer "B.Fab")
			(effects
				(font
					(size 1.27 1.27)
				)
				(justify mirror)
			)
		)
		(duplicate_pad_numbers_are_jumpers no)
		(fp_line
			(start -2.248154 -4.9911)
			(end 2.248154 -4.9911)
			(stroke
				(width 0.1524)
				(type default)
			)
			(layer "B.SilkS")
		)
		(fp_line
			(start -2.248154 -1.954276)
			(end -2.248154 -4.9911)
			(stroke
				(width 0.1524)
				(type default)
			)
			(layer "B.SilkS")
		)
		(fp_line
			(start -2.248154 4.9911)
			(end -2.248154 1.986534)
			(stroke
				(width 0.1524)
				(type default)
			)
			(layer "B.SilkS")
		)
		(fp_line
			(start 2.248154 -4.9911)
			(end 2.248154 -1.954276)
			(stroke
				(width 0.1524)
				(type default)
			)
			(layer "B.SilkS")
		)
		(fp_line
			(start 2.248154 1.986534)
			(end 2.248154 4.9911)
			(stroke
				(width 0.1524)
				(type default)
			)
			(layer "B.SilkS")
		)
		(fp_line
			(start 2.248154 4.9911)
			(end -2.248154 4.9911)
			(stroke
				(width 0.1524)
				(type default)
			)
			(layer "B.SilkS")
		)
		(fp_line
			(start -1.700022 -0.899922)
			(end 1.700022 -0.899922)
			(stroke
				(width 0.1)
				(type default)
			)
			(layer "B.Fab")
		)
		(fp_line
			(start -1.700022 0.899922)
			(end -1.700022 -0.899922)
			(stroke
				(width 0.1)
				(type default)
			)
			(layer "B.Fab")
		)
		(fp_line
			(start 1.700022 -0.899922)
			(end 1.700022 0.899922)
			(stroke
				(width 0.1)
				(type default)
			)
			(layer "B.Fab")
		)
		(fp_line
			(start 1.700022 0.899922)
			(end -1.700022 0.899922)
			(stroke
				(width 0.1)
				(type default)
			)
			(layer "B.Fab")
		)
		(pad "1" smd rect
			(at 1.575054 0 180)
			(size 1.1684 9.8044)
			(layers "B.Cu" "B.Mask" "B.Paste")
			(net "P0V8_PEX3")
		)
		(pad "2" smd rect
			(at -1.575054 0 180)
			(size 1.1684 9.8044)
			(layers "B.Cu" "B.Mask" "B.Paste")
			(net "P0V8_SERDES_VDDA_PEX3")
		)
	)
	(footprint ""
		(layer "B.Cu")
		(at 125.704854 -321.813174 -90)
		(property "Reference" "R6475"
			(at 0 0 90)
			(layer "B.SilkS")
			(hide yes)
			(effects
				(font
					(size 1.27 1.27)
				)
				(justify mirror)
			)
		)
		(property "Value" ""
			(at 0 0 90)
			(layer "B.Fab")
			(effects
				(font
					(size 1.27 1.27)
				)
				(justify mirror)
			)
		)
		(duplicate_pad_numbers_are_jumpers no)
		(fp_line
			(start -0.7874 0.4064)
			(end 0.7874 0.4064)
			(stroke
				(width 0.1524)
				(type default)
			)
			(layer "B.SilkS")
		)
		(fp_line
			(start 0.7874 0.4064)
			(end 0.7874 -0.4064)
			(stroke
				(width 0.1524)
				(type default)
			)
			(layer "B.SilkS")
		)
		(fp_line
			(start -0.7874 -0.4064)
			(end -0.7874 0.4064)
			(stroke
				(width 0.1524)
				(type default)
			)
			(layer "B.SilkS")
		)
		(fp_line
			(start 0.7874 -0.4064)
			(end -0.7874 -0.4064)
			(stroke
				(width 0.1524)
				(type default)
			)
			(layer "B.SilkS")
		)
		(fp_line
			(start -0.67945 0.3048)
			(end -0.120396 0.3048)
			(stroke
				(width 0.1)
				(type default)
			)
			(layer "B.Fab")
		)
		(fp_line
			(start -0.120396 0.3048)
			(end -0.120396 0.2794)
			(stroke
				(width 0.1)
				(type default)
			)
			(layer "B.Fab")
		)
		(fp_line
			(start 0.12065 0.3048)
			(end 0.67945 0.3048)
			(stroke
				(width 0.1)
				(type default)
			)
			(layer "B.Fab")
		)
		(fp_line
			(start 0.67945 0.3048)
			(end 0.67945 -0.305054)
			(stroke
				(width 0.1)
				(type default)
			)
			(layer "B.Fab")
		)
		(fp_line
			(start -0.120396 0.2794)
			(end 0.12065 0.2794)
			(stroke
				(width 0.1)
				(type default)
			)
			(layer "B.Fab")
		)
		(fp_line
			(start 0.12065 0.2794)
			(end 0.12065 0.3048)
			(stroke
				(width 0.1)
				(type default)
			)
			(layer "B.Fab")
		)
		(fp_line
			(start -0.12065 -0.2794)
			(end -0.12065 -0.3048)
			(stroke
				(width 0.1)
				(type default)
			)
			(layer "B.Fab")
		)
		(fp_line
			(start 0.12065 -0.2794)
			(end -0.12065 -0.2794)
			(stroke
				(width 0.1)
				(type default)
			)
			(layer "B.Fab")
		)
		(fp_line
			(start -0.67945 -0.3048)
			(end -0.67945 0.3048)
			(stroke
				(width 0.1)
				(type default)
			)
			(layer "B.Fab")
		)
		(fp_line
			(start -0.12065 -0.3048)
			(end -0.67945 -0.3048)
			(stroke
				(width 0.1)
				(type default)
			)
			(layer "B.Fab")
		)
		(fp_line
			(start 0.12065 -0.305054)
			(end 0.12065 -0.2794)
			(stroke
				(width 0.1)
				(type default)
			)
			(layer "B.Fab")
		)
		(fp_line
			(start 0.67945 -0.305054)
			(end 0.12065 -0.305054)
			(stroke
				(width 0.1)
				(type default)
			)
			(layer "B.Fab")
		)
		(pad "1" smd circle
			(at 0.40005 0 90)
			(size 0 0)
			(layers "B.Cu" "B.Mask" "B.Paste")
			(net "P0V8_SERDES_VDDA_PEX1")
		)
		(pad "2" smd circle
			(at -0.40005 0 90)
			(size 0 0)
			(layers "B.Cu" "B.Mask" "B.Paste")
			(net "P0V8_SERDES_VDDA_PEX1_C0")
		)
	)
	(footprint ""
		(layer "B.Cu")
		(at 189.049914 -297.79976 180)
		(property "Reference" "C3123"
			(at 0 0 0)
			(layer "B.SilkS")
			(hide yes)
			(effects
				(font
					(size 1.27 1.27)
				)
				(justify mirror)
			)
		)
		(property "Value" ""
			(at 0 0 0)
			(layer "B.Fab")
			(effects
				(font
					(size 1.27 1.27)
				)
				(justify mirror)
			)
		)
		(duplicate_pad_numbers_are_jumpers no)
		(fp_line
			(start 0.299974 0.150114)
			(end 0.299974 -0.150114)
			(stroke
				(width 0.1)
				(type default)
			)
			(layer "B.Fab")
		)
		(fp_line
			(start 0.299974 -0.150114)
			(end -0.299974 -0.150114)
			(stroke
				(width 0.1)
				(type default)
			)
			(layer "B.Fab")
		)
		(fp_line
			(start -0.299974 0.150114)
			(end 0.299974 0.150114)
			(stroke
				(width 0.1)
				(type default)
			)
			(layer "B.Fab")
		)
		(fp_line
			(start -0.299974 -0.150114)
			(end -0.299974 0.150114)
			(stroke
				(width 0.1)
				(type default)
			)
			(layer "B.Fab")
		)
		(pad "1" smd rect
			(at 0.2667 0)
			(size 0.3048 0.381)
			(layers "B.Cu" "B.Mask" "B.Paste")
			(net "P1V25_SERDES_VDDPLL_PEX1")
		)
		(pad "2" smd rect
			(at -0.2667 0)
			(size 0.3048 0.381)
			(layers "B.Cu" "B.Mask" "B.Paste")
			(net "GND")
		)
	)
	(footprint ""
		(layer "B.Cu")
		(at 74.026776 -301.124874 -90)
		(property "Reference" "R1244"
			(at 0 0 90)
			(layer "B.SilkS")
			(hide yes)
			(effects
				(font
					(size 1.27 1.27)
				)
				(justify mirror)
			)
		)
		(property "Value" ""
			(at 0 0 90)
			(layer "B.Fab")
			(effects
				(font
					(size 1.27 1.27)
				)
				(justify mirror)
			)
		)
		(duplicate_pad_numbers_are_jumpers no)
		(fp_line
			(start -0.7874 0.4064)
			(end 0.7874 0.4064)
			(stroke
				(width 0.1524)
				(type default)
			)
			(layer "B.SilkS")
		)
		(fp_line
			(start 0.7874 0.4064)
			(end 0.7874 -0.4064)
			(stroke
				(width 0.1524)
				(type default)
			)
			(layer "B.SilkS")
		)
		(fp_line
			(start -0.7874 -0.4064)
			(end -0.7874 0.4064)
			(stroke
				(width 0.1524)
				(type default)
			)
			(layer "B.SilkS")
		)
		(fp_line
			(start 0.7874 -0.4064)
			(end -0.7874 -0.4064)
			(stroke
				(width 0.1524)
				(type default)
			)
			(layer "B.SilkS")
		)
		(fp_line
			(start -0.67945 0.3048)
			(end -0.120396 0.3048)
			(stroke
				(width 0.1)
				(type default)
			)
			(layer "B.Fab")
		)
		(fp_line
			(start -0.120396 0.3048)
			(end -0.120396 0.2794)
			(stroke
				(width 0.1)
				(type default)
			)
			(layer "B.Fab")
		)
		(fp_line
			(start 0.12065 0.3048)
			(end 0.67945 0.3048)
			(stroke
				(width 0.1)
				(type default)
			)
			(layer "B.Fab")
		)
		(fp_line
			(start 0.67945 0.3048)
			(end 0.67945 -0.305054)
			(stroke
				(width 0.1)
				(type default)
			)
			(layer "B.Fab")
		)
		(fp_line
			(start -0.120396 0.2794)
			(end 0.12065 0.2794)
			(stroke
				(width 0.1)
				(type default)
			)
			(layer "B.Fab")
		)
		(fp_line
			(start 0.12065 0.2794)
			(end 0.12065 0.3048)
			(stroke
				(width 0.1)
				(type default)
			)
			(layer "B.Fab")
		)
		(fp_line
			(start -0.12065 -0.2794)
			(end -0.12065 -0.3048)
			(stroke
				(width 0.1)
				(type default)
			)
			(layer "B.Fab")
		)
		(fp_line
			(start 0.12065 -0.2794)
			(end -0.12065 -0.2794)
			(stroke
				(width 0.1)
				(type default)
			)
			(layer "B.Fab")
		)
		(fp_line
			(start -0.67945 -0.3048)
			(end -0.67945 0.3048)
			(stroke
				(width 0.1)
				(type default)
			)
			(layer "B.Fab")
		)
		(fp_line
			(start -0.12065 -0.3048)
			(end -0.67945 -0.3048)
			(stroke
				(width 0.1)
				(type default)
			)
			(layer "B.Fab")
		)
		(fp_line
			(start 0.12065 -0.305054)
			(end 0.12065 -0.2794)
			(stroke
				(width 0.1)
				(type default)
			)
			(layer "B.Fab")
		)
		(fp_line
			(start 0.67945 -0.305054)
			(end 0.12065 -0.305054)
			(stroke
				(width 0.1)
				(type default)
			)
			(layer "B.Fab")
		)
		(pad "1" smd circle
			(at 0.40005 0 90)
			(size 0 0)
			(layers "B.Cu" "B.Mask" "B.Paste")
			(net "PEX0_ADCTEMP_VINP0")
		)
		(pad "2" smd circle
			(at -0.40005 0 90)
			(size 0 0)
			(layers "B.Cu" "B.Mask" "B.Paste")
			(net "GND")
		)
	)
	(footprint ""
		(layer "B.Cu")
		(at 292.351206 -305.399948 -90)
		(property "Reference" "C3315"
			(at 0 0 90)
			(layer "B.SilkS")
			(hide yes)
			(effects
				(font
					(size 1.27 1.27)
				)
				(justify mirror)
			)
		)
		(property "Value" ""
			(at 0 0 90)
			(layer "B.Fab")
			(effects
				(font
					(size 1.27 1.27)
				)
				(justify mirror)
			)
		)
		(duplicate_pad_numbers_are_jumpers no)
		(fp_line
			(start -0.299974 0.150114)
			(end 0.299974 0.150114)
			(stroke
				(width 0.1)
				(type default)
			)
			(layer "B.Fab")
		)
		(fp_line
			(start 0.299974 0.150114)
			(end 0.299974 -0.150114)
			(stroke
				(width 0.1)
				(type default)
			)
			(layer "B.Fab")
		)
		(fp_line
			(start -0.299974 -0.150114)
			(end -0.299974 0.150114)
			(stroke
				(width 0.1)
				(type default)
			)
			(layer "B.Fab")
		)
		(fp_line
			(start 0.299974 -0.150114)
			(end -0.299974 -0.150114)
			(stroke
				(width 0.1)
				(type default)
			)
			(layer "B.Fab")
		)
		(pad "1" smd rect
			(at 0.2667 0 90)
			(size 0.3048 0.381)
			(layers "B.Cu" "B.Mask" "B.Paste")
			(net "P1V25_SERDES_VDDPLL_PEX2")
		)
		(pad "2" smd rect
			(at -0.2667 0 90)
			(size 0.3048 0.381)
			(layers "B.Cu" "B.Mask" "B.Paste")
			(net "GND")
		)
	)
	(footprint ""
		(layer "B.Cu")
		(at 341.975948 -323.15531 -90)
		(property "Reference" "R6509"
			(at 0 0 90)
			(layer "B.SilkS")
			(hide yes)
			(effects
				(font
					(size 1.27 1.27)
				)
				(justify mirror)
			)
		)
		(property "Value" ""
			(at 0 0 90)
			(layer "B.Fab")
			(effects
				(font
					(size 1.27 1.27)
				)
				(justify mirror)
			)
		)
		(duplicate_pad_numbers_are_jumpers no)
		(fp_line
			(start -0.7874 0.4064)
			(end 0.7874 0.4064)
			(stroke
				(width 0.1524)
				(type default)
			)
			(layer "B.SilkS")
		)
		(fp_line
			(start 0.7874 0.4064)
			(end 0.7874 -0.4064)
			(stroke
				(width 0.1524)
				(type default)
			)
			(layer "B.SilkS")
		)
		(fp_line
			(start -0.7874 -0.4064)
			(end -0.7874 0.4064)
			(stroke
				(width 0.1524)
				(type default)
			)
			(layer "B.SilkS")
		)
		(fp_line
			(start 0.7874 -0.4064)
			(end -0.7874 -0.4064)
			(stroke
				(width 0.1524)
				(type default)
			)
			(layer "B.SilkS")
		)
		(fp_line
			(start -0.67945 0.3048)
			(end -0.120396 0.3048)
			(stroke
				(width 0.1)
				(type default)
			)
			(layer "B.Fab")
		)
		(fp_line
			(start -0.120396 0.3048)
			(end -0.120396 0.2794)
			(stroke
				(width 0.1)
				(type default)
			)
			(layer "B.Fab")
		)
		(fp_line
			(start 0.12065 0.3048)
			(end 0.67945 0.3048)
			(stroke
				(width 0.1)
				(type default)
			)
			(layer "B.Fab")
		)
		(fp_line
			(start 0.67945 0.3048)
			(end 0.67945 -0.305054)
			(stroke
				(width 0.1)
				(type default)
			)
			(layer "B.Fab")
		)
		(fp_line
			(start -0.120396 0.2794)
			(end 0.12065 0.2794)
			(stroke
				(width 0.1)
				(type default)
			)
			(layer "B.Fab")
		)
		(fp_line
			(start 0.12065 0.2794)
			(end 0.12065 0.3048)
			(stroke
				(width 0.1)
				(type default)
			)
			(layer "B.Fab")
		)
		(fp_line
			(start -0.12065 -0.2794)
			(end -0.12065 -0.3048)
			(stroke
				(width 0.1)
				(type default)
			)
			(layer "B.Fab")
		)
		(fp_line
			(start 0.12065 -0.2794)
			(end -0.12065 -0.2794)
			(stroke
				(width 0.1)
				(type default)
			)
			(layer "B.Fab")
		)
		(fp_line
			(start -0.67945 -0.3048)
			(end -0.67945 0.3048)
			(stroke
				(width 0.1)
				(type default)
			)
			(layer "B.Fab")
		)
		(fp_line
			(start -0.12065 -0.3048)
			(end -0.67945 -0.3048)
			(stroke
				(width 0.1)
				(type default)
			)
			(layer "B.Fab")
		)
		(fp_line
			(start 0.12065 -0.305054)
			(end 0.12065 -0.2794)
			(stroke
				(width 0.1)
				(type default)
			)
			(layer "B.Fab")
		)
		(fp_line
			(start 0.67945 -0.305054)
			(end 0.12065 -0.305054)
			(stroke
				(width 0.1)
				(type default)
			)
			(layer "B.Fab")
		)
		(pad "1" smd circle
			(at 0.40005 0 90)
			(size 0 0)
			(layers "B.Cu" "B.Mask" "B.Paste")
			(net "P0V8_SERDES_VDDA_PEX2")
		)
		(pad "2" smd circle
			(at -0.40005 0 90)
			(size 0 0)
			(layers "B.Cu" "B.Mask" "B.Paste")
			(net "P0V8_SERDES_VDDA_PEX2_C4")
		)
	)
	(footprint ""
		(layer "B.Cu")
		(at 309.741824 -98.021648 180)
		(property "Reference" "R268"
			(at 0 0 0)
			(layer "B.SilkS")
			(hide yes)
			(effects
				(font
					(size 1.27 1.27)
				)
				(justify mirror)
			)
		)
		(property "Value" ""
			(at 0 0 0)
			(layer "B.Fab")
			(effects
				(font
					(size 1.27 1.27)
				)
				(justify mirror)
			)
		)
		(duplicate_pad_numbers_are_jumpers no)
		(fp_line
			(start 0.7874 0.4064)
			(end 0.7874 -0.4064)
			(stroke
				(width 0.1524)
				(type default)
			)
			(layer "B.SilkS")
		)
		(fp_line
			(start 0.7874 -0.4064)
			(end -0.7874 -0.4064)
			(stroke
				(width 0.1524)
				(type default)
			)
			(layer "B.SilkS")
		)
		(fp_line
			(start -0.7874 0.4064)
			(end 0.7874 0.4064)
			(stroke
				(width 0.1524)
				(type default)
			)
			(layer "B.SilkS")
		)
		(fp_line
			(start -0.7874 -0.4064)
			(end -0.7874 0.4064)
			(stroke
				(width 0.1524)
				(type default)
			)
			(layer "B.SilkS")
		)
		(fp_line
			(start 0.67945 0.3048)
			(end 0.67945 -0.305054)
			(stroke
				(width 0.1)
				(type default)
			)
			(layer "B.Fab")
		)
		(fp_line
			(start 0.67945 -0.305054)
			(end 0.12065 -0.305054)
			(stroke
				(width 0.1)
				(type default)
			)
			(layer "B.Fab")
		)
		(fp_line
			(start 0.12065 0.3048)
			(end 0.67945 0.3048)
			(stroke
				(width 0.1)
				(type default)
			)
			(layer "B.Fab")
		)
		(fp_line
			(start 0.12065 0.2794)
			(end 0.12065 0.3048)
			(stroke
				(width 0.1)
				(type default)
			)
			(layer "B.Fab")
		)
		(fp_line
			(start 0.12065 -0.2794)
			(end -0.12065 -0.2794)
			(stroke
				(width 0.1)
				(type default)
			)
			(layer "B.Fab")
		)
		(fp_line
			(start 0.12065 -0.305054)
			(end 0.12065 -0.2794)
			(stroke
				(width 0.1)
				(type default)
			)
			(layer "B.Fab")
		)
		(fp_line
			(start -0.120396 0.3048)
			(end -0.120396 0.2794)
			(stroke
				(width 0.1)
				(type default)
			)
			(layer "B.Fab")
		)
		(fp_line
			(start -0.120396 0.2794)
			(end 0.12065 0.2794)
			(stroke
				(width 0.1)
				(type default)
			)
			(layer "B.Fab")
		)
		(fp_line
			(start -0.12065 -0.2794)
			(end -0.12065 -0.3048)
			(stroke
				(width 0.1)
				(type default)
			)
			(layer "B.Fab")
		)
		(fp_line
			(start -0.12065 -0.3048)
			(end -0.67945 -0.3048)
			(stroke
				(width 0.1)
				(type default)
			)
			(layer "B.Fab")
		)
		(fp_line
			(start -0.67945 0.3048)
			(end -0.120396 0.3048)
			(stroke
				(width 0.1)
				(type default)
			)
			(layer "B.Fab")
		)
		(fp_line
			(start -0.67945 -0.3048)
			(end -0.67945 0.3048)
			(stroke
				(width 0.1)
				(type default)
			)
			(layer "B.Fab")
		)
		(pad "1" smd circle
			(at 0.40005 0)
			(size 0 0)
			(layers "B.Cu" "B.Mask" "B.Paste")
			(net "NIC5_DATA_OUT")
		)
		(pad "2" smd circle
			(at -0.40005 0)
			(size 0 0)
			(layers "B.Cu" "B.Mask" "B.Paste")
			(net "GND")
		)
	)
	(footprint ""
		(layer "B.Cu")
		(at 353.842574 -260.509258 90)
		(property "Reference" "PR7139"
			(at 0 0 90)
			(layer "B.SilkS")
			(hide yes)
			(effects
				(font
					(size 1.27 1.27)
				)
				(justify mirror)
			)
		)
		(property "Value" ""
			(at 0 0 90)
			(layer "B.Fab")
			(effects
				(font
					(size 1.27 1.27)
				)
				(justify mirror)
			)
		)
		(duplicate_pad_numbers_are_jumpers no)
		(fp_line
			(start 0.7874 -0.4064)
			(end -0.7874 -0.4064)
			(stroke
				(width 0.1524)
				(type default)
			)
			(layer "B.SilkS")
		)
		(fp_line
			(start -0.7874 -0.4064)
			(end -0.7874 0.4064)
			(stroke
				(width 0.1524)
				(type default)
			)
			(layer "B.SilkS")
		)
		(fp_line
			(start 0.7874 0.4064)
			(end 0.7874 -0.4064)
			(stroke
				(width 0.1524)
				(type default)
			)
			(layer "B.SilkS")
		)
		(fp_line
			(start -0.7874 0.4064)
			(end 0.7874 0.4064)
			(stroke
				(width 0.1524)
				(type default)
			)
			(layer "B.SilkS")
		)
		(fp_line
			(start 0.67945 -0.305054)
			(end 0.12065 -0.305054)
			(stroke
				(width 0.1)
				(type default)
			)
			(layer "B.Fab")
		)
		(fp_line
			(start 0.12065 -0.305054)
			(end 0.12065 -0.2794)
			(stroke
				(width 0.1)
				(type default)
			)
			(layer "B.Fab")
		)
		(fp_line
			(start -0.12065 -0.3048)
			(end -0.67945 -0.3048)
			(stroke
				(width 0.1)
				(type default)
			)
			(layer "B.Fab")
		)
		(fp_line
			(start -0.67945 -0.3048)
			(end -0.67945 0.3048)
			(stroke
				(width 0.1)
				(type default)
			)
			(layer "B.Fab")
		)
		(fp_line
			(start 0.12065 -0.2794)
			(end -0.12065 -0.2794)
			(stroke
				(width 0.1)
				(type default)
			)
			(layer "B.Fab")
		)
		(fp_line
			(start -0.12065 -0.2794)
			(end -0.12065 -0.3048)
			(stroke
				(width 0.1)
				(type default)
			)
			(layer "B.Fab")
		)
		(fp_line
			(start 0.12065 0.2794)
			(end 0.12065 0.3048)
			(stroke
				(width 0.1)
				(type default)
			)
			(layer "B.Fab")
		)
		(fp_line
			(start -0.120396 0.2794)
			(end 0.12065 0.2794)
			(stroke
				(width 0.1)
				(type default)
			)
			(layer "B.Fab")
		)
		(fp_line
			(start 0.67945 0.3048)
			(end 0.67945 -0.305054)
			(stroke
				(width 0.1)
				(type default)
			)
			(layer "B.Fab")
		)
		(fp_line
			(start 0.12065 0.3048)
			(end 0.67945 0.3048)
			(stroke
				(width 0.1)
				(type default)
			)
			(layer "B.Fab")
		)
		(fp_line
			(start -0.120396 0.3048)
			(end -0.120396 0.2794)
			(stroke
				(width 0.1)
				(type default)
			)
			(layer "B.Fab")
		)
		(fp_line
			(start -0.67945 0.3048)
			(end -0.120396 0.3048)
			(stroke
				(width 0.1)
				(type default)
			)
			(layer "B.Fab")
		)
		(pad "1" smd circle
			(at 0.40005 0 270)
			(size 0 0)
			(layers "B.Cu" "B.Mask" "B.Paste")
			(net "NC_P0V8_PEX2_ISEN3")
		)
		(pad "2" smd circle
			(at -0.40005 0 270)
			(size 0 0)
			(layers "B.Cu" "B.Mask" "B.Paste")
			(net "GND")
		)
	)
	(footprint ""
		(layer "B.Cu")
		(at 160.549844 -298.74972)
		(property "Reference" "C3182"
			(at 0 0 0)
			(layer "B.SilkS")
			(hide yes)
			(effects
				(font
					(size 1.27 1.27)
				)
				(justify mirror)
			)
		)
		(property "Value" ""
			(at 0 0 0)
			(layer "B.Fab")
			(effects
				(font
					(size 1.27 1.27)
				)
				(justify mirror)
			)
		)
		(duplicate_pad_numbers_are_jumpers no)
		(fp_line
			(start -0.299974 -0.150114)
			(end -0.299974 0.150114)
			(stroke
				(width 0.1)
				(type default)
			)
			(layer "B.Fab")
		)
		(fp_line
			(start -0.299974 0.150114)
			(end 0.299974 0.150114)
			(stroke
				(width 0.1)
				(type default)
			)
			(layer "B.Fab")
		)
		(fp_line
			(start 0.299974 -0.150114)
			(end -0.299974 -0.150114)
			(stroke
				(width 0.1)
				(type default)
			)
			(layer "B.Fab")
		)
		(fp_line
			(start 0.299974 0.150114)
			(end 0.299974 -0.150114)
			(stroke
				(width 0.1)
				(type default)
			)
			(layer "B.Fab")
		)
		(pad "1" smd rect
			(at 0.2667 0 180)
			(size 0.3048 0.381)
			(layers "B.Cu" "B.Mask" "B.Paste")
			(net "P1V8_VDDA_PEX1")
		)
		(pad "2" smd rect
			(at -0.2667 0 180)
			(size 0.3048 0.381)
			(layers "B.Cu" "B.Mask" "B.Paste")
			(net "GND")
		)
	)
	(footprint ""
		(layer "B.Cu")
		(at 44.449746 -299.224954)
		(property "Reference" "C3009"
			(at 0 0 0)
			(layer "B.SilkS")
			(hide yes)
			(effects
				(font
					(size 1.27 1.27)
				)
				(justify mirror)
			)
		)
		(property "Value" ""
			(at 0 0 0)
			(layer "B.Fab")
			(effects
				(font
					(size 1.27 1.27)
				)
				(justify mirror)
			)
		)
		(duplicate_pad_numbers_are_jumpers no)
		(fp_line
			(start -0.299974 -0.150114)
			(end -0.299974 0.150114)
			(stroke
				(width 0.1)
				(type default)
			)
			(layer "B.Fab")
		)
		(fp_line
			(start -0.299974 0.150114)
			(end 0.299974 0.150114)
			(stroke
				(width 0.1)
				(type default)
			)
			(layer "B.Fab")
		)
		(fp_line
			(start 0.299974 -0.150114)
			(end -0.299974 -0.150114)
			(stroke
				(width 0.1)
				(type default)
			)
			(layer "B.Fab")
		)
		(fp_line
			(start 0.299974 0.150114)
			(end 0.299974 -0.150114)
			(stroke
				(width 0.1)
				(type default)
			)
			(layer "B.Fab")
		)
		(pad "1" smd rect
			(at 0.2667 0 180)
			(size 0.3048 0.381)
			(layers "B.Cu" "B.Mask" "B.Paste")
			(net "P1V8_VDDA_PEX0")
		)
		(pad "2" smd rect
			(at -0.2667 0 180)
			(size 0.3048 0.381)
			(layers "B.Cu" "B.Mask" "B.Paste")
			(net "GND")
		)
	)
	(footprint ""
		(layer "B.Cu")
		(at 53.474874 -286.399732 90)
		(property "Reference" "C2971"
			(at 0 0 90)
			(layer "B.SilkS")
			(hide yes)
			(effects
				(font
					(size 1.27 1.27)
				)
				(justify mirror)
			)
		)
		(property "Value" ""
			(at 0 0 90)
			(layer "B.Fab")
			(effects
				(font
					(size 1.27 1.27)
				)
				(justify mirror)
			)
		)
		(duplicate_pad_numbers_are_jumpers no)
		(fp_line
			(start 0.299974 -0.150114)
			(end -0.299974 -0.150114)
			(stroke
				(width 0.1)
				(type default)
			)
			(layer "B.Fab")
		)
		(fp_line
			(start -0.299974 -0.150114)
			(end -0.299974 0.150114)
			(stroke
				(width 0.1)
				(type default)
			)
			(layer "B.Fab")
		)
		(fp_line
			(start 0.299974 0.150114)
			(end 0.299974 -0.150114)
			(stroke
				(width 0.1)
				(type default)
			)
			(layer "B.Fab")
		)
		(fp_line
			(start -0.299974 0.150114)
			(end 0.299974 0.150114)
			(stroke
				(width 0.1)
				(type default)
			)
			(layer "B.Fab")
		)
		(pad "1" smd rect
			(at 0.2667 0 270)
			(size 0.3048 0.381)
			(layers "B.Cu" "B.Mask" "B.Paste")
			(net "P1V25_SERDES_VDDPLL_PEX0")
		)
		(pad "2" smd rect
			(at -0.2667 0 270)
			(size 0.3048 0.381)
			(layers "B.Cu" "B.Mask" "B.Paste")
			(net "GND")
		)
	)
	(footprint ""
		(layer "B.Cu")
		(at 59.649868 -303.499774 -90)
		(property "Reference" "C2906"
			(at 0 0 90)
			(layer "B.SilkS")
			(hide yes)
			(effects
				(font
					(size 1.27 1.27)
				)
				(justify mirror)
			)
		)
		(property "Value" ""
			(at 0 0 90)
			(layer "B.Fab")
			(effects
				(font
					(size 1.27 1.27)
				)
				(justify mirror)
			)
		)
		(duplicate_pad_numbers_are_jumpers no)
		(fp_line
			(start -0.299974 0.150114)
			(end 0.299974 0.150114)
			(stroke
				(width 0.1)
				(type default)
			)
			(layer "B.Fab")
		)
		(fp_line
			(start 0.299974 0.150114)
			(end 0.299974 -0.150114)
			(stroke
				(width 0.1)
				(type default)
			)
			(layer "B.Fab")
		)
		(fp_line
			(start -0.299974 -0.150114)
			(end -0.299974 0.150114)
			(stroke
				(width 0.1)
				(type default)
			)
			(layer "B.Fab")
		)
		(fp_line
			(start 0.299974 -0.150114)
			(end -0.299974 -0.150114)
			(stroke
				(width 0.1)
				(type default)
			)
			(layer "B.Fab")
		)
		(pad "1" smd rect
			(at 0.2667 0 90)
			(size 0.3048 0.381)
			(layers "B.Cu" "B.Mask" "B.Paste")
			(net "P1V25_PEX0")
		)
		(pad "2" smd rect
			(at -0.2667 0 90)
			(size 0.3048 0.381)
			(layers "B.Cu" "B.Mask" "B.Paste")
			(net "GND")
		)
	)
	(footprint ""
		(layer "B.Cu")
		(at 340.648798 -326.945498 -90)
		(property "Reference" "C4327"
			(at 0 0 90)
			(layer "B.SilkS")
			(hide yes)
			(effects
				(font
					(size 1.27 1.27)
				)
				(justify mirror)
			)
		)
		(property "Value" ""
			(at 0 0 90)
			(layer "B.Fab")
			(effects
				(font
					(size 1.27 1.27)
				)
				(justify mirror)
			)
		)
		(duplicate_pad_numbers_are_jumpers no)
		(fp_line
			(start -1.2954 0.5842)
			(end 1.2954 0.5842)
			(stroke
				(width 0.1524)
				(type default)
			)
			(layer "B.SilkS")
		)
		(fp_line
			(start 1.2954 0.5842)
			(end 1.2954 -0.5842)
			(stroke
				(width 0.1524)
				(type default)
			)
			(layer "B.SilkS")
		)
		(fp_line
			(start -1.2954 -0.5842)
			(end -1.2954 0.5842)
			(stroke
				(width 0.1524)
				(type default)
			)
			(layer "B.SilkS")
		)
		(fp_line
			(start 1.2954 -0.5842)
			(end -1.2954 -0.5842)
			(stroke
				(width 0.1524)
				(type default)
			)
			(layer "B.SilkS")
		)
		(fp_line
			(start -0.8636 0.4572)
			(end 0.8636 0.4572)
			(stroke
				(width 0.1)
				(type default)
			)
			(layer "B.Fab")
		)
		(fp_line
			(start 0.8636 0.4572)
			(end 0.8636 0.4064)
			(stroke
				(width 0.1)
				(type default)
			)
			(layer "B.Fab")
		)
		(fp_line
			(start -1.1938 0.4064)
			(end -0.8636 0.4064)
			(stroke
				(width 0.1)
				(type default)
			)
			(layer "B.Fab")
		)
		(fp_line
			(start -0.8636 0.4064)
			(end -0.8636 0.4572)
			(stroke
				(width 0.1)
				(type default)
			)
			(layer "B.Fab")
		)
		(fp_line
			(start 0.8636 0.4064)
			(end 1.1938 0.4064)
			(stroke
				(width 0.1)
				(type default)
			)
			(layer "B.Fab")
		)
		(fp_line
			(start 1.1938 0.4064)
			(end 1.1938 -0.4064)
			(stroke
				(width 0.1)
				(type default)
			)
			(layer "B.Fab")
		)
		(fp_line
			(start -1.1938 -0.4064)
			(end -1.1938 0.4064)
			(stroke
				(width 0.1)
				(type default)
			)
			(layer "B.Fab")
		)
		(fp_line
			(start -0.8636 -0.4064)
			(end -1.1938 -0.4064)
			(stroke
				(width 0.1)
				(type default)
			)
			(layer "B.Fab")
		)
		(fp_line
			(start 0.8636 -0.4064)
			(end 0.8636 -0.4572)
			(stroke
				(width 0.1)
				(type default)
			)
			(layer "B.Fab")
		)
		(fp_line
			(start 1.1938 -0.4064)
			(end 0.8636 -0.4064)
			(stroke
				(width 0.1)
				(type default)
			)
			(layer "B.Fab")
		)
		(fp_line
			(start -0.8636 -0.4572)
			(end -0.8636 -0.4064)
			(stroke
				(width 0.1)
				(type default)
			)
			(layer "B.Fab")
		)
		(fp_line
			(start 0.8636 -0.4572)
			(end -0.8636 -0.4572)
			(stroke
				(width 0.1)
				(type default)
			)
			(layer "B.Fab")
		)
		(pad "1" smd rect
			(at 0.7366 0 180)
			(size 0.7112 0.8128)
			(layers "B.Cu" "B.Mask" "B.Paste")
			(net "P0V8_SERDES_VDDA_PEX2_C9")
		)
		(pad "2" smd rect
			(at -0.7366 0 180)
			(size 0.7112 0.8128)
			(layers "B.Cu" "B.Mask" "B.Paste")
			(net "GND")
		)
	)
	(footprint ""
		(layer "B.Cu")
		(at 412.251398 -305.399948 -90)
		(property "Reference" "C3480"
			(at 0 0 90)
			(layer "B.SilkS")
			(hide yes)
			(effects
				(font
					(size 1.27 1.27)
				)
				(justify mirror)
			)
		)
		(property "Value" ""
			(at 0 0 90)
			(layer "B.Fab")
			(effects
				(font
					(size 1.27 1.27)
				)
				(justify mirror)
			)
		)
		(duplicate_pad_numbers_are_jumpers no)
		(fp_line
			(start -0.299974 0.150114)
			(end 0.299974 0.150114)
			(stroke
				(width 0.1)
				(type default)
			)
			(layer "B.Fab")
		)
		(fp_line
			(start 0.299974 0.150114)
			(end 0.299974 -0.150114)
			(stroke
				(width 0.1)
				(type default)
			)
			(layer "B.Fab")
		)
		(fp_line
			(start -0.299974 -0.150114)
			(end -0.299974 0.150114)
			(stroke
				(width 0.1)
				(type default)
			)
			(layer "B.Fab")
		)
		(fp_line
			(start 0.299974 -0.150114)
			(end -0.299974 -0.150114)
			(stroke
				(width 0.1)
				(type default)
			)
			(layer "B.Fab")
		)
		(pad "1" smd rect
			(at 0.2667 0 90)
			(size 0.3048 0.381)
			(layers "B.Cu" "B.Mask" "B.Paste")
			(net "P1V25_SERDES_VDDPLL_PEX3")
		)
		(pad "2" smd rect
			(at -0.2667 0 90)
			(size 0.3048 0.381)
			(layers "B.Cu" "B.Mask" "B.Paste")
			(net "GND")
		)
	)
	(footprint ""
		(layer "B.Cu")
		(at 46.355 -292.57498)
		(property "Reference" "C3056"
			(at 0 0 0)
			(layer "B.SilkS")
			(hide yes)
			(effects
				(font
					(size 1.27 1.27)
				)
				(justify mirror)
			)
		)
		(property "Value" ""
			(at 0 0 0)
			(layer "B.Fab")
			(effects
				(font
					(size 1.27 1.27)
				)
				(justify mirror)
			)
		)
		(duplicate_pad_numbers_are_jumpers no)
		(fp_line
			(start -0.299974 -0.150114)
			(end -0.299974 0.150114)
			(stroke
				(width 0.1)
				(type default)
			)
			(layer "B.Fab")
		)
		(fp_line
			(start -0.299974 0.150114)
			(end 0.299974 0.150114)
			(stroke
				(width 0.1)
				(type default)
			)
			(layer "B.Fab")
		)
		(fp_line
			(start 0.299974 -0.150114)
			(end -0.299974 -0.150114)
			(stroke
				(width 0.1)
				(type default)
			)
			(layer "B.Fab")
		)
		(fp_line
			(start 0.299974 0.150114)
			(end 0.299974 -0.150114)
			(stroke
				(width 0.1)
				(type default)
			)
			(layer "B.Fab")
		)
		(pad "1" smd rect
			(at 0.2667 0 180)
			(size 0.3048 0.381)
			(layers "B.Cu" "B.Mask" "B.Paste")
			(net "PCEPLL6_VDDA18_PEX0")
		)
		(pad "2" smd rect
			(at -0.2667 0 180)
			(size 0.3048 0.381)
			(layers "B.Cu" "B.Mask" "B.Paste")
			(net "GND")
		)
	)
	(footprint ""
		(layer "B.Cu")
		(at 285.674816 -297.79976 90)
		(property "Reference" "C1620"
			(at 0 0 90)
			(layer "B.SilkS")
			(hide yes)
			(effects
				(font
					(size 1.27 1.27)
				)
				(justify mirror)
			)
		)
		(property "Value" ""
			(at 0 0 90)
			(layer "B.Fab")
			(effects
				(font
					(size 1.27 1.27)
				)
				(justify mirror)
			)
		)
		(duplicate_pad_numbers_are_jumpers no)
		(fp_line
			(start 0.299974 -0.150114)
			(end -0.299974 -0.150114)
			(stroke
				(width 0.1)
				(type default)
			)
			(layer "B.Fab")
		)
		(fp_line
			(start -0.299974 -0.150114)
			(end -0.299974 0.150114)
			(stroke
				(width 0.1)
				(type default)
			)
			(layer "B.Fab")
		)
		(fp_line
			(start 0.299974 0.150114)
			(end 0.299974 -0.150114)
			(stroke
				(width 0.1)
				(type default)
			)
			(layer "B.Fab")
		)
		(fp_line
			(start -0.299974 0.150114)
			(end 0.299974 0.150114)
			(stroke
				(width 0.1)
				(type default)
			)
			(layer "B.Fab")
		)
		(pad "1" smd rect
			(at 0.2667 0 270)
			(size 0.3048 0.381)
			(layers "B.Cu" "B.Mask" "B.Paste")
			(net "P0V8_PEX2")
		)
		(pad "2" smd rect
			(at -0.2667 0 270)
			(size 0.3048 0.381)
			(layers "B.Cu" "B.Mask" "B.Paste")
			(net "GND")
		)
	)
	(footprint ""
		(layer "B.Cu")
		(at 403.199854 -292.099746 90)
		(property "Reference" "C1983"
			(at 0 0 90)
			(layer "B.SilkS")
			(hide yes)
			(effects
				(font
					(size 1.27 1.27)
				)
				(justify mirror)
			)
		)
		(property "Value" ""
			(at 0 0 90)
			(layer "B.Fab")
			(effects
				(font
					(size 1.27 1.27)
				)
				(justify mirror)
			)
		)
		(duplicate_pad_numbers_are_jumpers no)
		(fp_line
			(start 0.299974 -0.150114)
			(end -0.299974 -0.150114)
			(stroke
				(width 0.1)
				(type default)
			)
			(layer "B.Fab")
		)
		(fp_line
			(start -0.299974 -0.150114)
			(end -0.299974 0.150114)
			(stroke
				(width 0.1)
				(type default)
			)
			(layer "B.Fab")
		)
		(fp_line
			(start 0.299974 0.150114)
			(end 0.299974 -0.150114)
			(stroke
				(width 0.1)
				(type default)
			)
			(layer "B.Fab")
		)
		(fp_line
			(start -0.299974 0.150114)
			(end 0.299974 0.150114)
			(stroke
				(width 0.1)
				(type default)
			)
			(layer "B.Fab")
		)
		(pad "1" smd rect
			(at 0.2667 0 270)
			(size 0.3048 0.381)
			(layers "B.Cu" "B.Mask" "B.Paste")
			(net "P0V8_SERDES_VDDA_PEX3")
		)
		(pad "2" smd rect
			(at -0.2667 0 270)
			(size 0.3048 0.381)
			(layers "B.Cu" "B.Mask" "B.Paste")
			(net "GND")
		)
	)
	(footprint ""
		(layer "B.Cu")
		(at 163.874958 -298.00804 90)
		(property "Reference" "C3242"
			(at 0 0 90)
			(layer "B.SilkS")
			(hide yes)
			(effects
				(font
					(size 1.27 1.27)
				)
				(justify mirror)
			)
		)
		(property "Value" ""
			(at 0 0 90)
			(layer "B.Fab")
			(effects
				(font
					(size 1.27 1.27)
				)
				(justify mirror)
			)
		)
		(duplicate_pad_numbers_are_jumpers no)
		(fp_line
			(start 0.299974 -0.150114)
			(end -0.299974 -0.150114)
			(stroke
				(width 0.1)
				(type default)
			)
			(layer "B.Fab")
		)
		(fp_line
			(start -0.299974 -0.150114)
			(end -0.299974 0.150114)
			(stroke
				(width 0.1)
				(type default)
			)
			(layer "B.Fab")
		)
		(fp_line
			(start 0.299974 0.150114)
			(end 0.299974 -0.150114)
			(stroke
				(width 0.1)
				(type default)
			)
			(layer "B.Fab")
		)
		(fp_line
			(start -0.299974 0.150114)
			(end 0.299974 0.150114)
			(stroke
				(width 0.1)
				(type default)
			)
			(layer "B.Fab")
		)
		(pad "1" smd rect
			(at 0.2667 0 270)
			(size 0.3048 0.381)
			(layers "B.Cu" "B.Mask" "B.Paste")
			(net "SYSPLL_VDDA18_PEX1")
		)
		(pad "2" smd rect
			(at -0.2667 0 270)
			(size 0.3048 0.381)
			(layers "B.Cu" "B.Mask" "B.Paste")
			(net "GND")
		)
	)
	(footprint ""
		(layer "B.Cu")
		(at 363.305344 -324.163944 -90)
		(property "Reference" "C4384"
			(at 0 0 90)
			(layer "B.SilkS")
			(hide yes)
			(effects
				(font
					(size 1.27 1.27)
				)
				(justify mirror)
			)
		)
		(property "Value" ""
			(at 0 0 90)
			(layer "B.Fab")
			(effects
				(font
					(size 1.27 1.27)
				)
				(justify mirror)
			)
		)
		(duplicate_pad_numbers_are_jumpers no)
		(fp_line
			(start -1.2954 0.5842)
			(end 1.2954 0.5842)
			(stroke
				(width 0.1524)
				(type default)
			)
			(layer "B.SilkS")
		)
		(fp_line
			(start 1.2954 0.5842)
			(end 1.2954 -0.5842)
			(stroke
				(width 0.1524)
				(type default)
			)
			(layer "B.SilkS")
		)
		(fp_line
			(start -1.2954 -0.5842)
			(end -1.2954 0.5842)
			(stroke
				(width 0.1524)
				(type default)
			)
			(layer "B.SilkS")
		)
		(fp_line
			(start 1.2954 -0.5842)
			(end -1.2954 -0.5842)
			(stroke
				(width 0.1524)
				(type default)
			)
			(layer "B.SilkS")
		)
		(fp_line
			(start -0.8636 0.4572)
			(end 0.8636 0.4572)
			(stroke
				(width 0.1)
				(type default)
			)
			(layer "B.Fab")
		)
		(fp_line
			(start 0.8636 0.4572)
			(end 0.8636 0.4064)
			(stroke
				(width 0.1)
				(type default)
			)
			(layer "B.Fab")
		)
		(fp_line
			(start -1.1938 0.4064)
			(end -0.8636 0.4064)
			(stroke
				(width 0.1)
				(type default)
			)
			(layer "B.Fab")
		)
		(fp_line
			(start -0.8636 0.4064)
			(end -0.8636 0.4572)
			(stroke
				(width 0.1)
				(type default)
			)
			(layer "B.Fab")
		)
		(fp_line
			(start 0.8636 0.4064)
			(end 1.1938 0.4064)
			(stroke
				(width 0.1)
				(type default)
			)
			(layer "B.Fab")
		)
		(fp_line
			(start 1.1938 0.4064)
			(end 1.1938 -0.4064)
			(stroke
				(width 0.1)
				(type default)
			)
			(layer "B.Fab")
		)
		(fp_line
			(start -1.1938 -0.4064)
			(end -1.1938 0.4064)
			(stroke
				(width 0.1)
				(type default)
			)
			(layer "B.Fab")
		)
		(fp_line
			(start -0.8636 -0.4064)
			(end -1.1938 -0.4064)
			(stroke
				(width 0.1)
				(type default)
			)
			(layer "B.Fab")
		)
		(fp_line
			(start 0.8636 -0.4064)
			(end 0.8636 -0.4572)
			(stroke
				(width 0.1)
				(type default)
			)
			(layer "B.Fab")
		)
		(fp_line
			(start 1.1938 -0.4064)
			(end 0.8636 -0.4064)
			(stroke
				(width 0.1)
				(type default)
			)
			(layer "B.Fab")
		)
		(fp_line
			(start -0.8636 -0.4572)
			(end -0.8636 -0.4064)
			(stroke
				(width 0.1)
				(type default)
			)
			(layer "B.Fab")
		)
		(fp_line
			(start 0.8636 -0.4572)
			(end -0.8636 -0.4572)
			(stroke
				(width 0.1)
				(type default)
			)
			(layer "B.Fab")
		)
		(pad "1" smd rect
			(at 0.7366 0 180)
			(size 0.7112 0.8128)
			(layers "B.Cu" "B.Mask" "B.Paste")
			(net "P0V8_SERDES_VDDA_PEX3_C10")
		)
		(pad "2" smd rect
			(at -0.7366 0 180)
			(size 0.7112 0.8128)
			(layers "B.Cu" "B.Mask" "B.Paste")
			(net "GND")
		)
	)
	(footprint ""
		(layer "B.Cu")
		(at 414.599882 -290.199826 90)
		(property "Reference" "C1947"
			(at 0 0 90)
			(layer "B.SilkS")
			(hide yes)
			(effects
				(font
					(size 1.27 1.27)
				)
				(justify mirror)
			)
		)
		(property "Value" ""
			(at 0 0 90)
			(layer "B.Fab")
			(effects
				(font
					(size 1.27 1.27)
				)
				(justify mirror)
			)
		)
		(duplicate_pad_numbers_are_jumpers no)
		(fp_line
			(start 0.299974 -0.150114)
			(end -0.299974 -0.150114)
			(stroke
				(width 0.1)
				(type default)
			)
			(layer "B.Fab")
		)
		(fp_line
			(start -0.299974 -0.150114)
			(end -0.299974 0.150114)
			(stroke
				(width 0.1)
				(type default)
			)
			(layer "B.Fab")
		)
		(fp_line
			(start 0.299974 0.150114)
			(end 0.299974 -0.150114)
			(stroke
				(width 0.1)
				(type default)
			)
			(layer "B.Fab")
		)
		(fp_line
			(start -0.299974 0.150114)
			(end 0.299974 0.150114)
			(stroke
				(width 0.1)
				(type default)
			)
			(layer "B.Fab")
		)
		(pad "1" smd rect
			(at 0.2667 0 270)
			(size 0.3048 0.381)
			(layers "B.Cu" "B.Mask" "B.Paste")
			(net "P0V8_SERDES_VDDA_PEX3")
		)
		(pad "2" smd rect
			(at -0.2667 0 270)
			(size 0.3048 0.381)
			(layers "B.Cu" "B.Mask" "B.Paste")
			(net "GND")
		)
	)
	(footprint ""
		(layer "B.Cu")
		(at 332.862428 -227.33127 -90)
		(property "Reference" "C2088"
			(at 0 0 90)
			(layer "B.SilkS")
			(hide yes)
			(effects
				(font
					(size 1.27 1.27)
				)
				(justify mirror)
			)
		)
		(property "Value" ""
			(at 0 0 90)
			(layer "B.Fab")
			(effects
				(font
					(size 1.27 1.27)
				)
				(justify mirror)
			)
		)
		(duplicate_pad_numbers_are_jumpers no)
		(fp_line
			(start -0.69215 0.2921)
			(end 0.69215 0.2921)
			(stroke
				(width 0.1524)
				(type default)
			)
			(layer "B.SilkS")
		)
		(fp_line
			(start 0.69215 0.2921)
			(end 0.69215 -0.2921)
			(stroke
				(width 0.1524)
				(type default)
			)
			(layer "B.SilkS")
		)
		(fp_line
			(start -0.69215 -0.2921)
			(end -0.69215 0.2921)
			(stroke
				(width 0.1524)
				(type default)
			)
			(layer "B.SilkS")
		)
		(fp_line
			(start 0.69215 -0.2921)
			(end -0.69215 -0.2921)
			(stroke
				(width 0.1524)
				(type default)
			)
			(layer "B.SilkS")
		)
		(fp_line
			(start -0.51435 0.2794)
			(end 0.51435 0.2794)
			(stroke
				(width 0.1)
				(type default)
			)
			(layer "B.Fab")
		)
		(fp_line
			(start 0.51435 0.2794)
			(end 0.51435 -0.2794)
			(stroke
				(width 0.1)
				(type default)
			)
			(layer "B.Fab")
		)
		(fp_line
			(start -0.51435 -0.2794)
			(end -0.51435 0.2794)
			(stroke
				(width 0.1)
				(type default)
			)
			(layer "B.Fab")
		)
		(fp_line
			(start 0.51435 -0.2794)
			(end -0.51435 -0.2794)
			(stroke
				(width 0.1)
				(type default)
			)
			(layer "B.Fab")
		)
		(pad "1" smd circle
			(at 0.40005 0 90)
			(size 0 0)
			(layers "B.Cu" "B.Mask" "B.Paste")
			(net "P3V3_FPGA_VCCIO5")
		)
		(pad "2" smd circle
			(at -0.40005 0 90)
			(size 0 0)
			(layers "B.Cu" "B.Mask" "B.Paste")
			(net "GND")
		)
		(zone
			(layer "B.Cu")
			(hatch none 0.5)
			(connect_pads
				(clearance 0)
			)
			(min_thickness 0.25)
			(keepout
				(tracks not_allowed)
				(vias allowed)
				(pads allowed)
				(copperpour not_allowed)
				(footprints allowed)
			)
			(placement
				(enabled no)
				(sheetname "")
			)
			(fill
				(thermal_gap 0.5)
				(thermal_bridge_width 0.5)
				(island_removal_mode 0)
			)
			(polygon
				(pts
					(xy 332.774798 -227.14077) (xy 332.716632 -227.23221) (xy 332.716632 -227.4316) (xy 332.774798 -227.52177)
					(xy 332.950058 -227.52177) (xy 333.008478 -227.4316) (xy 333.008478 -227.23221) (xy 332.950312 -227.14077)
				)
			)
		)
	)
	(footprint ""
		(layer "B.Cu")
		(at 414.599882 -292.099746 90)
		(property "Reference" "C1960"
			(at 0 0 90)
			(layer "B.SilkS")
			(hide yes)
			(effects
				(font
					(size 1.27 1.27)
				)
				(justify mirror)
			)
		)
		(property "Value" ""
			(at 0 0 90)
			(layer "B.Fab")
			(effects
				(font
					(size 1.27 1.27)
				)
				(justify mirror)
			)
		)
		(duplicate_pad_numbers_are_jumpers no)
		(fp_line
			(start 0.299974 -0.150114)
			(end -0.299974 -0.150114)
			(stroke
				(width 0.1)
				(type default)
			)
			(layer "B.Fab")
		)
		(fp_line
			(start -0.299974 -0.150114)
			(end -0.299974 0.150114)
			(stroke
				(width 0.1)
				(type default)
			)
			(layer "B.Fab")
		)
		(fp_line
			(start 0.299974 0.150114)
			(end 0.299974 -0.150114)
			(stroke
				(width 0.1)
				(type default)
			)
			(layer "B.Fab")
		)
		(fp_line
			(start -0.299974 0.150114)
			(end 0.299974 0.150114)
			(stroke
				(width 0.1)
				(type default)
			)
			(layer "B.Fab")
		)
		(pad "1" smd rect
			(at 0.2667 0 270)
			(size 0.3048 0.381)
			(layers "B.Cu" "B.Mask" "B.Paste")
			(net "P0V8_SERDES_VDDA_PEX3")
		)
		(pad "2" smd rect
			(at -0.2667 0 270)
			(size 0.3048 0.381)
			(layers "B.Cu" "B.Mask" "B.Paste")
			(net "GND")
		)
	)
	(footprint ""
		(layer "B.Cu")
		(at 160.549844 -293.99992)
		(property "Reference" "C3162"
			(at 0 0 0)
			(layer "B.SilkS")
			(hide yes)
			(effects
				(font
					(size 1.27 1.27)
				)
				(justify mirror)
			)
		)
		(property "Value" ""
			(at 0 0 0)
			(layer "B.Fab")
			(effects
				(font
					(size 1.27 1.27)
				)
				(justify mirror)
			)
		)
		(duplicate_pad_numbers_are_jumpers no)
		(fp_line
			(start -0.299974 -0.150114)
			(end -0.299974 0.150114)
			(stroke
				(width 0.1)
				(type default)
			)
			(layer "B.Fab")
		)
		(fp_line
			(start -0.299974 0.150114)
			(end 0.299974 0.150114)
			(stroke
				(width 0.1)
				(type default)
			)
			(layer "B.Fab")
		)
		(fp_line
			(start 0.299974 -0.150114)
			(end -0.299974 -0.150114)
			(stroke
				(width 0.1)
				(type default)
			)
			(layer "B.Fab")
		)
		(fp_line
			(start 0.299974 0.150114)
			(end 0.299974 -0.150114)
			(stroke
				(width 0.1)
				(type default)
			)
			(layer "B.Fab")
		)
		(pad "1" smd rect
			(at 0.2667 0 180)
			(size 0.3048 0.381)
			(layers "B.Cu" "B.Mask" "B.Paste")
			(net "P1V8_PEX")
		)
		(pad "2" smd rect
			(at -0.2667 0 180)
			(size 0.3048 0.381)
			(layers "B.Cu" "B.Mask" "B.Paste")
			(net "GND")
		)
	)
	(footprint ""
		(layer "B.Cu")
		(at 303.954942 -97.663 180)
		(property "Reference" "R277"
			(at 0 0 0)
			(layer "B.SilkS")
			(hide yes)
			(effects
				(font
					(size 1.27 1.27)
				)
				(justify mirror)
			)
		)
		(property "Value" ""
			(at 0 0 0)
			(layer "B.Fab")
			(effects
				(font
					(size 1.27 1.27)
				)
				(justify mirror)
			)
		)
		(duplicate_pad_numbers_are_jumpers no)
		(fp_line
			(start 0.7874 0.4064)
			(end 0.7874 -0.4064)
			(stroke
				(width 0.1524)
				(type default)
			)
			(layer "B.SilkS")
		)
		(fp_line
			(start 0.7874 -0.4064)
			(end -0.7874 -0.4064)
			(stroke
				(width 0.1524)
				(type default)
			)
			(layer "B.SilkS")
		)
		(fp_line
			(start -0.7874 0.4064)
			(end 0.7874 0.4064)
			(stroke
				(width 0.1524)
				(type default)
			)
			(layer "B.SilkS")
		)
		(fp_line
			(start -0.7874 -0.4064)
			(end -0.7874 0.4064)
			(stroke
				(width 0.1524)
				(type default)
			)
			(layer "B.SilkS")
		)
		(fp_line
			(start 0.67945 0.3048)
			(end 0.67945 -0.305054)
			(stroke
				(width 0.1)
				(type default)
			)
			(layer "B.Fab")
		)
		(fp_line
			(start 0.67945 -0.305054)
			(end 0.12065 -0.305054)
			(stroke
				(width 0.1)
				(type default)
			)
			(layer "B.Fab")
		)
		(fp_line
			(start 0.12065 0.3048)
			(end 0.67945 0.3048)
			(stroke
				(width 0.1)
				(type default)
			)
			(layer "B.Fab")
		)
		(fp_line
			(start 0.12065 0.2794)
			(end 0.12065 0.3048)
			(stroke
				(width 0.1)
				(type default)
			)
			(layer "B.Fab")
		)
		(fp_line
			(start 0.12065 -0.2794)
			(end -0.12065 -0.2794)
			(stroke
				(width 0.1)
				(type default)
			)
			(layer "B.Fab")
		)
		(fp_line
			(start 0.12065 -0.305054)
			(end 0.12065 -0.2794)
			(stroke
				(width 0.1)
				(type default)
			)
			(layer "B.Fab")
		)
		(fp_line
			(start -0.120396 0.3048)
			(end -0.120396 0.2794)
			(stroke
				(width 0.1)
				(type default)
			)
			(layer "B.Fab")
		)
		(fp_line
			(start -0.120396 0.2794)
			(end 0.12065 0.2794)
			(stroke
				(width 0.1)
				(type default)
			)
			(layer "B.Fab")
		)
		(fp_line
			(start -0.12065 -0.2794)
			(end -0.12065 -0.3048)
			(stroke
				(width 0.1)
				(type default)
			)
			(layer "B.Fab")
		)
		(fp_line
			(start -0.12065 -0.3048)
			(end -0.67945 -0.3048)
			(stroke
				(width 0.1)
				(type default)
			)
			(layer "B.Fab")
		)
		(fp_line
			(start -0.67945 0.3048)
			(end -0.120396 0.3048)
			(stroke
				(width 0.1)
				(type default)
			)
			(layer "B.Fab")
		)
		(fp_line
			(start -0.67945 -0.3048)
			(end -0.67945 0.3048)
			(stroke
				(width 0.1)
				(type default)
			)
			(layer "B.Fab")
		)
		(pad "1" smd circle
			(at 0.40005 0)
			(size 0 0)
			(layers "B.Cu" "B.Mask" "B.Paste")
			(net "PWRGD_NIC5_PWR_GOOD")
		)
		(pad "2" smd circle
			(at -0.40005 0)
			(size 0 0)
			(layers "B.Cu" "B.Mask" "B.Paste")
			(net "GND")
		)
	)
	(footprint ""
		(layer "B.Cu")
		(at 413.649922 -292.099746 90)
		(property "Reference" "C1933"
			(at 0 0 90)
			(layer "B.SilkS")
			(hide yes)
			(effects
				(font
					(size 1.27 1.27)
				)
				(justify mirror)
			)
		)
		(property "Value" ""
			(at 0 0 90)
			(layer "B.Fab")
			(effects
				(font
					(size 1.27 1.27)
				)
				(justify mirror)
			)
		)
		(duplicate_pad_numbers_are_jumpers no)
		(fp_line
			(start 0.299974 -0.150114)
			(end -0.299974 -0.150114)
			(stroke
				(width 0.1)
				(type default)
			)
			(layer "B.Fab")
		)
		(fp_line
			(start -0.299974 -0.150114)
			(end -0.299974 0.150114)
			(stroke
				(width 0.1)
				(type default)
			)
			(layer "B.Fab")
		)
		(fp_line
			(start 0.299974 0.150114)
			(end 0.299974 -0.150114)
			(stroke
				(width 0.1)
				(type default)
			)
			(layer "B.Fab")
		)
		(fp_line
			(start -0.299974 0.150114)
			(end 0.299974 0.150114)
			(stroke
				(width 0.1)
				(type default)
			)
			(layer "B.Fab")
		)
		(pad "1" smd rect
			(at 0.2667 0 270)
			(size 0.3048 0.381)
			(layers "B.Cu" "B.Mask" "B.Paste")
			(net "P0V8_SERDES_VDDA_PEX3")
		)
		(pad "2" smd rect
			(at -0.2667 0 270)
			(size 0.3048 0.381)
			(layers "B.Cu" "B.Mask" "B.Paste")
			(net "GND")
		)
	)
	(footprint ""
		(layer "B.Cu")
		(at 187.854844 -98.552)
		(property "Reference" "R155"
			(at 0 0 0)
			(layer "B.SilkS")
			(hide yes)
			(effects
				(font
					(size 1.27 1.27)
				)
				(justify mirror)
			)
		)
		(property "Value" ""
			(at 0 0 0)
			(layer "B.Fab")
			(effects
				(font
					(size 1.27 1.27)
				)
				(justify mirror)
			)
		)
		(duplicate_pad_numbers_are_jumpers no)
		(fp_line
			(start -0.7874 -0.4064)
			(end -0.7874 0.4064)
			(stroke
				(width 0.1524)
				(type default)
			)
			(layer "B.SilkS")
		)
		(fp_line
			(start -0.7874 0.4064)
			(end 0.7874 0.4064)
			(stroke
				(width 0.1524)
				(type default)
			)
			(layer "B.SilkS")
		)
		(fp_line
			(start 0.7874 -0.4064)
			(end -0.7874 -0.4064)
			(stroke
				(width 0.1524)
				(type default)
			)
			(layer "B.SilkS")
		)
		(fp_line
			(start 0.7874 0.4064)
			(end 0.7874 -0.4064)
			(stroke
				(width 0.1524)
				(type default)
			)
			(layer "B.SilkS")
		)
		(fp_line
			(start -0.67945 -0.3048)
			(end -0.67945 0.3048)
			(stroke
				(width 0.1)
				(type default)
			)
			(layer "B.Fab")
		)
		(fp_line
			(start -0.67945 0.3048)
			(end -0.120396 0.3048)
			(stroke
				(width 0.1)
				(type default)
			)
			(layer "B.Fab")
		)
		(fp_line
			(start -0.12065 -0.3048)
			(end -0.67945 -0.3048)
			(stroke
				(width 0.1)
				(type default)
			)
			(layer "B.Fab")
		)
		(fp_line
			(start -0.12065 -0.2794)
			(end -0.12065 -0.3048)
			(stroke
				(width 0.1)
				(type default)
			)
			(layer "B.Fab")
		)
		(fp_line
			(start -0.120396 0.2794)
			(end 0.12065 0.2794)
			(stroke
				(width 0.1)
				(type default)
			)
			(layer "B.Fab")
		)
		(fp_line
			(start -0.120396 0.3048)
			(end -0.120396 0.2794)
			(stroke
				(width 0.1)
				(type default)
			)
			(layer "B.Fab")
		)
		(fp_line
			(start 0.12065 -0.305054)
			(end 0.12065 -0.2794)
			(stroke
				(width 0.1)
				(type default)
			)
			(layer "B.Fab")
		)
		(fp_line
			(start 0.12065 -0.2794)
			(end -0.12065 -0.2794)
			(stroke
				(width 0.1)
				(type default)
			)
			(layer "B.Fab")
		)
		(fp_line
			(start 0.12065 0.2794)
			(end 0.12065 0.3048)
			(stroke
				(width 0.1)
				(type default)
			)
			(layer "B.Fab")
		)
		(fp_line
			(start 0.12065 0.3048)
			(end 0.67945 0.3048)
			(stroke
				(width 0.1)
				(type default)
			)
			(layer "B.Fab")
		)
		(fp_line
			(start 0.67945 -0.305054)
			(end 0.12065 -0.305054)
			(stroke
				(width 0.1)
				(type default)
			)
			(layer "B.Fab")
		)
		(fp_line
			(start 0.67945 0.3048)
			(end 0.67945 -0.305054)
			(stroke
				(width 0.1)
				(type default)
			)
			(layer "B.Fab")
		)
		(pad "1" smd circle
			(at 0.40005 0 180)
			(size 0 0)
			(layers "B.Cu" "B.Mask" "B.Paste")
			(net "NIC3_MAIN_PWR_EN_R")
		)
		(pad "2" smd circle
			(at -0.40005 0 180)
			(size 0 0)
			(layers "B.Cu" "B.Mask" "B.Paste")
			(net "NIC3_MAIN_PWR_EN")
		)
	)
	(footprint ""
		(layer "B.Cu")
		(at 209.67446 -225.671888 90)
		(property "Reference" "R6817"
			(at 0 0 90)
			(layer "B.SilkS")
			(hide yes)
			(effects
				(font
					(size 1.27 1.27)
				)
				(justify mirror)
			)
		)
		(property "Value" ""
			(at 0 0 90)
			(layer "B.Fab")
			(effects
				(font
					(size 1.27 1.27)
				)
				(justify mirror)
			)
		)
		(duplicate_pad_numbers_are_jumpers no)
		(fp_line
			(start 0.7874 -0.4064)
			(end -0.7874 -0.4064)
			(stroke
				(width 0.1524)
				(type default)
			)
			(layer "B.SilkS")
		)
		(fp_line
			(start -0.7874 -0.4064)
			(end -0.7874 0.4064)
			(stroke
				(width 0.1524)
				(type default)
			)
			(layer "B.SilkS")
		)
		(fp_line
			(start 0.7874 0.4064)
			(end 0.7874 -0.4064)
			(stroke
				(width 0.1524)
				(type default)
			)
			(layer "B.SilkS")
		)
		(fp_line
			(start -0.7874 0.4064)
			(end 0.7874 0.4064)
			(stroke
				(width 0.1524)
				(type default)
			)
			(layer "B.SilkS")
		)
		(fp_line
			(start 0.67945 -0.305054)
			(end 0.12065 -0.305054)
			(stroke
				(width 0.1)
				(type default)
			)
			(layer "B.Fab")
		)
		(fp_line
			(start 0.12065 -0.305054)
			(end 0.12065 -0.2794)
			(stroke
				(width 0.1)
				(type default)
			)
			(layer "B.Fab")
		)
		(fp_line
			(start -0.12065 -0.3048)
			(end -0.67945 -0.3048)
			(stroke
				(width 0.1)
				(type default)
			)
			(layer "B.Fab")
		)
		(fp_line
			(start -0.67945 -0.3048)
			(end -0.67945 0.3048)
			(stroke
				(width 0.1)
				(type default)
			)
			(layer "B.Fab")
		)
		(fp_line
			(start 0.12065 -0.2794)
			(end -0.12065 -0.2794)
			(stroke
				(width 0.1)
				(type default)
			)
			(layer "B.Fab")
		)
		(fp_line
			(start -0.12065 -0.2794)
			(end -0.12065 -0.3048)
			(stroke
				(width 0.1)
				(type default)
			)
			(layer "B.Fab")
		)
		(fp_line
			(start 0.12065 0.2794)
			(end 0.12065 0.3048)
			(stroke
				(width 0.1)
				(type default)
			)
			(layer "B.Fab")
		)
		(fp_line
			(start -0.120396 0.2794)
			(end 0.12065 0.2794)
			(stroke
				(width 0.1)
				(type default)
			)
			(layer "B.Fab")
		)
		(fp_line
			(start 0.67945 0.3048)
			(end 0.67945 -0.305054)
			(stroke
				(width 0.1)
				(type default)
			)
			(layer "B.Fab")
		)
		(fp_line
			(start 0.12065 0.3048)
			(end 0.67945 0.3048)
			(stroke
				(width 0.1)
				(type default)
			)
			(layer "B.Fab")
		)
		(fp_line
			(start -0.120396 0.3048)
			(end -0.120396 0.2794)
			(stroke
				(width 0.1)
				(type default)
			)
			(layer "B.Fab")
		)
		(fp_line
			(start -0.67945 0.3048)
			(end -0.120396 0.3048)
			(stroke
				(width 0.1)
				(type default)
			)
			(layer "B.Fab")
		)
		(pad "1" smd circle
			(at 0.40005 0 270)
			(size 0 0)
			(layers "B.Cu" "B.Mask" "B.Paste")
			(net "GND")
		)
		(pad "2" smd circle
			(at -0.40005 0 270)
			(size 0 0)
			(layers "B.Cu" "B.Mask" "B.Paste")
			(net "ADC_TYPE_ADC_R")
		)
	)
	(footprint ""
		(layer "B.Cu")
		(at 360.540554 -321.831716 -90)
		(property "Reference" "R6548"
			(at 0 0 90)
			(layer "B.SilkS")
			(hide yes)
			(effects
				(font
					(size 1.27 1.27)
				)
				(justify mirror)
			)
		)
		(property "Value" ""
			(at 0 0 90)
			(layer "B.Fab")
			(effects
				(font
					(size 1.27 1.27)
				)
				(justify mirror)
			)
		)
		(duplicate_pad_numbers_are_jumpers no)
		(fp_line
			(start -0.7874 0.4064)
			(end 0.7874 0.4064)
			(stroke
				(width 0.1524)
				(type default)
			)
			(layer "B.SilkS")
		)
		(fp_line
			(start 0.7874 0.4064)
			(end 0.7874 -0.4064)
			(stroke
				(width 0.1524)
				(type default)
			)
			(layer "B.SilkS")
		)
		(fp_line
			(start -0.7874 -0.4064)
			(end -0.7874 0.4064)
			(stroke
				(width 0.1524)
				(type default)
			)
			(layer "B.SilkS")
		)
		(fp_line
			(start 0.7874 -0.4064)
			(end -0.7874 -0.4064)
			(stroke
				(width 0.1524)
				(type default)
			)
			(layer "B.SilkS")
		)
		(fp_line
			(start -0.67945 0.3048)
			(end -0.120396 0.3048)
			(stroke
				(width 0.1)
				(type default)
			)
			(layer "B.Fab")
		)
		(fp_line
			(start -0.120396 0.3048)
			(end -0.120396 0.2794)
			(stroke
				(width 0.1)
				(type default)
			)
			(layer "B.Fab")
		)
		(fp_line
			(start 0.12065 0.3048)
			(end 0.67945 0.3048)
			(stroke
				(width 0.1)
				(type default)
			)
			(layer "B.Fab")
		)
		(fp_line
			(start 0.67945 0.3048)
			(end 0.67945 -0.305054)
			(stroke
				(width 0.1)
				(type default)
			)
			(layer "B.Fab")
		)
		(fp_line
			(start -0.120396 0.2794)
			(end 0.12065 0.2794)
			(stroke
				(width 0.1)
				(type default)
			)
			(layer "B.Fab")
		)
		(fp_line
			(start 0.12065 0.2794)
			(end 0.12065 0.3048)
			(stroke
				(width 0.1)
				(type default)
			)
			(layer "B.Fab")
		)
		(fp_line
			(start -0.12065 -0.2794)
			(end -0.12065 -0.3048)
			(stroke
				(width 0.1)
				(type default)
			)
			(layer "B.Fab")
		)
		(fp_line
			(start 0.12065 -0.2794)
			(end -0.12065 -0.2794)
			(stroke
				(width 0.1)
				(type default)
			)
			(layer "B.Fab")
		)
		(fp_line
			(start -0.67945 -0.3048)
			(end -0.67945 0.3048)
			(stroke
				(width 0.1)
				(type default)
			)
			(layer "B.Fab")
		)
		(fp_line
			(start -0.12065 -0.3048)
			(end -0.67945 -0.3048)
			(stroke
				(width 0.1)
				(type default)
			)
			(layer "B.Fab")
		)
		(fp_line
			(start 0.12065 -0.305054)
			(end 0.12065 -0.2794)
			(stroke
				(width 0.1)
				(type default)
			)
			(layer "B.Fab")
		)
		(fp_line
			(start 0.67945 -0.305054)
			(end 0.12065 -0.305054)
			(stroke
				(width 0.1)
				(type default)
			)
			(layer "B.Fab")
		)
		(pad "1" smd circle
			(at 0.40005 0 90)
			(size 0 0)
			(layers "B.Cu" "B.Mask" "B.Paste")
			(net "P0V8_SERDES_VDDA_PEX3")
		)
		(pad "2" smd circle
			(at -0.40005 0 90)
			(size 0 0)
			(layers "B.Cu" "B.Mask" "B.Paste")
			(net "P0V8_SERDES_VDDA_PEX3_C11")
		)
	)
	(footprint ""
		(layer "B.Cu")
		(at 177.423826 -194.683634)
		(property "Reference" "R1035"
			(at 0 0 0)
			(layer "B.SilkS")
			(hide yes)
			(effects
				(font
					(size 1.27 1.27)
				)
				(justify mirror)
			)
		)
		(property "Value" ""
			(at 0 0 0)
			(layer "B.Fab")
			(effects
				(font
					(size 1.27 1.27)
				)
				(justify mirror)
			)
		)
		(duplicate_pad_numbers_are_jumpers no)
		(fp_line
			(start -0.7874 -0.4064)
			(end -0.7874 0.4064)
			(stroke
				(width 0.1524)
				(type default)
			)
			(layer "B.SilkS")
		)
		(fp_line
			(start -0.7874 0.4064)
			(end 0.7874 0.4064)
			(stroke
				(width 0.1524)
				(type default)
			)
			(layer "B.SilkS")
		)
		(fp_line
			(start 0.7874 -0.4064)
			(end -0.7874 -0.4064)
			(stroke
				(width 0.1524)
				(type default)
			)
			(layer "B.SilkS")
		)
		(fp_line
			(start 0.7874 0.4064)
			(end 0.7874 -0.4064)
			(stroke
				(width 0.1524)
				(type default)
			)
			(layer "B.SilkS")
		)
		(fp_line
			(start -0.67945 -0.3048)
			(end -0.67945 0.3048)
			(stroke
				(width 0.1)
				(type default)
			)
			(layer "B.Fab")
		)
		(fp_line
			(start -0.67945 0.3048)
			(end -0.120396 0.3048)
			(stroke
				(width 0.1)
				(type default)
			)
			(layer "B.Fab")
		)
		(fp_line
			(start -0.12065 -0.3048)
			(end -0.67945 -0.3048)
			(stroke
				(width 0.1)
				(type default)
			)
			(layer "B.Fab")
		)
		(fp_line
			(start -0.12065 -0.2794)
			(end -0.12065 -0.3048)
			(stroke
				(width 0.1)
				(type default)
			)
			(layer "B.Fab")
		)
		(fp_line
			(start -0.120396 0.2794)
			(end 0.12065 0.2794)
			(stroke
				(width 0.1)
				(type default)
			)
			(layer "B.Fab")
		)
		(fp_line
			(start -0.120396 0.3048)
			(end -0.120396 0.2794)
			(stroke
				(width 0.1)
				(type default)
			)
			(layer "B.Fab")
		)
		(fp_line
			(start 0.12065 -0.305054)
			(end 0.12065 -0.2794)
			(stroke
				(width 0.1)
				(type default)
			)
			(layer "B.Fab")
		)
		(fp_line
			(start 0.12065 -0.2794)
			(end -0.12065 -0.2794)
			(stroke
				(width 0.1)
				(type default)
			)
			(layer "B.Fab")
		)
		(fp_line
			(start 0.12065 0.2794)
			(end 0.12065 0.3048)
			(stroke
				(width 0.1)
				(type default)
			)
			(layer "B.Fab")
		)
		(fp_line
			(start 0.12065 0.3048)
			(end 0.67945 0.3048)
			(stroke
				(width 0.1)
				(type default)
			)
			(layer "B.Fab")
		)
		(fp_line
			(start 0.67945 -0.305054)
			(end 0.12065 -0.305054)
			(stroke
				(width 0.1)
				(type default)
			)
			(layer "B.Fab")
		)
		(fp_line
			(start 0.67945 0.3048)
			(end 0.67945 -0.305054)
			(stroke
				(width 0.1)
				(type default)
			)
			(layer "B.Fab")
		)
		(pad "1" smd circle
			(at 0.40005 0 180)
			(size 0 0)
			(layers "B.Cu" "B.Mask" "B.Paste")
			(net "GND")
		)
		(pad "2" smd circle
			(at -0.40005 0 180)
			(size 0 0)
			(layers "B.Cu" "B.Mask" "B.Paste")
			(net "SPI_BIC1_MOSI_LS01_DIR3")
		)
	)
	(footprint ""
		(layer "B.Cu")
		(at 51.574954 -297.79976 90)
		(property "Reference" "C1140"
			(at 0 0 90)
			(layer "B.SilkS")
			(hide yes)
			(effects
				(font
					(size 1.27 1.27)
				)
				(justify mirror)
			)
		)
		(property "Value" ""
			(at 0 0 90)
			(layer "B.Fab")
			(effects
				(font
					(size 1.27 1.27)
				)
				(justify mirror)
			)
		)
		(duplicate_pad_numbers_are_jumpers no)
		(fp_line
			(start 0.299974 -0.150114)
			(end -0.299974 -0.150114)
			(stroke
				(width 0.1)
				(type default)
			)
			(layer "B.Fab")
		)
		(fp_line
			(start -0.299974 -0.150114)
			(end -0.299974 0.150114)
			(stroke
				(width 0.1)
				(type default)
			)
			(layer "B.Fab")
		)
		(fp_line
			(start 0.299974 0.150114)
			(end 0.299974 -0.150114)
			(stroke
				(width 0.1)
				(type default)
			)
			(layer "B.Fab")
		)
		(fp_line
			(start -0.299974 0.150114)
			(end 0.299974 0.150114)
			(stroke
				(width 0.1)
				(type default)
			)
			(layer "B.Fab")
		)
		(pad "1" smd rect
			(at 0.2667 0 270)
			(size 0.3048 0.381)
			(layers "B.Cu" "B.Mask" "B.Paste")
			(net "P0V8_PEX0")
		)
		(pad "2" smd rect
			(at -0.2667 0 270)
			(size 0.3048 0.381)
			(layers "B.Cu" "B.Mask" "B.Paste")
			(net "GND")
		)
	)
	(footprint ""
		(layer "B.Cu")
		(at 416.499802 -298.27474 180)
		(property "Reference" "C1890"
			(at 0 0 0)
			(layer "B.SilkS")
			(hide yes)
			(effects
				(font
					(size 1.27 1.27)
				)
				(justify mirror)
			)
		)
		(property "Value" ""
			(at 0 0 0)
			(layer "B.Fab")
			(effects
				(font
					(size 1.27 1.27)
				)
				(justify mirror)
			)
		)
		(duplicate_pad_numbers_are_jumpers no)
		(fp_line
			(start 0.299974 0.150114)
			(end 0.299974 -0.150114)
			(stroke
				(width 0.1)
				(type default)
			)
			(layer "B.Fab")
		)
		(fp_line
			(start 0.299974 -0.150114)
			(end -0.299974 -0.150114)
			(stroke
				(width 0.1)
				(type default)
			)
			(layer "B.Fab")
		)
		(fp_line
			(start -0.299974 0.150114)
			(end 0.299974 0.150114)
			(stroke
				(width 0.1)
				(type default)
			)
			(layer "B.Fab")
		)
		(fp_line
			(start -0.299974 -0.150114)
			(end -0.299974 0.150114)
			(stroke
				(width 0.1)
				(type default)
			)
			(layer "B.Fab")
		)
		(pad "1" smd rect
			(at 0.2667 0)
			(size 0.3048 0.381)
			(layers "B.Cu" "B.Mask" "B.Paste")
			(net "P0V8_PEX3")
		)
		(pad "2" smd rect
			(at -0.2667 0)
			(size 0.3048 0.381)
			(layers "B.Cu" "B.Mask" "B.Paste")
			(net "GND")
		)
	)
	(footprint ""
		(layer "B.Cu")
		(at 198.549768 -366.339628)
		(property "Reference" "PC8"
			(at 0 0 0)
			(layer "B.SilkS")
			(hide yes)
			(effects
				(font
					(size 1.27 1.27)
				)
				(justify mirror)
			)
		)
		(property "Value" ""
			(at 0 0 0)
			(layer "B.Fab")
			(effects
				(font
					(size 1.27 1.27)
				)
				(justify mirror)
			)
		)
		(duplicate_pad_numbers_are_jumpers no)
		(fp_line
			(start -0.7874 -0.4064)
			(end -0.7874 0.4064)
			(stroke
				(width 0.1524)
				(type default)
			)
			(layer "B.SilkS")
		)
		(fp_line
			(start -0.7874 0.4064)
			(end 0.7874 0.4064)
			(stroke
				(width 0.1524)
				(type default)
			)
			(layer "B.SilkS")
		)
		(fp_line
			(start 0.7874 -0.4064)
			(end -0.7874 -0.4064)
			(stroke
				(width 0.1524)
				(type default)
			)
			(layer "B.SilkS")
		)
		(fp_line
			(start 0.7874 0.4064)
			(end 0.7874 -0.4064)
			(stroke
				(width 0.1524)
				(type default)
			)
			(layer "B.SilkS")
		)
		(fp_line
			(start -0.67945 -0.3048)
			(end -0.67945 0.3048)
			(stroke
				(width 0.1)
				(type default)
			)
			(layer "B.Fab")
		)
		(fp_line
			(start -0.67945 0.3048)
			(end -0.120396 0.3048)
			(stroke
				(width 0.1)
				(type default)
			)
			(layer "B.Fab")
		)
		(fp_line
			(start -0.12065 -0.3048)
			(end -0.67945 -0.3048)
			(stroke
				(width 0.1)
				(type default)
			)
			(layer "B.Fab")
		)
		(fp_line
			(start -0.12065 -0.2794)
			(end -0.12065 -0.3048)
			(stroke
				(width 0.1)
				(type default)
			)
			(layer "B.Fab")
		)
		(fp_line
			(start -0.120396 0.2794)
			(end 0.12065 0.2794)
			(stroke
				(width 0.1)
				(type default)
			)
			(layer "B.Fab")
		)
		(fp_line
			(start -0.120396 0.3048)
			(end -0.120396 0.2794)
			(stroke
				(width 0.1)
				(type default)
			)
			(layer "B.Fab")
		)
		(fp_line
			(start 0.12065 -0.305054)
			(end 0.12065 -0.2794)
			(stroke
				(width 0.1)
				(type default)
			)
			(layer "B.Fab")
		)
		(fp_line
			(start 0.12065 -0.2794)
			(end -0.12065 -0.2794)
			(stroke
				(width 0.1)
				(type default)
			)
			(layer "B.Fab")
		)
		(fp_line
			(start 0.12065 0.2794)
			(end 0.12065 0.3048)
			(stroke
				(width 0.1)
				(type default)
			)
			(layer "B.Fab")
		)
		(fp_line
			(start 0.12065 0.3048)
			(end 0.67945 0.3048)
			(stroke
				(width 0.1)
				(type default)
			)
			(layer "B.Fab")
		)
		(fp_line
			(start 0.67945 -0.305054)
			(end 0.12065 -0.305054)
			(stroke
				(width 0.1)
				(type default)
			)
			(layer "B.Fab")
		)
		(fp_line
			(start 0.67945 0.3048)
			(end 0.67945 -0.305054)
			(stroke
				(width 0.1)
				(type default)
			)
			(layer "B.Fab")
		)
		(pad "1" smd circle
			(at 0.40005 0 180)
			(size 0 0)
			(layers "B.Cu" "B.Mask" "B.Paste")
			(net "HSC_SS")
		)
		(pad "2" smd circle
			(at -0.40005 0 180)
			(size 0 0)
			(layers "B.Cu" "B.Mask" "B.Paste")
			(net "AGND_HSC")
		)
	)
	(footprint ""
		(layer "B.Cu")
		(at 461.729328 -307.589428 90)
		(property "Reference" "R4438"
			(at 0 0 90)
			(layer "B.SilkS")
			(hide yes)
			(effects
				(font
					(size 1.27 1.27)
				)
				(justify mirror)
			)
		)
		(property "Value" ""
			(at 0 0 90)
			(layer "B.Fab")
			(effects
				(font
					(size 1.27 1.27)
				)
				(justify mirror)
			)
		)
		(duplicate_pad_numbers_are_jumpers no)
		(fp_line
			(start 0.7874 -0.4064)
			(end -0.7874 -0.4064)
			(stroke
				(width 0.1524)
				(type default)
			)
			(layer "B.SilkS")
		)
		(fp_line
			(start -0.7874 -0.4064)
			(end -0.7874 0.4064)
			(stroke
				(width 0.1524)
				(type default)
			)
			(layer "B.SilkS")
		)
		(fp_line
			(start 0.7874 0.4064)
			(end 0.7874 -0.4064)
			(stroke
				(width 0.1524)
				(type default)
			)
			(layer "B.SilkS")
		)
		(fp_line
			(start -0.7874 0.4064)
			(end 0.7874 0.4064)
			(stroke
				(width 0.1524)
				(type default)
			)
			(layer "B.SilkS")
		)
		(fp_line
			(start 0.67945 -0.305054)
			(end 0.12065 -0.305054)
			(stroke
				(width 0.1)
				(type default)
			)
			(layer "B.Fab")
		)
		(fp_line
			(start 0.12065 -0.305054)
			(end 0.12065 -0.2794)
			(stroke
				(width 0.1)
				(type default)
			)
			(layer "B.Fab")
		)
		(fp_line
			(start -0.12065 -0.3048)
			(end -0.67945 -0.3048)
			(stroke
				(width 0.1)
				(type default)
			)
			(layer "B.Fab")
		)
		(fp_line
			(start -0.67945 -0.3048)
			(end -0.67945 0.3048)
			(stroke
				(width 0.1)
				(type default)
			)
			(layer "B.Fab")
		)
		(fp_line
			(start 0.12065 -0.2794)
			(end -0.12065 -0.2794)
			(stroke
				(width 0.1)
				(type default)
			)
			(layer "B.Fab")
		)
		(fp_line
			(start -0.12065 -0.2794)
			(end -0.12065 -0.3048)
			(stroke
				(width 0.1)
				(type default)
			)
			(layer "B.Fab")
		)
		(fp_line
			(start 0.12065 0.2794)
			(end 0.12065 0.3048)
			(stroke
				(width 0.1)
				(type default)
			)
			(layer "B.Fab")
		)
		(fp_line
			(start -0.120396 0.2794)
			(end 0.12065 0.2794)
			(stroke
				(width 0.1)
				(type default)
			)
			(layer "B.Fab")
		)
		(fp_line
			(start 0.67945 0.3048)
			(end 0.67945 -0.305054)
			(stroke
				(width 0.1)
				(type default)
			)
			(layer "B.Fab")
		)
		(fp_line
			(start 0.12065 0.3048)
			(end 0.67945 0.3048)
			(stroke
				(width 0.1)
				(type default)
			)
			(layer "B.Fab")
		)
		(fp_line
			(start -0.120396 0.3048)
			(end -0.120396 0.2794)
			(stroke
				(width 0.1)
				(type default)
			)
			(layer "B.Fab")
		)
		(fp_line
			(start -0.67945 0.3048)
			(end -0.120396 0.3048)
			(stroke
				(width 0.1)
				(type default)
			)
			(layer "B.Fab")
		)
		(pad "1" smd circle
			(at 0.40005 0 270)
			(size 0 0)
			(layers "B.Cu" "B.Mask" "B.Paste")
			(net "PWRGD_P1V25_PEX3_R")
		)
		(pad "2" smd circle
			(at -0.40005 0 270)
			(size 0 0)
			(layers "B.Cu" "B.Mask" "B.Paste")
			(net "PWRGD_P1V25_PEX3")
		)
	)
	(footprint ""
		(layer "B.Cu")
		(at 299.449744 -299.699934 -90)
		(property "Reference" "C1694"
			(at 0 0 90)
			(layer "B.SilkS")
			(hide yes)
			(effects
				(font
					(size 1.27 1.27)
				)
				(justify mirror)
			)
		)
		(property "Value" ""
			(at 0 0 90)
			(layer "B.Fab")
			(effects
				(font
					(size 1.27 1.27)
				)
				(justify mirror)
			)
		)
		(duplicate_pad_numbers_are_jumpers no)
		(fp_line
			(start -0.299974 0.150114)
			(end 0.299974 0.150114)
			(stroke
				(width 0.1)
				(type default)
			)
			(layer "B.Fab")
		)
		(fp_line
			(start 0.299974 0.150114)
			(end 0.299974 -0.150114)
			(stroke
				(width 0.1)
				(type default)
			)
			(layer "B.Fab")
		)
		(fp_line
			(start -0.299974 -0.150114)
			(end -0.299974 0.150114)
			(stroke
				(width 0.1)
				(type default)
			)
			(layer "B.Fab")
		)
		(fp_line
			(start 0.299974 -0.150114)
			(end -0.299974 -0.150114)
			(stroke
				(width 0.1)
				(type default)
			)
			(layer "B.Fab")
		)
		(pad "1" smd rect
			(at 0.2667 0 90)
			(size 0.3048 0.381)
			(layers "B.Cu" "B.Mask" "B.Paste")
			(net "P0V8_SERDES_VDDA_PEX2")
		)
		(pad "2" smd rect
			(at -0.2667 0 90)
			(size 0.3048 0.381)
			(layers "B.Cu" "B.Mask" "B.Paste")
			(net "GND")
		)
	)
	(footprint ""
		(layer "B.Cu")
		(at 111.082836 -84.812378)
		(property "Reference" "C2669"
			(at 0 0 0)
			(layer "B.SilkS")
			(hide yes)
			(effects
				(font
					(size 1.27 1.27)
				)
				(justify mirror)
			)
		)
		(property "Value" ""
			(at 0 0 0)
			(layer "B.Fab")
			(effects
				(font
					(size 1.27 1.27)
				)
				(justify mirror)
			)
		)
		(duplicate_pad_numbers_are_jumpers no)
		(fp_line
			(start -0.7874 -0.4064)
			(end -0.7874 0.4064)
			(stroke
				(width 0.1524)
				(type default)
			)
			(layer "B.SilkS")
		)
		(fp_line
			(start -0.7874 0.4064)
			(end 0.7874 0.4064)
			(stroke
				(width 0.1524)
				(type default)
			)
			(layer "B.SilkS")
		)
		(fp_line
			(start 0.7874 -0.4064)
			(end -0.7874 -0.4064)
			(stroke
				(width 0.1524)
				(type default)
			)
			(layer "B.SilkS")
		)
		(fp_line
			(start 0.7874 0.4064)
			(end 0.7874 -0.4064)
			(stroke
				(width 0.1524)
				(type default)
			)
			(layer "B.SilkS")
		)
		(fp_line
			(start -0.67945 -0.3048)
			(end -0.67945 0.3048)
			(stroke
				(width 0.1)
				(type default)
			)
			(layer "B.Fab")
		)
		(fp_line
			(start -0.67945 0.3048)
			(end -0.120396 0.3048)
			(stroke
				(width 0.1)
				(type default)
			)
			(layer "B.Fab")
		)
		(fp_line
			(start -0.12065 -0.3048)
			(end -0.67945 -0.3048)
			(stroke
				(width 0.1)
				(type default)
			)
			(layer "B.Fab")
		)
		(fp_line
			(start -0.12065 -0.2794)
			(end -0.12065 -0.3048)
			(stroke
				(width 0.1)
				(type default)
			)
			(layer "B.Fab")
		)
		(fp_line
			(start -0.120396 0.2794)
			(end 0.12065 0.2794)
			(stroke
				(width 0.1)
				(type default)
			)
			(layer "B.Fab")
		)
		(fp_line
			(start -0.120396 0.3048)
			(end -0.120396 0.2794)
			(stroke
				(width 0.1)
				(type default)
			)
			(layer "B.Fab")
		)
		(fp_line
			(start 0.12065 -0.305054)
			(end 0.12065 -0.2794)
			(stroke
				(width 0.1)
				(type default)
			)
			(layer "B.Fab")
		)
		(fp_line
			(start 0.12065 -0.2794)
			(end -0.12065 -0.2794)
			(stroke
				(width 0.1)
				(type default)
			)
			(layer "B.Fab")
		)
		(fp_line
			(start 0.12065 0.2794)
			(end 0.12065 0.3048)
			(stroke
				(width 0.1)
				(type default)
			)
			(layer "B.Fab")
		)
		(fp_line
			(start 0.12065 0.3048)
			(end 0.67945 0.3048)
			(stroke
				(width 0.1)
				(type default)
			)
			(layer "B.Fab")
		)
		(fp_line
			(start 0.67945 -0.305054)
			(end 0.12065 -0.305054)
			(stroke
				(width 0.1)
				(type default)
			)
			(layer "B.Fab")
		)
		(fp_line
			(start 0.67945 0.3048)
			(end 0.67945 -0.305054)
			(stroke
				(width 0.1)
				(type default)
			)
			(layer "B.Fab")
		)
		(pad "1" smd circle
			(at 0.40005 0 180)
			(size 0 0)
			(layers "B.Cu" "B.Mask" "B.Paste")
			(net "P3V3_VDD_9ZXL0851_0_7")
		)
		(pad "2" smd circle
			(at -0.40005 0 180)
			(size 0 0)
			(layers "B.Cu" "B.Mask" "B.Paste")
			(net "GND")
		)
	)
	(footprint ""
		(layer "B.Cu")
		(at 363.093 -229.997)
		(property "Reference" "R3501"
			(at 0 0 0)
			(layer "B.SilkS")
			(hide yes)
			(effects
				(font
					(size 1.27 1.27)
				)
				(justify mirror)
			)
		)
		(property "Value" ""
			(at 0 0 0)
			(layer "B.Fab")
			(effects
				(font
					(size 1.27 1.27)
				)
				(justify mirror)
			)
		)
		(duplicate_pad_numbers_are_jumpers no)
		(fp_line
			(start -0.7874 -0.4064)
			(end -0.7874 0.4064)
			(stroke
				(width 0.1524)
				(type default)
			)
			(layer "B.SilkS")
		)
		(fp_line
			(start -0.7874 0.4064)
			(end 0.7874 0.4064)
			(stroke
				(width 0.1524)
				(type default)
			)
			(layer "B.SilkS")
		)
		(fp_line
			(start 0.7874 -0.4064)
			(end -0.7874 -0.4064)
			(stroke
				(width 0.1524)
				(type default)
			)
			(layer "B.SilkS")
		)
		(fp_line
			(start 0.7874 0.4064)
			(end 0.7874 -0.4064)
			(stroke
				(width 0.1524)
				(type default)
			)
			(layer "B.SilkS")
		)
		(fp_line
			(start -0.67945 -0.3048)
			(end -0.67945 0.3048)
			(stroke
				(width 0.1)
				(type default)
			)
			(layer "B.Fab")
		)
		(fp_line
			(start -0.67945 0.3048)
			(end -0.120396 0.3048)
			(stroke
				(width 0.1)
				(type default)
			)
			(layer "B.Fab")
		)
		(fp_line
			(start -0.12065 -0.3048)
			(end -0.67945 -0.3048)
			(stroke
				(width 0.1)
				(type default)
			)
			(layer "B.Fab")
		)
		(fp_line
			(start -0.12065 -0.2794)
			(end -0.12065 -0.3048)
			(stroke
				(width 0.1)
				(type default)
			)
			(layer "B.Fab")
		)
		(fp_line
			(start -0.120396 0.2794)
			(end 0.12065 0.2794)
			(stroke
				(width 0.1)
				(type default)
			)
			(layer "B.Fab")
		)
		(fp_line
			(start -0.120396 0.3048)
			(end -0.120396 0.2794)
			(stroke
				(width 0.1)
				(type default)
			)
			(layer "B.Fab")
		)
		(fp_line
			(start 0.12065 -0.305054)
			(end 0.12065 -0.2794)
			(stroke
				(width 0.1)
				(type default)
			)
			(layer "B.Fab")
		)
		(fp_line
			(start 0.12065 -0.2794)
			(end -0.12065 -0.2794)
			(stroke
				(width 0.1)
				(type default)
			)
			(layer "B.Fab")
		)
		(fp_line
			(start 0.12065 0.2794)
			(end 0.12065 0.3048)
			(stroke
				(width 0.1)
				(type default)
			)
			(layer "B.Fab")
		)
		(fp_line
			(start 0.12065 0.3048)
			(end 0.67945 0.3048)
			(stroke
				(width 0.1)
				(type default)
			)
			(layer "B.Fab")
		)
		(fp_line
			(start 0.67945 -0.305054)
			(end 0.12065 -0.305054)
			(stroke
				(width 0.1)
				(type default)
			)
			(layer "B.Fab")
		)
		(fp_line
			(start 0.67945 0.3048)
			(end 0.67945 -0.305054)
			(stroke
				(width 0.1)
				(type default)
			)
			(layer "B.Fab")
		)
		(pad "1" smd circle
			(at 0.40005 0 180)
			(size 0 0)
			(layers "B.Cu" "B.Mask" "B.Paste")
			(net "SPI_PEX3_SDIO2_R")
		)
		(pad "2" smd circle
			(at -0.40005 0 180)
			(size 0 0)
			(layers "B.Cu" "B.Mask" "B.Paste")
			(net "SPI_PEX3_SDIO2_R1")
		)
	)
	(footprint ""
		(layer "B.Cu")
		(at 417.450016 -300.174914 180)
		(property "Reference" "C3530"
			(at 0 0 0)
			(layer "B.SilkS")
			(hide yes)
			(effects
				(font
					(size 1.27 1.27)
				)
				(justify mirror)
			)
		)
		(property "Value" ""
			(at 0 0 0)
			(layer "B.Fab")
			(effects
				(font
					(size 1.27 1.27)
				)
				(justify mirror)
			)
		)
		(duplicate_pad_numbers_are_jumpers no)
		(fp_line
			(start 0.299974 0.150114)
			(end 0.299974 -0.150114)
			(stroke
				(width 0.1)
				(type default)
			)
			(layer "B.Fab")
		)
		(fp_line
			(start 0.299974 -0.150114)
			(end -0.299974 -0.150114)
			(stroke
				(width 0.1)
				(type default)
			)
			(layer "B.Fab")
		)
		(fp_line
			(start -0.299974 0.150114)
			(end 0.299974 0.150114)
			(stroke
				(width 0.1)
				(type default)
			)
			(layer "B.Fab")
		)
		(fp_line
			(start -0.299974 -0.150114)
			(end -0.299974 0.150114)
			(stroke
				(width 0.1)
				(type default)
			)
			(layer "B.Fab")
		)
		(pad "1" smd rect
			(at 0.2667 0)
			(size 0.3048 0.381)
			(layers "B.Cu" "B.Mask" "B.Paste")
			(net "P1V8_VDDA_PEX3")
		)
		(pad "2" smd rect
			(at -0.2667 0)
			(size 0.3048 0.381)
			(layers "B.Cu" "B.Mask" "B.Paste")
			(net "GND")
		)
	)
	(footprint ""
		(layer "B.Cu")
		(at 288.52495 -297.79976 -90)
		(property "Reference" "C1624"
			(at 0 0 90)
			(layer "B.SilkS")
			(hide yes)
			(effects
				(font
					(size 1.27 1.27)
				)
				(justify mirror)
			)
		)
		(property "Value" ""
			(at 0 0 90)
			(layer "B.Fab")
			(effects
				(font
					(size 1.27 1.27)
				)
				(justify mirror)
			)
		)
		(duplicate_pad_numbers_are_jumpers no)
		(fp_line
			(start -0.299974 0.150114)
			(end 0.299974 0.150114)
			(stroke
				(width 0.1)
				(type default)
			)
			(layer "B.Fab")
		)
		(fp_line
			(start 0.299974 0.150114)
			(end 0.299974 -0.150114)
			(stroke
				(width 0.1)
				(type default)
			)
			(layer "B.Fab")
		)
		(fp_line
			(start -0.299974 -0.150114)
			(end -0.299974 0.150114)
			(stroke
				(width 0.1)
				(type default)
			)
			(layer "B.Fab")
		)
		(fp_line
			(start 0.299974 -0.150114)
			(end -0.299974 -0.150114)
			(stroke
				(width 0.1)
				(type default)
			)
			(layer "B.Fab")
		)
		(pad "1" smd rect
			(at 0.2667 0 90)
			(size 0.3048 0.381)
			(layers "B.Cu" "B.Mask" "B.Paste")
			(net "P0V8_PEX2")
		)
		(pad "2" smd rect
			(at -0.2667 0 90)
			(size 0.3048 0.381)
			(layers "B.Cu" "B.Mask" "B.Paste")
			(net "GND")
		)
	)
	(footprint ""
		(layer "B.Cu")
		(at 128.321816 -211.588858 180)
		(property "Reference" "U105"
			(at 1.53924 -1.966722 0)
			(unlocked yes)
			(layer "B.SilkS")
			(effects
				(font
					(size 0.7874 0.5842)
					(thickness 0.1524)
				)
				(justify mirror)
			)
		)
		(property "Value" ""
			(at 0 0 0)
			(layer "B.Fab")
			(effects
				(font
					(size 1.27 1.27)
				)
				(justify mirror)
			)
		)
		(duplicate_pad_numbers_are_jumpers no)
		(fp_line
			(start 1.7272 1.1176)
			(end 1.7272 -1.1176)
			(stroke
				(width 0.1524)
				(type default)
			)
			(layer "B.SilkS")
		)
		(fp_line
			(start 0.254 -1.1176)
			(end 1.7272 -1.1176)
			(stroke
				(width 0.1524)
				(type default)
			)
			(layer "B.SilkS")
		)
		(fp_line
			(start 0 -0.7366)
			(end 0.254 -1.1176)
			(stroke
				(width 0.1524)
				(type default)
			)
			(layer "B.SilkS")
		)
		(fp_line
			(start -0.254 -1.1176)
			(end 0 -0.7366)
			(stroke
				(width 0.1524)
				(type default)
			)
			(layer "B.SilkS")
		)
		(fp_line
			(start -1.7272 1.1176)
			(end 1.7272 1.1176)
			(stroke
				(width 0.1524)
				(type default)
			)
			(layer "B.SilkS")
		)
		(fp_line
			(start -1.7272 -1.1176)
			(end -0.254 -1.1176)
			(stroke
				(width 0.1524)
				(type default)
			)
			(layer "B.SilkS")
		)
		(fp_line
			(start -1.7272 -1.1176)
			(end -1.7272 1.1176)
			(stroke
				(width 0.1524)
				(type default)
			)
			(layer "B.SilkS")
		)
		(fp_poly
			(pts
				(xy 1.9558 -0.649986) (xy 2.7178 -0.268986) (xy 2.7178 -1.030986)
			)
			(stroke
				(width 0)
				(type default)
			)
			(fill yes)
			(layer "B.SilkS")
		)
		(fp_line
			(start 1.5748 1.1176)
			(end -1.5748 1.1176)
			(stroke
				(width 0.1)
				(type default)
			)
			(layer "B.Fab")
		)
		(fp_line
			(start 1.5748 -1.1176)
			(end 1.5748 1.1176)
			(stroke
				(width 0.1)
				(type default)
			)
			(layer "B.Fab")
		)
		(fp_line
			(start -1.5748 1.1176)
			(end -1.5748 -1.1176)
			(stroke
				(width 0.1)
				(type default)
			)
			(layer "B.Fab")
		)
		(fp_line
			(start -1.5748 -1.1176)
			(end 1.5748 -1.1176)
			(stroke
				(width 0.1)
				(type default)
			)
			(layer "B.Fab")
		)
		(fp_poly
			(pts
				(xy 1.9558 -0.649986) (xy 2.7178 -0.268986) (xy 2.7178 -1.030986)
			)
			(stroke
				(width 0)
				(type default)
			)
			(fill yes)
			(layer "B.Fab")
		)
		(pad "1" smd rect
			(at 0.999998 -0.649986 90)
			(size 0.3556 1.1176)
			(layers "B.Cu" "B.Mask" "B.Paste")
			(net "UART_PEX0_CLI_R_TX")
		)
		(pad "2" smd rect
			(at 0.999998 0 90)
			(size 0.3556 1.1176)
			(layers "B.Cu" "B.Mask" "B.Paste")
			(net "GND")
		)
		(pad "3" smd rect
			(at 0.999998 0.649986 90)
			(size 0.3556 1.1176)
			(layers "B.Cu" "B.Mask" "B.Paste")
			(net "UART_PEX1_CLI_R_TX")
		)
		(pad "4" smd rect
			(at -0.999998 0.649986 90)
			(size 0.3556 1.1176)
			(layers "B.Cu" "B.Mask" "B.Paste")
			(net "UART_PEX1_CLI_BUF_R_TX")
		)
		(pad "5" smd rect
			(at -0.999998 0 90)
			(size 0.3556 1.1176)
			(layers "B.Cu" "B.Mask" "B.Paste")
			(net "P1V8_PEX")
		)
		(pad "6" smd rect
			(at -0.999998 -0.649986 90)
			(size 0.3556 1.1176)
			(layers "B.Cu" "B.Mask" "B.Paste")
			(net "UART_PEX0_CLI_BUF_R_TX")
		)
	)
	(footprint ""
		(layer "B.Cu")
		(at 357.356664 -321.84594 -90)
		(property "Reference" "R6546"
			(at 0 0 90)
			(layer "B.SilkS")
			(hide yes)
			(effects
				(font
					(size 1.27 1.27)
				)
				(justify mirror)
			)
		)
		(property "Value" ""
			(at 0 0 90)
			(layer "B.Fab")
			(effects
				(font
					(size 1.27 1.27)
				)
				(justify mirror)
			)
		)
		(duplicate_pad_numbers_are_jumpers no)
		(fp_line
			(start -0.7874 0.4064)
			(end 0.7874 0.4064)
			(stroke
				(width 0.1524)
				(type default)
			)
			(layer "B.SilkS")
		)
		(fp_line
			(start 0.7874 0.4064)
			(end 0.7874 -0.4064)
			(stroke
				(width 0.1524)
				(type default)
			)
			(layer "B.SilkS")
		)
		(fp_line
			(start -0.7874 -0.4064)
			(end -0.7874 0.4064)
			(stroke
				(width 0.1524)
				(type default)
			)
			(layer "B.SilkS")
		)
		(fp_line
			(start 0.7874 -0.4064)
			(end -0.7874 -0.4064)
			(stroke
				(width 0.1524)
				(type default)
			)
			(layer "B.SilkS")
		)
		(fp_line
			(start -0.67945 0.3048)
			(end -0.120396 0.3048)
			(stroke
				(width 0.1)
				(type default)
			)
			(layer "B.Fab")
		)
		(fp_line
			(start -0.120396 0.3048)
			(end -0.120396 0.2794)
			(stroke
				(width 0.1)
				(type default)
			)
			(layer "B.Fab")
		)
		(fp_line
			(start 0.12065 0.3048)
			(end 0.67945 0.3048)
			(stroke
				(width 0.1)
				(type default)
			)
			(layer "B.Fab")
		)
		(fp_line
			(start 0.67945 0.3048)
			(end 0.67945 -0.305054)
			(stroke
				(width 0.1)
				(type default)
			)
			(layer "B.Fab")
		)
		(fp_line
			(start -0.120396 0.2794)
			(end 0.12065 0.2794)
			(stroke
				(width 0.1)
				(type default)
			)
			(layer "B.Fab")
		)
		(fp_line
			(start 0.12065 0.2794)
			(end 0.12065 0.3048)
			(stroke
				(width 0.1)
				(type default)
			)
			(layer "B.Fab")
		)
		(fp_line
			(start -0.12065 -0.2794)
			(end -0.12065 -0.3048)
			(stroke
				(width 0.1)
				(type default)
			)
			(layer "B.Fab")
		)
		(fp_line
			(start 0.12065 -0.2794)
			(end -0.12065 -0.2794)
			(stroke
				(width 0.1)
				(type default)
			)
			(layer "B.Fab")
		)
		(fp_line
			(start -0.67945 -0.3048)
			(end -0.67945 0.3048)
			(stroke
				(width 0.1)
				(type default)
			)
			(layer "B.Fab")
		)
		(fp_line
			(start -0.12065 -0.3048)
			(end -0.67945 -0.3048)
			(stroke
				(width 0.1)
				(type default)
			)
			(layer "B.Fab")
		)
		(fp_line
			(start 0.12065 -0.305054)
			(end 0.12065 -0.2794)
			(stroke
				(width 0.1)
				(type default)
			)
			(layer "B.Fab")
		)
		(fp_line
			(start 0.67945 -0.305054)
			(end 0.12065 -0.305054)
			(stroke
				(width 0.1)
				(type default)
			)
			(layer "B.Fab")
		)
		(pad "1" smd circle
			(at 0.40005 0 90)
			(size 0 0)
			(layers "B.Cu" "B.Mask" "B.Paste")
			(net "P0V8_SERDES_VDDA_PEX3")
		)
		(pad "2" smd circle
			(at -0.40005 0 90)
			(size 0 0)
			(layers "B.Cu" "B.Mask" "B.Paste")
			(net "P0V8_SERDES_VDDA_PEX3_C9")
		)
	)
	(footprint ""
		(layer "B.Cu")
		(at 231.86771 -215.104218)
		(property "Reference" "C3606"
			(at 0 0 0)
			(layer "B.SilkS")
			(hide yes)
			(effects
				(font
					(size 1.27 1.27)
				)
				(justify mirror)
			)
		)
		(property "Value" ""
			(at 0 0 0)
			(layer "B.Fab")
			(effects
				(font
					(size 1.27 1.27)
				)
				(justify mirror)
			)
		)
		(duplicate_pad_numbers_are_jumpers no)
		(fp_line
			(start -0.69215 -0.2921)
			(end -0.69215 0.2921)
			(stroke
				(width 0.1524)
				(type default)
			)
			(layer "B.SilkS")
		)
		(fp_line
			(start -0.69215 0.2921)
			(end 0.69215 0.2921)
			(stroke
				(width 0.1524)
				(type default)
			)
			(layer "B.SilkS")
		)
		(fp_line
			(start 0.69215 -0.2921)
			(end -0.69215 -0.2921)
			(stroke
				(width 0.1524)
				(type default)
			)
			(layer "B.SilkS")
		)
		(fp_line
			(start 0.69215 0.2921)
			(end 0.69215 -0.2921)
			(stroke
				(width 0.1524)
				(type default)
			)
			(layer "B.SilkS")
		)
		(fp_line
			(start -0.51435 -0.2794)
			(end -0.51435 0.2794)
			(stroke
				(width 0.1)
				(type default)
			)
			(layer "B.Fab")
		)
		(fp_line
			(start -0.51435 0.2794)
			(end 0.51435 0.2794)
			(stroke
				(width 0.1)
				(type default)
			)
			(layer "B.Fab")
		)
		(fp_line
			(start 0.51435 -0.2794)
			(end -0.51435 -0.2794)
			(stroke
				(width 0.1)
				(type default)
			)
			(layer "B.Fab")
		)
		(fp_line
			(start 0.51435 0.2794)
			(end 0.51435 -0.2794)
			(stroke
				(width 0.1)
				(type default)
			)
			(layer "B.Fab")
		)
		(pad "1" smd circle
			(at 0.40005 0 180)
			(size 0 0)
			(layers "B.Cu" "B.Mask" "B.Paste")
			(net "P1V2_BIC_USB2AV12")
		)
		(pad "2" smd circle
			(at -0.40005 0 180)
			(size 0 0)
			(layers "B.Cu" "B.Mask" "B.Paste")
			(net "GND")
		)
		(zone
			(layer "B.Cu")
			(hatch none 0.5)
			(connect_pads
				(clearance 0)
			)
			(min_thickness 0.25)
			(keepout
				(tracks not_allowed)
				(vias allowed)
				(pads allowed)
				(copperpour not_allowed)
				(footprints allowed)
			)
			(placement
				(enabled no)
				(sheetname "")
			)
			(fill
				(thermal_gap 0.5)
				(thermal_bridge_width 0.5)
				(island_removal_mode 0)
			)
			(polygon
				(pts
					(xy 232.05821 -215.016588) (xy 231.96677 -214.958422) (xy 231.76738 -214.958422) (xy 231.67721 -215.016588)
					(xy 231.67721 -215.191848) (xy 231.76738 -215.250268) (xy 231.96677 -215.250268) (xy 232.05821 -215.192102)
				)
			)
		)
	)
	(footprint ""
		(layer "B.Cu")
		(at 24.711406 -223.315276 180)
		(property "Reference" "C2755"
			(at 0 0 0)
			(layer "B.SilkS")
			(hide yes)
			(effects
				(font
					(size 1.27 1.27)
				)
				(justify mirror)
			)
		)
		(property "Value" ""
			(at 0 0 0)
			(layer "B.Fab")
			(effects
				(font
					(size 1.27 1.27)
				)
				(justify mirror)
			)
		)
		(duplicate_pad_numbers_are_jumpers no)
		(fp_line
			(start 0.7874 0.4064)
			(end 0.7874 -0.4064)
			(stroke
				(width 0.1524)
				(type default)
			)
			(layer "B.SilkS")
		)
		(fp_line
			(start 0.7874 -0.4064)
			(end -0.7874 -0.4064)
			(stroke
				(width 0.1524)
				(type default)
			)
			(layer "B.SilkS")
		)
		(fp_line
			(start -0.7874 0.4064)
			(end 0.7874 0.4064)
			(stroke
				(width 0.1524)
				(type default)
			)
			(layer "B.SilkS")
		)
		(fp_line
			(start -0.7874 -0.4064)
			(end -0.7874 0.4064)
			(stroke
				(width 0.1524)
				(type default)
			)
			(layer "B.SilkS")
		)
		(fp_line
			(start 0.67945 0.3048)
			(end 0.67945 -0.305054)
			(stroke
				(width 0.1)
				(type default)
			)
			(layer "B.Fab")
		)
		(fp_line
			(start 0.67945 -0.305054)
			(end 0.12065 -0.305054)
			(stroke
				(width 0.1)
				(type default)
			)
			(layer "B.Fab")
		)
		(fp_line
			(start 0.12065 0.3048)
			(end 0.67945 0.3048)
			(stroke
				(width 0.1)
				(type default)
			)
			(layer "B.Fab")
		)
		(fp_line
			(start 0.12065 0.2794)
			(end 0.12065 0.3048)
			(stroke
				(width 0.1)
				(type default)
			)
			(layer "B.Fab")
		)
		(fp_line
			(start 0.12065 -0.2794)
			(end -0.12065 -0.2794)
			(stroke
				(width 0.1)
				(type default)
			)
			(layer "B.Fab")
		)
		(fp_line
			(start 0.12065 -0.305054)
			(end 0.12065 -0.2794)
			(stroke
				(width 0.1)
				(type default)
			)
			(layer "B.Fab")
		)
		(fp_line
			(start -0.120396 0.3048)
			(end -0.120396 0.2794)
			(stroke
				(width 0.1)
				(type default)
			)
			(layer "B.Fab")
		)
		(fp_line
			(start -0.120396 0.2794)
			(end 0.12065 0.2794)
			(stroke
				(width 0.1)
				(type default)
			)
			(layer "B.Fab")
		)
		(fp_line
			(start -0.12065 -0.2794)
			(end -0.12065 -0.3048)
			(stroke
				(width 0.1)
				(type default)
			)
			(layer "B.Fab")
		)
		(fp_line
			(start -0.12065 -0.3048)
			(end -0.67945 -0.3048)
			(stroke
				(width 0.1)
				(type default)
			)
			(layer "B.Fab")
		)
		(fp_line
			(start -0.67945 0.3048)
			(end -0.120396 0.3048)
			(stroke
				(width 0.1)
				(type default)
			)
			(layer "B.Fab")
		)
		(fp_line
			(start -0.67945 -0.3048)
			(end -0.67945 0.3048)
			(stroke
				(width 0.1)
				(type default)
			)
			(layer "B.Fab")
		)
		(pad "1" smd circle
			(at 0.40005 0)
			(size 0 0)
			(layers "B.Cu" "B.Mask" "B.Paste")
			(net "GND")
		)
		(pad "2" smd circle
			(at -0.40005 0)
			(size 0 0)
			(layers "B.Cu" "B.Mask" "B.Paste")
			(net "P1V8_PEX")
		)
	)
	(footprint ""
		(layer "B.Cu")
		(at 238.538766 -214.3633)
		(property "Reference" "L146"
			(at 0 0 0)
			(layer "B.SilkS")
			(hide yes)
			(effects
				(font
					(size 1.27 1.27)
				)
				(justify mirror)
			)
		)
		(property "Value" ""
			(at 0 0 0)
			(layer "B.Fab")
			(effects
				(font
					(size 1.27 1.27)
				)
				(justify mirror)
			)
		)
		(duplicate_pad_numbers_are_jumpers no)
		(fp_line
			(start -1.27 0.5842)
			(end -1.27 -0.5842)
			(stroke
				(width 0.1524)
				(type default)
			)
			(layer "B.SilkS")
		)
		(fp_line
			(start -1.27 0.5842)
			(end 1.27 0.5842)
			(stroke
				(width 0.1524)
				(type default)
			)
			(layer "B.SilkS")
		)
		(fp_line
			(start 1.27 -0.5842)
			(end -1.27 -0.5842)
			(stroke
				(width 0.1524)
				(type default)
			)
			(layer "B.SilkS")
		)
		(fp_line
			(start 1.27 -0.5588)
			(end 1.27 -0.5842)
			(stroke
				(width 0.1524)
				(type default)
			)
			(layer "B.SilkS")
		)
		(fp_line
			(start 1.27 0.5842)
			(end 1.27 -0.5842)
			(stroke
				(width 0.1524)
				(type default)
			)
			(layer "B.SilkS")
		)
		(fp_line
			(start -1.1938 -0.406654)
			(end -1.1938 0.4064)
			(stroke
				(width 0.1)
				(type default)
			)
			(layer "B.Fab")
		)
		(fp_line
			(start -1.1938 0.4064)
			(end -0.9144 0.4064)
			(stroke
				(width 0.1)
				(type default)
			)
			(layer "B.Fab")
		)
		(fp_line
			(start -0.9144 -0.508)
			(end -0.9144 -0.406654)
			(stroke
				(width 0.1)
				(type default)
			)
			(layer "B.Fab")
		)
		(fp_line
			(start -0.9144 -0.406654)
			(end -1.1938 -0.406654)
			(stroke
				(width 0.1)
				(type default)
			)
			(layer "B.Fab")
		)
		(fp_line
			(start -0.9144 0.4064)
			(end -0.9144 0.508)
			(stroke
				(width 0.1)
				(type default)
			)
			(layer "B.Fab")
		)
		(fp_line
			(start -0.9144 0.508)
			(end 0.9144 0.508)
			(stroke
				(width 0.1)
				(type default)
			)
			(layer "B.Fab")
		)
		(fp_line
			(start 0.9144 -0.508)
			(end -0.9144 -0.508)
			(stroke
				(width 0.1)
				(type default)
			)
			(layer "B.Fab")
		)
		(fp_line
			(start 0.9144 -0.406654)
			(end 0.9144 -0.508)
			(stroke
				(width 0.1)
				(type default)
			)
			(layer "B.Fab")
		)
		(fp_line
			(start 0.9144 0.406654)
			(end 1.194308 0.406654)
			(stroke
				(width 0.1)
				(type default)
			)
			(layer "B.Fab")
		)
		(fp_line
			(start 0.9144 0.508)
			(end 0.9144 0.406654)
			(stroke
				(width 0.1)
				(type default)
			)
			(layer "B.Fab")
		)
		(fp_line
			(start 1.194308 -0.406654)
			(end 0.9144 -0.406654)
			(stroke
				(width 0.1)
				(type default)
			)
			(layer "B.Fab")
		)
		(fp_line
			(start 1.194308 0.406654)
			(end 1.194308 -0.406654)
			(stroke
				(width 0.1)
				(type default)
			)
			(layer "B.Fab")
		)
		(pad "1" smd rect
			(at 0.7366 0 270)
			(size 0.7112 0.8128)
			(layers "B.Cu" "B.Mask" "B.Paste")
			(net "P1V2_AUX")
		)
		(pad "2" smd rect
			(at -0.7366 0 270)
			(size 0.7112 0.8128)
			(layers "B.Cu" "B.Mask" "B.Paste")
			(net "P1V2_BIC_USB2AV12")
		)
	)
	(footprint ""
		(layer "B.Cu")
		(at 102.732586 -344.563954 90)
		(property "Reference" "R6367"
			(at 0 0 90)
			(layer "B.SilkS")
			(hide yes)
			(effects
				(font
					(size 1.27 1.27)
				)
				(justify mirror)
			)
		)
		(property "Value" ""
			(at 0 0 90)
			(layer "B.Fab")
			(effects
				(font
					(size 1.27 1.27)
				)
				(justify mirror)
			)
		)
		(duplicate_pad_numbers_are_jumpers no)
		(fp_line
			(start 0.7874 -0.4064)
			(end -0.7874 -0.4064)
			(stroke
				(width 0.1524)
				(type default)
			)
			(layer "B.SilkS")
		)
		(fp_line
			(start -0.7874 -0.4064)
			(end -0.7874 0.4064)
			(stroke
				(width 0.1524)
				(type default)
			)
			(layer "B.SilkS")
		)
		(fp_line
			(start 0.7874 0.4064)
			(end 0.7874 -0.4064)
			(stroke
				(width 0.1524)
				(type default)
			)
			(layer "B.SilkS")
		)
		(fp_line
			(start -0.7874 0.4064)
			(end 0.7874 0.4064)
			(stroke
				(width 0.1524)
				(type default)
			)
			(layer "B.SilkS")
		)
		(fp_line
			(start 0.67945 -0.305054)
			(end 0.12065 -0.305054)
			(stroke
				(width 0.1)
				(type default)
			)
			(layer "B.Fab")
		)
		(fp_line
			(start 0.12065 -0.305054)
			(end 0.12065 -0.2794)
			(stroke
				(width 0.1)
				(type default)
			)
			(layer "B.Fab")
		)
		(fp_line
			(start -0.12065 -0.3048)
			(end -0.67945 -0.3048)
			(stroke
				(width 0.1)
				(type default)
			)
			(layer "B.Fab")
		)
		(fp_line
			(start -0.67945 -0.3048)
			(end -0.67945 0.3048)
			(stroke
				(width 0.1)
				(type default)
			)
			(layer "B.Fab")
		)
		(fp_line
			(start 0.12065 -0.2794)
			(end -0.12065 -0.2794)
			(stroke
				(width 0.1)
				(type default)
			)
			(layer "B.Fab")
		)
		(fp_line
			(start -0.12065 -0.2794)
			(end -0.12065 -0.3048)
			(stroke
				(width 0.1)
				(type default)
			)
			(layer "B.Fab")
		)
		(fp_line
			(start 0.12065 0.2794)
			(end 0.12065 0.3048)
			(stroke
				(width 0.1)
				(type default)
			)
			(layer "B.Fab")
		)
		(fp_line
			(start -0.120396 0.2794)
			(end 0.12065 0.2794)
			(stroke
				(width 0.1)
				(type default)
			)
			(layer "B.Fab")
		)
		(fp_line
			(start 0.67945 0.3048)
			(end 0.67945 -0.305054)
			(stroke
				(width 0.1)
				(type default)
			)
			(layer "B.Fab")
		)
		(fp_line
			(start 0.12065 0.3048)
			(end 0.67945 0.3048)
			(stroke
				(width 0.1)
				(type default)
			)
			(layer "B.Fab")
		)
		(fp_line
			(start -0.120396 0.3048)
			(end -0.120396 0.2794)
			(stroke
				(width 0.1)
				(type default)
			)
			(layer "B.Fab")
		)
		(fp_line
			(start -0.67945 0.3048)
			(end -0.120396 0.3048)
			(stroke
				(width 0.1)
				(type default)
			)
			(layer "B.Fab")
		)
		(pad "1" smd circle
			(at 0.40005 0 270)
			(size 0 0)
			(layers "B.Cu" "B.Mask" "B.Paste")
			(net "CLK_100M_MB_1_R_DN")
		)
		(pad "2" smd circle
			(at -0.40005 0 270)
			(size 0 0)
			(layers "B.Cu" "B.Mask" "B.Paste")
			(net "CLK_100M_MB_1_DN")
		)
	)
	(footprint ""
		(layer "B.Cu")
		(at 73.400158 -109.251496)
		(property "Reference" "C864"
			(at 0 0 0)
			(layer "B.SilkS")
			(hide yes)
			(effects
				(font
					(size 1.27 1.27)
				)
				(justify mirror)
			)
		)
		(property "Value" ""
			(at 0 0 0)
			(layer "B.Fab")
			(effects
				(font
					(size 1.27 1.27)
				)
				(justify mirror)
			)
		)
		(duplicate_pad_numbers_are_jumpers no)
		(fp_line
			(start -0.299974 -0.150114)
			(end -0.299974 0.150114)
			(stroke
				(width 0.1)
				(type default)
			)
			(layer "B.Fab")
		)
		(fp_line
			(start -0.299974 0.150114)
			(end 0.299974 0.150114)
			(stroke
				(width 0.1)
				(type default)
			)
			(layer "B.Fab")
		)
		(fp_line
			(start 0.299974 -0.150114)
			(end -0.299974 -0.150114)
			(stroke
				(width 0.1)
				(type default)
			)
			(layer "B.Fab")
		)
		(fp_line
			(start 0.299974 0.150114)
			(end 0.299974 -0.150114)
			(stroke
				(width 0.1)
				(type default)
			)
			(layer "B.Fab")
		)
		(pad "1" smd rect
			(at 0.2667 0 180)
			(size 0.3048 0.381)
			(layers "B.Cu" "B.Mask" "B.Paste")
			(net "P12V_NIC1")
		)
		(pad "2" smd rect
			(at -0.2667 0 180)
			(size 0.3048 0.381)
			(layers "B.Cu" "B.Mask" "B.Paste")
			(net "GND")
		)
	)
	(footprint ""
		(layer "B.Cu")
		(at 360.919014 -308.677818 90)
		(property "Reference" "C4376"
			(at 0 0 90)
			(layer "B.SilkS")
			(hide yes)
			(effects
				(font
					(size 1.27 1.27)
				)
				(justify mirror)
			)
		)
		(property "Value" ""
			(at 0 0 90)
			(layer "B.Fab")
			(effects
				(font
					(size 1.27 1.27)
				)
				(justify mirror)
			)
		)
		(duplicate_pad_numbers_are_jumpers no)
		(fp_line
			(start 0.299974 -0.150114)
			(end -0.299974 -0.150114)
			(stroke
				(width 0.1)
				(type default)
			)
			(layer "B.Fab")
		)
		(fp_line
			(start -0.299974 -0.150114)
			(end -0.299974 0.150114)
			(stroke
				(width 0.1)
				(type default)
			)
			(layer "B.Fab")
		)
		(fp_line
			(start 0.299974 0.150114)
			(end 0.299974 -0.150114)
			(stroke
				(width 0.1)
				(type default)
			)
			(layer "B.Fab")
		)
		(fp_line
			(start -0.299974 0.150114)
			(end 0.299974 0.150114)
			(stroke
				(width 0.1)
				(type default)
			)
			(layer "B.Fab")
		)
		(pad "1" smd rect
			(at 0.2667 0 270)
			(size 0.3048 0.381)
			(layers "B.Cu" "B.Mask" "B.Paste")
			(net "P0V8_PEX3")
		)
		(pad "2" smd rect
			(at -0.2667 0 270)
			(size 0.3048 0.381)
			(layers "B.Cu" "B.Mask" "B.Paste")
			(net "GND")
		)
	)
	(footprint ""
		(layer "B.Cu")
		(at 102.25913 -308.42966 90)
		(property "Reference" "C4201"
			(at 0 0 90)
			(layer "B.SilkS")
			(hide yes)
			(effects
				(font
					(size 1.27 1.27)
				)
				(justify mirror)
			)
		)
		(property "Value" ""
			(at 0 0 90)
			(layer "B.Fab")
			(effects
				(font
					(size 1.27 1.27)
				)
				(justify mirror)
			)
		)
		(duplicate_pad_numbers_are_jumpers no)
		(fp_line
			(start 0.299974 -0.150114)
			(end -0.299974 -0.150114)
			(stroke
				(width 0.1)
				(type default)
			)
			(layer "B.Fab")
		)
		(fp_line
			(start -0.299974 -0.150114)
			(end -0.299974 0.150114)
			(stroke
				(width 0.1)
				(type default)
			)
			(layer "B.Fab")
		)
		(fp_line
			(start 0.299974 0.150114)
			(end 0.299974 -0.150114)
			(stroke
				(width 0.1)
				(type default)
			)
			(layer "B.Fab")
		)
		(fp_line
			(start -0.299974 0.150114)
			(end 0.299974 0.150114)
			(stroke
				(width 0.1)
				(type default)
			)
			(layer "B.Fab")
		)
		(pad "1" smd rect
			(at 0.2667 0 270)
			(size 0.3048 0.381)
			(layers "B.Cu" "B.Mask" "B.Paste")
			(net "P0V8_PEX0")
		)
		(pad "2" smd rect
			(at -0.2667 0 270)
			(size 0.3048 0.381)
			(layers "B.Cu" "B.Mask" "B.Paste")
			(net "GND")
		)
	)
	(footprint ""
		(layer "B.Cu")
		(at 179.07508 -305.399948 -90)
		(property "Reference" "C3139"
			(at 0 0 90)
			(layer "B.SilkS")
			(hide yes)
			(effects
				(font
					(size 1.27 1.27)
				)
				(justify mirror)
			)
		)
		(property "Value" ""
			(at 0 0 90)
			(layer "B.Fab")
			(effects
				(font
					(size 1.27 1.27)
				)
				(justify mirror)
			)
		)
		(duplicate_pad_numbers_are_jumpers no)
		(fp_line
			(start -0.299974 0.150114)
			(end 0.299974 0.150114)
			(stroke
				(width 0.1)
				(type default)
			)
			(layer "B.Fab")
		)
		(fp_line
			(start 0.299974 0.150114)
			(end 0.299974 -0.150114)
			(stroke
				(width 0.1)
				(type default)
			)
			(layer "B.Fab")
		)
		(fp_line
			(start -0.299974 -0.150114)
			(end -0.299974 0.150114)
			(stroke
				(width 0.1)
				(type default)
			)
			(layer "B.Fab")
		)
		(fp_line
			(start 0.299974 -0.150114)
			(end -0.299974 -0.150114)
			(stroke
				(width 0.1)
				(type default)
			)
			(layer "B.Fab")
		)
		(pad "1" smd rect
			(at 0.2667 0 90)
			(size 0.3048 0.381)
			(layers "B.Cu" "B.Mask" "B.Paste")
			(net "P1V25_SERDES_VDDPLL_PEX1")
		)
		(pad "2" smd rect
			(at -0.2667 0 90)
			(size 0.3048 0.381)
			(layers "B.Cu" "B.Mask" "B.Paste")
			(net "GND")
		)
	)
	(footprint ""
		(layer "B.Cu")
		(at 185.04154 -286.874966)
		(property "Reference" "C3171"
			(at 0 0 0)
			(layer "B.SilkS")
			(hide yes)
			(effects
				(font
					(size 1.27 1.27)
				)
				(justify mirror)
			)
		)
		(property "Value" ""
			(at 0 0 0)
			(layer "B.Fab")
			(effects
				(font
					(size 1.27 1.27)
				)
				(justify mirror)
			)
		)
		(duplicate_pad_numbers_are_jumpers no)
		(fp_line
			(start -0.299974 -0.150114)
			(end -0.299974 0.150114)
			(stroke
				(width 0.1)
				(type default)
			)
			(layer "B.Fab")
		)
		(fp_line
			(start -0.299974 0.150114)
			(end 0.299974 0.150114)
			(stroke
				(width 0.1)
				(type default)
			)
			(layer "B.Fab")
		)
		(fp_line
			(start 0.299974 -0.150114)
			(end -0.299974 -0.150114)
			(stroke
				(width 0.1)
				(type default)
			)
			(layer "B.Fab")
		)
		(fp_line
			(start 0.299974 0.150114)
			(end 0.299974 -0.150114)
			(stroke
				(width 0.1)
				(type default)
			)
			(layer "B.Fab")
		)
		(pad "1" smd rect
			(at 0.2667 0 180)
			(size 0.3048 0.381)
			(layers "B.Cu" "B.Mask" "B.Paste")
			(net "P1V8_VDDA_PEX1")
		)
		(pad "2" smd rect
			(at -0.2667 0 180)
			(size 0.3048 0.381)
			(layers "B.Cu" "B.Mask" "B.Paste")
			(net "GND")
		)
	)
	(footprint ""
		(layer "B.Cu")
		(at 189.500002 -111.791496)
		(property "Reference" "C892"
			(at 0 0 0)
			(layer "B.SilkS")
			(hide yes)
			(effects
				(font
					(size 1.27 1.27)
				)
				(justify mirror)
			)
		)
		(property "Value" ""
			(at 0 0 0)
			(layer "B.Fab")
			(effects
				(font
					(size 1.27 1.27)
				)
				(justify mirror)
			)
		)
		(duplicate_pad_numbers_are_jumpers no)
		(fp_line
			(start -0.299974 -0.150114)
			(end -0.299974 0.150114)
			(stroke
				(width 0.1)
				(type default)
			)
			(layer "B.Fab")
		)
		(fp_line
			(start -0.299974 0.150114)
			(end 0.299974 0.150114)
			(stroke
				(width 0.1)
				(type default)
			)
			(layer "B.Fab")
		)
		(fp_line
			(start 0.299974 -0.150114)
			(end -0.299974 -0.150114)
			(stroke
				(width 0.1)
				(type default)
			)
			(layer "B.Fab")
		)
		(fp_line
			(start 0.299974 0.150114)
			(end 0.299974 -0.150114)
			(stroke
				(width 0.1)
				(type default)
			)
			(layer "B.Fab")
		)
		(pad "1" smd rect
			(at 0.2667 0 180)
			(size 0.3048 0.381)
			(layers "B.Cu" "B.Mask" "B.Paste")
			(net "P12V_NIC3")
		)
		(pad "2" smd rect
			(at -0.2667 0 180)
			(size 0.3048 0.381)
			(layers "B.Cu" "B.Mask" "B.Paste")
			(net "GND")
		)
	)
	(footprint ""
		(layer "B.Cu")
		(at 219.92082 -220.762068)
		(property "Reference" "R6802"
			(at 0 0 0)
			(layer "B.SilkS")
			(hide yes)
			(effects
				(font
					(size 1.27 1.27)
				)
				(justify mirror)
			)
		)
		(property "Value" ""
			(at 0 0 0)
			(layer "B.Fab")
			(effects
				(font
					(size 1.27 1.27)
				)
				(justify mirror)
			)
		)
		(duplicate_pad_numbers_are_jumpers no)
		(fp_line
			(start -0.7874 -0.4064)
			(end -0.7874 0.4064)
			(stroke
				(width 0.1524)
				(type default)
			)
			(layer "B.SilkS")
		)
		(fp_line
			(start -0.7874 0.4064)
			(end 0.7874 0.4064)
			(stroke
				(width 0.1524)
				(type default)
			)
			(layer "B.SilkS")
		)
		(fp_line
			(start 0.7874 -0.4064)
			(end -0.7874 -0.4064)
			(stroke
				(width 0.1524)
				(type default)
			)
			(layer "B.SilkS")
		)
		(fp_line
			(start 0.7874 0.4064)
			(end 0.7874 -0.4064)
			(stroke
				(width 0.1524)
				(type default)
			)
			(layer "B.SilkS")
		)
		(fp_line
			(start -0.67945 -0.3048)
			(end -0.67945 0.3048)
			(stroke
				(width 0.1)
				(type default)
			)
			(layer "B.Fab")
		)
		(fp_line
			(start -0.67945 0.3048)
			(end -0.120396 0.3048)
			(stroke
				(width 0.1)
				(type default)
			)
			(layer "B.Fab")
		)
		(fp_line
			(start -0.12065 -0.3048)
			(end -0.67945 -0.3048)
			(stroke
				(width 0.1)
				(type default)
			)
			(layer "B.Fab")
		)
		(fp_line
			(start -0.12065 -0.2794)
			(end -0.12065 -0.3048)
			(stroke
				(width 0.1)
				(type default)
			)
			(layer "B.Fab")
		)
		(fp_line
			(start -0.120396 0.2794)
			(end 0.12065 0.2794)
			(stroke
				(width 0.1)
				(type default)
			)
			(layer "B.Fab")
		)
		(fp_line
			(start -0.120396 0.3048)
			(end -0.120396 0.2794)
			(stroke
				(width 0.1)
				(type default)
			)
			(layer "B.Fab")
		)
		(fp_line
			(start 0.12065 -0.305054)
			(end 0.12065 -0.2794)
			(stroke
				(width 0.1)
				(type default)
			)
			(layer "B.Fab")
		)
		(fp_line
			(start 0.12065 -0.2794)
			(end -0.12065 -0.2794)
			(stroke
				(width 0.1)
				(type default)
			)
			(layer "B.Fab")
		)
		(fp_line
			(start 0.12065 0.2794)
			(end 0.12065 0.3048)
			(stroke
				(width 0.1)
				(type default)
			)
			(layer "B.Fab")
		)
		(fp_line
			(start 0.12065 0.3048)
			(end 0.67945 0.3048)
			(stroke
				(width 0.1)
				(type default)
			)
			(layer "B.Fab")
		)
		(fp_line
			(start 0.67945 -0.305054)
			(end 0.12065 -0.305054)
			(stroke
				(width 0.1)
				(type default)
			)
			(layer "B.Fab")
		)
		(fp_line
			(start 0.67945 0.3048)
			(end 0.67945 -0.305054)
			(stroke
				(width 0.1)
				(type default)
			)
			(layer "B.Fab")
		)
		(pad "1" smd circle
			(at 0.40005 0 180)
			(size 0 0)
			(layers "B.Cu" "B.Mask" "B.Paste")
			(net "SMB_BIC_FPGA_R2_SCL")
		)
		(pad "2" smd circle
			(at -0.40005 0 180)
			(size 0 0)
			(layers "B.Cu" "B.Mask" "B.Paste")
			(net "SMB_BIC_FPGA_SCL")
		)
	)
	(footprint ""
		(layer "B.Cu")
		(at 146.685254 -207.784192 -90)
		(property "Reference" "R981"
			(at 0 0 90)
			(layer "B.SilkS")
			(hide yes)
			(effects
				(font
					(size 1.27 1.27)
				)
				(justify mirror)
			)
		)
		(property "Value" ""
			(at 0 0 90)
			(layer "B.Fab")
			(effects
				(font
					(size 1.27 1.27)
				)
				(justify mirror)
			)
		)
		(duplicate_pad_numbers_are_jumpers no)
		(fp_line
			(start -0.7874 0.4064)
			(end 0.7874 0.4064)
			(stroke
				(width 0.1524)
				(type default)
			)
			(layer "B.SilkS")
		)
		(fp_line
			(start 0.7874 0.4064)
			(end 0.7874 -0.4064)
			(stroke
				(width 0.1524)
				(type default)
			)
			(layer "B.SilkS")
		)
		(fp_line
			(start -0.7874 -0.4064)
			(end -0.7874 0.4064)
			(stroke
				(width 0.1524)
				(type default)
			)
			(layer "B.SilkS")
		)
		(fp_line
			(start 0.7874 -0.4064)
			(end -0.7874 -0.4064)
			(stroke
				(width 0.1524)
				(type default)
			)
			(layer "B.SilkS")
		)
		(fp_line
			(start -0.67945 0.3048)
			(end -0.120396 0.3048)
			(stroke
				(width 0.1)
				(type default)
			)
			(layer "B.Fab")
		)
		(fp_line
			(start -0.120396 0.3048)
			(end -0.120396 0.2794)
			(stroke
				(width 0.1)
				(type default)
			)
			(layer "B.Fab")
		)
		(fp_line
			(start 0.12065 0.3048)
			(end 0.67945 0.3048)
			(stroke
				(width 0.1)
				(type default)
			)
			(layer "B.Fab")
		)
		(fp_line
			(start 0.67945 0.3048)
			(end 0.67945 -0.305054)
			(stroke
				(width 0.1)
				(type default)
			)
			(layer "B.Fab")
		)
		(fp_line
			(start -0.120396 0.2794)
			(end 0.12065 0.2794)
			(stroke
				(width 0.1)
				(type default)
			)
			(layer "B.Fab")
		)
		(fp_line
			(start 0.12065 0.2794)
			(end 0.12065 0.3048)
			(stroke
				(width 0.1)
				(type default)
			)
			(layer "B.Fab")
		)
		(fp_line
			(start -0.12065 -0.2794)
			(end -0.12065 -0.3048)
			(stroke
				(width 0.1)
				(type default)
			)
			(layer "B.Fab")
		)
		(fp_line
			(start 0.12065 -0.2794)
			(end -0.12065 -0.2794)
			(stroke
				(width 0.1)
				(type default)
			)
			(layer "B.Fab")
		)
		(fp_line
			(start -0.67945 -0.3048)
			(end -0.67945 0.3048)
			(stroke
				(width 0.1)
				(type default)
			)
			(layer "B.Fab")
		)
		(fp_line
			(start -0.12065 -0.3048)
			(end -0.67945 -0.3048)
			(stroke
				(width 0.1)
				(type default)
			)
			(layer "B.Fab")
		)
		(fp_line
			(start 0.12065 -0.305054)
			(end 0.12065 -0.2794)
			(stroke
				(width 0.1)
				(type default)
			)
			(layer "B.Fab")
		)
		(fp_line
			(start 0.67945 -0.305054)
			(end 0.12065 -0.305054)
			(stroke
				(width 0.1)
				(type default)
			)
			(layer "B.Fab")
		)
		(pad "1" smd circle
			(at 0.40005 0 90)
			(size 0 0)
			(layers "B.Cu" "B.Mask" "B.Paste")
			(net "UART_PEX1_CLI_BUF_R_RX")
		)
		(pad "2" smd circle
			(at -0.40005 0 90)
			(size 0 0)
			(layers "B.Cu" "B.Mask" "B.Paste")
			(net "UART_PEX1_CLI_BUF_RX")
		)
	)
	(footprint ""
		(layer "B.Cu")
		(at 405.100028 -299.699934 -90)
		(property "Reference" "C1973"
			(at 0 0 90)
			(layer "B.SilkS")
			(hide yes)
			(effects
				(font
					(size 1.27 1.27)
				)
				(justify mirror)
			)
		)
		(property "Value" ""
			(at 0 0 90)
			(layer "B.Fab")
			(effects
				(font
					(size 1.27 1.27)
				)
				(justify mirror)
			)
		)
		(duplicate_pad_numbers_are_jumpers no)
		(fp_line
			(start -0.299974 0.150114)
			(end 0.299974 0.150114)
			(stroke
				(width 0.1)
				(type default)
			)
			(layer "B.Fab")
		)
		(fp_line
			(start 0.299974 0.150114)
			(end 0.299974 -0.150114)
			(stroke
				(width 0.1)
				(type default)
			)
			(layer "B.Fab")
		)
		(fp_line
			(start -0.299974 -0.150114)
			(end -0.299974 0.150114)
			(stroke
				(width 0.1)
				(type default)
			)
			(layer "B.Fab")
		)
		(fp_line
			(start 0.299974 -0.150114)
			(end -0.299974 -0.150114)
			(stroke
				(width 0.1)
				(type default)
			)
			(layer "B.Fab")
		)
		(pad "1" smd rect
			(at 0.2667 0 90)
			(size 0.3048 0.381)
			(layers "B.Cu" "B.Mask" "B.Paste")
			(net "P0V8_SERDES_VDDA_PEX3")
		)
		(pad "2" smd rect
			(at -0.2667 0 90)
			(size 0.3048 0.381)
			(layers "B.Cu" "B.Mask" "B.Paste")
			(net "GND")
		)
	)
	(footprint ""
		(layer "B.Cu")
		(at 12.709398 -270.452596 180)
		(property "Reference" "C4221"
			(at 0 0 0)
			(layer "B.SilkS")
			(hide yes)
			(effects
				(font
					(size 1.27 1.27)
				)
				(justify mirror)
			)
		)
		(property "Value" ""
			(at 0 0 0)
			(layer "B.Fab")
			(effects
				(font
					(size 1.27 1.27)
				)
				(justify mirror)
			)
		)
		(duplicate_pad_numbers_are_jumpers no)
		(fp_line
			(start 1.2954 0.5842)
			(end 1.2954 -0.5842)
			(stroke
				(width 0.1524)
				(type default)
			)
			(layer "B.SilkS")
		)
		(fp_line
			(start 1.2954 -0.5842)
			(end -1.2954 -0.5842)
			(stroke
				(width 0.1524)
				(type default)
			)
			(layer "B.SilkS")
		)
		(fp_line
			(start -1.2954 0.5842)
			(end 1.2954 0.5842)
			(stroke
				(width 0.1524)
				(type default)
			)
			(layer "B.SilkS")
		)
		(fp_line
			(start -1.2954 -0.5842)
			(end -1.2954 0.5842)
			(stroke
				(width 0.1524)
				(type default)
			)
			(layer "B.SilkS")
		)
		(fp_line
			(start 1.1938 0.4064)
			(end 1.1938 -0.4064)
			(stroke
				(width 0.1)
				(type default)
			)
			(layer "B.Fab")
		)
		(fp_line
			(start 1.1938 -0.4064)
			(end 0.8636 -0.4064)
			(stroke
				(width 0.1)
				(type default)
			)
			(layer "B.Fab")
		)
		(fp_line
			(start 0.8636 0.4572)
			(end 0.8636 0.4064)
			(stroke
				(width 0.1)
				(type default)
			)
			(layer "B.Fab")
		)
		(fp_line
			(start 0.8636 0.4064)
			(end 1.1938 0.4064)
			(stroke
				(width 0.1)
				(type default)
			)
			(layer "B.Fab")
		)
		(fp_line
			(start 0.8636 -0.4064)
			(end 0.8636 -0.4572)
			(stroke
				(width 0.1)
				(type default)
			)
			(layer "B.Fab")
		)
		(fp_line
			(start 0.8636 -0.4572)
			(end -0.8636 -0.4572)
			(stroke
				(width 0.1)
				(type default)
			)
			(layer "B.Fab")
		)
		(fp_line
			(start -0.8636 0.4572)
			(end 0.8636 0.4572)
			(stroke
				(width 0.1)
				(type default)
			)
			(layer "B.Fab")
		)
		(fp_line
			(start -0.8636 0.4064)
			(end -0.8636 0.4572)
			(stroke
				(width 0.1)
				(type default)
			)
			(layer "B.Fab")
		)
		(fp_line
			(start -0.8636 -0.4064)
			(end -1.1938 -0.4064)
			(stroke
				(width 0.1)
				(type default)
			)
			(layer "B.Fab")
		)
		(fp_line
			(start -0.8636 -0.4572)
			(end -0.8636 -0.4064)
			(stroke
				(width 0.1)
				(type default)
			)
			(layer "B.Fab")
		)
		(fp_line
			(start -1.1938 0.4064)
			(end -0.8636 0.4064)
			(stroke
				(width 0.1)
				(type default)
			)
			(layer "B.Fab")
		)
		(fp_line
			(start -1.1938 -0.4064)
			(end -1.1938 0.4064)
			(stroke
				(width 0.1)
				(type default)
			)
			(layer "B.Fab")
		)
		(pad "1" smd rect
			(at 0.7366 0 90)
			(size 0.7112 0.8128)
			(layers "B.Cu" "B.Mask" "B.Paste")
			(net "P1V25_PEX0")
		)
		(pad "2" smd rect
			(at -0.7366 0 90)
			(size 0.7112 0.8128)
			(layers "B.Cu" "B.Mask" "B.Paste")
			(net "GND")
		)
	)
	(footprint ""
		(layer "B.Cu")
		(at 213.706456 -226.441762 180)
		(property "Reference" "R4871"
			(at 0 0 0)
			(layer "B.SilkS")
			(hide yes)
			(effects
				(font
					(size 1.27 1.27)
				)
				(justify mirror)
			)
		)
		(property "Value" ""
			(at 0 0 0)
			(layer "B.Fab")
			(effects
				(font
					(size 1.27 1.27)
				)
				(justify mirror)
			)
		)
		(duplicate_pad_numbers_are_jumpers no)
		(fp_line
			(start 0.7874 0.4064)
			(end 0.7874 -0.4064)
			(stroke
				(width 0.1524)
				(type default)
			)
			(layer "B.SilkS")
		)
		(fp_line
			(start 0.7874 -0.4064)
			(end -0.7874 -0.4064)
			(stroke
				(width 0.1524)
				(type default)
			)
			(layer "B.SilkS")
		)
		(fp_line
			(start -0.7874 0.4064)
			(end 0.7874 0.4064)
			(stroke
				(width 0.1524)
				(type default)
			)
			(layer "B.SilkS")
		)
		(fp_line
			(start -0.7874 -0.4064)
			(end -0.7874 0.4064)
			(stroke
				(width 0.1524)
				(type default)
			)
			(layer "B.SilkS")
		)
		(fp_line
			(start 0.67945 0.3048)
			(end 0.67945 -0.305054)
			(stroke
				(width 0.1)
				(type default)
			)
			(layer "B.Fab")
		)
		(fp_line
			(start 0.67945 -0.305054)
			(end 0.12065 -0.305054)
			(stroke
				(width 0.1)
				(type default)
			)
			(layer "B.Fab")
		)
		(fp_line
			(start 0.12065 0.3048)
			(end 0.67945 0.3048)
			(stroke
				(width 0.1)
				(type default)
			)
			(layer "B.Fab")
		)
		(fp_line
			(start 0.12065 0.2794)
			(end 0.12065 0.3048)
			(stroke
				(width 0.1)
				(type default)
			)
			(layer "B.Fab")
		)
		(fp_line
			(start 0.12065 -0.2794)
			(end -0.12065 -0.2794)
			(stroke
				(width 0.1)
				(type default)
			)
			(layer "B.Fab")
		)
		(fp_line
			(start 0.12065 -0.305054)
			(end 0.12065 -0.2794)
			(stroke
				(width 0.1)
				(type default)
			)
			(layer "B.Fab")
		)
		(fp_line
			(start -0.120396 0.3048)
			(end -0.120396 0.2794)
			(stroke
				(width 0.1)
				(type default)
			)
			(layer "B.Fab")
		)
		(fp_line
			(start -0.120396 0.2794)
			(end 0.12065 0.2794)
			(stroke
				(width 0.1)
				(type default)
			)
			(layer "B.Fab")
		)
		(fp_line
			(start -0.12065 -0.2794)
			(end -0.12065 -0.3048)
			(stroke
				(width 0.1)
				(type default)
			)
			(layer "B.Fab")
		)
		(fp_line
			(start -0.12065 -0.3048)
			(end -0.67945 -0.3048)
			(stroke
				(width 0.1)
				(type default)
			)
			(layer "B.Fab")
		)
		(fp_line
			(start -0.67945 0.3048)
			(end -0.120396 0.3048)
			(stroke
				(width 0.1)
				(type default)
			)
			(layer "B.Fab")
		)
		(fp_line
			(start -0.67945 -0.3048)
			(end -0.67945 0.3048)
			(stroke
				(width 0.1)
				(type default)
			)
			(layer "B.Fab")
		)
		(pad "1" smd circle
			(at 0.40005 0)
			(size 0 0)
			(layers "B.Cu" "B.Mask" "B.Paste")
			(net "P3V3_AUX")
		)
		(pad "2" smd circle
			(at -0.40005 0)
			(size 0 0)
			(layers "B.Cu" "B.Mask" "B.Paste")
			(net "SMB_FIO_SCL")
		)
	)
	(footprint ""
		(layer "B.Cu")
		(at 278.064214 -143.608552 180)
		(property "Reference" "C908"
			(at 0 0 0)
			(layer "B.SilkS")
			(hide yes)
			(effects
				(font
					(size 1.27 1.27)
				)
				(justify mirror)
			)
		)
		(property "Value" ""
			(at 0 0 0)
			(layer "B.Fab")
			(effects
				(font
					(size 1.27 1.27)
				)
				(justify mirror)
			)
		)
		(duplicate_pad_numbers_are_jumpers no)
		(fp_line
			(start 0.299974 0.150114)
			(end 0.299974 -0.150114)
			(stroke
				(width 0.1)
				(type default)
			)
			(layer "B.Fab")
		)
		(fp_line
			(start 0.299974 -0.150114)
			(end -0.299974 -0.150114)
			(stroke
				(width 0.1)
				(type default)
			)
			(layer "B.Fab")
		)
		(fp_line
			(start -0.299974 0.150114)
			(end 0.299974 0.150114)
			(stroke
				(width 0.1)
				(type default)
			)
			(layer "B.Fab")
		)
		(fp_line
			(start -0.299974 -0.150114)
			(end -0.299974 0.150114)
			(stroke
				(width 0.1)
				(type default)
			)
			(layer "B.Fab")
		)
		(pad "1" smd rect
			(at 0.2667 0)
			(size 0.3048 0.381)
			(layers "B.Cu" "B.Mask" "B.Paste")
			(net "P12V_NIC4")
		)
		(pad "2" smd rect
			(at -0.2667 0)
			(size 0.3048 0.381)
			(layers "B.Cu" "B.Mask" "B.Paste")
			(net "GND")
		)
	)
	(footprint ""
		(layer "B.Cu")
		(at 217.244422 -226.755452)
		(property "Reference" "R1490"
			(at 0 0 0)
			(layer "B.SilkS")
			(hide yes)
			(effects
				(font
					(size 1.27 1.27)
				)
				(justify mirror)
			)
		)
		(property "Value" ""
			(at 0 0 0)
			(layer "B.Fab")
			(effects
				(font
					(size 1.27 1.27)
				)
				(justify mirror)
			)
		)
		(duplicate_pad_numbers_are_jumpers no)
		(fp_line
			(start -0.7874 -0.4064)
			(end -0.7874 0.4064)
			(stroke
				(width 0.1524)
				(type default)
			)
			(layer "B.SilkS")
		)
		(fp_line
			(start -0.7874 0.4064)
			(end 0.7874 0.4064)
			(stroke
				(width 0.1524)
				(type default)
			)
			(layer "B.SilkS")
		)
		(fp_line
			(start 0.7874 -0.4064)
			(end -0.7874 -0.4064)
			(stroke
				(width 0.1524)
				(type default)
			)
			(layer "B.SilkS")
		)
		(fp_line
			(start 0.7874 0.4064)
			(end 0.7874 -0.4064)
			(stroke
				(width 0.1524)
				(type default)
			)
			(layer "B.SilkS")
		)
		(fp_line
			(start -0.67945 -0.3048)
			(end -0.67945 0.3048)
			(stroke
				(width 0.1)
				(type default)
			)
			(layer "B.Fab")
		)
		(fp_line
			(start -0.67945 0.3048)
			(end -0.120396 0.3048)
			(stroke
				(width 0.1)
				(type default)
			)
			(layer "B.Fab")
		)
		(fp_line
			(start -0.12065 -0.3048)
			(end -0.67945 -0.3048)
			(stroke
				(width 0.1)
				(type default)
			)
			(layer "B.Fab")
		)
		(fp_line
			(start -0.12065 -0.2794)
			(end -0.12065 -0.3048)
			(stroke
				(width 0.1)
				(type default)
			)
			(layer "B.Fab")
		)
		(fp_line
			(start -0.120396 0.2794)
			(end 0.12065 0.2794)
			(stroke
				(width 0.1)
				(type default)
			)
			(layer "B.Fab")
		)
		(fp_line
			(start -0.120396 0.3048)
			(end -0.120396 0.2794)
			(stroke
				(width 0.1)
				(type default)
			)
			(layer "B.Fab")
		)
		(fp_line
			(start 0.12065 -0.305054)
			(end 0.12065 -0.2794)
			(stroke
				(width 0.1)
				(type default)
			)
			(layer "B.Fab")
		)
		(fp_line
			(start 0.12065 -0.2794)
			(end -0.12065 -0.2794)
			(stroke
				(width 0.1)
				(type default)
			)
			(layer "B.Fab")
		)
		(fp_line
			(start 0.12065 0.2794)
			(end 0.12065 0.3048)
			(stroke
				(width 0.1)
				(type default)
			)
			(layer "B.Fab")
		)
		(fp_line
			(start 0.12065 0.3048)
			(end 0.67945 0.3048)
			(stroke
				(width 0.1)
				(type default)
			)
			(layer "B.Fab")
		)
		(fp_line
			(start 0.67945 -0.305054)
			(end 0.12065 -0.305054)
			(stroke
				(width 0.1)
				(type default)
			)
			(layer "B.Fab")
		)
		(fp_line
			(start 0.67945 0.3048)
			(end 0.67945 -0.305054)
			(stroke
				(width 0.1)
				(type default)
			)
			(layer "B.Fab")
		)
		(pad "1" smd circle
			(at 0.40005 0 180)
			(size 0 0)
			(layers "B.Cu" "B.Mask" "B.Paste")
			(net "SMB_FIO_SCL")
		)
		(pad "2" smd circle
			(at -0.40005 0 180)
			(size 0 0)
			(layers "B.Cu" "B.Mask" "B.Paste")
			(net "SMB_FIO_R1_SCL")
		)
	)
	(footprint ""
		(layer "B.Cu")
		(at 179.57038 -296.37482)
		(property "Reference" "C1393"
			(at 0 0 0)
			(layer "B.SilkS")
			(hide yes)
			(effects
				(font
					(size 1.27 1.27)
				)
				(justify mirror)
			)
		)
		(property "Value" ""
			(at 0 0 0)
			(layer "B.Fab")
			(effects
				(font
					(size 1.27 1.27)
				)
				(justify mirror)
			)
		)
		(duplicate_pad_numbers_are_jumpers no)
		(fp_line
			(start -0.299974 -0.150114)
			(end -0.299974 0.150114)
			(stroke
				(width 0.1)
				(type default)
			)
			(layer "B.Fab")
		)
		(fp_line
			(start -0.299974 0.150114)
			(end 0.299974 0.150114)
			(stroke
				(width 0.1)
				(type default)
			)
			(layer "B.Fab")
		)
		(fp_line
			(start 0.299974 -0.150114)
			(end -0.299974 -0.150114)
			(stroke
				(width 0.1)
				(type default)
			)
			(layer "B.Fab")
		)
		(fp_line
			(start 0.299974 0.150114)
			(end 0.299974 -0.150114)
			(stroke
				(width 0.1)
				(type default)
			)
			(layer "B.Fab")
		)
		(pad "1" smd rect
			(at 0.2667 0 180)
			(size 0.3048 0.381)
			(layers "B.Cu" "B.Mask" "B.Paste")
			(net "P0V8_PEX1")
		)
		(pad "2" smd rect
			(at -0.2667 0 180)
			(size 0.3048 0.381)
			(layers "B.Cu" "B.Mask" "B.Paste")
			(net "GND")
		)
	)
	(footprint ""
		(layer "B.Cu")
		(at 207.500728 -233.686604)
		(property "Reference" "R6326"
			(at 0 0 0)
			(layer "B.SilkS")
			(hide yes)
			(effects
				(font
					(size 1.27 1.27)
				)
				(justify mirror)
			)
		)
		(property "Value" ""
			(at 0 0 0)
			(layer "B.Fab")
			(effects
				(font
					(size 1.27 1.27)
				)
				(justify mirror)
			)
		)
		(duplicate_pad_numbers_are_jumpers no)
		(fp_line
			(start -0.7874 -0.4064)
			(end -0.7874 0.4064)
			(stroke
				(width 0.1524)
				(type default)
			)
			(layer "B.SilkS")
		)
		(fp_line
			(start -0.7874 0.4064)
			(end 0.7874 0.4064)
			(stroke
				(width 0.1524)
				(type default)
			)
			(layer "B.SilkS")
		)
		(fp_line
			(start 0.7874 -0.4064)
			(end -0.7874 -0.4064)
			(stroke
				(width 0.1524)
				(type default)
			)
			(layer "B.SilkS")
		)
		(fp_line
			(start 0.7874 0.4064)
			(end 0.7874 -0.4064)
			(stroke
				(width 0.1524)
				(type default)
			)
			(layer "B.SilkS")
		)
		(fp_line
			(start -0.67945 -0.3048)
			(end -0.67945 0.3048)
			(stroke
				(width 0.1)
				(type default)
			)
			(layer "B.Fab")
		)
		(fp_line
			(start -0.67945 0.3048)
			(end -0.120396 0.3048)
			(stroke
				(width 0.1)
				(type default)
			)
			(layer "B.Fab")
		)
		(fp_line
			(start -0.12065 -0.3048)
			(end -0.67945 -0.3048)
			(stroke
				(width 0.1)
				(type default)
			)
			(layer "B.Fab")
		)
		(fp_line
			(start -0.12065 -0.2794)
			(end -0.12065 -0.3048)
			(stroke
				(width 0.1)
				(type default)
			)
			(layer "B.Fab")
		)
		(fp_line
			(start -0.120396 0.2794)
			(end 0.12065 0.2794)
			(stroke
				(width 0.1)
				(type default)
			)
			(layer "B.Fab")
		)
		(fp_line
			(start -0.120396 0.3048)
			(end -0.120396 0.2794)
			(stroke
				(width 0.1)
				(type default)
			)
			(layer "B.Fab")
		)
		(fp_line
			(start 0.12065 -0.305054)
			(end 0.12065 -0.2794)
			(stroke
				(width 0.1)
				(type default)
			)
			(layer "B.Fab")
		)
		(fp_line
			(start 0.12065 -0.2794)
			(end -0.12065 -0.2794)
			(stroke
				(width 0.1)
				(type default)
			)
			(layer "B.Fab")
		)
		(fp_line
			(start 0.12065 0.2794)
			(end 0.12065 0.3048)
			(stroke
				(width 0.1)
				(type default)
			)
			(layer "B.Fab")
		)
		(fp_line
			(start 0.12065 0.3048)
			(end 0.67945 0.3048)
			(stroke
				(width 0.1)
				(type default)
			)
			(layer "B.Fab")
		)
		(fp_line
			(start 0.67945 -0.305054)
			(end 0.12065 -0.305054)
			(stroke
				(width 0.1)
				(type default)
			)
			(layer "B.Fab")
		)
		(fp_line
			(start 0.67945 0.3048)
			(end 0.67945 -0.305054)
			(stroke
				(width 0.1)
				(type default)
			)
			(layer "B.Fab")
		)
		(pad "1" smd circle
			(at 0.40005 0 180)
			(size 0 0)
			(layers "B.Cu" "B.Mask" "B.Paste")
			(net "SMB_PEX1_SCL")
		)
		(pad "2" smd circle
			(at -0.40005 0 180)
			(size 0 0)
			(layers "B.Cu" "B.Mask" "B.Paste")
			(net "SMB_PEX1_MUX_SCL")
		)
	)
	(footprint ""
		(layer "B.Cu")
		(at 187.390532 -118.711218 180)
		(property "Reference" "R177"
			(at 0 0 0)
			(layer "B.SilkS")
			(hide yes)
			(effects
				(font
					(size 1.27 1.27)
				)
				(justify mirror)
			)
		)
		(property "Value" ""
			(at 0 0 0)
			(layer "B.Fab")
			(effects
				(font
					(size 1.27 1.27)
				)
				(justify mirror)
			)
		)
		(duplicate_pad_numbers_are_jumpers no)
		(fp_line
			(start 0.7874 0.4064)
			(end 0.7874 -0.4064)
			(stroke
				(width 0.1524)
				(type default)
			)
			(layer "B.SilkS")
		)
		(fp_line
			(start 0.7874 -0.4064)
			(end -0.7874 -0.4064)
			(stroke
				(width 0.1524)
				(type default)
			)
			(layer "B.SilkS")
		)
		(fp_line
			(start -0.7874 0.4064)
			(end 0.7874 0.4064)
			(stroke
				(width 0.1524)
				(type default)
			)
			(layer "B.SilkS")
		)
		(fp_line
			(start -0.7874 -0.4064)
			(end -0.7874 0.4064)
			(stroke
				(width 0.1524)
				(type default)
			)
			(layer "B.SilkS")
		)
		(fp_line
			(start 0.67945 0.3048)
			(end 0.67945 -0.305054)
			(stroke
				(width 0.1)
				(type default)
			)
			(layer "B.Fab")
		)
		(fp_line
			(start 0.67945 -0.305054)
			(end 0.12065 -0.305054)
			(stroke
				(width 0.1)
				(type default)
			)
			(layer "B.Fab")
		)
		(fp_line
			(start 0.12065 0.3048)
			(end 0.67945 0.3048)
			(stroke
				(width 0.1)
				(type default)
			)
			(layer "B.Fab")
		)
		(fp_line
			(start 0.12065 0.2794)
			(end 0.12065 0.3048)
			(stroke
				(width 0.1)
				(type default)
			)
			(layer "B.Fab")
		)
		(fp_line
			(start 0.12065 -0.2794)
			(end -0.12065 -0.2794)
			(stroke
				(width 0.1)
				(type default)
			)
			(layer "B.Fab")
		)
		(fp_line
			(start 0.12065 -0.305054)
			(end 0.12065 -0.2794)
			(stroke
				(width 0.1)
				(type default)
			)
			(layer "B.Fab")
		)
		(fp_line
			(start -0.120396 0.3048)
			(end -0.120396 0.2794)
			(stroke
				(width 0.1)
				(type default)
			)
			(layer "B.Fab")
		)
		(fp_line
			(start -0.120396 0.2794)
			(end 0.12065 0.2794)
			(stroke
				(width 0.1)
				(type default)
			)
			(layer "B.Fab")
		)
		(fp_line
			(start -0.12065 -0.2794)
			(end -0.12065 -0.3048)
			(stroke
				(width 0.1)
				(type default)
			)
			(layer "B.Fab")
		)
		(fp_line
			(start -0.12065 -0.3048)
			(end -0.67945 -0.3048)
			(stroke
				(width 0.1)
				(type default)
			)
			(layer "B.Fab")
		)
		(fp_line
			(start -0.67945 0.3048)
			(end -0.120396 0.3048)
			(stroke
				(width 0.1)
				(type default)
			)
			(layer "B.Fab")
		)
		(fp_line
			(start -0.67945 -0.3048)
			(end -0.67945 0.3048)
			(stroke
				(width 0.1)
				(type default)
			)
			(layer "B.Fab")
		)
		(pad "1" smd circle
			(at 0.40005 0)
			(size 0 0)
			(layers "B.Cu" "B.Mask" "B.Paste")
			(net "NIC3_AUX_PWR_EN")
		)
		(pad "2" smd circle
			(at -0.40005 0)
			(size 0 0)
			(layers "B.Cu" "B.Mask" "B.Paste")
			(net "GND")
		)
	)
	(footprint ""
		(layer "B.Cu")
		(at 47.7774 -299.5422 90)
		(property "Reference" "C3023"
			(at 0 0 90)
			(layer "B.SilkS")
			(hide yes)
			(effects
				(font
					(size 1.27 1.27)
				)
				(justify mirror)
			)
		)
		(property "Value" ""
			(at 0 0 90)
			(layer "B.Fab")
			(effects
				(font
					(size 1.27 1.27)
				)
				(justify mirror)
			)
		)
		(duplicate_pad_numbers_are_jumpers no)
		(fp_line
			(start 0.299974 -0.150114)
			(end -0.299974 -0.150114)
			(stroke
				(width 0.1)
				(type default)
			)
			(layer "B.Fab")
		)
		(fp_line
			(start -0.299974 -0.150114)
			(end -0.299974 0.150114)
			(stroke
				(width 0.1)
				(type default)
			)
			(layer "B.Fab")
		)
		(fp_line
			(start 0.299974 0.150114)
			(end 0.299974 -0.150114)
			(stroke
				(width 0.1)
				(type default)
			)
			(layer "B.Fab")
		)
		(fp_line
			(start -0.299974 0.150114)
			(end 0.299974 0.150114)
			(stroke
				(width 0.1)
				(type default)
			)
			(layer "B.Fab")
		)
		(pad "1" smd rect
			(at 0.2667 0 270)
			(size 0.3048 0.381)
			(layers "B.Cu" "B.Mask" "B.Paste")
			(net "PCEPLL0_VDDA18_PEX0")
		)
		(pad "2" smd rect
			(at -0.2667 0 270)
			(size 0.3048 0.381)
			(layers "B.Cu" "B.Mask" "B.Paste")
			(net "GND")
		)
	)
	(footprint ""
		(layer "B.Cu")
		(at 235.569252 -217.104214 -90)
		(property "Reference" "C2024"
			(at 0 0 90)
			(layer "B.SilkS")
			(hide yes)
			(effects
				(font
					(size 1.27 1.27)
				)
				(justify mirror)
			)
		)
		(property "Value" ""
			(at 0 0 90)
			(layer "B.Fab")
			(effects
				(font
					(size 1.27 1.27)
				)
				(justify mirror)
			)
		)
		(duplicate_pad_numbers_are_jumpers no)
		(fp_line
			(start -0.69215 0.2921)
			(end 0.69215 0.2921)
			(stroke
				(width 0.1524)
				(type default)
			)
			(layer "B.SilkS")
		)
		(fp_line
			(start 0.69215 0.2921)
			(end 0.69215 -0.2921)
			(stroke
				(width 0.1524)
				(type default)
			)
			(layer "B.SilkS")
		)
		(fp_line
			(start -0.69215 -0.2921)
			(end -0.69215 0.2921)
			(stroke
				(width 0.1524)
				(type default)
			)
			(layer "B.SilkS")
		)
		(fp_line
			(start 0.69215 -0.2921)
			(end -0.69215 -0.2921)
			(stroke
				(width 0.1524)
				(type default)
			)
			(layer "B.SilkS")
		)
		(fp_line
			(start -0.51435 0.2794)
			(end 0.51435 0.2794)
			(stroke
				(width 0.1)
				(type default)
			)
			(layer "B.Fab")
		)
		(fp_line
			(start 0.51435 0.2794)
			(end 0.51435 -0.2794)
			(stroke
				(width 0.1)
				(type default)
			)
			(layer "B.Fab")
		)
		(fp_line
			(start -0.51435 -0.2794)
			(end -0.51435 0.2794)
			(stroke
				(width 0.1)
				(type default)
			)
			(layer "B.Fab")
		)
		(fp_line
			(start 0.51435 -0.2794)
			(end -0.51435 -0.2794)
			(stroke
				(width 0.1)
				(type default)
			)
			(layer "B.Fab")
		)
		(pad "1" smd circle
			(at 0.40005 0 90)
			(size 0 0)
			(layers "B.Cu" "B.Mask" "B.Paste")
			(net "P1V2_BIC_PLL")
		)
		(pad "2" smd circle
			(at -0.40005 0 90)
			(size 0 0)
			(layers "B.Cu" "B.Mask" "B.Paste")
			(net "GND")
		)
		(zone
			(layer "B.Cu")
			(hatch none 0.5)
			(connect_pads
				(clearance 0)
			)
			(min_thickness 0.25)
			(keepout
				(tracks not_allowed)
				(vias allowed)
				(pads allowed)
				(copperpour not_allowed)
				(footprints allowed)
			)
			(placement
				(enabled no)
				(sheetname "")
			)
			(fill
				(thermal_gap 0.5)
				(thermal_bridge_width 0.5)
				(island_removal_mode 0)
			)
			(polygon
				(pts
					(xy 235.481622 -216.913714) (xy 235.423456 -217.005154) (xy 235.423456 -217.204544) (xy 235.481622 -217.294714)
					(xy 235.656882 -217.294714) (xy 235.715302 -217.204544) (xy 235.715302 -217.005154) (xy 235.657136 -216.913714)
				)
			)
		)
	)
	(footprint ""
		(layer "B.Cu")
		(at 363.093 -228.981)
		(property "Reference" "R3504"
			(at 0 0 0)
			(layer "B.SilkS")
			(hide yes)
			(effects
				(font
					(size 1.27 1.27)
				)
				(justify mirror)
			)
		)
		(property "Value" ""
			(at 0 0 0)
			(layer "B.Fab")
			(effects
				(font
					(size 1.27 1.27)
				)
				(justify mirror)
			)
		)
		(duplicate_pad_numbers_are_jumpers no)
		(fp_line
			(start -0.7874 -0.4064)
			(end -0.7874 0.4064)
			(stroke
				(width 0.1524)
				(type default)
			)
			(layer "B.SilkS")
		)
		(fp_line
			(start -0.7874 0.4064)
			(end 0.7874 0.4064)
			(stroke
				(width 0.1524)
				(type default)
			)
			(layer "B.SilkS")
		)
		(fp_line
			(start 0.7874 -0.4064)
			(end -0.7874 -0.4064)
			(stroke
				(width 0.1524)
				(type default)
			)
			(layer "B.SilkS")
		)
		(fp_line
			(start 0.7874 0.4064)
			(end 0.7874 -0.4064)
			(stroke
				(width 0.1524)
				(type default)
			)
			(layer "B.SilkS")
		)
		(fp_line
			(start -0.67945 -0.3048)
			(end -0.67945 0.3048)
			(stroke
				(width 0.1)
				(type default)
			)
			(layer "B.Fab")
		)
		(fp_line
			(start -0.67945 0.3048)
			(end -0.120396 0.3048)
			(stroke
				(width 0.1)
				(type default)
			)
			(layer "B.Fab")
		)
		(fp_line
			(start -0.12065 -0.3048)
			(end -0.67945 -0.3048)
			(stroke
				(width 0.1)
				(type default)
			)
			(layer "B.Fab")
		)
		(fp_line
			(start -0.12065 -0.2794)
			(end -0.12065 -0.3048)
			(stroke
				(width 0.1)
				(type default)
			)
			(layer "B.Fab")
		)
		(fp_line
			(start -0.120396 0.2794)
			(end 0.12065 0.2794)
			(stroke
				(width 0.1)
				(type default)
			)
			(layer "B.Fab")
		)
		(fp_line
			(start -0.120396 0.3048)
			(end -0.120396 0.2794)
			(stroke
				(width 0.1)
				(type default)
			)
			(layer "B.Fab")
		)
		(fp_line
			(start 0.12065 -0.305054)
			(end 0.12065 -0.2794)
			(stroke
				(width 0.1)
				(type default)
			)
			(layer "B.Fab")
		)
		(fp_line
			(start 0.12065 -0.2794)
			(end -0.12065 -0.2794)
			(stroke
				(width 0.1)
				(type default)
			)
			(layer "B.Fab")
		)
		(fp_line
			(start 0.12065 0.2794)
			(end 0.12065 0.3048)
			(stroke
				(width 0.1)
				(type default)
			)
			(layer "B.Fab")
		)
		(fp_line
			(start 0.12065 0.3048)
			(end 0.67945 0.3048)
			(stroke
				(width 0.1)
				(type default)
			)
			(layer "B.Fab")
		)
		(fp_line
			(start 0.67945 -0.305054)
			(end 0.12065 -0.305054)
			(stroke
				(width 0.1)
				(type default)
			)
			(layer "B.Fab")
		)
		(fp_line
			(start 0.67945 0.3048)
			(end 0.67945 -0.305054)
			(stroke
				(width 0.1)
				(type default)
			)
			(layer "B.Fab")
		)
		(pad "1" smd circle
			(at 0.40005 0 180)
			(size 0 0)
			(layers "B.Cu" "B.Mask" "B.Paste")
			(net "P1V8_PEX")
		)
		(pad "2" smd circle
			(at -0.40005 0 180)
			(size 0 0)
			(layers "B.Cu" "B.Mask" "B.Paste")
			(net "SPI_PEX3_SDIO2_R1")
		)
	)
	(footprint ""
		(layer "B.Cu")
		(at 295.649904 -303.499774 -90)
		(property "Reference" "C3257"
			(at 0 0 90)
			(layer "B.SilkS")
			(hide yes)
			(effects
				(font
					(size 1.27 1.27)
				)
				(justify mirror)
			)
		)
		(property "Value" ""
			(at 0 0 90)
			(layer "B.Fab")
			(effects
				(font
					(size 1.27 1.27)
				)
				(justify mirror)
			)
		)
		(duplicate_pad_numbers_are_jumpers no)
		(fp_line
			(start -0.299974 0.150114)
			(end 0.299974 0.150114)
			(stroke
				(width 0.1)
				(type default)
			)
			(layer "B.Fab")
		)
		(fp_line
			(start 0.299974 0.150114)
			(end 0.299974 -0.150114)
			(stroke
				(width 0.1)
				(type default)
			)
			(layer "B.Fab")
		)
		(fp_line
			(start -0.299974 -0.150114)
			(end -0.299974 0.150114)
			(stroke
				(width 0.1)
				(type default)
			)
			(layer "B.Fab")
		)
		(fp_line
			(start 0.299974 -0.150114)
			(end -0.299974 -0.150114)
			(stroke
				(width 0.1)
				(type default)
			)
			(layer "B.Fab")
		)
		(pad "1" smd rect
			(at 0.2667 0 90)
			(size 0.3048 0.381)
			(layers "B.Cu" "B.Mask" "B.Paste")
			(net "P1V25_PEX2")
		)
		(pad "2" smd rect
			(at -0.2667 0 90)
			(size 0.3048 0.381)
			(layers "B.Cu" "B.Mask" "B.Paste")
			(net "GND")
		)
	)
	(footprint ""
		(layer "B.Cu")
		(at 289.04565 -296.37482)
		(property "Reference" "C1627"
			(at 0 0 0)
			(layer "B.SilkS")
			(hide yes)
			(effects
				(font
					(size 1.27 1.27)
				)
				(justify mirror)
			)
		)
		(property "Value" ""
			(at 0 0 0)
			(layer "B.Fab")
			(effects
				(font
					(size 1.27 1.27)
				)
				(justify mirror)
			)
		)
		(duplicate_pad_numbers_are_jumpers no)
		(fp_line
			(start -0.299974 -0.150114)
			(end -0.299974 0.150114)
			(stroke
				(width 0.1)
				(type default)
			)
			(layer "B.Fab")
		)
		(fp_line
			(start -0.299974 0.150114)
			(end 0.299974 0.150114)
			(stroke
				(width 0.1)
				(type default)
			)
			(layer "B.Fab")
		)
		(fp_line
			(start 0.299974 -0.150114)
			(end -0.299974 -0.150114)
			(stroke
				(width 0.1)
				(type default)
			)
			(layer "B.Fab")
		)
		(fp_line
			(start 0.299974 0.150114)
			(end 0.299974 -0.150114)
			(stroke
				(width 0.1)
				(type default)
			)
			(layer "B.Fab")
		)
		(pad "1" smd rect
			(at 0.2667 0 180)
			(size 0.3048 0.381)
			(layers "B.Cu" "B.Mask" "B.Paste")
			(net "P0V8_PEX2")
		)
		(pad "2" smd rect
			(at -0.2667 0 180)
			(size 0.3048 0.381)
			(layers "B.Cu" "B.Mask" "B.Paste")
			(net "GND")
		)
	)
	(footprint ""
		(layer "B.Cu")
		(at 130.49885 -171.43857 90)
		(property "Reference" "R1467"
			(at 0 0 90)
			(layer "B.SilkS")
			(hide yes)
			(effects
				(font
					(size 1.27 1.27)
				)
				(justify mirror)
			)
		)
		(property "Value" ""
			(at 0 0 90)
			(layer "B.Fab")
			(effects
				(font
					(size 1.27 1.27)
				)
				(justify mirror)
			)
		)
		(duplicate_pad_numbers_are_jumpers no)
		(fp_line
			(start 0.7874 -0.4064)
			(end -0.7874 -0.4064)
			(stroke
				(width 0.1524)
				(type default)
			)
			(layer "B.SilkS")
		)
		(fp_line
			(start -0.7874 -0.4064)
			(end -0.7874 0.4064)
			(stroke
				(width 0.1524)
				(type default)
			)
			(layer "B.SilkS")
		)
		(fp_line
			(start 0.7874 0.4064)
			(end 0.7874 -0.4064)
			(stroke
				(width 0.1524)
				(type default)
			)
			(layer "B.SilkS")
		)
		(fp_line
			(start -0.7874 0.4064)
			(end 0.7874 0.4064)
			(stroke
				(width 0.1524)
				(type default)
			)
			(layer "B.SilkS")
		)
		(fp_line
			(start 0.67945 -0.305054)
			(end 0.12065 -0.305054)
			(stroke
				(width 0.1)
				(type default)
			)
			(layer "B.Fab")
		)
		(fp_line
			(start 0.12065 -0.305054)
			(end 0.12065 -0.2794)
			(stroke
				(width 0.1)
				(type default)
			)
			(layer "B.Fab")
		)
		(fp_line
			(start -0.12065 -0.3048)
			(end -0.67945 -0.3048)
			(stroke
				(width 0.1)
				(type default)
			)
			(layer "B.Fab")
		)
		(fp_line
			(start -0.67945 -0.3048)
			(end -0.67945 0.3048)
			(stroke
				(width 0.1)
				(type default)
			)
			(layer "B.Fab")
		)
		(fp_line
			(start 0.12065 -0.2794)
			(end -0.12065 -0.2794)
			(stroke
				(width 0.1)
				(type default)
			)
			(layer "B.Fab")
		)
		(fp_line
			(start -0.12065 -0.2794)
			(end -0.12065 -0.3048)
			(stroke
				(width 0.1)
				(type default)
			)
			(layer "B.Fab")
		)
		(fp_line
			(start 0.12065 0.2794)
			(end 0.12065 0.3048)
			(stroke
				(width 0.1)
				(type default)
			)
			(layer "B.Fab")
		)
		(fp_line
			(start -0.120396 0.2794)
			(end 0.12065 0.2794)
			(stroke
				(width 0.1)
				(type default)
			)
			(layer "B.Fab")
		)
		(fp_line
			(start 0.67945 0.3048)
			(end 0.67945 -0.305054)
			(stroke
				(width 0.1)
				(type default)
			)
			(layer "B.Fab")
		)
		(fp_line
			(start 0.12065 0.3048)
			(end 0.67945 0.3048)
			(stroke
				(width 0.1)
				(type default)
			)
			(layer "B.Fab")
		)
		(fp_line
			(start -0.120396 0.3048)
			(end -0.120396 0.2794)
			(stroke
				(width 0.1)
				(type default)
			)
			(layer "B.Fab")
		)
		(fp_line
			(start -0.67945 0.3048)
			(end -0.120396 0.3048)
			(stroke
				(width 0.1)
				(type default)
			)
			(layer "B.Fab")
		)
		(pad "1" smd circle
			(at 0.40005 0 270)
			(size 0 0)
			(layers "B.Cu" "B.Mask" "B.Paste")
			(net "SMB_BMC_9QXL2001_SDA")
		)
		(pad "2" smd circle
			(at -0.40005 0 270)
			(size 0 0)
			(layers "B.Cu" "B.Mask" "B.Paste")
			(net "SMB_CLK_ISO_R_SDA")
		)
	)
	(footprint ""
		(layer "B.Cu")
		(at 71.755 -98.552)
		(property "Reference" "R53"
			(at 0 0 0)
			(layer "B.SilkS")
			(hide yes)
			(effects
				(font
					(size 1.27 1.27)
				)
				(justify mirror)
			)
		)
		(property "Value" ""
			(at 0 0 0)
			(layer "B.Fab")
			(effects
				(font
					(size 1.27 1.27)
				)
				(justify mirror)
			)
		)
		(duplicate_pad_numbers_are_jumpers no)
		(fp_line
			(start -0.7874 -0.4064)
			(end -0.7874 0.4064)
			(stroke
				(width 0.1524)
				(type default)
			)
			(layer "B.SilkS")
		)
		(fp_line
			(start -0.7874 0.4064)
			(end 0.7874 0.4064)
			(stroke
				(width 0.1524)
				(type default)
			)
			(layer "B.SilkS")
		)
		(fp_line
			(start 0.7874 -0.4064)
			(end -0.7874 -0.4064)
			(stroke
				(width 0.1524)
				(type default)
			)
			(layer "B.SilkS")
		)
		(fp_line
			(start 0.7874 0.4064)
			(end 0.7874 -0.4064)
			(stroke
				(width 0.1524)
				(type default)
			)
			(layer "B.SilkS")
		)
		(fp_line
			(start -0.67945 -0.3048)
			(end -0.67945 0.3048)
			(stroke
				(width 0.1)
				(type default)
			)
			(layer "B.Fab")
		)
		(fp_line
			(start -0.67945 0.3048)
			(end -0.120396 0.3048)
			(stroke
				(width 0.1)
				(type default)
			)
			(layer "B.Fab")
		)
		(fp_line
			(start -0.12065 -0.3048)
			(end -0.67945 -0.3048)
			(stroke
				(width 0.1)
				(type default)
			)
			(layer "B.Fab")
		)
		(fp_line
			(start -0.12065 -0.2794)
			(end -0.12065 -0.3048)
			(stroke
				(width 0.1)
				(type default)
			)
			(layer "B.Fab")
		)
		(fp_line
			(start -0.120396 0.2794)
			(end 0.12065 0.2794)
			(stroke
				(width 0.1)
				(type default)
			)
			(layer "B.Fab")
		)
		(fp_line
			(start -0.120396 0.3048)
			(end -0.120396 0.2794)
			(stroke
				(width 0.1)
				(type default)
			)
			(layer "B.Fab")
		)
		(fp_line
			(start 0.12065 -0.305054)
			(end 0.12065 -0.2794)
			(stroke
				(width 0.1)
				(type default)
			)
			(layer "B.Fab")
		)
		(fp_line
			(start 0.12065 -0.2794)
			(end -0.12065 -0.2794)
			(stroke
				(width 0.1)
				(type default)
			)
			(layer "B.Fab")
		)
		(fp_line
			(start 0.12065 0.2794)
			(end 0.12065 0.3048)
			(stroke
				(width 0.1)
				(type default)
			)
			(layer "B.Fab")
		)
		(fp_line
			(start 0.12065 0.3048)
			(end 0.67945 0.3048)
			(stroke
				(width 0.1)
				(type default)
			)
			(layer "B.Fab")
		)
		(fp_line
			(start 0.67945 -0.305054)
			(end 0.12065 -0.305054)
			(stroke
				(width 0.1)
				(type default)
			)
			(layer "B.Fab")
		)
		(fp_line
			(start 0.67945 0.3048)
			(end 0.67945 -0.305054)
			(stroke
				(width 0.1)
				(type default)
			)
			(layer "B.Fab")
		)
		(pad "1" smd circle
			(at 0.40005 0 180)
			(size 0 0)
			(layers "B.Cu" "B.Mask" "B.Paste")
			(net "NIC1_MAIN_PWR_EN_R")
		)
		(pad "2" smd circle
			(at -0.40005 0 180)
			(size 0 0)
			(layers "B.Cu" "B.Mask" "B.Paste")
			(net "NIC1_MAIN_PWR_EN")
		)
	)
	(footprint ""
		(layer "B.Cu")
		(at 211.810092 -368.406172 -90)
		(property "Reference" "PR8"
			(at 0 0 90)
			(layer "B.SilkS")
			(hide yes)
			(effects
				(font
					(size 1.27 1.27)
				)
				(justify mirror)
			)
		)
		(property "Value" ""
			(at 0 0 90)
			(layer "B.Fab")
			(effects
				(font
					(size 1.27 1.27)
				)
				(justify mirror)
			)
		)
		(duplicate_pad_numbers_are_jumpers no)
		(fp_line
			(start -0.7874 0.4064)
			(end 0.7874 0.4064)
			(stroke
				(width 0.1524)
				(type default)
			)
			(layer "B.SilkS")
		)
		(fp_line
			(start 0.7874 0.4064)
			(end 0.7874 -0.4064)
			(stroke
				(width 0.1524)
				(type default)
			)
			(layer "B.SilkS")
		)
		(fp_line
			(start -0.7874 -0.4064)
			(end -0.7874 0.4064)
			(stroke
				(width 0.1524)
				(type default)
			)
			(layer "B.SilkS")
		)
		(fp_line
			(start 0.7874 -0.4064)
			(end -0.7874 -0.4064)
			(stroke
				(width 0.1524)
				(type default)
			)
			(layer "B.SilkS")
		)
		(fp_line
			(start -0.67945 0.3048)
			(end -0.120396 0.3048)
			(stroke
				(width 0.1)
				(type default)
			)
			(layer "B.Fab")
		)
		(fp_line
			(start -0.120396 0.3048)
			(end -0.120396 0.2794)
			(stroke
				(width 0.1)
				(type default)
			)
			(layer "B.Fab")
		)
		(fp_line
			(start 0.12065 0.3048)
			(end 0.67945 0.3048)
			(stroke
				(width 0.1)
				(type default)
			)
			(layer "B.Fab")
		)
		(fp_line
			(start 0.67945 0.3048)
			(end 0.67945 -0.305054)
			(stroke
				(width 0.1)
				(type default)
			)
			(layer "B.Fab")
		)
		(fp_line
			(start -0.120396 0.2794)
			(end 0.12065 0.2794)
			(stroke
				(width 0.1)
				(type default)
			)
			(layer "B.Fab")
		)
		(fp_line
			(start 0.12065 0.2794)
			(end 0.12065 0.3048)
			(stroke
				(width 0.1)
				(type default)
			)
			(layer "B.Fab")
		)
		(fp_line
			(start -0.12065 -0.2794)
			(end -0.12065 -0.3048)
			(stroke
				(width 0.1)
				(type default)
			)
			(layer "B.Fab")
		)
		(fp_line
			(start 0.12065 -0.2794)
			(end -0.12065 -0.2794)
			(stroke
				(width 0.1)
				(type default)
			)
			(layer "B.Fab")
		)
		(fp_line
			(start -0.67945 -0.3048)
			(end -0.67945 0.3048)
			(stroke
				(width 0.1)
				(type default)
			)
			(layer "B.Fab")
		)
		(fp_line
			(start -0.12065 -0.3048)
			(end -0.67945 -0.3048)
			(stroke
				(width 0.1)
				(type default)
			)
			(layer "B.Fab")
		)
		(fp_line
			(start 0.12065 -0.305054)
			(end 0.12065 -0.2794)
			(stroke
				(width 0.1)
				(type default)
			)
			(layer "B.Fab")
		)
		(fp_line
			(start 0.67945 -0.305054)
			(end 0.12065 -0.305054)
			(stroke
				(width 0.1)
				(type default)
			)
			(layer "B.Fab")
		)
		(pad "1" smd circle
			(at 0.40005 0 90)
			(size 0 0)
			(layers "B.Cu" "B.Mask" "B.Paste")
			(net "HSC_FAULT_N")
		)
		(pad "2" smd circle
			(at -0.40005 0 90)
			(size 0 0)
			(layers "B.Cu" "B.Mask" "B.Paste")
			(net "HSC_VDD")
		)
	)
	(footprint ""
		(layer "B.Cu")
		(at 68.672202 -112.421924)
		(property "Reference" "R60"
			(at 0 0 0)
			(layer "B.SilkS")
			(hide yes)
			(effects
				(font
					(size 1.27 1.27)
				)
				(justify mirror)
			)
		)
		(property "Value" ""
			(at 0 0 0)
			(layer "B.Fab")
			(effects
				(font
					(size 1.27 1.27)
				)
				(justify mirror)
			)
		)
		(duplicate_pad_numbers_are_jumpers no)
		(fp_line
			(start -0.7874 -0.4064)
			(end -0.7874 0.4064)
			(stroke
				(width 0.1524)
				(type default)
			)
			(layer "B.SilkS")
		)
		(fp_line
			(start -0.7874 0.4064)
			(end 0.7874 0.4064)
			(stroke
				(width 0.1524)
				(type default)
			)
			(layer "B.SilkS")
		)
		(fp_line
			(start 0.7874 -0.4064)
			(end -0.7874 -0.4064)
			(stroke
				(width 0.1524)
				(type default)
			)
			(layer "B.SilkS")
		)
		(fp_line
			(start 0.7874 0.4064)
			(end 0.7874 -0.4064)
			(stroke
				(width 0.1524)
				(type default)
			)
			(layer "B.SilkS")
		)
		(fp_line
			(start -0.67945 -0.3048)
			(end -0.67945 0.3048)
			(stroke
				(width 0.1)
				(type default)
			)
			(layer "B.Fab")
		)
		(fp_line
			(start -0.67945 0.3048)
			(end -0.120396 0.3048)
			(stroke
				(width 0.1)
				(type default)
			)
			(layer "B.Fab")
		)
		(fp_line
			(start -0.12065 -0.3048)
			(end -0.67945 -0.3048)
			(stroke
				(width 0.1)
				(type default)
			)
			(layer "B.Fab")
		)
		(fp_line
			(start -0.12065 -0.2794)
			(end -0.12065 -0.3048)
			(stroke
				(width 0.1)
				(type default)
			)
			(layer "B.Fab")
		)
		(fp_line
			(start -0.120396 0.2794)
			(end 0.12065 0.2794)
			(stroke
				(width 0.1)
				(type default)
			)
			(layer "B.Fab")
		)
		(fp_line
			(start -0.120396 0.3048)
			(end -0.120396 0.2794)
			(stroke
				(width 0.1)
				(type default)
			)
			(layer "B.Fab")
		)
		(fp_line
			(start 0.12065 -0.305054)
			(end 0.12065 -0.2794)
			(stroke
				(width 0.1)
				(type default)
			)
			(layer "B.Fab")
		)
		(fp_line
			(start 0.12065 -0.2794)
			(end -0.12065 -0.2794)
			(stroke
				(width 0.1)
				(type default)
			)
			(layer "B.Fab")
		)
		(fp_line
			(start 0.12065 0.2794)
			(end 0.12065 0.3048)
			(stroke
				(width 0.1)
				(type default)
			)
			(layer "B.Fab")
		)
		(fp_line
			(start 0.12065 0.3048)
			(end 0.67945 0.3048)
			(stroke
				(width 0.1)
				(type default)
			)
			(layer "B.Fab")
		)
		(fp_line
			(start 0.67945 -0.305054)
			(end 0.12065 -0.305054)
			(stroke
				(width 0.1)
				(type default)
			)
			(layer "B.Fab")
		)
		(fp_line
			(start 0.67945 0.3048)
			(end 0.67945 -0.305054)
			(stroke
				(width 0.1)
				(type default)
			)
			(layer "B.Fab")
		)
		(pad "1" smd circle
			(at 0.40005 0 180)
			(size 0 0)
			(layers "B.Cu" "B.Mask" "B.Paste")
			(net "P3V3_NIC1")
		)
		(pad "2" smd circle
			(at -0.40005 0 180)
			(size 0 0)
			(layers "B.Cu" "B.Mask" "B.Paste")
			(net "SMB_NIC1_R_SCL")
		)
	)
	(footprint ""
		(layer "B.Cu")
		(at 130.539744 -206.241142 180)
		(property "Reference" "R920"
			(at 0 0 0)
			(layer "B.SilkS")
			(hide yes)
			(effects
				(font
					(size 1.27 1.27)
				)
				(justify mirror)
			)
		)
		(property "Value" ""
			(at 0 0 0)
			(layer "B.Fab")
			(effects
				(font
					(size 1.27 1.27)
				)
				(justify mirror)
			)
		)
		(duplicate_pad_numbers_are_jumpers no)
		(fp_line
			(start 0.7874 0.4064)
			(end 0.7874 -0.4064)
			(stroke
				(width 0.1524)
				(type default)
			)
			(layer "B.SilkS")
		)
		(fp_line
			(start 0.7874 -0.4064)
			(end -0.7874 -0.4064)
			(stroke
				(width 0.1524)
				(type default)
			)
			(layer "B.SilkS")
		)
		(fp_line
			(start -0.7874 0.4064)
			(end 0.7874 0.4064)
			(stroke
				(width 0.1524)
				(type default)
			)
			(layer "B.SilkS")
		)
		(fp_line
			(start -0.7874 -0.4064)
			(end -0.7874 0.4064)
			(stroke
				(width 0.1524)
				(type default)
			)
			(layer "B.SilkS")
		)
		(fp_line
			(start 0.67945 0.3048)
			(end 0.67945 -0.305054)
			(stroke
				(width 0.1)
				(type default)
			)
			(layer "B.Fab")
		)
		(fp_line
			(start 0.67945 -0.305054)
			(end 0.12065 -0.305054)
			(stroke
				(width 0.1)
				(type default)
			)
			(layer "B.Fab")
		)
		(fp_line
			(start 0.12065 0.3048)
			(end 0.67945 0.3048)
			(stroke
				(width 0.1)
				(type default)
			)
			(layer "B.Fab")
		)
		(fp_line
			(start 0.12065 0.2794)
			(end 0.12065 0.3048)
			(stroke
				(width 0.1)
				(type default)
			)
			(layer "B.Fab")
		)
		(fp_line
			(start 0.12065 -0.2794)
			(end -0.12065 -0.2794)
			(stroke
				(width 0.1)
				(type default)
			)
			(layer "B.Fab")
		)
		(fp_line
			(start 0.12065 -0.305054)
			(end 0.12065 -0.2794)
			(stroke
				(width 0.1)
				(type default)
			)
			(layer "B.Fab")
		)
		(fp_line
			(start -0.120396 0.3048)
			(end -0.120396 0.2794)
			(stroke
				(width 0.1)
				(type default)
			)
			(layer "B.Fab")
		)
		(fp_line
			(start -0.120396 0.2794)
			(end 0.12065 0.2794)
			(stroke
				(width 0.1)
				(type default)
			)
			(layer "B.Fab")
		)
		(fp_line
			(start -0.12065 -0.2794)
			(end -0.12065 -0.3048)
			(stroke
				(width 0.1)
				(type default)
			)
			(layer "B.Fab")
		)
		(fp_line
			(start -0.12065 -0.3048)
			(end -0.67945 -0.3048)
			(stroke
				(width 0.1)
				(type default)
			)
			(layer "B.Fab")
		)
		(fp_line
			(start -0.67945 0.3048)
			(end -0.120396 0.3048)
			(stroke
				(width 0.1)
				(type default)
			)
			(layer "B.Fab")
		)
		(fp_line
			(start -0.67945 -0.3048)
			(end -0.67945 0.3048)
			(stroke
				(width 0.1)
				(type default)
			)
			(layer "B.Fab")
		)
		(pad "1" smd circle
			(at 0.40005 0)
			(size 0 0)
			(layers "B.Cu" "B.Mask" "B.Paste")
			(net "FT4232_CLI_EEPROM_R_SCL")
		)
		(pad "2" smd circle
			(at -0.40005 0)
			(size 0 0)
			(layers "B.Cu" "B.Mask" "B.Paste")
			(net "P3V3_AUX")
		)
	)
	(footprint ""
		(layer "B.Cu")
		(at 293.27475 -293.99992 90)
		(property "Reference" "C1623"
			(at 0 0 90)
			(layer "B.SilkS")
			(hide yes)
			(effects
				(font
					(size 1.27 1.27)
				)
				(justify mirror)
			)
		)
		(property "Value" ""
			(at 0 0 90)
			(layer "B.Fab")
			(effects
				(font
					(size 1.27 1.27)
				)
				(justify mirror)
			)
		)
		(duplicate_pad_numbers_are_jumpers no)
		(fp_line
			(start 0.299974 -0.150114)
			(end -0.299974 -0.150114)
			(stroke
				(width 0.1)
				(type default)
			)
			(layer "B.Fab")
		)
		(fp_line
			(start -0.299974 -0.150114)
			(end -0.299974 0.150114)
			(stroke
				(width 0.1)
				(type default)
			)
			(layer "B.Fab")
		)
		(fp_line
			(start 0.299974 0.150114)
			(end 0.299974 -0.150114)
			(stroke
				(width 0.1)
				(type default)
			)
			(layer "B.Fab")
		)
		(fp_line
			(start -0.299974 0.150114)
			(end 0.299974 0.150114)
			(stroke
				(width 0.1)
				(type default)
			)
			(layer "B.Fab")
		)
		(pad "1" smd rect
			(at 0.2667 0 270)
			(size 0.3048 0.381)
			(layers "B.Cu" "B.Mask" "B.Paste")
			(net "P0V8_PEX2")
		)
		(pad "2" smd rect
			(at -0.2667 0 270)
			(size 0.3048 0.381)
			(layers "B.Cu" "B.Mask" "B.Paste")
			(net "GND")
		)
	)
	(footprint ""
		(layer "B.Cu")
		(at 171.949872 -299.699934 -90)
		(property "Reference" "C1457"
			(at 0 0 90)
			(layer "B.SilkS")
			(hide yes)
			(effects
				(font
					(size 1.27 1.27)
				)
				(justify mirror)
			)
		)
		(property "Value" ""
			(at 0 0 90)
			(layer "B.Fab")
			(effects
				(font
					(size 1.27 1.27)
				)
				(justify mirror)
			)
		)
		(duplicate_pad_numbers_are_jumpers no)
		(fp_line
			(start -0.299974 0.150114)
			(end 0.299974 0.150114)
			(stroke
				(width 0.1)
				(type default)
			)
			(layer "B.Fab")
		)
		(fp_line
			(start 0.299974 0.150114)
			(end 0.299974 -0.150114)
			(stroke
				(width 0.1)
				(type default)
			)
			(layer "B.Fab")
		)
		(fp_line
			(start -0.299974 -0.150114)
			(end -0.299974 0.150114)
			(stroke
				(width 0.1)
				(type default)
			)
			(layer "B.Fab")
		)
		(fp_line
			(start 0.299974 -0.150114)
			(end -0.299974 -0.150114)
			(stroke
				(width 0.1)
				(type default)
			)
			(layer "B.Fab")
		)
		(pad "1" smd rect
			(at 0.2667 0 90)
			(size 0.3048 0.381)
			(layers "B.Cu" "B.Mask" "B.Paste")
			(net "P0V8_SERDES_VDDA_PEX1")
		)
		(pad "2" smd rect
			(at -0.2667 0 90)
			(size 0.3048 0.381)
			(layers "B.Cu" "B.Mask" "B.Paste")
			(net "GND")
		)
	)
	(footprint ""
		(layer "B.Cu")
		(at 162.7886 -298.4246)
		(property "Reference" "C3243"
			(at 0 0 0)
			(layer "B.SilkS")
			(hide yes)
			(effects
				(font
					(size 1.27 1.27)
				)
				(justify mirror)
			)
		)
		(property "Value" ""
			(at 0 0 0)
			(layer "B.Fab")
			(effects
				(font
					(size 1.27 1.27)
				)
				(justify mirror)
			)
		)
		(duplicate_pad_numbers_are_jumpers no)
		(fp_line
			(start -0.299974 -0.150114)
			(end -0.299974 0.150114)
			(stroke
				(width 0.1)
				(type default)
			)
			(layer "B.Fab")
		)
		(fp_line
			(start -0.299974 0.150114)
			(end 0.299974 0.150114)
			(stroke
				(width 0.1)
				(type default)
			)
			(layer "B.Fab")
		)
		(fp_line
			(start 0.299974 -0.150114)
			(end -0.299974 -0.150114)
			(stroke
				(width 0.1)
				(type default)
			)
			(layer "B.Fab")
		)
		(fp_line
			(start 0.299974 0.150114)
			(end 0.299974 -0.150114)
			(stroke
				(width 0.1)
				(type default)
			)
			(layer "B.Fab")
		)
		(pad "1" smd rect
			(at 0.2667 0 180)
			(size 0.3048 0.381)
			(layers "B.Cu" "B.Mask" "B.Paste")
			(net "SYSPLL_VDDA18_PEX1")
		)
		(pad "2" smd rect
			(at -0.2667 0 180)
			(size 0.3048 0.381)
			(layers "B.Cu" "B.Mask" "B.Paste")
			(net "GND")
		)
	)
	(footprint ""
		(layer "B.Cu")
		(at 173.850046 -290.199826 90)
		(property "Reference" "C1467"
			(at 0 0 90)
			(layer "B.SilkS")
			(hide yes)
			(effects
				(font
					(size 1.27 1.27)
				)
				(justify mirror)
			)
		)
		(property "Value" ""
			(at 0 0 90)
			(layer "B.Fab")
			(effects
				(font
					(size 1.27 1.27)
				)
				(justify mirror)
			)
		)
		(duplicate_pad_numbers_are_jumpers no)
		(fp_line
			(start 0.299974 -0.150114)
			(end -0.299974 -0.150114)
			(stroke
				(width 0.1)
				(type default)
			)
			(layer "B.Fab")
		)
		(fp_line
			(start -0.299974 -0.150114)
			(end -0.299974 0.150114)
			(stroke
				(width 0.1)
				(type default)
			)
			(layer "B.Fab")
		)
		(fp_line
			(start 0.299974 0.150114)
			(end 0.299974 -0.150114)
			(stroke
				(width 0.1)
				(type default)
			)
			(layer "B.Fab")
		)
		(fp_line
			(start -0.299974 0.150114)
			(end 0.299974 0.150114)
			(stroke
				(width 0.1)
				(type default)
			)
			(layer "B.Fab")
		)
		(pad "1" smd rect
			(at 0.2667 0 270)
			(size 0.3048 0.381)
			(layers "B.Cu" "B.Mask" "B.Paste")
			(net "P0V8_SERDES_VDDA_PEX1")
		)
		(pad "2" smd rect
			(at -0.2667 0 270)
			(size 0.3048 0.381)
			(layers "B.Cu" "B.Mask" "B.Paste")
			(net "GND")
		)
	)
	(footprint ""
		(layer "B.Cu")
		(at 178.599846 -299.699934 -90)
		(property "Reference" "C1481"
			(at 0 0 90)
			(layer "B.SilkS")
			(hide yes)
			(effects
				(font
					(size 1.27 1.27)
				)
				(justify mirror)
			)
		)
		(property "Value" ""
			(at 0 0 90)
			(layer "B.Fab")
			(effects
				(font
					(size 1.27 1.27)
				)
				(justify mirror)
			)
		)
		(duplicate_pad_numbers_are_jumpers no)
		(fp_line
			(start -0.299974 0.150114)
			(end 0.299974 0.150114)
			(stroke
				(width 0.1)
				(type default)
			)
			(layer "B.Fab")
		)
		(fp_line
			(start 0.299974 0.150114)
			(end 0.299974 -0.150114)
			(stroke
				(width 0.1)
				(type default)
			)
			(layer "B.Fab")
		)
		(fp_line
			(start -0.299974 -0.150114)
			(end -0.299974 0.150114)
			(stroke
				(width 0.1)
				(type default)
			)
			(layer "B.Fab")
		)
		(fp_line
			(start 0.299974 -0.150114)
			(end -0.299974 -0.150114)
			(stroke
				(width 0.1)
				(type default)
			)
			(layer "B.Fab")
		)
		(pad "1" smd rect
			(at 0.2667 0 90)
			(size 0.3048 0.381)
			(layers "B.Cu" "B.Mask" "B.Paste")
			(net "P0V8_SERDES_VDDA_PEX1")
		)
		(pad "2" smd rect
			(at -0.2667 0 90)
			(size 0.3048 0.381)
			(layers "B.Cu" "B.Mask" "B.Paste")
			(net "GND")
		)
	)
	(footprint ""
		(layer "B.Cu")
		(at 229.222046 -141.316202)
		(property "Reference" "C2796"
			(at 0 0 0)
			(layer "B.SilkS")
			(hide yes)
			(effects
				(font
					(size 1.27 1.27)
				)
				(justify mirror)
			)
		)
		(property "Value" ""
			(at 0 0 0)
			(layer "B.Fab")
			(effects
				(font
					(size 1.27 1.27)
				)
				(justify mirror)
			)
		)
		(duplicate_pad_numbers_are_jumpers no)
		(fp_line
			(start -0.7874 -0.4064)
			(end -0.7874 0.4064)
			(stroke
				(width 0.1524)
				(type default)
			)
			(layer "B.SilkS")
		)
		(fp_line
			(start -0.7874 0.4064)
			(end 0.7874 0.4064)
			(stroke
				(width 0.1524)
				(type default)
			)
			(layer "B.SilkS")
		)
		(fp_line
			(start 0.7874 -0.4064)
			(end -0.7874 -0.4064)
			(stroke
				(width 0.1524)
				(type default)
			)
			(layer "B.SilkS")
		)
		(fp_line
			(start 0.7874 0.4064)
			(end 0.7874 -0.4064)
			(stroke
				(width 0.1524)
				(type default)
			)
			(layer "B.SilkS")
		)
		(fp_line
			(start -0.67945 -0.3048)
			(end -0.67945 0.3048)
			(stroke
				(width 0.1)
				(type default)
			)
			(layer "B.Fab")
		)
		(fp_line
			(start -0.67945 0.3048)
			(end -0.120396 0.3048)
			(stroke
				(width 0.1)
				(type default)
			)
			(layer "B.Fab")
		)
		(fp_line
			(start -0.12065 -0.3048)
			(end -0.67945 -0.3048)
			(stroke
				(width 0.1)
				(type default)
			)
			(layer "B.Fab")
		)
		(fp_line
			(start -0.12065 -0.2794)
			(end -0.12065 -0.3048)
			(stroke
				(width 0.1)
				(type default)
			)
			(layer "B.Fab")
		)
		(fp_line
			(start -0.120396 0.2794)
			(end 0.12065 0.2794)
			(stroke
				(width 0.1)
				(type default)
			)
			(layer "B.Fab")
		)
		(fp_line
			(start -0.120396 0.3048)
			(end -0.120396 0.2794)
			(stroke
				(width 0.1)
				(type default)
			)
			(layer "B.Fab")
		)
		(fp_line
			(start 0.12065 -0.305054)
			(end 0.12065 -0.2794)
			(stroke
				(width 0.1)
				(type default)
			)
			(layer "B.Fab")
		)
		(fp_line
			(start 0.12065 -0.2794)
			(end -0.12065 -0.2794)
			(stroke
				(width 0.1)
				(type default)
			)
			(layer "B.Fab")
		)
		(fp_line
			(start 0.12065 0.2794)
			(end 0.12065 0.3048)
			(stroke
				(width 0.1)
				(type default)
			)
			(layer "B.Fab")
		)
		(fp_line
			(start 0.12065 0.3048)
			(end 0.67945 0.3048)
			(stroke
				(width 0.1)
				(type default)
			)
			(layer "B.Fab")
		)
		(fp_line
			(start 0.67945 -0.305054)
			(end 0.12065 -0.305054)
			(stroke
				(width 0.1)
				(type default)
			)
			(layer "B.Fab")
		)
		(fp_line
			(start 0.67945 0.3048)
			(end 0.67945 -0.305054)
			(stroke
				(width 0.1)
				(type default)
			)
			(layer "B.Fab")
		)
		(pad "1" smd circle
			(at 0.40005 0 180)
			(size 0 0)
			(layers "B.Cu" "B.Mask" "B.Paste")
			(net "P3V3_CLK_GEN_VDDXTAL_CK440_PEX")
		)
		(pad "2" smd circle
			(at -0.40005 0 180)
			(size 0 0)
			(layers "B.Cu" "B.Mask" "B.Paste")
			(net "GND")
		)
	)
	(footprint ""
		(layer "B.Cu")
		(at 222.482664 -204.44206 -90)
		(property "Reference" "R5527"
			(at 0 0 90)
			(layer "B.SilkS")
			(hide yes)
			(effects
				(font
					(size 1.27 1.27)
				)
				(justify mirror)
			)
		)
		(property "Value" ""
			(at 0 0 90)
			(layer "B.Fab")
			(effects
				(font
					(size 1.27 1.27)
				)
				(justify mirror)
			)
		)
		(duplicate_pad_numbers_are_jumpers no)
		(fp_line
			(start -0.7874 0.4064)
			(end 0.7874 0.4064)
			(stroke
				(width 0.1524)
				(type default)
			)
			(layer "B.SilkS")
		)
		(fp_line
			(start 0.7874 0.4064)
			(end 0.7874 -0.4064)
			(stroke
				(width 0.1524)
				(type default)
			)
			(layer "B.SilkS")
		)
		(fp_line
			(start -0.7874 -0.4064)
			(end -0.7874 0.4064)
			(stroke
				(width 0.1524)
				(type default)
			)
			(layer "B.SilkS")
		)
		(fp_line
			(start 0.7874 -0.4064)
			(end -0.7874 -0.4064)
			(stroke
				(width 0.1524)
				(type default)
			)
			(layer "B.SilkS")
		)
		(fp_line
			(start -0.67945 0.3048)
			(end -0.120396 0.3048)
			(stroke
				(width 0.1)
				(type default)
			)
			(layer "B.Fab")
		)
		(fp_line
			(start -0.120396 0.3048)
			(end -0.120396 0.2794)
			(stroke
				(width 0.1)
				(type default)
			)
			(layer "B.Fab")
		)
		(fp_line
			(start 0.12065 0.3048)
			(end 0.67945 0.3048)
			(stroke
				(width 0.1)
				(type default)
			)
			(layer "B.Fab")
		)
		(fp_line
			(start 0.67945 0.3048)
			(end 0.67945 -0.305054)
			(stroke
				(width 0.1)
				(type default)
			)
			(layer "B.Fab")
		)
		(fp_line
			(start -0.120396 0.2794)
			(end 0.12065 0.2794)
			(stroke
				(width 0.1)
				(type default)
			)
			(layer "B.Fab")
		)
		(fp_line
			(start 0.12065 0.2794)
			(end 0.12065 0.3048)
			(stroke
				(width 0.1)
				(type default)
			)
			(layer "B.Fab")
		)
		(fp_line
			(start -0.12065 -0.2794)
			(end -0.12065 -0.3048)
			(stroke
				(width 0.1)
				(type default)
			)
			(layer "B.Fab")
		)
		(fp_line
			(start 0.12065 -0.2794)
			(end -0.12065 -0.2794)
			(stroke
				(width 0.1)
				(type default)
			)
			(layer "B.Fab")
		)
		(fp_line
			(start -0.67945 -0.3048)
			(end -0.67945 0.3048)
			(stroke
				(width 0.1)
				(type default)
			)
			(layer "B.Fab")
		)
		(fp_line
			(start -0.12065 -0.3048)
			(end -0.67945 -0.3048)
			(stroke
				(width 0.1)
				(type default)
			)
			(layer "B.Fab")
		)
		(fp_line
			(start 0.12065 -0.305054)
			(end 0.12065 -0.2794)
			(stroke
				(width 0.1)
				(type default)
			)
			(layer "B.Fab")
		)
		(fp_line
			(start 0.67945 -0.305054)
			(end 0.12065 -0.305054)
			(stroke
				(width 0.1)
				(type default)
			)
			(layer "B.Fab")
		)
		(pad "1" smd circle
			(at 0.40005 0 90)
			(size 0 0)
			(layers "B.Cu" "B.Mask" "B.Paste")
			(net "P3V3_AUX")
		)
		(pad "2" smd circle
			(at -0.40005 0 90)
			(size 0 0)
			(layers "B.Cu" "B.Mask" "B.Paste")
			(net "SGPIO_BIC_DOUT")
		)
	)
	(footprint ""
		(layer "B.Cu")
		(at 217.235786 -212.206586 180)
		(property "Reference" "R5722"
			(at 0 0 0)
			(layer "B.SilkS")
			(hide yes)
			(effects
				(font
					(size 1.27 1.27)
				)
				(justify mirror)
			)
		)
		(property "Value" ""
			(at 0 0 0)
			(layer "B.Fab")
			(effects
				(font
					(size 1.27 1.27)
				)
				(justify mirror)
			)
		)
		(duplicate_pad_numbers_are_jumpers no)
		(fp_line
			(start 0.7874 0.4064)
			(end 0.7874 -0.4064)
			(stroke
				(width 0.1524)
				(type default)
			)
			(layer "B.SilkS")
		)
		(fp_line
			(start 0.7874 -0.4064)
			(end -0.7874 -0.4064)
			(stroke
				(width 0.1524)
				(type default)
			)
			(layer "B.SilkS")
		)
		(fp_line
			(start -0.7874 0.4064)
			(end 0.7874 0.4064)
			(stroke
				(width 0.1524)
				(type default)
			)
			(layer "B.SilkS")
		)
		(fp_line
			(start -0.7874 -0.4064)
			(end -0.7874 0.4064)
			(stroke
				(width 0.1524)
				(type default)
			)
			(layer "B.SilkS")
		)
		(fp_line
			(start 0.67945 0.3048)
			(end 0.67945 -0.305054)
			(stroke
				(width 0.1)
				(type default)
			)
			(layer "B.Fab")
		)
		(fp_line
			(start 0.67945 -0.305054)
			(end 0.12065 -0.305054)
			(stroke
				(width 0.1)
				(type default)
			)
			(layer "B.Fab")
		)
		(fp_line
			(start 0.12065 0.3048)
			(end 0.67945 0.3048)
			(stroke
				(width 0.1)
				(type default)
			)
			(layer "B.Fab")
		)
		(fp_line
			(start 0.12065 0.2794)
			(end 0.12065 0.3048)
			(stroke
				(width 0.1)
				(type default)
			)
			(layer "B.Fab")
		)
		(fp_line
			(start 0.12065 -0.2794)
			(end -0.12065 -0.2794)
			(stroke
				(width 0.1)
				(type default)
			)
			(layer "B.Fab")
		)
		(fp_line
			(start 0.12065 -0.305054)
			(end 0.12065 -0.2794)
			(stroke
				(width 0.1)
				(type default)
			)
			(layer "B.Fab")
		)
		(fp_line
			(start -0.120396 0.3048)
			(end -0.120396 0.2794)
			(stroke
				(width 0.1)
				(type default)
			)
			(layer "B.Fab")
		)
		(fp_line
			(start -0.120396 0.2794)
			(end 0.12065 0.2794)
			(stroke
				(width 0.1)
				(type default)
			)
			(layer "B.Fab")
		)
		(fp_line
			(start -0.12065 -0.2794)
			(end -0.12065 -0.3048)
			(stroke
				(width 0.1)
				(type default)
			)
			(layer "B.Fab")
		)
		(fp_line
			(start -0.12065 -0.3048)
			(end -0.67945 -0.3048)
			(stroke
				(width 0.1)
				(type default)
			)
			(layer "B.Fab")
		)
		(fp_line
			(start -0.67945 0.3048)
			(end -0.120396 0.3048)
			(stroke
				(width 0.1)
				(type default)
			)
			(layer "B.Fab")
		)
		(fp_line
			(start -0.67945 -0.3048)
			(end -0.67945 0.3048)
			(stroke
				(width 0.1)
				(type default)
			)
			(layer "B.Fab")
		)
		(pad "1" smd circle
			(at 0.40005 0)
			(size 0 0)
			(layers "B.Cu" "B.Mask" "B.Paste")
			(net "RST_PEX_USB_HUB_R_N")
		)
		(pad "2" smd circle
			(at -0.40005 0)
			(size 0 0)
			(layers "B.Cu" "B.Mask" "B.Paste")
			(net "RST_PEX_USB_HUB_N")
		)
	)
	(footprint ""
		(layer "B.Cu")
		(at 173.850046 -288.299906 90)
		(property "Reference" "C3093"
			(at 0 0 90)
			(layer "B.SilkS")
			(hide yes)
			(effects
				(font
					(size 1.27 1.27)
				)
				(justify mirror)
			)
		)
		(property "Value" ""
			(at 0 0 90)
			(layer "B.Fab")
			(effects
				(font
					(size 1.27 1.27)
				)
				(justify mirror)
			)
		)
		(duplicate_pad_numbers_are_jumpers no)
		(fp_line
			(start 0.299974 -0.150114)
			(end -0.299974 -0.150114)
			(stroke
				(width 0.1)
				(type default)
			)
			(layer "B.Fab")
		)
		(fp_line
			(start -0.299974 -0.150114)
			(end -0.299974 0.150114)
			(stroke
				(width 0.1)
				(type default)
			)
			(layer "B.Fab")
		)
		(fp_line
			(start 0.299974 0.150114)
			(end 0.299974 -0.150114)
			(stroke
				(width 0.1)
				(type default)
			)
			(layer "B.Fab")
		)
		(fp_line
			(start -0.299974 0.150114)
			(end 0.299974 0.150114)
			(stroke
				(width 0.1)
				(type default)
			)
			(layer "B.Fab")
		)
		(pad "1" smd rect
			(at 0.2667 0 270)
			(size 0.3048 0.381)
			(layers "B.Cu" "B.Mask" "B.Paste")
			(net "P1V25_PEX1")
		)
		(pad "2" smd rect
			(at -0.2667 0 270)
			(size 0.3048 0.381)
			(layers "B.Cu" "B.Mask" "B.Paste")
			(net "GND")
		)
	)
	(footprint ""
		(layer "B.Cu")
		(at 243.568982 -234.471464)
		(property "Reference" "R6815"
			(at 0 0 0)
			(layer "B.SilkS")
			(hide yes)
			(effects
				(font
					(size 1.27 1.27)
				)
				(justify mirror)
			)
		)
		(property "Value" ""
			(at 0 0 0)
			(layer "B.Fab")
			(effects
				(font
					(size 1.27 1.27)
				)
				(justify mirror)
			)
		)
		(duplicate_pad_numbers_are_jumpers no)
		(fp_line
			(start -0.7874 -0.4064)
			(end -0.7874 0.4064)
			(stroke
				(width 0.1524)
				(type default)
			)
			(layer "B.SilkS")
		)
		(fp_line
			(start -0.7874 0.4064)
			(end 0.7874 0.4064)
			(stroke
				(width 0.1524)
				(type default)
			)
			(layer "B.SilkS")
		)
		(fp_line
			(start 0.7874 -0.4064)
			(end -0.7874 -0.4064)
			(stroke
				(width 0.1524)
				(type default)
			)
			(layer "B.SilkS")
		)
		(fp_line
			(start 0.7874 0.4064)
			(end 0.7874 -0.4064)
			(stroke
				(width 0.1524)
				(type default)
			)
			(layer "B.SilkS")
		)
		(fp_line
			(start -0.67945 -0.3048)
			(end -0.67945 0.3048)
			(stroke
				(width 0.1)
				(type default)
			)
			(layer "B.Fab")
		)
		(fp_line
			(start -0.67945 0.3048)
			(end -0.120396 0.3048)
			(stroke
				(width 0.1)
				(type default)
			)
			(layer "B.Fab")
		)
		(fp_line
			(start -0.12065 -0.3048)
			(end -0.67945 -0.3048)
			(stroke
				(width 0.1)
				(type default)
			)
			(layer "B.Fab")
		)
		(fp_line
			(start -0.12065 -0.2794)
			(end -0.12065 -0.3048)
			(stroke
				(width 0.1)
				(type default)
			)
			(layer "B.Fab")
		)
		(fp_line
			(start -0.120396 0.2794)
			(end 0.12065 0.2794)
			(stroke
				(width 0.1)
				(type default)
			)
			(layer "B.Fab")
		)
		(fp_line
			(start -0.120396 0.3048)
			(end -0.120396 0.2794)
			(stroke
				(width 0.1)
				(type default)
			)
			(layer "B.Fab")
		)
		(fp_line
			(start 0.12065 -0.305054)
			(end 0.12065 -0.2794)
			(stroke
				(width 0.1)
				(type default)
			)
			(layer "B.Fab")
		)
		(fp_line
			(start 0.12065 -0.2794)
			(end -0.12065 -0.2794)
			(stroke
				(width 0.1)
				(type default)
			)
			(layer "B.Fab")
		)
		(fp_line
			(start 0.12065 0.2794)
			(end 0.12065 0.3048)
			(stroke
				(width 0.1)
				(type default)
			)
			(layer "B.Fab")
		)
		(fp_line
			(start 0.12065 0.3048)
			(end 0.67945 0.3048)
			(stroke
				(width 0.1)
				(type default)
			)
			(layer "B.Fab")
		)
		(fp_line
			(start 0.67945 -0.305054)
			(end 0.12065 -0.305054)
			(stroke
				(width 0.1)
				(type default)
			)
			(layer "B.Fab")
		)
		(fp_line
			(start 0.67945 0.3048)
			(end 0.67945 -0.305054)
			(stroke
				(width 0.1)
				(type default)
			)
			(layer "B.Fab")
		)
		(pad "1" smd circle
			(at 0.40005 0 180)
			(size 0 0)
			(layers "B.Cu" "B.Mask" "B.Paste")
			(net "BOARD_TYPE_2_ADC_R")
		)
		(pad "2" smd circle
			(at -0.40005 0 180)
			(size 0 0)
			(layers "B.Cu" "B.Mask" "B.Paste")
			(net "P3V3_AUX")
		)
	)
	(footprint ""
		(layer "B.Cu")
		(at 181.92496 -293.99992 -90)
		(property "Reference" "C1386"
			(at 0 0 90)
			(layer "B.SilkS")
			(hide yes)
			(effects
				(font
					(size 1.27 1.27)
				)
				(justify mirror)
			)
		)
		(property "Value" ""
			(at 0 0 90)
			(layer "B.Fab")
			(effects
				(font
					(size 1.27 1.27)
				)
				(justify mirror)
			)
		)
		(duplicate_pad_numbers_are_jumpers no)
		(fp_line
			(start -0.299974 0.150114)
			(end 0.299974 0.150114)
			(stroke
				(width 0.1)
				(type default)
			)
			(layer "B.Fab")
		)
		(fp_line
			(start 0.299974 0.150114)
			(end 0.299974 -0.150114)
			(stroke
				(width 0.1)
				(type default)
			)
			(layer "B.Fab")
		)
		(fp_line
			(start -0.299974 -0.150114)
			(end -0.299974 0.150114)
			(stroke
				(width 0.1)
				(type default)
			)
			(layer "B.Fab")
		)
		(fp_line
			(start 0.299974 -0.150114)
			(end -0.299974 -0.150114)
			(stroke
				(width 0.1)
				(type default)
			)
			(layer "B.Fab")
		)
		(pad "1" smd rect
			(at 0.2667 0 90)
			(size 0.3048 0.381)
			(layers "B.Cu" "B.Mask" "B.Paste")
			(net "P0V8_PEX1")
		)
		(pad "2" smd rect
			(at -0.2667 0 90)
			(size 0.3048 0.381)
			(layers "B.Cu" "B.Mask" "B.Paste")
			(net "GND")
		)
	)
	(footprint ""
		(layer "B.Cu")
		(at 285.199836 -292.099746 90)
		(property "Reference" "C1700"
			(at 0 0 90)
			(layer "B.SilkS")
			(hide yes)
			(effects
				(font
					(size 1.27 1.27)
				)
				(justify mirror)
			)
		)
		(property "Value" ""
			(at 0 0 90)
			(layer "B.Fab")
			(effects
				(font
					(size 1.27 1.27)
				)
				(justify mirror)
			)
		)
		(duplicate_pad_numbers_are_jumpers no)
		(fp_line
			(start 0.299974 -0.150114)
			(end -0.299974 -0.150114)
			(stroke
				(width 0.1)
				(type default)
			)
			(layer "B.Fab")
		)
		(fp_line
			(start -0.299974 -0.150114)
			(end -0.299974 0.150114)
			(stroke
				(width 0.1)
				(type default)
			)
			(layer "B.Fab")
		)
		(fp_line
			(start 0.299974 0.150114)
			(end 0.299974 -0.150114)
			(stroke
				(width 0.1)
				(type default)
			)
			(layer "B.Fab")
		)
		(fp_line
			(start -0.299974 0.150114)
			(end 0.299974 0.150114)
			(stroke
				(width 0.1)
				(type default)
			)
			(layer "B.Fab")
		)
		(pad "1" smd rect
			(at 0.2667 0 270)
			(size 0.3048 0.381)
			(layers "B.Cu" "B.Mask" "B.Paste")
			(net "P0V8_SERDES_VDDA_PEX2")
		)
		(pad "2" smd rect
			(at -0.2667 0 270)
			(size 0.3048 0.381)
			(layers "B.Cu" "B.Mask" "B.Paste")
			(net "GND")
		)
	)
	(footprint ""
		(layer "B.Cu")
		(at 217.24366 -225.477578)
		(property "Reference" "R1492"
			(at 0 0 0)
			(layer "B.SilkS")
			(hide yes)
			(effects
				(font
					(size 1.27 1.27)
				)
				(justify mirror)
			)
		)
		(property "Value" ""
			(at 0 0 0)
			(layer "B.Fab")
			(effects
				(font
					(size 1.27 1.27)
				)
				(justify mirror)
			)
		)
		(duplicate_pad_numbers_are_jumpers no)
		(fp_line
			(start -0.7874 -0.4064)
			(end -0.7874 0.4064)
			(stroke
				(width 0.1524)
				(type default)
			)
			(layer "B.SilkS")
		)
		(fp_line
			(start -0.7874 0.4064)
			(end 0.7874 0.4064)
			(stroke
				(width 0.1524)
				(type default)
			)
			(layer "B.SilkS")
		)
		(fp_line
			(start 0.7874 -0.4064)
			(end -0.7874 -0.4064)
			(stroke
				(width 0.1524)
				(type default)
			)
			(layer "B.SilkS")
		)
		(fp_line
			(start 0.7874 0.4064)
			(end 0.7874 -0.4064)
			(stroke
				(width 0.1524)
				(type default)
			)
			(layer "B.SilkS")
		)
		(fp_line
			(start -0.67945 -0.3048)
			(end -0.67945 0.3048)
			(stroke
				(width 0.1)
				(type default)
			)
			(layer "B.Fab")
		)
		(fp_line
			(start -0.67945 0.3048)
			(end -0.120396 0.3048)
			(stroke
				(width 0.1)
				(type default)
			)
			(layer "B.Fab")
		)
		(fp_line
			(start -0.12065 -0.3048)
			(end -0.67945 -0.3048)
			(stroke
				(width 0.1)
				(type default)
			)
			(layer "B.Fab")
		)
		(fp_line
			(start -0.12065 -0.2794)
			(end -0.12065 -0.3048)
			(stroke
				(width 0.1)
				(type default)
			)
			(layer "B.Fab")
		)
		(fp_line
			(start -0.120396 0.2794)
			(end 0.12065 0.2794)
			(stroke
				(width 0.1)
				(type default)
			)
			(layer "B.Fab")
		)
		(fp_line
			(start -0.120396 0.3048)
			(end -0.120396 0.2794)
			(stroke
				(width 0.1)
				(type default)
			)
			(layer "B.Fab")
		)
		(fp_line
			(start 0.12065 -0.305054)
			(end 0.12065 -0.2794)
			(stroke
				(width 0.1)
				(type default)
			)
			(layer "B.Fab")
		)
		(fp_line
			(start 0.12065 -0.2794)
			(end -0.12065 -0.2794)
			(stroke
				(width 0.1)
				(type default)
			)
			(layer "B.Fab")
		)
		(fp_line
			(start 0.12065 0.2794)
			(end 0.12065 0.3048)
			(stroke
				(width 0.1)
				(type default)
			)
			(layer "B.Fab")
		)
		(fp_line
			(start 0.12065 0.3048)
			(end 0.67945 0.3048)
			(stroke
				(width 0.1)
				(type default)
			)
			(layer "B.Fab")
		)
		(fp_line
			(start 0.67945 -0.305054)
			(end 0.12065 -0.305054)
			(stroke
				(width 0.1)
				(type default)
			)
			(layer "B.Fab")
		)
		(fp_line
			(start 0.67945 0.3048)
			(end 0.67945 -0.305054)
			(stroke
				(width 0.1)
				(type default)
			)
			(layer "B.Fab")
		)
		(pad "1" smd circle
			(at 0.40005 0 180)
			(size 0 0)
			(layers "B.Cu" "B.Mask" "B.Paste")
			(net "SMB_FIO_SDA")
		)
		(pad "2" smd circle
			(at -0.40005 0 180)
			(size 0 0)
			(layers "B.Cu" "B.Mask" "B.Paste")
			(net "SMB_FIO_R1_SDA")
		)
	)
	(footprint ""
		(layer "B.Cu")
		(at 407.949908 -303.499774 -90)
		(property "Reference" "C3428"
			(at 0 0 90)
			(layer "B.SilkS")
			(hide yes)
			(effects
				(font
					(size 1.27 1.27)
				)
				(justify mirror)
			)
		)
		(property "Value" ""
			(at 0 0 90)
			(layer "B.Fab")
			(effects
				(font
					(size 1.27 1.27)
				)
				(justify mirror)
			)
		)
		(duplicate_pad_numbers_are_jumpers no)
		(fp_line
			(start -0.299974 0.150114)
			(end 0.299974 0.150114)
			(stroke
				(width 0.1)
				(type default)
			)
			(layer "B.Fab")
		)
		(fp_line
			(start 0.299974 0.150114)
			(end 0.299974 -0.150114)
			(stroke
				(width 0.1)
				(type default)
			)
			(layer "B.Fab")
		)
		(fp_line
			(start -0.299974 -0.150114)
			(end -0.299974 0.150114)
			(stroke
				(width 0.1)
				(type default)
			)
			(layer "B.Fab")
		)
		(fp_line
			(start 0.299974 -0.150114)
			(end -0.299974 -0.150114)
			(stroke
				(width 0.1)
				(type default)
			)
			(layer "B.Fab")
		)
		(pad "1" smd rect
			(at 0.2667 0 90)
			(size 0.3048 0.381)
			(layers "B.Cu" "B.Mask" "B.Paste")
			(net "P1V25_PEX3")
		)
		(pad "2" smd rect
			(at -0.2667 0 90)
			(size 0.3048 0.381)
			(layers "B.Cu" "B.Mask" "B.Paste")
			(net "GND")
		)
	)
	(footprint ""
		(layer "B.Cu")
		(at 226.047046 -141.443202 -90)
		(property "Reference" "R4198"
			(at 0 0 90)
			(layer "B.SilkS")
			(hide yes)
			(effects
				(font
					(size 1.27 1.27)
				)
				(justify mirror)
			)
		)
		(property "Value" ""
			(at 0 0 90)
			(layer "B.Fab")
			(effects
				(font
					(size 1.27 1.27)
				)
				(justify mirror)
			)
		)
		(duplicate_pad_numbers_are_jumpers no)
		(fp_line
			(start -1.2954 0.5842)
			(end 1.2954 0.5842)
			(stroke
				(width 0.1524)
				(type default)
			)
			(layer "B.SilkS")
		)
		(fp_line
			(start 1.2954 0.5842)
			(end 1.2954 -0.5842)
			(stroke
				(width 0.1524)
				(type default)
			)
			(layer "B.SilkS")
		)
		(fp_line
			(start -1.2954 -0.5842)
			(end -1.2954 0.5842)
			(stroke
				(width 0.1524)
				(type default)
			)
			(layer "B.SilkS")
		)
		(fp_line
			(start 1.2954 -0.5842)
			(end -1.2954 -0.5842)
			(stroke
				(width 0.1524)
				(type default)
			)
			(layer "B.SilkS")
		)
		(fp_line
			(start -0.8636 0.4572)
			(end 0.8636 0.4572)
			(stroke
				(width 0.1)
				(type default)
			)
			(layer "B.Fab")
		)
		(fp_line
			(start 0.8636 0.4572)
			(end 0.8636 0.4318)
			(stroke
				(width 0.1)
				(type default)
			)
			(layer "B.Fab")
		)
		(fp_line
			(start 0.8636 0.4318)
			(end 0.8636 0.4064)
			(stroke
				(width 0.1)
				(type default)
			)
			(layer "B.Fab")
		)
		(fp_line
			(start -1.1938 0.4064)
			(end -0.8636 0.4064)
			(stroke
				(width 0.1)
				(type default)
			)
			(layer "B.Fab")
		)
		(fp_line
			(start -0.8636 0.4064)
			(end -0.8636 0.4572)
			(stroke
				(width 0.1)
				(type default)
			)
			(layer "B.Fab")
		)
		(fp_line
			(start 0.8636 0.4064)
			(end 1.1938 0.4064)
			(stroke
				(width 0.1)
				(type default)
			)
			(layer "B.Fab")
		)
		(fp_line
			(start 1.1938 0.4064)
			(end 1.1938 -0.406654)
			(stroke
				(width 0.1)
				(type default)
			)
			(layer "B.Fab")
		)
		(fp_line
			(start -1.1938 -0.406654)
			(end -1.1938 0.4064)
			(stroke
				(width 0.1)
				(type default)
			)
			(layer "B.Fab")
		)
		(fp_line
			(start -0.8636 -0.406654)
			(end -1.1938 -0.406654)
			(stroke
				(width 0.1)
				(type default)
			)
			(layer "B.Fab")
		)
		(fp_line
			(start 0.8636 -0.406654)
			(end 0.8636 -0.4572)
			(stroke
				(width 0.1)
				(type default)
			)
			(layer "B.Fab")
		)
		(fp_line
			(start 1.1938 -0.406654)
			(end 0.8636 -0.406654)
			(stroke
				(width 0.1)
				(type default)
			)
			(layer "B.Fab")
		)
		(fp_line
			(start -0.8636 -0.4572)
			(end -0.8636 -0.406654)
			(stroke
				(width 0.1)
				(type default)
			)
			(layer "B.Fab")
		)
		(fp_line
			(start 0.8636 -0.4572)
			(end -0.8636 -0.4572)
			(stroke
				(width 0.1)
				(type default)
			)
			(layer "B.Fab")
		)
		(pad "1" smd rect
			(at 0.7366 0 180)
			(size 0.7112 0.8128)
			(layers "B.Cu" "B.Mask" "B.Paste")
			(net "P3V3_CLK_GEN_VDDMXCK_CK440_PEX")
		)
		(pad "2" smd rect
			(at -0.7366 0 180)
			(size 0.7112 0.8128)
			(layers "B.Cu" "B.Mask" "B.Paste")
			(net "P3V3_CLK_GEN_VDDPT_CK440_PEX")
		)
	)
	(footprint ""
		(layer "B.Cu")
		(at 50.624994 -293.99992 90)
		(property "Reference" "C1119"
			(at 0 0 90)
			(layer "B.SilkS")
			(hide yes)
			(effects
				(font
					(size 1.27 1.27)
				)
				(justify mirror)
			)
		)
		(property "Value" ""
			(at 0 0 90)
			(layer "B.Fab")
			(effects
				(font
					(size 1.27 1.27)
				)
				(justify mirror)
			)
		)
		(duplicate_pad_numbers_are_jumpers no)
		(fp_line
			(start 0.299974 -0.150114)
			(end -0.299974 -0.150114)
			(stroke
				(width 0.1)
				(type default)
			)
			(layer "B.Fab")
		)
		(fp_line
			(start -0.299974 -0.150114)
			(end -0.299974 0.150114)
			(stroke
				(width 0.1)
				(type default)
			)
			(layer "B.Fab")
		)
		(fp_line
			(start 0.299974 0.150114)
			(end 0.299974 -0.150114)
			(stroke
				(width 0.1)
				(type default)
			)
			(layer "B.Fab")
		)
		(fp_line
			(start -0.299974 0.150114)
			(end 0.299974 0.150114)
			(stroke
				(width 0.1)
				(type default)
			)
			(layer "B.Fab")
		)
		(pad "1" smd rect
			(at 0.2667 0 270)
			(size 0.3048 0.381)
			(layers "B.Cu" "B.Mask" "B.Paste")
			(net "P0V8_PEX0")
		)
		(pad "2" smd rect
			(at -0.2667 0 270)
			(size 0.3048 0.381)
			(layers "B.Cu" "B.Mask" "B.Paste")
			(net "GND")
		)
	)
	(footprint ""
		(layer "B.Cu")
		(at 126.328678 -285.606998 -90)
		(property "Reference" "PR7177"
			(at 0 0 90)
			(layer "B.SilkS")
			(hide yes)
			(effects
				(font
					(size 1.27 1.27)
				)
				(justify mirror)
			)
		)
		(property "Value" ""
			(at 0 0 90)
			(layer "B.Fab")
			(effects
				(font
					(size 1.27 1.27)
				)
				(justify mirror)
			)
		)
		(duplicate_pad_numbers_are_jumpers no)
		(fp_line
			(start -0.7874 0.4064)
			(end 0.7874 0.4064)
			(stroke
				(width 0.1524)
				(type default)
			)
			(layer "B.SilkS")
		)
		(fp_line
			(start 0.7874 0.4064)
			(end 0.7874 -0.4064)
			(stroke
				(width 0.1524)
				(type default)
			)
			(layer "B.SilkS")
		)
		(fp_line
			(start -0.7874 -0.4064)
			(end -0.7874 0.4064)
			(stroke
				(width 0.1524)
				(type default)
			)
			(layer "B.SilkS")
		)
		(fp_line
			(start 0.7874 -0.4064)
			(end -0.7874 -0.4064)
			(stroke
				(width 0.1524)
				(type default)
			)
			(layer "B.SilkS")
		)
		(fp_line
			(start -0.67945 0.3048)
			(end -0.120396 0.3048)
			(stroke
				(width 0.1)
				(type default)
			)
			(layer "B.Fab")
		)
		(fp_line
			(start -0.120396 0.3048)
			(end -0.120396 0.2794)
			(stroke
				(width 0.1)
				(type default)
			)
			(layer "B.Fab")
		)
		(fp_line
			(start 0.12065 0.3048)
			(end 0.67945 0.3048)
			(stroke
				(width 0.1)
				(type default)
			)
			(layer "B.Fab")
		)
		(fp_line
			(start 0.67945 0.3048)
			(end 0.67945 -0.305054)
			(stroke
				(width 0.1)
				(type default)
			)
			(layer "B.Fab")
		)
		(fp_line
			(start -0.120396 0.2794)
			(end 0.12065 0.2794)
			(stroke
				(width 0.1)
				(type default)
			)
			(layer "B.Fab")
		)
		(fp_line
			(start 0.12065 0.2794)
			(end 0.12065 0.3048)
			(stroke
				(width 0.1)
				(type default)
			)
			(layer "B.Fab")
		)
		(fp_line
			(start -0.12065 -0.2794)
			(end -0.12065 -0.3048)
			(stroke
				(width 0.1)
				(type default)
			)
			(layer "B.Fab")
		)
		(fp_line
			(start 0.12065 -0.2794)
			(end -0.12065 -0.2794)
			(stroke
				(width 0.1)
				(type default)
			)
			(layer "B.Fab")
		)
		(fp_line
			(start -0.67945 -0.3048)
			(end -0.67945 0.3048)
			(stroke
				(width 0.1)
				(type default)
			)
			(layer "B.Fab")
		)
		(fp_line
			(start -0.12065 -0.3048)
			(end -0.67945 -0.3048)
			(stroke
				(width 0.1)
				(type default)
			)
			(layer "B.Fab")
		)
		(fp_line
			(start 0.12065 -0.305054)
			(end 0.12065 -0.2794)
			(stroke
				(width 0.1)
				(type default)
			)
			(layer "B.Fab")
		)
		(fp_line
			(start 0.67945 -0.305054)
			(end 0.12065 -0.305054)
			(stroke
				(width 0.1)
				(type default)
			)
			(layer "B.Fab")
		)
		(pad "1" smd circle
			(at 0.40005 0 90)
			(size 0 0)
			(layers "B.Cu" "B.Mask" "B.Paste")
			(net "P0V8_PEX1_PVCC")
		)
		(pad "2" smd circle
			(at -0.40005 0 90)
			(size 0 0)
			(layers "B.Cu" "B.Mask" "B.Paste")
			(net "P3V3_AUX")
		)
	)
	(footprint ""
		(layer "B.Cu")
		(at 386.842 -246.253 90)
		(property "Reference" "C2606"
			(at 0 0 90)
			(layer "B.SilkS")
			(hide yes)
			(effects
				(font
					(size 1.27 1.27)
				)
				(justify mirror)
			)
		)
		(property "Value" ""
			(at 0 0 90)
			(layer "B.Fab")
			(effects
				(font
					(size 1.27 1.27)
				)
				(justify mirror)
			)
		)
		(duplicate_pad_numbers_are_jumpers no)
		(fp_line
			(start 0.7874 -0.4064)
			(end -0.7874 -0.4064)
			(stroke
				(width 0.1524)
				(type default)
			)
			(layer "B.SilkS")
		)
		(fp_line
			(start -0.7874 -0.4064)
			(end -0.7874 0.4064)
			(stroke
				(width 0.1524)
				(type default)
			)
			(layer "B.SilkS")
		)
		(fp_line
			(start 0.7874 0.4064)
			(end 0.7874 -0.4064)
			(stroke
				(width 0.1524)
				(type default)
			)
			(layer "B.SilkS")
		)
		(fp_line
			(start -0.7874 0.4064)
			(end 0.7874 0.4064)
			(stroke
				(width 0.1524)
				(type default)
			)
			(layer "B.SilkS")
		)
		(fp_line
			(start 0.67945 -0.305054)
			(end 0.12065 -0.305054)
			(stroke
				(width 0.1)
				(type default)
			)
			(layer "B.Fab")
		)
		(fp_line
			(start 0.12065 -0.305054)
			(end 0.12065 -0.2794)
			(stroke
				(width 0.1)
				(type default)
			)
			(layer "B.Fab")
		)
		(fp_line
			(start -0.12065 -0.3048)
			(end -0.67945 -0.3048)
			(stroke
				(width 0.1)
				(type default)
			)
			(layer "B.Fab")
		)
		(fp_line
			(start -0.67945 -0.3048)
			(end -0.67945 0.3048)
			(stroke
				(width 0.1)
				(type default)
			)
			(layer "B.Fab")
		)
		(fp_line
			(start 0.12065 -0.2794)
			(end -0.12065 -0.2794)
			(stroke
				(width 0.1)
				(type default)
			)
			(layer "B.Fab")
		)
		(fp_line
			(start -0.12065 -0.2794)
			(end -0.12065 -0.3048)
			(stroke
				(width 0.1)
				(type default)
			)
			(layer "B.Fab")
		)
		(fp_line
			(start 0.12065 0.2794)
			(end 0.12065 0.3048)
			(stroke
				(width 0.1)
				(type default)
			)
			(layer "B.Fab")
		)
		(fp_line
			(start -0.120396 0.2794)
			(end 0.12065 0.2794)
			(stroke
				(width 0.1)
				(type default)
			)
			(layer "B.Fab")
		)
		(fp_line
			(start 0.67945 0.3048)
			(end 0.67945 -0.305054)
			(stroke
				(width 0.1)
				(type default)
			)
			(layer "B.Fab")
		)
		(fp_line
			(start 0.12065 0.3048)
			(end 0.67945 0.3048)
			(stroke
				(width 0.1)
				(type default)
			)
			(layer "B.Fab")
		)
		(fp_line
			(start -0.120396 0.3048)
			(end -0.120396 0.2794)
			(stroke
				(width 0.1)
				(type default)
			)
			(layer "B.Fab")
		)
		(fp_line
			(start -0.67945 0.3048)
			(end -0.120396 0.3048)
			(stroke
				(width 0.1)
				(type default)
			)
			(layer "B.Fab")
		)
		(pad "1" smd circle
			(at 0.40005 0 270)
			(size 0 0)
			(layers "B.Cu" "B.Mask" "B.Paste")
			(net "GND")
		)
		(pad "2" smd circle
			(at -0.40005 0 270)
			(size 0 0)
			(layers "B.Cu" "B.Mask" "B.Paste")
			(net "P3V3_AUX")
		)
	)
	(footprint ""
		(layer "B.Cu")
		(at 350.491044 -224.795334 180)
		(property "Reference" "C2041"
			(at 0 0 0)
			(layer "B.SilkS")
			(hide yes)
			(effects
				(font
					(size 1.27 1.27)
				)
				(justify mirror)
			)
		)
		(property "Value" ""
			(at 0 0 0)
			(layer "B.Fab")
			(effects
				(font
					(size 1.27 1.27)
				)
				(justify mirror)
			)
		)
		(duplicate_pad_numbers_are_jumpers no)
		(fp_line
			(start 0.69215 0.2921)
			(end 0.69215 -0.2921)
			(stroke
				(width 0.1524)
				(type default)
			)
			(layer "B.SilkS")
		)
		(fp_line
			(start 0.69215 -0.2921)
			(end -0.69215 -0.2921)
			(stroke
				(width 0.1524)
				(type default)
			)
			(layer "B.SilkS")
		)
		(fp_line
			(start -0.69215 0.2921)
			(end 0.69215 0.2921)
			(stroke
				(width 0.1524)
				(type default)
			)
			(layer "B.SilkS")
		)
		(fp_line
			(start -0.69215 -0.2921)
			(end -0.69215 0.2921)
			(stroke
				(width 0.1524)
				(type default)
			)
			(layer "B.SilkS")
		)
		(fp_line
			(start 0.51435 0.2794)
			(end 0.51435 -0.2794)
			(stroke
				(width 0.1)
				(type default)
			)
			(layer "B.Fab")
		)
		(fp_line
			(start 0.51435 -0.2794)
			(end -0.51435 -0.2794)
			(stroke
				(width 0.1)
				(type default)
			)
			(layer "B.Fab")
		)
		(fp_line
			(start -0.51435 0.2794)
			(end 0.51435 0.2794)
			(stroke
				(width 0.1)
				(type default)
			)
			(layer "B.Fab")
		)
		(fp_line
			(start -0.51435 -0.2794)
			(end -0.51435 0.2794)
			(stroke
				(width 0.1)
				(type default)
			)
			(layer "B.Fab")
		)
		(pad "1" smd circle
			(at 0.40005 0)
			(size 0 0)
			(layers "B.Cu" "B.Mask" "B.Paste")
			(net "P3V3_FPGA_VCCIO1")
		)
		(pad "2" smd circle
			(at -0.40005 0)
			(size 0 0)
			(layers "B.Cu" "B.Mask" "B.Paste")
			(net "GND")
		)
		(zone
			(layer "B.Cu")
			(hatch none 0.5)
			(connect_pads
				(clearance 0)
			)
			(min_thickness 0.25)
			(keepout
				(tracks not_allowed)
				(vias allowed)
				(pads allowed)
				(copperpour not_allowed)
				(footprints allowed)
			)
			(placement
				(enabled no)
				(sheetname "")
			)
			(fill
				(thermal_gap 0.5)
				(thermal_bridge_width 0.5)
				(island_removal_mode 0)
			)
			(polygon
				(pts
					(xy 350.300544 -224.882964) (xy 350.391984 -224.94113) (xy 350.591374 -224.94113) (xy 350.681544 -224.882964)
					(xy 350.681544 -224.707704) (xy 350.591374 -224.649284) (xy 350.391984 -224.649284) (xy 350.300544 -224.70745)
				)
			)
		)
	)
	(footprint ""
		(layer "B.Cu")
		(at 167.200072 -292.099746 90)
		(property "Reference" "C1442"
			(at 0 0 90)
			(layer "B.SilkS")
			(hide yes)
			(effects
				(font
					(size 1.27 1.27)
				)
				(justify mirror)
			)
		)
		(property "Value" ""
			(at 0 0 90)
			(layer "B.Fab")
			(effects
				(font
					(size 1.27 1.27)
				)
				(justify mirror)
			)
		)
		(duplicate_pad_numbers_are_jumpers no)
		(fp_line
			(start 0.299974 -0.150114)
			(end -0.299974 -0.150114)
			(stroke
				(width 0.1)
				(type default)
			)
			(layer "B.Fab")
		)
		(fp_line
			(start -0.299974 -0.150114)
			(end -0.299974 0.150114)
			(stroke
				(width 0.1)
				(type default)
			)
			(layer "B.Fab")
		)
		(fp_line
			(start 0.299974 0.150114)
			(end 0.299974 -0.150114)
			(stroke
				(width 0.1)
				(type default)
			)
			(layer "B.Fab")
		)
		(fp_line
			(start -0.299974 0.150114)
			(end 0.299974 0.150114)
			(stroke
				(width 0.1)
				(type default)
			)
			(layer "B.Fab")
		)
		(pad "1" smd rect
			(at 0.2667 0 270)
			(size 0.3048 0.381)
			(layers "B.Cu" "B.Mask" "B.Paste")
			(net "P0V8_SERDES_VDDA_PEX1")
		)
		(pad "2" smd rect
			(at -0.2667 0 270)
			(size 0.3048 0.381)
			(layers "B.Cu" "B.Mask" "B.Paste")
			(net "GND")
		)
	)
	(footprint ""
		(layer "B.Cu")
		(at 170.964606 -140.931138 180)
		(property "Reference" "U18"
			(at -0.478282 1.872234 0)
			(unlocked yes)
			(layer "B.SilkS")
			(effects
				(font
					(size 0.7874 0.5842)
					(thickness 0.1524)
				)
				(justify mirror)
			)
		)
		(property "Value" ""
			(at 0 0 0)
			(layer "B.Fab")
			(effects
				(font
					(size 1.27 1.27)
				)
				(justify mirror)
			)
		)
		(duplicate_pad_numbers_are_jumpers no)
		(fp_line
			(start 1.3462 1.1938)
			(end -1.3462 1.1938)
			(stroke
				(width 0.1524)
				(type default)
			)
			(layer "B.SilkS")
		)
		(fp_line
			(start 1.3462 -1.1938)
			(end 1.3462 1.1684)
			(stroke
				(width 0.1524)
				(type default)
			)
			(layer "B.SilkS")
		)
		(fp_line
			(start -1.3462 1.1938)
			(end -1.3462 -1.1938)
			(stroke
				(width 0.1524)
				(type default)
			)
			(layer "B.SilkS")
		)
		(fp_line
			(start -1.3462 -1.1938)
			(end 1.3462 -1.1938)
			(stroke
				(width 0.1524)
				(type default)
			)
			(layer "B.SilkS")
		)
		(fp_poly
			(pts
				(xy 1.447038 -0.760476) (xy 2.052066 -0.457962) (xy 2.052066 -1.06299)
			)
			(stroke
				(width 0)
				(type default)
			)
			(fill yes)
			(layer "B.SilkS")
		)
		(fp_line
			(start 0.674878 1.124966)
			(end -0.674878 1.124966)
			(stroke
				(width 0.1)
				(type default)
			)
			(layer "B.Fab")
		)
		(fp_line
			(start 0.674878 -1.124966)
			(end 0.674878 1.124966)
			(stroke
				(width 0.1)
				(type default)
			)
			(layer "B.Fab")
		)
		(fp_line
			(start -0.674878 1.124966)
			(end -0.674878 -1.124966)
			(stroke
				(width 0.1)
				(type default)
			)
			(layer "B.Fab")
		)
		(fp_line
			(start -0.674878 -1.124966)
			(end 0.674878 -1.124966)
			(stroke
				(width 0.1)
				(type default)
			)
			(layer "B.Fab")
		)
		(fp_poly
			(pts
				(xy 1.447038 -0.760476) (xy 2.052066 -0.457962) (xy 2.052066 -1.06299)
			)
			(stroke
				(width 0)
				(type default)
			)
			(fill yes)
			(layer "B.Fab")
		)
		(pad "1" smd rect
			(at 0.899922 -0.750062)
			(size 0.6096 0.6096)
			(layers "B.Cu" "B.Mask" "B.Paste")
			(net "NIC2_AUX_PWR_EN_R")
		)
		(pad "2" smd rect
			(at 0.899922 0 270)
			(size 0.4064 0.6096)
			(layers "B.Cu" "B.Mask" "B.Paste")
			(net "RST_SMB_NIC2_MUX_N")
		)
		(pad "3" smd rect
			(at 0.899922 0.750062)
			(size 0.6096 0.6096)
			(layers "B.Cu" "B.Mask" "B.Paste")
			(net "GND")
		)
		(pad "4" smd rect
			(at -0.899922 0.750062)
			(size 0.6096 0.6096)
			(layers "B.Cu" "B.Mask" "B.Paste")
			(net "RST_SMB_NIC2_MUX_ISO_N")
		)
		(pad "5" smd rect
			(at -0.899922 -0.750062)
			(size 0.6096 0.6096)
			(layers "B.Cu" "B.Mask" "B.Paste")
			(net "P3V3_AUX")
		)
	)
	(footprint ""
		(layer "B.Cu")
		(at 341.293704 -221.98711 90)
		(property "Reference" "C2030"
			(at 0 0 90)
			(layer "B.SilkS")
			(hide yes)
			(effects
				(font
					(size 1.27 1.27)
				)
				(justify mirror)
			)
		)
		(property "Value" ""
			(at 0 0 90)
			(layer "B.Fab")
			(effects
				(font
					(size 1.27 1.27)
				)
				(justify mirror)
			)
		)
		(duplicate_pad_numbers_are_jumpers no)
		(fp_line
			(start 0.69215 -0.2921)
			(end -0.69215 -0.2921)
			(stroke
				(width 0.1524)
				(type default)
			)
			(layer "B.SilkS")
		)
		(fp_line
			(start -0.69215 -0.2921)
			(end -0.69215 0.2921)
			(stroke
				(width 0.1524)
				(type default)
			)
			(layer "B.SilkS")
		)
		(fp_line
			(start 0.69215 0.2921)
			(end 0.69215 -0.2921)
			(stroke
				(width 0.1524)
				(type default)
			)
			(layer "B.SilkS")
		)
		(fp_line
			(start -0.69215 0.2921)
			(end 0.69215 0.2921)
			(stroke
				(width 0.1524)
				(type default)
			)
			(layer "B.SilkS")
		)
		(fp_line
			(start 0.51435 -0.2794)
			(end -0.51435 -0.2794)
			(stroke
				(width 0.1)
				(type default)
			)
			(layer "B.Fab")
		)
		(fp_line
			(start -0.51435 -0.2794)
			(end -0.51435 0.2794)
			(stroke
				(width 0.1)
				(type default)
			)
			(layer "B.Fab")
		)
		(fp_line
			(start 0.51435 0.2794)
			(end 0.51435 -0.2794)
			(stroke
				(width 0.1)
				(type default)
			)
			(layer "B.Fab")
		)
		(fp_line
			(start -0.51435 0.2794)
			(end 0.51435 0.2794)
			(stroke
				(width 0.1)
				(type default)
			)
			(layer "B.Fab")
		)
		(pad "1" smd circle
			(at 0.40005 0 270)
			(size 0 0)
			(layers "B.Cu" "B.Mask" "B.Paste")
			(net "P3V3_FPGA_VCCIO0")
		)
		(pad "2" smd circle
			(at -0.40005 0 270)
			(size 0 0)
			(layers "B.Cu" "B.Mask" "B.Paste")
			(net "GND")
		)
		(zone
			(layer "B.Cu")
			(hatch none 0.5)
			(connect_pads
				(clearance 0)
			)
			(min_thickness 0.25)
			(keepout
				(tracks not_allowed)
				(vias allowed)
				(pads allowed)
				(copperpour not_allowed)
				(footprints allowed)
			)
			(placement
				(enabled no)
				(sheetname "")
			)
			(fill
				(thermal_gap 0.5)
				(thermal_bridge_width 0.5)
				(island_removal_mode 0)
			)
			(polygon
				(pts
					(xy 341.381334 -222.17761) (xy 341.4395 -222.08617) (xy 341.4395 -221.88678) (xy 341.381334 -221.79661)
					(xy 341.206074 -221.79661) (xy 341.147654 -221.88678) (xy 341.147654 -222.08617) (xy 341.20582 -222.17761)
				)
			)
		)
	)
	(footprint ""
		(layer "B.Cu")
		(at 186.203844 -97.663)
		(property "Reference" "R157"
			(at 0 0 0)
			(layer "B.SilkS")
			(hide yes)
			(effects
				(font
					(size 1.27 1.27)
				)
				(justify mirror)
			)
		)
		(property "Value" ""
			(at 0 0 0)
			(layer "B.Fab")
			(effects
				(font
					(size 1.27 1.27)
				)
				(justify mirror)
			)
		)
		(duplicate_pad_numbers_are_jumpers no)
		(fp_line
			(start -0.7874 -0.4064)
			(end -0.7874 0.4064)
			(stroke
				(width 0.1524)
				(type default)
			)
			(layer "B.SilkS")
		)
		(fp_line
			(start -0.7874 0.4064)
			(end 0.7874 0.4064)
			(stroke
				(width 0.1524)
				(type default)
			)
			(layer "B.SilkS")
		)
		(fp_line
			(start 0.7874 -0.4064)
			(end -0.7874 -0.4064)
			(stroke
				(width 0.1524)
				(type default)
			)
			(layer "B.SilkS")
		)
		(fp_line
			(start 0.7874 0.4064)
			(end 0.7874 -0.4064)
			(stroke
				(width 0.1524)
				(type default)
			)
			(layer "B.SilkS")
		)
		(fp_line
			(start -0.67945 -0.3048)
			(end -0.67945 0.3048)
			(stroke
				(width 0.1)
				(type default)
			)
			(layer "B.Fab")
		)
		(fp_line
			(start -0.67945 0.3048)
			(end -0.120396 0.3048)
			(stroke
				(width 0.1)
				(type default)
			)
			(layer "B.Fab")
		)
		(fp_line
			(start -0.12065 -0.3048)
			(end -0.67945 -0.3048)
			(stroke
				(width 0.1)
				(type default)
			)
			(layer "B.Fab")
		)
		(fp_line
			(start -0.12065 -0.2794)
			(end -0.12065 -0.3048)
			(stroke
				(width 0.1)
				(type default)
			)
			(layer "B.Fab")
		)
		(fp_line
			(start -0.120396 0.2794)
			(end 0.12065 0.2794)
			(stroke
				(width 0.1)
				(type default)
			)
			(layer "B.Fab")
		)
		(fp_line
			(start -0.120396 0.3048)
			(end -0.120396 0.2794)
			(stroke
				(width 0.1)
				(type default)
			)
			(layer "B.Fab")
		)
		(fp_line
			(start 0.12065 -0.305054)
			(end 0.12065 -0.2794)
			(stroke
				(width 0.1)
				(type default)
			)
			(layer "B.Fab")
		)
		(fp_line
			(start 0.12065 -0.2794)
			(end -0.12065 -0.2794)
			(stroke
				(width 0.1)
				(type default)
			)
			(layer "B.Fab")
		)
		(fp_line
			(start 0.12065 0.2794)
			(end 0.12065 0.3048)
			(stroke
				(width 0.1)
				(type default)
			)
			(layer "B.Fab")
		)
		(fp_line
			(start 0.12065 0.3048)
			(end 0.67945 0.3048)
			(stroke
				(width 0.1)
				(type default)
			)
			(layer "B.Fab")
		)
		(fp_line
			(start 0.67945 -0.305054)
			(end 0.12065 -0.305054)
			(stroke
				(width 0.1)
				(type default)
			)
			(layer "B.Fab")
		)
		(fp_line
			(start 0.67945 0.3048)
			(end 0.67945 -0.305054)
			(stroke
				(width 0.1)
				(type default)
			)
			(layer "B.Fab")
		)
		(pad "1" smd circle
			(at 0.40005 0 180)
			(size 0 0)
			(layers "B.Cu" "B.Mask" "B.Paste")
			(net "PWRGD_NIC3_PWR_GOOD")
		)
		(pad "2" smd circle
			(at -0.40005 0 180)
			(size 0 0)
			(layers "B.Cu" "B.Mask" "B.Paste")
			(net "PWRGD_NIC3_PWR_GOOD_R")
		)
	)
	(footprint ""
		(layer "B.Cu")
		(at 246.798592 -310.548528 -90)
		(property "Reference" "R845"
			(at 0 0 90)
			(layer "B.SilkS")
			(hide yes)
			(effects
				(font
					(size 1.27 1.27)
				)
				(justify mirror)
			)
		)
		(property "Value" ""
			(at 0 0 90)
			(layer "B.Fab")
			(effects
				(font
					(size 1.27 1.27)
				)
				(justify mirror)
			)
		)
		(duplicate_pad_numbers_are_jumpers no)
		(fp_line
			(start -0.7874 0.4064)
			(end 0.7874 0.4064)
			(stroke
				(width 0.1524)
				(type default)
			)
			(layer "B.SilkS")
		)
		(fp_line
			(start 0.7874 0.4064)
			(end 0.7874 -0.4064)
			(stroke
				(width 0.1524)
				(type default)
			)
			(layer "B.SilkS")
		)
		(fp_line
			(start -0.7874 -0.4064)
			(end -0.7874 0.4064)
			(stroke
				(width 0.1524)
				(type default)
			)
			(layer "B.SilkS")
		)
		(fp_line
			(start 0.7874 -0.4064)
			(end -0.7874 -0.4064)
			(stroke
				(width 0.1524)
				(type default)
			)
			(layer "B.SilkS")
		)
		(fp_line
			(start -0.67945 0.3048)
			(end -0.120396 0.3048)
			(stroke
				(width 0.1)
				(type default)
			)
			(layer "B.Fab")
		)
		(fp_line
			(start -0.120396 0.3048)
			(end -0.120396 0.2794)
			(stroke
				(width 0.1)
				(type default)
			)
			(layer "B.Fab")
		)
		(fp_line
			(start 0.12065 0.3048)
			(end 0.67945 0.3048)
			(stroke
				(width 0.1)
				(type default)
			)
			(layer "B.Fab")
		)
		(fp_line
			(start 0.67945 0.3048)
			(end 0.67945 -0.305054)
			(stroke
				(width 0.1)
				(type default)
			)
			(layer "B.Fab")
		)
		(fp_line
			(start -0.120396 0.2794)
			(end 0.12065 0.2794)
			(stroke
				(width 0.1)
				(type default)
			)
			(layer "B.Fab")
		)
		(fp_line
			(start 0.12065 0.2794)
			(end 0.12065 0.3048)
			(stroke
				(width 0.1)
				(type default)
			)
			(layer "B.Fab")
		)
		(fp_line
			(start -0.12065 -0.2794)
			(end -0.12065 -0.3048)
			(stroke
				(width 0.1)
				(type default)
			)
			(layer "B.Fab")
		)
		(fp_line
			(start 0.12065 -0.2794)
			(end -0.12065 -0.2794)
			(stroke
				(width 0.1)
				(type default)
			)
			(layer "B.Fab")
		)
		(fp_line
			(start -0.67945 -0.3048)
			(end -0.67945 0.3048)
			(stroke
				(width 0.1)
				(type default)
			)
			(layer "B.Fab")
		)
		(fp_line
			(start -0.12065 -0.3048)
			(end -0.67945 -0.3048)
			(stroke
				(width 0.1)
				(type default)
			)
			(layer "B.Fab")
		)
		(fp_line
			(start 0.12065 -0.305054)
			(end 0.12065 -0.2794)
			(stroke
				(width 0.1)
				(type default)
			)
			(layer "B.Fab")
		)
		(fp_line
			(start 0.67945 -0.305054)
			(end 0.12065 -0.305054)
			(stroke
				(width 0.1)
				(type default)
			)
			(layer "B.Fab")
		)
		(pad "1" smd circle
			(at 0.40005 0 90)
			(size 0 0)
			(layers "B.Cu" "B.Mask" "B.Paste")
			(net "P1V25_PEX2_VCC")
		)
		(pad "2" smd circle
			(at -0.40005 0 90)
			(size 0 0)
			(layers "B.Cu" "B.Mask" "B.Paste")
			(net "PWRGD_P1V25_PEX2")
		)
	)
	(footprint ""
		(layer "B.Cu")
		(at 193.641726 -98.021648 180)
		(property "Reference" "R166"
			(at 0 0 0)
			(layer "B.SilkS")
			(hide yes)
			(effects
				(font
					(size 1.27 1.27)
				)
				(justify mirror)
			)
		)
		(property "Value" ""
			(at 0 0 0)
			(layer "B.Fab")
			(effects
				(font
					(size 1.27 1.27)
				)
				(justify mirror)
			)
		)
		(duplicate_pad_numbers_are_jumpers no)
		(fp_line
			(start 0.7874 0.4064)
			(end 0.7874 -0.4064)
			(stroke
				(width 0.1524)
				(type default)
			)
			(layer "B.SilkS")
		)
		(fp_line
			(start 0.7874 -0.4064)
			(end -0.7874 -0.4064)
			(stroke
				(width 0.1524)
				(type default)
			)
			(layer "B.SilkS")
		)
		(fp_line
			(start -0.7874 0.4064)
			(end 0.7874 0.4064)
			(stroke
				(width 0.1524)
				(type default)
			)
			(layer "B.SilkS")
		)
		(fp_line
			(start -0.7874 -0.4064)
			(end -0.7874 0.4064)
			(stroke
				(width 0.1524)
				(type default)
			)
			(layer "B.SilkS")
		)
		(fp_line
			(start 0.67945 0.3048)
			(end 0.67945 -0.305054)
			(stroke
				(width 0.1)
				(type default)
			)
			(layer "B.Fab")
		)
		(fp_line
			(start 0.67945 -0.305054)
			(end 0.12065 -0.305054)
			(stroke
				(width 0.1)
				(type default)
			)
			(layer "B.Fab")
		)
		(fp_line
			(start 0.12065 0.3048)
			(end 0.67945 0.3048)
			(stroke
				(width 0.1)
				(type default)
			)
			(layer "B.Fab")
		)
		(fp_line
			(start 0.12065 0.2794)
			(end 0.12065 0.3048)
			(stroke
				(width 0.1)
				(type default)
			)
			(layer "B.Fab")
		)
		(fp_line
			(start 0.12065 -0.2794)
			(end -0.12065 -0.2794)
			(stroke
				(width 0.1)
				(type default)
			)
			(layer "B.Fab")
		)
		(fp_line
			(start 0.12065 -0.305054)
			(end 0.12065 -0.2794)
			(stroke
				(width 0.1)
				(type default)
			)
			(layer "B.Fab")
		)
		(fp_line
			(start -0.120396 0.3048)
			(end -0.120396 0.2794)
			(stroke
				(width 0.1)
				(type default)
			)
			(layer "B.Fab")
		)
		(fp_line
			(start -0.120396 0.2794)
			(end 0.12065 0.2794)
			(stroke
				(width 0.1)
				(type default)
			)
			(layer "B.Fab")
		)
		(fp_line
			(start -0.12065 -0.2794)
			(end -0.12065 -0.3048)
			(stroke
				(width 0.1)
				(type default)
			)
			(layer "B.Fab")
		)
		(fp_line
			(start -0.12065 -0.3048)
			(end -0.67945 -0.3048)
			(stroke
				(width 0.1)
				(type default)
			)
			(layer "B.Fab")
		)
		(fp_line
			(start -0.67945 0.3048)
			(end -0.120396 0.3048)
			(stroke
				(width 0.1)
				(type default)
			)
			(layer "B.Fab")
		)
		(fp_line
			(start -0.67945 -0.3048)
			(end -0.67945 0.3048)
			(stroke
				(width 0.1)
				(type default)
			)
			(layer "B.Fab")
		)
		(pad "1" smd circle
			(at 0.40005 0)
			(size 0 0)
			(layers "B.Cu" "B.Mask" "B.Paste")
			(net "NIC3_DATA_OUT")
		)
		(pad "2" smd circle
			(at -0.40005 0)
			(size 0 0)
			(layers "B.Cu" "B.Mask" "B.Paste")
			(net "GND")
		)
	)
	(footprint ""
		(layer "B.Cu")
		(at 303.49063 -118.711218 180)
		(property "Reference" "R279"
			(at 0 0 0)
			(layer "B.SilkS")
			(hide yes)
			(effects
				(font
					(size 1.27 1.27)
				)
				(justify mirror)
			)
		)
		(property "Value" ""
			(at 0 0 0)
			(layer "B.Fab")
			(effects
				(font
					(size 1.27 1.27)
				)
				(justify mirror)
			)
		)
		(duplicate_pad_numbers_are_jumpers no)
		(fp_line
			(start 0.7874 0.4064)
			(end 0.7874 -0.4064)
			(stroke
				(width 0.1524)
				(type default)
			)
			(layer "B.SilkS")
		)
		(fp_line
			(start 0.7874 -0.4064)
			(end -0.7874 -0.4064)
			(stroke
				(width 0.1524)
				(type default)
			)
			(layer "B.SilkS")
		)
		(fp_line
			(start -0.7874 0.4064)
			(end 0.7874 0.4064)
			(stroke
				(width 0.1524)
				(type default)
			)
			(layer "B.SilkS")
		)
		(fp_line
			(start -0.7874 -0.4064)
			(end -0.7874 0.4064)
			(stroke
				(width 0.1524)
				(type default)
			)
			(layer "B.SilkS")
		)
		(fp_line
			(start 0.67945 0.3048)
			(end 0.67945 -0.305054)
			(stroke
				(width 0.1)
				(type default)
			)
			(layer "B.Fab")
		)
		(fp_line
			(start 0.67945 -0.305054)
			(end 0.12065 -0.305054)
			(stroke
				(width 0.1)
				(type default)
			)
			(layer "B.Fab")
		)
		(fp_line
			(start 0.12065 0.3048)
			(end 0.67945 0.3048)
			(stroke
				(width 0.1)
				(type default)
			)
			(layer "B.Fab")
		)
		(fp_line
			(start 0.12065 0.2794)
			(end 0.12065 0.3048)
			(stroke
				(width 0.1)
				(type default)
			)
			(layer "B.Fab")
		)
		(fp_line
			(start 0.12065 -0.2794)
			(end -0.12065 -0.2794)
			(stroke
				(width 0.1)
				(type default)
			)
			(layer "B.Fab")
		)
		(fp_line
			(start 0.12065 -0.305054)
			(end 0.12065 -0.2794)
			(stroke
				(width 0.1)
				(type default)
			)
			(layer "B.Fab")
		)
		(fp_line
			(start -0.120396 0.3048)
			(end -0.120396 0.2794)
			(stroke
				(width 0.1)
				(type default)
			)
			(layer "B.Fab")
		)
		(fp_line
			(start -0.120396 0.2794)
			(end 0.12065 0.2794)
			(stroke
				(width 0.1)
				(type default)
			)
			(layer "B.Fab")
		)
		(fp_line
			(start -0.12065 -0.2794)
			(end -0.12065 -0.3048)
			(stroke
				(width 0.1)
				(type default)
			)
			(layer "B.Fab")
		)
		(fp_line
			(start -0.12065 -0.3048)
			(end -0.67945 -0.3048)
			(stroke
				(width 0.1)
				(type default)
			)
			(layer "B.Fab")
		)
		(fp_line
			(start -0.67945 0.3048)
			(end -0.120396 0.3048)
			(stroke
				(width 0.1)
				(type default)
			)
			(layer "B.Fab")
		)
		(fp_line
			(start -0.67945 -0.3048)
			(end -0.67945 0.3048)
			(stroke
				(width 0.1)
				(type default)
			)
			(layer "B.Fab")
		)
		(pad "1" smd circle
			(at 0.40005 0)
			(size 0 0)
			(layers "B.Cu" "B.Mask" "B.Paste")
			(net "NIC5_AUX_PWR_EN")
		)
		(pad "2" smd circle
			(at -0.40005 0)
			(size 0 0)
			(layers "B.Cu" "B.Mask" "B.Paste")
			(net "GND")
		)
	)
	(footprint ""
		(layer "B.Cu")
		(at 175.749966 -292.099746 90)
		(property "Reference" "C1487"
			(at 0 0 90)
			(layer "B.SilkS")
			(hide yes)
			(effects
				(font
					(size 1.27 1.27)
				)
				(justify mirror)
			)
		)
		(property "Value" ""
			(at 0 0 90)
			(layer "B.Fab")
			(effects
				(font
					(size 1.27 1.27)
				)
				(justify mirror)
			)
		)
		(duplicate_pad_numbers_are_jumpers no)
		(fp_line
			(start 0.299974 -0.150114)
			(end -0.299974 -0.150114)
			(stroke
				(width 0.1)
				(type default)
			)
			(layer "B.Fab")
		)
		(fp_line
			(start -0.299974 -0.150114)
			(end -0.299974 0.150114)
			(stroke
				(width 0.1)
				(type default)
			)
			(layer "B.Fab")
		)
		(fp_line
			(start 0.299974 0.150114)
			(end 0.299974 -0.150114)
			(stroke
				(width 0.1)
				(type default)
			)
			(layer "B.Fab")
		)
		(fp_line
			(start -0.299974 0.150114)
			(end 0.299974 0.150114)
			(stroke
				(width 0.1)
				(type default)
			)
			(layer "B.Fab")
		)
		(pad "1" smd rect
			(at 0.2667 0 270)
			(size 0.3048 0.381)
			(layers "B.Cu" "B.Mask" "B.Paste")
			(net "P0V8_SERDES_VDDA_PEX1")
		)
		(pad "2" smd rect
			(at -0.2667 0 270)
			(size 0.3048 0.381)
			(layers "B.Cu" "B.Mask" "B.Paste")
			(net "GND")
		)
	)
	(footprint ""
		(layer "B.Cu")
		(at 397.85544 -157.0736 180)
		(property "Reference" "R307"
			(at 0 0 0)
			(layer "B.SilkS")
			(hide yes)
			(effects
				(font
					(size 1.27 1.27)
				)
				(justify mirror)
			)
		)
		(property "Value" ""
			(at 0 0 0)
			(layer "B.Fab")
			(effects
				(font
					(size 1.27 1.27)
				)
				(justify mirror)
			)
		)
		(duplicate_pad_numbers_are_jumpers no)
		(fp_line
			(start 0.7874 0.4064)
			(end 0.7874 -0.4064)
			(stroke
				(width 0.1524)
				(type default)
			)
			(layer "B.SilkS")
		)
		(fp_line
			(start 0.7874 -0.4064)
			(end -0.7874 -0.4064)
			(stroke
				(width 0.1524)
				(type default)
			)
			(layer "B.SilkS")
		)
		(fp_line
			(start -0.7874 0.4064)
			(end 0.7874 0.4064)
			(stroke
				(width 0.1524)
				(type default)
			)
			(layer "B.SilkS")
		)
		(fp_line
			(start -0.7874 -0.4064)
			(end -0.7874 0.4064)
			(stroke
				(width 0.1524)
				(type default)
			)
			(layer "B.SilkS")
		)
		(fp_line
			(start 0.67945 0.3048)
			(end 0.67945 -0.305054)
			(stroke
				(width 0.1)
				(type default)
			)
			(layer "B.Fab")
		)
		(fp_line
			(start 0.67945 -0.305054)
			(end 0.12065 -0.305054)
			(stroke
				(width 0.1)
				(type default)
			)
			(layer "B.Fab")
		)
		(fp_line
			(start 0.12065 0.3048)
			(end 0.67945 0.3048)
			(stroke
				(width 0.1)
				(type default)
			)
			(layer "B.Fab")
		)
		(fp_line
			(start 0.12065 0.2794)
			(end 0.12065 0.3048)
			(stroke
				(width 0.1)
				(type default)
			)
			(layer "B.Fab")
		)
		(fp_line
			(start 0.12065 -0.2794)
			(end -0.12065 -0.2794)
			(stroke
				(width 0.1)
				(type default)
			)
			(layer "B.Fab")
		)
		(fp_line
			(start 0.12065 -0.305054)
			(end 0.12065 -0.2794)
			(stroke
				(width 0.1)
				(type default)
			)
			(layer "B.Fab")
		)
		(fp_line
			(start -0.120396 0.3048)
			(end -0.120396 0.2794)
			(stroke
				(width 0.1)
				(type default)
			)
			(layer "B.Fab")
		)
		(fp_line
			(start -0.120396 0.2794)
			(end 0.12065 0.2794)
			(stroke
				(width 0.1)
				(type default)
			)
			(layer "B.Fab")
		)
		(fp_line
			(start -0.12065 -0.2794)
			(end -0.12065 -0.3048)
			(stroke
				(width 0.1)
				(type default)
			)
			(layer "B.Fab")
		)
		(fp_line
			(start -0.12065 -0.3048)
			(end -0.67945 -0.3048)
			(stroke
				(width 0.1)
				(type default)
			)
			(layer "B.Fab")
		)
		(fp_line
			(start -0.67945 0.3048)
			(end -0.120396 0.3048)
			(stroke
				(width 0.1)
				(type default)
			)
			(layer "B.Fab")
		)
		(fp_line
			(start -0.67945 -0.3048)
			(end -0.67945 0.3048)
			(stroke
				(width 0.1)
				(type default)
			)
			(layer "B.Fab")
		)
		(pad "1" smd circle
			(at 0.40005 0)
			(size 0 0)
			(layers "B.Cu" "B.Mask" "B.Paste")
			(net "NIC6_RBT_ARB_OUT")
		)
		(pad "2" smd circle
			(at -0.40005 0)
			(size 0 0)
			(layers "B.Cu" "B.Mask" "B.Paste")
			(net "NIC6_RBT_ARB_IN")
		)
	)
	(footprint ""
		(layer "B.Cu")
		(at 294.251126 -305.399948 -90)
		(property "Reference" "C3314"
			(at 0 0 90)
			(layer "B.SilkS")
			(hide yes)
			(effects
				(font
					(size 1.27 1.27)
				)
				(justify mirror)
			)
		)
		(property "Value" ""
			(at 0 0 90)
			(layer "B.Fab")
			(effects
				(font
					(size 1.27 1.27)
				)
				(justify mirror)
			)
		)
		(duplicate_pad_numbers_are_jumpers no)
		(fp_line
			(start -0.299974 0.150114)
			(end 0.299974 0.150114)
			(stroke
				(width 0.1)
				(type default)
			)
			(layer "B.Fab")
		)
		(fp_line
			(start 0.299974 0.150114)
			(end 0.299974 -0.150114)
			(stroke
				(width 0.1)
				(type default)
			)
			(layer "B.Fab")
		)
		(fp_line
			(start -0.299974 -0.150114)
			(end -0.299974 0.150114)
			(stroke
				(width 0.1)
				(type default)
			)
			(layer "B.Fab")
		)
		(fp_line
			(start 0.299974 -0.150114)
			(end -0.299974 -0.150114)
			(stroke
				(width 0.1)
				(type default)
			)
			(layer "B.Fab")
		)
		(pad "1" smd rect
			(at 0.2667 0 90)
			(size 0.3048 0.381)
			(layers "B.Cu" "B.Mask" "B.Paste")
			(net "P1V25_SERDES_VDDPLL_PEX2")
		)
		(pad "2" smd rect
			(at -0.2667 0 90)
			(size 0.3048 0.381)
			(layers "B.Cu" "B.Mask" "B.Paste")
			(net "GND")
		)
	)
	(footprint ""
		(layer "B.Cu")
		(at 405.575008 -293.99992 -90)
		(property "Reference" "C1906"
			(at 0 0 90)
			(layer "B.SilkS")
			(hide yes)
			(effects
				(font
					(size 1.27 1.27)
				)
				(justify mirror)
			)
		)
		(property "Value" ""
			(at 0 0 90)
			(layer "B.Fab")
			(effects
				(font
					(size 1.27 1.27)
				)
				(justify mirror)
			)
		)
		(duplicate_pad_numbers_are_jumpers no)
		(fp_line
			(start -0.299974 0.150114)
			(end 0.299974 0.150114)
			(stroke
				(width 0.1)
				(type default)
			)
			(layer "B.Fab")
		)
		(fp_line
			(start 0.299974 0.150114)
			(end 0.299974 -0.150114)
			(stroke
				(width 0.1)
				(type default)
			)
			(layer "B.Fab")
		)
		(fp_line
			(start -0.299974 -0.150114)
			(end -0.299974 0.150114)
			(stroke
				(width 0.1)
				(type default)
			)
			(layer "B.Fab")
		)
		(fp_line
			(start 0.299974 -0.150114)
			(end -0.299974 -0.150114)
			(stroke
				(width 0.1)
				(type default)
			)
			(layer "B.Fab")
		)
		(pad "1" smd rect
			(at 0.2667 0 90)
			(size 0.3048 0.381)
			(layers "B.Cu" "B.Mask" "B.Paste")
			(net "P0V8_PEX3")
		)
		(pad "2" smd rect
			(at -0.2667 0 90)
			(size 0.3048 0.381)
			(layers "B.Cu" "B.Mask" "B.Paste")
			(net "GND")
		)
	)
	(footprint ""
		(layer "B.Cu")
		(at 100.571554 -308.4576 90)
		(property "Reference" "C4190"
			(at 0 0 90)
			(layer "B.SilkS")
			(hide yes)
			(effects
				(font
					(size 1.27 1.27)
				)
				(justify mirror)
			)
		)
		(property "Value" ""
			(at 0 0 90)
			(layer "B.Fab")
			(effects
				(font
					(size 1.27 1.27)
				)
				(justify mirror)
			)
		)
		(duplicate_pad_numbers_are_jumpers no)
		(fp_line
			(start 0.299974 -0.150114)
			(end -0.299974 -0.150114)
			(stroke
				(width 0.1)
				(type default)
			)
			(layer "B.Fab")
		)
		(fp_line
			(start -0.299974 -0.150114)
			(end -0.299974 0.150114)
			(stroke
				(width 0.1)
				(type default)
			)
			(layer "B.Fab")
		)
		(fp_line
			(start 0.299974 0.150114)
			(end 0.299974 -0.150114)
			(stroke
				(width 0.1)
				(type default)
			)
			(layer "B.Fab")
		)
		(fp_line
			(start -0.299974 0.150114)
			(end 0.299974 0.150114)
			(stroke
				(width 0.1)
				(type default)
			)
			(layer "B.Fab")
		)
		(pad "1" smd rect
			(at 0.2667 0 270)
			(size 0.3048 0.381)
			(layers "B.Cu" "B.Mask" "B.Paste")
			(net "P0V8_PEX0")
		)
		(pad "2" smd rect
			(at -0.2667 0 270)
			(size 0.3048 0.381)
			(layers "B.Cu" "B.Mask" "B.Paste")
			(net "GND")
		)
	)
	(footprint ""
		(layer "B.Cu")
		(at 113.337848 -325.161656 -90)
		(property "Reference" "C4213"
			(at 0 0 90)
			(layer "B.SilkS")
			(hide yes)
			(effects
				(font
					(size 1.27 1.27)
				)
				(justify mirror)
			)
		)
		(property "Value" ""
			(at 0 0 90)
			(layer "B.Fab")
			(effects
				(font
					(size 1.27 1.27)
				)
				(justify mirror)
			)
		)
		(duplicate_pad_numbers_are_jumpers no)
		(fp_line
			(start -1.2954 0.5842)
			(end 1.2954 0.5842)
			(stroke
				(width 0.1524)
				(type default)
			)
			(layer "B.SilkS")
		)
		(fp_line
			(start 1.2954 0.5842)
			(end 1.2954 -0.5842)
			(stroke
				(width 0.1524)
				(type default)
			)
			(layer "B.SilkS")
		)
		(fp_line
			(start -1.2954 -0.5842)
			(end -1.2954 0.5842)
			(stroke
				(width 0.1524)
				(type default)
			)
			(layer "B.SilkS")
		)
		(fp_line
			(start 1.2954 -0.5842)
			(end -1.2954 -0.5842)
			(stroke
				(width 0.1524)
				(type default)
			)
			(layer "B.SilkS")
		)
		(fp_line
			(start -0.8636 0.4572)
			(end 0.8636 0.4572)
			(stroke
				(width 0.1)
				(type default)
			)
			(layer "B.Fab")
		)
		(fp_line
			(start 0.8636 0.4572)
			(end 0.8636 0.4064)
			(stroke
				(width 0.1)
				(type default)
			)
			(layer "B.Fab")
		)
		(fp_line
			(start -1.1938 0.4064)
			(end -0.8636 0.4064)
			(stroke
				(width 0.1)
				(type default)
			)
			(layer "B.Fab")
		)
		(fp_line
			(start -0.8636 0.4064)
			(end -0.8636 0.4572)
			(stroke
				(width 0.1)
				(type default)
			)
			(layer "B.Fab")
		)
		(fp_line
			(start 0.8636 0.4064)
			(end 1.1938 0.4064)
			(stroke
				(width 0.1)
				(type default)
			)
			(layer "B.Fab")
		)
		(fp_line
			(start 1.1938 0.4064)
			(end 1.1938 -0.4064)
			(stroke
				(width 0.1)
				(type default)
			)
			(layer "B.Fab")
		)
		(fp_line
			(start -1.1938 -0.4064)
			(end -1.1938 0.4064)
			(stroke
				(width 0.1)
				(type default)
			)
			(layer "B.Fab")
		)
		(fp_line
			(start -0.8636 -0.4064)
			(end -1.1938 -0.4064)
			(stroke
				(width 0.1)
				(type default)
			)
			(layer "B.Fab")
		)
		(fp_line
			(start 0.8636 -0.4064)
			(end 0.8636 -0.4572)
			(stroke
				(width 0.1)
				(type default)
			)
			(layer "B.Fab")
		)
		(fp_line
			(start 1.1938 -0.4064)
			(end 0.8636 -0.4064)
			(stroke
				(width 0.1)
				(type default)
			)
			(layer "B.Fab")
		)
		(fp_line
			(start -0.8636 -0.4572)
			(end -0.8636 -0.4064)
			(stroke
				(width 0.1)
				(type default)
			)
			(layer "B.Fab")
		)
		(fp_line
			(start 0.8636 -0.4572)
			(end -0.8636 -0.4572)
			(stroke
				(width 0.1)
				(type default)
			)
			(layer "B.Fab")
		)
		(pad "1" smd rect
			(at 0.7366 0 180)
			(size 0.7112 0.8128)
			(layers "B.Cu" "B.Mask" "B.Paste")
			(net "P0V8_SERDES_VDDA_PEX0_C7")
		)
		(pad "2" smd rect
			(at -0.7366 0 180)
			(size 0.7112 0.8128)
			(layers "B.Cu" "B.Mask" "B.Paste")
			(net "GND")
		)
	)
	(footprint ""
		(layer "B.Cu")
		(at 405.520144 -305.399948 -90)
		(property "Reference" "C3487"
			(at 0 0 90)
			(layer "B.SilkS")
			(hide yes)
			(effects
				(font
					(size 1.27 1.27)
				)
				(justify mirror)
			)
		)
		(property "Value" ""
			(at 0 0 90)
			(layer "B.Fab")
			(effects
				(font
					(size 1.27 1.27)
				)
				(justify mirror)
			)
		)
		(duplicate_pad_numbers_are_jumpers no)
		(fp_line
			(start -0.299974 0.150114)
			(end 0.299974 0.150114)
			(stroke
				(width 0.1)
				(type default)
			)
			(layer "B.Fab")
		)
		(fp_line
			(start 0.299974 0.150114)
			(end 0.299974 -0.150114)
			(stroke
				(width 0.1)
				(type default)
			)
			(layer "B.Fab")
		)
		(fp_line
			(start -0.299974 -0.150114)
			(end -0.299974 0.150114)
			(stroke
				(width 0.1)
				(type default)
			)
			(layer "B.Fab")
		)
		(fp_line
			(start 0.299974 -0.150114)
			(end -0.299974 -0.150114)
			(stroke
				(width 0.1)
				(type default)
			)
			(layer "B.Fab")
		)
		(pad "1" smd rect
			(at 0.2667 0 90)
			(size 0.3048 0.381)
			(layers "B.Cu" "B.Mask" "B.Paste")
			(net "P1V25_SERDES_VDDPLL_PEX3")
		)
		(pad "2" smd rect
			(at -0.2667 0 90)
			(size 0.3048 0.381)
			(layers "B.Cu" "B.Mask" "B.Paste")
			(net "GND")
		)
	)
	(footprint ""
		(layer "B.Cu")
		(at 189.049914 -294.94988 180)
		(property "Reference" "C3121"
			(at 0 0 0)
			(layer "B.SilkS")
			(hide yes)
			(effects
				(font
					(size 1.27 1.27)
				)
				(justify mirror)
			)
		)
		(property "Value" ""
			(at 0 0 0)
			(layer "B.Fab")
			(effects
				(font
					(size 1.27 1.27)
				)
				(justify mirror)
			)
		)
		(duplicate_pad_numbers_are_jumpers no)
		(fp_line
			(start 0.299974 0.150114)
			(end 0.299974 -0.150114)
			(stroke
				(width 0.1)
				(type default)
			)
			(layer "B.Fab")
		)
		(fp_line
			(start 0.299974 -0.150114)
			(end -0.299974 -0.150114)
			(stroke
				(width 0.1)
				(type default)
			)
			(layer "B.Fab")
		)
		(fp_line
			(start -0.299974 0.150114)
			(end 0.299974 0.150114)
			(stroke
				(width 0.1)
				(type default)
			)
			(layer "B.Fab")
		)
		(fp_line
			(start -0.299974 -0.150114)
			(end -0.299974 0.150114)
			(stroke
				(width 0.1)
				(type default)
			)
			(layer "B.Fab")
		)
		(pad "1" smd rect
			(at 0.2667 0)
			(size 0.3048 0.381)
			(layers "B.Cu" "B.Mask" "B.Paste")
			(net "P1V25_SERDES_VDDPLL_PEX1")
		)
		(pad "2" smd rect
			(at -0.2667 0)
			(size 0.3048 0.381)
			(layers "B.Cu" "B.Mask" "B.Paste")
			(net "GND")
		)
	)
	(footprint ""
		(layer "B.Cu")
		(at 399.400014 -292.099746 90)
		(property "Reference" "C1954"
			(at 0 0 90)
			(layer "B.SilkS")
			(hide yes)
			(effects
				(font
					(size 1.27 1.27)
				)
				(justify mirror)
			)
		)
		(property "Value" ""
			(at 0 0 90)
			(layer "B.Fab")
			(effects
				(font
					(size 1.27 1.27)
				)
				(justify mirror)
			)
		)
		(duplicate_pad_numbers_are_jumpers no)
		(fp_line
			(start 0.299974 -0.150114)
			(end -0.299974 -0.150114)
			(stroke
				(width 0.1)
				(type default)
			)
			(layer "B.Fab")
		)
		(fp_line
			(start -0.299974 -0.150114)
			(end -0.299974 0.150114)
			(stroke
				(width 0.1)
				(type default)
			)
			(layer "B.Fab")
		)
		(fp_line
			(start 0.299974 0.150114)
			(end 0.299974 -0.150114)
			(stroke
				(width 0.1)
				(type default)
			)
			(layer "B.Fab")
		)
		(fp_line
			(start -0.299974 0.150114)
			(end 0.299974 0.150114)
			(stroke
				(width 0.1)
				(type default)
			)
			(layer "B.Fab")
		)
		(pad "1" smd rect
			(at 0.2667 0 270)
			(size 0.3048 0.381)
			(layers "B.Cu" "B.Mask" "B.Paste")
			(net "P0V8_SERDES_VDDA_PEX3")
		)
		(pad "2" smd rect
			(at -0.2667 0 270)
			(size 0.3048 0.381)
			(layers "B.Cu" "B.Mask" "B.Paste")
			(net "GND")
		)
	)
	(footprint ""
		(layer "B.Cu")
		(at 290.42487 -286.399732 90)
		(property "Reference" "C3307"
			(at 0 0 90)
			(layer "B.SilkS")
			(hide yes)
			(effects
				(font
					(size 1.27 1.27)
				)
				(justify mirror)
			)
		)
		(property "Value" ""
			(at 0 0 90)
			(layer "B.Fab")
			(effects
				(font
					(size 1.27 1.27)
				)
				(justify mirror)
			)
		)
		(duplicate_pad_numbers_are_jumpers no)
		(fp_line
			(start 0.299974 -0.150114)
			(end -0.299974 -0.150114)
			(stroke
				(width 0.1)
				(type default)
			)
			(layer "B.Fab")
		)
		(fp_line
			(start -0.299974 -0.150114)
			(end -0.299974 0.150114)
			(stroke
				(width 0.1)
				(type default)
			)
			(layer "B.Fab")
		)
		(fp_line
			(start 0.299974 0.150114)
			(end 0.299974 -0.150114)
			(stroke
				(width 0.1)
				(type default)
			)
			(layer "B.Fab")
		)
		(fp_line
			(start -0.299974 0.150114)
			(end 0.299974 0.150114)
			(stroke
				(width 0.1)
				(type default)
			)
			(layer "B.Fab")
		)
		(pad "1" smd rect
			(at 0.2667 0 270)
			(size 0.3048 0.381)
			(layers "B.Cu" "B.Mask" "B.Paste")
			(net "P1V25_SERDES_VDDPLL_PEX2")
		)
		(pad "2" smd rect
			(at -0.2667 0 270)
			(size 0.3048 0.381)
			(layers "B.Cu" "B.Mask" "B.Paste")
			(net "GND")
		)
	)
	(footprint ""
		(layer "B.Cu")
		(at 214.454486 -216.270586 180)
		(property "Reference" "R5720"
			(at 0 0 0)
			(layer "B.SilkS")
			(hide yes)
			(effects
				(font
					(size 1.27 1.27)
				)
				(justify mirror)
			)
		)
		(property "Value" ""
			(at 0 0 0)
			(layer "B.Fab")
			(effects
				(font
					(size 1.27 1.27)
				)
				(justify mirror)
			)
		)
		(duplicate_pad_numbers_are_jumpers no)
		(fp_line
			(start 0.7874 0.4064)
			(end 0.7874 -0.4064)
			(stroke
				(width 0.1524)
				(type default)
			)
			(layer "B.SilkS")
		)
		(fp_line
			(start 0.7874 -0.4064)
			(end -0.7874 -0.4064)
			(stroke
				(width 0.1524)
				(type default)
			)
			(layer "B.SilkS")
		)
		(fp_line
			(start -0.7874 0.4064)
			(end 0.7874 0.4064)
			(stroke
				(width 0.1524)
				(type default)
			)
			(layer "B.SilkS")
		)
		(fp_line
			(start -0.7874 -0.4064)
			(end -0.7874 0.4064)
			(stroke
				(width 0.1524)
				(type default)
			)
			(layer "B.SilkS")
		)
		(fp_line
			(start 0.67945 0.3048)
			(end 0.67945 -0.305054)
			(stroke
				(width 0.1)
				(type default)
			)
			(layer "B.Fab")
		)
		(fp_line
			(start 0.67945 -0.305054)
			(end 0.12065 -0.305054)
			(stroke
				(width 0.1)
				(type default)
			)
			(layer "B.Fab")
		)
		(fp_line
			(start 0.12065 0.3048)
			(end 0.67945 0.3048)
			(stroke
				(width 0.1)
				(type default)
			)
			(layer "B.Fab")
		)
		(fp_line
			(start 0.12065 0.2794)
			(end 0.12065 0.3048)
			(stroke
				(width 0.1)
				(type default)
			)
			(layer "B.Fab")
		)
		(fp_line
			(start 0.12065 -0.2794)
			(end -0.12065 -0.2794)
			(stroke
				(width 0.1)
				(type default)
			)
			(layer "B.Fab")
		)
		(fp_line
			(start 0.12065 -0.305054)
			(end 0.12065 -0.2794)
			(stroke
				(width 0.1)
				(type default)
			)
			(layer "B.Fab")
		)
		(fp_line
			(start -0.120396 0.3048)
			(end -0.120396 0.2794)
			(stroke
				(width 0.1)
				(type default)
			)
			(layer "B.Fab")
		)
		(fp_line
			(start -0.120396 0.2794)
			(end 0.12065 0.2794)
			(stroke
				(width 0.1)
				(type default)
			)
			(layer "B.Fab")
		)
		(fp_line
			(start -0.12065 -0.2794)
			(end -0.12065 -0.3048)
			(stroke
				(width 0.1)
				(type default)
			)
			(layer "B.Fab")
		)
		(fp_line
			(start -0.12065 -0.3048)
			(end -0.67945 -0.3048)
			(stroke
				(width 0.1)
				(type default)
			)
			(layer "B.Fab")
		)
		(fp_line
			(start -0.67945 0.3048)
			(end -0.120396 0.3048)
			(stroke
				(width 0.1)
				(type default)
			)
			(layer "B.Fab")
		)
		(fp_line
			(start -0.67945 -0.3048)
			(end -0.67945 0.3048)
			(stroke
				(width 0.1)
				(type default)
			)
			(layer "B.Fab")
		)
		(pad "1" smd circle
			(at 0.40005 0)
			(size 0 0)
			(layers "B.Cu" "B.Mask" "B.Paste")
			(net "RST_BIC_I2C6_MUX_R_N")
		)
		(pad "2" smd circle
			(at -0.40005 0)
			(size 0 0)
			(layers "B.Cu" "B.Mask" "B.Paste")
			(net "RST_BIC_I2C6_MUX_N")
		)
	)
	(footprint ""
		(layer "B.Cu")
		(at 178.599846 -288.299906 90)
		(property "Reference" "C3111"
			(at 0 0 90)
			(layer "B.SilkS")
			(hide yes)
			(effects
				(font
					(size 1.27 1.27)
				)
				(justify mirror)
			)
		)
		(property "Value" ""
			(at 0 0 90)
			(layer "B.Fab")
			(effects
				(font
					(size 1.27 1.27)
				)
				(justify mirror)
			)
		)
		(duplicate_pad_numbers_are_jumpers no)
		(fp_line
			(start 0.299974 -0.150114)
			(end -0.299974 -0.150114)
			(stroke
				(width 0.1)
				(type default)
			)
			(layer "B.Fab")
		)
		(fp_line
			(start -0.299974 -0.150114)
			(end -0.299974 0.150114)
			(stroke
				(width 0.1)
				(type default)
			)
			(layer "B.Fab")
		)
		(fp_line
			(start 0.299974 0.150114)
			(end 0.299974 -0.150114)
			(stroke
				(width 0.1)
				(type default)
			)
			(layer "B.Fab")
		)
		(fp_line
			(start -0.299974 0.150114)
			(end 0.299974 0.150114)
			(stroke
				(width 0.1)
				(type default)
			)
			(layer "B.Fab")
		)
		(pad "1" smd rect
			(at 0.2667 0 270)
			(size 0.3048 0.381)
			(layers "B.Cu" "B.Mask" "B.Paste")
			(net "P1V25_PEX1")
		)
		(pad "2" smd rect
			(at -0.2667 0 270)
			(size 0.3048 0.381)
			(layers "B.Cu" "B.Mask" "B.Paste")
			(net "GND")
		)
	)
	(footprint ""
		(layer "B.Cu")
		(at 410.324808 -286.399732 90)
		(property "Reference" "C3481"
			(at 0 0 90)
			(layer "B.SilkS")
			(hide yes)
			(effects
				(font
					(size 1.27 1.27)
				)
				(justify mirror)
			)
		)
		(property "Value" ""
			(at 0 0 90)
			(layer "B.Fab")
			(effects
				(font
					(size 1.27 1.27)
				)
				(justify mirror)
			)
		)
		(duplicate_pad_numbers_are_jumpers no)
		(fp_line
			(start 0.299974 -0.150114)
			(end -0.299974 -0.150114)
			(stroke
				(width 0.1)
				(type default)
			)
			(layer "B.Fab")
		)
		(fp_line
			(start -0.299974 -0.150114)
			(end -0.299974 0.150114)
			(stroke
				(width 0.1)
				(type default)
			)
			(layer "B.Fab")
		)
		(fp_line
			(start 0.299974 0.150114)
			(end 0.299974 -0.150114)
			(stroke
				(width 0.1)
				(type default)
			)
			(layer "B.Fab")
		)
		(fp_line
			(start -0.299974 0.150114)
			(end 0.299974 0.150114)
			(stroke
				(width 0.1)
				(type default)
			)
			(layer "B.Fab")
		)
		(pad "1" smd rect
			(at 0.2667 0 270)
			(size 0.3048 0.381)
			(layers "B.Cu" "B.Mask" "B.Paste")
			(net "P1V25_SERDES_VDDPLL_PEX3")
		)
		(pad "2" smd rect
			(at -0.2667 0 270)
			(size 0.3048 0.381)
			(layers "B.Cu" "B.Mask" "B.Paste")
			(net "GND")
		)
	)
	(footprint ""
		(layer "B.Cu")
		(at 234.724956 -272.889218)
		(property "Reference" "C4333"
			(at 0 0 0)
			(layer "B.SilkS")
			(hide yes)
			(effects
				(font
					(size 1.27 1.27)
				)
				(justify mirror)
			)
		)
		(property "Value" ""
			(at 0 0 0)
			(layer "B.Fab")
			(effects
				(font
					(size 1.27 1.27)
				)
				(justify mirror)
			)
		)
		(duplicate_pad_numbers_are_jumpers no)
		(fp_line
			(start -1.2954 -0.5842)
			(end -1.2954 0.5842)
			(stroke
				(width 0.1524)
				(type default)
			)
			(layer "B.SilkS")
		)
		(fp_line
			(start -1.2954 0.5842)
			(end 1.2954 0.5842)
			(stroke
				(width 0.1524)
				(type default)
			)
			(layer "B.SilkS")
		)
		(fp_line
			(start 1.2954 -0.5842)
			(end -1.2954 -0.5842)
			(stroke
				(width 0.1524)
				(type default)
			)
			(layer "B.SilkS")
		)
		(fp_line
			(start 1.2954 0.5842)
			(end 1.2954 -0.5842)
			(stroke
				(width 0.1524)
				(type default)
			)
			(layer "B.SilkS")
		)
		(fp_line
			(start -1.1938 -0.4064)
			(end -1.1938 0.4064)
			(stroke
				(width 0.1)
				(type default)
			)
			(layer "B.Fab")
		)
		(fp_line
			(start -1.1938 0.4064)
			(end -0.8636 0.4064)
			(stroke
				(width 0.1)
				(type default)
			)
			(layer "B.Fab")
		)
		(fp_line
			(start -0.8636 -0.4572)
			(end -0.8636 -0.4064)
			(stroke
				(width 0.1)
				(type default)
			)
			(layer "B.Fab")
		)
		(fp_line
			(start -0.8636 -0.4064)
			(end -1.1938 -0.4064)
			(stroke
				(width 0.1)
				(type default)
			)
			(layer "B.Fab")
		)
		(fp_line
			(start -0.8636 0.4064)
			(end -0.8636 0.4572)
			(stroke
				(width 0.1)
				(type default)
			)
			(layer "B.Fab")
		)
		(fp_line
			(start -0.8636 0.4572)
			(end 0.8636 0.4572)
			(stroke
				(width 0.1)
				(type default)
			)
			(layer "B.Fab")
		)
		(fp_line
			(start 0.8636 -0.4572)
			(end -0.8636 -0.4572)
			(stroke
				(width 0.1)
				(type default)
			)
			(layer "B.Fab")
		)
		(fp_line
			(start 0.8636 -0.4064)
			(end 0.8636 -0.4572)
			(stroke
				(width 0.1)
				(type default)
			)
			(layer "B.Fab")
		)
		(fp_line
			(start 0.8636 0.4064)
			(end 1.1938 0.4064)
			(stroke
				(width 0.1)
				(type default)
			)
			(layer "B.Fab")
		)
		(fp_line
			(start 0.8636 0.4572)
			(end 0.8636 0.4064)
			(stroke
				(width 0.1)
				(type default)
			)
			(layer "B.Fab")
		)
		(fp_line
			(start 1.1938 -0.4064)
			(end 0.8636 -0.4064)
			(stroke
				(width 0.1)
				(type default)
			)
			(layer "B.Fab")
		)
		(fp_line
			(start 1.1938 0.4064)
			(end 1.1938 -0.4064)
			(stroke
				(width 0.1)
				(type default)
			)
			(layer "B.Fab")
		)
		(pad "1" smd rect
			(at 0.7366 0 270)
			(size 0.7112 0.8128)
			(layers "B.Cu" "B.Mask" "B.Paste")
			(net "P1V25_PEX2")
		)
		(pad "2" smd rect
			(at -0.7366 0 270)
			(size 0.7112 0.8128)
			(layers "B.Cu" "B.Mask" "B.Paste")
			(net "GND")
		)
	)
	(footprint ""
		(layer "B.Cu")
		(at 217.700606 -273.94154)
		(property "Reference" "C4277"
			(at 0 0 0)
			(layer "B.SilkS")
			(hide yes)
			(effects
				(font
					(size 1.27 1.27)
				)
				(justify mirror)
			)
		)
		(property "Value" ""
			(at 0 0 0)
			(layer "B.Fab")
			(effects
				(font
					(size 1.27 1.27)
				)
				(justify mirror)
			)
		)
		(duplicate_pad_numbers_are_jumpers no)
		(fp_line
			(start -1.2954 -0.5842)
			(end -1.2954 0.5842)
			(stroke
				(width 0.1524)
				(type default)
			)
			(layer "B.SilkS")
		)
		(fp_line
			(start -1.2954 0.5842)
			(end 1.2954 0.5842)
			(stroke
				(width 0.1524)
				(type default)
			)
			(layer "B.SilkS")
		)
		(fp_line
			(start 1.2954 -0.5842)
			(end -1.2954 -0.5842)
			(stroke
				(width 0.1524)
				(type default)
			)
			(layer "B.SilkS")
		)
		(fp_line
			(start 1.2954 0.5842)
			(end 1.2954 -0.5842)
			(stroke
				(width 0.1524)
				(type default)
			)
			(layer "B.SilkS")
		)
		(fp_line
			(start -1.1938 -0.4064)
			(end -1.1938 0.4064)
			(stroke
				(width 0.1)
				(type default)
			)
			(layer "B.Fab")
		)
		(fp_line
			(start -1.1938 0.4064)
			(end -0.8636 0.4064)
			(stroke
				(width 0.1)
				(type default)
			)
			(layer "B.Fab")
		)
		(fp_line
			(start -0.8636 -0.4572)
			(end -0.8636 -0.4064)
			(stroke
				(width 0.1)
				(type default)
			)
			(layer "B.Fab")
		)
		(fp_line
			(start -0.8636 -0.4064)
			(end -1.1938 -0.4064)
			(stroke
				(width 0.1)
				(type default)
			)
			(layer "B.Fab")
		)
		(fp_line
			(start -0.8636 0.4064)
			(end -0.8636 0.4572)
			(stroke
				(width 0.1)
				(type default)
			)
			(layer "B.Fab")
		)
		(fp_line
			(start -0.8636 0.4572)
			(end 0.8636 0.4572)
			(stroke
				(width 0.1)
				(type default)
			)
			(layer "B.Fab")
		)
		(fp_line
			(start 0.8636 -0.4572)
			(end -0.8636 -0.4572)
			(stroke
				(width 0.1)
				(type default)
			)
			(layer "B.Fab")
		)
		(fp_line
			(start 0.8636 -0.4064)
			(end 0.8636 -0.4572)
			(stroke
				(width 0.1)
				(type default)
			)
			(layer "B.Fab")
		)
		(fp_line
			(start 0.8636 0.4064)
			(end 1.1938 0.4064)
			(stroke
				(width 0.1)
				(type default)
			)
			(layer "B.Fab")
		)
		(fp_line
			(start 0.8636 0.4572)
			(end 0.8636 0.4064)
			(stroke
				(width 0.1)
				(type default)
			)
			(layer "B.Fab")
		)
		(fp_line
			(start 1.1938 -0.4064)
			(end 0.8636 -0.4064)
			(stroke
				(width 0.1)
				(type default)
			)
			(layer "B.Fab")
		)
		(fp_line
			(start 1.1938 0.4064)
			(end 1.1938 -0.4064)
			(stroke
				(width 0.1)
				(type default)
			)
			(layer "B.Fab")
		)
		(pad "1" smd rect
			(at 0.7366 0 270)
			(size 0.7112 0.8128)
			(layers "B.Cu" "B.Mask" "B.Paste")
			(net "P1V25_PEX1")
		)
		(pad "2" smd rect
			(at -0.7366 0 270)
			(size 0.7112 0.8128)
			(layers "B.Cu" "B.Mask" "B.Paste")
			(net "GND")
		)
	)
	(footprint ""
		(layer "B.Cu")
		(at 209.384392 -234.033822)
		(property "Reference" "R6328"
			(at 0 0 0)
			(layer "B.SilkS")
			(hide yes)
			(effects
				(font
					(size 1.27 1.27)
				)
				(justify mirror)
			)
		)
		(property "Value" ""
			(at 0 0 0)
			(layer "B.Fab")
			(effects
				(font
					(size 1.27 1.27)
				)
				(justify mirror)
			)
		)
		(duplicate_pad_numbers_are_jumpers no)
		(fp_line
			(start -0.7874 -0.4064)
			(end -0.7874 0.4064)
			(stroke
				(width 0.1524)
				(type default)
			)
			(layer "B.SilkS")
		)
		(fp_line
			(start -0.7874 0.4064)
			(end 0.7874 0.4064)
			(stroke
				(width 0.1524)
				(type default)
			)
			(layer "B.SilkS")
		)
		(fp_line
			(start 0.7874 -0.4064)
			(end -0.7874 -0.4064)
			(stroke
				(width 0.1524)
				(type default)
			)
			(layer "B.SilkS")
		)
		(fp_line
			(start 0.7874 0.4064)
			(end 0.7874 -0.4064)
			(stroke
				(width 0.1524)
				(type default)
			)
			(layer "B.SilkS")
		)
		(fp_line
			(start -0.67945 -0.3048)
			(end -0.67945 0.3048)
			(stroke
				(width 0.1)
				(type default)
			)
			(layer "B.Fab")
		)
		(fp_line
			(start -0.67945 0.3048)
			(end -0.120396 0.3048)
			(stroke
				(width 0.1)
				(type default)
			)
			(layer "B.Fab")
		)
		(fp_line
			(start -0.12065 -0.3048)
			(end -0.67945 -0.3048)
			(stroke
				(width 0.1)
				(type default)
			)
			(layer "B.Fab")
		)
		(fp_line
			(start -0.12065 -0.2794)
			(end -0.12065 -0.3048)
			(stroke
				(width 0.1)
				(type default)
			)
			(layer "B.Fab")
		)
		(fp_line
			(start -0.120396 0.2794)
			(end 0.12065 0.2794)
			(stroke
				(width 0.1)
				(type default)
			)
			(layer "B.Fab")
		)
		(fp_line
			(start -0.120396 0.3048)
			(end -0.120396 0.2794)
			(stroke
				(width 0.1)
				(type default)
			)
			(layer "B.Fab")
		)
		(fp_line
			(start 0.12065 -0.305054)
			(end 0.12065 -0.2794)
			(stroke
				(width 0.1)
				(type default)
			)
			(layer "B.Fab")
		)
		(fp_line
			(start 0.12065 -0.2794)
			(end -0.12065 -0.2794)
			(stroke
				(width 0.1)
				(type default)
			)
			(layer "B.Fab")
		)
		(fp_line
			(start 0.12065 0.2794)
			(end 0.12065 0.3048)
			(stroke
				(width 0.1)
				(type default)
			)
			(layer "B.Fab")
		)
		(fp_line
			(start 0.12065 0.3048)
			(end 0.67945 0.3048)
			(stroke
				(width 0.1)
				(type default)
			)
			(layer "B.Fab")
		)
		(fp_line
			(start 0.67945 -0.305054)
			(end 0.12065 -0.305054)
			(stroke
				(width 0.1)
				(type default)
			)
			(layer "B.Fab")
		)
		(fp_line
			(start 0.67945 0.3048)
			(end 0.67945 -0.305054)
			(stroke
				(width 0.1)
				(type default)
			)
			(layer "B.Fab")
		)
		(pad "1" smd circle
			(at 0.40005 0 180)
			(size 0 0)
			(layers "B.Cu" "B.Mask" "B.Paste")
			(net "SMB_PEX2_SDA")
		)
		(pad "2" smd circle
			(at -0.40005 0 180)
			(size 0 0)
			(layers "B.Cu" "B.Mask" "B.Paste")
			(net "SMB_PEX2_MUX_SDA")
		)
	)
	(footprint ""
		(layer "B.Cu")
		(at 185.725054 -304.241454 90)
		(property "Reference" "C3186"
			(at 0 0 90)
			(layer "B.SilkS")
			(hide yes)
			(effects
				(font
					(size 1.27 1.27)
				)
				(justify mirror)
			)
		)
		(property "Value" ""
			(at 0 0 90)
			(layer "B.Fab")
			(effects
				(font
					(size 1.27 1.27)
				)
				(justify mirror)
			)
		)
		(duplicate_pad_numbers_are_jumpers no)
		(fp_line
			(start 0.299974 -0.150114)
			(end -0.299974 -0.150114)
			(stroke
				(width 0.1)
				(type default)
			)
			(layer "B.Fab")
		)
		(fp_line
			(start -0.299974 -0.150114)
			(end -0.299974 0.150114)
			(stroke
				(width 0.1)
				(type default)
			)
			(layer "B.Fab")
		)
		(fp_line
			(start 0.299974 0.150114)
			(end 0.299974 -0.150114)
			(stroke
				(width 0.1)
				(type default)
			)
			(layer "B.Fab")
		)
		(fp_line
			(start -0.299974 0.150114)
			(end 0.299974 0.150114)
			(stroke
				(width 0.1)
				(type default)
			)
			(layer "B.Fab")
		)
		(pad "1" smd rect
			(at 0.2667 0 270)
			(size 0.3048 0.381)
			(layers "B.Cu" "B.Mask" "B.Paste")
			(net "P1V8_VDDA_PEX1")
		)
		(pad "2" smd rect
			(at -0.2667 0 270)
			(size 0.3048 0.381)
			(layers "B.Cu" "B.Mask" "B.Paste")
			(net "GND")
		)
	)
	(footprint ""
		(layer "B.Cu")
		(at 117.097556 -308.580028 90)
		(property "Reference" "C1159"
			(at 0 0 90)
			(layer "B.SilkS")
			(hide yes)
			(effects
				(font
					(size 1.27 1.27)
				)
				(justify mirror)
			)
		)
		(property "Value" ""
			(at 0 0 90)
			(layer "B.Fab")
			(effects
				(font
					(size 1.27 1.27)
				)
				(justify mirror)
			)
		)
		(duplicate_pad_numbers_are_jumpers no)
		(fp_line
			(start 1.2954 -0.5842)
			(end -1.2954 -0.5842)
			(stroke
				(width 0.1524)
				(type default)
			)
			(layer "B.SilkS")
		)
		(fp_line
			(start -1.2954 -0.5842)
			(end -1.2954 0.5842)
			(stroke
				(width 0.1524)
				(type default)
			)
			(layer "B.SilkS")
		)
		(fp_line
			(start 1.2954 0.5842)
			(end 1.2954 -0.5842)
			(stroke
				(width 0.1524)
				(type default)
			)
			(layer "B.SilkS")
		)
		(fp_line
			(start -1.2954 0.5842)
			(end 1.2954 0.5842)
			(stroke
				(width 0.1524)
				(type default)
			)
			(layer "B.SilkS")
		)
		(fp_line
			(start 0.8636 -0.4572)
			(end -0.8636 -0.4572)
			(stroke
				(width 0.1)
				(type default)
			)
			(layer "B.Fab")
		)
		(fp_line
			(start -0.8636 -0.4572)
			(end -0.8636 -0.4064)
			(stroke
				(width 0.1)
				(type default)
			)
			(layer "B.Fab")
		)
		(fp_line
			(start 1.1938 -0.4064)
			(end 0.8636 -0.4064)
			(stroke
				(width 0.1)
				(type default)
			)
			(layer "B.Fab")
		)
		(fp_line
			(start 0.8636 -0.4064)
			(end 0.8636 -0.4572)
			(stroke
				(width 0.1)
				(type default)
			)
			(layer "B.Fab")
		)
		(fp_line
			(start -0.8636 -0.4064)
			(end -1.1938 -0.4064)
			(stroke
				(width 0.1)
				(type default)
			)
			(layer "B.Fab")
		)
		(fp_line
			(start -1.1938 -0.4064)
			(end -1.1938 0.4064)
			(stroke
				(width 0.1)
				(type default)
			)
			(layer "B.Fab")
		)
		(fp_line
			(start 1.1938 0.4064)
			(end 1.1938 -0.4064)
			(stroke
				(width 0.1)
				(type default)
			)
			(layer "B.Fab")
		)
		(fp_line
			(start 0.8636 0.4064)
			(end 1.1938 0.4064)
			(stroke
				(width 0.1)
				(type default)
			)
			(layer "B.Fab")
		)
		(fp_line
			(start -0.8636 0.4064)
			(end -0.8636 0.4572)
			(stroke
				(width 0.1)
				(type default)
			)
			(layer "B.Fab")
		)
		(fp_line
			(start -1.1938 0.4064)
			(end -0.8636 0.4064)
			(stroke
				(width 0.1)
				(type default)
			)
			(layer "B.Fab")
		)
		(fp_line
			(start 0.8636 0.4572)
			(end 0.8636 0.4064)
			(stroke
				(width 0.1)
				(type default)
			)
			(layer "B.Fab")
		)
		(fp_line
			(start -0.8636 0.4572)
			(end 0.8636 0.4572)
			(stroke
				(width 0.1)
				(type default)
			)
			(layer "B.Fab")
		)
		(pad "1" smd rect
			(at 0.7366 0)
			(size 0.7112 0.8128)
			(layers "B.Cu" "B.Mask" "B.Paste")
			(net "P0V8_SERDES_VDDA_PEX0")
		)
		(pad "2" smd rect
			(at -0.7366 0)
			(size 0.7112 0.8128)
			(layers "B.Cu" "B.Mask" "B.Paste")
			(net "GND")
		)
	)
	(footprint ""
		(layer "B.Cu")
		(at 212.09 -194.183 90)
		(property "Reference" "R1535"
			(at 0 0 90)
			(layer "B.SilkS")
			(hide yes)
			(effects
				(font
					(size 1.27 1.27)
				)
				(justify mirror)
			)
		)
		(property "Value" ""
			(at 0 0 90)
			(layer "B.Fab")
			(effects
				(font
					(size 1.27 1.27)
				)
				(justify mirror)
			)
		)
		(duplicate_pad_numbers_are_jumpers no)
		(fp_line
			(start 0.7874 -0.4064)
			(end -0.7874 -0.4064)
			(stroke
				(width 0.1524)
				(type default)
			)
			(layer "B.SilkS")
		)
		(fp_line
			(start -0.7874 -0.4064)
			(end -0.7874 0.4064)
			(stroke
				(width 0.1524)
				(type default)
			)
			(layer "B.SilkS")
		)
		(fp_line
			(start 0.7874 0.4064)
			(end 0.7874 -0.4064)
			(stroke
				(width 0.1524)
				(type default)
			)
			(layer "B.SilkS")
		)
		(fp_line
			(start -0.7874 0.4064)
			(end 0.7874 0.4064)
			(stroke
				(width 0.1524)
				(type default)
			)
			(layer "B.SilkS")
		)
		(fp_line
			(start 0.67945 -0.305054)
			(end 0.12065 -0.305054)
			(stroke
				(width 0.1)
				(type default)
			)
			(layer "B.Fab")
		)
		(fp_line
			(start 0.12065 -0.305054)
			(end 0.12065 -0.2794)
			(stroke
				(width 0.1)
				(type default)
			)
			(layer "B.Fab")
		)
		(fp_line
			(start -0.12065 -0.3048)
			(end -0.67945 -0.3048)
			(stroke
				(width 0.1)
				(type default)
			)
			(layer "B.Fab")
		)
		(fp_line
			(start -0.67945 -0.3048)
			(end -0.67945 0.3048)
			(stroke
				(width 0.1)
				(type default)
			)
			(layer "B.Fab")
		)
		(fp_line
			(start 0.12065 -0.2794)
			(end -0.12065 -0.2794)
			(stroke
				(width 0.1)
				(type default)
			)
			(layer "B.Fab")
		)
		(fp_line
			(start -0.12065 -0.2794)
			(end -0.12065 -0.3048)
			(stroke
				(width 0.1)
				(type default)
			)
			(layer "B.Fab")
		)
		(fp_line
			(start 0.12065 0.2794)
			(end 0.12065 0.3048)
			(stroke
				(width 0.1)
				(type default)
			)
			(layer "B.Fab")
		)
		(fp_line
			(start -0.120396 0.2794)
			(end 0.12065 0.2794)
			(stroke
				(width 0.1)
				(type default)
			)
			(layer "B.Fab")
		)
		(fp_line
			(start 0.67945 0.3048)
			(end 0.67945 -0.305054)
			(stroke
				(width 0.1)
				(type default)
			)
			(layer "B.Fab")
		)
		(fp_line
			(start 0.12065 0.3048)
			(end 0.67945 0.3048)
			(stroke
				(width 0.1)
				(type default)
			)
			(layer "B.Fab")
		)
		(fp_line
			(start -0.120396 0.3048)
			(end -0.120396 0.2794)
			(stroke
				(width 0.1)
				(type default)
			)
			(layer "B.Fab")
		)
		(fp_line
			(start -0.67945 0.3048)
			(end -0.120396 0.3048)
			(stroke
				(width 0.1)
				(type default)
			)
			(layer "B.Fab")
		)
		(pad "1" smd circle
			(at 0.40005 0 270)
			(size 0 0)
			(layers "B.Cu" "B.Mask" "B.Paste")
			(net "SMB_NIC7_LS_R_SDA")
		)
		(pad "2" smd circle
			(at -0.40005 0 270)
			(size 0 0)
			(layers "B.Cu" "B.Mask" "B.Paste")
			(net "SMB_NIC7_R_SDA")
		)
	)
	(footprint ""
		(layer "B.Cu")
		(at 48.72482 -293.99992 90)
		(property "Reference" "C1108"
			(at 0 0 90)
			(layer "B.SilkS")
			(hide yes)
			(effects
				(font
					(size 1.27 1.27)
				)
				(justify mirror)
			)
		)
		(property "Value" ""
			(at 0 0 90)
			(layer "B.Fab")
			(effects
				(font
					(size 1.27 1.27)
				)
				(justify mirror)
			)
		)
		(duplicate_pad_numbers_are_jumpers no)
		(fp_line
			(start 0.299974 -0.150114)
			(end -0.299974 -0.150114)
			(stroke
				(width 0.1)
				(type default)
			)
			(layer "B.Fab")
		)
		(fp_line
			(start -0.299974 -0.150114)
			(end -0.299974 0.150114)
			(stroke
				(width 0.1)
				(type default)
			)
			(layer "B.Fab")
		)
		(fp_line
			(start 0.299974 0.150114)
			(end 0.299974 -0.150114)
			(stroke
				(width 0.1)
				(type default)
			)
			(layer "B.Fab")
		)
		(fp_line
			(start -0.299974 0.150114)
			(end 0.299974 0.150114)
			(stroke
				(width 0.1)
				(type default)
			)
			(layer "B.Fab")
		)
		(pad "1" smd rect
			(at 0.2667 0 270)
			(size 0.3048 0.381)
			(layers "B.Cu" "B.Mask" "B.Paste")
			(net "P0V8_PEX0")
		)
		(pad "2" smd rect
			(at -0.2667 0 270)
			(size 0.3048 0.381)
			(layers "B.Cu" "B.Mask" "B.Paste")
			(net "GND")
		)
	)
	(footprint ""
		(layer "B.Cu")
		(at 379.365002 -223.733106)
		(property "Reference" "R929"
			(at 0 0 0)
			(layer "B.SilkS")
			(hide yes)
			(effects
				(font
					(size 1.27 1.27)
				)
				(justify mirror)
			)
		)
		(property "Value" ""
			(at 0 0 0)
			(layer "B.Fab")
			(effects
				(font
					(size 1.27 1.27)
				)
				(justify mirror)
			)
		)
		(duplicate_pad_numbers_are_jumpers no)
		(fp_line
			(start -0.7874 -0.4064)
			(end -0.7874 0.4064)
			(stroke
				(width 0.1524)
				(type default)
			)
			(layer "B.SilkS")
		)
		(fp_line
			(start -0.7874 0.4064)
			(end 0.7874 0.4064)
			(stroke
				(width 0.1524)
				(type default)
			)
			(layer "B.SilkS")
		)
		(fp_line
			(start 0.7874 -0.4064)
			(end -0.7874 -0.4064)
			(stroke
				(width 0.1524)
				(type default)
			)
			(layer "B.SilkS")
		)
		(fp_line
			(start 0.7874 0.4064)
			(end 0.7874 -0.4064)
			(stroke
				(width 0.1524)
				(type default)
			)
			(layer "B.SilkS")
		)
		(fp_line
			(start -0.67945 -0.3048)
			(end -0.67945 0.3048)
			(stroke
				(width 0.1)
				(type default)
			)
			(layer "B.Fab")
		)
		(fp_line
			(start -0.67945 0.3048)
			(end -0.120396 0.3048)
			(stroke
				(width 0.1)
				(type default)
			)
			(layer "B.Fab")
		)
		(fp_line
			(start -0.12065 -0.3048)
			(end -0.67945 -0.3048)
			(stroke
				(width 0.1)
				(type default)
			)
			(layer "B.Fab")
		)
		(fp_line
			(start -0.12065 -0.2794)
			(end -0.12065 -0.3048)
			(stroke
				(width 0.1)
				(type default)
			)
			(layer "B.Fab")
		)
		(fp_line
			(start -0.120396 0.2794)
			(end 0.12065 0.2794)
			(stroke
				(width 0.1)
				(type default)
			)
			(layer "B.Fab")
		)
		(fp_line
			(start -0.120396 0.3048)
			(end -0.120396 0.2794)
			(stroke
				(width 0.1)
				(type default)
			)
			(layer "B.Fab")
		)
		(fp_line
			(start 0.12065 -0.305054)
			(end 0.12065 -0.2794)
			(stroke
				(width 0.1)
				(type default)
			)
			(layer "B.Fab")
		)
		(fp_line
			(start 0.12065 -0.2794)
			(end -0.12065 -0.2794)
			(stroke
				(width 0.1)
				(type default)
			)
			(layer "B.Fab")
		)
		(fp_line
			(start 0.12065 0.2794)
			(end 0.12065 0.3048)
			(stroke
				(width 0.1)
				(type default)
			)
			(layer "B.Fab")
		)
		(fp_line
			(start 0.12065 0.3048)
			(end 0.67945 0.3048)
			(stroke
				(width 0.1)
				(type default)
			)
			(layer "B.Fab")
		)
		(fp_line
			(start 0.67945 -0.305054)
			(end 0.12065 -0.305054)
			(stroke
				(width 0.1)
				(type default)
			)
			(layer "B.Fab")
		)
		(fp_line
			(start 0.67945 0.3048)
			(end 0.67945 -0.305054)
			(stroke
				(width 0.1)
				(type default)
			)
			(layer "B.Fab")
		)
		(pad "1" smd circle
			(at 0.40005 0 180)
			(size 0 0)
			(layers "B.Cu" "B.Mask" "B.Paste")
			(net "UART_PEX0_SDB_BUF_R_RX")
		)
		(pad "2" smd circle
			(at -0.40005 0 180)
			(size 0 0)
			(layers "B.Cu" "B.Mask" "B.Paste")
			(net "UART_PEX0_SDB_BUF_RX")
		)
	)
	(footprint ""
		(layer "B.Cu")
		(at 66.801238 -305.399948 -90)
		(property "Reference" "C2962"
			(at 0 0 90)
			(layer "B.SilkS")
			(hide yes)
			(effects
				(font
					(size 1.27 1.27)
				)
				(justify mirror)
			)
		)
		(property "Value" ""
			(at 0 0 90)
			(layer "B.Fab")
			(effects
				(font
					(size 1.27 1.27)
				)
				(justify mirror)
			)
		)
		(duplicate_pad_numbers_are_jumpers no)
		(fp_line
			(start -0.299974 0.150114)
			(end 0.299974 0.150114)
			(stroke
				(width 0.1)
				(type default)
			)
			(layer "B.Fab")
		)
		(fp_line
			(start 0.299974 0.150114)
			(end 0.299974 -0.150114)
			(stroke
				(width 0.1)
				(type default)
			)
			(layer "B.Fab")
		)
		(fp_line
			(start -0.299974 -0.150114)
			(end -0.299974 0.150114)
			(stroke
				(width 0.1)
				(type default)
			)
			(layer "B.Fab")
		)
		(fp_line
			(start 0.299974 -0.150114)
			(end -0.299974 -0.150114)
			(stroke
				(width 0.1)
				(type default)
			)
			(layer "B.Fab")
		)
		(pad "1" smd rect
			(at 0.2667 0 90)
			(size 0.3048 0.381)
			(layers "B.Cu" "B.Mask" "B.Paste")
			(net "P1V25_SERDES_VDDPLL_PEX0")
		)
		(pad "2" smd rect
			(at -0.2667 0 90)
			(size 0.3048 0.381)
			(layers "B.Cu" "B.Mask" "B.Paste")
			(net "GND")
		)
	)
	(footprint ""
		(layer "B.Cu")
		(at 341.978234 -326.945498 -90)
		(property "Reference" "C4314"
			(at 0 0 90)
			(layer "B.SilkS")
			(hide yes)
			(effects
				(font
					(size 1.27 1.27)
				)
				(justify mirror)
			)
		)
		(property "Value" ""
			(at 0 0 90)
			(layer "B.Fab")
			(effects
				(font
					(size 1.27 1.27)
				)
				(justify mirror)
			)
		)
		(duplicate_pad_numbers_are_jumpers no)
		(fp_line
			(start -1.2954 0.5842)
			(end 1.2954 0.5842)
			(stroke
				(width 0.1524)
				(type default)
			)
			(layer "B.SilkS")
		)
		(fp_line
			(start 1.2954 0.5842)
			(end 1.2954 -0.5842)
			(stroke
				(width 0.1524)
				(type default)
			)
			(layer "B.SilkS")
		)
		(fp_line
			(start -1.2954 -0.5842)
			(end -1.2954 0.5842)
			(stroke
				(width 0.1524)
				(type default)
			)
			(layer "B.SilkS")
		)
		(fp_line
			(start 1.2954 -0.5842)
			(end -1.2954 -0.5842)
			(stroke
				(width 0.1524)
				(type default)
			)
			(layer "B.SilkS")
		)
		(fp_line
			(start -0.8636 0.4572)
			(end 0.8636 0.4572)
			(stroke
				(width 0.1)
				(type default)
			)
			(layer "B.Fab")
		)
		(fp_line
			(start 0.8636 0.4572)
			(end 0.8636 0.4064)
			(stroke
				(width 0.1)
				(type default)
			)
			(layer "B.Fab")
		)
		(fp_line
			(start -1.1938 0.4064)
			(end -0.8636 0.4064)
			(stroke
				(width 0.1)
				(type default)
			)
			(layer "B.Fab")
		)
		(fp_line
			(start -0.8636 0.4064)
			(end -0.8636 0.4572)
			(stroke
				(width 0.1)
				(type default)
			)
			(layer "B.Fab")
		)
		(fp_line
			(start 0.8636 0.4064)
			(end 1.1938 0.4064)
			(stroke
				(width 0.1)
				(type default)
			)
			(layer "B.Fab")
		)
		(fp_line
			(start 1.1938 0.4064)
			(end 1.1938 -0.4064)
			(stroke
				(width 0.1)
				(type default)
			)
			(layer "B.Fab")
		)
		(fp_line
			(start -1.1938 -0.4064)
			(end -1.1938 0.4064)
			(stroke
				(width 0.1)
				(type default)
			)
			(layer "B.Fab")
		)
		(fp_line
			(start -0.8636 -0.4064)
			(end -1.1938 -0.4064)
			(stroke
				(width 0.1)
				(type default)
			)
			(layer "B.Fab")
		)
		(fp_line
			(start 0.8636 -0.4064)
			(end 0.8636 -0.4572)
			(stroke
				(width 0.1)
				(type default)
			)
			(layer "B.Fab")
		)
		(fp_line
			(start 1.1938 -0.4064)
			(end 0.8636 -0.4064)
			(stroke
				(width 0.1)
				(type default)
			)
			(layer "B.Fab")
		)
		(fp_line
			(start -0.8636 -0.4572)
			(end -0.8636 -0.4064)
			(stroke
				(width 0.1)
				(type default)
			)
			(layer "B.Fab")
		)
		(fp_line
			(start 0.8636 -0.4572)
			(end -0.8636 -0.4572)
			(stroke
				(width 0.1)
				(type default)
			)
			(layer "B.Fab")
		)
		(pad "1" smd rect
			(at 0.7366 0 180)
			(size 0.7112 0.8128)
			(layers "B.Cu" "B.Mask" "B.Paste")
			(net "P0V8_SERDES_VDDA_PEX2_C4")
		)
		(pad "2" smd rect
			(at -0.7366 0 180)
			(size 0.7112 0.8128)
			(layers "B.Cu" "B.Mask" "B.Paste")
			(net "GND")
		)
	)
	(footprint ""
		(layer "B.Cu")
		(at 408.424888 -293.99992 -90)
		(property "Reference" "C1920"
			(at 0 0 90)
			(layer "B.SilkS")
			(hide yes)
			(effects
				(font
					(size 1.27 1.27)
				)
				(justify mirror)
			)
		)
		(property "Value" ""
			(at 0 0 90)
			(layer "B.Fab")
			(effects
				(font
					(size 1.27 1.27)
				)
				(justify mirror)
			)
		)
		(duplicate_pad_numbers_are_jumpers no)
		(fp_line
			(start -0.299974 0.150114)
			(end 0.299974 0.150114)
			(stroke
				(width 0.1)
				(type default)
			)
			(layer "B.Fab")
		)
		(fp_line
			(start 0.299974 0.150114)
			(end 0.299974 -0.150114)
			(stroke
				(width 0.1)
				(type default)
			)
			(layer "B.Fab")
		)
		(fp_line
			(start -0.299974 -0.150114)
			(end -0.299974 0.150114)
			(stroke
				(width 0.1)
				(type default)
			)
			(layer "B.Fab")
		)
		(fp_line
			(start 0.299974 -0.150114)
			(end -0.299974 -0.150114)
			(stroke
				(width 0.1)
				(type default)
			)
			(layer "B.Fab")
		)
		(pad "1" smd rect
			(at 0.2667 0 90)
			(size 0.3048 0.381)
			(layers "B.Cu" "B.Mask" "B.Paste")
			(net "P0V8_PEX3")
		)
		(pad "2" smd rect
			(at -0.2667 0 90)
			(size 0.3048 0.381)
			(layers "B.Cu" "B.Mask" "B.Paste")
			(net "GND")
		)
	)
	(footprint ""
		(layer "B.Cu")
		(at 388.202678 -247.165114 -90)
		(property "Reference" "R941"
			(at 0 0 90)
			(layer "B.SilkS")
			(hide yes)
			(effects
				(font
					(size 1.27 1.27)
				)
				(justify mirror)
			)
		)
		(property "Value" ""
			(at 0 0 90)
			(layer "B.Fab")
			(effects
				(font
					(size 1.27 1.27)
				)
				(justify mirror)
			)
		)
		(duplicate_pad_numbers_are_jumpers no)
		(fp_line
			(start -0.7874 0.4064)
			(end 0.7874 0.4064)
			(stroke
				(width 0.1524)
				(type default)
			)
			(layer "B.SilkS")
		)
		(fp_line
			(start 0.7874 0.4064)
			(end 0.7874 -0.4064)
			(stroke
				(width 0.1524)
				(type default)
			)
			(layer "B.SilkS")
		)
		(fp_line
			(start -0.7874 -0.4064)
			(end -0.7874 0.4064)
			(stroke
				(width 0.1524)
				(type default)
			)
			(layer "B.SilkS")
		)
		(fp_line
			(start 0.7874 -0.4064)
			(end -0.7874 -0.4064)
			(stroke
				(width 0.1524)
				(type default)
			)
			(layer "B.SilkS")
		)
		(fp_line
			(start -0.67945 0.3048)
			(end -0.120396 0.3048)
			(stroke
				(width 0.1)
				(type default)
			)
			(layer "B.Fab")
		)
		(fp_line
			(start -0.120396 0.3048)
			(end -0.120396 0.2794)
			(stroke
				(width 0.1)
				(type default)
			)
			(layer "B.Fab")
		)
		(fp_line
			(start 0.12065 0.3048)
			(end 0.67945 0.3048)
			(stroke
				(width 0.1)
				(type default)
			)
			(layer "B.Fab")
		)
		(fp_line
			(start 0.67945 0.3048)
			(end 0.67945 -0.305054)
			(stroke
				(width 0.1)
				(type default)
			)
			(layer "B.Fab")
		)
		(fp_line
			(start -0.120396 0.2794)
			(end 0.12065 0.2794)
			(stroke
				(width 0.1)
				(type default)
			)
			(layer "B.Fab")
		)
		(fp_line
			(start 0.12065 0.2794)
			(end 0.12065 0.3048)
			(stroke
				(width 0.1)
				(type default)
			)
			(layer "B.Fab")
		)
		(fp_line
			(start -0.12065 -0.2794)
			(end -0.12065 -0.3048)
			(stroke
				(width 0.1)
				(type default)
			)
			(layer "B.Fab")
		)
		(fp_line
			(start 0.12065 -0.2794)
			(end -0.12065 -0.2794)
			(stroke
				(width 0.1)
				(type default)
			)
			(layer "B.Fab")
		)
		(fp_line
			(start -0.67945 -0.3048)
			(end -0.67945 0.3048)
			(stroke
				(width 0.1)
				(type default)
			)
			(layer "B.Fab")
		)
		(fp_line
			(start -0.12065 -0.3048)
			(end -0.67945 -0.3048)
			(stroke
				(width 0.1)
				(type default)
			)
			(layer "B.Fab")
		)
		(fp_line
			(start 0.12065 -0.305054)
			(end 0.12065 -0.2794)
			(stroke
				(width 0.1)
				(type default)
			)
			(layer "B.Fab")
		)
		(fp_line
			(start 0.67945 -0.305054)
			(end 0.12065 -0.305054)
			(stroke
				(width 0.1)
				(type default)
			)
			(layer "B.Fab")
		)
		(pad "1" smd circle
			(at 0.40005 0 90)
			(size 0 0)
			(layers "B.Cu" "B.Mask" "B.Paste")
			(net "UART_PEX2_SDB_BUF_R_RX")
		)
		(pad "2" smd circle
			(at -0.40005 0 90)
			(size 0 0)
			(layers "B.Cu" "B.Mask" "B.Paste")
			(net "UART_PEX2_SDB_BUF_RX")
		)
	)
	(footprint ""
		(layer "B.Cu")
		(at 44.449746 -292.099746)
		(property "Reference" "C2999"
			(at 0 0 0)
			(layer "B.SilkS")
			(hide yes)
			(effects
				(font
					(size 1.27 1.27)
				)
				(justify mirror)
			)
		)
		(property "Value" ""
			(at 0 0 0)
			(layer "B.Fab")
			(effects
				(font
					(size 1.27 1.27)
				)
				(justify mirror)
			)
		)
		(duplicate_pad_numbers_are_jumpers no)
		(fp_line
			(start -0.299974 -0.150114)
			(end -0.299974 0.150114)
			(stroke
				(width 0.1)
				(type default)
			)
			(layer "B.Fab")
		)
		(fp_line
			(start -0.299974 0.150114)
			(end 0.299974 0.150114)
			(stroke
				(width 0.1)
				(type default)
			)
			(layer "B.Fab")
		)
		(fp_line
			(start 0.299974 -0.150114)
			(end -0.299974 -0.150114)
			(stroke
				(width 0.1)
				(type default)
			)
			(layer "B.Fab")
		)
		(fp_line
			(start 0.299974 0.150114)
			(end 0.299974 -0.150114)
			(stroke
				(width 0.1)
				(type default)
			)
			(layer "B.Fab")
		)
		(pad "1" smd rect
			(at 0.2667 0 180)
			(size 0.3048 0.381)
			(layers "B.Cu" "B.Mask" "B.Paste")
			(net "P1V8_PEX")
		)
		(pad "2" smd rect
			(at -0.2667 0 180)
			(size 0.3048 0.381)
			(layers "B.Cu" "B.Mask" "B.Paste")
			(net "GND")
		)
	)
	(footprint ""
		(layer "B.Cu")
		(at 116.788184 -318.542416 180)
		(property "Reference" "C4209"
			(at 0 0 0)
			(layer "B.SilkS")
			(hide yes)
			(effects
				(font
					(size 1.27 1.27)
				)
				(justify mirror)
			)
		)
		(property "Value" ""
			(at 0 0 0)
			(layer "B.Fab")
			(effects
				(font
					(size 1.27 1.27)
				)
				(justify mirror)
			)
		)
		(duplicate_pad_numbers_are_jumpers no)
		(fp_line
			(start 0.299974 0.150114)
			(end 0.299974 -0.150114)
			(stroke
				(width 0.1)
				(type default)
			)
			(layer "B.Fab")
		)
		(fp_line
			(start 0.299974 -0.150114)
			(end -0.299974 -0.150114)
			(stroke
				(width 0.1)
				(type default)
			)
			(layer "B.Fab")
		)
		(fp_line
			(start -0.299974 0.150114)
			(end 0.299974 0.150114)
			(stroke
				(width 0.1)
				(type default)
			)
			(layer "B.Fab")
		)
		(fp_line
			(start -0.299974 -0.150114)
			(end -0.299974 0.150114)
			(stroke
				(width 0.1)
				(type default)
			)
			(layer "B.Fab")
		)
		(pad "1" smd rect
			(at 0.2667 0)
			(size 0.3048 0.381)
			(layers "B.Cu" "B.Mask" "B.Paste")
			(net "P0V8_SERDES_VDDA_PEX0")
		)
		(pad "2" smd rect
			(at -0.2667 0)
			(size 0.3048 0.381)
			(layers "B.Cu" "B.Mask" "B.Paste")
			(net "GND")
		)
	)
	(footprint ""
		(layer "B.Cu")
		(at 103.764842 -337.475576 -90)
		(property "Reference" "C2697"
			(at 0 0 90)
			(layer "B.SilkS")
			(hide yes)
			(effects
				(font
					(size 1.27 1.27)
				)
				(justify mirror)
			)
		)
		(property "Value" ""
			(at 0 0 90)
			(layer "B.Fab")
			(effects
				(font
					(size 1.27 1.27)
				)
				(justify mirror)
			)
		)
		(duplicate_pad_numbers_are_jumpers no)
		(fp_line
			(start -0.7874 0.4064)
			(end 0.7874 0.4064)
			(stroke
				(width 0.1524)
				(type default)
			)
			(layer "B.SilkS")
		)
		(fp_line
			(start 0.7874 0.4064)
			(end 0.7874 -0.4064)
			(stroke
				(width 0.1524)
				(type default)
			)
			(layer "B.SilkS")
		)
		(fp_line
			(start -0.7874 -0.4064)
			(end -0.7874 0.4064)
			(stroke
				(width 0.1524)
				(type default)
			)
			(layer "B.SilkS")
		)
		(fp_line
			(start 0.7874 -0.4064)
			(end -0.7874 -0.4064)
			(stroke
				(width 0.1524)
				(type default)
			)
			(layer "B.SilkS")
		)
		(fp_line
			(start -0.67945 0.3048)
			(end -0.120396 0.3048)
			(stroke
				(width 0.1)
				(type default)
			)
			(layer "B.Fab")
		)
		(fp_line
			(start -0.120396 0.3048)
			(end -0.120396 0.2794)
			(stroke
				(width 0.1)
				(type default)
			)
			(layer "B.Fab")
		)
		(fp_line
			(start 0.12065 0.3048)
			(end 0.67945 0.3048)
			(stroke
				(width 0.1)
				(type default)
			)
			(layer "B.Fab")
		)
		(fp_line
			(start 0.67945 0.3048)
			(end 0.67945 -0.305054)
			(stroke
				(width 0.1)
				(type default)
			)
			(layer "B.Fab")
		)
		(fp_line
			(start -0.120396 0.2794)
			(end 0.12065 0.2794)
			(stroke
				(width 0.1)
				(type default)
			)
			(layer "B.Fab")
		)
		(fp_line
			(start 0.12065 0.2794)
			(end 0.12065 0.3048)
			(stroke
				(width 0.1)
				(type default)
			)
			(layer "B.Fab")
		)
		(fp_line
			(start -0.12065 -0.2794)
			(end -0.12065 -0.3048)
			(stroke
				(width 0.1)
				(type default)
			)
			(layer "B.Fab")
		)
		(fp_line
			(start 0.12065 -0.2794)
			(end -0.12065 -0.2794)
			(stroke
				(width 0.1)
				(type default)
			)
			(layer "B.Fab")
		)
		(fp_line
			(start -0.67945 -0.3048)
			(end -0.67945 0.3048)
			(stroke
				(width 0.1)
				(type default)
			)
			(layer "B.Fab")
		)
		(fp_line
			(start -0.12065 -0.3048)
			(end -0.67945 -0.3048)
			(stroke
				(width 0.1)
				(type default)
			)
			(layer "B.Fab")
		)
		(fp_line
			(start 0.12065 -0.305054)
			(end 0.12065 -0.2794)
			(stroke
				(width 0.1)
				(type default)
			)
			(layer "B.Fab")
		)
		(fp_line
			(start 0.67945 -0.305054)
			(end 0.12065 -0.305054)
			(stroke
				(width 0.1)
				(type default)
			)
			(layer "B.Fab")
		)
		(pad "1" smd circle
			(at 0.40005 0 90)
			(size 0 0)
			(layers "B.Cu" "B.Mask" "B.Paste")
			(net "P3V3_CLK_BUFFER_9ZXL0451E_VZX3P3")
		)
		(pad "2" smd circle
			(at -0.40005 0 90)
			(size 0 0)
			(layers "B.Cu" "B.Mask" "B.Paste")
			(net "GND")
		)
	)
	(footprint ""
		(layer "B.Cu")
		(at 87.150448 -447.452496)
		(property "Reference" "X57"
			(at 0.1778 -1.92913 0)
			(unlocked yes)
			(layer "B.SilkS")
			(effects
				(font
					(size 0.7874 0.5842)
					(thickness 0.1524)
				)
				(justify left mirror)
			)
		)
		(property "Value" ""
			(at 0 0 0)
			(layer "B.Fab")
			(effects
				(font
					(size 1.27 1.27)
				)
				(justify mirror)
			)
		)
		(property "Device Type" "TP_TDR_4P_FTS_MPKT4_H025P0200_IO_TP15_TP_TDR_4P_DIP"
			(at -1.30175 1.27 270)
			(unlocked yes)
			(layer "B.Fab")
			(hide yes)
			(effects
				(font
					(size 0.635 0.4064)
					(thickness 0.1524)
				)
				(justify mirror)
			)
		)
		(property "User Part Number" "TP15"
			(at -1.30175 1.27 270)
			(unlocked yes)
			(layer "Cmts.User")
			(hide yes)
			(effects
				(font
					(size 0.635 0.4064)
					(thickness 0.1524)
				)
				(justify mirror)
			)
		)
		(duplicate_pad_numbers_are_jumpers no)
		(fp_line
			(start -2.54 -1.27)
			(end 0 -1.27)
			(stroke
				(width 0.1524)
				(type default)
			)
			(layer "B.SilkS")
		)
		(fp_line
			(start -2.54 -1.1303)
			(end -2.54 -1.27)
			(stroke
				(width 0.1524)
				(type default)
			)
			(layer "B.SilkS")
		)
		(fp_line
			(start -2.54 1.4097)
			(end -2.54 1.1303)
			(stroke
				(width 0.1524)
				(type default)
			)
			(layer "B.SilkS")
		)
		(fp_line
			(start -2.54 3.81)
			(end -2.54 3.6703)
			(stroke
				(width 0.1524)
				(type default)
			)
			(layer "B.SilkS")
		)
		(fp_line
			(start 0 -1.27)
			(end 0 -0.635)
			(stroke
				(width 0.1524)
				(type default)
			)
			(layer "B.SilkS")
		)
		(fp_line
			(start 0 0.635)
			(end 0 1.905)
			(stroke
				(width 0.1524)
				(type default)
			)
			(layer "B.SilkS")
		)
		(fp_line
			(start 0 3.175)
			(end 0 3.81)
			(stroke
				(width 0.1524)
				(type default)
			)
			(layer "B.SilkS")
		)
		(fp_line
			(start 0 3.81)
			(end -2.54 3.81)
			(stroke
				(width 0.1524)
				(type default)
			)
			(layer "B.SilkS")
		)
		(fp_poly
			(pts
				(xy 0.761746 0) (xy 2.285746 -0.762) (xy 2.285746 0.762)
			)
			(stroke
				(width 0)
				(type default)
			)
			(fill yes)
			(layer "B.SilkS")
		)
		(fp_line
			(start -2.54 -1.27)
			(end 0 -1.27)
			(stroke
				(width 0.1)
				(type default)
			)
			(layer "B.Fab")
		)
		(fp_line
			(start -2.54 3.81)
			(end -2.54 -1.27)
			(stroke
				(width 0.1)
				(type default)
			)
			(layer "B.Fab")
		)
		(fp_line
			(start 0 -1.27)
			(end 0 3.81)
			(stroke
				(width 0.1)
				(type default)
			)
			(layer "B.Fab")
		)
		(fp_line
			(start 0 3.81)
			(end -2.54 3.81)
			(stroke
				(width 0.1)
				(type default)
			)
			(layer "B.Fab")
		)
		(fp_poly
			(pts
				(xy 0.761746 0) (xy 2.285746 -0.762) (xy 2.285746 0.762)
			)
			(stroke
				(width 0)
				(type default)
			)
			(fill yes)
			(layer "B.Fab")
		)
		(pad "1" thru_hole circle
			(at 0 0 180)
			(size 1.0033 1.0033)
			(drill 0.249936)
			(layers "*.Cu" "*.Mask")
			(remove_unused_layers no)
			(net "TDR_DIFF_85_BOT_DIN")
			(clearance 0.10795)
			(padstack
				(mode front_inner_back)
				(layer "Inner"
					(shape circle)
					(size 0.8001 0.8001)
					(clearance 0.1524)
				)
				(layer "B.Cu"
					(shape circle)
					(size 1.0033 1.0033)
					(thermal_gap 0.10795)
					(clearance 0.10795)
				)
			)
		)
		(pad "2" thru_hole circle
			(at -2.54 0 180)
			(size 1.9939 1.9939)
			(drill 0.249936)
			(layers "*.Cu" "*.Mask")
			(remove_unused_layers no)
			(net "COUPON_GND1")
			(clearance 0.10795)
			(padstack
				(mode front_inner_back)
				(layer "Inner"
					(shape circle)
					(size 0.8001 0.8001)
					(clearance 0.1524)
				)
				(layer "B.Cu"
					(shape circle)
					(size 1.9939 1.9939)
					(thermal_gap 0.10795)
					(clearance 0.10795)
				)
			)
		)
		(pad "3" thru_hole circle
			(at -2.54 2.54 180)
			(size 1.9939 1.9939)
			(drill 0.249936)
			(layers "*.Cu" "*.Mask")
			(remove_unused_layers no)
			(net "COUPON_GND1")
			(clearance 0.10795)
			(padstack
				(mode front_inner_back)
				(layer "Inner"
					(shape circle)
					(size 0.8001 0.8001)
					(clearance 0.1524)
				)
				(layer "B.Cu"
					(shape circle)
					(size 1.9939 1.9939)
					(thermal_gap 0.10795)
					(clearance 0.10795)
				)
			)
		)
		(pad "4" thru_hole circle
			(at 0 2.54 180)
			(size 1.0033 1.0033)
			(drill 0.249936)
			(layers "*.Cu" "*.Mask")
			(remove_unused_layers no)
			(net "TDR_DIFF_85_BOT_DIP")
			(clearance 0.10795)
			(padstack
				(mode front_inner_back)
				(layer "Inner"
					(shape circle)
					(size 0.8001 0.8001)
					(clearance 0.1524)
				)
				(layer "B.Cu"
					(shape circle)
					(size 1.0033 1.0033)
					(thermal_gap 0.10795)
					(clearance 0.10795)
				)
			)
		)
	)
	(footprint ""
		(layer "B.Cu")
		(at 413.649922 -299.699934 -90)
		(property "Reference" "C1934"
			(at 0 0 90)
			(layer "B.SilkS")
			(hide yes)
			(effects
				(font
					(size 1.27 1.27)
				)
				(justify mirror)
			)
		)
		(property "Value" ""
			(at 0 0 90)
			(layer "B.Fab")
			(effects
				(font
					(size 1.27 1.27)
				)
				(justify mirror)
			)
		)
		(duplicate_pad_numbers_are_jumpers no)
		(fp_line
			(start -0.299974 0.150114)
			(end 0.299974 0.150114)
			(stroke
				(width 0.1)
				(type default)
			)
			(layer "B.Fab")
		)
		(fp_line
			(start 0.299974 0.150114)
			(end 0.299974 -0.150114)
			(stroke
				(width 0.1)
				(type default)
			)
			(layer "B.Fab")
		)
		(fp_line
			(start -0.299974 -0.150114)
			(end -0.299974 0.150114)
			(stroke
				(width 0.1)
				(type default)
			)
			(layer "B.Fab")
		)
		(fp_line
			(start 0.299974 -0.150114)
			(end -0.299974 -0.150114)
			(stroke
				(width 0.1)
				(type default)
			)
			(layer "B.Fab")
		)
		(pad "1" smd rect
			(at 0.2667 0 90)
			(size 0.3048 0.381)
			(layers "B.Cu" "B.Mask" "B.Paste")
			(net "P0V8_SERDES_VDDA_PEX3")
		)
		(pad "2" smd rect
			(at -0.2667 0 90)
			(size 0.3048 0.381)
			(layers "B.Cu" "B.Mask" "B.Paste")
			(net "GND")
		)
	)
	(footprint ""
		(layer "B.Cu")
		(at 65.349882 -290.199826 90)
		(property "Reference" "C1168"
			(at 0 0 90)
			(layer "B.SilkS")
			(hide yes)
			(effects
				(font
					(size 1.27 1.27)
				)
				(justify mirror)
			)
		)
		(property "Value" ""
			(at 0 0 90)
			(layer "B.Fab")
			(effects
				(font
					(size 1.27 1.27)
				)
				(justify mirror)
			)
		)
		(duplicate_pad_numbers_are_jumpers no)
		(fp_line
			(start 0.299974 -0.150114)
			(end -0.299974 -0.150114)
			(stroke
				(width 0.1)
				(type default)
			)
			(layer "B.Fab")
		)
		(fp_line
			(start -0.299974 -0.150114)
			(end -0.299974 0.150114)
			(stroke
				(width 0.1)
				(type default)
			)
			(layer "B.Fab")
		)
		(fp_line
			(start 0.299974 0.150114)
			(end 0.299974 -0.150114)
			(stroke
				(width 0.1)
				(type default)
			)
			(layer "B.Fab")
		)
		(fp_line
			(start -0.299974 0.150114)
			(end 0.299974 0.150114)
			(stroke
				(width 0.1)
				(type default)
			)
			(layer "B.Fab")
		)
		(pad "1" smd rect
			(at 0.2667 0 270)
			(size 0.3048 0.381)
			(layers "B.Cu" "B.Mask" "B.Paste")
			(net "P0V8_SERDES_VDDA_PEX0")
		)
		(pad "2" smd rect
			(at -0.2667 0 270)
			(size 0.3048 0.381)
			(layers "B.Cu" "B.Mask" "B.Paste")
			(net "GND")
		)
	)
	(footprint ""
		(layer "B.Cu")
		(at 210.691476 -246.686578 -90)
		(property "Reference" "R6338"
			(at 0 0 90)
			(layer "B.SilkS")
			(hide yes)
			(effects
				(font
					(size 1.27 1.27)
				)
				(justify mirror)
			)
		)
		(property "Value" ""
			(at 0 0 90)
			(layer "B.Fab")
			(effects
				(font
					(size 1.27 1.27)
				)
				(justify mirror)
			)
		)
		(duplicate_pad_numbers_are_jumpers no)
		(fp_line
			(start -0.7874 0.4064)
			(end 0.7874 0.4064)
			(stroke
				(width 0.1524)
				(type default)
			)
			(layer "B.SilkS")
		)
		(fp_line
			(start 0.7874 0.4064)
			(end 0.7874 -0.4064)
			(stroke
				(width 0.1524)
				(type default)
			)
			(layer "B.SilkS")
		)
		(fp_line
			(start -0.7874 -0.4064)
			(end -0.7874 0.4064)
			(stroke
				(width 0.1524)
				(type default)
			)
			(layer "B.SilkS")
		)
		(fp_line
			(start 0.7874 -0.4064)
			(end -0.7874 -0.4064)
			(stroke
				(width 0.1524)
				(type default)
			)
			(layer "B.SilkS")
		)
		(fp_line
			(start -0.67945 0.3048)
			(end -0.120396 0.3048)
			(stroke
				(width 0.1)
				(type default)
			)
			(layer "B.Fab")
		)
		(fp_line
			(start -0.120396 0.3048)
			(end -0.120396 0.2794)
			(stroke
				(width 0.1)
				(type default)
			)
			(layer "B.Fab")
		)
		(fp_line
			(start 0.12065 0.3048)
			(end 0.67945 0.3048)
			(stroke
				(width 0.1)
				(type default)
			)
			(layer "B.Fab")
		)
		(fp_line
			(start 0.67945 0.3048)
			(end 0.67945 -0.305054)
			(stroke
				(width 0.1)
				(type default)
			)
			(layer "B.Fab")
		)
		(fp_line
			(start -0.120396 0.2794)
			(end 0.12065 0.2794)
			(stroke
				(width 0.1)
				(type default)
			)
			(layer "B.Fab")
		)
		(fp_line
			(start 0.12065 0.2794)
			(end 0.12065 0.3048)
			(stroke
				(width 0.1)
				(type default)
			)
			(layer "B.Fab")
		)
		(fp_line
			(start -0.12065 -0.2794)
			(end -0.12065 -0.3048)
			(stroke
				(width 0.1)
				(type default)
			)
			(layer "B.Fab")
		)
		(fp_line
			(start 0.12065 -0.2794)
			(end -0.12065 -0.2794)
			(stroke
				(width 0.1)
				(type default)
			)
			(layer "B.Fab")
		)
		(fp_line
			(start -0.67945 -0.3048)
			(end -0.67945 0.3048)
			(stroke
				(width 0.1)
				(type default)
			)
			(layer "B.Fab")
		)
		(fp_line
			(start -0.12065 -0.3048)
			(end -0.67945 -0.3048)
			(stroke
				(width 0.1)
				(type default)
			)
			(layer "B.Fab")
		)
		(fp_line
			(start 0.12065 -0.305054)
			(end 0.12065 -0.2794)
			(stroke
				(width 0.1)
				(type default)
			)
			(layer "B.Fab")
		)
		(fp_line
			(start 0.67945 -0.305054)
			(end 0.12065 -0.305054)
			(stroke
				(width 0.1)
				(type default)
			)
			(layer "B.Fab")
		)
		(pad "1" smd circle
			(at 0.40005 0 90)
			(size 0 0)
			(layers "B.Cu" "B.Mask" "B.Paste")
			(net "P1V8_PEX")
		)
		(pad "2" smd circle
			(at -0.40005 0 90)
			(size 0 0)
			(layers "B.Cu" "B.Mask" "B.Paste")
			(net "PEX_MUX_A2")
		)
	)
	(footprint ""
		(layer "B.Cu")
		(at 24.120348 -220.932756 90)
		(property "Reference" "R3446"
			(at 0 0 90)
			(layer "B.SilkS")
			(hide yes)
			(effects
				(font
					(size 1.27 1.27)
				)
				(justify mirror)
			)
		)
		(property "Value" ""
			(at 0 0 90)
			(layer "B.Fab")
			(effects
				(font
					(size 1.27 1.27)
				)
				(justify mirror)
			)
		)
		(duplicate_pad_numbers_are_jumpers no)
		(fp_line
			(start 0.7874 -0.4064)
			(end -0.7874 -0.4064)
			(stroke
				(width 0.1524)
				(type default)
			)
			(layer "B.SilkS")
		)
		(fp_line
			(start -0.7874 -0.4064)
			(end -0.7874 0.4064)
			(stroke
				(width 0.1524)
				(type default)
			)
			(layer "B.SilkS")
		)
		(fp_line
			(start 0.7874 0.4064)
			(end 0.7874 -0.4064)
			(stroke
				(width 0.1524)
				(type default)
			)
			(layer "B.SilkS")
		)
		(fp_line
			(start -0.7874 0.4064)
			(end 0.7874 0.4064)
			(stroke
				(width 0.1524)
				(type default)
			)
			(layer "B.SilkS")
		)
		(fp_line
			(start 0.67945 -0.305054)
			(end 0.12065 -0.305054)
			(stroke
				(width 0.1)
				(type default)
			)
			(layer "B.Fab")
		)
		(fp_line
			(start 0.12065 -0.305054)
			(end 0.12065 -0.2794)
			(stroke
				(width 0.1)
				(type default)
			)
			(layer "B.Fab")
		)
		(fp_line
			(start -0.12065 -0.3048)
			(end -0.67945 -0.3048)
			(stroke
				(width 0.1)
				(type default)
			)
			(layer "B.Fab")
		)
		(fp_line
			(start -0.67945 -0.3048)
			(end -0.67945 0.3048)
			(stroke
				(width 0.1)
				(type default)
			)
			(layer "B.Fab")
		)
		(fp_line
			(start 0.12065 -0.2794)
			(end -0.12065 -0.2794)
			(stroke
				(width 0.1)
				(type default)
			)
			(layer "B.Fab")
		)
		(fp_line
			(start -0.12065 -0.2794)
			(end -0.12065 -0.3048)
			(stroke
				(width 0.1)
				(type default)
			)
			(layer "B.Fab")
		)
		(fp_line
			(start 0.12065 0.2794)
			(end 0.12065 0.3048)
			(stroke
				(width 0.1)
				(type default)
			)
			(layer "B.Fab")
		)
		(fp_line
			(start -0.120396 0.2794)
			(end 0.12065 0.2794)
			(stroke
				(width 0.1)
				(type default)
			)
			(layer "B.Fab")
		)
		(fp_line
			(start 0.67945 0.3048)
			(end 0.67945 -0.305054)
			(stroke
				(width 0.1)
				(type default)
			)
			(layer "B.Fab")
		)
		(fp_line
			(start 0.12065 0.3048)
			(end 0.67945 0.3048)
			(stroke
				(width 0.1)
				(type default)
			)
			(layer "B.Fab")
		)
		(fp_line
			(start -0.120396 0.3048)
			(end -0.120396 0.2794)
			(stroke
				(width 0.1)
				(type default)
			)
			(layer "B.Fab")
		)
		(fp_line
			(start -0.67945 0.3048)
			(end -0.120396 0.3048)
			(stroke
				(width 0.1)
				(type default)
			)
			(layer "B.Fab")
		)
		(pad "1" smd circle
			(at 0.40005 0 270)
			(size 0 0)
			(layers "B.Cu" "B.Mask" "B.Paste")
			(net "SPI_PEX0_SDIO3_R")
		)
		(pad "2" smd circle
			(at -0.40005 0 270)
			(size 0 0)
			(layers "B.Cu" "B.Mask" "B.Paste")
			(net "SPI_PEX0_SDIO3_R1")
		)
	)
	(footprint ""
		(layer "B.Cu")
		(at 420.05504 -98.552)
		(property "Reference" "R359"
			(at 0 0 0)
			(layer "B.SilkS")
			(hide yes)
			(effects
				(font
					(size 1.27 1.27)
				)
				(justify mirror)
			)
		)
		(property "Value" ""
			(at 0 0 0)
			(layer "B.Fab")
			(effects
				(font
					(size 1.27 1.27)
				)
				(justify mirror)
			)
		)
		(duplicate_pad_numbers_are_jumpers no)
		(fp_line
			(start -0.7874 -0.4064)
			(end -0.7874 0.4064)
			(stroke
				(width 0.1524)
				(type default)
			)
			(layer "B.SilkS")
		)
		(fp_line
			(start -0.7874 0.4064)
			(end 0.7874 0.4064)
			(stroke
				(width 0.1524)
				(type default)
			)
			(layer "B.SilkS")
		)
		(fp_line
			(start 0.7874 -0.4064)
			(end -0.7874 -0.4064)
			(stroke
				(width 0.1524)
				(type default)
			)
			(layer "B.SilkS")
		)
		(fp_line
			(start 0.7874 0.4064)
			(end 0.7874 -0.4064)
			(stroke
				(width 0.1524)
				(type default)
			)
			(layer "B.SilkS")
		)
		(fp_line
			(start -0.67945 -0.3048)
			(end -0.67945 0.3048)
			(stroke
				(width 0.1)
				(type default)
			)
			(layer "B.Fab")
		)
		(fp_line
			(start -0.67945 0.3048)
			(end -0.120396 0.3048)
			(stroke
				(width 0.1)
				(type default)
			)
			(layer "B.Fab")
		)
		(fp_line
			(start -0.12065 -0.3048)
			(end -0.67945 -0.3048)
			(stroke
				(width 0.1)
				(type default)
			)
			(layer "B.Fab")
		)
		(fp_line
			(start -0.12065 -0.2794)
			(end -0.12065 -0.3048)
			(stroke
				(width 0.1)
				(type default)
			)
			(layer "B.Fab")
		)
		(fp_line
			(start -0.120396 0.2794)
			(end 0.12065 0.2794)
			(stroke
				(width 0.1)
				(type default)
			)
			(layer "B.Fab")
		)
		(fp_line
			(start -0.120396 0.3048)
			(end -0.120396 0.2794)
			(stroke
				(width 0.1)
				(type default)
			)
			(layer "B.Fab")
		)
		(fp_line
			(start 0.12065 -0.305054)
			(end 0.12065 -0.2794)
			(stroke
				(width 0.1)
				(type default)
			)
			(layer "B.Fab")
		)
		(fp_line
			(start 0.12065 -0.2794)
			(end -0.12065 -0.2794)
			(stroke
				(width 0.1)
				(type default)
			)
			(layer "B.Fab")
		)
		(fp_line
			(start 0.12065 0.2794)
			(end 0.12065 0.3048)
			(stroke
				(width 0.1)
				(type default)
			)
			(layer "B.Fab")
		)
		(fp_line
			(start 0.12065 0.3048)
			(end 0.67945 0.3048)
			(stroke
				(width 0.1)
				(type default)
			)
			(layer "B.Fab")
		)
		(fp_line
			(start 0.67945 -0.305054)
			(end 0.12065 -0.305054)
			(stroke
				(width 0.1)
				(type default)
			)
			(layer "B.Fab")
		)
		(fp_line
			(start 0.67945 0.3048)
			(end 0.67945 -0.305054)
			(stroke
				(width 0.1)
				(type default)
			)
			(layer "B.Fab")
		)
		(pad "1" smd circle
			(at 0.40005 0 180)
			(size 0 0)
			(layers "B.Cu" "B.Mask" "B.Paste")
			(net "NIC7_MAIN_PWR_EN_R")
		)
		(pad "2" smd circle
			(at -0.40005 0 180)
			(size 0 0)
			(layers "B.Cu" "B.Mask" "B.Paste")
			(net "NIC7_MAIN_PWR_EN")
		)
	)
	(footprint ""
		(layer "B.Cu")
		(at 397.85544 -155.0416)
		(property "Reference" "R333"
			(at 0 0 0)
			(layer "B.SilkS")
			(hide yes)
			(effects
				(font
					(size 1.27 1.27)
				)
				(justify mirror)
			)
		)
		(property "Value" ""
			(at 0 0 0)
			(layer "B.Fab")
			(effects
				(font
					(size 1.27 1.27)
				)
				(justify mirror)
			)
		)
		(duplicate_pad_numbers_are_jumpers no)
		(fp_line
			(start -0.7874 -0.4064)
			(end -0.7874 0.4064)
			(stroke
				(width 0.1524)
				(type default)
			)
			(layer "B.SilkS")
		)
		(fp_line
			(start -0.7874 0.4064)
			(end 0.7874 0.4064)
			(stroke
				(width 0.1524)
				(type default)
			)
			(layer "B.SilkS")
		)
		(fp_line
			(start 0.7874 -0.4064)
			(end -0.7874 -0.4064)
			(stroke
				(width 0.1524)
				(type default)
			)
			(layer "B.SilkS")
		)
		(fp_line
			(start 0.7874 0.4064)
			(end 0.7874 -0.4064)
			(stroke
				(width 0.1524)
				(type default)
			)
			(layer "B.SilkS")
		)
		(fp_line
			(start -0.67945 -0.3048)
			(end -0.67945 0.3048)
			(stroke
				(width 0.1)
				(type default)
			)
			(layer "B.Fab")
		)
		(fp_line
			(start -0.67945 0.3048)
			(end -0.120396 0.3048)
			(stroke
				(width 0.1)
				(type default)
			)
			(layer "B.Fab")
		)
		(fp_line
			(start -0.12065 -0.3048)
			(end -0.67945 -0.3048)
			(stroke
				(width 0.1)
				(type default)
			)
			(layer "B.Fab")
		)
		(fp_line
			(start -0.12065 -0.2794)
			(end -0.12065 -0.3048)
			(stroke
				(width 0.1)
				(type default)
			)
			(layer "B.Fab")
		)
		(fp_line
			(start -0.120396 0.2794)
			(end 0.12065 0.2794)
			(stroke
				(width 0.1)
				(type default)
			)
			(layer "B.Fab")
		)
		(fp_line
			(start -0.120396 0.3048)
			(end -0.120396 0.2794)
			(stroke
				(width 0.1)
				(type default)
			)
			(layer "B.Fab")
		)
		(fp_line
			(start 0.12065 -0.305054)
			(end 0.12065 -0.2794)
			(stroke
				(width 0.1)
				(type default)
			)
			(layer "B.Fab")
		)
		(fp_line
			(start 0.12065 -0.2794)
			(end -0.12065 -0.2794)
			(stroke
				(width 0.1)
				(type default)
			)
			(layer "B.Fab")
		)
		(fp_line
			(start 0.12065 0.2794)
			(end 0.12065 0.3048)
			(stroke
				(width 0.1)
				(type default)
			)
			(layer "B.Fab")
		)
		(fp_line
			(start 0.12065 0.3048)
			(end 0.67945 0.3048)
			(stroke
				(width 0.1)
				(type default)
			)
			(layer "B.Fab")
		)
		(fp_line
			(start 0.67945 -0.305054)
			(end 0.12065 -0.305054)
			(stroke
				(width 0.1)
				(type default)
			)
			(layer "B.Fab")
		)
		(fp_line
			(start 0.67945 0.3048)
			(end 0.67945 -0.305054)
			(stroke
				(width 0.1)
				(type default)
			)
			(layer "B.Fab")
		)
		(pad "1" smd circle
			(at 0.40005 0 180)
			(size 0 0)
			(layers "B.Cu" "B.Mask" "B.Paste")
			(net "NIC6_SLOT_ID1")
		)
		(pad "2" smd circle
			(at -0.40005 0 180)
			(size 0 0)
			(layers "B.Cu" "B.Mask" "B.Paste")
			(net "P3V3_NIC6")
		)
	)
	(footprint ""
		(layer "B.Cu")
		(at 375.58853 -236.556296 180)
		(property "Reference" "R910"
			(at 0 0 0)
			(layer "B.SilkS")
			(hide yes)
			(effects
				(font
					(size 1.27 1.27)
				)
				(justify mirror)
			)
		)
		(property "Value" ""
			(at 0 0 0)
			(layer "B.Fab")
			(effects
				(font
					(size 1.27 1.27)
				)
				(justify mirror)
			)
		)
		(duplicate_pad_numbers_are_jumpers no)
		(fp_line
			(start 0.7874 0.4064)
			(end 0.7874 -0.4064)
			(stroke
				(width 0.1524)
				(type default)
			)
			(layer "B.SilkS")
		)
		(fp_line
			(start 0.7874 -0.4064)
			(end -0.7874 -0.4064)
			(stroke
				(width 0.1524)
				(type default)
			)
			(layer "B.SilkS")
		)
		(fp_line
			(start -0.7874 0.4064)
			(end 0.7874 0.4064)
			(stroke
				(width 0.1524)
				(type default)
			)
			(layer "B.SilkS")
		)
		(fp_line
			(start -0.7874 -0.4064)
			(end -0.7874 0.4064)
			(stroke
				(width 0.1524)
				(type default)
			)
			(layer "B.SilkS")
		)
		(fp_line
			(start 0.67945 0.3048)
			(end 0.67945 -0.305054)
			(stroke
				(width 0.1)
				(type default)
			)
			(layer "B.Fab")
		)
		(fp_line
			(start 0.67945 -0.305054)
			(end 0.12065 -0.305054)
			(stroke
				(width 0.1)
				(type default)
			)
			(layer "B.Fab")
		)
		(fp_line
			(start 0.12065 0.3048)
			(end 0.67945 0.3048)
			(stroke
				(width 0.1)
				(type default)
			)
			(layer "B.Fab")
		)
		(fp_line
			(start 0.12065 0.2794)
			(end 0.12065 0.3048)
			(stroke
				(width 0.1)
				(type default)
			)
			(layer "B.Fab")
		)
		(fp_line
			(start 0.12065 -0.2794)
			(end -0.12065 -0.2794)
			(stroke
				(width 0.1)
				(type default)
			)
			(layer "B.Fab")
		)
		(fp_line
			(start 0.12065 -0.305054)
			(end 0.12065 -0.2794)
			(stroke
				(width 0.1)
				(type default)
			)
			(layer "B.Fab")
		)
		(fp_line
			(start -0.120396 0.3048)
			(end -0.120396 0.2794)
			(stroke
				(width 0.1)
				(type default)
			)
			(layer "B.Fab")
		)
		(fp_line
			(start -0.120396 0.2794)
			(end 0.12065 0.2794)
			(stroke
				(width 0.1)
				(type default)
			)
			(layer "B.Fab")
		)
		(fp_line
			(start -0.12065 -0.2794)
			(end -0.12065 -0.3048)
			(stroke
				(width 0.1)
				(type default)
			)
			(layer "B.Fab")
		)
		(fp_line
			(start -0.12065 -0.3048)
			(end -0.67945 -0.3048)
			(stroke
				(width 0.1)
				(type default)
			)
			(layer "B.Fab")
		)
		(fp_line
			(start -0.67945 0.3048)
			(end -0.120396 0.3048)
			(stroke
				(width 0.1)
				(type default)
			)
			(layer "B.Fab")
		)
		(fp_line
			(start -0.67945 -0.3048)
			(end -0.67945 0.3048)
			(stroke
				(width 0.1)
				(type default)
			)
			(layer "B.Fab")
		)
		(pad "1" smd circle
			(at 0.40005 0)
			(size 0 0)
			(layers "B.Cu" "B.Mask" "B.Paste")
			(net "FT4232_SDB_EEPROM_R_CS")
		)
		(pad "2" smd circle
			(at -0.40005 0)
			(size 0 0)
			(layers "B.Cu" "B.Mask" "B.Paste")
			(net "P3V3_AUX")
		)
	)
	(footprint ""
		(layer "B.Cu")
		(at 365.864394 -321.84594 -90)
		(property "Reference" "R6539"
			(at 0 0 90)
			(layer "B.SilkS")
			(hide yes)
			(effects
				(font
					(size 1.27 1.27)
				)
				(justify mirror)
			)
		)
		(property "Value" ""
			(at 0 0 90)
			(layer "B.Fab")
			(effects
				(font
					(size 1.27 1.27)
				)
				(justify mirror)
			)
		)
		(duplicate_pad_numbers_are_jumpers no)
		(fp_line
			(start -0.7874 0.4064)
			(end 0.7874 0.4064)
			(stroke
				(width 0.1524)
				(type default)
			)
			(layer "B.SilkS")
		)
		(fp_line
			(start 0.7874 0.4064)
			(end 0.7874 -0.4064)
			(stroke
				(width 0.1524)
				(type default)
			)
			(layer "B.SilkS")
		)
		(fp_line
			(start -0.7874 -0.4064)
			(end -0.7874 0.4064)
			(stroke
				(width 0.1524)
				(type default)
			)
			(layer "B.SilkS")
		)
		(fp_line
			(start 0.7874 -0.4064)
			(end -0.7874 -0.4064)
			(stroke
				(width 0.1524)
				(type default)
			)
			(layer "B.SilkS")
		)
		(fp_line
			(start -0.67945 0.3048)
			(end -0.120396 0.3048)
			(stroke
				(width 0.1)
				(type default)
			)
			(layer "B.Fab")
		)
		(fp_line
			(start -0.120396 0.3048)
			(end -0.120396 0.2794)
			(stroke
				(width 0.1)
				(type default)
			)
			(layer "B.Fab")
		)
		(fp_line
			(start 0.12065 0.3048)
			(end 0.67945 0.3048)
			(stroke
				(width 0.1)
				(type default)
			)
			(layer "B.Fab")
		)
		(fp_line
			(start 0.67945 0.3048)
			(end 0.67945 -0.305054)
			(stroke
				(width 0.1)
				(type default)
			)
			(layer "B.Fab")
		)
		(fp_line
			(start -0.120396 0.2794)
			(end 0.12065 0.2794)
			(stroke
				(width 0.1)
				(type default)
			)
			(layer "B.Fab")
		)
		(fp_line
			(start 0.12065 0.2794)
			(end 0.12065 0.3048)
			(stroke
				(width 0.1)
				(type default)
			)
			(layer "B.Fab")
		)
		(fp_line
			(start -0.12065 -0.2794)
			(end -0.12065 -0.3048)
			(stroke
				(width 0.1)
				(type default)
			)
			(layer "B.Fab")
		)
		(fp_line
			(start 0.12065 -0.2794)
			(end -0.12065 -0.2794)
			(stroke
				(width 0.1)
				(type default)
			)
			(layer "B.Fab")
		)
		(fp_line
			(start -0.67945 -0.3048)
			(end -0.67945 0.3048)
			(stroke
				(width 0.1)
				(type default)
			)
			(layer "B.Fab")
		)
		(fp_line
			(start -0.12065 -0.3048)
			(end -0.67945 -0.3048)
			(stroke
				(width 0.1)
				(type default)
			)
			(layer "B.Fab")
		)
		(fp_line
			(start 0.12065 -0.305054)
			(end 0.12065 -0.2794)
			(stroke
				(width 0.1)
				(type default)
			)
			(layer "B.Fab")
		)
		(fp_line
			(start 0.67945 -0.305054)
			(end 0.12065 -0.305054)
			(stroke
				(width 0.1)
				(type default)
			)
			(layer "B.Fab")
		)
		(pad "1" smd circle
			(at 0.40005 0 90)
			(size 0 0)
			(layers "B.Cu" "B.Mask" "B.Paste")
			(net "P0V8_SERDES_VDDA_PEX3")
		)
		(pad "2" smd circle
			(at -0.40005 0 90)
			(size 0 0)
			(layers "B.Cu" "B.Mask" "B.Paste")
			(net "P0V8_SERDES_VDDA_PEX3_C4")
		)
	)
	(footprint ""
		(layer "B.Cu")
		(at 303.954942 -98.552)
		(property "Reference" "R257"
			(at 0 0 0)
			(layer "B.SilkS")
			(hide yes)
			(effects
				(font
					(size 1.27 1.27)
				)
				(justify mirror)
			)
		)
		(property "Value" ""
			(at 0 0 0)
			(layer "B.Fab")
			(effects
				(font
					(size 1.27 1.27)
				)
				(justify mirror)
			)
		)
		(duplicate_pad_numbers_are_jumpers no)
		(fp_line
			(start -0.7874 -0.4064)
			(end -0.7874 0.4064)
			(stroke
				(width 0.1524)
				(type default)
			)
			(layer "B.SilkS")
		)
		(fp_line
			(start -0.7874 0.4064)
			(end 0.7874 0.4064)
			(stroke
				(width 0.1524)
				(type default)
			)
			(layer "B.SilkS")
		)
		(fp_line
			(start 0.7874 -0.4064)
			(end -0.7874 -0.4064)
			(stroke
				(width 0.1524)
				(type default)
			)
			(layer "B.SilkS")
		)
		(fp_line
			(start 0.7874 0.4064)
			(end 0.7874 -0.4064)
			(stroke
				(width 0.1524)
				(type default)
			)
			(layer "B.SilkS")
		)
		(fp_line
			(start -0.67945 -0.3048)
			(end -0.67945 0.3048)
			(stroke
				(width 0.1)
				(type default)
			)
			(layer "B.Fab")
		)
		(fp_line
			(start -0.67945 0.3048)
			(end -0.120396 0.3048)
			(stroke
				(width 0.1)
				(type default)
			)
			(layer "B.Fab")
		)
		(fp_line
			(start -0.12065 -0.3048)
			(end -0.67945 -0.3048)
			(stroke
				(width 0.1)
				(type default)
			)
			(layer "B.Fab")
		)
		(fp_line
			(start -0.12065 -0.2794)
			(end -0.12065 -0.3048)
			(stroke
				(width 0.1)
				(type default)
			)
			(layer "B.Fab")
		)
		(fp_line
			(start -0.120396 0.2794)
			(end 0.12065 0.2794)
			(stroke
				(width 0.1)
				(type default)
			)
			(layer "B.Fab")
		)
		(fp_line
			(start -0.120396 0.3048)
			(end -0.120396 0.2794)
			(stroke
				(width 0.1)
				(type default)
			)
			(layer "B.Fab")
		)
		(fp_line
			(start 0.12065 -0.305054)
			(end 0.12065 -0.2794)
			(stroke
				(width 0.1)
				(type default)
			)
			(layer "B.Fab")
		)
		(fp_line
			(start 0.12065 -0.2794)
			(end -0.12065 -0.2794)
			(stroke
				(width 0.1)
				(type default)
			)
			(layer "B.Fab")
		)
		(fp_line
			(start 0.12065 0.2794)
			(end 0.12065 0.3048)
			(stroke
				(width 0.1)
				(type default)
			)
			(layer "B.Fab")
		)
		(fp_line
			(start 0.12065 0.3048)
			(end 0.67945 0.3048)
			(stroke
				(width 0.1)
				(type default)
			)
			(layer "B.Fab")
		)
		(fp_line
			(start 0.67945 -0.305054)
			(end 0.12065 -0.305054)
			(stroke
				(width 0.1)
				(type default)
			)
			(layer "B.Fab")
		)
		(fp_line
			(start 0.67945 0.3048)
			(end 0.67945 -0.305054)
			(stroke
				(width 0.1)
				(type default)
			)
			(layer "B.Fab")
		)
		(pad "1" smd circle
			(at 0.40005 0 180)
			(size 0 0)
			(layers "B.Cu" "B.Mask" "B.Paste")
			(net "NIC5_MAIN_PWR_EN_R")
		)
		(pad "2" smd circle
			(at -0.40005 0 180)
			(size 0 0)
			(layers "B.Cu" "B.Mask" "B.Paste")
			(net "NIC5_MAIN_PWR_EN")
		)
	)
	(footprint ""
		(layer "B.Cu")
		(at 409.897326 -108.465366)
		(property "Reference" "R386"
			(at 0 0 0)
			(layer "B.SilkS")
			(hide yes)
			(effects
				(font
					(size 1.27 1.27)
				)
				(justify mirror)
			)
		)
		(property "Value" ""
			(at 0 0 0)
			(layer "B.Fab")
			(effects
				(font
					(size 1.27 1.27)
				)
				(justify mirror)
			)
		)
		(duplicate_pad_numbers_are_jumpers no)
		(fp_line
			(start -0.7874 -0.4064)
			(end -0.7874 0.4064)
			(stroke
				(width 0.1524)
				(type default)
			)
			(layer "B.SilkS")
		)
		(fp_line
			(start -0.7874 0.4064)
			(end 0.7874 0.4064)
			(stroke
				(width 0.1524)
				(type default)
			)
			(layer "B.SilkS")
		)
		(fp_line
			(start 0.7874 -0.4064)
			(end -0.7874 -0.4064)
			(stroke
				(width 0.1524)
				(type default)
			)
			(layer "B.SilkS")
		)
		(fp_line
			(start 0.7874 0.4064)
			(end 0.7874 -0.4064)
			(stroke
				(width 0.1524)
				(type default)
			)
			(layer "B.SilkS")
		)
		(fp_line
			(start -0.67945 -0.3048)
			(end -0.67945 0.3048)
			(stroke
				(width 0.1)
				(type default)
			)
			(layer "B.Fab")
		)
		(fp_line
			(start -0.67945 0.3048)
			(end -0.120396 0.3048)
			(stroke
				(width 0.1)
				(type default)
			)
			(layer "B.Fab")
		)
		(fp_line
			(start -0.12065 -0.3048)
			(end -0.67945 -0.3048)
			(stroke
				(width 0.1)
				(type default)
			)
			(layer "B.Fab")
		)
		(fp_line
			(start -0.12065 -0.2794)
			(end -0.12065 -0.3048)
			(stroke
				(width 0.1)
				(type default)
			)
			(layer "B.Fab")
		)
		(fp_line
			(start -0.120396 0.2794)
			(end 0.12065 0.2794)
			(stroke
				(width 0.1)
				(type default)
			)
			(layer "B.Fab")
		)
		(fp_line
			(start -0.120396 0.3048)
			(end -0.120396 0.2794)
			(stroke
				(width 0.1)
				(type default)
			)
			(layer "B.Fab")
		)
		(fp_line
			(start 0.12065 -0.305054)
			(end 0.12065 -0.2794)
			(stroke
				(width 0.1)
				(type default)
			)
			(layer "B.Fab")
		)
		(fp_line
			(start 0.12065 -0.2794)
			(end -0.12065 -0.2794)
			(stroke
				(width 0.1)
				(type default)
			)
			(layer "B.Fab")
		)
		(fp_line
			(start 0.12065 0.2794)
			(end 0.12065 0.3048)
			(stroke
				(width 0.1)
				(type default)
			)
			(layer "B.Fab")
		)
		(fp_line
			(start 0.12065 0.3048)
			(end 0.67945 0.3048)
			(stroke
				(width 0.1)
				(type default)
			)
			(layer "B.Fab")
		)
		(fp_line
			(start 0.67945 -0.305054)
			(end 0.12065 -0.305054)
			(stroke
				(width 0.1)
				(type default)
			)
			(layer "B.Fab")
		)
		(fp_line
			(start 0.67945 0.3048)
			(end 0.67945 -0.305054)
			(stroke
				(width 0.1)
				(type default)
			)
			(layer "B.Fab")
		)
		(pad "1" smd circle
			(at 0.40005 0 180)
			(size 0 0)
			(layers "B.Cu" "B.Mask" "B.Paste")
			(net "NIC7_BIF0_N")
		)
		(pad "2" smd circle
			(at -0.40005 0 180)
			(size 0 0)
			(layers "B.Cu" "B.Mask" "B.Paste")
			(net "P3V3_AUX")
		)
	)
	(footprint ""
		(layer "B.Cu")
		(at 168.150032 -303.499774 -90)
		(property "Reference" "C3077"
			(at 0 0 90)
			(layer "B.SilkS")
			(hide yes)
			(effects
				(font
					(size 1.27 1.27)
				)
				(justify mirror)
			)
		)
		(property "Value" ""
			(at 0 0 90)
			(layer "B.Fab")
			(effects
				(font
					(size 1.27 1.27)
				)
				(justify mirror)
			)
		)
		(duplicate_pad_numbers_are_jumpers no)
		(fp_line
			(start -0.299974 0.150114)
			(end 0.299974 0.150114)
			(stroke
				(width 0.1)
				(type default)
			)
			(layer "B.Fab")
		)
		(fp_line
			(start 0.299974 0.150114)
			(end 0.299974 -0.150114)
			(stroke
				(width 0.1)
				(type default)
			)
			(layer "B.Fab")
		)
		(fp_line
			(start -0.299974 -0.150114)
			(end -0.299974 0.150114)
			(stroke
				(width 0.1)
				(type default)
			)
			(layer "B.Fab")
		)
		(fp_line
			(start 0.299974 -0.150114)
			(end -0.299974 -0.150114)
			(stroke
				(width 0.1)
				(type default)
			)
			(layer "B.Fab")
		)
		(pad "1" smd rect
			(at 0.2667 0 90)
			(size 0.3048 0.381)
			(layers "B.Cu" "B.Mask" "B.Paste")
			(net "P1V25_PEX1")
		)
		(pad "2" smd rect
			(at -0.2667 0 90)
			(size 0.3048 0.381)
			(layers "B.Cu" "B.Mask" "B.Paste")
			(net "GND")
		)
	)
	(footprint ""
		(layer "B.Cu")
		(at 63.951358 -305.399948 -90)
		(property "Reference" "C2952"
			(at 0 0 90)
			(layer "B.SilkS")
			(hide yes)
			(effects
				(font
					(size 1.27 1.27)
				)
				(justify mirror)
			)
		)
		(property "Value" ""
			(at 0 0 90)
			(layer "B.Fab")
			(effects
				(font
					(size 1.27 1.27)
				)
				(justify mirror)
			)
		)
		(duplicate_pad_numbers_are_jumpers no)
		(fp_line
			(start -0.299974 0.150114)
			(end 0.299974 0.150114)
			(stroke
				(width 0.1)
				(type default)
			)
			(layer "B.Fab")
		)
		(fp_line
			(start 0.299974 0.150114)
			(end 0.299974 -0.150114)
			(stroke
				(width 0.1)
				(type default)
			)
			(layer "B.Fab")
		)
		(fp_line
			(start -0.299974 -0.150114)
			(end -0.299974 0.150114)
			(stroke
				(width 0.1)
				(type default)
			)
			(layer "B.Fab")
		)
		(fp_line
			(start 0.299974 -0.150114)
			(end -0.299974 -0.150114)
			(stroke
				(width 0.1)
				(type default)
			)
			(layer "B.Fab")
		)
		(pad "1" smd rect
			(at 0.2667 0 90)
			(size 0.3048 0.381)
			(layers "B.Cu" "B.Mask" "B.Paste")
			(net "P1V25_SERDES_VDDPLL_PEX0")
		)
		(pad "2" smd rect
			(at -0.2667 0 90)
			(size 0.3048 0.381)
			(layers "B.Cu" "B.Mask" "B.Paste")
			(net "GND")
		)
	)
	(footprint ""
		(layer "B.Cu")
		(at 285.199836 -288.299906 90)
		(property "Reference" "C3282"
			(at 0 0 90)
			(layer "B.SilkS")
			(hide yes)
			(effects
				(font
					(size 1.27 1.27)
				)
				(justify mirror)
			)
		)
		(property "Value" ""
			(at 0 0 90)
			(layer "B.Fab")
			(effects
				(font
					(size 1.27 1.27)
				)
				(justify mirror)
			)
		)
		(duplicate_pad_numbers_are_jumpers no)
		(fp_line
			(start 0.299974 -0.150114)
			(end -0.299974 -0.150114)
			(stroke
				(width 0.1)
				(type default)
			)
			(layer "B.Fab")
		)
		(fp_line
			(start -0.299974 -0.150114)
			(end -0.299974 0.150114)
			(stroke
				(width 0.1)
				(type default)
			)
			(layer "B.Fab")
		)
		(fp_line
			(start 0.299974 0.150114)
			(end 0.299974 -0.150114)
			(stroke
				(width 0.1)
				(type default)
			)
			(layer "B.Fab")
		)
		(fp_line
			(start -0.299974 0.150114)
			(end 0.299974 0.150114)
			(stroke
				(width 0.1)
				(type default)
			)
			(layer "B.Fab")
		)
		(pad "1" smd rect
			(at 0.2667 0 270)
			(size 0.3048 0.381)
			(layers "B.Cu" "B.Mask" "B.Paste")
			(net "P1V25_PEX2")
		)
		(pad "2" smd rect
			(at -0.2667 0 270)
			(size 0.3048 0.381)
			(layers "B.Cu" "B.Mask" "B.Paste")
			(net "GND")
		)
	)
	(footprint ""
		(layer "B.Cu")
		(at 261.31393 -242.372388)
		(property "Reference" "R6581"
			(at 0 0 0)
			(layer "B.SilkS")
			(hide yes)
			(effects
				(font
					(size 1.27 1.27)
				)
				(justify mirror)
			)
		)
		(property "Value" ""
			(at 0 0 0)
			(layer "B.Fab")
			(effects
				(font
					(size 1.27 1.27)
				)
				(justify mirror)
			)
		)
		(duplicate_pad_numbers_are_jumpers no)
		(fp_line
			(start -0.7874 -0.4064)
			(end -0.7874 0.4064)
			(stroke
				(width 0.1524)
				(type default)
			)
			(layer "B.SilkS")
		)
		(fp_line
			(start -0.7874 0.4064)
			(end 0.7874 0.4064)
			(stroke
				(width 0.1524)
				(type default)
			)
			(layer "B.SilkS")
		)
		(fp_line
			(start 0.7874 -0.4064)
			(end -0.7874 -0.4064)
			(stroke
				(width 0.1524)
				(type default)
			)
			(layer "B.SilkS")
		)
		(fp_line
			(start 0.7874 0.4064)
			(end 0.7874 -0.4064)
			(stroke
				(width 0.1524)
				(type default)
			)
			(layer "B.SilkS")
		)
		(fp_line
			(start -0.67945 -0.3048)
			(end -0.67945 0.3048)
			(stroke
				(width 0.1)
				(type default)
			)
			(layer "B.Fab")
		)
		(fp_line
			(start -0.67945 0.3048)
			(end -0.120396 0.3048)
			(stroke
				(width 0.1)
				(type default)
			)
			(layer "B.Fab")
		)
		(fp_line
			(start -0.12065 -0.3048)
			(end -0.67945 -0.3048)
			(stroke
				(width 0.1)
				(type default)
			)
			(layer "B.Fab")
		)
		(fp_line
			(start -0.12065 -0.2794)
			(end -0.12065 -0.3048)
			(stroke
				(width 0.1)
				(type default)
			)
			(layer "B.Fab")
		)
		(fp_line
			(start -0.120396 0.2794)
			(end 0.12065 0.2794)
			(stroke
				(width 0.1)
				(type default)
			)
			(layer "B.Fab")
		)
		(fp_line
			(start -0.120396 0.3048)
			(end -0.120396 0.2794)
			(stroke
				(width 0.1)
				(type default)
			)
			(layer "B.Fab")
		)
		(fp_line
			(start 0.12065 -0.305054)
			(end 0.12065 -0.2794)
			(stroke
				(width 0.1)
				(type default)
			)
			(layer "B.Fab")
		)
		(fp_line
			(start 0.12065 -0.2794)
			(end -0.12065 -0.2794)
			(stroke
				(width 0.1)
				(type default)
			)
			(layer "B.Fab")
		)
		(fp_line
			(start 0.12065 0.2794)
			(end 0.12065 0.3048)
			(stroke
				(width 0.1)
				(type default)
			)
			(layer "B.Fab")
		)
		(fp_line
			(start 0.12065 0.3048)
			(end 0.67945 0.3048)
			(stroke
				(width 0.1)
				(type default)
			)
			(layer "B.Fab")
		)
		(fp_line
			(start 0.67945 -0.305054)
			(end 0.12065 -0.305054)
			(stroke
				(width 0.1)
				(type default)
			)
			(layer "B.Fab")
		)
		(fp_line
			(start 0.67945 0.3048)
			(end 0.67945 -0.305054)
			(stroke
				(width 0.1)
				(type default)
			)
			(layer "B.Fab")
		)
		(pad "1" smd circle
			(at 0.40005 0 180)
			(size 0 0)
			(layers "B.Cu" "B.Mask" "B.Paste")
			(net "P3V3_AUX")
		)
		(pad "2" smd circle
			(at -0.40005 0 180)
			(size 0 0)
			(layers "B.Cu" "B.Mask" "B.Paste")
			(net "PWRGD_PEX2_P1V8_PLL")
		)
	)
	(footprint ""
		(layer "B.Cu")
		(at 370.921534 -236.689392 180)
		(property "Reference" "U97"
			(at 0.112776 -2.450338 0)
			(unlocked yes)
			(layer "B.SilkS")
			(effects
				(font
					(size 0.7874 0.5842)
					(thickness 0.1524)
				)
				(justify mirror)
			)
		)
		(property "Value" ""
			(at 0 0 0)
			(layer "B.Fab")
			(effects
				(font
					(size 1.27 1.27)
				)
				(justify mirror)
			)
		)
		(duplicate_pad_numbers_are_jumpers no)
		(fp_line
			(start 2.085848 1.549908)
			(end 2.085848 -1.549908)
			(stroke
				(width 0.1524)
				(type default)
			)
			(layer "B.SilkS")
		)
		(fp_line
			(start 2.085848 -1.549908)
			(end 0.695198 -1.549908)
			(stroke
				(width 0.1524)
				(type default)
			)
			(layer "B.SilkS")
		)
		(fp_line
			(start 0.695198 -1.549908)
			(end 0 -0.85471)
			(stroke
				(width 0.1524)
				(type default)
			)
			(layer "B.SilkS")
		)
		(fp_line
			(start 0 -0.85471)
			(end -0.695198 -1.549908)
			(stroke
				(width 0.1524)
				(type default)
			)
			(layer "B.SilkS")
		)
		(fp_line
			(start -0.695198 -1.549908)
			(end -2.085848 -1.549908)
			(stroke
				(width 0.1524)
				(type default)
			)
			(layer "B.SilkS")
		)
		(fp_line
			(start -2.085848 1.549908)
			(end 2.085848 1.549908)
			(stroke
				(width 0.1524)
				(type default)
			)
			(layer "B.SilkS")
		)
		(fp_line
			(start -2.085848 -1.549908)
			(end -2.085848 1.549908)
			(stroke
				(width 0.1524)
				(type default)
			)
			(layer "B.SilkS")
		)
		(fp_poly
			(pts
				(xy 3.432048 -1.45796) (xy 3.432048 -0.44196) (xy 2.416048 -0.94996)
			)
			(stroke
				(width 0)
				(type default)
			)
			(fill yes)
			(layer "B.SilkS")
		)
		(fp_line
			(start 0.899922 1.549908)
			(end 0.899922 -1.549908)
			(stroke
				(width 0.1)
				(type default)
			)
			(layer "B.Fab")
		)
		(fp_line
			(start 0.899922 -1.549908)
			(end -0.899922 -1.549908)
			(stroke
				(width 0.1)
				(type default)
			)
			(layer "B.Fab")
		)
		(fp_line
			(start -0.899922 1.549908)
			(end 0.899922 1.549908)
			(stroke
				(width 0.1)
				(type default)
			)
			(layer "B.Fab")
		)
		(fp_line
			(start -0.899922 -1.549908)
			(end -0.899922 1.549908)
			(stroke
				(width 0.1)
				(type default)
			)
			(layer "B.Fab")
		)
		(fp_poly
			(pts
				(xy 3.432048 -1.45796) (xy 3.432048 -0.44196) (xy 2.416048 -0.94996)
			)
			(stroke
				(width 0)
				(type default)
			)
			(fill yes)
			(layer "B.Fab")
		)
		(pad "1" smd rect
			(at 1.400048 -0.94996 90)
			(size 0.6096 1.1176)
			(layers "B.Cu" "B.Mask" "B.Paste")
			(net "FT4232_SDB_EEPROM_DO")
		)
		(pad "2" smd rect
			(at 1.400048 0 90)
			(size 0.6096 1.1176)
			(layers "B.Cu" "B.Mask" "B.Paste")
			(net "GND")
		)
		(pad "3" smd rect
			(at 1.400048 0.94996 90)
			(size 0.6096 1.1176)
			(layers "B.Cu" "B.Mask" "B.Paste")
			(net "FT4232_SDB_EEPROM_R_SDA")
		)
		(pad "4" smd rect
			(at -1.400048 0.94996 90)
			(size 0.6096 1.1176)
			(layers "B.Cu" "B.Mask" "B.Paste")
			(net "FT4232_SDB_EEPROM_R_SCL")
		)
		(pad "5" smd rect
			(at -1.400048 0 90)
			(size 0.6096 1.1176)
			(layers "B.Cu" "B.Mask" "B.Paste")
			(net "FT4232_SDB_EEPROM_R_CS")
		)
		(pad "6" smd rect
			(at -1.400048 -0.94996 90)
			(size 0.6096 1.1176)
			(layers "B.Cu" "B.Mask" "B.Paste")
			(net "P3V3_AUX")
		)
	)
	(footprint ""
		(layer "B.Cu")
		(at 411.274768 -293.99992 90)
		(property "Reference" "C1910"
			(at 0 0 90)
			(layer "B.SilkS")
			(hide yes)
			(effects
				(font
					(size 1.27 1.27)
				)
				(justify mirror)
			)
		)
		(property "Value" ""
			(at 0 0 90)
			(layer "B.Fab")
			(effects
				(font
					(size 1.27 1.27)
				)
				(justify mirror)
			)
		)
		(duplicate_pad_numbers_are_jumpers no)
		(fp_line
			(start 0.299974 -0.150114)
			(end -0.299974 -0.150114)
			(stroke
				(width 0.1)
				(type default)
			)
			(layer "B.Fab")
		)
		(fp_line
			(start -0.299974 -0.150114)
			(end -0.299974 0.150114)
			(stroke
				(width 0.1)
				(type default)
			)
			(layer "B.Fab")
		)
		(fp_line
			(start 0.299974 0.150114)
			(end 0.299974 -0.150114)
			(stroke
				(width 0.1)
				(type default)
			)
			(layer "B.Fab")
		)
		(fp_line
			(start -0.299974 0.150114)
			(end 0.299974 0.150114)
			(stroke
				(width 0.1)
				(type default)
			)
			(layer "B.Fab")
		)
		(pad "1" smd rect
			(at 0.2667 0 270)
			(size 0.3048 0.381)
			(layers "B.Cu" "B.Mask" "B.Paste")
			(net "P0V8_PEX3")
		)
		(pad "2" smd rect
			(at -0.2667 0 270)
			(size 0.3048 0.381)
			(layers "B.Cu" "B.Mask" "B.Paste")
			(net "GND")
		)
	)
	(footprint ""
		(layer "B.Cu")
		(at 128.241044 -181.03977)
		(property "Reference" "C2660"
			(at 0 0 0)
			(layer "B.SilkS")
			(hide yes)
			(effects
				(font
					(size 1.27 1.27)
				)
				(justify mirror)
			)
		)
		(property "Value" ""
			(at 0 0 0)
			(layer "B.Fab")
			(effects
				(font
					(size 1.27 1.27)
				)
				(justify mirror)
			)
		)
		(duplicate_pad_numbers_are_jumpers no)
		(fp_line
			(start -0.7874 -0.4064)
			(end -0.7874 0.4064)
			(stroke
				(width 0.1524)
				(type default)
			)
			(layer "B.SilkS")
		)
		(fp_line
			(start -0.7874 0.4064)
			(end 0.7874 0.4064)
			(stroke
				(width 0.1524)
				(type default)
			)
			(layer "B.SilkS")
		)
		(fp_line
			(start 0.7874 -0.4064)
			(end -0.7874 -0.4064)
			(stroke
				(width 0.1524)
				(type default)
			)
			(layer "B.SilkS")
		)
		(fp_line
			(start 0.7874 0.4064)
			(end 0.7874 -0.4064)
			(stroke
				(width 0.1524)
				(type default)
			)
			(layer "B.SilkS")
		)
		(fp_line
			(start -0.67945 -0.3048)
			(end -0.67945 0.3048)
			(stroke
				(width 0.1)
				(type default)
			)
			(layer "B.Fab")
		)
		(fp_line
			(start -0.67945 0.3048)
			(end -0.120396 0.3048)
			(stroke
				(width 0.1)
				(type default)
			)
			(layer "B.Fab")
		)
		(fp_line
			(start -0.12065 -0.3048)
			(end -0.67945 -0.3048)
			(stroke
				(width 0.1)
				(type default)
			)
			(layer "B.Fab")
		)
		(fp_line
			(start -0.12065 -0.2794)
			(end -0.12065 -0.3048)
			(stroke
				(width 0.1)
				(type default)
			)
			(layer "B.Fab")
		)
		(fp_line
			(start -0.120396 0.2794)
			(end 0.12065 0.2794)
			(stroke
				(width 0.1)
				(type default)
			)
			(layer "B.Fab")
		)
		(fp_line
			(start -0.120396 0.3048)
			(end -0.120396 0.2794)
			(stroke
				(width 0.1)
				(type default)
			)
			(layer "B.Fab")
		)
		(fp_line
			(start 0.12065 -0.305054)
			(end 0.12065 -0.2794)
			(stroke
				(width 0.1)
				(type default)
			)
			(layer "B.Fab")
		)
		(fp_line
			(start 0.12065 -0.2794)
			(end -0.12065 -0.2794)
			(stroke
				(width 0.1)
				(type default)
			)
			(layer "B.Fab")
		)
		(fp_line
			(start 0.12065 0.2794)
			(end 0.12065 0.3048)
			(stroke
				(width 0.1)
				(type default)
			)
			(layer "B.Fab")
		)
		(fp_line
			(start 0.12065 0.3048)
			(end 0.67945 0.3048)
			(stroke
				(width 0.1)
				(type default)
			)
			(layer "B.Fab")
		)
		(fp_line
			(start 0.67945 -0.305054)
			(end 0.12065 -0.305054)
			(stroke
				(width 0.1)
				(type default)
			)
			(layer "B.Fab")
		)
		(fp_line
			(start 0.67945 0.3048)
			(end 0.67945 -0.305054)
			(stroke
				(width 0.1)
				(type default)
			)
			(layer "B.Fab")
		)
		(pad "1" smd circle
			(at 0.40005 0 180)
			(size 0 0)
			(layers "B.Cu" "B.Mask" "B.Paste")
			(net "P3V3_DB2000QL_VDD")
		)
		(pad "2" smd circle
			(at -0.40005 0 180)
			(size 0 0)
			(layers "B.Cu" "B.Mask" "B.Paste")
			(net "GND")
		)
	)
	(footprint ""
		(layer "B.Cu")
		(at 338.64169 -293.660068 90)
		(property "Reference" "PC165"
			(at 0 0 90)
			(layer "B.SilkS")
			(hide yes)
			(effects
				(font
					(size 1.27 1.27)
				)
				(justify mirror)
			)
		)
		(property "Value" ""
			(at 0 0 90)
			(layer "B.Fab")
			(effects
				(font
					(size 1.27 1.27)
				)
				(justify mirror)
			)
		)
		(duplicate_pad_numbers_are_jumpers no)
		(fp_line
			(start 4.84378 -2.150618)
			(end 4.53898 -2.150618)
			(stroke
				(width 0.1524)
				(type default)
			)
			(layer "B.SilkS")
		)
		(fp_line
			(start 4.84378 -2.150618)
			(end 4.842256 2.163064)
			(stroke
				(width 0.1524)
				(type default)
			)
			(layer "B.SilkS")
		)
		(fp_line
			(start 4.69138 -2.150618)
			(end 4.692396 2.161032)
			(stroke
				(width 0.1524)
				(type default)
			)
			(layer "B.SilkS")
		)
		(fp_line
			(start 4.53898 -2.150618)
			(end 4.539742 2.152142)
			(stroke
				(width 0.1524)
				(type default)
			)
			(layer "B.SilkS")
		)
		(fp_line
			(start 4.53898 -2.15011)
			(end -4.53898 -2.15011)
			(stroke
				(width 0.1524)
				(type default)
			)
			(layer "B.SilkS")
		)
		(fp_line
			(start -4.53898 -2.15011)
			(end -4.53898 2.15011)
			(stroke
				(width 0.1524)
				(type default)
			)
			(layer "B.SilkS")
		)
		(fp_line
			(start 4.53898 2.15011)
			(end 4.53898 -2.15011)
			(stroke
				(width 0.1524)
				(type default)
			)
			(layer "B.SilkS")
		)
		(fp_line
			(start -4.53898 2.15011)
			(end 4.53898 2.15011)
			(stroke
				(width 0.1524)
				(type default)
			)
			(layer "B.SilkS")
		)
		(fp_line
			(start 4.83108 2.150364)
			(end 4.447794 2.149348)
			(stroke
				(width 0.1524)
				(type default)
			)
			(layer "B.SilkS")
		)
		(fp_line
			(start 3.64998 -2.15011)
			(end -3.64998 -2.15011)
			(stroke
				(width 0.1)
				(type default)
			)
			(layer "B.Fab")
		)
		(fp_line
			(start -3.64998 -2.15011)
			(end -3.64998 2.15011)
			(stroke
				(width 0.1)
				(type default)
			)
			(layer "B.Fab")
		)
		(fp_line
			(start 3.64998 2.15011)
			(end 3.64998 -2.15011)
			(stroke
				(width 0.1)
				(type default)
			)
			(layer "B.Fab")
		)
		(fp_line
			(start -3.64998 2.15011)
			(end 3.64998 2.15011)
			(stroke
				(width 0.1)
				(type default)
			)
			(layer "B.Fab")
		)
		(fp_text user "+"
			(at 6.214872 -0.337058 90)
			(unlocked yes)
			(layer "B.SilkS")
			(effects
				(font
					(size 1.905 1.4224)
					(thickness 0.1524)
				)
				(justify left mirror)
			)
		)
		(fp_text user "-"
			(at -4.313174 -0.094488 90)
			(unlocked yes)
			(layer "B.SilkS")
			(effects
				(font
					(size 1.905 1.4224)
					(thickness 0.1524)
				)
				(justify left mirror)
			)
		)
		(fp_text user "+"
			(at 6.214872 -0.337058 90)
			(unlocked yes)
			(layer "B.Fab")
			(effects
				(font
					(size 1.905 1.4224)
					(thickness 0.1524)
				)
				(justify left mirror)
			)
		)
		(fp_text user "-"
			(at -4.313174 -0.094488 90)
			(unlocked yes)
			(layer "B.Fab")
			(effects
				(font
					(size 1.905 1.4224)
					(thickness 0.1524)
				)
				(justify left mirror)
			)
		)
		(pad "1" smd rect
			(at 3.199892 0 270)
			(size 2.413 2.8194)
			(layers "B.Cu" "B.Mask" "B.Paste")
			(net "P0V8_PEX2")
		)
		(pad "2" smd rect
			(at -3.199892 0 270)
			(size 2.413 2.8194)
			(layers "B.Cu" "B.Mask" "B.Paste")
			(net "GND")
		)
	)
	(footprint ""
		(layer "B.Cu")
		(at 333.171546 -317.143384 90)
		(property "Reference" "C4304"
			(at 0 0 90)
			(layer "B.SilkS")
			(hide yes)
			(effects
				(font
					(size 1.27 1.27)
				)
				(justify mirror)
			)
		)
		(property "Value" ""
			(at 0 0 90)
			(layer "B.Fab")
			(effects
				(font
					(size 1.27 1.27)
				)
				(justify mirror)
			)
		)
		(duplicate_pad_numbers_are_jumpers no)
		(fp_line
			(start 1.2954 -0.5842)
			(end -1.2954 -0.5842)
			(stroke
				(width 0.1524)
				(type default)
			)
			(layer "B.SilkS")
		)
		(fp_line
			(start -1.2954 -0.5842)
			(end -1.2954 0.5842)
			(stroke
				(width 0.1524)
				(type default)
			)
			(layer "B.SilkS")
		)
		(fp_line
			(start 1.2954 0.5842)
			(end 1.2954 -0.5842)
			(stroke
				(width 0.1524)
				(type default)
			)
			(layer "B.SilkS")
		)
		(fp_line
			(start -1.2954 0.5842)
			(end 1.2954 0.5842)
			(stroke
				(width 0.1524)
				(type default)
			)
			(layer "B.SilkS")
		)
		(fp_line
			(start 0.8636 -0.4572)
			(end -0.8636 -0.4572)
			(stroke
				(width 0.1)
				(type default)
			)
			(layer "B.Fab")
		)
		(fp_line
			(start -0.8636 -0.4572)
			(end -0.8636 -0.4064)
			(stroke
				(width 0.1)
				(type default)
			)
			(layer "B.Fab")
		)
		(fp_line
			(start 1.1938 -0.4064)
			(end 0.8636 -0.4064)
			(stroke
				(width 0.1)
				(type default)
			)
			(layer "B.Fab")
		)
		(fp_line
			(start 0.8636 -0.4064)
			(end 0.8636 -0.4572)
			(stroke
				(width 0.1)
				(type default)
			)
			(layer "B.Fab")
		)
		(fp_line
			(start -0.8636 -0.4064)
			(end -1.1938 -0.4064)
			(stroke
				(width 0.1)
				(type default)
			)
			(layer "B.Fab")
		)
		(fp_line
			(start -1.1938 -0.4064)
			(end -1.1938 0.4064)
			(stroke
				(width 0.1)
				(type default)
			)
			(layer "B.Fab")
		)
		(fp_line
			(start 1.1938 0.4064)
			(end 1.1938 -0.4064)
			(stroke
				(width 0.1)
				(type default)
			)
			(layer "B.Fab")
		)
		(fp_line
			(start 0.8636 0.4064)
			(end 1.1938 0.4064)
			(stroke
				(width 0.1)
				(type default)
			)
			(layer "B.Fab")
		)
		(fp_line
			(start -0.8636 0.4064)
			(end -0.8636 0.4572)
			(stroke
				(width 0.1)
				(type default)
			)
			(layer "B.Fab")
		)
		(fp_line
			(start -1.1938 0.4064)
			(end -0.8636 0.4064)
			(stroke
				(width 0.1)
				(type default)
			)
			(layer "B.Fab")
		)
		(fp_line
			(start 0.8636 0.4572)
			(end 0.8636 0.4064)
			(stroke
				(width 0.1)
				(type default)
			)
			(layer "B.Fab")
		)
		(fp_line
			(start -0.8636 0.4572)
			(end 0.8636 0.4572)
			(stroke
				(width 0.1)
				(type default)
			)
			(layer "B.Fab")
		)
		(pad "1" smd rect
			(at 0.7366 0)
			(size 0.7112 0.8128)
			(layers "B.Cu" "B.Mask" "B.Paste")
			(net "P0V8_PEX2")
		)
		(pad "2" smd rect
			(at -0.7366 0)
			(size 0.7112 0.8128)
			(layers "B.Cu" "B.Mask" "B.Paste")
			(net "GND")
		)
	)
	(footprint ""
		(layer "B.Cu")
		(at 283.774896 -297.79976 90)
		(property "Reference" "C1660"
			(at 0 0 90)
			(layer "B.SilkS")
			(hide yes)
			(effects
				(font
					(size 1.27 1.27)
				)
				(justify mirror)
			)
		)
		(property "Value" ""
			(at 0 0 90)
			(layer "B.Fab")
			(effects
				(font
					(size 1.27 1.27)
				)
				(justify mirror)
			)
		)
		(duplicate_pad_numbers_are_jumpers no)
		(fp_line
			(start 0.299974 -0.150114)
			(end -0.299974 -0.150114)
			(stroke
				(width 0.1)
				(type default)
			)
			(layer "B.Fab")
		)
		(fp_line
			(start -0.299974 -0.150114)
			(end -0.299974 0.150114)
			(stroke
				(width 0.1)
				(type default)
			)
			(layer "B.Fab")
		)
		(fp_line
			(start 0.299974 0.150114)
			(end 0.299974 -0.150114)
			(stroke
				(width 0.1)
				(type default)
			)
			(layer "B.Fab")
		)
		(fp_line
			(start -0.299974 0.150114)
			(end 0.299974 0.150114)
			(stroke
				(width 0.1)
				(type default)
			)
			(layer "B.Fab")
		)
		(pad "1" smd rect
			(at 0.2667 0 270)
			(size 0.3048 0.381)
			(layers "B.Cu" "B.Mask" "B.Paste")
			(net "P0V8_PEX2")
		)
		(pad "2" smd rect
			(at -0.2667 0 270)
			(size 0.3048 0.381)
			(layers "B.Cu" "B.Mask" "B.Paste")
			(net "GND")
		)
	)
	(footprint ""
		(layer "B.Cu")
		(at 299.449744 -290.199826 90)
		(property "Reference" "C1705"
			(at 0 0 90)
			(layer "B.SilkS")
			(hide yes)
			(effects
				(font
					(size 1.27 1.27)
				)
				(justify mirror)
			)
		)
		(property "Value" ""
			(at 0 0 90)
			(layer "B.Fab")
			(effects
				(font
					(size 1.27 1.27)
				)
				(justify mirror)
			)
		)
		(duplicate_pad_numbers_are_jumpers no)
		(fp_line
			(start 0.299974 -0.150114)
			(end -0.299974 -0.150114)
			(stroke
				(width 0.1)
				(type default)
			)
			(layer "B.Fab")
		)
		(fp_line
			(start -0.299974 -0.150114)
			(end -0.299974 0.150114)
			(stroke
				(width 0.1)
				(type default)
			)
			(layer "B.Fab")
		)
		(fp_line
			(start 0.299974 0.150114)
			(end 0.299974 -0.150114)
			(stroke
				(width 0.1)
				(type default)
			)
			(layer "B.Fab")
		)
		(fp_line
			(start -0.299974 0.150114)
			(end 0.299974 0.150114)
			(stroke
				(width 0.1)
				(type default)
			)
			(layer "B.Fab")
		)
		(pad "1" smd rect
			(at 0.2667 0 270)
			(size 0.3048 0.381)
			(layers "B.Cu" "B.Mask" "B.Paste")
			(net "P0V8_SERDES_VDDA_PEX2")
		)
		(pad "2" smd rect
			(at -0.2667 0 270)
			(size 0.3048 0.381)
			(layers "B.Cu" "B.Mask" "B.Paste")
			(net "GND")
		)
	)
	(footprint ""
		(layer "B.Cu")
		(at 342.175846 -293.506906 90)
		(property "Reference" "PC148"
			(at 0 0 90)
			(layer "B.SilkS")
			(hide yes)
			(effects
				(font
					(size 1.27 1.27)
				)
				(justify mirror)
			)
		)
		(property "Value" ""
			(at 0 0 90)
			(layer "B.Fab")
			(effects
				(font
					(size 1.27 1.27)
				)
				(justify mirror)
			)
		)
		(duplicate_pad_numbers_are_jumpers no)
		(fp_line
			(start 1.524 -0.762)
			(end -1.524 -0.762)
			(stroke
				(width 0.1524)
				(type default)
			)
			(layer "B.SilkS")
		)
		(fp_line
			(start -1.524 -0.762)
			(end -1.524 0.762)
			(stroke
				(width 0.1524)
				(type default)
			)
			(layer "B.SilkS")
		)
		(fp_line
			(start 1.524 0.762)
			(end 1.524 -0.762)
			(stroke
				(width 0.1524)
				(type default)
			)
			(layer "B.SilkS")
		)
		(fp_line
			(start -1.524 0.762)
			(end 1.524 0.762)
			(stroke
				(width 0.1524)
				(type default)
			)
			(layer "B.SilkS")
		)
		(fp_line
			(start 1.1049 -0.724916)
			(end 1.1049 0.724916)
			(stroke
				(width 0.1)
				(type default)
			)
			(layer "B.Fab")
		)
		(fp_line
			(start -1.1049 -0.724916)
			(end 1.1049 -0.724916)
			(stroke
				(width 0.1)
				(type default)
			)
			(layer "B.Fab")
		)
		(fp_line
			(start 1.1049 0.724916)
			(end -1.1049 0.724916)
			(stroke
				(width 0.1)
				(type default)
			)
			(layer "B.Fab")
		)
		(fp_line
			(start -1.1049 0.724916)
			(end -1.1049 -0.724916)
			(stroke
				(width 0.1)
				(type default)
			)
			(layer "B.Fab")
		)
		(pad "1" smd rect
			(at 0.889 0 90)
			(size 1.016 1.27)
			(layers "B.Cu" "B.Mask" "B.Paste")
			(net "P0V8_PEX2")
		)
		(pad "2" smd rect
			(at -0.889 0 90)
			(size 1.016 1.27)
			(layers "B.Cu" "B.Mask" "B.Paste")
			(net "GND")
		)
	)
	(footprint ""
		(layer "B.Cu")
		(at 165.299898 -291.624766)
		(property "Reference" "C1360"
			(at 0 0 0)
			(layer "B.SilkS")
			(hide yes)
			(effects
				(font
					(size 1.27 1.27)
				)
				(justify mirror)
			)
		)
		(property "Value" ""
			(at 0 0 0)
			(layer "B.Fab")
			(effects
				(font
					(size 1.27 1.27)
				)
				(justify mirror)
			)
		)
		(duplicate_pad_numbers_are_jumpers no)
		(fp_line
			(start -0.299974 -0.150114)
			(end -0.299974 0.150114)
			(stroke
				(width 0.1)
				(type default)
			)
			(layer "B.Fab")
		)
		(fp_line
			(start -0.299974 0.150114)
			(end 0.299974 0.150114)
			(stroke
				(width 0.1)
				(type default)
			)
			(layer "B.Fab")
		)
		(fp_line
			(start 0.299974 -0.150114)
			(end -0.299974 -0.150114)
			(stroke
				(width 0.1)
				(type default)
			)
			(layer "B.Fab")
		)
		(fp_line
			(start 0.299974 0.150114)
			(end 0.299974 -0.150114)
			(stroke
				(width 0.1)
				(type default)
			)
			(layer "B.Fab")
		)
		(pad "1" smd rect
			(at 0.2667 0 180)
			(size 0.3048 0.381)
			(layers "B.Cu" "B.Mask" "B.Paste")
			(net "P0V8_PEX1")
		)
		(pad "2" smd rect
			(at -0.2667 0 180)
			(size 0.3048 0.381)
			(layers "B.Cu" "B.Mask" "B.Paste")
			(net "GND")
		)
	)
	(footprint ""
		(layer "B.Cu")
		(at 165.655244 -156.0576)
		(property "Reference" "R130"
			(at 0 0 0)
			(layer "B.SilkS")
			(hide yes)
			(effects
				(font
					(size 1.27 1.27)
				)
				(justify mirror)
			)
		)
		(property "Value" ""
			(at 0 0 0)
			(layer "B.Fab")
			(effects
				(font
					(size 1.27 1.27)
				)
				(justify mirror)
			)
		)
		(duplicate_pad_numbers_are_jumpers no)
		(fp_line
			(start -0.7874 -0.4064)
			(end -0.7874 0.4064)
			(stroke
				(width 0.1524)
				(type default)
			)
			(layer "B.SilkS")
		)
		(fp_line
			(start -0.7874 0.4064)
			(end 0.7874 0.4064)
			(stroke
				(width 0.1524)
				(type default)
			)
			(layer "B.SilkS")
		)
		(fp_line
			(start 0.7874 -0.4064)
			(end -0.7874 -0.4064)
			(stroke
				(width 0.1524)
				(type default)
			)
			(layer "B.SilkS")
		)
		(fp_line
			(start 0.7874 0.4064)
			(end 0.7874 -0.4064)
			(stroke
				(width 0.1524)
				(type default)
			)
			(layer "B.SilkS")
		)
		(fp_line
			(start -0.67945 -0.3048)
			(end -0.67945 0.3048)
			(stroke
				(width 0.1)
				(type default)
			)
			(layer "B.Fab")
		)
		(fp_line
			(start -0.67945 0.3048)
			(end -0.120396 0.3048)
			(stroke
				(width 0.1)
				(type default)
			)
			(layer "B.Fab")
		)
		(fp_line
			(start -0.12065 -0.3048)
			(end -0.67945 -0.3048)
			(stroke
				(width 0.1)
				(type default)
			)
			(layer "B.Fab")
		)
		(fp_line
			(start -0.12065 -0.2794)
			(end -0.12065 -0.3048)
			(stroke
				(width 0.1)
				(type default)
			)
			(layer "B.Fab")
		)
		(fp_line
			(start -0.120396 0.2794)
			(end 0.12065 0.2794)
			(stroke
				(width 0.1)
				(type default)
			)
			(layer "B.Fab")
		)
		(fp_line
			(start -0.120396 0.3048)
			(end -0.120396 0.2794)
			(stroke
				(width 0.1)
				(type default)
			)
			(layer "B.Fab")
		)
		(fp_line
			(start 0.12065 -0.305054)
			(end 0.12065 -0.2794)
			(stroke
				(width 0.1)
				(type default)
			)
			(layer "B.Fab")
		)
		(fp_line
			(start 0.12065 -0.2794)
			(end -0.12065 -0.2794)
			(stroke
				(width 0.1)
				(type default)
			)
			(layer "B.Fab")
		)
		(fp_line
			(start 0.12065 0.2794)
			(end 0.12065 0.3048)
			(stroke
				(width 0.1)
				(type default)
			)
			(layer "B.Fab")
		)
		(fp_line
			(start 0.12065 0.3048)
			(end 0.67945 0.3048)
			(stroke
				(width 0.1)
				(type default)
			)
			(layer "B.Fab")
		)
		(fp_line
			(start 0.67945 -0.305054)
			(end 0.12065 -0.305054)
			(stroke
				(width 0.1)
				(type default)
			)
			(layer "B.Fab")
		)
		(fp_line
			(start 0.67945 0.3048)
			(end 0.67945 -0.305054)
			(stroke
				(width 0.1)
				(type default)
			)
			(layer "B.Fab")
		)
		(pad "1" smd circle
			(at 0.40005 0 180)
			(size 0 0)
			(layers "B.Cu" "B.Mask" "B.Paste")
			(net "NIC2_SLOT_ID1")
		)
		(pad "2" smd circle
			(at -0.40005 0 180)
			(size 0 0)
			(layers "B.Cu" "B.Mask" "B.Paste")
			(net "GND")
		)
	)
	(footprint ""
		(layer "B.Cu")
		(at 259.448554 -81.001616 -90)
		(property "Reference" "C2635"
			(at 0 0 90)
			(layer "B.SilkS")
			(hide yes)
			(effects
				(font
					(size 1.27 1.27)
				)
				(justify mirror)
			)
		)
		(property "Value" ""
			(at 0 0 90)
			(layer "B.Fab")
			(effects
				(font
					(size 1.27 1.27)
				)
				(justify mirror)
			)
		)
		(duplicate_pad_numbers_are_jumpers no)
		(fp_line
			(start -0.7874 0.4064)
			(end 0.7874 0.4064)
			(stroke
				(width 0.1524)
				(type default)
			)
			(layer "B.SilkS")
		)
		(fp_line
			(start 0.7874 0.4064)
			(end 0.7874 -0.4064)
			(stroke
				(width 0.1524)
				(type default)
			)
			(layer "B.SilkS")
		)
		(fp_line
			(start -0.7874 -0.4064)
			(end -0.7874 0.4064)
			(stroke
				(width 0.1524)
				(type default)
			)
			(layer "B.SilkS")
		)
		(fp_line
			(start 0.7874 -0.4064)
			(end -0.7874 -0.4064)
			(stroke
				(width 0.1524)
				(type default)
			)
			(layer "B.SilkS")
		)
		(fp_line
			(start -0.67945 0.3048)
			(end -0.120396 0.3048)
			(stroke
				(width 0.1)
				(type default)
			)
			(layer "B.Fab")
		)
		(fp_line
			(start -0.120396 0.3048)
			(end -0.120396 0.2794)
			(stroke
				(width 0.1)
				(type default)
			)
			(layer "B.Fab")
		)
		(fp_line
			(start 0.12065 0.3048)
			(end 0.67945 0.3048)
			(stroke
				(width 0.1)
				(type default)
			)
			(layer "B.Fab")
		)
		(fp_line
			(start 0.67945 0.3048)
			(end 0.67945 -0.305054)
			(stroke
				(width 0.1)
				(type default)
			)
			(layer "B.Fab")
		)
		(fp_line
			(start -0.120396 0.2794)
			(end 0.12065 0.2794)
			(stroke
				(width 0.1)
				(type default)
			)
			(layer "B.Fab")
		)
		(fp_line
			(start 0.12065 0.2794)
			(end 0.12065 0.3048)
			(stroke
				(width 0.1)
				(type default)
			)
			(layer "B.Fab")
		)
		(fp_line
			(start -0.12065 -0.2794)
			(end -0.12065 -0.3048)
			(stroke
				(width 0.1)
				(type default)
			)
			(layer "B.Fab")
		)
		(fp_line
			(start 0.12065 -0.2794)
			(end -0.12065 -0.2794)
			(stroke
				(width 0.1)
				(type default)
			)
			(layer "B.Fab")
		)
		(fp_line
			(start -0.67945 -0.3048)
			(end -0.67945 0.3048)
			(stroke
				(width 0.1)
				(type default)
			)
			(layer "B.Fab")
		)
		(fp_line
			(start -0.12065 -0.3048)
			(end -0.67945 -0.3048)
			(stroke
				(width 0.1)
				(type default)
			)
			(layer "B.Fab")
		)
		(fp_line
			(start 0.12065 -0.305054)
			(end 0.12065 -0.2794)
			(stroke
				(width 0.1)
				(type default)
			)
			(layer "B.Fab")
		)
		(fp_line
			(start 0.67945 -0.305054)
			(end 0.12065 -0.305054)
			(stroke
				(width 0.1)
				(type default)
			)
			(layer "B.Fab")
		)
		(pad "1" smd circle
			(at 0.40005 0 90)
			(size 0 0)
			(layers "B.Cu" "B.Mask" "B.Paste")
			(net "P3V3_CLK_GEN_VDDA100M_CK440")
		)
		(pad "2" smd circle
			(at -0.40005 0 90)
			(size 0 0)
			(layers "B.Cu" "B.Mask" "B.Paste")
			(net "GND")
		)
	)
	(footprint ""
		(layer "B.Cu")
		(at 289.47491 -293.99992 -90)
		(property "Reference" "C1653"
			(at 0 0 90)
			(layer "B.SilkS")
			(hide yes)
			(effects
				(font
					(size 1.27 1.27)
				)
				(justify mirror)
			)
		)
		(property "Value" ""
			(at 0 0 90)
			(layer "B.Fab")
			(effects
				(font
					(size 1.27 1.27)
				)
				(justify mirror)
			)
		)
		(duplicate_pad_numbers_are_jumpers no)
		(fp_line
			(start -0.299974 0.150114)
			(end 0.299974 0.150114)
			(stroke
				(width 0.1)
				(type default)
			)
			(layer "B.Fab")
		)
		(fp_line
			(start 0.299974 0.150114)
			(end 0.299974 -0.150114)
			(stroke
				(width 0.1)
				(type default)
			)
			(layer "B.Fab")
		)
		(fp_line
			(start -0.299974 -0.150114)
			(end -0.299974 0.150114)
			(stroke
				(width 0.1)
				(type default)
			)
			(layer "B.Fab")
		)
		(fp_line
			(start 0.299974 -0.150114)
			(end -0.299974 -0.150114)
			(stroke
				(width 0.1)
				(type default)
			)
			(layer "B.Fab")
		)
		(pad "1" smd rect
			(at 0.2667 0 90)
			(size 0.3048 0.381)
			(layers "B.Cu" "B.Mask" "B.Paste")
			(net "P0V8_PEX2")
		)
		(pad "2" smd rect
			(at -0.2667 0 90)
			(size 0.3048 0.381)
			(layers "B.Cu" "B.Mask" "B.Paste")
			(net "GND")
		)
	)
	(footprint ""
		(layer "B.Cu")
		(at 414.124902 -286.399732 90)
		(property "Reference" "C3507"
			(at 0 0 90)
			(layer "B.SilkS")
			(hide yes)
			(effects
				(font
					(size 1.27 1.27)
				)
				(justify mirror)
			)
		)
		(property "Value" ""
			(at 0 0 90)
			(layer "B.Fab")
			(effects
				(font
					(size 1.27 1.27)
				)
				(justify mirror)
			)
		)
		(duplicate_pad_numbers_are_jumpers no)
		(fp_line
			(start 0.299974 -0.150114)
			(end -0.299974 -0.150114)
			(stroke
				(width 0.1)
				(type default)
			)
			(layer "B.Fab")
		)
		(fp_line
			(start -0.299974 -0.150114)
			(end -0.299974 0.150114)
			(stroke
				(width 0.1)
				(type default)
			)
			(layer "B.Fab")
		)
		(fp_line
			(start 0.299974 0.150114)
			(end 0.299974 -0.150114)
			(stroke
				(width 0.1)
				(type default)
			)
			(layer "B.Fab")
		)
		(fp_line
			(start -0.299974 0.150114)
			(end 0.299974 0.150114)
			(stroke
				(width 0.1)
				(type default)
			)
			(layer "B.Fab")
		)
		(pad "1" smd rect
			(at 0.2667 0 270)
			(size 0.3048 0.381)
			(layers "B.Cu" "B.Mask" "B.Paste")
			(net "P1V25_SERDES_VDDPLL_PEX3")
		)
		(pad "2" smd rect
			(at -0.2667 0 270)
			(size 0.3048 0.381)
			(layers "B.Cu" "B.Mask" "B.Paste")
			(net "GND")
		)
	)
	(footprint ""
		(layer "B.Cu")
		(at 421.249856 -297.79976 180)
		(property "Reference" "C3469"
			(at 0 0 0)
			(layer "B.SilkS")
			(hide yes)
			(effects
				(font
					(size 1.27 1.27)
				)
				(justify mirror)
			)
		)
		(property "Value" ""
			(at 0 0 0)
			(layer "B.Fab")
			(effects
				(font
					(size 1.27 1.27)
				)
				(justify mirror)
			)
		)
		(duplicate_pad_numbers_are_jumpers no)
		(fp_line
			(start 0.299974 0.150114)
			(end 0.299974 -0.150114)
			(stroke
				(width 0.1)
				(type default)
			)
			(layer "B.Fab")
		)
		(fp_line
			(start 0.299974 -0.150114)
			(end -0.299974 -0.150114)
			(stroke
				(width 0.1)
				(type default)
			)
			(layer "B.Fab")
		)
		(fp_line
			(start -0.299974 0.150114)
			(end 0.299974 0.150114)
			(stroke
				(width 0.1)
				(type default)
			)
			(layer "B.Fab")
		)
		(fp_line
			(start -0.299974 -0.150114)
			(end -0.299974 0.150114)
			(stroke
				(width 0.1)
				(type default)
			)
			(layer "B.Fab")
		)
		(pad "1" smd rect
			(at 0.2667 0)
			(size 0.3048 0.381)
			(layers "B.Cu" "B.Mask" "B.Paste")
			(net "P1V25_SERDES_VDDPLL_PEX3")
		)
		(pad "2" smd rect
			(at -0.2667 0)
			(size 0.3048 0.381)
			(layers "B.Cu" "B.Mask" "B.Paste")
			(net "GND")
		)
	)
	(footprint ""
		(layer "B.Cu")
		(at 162.4457 -301.076868)
		(property "Reference" "C3173"
			(at 0 0 0)
			(layer "B.SilkS")
			(hide yes)
			(effects
				(font
					(size 1.27 1.27)
				)
				(justify mirror)
			)
		)
		(property "Value" ""
			(at 0 0 0)
			(layer "B.Fab")
			(effects
				(font
					(size 1.27 1.27)
				)
				(justify mirror)
			)
		)
		(duplicate_pad_numbers_are_jumpers no)
		(fp_line
			(start -0.299974 -0.150114)
			(end -0.299974 0.150114)
			(stroke
				(width 0.1)
				(type default)
			)
			(layer "B.Fab")
		)
		(fp_line
			(start -0.299974 0.150114)
			(end 0.299974 0.150114)
			(stroke
				(width 0.1)
				(type default)
			)
			(layer "B.Fab")
		)
		(fp_line
			(start 0.299974 -0.150114)
			(end -0.299974 -0.150114)
			(stroke
				(width 0.1)
				(type default)
			)
			(layer "B.Fab")
		)
		(fp_line
			(start 0.299974 0.150114)
			(end 0.299974 -0.150114)
			(stroke
				(width 0.1)
				(type default)
			)
			(layer "B.Fab")
		)
		(pad "1" smd rect
			(at 0.2667 0 180)
			(size 0.3048 0.381)
			(layers "B.Cu" "B.Mask" "B.Paste")
			(net "P1V8_PEX")
		)
		(pad "2" smd rect
			(at -0.2667 0 180)
			(size 0.3048 0.381)
			(layers "B.Cu" "B.Mask" "B.Paste")
			(net "GND")
		)
	)
	(footprint ""
		(layer "B.Cu")
		(at 413.649922 -290.199826 90)
		(property "Reference" "C1958"
			(at 0 0 90)
			(layer "B.SilkS")
			(hide yes)
			(effects
				(font
					(size 1.27 1.27)
				)
				(justify mirror)
			)
		)
		(property "Value" ""
			(at 0 0 90)
			(layer "B.Fab")
			(effects
				(font
					(size 1.27 1.27)
				)
				(justify mirror)
			)
		)
		(duplicate_pad_numbers_are_jumpers no)
		(fp_line
			(start 0.299974 -0.150114)
			(end -0.299974 -0.150114)
			(stroke
				(width 0.1)
				(type default)
			)
			(layer "B.Fab")
		)
		(fp_line
			(start -0.299974 -0.150114)
			(end -0.299974 0.150114)
			(stroke
				(width 0.1)
				(type default)
			)
			(layer "B.Fab")
		)
		(fp_line
			(start 0.299974 0.150114)
			(end 0.299974 -0.150114)
			(stroke
				(width 0.1)
				(type default)
			)
			(layer "B.Fab")
		)
		(fp_line
			(start -0.299974 0.150114)
			(end 0.299974 0.150114)
			(stroke
				(width 0.1)
				(type default)
			)
			(layer "B.Fab")
		)
		(pad "1" smd rect
			(at 0.2667 0 270)
			(size 0.3048 0.381)
			(layers "B.Cu" "B.Mask" "B.Paste")
			(net "P0V8_SERDES_VDDA_PEX3")
		)
		(pad "2" smd rect
			(at -0.2667 0 270)
			(size 0.3048 0.381)
			(layers "B.Cu" "B.Mask" "B.Paste")
			(net "GND")
		)
	)
	(footprint ""
		(layer "B.Cu")
		(at 61.549788 -303.499774 -90)
		(property "Reference" "C2908"
			(at 0 0 90)
			(layer "B.SilkS")
			(hide yes)
			(effects
				(font
					(size 1.27 1.27)
				)
				(justify mirror)
			)
		)
		(property "Value" ""
			(at 0 0 90)
			(layer "B.Fab")
			(effects
				(font
					(size 1.27 1.27)
				)
				(justify mirror)
			)
		)
		(duplicate_pad_numbers_are_jumpers no)
		(fp_line
			(start -0.299974 0.150114)
			(end 0.299974 0.150114)
			(stroke
				(width 0.1)
				(type default)
			)
			(layer "B.Fab")
		)
		(fp_line
			(start 0.299974 0.150114)
			(end 0.299974 -0.150114)
			(stroke
				(width 0.1)
				(type default)
			)
			(layer "B.Fab")
		)
		(fp_line
			(start -0.299974 -0.150114)
			(end -0.299974 0.150114)
			(stroke
				(width 0.1)
				(type default)
			)
			(layer "B.Fab")
		)
		(fp_line
			(start 0.299974 -0.150114)
			(end -0.299974 -0.150114)
			(stroke
				(width 0.1)
				(type default)
			)
			(layer "B.Fab")
		)
		(pad "1" smd rect
			(at 0.2667 0 90)
			(size 0.3048 0.381)
			(layers "B.Cu" "B.Mask" "B.Paste")
			(net "P1V25_PEX0")
		)
		(pad "2" smd rect
			(at -0.2667 0 90)
			(size 0.3048 0.381)
			(layers "B.Cu" "B.Mask" "B.Paste")
			(net "GND")
		)
	)
	(footprint ""
		(layer "B.Cu")
		(at 295.575228 -109.481366 180)
		(property "Reference" "R287"
			(at 0 0 0)
			(layer "B.SilkS")
			(hide yes)
			(effects
				(font
					(size 1.27 1.27)
				)
				(justify mirror)
			)
		)
		(property "Value" ""
			(at 0 0 0)
			(layer "B.Fab")
			(effects
				(font
					(size 1.27 1.27)
				)
				(justify mirror)
			)
		)
		(duplicate_pad_numbers_are_jumpers no)
		(fp_line
			(start 0.7874 0.4064)
			(end 0.7874 -0.4064)
			(stroke
				(width 0.1524)
				(type default)
			)
			(layer "B.SilkS")
		)
		(fp_line
			(start 0.7874 -0.4064)
			(end -0.7874 -0.4064)
			(stroke
				(width 0.1524)
				(type default)
			)
			(layer "B.SilkS")
		)
		(fp_line
			(start -0.7874 0.4064)
			(end 0.7874 0.4064)
			(stroke
				(width 0.1524)
				(type default)
			)
			(layer "B.SilkS")
		)
		(fp_line
			(start -0.7874 -0.4064)
			(end -0.7874 0.4064)
			(stroke
				(width 0.1524)
				(type default)
			)
			(layer "B.SilkS")
		)
		(fp_line
			(start 0.67945 0.3048)
			(end 0.67945 -0.305054)
			(stroke
				(width 0.1)
				(type default)
			)
			(layer "B.Fab")
		)
		(fp_line
			(start 0.67945 -0.305054)
			(end 0.12065 -0.305054)
			(stroke
				(width 0.1)
				(type default)
			)
			(layer "B.Fab")
		)
		(fp_line
			(start 0.12065 0.3048)
			(end 0.67945 0.3048)
			(stroke
				(width 0.1)
				(type default)
			)
			(layer "B.Fab")
		)
		(fp_line
			(start 0.12065 0.2794)
			(end 0.12065 0.3048)
			(stroke
				(width 0.1)
				(type default)
			)
			(layer "B.Fab")
		)
		(fp_line
			(start 0.12065 -0.2794)
			(end -0.12065 -0.2794)
			(stroke
				(width 0.1)
				(type default)
			)
			(layer "B.Fab")
		)
		(fp_line
			(start 0.12065 -0.305054)
			(end 0.12065 -0.2794)
			(stroke
				(width 0.1)
				(type default)
			)
			(layer "B.Fab")
		)
		(fp_line
			(start -0.120396 0.3048)
			(end -0.120396 0.2794)
			(stroke
				(width 0.1)
				(type default)
			)
			(layer "B.Fab")
		)
		(fp_line
			(start -0.120396 0.2794)
			(end 0.12065 0.2794)
			(stroke
				(width 0.1)
				(type default)
			)
			(layer "B.Fab")
		)
		(fp_line
			(start -0.12065 -0.2794)
			(end -0.12065 -0.3048)
			(stroke
				(width 0.1)
				(type default)
			)
			(layer "B.Fab")
		)
		(fp_line
			(start -0.12065 -0.3048)
			(end -0.67945 -0.3048)
			(stroke
				(width 0.1)
				(type default)
			)
			(layer "B.Fab")
		)
		(fp_line
			(start -0.67945 0.3048)
			(end -0.120396 0.3048)
			(stroke
				(width 0.1)
				(type default)
			)
			(layer "B.Fab")
		)
		(fp_line
			(start -0.67945 -0.3048)
			(end -0.67945 0.3048)
			(stroke
				(width 0.1)
				(type default)
			)
			(layer "B.Fab")
		)
		(pad "1" smd circle
			(at 0.40005 0)
			(size 0 0)
			(layers "B.Cu" "B.Mask" "B.Paste")
			(net "NIC5_BIF1_N")
		)
		(pad "2" smd circle
			(at -0.40005 0)
			(size 0 0)
			(layers "B.Cu" "B.Mask" "B.Paste")
			(net "GND")
		)
	)
	(footprint ""
		(layer "B.Cu")
		(at 374.015 -234.569 180)
		(property "Reference" "C2584"
			(at 0 0 0)
			(layer "B.SilkS")
			(hide yes)
			(effects
				(font
					(size 1.27 1.27)
				)
				(justify mirror)
			)
		)
		(property "Value" ""
			(at 0 0 0)
			(layer "B.Fab")
			(effects
				(font
					(size 1.27 1.27)
				)
				(justify mirror)
			)
		)
		(duplicate_pad_numbers_are_jumpers no)
		(fp_line
			(start 0.7874 0.4064)
			(end 0.7874 -0.4064)
			(stroke
				(width 0.1524)
				(type default)
			)
			(layer "B.SilkS")
		)
		(fp_line
			(start 0.7874 -0.4064)
			(end -0.7874 -0.4064)
			(stroke
				(width 0.1524)
				(type default)
			)
			(layer "B.SilkS")
		)
		(fp_line
			(start -0.7874 0.4064)
			(end 0.7874 0.4064)
			(stroke
				(width 0.1524)
				(type default)
			)
			(layer "B.SilkS")
		)
		(fp_line
			(start -0.7874 -0.4064)
			(end -0.7874 0.4064)
			(stroke
				(width 0.1524)
				(type default)
			)
			(layer "B.SilkS")
		)
		(fp_line
			(start 0.67945 0.3048)
			(end 0.67945 -0.305054)
			(stroke
				(width 0.1)
				(type default)
			)
			(layer "B.Fab")
		)
		(fp_line
			(start 0.67945 -0.305054)
			(end 0.12065 -0.305054)
			(stroke
				(width 0.1)
				(type default)
			)
			(layer "B.Fab")
		)
		(fp_line
			(start 0.12065 0.3048)
			(end 0.67945 0.3048)
			(stroke
				(width 0.1)
				(type default)
			)
			(layer "B.Fab")
		)
		(fp_line
			(start 0.12065 0.2794)
			(end 0.12065 0.3048)
			(stroke
				(width 0.1)
				(type default)
			)
			(layer "B.Fab")
		)
		(fp_line
			(start 0.12065 -0.2794)
			(end -0.12065 -0.2794)
			(stroke
				(width 0.1)
				(type default)
			)
			(layer "B.Fab")
		)
		(fp_line
			(start 0.12065 -0.305054)
			(end 0.12065 -0.2794)
			(stroke
				(width 0.1)
				(type default)
			)
			(layer "B.Fab")
		)
		(fp_line
			(start -0.120396 0.3048)
			(end -0.120396 0.2794)
			(stroke
				(width 0.1)
				(type default)
			)
			(layer "B.Fab")
		)
		(fp_line
			(start -0.120396 0.2794)
			(end 0.12065 0.2794)
			(stroke
				(width 0.1)
				(type default)
			)
			(layer "B.Fab")
		)
		(fp_line
			(start -0.12065 -0.2794)
			(end -0.12065 -0.3048)
			(stroke
				(width 0.1)
				(type default)
			)
			(layer "B.Fab")
		)
		(fp_line
			(start -0.12065 -0.3048)
			(end -0.67945 -0.3048)
			(stroke
				(width 0.1)
				(type default)
			)
			(layer "B.Fab")
		)
		(fp_line
			(start -0.67945 0.3048)
			(end -0.120396 0.3048)
			(stroke
				(width 0.1)
				(type default)
			)
			(layer "B.Fab")
		)
		(fp_line
			(start -0.67945 -0.3048)
			(end -0.67945 0.3048)
			(stroke
				(width 0.1)
				(type default)
			)
			(layer "B.Fab")
		)
		(pad "1" smd circle
			(at 0.40005 0)
			(size 0 0)
			(layers "B.Cu" "B.Mask" "B.Paste")
			(net "P3V3_AUX")
		)
		(pad "2" smd circle
			(at -0.40005 0)
			(size 0 0)
			(layers "B.Cu" "B.Mask" "B.Paste")
			(net "GND")
		)
	)
	(footprint ""
		(layer "B.Cu")
		(at 46.736 -291.624766)
		(property "Reference" "C3060"
			(at 0 0 0)
			(layer "B.SilkS")
			(hide yes)
			(effects
				(font
					(size 1.27 1.27)
				)
				(justify mirror)
			)
		)
		(property "Value" ""
			(at 0 0 0)
			(layer "B.Fab")
			(effects
				(font
					(size 1.27 1.27)
				)
				(justify mirror)
			)
		)
		(duplicate_pad_numbers_are_jumpers no)
		(fp_line
			(start -0.299974 -0.150114)
			(end -0.299974 0.150114)
			(stroke
				(width 0.1)
				(type default)
			)
			(layer "B.Fab")
		)
		(fp_line
			(start -0.299974 0.150114)
			(end 0.299974 0.150114)
			(stroke
				(width 0.1)
				(type default)
			)
			(layer "B.Fab")
		)
		(fp_line
			(start 0.299974 -0.150114)
			(end -0.299974 -0.150114)
			(stroke
				(width 0.1)
				(type default)
			)
			(layer "B.Fab")
		)
		(fp_line
			(start 0.299974 0.150114)
			(end 0.299974 -0.150114)
			(stroke
				(width 0.1)
				(type default)
			)
			(layer "B.Fab")
		)
		(pad "1" smd rect
			(at 0.2667 0 180)
			(size 0.3048 0.381)
			(layers "B.Cu" "B.Mask" "B.Paste")
			(net "PCEPLL7_VDDA18_PEX0")
		)
		(pad "2" smd rect
			(at -0.2667 0 180)
			(size 0.3048 0.381)
			(layers "B.Cu" "B.Mask" "B.Paste")
			(net "GND")
		)
	)
	(footprint ""
		(layer "B.Cu")
		(at 236.18952 -288.197544)
		(property "Reference" "PC254"
			(at 0 0 0)
			(layer "B.SilkS")
			(hide yes)
			(effects
				(font
					(size 1.27 1.27)
				)
				(justify mirror)
			)
		)
		(property "Value" ""
			(at 0 0 0)
			(layer "B.Fab")
			(effects
				(font
					(size 1.27 1.27)
				)
				(justify mirror)
			)
		)
		(duplicate_pad_numbers_are_jumpers no)
		(fp_line
			(start -1.524 -0.762)
			(end -1.524 0.762)
			(stroke
				(width 0.1524)
				(type default)
			)
			(layer "B.SilkS")
		)
		(fp_line
			(start -1.524 0.762)
			(end 1.524 0.762)
			(stroke
				(width 0.1524)
				(type default)
			)
			(layer "B.SilkS")
		)
		(fp_line
			(start 1.524 -0.762)
			(end -1.524 -0.762)
			(stroke
				(width 0.1524)
				(type default)
			)
			(layer "B.SilkS")
		)
		(fp_line
			(start 1.524 0.762)
			(end 1.524 -0.762)
			(stroke
				(width 0.1524)
				(type default)
			)
			(layer "B.SilkS")
		)
		(fp_line
			(start -1.1049 -0.724916)
			(end 1.1049 -0.724916)
			(stroke
				(width 0.1)
				(type default)
			)
			(layer "B.Fab")
		)
		(fp_line
			(start -1.1049 0.724916)
			(end -1.1049 -0.724916)
			(stroke
				(width 0.1)
				(type default)
			)
			(layer "B.Fab")
		)
		(fp_line
			(start 1.1049 -0.724916)
			(end 1.1049 0.724916)
			(stroke
				(width 0.1)
				(type default)
			)
			(layer "B.Fab")
		)
		(fp_line
			(start 1.1049 0.724916)
			(end -1.1049 0.724916)
			(stroke
				(width 0.1)
				(type default)
			)
			(layer "B.Fab")
		)
		(pad "1" smd rect
			(at 0.889 0)
			(size 1.016 1.27)
			(layers "B.Cu" "B.Mask" "B.Paste")
			(net "P1V25_PEX2_R")
		)
		(pad "2" smd rect
			(at -0.889 0)
			(size 1.016 1.27)
			(layers "B.Cu" "B.Mask" "B.Paste")
			(net "GND")
		)
	)
	(footprint ""
		(layer "B.Cu")
		(at 294.69969 -290.199826 90)
		(property "Reference" "C1711"
			(at 0 0 90)
			(layer "B.SilkS")
			(hide yes)
			(effects
				(font
					(size 1.27 1.27)
				)
				(justify mirror)
			)
		)
		(property "Value" ""
			(at 0 0 90)
			(layer "B.Fab")
			(effects
				(font
					(size 1.27 1.27)
				)
				(justify mirror)
			)
		)
		(duplicate_pad_numbers_are_jumpers no)
		(fp_line
			(start 0.299974 -0.150114)
			(end -0.299974 -0.150114)
			(stroke
				(width 0.1)
				(type default)
			)
			(layer "B.Fab")
		)
		(fp_line
			(start -0.299974 -0.150114)
			(end -0.299974 0.150114)
			(stroke
				(width 0.1)
				(type default)
			)
			(layer "B.Fab")
		)
		(fp_line
			(start 0.299974 0.150114)
			(end 0.299974 -0.150114)
			(stroke
				(width 0.1)
				(type default)
			)
			(layer "B.Fab")
		)
		(fp_line
			(start -0.299974 0.150114)
			(end 0.299974 0.150114)
			(stroke
				(width 0.1)
				(type default)
			)
			(layer "B.Fab")
		)
		(pad "1" smd rect
			(at 0.2667 0 270)
			(size 0.3048 0.381)
			(layers "B.Cu" "B.Mask" "B.Paste")
			(net "P0V8_SERDES_VDDA_PEX2")
		)
		(pad "2" smd rect
			(at -0.2667 0 270)
			(size 0.3048 0.381)
			(layers "B.Cu" "B.Mask" "B.Paste")
			(net "GND")
		)
	)
	(footprint ""
		(layer "B.Cu")
		(at 302.061626 -251.787406 90)
		(property "Reference" "R4099"
			(at 0 0 90)
			(layer "B.SilkS")
			(hide yes)
			(effects
				(font
					(size 1.27 1.27)
				)
				(justify mirror)
			)
		)
		(property "Value" ""
			(at 0 0 90)
			(layer "B.Fab")
			(effects
				(font
					(size 1.27 1.27)
				)
				(justify mirror)
			)
		)
		(duplicate_pad_numbers_are_jumpers no)
		(fp_line
			(start 0.7874 -0.4064)
			(end -0.7874 -0.4064)
			(stroke
				(width 0.1524)
				(type default)
			)
			(layer "B.SilkS")
		)
		(fp_line
			(start -0.7874 -0.4064)
			(end -0.7874 0.4064)
			(stroke
				(width 0.1524)
				(type default)
			)
			(layer "B.SilkS")
		)
		(fp_line
			(start 0.7874 0.4064)
			(end 0.7874 -0.4064)
			(stroke
				(width 0.1524)
				(type default)
			)
			(layer "B.SilkS")
		)
		(fp_line
			(start -0.7874 0.4064)
			(end 0.7874 0.4064)
			(stroke
				(width 0.1524)
				(type default)
			)
			(layer "B.SilkS")
		)
		(fp_line
			(start 0.67945 -0.305054)
			(end 0.12065 -0.305054)
			(stroke
				(width 0.1)
				(type default)
			)
			(layer "B.Fab")
		)
		(fp_line
			(start 0.12065 -0.305054)
			(end 0.12065 -0.2794)
			(stroke
				(width 0.1)
				(type default)
			)
			(layer "B.Fab")
		)
		(fp_line
			(start -0.12065 -0.3048)
			(end -0.67945 -0.3048)
			(stroke
				(width 0.1)
				(type default)
			)
			(layer "B.Fab")
		)
		(fp_line
			(start -0.67945 -0.3048)
			(end -0.67945 0.3048)
			(stroke
				(width 0.1)
				(type default)
			)
			(layer "B.Fab")
		)
		(fp_line
			(start 0.12065 -0.2794)
			(end -0.12065 -0.2794)
			(stroke
				(width 0.1)
				(type default)
			)
			(layer "B.Fab")
		)
		(fp_line
			(start -0.12065 -0.2794)
			(end -0.12065 -0.3048)
			(stroke
				(width 0.1)
				(type default)
			)
			(layer "B.Fab")
		)
		(fp_line
			(start 0.12065 0.2794)
			(end 0.12065 0.3048)
			(stroke
				(width 0.1)
				(type default)
			)
			(layer "B.Fab")
		)
		(fp_line
			(start -0.120396 0.2794)
			(end 0.12065 0.2794)
			(stroke
				(width 0.1)
				(type default)
			)
			(layer "B.Fab")
		)
		(fp_line
			(start 0.67945 0.3048)
			(end 0.67945 -0.305054)
			(stroke
				(width 0.1)
				(type default)
			)
			(layer "B.Fab")
		)
		(fp_line
			(start 0.12065 0.3048)
			(end 0.67945 0.3048)
			(stroke
				(width 0.1)
				(type default)
			)
			(layer "B.Fab")
		)
		(fp_line
			(start -0.120396 0.3048)
			(end -0.120396 0.2794)
			(stroke
				(width 0.1)
				(type default)
			)
			(layer "B.Fab")
		)
		(fp_line
			(start -0.67945 0.3048)
			(end -0.120396 0.3048)
			(stroke
				(width 0.1)
				(type default)
			)
			(layer "B.Fab")
		)
		(pad "1" smd circle
			(at 0.40005 0 270)
			(size 0 0)
			(layers "B.Cu" "B.Mask" "B.Paste")
			(net "SMB_MB_BMC_R_SDA")
		)
		(pad "2" smd circle
			(at -0.40005 0 270)
			(size 0 0)
			(layers "B.Cu" "B.Mask" "B.Paste")
			(net "P3V3_AUX")
		)
	)
	(footprint ""
		(layer "B.Cu")
		(at 130.539744 -203.193142 180)
		(property "Reference" "R921"
			(at 0 0 0)
			(layer "B.SilkS")
			(hide yes)
			(effects
				(font
					(size 1.27 1.27)
				)
				(justify mirror)
			)
		)
		(property "Value" ""
			(at 0 0 0)
			(layer "B.Fab")
			(effects
				(font
					(size 1.27 1.27)
				)
				(justify mirror)
			)
		)
		(duplicate_pad_numbers_are_jumpers no)
		(fp_line
			(start 0.7874 0.4064)
			(end 0.7874 -0.4064)
			(stroke
				(width 0.1524)
				(type default)
			)
			(layer "B.SilkS")
		)
		(fp_line
			(start 0.7874 -0.4064)
			(end -0.7874 -0.4064)
			(stroke
				(width 0.1524)
				(type default)
			)
			(layer "B.SilkS")
		)
		(fp_line
			(start -0.7874 0.4064)
			(end 0.7874 0.4064)
			(stroke
				(width 0.1524)
				(type default)
			)
			(layer "B.SilkS")
		)
		(fp_line
			(start -0.7874 -0.4064)
			(end -0.7874 0.4064)
			(stroke
				(width 0.1524)
				(type default)
			)
			(layer "B.SilkS")
		)
		(fp_line
			(start 0.67945 0.3048)
			(end 0.67945 -0.305054)
			(stroke
				(width 0.1)
				(type default)
			)
			(layer "B.Fab")
		)
		(fp_line
			(start 0.67945 -0.305054)
			(end 0.12065 -0.305054)
			(stroke
				(width 0.1)
				(type default)
			)
			(layer "B.Fab")
		)
		(fp_line
			(start 0.12065 0.3048)
			(end 0.67945 0.3048)
			(stroke
				(width 0.1)
				(type default)
			)
			(layer "B.Fab")
		)
		(fp_line
			(start 0.12065 0.2794)
			(end 0.12065 0.3048)
			(stroke
				(width 0.1)
				(type default)
			)
			(layer "B.Fab")
		)
		(fp_line
			(start 0.12065 -0.2794)
			(end -0.12065 -0.2794)
			(stroke
				(width 0.1)
				(type default)
			)
			(layer "B.Fab")
		)
		(fp_line
			(start 0.12065 -0.305054)
			(end 0.12065 -0.2794)
			(stroke
				(width 0.1)
				(type default)
			)
			(layer "B.Fab")
		)
		(fp_line
			(start -0.120396 0.3048)
			(end -0.120396 0.2794)
			(stroke
				(width 0.1)
				(type default)
			)
			(layer "B.Fab")
		)
		(fp_line
			(start -0.120396 0.2794)
			(end 0.12065 0.2794)
			(stroke
				(width 0.1)
				(type default)
			)
			(layer "B.Fab")
		)
		(fp_line
			(start -0.12065 -0.2794)
			(end -0.12065 -0.3048)
			(stroke
				(width 0.1)
				(type default)
			)
			(layer "B.Fab")
		)
		(fp_line
			(start -0.12065 -0.3048)
			(end -0.67945 -0.3048)
			(stroke
				(width 0.1)
				(type default)
			)
			(layer "B.Fab")
		)
		(fp_line
			(start -0.67945 0.3048)
			(end -0.120396 0.3048)
			(stroke
				(width 0.1)
				(type default)
			)
			(layer "B.Fab")
		)
		(fp_line
			(start -0.67945 -0.3048)
			(end -0.67945 0.3048)
			(stroke
				(width 0.1)
				(type default)
			)
			(layer "B.Fab")
		)
		(pad "1" smd circle
			(at 0.40005 0)
			(size 0 0)
			(layers "B.Cu" "B.Mask" "B.Paste")
			(net "FT4232_CLI_EEPROM_R_CS")
		)
		(pad "2" smd circle
			(at -0.40005 0)
			(size 0 0)
			(layers "B.Cu" "B.Mask" "B.Paste")
			(net "FT4232_CLI_EEPROM_CS")
		)
	)
	(footprint ""
		(layer "B.Cu")
		(at 16.954246 -208.970372)
		(property "Reference" "C4417"
			(at 0 0 0)
			(layer "B.SilkS")
			(hide yes)
			(effects
				(font
					(size 1.27 1.27)
				)
				(justify mirror)
			)
		)
		(property "Value" ""
			(at 0 0 0)
			(layer "B.Fab")
			(effects
				(font
					(size 1.27 1.27)
				)
				(justify mirror)
			)
		)
		(duplicate_pad_numbers_are_jumpers no)
		(fp_line
			(start -0.7874 -0.4064)
			(end -0.7874 0.4064)
			(stroke
				(width 0.1524)
				(type default)
			)
			(layer "B.SilkS")
		)
		(fp_line
			(start -0.7874 0.4064)
			(end 0.7874 0.4064)
			(stroke
				(width 0.1524)
				(type default)
			)
			(layer "B.SilkS")
		)
		(fp_line
			(start 0.7874 -0.4064)
			(end -0.7874 -0.4064)
			(stroke
				(width 0.1524)
				(type default)
			)
			(layer "B.SilkS")
		)
		(fp_line
			(start 0.7874 0.4064)
			(end 0.7874 -0.4064)
			(stroke
				(width 0.1524)
				(type default)
			)
			(layer "B.SilkS")
		)
		(fp_line
			(start -0.67945 -0.3048)
			(end -0.67945 0.3048)
			(stroke
				(width 0.1)
				(type default)
			)
			(layer "B.Fab")
		)
		(fp_line
			(start -0.67945 0.3048)
			(end -0.120396 0.3048)
			(stroke
				(width 0.1)
				(type default)
			)
			(layer "B.Fab")
		)
		(fp_line
			(start -0.12065 -0.3048)
			(end -0.67945 -0.3048)
			(stroke
				(width 0.1)
				(type default)
			)
			(layer "B.Fab")
		)
		(fp_line
			(start -0.12065 -0.2794)
			(end -0.12065 -0.3048)
			(stroke
				(width 0.1)
				(type default)
			)
			(layer "B.Fab")
		)
		(fp_line
			(start -0.120396 0.2794)
			(end 0.12065 0.2794)
			(stroke
				(width 0.1)
				(type default)
			)
			(layer "B.Fab")
		)
		(fp_line
			(start -0.120396 0.3048)
			(end -0.120396 0.2794)
			(stroke
				(width 0.1)
				(type default)
			)
			(layer "B.Fab")
		)
		(fp_line
			(start 0.12065 -0.305054)
			(end 0.12065 -0.2794)
			(stroke
				(width 0.1)
				(type default)
			)
			(layer "B.Fab")
		)
		(fp_line
			(start 0.12065 -0.2794)
			(end -0.12065 -0.2794)
			(stroke
				(width 0.1)
				(type default)
			)
			(layer "B.Fab")
		)
		(fp_line
			(start 0.12065 0.2794)
			(end 0.12065 0.3048)
			(stroke
				(width 0.1)
				(type default)
			)
			(layer "B.Fab")
		)
		(fp_line
			(start 0.12065 0.3048)
			(end 0.67945 0.3048)
			(stroke
				(width 0.1)
				(type default)
			)
			(layer "B.Fab")
		)
		(fp_line
			(start 0.67945 -0.305054)
			(end 0.12065 -0.305054)
			(stroke
				(width 0.1)
				(type default)
			)
			(layer "B.Fab")
		)
		(fp_line
			(start 0.67945 0.3048)
			(end 0.67945 -0.305054)
			(stroke
				(width 0.1)
				(type default)
			)
			(layer "B.Fab")
		)
		(pad "1" smd circle
			(at 0.40005 0 180)
			(size 0 0)
			(layers "B.Cu" "B.Mask" "B.Paste")
			(net "P1V8_PLL0_PEX0")
		)
		(pad "2" smd circle
			(at -0.40005 0 180)
			(size 0 0)
			(layers "B.Cu" "B.Mask" "B.Paste")
			(net "GND")
		)
	)
	(footprint ""
		(layer "B.Cu")
		(at 166.725092 -293.99992 90)
		(property "Reference" "C1382"
			(at 0 0 90)
			(layer "B.SilkS")
			(hide yes)
			(effects
				(font
					(size 1.27 1.27)
				)
				(justify mirror)
			)
		)
		(property "Value" ""
			(at 0 0 90)
			(layer "B.Fab")
			(effects
				(font
					(size 1.27 1.27)
				)
				(justify mirror)
			)
		)
		(duplicate_pad_numbers_are_jumpers no)
		(fp_line
			(start 0.299974 -0.150114)
			(end -0.299974 -0.150114)
			(stroke
				(width 0.1)
				(type default)
			)
			(layer "B.Fab")
		)
		(fp_line
			(start -0.299974 -0.150114)
			(end -0.299974 0.150114)
			(stroke
				(width 0.1)
				(type default)
			)
			(layer "B.Fab")
		)
		(fp_line
			(start 0.299974 0.150114)
			(end 0.299974 -0.150114)
			(stroke
				(width 0.1)
				(type default)
			)
			(layer "B.Fab")
		)
		(fp_line
			(start -0.299974 0.150114)
			(end 0.299974 0.150114)
			(stroke
				(width 0.1)
				(type default)
			)
			(layer "B.Fab")
		)
		(pad "1" smd rect
			(at 0.2667 0 270)
			(size 0.3048 0.381)
			(layers "B.Cu" "B.Mask" "B.Paste")
			(net "P0V8_PEX1")
		)
		(pad "2" smd rect
			(at -0.2667 0 270)
			(size 0.3048 0.381)
			(layers "B.Cu" "B.Mask" "B.Paste")
			(net "GND")
		)
	)
	(footprint ""
		(layer "B.Cu")
		(at 301.349918 -302.074834)
		(property "Reference" "C3340"
			(at 0 0 0)
			(layer "B.SilkS")
			(hide yes)
			(effects
				(font
					(size 1.27 1.27)
				)
				(justify mirror)
			)
		)
		(property "Value" ""
			(at 0 0 0)
			(layer "B.Fab")
			(effects
				(font
					(size 1.27 1.27)
				)
				(justify mirror)
			)
		)
		(duplicate_pad_numbers_are_jumpers no)
		(fp_line
			(start -0.299974 -0.150114)
			(end -0.299974 0.150114)
			(stroke
				(width 0.1)
				(type default)
			)
			(layer "B.Fab")
		)
		(fp_line
			(start -0.299974 0.150114)
			(end 0.299974 0.150114)
			(stroke
				(width 0.1)
				(type default)
			)
			(layer "B.Fab")
		)
		(fp_line
			(start 0.299974 -0.150114)
			(end -0.299974 -0.150114)
			(stroke
				(width 0.1)
				(type default)
			)
			(layer "B.Fab")
		)
		(fp_line
			(start 0.299974 0.150114)
			(end 0.299974 -0.150114)
			(stroke
				(width 0.1)
				(type default)
			)
			(layer "B.Fab")
		)
		(pad "1" smd rect
			(at 0.2667 0 180)
			(size 0.3048 0.381)
			(layers "B.Cu" "B.Mask" "B.Paste")
			(net "P1V8_PEX")
		)
		(pad "2" smd rect
			(at -0.2667 0 180)
			(size 0.3048 0.381)
			(layers "B.Cu" "B.Mask" "B.Paste")
			(net "GND")
		)
	)
	(footprint ""
		(layer "B.Cu")
		(at 44.449746 -300.174914)
		(property "Reference" "C3008"
			(at 0 0 0)
			(layer "B.SilkS")
			(hide yes)
			(effects
				(font
					(size 1.27 1.27)
				)
				(justify mirror)
			)
		)
		(property "Value" ""
			(at 0 0 0)
			(layer "B.Fab")
			(effects
				(font
					(size 1.27 1.27)
				)
				(justify mirror)
			)
		)
		(duplicate_pad_numbers_are_jumpers no)
		(fp_line
			(start -0.299974 -0.150114)
			(end -0.299974 0.150114)
			(stroke
				(width 0.1)
				(type default)
			)
			(layer "B.Fab")
		)
		(fp_line
			(start -0.299974 0.150114)
			(end 0.299974 0.150114)
			(stroke
				(width 0.1)
				(type default)
			)
			(layer "B.Fab")
		)
		(fp_line
			(start 0.299974 -0.150114)
			(end -0.299974 -0.150114)
			(stroke
				(width 0.1)
				(type default)
			)
			(layer "B.Fab")
		)
		(fp_line
			(start 0.299974 0.150114)
			(end 0.299974 -0.150114)
			(stroke
				(width 0.1)
				(type default)
			)
			(layer "B.Fab")
		)
		(pad "1" smd rect
			(at 0.2667 0 180)
			(size 0.3048 0.381)
			(layers "B.Cu" "B.Mask" "B.Paste")
			(net "P1V8_VDDA_PEX0")
		)
		(pad "2" smd rect
			(at -0.2667 0 180)
			(size 0.3048 0.381)
			(layers "B.Cu" "B.Mask" "B.Paste")
			(net "GND")
		)
	)
	(footprint ""
		(layer "B.Cu")
		(at 240.255806 -278.870664 -90)
		(property "Reference" "C4330"
			(at 0 0 90)
			(layer "B.SilkS")
			(hide yes)
			(effects
				(font
					(size 1.27 1.27)
				)
				(justify mirror)
			)
		)
		(property "Value" ""
			(at 0 0 90)
			(layer "B.Fab")
			(effects
				(font
					(size 1.27 1.27)
				)
				(justify mirror)
			)
		)
		(duplicate_pad_numbers_are_jumpers no)
		(fp_line
			(start -1.2954 0.5842)
			(end 1.2954 0.5842)
			(stroke
				(width 0.1524)
				(type default)
			)
			(layer "B.SilkS")
		)
		(fp_line
			(start 1.2954 0.5842)
			(end 1.2954 -0.5842)
			(stroke
				(width 0.1524)
				(type default)
			)
			(layer "B.SilkS")
		)
		(fp_line
			(start -1.2954 -0.5842)
			(end -1.2954 0.5842)
			(stroke
				(width 0.1524)
				(type default)
			)
			(layer "B.SilkS")
		)
		(fp_line
			(start 1.2954 -0.5842)
			(end -1.2954 -0.5842)
			(stroke
				(width 0.1524)
				(type default)
			)
			(layer "B.SilkS")
		)
		(fp_line
			(start -0.8636 0.4572)
			(end 0.8636 0.4572)
			(stroke
				(width 0.1)
				(type default)
			)
			(layer "B.Fab")
		)
		(fp_line
			(start 0.8636 0.4572)
			(end 0.8636 0.4064)
			(stroke
				(width 0.1)
				(type default)
			)
			(layer "B.Fab")
		)
		(fp_line
			(start -1.1938 0.4064)
			(end -0.8636 0.4064)
			(stroke
				(width 0.1)
				(type default)
			)
			(layer "B.Fab")
		)
		(fp_line
			(start -0.8636 0.4064)
			(end -0.8636 0.4572)
			(stroke
				(width 0.1)
				(type default)
			)
			(layer "B.Fab")
		)
		(fp_line
			(start 0.8636 0.4064)
			(end 1.1938 0.4064)
			(stroke
				(width 0.1)
				(type default)
			)
			(layer "B.Fab")
		)
		(fp_line
			(start 1.1938 0.4064)
			(end 1.1938 -0.4064)
			(stroke
				(width 0.1)
				(type default)
			)
			(layer "B.Fab")
		)
		(fp_line
			(start -1.1938 -0.4064)
			(end -1.1938 0.4064)
			(stroke
				(width 0.1)
				(type default)
			)
			(layer "B.Fab")
		)
		(fp_line
			(start -0.8636 -0.4064)
			(end -1.1938 -0.4064)
			(stroke
				(width 0.1)
				(type default)
			)
			(layer "B.Fab")
		)
		(fp_line
			(start 0.8636 -0.4064)
			(end 0.8636 -0.4572)
			(stroke
				(width 0.1)
				(type default)
			)
			(layer "B.Fab")
		)
		(fp_line
			(start 1.1938 -0.4064)
			(end 0.8636 -0.4064)
			(stroke
				(width 0.1)
				(type default)
			)
			(layer "B.Fab")
		)
		(fp_line
			(start -0.8636 -0.4572)
			(end -0.8636 -0.4064)
			(stroke
				(width 0.1)
				(type default)
			)
			(layer "B.Fab")
		)
		(fp_line
			(start 0.8636 -0.4572)
			(end -0.8636 -0.4572)
			(stroke
				(width 0.1)
				(type default)
			)
			(layer "B.Fab")
		)
		(pad "1" smd rect
			(at 0.7366 0 180)
			(size 0.7112 0.8128)
			(layers "B.Cu" "B.Mask" "B.Paste")
			(net "P1V25_PEX2")
		)
		(pad "2" smd rect
			(at -0.7366 0 180)
			(size 0.7112 0.8128)
			(layers "B.Cu" "B.Mask" "B.Paste")
			(net "GND")
		)
	)
	(footprint ""
		(layer "B.Cu")
		(at 246.804688 -312.434478 90)
		(property "Reference" "R4437"
			(at 0 0 90)
			(layer "B.SilkS")
			(hide yes)
			(effects
				(font
					(size 1.27 1.27)
				)
				(justify mirror)
			)
		)
		(property "Value" ""
			(at 0 0 90)
			(layer "B.Fab")
			(effects
				(font
					(size 1.27 1.27)
				)
				(justify mirror)
			)
		)
		(duplicate_pad_numbers_are_jumpers no)
		(fp_line
			(start 0.7874 -0.4064)
			(end -0.7874 -0.4064)
			(stroke
				(width 0.1524)
				(type default)
			)
			(layer "B.SilkS")
		)
		(fp_line
			(start -0.7874 -0.4064)
			(end -0.7874 0.4064)
			(stroke
				(width 0.1524)
				(type default)
			)
			(layer "B.SilkS")
		)
		(fp_line
			(start 0.7874 0.4064)
			(end 0.7874 -0.4064)
			(stroke
				(width 0.1524)
				(type default)
			)
			(layer "B.SilkS")
		)
		(fp_line
			(start -0.7874 0.4064)
			(end 0.7874 0.4064)
			(stroke
				(width 0.1524)
				(type default)
			)
			(layer "B.SilkS")
		)
		(fp_line
			(start 0.67945 -0.305054)
			(end 0.12065 -0.305054)
			(stroke
				(width 0.1)
				(type default)
			)
			(layer "B.Fab")
		)
		(fp_line
			(start 0.12065 -0.305054)
			(end 0.12065 -0.2794)
			(stroke
				(width 0.1)
				(type default)
			)
			(layer "B.Fab")
		)
		(fp_line
			(start -0.12065 -0.3048)
			(end -0.67945 -0.3048)
			(stroke
				(width 0.1)
				(type default)
			)
			(layer "B.Fab")
		)
		(fp_line
			(start -0.67945 -0.3048)
			(end -0.67945 0.3048)
			(stroke
				(width 0.1)
				(type default)
			)
			(layer "B.Fab")
		)
		(fp_line
			(start 0.12065 -0.2794)
			(end -0.12065 -0.2794)
			(stroke
				(width 0.1)
				(type default)
			)
			(layer "B.Fab")
		)
		(fp_line
			(start -0.12065 -0.2794)
			(end -0.12065 -0.3048)
			(stroke
				(width 0.1)
				(type default)
			)
			(layer "B.Fab")
		)
		(fp_line
			(start 0.12065 0.2794)
			(end 0.12065 0.3048)
			(stroke
				(width 0.1)
				(type default)
			)
			(layer "B.Fab")
		)
		(fp_line
			(start -0.120396 0.2794)
			(end 0.12065 0.2794)
			(stroke
				(width 0.1)
				(type default)
			)
			(layer "B.Fab")
		)
		(fp_line
			(start 0.67945 0.3048)
			(end 0.67945 -0.305054)
			(stroke
				(width 0.1)
				(type default)
			)
			(layer "B.Fab")
		)
		(fp_line
			(start 0.12065 0.3048)
			(end 0.67945 0.3048)
			(stroke
				(width 0.1)
				(type default)
			)
			(layer "B.Fab")
		)
		(fp_line
			(start -0.120396 0.3048)
			(end -0.120396 0.2794)
			(stroke
				(width 0.1)
				(type default)
			)
			(layer "B.Fab")
		)
		(fp_line
			(start -0.67945 0.3048)
			(end -0.120396 0.3048)
			(stroke
				(width 0.1)
				(type default)
			)
			(layer "B.Fab")
		)
		(pad "1" smd circle
			(at 0.40005 0 270)
			(size 0 0)
			(layers "B.Cu" "B.Mask" "B.Paste")
			(net "PWRGD_P1V25_PEX2_R")
		)
		(pad "2" smd circle
			(at -0.40005 0 270)
			(size 0 0)
			(layers "B.Cu" "B.Mask" "B.Paste")
			(net "PWRGD_P1V25_PEX2")
		)
	)
	(footprint ""
		(layer "B.Cu")
		(at 66.076576 -111.334042 180)
		(property "Reference" "R87"
			(at 0 0 0)
			(layer "B.SilkS")
			(hide yes)
			(effects
				(font
					(size 1.27 1.27)
				)
				(justify mirror)
			)
		)
		(property "Value" ""
			(at 0 0 0)
			(layer "B.Fab")
			(effects
				(font
					(size 1.27 1.27)
				)
				(justify mirror)
			)
		)
		(duplicate_pad_numbers_are_jumpers no)
		(fp_line
			(start 0.7874 0.4064)
			(end 0.7874 -0.4064)
			(stroke
				(width 0.1524)
				(type default)
			)
			(layer "B.SilkS")
		)
		(fp_line
			(start 0.7874 -0.4064)
			(end -0.7874 -0.4064)
			(stroke
				(width 0.1524)
				(type default)
			)
			(layer "B.SilkS")
		)
		(fp_line
			(start -0.7874 0.4064)
			(end 0.7874 0.4064)
			(stroke
				(width 0.1524)
				(type default)
			)
			(layer "B.SilkS")
		)
		(fp_line
			(start -0.7874 -0.4064)
			(end -0.7874 0.4064)
			(stroke
				(width 0.1524)
				(type default)
			)
			(layer "B.SilkS")
		)
		(fp_line
			(start 0.67945 0.3048)
			(end 0.67945 -0.305054)
			(stroke
				(width 0.1)
				(type default)
			)
			(layer "B.Fab")
		)
		(fp_line
			(start 0.67945 -0.305054)
			(end 0.12065 -0.305054)
			(stroke
				(width 0.1)
				(type default)
			)
			(layer "B.Fab")
		)
		(fp_line
			(start 0.12065 0.3048)
			(end 0.67945 0.3048)
			(stroke
				(width 0.1)
				(type default)
			)
			(layer "B.Fab")
		)
		(fp_line
			(start 0.12065 0.2794)
			(end 0.12065 0.3048)
			(stroke
				(width 0.1)
				(type default)
			)
			(layer "B.Fab")
		)
		(fp_line
			(start 0.12065 -0.2794)
			(end -0.12065 -0.2794)
			(stroke
				(width 0.1)
				(type default)
			)
			(layer "B.Fab")
		)
		(fp_line
			(start 0.12065 -0.305054)
			(end 0.12065 -0.2794)
			(stroke
				(width 0.1)
				(type default)
			)
			(layer "B.Fab")
		)
		(fp_line
			(start -0.120396 0.3048)
			(end -0.120396 0.2794)
			(stroke
				(width 0.1)
				(type default)
			)
			(layer "B.Fab")
		)
		(fp_line
			(start -0.120396 0.2794)
			(end 0.12065 0.2794)
			(stroke
				(width 0.1)
				(type default)
			)
			(layer "B.Fab")
		)
		(fp_line
			(start -0.12065 -0.2794)
			(end -0.12065 -0.3048)
			(stroke
				(width 0.1)
				(type default)
			)
			(layer "B.Fab")
		)
		(fp_line
			(start -0.12065 -0.3048)
			(end -0.67945 -0.3048)
			(stroke
				(width 0.1)
				(type default)
			)
			(layer "B.Fab")
		)
		(fp_line
			(start -0.67945 0.3048)
			(end -0.120396 0.3048)
			(stroke
				(width 0.1)
				(type default)
			)
			(layer "B.Fab")
		)
		(fp_line
			(start -0.67945 -0.3048)
			(end -0.67945 0.3048)
			(stroke
				(width 0.1)
				(type default)
			)
			(layer "B.Fab")
		)
		(pad "1" smd circle
			(at 0.40005 0)
			(size 0 0)
			(layers "B.Cu" "B.Mask" "B.Paste")
			(net "RST_SMB_NIC_MUX_R_N")
		)
		(pad "2" smd circle
			(at -0.40005 0)
			(size 0 0)
			(layers "B.Cu" "B.Mask" "B.Paste")
			(net "RST_SMB_NIC1_MUX_N")
		)
	)
	(footprint ""
		(layer "B.Cu")
		(at 183.3499 -288.299906 90)
		(property "Reference" "C3103"
			(at 0 0 90)
			(layer "B.SilkS")
			(hide yes)
			(effects
				(font
					(size 1.27 1.27)
				)
				(justify mirror)
			)
		)
		(property "Value" ""
			(at 0 0 90)
			(layer "B.Fab")
			(effects
				(font
					(size 1.27 1.27)
				)
				(justify mirror)
			)
		)
		(duplicate_pad_numbers_are_jumpers no)
		(fp_line
			(start 0.299974 -0.150114)
			(end -0.299974 -0.150114)
			(stroke
				(width 0.1)
				(type default)
			)
			(layer "B.Fab")
		)
		(fp_line
			(start -0.299974 -0.150114)
			(end -0.299974 0.150114)
			(stroke
				(width 0.1)
				(type default)
			)
			(layer "B.Fab")
		)
		(fp_line
			(start 0.299974 0.150114)
			(end 0.299974 -0.150114)
			(stroke
				(width 0.1)
				(type default)
			)
			(layer "B.Fab")
		)
		(fp_line
			(start -0.299974 0.150114)
			(end 0.299974 0.150114)
			(stroke
				(width 0.1)
				(type default)
			)
			(layer "B.Fab")
		)
		(pad "1" smd rect
			(at 0.2667 0 270)
			(size 0.3048 0.381)
			(layers "B.Cu" "B.Mask" "B.Paste")
			(net "P1V25_PEX1")
		)
		(pad "2" smd rect
			(at -0.2667 0 270)
			(size 0.3048 0.381)
			(layers "B.Cu" "B.Mask" "B.Paste")
			(net "GND")
		)
	)
	(footprint ""
		(layer "B.Cu")
		(at 375.58853 -235.540296 180)
		(property "Reference" "R912"
			(at 0 0 0)
			(layer "B.SilkS")
			(hide yes)
			(effects
				(font
					(size 1.27 1.27)
				)
				(justify mirror)
			)
		)
		(property "Value" ""
			(at 0 0 0)
			(layer "B.Fab")
			(effects
				(font
					(size 1.27 1.27)
				)
				(justify mirror)
			)
		)
		(duplicate_pad_numbers_are_jumpers no)
		(fp_line
			(start 0.7874 0.4064)
			(end 0.7874 -0.4064)
			(stroke
				(width 0.1524)
				(type default)
			)
			(layer "B.SilkS")
		)
		(fp_line
			(start 0.7874 -0.4064)
			(end -0.7874 -0.4064)
			(stroke
				(width 0.1524)
				(type default)
			)
			(layer "B.SilkS")
		)
		(fp_line
			(start -0.7874 0.4064)
			(end 0.7874 0.4064)
			(stroke
				(width 0.1524)
				(type default)
			)
			(layer "B.SilkS")
		)
		(fp_line
			(start -0.7874 -0.4064)
			(end -0.7874 0.4064)
			(stroke
				(width 0.1524)
				(type default)
			)
			(layer "B.SilkS")
		)
		(fp_line
			(start 0.67945 0.3048)
			(end 0.67945 -0.305054)
			(stroke
				(width 0.1)
				(type default)
			)
			(layer "B.Fab")
		)
		(fp_line
			(start 0.67945 -0.305054)
			(end 0.12065 -0.305054)
			(stroke
				(width 0.1)
				(type default)
			)
			(layer "B.Fab")
		)
		(fp_line
			(start 0.12065 0.3048)
			(end 0.67945 0.3048)
			(stroke
				(width 0.1)
				(type default)
			)
			(layer "B.Fab")
		)
		(fp_line
			(start 0.12065 0.2794)
			(end 0.12065 0.3048)
			(stroke
				(width 0.1)
				(type default)
			)
			(layer "B.Fab")
		)
		(fp_line
			(start 0.12065 -0.2794)
			(end -0.12065 -0.2794)
			(stroke
				(width 0.1)
				(type default)
			)
			(layer "B.Fab")
		)
		(fp_line
			(start 0.12065 -0.305054)
			(end 0.12065 -0.2794)
			(stroke
				(width 0.1)
				(type default)
			)
			(layer "B.Fab")
		)
		(fp_line
			(start -0.120396 0.3048)
			(end -0.120396 0.2794)
			(stroke
				(width 0.1)
				(type default)
			)
			(layer "B.Fab")
		)
		(fp_line
			(start -0.120396 0.2794)
			(end 0.12065 0.2794)
			(stroke
				(width 0.1)
				(type default)
			)
			(layer "B.Fab")
		)
		(fp_line
			(start -0.12065 -0.2794)
			(end -0.12065 -0.3048)
			(stroke
				(width 0.1)
				(type default)
			)
			(layer "B.Fab")
		)
		(fp_line
			(start -0.12065 -0.3048)
			(end -0.67945 -0.3048)
			(stroke
				(width 0.1)
				(type default)
			)
			(layer "B.Fab")
		)
		(fp_line
			(start -0.67945 0.3048)
			(end -0.120396 0.3048)
			(stroke
				(width 0.1)
				(type default)
			)
			(layer "B.Fab")
		)
		(fp_line
			(start -0.67945 -0.3048)
			(end -0.67945 0.3048)
			(stroke
				(width 0.1)
				(type default)
			)
			(layer "B.Fab")
		)
		(pad "1" smd circle
			(at 0.40005 0)
			(size 0 0)
			(layers "B.Cu" "B.Mask" "B.Paste")
			(net "FT4232_SDB_EEPROM_R_CS")
		)
		(pad "2" smd circle
			(at -0.40005 0)
			(size 0 0)
			(layers "B.Cu" "B.Mask" "B.Paste")
			(net "FT4232_SDB_EEPROM_CS")
		)
	)
	(footprint ""
		(layer "B.Cu")
		(at 403.10054 -85.797898 180)
		(property "Reference" "R6271"
			(at 0 0 0)
			(layer "B.SilkS")
			(hide yes)
			(effects
				(font
					(size 1.27 1.27)
				)
				(justify mirror)
			)
		)
		(property "Value" ""
			(at 0 0 0)
			(layer "B.Fab")
			(effects
				(font
					(size 1.27 1.27)
				)
				(justify mirror)
			)
		)
		(duplicate_pad_numbers_are_jumpers no)
		(fp_line
			(start 0.7874 0.4064)
			(end 0.7874 -0.4064)
			(stroke
				(width 0.1524)
				(type default)
			)
			(layer "B.SilkS")
		)
		(fp_line
			(start 0.7874 -0.4064)
			(end -0.7874 -0.4064)
			(stroke
				(width 0.1524)
				(type default)
			)
			(layer "B.SilkS")
		)
		(fp_line
			(start -0.7874 0.4064)
			(end 0.7874 0.4064)
			(stroke
				(width 0.1524)
				(type default)
			)
			(layer "B.SilkS")
		)
		(fp_line
			(start -0.7874 -0.4064)
			(end -0.7874 0.4064)
			(stroke
				(width 0.1524)
				(type default)
			)
			(layer "B.SilkS")
		)
		(fp_line
			(start 0.67945 0.3048)
			(end 0.67945 -0.305054)
			(stroke
				(width 0.1)
				(type default)
			)
			(layer "B.Fab")
		)
		(fp_line
			(start 0.67945 -0.305054)
			(end 0.12065 -0.305054)
			(stroke
				(width 0.1)
				(type default)
			)
			(layer "B.Fab")
		)
		(fp_line
			(start 0.12065 0.3048)
			(end 0.67945 0.3048)
			(stroke
				(width 0.1)
				(type default)
			)
			(layer "B.Fab")
		)
		(fp_line
			(start 0.12065 0.2794)
			(end 0.12065 0.3048)
			(stroke
				(width 0.1)
				(type default)
			)
			(layer "B.Fab")
		)
		(fp_line
			(start 0.12065 -0.2794)
			(end -0.12065 -0.2794)
			(stroke
				(width 0.1)
				(type default)
			)
			(layer "B.Fab")
		)
		(fp_line
			(start 0.12065 -0.305054)
			(end 0.12065 -0.2794)
			(stroke
				(width 0.1)
				(type default)
			)
			(layer "B.Fab")
		)
		(fp_line
			(start -0.120396 0.3048)
			(end -0.120396 0.2794)
			(stroke
				(width 0.1)
				(type default)
			)
			(layer "B.Fab")
		)
		(fp_line
			(start -0.120396 0.2794)
			(end 0.12065 0.2794)
			(stroke
				(width 0.1)
				(type default)
			)
			(layer "B.Fab")
		)
		(fp_line
			(start -0.12065 -0.2794)
			(end -0.12065 -0.3048)
			(stroke
				(width 0.1)
				(type default)
			)
			(layer "B.Fab")
		)
		(fp_line
			(start -0.12065 -0.3048)
			(end -0.67945 -0.3048)
			(stroke
				(width 0.1)
				(type default)
			)
			(layer "B.Fab")
		)
		(fp_line
			(start -0.67945 0.3048)
			(end -0.120396 0.3048)
			(stroke
				(width 0.1)
				(type default)
			)
			(layer "B.Fab")
		)
		(fp_line
			(start -0.67945 -0.3048)
			(end -0.67945 0.3048)
			(stroke
				(width 0.1)
				(type default)
			)
			(layer "B.Fab")
		)
		(pad "1" smd circle
			(at 0.40005 0)
			(size 0 0)
			(layers "B.Cu" "B.Mask" "B.Paste")
			(net "SMB_BIC_I2C6_MUX_CLK_R_SCL")
		)
		(pad "2" smd circle
			(at -0.40005 0)
			(size 0 0)
			(layers "B.Cu" "B.Mask" "B.Paste")
			(net "SMB_CLK_ISO_SCL")
		)
	)
	(footprint ""
		(layer "B.Cu")
		(at 366.132364 -222.658432)
		(property "Reference" "C2503"
			(at 0 0 0)
			(layer "B.SilkS")
			(hide yes)
			(effects
				(font
					(size 1.27 1.27)
				)
				(justify mirror)
			)
		)
		(property "Value" ""
			(at 0 0 0)
			(layer "B.Fab")
			(effects
				(font
					(size 1.27 1.27)
				)
				(justify mirror)
			)
		)
		(duplicate_pad_numbers_are_jumpers no)
		(fp_line
			(start -0.7874 -0.4064)
			(end -0.7874 0.4064)
			(stroke
				(width 0.1524)
				(type default)
			)
			(layer "B.SilkS")
		)
		(fp_line
			(start -0.7874 0.4064)
			(end 0.7874 0.4064)
			(stroke
				(width 0.1524)
				(type default)
			)
			(layer "B.SilkS")
		)
		(fp_line
			(start 0.7874 -0.4064)
			(end -0.7874 -0.4064)
			(stroke
				(width 0.1524)
				(type default)
			)
			(layer "B.SilkS")
		)
		(fp_line
			(start 0.7874 0.4064)
			(end 0.7874 -0.4064)
			(stroke
				(width 0.1524)
				(type default)
			)
			(layer "B.SilkS")
		)
		(fp_line
			(start -0.67945 -0.3048)
			(end -0.67945 0.3048)
			(stroke
				(width 0.1)
				(type default)
			)
			(layer "B.Fab")
		)
		(fp_line
			(start -0.67945 0.3048)
			(end -0.120396 0.3048)
			(stroke
				(width 0.1)
				(type default)
			)
			(layer "B.Fab")
		)
		(fp_line
			(start -0.12065 -0.3048)
			(end -0.67945 -0.3048)
			(stroke
				(width 0.1)
				(type default)
			)
			(layer "B.Fab")
		)
		(fp_line
			(start -0.12065 -0.2794)
			(end -0.12065 -0.3048)
			(stroke
				(width 0.1)
				(type default)
			)
			(layer "B.Fab")
		)
		(fp_line
			(start -0.120396 0.2794)
			(end 0.12065 0.2794)
			(stroke
				(width 0.1)
				(type default)
			)
			(layer "B.Fab")
		)
		(fp_line
			(start -0.120396 0.3048)
			(end -0.120396 0.2794)
			(stroke
				(width 0.1)
				(type default)
			)
			(layer "B.Fab")
		)
		(fp_line
			(start 0.12065 -0.305054)
			(end 0.12065 -0.2794)
			(stroke
				(width 0.1)
				(type default)
			)
			(layer "B.Fab")
		)
		(fp_line
			(start 0.12065 -0.2794)
			(end -0.12065 -0.2794)
			(stroke
				(width 0.1)
				(type default)
			)
			(layer "B.Fab")
		)
		(fp_line
			(start 0.12065 0.2794)
			(end 0.12065 0.3048)
			(stroke
				(width 0.1)
				(type default)
			)
			(layer "B.Fab")
		)
		(fp_line
			(start 0.12065 0.3048)
			(end 0.67945 0.3048)
			(stroke
				(width 0.1)
				(type default)
			)
			(layer "B.Fab")
		)
		(fp_line
			(start 0.67945 -0.305054)
			(end 0.12065 -0.305054)
			(stroke
				(width 0.1)
				(type default)
			)
			(layer "B.Fab")
		)
		(fp_line
			(start 0.67945 0.3048)
			(end 0.67945 -0.305054)
			(stroke
				(width 0.1)
				(type default)
			)
			(layer "B.Fab")
		)
		(pad "1" smd circle
			(at 0.40005 0 180)
			(size 0 0)
			(layers "B.Cu" "B.Mask" "B.Paste")
			(net "GND")
		)
		(pad "2" smd circle
			(at -0.40005 0 180)
			(size 0 0)
			(layers "B.Cu" "B.Mask" "B.Paste")
			(net "P3V3_AUX")
		)
	)
	(footprint ""
		(layer "B.Cu")
		(at 339.311742 -326.945498 -90)
		(property "Reference" "C4311"
			(at 0 0 90)
			(layer "B.SilkS")
			(hide yes)
			(effects
				(font
					(size 1.27 1.27)
				)
				(justify mirror)
			)
		)
		(property "Value" ""
			(at 0 0 90)
			(layer "B.Fab")
			(effects
				(font
					(size 1.27 1.27)
				)
				(justify mirror)
			)
		)
		(duplicate_pad_numbers_are_jumpers no)
		(fp_line
			(start -1.2954 0.5842)
			(end 1.2954 0.5842)
			(stroke
				(width 0.1524)
				(type default)
			)
			(layer "B.SilkS")
		)
		(fp_line
			(start 1.2954 0.5842)
			(end 1.2954 -0.5842)
			(stroke
				(width 0.1524)
				(type default)
			)
			(layer "B.SilkS")
		)
		(fp_line
			(start -1.2954 -0.5842)
			(end -1.2954 0.5842)
			(stroke
				(width 0.1524)
				(type default)
			)
			(layer "B.SilkS")
		)
		(fp_line
			(start 1.2954 -0.5842)
			(end -1.2954 -0.5842)
			(stroke
				(width 0.1524)
				(type default)
			)
			(layer "B.SilkS")
		)
		(fp_line
			(start -0.8636 0.4572)
			(end 0.8636 0.4572)
			(stroke
				(width 0.1)
				(type default)
			)
			(layer "B.Fab")
		)
		(fp_line
			(start 0.8636 0.4572)
			(end 0.8636 0.4064)
			(stroke
				(width 0.1)
				(type default)
			)
			(layer "B.Fab")
		)
		(fp_line
			(start -1.1938 0.4064)
			(end -0.8636 0.4064)
			(stroke
				(width 0.1)
				(type default)
			)
			(layer "B.Fab")
		)
		(fp_line
			(start -0.8636 0.4064)
			(end -0.8636 0.4572)
			(stroke
				(width 0.1)
				(type default)
			)
			(layer "B.Fab")
		)
		(fp_line
			(start 0.8636 0.4064)
			(end 1.1938 0.4064)
			(stroke
				(width 0.1)
				(type default)
			)
			(layer "B.Fab")
		)
		(fp_line
			(start 1.1938 0.4064)
			(end 1.1938 -0.4064)
			(stroke
				(width 0.1)
				(type default)
			)
			(layer "B.Fab")
		)
		(fp_line
			(start -1.1938 -0.4064)
			(end -1.1938 0.4064)
			(stroke
				(width 0.1)
				(type default)
			)
			(layer "B.Fab")
		)
		(fp_line
			(start -0.8636 -0.4064)
			(end -1.1938 -0.4064)
			(stroke
				(width 0.1)
				(type default)
			)
			(layer "B.Fab")
		)
		(fp_line
			(start 0.8636 -0.4064)
			(end 0.8636 -0.4572)
			(stroke
				(width 0.1)
				(type default)
			)
			(layer "B.Fab")
		)
		(fp_line
			(start 1.1938 -0.4064)
			(end 0.8636 -0.4064)
			(stroke
				(width 0.1)
				(type default)
			)
			(layer "B.Fab")
		)
		(fp_line
			(start -0.8636 -0.4572)
			(end -0.8636 -0.4064)
			(stroke
				(width 0.1)
				(type default)
			)
			(layer "B.Fab")
		)
		(fp_line
			(start 0.8636 -0.4572)
			(end -0.8636 -0.4572)
			(stroke
				(width 0.1)
				(type default)
			)
			(layer "B.Fab")
		)
		(pad "1" smd rect
			(at 0.7366 0 180)
			(size 0.7112 0.8128)
			(layers "B.Cu" "B.Mask" "B.Paste")
			(net "P0V8_SERDES_VDDA_PEX2_C1")
		)
		(pad "2" smd rect
			(at -0.7366 0 180)
			(size 0.7112 0.8128)
			(layers "B.Cu" "B.Mask" "B.Paste")
			(net "GND")
		)
	)
	(footprint ""
		(layer "B.Cu")
		(at 193.641726 -99.037648 180)
		(property "Reference" "R167"
			(at 0 0 0)
			(layer "B.SilkS")
			(hide yes)
			(effects
				(font
					(size 1.27 1.27)
				)
				(justify mirror)
			)
		)
		(property "Value" ""
			(at 0 0 0)
			(layer "B.Fab")
			(effects
				(font
					(size 1.27 1.27)
				)
				(justify mirror)
			)
		)
		(duplicate_pad_numbers_are_jumpers no)
		(fp_line
			(start 0.7874 0.4064)
			(end 0.7874 -0.4064)
			(stroke
				(width 0.1524)
				(type default)
			)
			(layer "B.SilkS")
		)
		(fp_line
			(start 0.7874 -0.4064)
			(end -0.7874 -0.4064)
			(stroke
				(width 0.1524)
				(type default)
			)
			(layer "B.SilkS")
		)
		(fp_line
			(start -0.7874 0.4064)
			(end 0.7874 0.4064)
			(stroke
				(width 0.1524)
				(type default)
			)
			(layer "B.SilkS")
		)
		(fp_line
			(start -0.7874 -0.4064)
			(end -0.7874 0.4064)
			(stroke
				(width 0.1524)
				(type default)
			)
			(layer "B.SilkS")
		)
		(fp_line
			(start 0.67945 0.3048)
			(end 0.67945 -0.305054)
			(stroke
				(width 0.1)
				(type default)
			)
			(layer "B.Fab")
		)
		(fp_line
			(start 0.67945 -0.305054)
			(end 0.12065 -0.305054)
			(stroke
				(width 0.1)
				(type default)
			)
			(layer "B.Fab")
		)
		(fp_line
			(start 0.12065 0.3048)
			(end 0.67945 0.3048)
			(stroke
				(width 0.1)
				(type default)
			)
			(layer "B.Fab")
		)
		(fp_line
			(start 0.12065 0.2794)
			(end 0.12065 0.3048)
			(stroke
				(width 0.1)
				(type default)
			)
			(layer "B.Fab")
		)
		(fp_line
			(start 0.12065 -0.2794)
			(end -0.12065 -0.2794)
			(stroke
				(width 0.1)
				(type default)
			)
			(layer "B.Fab")
		)
		(fp_line
			(start 0.12065 -0.305054)
			(end 0.12065 -0.2794)
			(stroke
				(width 0.1)
				(type default)
			)
			(layer "B.Fab")
		)
		(fp_line
			(start -0.120396 0.3048)
			(end -0.120396 0.2794)
			(stroke
				(width 0.1)
				(type default)
			)
			(layer "B.Fab")
		)
		(fp_line
			(start -0.120396 0.2794)
			(end 0.12065 0.2794)
			(stroke
				(width 0.1)
				(type default)
			)
			(layer "B.Fab")
		)
		(fp_line
			(start -0.12065 -0.2794)
			(end -0.12065 -0.3048)
			(stroke
				(width 0.1)
				(type default)
			)
			(layer "B.Fab")
		)
		(fp_line
			(start -0.12065 -0.3048)
			(end -0.67945 -0.3048)
			(stroke
				(width 0.1)
				(type default)
			)
			(layer "B.Fab")
		)
		(fp_line
			(start -0.67945 0.3048)
			(end -0.120396 0.3048)
			(stroke
				(width 0.1)
				(type default)
			)
			(layer "B.Fab")
		)
		(fp_line
			(start -0.67945 -0.3048)
			(end -0.67945 0.3048)
			(stroke
				(width 0.1)
				(type default)
			)
			(layer "B.Fab")
		)
		(pad "1" smd circle
			(at 0.40005 0)
			(size 0 0)
			(layers "B.Cu" "B.Mask" "B.Paste")
			(net "NIC3_CLK")
		)
		(pad "2" smd circle
			(at -0.40005 0)
			(size 0 0)
			(layers "B.Cu" "B.Mask" "B.Paste")
			(net "GND")
		)
	)
	(footprint ""
		(layer "B.Cu")
		(at 60.599828 -303.499774 -90)
		(property "Reference" "C2901"
			(at 0 0 90)
			(layer "B.SilkS")
			(hide yes)
			(effects
				(font
					(size 1.27 1.27)
				)
				(justify mirror)
			)
		)
		(property "Value" ""
			(at 0 0 90)
			(layer "B.Fab")
			(effects
				(font
					(size 1.27 1.27)
				)
				(justify mirror)
			)
		)
		(duplicate_pad_numbers_are_jumpers no)
		(fp_line
			(start -0.299974 0.150114)
			(end 0.299974 0.150114)
			(stroke
				(width 0.1)
				(type default)
			)
			(layer "B.Fab")
		)
		(fp_line
			(start 0.299974 0.150114)
			(end 0.299974 -0.150114)
			(stroke
				(width 0.1)
				(type default)
			)
			(layer "B.Fab")
		)
		(fp_line
			(start -0.299974 -0.150114)
			(end -0.299974 0.150114)
			(stroke
				(width 0.1)
				(type default)
			)
			(layer "B.Fab")
		)
		(fp_line
			(start 0.299974 -0.150114)
			(end -0.299974 -0.150114)
			(stroke
				(width 0.1)
				(type default)
			)
			(layer "B.Fab")
		)
		(pad "1" smd rect
			(at 0.2667 0 90)
			(size 0.3048 0.381)
			(layers "B.Cu" "B.Mask" "B.Paste")
			(net "P1V25_PEX0")
		)
		(pad "2" smd rect
			(at -0.2667 0 90)
			(size 0.3048 0.381)
			(layers "B.Cu" "B.Mask" "B.Paste")
			(net "GND")
		)
	)
	(footprint ""
		(layer "B.Cu")
		(at 207.180942 -259.311648 90)
		(property "Reference" "R6345"
			(at 0 0 90)
			(layer "B.SilkS")
			(hide yes)
			(effects
				(font
					(size 1.27 1.27)
				)
				(justify mirror)
			)
		)
		(property "Value" ""
			(at 0 0 90)
			(layer "B.Fab")
			(effects
				(font
					(size 1.27 1.27)
				)
				(justify mirror)
			)
		)
		(duplicate_pad_numbers_are_jumpers no)
		(fp_line
			(start 0.7874 -0.4064)
			(end -0.7874 -0.4064)
			(stroke
				(width 0.1524)
				(type default)
			)
			(layer "B.SilkS")
		)
		(fp_line
			(start -0.7874 -0.4064)
			(end -0.7874 0.4064)
			(stroke
				(width 0.1524)
				(type default)
			)
			(layer "B.SilkS")
		)
		(fp_line
			(start 0.7874 0.4064)
			(end 0.7874 -0.4064)
			(stroke
				(width 0.1524)
				(type default)
			)
			(layer "B.SilkS")
		)
		(fp_line
			(start -0.7874 0.4064)
			(end 0.7874 0.4064)
			(stroke
				(width 0.1524)
				(type default)
			)
			(layer "B.SilkS")
		)
		(fp_line
			(start 0.67945 -0.305054)
			(end 0.12065 -0.305054)
			(stroke
				(width 0.1)
				(type default)
			)
			(layer "B.Fab")
		)
		(fp_line
			(start 0.12065 -0.305054)
			(end 0.12065 -0.2794)
			(stroke
				(width 0.1)
				(type default)
			)
			(layer "B.Fab")
		)
		(fp_line
			(start -0.12065 -0.3048)
			(end -0.67945 -0.3048)
			(stroke
				(width 0.1)
				(type default)
			)
			(layer "B.Fab")
		)
		(fp_line
			(start -0.67945 -0.3048)
			(end -0.67945 0.3048)
			(stroke
				(width 0.1)
				(type default)
			)
			(layer "B.Fab")
		)
		(fp_line
			(start 0.12065 -0.2794)
			(end -0.12065 -0.2794)
			(stroke
				(width 0.1)
				(type default)
			)
			(layer "B.Fab")
		)
		(fp_line
			(start -0.12065 -0.2794)
			(end -0.12065 -0.3048)
			(stroke
				(width 0.1)
				(type default)
			)
			(layer "B.Fab")
		)
		(fp_line
			(start 0.12065 0.2794)
			(end 0.12065 0.3048)
			(stroke
				(width 0.1)
				(type default)
			)
			(layer "B.Fab")
		)
		(fp_line
			(start -0.120396 0.2794)
			(end 0.12065 0.2794)
			(stroke
				(width 0.1)
				(type default)
			)
			(layer "B.Fab")
		)
		(fp_line
			(start 0.67945 0.3048)
			(end 0.67945 -0.305054)
			(stroke
				(width 0.1)
				(type default)
			)
			(layer "B.Fab")
		)
		(fp_line
			(start 0.12065 0.3048)
			(end 0.67945 0.3048)
			(stroke
				(width 0.1)
				(type default)
			)
			(layer "B.Fab")
		)
		(fp_line
			(start -0.120396 0.3048)
			(end -0.120396 0.2794)
			(stroke
				(width 0.1)
				(type default)
			)
			(layer "B.Fab")
		)
		(fp_line
			(start -0.67945 0.3048)
			(end -0.120396 0.3048)
			(stroke
				(width 0.1)
				(type default)
			)
			(layer "B.Fab")
		)
		(pad "1" smd circle
			(at 0.40005 0 270)
			(size 0 0)
			(layers "B.Cu" "B.Mask" "B.Paste")
			(net "P1V8_PEX")
		)
		(pad "2" smd circle
			(at -0.40005 0 270)
			(size 0 0)
			(layers "B.Cu" "B.Mask" "B.Paste")
			(net "SMB_PEX1_MUX_SCL")
		)
	)
	(footprint ""
		(layer "B.Cu")
		(at 59.649868 -301.599854 -90)
		(property "Reference" "C1228"
			(at 0 0 90)
			(layer "B.SilkS")
			(hide yes)
			(effects
				(font
					(size 1.27 1.27)
				)
				(justify mirror)
			)
		)
		(property "Value" ""
			(at 0 0 90)
			(layer "B.Fab")
			(effects
				(font
					(size 1.27 1.27)
				)
				(justify mirror)
			)
		)
		(duplicate_pad_numbers_are_jumpers no)
		(fp_line
			(start -0.299974 0.150114)
			(end 0.299974 0.150114)
			(stroke
				(width 0.1)
				(type default)
			)
			(layer "B.Fab")
		)
		(fp_line
			(start 0.299974 0.150114)
			(end 0.299974 -0.150114)
			(stroke
				(width 0.1)
				(type default)
			)
			(layer "B.Fab")
		)
		(fp_line
			(start -0.299974 -0.150114)
			(end -0.299974 0.150114)
			(stroke
				(width 0.1)
				(type default)
			)
			(layer "B.Fab")
		)
		(fp_line
			(start 0.299974 -0.150114)
			(end -0.299974 -0.150114)
			(stroke
				(width 0.1)
				(type default)
			)
			(layer "B.Fab")
		)
		(pad "1" smd rect
			(at 0.2667 0 90)
			(size 0.3048 0.381)
			(layers "B.Cu" "B.Mask" "B.Paste")
			(net "P0V8_SERDES_VDDA_PEX0")
		)
		(pad "2" smd rect
			(at -0.2667 0 90)
			(size 0.3048 0.381)
			(layers "B.Cu" "B.Mask" "B.Paste")
			(net "GND")
		)
	)
	(footprint ""
		(layer "B.Cu")
		(at 52.524914 -286.399732 90)
		(property "Reference" "C2981"
			(at 0 0 90)
			(layer "B.SilkS")
			(hide yes)
			(effects
				(font
					(size 1.27 1.27)
				)
				(justify mirror)
			)
		)
		(property "Value" ""
			(at 0 0 90)
			(layer "B.Fab")
			(effects
				(font
					(size 1.27 1.27)
				)
				(justify mirror)
			)
		)
		(duplicate_pad_numbers_are_jumpers no)
		(fp_line
			(start 0.299974 -0.150114)
			(end -0.299974 -0.150114)
			(stroke
				(width 0.1)
				(type default)
			)
			(layer "B.Fab")
		)
		(fp_line
			(start -0.299974 -0.150114)
			(end -0.299974 0.150114)
			(stroke
				(width 0.1)
				(type default)
			)
			(layer "B.Fab")
		)
		(fp_line
			(start 0.299974 0.150114)
			(end 0.299974 -0.150114)
			(stroke
				(width 0.1)
				(type default)
			)
			(layer "B.Fab")
		)
		(fp_line
			(start -0.299974 0.150114)
			(end 0.299974 0.150114)
			(stroke
				(width 0.1)
				(type default)
			)
			(layer "B.Fab")
		)
		(pad "1" smd rect
			(at 0.2667 0 270)
			(size 0.3048 0.381)
			(layers "B.Cu" "B.Mask" "B.Paste")
			(net "P1V25_SERDES_VDDPLL_PEX0")
		)
		(pad "2" smd rect
			(at -0.2667 0 270)
			(size 0.3048 0.381)
			(layers "B.Cu" "B.Mask" "B.Paste")
			(net "GND")
		)
	)
	(footprint ""
		(layer "B.Cu")
		(at 343.027 -233.553 90)
		(property "Reference" "R3556"
			(at 0 0 90)
			(layer "B.SilkS")
			(hide yes)
			(effects
				(font
					(size 1.27 1.27)
				)
				(justify mirror)
			)
		)
		(property "Value" ""
			(at 0 0 90)
			(layer "B.Fab")
			(effects
				(font
					(size 1.27 1.27)
				)
				(justify mirror)
			)
		)
		(duplicate_pad_numbers_are_jumpers no)
		(fp_line
			(start 0.7874 -0.4064)
			(end -0.7874 -0.4064)
			(stroke
				(width 0.1524)
				(type default)
			)
			(layer "B.SilkS")
		)
		(fp_line
			(start -0.7874 -0.4064)
			(end -0.7874 0.4064)
			(stroke
				(width 0.1524)
				(type default)
			)
			(layer "B.SilkS")
		)
		(fp_line
			(start 0.7874 0.4064)
			(end 0.7874 -0.4064)
			(stroke
				(width 0.1524)
				(type default)
			)
			(layer "B.SilkS")
		)
		(fp_line
			(start -0.7874 0.4064)
			(end 0.7874 0.4064)
			(stroke
				(width 0.1524)
				(type default)
			)
			(layer "B.SilkS")
		)
		(fp_line
			(start 0.67945 -0.305054)
			(end 0.12065 -0.305054)
			(stroke
				(width 0.1)
				(type default)
			)
			(layer "B.Fab")
		)
		(fp_line
			(start 0.12065 -0.305054)
			(end 0.12065 -0.2794)
			(stroke
				(width 0.1)
				(type default)
			)
			(layer "B.Fab")
		)
		(fp_line
			(start -0.12065 -0.3048)
			(end -0.67945 -0.3048)
			(stroke
				(width 0.1)
				(type default)
			)
			(layer "B.Fab")
		)
		(fp_line
			(start -0.67945 -0.3048)
			(end -0.67945 0.3048)
			(stroke
				(width 0.1)
				(type default)
			)
			(layer "B.Fab")
		)
		(fp_line
			(start 0.12065 -0.2794)
			(end -0.12065 -0.2794)
			(stroke
				(width 0.1)
				(type default)
			)
			(layer "B.Fab")
		)
		(fp_line
			(start -0.12065 -0.2794)
			(end -0.12065 -0.3048)
			(stroke
				(width 0.1)
				(type default)
			)
			(layer "B.Fab")
		)
		(fp_line
			(start 0.12065 0.2794)
			(end 0.12065 0.3048)
			(stroke
				(width 0.1)
				(type default)
			)
			(layer "B.Fab")
		)
		(fp_line
			(start -0.120396 0.2794)
			(end 0.12065 0.2794)
			(stroke
				(width 0.1)
				(type default)
			)
			(layer "B.Fab")
		)
		(fp_line
			(start 0.67945 0.3048)
			(end 0.67945 -0.305054)
			(stroke
				(width 0.1)
				(type default)
			)
			(layer "B.Fab")
		)
		(fp_line
			(start 0.12065 0.3048)
			(end 0.67945 0.3048)
			(stroke
				(width 0.1)
				(type default)
			)
			(layer "B.Fab")
		)
		(fp_line
			(start -0.120396 0.3048)
			(end -0.120396 0.2794)
			(stroke
				(width 0.1)
				(type default)
			)
			(layer "B.Fab")
		)
		(fp_line
			(start -0.67945 0.3048)
			(end -0.120396 0.3048)
			(stroke
				(width 0.1)
				(type default)
			)
			(layer "B.Fab")
		)
		(pad "1" smd circle
			(at 0.40005 0 270)
			(size 0 0)
			(layers "B.Cu" "B.Mask" "B.Paste")
			(net "SSD4_CLK_EN_R_N")
		)
		(pad "2" smd circle
			(at -0.40005 0 270)
			(size 0 0)
			(layers "B.Cu" "B.Mask" "B.Paste")
			(net "SSD4_CLK_EN_N")
		)
	)
	(footprint ""
		(layer "B.Cu")
		(at 379.857 -245.872 180)
		(property "Reference" "R943"
			(at 0 0 0)
			(layer "B.SilkS")
			(hide yes)
			(effects
				(font
					(size 1.27 1.27)
				)
				(justify mirror)
			)
		)
		(property "Value" ""
			(at 0 0 0)
			(layer "B.Fab")
			(effects
				(font
					(size 1.27 1.27)
				)
				(justify mirror)
			)
		)
		(duplicate_pad_numbers_are_jumpers no)
		(fp_line
			(start 0.7874 0.4064)
			(end 0.7874 -0.4064)
			(stroke
				(width 0.1524)
				(type default)
			)
			(layer "B.SilkS")
		)
		(fp_line
			(start 0.7874 -0.4064)
			(end -0.7874 -0.4064)
			(stroke
				(width 0.1524)
				(type default)
			)
			(layer "B.SilkS")
		)
		(fp_line
			(start -0.7874 0.4064)
			(end 0.7874 0.4064)
			(stroke
				(width 0.1524)
				(type default)
			)
			(layer "B.SilkS")
		)
		(fp_line
			(start -0.7874 -0.4064)
			(end -0.7874 0.4064)
			(stroke
				(width 0.1524)
				(type default)
			)
			(layer "B.SilkS")
		)
		(fp_line
			(start 0.67945 0.3048)
			(end 0.67945 -0.305054)
			(stroke
				(width 0.1)
				(type default)
			)
			(layer "B.Fab")
		)
		(fp_line
			(start 0.67945 -0.305054)
			(end 0.12065 -0.305054)
			(stroke
				(width 0.1)
				(type default)
			)
			(layer "B.Fab")
		)
		(fp_line
			(start 0.12065 0.3048)
			(end 0.67945 0.3048)
			(stroke
				(width 0.1)
				(type default)
			)
			(layer "B.Fab")
		)
		(fp_line
			(start 0.12065 0.2794)
			(end 0.12065 0.3048)
			(stroke
				(width 0.1)
				(type default)
			)
			(layer "B.Fab")
		)
		(fp_line
			(start 0.12065 -0.2794)
			(end -0.12065 -0.2794)
			(stroke
				(width 0.1)
				(type default)
			)
			(layer "B.Fab")
		)
		(fp_line
			(start 0.12065 -0.305054)
			(end 0.12065 -0.2794)
			(stroke
				(width 0.1)
				(type default)
			)
			(layer "B.Fab")
		)
		(fp_line
			(start -0.120396 0.3048)
			(end -0.120396 0.2794)
			(stroke
				(width 0.1)
				(type default)
			)
			(layer "B.Fab")
		)
		(fp_line
			(start -0.120396 0.2794)
			(end 0.12065 0.2794)
			(stroke
				(width 0.1)
				(type default)
			)
			(layer "B.Fab")
		)
		(fp_line
			(start -0.12065 -0.2794)
			(end -0.12065 -0.3048)
			(stroke
				(width 0.1)
				(type default)
			)
			(layer "B.Fab")
		)
		(fp_line
			(start -0.12065 -0.3048)
			(end -0.67945 -0.3048)
			(stroke
				(width 0.1)
				(type default)
			)
			(layer "B.Fab")
		)
		(fp_line
			(start -0.67945 0.3048)
			(end -0.120396 0.3048)
			(stroke
				(width 0.1)
				(type default)
			)
			(layer "B.Fab")
		)
		(fp_line
			(start -0.67945 -0.3048)
			(end -0.67945 0.3048)
			(stroke
				(width 0.1)
				(type default)
			)
			(layer "B.Fab")
		)
		(pad "1" smd circle
			(at 0.40005 0)
			(size 0 0)
			(layers "B.Cu" "B.Mask" "B.Paste")
			(net "UART_PEX2_SDB_BUF_TX")
		)
		(pad "2" smd circle
			(at -0.40005 0)
			(size 0 0)
			(layers "B.Cu" "B.Mask" "B.Paste")
			(net "P3V3_AUX")
		)
	)
	(footprint ""
		(layer "B.Cu")
		(at 394.65504 -300.1772)
		(property "Reference" "C3547"
			(at 0 0 0)
			(layer "B.SilkS")
			(hide yes)
			(effects
				(font
					(size 1.27 1.27)
				)
				(justify mirror)
			)
		)
		(property "Value" ""
			(at 0 0 0)
			(layer "B.Fab")
			(effects
				(font
					(size 1.27 1.27)
				)
				(justify mirror)
			)
		)
		(duplicate_pad_numbers_are_jumpers no)
		(fp_line
			(start -0.299974 -0.150114)
			(end -0.299974 0.150114)
			(stroke
				(width 0.1)
				(type default)
			)
			(layer "B.Fab")
		)
		(fp_line
			(start -0.299974 0.150114)
			(end 0.299974 0.150114)
			(stroke
				(width 0.1)
				(type default)
			)
			(layer "B.Fab")
		)
		(fp_line
			(start 0.299974 -0.150114)
			(end -0.299974 -0.150114)
			(stroke
				(width 0.1)
				(type default)
			)
			(layer "B.Fab")
		)
		(fp_line
			(start 0.299974 0.150114)
			(end 0.299974 -0.150114)
			(stroke
				(width 0.1)
				(type default)
			)
			(layer "B.Fab")
		)
		(pad "1" smd rect
			(at 0.2667 0 180)
			(size 0.3048 0.381)
			(layers "B.Cu" "B.Mask" "B.Paste")
			(net "PCEPLL1_VDDA18_PEX3")
		)
		(pad "2" smd rect
			(at -0.2667 0 180)
			(size 0.3048 0.381)
			(layers "B.Cu" "B.Mask" "B.Paste")
			(net "GND")
		)
	)
	(footprint ""
		(layer "B.Cu")
		(at 288.99993 -288.299906 90)
		(property "Reference" "C3291"
			(at 0 0 90)
			(layer "B.SilkS")
			(hide yes)
			(effects
				(font
					(size 1.27 1.27)
				)
				(justify mirror)
			)
		)
		(property "Value" ""
			(at 0 0 90)
			(layer "B.Fab")
			(effects
				(font
					(size 1.27 1.27)
				)
				(justify mirror)
			)
		)
		(duplicate_pad_numbers_are_jumpers no)
		(fp_line
			(start 0.299974 -0.150114)
			(end -0.299974 -0.150114)
			(stroke
				(width 0.1)
				(type default)
			)
			(layer "B.Fab")
		)
		(fp_line
			(start -0.299974 -0.150114)
			(end -0.299974 0.150114)
			(stroke
				(width 0.1)
				(type default)
			)
			(layer "B.Fab")
		)
		(fp_line
			(start 0.299974 0.150114)
			(end 0.299974 -0.150114)
			(stroke
				(width 0.1)
				(type default)
			)
			(layer "B.Fab")
		)
		(fp_line
			(start -0.299974 0.150114)
			(end 0.299974 0.150114)
			(stroke
				(width 0.1)
				(type default)
			)
			(layer "B.Fab")
		)
		(pad "1" smd rect
			(at 0.2667 0 270)
			(size 0.3048 0.381)
			(layers "B.Cu" "B.Mask" "B.Paste")
			(net "P1V25_PEX2")
		)
		(pad "2" smd rect
			(at -0.2667 0 270)
			(size 0.3048 0.381)
			(layers "B.Cu" "B.Mask" "B.Paste")
			(net "GND")
		)
	)
	(footprint ""
		(layer "B.Cu")
		(at 209.587084 -246.671592 90)
		(property "Reference" "R6341"
			(at 0 0 90)
			(layer "B.SilkS")
			(hide yes)
			(effects
				(font
					(size 1.27 1.27)
				)
				(justify mirror)
			)
		)
		(property "Value" ""
			(at 0 0 90)
			(layer "B.Fab")
			(effects
				(font
					(size 1.27 1.27)
				)
				(justify mirror)
			)
		)
		(duplicate_pad_numbers_are_jumpers no)
		(fp_line
			(start 0.7874 -0.4064)
			(end -0.7874 -0.4064)
			(stroke
				(width 0.1524)
				(type default)
			)
			(layer "B.SilkS")
		)
		(fp_line
			(start -0.7874 -0.4064)
			(end -0.7874 0.4064)
			(stroke
				(width 0.1524)
				(type default)
			)
			(layer "B.SilkS")
		)
		(fp_line
			(start 0.7874 0.4064)
			(end 0.7874 -0.4064)
			(stroke
				(width 0.1524)
				(type default)
			)
			(layer "B.SilkS")
		)
		(fp_line
			(start -0.7874 0.4064)
			(end 0.7874 0.4064)
			(stroke
				(width 0.1524)
				(type default)
			)
			(layer "B.SilkS")
		)
		(fp_line
			(start 0.67945 -0.305054)
			(end 0.12065 -0.305054)
			(stroke
				(width 0.1)
				(type default)
			)
			(layer "B.Fab")
		)
		(fp_line
			(start 0.12065 -0.305054)
			(end 0.12065 -0.2794)
			(stroke
				(width 0.1)
				(type default)
			)
			(layer "B.Fab")
		)
		(fp_line
			(start -0.12065 -0.3048)
			(end -0.67945 -0.3048)
			(stroke
				(width 0.1)
				(type default)
			)
			(layer "B.Fab")
		)
		(fp_line
			(start -0.67945 -0.3048)
			(end -0.67945 0.3048)
			(stroke
				(width 0.1)
				(type default)
			)
			(layer "B.Fab")
		)
		(fp_line
			(start 0.12065 -0.2794)
			(end -0.12065 -0.2794)
			(stroke
				(width 0.1)
				(type default)
			)
			(layer "B.Fab")
		)
		(fp_line
			(start -0.12065 -0.2794)
			(end -0.12065 -0.3048)
			(stroke
				(width 0.1)
				(type default)
			)
			(layer "B.Fab")
		)
		(fp_line
			(start 0.12065 0.2794)
			(end 0.12065 0.3048)
			(stroke
				(width 0.1)
				(type default)
			)
			(layer "B.Fab")
		)
		(fp_line
			(start -0.120396 0.2794)
			(end 0.12065 0.2794)
			(stroke
				(width 0.1)
				(type default)
			)
			(layer "B.Fab")
		)
		(fp_line
			(start 0.67945 0.3048)
			(end 0.67945 -0.305054)
			(stroke
				(width 0.1)
				(type default)
			)
			(layer "B.Fab")
		)
		(fp_line
			(start 0.12065 0.3048)
			(end 0.67945 0.3048)
			(stroke
				(width 0.1)
				(type default)
			)
			(layer "B.Fab")
		)
		(fp_line
			(start -0.120396 0.3048)
			(end -0.120396 0.2794)
			(stroke
				(width 0.1)
				(type default)
			)
			(layer "B.Fab")
		)
		(fp_line
			(start -0.67945 0.3048)
			(end -0.120396 0.3048)
			(stroke
				(width 0.1)
				(type default)
			)
			(layer "B.Fab")
		)
		(pad "1" smd circle
			(at 0.40005 0 270)
			(size 0 0)
			(layers "B.Cu" "B.Mask" "B.Paste")
			(net "PEX_MUX_A2")
		)
		(pad "2" smd circle
			(at -0.40005 0 270)
			(size 0 0)
			(layers "B.Cu" "B.Mask" "B.Paste")
			(net "GND")
		)
	)
	(footprint ""
		(layer "B.Cu")
		(at 66.774822 -297.79976 -90)
		(property "Reference" "C1174"
			(at 0 0 90)
			(layer "B.SilkS")
			(hide yes)
			(effects
				(font
					(size 1.27 1.27)
				)
				(justify mirror)
			)
		)
		(property "Value" ""
			(at 0 0 90)
			(layer "B.Fab")
			(effects
				(font
					(size 1.27 1.27)
				)
				(justify mirror)
			)
		)
		(duplicate_pad_numbers_are_jumpers no)
		(fp_line
			(start -0.299974 0.150114)
			(end 0.299974 0.150114)
			(stroke
				(width 0.1)
				(type default)
			)
			(layer "B.Fab")
		)
		(fp_line
			(start 0.299974 0.150114)
			(end 0.299974 -0.150114)
			(stroke
				(width 0.1)
				(type default)
			)
			(layer "B.Fab")
		)
		(fp_line
			(start -0.299974 -0.150114)
			(end -0.299974 0.150114)
			(stroke
				(width 0.1)
				(type default)
			)
			(layer "B.Fab")
		)
		(fp_line
			(start 0.299974 -0.150114)
			(end -0.299974 -0.150114)
			(stroke
				(width 0.1)
				(type default)
			)
			(layer "B.Fab")
		)
		(pad "1" smd rect
			(at 0.2667 0 90)
			(size 0.3048 0.381)
			(layers "B.Cu" "B.Mask" "B.Paste")
			(net "P0V8_SERDES_VDDA_PEX0")
		)
		(pad "2" smd rect
			(at -0.2667 0 90)
			(size 0.3048 0.381)
			(layers "B.Cu" "B.Mask" "B.Paste")
			(net "GND")
		)
	)
	(footprint ""
		(layer "B.Cu")
		(at 329.807316 -231.515412)
		(property "Reference" "R2621"
			(at 0 0 0)
			(layer "B.SilkS")
			(hide yes)
			(effects
				(font
					(size 1.27 1.27)
				)
				(justify mirror)
			)
		)
		(property "Value" ""
			(at 0 0 0)
			(layer "B.Fab")
			(effects
				(font
					(size 1.27 1.27)
				)
				(justify mirror)
			)
		)
		(duplicate_pad_numbers_are_jumpers no)
		(fp_line
			(start -0.7874 -0.4064)
			(end -0.7874 0.4064)
			(stroke
				(width 0.1524)
				(type default)
			)
			(layer "B.SilkS")
		)
		(fp_line
			(start -0.7874 0.4064)
			(end 0.7874 0.4064)
			(stroke
				(width 0.1524)
				(type default)
			)
			(layer "B.SilkS")
		)
		(fp_line
			(start 0.7874 -0.4064)
			(end -0.7874 -0.4064)
			(stroke
				(width 0.1524)
				(type default)
			)
			(layer "B.SilkS")
		)
		(fp_line
			(start 0.7874 0.4064)
			(end 0.7874 -0.4064)
			(stroke
				(width 0.1524)
				(type default)
			)
			(layer "B.SilkS")
		)
		(fp_line
			(start -0.67945 -0.3048)
			(end -0.67945 0.3048)
			(stroke
				(width 0.1)
				(type default)
			)
			(layer "B.Fab")
		)
		(fp_line
			(start -0.67945 0.3048)
			(end -0.120396 0.3048)
			(stroke
				(width 0.1)
				(type default)
			)
			(layer "B.Fab")
		)
		(fp_line
			(start -0.12065 -0.3048)
			(end -0.67945 -0.3048)
			(stroke
				(width 0.1)
				(type default)
			)
			(layer "B.Fab")
		)
		(fp_line
			(start -0.12065 -0.2794)
			(end -0.12065 -0.3048)
			(stroke
				(width 0.1)
				(type default)
			)
			(layer "B.Fab")
		)
		(fp_line
			(start -0.120396 0.2794)
			(end 0.12065 0.2794)
			(stroke
				(width 0.1)
				(type default)
			)
			(layer "B.Fab")
		)
		(fp_line
			(start -0.120396 0.3048)
			(end -0.120396 0.2794)
			(stroke
				(width 0.1)
				(type default)
			)
			(layer "B.Fab")
		)
		(fp_line
			(start 0.12065 -0.305054)
			(end 0.12065 -0.2794)
			(stroke
				(width 0.1)
				(type default)
			)
			(layer "B.Fab")
		)
		(fp_line
			(start 0.12065 -0.2794)
			(end -0.12065 -0.2794)
			(stroke
				(width 0.1)
				(type default)
			)
			(layer "B.Fab")
		)
		(fp_line
			(start 0.12065 0.2794)
			(end 0.12065 0.3048)
			(stroke
				(width 0.1)
				(type default)
			)
			(layer "B.Fab")
		)
		(fp_line
			(start 0.12065 0.3048)
			(end 0.67945 0.3048)
			(stroke
				(width 0.1)
				(type default)
			)
			(layer "B.Fab")
		)
		(fp_line
			(start 0.67945 -0.305054)
			(end 0.12065 -0.305054)
			(stroke
				(width 0.1)
				(type default)
			)
			(layer "B.Fab")
		)
		(fp_line
			(start 0.67945 0.3048)
			(end 0.67945 -0.305054)
			(stroke
				(width 0.1)
				(type default)
			)
			(layer "B.Fab")
		)
		(pad "1" smd circle
			(at 0.40005 0 180)
			(size 0 0)
			(layers "B.Cu" "B.Mask" "B.Paste")
			(net "JTAG_FPGA_TDI")
		)
		(pad "2" smd circle
			(at -0.40005 0 180)
			(size 0 0)
			(layers "B.Cu" "B.Mask" "B.Paste")
			(net "P3V3_AUX")
		)
	)
	(footprint ""
		(layer "B.Cu")
		(at 106.00055 -308.580028 90)
		(property "Reference" "C4191"
			(at 0 0 90)
			(layer "B.SilkS")
			(hide yes)
			(effects
				(font
					(size 1.27 1.27)
				)
				(justify mirror)
			)
		)
		(property "Value" ""
			(at 0 0 90)
			(layer "B.Fab")
			(effects
				(font
					(size 1.27 1.27)
				)
				(justify mirror)
			)
		)
		(duplicate_pad_numbers_are_jumpers no)
		(fp_line
			(start 1.2954 -0.5842)
			(end -1.2954 -0.5842)
			(stroke
				(width 0.1524)
				(type default)
			)
			(layer "B.SilkS")
		)
		(fp_line
			(start -1.2954 -0.5842)
			(end -1.2954 0.5842)
			(stroke
				(width 0.1524)
				(type default)
			)
			(layer "B.SilkS")
		)
		(fp_line
			(start 1.2954 0.5842)
			(end 1.2954 -0.5842)
			(stroke
				(width 0.1524)
				(type default)
			)
			(layer "B.SilkS")
		)
		(fp_line
			(start -1.2954 0.5842)
			(end 1.2954 0.5842)
			(stroke
				(width 0.1524)
				(type default)
			)
			(layer "B.SilkS")
		)
		(fp_line
			(start 0.8636 -0.4572)
			(end -0.8636 -0.4572)
			(stroke
				(width 0.1)
				(type default)
			)
			(layer "B.Fab")
		)
		(fp_line
			(start -0.8636 -0.4572)
			(end -0.8636 -0.4064)
			(stroke
				(width 0.1)
				(type default)
			)
			(layer "B.Fab")
		)
		(fp_line
			(start 1.1938 -0.4064)
			(end 0.8636 -0.4064)
			(stroke
				(width 0.1)
				(type default)
			)
			(layer "B.Fab")
		)
		(fp_line
			(start 0.8636 -0.4064)
			(end 0.8636 -0.4572)
			(stroke
				(width 0.1)
				(type default)
			)
			(layer "B.Fab")
		)
		(fp_line
			(start -0.8636 -0.4064)
			(end -1.1938 -0.4064)
			(stroke
				(width 0.1)
				(type default)
			)
			(layer "B.Fab")
		)
		(fp_line
			(start -1.1938 -0.4064)
			(end -1.1938 0.4064)
			(stroke
				(width 0.1)
				(type default)
			)
			(layer "B.Fab")
		)
		(fp_line
			(start 1.1938 0.4064)
			(end 1.1938 -0.4064)
			(stroke
				(width 0.1)
				(type default)
			)
			(layer "B.Fab")
		)
		(fp_line
			(start 0.8636 0.4064)
			(end 1.1938 0.4064)
			(stroke
				(width 0.1)
				(type default)
			)
			(layer "B.Fab")
		)
		(fp_line
			(start -0.8636 0.4064)
			(end -0.8636 0.4572)
			(stroke
				(width 0.1)
				(type default)
			)
			(layer "B.Fab")
		)
		(fp_line
			(start -1.1938 0.4064)
			(end -0.8636 0.4064)
			(stroke
				(width 0.1)
				(type default)
			)
			(layer "B.Fab")
		)
		(fp_line
			(start 0.8636 0.4572)
			(end 0.8636 0.4064)
			(stroke
				(width 0.1)
				(type default)
			)
			(layer "B.Fab")
		)
		(fp_line
			(start -0.8636 0.4572)
			(end 0.8636 0.4572)
			(stroke
				(width 0.1)
				(type default)
			)
			(layer "B.Fab")
		)
		(pad "1" smd rect
			(at 0.7366 0)
			(size 0.7112 0.8128)
			(layers "B.Cu" "B.Mask" "B.Paste")
			(net "P0V8_PEX0")
		)
		(pad "2" smd rect
			(at -0.7366 0)
			(size 0.7112 0.8128)
			(layers "B.Cu" "B.Mask" "B.Paste")
			(net "GND")
		)
	)
	(footprint ""
		(layer "B.Cu")
		(at 72.949816 -296.8498 180)
		(property "Reference" "C2948"
			(at 0 0 0)
			(layer "B.SilkS")
			(hide yes)
			(effects
				(font
					(size 1.27 1.27)
				)
				(justify mirror)
			)
		)
		(property "Value" ""
			(at 0 0 0)
			(layer "B.Fab")
			(effects
				(font
					(size 1.27 1.27)
				)
				(justify mirror)
			)
		)
		(duplicate_pad_numbers_are_jumpers no)
		(fp_line
			(start 0.299974 0.150114)
			(end 0.299974 -0.150114)
			(stroke
				(width 0.1)
				(type default)
			)
			(layer "B.Fab")
		)
		(fp_line
			(start 0.299974 -0.150114)
			(end -0.299974 -0.150114)
			(stroke
				(width 0.1)
				(type default)
			)
			(layer "B.Fab")
		)
		(fp_line
			(start -0.299974 0.150114)
			(end 0.299974 0.150114)
			(stroke
				(width 0.1)
				(type default)
			)
			(layer "B.Fab")
		)
		(fp_line
			(start -0.299974 -0.150114)
			(end -0.299974 0.150114)
			(stroke
				(width 0.1)
				(type default)
			)
			(layer "B.Fab")
		)
		(pad "1" smd rect
			(at 0.2667 0)
			(size 0.3048 0.381)
			(layers "B.Cu" "B.Mask" "B.Paste")
			(net "P1V25_SERDES_VDDPLL_PEX0")
		)
		(pad "2" smd rect
			(at -0.2667 0)
			(size 0.3048 0.381)
			(layers "B.Cu" "B.Mask" "B.Paste")
			(net "GND")
		)
	)
	(footprint ""
		(layer "B.Cu")
		(at 294.22471 -286.399732 90)
		(property "Reference" "C3306"
			(at 0 0 90)
			(layer "B.SilkS")
			(hide yes)
			(effects
				(font
					(size 1.27 1.27)
				)
				(justify mirror)
			)
		)
		(property "Value" ""
			(at 0 0 90)
			(layer "B.Fab")
			(effects
				(font
					(size 1.27 1.27)
				)
				(justify mirror)
			)
		)
		(duplicate_pad_numbers_are_jumpers no)
		(fp_line
			(start 0.299974 -0.150114)
			(end -0.299974 -0.150114)
			(stroke
				(width 0.1)
				(type default)
			)
			(layer "B.Fab")
		)
		(fp_line
			(start -0.299974 -0.150114)
			(end -0.299974 0.150114)
			(stroke
				(width 0.1)
				(type default)
			)
			(layer "B.Fab")
		)
		(fp_line
			(start 0.299974 0.150114)
			(end 0.299974 -0.150114)
			(stroke
				(width 0.1)
				(type default)
			)
			(layer "B.Fab")
		)
		(fp_line
			(start -0.299974 0.150114)
			(end 0.299974 0.150114)
			(stroke
				(width 0.1)
				(type default)
			)
			(layer "B.Fab")
		)
		(pad "1" smd rect
			(at 0.2667 0 270)
			(size 0.3048 0.381)
			(layers "B.Cu" "B.Mask" "B.Paste")
			(net "P1V25_SERDES_VDDPLL_PEX2")
		)
		(pad "2" smd rect
			(at -0.2667 0 270)
			(size 0.3048 0.381)
			(layers "B.Cu" "B.Mask" "B.Paste")
			(net "GND")
		)
	)
	(footprint ""
		(layer "B.Cu")
		(at 236.927136 -266.873228)
		(property "Reference" "R6134"
			(at 0 0 0)
			(layer "B.SilkS")
			(hide yes)
			(effects
				(font
					(size 1.27 1.27)
				)
				(justify mirror)
			)
		)
		(property "Value" ""
			(at 0 0 0)
			(layer "B.Fab")
			(effects
				(font
					(size 1.27 1.27)
				)
				(justify mirror)
			)
		)
		(duplicate_pad_numbers_are_jumpers no)
		(fp_line
			(start -2.576322 -1.1303)
			(end -2.576322 1.1303)
			(stroke
				(width 0.1524)
				(type default)
			)
			(layer "B.SilkS")
		)
		(fp_line
			(start -2.576322 1.1303)
			(end 2.576322 1.1303)
			(stroke
				(width 0.1524)
				(type default)
			)
			(layer "B.SilkS")
		)
		(fp_line
			(start 2.576322 -1.1303)
			(end -2.576322 -1.1303)
			(stroke
				(width 0.1524)
				(type default)
			)
			(layer "B.SilkS")
		)
		(fp_line
			(start 2.576322 1.1303)
			(end 2.576322 -1.1303)
			(stroke
				(width 0.1524)
				(type default)
			)
			(layer "B.SilkS")
		)
		(fp_line
			(start -1.649984 -0.899922)
			(end 1.649984 -0.899922)
			(stroke
				(width 0.1)
				(type default)
			)
			(layer "B.Fab")
		)
		(fp_line
			(start -1.649984 0.899922)
			(end -1.649984 -0.899922)
			(stroke
				(width 0.1)
				(type default)
			)
			(layer "B.Fab")
		)
		(fp_line
			(start 1.649984 -0.899922)
			(end 1.649984 0.899922)
			(stroke
				(width 0.1)
				(type default)
			)
			(layer "B.Fab")
		)
		(fp_line
			(start 1.649984 0.899922)
			(end -1.649984 0.899922)
			(stroke
				(width 0.1)
				(type default)
			)
			(layer "B.Fab")
		)
		(pad "1A" smd rect
			(at 1.700022 0 180)
			(size 1.4986 2.0066)
			(layers "B.Cu" "B.Mask" "B.Paste")
			(net "P1V25_PEX2")
		)
		(pad "1B" smd rect
			(at 1.077722 0 180)
			(size 0.254 0.508)
			(layers "B.Cu" "B.Mask" "B.Paste")
			(net "P1V25_PEX2")
		)
		(pad "2A" smd rect
			(at -1.700022 0 180)
			(size 1.4986 2.0066)
			(layers "B.Cu" "B.Mask" "B.Paste")
			(net "P1V25_SERDES_VDDPLL_PEX2")
		)
		(pad "2B" smd rect
			(at -1.077722 0 180)
			(size 0.254 0.508)
			(layers "B.Cu" "B.Mask" "B.Paste")
			(net "P1V25_SERDES_VDDPLL_PEX2")
		)
	)
	(footprint ""
		(layer "B.Cu")
		(at 237.521496 -212.332824 -90)
		(property "Reference" "R475"
			(at 0 0 90)
			(layer "B.SilkS")
			(hide yes)
			(effects
				(font
					(size 1.27 1.27)
				)
				(justify mirror)
			)
		)
		(property "Value" ""
			(at 0 0 90)
			(layer "B.Fab")
			(effects
				(font
					(size 1.27 1.27)
				)
				(justify mirror)
			)
		)
		(duplicate_pad_numbers_are_jumpers no)
		(fp_line
			(start -0.7874 0.4064)
			(end 0.7874 0.4064)
			(stroke
				(width 0.1524)
				(type default)
			)
			(layer "B.SilkS")
		)
		(fp_line
			(start 0.7874 0.4064)
			(end 0.7874 -0.4064)
			(stroke
				(width 0.1524)
				(type default)
			)
			(layer "B.SilkS")
		)
		(fp_line
			(start -0.7874 -0.4064)
			(end -0.7874 0.4064)
			(stroke
				(width 0.1524)
				(type default)
			)
			(layer "B.SilkS")
		)
		(fp_line
			(start 0.7874 -0.4064)
			(end -0.7874 -0.4064)
			(stroke
				(width 0.1524)
				(type default)
			)
			(layer "B.SilkS")
		)
		(fp_line
			(start -0.67945 0.3048)
			(end -0.120396 0.3048)
			(stroke
				(width 0.1)
				(type default)
			)
			(layer "B.Fab")
		)
		(fp_line
			(start -0.120396 0.3048)
			(end -0.120396 0.2794)
			(stroke
				(width 0.1)
				(type default)
			)
			(layer "B.Fab")
		)
		(fp_line
			(start 0.12065 0.3048)
			(end 0.67945 0.3048)
			(stroke
				(width 0.1)
				(type default)
			)
			(layer "B.Fab")
		)
		(fp_line
			(start 0.67945 0.3048)
			(end 0.67945 -0.305054)
			(stroke
				(width 0.1)
				(type default)
			)
			(layer "B.Fab")
		)
		(fp_line
			(start -0.120396 0.2794)
			(end 0.12065 0.2794)
			(stroke
				(width 0.1)
				(type default)
			)
			(layer "B.Fab")
		)
		(fp_line
			(start 0.12065 0.2794)
			(end 0.12065 0.3048)
			(stroke
				(width 0.1)
				(type default)
			)
			(layer "B.Fab")
		)
		(fp_line
			(start -0.12065 -0.2794)
			(end -0.12065 -0.3048)
			(stroke
				(width 0.1)
				(type default)
			)
			(layer "B.Fab")
		)
		(fp_line
			(start 0.12065 -0.2794)
			(end -0.12065 -0.2794)
			(stroke
				(width 0.1)
				(type default)
			)
			(layer "B.Fab")
		)
		(fp_line
			(start -0.67945 -0.3048)
			(end -0.67945 0.3048)
			(stroke
				(width 0.1)
				(type default)
			)
			(layer "B.Fab")
		)
		(fp_line
			(start -0.12065 -0.3048)
			(end -0.67945 -0.3048)
			(stroke
				(width 0.1)
				(type default)
			)
			(layer "B.Fab")
		)
		(fp_line
			(start 0.12065 -0.305054)
			(end 0.12065 -0.2794)
			(stroke
				(width 0.1)
				(type default)
			)
			(layer "B.Fab")
		)
		(fp_line
			(start 0.67945 -0.305054)
			(end 0.12065 -0.305054)
			(stroke
				(width 0.1)
				(type default)
			)
			(layer "B.Fab")
		)
		(pad "1" smd circle
			(at 0.40005 0 90)
			(size 0 0)
			(layers "B.Cu" "B.Mask" "B.Paste")
			(net "P1V2_AUX")
		)
		(pad "2" smd circle
			(at -0.40005 0 90)
			(size 0 0)
			(layers "B.Cu" "B.Mask" "B.Paste")
			(net "P1V2_AUX_SCALED")
		)
	)
	(footprint ""
		(layer "B.Cu")
		(at 172.900086 -288.299906 90)
		(property "Reference" "C3116"
			(at 0 0 90)
			(layer "B.SilkS")
			(hide yes)
			(effects
				(font
					(size 1.27 1.27)
				)
				(justify mirror)
			)
		)
		(property "Value" ""
			(at 0 0 90)
			(layer "B.Fab")
			(effects
				(font
					(size 1.27 1.27)
				)
				(justify mirror)
			)
		)
		(duplicate_pad_numbers_are_jumpers no)
		(fp_line
			(start 0.299974 -0.150114)
			(end -0.299974 -0.150114)
			(stroke
				(width 0.1)
				(type default)
			)
			(layer "B.Fab")
		)
		(fp_line
			(start -0.299974 -0.150114)
			(end -0.299974 0.150114)
			(stroke
				(width 0.1)
				(type default)
			)
			(layer "B.Fab")
		)
		(fp_line
			(start 0.299974 0.150114)
			(end 0.299974 -0.150114)
			(stroke
				(width 0.1)
				(type default)
			)
			(layer "B.Fab")
		)
		(fp_line
			(start -0.299974 0.150114)
			(end 0.299974 0.150114)
			(stroke
				(width 0.1)
				(type default)
			)
			(layer "B.Fab")
		)
		(pad "1" smd rect
			(at 0.2667 0 270)
			(size 0.3048 0.381)
			(layers "B.Cu" "B.Mask" "B.Paste")
			(net "P1V25_PEX1")
		)
		(pad "2" smd rect
			(at -0.2667 0 270)
			(size 0.3048 0.381)
			(layers "B.Cu" "B.Mask" "B.Paste")
			(net "GND")
		)
	)
	(footprint ""
		(layer "B.Cu")
		(at 17.869662 -222.658432)
		(property "Reference" "C2216"
			(at 0 0 0)
			(layer "B.SilkS")
			(hide yes)
			(effects
				(font
					(size 1.27 1.27)
				)
				(justify mirror)
			)
		)
		(property "Value" ""
			(at 0 0 0)
			(layer "B.Fab")
			(effects
				(font
					(size 1.27 1.27)
				)
				(justify mirror)
			)
		)
		(duplicate_pad_numbers_are_jumpers no)
		(fp_line
			(start -0.7874 -0.4064)
			(end -0.7874 0.4064)
			(stroke
				(width 0.1524)
				(type default)
			)
			(layer "B.SilkS")
		)
		(fp_line
			(start -0.7874 0.4064)
			(end 0.7874 0.4064)
			(stroke
				(width 0.1524)
				(type default)
			)
			(layer "B.SilkS")
		)
		(fp_line
			(start 0.7874 -0.4064)
			(end -0.7874 -0.4064)
			(stroke
				(width 0.1524)
				(type default)
			)
			(layer "B.SilkS")
		)
		(fp_line
			(start 0.7874 0.4064)
			(end 0.7874 -0.4064)
			(stroke
				(width 0.1524)
				(type default)
			)
			(layer "B.SilkS")
		)
		(fp_line
			(start -0.67945 -0.3048)
			(end -0.67945 0.3048)
			(stroke
				(width 0.1)
				(type default)
			)
			(layer "B.Fab")
		)
		(fp_line
			(start -0.67945 0.3048)
			(end -0.120396 0.3048)
			(stroke
				(width 0.1)
				(type default)
			)
			(layer "B.Fab")
		)
		(fp_line
			(start -0.12065 -0.3048)
			(end -0.67945 -0.3048)
			(stroke
				(width 0.1)
				(type default)
			)
			(layer "B.Fab")
		)
		(fp_line
			(start -0.12065 -0.2794)
			(end -0.12065 -0.3048)
			(stroke
				(width 0.1)
				(type default)
			)
			(layer "B.Fab")
		)
		(fp_line
			(start -0.120396 0.2794)
			(end 0.12065 0.2794)
			(stroke
				(width 0.1)
				(type default)
			)
			(layer "B.Fab")
		)
		(fp_line
			(start -0.120396 0.3048)
			(end -0.120396 0.2794)
			(stroke
				(width 0.1)
				(type default)
			)
			(layer "B.Fab")
		)
		(fp_line
			(start 0.12065 -0.305054)
			(end 0.12065 -0.2794)
			(stroke
				(width 0.1)
				(type default)
			)
			(layer "B.Fab")
		)
		(fp_line
			(start 0.12065 -0.2794)
			(end -0.12065 -0.2794)
			(stroke
				(width 0.1)
				(type default)
			)
			(layer "B.Fab")
		)
		(fp_line
			(start 0.12065 0.2794)
			(end 0.12065 0.3048)
			(stroke
				(width 0.1)
				(type default)
			)
			(layer "B.Fab")
		)
		(fp_line
			(start 0.12065 0.3048)
			(end 0.67945 0.3048)
			(stroke
				(width 0.1)
				(type default)
			)
			(layer "B.Fab")
		)
		(fp_line
			(start 0.67945 -0.305054)
			(end 0.12065 -0.305054)
			(stroke
				(width 0.1)
				(type default)
			)
			(layer "B.Fab")
		)
		(fp_line
			(start 0.67945 0.3048)
			(end 0.67945 -0.305054)
			(stroke
				(width 0.1)
				(type default)
			)
			(layer "B.Fab")
		)
		(pad "1" smd circle
			(at 0.40005 0 180)
			(size 0 0)
			(layers "B.Cu" "B.Mask" "B.Paste")
			(net "GND")
		)
		(pad "2" smd circle
			(at -0.40005 0 180)
			(size 0 0)
			(layers "B.Cu" "B.Mask" "B.Paste")
			(net "P3V3_AUX")
		)
	)
	(footprint ""
		(layer "B.Cu")
		(at 68.672202 -113.437924)
		(property "Reference" "R61"
			(at 0 0 0)
			(layer "B.SilkS")
			(hide yes)
			(effects
				(font
					(size 1.27 1.27)
				)
				(justify mirror)
			)
		)
		(property "Value" ""
			(at 0 0 0)
			(layer "B.Fab")
			(effects
				(font
					(size 1.27 1.27)
				)
				(justify mirror)
			)
		)
		(duplicate_pad_numbers_are_jumpers no)
		(fp_line
			(start -0.7874 -0.4064)
			(end -0.7874 0.4064)
			(stroke
				(width 0.1524)
				(type default)
			)
			(layer "B.SilkS")
		)
		(fp_line
			(start -0.7874 0.4064)
			(end 0.7874 0.4064)
			(stroke
				(width 0.1524)
				(type default)
			)
			(layer "B.SilkS")
		)
		(fp_line
			(start 0.7874 -0.4064)
			(end -0.7874 -0.4064)
			(stroke
				(width 0.1524)
				(type default)
			)
			(layer "B.SilkS")
		)
		(fp_line
			(start 0.7874 0.4064)
			(end 0.7874 -0.4064)
			(stroke
				(width 0.1524)
				(type default)
			)
			(layer "B.SilkS")
		)
		(fp_line
			(start -0.67945 -0.3048)
			(end -0.67945 0.3048)
			(stroke
				(width 0.1)
				(type default)
			)
			(layer "B.Fab")
		)
		(fp_line
			(start -0.67945 0.3048)
			(end -0.120396 0.3048)
			(stroke
				(width 0.1)
				(type default)
			)
			(layer "B.Fab")
		)
		(fp_line
			(start -0.12065 -0.3048)
			(end -0.67945 -0.3048)
			(stroke
				(width 0.1)
				(type default)
			)
			(layer "B.Fab")
		)
		(fp_line
			(start -0.12065 -0.2794)
			(end -0.12065 -0.3048)
			(stroke
				(width 0.1)
				(type default)
			)
			(layer "B.Fab")
		)
		(fp_line
			(start -0.120396 0.2794)
			(end 0.12065 0.2794)
			(stroke
				(width 0.1)
				(type default)
			)
			(layer "B.Fab")
		)
		(fp_line
			(start -0.120396 0.3048)
			(end -0.120396 0.2794)
			(stroke
				(width 0.1)
				(type default)
			)
			(layer "B.Fab")
		)
		(fp_line
			(start 0.12065 -0.305054)
			(end 0.12065 -0.2794)
			(stroke
				(width 0.1)
				(type default)
			)
			(layer "B.Fab")
		)
		(fp_line
			(start 0.12065 -0.2794)
			(end -0.12065 -0.2794)
			(stroke
				(width 0.1)
				(type default)
			)
			(layer "B.Fab")
		)
		(fp_line
			(start 0.12065 0.2794)
			(end 0.12065 0.3048)
			(stroke
				(width 0.1)
				(type default)
			)
			(layer "B.Fab")
		)
		(fp_line
			(start 0.12065 0.3048)
			(end 0.67945 0.3048)
			(stroke
				(width 0.1)
				(type default)
			)
			(layer "B.Fab")
		)
		(fp_line
			(start 0.67945 -0.305054)
			(end 0.12065 -0.305054)
			(stroke
				(width 0.1)
				(type default)
			)
			(layer "B.Fab")
		)
		(fp_line
			(start 0.67945 0.3048)
			(end 0.67945 -0.305054)
			(stroke
				(width 0.1)
				(type default)
			)
			(layer "B.Fab")
		)
		(pad "1" smd circle
			(at 0.40005 0 180)
			(size 0 0)
			(layers "B.Cu" "B.Mask" "B.Paste")
			(net "P3V3_NIC1")
		)
		(pad "2" smd circle
			(at -0.40005 0 180)
			(size 0 0)
			(layers "B.Cu" "B.Mask" "B.Paste")
			(net "SMB_NIC1_R_SDA")
		)
	)
	(footprint ""
		(layer "B.Cu")
		(at 224.269046 -143.094202 90)
		(property "Reference" "C2797"
			(at 0 0 90)
			(layer "B.SilkS")
			(hide yes)
			(effects
				(font
					(size 1.27 1.27)
				)
				(justify mirror)
			)
		)
		(property "Value" ""
			(at 0 0 90)
			(layer "B.Fab")
			(effects
				(font
					(size 1.27 1.27)
				)
				(justify mirror)
			)
		)
		(duplicate_pad_numbers_are_jumpers no)
		(fp_line
			(start 1.2954 -0.5842)
			(end -1.2954 -0.5842)
			(stroke
				(width 0.1524)
				(type default)
			)
			(layer "B.SilkS")
		)
		(fp_line
			(start -1.2954 -0.5842)
			(end -1.2954 0.5842)
			(stroke
				(width 0.1524)
				(type default)
			)
			(layer "B.SilkS")
		)
		(fp_line
			(start 1.2954 0.5842)
			(end 1.2954 -0.5842)
			(stroke
				(width 0.1524)
				(type default)
			)
			(layer "B.SilkS")
		)
		(fp_line
			(start -1.2954 0.5842)
			(end 1.2954 0.5842)
			(stroke
				(width 0.1524)
				(type default)
			)
			(layer "B.SilkS")
		)
		(fp_line
			(start 0.8636 -0.4572)
			(end -0.8636 -0.4572)
			(stroke
				(width 0.1)
				(type default)
			)
			(layer "B.Fab")
		)
		(fp_line
			(start -0.8636 -0.4572)
			(end -0.8636 -0.4064)
			(stroke
				(width 0.1)
				(type default)
			)
			(layer "B.Fab")
		)
		(fp_line
			(start 1.1938 -0.4064)
			(end 0.8636 -0.4064)
			(stroke
				(width 0.1)
				(type default)
			)
			(layer "B.Fab")
		)
		(fp_line
			(start 0.8636 -0.4064)
			(end 0.8636 -0.4572)
			(stroke
				(width 0.1)
				(type default)
			)
			(layer "B.Fab")
		)
		(fp_line
			(start -0.8636 -0.4064)
			(end -1.1938 -0.4064)
			(stroke
				(width 0.1)
				(type default)
			)
			(layer "B.Fab")
		)
		(fp_line
			(start -1.1938 -0.4064)
			(end -1.1938 0.4064)
			(stroke
				(width 0.1)
				(type default)
			)
			(layer "B.Fab")
		)
		(fp_line
			(start 1.1938 0.4064)
			(end 1.1938 -0.4064)
			(stroke
				(width 0.1)
				(type default)
			)
			(layer "B.Fab")
		)
		(fp_line
			(start 0.8636 0.4064)
			(end 1.1938 0.4064)
			(stroke
				(width 0.1)
				(type default)
			)
			(layer "B.Fab")
		)
		(fp_line
			(start -0.8636 0.4064)
			(end -0.8636 0.4572)
			(stroke
				(width 0.1)
				(type default)
			)
			(layer "B.Fab")
		)
		(fp_line
			(start -1.1938 0.4064)
			(end -0.8636 0.4064)
			(stroke
				(width 0.1)
				(type default)
			)
			(layer "B.Fab")
		)
		(fp_line
			(start 0.8636 0.4572)
			(end 0.8636 0.4064)
			(stroke
				(width 0.1)
				(type default)
			)
			(layer "B.Fab")
		)
		(fp_line
			(start -0.8636 0.4572)
			(end 0.8636 0.4572)
			(stroke
				(width 0.1)
				(type default)
			)
			(layer "B.Fab")
		)
		(pad "1" smd rect
			(at 0.7366 0)
			(size 0.7112 0.8128)
			(layers "B.Cu" "B.Mask" "B.Paste")
			(net "P3V3_CLK_GEN_VDDA25M_CK440_PEX")
		)
		(pad "2" smd rect
			(at -0.7366 0)
			(size 0.7112 0.8128)
			(layers "B.Cu" "B.Mask" "B.Paste")
			(net "GND")
		)
	)
	(footprint ""
		(layer "B.Cu")
		(at 278.064214 -144.421352 180)
		(property "Reference" "C910"
			(at 0 0 0)
			(layer "B.SilkS")
			(hide yes)
			(effects
				(font
					(size 1.27 1.27)
				)
				(justify mirror)
			)
		)
		(property "Value" ""
			(at 0 0 0)
			(layer "B.Fab")
			(effects
				(font
					(size 1.27 1.27)
				)
				(justify mirror)
			)
		)
		(duplicate_pad_numbers_are_jumpers no)
		(fp_line
			(start 0.299974 0.150114)
			(end 0.299974 -0.150114)
			(stroke
				(width 0.1)
				(type default)
			)
			(layer "B.Fab")
		)
		(fp_line
			(start 0.299974 -0.150114)
			(end -0.299974 -0.150114)
			(stroke
				(width 0.1)
				(type default)
			)
			(layer "B.Fab")
		)
		(fp_line
			(start -0.299974 0.150114)
			(end 0.299974 0.150114)
			(stroke
				(width 0.1)
				(type default)
			)
			(layer "B.Fab")
		)
		(fp_line
			(start -0.299974 -0.150114)
			(end -0.299974 0.150114)
			(stroke
				(width 0.1)
				(type default)
			)
			(layer "B.Fab")
		)
		(pad "1" smd rect
			(at 0.2667 0)
			(size 0.3048 0.381)
			(layers "B.Cu" "B.Mask" "B.Paste")
			(net "P12V_NIC4")
		)
		(pad "2" smd rect
			(at -0.2667 0)
			(size 0.3048 0.381)
			(layers "B.Cu" "B.Mask" "B.Paste")
			(net "GND")
		)
	)
	(footprint ""
		(layer "B.Cu")
		(at 394.65504 -301.0408)
		(property "Reference" "C3521"
			(at 0 0 0)
			(layer "B.SilkS")
			(hide yes)
			(effects
				(font
					(size 1.27 1.27)
				)
				(justify mirror)
			)
		)
		(property "Value" ""
			(at 0 0 0)
			(layer "B.Fab")
			(effects
				(font
					(size 1.27 1.27)
				)
				(justify mirror)
			)
		)
		(duplicate_pad_numbers_are_jumpers no)
		(fp_line
			(start -0.299974 -0.150114)
			(end -0.299974 0.150114)
			(stroke
				(width 0.1)
				(type default)
			)
			(layer "B.Fab")
		)
		(fp_line
			(start -0.299974 0.150114)
			(end 0.299974 0.150114)
			(stroke
				(width 0.1)
				(type default)
			)
			(layer "B.Fab")
		)
		(fp_line
			(start 0.299974 -0.150114)
			(end -0.299974 -0.150114)
			(stroke
				(width 0.1)
				(type default)
			)
			(layer "B.Fab")
		)
		(fp_line
			(start 0.299974 0.150114)
			(end 0.299974 -0.150114)
			(stroke
				(width 0.1)
				(type default)
			)
			(layer "B.Fab")
		)
		(pad "1" smd rect
			(at 0.2667 0 180)
			(size 0.3048 0.381)
			(layers "B.Cu" "B.Mask" "B.Paste")
			(net "P1V8_PEX")
		)
		(pad "2" smd rect
			(at -0.2667 0 180)
			(size 0.3048 0.381)
			(layers "B.Cu" "B.Mask" "B.Paste")
			(net "GND")
		)
	)
	(footprint ""
		(layer "B.Cu")
		(at 198.539608 -367.333276)
		(property "Reference" "PR4"
			(at 0 0 0)
			(layer "B.SilkS")
			(hide yes)
			(effects
				(font
					(size 1.27 1.27)
				)
				(justify mirror)
			)
		)
		(property "Value" ""
			(at 0 0 0)
			(layer "B.Fab")
			(effects
				(font
					(size 1.27 1.27)
				)
				(justify mirror)
			)
		)
		(duplicate_pad_numbers_are_jumpers no)
		(fp_line
			(start -0.7874 -0.4064)
			(end -0.7874 0.4064)
			(stroke
				(width 0.1524)
				(type default)
			)
			(layer "B.SilkS")
		)
		(fp_line
			(start -0.7874 0.4064)
			(end 0.7874 0.4064)
			(stroke
				(width 0.1524)
				(type default)
			)
			(layer "B.SilkS")
		)
		(fp_line
			(start 0.7874 -0.4064)
			(end -0.7874 -0.4064)
			(stroke
				(width 0.1524)
				(type default)
			)
			(layer "B.SilkS")
		)
		(fp_line
			(start 0.7874 0.4064)
			(end 0.7874 -0.4064)
			(stroke
				(width 0.1524)
				(type default)
			)
			(layer "B.SilkS")
		)
		(fp_line
			(start -0.67945 -0.3048)
			(end -0.67945 0.3048)
			(stroke
				(width 0.1)
				(type default)
			)
			(layer "B.Fab")
		)
		(fp_line
			(start -0.67945 0.3048)
			(end -0.120396 0.3048)
			(stroke
				(width 0.1)
				(type default)
			)
			(layer "B.Fab")
		)
		(fp_line
			(start -0.12065 -0.3048)
			(end -0.67945 -0.3048)
			(stroke
				(width 0.1)
				(type default)
			)
			(layer "B.Fab")
		)
		(fp_line
			(start -0.12065 -0.2794)
			(end -0.12065 -0.3048)
			(stroke
				(width 0.1)
				(type default)
			)
			(layer "B.Fab")
		)
		(fp_line
			(start -0.120396 0.2794)
			(end 0.12065 0.2794)
			(stroke
				(width 0.1)
				(type default)
			)
			(layer "B.Fab")
		)
		(fp_line
			(start -0.120396 0.3048)
			(end -0.120396 0.2794)
			(stroke
				(width 0.1)
				(type default)
			)
			(layer "B.Fab")
		)
		(fp_line
			(start 0.12065 -0.305054)
			(end 0.12065 -0.2794)
			(stroke
				(width 0.1)
				(type default)
			)
			(layer "B.Fab")
		)
		(fp_line
			(start 0.12065 -0.2794)
			(end -0.12065 -0.2794)
			(stroke
				(width 0.1)
				(type default)
			)
			(layer "B.Fab")
		)
		(fp_line
			(start 0.12065 0.2794)
			(end 0.12065 0.3048)
			(stroke
				(width 0.1)
				(type default)
			)
			(layer "B.Fab")
		)
		(fp_line
			(start 0.12065 0.3048)
			(end 0.67945 0.3048)
			(stroke
				(width 0.1)
				(type default)
			)
			(layer "B.Fab")
		)
		(fp_line
			(start 0.67945 -0.305054)
			(end 0.12065 -0.305054)
			(stroke
				(width 0.1)
				(type default)
			)
			(layer "B.Fab")
		)
		(fp_line
			(start 0.67945 0.3048)
			(end 0.67945 -0.305054)
			(stroke
				(width 0.1)
				(type default)
			)
			(layer "B.Fab")
		)
		(pad "1" smd circle
			(at 0.40005 0 180)
			(size 0 0)
			(layers "B.Cu" "B.Mask" "B.Paste")
			(net "HSC_VDD_R")
		)
		(pad "2" smd circle
			(at -0.40005 0 180)
			(size 0 0)
			(layers "B.Cu" "B.Mask" "B.Paste")
			(net "HSC_VDD")
		)
	)
	(footprint ""
		(layer "B.Cu")
		(at 185.104024 -117.723666)
		(property "Reference" "C887"
			(at 0 0 0)
			(layer "B.SilkS")
			(hide yes)
			(effects
				(font
					(size 1.27 1.27)
				)
				(justify mirror)
			)
		)
		(property "Value" ""
			(at 0 0 0)
			(layer "B.Fab")
			(effects
				(font
					(size 1.27 1.27)
				)
				(justify mirror)
			)
		)
		(duplicate_pad_numbers_are_jumpers no)
		(fp_line
			(start -0.7874 -0.4064)
			(end -0.7874 0.4064)
			(stroke
				(width 0.1524)
				(type default)
			)
			(layer "B.SilkS")
		)
		(fp_line
			(start -0.7874 0.4064)
			(end 0.7874 0.4064)
			(stroke
				(width 0.1524)
				(type default)
			)
			(layer "B.SilkS")
		)
		(fp_line
			(start 0.7874 -0.4064)
			(end -0.7874 -0.4064)
			(stroke
				(width 0.1524)
				(type default)
			)
			(layer "B.SilkS")
		)
		(fp_line
			(start 0.7874 0.4064)
			(end 0.7874 -0.4064)
			(stroke
				(width 0.1524)
				(type default)
			)
			(layer "B.SilkS")
		)
		(fp_line
			(start -0.67945 -0.3048)
			(end -0.67945 0.3048)
			(stroke
				(width 0.1)
				(type default)
			)
			(layer "B.Fab")
		)
		(fp_line
			(start -0.67945 0.3048)
			(end -0.120396 0.3048)
			(stroke
				(width 0.1)
				(type default)
			)
			(layer "B.Fab")
		)
		(fp_line
			(start -0.12065 -0.3048)
			(end -0.67945 -0.3048)
			(stroke
				(width 0.1)
				(type default)
			)
			(layer "B.Fab")
		)
		(fp_line
			(start -0.12065 -0.2794)
			(end -0.12065 -0.3048)
			(stroke
				(width 0.1)
				(type default)
			)
			(layer "B.Fab")
		)
		(fp_line
			(start -0.120396 0.2794)
			(end 0.12065 0.2794)
			(stroke
				(width 0.1)
				(type default)
			)
			(layer "B.Fab")
		)
		(fp_line
			(start -0.120396 0.3048)
			(end -0.120396 0.2794)
			(stroke
				(width 0.1)
				(type default)
			)
			(layer "B.Fab")
		)
		(fp_line
			(start 0.12065 -0.305054)
			(end 0.12065 -0.2794)
			(stroke
				(width 0.1)
				(type default)
			)
			(layer "B.Fab")
		)
		(fp_line
			(start 0.12065 -0.2794)
			(end -0.12065 -0.2794)
			(stroke
				(width 0.1)
				(type default)
			)
			(layer "B.Fab")
		)
		(fp_line
			(start 0.12065 0.2794)
			(end 0.12065 0.3048)
			(stroke
				(width 0.1)
				(type default)
			)
			(layer "B.Fab")
		)
		(fp_line
			(start 0.12065 0.3048)
			(end 0.67945 0.3048)
			(stroke
				(width 0.1)
				(type default)
			)
			(layer "B.Fab")
		)
		(fp_line
			(start 0.67945 -0.305054)
			(end 0.12065 -0.305054)
			(stroke
				(width 0.1)
				(type default)
			)
			(layer "B.Fab")
		)
		(fp_line
			(start 0.67945 0.3048)
			(end 0.67945 -0.305054)
			(stroke
				(width 0.1)
				(type default)
			)
			(layer "B.Fab")
		)
		(pad "1" smd circle
			(at 0.40005 0 180)
			(size 0 0)
			(layers "B.Cu" "B.Mask" "B.Paste")
			(net "P3V3_AUX")
		)
		(pad "2" smd circle
			(at -0.40005 0 180)
			(size 0 0)
			(layers "B.Cu" "B.Mask" "B.Paste")
			(net "GND")
		)
	)
	(footprint ""
		(layer "B.Cu")
		(at 350.888554 -277.639272)
		(property "Reference" "PC6621"
			(at 0 0 0)
			(layer "B.SilkS")
			(hide yes)
			(effects
				(font
					(size 1.27 1.27)
				)
				(justify mirror)
			)
		)
		(property "Value" ""
			(at 0 0 0)
			(layer "B.Fab")
			(effects
				(font
					(size 1.27 1.27)
				)
				(justify mirror)
			)
		)
		(duplicate_pad_numbers_are_jumpers no)
		(fp_line
			(start -1.524 -0.762)
			(end -1.524 0.762)
			(stroke
				(width 0.1524)
				(type default)
			)
			(layer "B.SilkS")
		)
		(fp_line
			(start -1.524 0.762)
			(end 1.524 0.762)
			(stroke
				(width 0.1524)
				(type default)
			)
			(layer "B.SilkS")
		)
		(fp_line
			(start 1.524 -0.762)
			(end -1.524 -0.762)
			(stroke
				(width 0.1524)
				(type default)
			)
			(layer "B.SilkS")
		)
		(fp_line
			(start 1.524 0.762)
			(end 1.524 -0.762)
			(stroke
				(width 0.1524)
				(type default)
			)
			(layer "B.SilkS")
		)
		(fp_line
			(start -1.1049 -0.724916)
			(end 1.1049 -0.724916)
			(stroke
				(width 0.1)
				(type default)
			)
			(layer "B.Fab")
		)
		(fp_line
			(start -1.1049 0.724916)
			(end -1.1049 -0.724916)
			(stroke
				(width 0.1)
				(type default)
			)
			(layer "B.Fab")
		)
		(fp_line
			(start 1.1049 -0.724916)
			(end 1.1049 0.724916)
			(stroke
				(width 0.1)
				(type default)
			)
			(layer "B.Fab")
		)
		(fp_line
			(start 1.1049 0.724916)
			(end -1.1049 0.724916)
			(stroke
				(width 0.1)
				(type default)
			)
			(layer "B.Fab")
		)
		(pad "1" smd rect
			(at 0.889 0)
			(size 1.016 1.27)
			(layers "B.Cu" "B.Mask" "B.Paste")
			(net "SW_P12V_P0V8_PEX3_FLT")
		)
		(pad "2" smd rect
			(at -0.889 0)
			(size 1.016 1.27)
			(layers "B.Cu" "B.Mask" "B.Paste")
			(net "GND")
		)
	)
	(footprint ""
		(layer "B.Cu")
		(at 52.049934 -292.099746 90)
		(property "Reference" "C1187"
			(at 0 0 90)
			(layer "B.SilkS")
			(hide yes)
			(effects
				(font
					(size 1.27 1.27)
				)
				(justify mirror)
			)
		)
		(property "Value" ""
			(at 0 0 90)
			(layer "B.Fab")
			(effects
				(font
					(size 1.27 1.27)
				)
				(justify mirror)
			)
		)
		(duplicate_pad_numbers_are_jumpers no)
		(fp_line
			(start 0.299974 -0.150114)
			(end -0.299974 -0.150114)
			(stroke
				(width 0.1)
				(type default)
			)
			(layer "B.Fab")
		)
		(fp_line
			(start -0.299974 -0.150114)
			(end -0.299974 0.150114)
			(stroke
				(width 0.1)
				(type default)
			)
			(layer "B.Fab")
		)
		(fp_line
			(start 0.299974 0.150114)
			(end 0.299974 -0.150114)
			(stroke
				(width 0.1)
				(type default)
			)
			(layer "B.Fab")
		)
		(fp_line
			(start -0.299974 0.150114)
			(end 0.299974 0.150114)
			(stroke
				(width 0.1)
				(type default)
			)
			(layer "B.Fab")
		)
		(pad "1" smd rect
			(at 0.2667 0 270)
			(size 0.3048 0.381)
			(layers "B.Cu" "B.Mask" "B.Paste")
			(net "P0V8_SERDES_VDDA_PEX0")
		)
		(pad "2" smd rect
			(at -0.2667 0 270)
			(size 0.3048 0.381)
			(layers "B.Cu" "B.Mask" "B.Paste")
			(net "GND")
		)
	)
	(footprint ""
		(layer "B.Cu")
		(at 279.3492 -384.403092)
		(property "Reference" "PR7159"
			(at 0 0 0)
			(layer "B.SilkS")
			(hide yes)
			(effects
				(font
					(size 1.27 1.27)
				)
				(justify mirror)
			)
		)
		(property "Value" ""
			(at 0 0 0)
			(layer "B.Fab")
			(effects
				(font
					(size 1.27 1.27)
				)
				(justify mirror)
			)
		)
		(duplicate_pad_numbers_are_jumpers no)
		(fp_line
			(start -0.7874 -0.4064)
			(end -0.7874 0.4064)
			(stroke
				(width 0.1524)
				(type default)
			)
			(layer "B.SilkS")
		)
		(fp_line
			(start -0.7874 0.4064)
			(end 0.7874 0.4064)
			(stroke
				(width 0.1524)
				(type default)
			)
			(layer "B.SilkS")
		)
		(fp_line
			(start 0.7874 -0.4064)
			(end -0.7874 -0.4064)
			(stroke
				(width 0.1524)
				(type default)
			)
			(layer "B.SilkS")
		)
		(fp_line
			(start 0.7874 0.4064)
			(end 0.7874 -0.4064)
			(stroke
				(width 0.1524)
				(type default)
			)
			(layer "B.SilkS")
		)
		(fp_line
			(start -0.67945 -0.3048)
			(end -0.67945 0.3048)
			(stroke
				(width 0.1)
				(type default)
			)
			(layer "B.Fab")
		)
		(fp_line
			(start -0.67945 0.3048)
			(end -0.120396 0.3048)
			(stroke
				(width 0.1)
				(type default)
			)
			(layer "B.Fab")
		)
		(fp_line
			(start -0.12065 -0.3048)
			(end -0.67945 -0.3048)
			(stroke
				(width 0.1)
				(type default)
			)
			(layer "B.Fab")
		)
		(fp_line
			(start -0.12065 -0.2794)
			(end -0.12065 -0.3048)
			(stroke
				(width 0.1)
				(type default)
			)
			(layer "B.Fab")
		)
		(fp_line
			(start -0.120396 0.2794)
			(end 0.12065 0.2794)
			(stroke
				(width 0.1)
				(type default)
			)
			(layer "B.Fab")
		)
		(fp_line
			(start -0.120396 0.3048)
			(end -0.120396 0.2794)
			(stroke
				(width 0.1)
				(type default)
			)
			(layer "B.Fab")
		)
		(fp_line
			(start 0.12065 -0.305054)
			(end 0.12065 -0.2794)
			(stroke
				(width 0.1)
				(type default)
			)
			(layer "B.Fab")
		)
		(fp_line
			(start 0.12065 -0.2794)
			(end -0.12065 -0.2794)
			(stroke
				(width 0.1)
				(type default)
			)
			(layer "B.Fab")
		)
		(fp_line
			(start 0.12065 0.2794)
			(end 0.12065 0.3048)
			(stroke
				(width 0.1)
				(type default)
			)
			(layer "B.Fab")
		)
		(fp_line
			(start 0.12065 0.3048)
			(end 0.67945 0.3048)
			(stroke
				(width 0.1)
				(type default)
			)
			(layer "B.Fab")
		)
		(fp_line
			(start 0.67945 -0.305054)
			(end 0.12065 -0.305054)
			(stroke
				(width 0.1)
				(type default)
			)
			(layer "B.Fab")
		)
		(fp_line
			(start 0.67945 0.3048)
			(end 0.67945 -0.305054)
			(stroke
				(width 0.1)
				(type default)
			)
			(layer "B.Fab")
		)
		(pad "1" smd circle
			(at 0.40005 0 180)
			(size 0 0)
			(layers "B.Cu" "B.Mask" "B.Paste")
			(net "LTC4282_T_CRIT_N")
		)
		(pad "2" smd circle
			(at -0.40005 0 180)
			(size 0 0)
			(layers "B.Cu" "B.Mask" "B.Paste")
			(net "P3V3_AUX")
		)
	)
	(footprint ""
		(layer "B.Cu")
		(at 298.974764 -286.399732 90)
		(property "Reference" "C3313"
			(at 0 0 90)
			(layer "B.SilkS")
			(hide yes)
			(effects
				(font
					(size 1.27 1.27)
				)
				(justify mirror)
			)
		)
		(property "Value" ""
			(at 0 0 90)
			(layer "B.Fab")
			(effects
				(font
					(size 1.27 1.27)
				)
				(justify mirror)
			)
		)
		(duplicate_pad_numbers_are_jumpers no)
		(fp_line
			(start 0.299974 -0.150114)
			(end -0.299974 -0.150114)
			(stroke
				(width 0.1)
				(type default)
			)
			(layer "B.Fab")
		)
		(fp_line
			(start -0.299974 -0.150114)
			(end -0.299974 0.150114)
			(stroke
				(width 0.1)
				(type default)
			)
			(layer "B.Fab")
		)
		(fp_line
			(start 0.299974 0.150114)
			(end 0.299974 -0.150114)
			(stroke
				(width 0.1)
				(type default)
			)
			(layer "B.Fab")
		)
		(fp_line
			(start -0.299974 0.150114)
			(end 0.299974 0.150114)
			(stroke
				(width 0.1)
				(type default)
			)
			(layer "B.Fab")
		)
		(pad "1" smd rect
			(at 0.2667 0 270)
			(size 0.3048 0.381)
			(layers "B.Cu" "B.Mask" "B.Paste")
			(net "P1V25_SERDES_VDDPLL_PEX2")
		)
		(pad "2" smd rect
			(at -0.2667 0 270)
			(size 0.3048 0.381)
			(layers "B.Cu" "B.Mask" "B.Paste")
			(net "GND")
		)
	)
	(footprint ""
		(layer "B.Cu")
		(at 353.523296 -223.750632)
		(property "Reference" "R5635"
			(at 0 0 0)
			(layer "B.SilkS")
			(hide yes)
			(effects
				(font
					(size 1.27 1.27)
				)
				(justify mirror)
			)
		)
		(property "Value" ""
			(at 0 0 0)
			(layer "B.Fab")
			(effects
				(font
					(size 1.27 1.27)
				)
				(justify mirror)
			)
		)
		(duplicate_pad_numbers_are_jumpers no)
		(fp_line
			(start -1.2954 -0.5842)
			(end -1.2954 0.5842)
			(stroke
				(width 0.1524)
				(type default)
			)
			(layer "B.SilkS")
		)
		(fp_line
			(start -1.2954 0.5842)
			(end 1.2954 0.5842)
			(stroke
				(width 0.1524)
				(type default)
			)
			(layer "B.SilkS")
		)
		(fp_line
			(start 1.2954 -0.5842)
			(end -1.2954 -0.5842)
			(stroke
				(width 0.1524)
				(type default)
			)
			(layer "B.SilkS")
		)
		(fp_line
			(start 1.2954 0.5842)
			(end 1.2954 -0.5842)
			(stroke
				(width 0.1524)
				(type default)
			)
			(layer "B.SilkS")
		)
		(fp_line
			(start -1.1938 -0.406654)
			(end -1.1938 0.4064)
			(stroke
				(width 0.1)
				(type default)
			)
			(layer "B.Fab")
		)
		(fp_line
			(start -1.1938 0.4064)
			(end -0.8636 0.4064)
			(stroke
				(width 0.1)
				(type default)
			)
			(layer "B.Fab")
		)
		(fp_line
			(start -0.8636 -0.4572)
			(end -0.8636 -0.406654)
			(stroke
				(width 0.1)
				(type default)
			)
			(layer "B.Fab")
		)
		(fp_line
			(start -0.8636 -0.406654)
			(end -1.1938 -0.406654)
			(stroke
				(width 0.1)
				(type default)
			)
			(layer "B.Fab")
		)
		(fp_line
			(start -0.8636 0.4064)
			(end -0.8636 0.4572)
			(stroke
				(width 0.1)
				(type default)
			)
			(layer "B.Fab")
		)
		(fp_line
			(start -0.8636 0.4572)
			(end 0.8636 0.4572)
			(stroke
				(width 0.1)
				(type default)
			)
			(layer "B.Fab")
		)
		(fp_line
			(start 0.8636 -0.4572)
			(end -0.8636 -0.4572)
			(stroke
				(width 0.1)
				(type default)
			)
			(layer "B.Fab")
		)
		(fp_line
			(start 0.8636 -0.406654)
			(end 0.8636 -0.4572)
			(stroke
				(width 0.1)
				(type default)
			)
			(layer "B.Fab")
		)
		(fp_line
			(start 0.8636 0.4064)
			(end 1.1938 0.4064)
			(stroke
				(width 0.1)
				(type default)
			)
			(layer "B.Fab")
		)
		(fp_line
			(start 0.8636 0.4318)
			(end 0.8636 0.4064)
			(stroke
				(width 0.1)
				(type default)
			)
			(layer "B.Fab")
		)
		(fp_line
			(start 0.8636 0.4572)
			(end 0.8636 0.4318)
			(stroke
				(width 0.1)
				(type default)
			)
			(layer "B.Fab")
		)
		(fp_line
			(start 1.1938 -0.406654)
			(end 0.8636 -0.406654)
			(stroke
				(width 0.1)
				(type default)
			)
			(layer "B.Fab")
		)
		(fp_line
			(start 1.1938 0.4064)
			(end 1.1938 -0.406654)
			(stroke
				(width 0.1)
				(type default)
			)
			(layer "B.Fab")
		)
		(pad "1" smd rect
			(at 0.7366 0 270)
			(size 0.7112 0.8128)
			(layers "B.Cu" "B.Mask" "B.Paste")
			(net "P3V3_AUX")
		)
		(pad "2" smd rect
			(at -0.7366 0 270)
			(size 0.7112 0.8128)
			(layers "B.Cu" "B.Mask" "B.Paste")
			(net "P3V3_VCC_FPGA_CORE")
		)
	)
	(footprint ""
		(layer "B.Cu")
		(at 56.325008 -297.79976 -90)
		(property "Reference" "C1154"
			(at 0 0 90)
			(layer "B.SilkS")
			(hide yes)
			(effects
				(font
					(size 1.27 1.27)
				)
				(justify mirror)
			)
		)
		(property "Value" ""
			(at 0 0 90)
			(layer "B.Fab")
			(effects
				(font
					(size 1.27 1.27)
				)
				(justify mirror)
			)
		)
		(duplicate_pad_numbers_are_jumpers no)
		(fp_line
			(start -0.299974 0.150114)
			(end 0.299974 0.150114)
			(stroke
				(width 0.1)
				(type default)
			)
			(layer "B.Fab")
		)
		(fp_line
			(start 0.299974 0.150114)
			(end 0.299974 -0.150114)
			(stroke
				(width 0.1)
				(type default)
			)
			(layer "B.Fab")
		)
		(fp_line
			(start -0.299974 -0.150114)
			(end -0.299974 0.150114)
			(stroke
				(width 0.1)
				(type default)
			)
			(layer "B.Fab")
		)
		(fp_line
			(start 0.299974 -0.150114)
			(end -0.299974 -0.150114)
			(stroke
				(width 0.1)
				(type default)
			)
			(layer "B.Fab")
		)
		(pad "1" smd rect
			(at 0.2667 0 90)
			(size 0.3048 0.381)
			(layers "B.Cu" "B.Mask" "B.Paste")
			(net "P0V8_PEX0")
		)
		(pad "2" smd rect
			(at -0.2667 0 90)
			(size 0.3048 0.381)
			(layers "B.Cu" "B.Mask" "B.Paste")
			(net "GND")
		)
	)
	(footprint ""
		(layer "B.Cu")
		(at 116.788184 -316.017402 180)
		(property "Reference" "C4211"
			(at 0 0 0)
			(layer "B.SilkS")
			(hide yes)
			(effects
				(font
					(size 1.27 1.27)
				)
				(justify mirror)
			)
		)
		(property "Value" ""
			(at 0 0 0)
			(layer "B.Fab")
			(effects
				(font
					(size 1.27 1.27)
				)
				(justify mirror)
			)
		)
		(duplicate_pad_numbers_are_jumpers no)
		(fp_line
			(start 0.299974 0.150114)
			(end 0.299974 -0.150114)
			(stroke
				(width 0.1)
				(type default)
			)
			(layer "B.Fab")
		)
		(fp_line
			(start 0.299974 -0.150114)
			(end -0.299974 -0.150114)
			(stroke
				(width 0.1)
				(type default)
			)
			(layer "B.Fab")
		)
		(fp_line
			(start -0.299974 0.150114)
			(end 0.299974 0.150114)
			(stroke
				(width 0.1)
				(type default)
			)
			(layer "B.Fab")
		)
		(fp_line
			(start -0.299974 -0.150114)
			(end -0.299974 0.150114)
			(stroke
				(width 0.1)
				(type default)
			)
			(layer "B.Fab")
		)
		(pad "1" smd rect
			(at 0.2667 0)
			(size 0.3048 0.381)
			(layers "B.Cu" "B.Mask" "B.Paste")
			(net "P0V8_SERDES_VDDA_PEX0")
		)
		(pad "2" smd rect
			(at -0.2667 0)
			(size 0.3048 0.381)
			(layers "B.Cu" "B.Mask" "B.Paste")
			(net "GND")
		)
	)
	(footprint ""
		(layer "B.Cu")
		(at 77.541882 -102.088696 180)
		(property "Reference" "R68"
			(at 0 0 0)
			(layer "B.SilkS")
			(hide yes)
			(effects
				(font
					(size 1.27 1.27)
				)
				(justify mirror)
			)
		)
		(property "Value" ""
			(at 0 0 0)
			(layer "B.Fab")
			(effects
				(font
					(size 1.27 1.27)
				)
				(justify mirror)
			)
		)
		(duplicate_pad_numbers_are_jumpers no)
		(fp_line
			(start 0.7874 0.4064)
			(end 0.7874 -0.4064)
			(stroke
				(width 0.1524)
				(type default)
			)
			(layer "B.SilkS")
		)
		(fp_line
			(start 0.7874 -0.4064)
			(end -0.7874 -0.4064)
			(stroke
				(width 0.1524)
				(type default)
			)
			(layer "B.SilkS")
		)
		(fp_line
			(start -0.7874 0.4064)
			(end 0.7874 0.4064)
			(stroke
				(width 0.1524)
				(type default)
			)
			(layer "B.SilkS")
		)
		(fp_line
			(start -0.7874 -0.4064)
			(end -0.7874 0.4064)
			(stroke
				(width 0.1524)
				(type default)
			)
			(layer "B.SilkS")
		)
		(fp_line
			(start 0.67945 0.3048)
			(end 0.67945 -0.305054)
			(stroke
				(width 0.1)
				(type default)
			)
			(layer "B.Fab")
		)
		(fp_line
			(start 0.67945 -0.305054)
			(end 0.12065 -0.305054)
			(stroke
				(width 0.1)
				(type default)
			)
			(layer "B.Fab")
		)
		(fp_line
			(start 0.12065 0.3048)
			(end 0.67945 0.3048)
			(stroke
				(width 0.1)
				(type default)
			)
			(layer "B.Fab")
		)
		(fp_line
			(start 0.12065 0.2794)
			(end 0.12065 0.3048)
			(stroke
				(width 0.1)
				(type default)
			)
			(layer "B.Fab")
		)
		(fp_line
			(start 0.12065 -0.2794)
			(end -0.12065 -0.2794)
			(stroke
				(width 0.1)
				(type default)
			)
			(layer "B.Fab")
		)
		(fp_line
			(start 0.12065 -0.305054)
			(end 0.12065 -0.2794)
			(stroke
				(width 0.1)
				(type default)
			)
			(layer "B.Fab")
		)
		(fp_line
			(start -0.120396 0.3048)
			(end -0.120396 0.2794)
			(stroke
				(width 0.1)
				(type default)
			)
			(layer "B.Fab")
		)
		(fp_line
			(start -0.120396 0.2794)
			(end 0.12065 0.2794)
			(stroke
				(width 0.1)
				(type default)
			)
			(layer "B.Fab")
		)
		(fp_line
			(start -0.12065 -0.2794)
			(end -0.12065 -0.3048)
			(stroke
				(width 0.1)
				(type default)
			)
			(layer "B.Fab")
		)
		(fp_line
			(start -0.12065 -0.3048)
			(end -0.67945 -0.3048)
			(stroke
				(width 0.1)
				(type default)
			)
			(layer "B.Fab")
		)
		(fp_line
			(start -0.67945 0.3048)
			(end -0.120396 0.3048)
			(stroke
				(width 0.1)
				(type default)
			)
			(layer "B.Fab")
		)
		(fp_line
			(start -0.67945 -0.3048)
			(end -0.67945 0.3048)
			(stroke
				(width 0.1)
				(type default)
			)
			(layer "B.Fab")
		)
		(pad "1" smd circle
			(at 0.40005 0)
			(size 0 0)
			(layers "B.Cu" "B.Mask" "B.Paste")
			(net "NCSI_NIC1_RXD1")
		)
		(pad "2" smd circle
			(at -0.40005 0)
			(size 0 0)
			(layers "B.Cu" "B.Mask" "B.Paste")
			(net "GND")
		)
	)
	(footprint ""
		(layer "B.Cu")
		(at 3.066796 -277.35403)
		(property "Reference" "C4235"
			(at 0 0 0)
			(layer "B.SilkS")
			(hide yes)
			(effects
				(font
					(size 1.27 1.27)
				)
				(justify mirror)
			)
		)
		(property "Value" ""
			(at 0 0 0)
			(layer "B.Fab")
			(effects
				(font
					(size 1.27 1.27)
				)
				(justify mirror)
			)
		)
		(duplicate_pad_numbers_are_jumpers no)
		(fp_line
			(start -1.2954 -0.5842)
			(end -1.2954 0.5842)
			(stroke
				(width 0.1524)
				(type default)
			)
			(layer "B.SilkS")
		)
		(fp_line
			(start -1.2954 0.5842)
			(end 1.2954 0.5842)
			(stroke
				(width 0.1524)
				(type default)
			)
			(layer "B.SilkS")
		)
		(fp_line
			(start 1.2954 -0.5842)
			(end -1.2954 -0.5842)
			(stroke
				(width 0.1524)
				(type default)
			)
			(layer "B.SilkS")
		)
		(fp_line
			(start 1.2954 0.5842)
			(end 1.2954 -0.5842)
			(stroke
				(width 0.1524)
				(type default)
			)
			(layer "B.SilkS")
		)
		(fp_line
			(start -1.1938 -0.4064)
			(end -1.1938 0.4064)
			(stroke
				(width 0.1)
				(type default)
			)
			(layer "B.Fab")
		)
		(fp_line
			(start -1.1938 0.4064)
			(end -0.8636 0.4064)
			(stroke
				(width 0.1)
				(type default)
			)
			(layer "B.Fab")
		)
		(fp_line
			(start -0.8636 -0.4572)
			(end -0.8636 -0.4064)
			(stroke
				(width 0.1)
				(type default)
			)
			(layer "B.Fab")
		)
		(fp_line
			(start -0.8636 -0.4064)
			(end -1.1938 -0.4064)
			(stroke
				(width 0.1)
				(type default)
			)
			(layer "B.Fab")
		)
		(fp_line
			(start -0.8636 0.4064)
			(end -0.8636 0.4572)
			(stroke
				(width 0.1)
				(type default)
			)
			(layer "B.Fab")
		)
		(fp_line
			(start -0.8636 0.4572)
			(end 0.8636 0.4572)
			(stroke
				(width 0.1)
				(type default)
			)
			(layer "B.Fab")
		)
		(fp_line
			(start 0.8636 -0.4572)
			(end -0.8636 -0.4572)
			(stroke
				(width 0.1)
				(type default)
			)
			(layer "B.Fab")
		)
		(fp_line
			(start 0.8636 -0.4064)
			(end 0.8636 -0.4572)
			(stroke
				(width 0.1)
				(type default)
			)
			(layer "B.Fab")
		)
		(fp_line
			(start 0.8636 0.4064)
			(end 1.1938 0.4064)
			(stroke
				(width 0.1)
				(type default)
			)
			(layer "B.Fab")
		)
		(fp_line
			(start 0.8636 0.4572)
			(end 0.8636 0.4064)
			(stroke
				(width 0.1)
				(type default)
			)
			(layer "B.Fab")
		)
		(fp_line
			(start 1.1938 -0.4064)
			(end 0.8636 -0.4064)
			(stroke
				(width 0.1)
				(type default)
			)
			(layer "B.Fab")
		)
		(fp_line
			(start 1.1938 0.4064)
			(end 1.1938 -0.4064)
			(stroke
				(width 0.1)
				(type default)
			)
			(layer "B.Fab")
		)
		(pad "1" smd rect
			(at 0.7366 0 270)
			(size 0.7112 0.8128)
			(layers "B.Cu" "B.Mask" "B.Paste")
			(net "P1V25_PEX0")
		)
		(pad "2" smd rect
			(at -0.7366 0 270)
			(size 0.7112 0.8128)
			(layers "B.Cu" "B.Mask" "B.Paste")
			(net "GND")
		)
	)
	(footprint ""
		(layer "B.Cu")
		(at 409.849828 -290.199826 90)
		(property "Reference" "C1975"
			(at 0 0 90)
			(layer "B.SilkS")
			(hide yes)
			(effects
				(font
					(size 1.27 1.27)
				)
				(justify mirror)
			)
		)
		(property "Value" ""
			(at 0 0 90)
			(layer "B.Fab")
			(effects
				(font
					(size 1.27 1.27)
				)
				(justify mirror)
			)
		)
		(duplicate_pad_numbers_are_jumpers no)
		(fp_line
			(start 0.299974 -0.150114)
			(end -0.299974 -0.150114)
			(stroke
				(width 0.1)
				(type default)
			)
			(layer "B.Fab")
		)
		(fp_line
			(start -0.299974 -0.150114)
			(end -0.299974 0.150114)
			(stroke
				(width 0.1)
				(type default)
			)
			(layer "B.Fab")
		)
		(fp_line
			(start 0.299974 0.150114)
			(end 0.299974 -0.150114)
			(stroke
				(width 0.1)
				(type default)
			)
			(layer "B.Fab")
		)
		(fp_line
			(start -0.299974 0.150114)
			(end 0.299974 0.150114)
			(stroke
				(width 0.1)
				(type default)
			)
			(layer "B.Fab")
		)
		(pad "1" smd rect
			(at 0.2667 0 270)
			(size 0.3048 0.381)
			(layers "B.Cu" "B.Mask" "B.Paste")
			(net "P0V8_SERDES_VDDA_PEX3")
		)
		(pad "2" smd rect
			(at -0.2667 0 270)
			(size 0.3048 0.381)
			(layers "B.Cu" "B.Mask" "B.Paste")
			(net "GND")
		)
	)
	(footprint ""
		(layer "B.Cu")
		(at 414.599882 -288.299906 90)
		(property "Reference" "C3445"
			(at 0 0 90)
			(layer "B.SilkS")
			(hide yes)
			(effects
				(font
					(size 1.27 1.27)
				)
				(justify mirror)
			)
		)
		(property "Value" ""
			(at 0 0 90)
			(layer "B.Fab")
			(effects
				(font
					(size 1.27 1.27)
				)
				(justify mirror)
			)
		)
		(duplicate_pad_numbers_are_jumpers no)
		(fp_line
			(start 0.299974 -0.150114)
			(end -0.299974 -0.150114)
			(stroke
				(width 0.1)
				(type default)
			)
			(layer "B.Fab")
		)
		(fp_line
			(start -0.299974 -0.150114)
			(end -0.299974 0.150114)
			(stroke
				(width 0.1)
				(type default)
			)
			(layer "B.Fab")
		)
		(fp_line
			(start 0.299974 0.150114)
			(end 0.299974 -0.150114)
			(stroke
				(width 0.1)
				(type default)
			)
			(layer "B.Fab")
		)
		(fp_line
			(start -0.299974 0.150114)
			(end 0.299974 0.150114)
			(stroke
				(width 0.1)
				(type default)
			)
			(layer "B.Fab")
		)
		(pad "1" smd rect
			(at 0.2667 0 270)
			(size 0.3048 0.381)
			(layers "B.Cu" "B.Mask" "B.Paste")
			(net "P1V25_PEX3")
		)
		(pad "2" smd rect
			(at -0.2667 0 270)
			(size 0.3048 0.381)
			(layers "B.Cu" "B.Mask" "B.Paste")
			(net "GND")
		)
	)
	(footprint ""
		(layer "B.Cu")
		(at 404.149814 -299.699934 -90)
		(property "Reference" "C1998"
			(at 0 0 90)
			(layer "B.SilkS")
			(hide yes)
			(effects
				(font
					(size 1.27 1.27)
				)
				(justify mirror)
			)
		)
		(property "Value" ""
			(at 0 0 90)
			(layer "B.Fab")
			(effects
				(font
					(size 1.27 1.27)
				)
				(justify mirror)
			)
		)
		(duplicate_pad_numbers_are_jumpers no)
		(fp_line
			(start -0.299974 0.150114)
			(end 0.299974 0.150114)
			(stroke
				(width 0.1)
				(type default)
			)
			(layer "B.Fab")
		)
		(fp_line
			(start 0.299974 0.150114)
			(end 0.299974 -0.150114)
			(stroke
				(width 0.1)
				(type default)
			)
			(layer "B.Fab")
		)
		(fp_line
			(start -0.299974 -0.150114)
			(end -0.299974 0.150114)
			(stroke
				(width 0.1)
				(type default)
			)
			(layer "B.Fab")
		)
		(fp_line
			(start 0.299974 -0.150114)
			(end -0.299974 -0.150114)
			(stroke
				(width 0.1)
				(type default)
			)
			(layer "B.Fab")
		)
		(pad "1" smd rect
			(at 0.2667 0 90)
			(size 0.3048 0.381)
			(layers "B.Cu" "B.Mask" "B.Paste")
			(net "P0V8_SERDES_VDDA_PEX3")
		)
		(pad "2" smd rect
			(at -0.2667 0 90)
			(size 0.3048 0.381)
			(layers "B.Cu" "B.Mask" "B.Paste")
			(net "GND")
		)
	)
	(footprint ""
		(layer "B.Cu")
		(at 328.106024 10.656824 180)
		(property "Reference" "DE16T_1"
			(at -2.805176 -3.009646 0)
			(unlocked yes)
			(layer "B.SilkS")
			(effects
				(font
					(size 0.7874 0.5842)
					(thickness 0.1524)
				)
				(justify left mirror)
			)
		)
		(property "Value" ""
			(at 0 0 0)
			(layer "B.Fab")
			(effects
				(font
					(size 1.27 1.27)
				)
				(justify mirror)
			)
		)
		(duplicate_pad_numbers_are_jumpers no)
		(fp_line
			(start 1.2192 2.1082)
			(end 1.2192 -2.1082)
			(stroke
				(width 0.1524)
				(type default)
			)
			(layer "B.SilkS")
		)
		(fp_line
			(start 1.2192 -2.1082)
			(end -1.2192 -2.1082)
			(stroke
				(width 0.1524)
				(type default)
			)
			(layer "B.SilkS")
		)
		(fp_line
			(start -1.2192 2.1082)
			(end 1.2192 2.1082)
			(stroke
				(width 0.1524)
				(type default)
			)
			(layer "B.SilkS")
		)
		(fp_line
			(start -1.2192 -2.1082)
			(end -1.2192 2.1082)
			(stroke
				(width 0.1524)
				(type default)
			)
			(layer "B.SilkS")
		)
		(pad "" np_thru_hole circle
			(at -3.4671 -1.27 90)
			(size 1.0414 1.0414)
			(drill 1.0414)
			(layers "*.Cu" "*.Mask")
			(clearance 0.381)
			(thermal_gap 0.381)
		)
		(pad "" np_thru_hole circle
			(at -3.4671 1.27 90)
			(size 1.0414 1.0414)
			(drill 1.0414)
			(layers "*.Cu" "*.Mask")
			(clearance 0.381)
			(thermal_gap 0.381)
		)
		(pad "" np_thru_hole circle
			(at 2.8829 -1.27 90)
			(size 1.0414 1.0414)
			(drill 1.0414)
			(layers "*.Cu" "*.Mask")
			(clearance 0.381)
			(thermal_gap 0.381)
		)
		(pad "" np_thru_hole circle
			(at 2.8829 1.27 90)
			(size 1.0414 1.0414)
			(drill 1.0414)
			(layers "*.Cu" "*.Mask")
			(clearance 0.381)
			(thermal_gap 0.381)
		)
		(pad "1" smd rect
			(at -0.8255 -0.249936 90)
			(size 0.3048 0.508)
			(layers "B.Cu" "B.Mask" "B.Paste")
			(net "85_10INCH_IN4_DP")
		)
		(pad "2" smd rect
			(at -0.8255 0.249936 90)
			(size 0.3048 0.508)
			(layers "B.Cu" "B.Mask" "B.Paste")
			(net "85_10INCH_IN4_DN")
		)
		(pad "3" smd circle
			(at 0 0)
			(size 0 0)
			(layers "B.Cu" "B.Mask" "B.Paste")
			(net "COUPON_GND2")
		)
		(zone
			(layers "F.Cu" "B.Cu" "In1.Cu" "In2.Cu" "In3.Cu" "In4.Cu" "In5.Cu" "In6.Cu"
				"In7.Cu" "In8.Cu" "In9.Cu" "In10.Cu" "In11.Cu" "In12.Cu" "In13.Cu" "In14.Cu"
				"In15.Cu" "In16.Cu"
			)
			(hatch none 0.5)
			(connect_pads
				(clearance 0)
			)
			(min_thickness 0.25)
			(keepout
				(tracks not_allowed)
				(vias allowed)
				(pads allowed)
				(copperpour not_allowed)
				(footprints allowed)
			)
			(placement
				(enabled no)
				(sheetname "")
			)
			(fill
				(thermal_gap 0.5)
				(thermal_bridge_width 0.5)
				(island_removal_mode 0)
			)
			(polygon
				(pts
					(arc
						(start 326.150224 9.386824)
						(mid 324.296024 9.386824)
						(end 326.150224 9.386824)
					)
				)
			)
		)
		(zone
			(layers "F.Cu" "B.Cu" "In1.Cu" "In2.Cu" "In3.Cu" "In4.Cu" "In5.Cu" "In6.Cu"
				"In7.Cu" "In8.Cu" "In9.Cu" "In10.Cu" "In11.Cu" "In12.Cu" "In13.Cu" "In14.Cu"
				"In15.Cu" "In16.Cu"
			)
			(hatch none 0.5)
			(connect_pads
				(clearance 0)
			)
			(min_thickness 0.25)
			(keepout
				(tracks not_allowed)
				(vias allowed)
				(pads allowed)
				(copperpour not_allowed)
				(footprints allowed)
			)
			(placement
				(enabled no)
				(sheetname "")
			)
			(fill
				(thermal_gap 0.5)
				(thermal_bridge_width 0.5)
				(island_removal_mode 0)
			)
			(polygon
				(pts
					(arc
						(start 326.150224 11.926824)
						(mid 324.296024 11.926824)
						(end 326.150224 11.926824)
					)
				)
			)
		)
		(zone
			(layers "F.Cu" "B.Cu" "In1.Cu" "In2.Cu" "In3.Cu" "In4.Cu" "In5.Cu" "In6.Cu"
				"In7.Cu" "In8.Cu" "In9.Cu" "In10.Cu" "In11.Cu" "In12.Cu" "In13.Cu" "In14.Cu"
				"In15.Cu" "In16.Cu"
			)
			(hatch none 0.5)
			(connect_pads
				(clearance 0)
			)
			(min_thickness 0.25)
			(keepout
				(tracks not_allowed)
				(vias allowed)
				(pads allowed)
				(copperpour not_allowed)
				(footprints allowed)
			)
			(placement
				(enabled no)
				(sheetname "")
			)
			(fill
				(thermal_gap 0.5)
				(thermal_bridge_width 0.5)
				(island_removal_mode 0)
			)
			(polygon
				(pts
					(arc
						(start 332.500224 9.386824)
						(mid 330.646024 9.386824)
						(end 332.500224 9.386824)
					)
				)
			)
		)
		(zone
			(layers "F.Cu" "B.Cu" "In1.Cu" "In2.Cu" "In3.Cu" "In4.Cu" "In5.Cu" "In6.Cu"
				"In7.Cu" "In8.Cu" "In9.Cu" "In10.Cu" "In11.Cu" "In12.Cu" "In13.Cu" "In14.Cu"
				"In15.Cu" "In16.Cu"
			)
			(hatch none 0.5)
			(connect_pads
				(clearance 0)
			)
			(min_thickness 0.25)
			(keepout
				(tracks not_allowed)
				(vias allowed)
				(pads allowed)
				(copperpour not_allowed)
				(footprints allowed)
			)
			(placement
				(enabled no)
				(sheetname "")
			)
			(fill
				(thermal_gap 0.5)
				(thermal_bridge_width 0.5)
				(island_removal_mode 0)
			)
			(polygon
				(pts
					(arc
						(start 332.500224 11.926824)
						(mid 330.646024 11.926824)
						(end 332.500224 11.926824)
					)
				)
			)
		)
		(zone
			(layer "B.Cu")
			(hatch none 0.5)
			(connect_pads
				(clearance 0)
			)
			(min_thickness 0.25)
			(keepout
				(tracks not_allowed)
				(vias allowed)
				(pads allowed)
				(copperpour not_allowed)
				(footprints allowed)
			)
			(placement
				(enabled no)
				(sheetname "")
			)
			(fill
				(thermal_gap 0.5)
				(thermal_bridge_width 0.5)
				(island_removal_mode 0)
			)
			(polygon
				(pts
					(xy 329.223624 11.205464) (xy 329.223624 11.10996) (xy 328.626724 11.10996) (xy 328.626724 10.70356)
					(xy 329.223624 10.70356) (xy 329.223624 10.610088) (xy 328.626724 10.610088) (xy 328.626724 10.203688)
					(xy 329.223624 10.203688) (xy 329.223624 10.108184) (xy 328.525124 10.108184) (xy 328.525124 11.205464)
				)
			)
		)
	)
	(footprint ""
		(layer "B.Cu")
		(at 348.98838 -317.6778 180)
		(property "Reference" "C4323"
			(at 0 0 0)
			(layer "B.SilkS")
			(hide yes)
			(effects
				(font
					(size 1.27 1.27)
				)
				(justify mirror)
			)
		)
		(property "Value" ""
			(at 0 0 0)
			(layer "B.Fab")
			(effects
				(font
					(size 1.27 1.27)
				)
				(justify mirror)
			)
		)
		(duplicate_pad_numbers_are_jumpers no)
		(fp_line
			(start 0.299974 0.150114)
			(end 0.299974 -0.150114)
			(stroke
				(width 0.1)
				(type default)
			)
			(layer "B.Fab")
		)
		(fp_line
			(start 0.299974 -0.150114)
			(end -0.299974 -0.150114)
			(stroke
				(width 0.1)
				(type default)
			)
			(layer "B.Fab")
		)
		(fp_line
			(start -0.299974 0.150114)
			(end 0.299974 0.150114)
			(stroke
				(width 0.1)
				(type default)
			)
			(layer "B.Fab")
		)
		(fp_line
			(start -0.299974 -0.150114)
			(end -0.299974 0.150114)
			(stroke
				(width 0.1)
				(type default)
			)
			(layer "B.Fab")
		)
		(pad "1" smd rect
			(at 0.2667 0)
			(size 0.3048 0.381)
			(layers "B.Cu" "B.Mask" "B.Paste")
			(net "P0V8_SERDES_VDDA_PEX2")
		)
		(pad "2" smd rect
			(at -0.2667 0)
			(size 0.3048 0.381)
			(layers "B.Cu" "B.Mask" "B.Paste")
			(net "GND")
		)
	)
	(footprint ""
		(layer "B.Cu")
		(at 182.17642 -111.334042 180)
		(property "Reference" "R189"
			(at 0 0 0)
			(layer "B.SilkS")
			(hide yes)
			(effects
				(font
					(size 1.27 1.27)
				)
				(justify mirror)
			)
		)
		(property "Value" ""
			(at 0 0 0)
			(layer "B.Fab")
			(effects
				(font
					(size 1.27 1.27)
				)
				(justify mirror)
			)
		)
		(duplicate_pad_numbers_are_jumpers no)
		(fp_line
			(start 0.7874 0.4064)
			(end 0.7874 -0.4064)
			(stroke
				(width 0.1524)
				(type default)
			)
			(layer "B.SilkS")
		)
		(fp_line
			(start 0.7874 -0.4064)
			(end -0.7874 -0.4064)
			(stroke
				(width 0.1524)
				(type default)
			)
			(layer "B.SilkS")
		)
		(fp_line
			(start -0.7874 0.4064)
			(end 0.7874 0.4064)
			(stroke
				(width 0.1524)
				(type default)
			)
			(layer "B.SilkS")
		)
		(fp_line
			(start -0.7874 -0.4064)
			(end -0.7874 0.4064)
			(stroke
				(width 0.1524)
				(type default)
			)
			(layer "B.SilkS")
		)
		(fp_line
			(start 0.67945 0.3048)
			(end 0.67945 -0.305054)
			(stroke
				(width 0.1)
				(type default)
			)
			(layer "B.Fab")
		)
		(fp_line
			(start 0.67945 -0.305054)
			(end 0.12065 -0.305054)
			(stroke
				(width 0.1)
				(type default)
			)
			(layer "B.Fab")
		)
		(fp_line
			(start 0.12065 0.3048)
			(end 0.67945 0.3048)
			(stroke
				(width 0.1)
				(type default)
			)
			(layer "B.Fab")
		)
		(fp_line
			(start 0.12065 0.2794)
			(end 0.12065 0.3048)
			(stroke
				(width 0.1)
				(type default)
			)
			(layer "B.Fab")
		)
		(fp_line
			(start 0.12065 -0.2794)
			(end -0.12065 -0.2794)
			(stroke
				(width 0.1)
				(type default)
			)
			(layer "B.Fab")
		)
		(fp_line
			(start 0.12065 -0.305054)
			(end 0.12065 -0.2794)
			(stroke
				(width 0.1)
				(type default)
			)
			(layer "B.Fab")
		)
		(fp_line
			(start -0.120396 0.3048)
			(end -0.120396 0.2794)
			(stroke
				(width 0.1)
				(type default)
			)
			(layer "B.Fab")
		)
		(fp_line
			(start -0.120396 0.2794)
			(end 0.12065 0.2794)
			(stroke
				(width 0.1)
				(type default)
			)
			(layer "B.Fab")
		)
		(fp_line
			(start -0.12065 -0.2794)
			(end -0.12065 -0.3048)
			(stroke
				(width 0.1)
				(type default)
			)
			(layer "B.Fab")
		)
		(fp_line
			(start -0.12065 -0.3048)
			(end -0.67945 -0.3048)
			(stroke
				(width 0.1)
				(type default)
			)
			(layer "B.Fab")
		)
		(fp_line
			(start -0.67945 0.3048)
			(end -0.120396 0.3048)
			(stroke
				(width 0.1)
				(type default)
			)
			(layer "B.Fab")
		)
		(fp_line
			(start -0.67945 -0.3048)
			(end -0.67945 0.3048)
			(stroke
				(width 0.1)
				(type default)
			)
			(layer "B.Fab")
		)
		(pad "1" smd circle
			(at 0.40005 0)
			(size 0 0)
			(layers "B.Cu" "B.Mask" "B.Paste")
			(net "RST_SMB_NIC_MUX_R_N")
		)
		(pad "2" smd circle
			(at -0.40005 0)
			(size 0 0)
			(layers "B.Cu" "B.Mask" "B.Paste")
			(net "RST_SMB_NIC3_MUX_N")
		)
	)
	(footprint ""
		(layer "B.Cu")
		(at 47.7774 -300.7995 -90)
		(property "Reference" "C3022"
			(at 0 0 90)
			(layer "B.SilkS")
			(hide yes)
			(effects
				(font
					(size 1.27 1.27)
				)
				(justify mirror)
			)
		)
		(property "Value" ""
			(at 0 0 90)
			(layer "B.Fab")
			(effects
				(font
					(size 1.27 1.27)
				)
				(justify mirror)
			)
		)
		(duplicate_pad_numbers_are_jumpers no)
		(fp_line
			(start -0.299974 0.150114)
			(end 0.299974 0.150114)
			(stroke
				(width 0.1)
				(type default)
			)
			(layer "B.Fab")
		)
		(fp_line
			(start 0.299974 0.150114)
			(end 0.299974 -0.150114)
			(stroke
				(width 0.1)
				(type default)
			)
			(layer "B.Fab")
		)
		(fp_line
			(start -0.299974 -0.150114)
			(end -0.299974 0.150114)
			(stroke
				(width 0.1)
				(type default)
			)
			(layer "B.Fab")
		)
		(fp_line
			(start 0.299974 -0.150114)
			(end -0.299974 -0.150114)
			(stroke
				(width 0.1)
				(type default)
			)
			(layer "B.Fab")
		)
		(pad "1" smd rect
			(at 0.2667 0 90)
			(size 0.3048 0.381)
			(layers "B.Cu" "B.Mask" "B.Paste")
			(net "PCEPLL0_VDDA18_PEX0")
		)
		(pad "2" smd rect
			(at -0.2667 0 90)
			(size 0.3048 0.381)
			(layers "B.Cu" "B.Mask" "B.Paste")
			(net "GND")
		)
	)
	(footprint ""
		(layer "B.Cu")
		(at 172.900086 -292.099746 90)
		(property "Reference" "C1479"
			(at 0 0 90)
			(layer "B.SilkS")
			(hide yes)
			(effects
				(font
					(size 1.27 1.27)
				)
				(justify mirror)
			)
		)
		(property "Value" ""
			(at 0 0 90)
			(layer "B.Fab")
			(effects
				(font
					(size 1.27 1.27)
				)
				(justify mirror)
			)
		)
		(duplicate_pad_numbers_are_jumpers no)
		(fp_line
			(start 0.299974 -0.150114)
			(end -0.299974 -0.150114)
			(stroke
				(width 0.1)
				(type default)
			)
			(layer "B.Fab")
		)
		(fp_line
			(start -0.299974 -0.150114)
			(end -0.299974 0.150114)
			(stroke
				(width 0.1)
				(type default)
			)
			(layer "B.Fab")
		)
		(fp_line
			(start 0.299974 0.150114)
			(end 0.299974 -0.150114)
			(stroke
				(width 0.1)
				(type default)
			)
			(layer "B.Fab")
		)
		(fp_line
			(start -0.299974 0.150114)
			(end 0.299974 0.150114)
			(stroke
				(width 0.1)
				(type default)
			)
			(layer "B.Fab")
		)
		(pad "1" smd rect
			(at 0.2667 0 270)
			(size 0.3048 0.381)
			(layers "B.Cu" "B.Mask" "B.Paste")
			(net "P0V8_SERDES_VDDA_PEX1")
		)
		(pad "2" smd rect
			(at -0.2667 0 270)
			(size 0.3048 0.381)
			(layers "B.Cu" "B.Mask" "B.Paste")
			(net "GND")
		)
	)
	(footprint ""
		(layer "B.Cu")
		(at 71.28637 -117.66169)
		(property "Reference" "R54"
			(at 0 0 0)
			(layer "B.SilkS")
			(hide yes)
			(effects
				(font
					(size 1.27 1.27)
				)
				(justify mirror)
			)
		)
		(property "Value" ""
			(at 0 0 0)
			(layer "B.Fab")
			(effects
				(font
					(size 1.27 1.27)
				)
				(justify mirror)
			)
		)
		(duplicate_pad_numbers_are_jumpers no)
		(fp_line
			(start -0.7874 -0.4064)
			(end -0.7874 0.4064)
			(stroke
				(width 0.1524)
				(type default)
			)
			(layer "B.SilkS")
		)
		(fp_line
			(start -0.7874 0.4064)
			(end 0.7874 0.4064)
			(stroke
				(width 0.1524)
				(type default)
			)
			(layer "B.SilkS")
		)
		(fp_line
			(start 0.7874 -0.4064)
			(end -0.7874 -0.4064)
			(stroke
				(width 0.1524)
				(type default)
			)
			(layer "B.SilkS")
		)
		(fp_line
			(start 0.7874 0.4064)
			(end 0.7874 -0.4064)
			(stroke
				(width 0.1524)
				(type default)
			)
			(layer "B.SilkS")
		)
		(fp_line
			(start -0.67945 -0.3048)
			(end -0.67945 0.3048)
			(stroke
				(width 0.1)
				(type default)
			)
			(layer "B.Fab")
		)
		(fp_line
			(start -0.67945 0.3048)
			(end -0.120396 0.3048)
			(stroke
				(width 0.1)
				(type default)
			)
			(layer "B.Fab")
		)
		(fp_line
			(start -0.12065 -0.3048)
			(end -0.67945 -0.3048)
			(stroke
				(width 0.1)
				(type default)
			)
			(layer "B.Fab")
		)
		(fp_line
			(start -0.12065 -0.2794)
			(end -0.12065 -0.3048)
			(stroke
				(width 0.1)
				(type default)
			)
			(layer "B.Fab")
		)
		(fp_line
			(start -0.120396 0.2794)
			(end 0.12065 0.2794)
			(stroke
				(width 0.1)
				(type default)
			)
			(layer "B.Fab")
		)
		(fp_line
			(start -0.120396 0.3048)
			(end -0.120396 0.2794)
			(stroke
				(width 0.1)
				(type default)
			)
			(layer "B.Fab")
		)
		(fp_line
			(start 0.12065 -0.305054)
			(end 0.12065 -0.2794)
			(stroke
				(width 0.1)
				(type default)
			)
			(layer "B.Fab")
		)
		(fp_line
			(start 0.12065 -0.2794)
			(end -0.12065 -0.2794)
			(stroke
				(width 0.1)
				(type default)
			)
			(layer "B.Fab")
		)
		(fp_line
			(start 0.12065 0.2794)
			(end 0.12065 0.3048)
			(stroke
				(width 0.1)
				(type default)
			)
			(layer "B.Fab")
		)
		(fp_line
			(start 0.12065 0.3048)
			(end 0.67945 0.3048)
			(stroke
				(width 0.1)
				(type default)
			)
			(layer "B.Fab")
		)
		(fp_line
			(start 0.67945 -0.305054)
			(end 0.12065 -0.305054)
			(stroke
				(width 0.1)
				(type default)
			)
			(layer "B.Fab")
		)
		(fp_line
			(start 0.67945 0.3048)
			(end 0.67945 -0.305054)
			(stroke
				(width 0.1)
				(type default)
			)
			(layer "B.Fab")
		)
		(pad "1" smd circle
			(at 0.40005 0 180)
			(size 0 0)
			(layers "B.Cu" "B.Mask" "B.Paste")
			(net "NIC1_AUX_PWR_EN_R")
		)
		(pad "2" smd circle
			(at -0.40005 0 180)
			(size 0 0)
			(layers "B.Cu" "B.Mask" "B.Paste")
			(net "NIC1_AUX_PWR_EN")
		)
	)
	(footprint ""
		(layer "B.Cu")
		(at 75.820778 -114.35207 90)
		(property "Reference" "C867"
			(at 0 0 90)
			(layer "B.SilkS")
			(hide yes)
			(effects
				(font
					(size 1.27 1.27)
				)
				(justify mirror)
			)
		)
		(property "Value" ""
			(at 0 0 90)
			(layer "B.Fab")
			(effects
				(font
					(size 1.27 1.27)
				)
				(justify mirror)
			)
		)
		(duplicate_pad_numbers_are_jumpers no)
		(fp_line
			(start 0.7874 -0.4064)
			(end -0.7874 -0.4064)
			(stroke
				(width 0.1524)
				(type default)
			)
			(layer "B.SilkS")
		)
		(fp_line
			(start -0.7874 -0.4064)
			(end -0.7874 0.4064)
			(stroke
				(width 0.1524)
				(type default)
			)
			(layer "B.SilkS")
		)
		(fp_line
			(start 0.7874 0.4064)
			(end 0.7874 -0.4064)
			(stroke
				(width 0.1524)
				(type default)
			)
			(layer "B.SilkS")
		)
		(fp_line
			(start -0.7874 0.4064)
			(end 0.7874 0.4064)
			(stroke
				(width 0.1524)
				(type default)
			)
			(layer "B.SilkS")
		)
		(fp_line
			(start 0.67945 -0.305054)
			(end 0.12065 -0.305054)
			(stroke
				(width 0.1)
				(type default)
			)
			(layer "B.Fab")
		)
		(fp_line
			(start 0.12065 -0.305054)
			(end 0.12065 -0.2794)
			(stroke
				(width 0.1)
				(type default)
			)
			(layer "B.Fab")
		)
		(fp_line
			(start -0.12065 -0.3048)
			(end -0.67945 -0.3048)
			(stroke
				(width 0.1)
				(type default)
			)
			(layer "B.Fab")
		)
		(fp_line
			(start -0.67945 -0.3048)
			(end -0.67945 0.3048)
			(stroke
				(width 0.1)
				(type default)
			)
			(layer "B.Fab")
		)
		(fp_line
			(start 0.12065 -0.2794)
			(end -0.12065 -0.2794)
			(stroke
				(width 0.1)
				(type default)
			)
			(layer "B.Fab")
		)
		(fp_line
			(start -0.12065 -0.2794)
			(end -0.12065 -0.3048)
			(stroke
				(width 0.1)
				(type default)
			)
			(layer "B.Fab")
		)
		(fp_line
			(start 0.12065 0.2794)
			(end 0.12065 0.3048)
			(stroke
				(width 0.1)
				(type default)
			)
			(layer "B.Fab")
		)
		(fp_line
			(start -0.120396 0.2794)
			(end 0.12065 0.2794)
			(stroke
				(width 0.1)
				(type default)
			)
			(layer "B.Fab")
		)
		(fp_line
			(start 0.67945 0.3048)
			(end 0.67945 -0.305054)
			(stroke
				(width 0.1)
				(type default)
			)
			(layer "B.Fab")
		)
		(fp_line
			(start 0.12065 0.3048)
			(end 0.67945 0.3048)
			(stroke
				(width 0.1)
				(type default)
			)
			(layer "B.Fab")
		)
		(fp_line
			(start -0.120396 0.3048)
			(end -0.120396 0.2794)
			(stroke
				(width 0.1)
				(type default)
			)
			(layer "B.Fab")
		)
		(fp_line
			(start -0.67945 0.3048)
			(end -0.120396 0.3048)
			(stroke
				(width 0.1)
				(type default)
			)
			(layer "B.Fab")
		)
		(pad "1" smd circle
			(at 0.40005 0 270)
			(size 0 0)
			(layers "B.Cu" "B.Mask" "B.Paste")
			(net "P3V3_NIC1")
		)
		(pad "2" smd circle
			(at -0.40005 0 270)
			(size 0 0)
			(layers "B.Cu" "B.Mask" "B.Paste")
			(net "GND")
		)
	)
	(footprint ""
		(layer "B.Cu")
		(at 262.967724 -82.487008)
		(property "Reference" "C2633"
			(at 0 0 0)
			(layer "B.SilkS")
			(hide yes)
			(effects
				(font
					(size 1.27 1.27)
				)
				(justify mirror)
			)
		)
		(property "Value" ""
			(at 0 0 0)
			(layer "B.Fab")
			(effects
				(font
					(size 1.27 1.27)
				)
				(justify mirror)
			)
		)
		(duplicate_pad_numbers_are_jumpers no)
		(fp_line
			(start -0.7874 -0.4064)
			(end -0.7874 0.4064)
			(stroke
				(width 0.1524)
				(type default)
			)
			(layer "B.SilkS")
		)
		(fp_line
			(start -0.7874 0.4064)
			(end 0.7874 0.4064)
			(stroke
				(width 0.1524)
				(type default)
			)
			(layer "B.SilkS")
		)
		(fp_line
			(start 0.7874 -0.4064)
			(end -0.7874 -0.4064)
			(stroke
				(width 0.1524)
				(type default)
			)
			(layer "B.SilkS")
		)
		(fp_line
			(start 0.7874 0.4064)
			(end 0.7874 -0.4064)
			(stroke
				(width 0.1524)
				(type default)
			)
			(layer "B.SilkS")
		)
		(fp_line
			(start -0.67945 -0.3048)
			(end -0.67945 0.3048)
			(stroke
				(width 0.1)
				(type default)
			)
			(layer "B.Fab")
		)
		(fp_line
			(start -0.67945 0.3048)
			(end -0.120396 0.3048)
			(stroke
				(width 0.1)
				(type default)
			)
			(layer "B.Fab")
		)
		(fp_line
			(start -0.12065 -0.3048)
			(end -0.67945 -0.3048)
			(stroke
				(width 0.1)
				(type default)
			)
			(layer "B.Fab")
		)
		(fp_line
			(start -0.12065 -0.2794)
			(end -0.12065 -0.3048)
			(stroke
				(width 0.1)
				(type default)
			)
			(layer "B.Fab")
		)
		(fp_line
			(start -0.120396 0.2794)
			(end 0.12065 0.2794)
			(stroke
				(width 0.1)
				(type default)
			)
			(layer "B.Fab")
		)
		(fp_line
			(start -0.120396 0.3048)
			(end -0.120396 0.2794)
			(stroke
				(width 0.1)
				(type default)
			)
			(layer "B.Fab")
		)
		(fp_line
			(start 0.12065 -0.305054)
			(end 0.12065 -0.2794)
			(stroke
				(width 0.1)
				(type default)
			)
			(layer "B.Fab")
		)
		(fp_line
			(start 0.12065 -0.2794)
			(end -0.12065 -0.2794)
			(stroke
				(width 0.1)
				(type default)
			)
			(layer "B.Fab")
		)
		(fp_line
			(start 0.12065 0.2794)
			(end 0.12065 0.3048)
			(stroke
				(width 0.1)
				(type default)
			)
			(layer "B.Fab")
		)
		(fp_line
			(start 0.12065 0.3048)
			(end 0.67945 0.3048)
			(stroke
				(width 0.1)
				(type default)
			)
			(layer "B.Fab")
		)
		(fp_line
			(start 0.67945 -0.305054)
			(end 0.12065 -0.305054)
			(stroke
				(width 0.1)
				(type default)
			)
			(layer "B.Fab")
		)
		(fp_line
			(start 0.67945 0.3048)
			(end 0.67945 -0.305054)
			(stroke
				(width 0.1)
				(type default)
			)
			(layer "B.Fab")
		)
		(pad "1" smd circle
			(at 0.40005 0 180)
			(size 0 0)
			(layers "B.Cu" "B.Mask" "B.Paste")
			(net "P3V3_CLK_GEN_VDD_CK440")
		)
		(pad "2" smd circle
			(at -0.40005 0 180)
			(size 0 0)
			(layers "B.Cu" "B.Mask" "B.Paste")
			(net "GND")
		)
	)
	(footprint ""
		(layer "B.Cu")
		(at 309.741824 -101.069648 180)
		(property "Reference" "R280"
			(at 0 0 0)
			(layer "B.SilkS")
			(hide yes)
			(effects
				(font
					(size 1.27 1.27)
				)
				(justify mirror)
			)
		)
		(property "Value" ""
			(at 0 0 0)
			(layer "B.Fab")
			(effects
				(font
					(size 1.27 1.27)
				)
				(justify mirror)
			)
		)
		(duplicate_pad_numbers_are_jumpers no)
		(fp_line
			(start 0.7874 0.4064)
			(end 0.7874 -0.4064)
			(stroke
				(width 0.1524)
				(type default)
			)
			(layer "B.SilkS")
		)
		(fp_line
			(start 0.7874 -0.4064)
			(end -0.7874 -0.4064)
			(stroke
				(width 0.1524)
				(type default)
			)
			(layer "B.SilkS")
		)
		(fp_line
			(start -0.7874 0.4064)
			(end 0.7874 0.4064)
			(stroke
				(width 0.1524)
				(type default)
			)
			(layer "B.SilkS")
		)
		(fp_line
			(start -0.7874 -0.4064)
			(end -0.7874 0.4064)
			(stroke
				(width 0.1524)
				(type default)
			)
			(layer "B.SilkS")
		)
		(fp_line
			(start 0.67945 0.3048)
			(end 0.67945 -0.305054)
			(stroke
				(width 0.1)
				(type default)
			)
			(layer "B.Fab")
		)
		(fp_line
			(start 0.67945 -0.305054)
			(end 0.12065 -0.305054)
			(stroke
				(width 0.1)
				(type default)
			)
			(layer "B.Fab")
		)
		(fp_line
			(start 0.12065 0.3048)
			(end 0.67945 0.3048)
			(stroke
				(width 0.1)
				(type default)
			)
			(layer "B.Fab")
		)
		(fp_line
			(start 0.12065 0.2794)
			(end 0.12065 0.3048)
			(stroke
				(width 0.1)
				(type default)
			)
			(layer "B.Fab")
		)
		(fp_line
			(start 0.12065 -0.2794)
			(end -0.12065 -0.2794)
			(stroke
				(width 0.1)
				(type default)
			)
			(layer "B.Fab")
		)
		(fp_line
			(start 0.12065 -0.305054)
			(end 0.12065 -0.2794)
			(stroke
				(width 0.1)
				(type default)
			)
			(layer "B.Fab")
		)
		(fp_line
			(start -0.120396 0.3048)
			(end -0.120396 0.2794)
			(stroke
				(width 0.1)
				(type default)
			)
			(layer "B.Fab")
		)
		(fp_line
			(start -0.120396 0.2794)
			(end 0.12065 0.2794)
			(stroke
				(width 0.1)
				(type default)
			)
			(layer "B.Fab")
		)
		(fp_line
			(start -0.12065 -0.2794)
			(end -0.12065 -0.3048)
			(stroke
				(width 0.1)
				(type default)
			)
			(layer "B.Fab")
		)
		(fp_line
			(start -0.12065 -0.3048)
			(end -0.67945 -0.3048)
			(stroke
				(width 0.1)
				(type default)
			)
			(layer "B.Fab")
		)
		(fp_line
			(start -0.67945 0.3048)
			(end -0.120396 0.3048)
			(stroke
				(width 0.1)
				(type default)
			)
			(layer "B.Fab")
		)
		(fp_line
			(start -0.67945 -0.3048)
			(end -0.67945 0.3048)
			(stroke
				(width 0.1)
				(type default)
			)
			(layer "B.Fab")
		)
		(pad "1" smd circle
			(at 0.40005 0)
			(size 0 0)
			(layers "B.Cu" "B.Mask" "B.Paste")
			(net "NIC5_SLOT_ID0")
		)
		(pad "2" smd circle
			(at -0.40005 0)
			(size 0 0)
			(layers "B.Cu" "B.Mask" "B.Paste")
			(net "P3V3_NIC5")
		)
	)
	(footprint ""
		(layer "B.Cu")
		(at 225.19894 -193.759582 90)
		(property "Reference" "R466"
			(at 0 0 90)
			(layer "B.SilkS")
			(hide yes)
			(effects
				(font
					(size 1.27 1.27)
				)
				(justify mirror)
			)
		)
		(property "Value" ""
			(at 0 0 90)
			(layer "B.Fab")
			(effects
				(font
					(size 1.27 1.27)
				)
				(justify mirror)
			)
		)
		(duplicate_pad_numbers_are_jumpers no)
		(fp_line
			(start 0.7874 -0.4064)
			(end -0.7874 -0.4064)
			(stroke
				(width 0.1524)
				(type default)
			)
			(layer "B.SilkS")
		)
		(fp_line
			(start -0.7874 -0.4064)
			(end -0.7874 0.4064)
			(stroke
				(width 0.1524)
				(type default)
			)
			(layer "B.SilkS")
		)
		(fp_line
			(start 0.7874 0.4064)
			(end 0.7874 -0.4064)
			(stroke
				(width 0.1524)
				(type default)
			)
			(layer "B.SilkS")
		)
		(fp_line
			(start -0.7874 0.4064)
			(end 0.7874 0.4064)
			(stroke
				(width 0.1524)
				(type default)
			)
			(layer "B.SilkS")
		)
		(fp_line
			(start 0.67945 -0.305054)
			(end 0.12065 -0.305054)
			(stroke
				(width 0.1)
				(type default)
			)
			(layer "B.Fab")
		)
		(fp_line
			(start 0.12065 -0.305054)
			(end 0.12065 -0.2794)
			(stroke
				(width 0.1)
				(type default)
			)
			(layer "B.Fab")
		)
		(fp_line
			(start -0.12065 -0.3048)
			(end -0.67945 -0.3048)
			(stroke
				(width 0.1)
				(type default)
			)
			(layer "B.Fab")
		)
		(fp_line
			(start -0.67945 -0.3048)
			(end -0.67945 0.3048)
			(stroke
				(width 0.1)
				(type default)
			)
			(layer "B.Fab")
		)
		(fp_line
			(start 0.12065 -0.2794)
			(end -0.12065 -0.2794)
			(stroke
				(width 0.1)
				(type default)
			)
			(layer "B.Fab")
		)
		(fp_line
			(start -0.12065 -0.2794)
			(end -0.12065 -0.3048)
			(stroke
				(width 0.1)
				(type default)
			)
			(layer "B.Fab")
		)
		(fp_line
			(start 0.12065 0.2794)
			(end 0.12065 0.3048)
			(stroke
				(width 0.1)
				(type default)
			)
			(layer "B.Fab")
		)
		(fp_line
			(start -0.120396 0.2794)
			(end 0.12065 0.2794)
			(stroke
				(width 0.1)
				(type default)
			)
			(layer "B.Fab")
		)
		(fp_line
			(start 0.67945 0.3048)
			(end 0.67945 -0.305054)
			(stroke
				(width 0.1)
				(type default)
			)
			(layer "B.Fab")
		)
		(fp_line
			(start 0.12065 0.3048)
			(end 0.67945 0.3048)
			(stroke
				(width 0.1)
				(type default)
			)
			(layer "B.Fab")
		)
		(fp_line
			(start -0.120396 0.3048)
			(end -0.120396 0.2794)
			(stroke
				(width 0.1)
				(type default)
			)
			(layer "B.Fab")
		)
		(fp_line
			(start -0.67945 0.3048)
			(end -0.120396 0.3048)
			(stroke
				(width 0.1)
				(type default)
			)
			(layer "B.Fab")
		)
		(pad "1" smd circle
			(at 0.40005 0 270)
			(size 0 0)
			(layers "B.Cu" "B.Mask" "B.Paste")
			(net "SPI_BIC1_CLK_R1")
		)
		(pad "2" smd circle
			(at -0.40005 0 270)
			(size 0 0)
			(layers "B.Cu" "B.Mask" "B.Paste")
			(net "SPI_BIC1_CLK_R2")
		)
	)
	(footprint ""
		(layer "B.Cu")
		(at 276.649688 -300.174914)
		(property "Reference" "C3356"
			(at 0 0 0)
			(layer "B.SilkS")
			(hide yes)
			(effects
				(font
					(size 1.27 1.27)
				)
				(justify mirror)
			)
		)
		(property "Value" ""
			(at 0 0 0)
			(layer "B.Fab")
			(effects
				(font
					(size 1.27 1.27)
				)
				(justify mirror)
			)
		)
		(duplicate_pad_numbers_are_jumpers no)
		(fp_line
			(start -0.299974 -0.150114)
			(end -0.299974 0.150114)
			(stroke
				(width 0.1)
				(type default)
			)
			(layer "B.Fab")
		)
		(fp_line
			(start -0.299974 0.150114)
			(end 0.299974 0.150114)
			(stroke
				(width 0.1)
				(type default)
			)
			(layer "B.Fab")
		)
		(fp_line
			(start 0.299974 -0.150114)
			(end -0.299974 -0.150114)
			(stroke
				(width 0.1)
				(type default)
			)
			(layer "B.Fab")
		)
		(fp_line
			(start 0.299974 0.150114)
			(end 0.299974 -0.150114)
			(stroke
				(width 0.1)
				(type default)
			)
			(layer "B.Fab")
		)
		(pad "1" smd rect
			(at 0.2667 0 180)
			(size 0.3048 0.381)
			(layers "B.Cu" "B.Mask" "B.Paste")
			(net "P1V8_VDDA_PEX2")
		)
		(pad "2" smd rect
			(at -0.2667 0 180)
			(size 0.3048 0.381)
			(layers "B.Cu" "B.Mask" "B.Paste")
			(net "GND")
		)
	)
	(footprint ""
		(layer "B.Cu")
		(at 140.183108 -220.932756 90)
		(property "Reference" "R3461"
			(at 0 0 90)
			(layer "B.SilkS")
			(hide yes)
			(effects
				(font
					(size 1.27 1.27)
				)
				(justify mirror)
			)
		)
		(property "Value" ""
			(at 0 0 90)
			(layer "B.Fab")
			(effects
				(font
					(size 1.27 1.27)
				)
				(justify mirror)
			)
		)
		(duplicate_pad_numbers_are_jumpers no)
		(fp_line
			(start 0.7874 -0.4064)
			(end -0.7874 -0.4064)
			(stroke
				(width 0.1524)
				(type default)
			)
			(layer "B.SilkS")
		)
		(fp_line
			(start -0.7874 -0.4064)
			(end -0.7874 0.4064)
			(stroke
				(width 0.1524)
				(type default)
			)
			(layer "B.SilkS")
		)
		(fp_line
			(start 0.7874 0.4064)
			(end 0.7874 -0.4064)
			(stroke
				(width 0.1524)
				(type default)
			)
			(layer "B.SilkS")
		)
		(fp_line
			(start -0.7874 0.4064)
			(end 0.7874 0.4064)
			(stroke
				(width 0.1524)
				(type default)
			)
			(layer "B.SilkS")
		)
		(fp_line
			(start 0.67945 -0.305054)
			(end 0.12065 -0.305054)
			(stroke
				(width 0.1)
				(type default)
			)
			(layer "B.Fab")
		)
		(fp_line
			(start 0.12065 -0.305054)
			(end 0.12065 -0.2794)
			(stroke
				(width 0.1)
				(type default)
			)
			(layer "B.Fab")
		)
		(fp_line
			(start -0.12065 -0.3048)
			(end -0.67945 -0.3048)
			(stroke
				(width 0.1)
				(type default)
			)
			(layer "B.Fab")
		)
		(fp_line
			(start -0.67945 -0.3048)
			(end -0.67945 0.3048)
			(stroke
				(width 0.1)
				(type default)
			)
			(layer "B.Fab")
		)
		(fp_line
			(start 0.12065 -0.2794)
			(end -0.12065 -0.2794)
			(stroke
				(width 0.1)
				(type default)
			)
			(layer "B.Fab")
		)
		(fp_line
			(start -0.12065 -0.2794)
			(end -0.12065 -0.3048)
			(stroke
				(width 0.1)
				(type default)
			)
			(layer "B.Fab")
		)
		(fp_line
			(start 0.12065 0.2794)
			(end 0.12065 0.3048)
			(stroke
				(width 0.1)
				(type default)
			)
			(layer "B.Fab")
		)
		(fp_line
			(start -0.120396 0.2794)
			(end 0.12065 0.2794)
			(stroke
				(width 0.1)
				(type default)
			)
			(layer "B.Fab")
		)
		(fp_line
			(start 0.67945 0.3048)
			(end 0.67945 -0.305054)
			(stroke
				(width 0.1)
				(type default)
			)
			(layer "B.Fab")
		)
		(fp_line
			(start 0.12065 0.3048)
			(end 0.67945 0.3048)
			(stroke
				(width 0.1)
				(type default)
			)
			(layer "B.Fab")
		)
		(fp_line
			(start -0.120396 0.3048)
			(end -0.120396 0.2794)
			(stroke
				(width 0.1)
				(type default)
			)
			(layer "B.Fab")
		)
		(fp_line
			(start -0.67945 0.3048)
			(end -0.120396 0.3048)
			(stroke
				(width 0.1)
				(type default)
			)
			(layer "B.Fab")
		)
		(pad "1" smd circle
			(at 0.40005 0 270)
			(size 0 0)
			(layers "B.Cu" "B.Mask" "B.Paste")
			(net "SPI_PEX1_SDIO3_R")
		)
		(pad "2" smd circle
			(at -0.40005 0 270)
			(size 0 0)
			(layers "B.Cu" "B.Mask" "B.Paste")
			(net "SPI_PEX1_SDIO3_R1")
		)
	)
	(footprint ""
		(layer "B.Cu")
		(at 404.624794 -286.399732 90)
		(property "Reference" "C3474"
			(at 0 0 90)
			(layer "B.SilkS")
			(hide yes)
			(effects
				(font
					(size 1.27 1.27)
				)
				(justify mirror)
			)
		)
		(property "Value" ""
			(at 0 0 90)
			(layer "B.Fab")
			(effects
				(font
					(size 1.27 1.27)
				)
				(justify mirror)
			)
		)
		(duplicate_pad_numbers_are_jumpers no)
		(fp_line
			(start 0.299974 -0.150114)
			(end -0.299974 -0.150114)
			(stroke
				(width 0.1)
				(type default)
			)
			(layer "B.Fab")
		)
		(fp_line
			(start -0.299974 -0.150114)
			(end -0.299974 0.150114)
			(stroke
				(width 0.1)
				(type default)
			)
			(layer "B.Fab")
		)
		(fp_line
			(start 0.299974 0.150114)
			(end 0.299974 -0.150114)
			(stroke
				(width 0.1)
				(type default)
			)
			(layer "B.Fab")
		)
		(fp_line
			(start -0.299974 0.150114)
			(end 0.299974 0.150114)
			(stroke
				(width 0.1)
				(type default)
			)
			(layer "B.Fab")
		)
		(pad "1" smd rect
			(at 0.2667 0 270)
			(size 0.3048 0.381)
			(layers "B.Cu" "B.Mask" "B.Paste")
			(net "P1V25_SERDES_VDDPLL_PEX3")
		)
		(pad "2" smd rect
			(at -0.2667 0 270)
			(size 0.3048 0.381)
			(layers "B.Cu" "B.Mask" "B.Paste")
			(net "GND")
		)
	)
	(footprint ""
		(layer "B.Cu")
		(at 167.200072 -299.699934 -90)
		(property "Reference" "C1426"
			(at 0 0 90)
			(layer "B.SilkS")
			(hide yes)
			(effects
				(font
					(size 1.27 1.27)
				)
				(justify mirror)
			)
		)
		(property "Value" ""
			(at 0 0 90)
			(layer "B.Fab")
			(effects
				(font
					(size 1.27 1.27)
				)
				(justify mirror)
			)
		)
		(duplicate_pad_numbers_are_jumpers no)
		(fp_line
			(start -0.299974 0.150114)
			(end 0.299974 0.150114)
			(stroke
				(width 0.1)
				(type default)
			)
			(layer "B.Fab")
		)
		(fp_line
			(start 0.299974 0.150114)
			(end 0.299974 -0.150114)
			(stroke
				(width 0.1)
				(type default)
			)
			(layer "B.Fab")
		)
		(fp_line
			(start -0.299974 -0.150114)
			(end -0.299974 0.150114)
			(stroke
				(width 0.1)
				(type default)
			)
			(layer "B.Fab")
		)
		(fp_line
			(start 0.299974 -0.150114)
			(end -0.299974 -0.150114)
			(stroke
				(width 0.1)
				(type default)
			)
			(layer "B.Fab")
		)
		(pad "1" smd rect
			(at 0.2667 0 90)
			(size 0.3048 0.381)
			(layers "B.Cu" "B.Mask" "B.Paste")
			(net "P0V8_SERDES_VDDA_PEX1")
		)
		(pad "2" smd rect
			(at -0.2667 0 90)
			(size 0.3048 0.381)
			(layers "B.Cu" "B.Mask" "B.Paste")
			(net "GND")
		)
	)
	(footprint ""
		(layer "B.Cu")
		(at 352.074988 -321.160394 -90)
		(property "Reference" "R6535"
			(at 0 0 90)
			(layer "B.SilkS")
			(hide yes)
			(effects
				(font
					(size 1.27 1.27)
				)
				(justify mirror)
			)
		)
		(property "Value" ""
			(at 0 0 90)
			(layer "B.Fab")
			(effects
				(font
					(size 1.27 1.27)
				)
				(justify mirror)
			)
		)
		(duplicate_pad_numbers_are_jumpers no)
		(fp_line
			(start -0.7874 0.4064)
			(end 0.7874 0.4064)
			(stroke
				(width 0.1524)
				(type default)
			)
			(layer "B.SilkS")
		)
		(fp_line
			(start 0.7874 0.4064)
			(end 0.7874 -0.4064)
			(stroke
				(width 0.1524)
				(type default)
			)
			(layer "B.SilkS")
		)
		(fp_line
			(start -0.7874 -0.4064)
			(end -0.7874 0.4064)
			(stroke
				(width 0.1524)
				(type default)
			)
			(layer "B.SilkS")
		)
		(fp_line
			(start 0.7874 -0.4064)
			(end -0.7874 -0.4064)
			(stroke
				(width 0.1524)
				(type default)
			)
			(layer "B.SilkS")
		)
		(fp_line
			(start -0.67945 0.3048)
			(end -0.120396 0.3048)
			(stroke
				(width 0.1)
				(type default)
			)
			(layer "B.Fab")
		)
		(fp_line
			(start -0.120396 0.3048)
			(end -0.120396 0.2794)
			(stroke
				(width 0.1)
				(type default)
			)
			(layer "B.Fab")
		)
		(fp_line
			(start 0.12065 0.3048)
			(end 0.67945 0.3048)
			(stroke
				(width 0.1)
				(type default)
			)
			(layer "B.Fab")
		)
		(fp_line
			(start 0.67945 0.3048)
			(end 0.67945 -0.305054)
			(stroke
				(width 0.1)
				(type default)
			)
			(layer "B.Fab")
		)
		(fp_line
			(start -0.120396 0.2794)
			(end 0.12065 0.2794)
			(stroke
				(width 0.1)
				(type default)
			)
			(layer "B.Fab")
		)
		(fp_line
			(start 0.12065 0.2794)
			(end 0.12065 0.3048)
			(stroke
				(width 0.1)
				(type default)
			)
			(layer "B.Fab")
		)
		(fp_line
			(start -0.12065 -0.2794)
			(end -0.12065 -0.3048)
			(stroke
				(width 0.1)
				(type default)
			)
			(layer "B.Fab")
		)
		(fp_line
			(start 0.12065 -0.2794)
			(end -0.12065 -0.2794)
			(stroke
				(width 0.1)
				(type default)
			)
			(layer "B.Fab")
		)
		(fp_line
			(start -0.67945 -0.3048)
			(end -0.67945 0.3048)
			(stroke
				(width 0.1)
				(type default)
			)
			(layer "B.Fab")
		)
		(fp_line
			(start -0.12065 -0.3048)
			(end -0.67945 -0.3048)
			(stroke
				(width 0.1)
				(type default)
			)
			(layer "B.Fab")
		)
		(fp_line
			(start 0.12065 -0.305054)
			(end 0.12065 -0.2794)
			(stroke
				(width 0.1)
				(type default)
			)
			(layer "B.Fab")
		)
		(fp_line
			(start 0.67945 -0.305054)
			(end 0.12065 -0.305054)
			(stroke
				(width 0.1)
				(type default)
			)
			(layer "B.Fab")
		)
		(pad "1" smd circle
			(at 0.40005 0 90)
			(size 0 0)
			(layers "B.Cu" "B.Mask" "B.Paste")
			(net "P0V8_SERDES_VDDA_PEX3")
		)
		(pad "2" smd circle
			(at -0.40005 0 90)
			(size 0 0)
			(layers "B.Cu" "B.Mask" "B.Paste")
			(net "P0V8_SERDES_VDDA_PEX3_C0")
		)
	)
	(footprint ""
		(layer "B.Cu")
		(at 255.960626 -242.524788 90)
		(property "Reference" "R6577"
			(at 0 0 90)
			(layer "B.SilkS")
			(hide yes)
			(effects
				(font
					(size 1.27 1.27)
				)
				(justify mirror)
			)
		)
		(property "Value" ""
			(at 0 0 90)
			(layer "B.Fab")
			(effects
				(font
					(size 1.27 1.27)
				)
				(justify mirror)
			)
		)
		(duplicate_pad_numbers_are_jumpers no)
		(fp_line
			(start 0.7874 -0.4064)
			(end -0.7874 -0.4064)
			(stroke
				(width 0.1524)
				(type default)
			)
			(layer "B.SilkS")
		)
		(fp_line
			(start -0.7874 -0.4064)
			(end -0.7874 0.4064)
			(stroke
				(width 0.1524)
				(type default)
			)
			(layer "B.SilkS")
		)
		(fp_line
			(start 0.7874 0.4064)
			(end 0.7874 -0.4064)
			(stroke
				(width 0.1524)
				(type default)
			)
			(layer "B.SilkS")
		)
		(fp_line
			(start -0.7874 0.4064)
			(end 0.7874 0.4064)
			(stroke
				(width 0.1524)
				(type default)
			)
			(layer "B.SilkS")
		)
		(fp_line
			(start 0.67945 -0.305054)
			(end 0.12065 -0.305054)
			(stroke
				(width 0.1)
				(type default)
			)
			(layer "B.Fab")
		)
		(fp_line
			(start 0.12065 -0.305054)
			(end 0.12065 -0.2794)
			(stroke
				(width 0.1)
				(type default)
			)
			(layer "B.Fab")
		)
		(fp_line
			(start -0.12065 -0.3048)
			(end -0.67945 -0.3048)
			(stroke
				(width 0.1)
				(type default)
			)
			(layer "B.Fab")
		)
		(fp_line
			(start -0.67945 -0.3048)
			(end -0.67945 0.3048)
			(stroke
				(width 0.1)
				(type default)
			)
			(layer "B.Fab")
		)
		(fp_line
			(start 0.12065 -0.2794)
			(end -0.12065 -0.2794)
			(stroke
				(width 0.1)
				(type default)
			)
			(layer "B.Fab")
		)
		(fp_line
			(start -0.12065 -0.2794)
			(end -0.12065 -0.3048)
			(stroke
				(width 0.1)
				(type default)
			)
			(layer "B.Fab")
		)
		(fp_line
			(start 0.12065 0.2794)
			(end 0.12065 0.3048)
			(stroke
				(width 0.1)
				(type default)
			)
			(layer "B.Fab")
		)
		(fp_line
			(start -0.120396 0.2794)
			(end 0.12065 0.2794)
			(stroke
				(width 0.1)
				(type default)
			)
			(layer "B.Fab")
		)
		(fp_line
			(start 0.67945 0.3048)
			(end 0.67945 -0.305054)
			(stroke
				(width 0.1)
				(type default)
			)
			(layer "B.Fab")
		)
		(fp_line
			(start 0.12065 0.3048)
			(end 0.67945 0.3048)
			(stroke
				(width 0.1)
				(type default)
			)
			(layer "B.Fab")
		)
		(fp_line
			(start -0.120396 0.3048)
			(end -0.120396 0.2794)
			(stroke
				(width 0.1)
				(type default)
			)
			(layer "B.Fab")
		)
		(fp_line
			(start -0.67945 0.3048)
			(end -0.120396 0.3048)
			(stroke
				(width 0.1)
				(type default)
			)
			(layer "B.Fab")
		)
		(pad "1" smd circle
			(at 0.40005 0 270)
			(size 0 0)
			(layers "B.Cu" "B.Mask" "B.Paste")
			(net "P3V3_AUX")
		)
		(pad "2" smd circle
			(at -0.40005 0 270)
			(size 0 0)
			(layers "B.Cu" "B.Mask" "B.Paste")
			(net "PEX2_P1V8_PLL_EN")
		)
	)
	(footprint ""
		(layer "B.Cu")
		(at 234.732322 -90.523314 -90)
		(property "Reference" "C2620"
			(at 0 0 90)
			(layer "B.SilkS")
			(hide yes)
			(effects
				(font
					(size 1.27 1.27)
				)
				(justify mirror)
			)
		)
		(property "Value" ""
			(at 0 0 90)
			(layer "B.Fab")
			(effects
				(font
					(size 1.27 1.27)
				)
				(justify mirror)
			)
		)
		(duplicate_pad_numbers_are_jumpers no)
		(fp_line
			(start -0.7874 0.4064)
			(end 0.7874 0.4064)
			(stroke
				(width 0.1524)
				(type default)
			)
			(layer "B.SilkS")
		)
		(fp_line
			(start 0.7874 0.4064)
			(end 0.7874 -0.4064)
			(stroke
				(width 0.1524)
				(type default)
			)
			(layer "B.SilkS")
		)
		(fp_line
			(start -0.7874 -0.4064)
			(end -0.7874 0.4064)
			(stroke
				(width 0.1524)
				(type default)
			)
			(layer "B.SilkS")
		)
		(fp_line
			(start 0.7874 -0.4064)
			(end -0.7874 -0.4064)
			(stroke
				(width 0.1524)
				(type default)
			)
			(layer "B.SilkS")
		)
		(fp_line
			(start -0.67945 0.3048)
			(end -0.120396 0.3048)
			(stroke
				(width 0.1)
				(type default)
			)
			(layer "B.Fab")
		)
		(fp_line
			(start -0.120396 0.3048)
			(end -0.120396 0.2794)
			(stroke
				(width 0.1)
				(type default)
			)
			(layer "B.Fab")
		)
		(fp_line
			(start 0.12065 0.3048)
			(end 0.67945 0.3048)
			(stroke
				(width 0.1)
				(type default)
			)
			(layer "B.Fab")
		)
		(fp_line
			(start 0.67945 0.3048)
			(end 0.67945 -0.305054)
			(stroke
				(width 0.1)
				(type default)
			)
			(layer "B.Fab")
		)
		(fp_line
			(start -0.120396 0.2794)
			(end 0.12065 0.2794)
			(stroke
				(width 0.1)
				(type default)
			)
			(layer "B.Fab")
		)
		(fp_line
			(start 0.12065 0.2794)
			(end 0.12065 0.3048)
			(stroke
				(width 0.1)
				(type default)
			)
			(layer "B.Fab")
		)
		(fp_line
			(start -0.12065 -0.2794)
			(end -0.12065 -0.3048)
			(stroke
				(width 0.1)
				(type default)
			)
			(layer "B.Fab")
		)
		(fp_line
			(start 0.12065 -0.2794)
			(end -0.12065 -0.2794)
			(stroke
				(width 0.1)
				(type default)
			)
			(layer "B.Fab")
		)
		(fp_line
			(start -0.67945 -0.3048)
			(end -0.67945 0.3048)
			(stroke
				(width 0.1)
				(type default)
			)
			(layer "B.Fab")
		)
		(fp_line
			(start -0.12065 -0.3048)
			(end -0.67945 -0.3048)
			(stroke
				(width 0.1)
				(type default)
			)
			(layer "B.Fab")
		)
		(fp_line
			(start 0.12065 -0.305054)
			(end 0.12065 -0.2794)
			(stroke
				(width 0.1)
				(type default)
			)
			(layer "B.Fab")
		)
		(fp_line
			(start 0.67945 -0.305054)
			(end 0.12065 -0.305054)
			(stroke
				(width 0.1)
				(type default)
			)
			(layer "B.Fab")
		)
		(pad "1" smd circle
			(at 0.40005 0 90)
			(size 0 0)
			(layers "B.Cu" "B.Mask" "B.Paste")
			(net "P3V3_PEX_USB_HUB")
		)
		(pad "2" smd circle
			(at -0.40005 0 90)
			(size 0 0)
			(layers "B.Cu" "B.Mask" "B.Paste")
			(net "GND")
		)
	)
	(footprint ""
		(layer "B.Cu")
		(at 298.976542 -293.99992 90)
		(property "Reference" "C1673"
			(at 0 0 90)
			(layer "B.SilkS")
			(hide yes)
			(effects
				(font
					(size 1.27 1.27)
				)
				(justify mirror)
			)
		)
		(property "Value" ""
			(at 0 0 90)
			(layer "B.Fab")
			(effects
				(font
					(size 1.27 1.27)
				)
				(justify mirror)
			)
		)
		(duplicate_pad_numbers_are_jumpers no)
		(fp_line
			(start 0.299974 -0.150114)
			(end -0.299974 -0.150114)
			(stroke
				(width 0.1)
				(type default)
			)
			(layer "B.Fab")
		)
		(fp_line
			(start -0.299974 -0.150114)
			(end -0.299974 0.150114)
			(stroke
				(width 0.1)
				(type default)
			)
			(layer "B.Fab")
		)
		(fp_line
			(start 0.299974 0.150114)
			(end 0.299974 -0.150114)
			(stroke
				(width 0.1)
				(type default)
			)
			(layer "B.Fab")
		)
		(fp_line
			(start -0.299974 0.150114)
			(end 0.299974 0.150114)
			(stroke
				(width 0.1)
				(type default)
			)
			(layer "B.Fab")
		)
		(pad "1" smd rect
			(at 0.2667 0 270)
			(size 0.3048 0.381)
			(layers "B.Cu" "B.Mask" "B.Paste")
			(net "P0V8_SERDES_VDDA_PEX2")
		)
		(pad "2" smd rect
			(at -0.2667 0 270)
			(size 0.3048 0.381)
			(layers "B.Cu" "B.Mask" "B.Paste")
			(net "GND")
		)
	)
	(footprint ""
		(layer "B.Cu")
		(at 407.949908 -288.299906 90)
		(property "Reference" "C3453"
			(at 0 0 90)
			(layer "B.SilkS")
			(hide yes)
			(effects
				(font
					(size 1.27 1.27)
				)
				(justify mirror)
			)
		)
		(property "Value" ""
			(at 0 0 90)
			(layer "B.Fab")
			(effects
				(font
					(size 1.27 1.27)
				)
				(justify mirror)
			)
		)
		(duplicate_pad_numbers_are_jumpers no)
		(fp_line
			(start 0.299974 -0.150114)
			(end -0.299974 -0.150114)
			(stroke
				(width 0.1)
				(type default)
			)
			(layer "B.Fab")
		)
		(fp_line
			(start -0.299974 -0.150114)
			(end -0.299974 0.150114)
			(stroke
				(width 0.1)
				(type default)
			)
			(layer "B.Fab")
		)
		(fp_line
			(start 0.299974 0.150114)
			(end 0.299974 -0.150114)
			(stroke
				(width 0.1)
				(type default)
			)
			(layer "B.Fab")
		)
		(fp_line
			(start -0.299974 0.150114)
			(end 0.299974 0.150114)
			(stroke
				(width 0.1)
				(type default)
			)
			(layer "B.Fab")
		)
		(pad "1" smd rect
			(at 0.2667 0 270)
			(size 0.3048 0.381)
			(layers "B.Cu" "B.Mask" "B.Paste")
			(net "P1V25_PEX3")
		)
		(pad "2" smd rect
			(at -0.2667 0 270)
			(size 0.3048 0.381)
			(layers "B.Cu" "B.Mask" "B.Paste")
			(net "GND")
		)
	)
	(footprint ""
		(layer "B.Cu")
		(at 49.1998 -288.774886 180)
		(property "Reference" "C3010"
			(at 0 0 0)
			(layer "B.SilkS")
			(hide yes)
			(effects
				(font
					(size 1.27 1.27)
				)
				(justify mirror)
			)
		)
		(property "Value" ""
			(at 0 0 0)
			(layer "B.Fab")
			(effects
				(font
					(size 1.27 1.27)
				)
				(justify mirror)
			)
		)
		(duplicate_pad_numbers_are_jumpers no)
		(fp_line
			(start 0.299974 0.150114)
			(end 0.299974 -0.150114)
			(stroke
				(width 0.1)
				(type default)
			)
			(layer "B.Fab")
		)
		(fp_line
			(start 0.299974 -0.150114)
			(end -0.299974 -0.150114)
			(stroke
				(width 0.1)
				(type default)
			)
			(layer "B.Fab")
		)
		(fp_line
			(start -0.299974 0.150114)
			(end 0.299974 0.150114)
			(stroke
				(width 0.1)
				(type default)
			)
			(layer "B.Fab")
		)
		(fp_line
			(start -0.299974 -0.150114)
			(end -0.299974 0.150114)
			(stroke
				(width 0.1)
				(type default)
			)
			(layer "B.Fab")
		)
		(pad "1" smd rect
			(at 0.2667 0)
			(size 0.3048 0.381)
			(layers "B.Cu" "B.Mask" "B.Paste")
			(net "P1V8_VDDA_PEX0")
		)
		(pad "2" smd rect
			(at -0.2667 0)
			(size 0.3048 0.381)
			(layers "B.Cu" "B.Mask" "B.Paste")
			(net "GND")
		)
	)
	(footprint ""
		(layer "B.Cu")
		(at 42.963846 -285.853632)
		(property "Reference" "C2990"
			(at 0 0 0)
			(layer "B.SilkS")
			(hide yes)
			(effects
				(font
					(size 1.27 1.27)
				)
				(justify mirror)
			)
		)
		(property "Value" ""
			(at 0 0 0)
			(layer "B.Fab")
			(effects
				(font
					(size 1.27 1.27)
				)
				(justify mirror)
			)
		)
		(duplicate_pad_numbers_are_jumpers no)
		(fp_line
			(start -1.2954 -0.5842)
			(end -1.2954 0.5842)
			(stroke
				(width 0.1524)
				(type default)
			)
			(layer "B.SilkS")
		)
		(fp_line
			(start -1.2954 0.5842)
			(end 1.2954 0.5842)
			(stroke
				(width 0.1524)
				(type default)
			)
			(layer "B.SilkS")
		)
		(fp_line
			(start 1.2954 -0.5842)
			(end -1.2954 -0.5842)
			(stroke
				(width 0.1524)
				(type default)
			)
			(layer "B.SilkS")
		)
		(fp_line
			(start 1.2954 0.5842)
			(end 1.2954 -0.5842)
			(stroke
				(width 0.1524)
				(type default)
			)
			(layer "B.SilkS")
		)
		(fp_line
			(start -1.1938 -0.4064)
			(end -1.1938 0.4064)
			(stroke
				(width 0.1)
				(type default)
			)
			(layer "B.Fab")
		)
		(fp_line
			(start -1.1938 0.4064)
			(end -0.8636 0.4064)
			(stroke
				(width 0.1)
				(type default)
			)
			(layer "B.Fab")
		)
		(fp_line
			(start -0.8636 -0.4572)
			(end -0.8636 -0.4064)
			(stroke
				(width 0.1)
				(type default)
			)
			(layer "B.Fab")
		)
		(fp_line
			(start -0.8636 -0.4064)
			(end -1.1938 -0.4064)
			(stroke
				(width 0.1)
				(type default)
			)
			(layer "B.Fab")
		)
		(fp_line
			(start -0.8636 0.4064)
			(end -0.8636 0.4572)
			(stroke
				(width 0.1)
				(type default)
			)
			(layer "B.Fab")
		)
		(fp_line
			(start -0.8636 0.4572)
			(end 0.8636 0.4572)
			(stroke
				(width 0.1)
				(type default)
			)
			(layer "B.Fab")
		)
		(fp_line
			(start 0.8636 -0.4572)
			(end -0.8636 -0.4572)
			(stroke
				(width 0.1)
				(type default)
			)
			(layer "B.Fab")
		)
		(fp_line
			(start 0.8636 -0.4064)
			(end 0.8636 -0.4572)
			(stroke
				(width 0.1)
				(type default)
			)
			(layer "B.Fab")
		)
		(fp_line
			(start 0.8636 0.4064)
			(end 1.1938 0.4064)
			(stroke
				(width 0.1)
				(type default)
			)
			(layer "B.Fab")
		)
		(fp_line
			(start 0.8636 0.4572)
			(end 0.8636 0.4064)
			(stroke
				(width 0.1)
				(type default)
			)
			(layer "B.Fab")
		)
		(fp_line
			(start 1.1938 -0.4064)
			(end 0.8636 -0.4064)
			(stroke
				(width 0.1)
				(type default)
			)
			(layer "B.Fab")
		)
		(fp_line
			(start 1.1938 0.4064)
			(end 1.1938 -0.4064)
			(stroke
				(width 0.1)
				(type default)
			)
			(layer "B.Fab")
		)
		(pad "1" smd rect
			(at 0.7366 0 270)
			(size 0.7112 0.8128)
			(layers "B.Cu" "B.Mask" "B.Paste")
			(net "P1V8_PEX")
		)
		(pad "2" smd rect
			(at -0.7366 0 270)
			(size 0.7112 0.8128)
			(layers "B.Cu" "B.Mask" "B.Paste")
			(net "GND")
		)
	)
	(footprint ""
		(layer "B.Cu")
		(at 217.659458 -278.05761)
		(property "Reference" "C4291"
			(at 0 0 0)
			(layer "B.SilkS")
			(hide yes)
			(effects
				(font
					(size 1.27 1.27)
				)
				(justify mirror)
			)
		)
		(property "Value" ""
			(at 0 0 0)
			(layer "B.Fab")
			(effects
				(font
					(size 1.27 1.27)
				)
				(justify mirror)
			)
		)
		(duplicate_pad_numbers_are_jumpers no)
		(fp_line
			(start -1.2954 -0.5842)
			(end -1.2954 0.5842)
			(stroke
				(width 0.1524)
				(type default)
			)
			(layer "B.SilkS")
		)
		(fp_line
			(start -1.2954 0.5842)
			(end 1.2954 0.5842)
			(stroke
				(width 0.1524)
				(type default)
			)
			(layer "B.SilkS")
		)
		(fp_line
			(start 1.2954 -0.5842)
			(end -1.2954 -0.5842)
			(stroke
				(width 0.1524)
				(type default)
			)
			(layer "B.SilkS")
		)
		(fp_line
			(start 1.2954 0.5842)
			(end 1.2954 -0.5842)
			(stroke
				(width 0.1524)
				(type default)
			)
			(layer "B.SilkS")
		)
		(fp_line
			(start -1.1938 -0.4064)
			(end -1.1938 0.4064)
			(stroke
				(width 0.1)
				(type default)
			)
			(layer "B.Fab")
		)
		(fp_line
			(start -1.1938 0.4064)
			(end -0.8636 0.4064)
			(stroke
				(width 0.1)
				(type default)
			)
			(layer "B.Fab")
		)
		(fp_line
			(start -0.8636 -0.4572)
			(end -0.8636 -0.4064)
			(stroke
				(width 0.1)
				(type default)
			)
			(layer "B.Fab")
		)
		(fp_line
			(start -0.8636 -0.4064)
			(end -1.1938 -0.4064)
			(stroke
				(width 0.1)
				(type default)
			)
			(layer "B.Fab")
		)
		(fp_line
			(start -0.8636 0.4064)
			(end -0.8636 0.4572)
			(stroke
				(width 0.1)
				(type default)
			)
			(layer "B.Fab")
		)
		(fp_line
			(start -0.8636 0.4572)
			(end 0.8636 0.4572)
			(stroke
				(width 0.1)
				(type default)
			)
			(layer "B.Fab")
		)
		(fp_line
			(start 0.8636 -0.4572)
			(end -0.8636 -0.4572)
			(stroke
				(width 0.1)
				(type default)
			)
			(layer "B.Fab")
		)
		(fp_line
			(start 0.8636 -0.4064)
			(end 0.8636 -0.4572)
			(stroke
				(width 0.1)
				(type default)
			)
			(layer "B.Fab")
		)
		(fp_line
			(start 0.8636 0.4064)
			(end 1.1938 0.4064)
			(stroke
				(width 0.1)
				(type default)
			)
			(layer "B.Fab")
		)
		(fp_line
			(start 0.8636 0.4572)
			(end 0.8636 0.4064)
			(stroke
				(width 0.1)
				(type default)
			)
			(layer "B.Fab")
		)
		(fp_line
			(start 1.1938 -0.4064)
			(end 0.8636 -0.4064)
			(stroke
				(width 0.1)
				(type default)
			)
			(layer "B.Fab")
		)
		(fp_line
			(start 1.1938 0.4064)
			(end 1.1938 -0.4064)
			(stroke
				(width 0.1)
				(type default)
			)
			(layer "B.Fab")
		)
		(pad "1" smd rect
			(at 0.7366 0 270)
			(size 0.7112 0.8128)
			(layers "B.Cu" "B.Mask" "B.Paste")
			(net "P1V25_PEX1")
		)
		(pad "2" smd rect
			(at -0.7366 0 270)
			(size 0.7112 0.8128)
			(layers "B.Cu" "B.Mask" "B.Paste")
			(net "GND")
		)
	)
	(footprint ""
		(layer "B.Cu")
		(at 177.42027 -199.303386)
		(property "Reference" "R1033"
			(at 0 0 0)
			(layer "B.SilkS")
			(hide yes)
			(effects
				(font
					(size 1.27 1.27)
				)
				(justify mirror)
			)
		)
		(property "Value" ""
			(at 0 0 0)
			(layer "B.Fab")
			(effects
				(font
					(size 1.27 1.27)
				)
				(justify mirror)
			)
		)
		(duplicate_pad_numbers_are_jumpers no)
		(fp_line
			(start -0.7874 -0.4064)
			(end -0.7874 0.4064)
			(stroke
				(width 0.1524)
				(type default)
			)
			(layer "B.SilkS")
		)
		(fp_line
			(start -0.7874 0.4064)
			(end 0.7874 0.4064)
			(stroke
				(width 0.1524)
				(type default)
			)
			(layer "B.SilkS")
		)
		(fp_line
			(start 0.7874 -0.4064)
			(end -0.7874 -0.4064)
			(stroke
				(width 0.1524)
				(type default)
			)
			(layer "B.SilkS")
		)
		(fp_line
			(start 0.7874 0.4064)
			(end 0.7874 -0.4064)
			(stroke
				(width 0.1524)
				(type default)
			)
			(layer "B.SilkS")
		)
		(fp_line
			(start -0.67945 -0.3048)
			(end -0.67945 0.3048)
			(stroke
				(width 0.1)
				(type default)
			)
			(layer "B.Fab")
		)
		(fp_line
			(start -0.67945 0.3048)
			(end -0.120396 0.3048)
			(stroke
				(width 0.1)
				(type default)
			)
			(layer "B.Fab")
		)
		(fp_line
			(start -0.12065 -0.3048)
			(end -0.67945 -0.3048)
			(stroke
				(width 0.1)
				(type default)
			)
			(layer "B.Fab")
		)
		(fp_line
			(start -0.12065 -0.2794)
			(end -0.12065 -0.3048)
			(stroke
				(width 0.1)
				(type default)
			)
			(layer "B.Fab")
		)
		(fp_line
			(start -0.120396 0.2794)
			(end 0.12065 0.2794)
			(stroke
				(width 0.1)
				(type default)
			)
			(layer "B.Fab")
		)
		(fp_line
			(start -0.120396 0.3048)
			(end -0.120396 0.2794)
			(stroke
				(width 0.1)
				(type default)
			)
			(layer "B.Fab")
		)
		(fp_line
			(start 0.12065 -0.305054)
			(end 0.12065 -0.2794)
			(stroke
				(width 0.1)
				(type default)
			)
			(layer "B.Fab")
		)
		(fp_line
			(start 0.12065 -0.2794)
			(end -0.12065 -0.2794)
			(stroke
				(width 0.1)
				(type default)
			)
			(layer "B.Fab")
		)
		(fp_line
			(start 0.12065 0.2794)
			(end 0.12065 0.3048)
			(stroke
				(width 0.1)
				(type default)
			)
			(layer "B.Fab")
		)
		(fp_line
			(start 0.12065 0.3048)
			(end 0.67945 0.3048)
			(stroke
				(width 0.1)
				(type default)
			)
			(layer "B.Fab")
		)
		(fp_line
			(start 0.67945 -0.305054)
			(end 0.12065 -0.305054)
			(stroke
				(width 0.1)
				(type default)
			)
			(layer "B.Fab")
		)
		(fp_line
			(start 0.67945 0.3048)
			(end 0.67945 -0.305054)
			(stroke
				(width 0.1)
				(type default)
			)
			(layer "B.Fab")
		)
		(pad "1" smd circle
			(at 0.40005 0 180)
			(size 0 0)
			(layers "B.Cu" "B.Mask" "B.Paste")
			(net "GND")
		)
		(pad "2" smd circle
			(at -0.40005 0 180)
			(size 0 0)
			(layers "B.Cu" "B.Mask" "B.Paste")
			(net "SPI_BIC1_CS0_LS01_N_DIR1")
		)
	)
	(footprint ""
		(layer "B.Cu")
		(at 342.493854 -226.387152)
		(property "Reference" "C2028"
			(at 0 0 0)
			(layer "B.SilkS")
			(hide yes)
			(effects
				(font
					(size 1.27 1.27)
				)
				(justify mirror)
			)
		)
		(property "Value" ""
			(at 0 0 0)
			(layer "B.Fab")
			(effects
				(font
					(size 1.27 1.27)
				)
				(justify mirror)
			)
		)
		(duplicate_pad_numbers_are_jumpers no)
		(fp_line
			(start -0.69215 -0.2921)
			(end -0.69215 0.2921)
			(stroke
				(width 0.1524)
				(type default)
			)
			(layer "B.SilkS")
		)
		(fp_line
			(start -0.69215 0.2921)
			(end 0.69215 0.2921)
			(stroke
				(width 0.1524)
				(type default)
			)
			(layer "B.SilkS")
		)
		(fp_line
			(start 0.69215 -0.2921)
			(end -0.69215 -0.2921)
			(stroke
				(width 0.1524)
				(type default)
			)
			(layer "B.SilkS")
		)
		(fp_line
			(start 0.69215 0.2921)
			(end 0.69215 -0.2921)
			(stroke
				(width 0.1524)
				(type default)
			)
			(layer "B.SilkS")
		)
		(fp_line
			(start -0.51435 -0.2794)
			(end -0.51435 0.2794)
			(stroke
				(width 0.1)
				(type default)
			)
			(layer "B.Fab")
		)
		(fp_line
			(start -0.51435 0.2794)
			(end 0.51435 0.2794)
			(stroke
				(width 0.1)
				(type default)
			)
			(layer "B.Fab")
		)
		(fp_line
			(start 0.51435 -0.2794)
			(end -0.51435 -0.2794)
			(stroke
				(width 0.1)
				(type default)
			)
			(layer "B.Fab")
		)
		(fp_line
			(start 0.51435 0.2794)
			(end 0.51435 -0.2794)
			(stroke
				(width 0.1)
				(type default)
			)
			(layer "B.Fab")
		)
		(pad "1" smd circle
			(at 0.40005 0 180)
			(size 0 0)
			(layers "B.Cu" "B.Mask" "B.Paste")
			(net "P3V3_FPGA_VCCIO0")
		)
		(pad "2" smd circle
			(at -0.40005 0 180)
			(size 0 0)
			(layers "B.Cu" "B.Mask" "B.Paste")
			(net "GND")
		)
		(zone
			(layer "B.Cu")
			(hatch none 0.5)
			(connect_pads
				(clearance 0)
			)
			(min_thickness 0.25)
			(keepout
				(tracks not_allowed)
				(vias allowed)
				(pads allowed)
				(copperpour not_allowed)
				(footprints allowed)
			)
			(placement
				(enabled no)
				(sheetname "")
			)
			(fill
				(thermal_gap 0.5)
				(thermal_bridge_width 0.5)
				(island_removal_mode 0)
			)
			(polygon
				(pts
					(xy 342.684354 -226.299522) (xy 342.592914 -226.241356) (xy 342.393524 -226.241356) (xy 342.303354 -226.299522)
					(xy 342.303354 -226.474782) (xy 342.393524 -226.533202) (xy 342.592914 -226.533202) (xy 342.684354 -226.475036)
				)
			)
		)
	)
	(footprint ""
		(layer "B.Cu")
		(at 413.174942 -286.399732 90)
		(property "Reference" "C3504"
			(at 0 0 90)
			(layer "B.SilkS")
			(hide yes)
			(effects
				(font
					(size 1.27 1.27)
				)
				(justify mirror)
			)
		)
		(property "Value" ""
			(at 0 0 90)
			(layer "B.Fab")
			(effects
				(font
					(size 1.27 1.27)
				)
				(justify mirror)
			)
		)
		(duplicate_pad_numbers_are_jumpers no)
		(fp_line
			(start 0.299974 -0.150114)
			(end -0.299974 -0.150114)
			(stroke
				(width 0.1)
				(type default)
			)
			(layer "B.Fab")
		)
		(fp_line
			(start -0.299974 -0.150114)
			(end -0.299974 0.150114)
			(stroke
				(width 0.1)
				(type default)
			)
			(layer "B.Fab")
		)
		(fp_line
			(start 0.299974 0.150114)
			(end 0.299974 -0.150114)
			(stroke
				(width 0.1)
				(type default)
			)
			(layer "B.Fab")
		)
		(fp_line
			(start -0.299974 0.150114)
			(end 0.299974 0.150114)
			(stroke
				(width 0.1)
				(type default)
			)
			(layer "B.Fab")
		)
		(pad "1" smd rect
			(at 0.2667 0 270)
			(size 0.3048 0.381)
			(layers "B.Cu" "B.Mask" "B.Paste")
			(net "P1V25_SERDES_VDDPLL_PEX3")
		)
		(pad "2" smd rect
			(at -0.2667 0 270)
			(size 0.3048 0.381)
			(layers "B.Cu" "B.Mask" "B.Paste")
			(net "GND")
		)
	)
	(footprint ""
		(layer "B.Cu")
		(at 168.150032 -299.699934 -90)
		(property "Reference" "C1432"
			(at 0 0 90)
			(layer "B.SilkS")
			(hide yes)
			(effects
				(font
					(size 1.27 1.27)
				)
				(justify mirror)
			)
		)
		(property "Value" ""
			(at 0 0 90)
			(layer "B.Fab")
			(effects
				(font
					(size 1.27 1.27)
				)
				(justify mirror)
			)
		)
		(duplicate_pad_numbers_are_jumpers no)
		(fp_line
			(start -0.299974 0.150114)
			(end 0.299974 0.150114)
			(stroke
				(width 0.1)
				(type default)
			)
			(layer "B.Fab")
		)
		(fp_line
			(start 0.299974 0.150114)
			(end 0.299974 -0.150114)
			(stroke
				(width 0.1)
				(type default)
			)
			(layer "B.Fab")
		)
		(fp_line
			(start -0.299974 -0.150114)
			(end -0.299974 0.150114)
			(stroke
				(width 0.1)
				(type default)
			)
			(layer "B.Fab")
		)
		(fp_line
			(start 0.299974 -0.150114)
			(end -0.299974 -0.150114)
			(stroke
				(width 0.1)
				(type default)
			)
			(layer "B.Fab")
		)
		(pad "1" smd rect
			(at 0.2667 0 90)
			(size 0.3048 0.381)
			(layers "B.Cu" "B.Mask" "B.Paste")
			(net "P0V8_SERDES_VDDA_PEX1")
		)
		(pad "2" smd rect
			(at -0.2667 0 90)
			(size 0.3048 0.381)
			(layers "B.Cu" "B.Mask" "B.Paste")
			(net "GND")
		)
	)
	(footprint ""
		(layer "B.Cu")
		(at 193.641726 -102.088696 180)
		(property "Reference" "R170"
			(at 0 0 0)
			(layer "B.SilkS")
			(hide yes)
			(effects
				(font
					(size 1.27 1.27)
				)
				(justify mirror)
			)
		)
		(property "Value" ""
			(at 0 0 0)
			(layer "B.Fab")
			(effects
				(font
					(size 1.27 1.27)
				)
				(justify mirror)
			)
		)
		(duplicate_pad_numbers_are_jumpers no)
		(fp_line
			(start 0.7874 0.4064)
			(end 0.7874 -0.4064)
			(stroke
				(width 0.1524)
				(type default)
			)
			(layer "B.SilkS")
		)
		(fp_line
			(start 0.7874 -0.4064)
			(end -0.7874 -0.4064)
			(stroke
				(width 0.1524)
				(type default)
			)
			(layer "B.SilkS")
		)
		(fp_line
			(start -0.7874 0.4064)
			(end 0.7874 0.4064)
			(stroke
				(width 0.1524)
				(type default)
			)
			(layer "B.SilkS")
		)
		(fp_line
			(start -0.7874 -0.4064)
			(end -0.7874 0.4064)
			(stroke
				(width 0.1524)
				(type default)
			)
			(layer "B.SilkS")
		)
		(fp_line
			(start 0.67945 0.3048)
			(end 0.67945 -0.305054)
			(stroke
				(width 0.1)
				(type default)
			)
			(layer "B.Fab")
		)
		(fp_line
			(start 0.67945 -0.305054)
			(end 0.12065 -0.305054)
			(stroke
				(width 0.1)
				(type default)
			)
			(layer "B.Fab")
		)
		(fp_line
			(start 0.12065 0.3048)
			(end 0.67945 0.3048)
			(stroke
				(width 0.1)
				(type default)
			)
			(layer "B.Fab")
		)
		(fp_line
			(start 0.12065 0.2794)
			(end 0.12065 0.3048)
			(stroke
				(width 0.1)
				(type default)
			)
			(layer "B.Fab")
		)
		(fp_line
			(start 0.12065 -0.2794)
			(end -0.12065 -0.2794)
			(stroke
				(width 0.1)
				(type default)
			)
			(layer "B.Fab")
		)
		(fp_line
			(start 0.12065 -0.305054)
			(end 0.12065 -0.2794)
			(stroke
				(width 0.1)
				(type default)
			)
			(layer "B.Fab")
		)
		(fp_line
			(start -0.120396 0.3048)
			(end -0.120396 0.2794)
			(stroke
				(width 0.1)
				(type default)
			)
			(layer "B.Fab")
		)
		(fp_line
			(start -0.120396 0.2794)
			(end 0.12065 0.2794)
			(stroke
				(width 0.1)
				(type default)
			)
			(layer "B.Fab")
		)
		(fp_line
			(start -0.12065 -0.2794)
			(end -0.12065 -0.3048)
			(stroke
				(width 0.1)
				(type default)
			)
			(layer "B.Fab")
		)
		(fp_line
			(start -0.12065 -0.3048)
			(end -0.67945 -0.3048)
			(stroke
				(width 0.1)
				(type default)
			)
			(layer "B.Fab")
		)
		(fp_line
			(start -0.67945 0.3048)
			(end -0.120396 0.3048)
			(stroke
				(width 0.1)
				(type default)
			)
			(layer "B.Fab")
		)
		(fp_line
			(start -0.67945 -0.3048)
			(end -0.67945 0.3048)
			(stroke
				(width 0.1)
				(type default)
			)
			(layer "B.Fab")
		)
		(pad "1" smd circle
			(at 0.40005 0)
			(size 0 0)
			(layers "B.Cu" "B.Mask" "B.Paste")
			(net "NCSI_NIC3_RXD1")
		)
		(pad "2" smd circle
			(at -0.40005 0)
			(size 0 0)
			(layers "B.Cu" "B.Mask" "B.Paste")
			(net "GND")
		)
	)
	(footprint ""
		(layer "B.Cu")
		(at 62.024768 -297.79976 90)
		(property "Reference" "C1115"
			(at 0 0 90)
			(layer "B.SilkS")
			(hide yes)
			(effects
				(font
					(size 1.27 1.27)
				)
				(justify mirror)
			)
		)
		(property "Value" ""
			(at 0 0 90)
			(layer "B.Fab")
			(effects
				(font
					(size 1.27 1.27)
				)
				(justify mirror)
			)
		)
		(duplicate_pad_numbers_are_jumpers no)
		(fp_line
			(start 0.299974 -0.150114)
			(end -0.299974 -0.150114)
			(stroke
				(width 0.1)
				(type default)
			)
			(layer "B.Fab")
		)
		(fp_line
			(start -0.299974 -0.150114)
			(end -0.299974 0.150114)
			(stroke
				(width 0.1)
				(type default)
			)
			(layer "B.Fab")
		)
		(fp_line
			(start 0.299974 0.150114)
			(end 0.299974 -0.150114)
			(stroke
				(width 0.1)
				(type default)
			)
			(layer "B.Fab")
		)
		(fp_line
			(start -0.299974 0.150114)
			(end 0.299974 0.150114)
			(stroke
				(width 0.1)
				(type default)
			)
			(layer "B.Fab")
		)
		(pad "1" smd rect
			(at 0.2667 0 270)
			(size 0.3048 0.381)
			(layers "B.Cu" "B.Mask" "B.Paste")
			(net "P0V8_PEX0")
		)
		(pad "2" smd rect
			(at -0.2667 0 270)
			(size 0.3048 0.381)
			(layers "B.Cu" "B.Mask" "B.Paste")
			(net "GND")
		)
	)
	(footprint ""
		(layer "B.Cu")
		(at 425.124118 -114.35207 90)
		(property "Reference" "C958"
			(at 0 0 90)
			(layer "B.SilkS")
			(hide yes)
			(effects
				(font
					(size 1.27 1.27)
				)
				(justify mirror)
			)
		)
		(property "Value" ""
			(at 0 0 90)
			(layer "B.Fab")
			(effects
				(font
					(size 1.27 1.27)
				)
				(justify mirror)
			)
		)
		(duplicate_pad_numbers_are_jumpers no)
		(fp_line
			(start 0.7874 -0.4064)
			(end -0.7874 -0.4064)
			(stroke
				(width 0.1524)
				(type default)
			)
			(layer "B.SilkS")
		)
		(fp_line
			(start -0.7874 -0.4064)
			(end -0.7874 0.4064)
			(stroke
				(width 0.1524)
				(type default)
			)
			(layer "B.SilkS")
		)
		(fp_line
			(start 0.7874 0.4064)
			(end 0.7874 -0.4064)
			(stroke
				(width 0.1524)
				(type default)
			)
			(layer "B.SilkS")
		)
		(fp_line
			(start -0.7874 0.4064)
			(end 0.7874 0.4064)
			(stroke
				(width 0.1524)
				(type default)
			)
			(layer "B.SilkS")
		)
		(fp_line
			(start 0.67945 -0.305054)
			(end 0.12065 -0.305054)
			(stroke
				(width 0.1)
				(type default)
			)
			(layer "B.Fab")
		)
		(fp_line
			(start 0.12065 -0.305054)
			(end 0.12065 -0.2794)
			(stroke
				(width 0.1)
				(type default)
			)
			(layer "B.Fab")
		)
		(fp_line
			(start -0.12065 -0.3048)
			(end -0.67945 -0.3048)
			(stroke
				(width 0.1)
				(type default)
			)
			(layer "B.Fab")
		)
		(fp_line
			(start -0.67945 -0.3048)
			(end -0.67945 0.3048)
			(stroke
				(width 0.1)
				(type default)
			)
			(layer "B.Fab")
		)
		(fp_line
			(start 0.12065 -0.2794)
			(end -0.12065 -0.2794)
			(stroke
				(width 0.1)
				(type default)
			)
			(layer "B.Fab")
		)
		(fp_line
			(start -0.12065 -0.2794)
			(end -0.12065 -0.3048)
			(stroke
				(width 0.1)
				(type default)
			)
			(layer "B.Fab")
		)
		(fp_line
			(start 0.12065 0.2794)
			(end 0.12065 0.3048)
			(stroke
				(width 0.1)
				(type default)
			)
			(layer "B.Fab")
		)
		(fp_line
			(start -0.120396 0.2794)
			(end 0.12065 0.2794)
			(stroke
				(width 0.1)
				(type default)
			)
			(layer "B.Fab")
		)
		(fp_line
			(start 0.67945 0.3048)
			(end 0.67945 -0.305054)
			(stroke
				(width 0.1)
				(type default)
			)
			(layer "B.Fab")
		)
		(fp_line
			(start 0.12065 0.3048)
			(end 0.67945 0.3048)
			(stroke
				(width 0.1)
				(type default)
			)
			(layer "B.Fab")
		)
		(fp_line
			(start -0.120396 0.3048)
			(end -0.120396 0.2794)
			(stroke
				(width 0.1)
				(type default)
			)
			(layer "B.Fab")
		)
		(fp_line
			(start -0.67945 0.3048)
			(end -0.120396 0.3048)
			(stroke
				(width 0.1)
				(type default)
			)
			(layer "B.Fab")
		)
		(pad "1" smd circle
			(at 0.40005 0 270)
			(size 0 0)
			(layers "B.Cu" "B.Mask" "B.Paste")
			(net "P3V3_NIC7")
		)
		(pad "2" smd circle
			(at -0.40005 0 270)
			(size 0 0)
			(layers "B.Cu" "B.Mask" "B.Paste")
			(net "GND")
		)
	)
	(footprint ""
		(layer "B.Cu")
		(at 288.99993 -299.699934 -90)
		(property "Reference" "C1709"
			(at 0 0 90)
			(layer "B.SilkS")
			(hide yes)
			(effects
				(font
					(size 1.27 1.27)
				)
				(justify mirror)
			)
		)
		(property "Value" ""
			(at 0 0 90)
			(layer "B.Fab")
			(effects
				(font
					(size 1.27 1.27)
				)
				(justify mirror)
			)
		)
		(duplicate_pad_numbers_are_jumpers no)
		(fp_line
			(start -0.299974 0.150114)
			(end 0.299974 0.150114)
			(stroke
				(width 0.1)
				(type default)
			)
			(layer "B.Fab")
		)
		(fp_line
			(start 0.299974 0.150114)
			(end 0.299974 -0.150114)
			(stroke
				(width 0.1)
				(type default)
			)
			(layer "B.Fab")
		)
		(fp_line
			(start -0.299974 -0.150114)
			(end -0.299974 0.150114)
			(stroke
				(width 0.1)
				(type default)
			)
			(layer "B.Fab")
		)
		(fp_line
			(start 0.299974 -0.150114)
			(end -0.299974 -0.150114)
			(stroke
				(width 0.1)
				(type default)
			)
			(layer "B.Fab")
		)
		(pad "1" smd rect
			(at 0.2667 0 90)
			(size 0.3048 0.381)
			(layers "B.Cu" "B.Mask" "B.Paste")
			(net "P0V8_SERDES_VDDA_PEX2")
		)
		(pad "2" smd rect
			(at -0.2667 0 90)
			(size 0.3048 0.381)
			(layers "B.Cu" "B.Mask" "B.Paste")
			(net "GND")
		)
	)
	(footprint ""
		(layer "B.Cu")
		(at 67.724782 -286.399732 90)
		(property "Reference" "C2953"
			(at 0 0 90)
			(layer "B.SilkS")
			(hide yes)
			(effects
				(font
					(size 1.27 1.27)
				)
				(justify mirror)
			)
		)
		(property "Value" ""
			(at 0 0 90)
			(layer "B.Fab")
			(effects
				(font
					(size 1.27 1.27)
				)
				(justify mirror)
			)
		)
		(duplicate_pad_numbers_are_jumpers no)
		(fp_line
			(start 0.299974 -0.150114)
			(end -0.299974 -0.150114)
			(stroke
				(width 0.1)
				(type default)
			)
			(layer "B.Fab")
		)
		(fp_line
			(start -0.299974 -0.150114)
			(end -0.299974 0.150114)
			(stroke
				(width 0.1)
				(type default)
			)
			(layer "B.Fab")
		)
		(fp_line
			(start 0.299974 0.150114)
			(end 0.299974 -0.150114)
			(stroke
				(width 0.1)
				(type default)
			)
			(layer "B.Fab")
		)
		(fp_line
			(start -0.299974 0.150114)
			(end 0.299974 0.150114)
			(stroke
				(width 0.1)
				(type default)
			)
			(layer "B.Fab")
		)
		(pad "1" smd rect
			(at 0.2667 0 270)
			(size 0.3048 0.381)
			(layers "B.Cu" "B.Mask" "B.Paste")
			(net "P1V25_SERDES_VDDPLL_PEX0")
		)
		(pad "2" smd rect
			(at -0.2667 0 270)
			(size 0.3048 0.381)
			(layers "B.Cu" "B.Mask" "B.Paste")
			(net "GND")
		)
	)
	(footprint ""
		(layer "B.Cu")
		(at 354.500434 -324.941438 -90)
		(property "Reference" "C4381"
			(at 0 0 90)
			(layer "B.SilkS")
			(hide yes)
			(effects
				(font
					(size 1.27 1.27)
				)
				(justify mirror)
			)
		)
		(property "Value" ""
			(at 0 0 90)
			(layer "B.Fab")
			(effects
				(font
					(size 1.27 1.27)
				)
				(justify mirror)
			)
		)
		(duplicate_pad_numbers_are_jumpers no)
		(fp_line
			(start -1.2954 0.5842)
			(end 1.2954 0.5842)
			(stroke
				(width 0.1524)
				(type default)
			)
			(layer "B.SilkS")
		)
		(fp_line
			(start 1.2954 0.5842)
			(end 1.2954 -0.5842)
			(stroke
				(width 0.1524)
				(type default)
			)
			(layer "B.SilkS")
		)
		(fp_line
			(start -1.2954 -0.5842)
			(end -1.2954 0.5842)
			(stroke
				(width 0.1524)
				(type default)
			)
			(layer "B.SilkS")
		)
		(fp_line
			(start 1.2954 -0.5842)
			(end -1.2954 -0.5842)
			(stroke
				(width 0.1524)
				(type default)
			)
			(layer "B.SilkS")
		)
		(fp_line
			(start -0.8636 0.4572)
			(end 0.8636 0.4572)
			(stroke
				(width 0.1)
				(type default)
			)
			(layer "B.Fab")
		)
		(fp_line
			(start 0.8636 0.4572)
			(end 0.8636 0.4064)
			(stroke
				(width 0.1)
				(type default)
			)
			(layer "B.Fab")
		)
		(fp_line
			(start -1.1938 0.4064)
			(end -0.8636 0.4064)
			(stroke
				(width 0.1)
				(type default)
			)
			(layer "B.Fab")
		)
		(fp_line
			(start -0.8636 0.4064)
			(end -0.8636 0.4572)
			(stroke
				(width 0.1)
				(type default)
			)
			(layer "B.Fab")
		)
		(fp_line
			(start 0.8636 0.4064)
			(end 1.1938 0.4064)
			(stroke
				(width 0.1)
				(type default)
			)
			(layer "B.Fab")
		)
		(fp_line
			(start 1.1938 0.4064)
			(end 1.1938 -0.4064)
			(stroke
				(width 0.1)
				(type default)
			)
			(layer "B.Fab")
		)
		(fp_line
			(start -1.1938 -0.4064)
			(end -1.1938 0.4064)
			(stroke
				(width 0.1)
				(type default)
			)
			(layer "B.Fab")
		)
		(fp_line
			(start -0.8636 -0.4064)
			(end -1.1938 -0.4064)
			(stroke
				(width 0.1)
				(type default)
			)
			(layer "B.Fab")
		)
		(fp_line
			(start 0.8636 -0.4064)
			(end 0.8636 -0.4572)
			(stroke
				(width 0.1)
				(type default)
			)
			(layer "B.Fab")
		)
		(fp_line
			(start 1.1938 -0.4064)
			(end 0.8636 -0.4064)
			(stroke
				(width 0.1)
				(type default)
			)
			(layer "B.Fab")
		)
		(fp_line
			(start -0.8636 -0.4572)
			(end -0.8636 -0.4064)
			(stroke
				(width 0.1)
				(type default)
			)
			(layer "B.Fab")
		)
		(fp_line
			(start 0.8636 -0.4572)
			(end -0.8636 -0.4572)
			(stroke
				(width 0.1)
				(type default)
			)
			(layer "B.Fab")
		)
		(pad "1" smd rect
			(at 0.7366 0 180)
			(size 0.7112 0.8128)
			(layers "B.Cu" "B.Mask" "B.Paste")
			(net "P0V8_SERDES_VDDA_PEX3_C7")
		)
		(pad "2" smd rect
			(at -0.7366 0 180)
			(size 0.7112 0.8128)
			(layers "B.Cu" "B.Mask" "B.Paste")
			(net "GND")
		)
	)
	(footprint ""
		(layer "B.Cu")
		(at 113.514124 -330.59243 180)
		(property "Reference" "R1219"
			(at 0 0 0)
			(layer "B.SilkS")
			(hide yes)
			(effects
				(font
					(size 1.27 1.27)
				)
				(justify mirror)
			)
		)
		(property "Value" ""
			(at 0 0 0)
			(layer "B.Fab")
			(effects
				(font
					(size 1.27 1.27)
				)
				(justify mirror)
			)
		)
		(duplicate_pad_numbers_are_jumpers no)
		(fp_line
			(start 0.7874 0.4064)
			(end 0.7874 -0.4064)
			(stroke
				(width 0.1524)
				(type default)
			)
			(layer "B.SilkS")
		)
		(fp_line
			(start 0.7874 -0.4064)
			(end -0.7874 -0.4064)
			(stroke
				(width 0.1524)
				(type default)
			)
			(layer "B.SilkS")
		)
		(fp_line
			(start -0.7874 0.4064)
			(end 0.7874 0.4064)
			(stroke
				(width 0.1524)
				(type default)
			)
			(layer "B.SilkS")
		)
		(fp_line
			(start -0.7874 -0.4064)
			(end -0.7874 0.4064)
			(stroke
				(width 0.1524)
				(type default)
			)
			(layer "B.SilkS")
		)
		(fp_line
			(start 0.67945 0.3048)
			(end 0.67945 -0.305054)
			(stroke
				(width 0.1)
				(type default)
			)
			(layer "B.Fab")
		)
		(fp_line
			(start 0.67945 -0.305054)
			(end 0.12065 -0.305054)
			(stroke
				(width 0.1)
				(type default)
			)
			(layer "B.Fab")
		)
		(fp_line
			(start 0.12065 0.3048)
			(end 0.67945 0.3048)
			(stroke
				(width 0.1)
				(type default)
			)
			(layer "B.Fab")
		)
		(fp_line
			(start 0.12065 0.2794)
			(end 0.12065 0.3048)
			(stroke
				(width 0.1)
				(type default)
			)
			(layer "B.Fab")
		)
		(fp_line
			(start 0.12065 -0.2794)
			(end -0.12065 -0.2794)
			(stroke
				(width 0.1)
				(type default)
			)
			(layer "B.Fab")
		)
		(fp_line
			(start 0.12065 -0.305054)
			(end 0.12065 -0.2794)
			(stroke
				(width 0.1)
				(type default)
			)
			(layer "B.Fab")
		)
		(fp_line
			(start -0.120396 0.3048)
			(end -0.120396 0.2794)
			(stroke
				(width 0.1)
				(type default)
			)
			(layer "B.Fab")
		)
		(fp_line
			(start -0.120396 0.2794)
			(end 0.12065 0.2794)
			(stroke
				(width 0.1)
				(type default)
			)
			(layer "B.Fab")
		)
		(fp_line
			(start -0.12065 -0.2794)
			(end -0.12065 -0.3048)
			(stroke
				(width 0.1)
				(type default)
			)
			(layer "B.Fab")
		)
		(fp_line
			(start -0.12065 -0.3048)
			(end -0.67945 -0.3048)
			(stroke
				(width 0.1)
				(type default)
			)
			(layer "B.Fab")
		)
		(fp_line
			(start -0.67945 0.3048)
			(end -0.120396 0.3048)
			(stroke
				(width 0.1)
				(type default)
			)
			(layer "B.Fab")
		)
		(fp_line
			(start -0.67945 -0.3048)
			(end -0.67945 0.3048)
			(stroke
				(width 0.1)
				(type default)
			)
			(layer "B.Fab")
		)
		(pad "1" smd circle
			(at 0.40005 0)
			(size 0 0)
			(layers "B.Cu" "B.Mask" "B.Paste")
			(net "CLK_100M_MB_0_R_DN")
		)
		(pad "2" smd circle
			(at -0.40005 0)
			(size 0 0)
			(layers "B.Cu" "B.Mask" "B.Paste")
			(net "CLK_100M_MB_0_DN")
		)
	)
	(footprint ""
		(layer "B.Cu")
		(at 204.132942 -259.311648 90)
		(property "Reference" "R6342"
			(at 0 0 90)
			(layer "B.SilkS")
			(hide yes)
			(effects
				(font
					(size 1.27 1.27)
				)
				(justify mirror)
			)
		)
		(property "Value" ""
			(at 0 0 90)
			(layer "B.Fab")
			(effects
				(font
					(size 1.27 1.27)
				)
				(justify mirror)
			)
		)
		(duplicate_pad_numbers_are_jumpers no)
		(fp_line
			(start 0.7874 -0.4064)
			(end -0.7874 -0.4064)
			(stroke
				(width 0.1524)
				(type default)
			)
			(layer "B.SilkS")
		)
		(fp_line
			(start -0.7874 -0.4064)
			(end -0.7874 0.4064)
			(stroke
				(width 0.1524)
				(type default)
			)
			(layer "B.SilkS")
		)
		(fp_line
			(start 0.7874 0.4064)
			(end 0.7874 -0.4064)
			(stroke
				(width 0.1524)
				(type default)
			)
			(layer "B.SilkS")
		)
		(fp_line
			(start -0.7874 0.4064)
			(end 0.7874 0.4064)
			(stroke
				(width 0.1524)
				(type default)
			)
			(layer "B.SilkS")
		)
		(fp_line
			(start 0.67945 -0.305054)
			(end 0.12065 -0.305054)
			(stroke
				(width 0.1)
				(type default)
			)
			(layer "B.Fab")
		)
		(fp_line
			(start 0.12065 -0.305054)
			(end 0.12065 -0.2794)
			(stroke
				(width 0.1)
				(type default)
			)
			(layer "B.Fab")
		)
		(fp_line
			(start -0.12065 -0.3048)
			(end -0.67945 -0.3048)
			(stroke
				(width 0.1)
				(type default)
			)
			(layer "B.Fab")
		)
		(fp_line
			(start -0.67945 -0.3048)
			(end -0.67945 0.3048)
			(stroke
				(width 0.1)
				(type default)
			)
			(layer "B.Fab")
		)
		(fp_line
			(start 0.12065 -0.2794)
			(end -0.12065 -0.2794)
			(stroke
				(width 0.1)
				(type default)
			)
			(layer "B.Fab")
		)
		(fp_line
			(start -0.12065 -0.2794)
			(end -0.12065 -0.3048)
			(stroke
				(width 0.1)
				(type default)
			)
			(layer "B.Fab")
		)
		(fp_line
			(start 0.12065 0.2794)
			(end 0.12065 0.3048)
			(stroke
				(width 0.1)
				(type default)
			)
			(layer "B.Fab")
		)
		(fp_line
			(start -0.120396 0.2794)
			(end 0.12065 0.2794)
			(stroke
				(width 0.1)
				(type default)
			)
			(layer "B.Fab")
		)
		(fp_line
			(start 0.67945 0.3048)
			(end 0.67945 -0.305054)
			(stroke
				(width 0.1)
				(type default)
			)
			(layer "B.Fab")
		)
		(fp_line
			(start 0.12065 0.3048)
			(end 0.67945 0.3048)
			(stroke
				(width 0.1)
				(type default)
			)
			(layer "B.Fab")
		)
		(fp_line
			(start -0.120396 0.3048)
			(end -0.120396 0.2794)
			(stroke
				(width 0.1)
				(type default)
			)
			(layer "B.Fab")
		)
		(fp_line
			(start -0.67945 0.3048)
			(end -0.120396 0.3048)
			(stroke
				(width 0.1)
				(type default)
			)
			(layer "B.Fab")
		)
		(pad "1" smd circle
			(at 0.40005 0 270)
			(size 0 0)
			(layers "B.Cu" "B.Mask" "B.Paste")
			(net "P1V8_PEX")
		)
		(pad "2" smd circle
			(at -0.40005 0 270)
			(size 0 0)
			(layers "B.Cu" "B.Mask" "B.Paste")
			(net "SMB_PEX0_MUX_SDA")
		)
	)
	(footprint ""
		(layer "B.Cu")
		(at 289.47491 -297.79976 90)
		(property "Reference" "C1661"
			(at 0 0 90)
			(layer "B.SilkS")
			(hide yes)
			(effects
				(font
					(size 1.27 1.27)
				)
				(justify mirror)
			)
		)
		(property "Value" ""
			(at 0 0 90)
			(layer "B.Fab")
			(effects
				(font
					(size 1.27 1.27)
				)
				(justify mirror)
			)
		)
		(duplicate_pad_numbers_are_jumpers no)
		(fp_line
			(start 0.299974 -0.150114)
			(end -0.299974 -0.150114)
			(stroke
				(width 0.1)
				(type default)
			)
			(layer "B.Fab")
		)
		(fp_line
			(start -0.299974 -0.150114)
			(end -0.299974 0.150114)
			(stroke
				(width 0.1)
				(type default)
			)
			(layer "B.Fab")
		)
		(fp_line
			(start 0.299974 0.150114)
			(end 0.299974 -0.150114)
			(stroke
				(width 0.1)
				(type default)
			)
			(layer "B.Fab")
		)
		(fp_line
			(start -0.299974 0.150114)
			(end 0.299974 0.150114)
			(stroke
				(width 0.1)
				(type default)
			)
			(layer "B.Fab")
		)
		(pad "1" smd rect
			(at 0.2667 0 270)
			(size 0.3048 0.381)
			(layers "B.Cu" "B.Mask" "B.Paste")
			(net "P0V8_PEX2")
		)
		(pad "2" smd rect
			(at -0.2667 0 270)
			(size 0.3048 0.381)
			(layers "B.Cu" "B.Mask" "B.Paste")
			(net "GND")
		)
	)
	(footprint ""
		(layer "B.Cu")
		(at 230.747316 -212.56625 180)
		(property "Reference" "C2027"
			(at 0 0 0)
			(layer "B.SilkS")
			(hide yes)
			(effects
				(font
					(size 1.27 1.27)
				)
				(justify mirror)
			)
		)
		(property "Value" ""
			(at 0 0 0)
			(layer "B.Fab")
			(effects
				(font
					(size 1.27 1.27)
				)
				(justify mirror)
			)
		)
		(duplicate_pad_numbers_are_jumpers no)
		(fp_line
			(start 0.69215 0.2921)
			(end 0.69215 -0.2921)
			(stroke
				(width 0.1524)
				(type default)
			)
			(layer "B.SilkS")
		)
		(fp_line
			(start 0.69215 -0.2921)
			(end -0.69215 -0.2921)
			(stroke
				(width 0.1524)
				(type default)
			)
			(layer "B.SilkS")
		)
		(fp_line
			(start -0.69215 0.2921)
			(end 0.69215 0.2921)
			(stroke
				(width 0.1524)
				(type default)
			)
			(layer "B.SilkS")
		)
		(fp_line
			(start -0.69215 -0.2921)
			(end -0.69215 0.2921)
			(stroke
				(width 0.1524)
				(type default)
			)
			(layer "B.SilkS")
		)
		(fp_line
			(start 0.51435 0.2794)
			(end 0.51435 -0.2794)
			(stroke
				(width 0.1)
				(type default)
			)
			(layer "B.Fab")
		)
		(fp_line
			(start 0.51435 -0.2794)
			(end -0.51435 -0.2794)
			(stroke
				(width 0.1)
				(type default)
			)
			(layer "B.Fab")
		)
		(fp_line
			(start -0.51435 0.2794)
			(end 0.51435 0.2794)
			(stroke
				(width 0.1)
				(type default)
			)
			(layer "B.Fab")
		)
		(fp_line
			(start -0.51435 -0.2794)
			(end -0.51435 0.2794)
			(stroke
				(width 0.1)
				(type default)
			)
			(layer "B.Fab")
		)
		(pad "1" smd circle
			(at 0.40005 0)
			(size 0 0)
			(layers "B.Cu" "B.Mask" "B.Paste")
			(net "P3V3_BIC_SPI")
		)
		(pad "2" smd circle
			(at -0.40005 0)
			(size 0 0)
			(layers "B.Cu" "B.Mask" "B.Paste")
			(net "GND")
		)
		(zone
			(layer "B.Cu")
			(hatch none 0.5)
			(connect_pads
				(clearance 0)
			)
			(min_thickness 0.25)
			(keepout
				(tracks not_allowed)
				(vias allowed)
				(pads allowed)
				(copperpour not_allowed)
				(footprints allowed)
			)
			(placement
				(enabled no)
				(sheetname "")
			)
			(fill
				(thermal_gap 0.5)
				(thermal_bridge_width 0.5)
				(island_removal_mode 0)
			)
			(polygon
				(pts
					(xy 230.556816 -212.65388) (xy 230.648256 -212.712046) (xy 230.847646 -212.712046) (xy 230.937816 -212.65388)
					(xy 230.937816 -212.47862) (xy 230.847646 -212.4202) (xy 230.648256 -212.4202) (xy 230.556816 -212.478366)
				)
			)
		)
	)
	(footprint ""
		(layer "B.Cu")
		(at 48.866044 -138.421618 180)
		(property "Reference" "R3"
			(at 0 0 0)
			(layer "B.SilkS")
			(hide yes)
			(effects
				(font
					(size 1.27 1.27)
				)
				(justify mirror)
			)
		)
		(property "Value" ""
			(at 0 0 0)
			(layer "B.Fab")
			(effects
				(font
					(size 1.27 1.27)
				)
				(justify mirror)
			)
		)
		(duplicate_pad_numbers_are_jumpers no)
		(fp_line
			(start 0.7874 0.4064)
			(end 0.7874 -0.4064)
			(stroke
				(width 0.1524)
				(type default)
			)
			(layer "B.SilkS")
		)
		(fp_line
			(start 0.7874 -0.4064)
			(end -0.7874 -0.4064)
			(stroke
				(width 0.1524)
				(type default)
			)
			(layer "B.SilkS")
		)
		(fp_line
			(start -0.7874 0.4064)
			(end 0.7874 0.4064)
			(stroke
				(width 0.1524)
				(type default)
			)
			(layer "B.SilkS")
		)
		(fp_line
			(start -0.7874 -0.4064)
			(end -0.7874 0.4064)
			(stroke
				(width 0.1524)
				(type default)
			)
			(layer "B.SilkS")
		)
		(fp_line
			(start 0.67945 0.3048)
			(end 0.67945 -0.305054)
			(stroke
				(width 0.1)
				(type default)
			)
			(layer "B.Fab")
		)
		(fp_line
			(start 0.67945 -0.305054)
			(end 0.12065 -0.305054)
			(stroke
				(width 0.1)
				(type default)
			)
			(layer "B.Fab")
		)
		(fp_line
			(start 0.12065 0.3048)
			(end 0.67945 0.3048)
			(stroke
				(width 0.1)
				(type default)
			)
			(layer "B.Fab")
		)
		(fp_line
			(start 0.12065 0.2794)
			(end 0.12065 0.3048)
			(stroke
				(width 0.1)
				(type default)
			)
			(layer "B.Fab")
		)
		(fp_line
			(start 0.12065 -0.2794)
			(end -0.12065 -0.2794)
			(stroke
				(width 0.1)
				(type default)
			)
			(layer "B.Fab")
		)
		(fp_line
			(start 0.12065 -0.305054)
			(end 0.12065 -0.2794)
			(stroke
				(width 0.1)
				(type default)
			)
			(layer "B.Fab")
		)
		(fp_line
			(start -0.120396 0.3048)
			(end -0.120396 0.2794)
			(stroke
				(width 0.1)
				(type default)
			)
			(layer "B.Fab")
		)
		(fp_line
			(start -0.120396 0.2794)
			(end 0.12065 0.2794)
			(stroke
				(width 0.1)
				(type default)
			)
			(layer "B.Fab")
		)
		(fp_line
			(start -0.12065 -0.2794)
			(end -0.12065 -0.3048)
			(stroke
				(width 0.1)
				(type default)
			)
			(layer "B.Fab")
		)
		(fp_line
			(start -0.12065 -0.3048)
			(end -0.67945 -0.3048)
			(stroke
				(width 0.1)
				(type default)
			)
			(layer "B.Fab")
		)
		(fp_line
			(start -0.67945 0.3048)
			(end -0.120396 0.3048)
			(stroke
				(width 0.1)
				(type default)
			)
			(layer "B.Fab")
		)
		(fp_line
			(start -0.67945 -0.3048)
			(end -0.67945 0.3048)
			(stroke
				(width 0.1)
				(type default)
			)
			(layer "B.Fab")
		)
		(pad "1" smd circle
			(at 0.40005 0)
			(size 0 0)
			(layers "B.Cu" "B.Mask" "B.Paste")
			(net "NIC0_AUX_PWR_EN_R")
		)
		(pad "2" smd circle
			(at -0.40005 0)
			(size 0 0)
			(layers "B.Cu" "B.Mask" "B.Paste")
			(net "NIC0_AUX_PWR_EN")
		)
	)
	(footprint ""
		(layer "B.Cu")
		(at 309.741824 -103.104696 180)
		(property "Reference" "R271"
			(at 0 0 0)
			(layer "B.SilkS")
			(hide yes)
			(effects
				(font
					(size 1.27 1.27)
				)
				(justify mirror)
			)
		)
		(property "Value" ""
			(at 0 0 0)
			(layer "B.Fab")
			(effects
				(font
					(size 1.27 1.27)
				)
				(justify mirror)
			)
		)
		(duplicate_pad_numbers_are_jumpers no)
		(fp_line
			(start 0.7874 0.4064)
			(end 0.7874 -0.4064)
			(stroke
				(width 0.1524)
				(type default)
			)
			(layer "B.SilkS")
		)
		(fp_line
			(start 0.7874 -0.4064)
			(end -0.7874 -0.4064)
			(stroke
				(width 0.1524)
				(type default)
			)
			(layer "B.SilkS")
		)
		(fp_line
			(start -0.7874 0.4064)
			(end 0.7874 0.4064)
			(stroke
				(width 0.1524)
				(type default)
			)
			(layer "B.SilkS")
		)
		(fp_line
			(start -0.7874 -0.4064)
			(end -0.7874 0.4064)
			(stroke
				(width 0.1524)
				(type default)
			)
			(layer "B.SilkS")
		)
		(fp_line
			(start 0.67945 0.3048)
			(end 0.67945 -0.305054)
			(stroke
				(width 0.1)
				(type default)
			)
			(layer "B.Fab")
		)
		(fp_line
			(start 0.67945 -0.305054)
			(end 0.12065 -0.305054)
			(stroke
				(width 0.1)
				(type default)
			)
			(layer "B.Fab")
		)
		(fp_line
			(start 0.12065 0.3048)
			(end 0.67945 0.3048)
			(stroke
				(width 0.1)
				(type default)
			)
			(layer "B.Fab")
		)
		(fp_line
			(start 0.12065 0.2794)
			(end 0.12065 0.3048)
			(stroke
				(width 0.1)
				(type default)
			)
			(layer "B.Fab")
		)
		(fp_line
			(start 0.12065 -0.2794)
			(end -0.12065 -0.2794)
			(stroke
				(width 0.1)
				(type default)
			)
			(layer "B.Fab")
		)
		(fp_line
			(start 0.12065 -0.305054)
			(end 0.12065 -0.2794)
			(stroke
				(width 0.1)
				(type default)
			)
			(layer "B.Fab")
		)
		(fp_line
			(start -0.120396 0.3048)
			(end -0.120396 0.2794)
			(stroke
				(width 0.1)
				(type default)
			)
			(layer "B.Fab")
		)
		(fp_line
			(start -0.120396 0.2794)
			(end 0.12065 0.2794)
			(stroke
				(width 0.1)
				(type default)
			)
			(layer "B.Fab")
		)
		(fp_line
			(start -0.12065 -0.2794)
			(end -0.12065 -0.3048)
			(stroke
				(width 0.1)
				(type default)
			)
			(layer "B.Fab")
		)
		(fp_line
			(start -0.12065 -0.3048)
			(end -0.67945 -0.3048)
			(stroke
				(width 0.1)
				(type default)
			)
			(layer "B.Fab")
		)
		(fp_line
			(start -0.67945 0.3048)
			(end -0.120396 0.3048)
			(stroke
				(width 0.1)
				(type default)
			)
			(layer "B.Fab")
		)
		(fp_line
			(start -0.67945 -0.3048)
			(end -0.67945 0.3048)
			(stroke
				(width 0.1)
				(type default)
			)
			(layer "B.Fab")
		)
		(pad "1" smd circle
			(at 0.40005 0)
			(size 0 0)
			(layers "B.Cu" "B.Mask" "B.Paste")
			(net "NCSI_NIC5_RXD0")
		)
		(pad "2" smd circle
			(at -0.40005 0)
			(size 0 0)
			(layers "B.Cu" "B.Mask" "B.Paste")
			(net "GND")
		)
	)
	(footprint ""
		(layer "B.Cu")
		(at 397.02486 -293.99992 90)
		(property "Reference" "C1891"
			(at 0 0 90)
			(layer "B.SilkS")
			(hide yes)
			(effects
				(font
					(size 1.27 1.27)
				)
				(justify mirror)
			)
		)
		(property "Value" ""
			(at 0 0 90)
			(layer "B.Fab")
			(effects
				(font
					(size 1.27 1.27)
				)
				(justify mirror)
			)
		)
		(duplicate_pad_numbers_are_jumpers no)
		(fp_line
			(start 0.299974 -0.150114)
			(end -0.299974 -0.150114)
			(stroke
				(width 0.1)
				(type default)
			)
			(layer "B.Fab")
		)
		(fp_line
			(start -0.299974 -0.150114)
			(end -0.299974 0.150114)
			(stroke
				(width 0.1)
				(type default)
			)
			(layer "B.Fab")
		)
		(fp_line
			(start 0.299974 0.150114)
			(end 0.299974 -0.150114)
			(stroke
				(width 0.1)
				(type default)
			)
			(layer "B.Fab")
		)
		(fp_line
			(start -0.299974 0.150114)
			(end 0.299974 0.150114)
			(stroke
				(width 0.1)
				(type default)
			)
			(layer "B.Fab")
		)
		(pad "1" smd rect
			(at 0.2667 0 270)
			(size 0.3048 0.381)
			(layers "B.Cu" "B.Mask" "B.Paste")
			(net "P0V8_PEX3")
		)
		(pad "2" smd rect
			(at -0.2667 0 270)
			(size 0.3048 0.381)
			(layers "B.Cu" "B.Mask" "B.Paste")
			(net "GND")
		)
	)
	(footprint ""
		(layer "B.Cu")
		(at 283.774896 -293.99992 -90)
		(property "Reference" "C1666"
			(at 0 0 90)
			(layer "B.SilkS")
			(hide yes)
			(effects
				(font
					(size 1.27 1.27)
				)
				(justify mirror)
			)
		)
		(property "Value" ""
			(at 0 0 90)
			(layer "B.Fab")
			(effects
				(font
					(size 1.27 1.27)
				)
				(justify mirror)
			)
		)
		(duplicate_pad_numbers_are_jumpers no)
		(fp_line
			(start -0.299974 0.150114)
			(end 0.299974 0.150114)
			(stroke
				(width 0.1)
				(type default)
			)
			(layer "B.Fab")
		)
		(fp_line
			(start 0.299974 0.150114)
			(end 0.299974 -0.150114)
			(stroke
				(width 0.1)
				(type default)
			)
			(layer "B.Fab")
		)
		(fp_line
			(start -0.299974 -0.150114)
			(end -0.299974 0.150114)
			(stroke
				(width 0.1)
				(type default)
			)
			(layer "B.Fab")
		)
		(fp_line
			(start 0.299974 -0.150114)
			(end -0.299974 -0.150114)
			(stroke
				(width 0.1)
				(type default)
			)
			(layer "B.Fab")
		)
		(pad "1" smd rect
			(at 0.2667 0 90)
			(size 0.3048 0.381)
			(layers "B.Cu" "B.Mask" "B.Paste")
			(net "P0V8_PEX2")
		)
		(pad "2" smd rect
			(at -0.2667 0 90)
			(size 0.3048 0.381)
			(layers "B.Cu" "B.Mask" "B.Paste")
			(net "GND")
		)
	)
	(footprint ""
		(layer "B.Cu")
		(at 180.50002 -290.199826 90)
		(property "Reference" "C1465"
			(at 0 0 90)
			(layer "B.SilkS")
			(hide yes)
			(effects
				(font
					(size 1.27 1.27)
				)
				(justify mirror)
			)
		)
		(property "Value" ""
			(at 0 0 90)
			(layer "B.Fab")
			(effects
				(font
					(size 1.27 1.27)
				)
				(justify mirror)
			)
		)
		(duplicate_pad_numbers_are_jumpers no)
		(fp_line
			(start 0.299974 -0.150114)
			(end -0.299974 -0.150114)
			(stroke
				(width 0.1)
				(type default)
			)
			(layer "B.Fab")
		)
		(fp_line
			(start -0.299974 -0.150114)
			(end -0.299974 0.150114)
			(stroke
				(width 0.1)
				(type default)
			)
			(layer "B.Fab")
		)
		(fp_line
			(start 0.299974 0.150114)
			(end 0.299974 -0.150114)
			(stroke
				(width 0.1)
				(type default)
			)
			(layer "B.Fab")
		)
		(fp_line
			(start -0.299974 0.150114)
			(end 0.299974 0.150114)
			(stroke
				(width 0.1)
				(type default)
			)
			(layer "B.Fab")
		)
		(pad "1" smd rect
			(at 0.2667 0 270)
			(size 0.3048 0.381)
			(layers "B.Cu" "B.Mask" "B.Paste")
			(net "P0V8_SERDES_VDDA_PEX1")
		)
		(pad "2" smd rect
			(at -0.2667 0 270)
			(size 0.3048 0.381)
			(layers "B.Cu" "B.Mask" "B.Paste")
			(net "GND")
		)
	)
	(footprint ""
		(layer "B.Cu")
		(at 416.972242 -112.421924)
		(property "Reference" "R366"
			(at 0 0 0)
			(layer "B.SilkS")
			(hide yes)
			(effects
				(font
					(size 1.27 1.27)
				)
				(justify mirror)
			)
		)
		(property "Value" ""
			(at 0 0 0)
			(layer "B.Fab")
			(effects
				(font
					(size 1.27 1.27)
				)
				(justify mirror)
			)
		)
		(duplicate_pad_numbers_are_jumpers no)
		(fp_line
			(start -0.7874 -0.4064)
			(end -0.7874 0.4064)
			(stroke
				(width 0.1524)
				(type default)
			)
			(layer "B.SilkS")
		)
		(fp_line
			(start -0.7874 0.4064)
			(end 0.7874 0.4064)
			(stroke
				(width 0.1524)
				(type default)
			)
			(layer "B.SilkS")
		)
		(fp_line
			(start 0.7874 -0.4064)
			(end -0.7874 -0.4064)
			(stroke
				(width 0.1524)
				(type default)
			)
			(layer "B.SilkS")
		)
		(fp_line
			(start 0.7874 0.4064)
			(end 0.7874 -0.4064)
			(stroke
				(width 0.1524)
				(type default)
			)
			(layer "B.SilkS")
		)
		(fp_line
			(start -0.67945 -0.3048)
			(end -0.67945 0.3048)
			(stroke
				(width 0.1)
				(type default)
			)
			(layer "B.Fab")
		)
		(fp_line
			(start -0.67945 0.3048)
			(end -0.120396 0.3048)
			(stroke
				(width 0.1)
				(type default)
			)
			(layer "B.Fab")
		)
		(fp_line
			(start -0.12065 -0.3048)
			(end -0.67945 -0.3048)
			(stroke
				(width 0.1)
				(type default)
			)
			(layer "B.Fab")
		)
		(fp_line
			(start -0.12065 -0.2794)
			(end -0.12065 -0.3048)
			(stroke
				(width 0.1)
				(type default)
			)
			(layer "B.Fab")
		)
		(fp_line
			(start -0.120396 0.2794)
			(end 0.12065 0.2794)
			(stroke
				(width 0.1)
				(type default)
			)
			(layer "B.Fab")
		)
		(fp_line
			(start -0.120396 0.3048)
			(end -0.120396 0.2794)
			(stroke
				(width 0.1)
				(type default)
			)
			(layer "B.Fab")
		)
		(fp_line
			(start 0.12065 -0.305054)
			(end 0.12065 -0.2794)
			(stroke
				(width 0.1)
				(type default)
			)
			(layer "B.Fab")
		)
		(fp_line
			(start 0.12065 -0.2794)
			(end -0.12065 -0.2794)
			(stroke
				(width 0.1)
				(type default)
			)
			(layer "B.Fab")
		)
		(fp_line
			(start 0.12065 0.2794)
			(end 0.12065 0.3048)
			(stroke
				(width 0.1)
				(type default)
			)
			(layer "B.Fab")
		)
		(fp_line
			(start 0.12065 0.3048)
			(end 0.67945 0.3048)
			(stroke
				(width 0.1)
				(type default)
			)
			(layer "B.Fab")
		)
		(fp_line
			(start 0.67945 -0.305054)
			(end 0.12065 -0.305054)
			(stroke
				(width 0.1)
				(type default)
			)
			(layer "B.Fab")
		)
		(fp_line
			(start 0.67945 0.3048)
			(end 0.67945 -0.305054)
			(stroke
				(width 0.1)
				(type default)
			)
			(layer "B.Fab")
		)
		(pad "1" smd circle
			(at 0.40005 0 180)
			(size 0 0)
			(layers "B.Cu" "B.Mask" "B.Paste")
			(net "P3V3_NIC7")
		)
		(pad "2" smd circle
			(at -0.40005 0 180)
			(size 0 0)
			(layers "B.Cu" "B.Mask" "B.Paste")
			(net "SMB_NIC7_LS_SCL")
		)
	)
	(footprint ""
		(layer "B.Cu")
		(at 257.529838 -228.268784 90)
		(property "Reference" "R3481"
			(at 0 0 90)
			(layer "B.SilkS")
			(hide yes)
			(effects
				(font
					(size 1.27 1.27)
				)
				(justify mirror)
			)
		)
		(property "Value" ""
			(at 0 0 90)
			(layer "B.Fab")
			(effects
				(font
					(size 1.27 1.27)
				)
				(justify mirror)
			)
		)
		(duplicate_pad_numbers_are_jumpers no)
		(fp_line
			(start 0.7874 -0.4064)
			(end -0.7874 -0.4064)
			(stroke
				(width 0.1524)
				(type default)
			)
			(layer "B.SilkS")
		)
		(fp_line
			(start -0.7874 -0.4064)
			(end -0.7874 0.4064)
			(stroke
				(width 0.1524)
				(type default)
			)
			(layer "B.SilkS")
		)
		(fp_line
			(start 0.7874 0.4064)
			(end 0.7874 -0.4064)
			(stroke
				(width 0.1524)
				(type default)
			)
			(layer "B.SilkS")
		)
		(fp_line
			(start -0.7874 0.4064)
			(end 0.7874 0.4064)
			(stroke
				(width 0.1524)
				(type default)
			)
			(layer "B.SilkS")
		)
		(fp_line
			(start 0.67945 -0.305054)
			(end 0.12065 -0.305054)
			(stroke
				(width 0.1)
				(type default)
			)
			(layer "B.Fab")
		)
		(fp_line
			(start 0.12065 -0.305054)
			(end 0.12065 -0.2794)
			(stroke
				(width 0.1)
				(type default)
			)
			(layer "B.Fab")
		)
		(fp_line
			(start -0.12065 -0.3048)
			(end -0.67945 -0.3048)
			(stroke
				(width 0.1)
				(type default)
			)
			(layer "B.Fab")
		)
		(fp_line
			(start -0.67945 -0.3048)
			(end -0.67945 0.3048)
			(stroke
				(width 0.1)
				(type default)
			)
			(layer "B.Fab")
		)
		(fp_line
			(start 0.12065 -0.2794)
			(end -0.12065 -0.2794)
			(stroke
				(width 0.1)
				(type default)
			)
			(layer "B.Fab")
		)
		(fp_line
			(start -0.12065 -0.2794)
			(end -0.12065 -0.3048)
			(stroke
				(width 0.1)
				(type default)
			)
			(layer "B.Fab")
		)
		(fp_line
			(start 0.12065 0.2794)
			(end 0.12065 0.3048)
			(stroke
				(width 0.1)
				(type default)
			)
			(layer "B.Fab")
		)
		(fp_line
			(start -0.120396 0.2794)
			(end 0.12065 0.2794)
			(stroke
				(width 0.1)
				(type default)
			)
			(layer "B.Fab")
		)
		(fp_line
			(start 0.67945 0.3048)
			(end 0.67945 -0.305054)
			(stroke
				(width 0.1)
				(type default)
			)
			(layer "B.Fab")
		)
		(fp_line
			(start 0.12065 0.3048)
			(end 0.67945 0.3048)
			(stroke
				(width 0.1)
				(type default)
			)
			(layer "B.Fab")
		)
		(fp_line
			(start -0.120396 0.3048)
			(end -0.120396 0.2794)
			(stroke
				(width 0.1)
				(type default)
			)
			(layer "B.Fab")
		)
		(fp_line
			(start -0.67945 0.3048)
			(end -0.120396 0.3048)
			(stroke
				(width 0.1)
				(type default)
			)
			(layer "B.Fab")
		)
		(pad "1" smd circle
			(at 0.40005 0 270)
			(size 0 0)
			(layers "B.Cu" "B.Mask" "B.Paste")
			(net "SPI_PEX2_CS_MUX_N")
		)
		(pad "2" smd circle
			(at -0.40005 0 270)
			(size 0 0)
			(layers "B.Cu" "B.Mask" "B.Paste")
			(net "SPI_PEX2_CS_MUX_R_N")
		)
	)
	(footprint ""
		(layer "B.Cu")
		(at 203.106274 -259.311648 90)
		(property "Reference" "R6360"
			(at 0 0 90)
			(layer "B.SilkS")
			(hide yes)
			(effects
				(font
					(size 1.27 1.27)
				)
				(justify mirror)
			)
		)
		(property "Value" ""
			(at 0 0 90)
			(layer "B.Fab")
			(effects
				(font
					(size 1.27 1.27)
				)
				(justify mirror)
			)
		)
		(duplicate_pad_numbers_are_jumpers no)
		(fp_line
			(start 0.7874 -0.4064)
			(end -0.7874 -0.4064)
			(stroke
				(width 0.1524)
				(type default)
			)
			(layer "B.SilkS")
		)
		(fp_line
			(start -0.7874 -0.4064)
			(end -0.7874 0.4064)
			(stroke
				(width 0.1524)
				(type default)
			)
			(layer "B.SilkS")
		)
		(fp_line
			(start 0.7874 0.4064)
			(end 0.7874 -0.4064)
			(stroke
				(width 0.1524)
				(type default)
			)
			(layer "B.SilkS")
		)
		(fp_line
			(start -0.7874 0.4064)
			(end 0.7874 0.4064)
			(stroke
				(width 0.1524)
				(type default)
			)
			(layer "B.SilkS")
		)
		(fp_line
			(start 0.67945 -0.305054)
			(end 0.12065 -0.305054)
			(stroke
				(width 0.1)
				(type default)
			)
			(layer "B.Fab")
		)
		(fp_line
			(start 0.12065 -0.305054)
			(end 0.12065 -0.2794)
			(stroke
				(width 0.1)
				(type default)
			)
			(layer "B.Fab")
		)
		(fp_line
			(start -0.12065 -0.3048)
			(end -0.67945 -0.3048)
			(stroke
				(width 0.1)
				(type default)
			)
			(layer "B.Fab")
		)
		(fp_line
			(start -0.67945 -0.3048)
			(end -0.67945 0.3048)
			(stroke
				(width 0.1)
				(type default)
			)
			(layer "B.Fab")
		)
		(fp_line
			(start 0.12065 -0.2794)
			(end -0.12065 -0.2794)
			(stroke
				(width 0.1)
				(type default)
			)
			(layer "B.Fab")
		)
		(fp_line
			(start -0.12065 -0.2794)
			(end -0.12065 -0.3048)
			(stroke
				(width 0.1)
				(type default)
			)
			(layer "B.Fab")
		)
		(fp_line
			(start 0.12065 0.2794)
			(end 0.12065 0.3048)
			(stroke
				(width 0.1)
				(type default)
			)
			(layer "B.Fab")
		)
		(fp_line
			(start -0.120396 0.2794)
			(end 0.12065 0.2794)
			(stroke
				(width 0.1)
				(type default)
			)
			(layer "B.Fab")
		)
		(fp_line
			(start 0.67945 0.3048)
			(end 0.67945 -0.305054)
			(stroke
				(width 0.1)
				(type default)
			)
			(layer "B.Fab")
		)
		(fp_line
			(start 0.12065 0.3048)
			(end 0.67945 0.3048)
			(stroke
				(width 0.1)
				(type default)
			)
			(layer "B.Fab")
		)
		(fp_line
			(start -0.120396 0.3048)
			(end -0.120396 0.2794)
			(stroke
				(width 0.1)
				(type default)
			)
			(layer "B.Fab")
		)
		(fp_line
			(start -0.67945 0.3048)
			(end -0.120396 0.3048)
			(stroke
				(width 0.1)
				(type default)
			)
			(layer "B.Fab")
		)
		(pad "1" smd circle
			(at 0.40005 0 270)
			(size 0 0)
			(layers "B.Cu" "B.Mask" "B.Paste")
			(net "P3V3_AUX")
		)
		(pad "2" smd circle
			(at -0.40005 0 270)
			(size 0 0)
			(layers "B.Cu" "B.Mask" "B.Paste")
			(net "RST_PEX_MUX_R_N")
		)
	)
	(footprint ""
		(layer "B.Cu")
		(at 385.425696 -247.311926 -90)
		(property "Reference" "R942"
			(at 0 0 90)
			(layer "B.SilkS")
			(hide yes)
			(effects
				(font
					(size 1.27 1.27)
				)
				(justify mirror)
			)
		)
		(property "Value" ""
			(at 0 0 90)
			(layer "B.Fab")
			(effects
				(font
					(size 1.27 1.27)
				)
				(justify mirror)
			)
		)
		(duplicate_pad_numbers_are_jumpers no)
		(fp_line
			(start -0.7874 0.4064)
			(end 0.7874 0.4064)
			(stroke
				(width 0.1524)
				(type default)
			)
			(layer "B.SilkS")
		)
		(fp_line
			(start 0.7874 0.4064)
			(end 0.7874 -0.4064)
			(stroke
				(width 0.1524)
				(type default)
			)
			(layer "B.SilkS")
		)
		(fp_line
			(start -0.7874 -0.4064)
			(end -0.7874 0.4064)
			(stroke
				(width 0.1524)
				(type default)
			)
			(layer "B.SilkS")
		)
		(fp_line
			(start 0.7874 -0.4064)
			(end -0.7874 -0.4064)
			(stroke
				(width 0.1524)
				(type default)
			)
			(layer "B.SilkS")
		)
		(fp_line
			(start -0.67945 0.3048)
			(end -0.120396 0.3048)
			(stroke
				(width 0.1)
				(type default)
			)
			(layer "B.Fab")
		)
		(fp_line
			(start -0.120396 0.3048)
			(end -0.120396 0.2794)
			(stroke
				(width 0.1)
				(type default)
			)
			(layer "B.Fab")
		)
		(fp_line
			(start 0.12065 0.3048)
			(end 0.67945 0.3048)
			(stroke
				(width 0.1)
				(type default)
			)
			(layer "B.Fab")
		)
		(fp_line
			(start 0.67945 0.3048)
			(end 0.67945 -0.305054)
			(stroke
				(width 0.1)
				(type default)
			)
			(layer "B.Fab")
		)
		(fp_line
			(start -0.120396 0.2794)
			(end 0.12065 0.2794)
			(stroke
				(width 0.1)
				(type default)
			)
			(layer "B.Fab")
		)
		(fp_line
			(start 0.12065 0.2794)
			(end 0.12065 0.3048)
			(stroke
				(width 0.1)
				(type default)
			)
			(layer "B.Fab")
		)
		(fp_line
			(start -0.12065 -0.2794)
			(end -0.12065 -0.3048)
			(stroke
				(width 0.1)
				(type default)
			)
			(layer "B.Fab")
		)
		(fp_line
			(start 0.12065 -0.2794)
			(end -0.12065 -0.2794)
			(stroke
				(width 0.1)
				(type default)
			)
			(layer "B.Fab")
		)
		(fp_line
			(start -0.67945 -0.3048)
			(end -0.67945 0.3048)
			(stroke
				(width 0.1)
				(type default)
			)
			(layer "B.Fab")
		)
		(fp_line
			(start -0.12065 -0.3048)
			(end -0.67945 -0.3048)
			(stroke
				(width 0.1)
				(type default)
			)
			(layer "B.Fab")
		)
		(fp_line
			(start 0.12065 -0.305054)
			(end 0.12065 -0.2794)
			(stroke
				(width 0.1)
				(type default)
			)
			(layer "B.Fab")
		)
		(fp_line
			(start 0.67945 -0.305054)
			(end 0.12065 -0.305054)
			(stroke
				(width 0.1)
				(type default)
			)
			(layer "B.Fab")
		)
		(pad "1" smd circle
			(at 0.40005 0 90)
			(size 0 0)
			(layers "B.Cu" "B.Mask" "B.Paste")
			(net "UART_PEX3_SDB_BUF_R_RX")
		)
		(pad "2" smd circle
			(at -0.40005 0 90)
			(size 0 0)
			(layers "B.Cu" "B.Mask" "B.Paste")
			(net "UART_PEX3_SDB_BUF_RX")
		)
	)
	(footprint ""
		(layer "B.Cu")
		(at 402.909024 20.575524 180)
		(property "Reference" "DE05F_4"
			(at -2.805176 -3.098546 0)
			(unlocked yes)
			(layer "B.SilkS")
			(effects
				(font
					(size 0.7874 0.5842)
					(thickness 0.1524)
				)
				(justify left mirror)
			)
		)
		(property "Value" ""
			(at 0 0 0)
			(layer "B.Fab")
			(effects
				(font
					(size 1.27 1.27)
				)
				(justify mirror)
			)
		)
		(duplicate_pad_numbers_are_jumpers no)
		(fp_line
			(start 1.2192 2.1082)
			(end 1.2192 -2.1082)
			(stroke
				(width 0.1524)
				(type default)
			)
			(layer "B.SilkS")
		)
		(fp_line
			(start 1.2192 -2.1082)
			(end -1.2192 -2.1082)
			(stroke
				(width 0.1524)
				(type default)
			)
			(layer "B.SilkS")
		)
		(fp_line
			(start -1.2192 2.1082)
			(end 1.2192 2.1082)
			(stroke
				(width 0.1524)
				(type default)
			)
			(layer "B.SilkS")
		)
		(fp_line
			(start -1.2192 -2.1082)
			(end -1.2192 2.1082)
			(stroke
				(width 0.1524)
				(type default)
			)
			(layer "B.SilkS")
		)
		(pad "" np_thru_hole circle
			(at -3.4671 -1.27 90)
			(size 1.0414 1.0414)
			(drill 1.0414)
			(layers "*.Cu" "*.Mask")
			(clearance 0.381)
			(thermal_gap 0.381)
		)
		(pad "" np_thru_hole circle
			(at -3.4671 1.27 90)
			(size 1.0414 1.0414)
			(drill 1.0414)
			(layers "*.Cu" "*.Mask")
			(clearance 0.381)
			(thermal_gap 0.381)
		)
		(pad "" np_thru_hole circle
			(at 2.8829 -1.27 90)
			(size 1.0414 1.0414)
			(drill 1.0414)
			(layers "*.Cu" "*.Mask")
			(clearance 0.381)
			(thermal_gap 0.381)
		)
		(pad "" np_thru_hole circle
			(at 2.8829 1.27 90)
			(size 1.0414 1.0414)
			(drill 1.0414)
			(layers "*.Cu" "*.Mask")
			(clearance 0.381)
			(thermal_gap 0.381)
		)
		(pad "1" smd rect
			(at -0.8255 -0.249936 90)
			(size 0.3048 0.508)
			(layers "B.Cu" "B.Mask" "B.Paste")
			(net "85_5INCH_IN5_DN")
		)
		(pad "2" smd rect
			(at -0.8255 0.249936 90)
			(size 0.3048 0.508)
			(layers "B.Cu" "B.Mask" "B.Paste")
			(net "85_5INCH_IN5_DP")
		)
		(pad "3" smd circle
			(at 0 0)
			(size 0 0)
			(layers "B.Cu" "B.Mask" "B.Paste")
			(net "COUPON_GND2")
		)
		(zone
			(layers "F.Cu" "B.Cu" "In1.Cu" "In2.Cu" "In3.Cu" "In4.Cu" "In5.Cu" "In6.Cu"
				"In7.Cu" "In8.Cu" "In9.Cu" "In10.Cu" "In11.Cu" "In12.Cu" "In13.Cu" "In14.Cu"
				"In15.Cu" "In16.Cu"
			)
			(hatch none 0.5)
			(connect_pads
				(clearance 0)
			)
			(min_thickness 0.25)
			(keepout
				(tracks not_allowed)
				(vias allowed)
				(pads allowed)
				(copperpour not_allowed)
				(footprints allowed)
			)
			(placement
				(enabled no)
				(sheetname "")
			)
			(fill
				(thermal_gap 0.5)
				(thermal_bridge_width 0.5)
				(island_removal_mode 0)
			)
			(polygon
				(pts
					(arc
						(start 400.953224 19.305524)
						(mid 399.099024 19.305524)
						(end 400.953224 19.305524)
					)
				)
			)
		)
		(zone
			(layers "F.Cu" "B.Cu" "In1.Cu" "In2.Cu" "In3.Cu" "In4.Cu" "In5.Cu" "In6.Cu"
				"In7.Cu" "In8.Cu" "In9.Cu" "In10.Cu" "In11.Cu" "In12.Cu" "In13.Cu" "In14.Cu"
				"In15.Cu" "In16.Cu"
			)
			(hatch none 0.5)
			(connect_pads
				(clearance 0)
			)
			(min_thickness 0.25)
			(keepout
				(tracks not_allowed)
				(vias allowed)
				(pads allowed)
				(copperpour not_allowed)
				(footprints allowed)
			)
			(placement
				(enabled no)
				(sheetname "")
			)
			(fill
				(thermal_gap 0.5)
				(thermal_bridge_width 0.5)
				(island_removal_mode 0)
			)
			(polygon
				(pts
					(arc
						(start 400.953224 21.845524)
						(mid 399.099024 21.845524)
						(end 400.953224 21.845524)
					)
				)
			)
		)
		(zone
			(layers "F.Cu" "B.Cu" "In1.Cu" "In2.Cu" "In3.Cu" "In4.Cu" "In5.Cu" "In6.Cu"
				"In7.Cu" "In8.Cu" "In9.Cu" "In10.Cu" "In11.Cu" "In12.Cu" "In13.Cu" "In14.Cu"
				"In15.Cu" "In16.Cu"
			)
			(hatch none 0.5)
			(connect_pads
				(clearance 0)
			)
			(min_thickness 0.25)
			(keepout
				(tracks not_allowed)
				(vias allowed)
				(pads allowed)
				(copperpour not_allowed)
				(footprints allowed)
			)
			(placement
				(enabled no)
				(sheetname "")
			)
			(fill
				(thermal_gap 0.5)
				(thermal_bridge_width 0.5)
				(island_removal_mode 0)
			)
			(polygon
				(pts
					(arc
						(start 407.303224 19.305524)
						(mid 405.449024 19.305524)
						(end 407.303224 19.305524)
					)
				)
			)
		)
		(zone
			(layers "F.Cu" "B.Cu" "In1.Cu" "In2.Cu" "In3.Cu" "In4.Cu" "In5.Cu" "In6.Cu"
				"In7.Cu" "In8.Cu" "In9.Cu" "In10.Cu" "In11.Cu" "In12.Cu" "In13.Cu" "In14.Cu"
				"In15.Cu" "In16.Cu"
			)
			(hatch none 0.5)
			(connect_pads
				(clearance 0)
			)
			(min_thickness 0.25)
			(keepout
				(tracks not_allowed)
				(vias allowed)
				(pads allowed)
				(copperpour not_allowed)
				(footprints allowed)
			)
			(placement
				(enabled no)
				(sheetname "")
			)
			(fill
				(thermal_gap 0.5)
				(thermal_bridge_width 0.5)
				(island_removal_mode 0)
			)
			(polygon
				(pts
					(arc
						(start 407.303224 21.845524)
						(mid 405.449024 21.845524)
						(end 407.303224 21.845524)
					)
				)
			)
		)
		(zone
			(layer "B.Cu")
			(hatch none 0.5)
			(connect_pads
				(clearance 0)
			)
			(min_thickness 0.25)
			(keepout
				(tracks not_allowed)
				(vias allowed)
				(pads allowed)
				(copperpour not_allowed)
				(footprints allowed)
			)
			(placement
				(enabled no)
				(sheetname "")
			)
			(fill
				(thermal_gap 0.5)
				(thermal_bridge_width 0.5)
				(island_removal_mode 0)
			)
			(polygon
				(pts
					(xy 404.026624 21.124164) (xy 404.026624 21.02866) (xy 403.429724 21.02866) (xy 403.429724 20.62226)
					(xy 404.026624 20.62226) (xy 404.026624 20.528788) (xy 403.429724 20.528788) (xy 403.429724 20.122388)
					(xy 404.026624 20.122388) (xy 404.026624 20.026884) (xy 403.328124 20.026884) (xy 403.328124 21.124164)
				)
			)
		)
	)
	(footprint ""
		(layer "B.Cu")
		(at 362.459016 -319.545462 -90)
		(property "Reference" "R5796"
			(at 0 0 90)
			(layer "B.SilkS")
			(hide yes)
			(effects
				(font
					(size 1.27 1.27)
				)
				(justify mirror)
			)
		)
		(property "Value" ""
			(at 0 0 90)
			(layer "B.Fab")
			(effects
				(font
					(size 1.27 1.27)
				)
				(justify mirror)
			)
		)
		(duplicate_pad_numbers_are_jumpers no)
		(fp_line
			(start -2.576322 1.1303)
			(end 2.576322 1.1303)
			(stroke
				(width 0.1524)
				(type default)
			)
			(layer "B.SilkS")
		)
		(fp_line
			(start 2.576322 1.1303)
			(end 2.576322 -1.1303)
			(stroke
				(width 0.1524)
				(type default)
			)
			(layer "B.SilkS")
		)
		(fp_line
			(start -2.576322 -1.1303)
			(end -2.576322 1.1303)
			(stroke
				(width 0.1524)
				(type default)
			)
			(layer "B.SilkS")
		)
		(fp_line
			(start 2.576322 -1.1303)
			(end -2.576322 -1.1303)
			(stroke
				(width 0.1524)
				(type default)
			)
			(layer "B.SilkS")
		)
		(fp_line
			(start -1.649984 0.899922)
			(end -1.649984 -0.899922)
			(stroke
				(width 0.1)
				(type default)
			)
			(layer "B.Fab")
		)
		(fp_line
			(start 1.649984 0.899922)
			(end -1.649984 0.899922)
			(stroke
				(width 0.1)
				(type default)
			)
			(layer "B.Fab")
		)
		(fp_line
			(start -1.649984 -0.899922)
			(end 1.649984 -0.899922)
			(stroke
				(width 0.1)
				(type default)
			)
			(layer "B.Fab")
		)
		(fp_line
			(start 1.649984 -0.899922)
			(end 1.649984 0.899922)
			(stroke
				(width 0.1)
				(type default)
			)
			(layer "B.Fab")
		)
		(pad "1A" smd rect
			(at 1.700022 0 90)
			(size 1.4986 2.0066)
			(layers "B.Cu" "B.Mask" "B.Paste")
			(net "P0V8_PEX3")
		)
		(pad "1B" smd rect
			(at 1.077722 0 90)
			(size 0.254 0.508)
			(layers "B.Cu" "B.Mask" "B.Paste")
			(net "P0V8_PEX3")
		)
		(pad "2A" smd rect
			(at -1.700022 0 90)
			(size 1.4986 2.0066)
			(layers "B.Cu" "B.Mask" "B.Paste")
			(net "P0V8_SERDES_VDDA_PEX3")
		)
		(pad "2B" smd rect
			(at -1.077722 0 90)
			(size 0.254 0.508)
			(layers "B.Cu" "B.Mask" "B.Paste")
			(net "P0V8_SERDES_VDDA_PEX3")
		)
	)
	(footprint ""
		(layer "B.Cu")
		(at 397.02486 -297.79976 -90)
		(property "Reference" "C1872"
			(at 0 0 90)
			(layer "B.SilkS")
			(hide yes)
			(effects
				(font
					(size 1.27 1.27)
				)
				(justify mirror)
			)
		)
		(property "Value" ""
			(at 0 0 90)
			(layer "B.Fab")
			(effects
				(font
					(size 1.27 1.27)
				)
				(justify mirror)
			)
		)
		(duplicate_pad_numbers_are_jumpers no)
		(fp_line
			(start -0.299974 0.150114)
			(end 0.299974 0.150114)
			(stroke
				(width 0.1)
				(type default)
			)
			(layer "B.Fab")
		)
		(fp_line
			(start 0.299974 0.150114)
			(end 0.299974 -0.150114)
			(stroke
				(width 0.1)
				(type default)
			)
			(layer "B.Fab")
		)
		(fp_line
			(start -0.299974 -0.150114)
			(end -0.299974 0.150114)
			(stroke
				(width 0.1)
				(type default)
			)
			(layer "B.Fab")
		)
		(fp_line
			(start 0.299974 -0.150114)
			(end -0.299974 -0.150114)
			(stroke
				(width 0.1)
				(type default)
			)
			(layer "B.Fab")
		)
		(pad "1" smd rect
			(at 0.2667 0 90)
			(size 0.3048 0.381)
			(layers "B.Cu" "B.Mask" "B.Paste")
			(net "P0V8_PEX3")
		)
		(pad "2" smd rect
			(at -0.2667 0 90)
			(size 0.3048 0.381)
			(layers "B.Cu" "B.Mask" "B.Paste")
			(net "GND")
		)
	)
	(footprint ""
		(layer "B.Cu")
		(at 298.974764 -297.79976 -90)
		(property "Reference" "C1695"
			(at 0 0 90)
			(layer "B.SilkS")
			(hide yes)
			(effects
				(font
					(size 1.27 1.27)
				)
				(justify mirror)
			)
		)
		(property "Value" ""
			(at 0 0 90)
			(layer "B.Fab")
			(effects
				(font
					(size 1.27 1.27)
				)
				(justify mirror)
			)
		)
		(duplicate_pad_numbers_are_jumpers no)
		(fp_line
			(start -0.299974 0.150114)
			(end 0.299974 0.150114)
			(stroke
				(width 0.1)
				(type default)
			)
			(layer "B.Fab")
		)
		(fp_line
			(start 0.299974 0.150114)
			(end 0.299974 -0.150114)
			(stroke
				(width 0.1)
				(type default)
			)
			(layer "B.Fab")
		)
		(fp_line
			(start -0.299974 -0.150114)
			(end -0.299974 0.150114)
			(stroke
				(width 0.1)
				(type default)
			)
			(layer "B.Fab")
		)
		(fp_line
			(start 0.299974 -0.150114)
			(end -0.299974 -0.150114)
			(stroke
				(width 0.1)
				(type default)
			)
			(layer "B.Fab")
		)
		(pad "1" smd rect
			(at 0.2667 0 90)
			(size 0.3048 0.381)
			(layers "B.Cu" "B.Mask" "B.Paste")
			(net "P0V8_SERDES_VDDA_PEX2")
		)
		(pad "2" smd rect
			(at -0.2667 0 90)
			(size 0.3048 0.381)
			(layers "B.Cu" "B.Mask" "B.Paste")
			(net "GND")
		)
	)
	(footprint ""
		(layer "B.Cu")
		(at 185.04154 -287.824926)
		(property "Reference" "C3170"
			(at 0 0 0)
			(layer "B.SilkS")
			(hide yes)
			(effects
				(font
					(size 1.27 1.27)
				)
				(justify mirror)
			)
		)
		(property "Value" ""
			(at 0 0 0)
			(layer "B.Fab")
			(effects
				(font
					(size 1.27 1.27)
				)
				(justify mirror)
			)
		)
		(duplicate_pad_numbers_are_jumpers no)
		(fp_line
			(start -0.299974 -0.150114)
			(end -0.299974 0.150114)
			(stroke
				(width 0.1)
				(type default)
			)
			(layer "B.Fab")
		)
		(fp_line
			(start -0.299974 0.150114)
			(end 0.299974 0.150114)
			(stroke
				(width 0.1)
				(type default)
			)
			(layer "B.Fab")
		)
		(fp_line
			(start 0.299974 -0.150114)
			(end -0.299974 -0.150114)
			(stroke
				(width 0.1)
				(type default)
			)
			(layer "B.Fab")
		)
		(fp_line
			(start 0.299974 0.150114)
			(end 0.299974 -0.150114)
			(stroke
				(width 0.1)
				(type default)
			)
			(layer "B.Fab")
		)
		(pad "1" smd rect
			(at 0.2667 0 180)
			(size 0.3048 0.381)
			(layers "B.Cu" "B.Mask" "B.Paste")
			(net "P1V8_VDDA_PEX1")
		)
		(pad "2" smd rect
			(at -0.2667 0 180)
			(size 0.3048 0.381)
			(layers "B.Cu" "B.Mask" "B.Paste")
			(net "GND")
		)
	)
	(footprint ""
		(layer "B.Cu")
		(at 208.196942 -259.311648 90)
		(property "Reference" "R6346"
			(at 0 0 90)
			(layer "B.SilkS")
			(hide yes)
			(effects
				(font
					(size 1.27 1.27)
				)
				(justify mirror)
			)
		)
		(property "Value" ""
			(at 0 0 90)
			(layer "B.Fab")
			(effects
				(font
					(size 1.27 1.27)
				)
				(justify mirror)
			)
		)
		(duplicate_pad_numbers_are_jumpers no)
		(fp_line
			(start 0.7874 -0.4064)
			(end -0.7874 -0.4064)
			(stroke
				(width 0.1524)
				(type default)
			)
			(layer "B.SilkS")
		)
		(fp_line
			(start -0.7874 -0.4064)
			(end -0.7874 0.4064)
			(stroke
				(width 0.1524)
				(type default)
			)
			(layer "B.SilkS")
		)
		(fp_line
			(start 0.7874 0.4064)
			(end 0.7874 -0.4064)
			(stroke
				(width 0.1524)
				(type default)
			)
			(layer "B.SilkS")
		)
		(fp_line
			(start -0.7874 0.4064)
			(end 0.7874 0.4064)
			(stroke
				(width 0.1524)
				(type default)
			)
			(layer "B.SilkS")
		)
		(fp_line
			(start 0.67945 -0.305054)
			(end 0.12065 -0.305054)
			(stroke
				(width 0.1)
				(type default)
			)
			(layer "B.Fab")
		)
		(fp_line
			(start 0.12065 -0.305054)
			(end 0.12065 -0.2794)
			(stroke
				(width 0.1)
				(type default)
			)
			(layer "B.Fab")
		)
		(fp_line
			(start -0.12065 -0.3048)
			(end -0.67945 -0.3048)
			(stroke
				(width 0.1)
				(type default)
			)
			(layer "B.Fab")
		)
		(fp_line
			(start -0.67945 -0.3048)
			(end -0.67945 0.3048)
			(stroke
				(width 0.1)
				(type default)
			)
			(layer "B.Fab")
		)
		(fp_line
			(start 0.12065 -0.2794)
			(end -0.12065 -0.2794)
			(stroke
				(width 0.1)
				(type default)
			)
			(layer "B.Fab")
		)
		(fp_line
			(start -0.12065 -0.2794)
			(end -0.12065 -0.3048)
			(stroke
				(width 0.1)
				(type default)
			)
			(layer "B.Fab")
		)
		(fp_line
			(start 0.12065 0.2794)
			(end 0.12065 0.3048)
			(stroke
				(width 0.1)
				(type default)
			)
			(layer "B.Fab")
		)
		(fp_line
			(start -0.120396 0.2794)
			(end 0.12065 0.2794)
			(stroke
				(width 0.1)
				(type default)
			)
			(layer "B.Fab")
		)
		(fp_line
			(start 0.67945 0.3048)
			(end 0.67945 -0.305054)
			(stroke
				(width 0.1)
				(type default)
			)
			(layer "B.Fab")
		)
		(fp_line
			(start 0.12065 0.3048)
			(end 0.67945 0.3048)
			(stroke
				(width 0.1)
				(type default)
			)
			(layer "B.Fab")
		)
		(fp_line
			(start -0.120396 0.3048)
			(end -0.120396 0.2794)
			(stroke
				(width 0.1)
				(type default)
			)
			(layer "B.Fab")
		)
		(fp_line
			(start -0.67945 0.3048)
			(end -0.120396 0.3048)
			(stroke
				(width 0.1)
				(type default)
			)
			(layer "B.Fab")
		)
		(pad "1" smd circle
			(at 0.40005 0 270)
			(size 0 0)
			(layers "B.Cu" "B.Mask" "B.Paste")
			(net "P1V8_PEX")
		)
		(pad "2" smd circle
			(at -0.40005 0 270)
			(size 0 0)
			(layers "B.Cu" "B.Mask" "B.Paste")
			(net "SMB_PEX2_MUX_SDA")
		)
	)
	(footprint ""
		(layer "B.Cu")
		(at 136.078214 -201.332846)
		(property "Reference" "C2601"
			(at 0 0 0)
			(layer "B.SilkS")
			(hide yes)
			(effects
				(font
					(size 1.27 1.27)
				)
				(justify mirror)
			)
		)
		(property "Value" ""
			(at 0 0 0)
			(layer "B.Fab")
			(effects
				(font
					(size 1.27 1.27)
				)
				(justify mirror)
			)
		)
		(duplicate_pad_numbers_are_jumpers no)
		(fp_line
			(start -0.7874 -0.4064)
			(end -0.7874 0.4064)
			(stroke
				(width 0.1524)
				(type default)
			)
			(layer "B.SilkS")
		)
		(fp_line
			(start -0.7874 0.4064)
			(end 0.7874 0.4064)
			(stroke
				(width 0.1524)
				(type default)
			)
			(layer "B.SilkS")
		)
		(fp_line
			(start 0.7874 -0.4064)
			(end -0.7874 -0.4064)
			(stroke
				(width 0.1524)
				(type default)
			)
			(layer "B.SilkS")
		)
		(fp_line
			(start 0.7874 0.4064)
			(end 0.7874 -0.4064)
			(stroke
				(width 0.1524)
				(type default)
			)
			(layer "B.SilkS")
		)
		(fp_line
			(start -0.67945 -0.3048)
			(end -0.67945 0.3048)
			(stroke
				(width 0.1)
				(type default)
			)
			(layer "B.Fab")
		)
		(fp_line
			(start -0.67945 0.3048)
			(end -0.120396 0.3048)
			(stroke
				(width 0.1)
				(type default)
			)
			(layer "B.Fab")
		)
		(fp_line
			(start -0.12065 -0.3048)
			(end -0.67945 -0.3048)
			(stroke
				(width 0.1)
				(type default)
			)
			(layer "B.Fab")
		)
		(fp_line
			(start -0.12065 -0.2794)
			(end -0.12065 -0.3048)
			(stroke
				(width 0.1)
				(type default)
			)
			(layer "B.Fab")
		)
		(fp_line
			(start -0.120396 0.2794)
			(end 0.12065 0.2794)
			(stroke
				(width 0.1)
				(type default)
			)
			(layer "B.Fab")
		)
		(fp_line
			(start -0.120396 0.3048)
			(end -0.120396 0.2794)
			(stroke
				(width 0.1)
				(type default)
			)
			(layer "B.Fab")
		)
		(fp_line
			(start 0.12065 -0.305054)
			(end 0.12065 -0.2794)
			(stroke
				(width 0.1)
				(type default)
			)
			(layer "B.Fab")
		)
		(fp_line
			(start 0.12065 -0.2794)
			(end -0.12065 -0.2794)
			(stroke
				(width 0.1)
				(type default)
			)
			(layer "B.Fab")
		)
		(fp_line
			(start 0.12065 0.2794)
			(end 0.12065 0.3048)
			(stroke
				(width 0.1)
				(type default)
			)
			(layer "B.Fab")
		)
		(fp_line
			(start 0.12065 0.3048)
			(end 0.67945 0.3048)
			(stroke
				(width 0.1)
				(type default)
			)
			(layer "B.Fab")
		)
		(fp_line
			(start 0.67945 -0.305054)
			(end 0.12065 -0.305054)
			(stroke
				(width 0.1)
				(type default)
			)
			(layer "B.Fab")
		)
		(fp_line
			(start 0.67945 0.3048)
			(end 0.67945 -0.305054)
			(stroke
				(width 0.1)
				(type default)
			)
			(layer "B.Fab")
		)
		(pad "1" smd circle
			(at 0.40005 0 180)
			(size 0 0)
			(layers "B.Cu" "B.Mask" "B.Paste")
			(net "P3V3_CLI_VPHY")
		)
		(pad "2" smd circle
			(at -0.40005 0 180)
			(size 0 0)
			(layers "B.Cu" "B.Mask" "B.Paste")
			(net "GND")
		)
	)
	(footprint ""
		(layer "B.Cu")
		(at 291.46119 -203.363068)
		(property "Reference" "R1039"
			(at 0 0 0)
			(layer "B.SilkS")
			(hide yes)
			(effects
				(font
					(size 1.27 1.27)
				)
				(justify mirror)
			)
		)
		(property "Value" ""
			(at 0 0 0)
			(layer "B.Fab")
			(effects
				(font
					(size 1.27 1.27)
				)
				(justify mirror)
			)
		)
		(duplicate_pad_numbers_are_jumpers no)
		(fp_line
			(start -0.7874 -0.4064)
			(end -0.7874 0.4064)
			(stroke
				(width 0.1524)
				(type default)
			)
			(layer "B.SilkS")
		)
		(fp_line
			(start -0.7874 0.4064)
			(end 0.7874 0.4064)
			(stroke
				(width 0.1524)
				(type default)
			)
			(layer "B.SilkS")
		)
		(fp_line
			(start 0.7874 -0.4064)
			(end -0.7874 -0.4064)
			(stroke
				(width 0.1524)
				(type default)
			)
			(layer "B.SilkS")
		)
		(fp_line
			(start 0.7874 0.4064)
			(end 0.7874 -0.4064)
			(stroke
				(width 0.1524)
				(type default)
			)
			(layer "B.SilkS")
		)
		(fp_line
			(start -0.67945 -0.3048)
			(end -0.67945 0.3048)
			(stroke
				(width 0.1)
				(type default)
			)
			(layer "B.Fab")
		)
		(fp_line
			(start -0.67945 0.3048)
			(end -0.120396 0.3048)
			(stroke
				(width 0.1)
				(type default)
			)
			(layer "B.Fab")
		)
		(fp_line
			(start -0.12065 -0.3048)
			(end -0.67945 -0.3048)
			(stroke
				(width 0.1)
				(type default)
			)
			(layer "B.Fab")
		)
		(fp_line
			(start -0.12065 -0.2794)
			(end -0.12065 -0.3048)
			(stroke
				(width 0.1)
				(type default)
			)
			(layer "B.Fab")
		)
		(fp_line
			(start -0.120396 0.2794)
			(end 0.12065 0.2794)
			(stroke
				(width 0.1)
				(type default)
			)
			(layer "B.Fab")
		)
		(fp_line
			(start -0.120396 0.3048)
			(end -0.120396 0.2794)
			(stroke
				(width 0.1)
				(type default)
			)
			(layer "B.Fab")
		)
		(fp_line
			(start 0.12065 -0.305054)
			(end 0.12065 -0.2794)
			(stroke
				(width 0.1)
				(type default)
			)
			(layer "B.Fab")
		)
		(fp_line
			(start 0.12065 -0.2794)
			(end -0.12065 -0.2794)
			(stroke
				(width 0.1)
				(type default)
			)
			(layer "B.Fab")
		)
		(fp_line
			(start 0.12065 0.2794)
			(end 0.12065 0.3048)
			(stroke
				(width 0.1)
				(type default)
			)
			(layer "B.Fab")
		)
		(fp_line
			(start 0.12065 0.3048)
			(end 0.67945 0.3048)
			(stroke
				(width 0.1)
				(type default)
			)
			(layer "B.Fab")
		)
		(fp_line
			(start 0.67945 -0.305054)
			(end 0.12065 -0.305054)
			(stroke
				(width 0.1)
				(type default)
			)
			(layer "B.Fab")
		)
		(fp_line
			(start 0.67945 0.3048)
			(end 0.67945 -0.305054)
			(stroke
				(width 0.1)
				(type default)
			)
			(layer "B.Fab")
		)
		(pad "1" smd circle
			(at 0.40005 0 180)
			(size 0 0)
			(layers "B.Cu" "B.Mask" "B.Paste")
			(net "SPI_BIC1_MOSI_LS23_DIR3")
		)
		(pad "2" smd circle
			(at -0.40005 0 180)
			(size 0 0)
			(layers "B.Cu" "B.Mask" "B.Paste")
			(net "P1V8_PEX")
		)
	)
	(footprint ""
		(layer "B.Cu")
		(at 291.367718 -286.18434 90)
		(property "Reference" "C3292"
			(at 0 0 90)
			(layer "B.SilkS")
			(hide yes)
			(effects
				(font
					(size 1.27 1.27)
				)
				(justify mirror)
			)
		)
		(property "Value" ""
			(at 0 0 90)
			(layer "B.Fab")
			(effects
				(font
					(size 1.27 1.27)
				)
				(justify mirror)
			)
		)
		(duplicate_pad_numbers_are_jumpers no)
		(fp_line
			(start 1.2954 -0.5842)
			(end -1.2954 -0.5842)
			(stroke
				(width 0.1524)
				(type default)
			)
			(layer "B.SilkS")
		)
		(fp_line
			(start -1.2954 -0.5842)
			(end -1.2954 0.5842)
			(stroke
				(width 0.1524)
				(type default)
			)
			(layer "B.SilkS")
		)
		(fp_line
			(start 1.2954 0.5842)
			(end 1.2954 -0.5842)
			(stroke
				(width 0.1524)
				(type default)
			)
			(layer "B.SilkS")
		)
		(fp_line
			(start -1.2954 0.5842)
			(end 1.2954 0.5842)
			(stroke
				(width 0.1524)
				(type default)
			)
			(layer "B.SilkS")
		)
		(fp_line
			(start 0.8636 -0.4572)
			(end -0.8636 -0.4572)
			(stroke
				(width 0.1)
				(type default)
			)
			(layer "B.Fab")
		)
		(fp_line
			(start -0.8636 -0.4572)
			(end -0.8636 -0.4064)
			(stroke
				(width 0.1)
				(type default)
			)
			(layer "B.Fab")
		)
		(fp_line
			(start 1.1938 -0.4064)
			(end 0.8636 -0.4064)
			(stroke
				(width 0.1)
				(type default)
			)
			(layer "B.Fab")
		)
		(fp_line
			(start 0.8636 -0.4064)
			(end 0.8636 -0.4572)
			(stroke
				(width 0.1)
				(type default)
			)
			(layer "B.Fab")
		)
		(fp_line
			(start -0.8636 -0.4064)
			(end -1.1938 -0.4064)
			(stroke
				(width 0.1)
				(type default)
			)
			(layer "B.Fab")
		)
		(fp_line
			(start -1.1938 -0.4064)
			(end -1.1938 0.4064)
			(stroke
				(width 0.1)
				(type default)
			)
			(layer "B.Fab")
		)
		(fp_line
			(start 1.1938 0.4064)
			(end 1.1938 -0.4064)
			(stroke
				(width 0.1)
				(type default)
			)
			(layer "B.Fab")
		)
		(fp_line
			(start 0.8636 0.4064)
			(end 1.1938 0.4064)
			(stroke
				(width 0.1)
				(type default)
			)
			(layer "B.Fab")
		)
		(fp_line
			(start -0.8636 0.4064)
			(end -0.8636 0.4572)
			(stroke
				(width 0.1)
				(type default)
			)
			(layer "B.Fab")
		)
		(fp_line
			(start -1.1938 0.4064)
			(end -0.8636 0.4064)
			(stroke
				(width 0.1)
				(type default)
			)
			(layer "B.Fab")
		)
		(fp_line
			(start 0.8636 0.4572)
			(end 0.8636 0.4064)
			(stroke
				(width 0.1)
				(type default)
			)
			(layer "B.Fab")
		)
		(fp_line
			(start -0.8636 0.4572)
			(end 0.8636 0.4572)
			(stroke
				(width 0.1)
				(type default)
			)
			(layer "B.Fab")
		)
		(pad "1" smd rect
			(at 0.7366 0)
			(size 0.7112 0.8128)
			(layers "B.Cu" "B.Mask" "B.Paste")
			(net "P1V25_SERDES_VDDPLL_PEX2")
		)
		(pad "2" smd rect
			(at -0.7366 0)
			(size 0.7112 0.8128)
			(layers "B.Cu" "B.Mask" "B.Paste")
			(net "GND")
		)
	)
	(footprint ""
		(layer "B.Cu")
		(at 278.554942 -297.32478)
		(property "Reference" "C3377"
			(at 0 0 0)
			(layer "B.SilkS")
			(hide yes)
			(effects
				(font
					(size 1.27 1.27)
				)
				(justify mirror)
			)
		)
		(property "Value" ""
			(at 0 0 0)
			(layer "B.Fab")
			(effects
				(font
					(size 1.27 1.27)
				)
				(justify mirror)
			)
		)
		(duplicate_pad_numbers_are_jumpers no)
		(fp_line
			(start -0.299974 -0.150114)
			(end -0.299974 0.150114)
			(stroke
				(width 0.1)
				(type default)
			)
			(layer "B.Fab")
		)
		(fp_line
			(start -0.299974 0.150114)
			(end 0.299974 0.150114)
			(stroke
				(width 0.1)
				(type default)
			)
			(layer "B.Fab")
		)
		(fp_line
			(start 0.299974 -0.150114)
			(end -0.299974 -0.150114)
			(stroke
				(width 0.1)
				(type default)
			)
			(layer "B.Fab")
		)
		(fp_line
			(start 0.299974 0.150114)
			(end 0.299974 -0.150114)
			(stroke
				(width 0.1)
				(type default)
			)
			(layer "B.Fab")
		)
		(pad "1" smd rect
			(at 0.2667 0 180)
			(size 0.3048 0.381)
			(layers "B.Cu" "B.Mask" "B.Paste")
			(net "PCEPLL2_VDDA18_PEX2")
		)
		(pad "2" smd rect
			(at -0.2667 0 180)
			(size 0.3048 0.381)
			(layers "B.Cu" "B.Mask" "B.Paste")
			(net "GND")
		)
	)
	(footprint ""
		(layer "B.Cu")
		(at 414.599882 -301.599854 -90)
		(property "Reference" "C1937"
			(at 0 0 90)
			(layer "B.SilkS")
			(hide yes)
			(effects
				(font
					(size 1.27 1.27)
				)
				(justify mirror)
			)
		)
		(property "Value" ""
			(at 0 0 90)
			(layer "B.Fab")
			(effects
				(font
					(size 1.27 1.27)
				)
				(justify mirror)
			)
		)
		(duplicate_pad_numbers_are_jumpers no)
		(fp_line
			(start -0.299974 0.150114)
			(end 0.299974 0.150114)
			(stroke
				(width 0.1)
				(type default)
			)
			(layer "B.Fab")
		)
		(fp_line
			(start 0.299974 0.150114)
			(end 0.299974 -0.150114)
			(stroke
				(width 0.1)
				(type default)
			)
			(layer "B.Fab")
		)
		(fp_line
			(start -0.299974 -0.150114)
			(end -0.299974 0.150114)
			(stroke
				(width 0.1)
				(type default)
			)
			(layer "B.Fab")
		)
		(fp_line
			(start 0.299974 -0.150114)
			(end -0.299974 -0.150114)
			(stroke
				(width 0.1)
				(type default)
			)
			(layer "B.Fab")
		)
		(pad "1" smd rect
			(at 0.2667 0 90)
			(size 0.3048 0.381)
			(layers "B.Cu" "B.Mask" "B.Paste")
			(net "P0V8_SERDES_VDDA_PEX3")
		)
		(pad "2" smd rect
			(at -0.2667 0 90)
			(size 0.3048 0.381)
			(layers "B.Cu" "B.Mask" "B.Paste")
			(net "GND")
		)
	)
	(footprint ""
		(layer "B.Cu")
		(at 144.841214 -204.380846 -90)
		(property "Reference" "C2589"
			(at 0 0 90)
			(layer "B.SilkS")
			(hide yes)
			(effects
				(font
					(size 1.27 1.27)
				)
				(justify mirror)
			)
		)
		(property "Value" ""
			(at 0 0 90)
			(layer "B.Fab")
			(effects
				(font
					(size 1.27 1.27)
				)
				(justify mirror)
			)
		)
		(duplicate_pad_numbers_are_jumpers no)
		(fp_line
			(start -0.7874 0.4064)
			(end 0.7874 0.4064)
			(stroke
				(width 0.1524)
				(type default)
			)
			(layer "B.SilkS")
		)
		(fp_line
			(start 0.7874 0.4064)
			(end 0.7874 -0.4064)
			(stroke
				(width 0.1524)
				(type default)
			)
			(layer "B.SilkS")
		)
		(fp_line
			(start -0.7874 -0.4064)
			(end -0.7874 0.4064)
			(stroke
				(width 0.1524)
				(type default)
			)
			(layer "B.SilkS")
		)
		(fp_line
			(start 0.7874 -0.4064)
			(end -0.7874 -0.4064)
			(stroke
				(width 0.1524)
				(type default)
			)
			(layer "B.SilkS")
		)
		(fp_line
			(start -0.67945 0.3048)
			(end -0.120396 0.3048)
			(stroke
				(width 0.1)
				(type default)
			)
			(layer "B.Fab")
		)
		(fp_line
			(start -0.120396 0.3048)
			(end -0.120396 0.2794)
			(stroke
				(width 0.1)
				(type default)
			)
			(layer "B.Fab")
		)
		(fp_line
			(start 0.12065 0.3048)
			(end 0.67945 0.3048)
			(stroke
				(width 0.1)
				(type default)
			)
			(layer "B.Fab")
		)
		(fp_line
			(start 0.67945 0.3048)
			(end 0.67945 -0.305054)
			(stroke
				(width 0.1)
				(type default)
			)
			(layer "B.Fab")
		)
		(fp_line
			(start -0.120396 0.2794)
			(end 0.12065 0.2794)
			(stroke
				(width 0.1)
				(type default)
			)
			(layer "B.Fab")
		)
		(fp_line
			(start 0.12065 0.2794)
			(end 0.12065 0.3048)
			(stroke
				(width 0.1)
				(type default)
			)
			(layer "B.Fab")
		)
		(fp_line
			(start -0.12065 -0.2794)
			(end -0.12065 -0.3048)
			(stroke
				(width 0.1)
				(type default)
			)
			(layer "B.Fab")
		)
		(fp_line
			(start 0.12065 -0.2794)
			(end -0.12065 -0.2794)
			(stroke
				(width 0.1)
				(type default)
			)
			(layer "B.Fab")
		)
		(fp_line
			(start -0.67945 -0.3048)
			(end -0.67945 0.3048)
			(stroke
				(width 0.1)
				(type default)
			)
			(layer "B.Fab")
		)
		(fp_line
			(start -0.12065 -0.3048)
			(end -0.67945 -0.3048)
			(stroke
				(width 0.1)
				(type default)
			)
			(layer "B.Fab")
		)
		(fp_line
			(start 0.12065 -0.305054)
			(end 0.12065 -0.2794)
			(stroke
				(width 0.1)
				(type default)
			)
			(layer "B.Fab")
		)
		(fp_line
			(start 0.67945 -0.305054)
			(end 0.12065 -0.305054)
			(stroke
				(width 0.1)
				(type default)
			)
			(layer "B.Fab")
		)
		(pad "1" smd circle
			(at 0.40005 0 90)
			(size 0 0)
			(layers "B.Cu" "B.Mask" "B.Paste")
			(net "P3V3_AUX")
		)
		(pad "2" smd circle
			(at -0.40005 0 90)
			(size 0 0)
			(layers "B.Cu" "B.Mask" "B.Paste")
			(net "GND")
		)
	)
	(footprint ""
		(layer "B.Cu")
		(at 118.688358 -277.639272)
		(property "Reference" "PC6611"
			(at 0 0 0)
			(layer "B.SilkS")
			(hide yes)
			(effects
				(font
					(size 1.27 1.27)
				)
				(justify mirror)
			)
		)
		(property "Value" ""
			(at 0 0 0)
			(layer "B.Fab")
			(effects
				(font
					(size 1.27 1.27)
				)
				(justify mirror)
			)
		)
		(duplicate_pad_numbers_are_jumpers no)
		(fp_line
			(start -1.524 -0.762)
			(end -1.524 0.762)
			(stroke
				(width 0.1524)
				(type default)
			)
			(layer "B.SilkS")
		)
		(fp_line
			(start -1.524 0.762)
			(end 1.524 0.762)
			(stroke
				(width 0.1524)
				(type default)
			)
			(layer "B.SilkS")
		)
		(fp_line
			(start 1.524 -0.762)
			(end -1.524 -0.762)
			(stroke
				(width 0.1524)
				(type default)
			)
			(layer "B.SilkS")
		)
		(fp_line
			(start 1.524 0.762)
			(end 1.524 -0.762)
			(stroke
				(width 0.1524)
				(type default)
			)
			(layer "B.SilkS")
		)
		(fp_line
			(start -1.1049 -0.724916)
			(end 1.1049 -0.724916)
			(stroke
				(width 0.1)
				(type default)
			)
			(layer "B.Fab")
		)
		(fp_line
			(start -1.1049 0.724916)
			(end -1.1049 -0.724916)
			(stroke
				(width 0.1)
				(type default)
			)
			(layer "B.Fab")
		)
		(fp_line
			(start 1.1049 -0.724916)
			(end 1.1049 0.724916)
			(stroke
				(width 0.1)
				(type default)
			)
			(layer "B.Fab")
		)
		(fp_line
			(start 1.1049 0.724916)
			(end -1.1049 0.724916)
			(stroke
				(width 0.1)
				(type default)
			)
			(layer "B.Fab")
		)
		(pad "1" smd rect
			(at 0.889 0)
			(size 1.016 1.27)
			(layers "B.Cu" "B.Mask" "B.Paste")
			(net "SW_P12V_P0V8_PEX1_FLT")
		)
		(pad "2" smd rect
			(at -0.889 0)
			(size 1.016 1.27)
			(layers "B.Cu" "B.Mask" "B.Paste")
			(net "GND")
		)
	)
	(footprint ""
		(layer "B.Cu")
		(at 138.618214 -203.237846 -90)
		(property "Reference" "R917"
			(at 0 0 90)
			(layer "B.SilkS")
			(hide yes)
			(effects
				(font
					(size 1.27 1.27)
				)
				(justify mirror)
			)
		)
		(property "Value" ""
			(at 0 0 90)
			(layer "B.Fab")
			(effects
				(font
					(size 1.27 1.27)
				)
				(justify mirror)
			)
		)
		(duplicate_pad_numbers_are_jumpers no)
		(fp_line
			(start -0.7874 0.4064)
			(end 0.7874 0.4064)
			(stroke
				(width 0.1524)
				(type default)
			)
			(layer "B.SilkS")
		)
		(fp_line
			(start 0.7874 0.4064)
			(end 0.7874 -0.4064)
			(stroke
				(width 0.1524)
				(type default)
			)
			(layer "B.SilkS")
		)
		(fp_line
			(start -0.7874 -0.4064)
			(end -0.7874 0.4064)
			(stroke
				(width 0.1524)
				(type default)
			)
			(layer "B.SilkS")
		)
		(fp_line
			(start 0.7874 -0.4064)
			(end -0.7874 -0.4064)
			(stroke
				(width 0.1524)
				(type default)
			)
			(layer "B.SilkS")
		)
		(fp_line
			(start -0.67945 0.3048)
			(end -0.120396 0.3048)
			(stroke
				(width 0.1)
				(type default)
			)
			(layer "B.Fab")
		)
		(fp_line
			(start -0.120396 0.3048)
			(end -0.120396 0.2794)
			(stroke
				(width 0.1)
				(type default)
			)
			(layer "B.Fab")
		)
		(fp_line
			(start 0.12065 0.3048)
			(end 0.67945 0.3048)
			(stroke
				(width 0.1)
				(type default)
			)
			(layer "B.Fab")
		)
		(fp_line
			(start 0.67945 0.3048)
			(end 0.67945 -0.305054)
			(stroke
				(width 0.1)
				(type default)
			)
			(layer "B.Fab")
		)
		(fp_line
			(start -0.120396 0.2794)
			(end 0.12065 0.2794)
			(stroke
				(width 0.1)
				(type default)
			)
			(layer "B.Fab")
		)
		(fp_line
			(start 0.12065 0.2794)
			(end 0.12065 0.3048)
			(stroke
				(width 0.1)
				(type default)
			)
			(layer "B.Fab")
		)
		(fp_line
			(start -0.12065 -0.2794)
			(end -0.12065 -0.3048)
			(stroke
				(width 0.1)
				(type default)
			)
			(layer "B.Fab")
		)
		(fp_line
			(start 0.12065 -0.2794)
			(end -0.12065 -0.2794)
			(stroke
				(width 0.1)
				(type default)
			)
			(layer "B.Fab")
		)
		(fp_line
			(start -0.67945 -0.3048)
			(end -0.67945 0.3048)
			(stroke
				(width 0.1)
				(type default)
			)
			(layer "B.Fab")
		)
		(fp_line
			(start -0.12065 -0.3048)
			(end -0.67945 -0.3048)
			(stroke
				(width 0.1)
				(type default)
			)
			(layer "B.Fab")
		)
		(fp_line
			(start 0.12065 -0.305054)
			(end 0.12065 -0.2794)
			(stroke
				(width 0.1)
				(type default)
			)
			(layer "B.Fab")
		)
		(fp_line
			(start 0.67945 -0.305054)
			(end 0.12065 -0.305054)
			(stroke
				(width 0.1)
				(type default)
			)
			(layer "B.Fab")
		)
		(pad "1" smd circle
			(at 0.40005 0 90)
			(size 0 0)
			(layers "B.Cu" "B.Mask" "B.Paste")
			(net "FT4232_CLI_REF")
		)
		(pad "2" smd circle
			(at -0.40005 0 90)
			(size 0 0)
			(layers "B.Cu" "B.Mask" "B.Paste")
			(net "GND")
		)
	)
	(footprint ""
		(layer "B.Cu")
		(at 115.919758 -260.400546 -90)
		(property "Reference" "PR95"
			(at 0 0 90)
			(layer "B.SilkS")
			(hide yes)
			(effects
				(font
					(size 1.27 1.27)
				)
				(justify mirror)
			)
		)
		(property "Value" ""
			(at 0 0 90)
			(layer "B.Fab")
			(effects
				(font
					(size 1.27 1.27)
				)
				(justify mirror)
			)
		)
		(duplicate_pad_numbers_are_jumpers no)
		(fp_line
			(start -0.7874 0.4064)
			(end 0.7874 0.4064)
			(stroke
				(width 0.1524)
				(type default)
			)
			(layer "B.SilkS")
		)
		(fp_line
			(start 0.7874 0.4064)
			(end 0.7874 -0.4064)
			(stroke
				(width 0.1524)
				(type default)
			)
			(layer "B.SilkS")
		)
		(fp_line
			(start -0.7874 -0.4064)
			(end -0.7874 0.4064)
			(stroke
				(width 0.1524)
				(type default)
			)
			(layer "B.SilkS")
		)
		(fp_line
			(start 0.7874 -0.4064)
			(end -0.7874 -0.4064)
			(stroke
				(width 0.1524)
				(type default)
			)
			(layer "B.SilkS")
		)
		(fp_line
			(start -0.67945 0.3048)
			(end -0.120396 0.3048)
			(stroke
				(width 0.1)
				(type default)
			)
			(layer "B.Fab")
		)
		(fp_line
			(start -0.120396 0.3048)
			(end -0.120396 0.2794)
			(stroke
				(width 0.1)
				(type default)
			)
			(layer "B.Fab")
		)
		(fp_line
			(start 0.12065 0.3048)
			(end 0.67945 0.3048)
			(stroke
				(width 0.1)
				(type default)
			)
			(layer "B.Fab")
		)
		(fp_line
			(start 0.67945 0.3048)
			(end 0.67945 -0.305054)
			(stroke
				(width 0.1)
				(type default)
			)
			(layer "B.Fab")
		)
		(fp_line
			(start -0.120396 0.2794)
			(end 0.12065 0.2794)
			(stroke
				(width 0.1)
				(type default)
			)
			(layer "B.Fab")
		)
		(fp_line
			(start 0.12065 0.2794)
			(end 0.12065 0.3048)
			(stroke
				(width 0.1)
				(type default)
			)
			(layer "B.Fab")
		)
		(fp_line
			(start -0.12065 -0.2794)
			(end -0.12065 -0.3048)
			(stroke
				(width 0.1)
				(type default)
			)
			(layer "B.Fab")
		)
		(fp_line
			(start 0.12065 -0.2794)
			(end -0.12065 -0.2794)
			(stroke
				(width 0.1)
				(type default)
			)
			(layer "B.Fab")
		)
		(fp_line
			(start -0.67945 -0.3048)
			(end -0.67945 0.3048)
			(stroke
				(width 0.1)
				(type default)
			)
			(layer "B.Fab")
		)
		(fp_line
			(start -0.12065 -0.3048)
			(end -0.67945 -0.3048)
			(stroke
				(width 0.1)
				(type default)
			)
			(layer "B.Fab")
		)
		(fp_line
			(start 0.12065 -0.305054)
			(end 0.12065 -0.2794)
			(stroke
				(width 0.1)
				(type default)
			)
			(layer "B.Fab")
		)
		(fp_line
			(start 0.67945 -0.305054)
			(end 0.12065 -0.305054)
			(stroke
				(width 0.1)
				(type default)
			)
			(layer "B.Fab")
		)
		(pad "1" smd circle
			(at 0.40005 0 90)
			(size 0 0)
			(layers "B.Cu" "B.Mask" "B.Paste")
			(net "P0V8_PEX0_TSEN_R")
		)
		(pad "2" smd circle
			(at -0.40005 0 90)
			(size 0 0)
			(layers "B.Cu" "B.Mask" "B.Paste")
			(net "P0V8_PEX0_TSEN")
		)
	)
	(footprint ""
		(layer "B.Cu")
		(at 364.453932 -223.937068 90)
		(property "Reference" "R3497"
			(at 0 0 90)
			(layer "B.SilkS")
			(hide yes)
			(effects
				(font
					(size 1.27 1.27)
				)
				(justify mirror)
			)
		)
		(property "Value" ""
			(at 0 0 90)
			(layer "B.Fab")
			(effects
				(font
					(size 1.27 1.27)
				)
				(justify mirror)
			)
		)
		(duplicate_pad_numbers_are_jumpers no)
		(fp_line
			(start 0.7874 -0.4064)
			(end -0.7874 -0.4064)
			(stroke
				(width 0.1524)
				(type default)
			)
			(layer "B.SilkS")
		)
		(fp_line
			(start -0.7874 -0.4064)
			(end -0.7874 0.4064)
			(stroke
				(width 0.1524)
				(type default)
			)
			(layer "B.SilkS")
		)
		(fp_line
			(start 0.7874 0.4064)
			(end 0.7874 -0.4064)
			(stroke
				(width 0.1524)
				(type default)
			)
			(layer "B.SilkS")
		)
		(fp_line
			(start -0.7874 0.4064)
			(end 0.7874 0.4064)
			(stroke
				(width 0.1524)
				(type default)
			)
			(layer "B.SilkS")
		)
		(fp_line
			(start 0.67945 -0.305054)
			(end 0.12065 -0.305054)
			(stroke
				(width 0.1)
				(type default)
			)
			(layer "B.Fab")
		)
		(fp_line
			(start 0.12065 -0.305054)
			(end 0.12065 -0.2794)
			(stroke
				(width 0.1)
				(type default)
			)
			(layer "B.Fab")
		)
		(fp_line
			(start -0.12065 -0.3048)
			(end -0.67945 -0.3048)
			(stroke
				(width 0.1)
				(type default)
			)
			(layer "B.Fab")
		)
		(fp_line
			(start -0.67945 -0.3048)
			(end -0.67945 0.3048)
			(stroke
				(width 0.1)
				(type default)
			)
			(layer "B.Fab")
		)
		(fp_line
			(start 0.12065 -0.2794)
			(end -0.12065 -0.2794)
			(stroke
				(width 0.1)
				(type default)
			)
			(layer "B.Fab")
		)
		(fp_line
			(start -0.12065 -0.2794)
			(end -0.12065 -0.3048)
			(stroke
				(width 0.1)
				(type default)
			)
			(layer "B.Fab")
		)
		(fp_line
			(start 0.12065 0.2794)
			(end 0.12065 0.3048)
			(stroke
				(width 0.1)
				(type default)
			)
			(layer "B.Fab")
		)
		(fp_line
			(start -0.120396 0.2794)
			(end 0.12065 0.2794)
			(stroke
				(width 0.1)
				(type default)
			)
			(layer "B.Fab")
		)
		(fp_line
			(start 0.67945 0.3048)
			(end 0.67945 -0.305054)
			(stroke
				(width 0.1)
				(type default)
			)
			(layer "B.Fab")
		)
		(fp_line
			(start 0.12065 0.3048)
			(end 0.67945 0.3048)
			(stroke
				(width 0.1)
				(type default)
			)
			(layer "B.Fab")
		)
		(fp_line
			(start -0.120396 0.3048)
			(end -0.120396 0.2794)
			(stroke
				(width 0.1)
				(type default)
			)
			(layer "B.Fab")
		)
		(fp_line
			(start -0.67945 0.3048)
			(end -0.120396 0.3048)
			(stroke
				(width 0.1)
				(type default)
			)
			(layer "B.Fab")
		)
		(pad "1" smd circle
			(at 0.40005 0 270)
			(size 0 0)
			(layers "B.Cu" "B.Mask" "B.Paste")
			(net "SPI_MUX_PEX3_EN_N")
		)
		(pad "2" smd circle
			(at -0.40005 0 270)
			(size 0 0)
			(layers "B.Cu" "B.Mask" "B.Paste")
			(net "GND")
		)
	)
	(footprint ""
		(layer "B.Cu")
		(at 180.50002 -301.599854 -90)
		(property "Reference" "C1475"
			(at 0 0 90)
			(layer "B.SilkS")
			(hide yes)
			(effects
				(font
					(size 1.27 1.27)
				)
				(justify mirror)
			)
		)
		(property "Value" ""
			(at 0 0 90)
			(layer "B.Fab")
			(effects
				(font
					(size 1.27 1.27)
				)
				(justify mirror)
			)
		)
		(duplicate_pad_numbers_are_jumpers no)
		(fp_line
			(start -0.299974 0.150114)
			(end 0.299974 0.150114)
			(stroke
				(width 0.1)
				(type default)
			)
			(layer "B.Fab")
		)
		(fp_line
			(start 0.299974 0.150114)
			(end 0.299974 -0.150114)
			(stroke
				(width 0.1)
				(type default)
			)
			(layer "B.Fab")
		)
		(fp_line
			(start -0.299974 -0.150114)
			(end -0.299974 0.150114)
			(stroke
				(width 0.1)
				(type default)
			)
			(layer "B.Fab")
		)
		(fp_line
			(start 0.299974 -0.150114)
			(end -0.299974 -0.150114)
			(stroke
				(width 0.1)
				(type default)
			)
			(layer "B.Fab")
		)
		(pad "1" smd rect
			(at 0.2667 0 90)
			(size 0.3048 0.381)
			(layers "B.Cu" "B.Mask" "B.Paste")
			(net "P0V8_SERDES_VDDA_PEX1")
		)
		(pad "2" smd rect
			(at -0.2667 0 90)
			(size 0.3048 0.381)
			(layers "B.Cu" "B.Mask" "B.Paste")
			(net "GND")
		)
	)
	(footprint ""
		(layer "B.Cu")
		(at 419.349936 -293.52494 180)
		(property "Reference" "C3452"
			(at 0 0 0)
			(layer "B.SilkS")
			(hide yes)
			(effects
				(font
					(size 1.27 1.27)
				)
				(justify mirror)
			)
		)
		(property "Value" ""
			(at 0 0 0)
			(layer "B.Fab")
			(effects
				(font
					(size 1.27 1.27)
				)
				(justify mirror)
			)
		)
		(duplicate_pad_numbers_are_jumpers no)
		(fp_line
			(start 0.299974 0.150114)
			(end 0.299974 -0.150114)
			(stroke
				(width 0.1)
				(type default)
			)
			(layer "B.Fab")
		)
		(fp_line
			(start 0.299974 -0.150114)
			(end -0.299974 -0.150114)
			(stroke
				(width 0.1)
				(type default)
			)
			(layer "B.Fab")
		)
		(fp_line
			(start -0.299974 0.150114)
			(end 0.299974 0.150114)
			(stroke
				(width 0.1)
				(type default)
			)
			(layer "B.Fab")
		)
		(fp_line
			(start -0.299974 -0.150114)
			(end -0.299974 0.150114)
			(stroke
				(width 0.1)
				(type default)
			)
			(layer "B.Fab")
		)
		(pad "1" smd rect
			(at 0.2667 0)
			(size 0.3048 0.381)
			(layers "B.Cu" "B.Mask" "B.Paste")
			(net "P1V25_PEX3")
		)
		(pad "2" smd rect
			(at -0.2667 0)
			(size 0.3048 0.381)
			(layers "B.Cu" "B.Mask" "B.Paste")
			(net "GND")
		)
	)
	(footprint ""
		(layer "B.Cu")
		(at 69.149976 -302.074834)
		(property "Reference" "C2992"
			(at 0 0 0)
			(layer "B.SilkS")
			(hide yes)
			(effects
				(font
					(size 1.27 1.27)
				)
				(justify mirror)
			)
		)
		(property "Value" ""
			(at 0 0 0)
			(layer "B.Fab")
			(effects
				(font
					(size 1.27 1.27)
				)
				(justify mirror)
			)
		)
		(duplicate_pad_numbers_are_jumpers no)
		(fp_line
			(start -0.299974 -0.150114)
			(end -0.299974 0.150114)
			(stroke
				(width 0.1)
				(type default)
			)
			(layer "B.Fab")
		)
		(fp_line
			(start -0.299974 0.150114)
			(end 0.299974 0.150114)
			(stroke
				(width 0.1)
				(type default)
			)
			(layer "B.Fab")
		)
		(fp_line
			(start 0.299974 -0.150114)
			(end -0.299974 -0.150114)
			(stroke
				(width 0.1)
				(type default)
			)
			(layer "B.Fab")
		)
		(fp_line
			(start 0.299974 0.150114)
			(end 0.299974 -0.150114)
			(stroke
				(width 0.1)
				(type default)
			)
			(layer "B.Fab")
		)
		(pad "1" smd rect
			(at 0.2667 0 180)
			(size 0.3048 0.381)
			(layers "B.Cu" "B.Mask" "B.Paste")
			(net "P1V8_PEX")
		)
		(pad "2" smd rect
			(at -0.2667 0 180)
			(size 0.3048 0.381)
			(layers "B.Cu" "B.Mask" "B.Paste")
			(net "GND")
		)
	)
	(footprint ""
		(layer "B.Cu")
		(at 409.374848 -297.79976 -90)
		(property "Reference" "C1909"
			(at 0 0 90)
			(layer "B.SilkS")
			(hide yes)
			(effects
				(font
					(size 1.27 1.27)
				)
				(justify mirror)
			)
		)
		(property "Value" ""
			(at 0 0 90)
			(layer "B.Fab")
			(effects
				(font
					(size 1.27 1.27)
				)
				(justify mirror)
			)
		)
		(duplicate_pad_numbers_are_jumpers no)
		(fp_line
			(start -0.299974 0.150114)
			(end 0.299974 0.150114)
			(stroke
				(width 0.1)
				(type default)
			)
			(layer "B.Fab")
		)
		(fp_line
			(start 0.299974 0.150114)
			(end 0.299974 -0.150114)
			(stroke
				(width 0.1)
				(type default)
			)
			(layer "B.Fab")
		)
		(fp_line
			(start -0.299974 -0.150114)
			(end -0.299974 0.150114)
			(stroke
				(width 0.1)
				(type default)
			)
			(layer "B.Fab")
		)
		(fp_line
			(start 0.299974 -0.150114)
			(end -0.299974 -0.150114)
			(stroke
				(width 0.1)
				(type default)
			)
			(layer "B.Fab")
		)
		(pad "1" smd rect
			(at 0.2667 0 90)
			(size 0.3048 0.381)
			(layers "B.Cu" "B.Mask" "B.Paste")
			(net "P0V8_PEX3")
		)
		(pad "2" smd rect
			(at -0.2667 0 90)
			(size 0.3048 0.381)
			(layers "B.Cu" "B.Mask" "B.Paste")
			(net "GND")
		)
	)
	(footprint ""
		(layer "B.Cu")
		(at 130.25882 -319.545462 -90)
		(property "Reference" "L30"
			(at 0 0 90)
			(layer "B.SilkS")
			(hide yes)
			(effects
				(font
					(size 1.27 1.27)
				)
				(justify mirror)
			)
		)
		(property "Value" ""
			(at 0 0 90)
			(layer "B.Fab")
			(effects
				(font
					(size 1.27 1.27)
				)
				(justify mirror)
			)
		)
		(duplicate_pad_numbers_are_jumpers no)
		(fp_line
			(start 2.248154 4.9911)
			(end -2.248154 4.9911)
			(stroke
				(width 0.1524)
				(type default)
			)
			(layer "B.SilkS")
		)
		(fp_line
			(start 2.248154 1.846834)
			(end 2.248154 4.9911)
			(stroke
				(width 0.1524)
				(type default)
			)
			(layer "B.SilkS")
		)
		(fp_line
			(start -2.248154 -4.9911)
			(end 2.248154 -4.9911)
			(stroke
				(width 0.1524)
				(type default)
			)
			(layer "B.SilkS")
		)
		(fp_line
			(start 2.248154 -4.9911)
			(end 2.248154 -2.276348)
			(stroke
				(width 0.1524)
				(type default)
			)
			(layer "B.SilkS")
		)
		(fp_line
			(start -1.700022 0.899922)
			(end -1.700022 -0.899922)
			(stroke
				(width 0.1)
				(type default)
			)
			(layer "B.Fab")
		)
		(fp_line
			(start 1.700022 0.899922)
			(end -1.700022 0.899922)
			(stroke
				(width 0.1)
				(type default)
			)
			(layer "B.Fab")
		)
		(fp_line
			(start -1.700022 -0.899922)
			(end 1.700022 -0.899922)
			(stroke
				(width 0.1)
				(type default)
			)
			(layer "B.Fab")
		)
		(fp_line
			(start 1.700022 -0.899922)
			(end 1.700022 0.899922)
			(stroke
				(width 0.1)
				(type default)
			)
			(layer "B.Fab")
		)
		(pad "1" smd rect
			(at 1.575054 0 90)
			(size 1.1684 9.8044)
			(layers "B.Cu" "B.Mask" "B.Paste")
			(net "P0V8_PEX1")
		)
		(pad "2" smd rect
			(at -1.575054 0 90)
			(size 1.1684 9.8044)
			(layers "B.Cu" "B.Mask" "B.Paste")
			(net "P0V8_SERDES_VDDA_PEX1")
		)
	)
	(footprint ""
		(layer "B.Cu")
		(at 400.349974 -288.299906 90)
		(property "Reference" "C3450"
			(at 0 0 90)
			(layer "B.SilkS")
			(hide yes)
			(effects
				(font
					(size 1.27 1.27)
				)
				(justify mirror)
			)
		)
		(property "Value" ""
			(at 0 0 90)
			(layer "B.Fab")
			(effects
				(font
					(size 1.27 1.27)
				)
				(justify mirror)
			)
		)
		(duplicate_pad_numbers_are_jumpers no)
		(fp_line
			(start 0.299974 -0.150114)
			(end -0.299974 -0.150114)
			(stroke
				(width 0.1)
				(type default)
			)
			(layer "B.Fab")
		)
		(fp_line
			(start -0.299974 -0.150114)
			(end -0.299974 0.150114)
			(stroke
				(width 0.1)
				(type default)
			)
			(layer "B.Fab")
		)
		(fp_line
			(start 0.299974 0.150114)
			(end 0.299974 -0.150114)
			(stroke
				(width 0.1)
				(type default)
			)
			(layer "B.Fab")
		)
		(fp_line
			(start -0.299974 0.150114)
			(end 0.299974 0.150114)
			(stroke
				(width 0.1)
				(type default)
			)
			(layer "B.Fab")
		)
		(pad "1" smd rect
			(at 0.2667 0 270)
			(size 0.3048 0.381)
			(layers "B.Cu" "B.Mask" "B.Paste")
			(net "P1V25_PEX3")
		)
		(pad "2" smd rect
			(at -0.2667 0 270)
			(size 0.3048 0.381)
			(layers "B.Cu" "B.Mask" "B.Paste")
			(net "GND")
		)
	)
	(footprint ""
		(layer "B.Cu")
		(at 286.624776 -286.399732 90)
		(property "Reference" "C3332"
			(at 0 0 90)
			(layer "B.SilkS")
			(hide yes)
			(effects
				(font
					(size 1.27 1.27)
				)
				(justify mirror)
			)
		)
		(property "Value" ""
			(at 0 0 90)
			(layer "B.Fab")
			(effects
				(font
					(size 1.27 1.27)
				)
				(justify mirror)
			)
		)
		(duplicate_pad_numbers_are_jumpers no)
		(fp_line
			(start 0.299974 -0.150114)
			(end -0.299974 -0.150114)
			(stroke
				(width 0.1)
				(type default)
			)
			(layer "B.Fab")
		)
		(fp_line
			(start -0.299974 -0.150114)
			(end -0.299974 0.150114)
			(stroke
				(width 0.1)
				(type default)
			)
			(layer "B.Fab")
		)
		(fp_line
			(start 0.299974 0.150114)
			(end 0.299974 -0.150114)
			(stroke
				(width 0.1)
				(type default)
			)
			(layer "B.Fab")
		)
		(fp_line
			(start -0.299974 0.150114)
			(end 0.299974 0.150114)
			(stroke
				(width 0.1)
				(type default)
			)
			(layer "B.Fab")
		)
		(pad "1" smd rect
			(at 0.2667 0 270)
			(size 0.3048 0.381)
			(layers "B.Cu" "B.Mask" "B.Paste")
			(net "P1V25_SERDES_VDDPLL_PEX2")
		)
		(pad "2" smd rect
			(at -0.2667 0 270)
			(size 0.3048 0.381)
			(layers "B.Cu" "B.Mask" "B.Paste")
			(net "GND")
		)
	)
	(footprint ""
		(layer "B.Cu")
		(at 292.79977 -290.199826 90)
		(property "Reference" "C1707"
			(at 0 0 90)
			(layer "B.SilkS")
			(hide yes)
			(effects
				(font
					(size 1.27 1.27)
				)
				(justify mirror)
			)
		)
		(property "Value" ""
			(at 0 0 90)
			(layer "B.Fab")
			(effects
				(font
					(size 1.27 1.27)
				)
				(justify mirror)
			)
		)
		(duplicate_pad_numbers_are_jumpers no)
		(fp_line
			(start 0.299974 -0.150114)
			(end -0.299974 -0.150114)
			(stroke
				(width 0.1)
				(type default)
			)
			(layer "B.Fab")
		)
		(fp_line
			(start -0.299974 -0.150114)
			(end -0.299974 0.150114)
			(stroke
				(width 0.1)
				(type default)
			)
			(layer "B.Fab")
		)
		(fp_line
			(start 0.299974 0.150114)
			(end 0.299974 -0.150114)
			(stroke
				(width 0.1)
				(type default)
			)
			(layer "B.Fab")
		)
		(fp_line
			(start -0.299974 0.150114)
			(end 0.299974 0.150114)
			(stroke
				(width 0.1)
				(type default)
			)
			(layer "B.Fab")
		)
		(pad "1" smd rect
			(at 0.2667 0 270)
			(size 0.3048 0.381)
			(layers "B.Cu" "B.Mask" "B.Paste")
			(net "P0V8_SERDES_VDDA_PEX2")
		)
		(pad "2" smd rect
			(at -0.2667 0 270)
			(size 0.3048 0.381)
			(layers "B.Cu" "B.Mask" "B.Paste")
			(net "GND")
		)
	)
	(footprint ""
		(layer "B.Cu")
		(at 349.135954 -260.400546 -90)
		(property "Reference" "PC135"
			(at 0 0 90)
			(layer "B.SilkS")
			(hide yes)
			(effects
				(font
					(size 1.27 1.27)
				)
				(justify mirror)
			)
		)
		(property "Value" ""
			(at 0 0 90)
			(layer "B.Fab")
			(effects
				(font
					(size 1.27 1.27)
				)
				(justify mirror)
			)
		)
		(duplicate_pad_numbers_are_jumpers no)
		(fp_line
			(start -0.7874 0.4064)
			(end 0.7874 0.4064)
			(stroke
				(width 0.1524)
				(type default)
			)
			(layer "B.SilkS")
		)
		(fp_line
			(start 0.7874 0.4064)
			(end 0.7874 -0.4064)
			(stroke
				(width 0.1524)
				(type default)
			)
			(layer "B.SilkS")
		)
		(fp_line
			(start -0.7874 -0.4064)
			(end -0.7874 0.4064)
			(stroke
				(width 0.1524)
				(type default)
			)
			(layer "B.SilkS")
		)
		(fp_line
			(start 0.7874 -0.4064)
			(end -0.7874 -0.4064)
			(stroke
				(width 0.1524)
				(type default)
			)
			(layer "B.SilkS")
		)
		(fp_line
			(start -0.67945 0.3048)
			(end -0.120396 0.3048)
			(stroke
				(width 0.1)
				(type default)
			)
			(layer "B.Fab")
		)
		(fp_line
			(start -0.120396 0.3048)
			(end -0.120396 0.2794)
			(stroke
				(width 0.1)
				(type default)
			)
			(layer "B.Fab")
		)
		(fp_line
			(start 0.12065 0.3048)
			(end 0.67945 0.3048)
			(stroke
				(width 0.1)
				(type default)
			)
			(layer "B.Fab")
		)
		(fp_line
			(start 0.67945 0.3048)
			(end 0.67945 -0.305054)
			(stroke
				(width 0.1)
				(type default)
			)
			(layer "B.Fab")
		)
		(fp_line
			(start -0.120396 0.2794)
			(end 0.12065 0.2794)
			(stroke
				(width 0.1)
				(type default)
			)
			(layer "B.Fab")
		)
		(fp_line
			(start 0.12065 0.2794)
			(end 0.12065 0.3048)
			(stroke
				(width 0.1)
				(type default)
			)
			(layer "B.Fab")
		)
		(fp_line
			(start -0.12065 -0.2794)
			(end -0.12065 -0.3048)
			(stroke
				(width 0.1)
				(type default)
			)
			(layer "B.Fab")
		)
		(fp_line
			(start 0.12065 -0.2794)
			(end -0.12065 -0.2794)
			(stroke
				(width 0.1)
				(type default)
			)
			(layer "B.Fab")
		)
		(fp_line
			(start -0.67945 -0.3048)
			(end -0.67945 0.3048)
			(stroke
				(width 0.1)
				(type default)
			)
			(layer "B.Fab")
		)
		(fp_line
			(start -0.12065 -0.3048)
			(end -0.67945 -0.3048)
			(stroke
				(width 0.1)
				(type default)
			)
			(layer "B.Fab")
		)
		(fp_line
			(start 0.12065 -0.305054)
			(end 0.12065 -0.2794)
			(stroke
				(width 0.1)
				(type default)
			)
			(layer "B.Fab")
		)
		(fp_line
			(start 0.67945 -0.305054)
			(end 0.12065 -0.305054)
			(stroke
				(width 0.1)
				(type default)
			)
			(layer "B.Fab")
		)
		(pad "1" smd circle
			(at 0.40005 0 90)
			(size 0 0)
			(layers "B.Cu" "B.Mask" "B.Paste")
			(net "P0V8_PEX2_TSEN_R")
		)
		(pad "2" smd circle
			(at -0.40005 0 90)
			(size 0 0)
			(layers "B.Cu" "B.Mask" "B.Paste")
			(net "GND")
		)
	)
	(footprint ""
		(layer "B.Cu")
		(at 122.96521 -260.469126 90)
		(property "Reference" "PR7134"
			(at 0 0 90)
			(layer "B.SilkS")
			(hide yes)
			(effects
				(font
					(size 1.27 1.27)
				)
				(justify mirror)
			)
		)
		(property "Value" ""
			(at 0 0 90)
			(layer "B.Fab")
			(effects
				(font
					(size 1.27 1.27)
				)
				(justify mirror)
			)
		)
		(duplicate_pad_numbers_are_jumpers no)
		(fp_line
			(start 0.7874 -0.4064)
			(end -0.7874 -0.4064)
			(stroke
				(width 0.1524)
				(type default)
			)
			(layer "B.SilkS")
		)
		(fp_line
			(start -0.7874 -0.4064)
			(end -0.7874 0.4064)
			(stroke
				(width 0.1524)
				(type default)
			)
			(layer "B.SilkS")
		)
		(fp_line
			(start 0.7874 0.4064)
			(end 0.7874 -0.4064)
			(stroke
				(width 0.1524)
				(type default)
			)
			(layer "B.SilkS")
		)
		(fp_line
			(start -0.7874 0.4064)
			(end 0.7874 0.4064)
			(stroke
				(width 0.1524)
				(type default)
			)
			(layer "B.SilkS")
		)
		(fp_line
			(start 0.67945 -0.305054)
			(end 0.12065 -0.305054)
			(stroke
				(width 0.1)
				(type default)
			)
			(layer "B.Fab")
		)
		(fp_line
			(start 0.12065 -0.305054)
			(end 0.12065 -0.2794)
			(stroke
				(width 0.1)
				(type default)
			)
			(layer "B.Fab")
		)
		(fp_line
			(start -0.12065 -0.3048)
			(end -0.67945 -0.3048)
			(stroke
				(width 0.1)
				(type default)
			)
			(layer "B.Fab")
		)
		(fp_line
			(start -0.67945 -0.3048)
			(end -0.67945 0.3048)
			(stroke
				(width 0.1)
				(type default)
			)
			(layer "B.Fab")
		)
		(fp_line
			(start 0.12065 -0.2794)
			(end -0.12065 -0.2794)
			(stroke
				(width 0.1)
				(type default)
			)
			(layer "B.Fab")
		)
		(fp_line
			(start -0.12065 -0.2794)
			(end -0.12065 -0.3048)
			(stroke
				(width 0.1)
				(type default)
			)
			(layer "B.Fab")
		)
		(fp_line
			(start 0.12065 0.2794)
			(end 0.12065 0.3048)
			(stroke
				(width 0.1)
				(type default)
			)
			(layer "B.Fab")
		)
		(fp_line
			(start -0.120396 0.2794)
			(end 0.12065 0.2794)
			(stroke
				(width 0.1)
				(type default)
			)
			(layer "B.Fab")
		)
		(fp_line
			(start 0.67945 0.3048)
			(end 0.67945 -0.305054)
			(stroke
				(width 0.1)
				(type default)
			)
			(layer "B.Fab")
		)
		(fp_line
			(start 0.12065 0.3048)
			(end 0.67945 0.3048)
			(stroke
				(width 0.1)
				(type default)
			)
			(layer "B.Fab")
		)
		(fp_line
			(start -0.120396 0.3048)
			(end -0.120396 0.2794)
			(stroke
				(width 0.1)
				(type default)
			)
			(layer "B.Fab")
		)
		(fp_line
			(start -0.67945 0.3048)
			(end -0.120396 0.3048)
			(stroke
				(width 0.1)
				(type default)
			)
			(layer "B.Fab")
		)
		(pad "1" smd circle
			(at 0.40005 0 270)
			(size 0 0)
			(layers "B.Cu" "B.Mask" "B.Paste")
			(net "NC_P0V8_PEX0_ISEN3")
		)
		(pad "2" smd circle
			(at -0.40005 0 270)
			(size 0 0)
			(layers "B.Cu" "B.Mask" "B.Paste")
			(net "GND")
		)
	)
	(footprint ""
		(layer "B.Cu")
		(at 165.508178 -303.024794 180)
		(property "Reference" "C3184"
			(at 0 0 0)
			(layer "B.SilkS")
			(hide yes)
			(effects
				(font
					(size 1.27 1.27)
				)
				(justify mirror)
			)
		)
		(property "Value" ""
			(at 0 0 0)
			(layer "B.Fab")
			(effects
				(font
					(size 1.27 1.27)
				)
				(justify mirror)
			)
		)
		(duplicate_pad_numbers_are_jumpers no)
		(fp_line
			(start 0.299974 0.150114)
			(end 0.299974 -0.150114)
			(stroke
				(width 0.1)
				(type default)
			)
			(layer "B.Fab")
		)
		(fp_line
			(start 0.299974 -0.150114)
			(end -0.299974 -0.150114)
			(stroke
				(width 0.1)
				(type default)
			)
			(layer "B.Fab")
		)
		(fp_line
			(start -0.299974 0.150114)
			(end 0.299974 0.150114)
			(stroke
				(width 0.1)
				(type default)
			)
			(layer "B.Fab")
		)
		(fp_line
			(start -0.299974 -0.150114)
			(end -0.299974 0.150114)
			(stroke
				(width 0.1)
				(type default)
			)
			(layer "B.Fab")
		)
		(pad "1" smd rect
			(at 0.2667 0)
			(size 0.3048 0.381)
			(layers "B.Cu" "B.Mask" "B.Paste")
			(net "P1V8_VDDA_PEX1")
		)
		(pad "2" smd rect
			(at -0.2667 0)
			(size 0.3048 0.381)
			(layers "B.Cu" "B.Mask" "B.Paste")
			(net "GND")
		)
	)
	(footprint ""
		(layer "B.Cu")
		(at 356.918006 -282.166822 90)
		(property "Reference" "R6768"
			(at 0 0 90)
			(layer "B.SilkS")
			(hide yes)
			(effects
				(font
					(size 1.27 1.27)
				)
				(justify mirror)
			)
		)
		(property "Value" ""
			(at 0 0 90)
			(layer "B.Fab")
			(effects
				(font
					(size 1.27 1.27)
				)
				(justify mirror)
			)
		)
		(duplicate_pad_numbers_are_jumpers no)
		(fp_line
			(start 0.7874 -0.4064)
			(end -0.7874 -0.4064)
			(stroke
				(width 0.1524)
				(type default)
			)
			(layer "B.SilkS")
		)
		(fp_line
			(start -0.7874 -0.4064)
			(end -0.7874 0.4064)
			(stroke
				(width 0.1524)
				(type default)
			)
			(layer "B.SilkS")
		)
		(fp_line
			(start 0.7874 0.4064)
			(end 0.7874 -0.4064)
			(stroke
				(width 0.1524)
				(type default)
			)
			(layer "B.SilkS")
		)
		(fp_line
			(start -0.7874 0.4064)
			(end 0.7874 0.4064)
			(stroke
				(width 0.1524)
				(type default)
			)
			(layer "B.SilkS")
		)
		(fp_line
			(start 0.67945 -0.305054)
			(end 0.12065 -0.305054)
			(stroke
				(width 0.1)
				(type default)
			)
			(layer "B.Fab")
		)
		(fp_line
			(start 0.12065 -0.305054)
			(end 0.12065 -0.2794)
			(stroke
				(width 0.1)
				(type default)
			)
			(layer "B.Fab")
		)
		(fp_line
			(start -0.12065 -0.3048)
			(end -0.67945 -0.3048)
			(stroke
				(width 0.1)
				(type default)
			)
			(layer "B.Fab")
		)
		(fp_line
			(start -0.67945 -0.3048)
			(end -0.67945 0.3048)
			(stroke
				(width 0.1)
				(type default)
			)
			(layer "B.Fab")
		)
		(fp_line
			(start 0.12065 -0.2794)
			(end -0.12065 -0.2794)
			(stroke
				(width 0.1)
				(type default)
			)
			(layer "B.Fab")
		)
		(fp_line
			(start -0.12065 -0.2794)
			(end -0.12065 -0.3048)
			(stroke
				(width 0.1)
				(type default)
			)
			(layer "B.Fab")
		)
		(fp_line
			(start 0.12065 0.2794)
			(end 0.12065 0.3048)
			(stroke
				(width 0.1)
				(type default)
			)
			(layer "B.Fab")
		)
		(fp_line
			(start -0.120396 0.2794)
			(end 0.12065 0.2794)
			(stroke
				(width 0.1)
				(type default)
			)
			(layer "B.Fab")
		)
		(fp_line
			(start 0.67945 0.3048)
			(end 0.67945 -0.305054)
			(stroke
				(width 0.1)
				(type default)
			)
			(layer "B.Fab")
		)
		(fp_line
			(start 0.12065 0.3048)
			(end 0.67945 0.3048)
			(stroke
				(width 0.1)
				(type default)
			)
			(layer "B.Fab")
		)
		(fp_line
			(start -0.120396 0.3048)
			(end -0.120396 0.2794)
			(stroke
				(width 0.1)
				(type default)
			)
			(layer "B.Fab")
		)
		(fp_line
			(start -0.67945 0.3048)
			(end -0.120396 0.3048)
			(stroke
				(width 0.1)
				(type default)
			)
			(layer "B.Fab")
		)
		(pad "1" smd circle
			(at 0.40005 0 270)
			(size 0 0)
			(layers "B.Cu" "B.Mask" "B.Paste")
			(net "P0V8_PEX3_VCC1")
		)
		(pad "2" smd circle
			(at -0.40005 0 270)
			(size 0 0)
			(layers "B.Cu" "B.Mask" "B.Paste")
			(net "P0V8_PEX2_EN3")
		)
	)
	(footprint ""
		(layer "B.Cu")
		(at 278.554942 -300.1772)
		(property "Reference" "C3373"
			(at 0 0 0)
			(layer "B.SilkS")
			(hide yes)
			(effects
				(font
					(size 1.27 1.27)
				)
				(justify mirror)
			)
		)
		(property "Value" ""
			(at 0 0 0)
			(layer "B.Fab")
			(effects
				(font
					(size 1.27 1.27)
				)
				(justify mirror)
			)
		)
		(duplicate_pad_numbers_are_jumpers no)
		(fp_line
			(start -0.299974 -0.150114)
			(end -0.299974 0.150114)
			(stroke
				(width 0.1)
				(type default)
			)
			(layer "B.Fab")
		)
		(fp_line
			(start -0.299974 0.150114)
			(end 0.299974 0.150114)
			(stroke
				(width 0.1)
				(type default)
			)
			(layer "B.Fab")
		)
		(fp_line
			(start 0.299974 -0.150114)
			(end -0.299974 -0.150114)
			(stroke
				(width 0.1)
				(type default)
			)
			(layer "B.Fab")
		)
		(fp_line
			(start 0.299974 0.150114)
			(end 0.299974 -0.150114)
			(stroke
				(width 0.1)
				(type default)
			)
			(layer "B.Fab")
		)
		(pad "1" smd rect
			(at 0.2667 0 180)
			(size 0.3048 0.381)
			(layers "B.Cu" "B.Mask" "B.Paste")
			(net "PCEPLL1_VDDA18_PEX2")
		)
		(pad "2" smd rect
			(at -0.2667 0 180)
			(size 0.3048 0.381)
			(layers "B.Cu" "B.Mask" "B.Paste")
			(net "GND")
		)
	)
	(footprint ""
		(layer "B.Cu")
		(at 72.949816 -293.99992 180)
		(property "Reference" "C2950"
			(at 0 0 0)
			(layer "B.SilkS")
			(hide yes)
			(effects
				(font
					(size 1.27 1.27)
				)
				(justify mirror)
			)
		)
		(property "Value" ""
			(at 0 0 0)
			(layer "B.Fab")
			(effects
				(font
					(size 1.27 1.27)
				)
				(justify mirror)
			)
		)
		(duplicate_pad_numbers_are_jumpers no)
		(fp_line
			(start 0.299974 0.150114)
			(end 0.299974 -0.150114)
			(stroke
				(width 0.1)
				(type default)
			)
			(layer "B.Fab")
		)
		(fp_line
			(start 0.299974 -0.150114)
			(end -0.299974 -0.150114)
			(stroke
				(width 0.1)
				(type default)
			)
			(layer "B.Fab")
		)
		(fp_line
			(start -0.299974 0.150114)
			(end 0.299974 0.150114)
			(stroke
				(width 0.1)
				(type default)
			)
			(layer "B.Fab")
		)
		(fp_line
			(start -0.299974 -0.150114)
			(end -0.299974 0.150114)
			(stroke
				(width 0.1)
				(type default)
			)
			(layer "B.Fab")
		)
		(pad "1" smd rect
			(at 0.2667 0)
			(size 0.3048 0.381)
			(layers "B.Cu" "B.Mask" "B.Paste")
			(net "P1V25_SERDES_VDDPLL_PEX0")
		)
		(pad "2" smd rect
			(at -0.2667 0)
			(size 0.3048 0.381)
			(layers "B.Cu" "B.Mask" "B.Paste")
			(net "GND")
		)
	)
	(footprint ""
		(layer "B.Cu")
		(at 107.621832 -348.226888 180)
		(property "Reference" "R6372"
			(at 0 0 0)
			(layer "B.SilkS")
			(hide yes)
			(effects
				(font
					(size 1.27 1.27)
				)
				(justify mirror)
			)
		)
		(property "Value" ""
			(at 0 0 0)
			(layer "B.Fab")
			(effects
				(font
					(size 1.27 1.27)
				)
				(justify mirror)
			)
		)
		(duplicate_pad_numbers_are_jumpers no)
		(fp_line
			(start 0.7874 0.4064)
			(end 0.7874 -0.4064)
			(stroke
				(width 0.1524)
				(type default)
			)
			(layer "B.SilkS")
		)
		(fp_line
			(start 0.7874 -0.4064)
			(end -0.7874 -0.4064)
			(stroke
				(width 0.1524)
				(type default)
			)
			(layer "B.SilkS")
		)
		(fp_line
			(start -0.7874 0.4064)
			(end 0.7874 0.4064)
			(stroke
				(width 0.1524)
				(type default)
			)
			(layer "B.SilkS")
		)
		(fp_line
			(start -0.7874 -0.4064)
			(end -0.7874 0.4064)
			(stroke
				(width 0.1524)
				(type default)
			)
			(layer "B.SilkS")
		)
		(fp_line
			(start 0.67945 0.3048)
			(end 0.67945 -0.305054)
			(stroke
				(width 0.1)
				(type default)
			)
			(layer "B.Fab")
		)
		(fp_line
			(start 0.67945 -0.305054)
			(end 0.12065 -0.305054)
			(stroke
				(width 0.1)
				(type default)
			)
			(layer "B.Fab")
		)
		(fp_line
			(start 0.12065 0.3048)
			(end 0.67945 0.3048)
			(stroke
				(width 0.1)
				(type default)
			)
			(layer "B.Fab")
		)
		(fp_line
			(start 0.12065 0.2794)
			(end 0.12065 0.3048)
			(stroke
				(width 0.1)
				(type default)
			)
			(layer "B.Fab")
		)
		(fp_line
			(start 0.12065 -0.2794)
			(end -0.12065 -0.2794)
			(stroke
				(width 0.1)
				(type default)
			)
			(layer "B.Fab")
		)
		(fp_line
			(start 0.12065 -0.305054)
			(end 0.12065 -0.2794)
			(stroke
				(width 0.1)
				(type default)
			)
			(layer "B.Fab")
		)
		(fp_line
			(start -0.120396 0.3048)
			(end -0.120396 0.2794)
			(stroke
				(width 0.1)
				(type default)
			)
			(layer "B.Fab")
		)
		(fp_line
			(start -0.120396 0.2794)
			(end 0.12065 0.2794)
			(stroke
				(width 0.1)
				(type default)
			)
			(layer "B.Fab")
		)
		(fp_line
			(start -0.12065 -0.2794)
			(end -0.12065 -0.3048)
			(stroke
				(width 0.1)
				(type default)
			)
			(layer "B.Fab")
		)
		(fp_line
			(start -0.12065 -0.3048)
			(end -0.67945 -0.3048)
			(stroke
				(width 0.1)
				(type default)
			)
			(layer "B.Fab")
		)
		(fp_line
			(start -0.67945 0.3048)
			(end -0.120396 0.3048)
			(stroke
				(width 0.1)
				(type default)
			)
			(layer "B.Fab")
		)
		(fp_line
			(start -0.67945 -0.3048)
			(end -0.67945 0.3048)
			(stroke
				(width 0.1)
				(type default)
			)
			(layer "B.Fab")
		)
		(pad "1" smd circle
			(at 0.40005 0)
			(size 0 0)
			(layers "B.Cu" "B.Mask" "B.Paste")
			(net "PU_9ZXL0451E_S3_HBW")
		)
		(pad "2" smd circle
			(at -0.40005 0)
			(size 0 0)
			(layers "B.Cu" "B.Mask" "B.Paste")
			(net "GND")
		)
	)
	(footprint ""
		(layer "B.Cu")
		(at 185.250074 -294.4749 180)
		(property "Reference" "C1417"
			(at 0 0 0)
			(layer "B.SilkS")
			(hide yes)
			(effects
				(font
					(size 1.27 1.27)
				)
				(justify mirror)
			)
		)
		(property "Value" ""
			(at 0 0 0)
			(layer "B.Fab")
			(effects
				(font
					(size 1.27 1.27)
				)
				(justify mirror)
			)
		)
		(duplicate_pad_numbers_are_jumpers no)
		(fp_line
			(start 0.299974 0.150114)
			(end 0.299974 -0.150114)
			(stroke
				(width 0.1)
				(type default)
			)
			(layer "B.Fab")
		)
		(fp_line
			(start 0.299974 -0.150114)
			(end -0.299974 -0.150114)
			(stroke
				(width 0.1)
				(type default)
			)
			(layer "B.Fab")
		)
		(fp_line
			(start -0.299974 0.150114)
			(end 0.299974 0.150114)
			(stroke
				(width 0.1)
				(type default)
			)
			(layer "B.Fab")
		)
		(fp_line
			(start -0.299974 -0.150114)
			(end -0.299974 0.150114)
			(stroke
				(width 0.1)
				(type default)
			)
			(layer "B.Fab")
		)
		(pad "1" smd rect
			(at 0.2667 0)
			(size 0.3048 0.381)
			(layers "B.Cu" "B.Mask" "B.Paste")
			(net "P0V8_SERDES_VDDA_PEX1")
		)
		(pad "2" smd rect
			(at -0.2667 0)
			(size 0.3048 0.381)
			(layers "B.Cu" "B.Mask" "B.Paste")
			(net "GND")
		)
	)
	(footprint ""
		(layer "B.Cu")
		(at 181.44998 -301.599854 -90)
		(property "Reference" "C1451"
			(at 0 0 90)
			(layer "B.SilkS")
			(hide yes)
			(effects
				(font
					(size 1.27 1.27)
				)
				(justify mirror)
			)
		)
		(property "Value" ""
			(at 0 0 90)
			(layer "B.Fab")
			(effects
				(font
					(size 1.27 1.27)
				)
				(justify mirror)
			)
		)
		(duplicate_pad_numbers_are_jumpers no)
		(fp_line
			(start -0.299974 0.150114)
			(end 0.299974 0.150114)
			(stroke
				(width 0.1)
				(type default)
			)
			(layer "B.Fab")
		)
		(fp_line
			(start 0.299974 0.150114)
			(end 0.299974 -0.150114)
			(stroke
				(width 0.1)
				(type default)
			)
			(layer "B.Fab")
		)
		(fp_line
			(start -0.299974 -0.150114)
			(end -0.299974 0.150114)
			(stroke
				(width 0.1)
				(type default)
			)
			(layer "B.Fab")
		)
		(fp_line
			(start 0.299974 -0.150114)
			(end -0.299974 -0.150114)
			(stroke
				(width 0.1)
				(type default)
			)
			(layer "B.Fab")
		)
		(pad "1" smd rect
			(at 0.2667 0 90)
			(size 0.3048 0.381)
			(layers "B.Cu" "B.Mask" "B.Paste")
			(net "P0V8_SERDES_VDDA_PEX1")
		)
		(pad "2" smd rect
			(at -0.2667 0 90)
			(size 0.3048 0.381)
			(layers "B.Cu" "B.Mask" "B.Paste")
			(net "GND")
		)
	)
	(footprint ""
		(layer "B.Cu")
		(at 261.904226 -224.75063 180)
		(property "Reference" "R6170"
			(at 0 0 0)
			(layer "B.SilkS")
			(hide yes)
			(effects
				(font
					(size 1.27 1.27)
				)
				(justify mirror)
			)
		)
		(property "Value" ""
			(at 0 0 0)
			(layer "B.Fab")
			(effects
				(font
					(size 1.27 1.27)
				)
				(justify mirror)
			)
		)
		(duplicate_pad_numbers_are_jumpers no)
		(fp_line
			(start 0.7874 0.4064)
			(end 0.7874 -0.4064)
			(stroke
				(width 0.1524)
				(type default)
			)
			(layer "B.SilkS")
		)
		(fp_line
			(start 0.7874 -0.4064)
			(end -0.7874 -0.4064)
			(stroke
				(width 0.1524)
				(type default)
			)
			(layer "B.SilkS")
		)
		(fp_line
			(start -0.7874 0.4064)
			(end 0.7874 0.4064)
			(stroke
				(width 0.1524)
				(type default)
			)
			(layer "B.SilkS")
		)
		(fp_line
			(start -0.7874 -0.4064)
			(end -0.7874 0.4064)
			(stroke
				(width 0.1524)
				(type default)
			)
			(layer "B.SilkS")
		)
		(fp_line
			(start 0.67945 0.3048)
			(end 0.67945 -0.305054)
			(stroke
				(width 0.1)
				(type default)
			)
			(layer "B.Fab")
		)
		(fp_line
			(start 0.67945 -0.305054)
			(end 0.12065 -0.305054)
			(stroke
				(width 0.1)
				(type default)
			)
			(layer "B.Fab")
		)
		(fp_line
			(start 0.12065 0.3048)
			(end 0.67945 0.3048)
			(stroke
				(width 0.1)
				(type default)
			)
			(layer "B.Fab")
		)
		(fp_line
			(start 0.12065 0.2794)
			(end 0.12065 0.3048)
			(stroke
				(width 0.1)
				(type default)
			)
			(layer "B.Fab")
		)
		(fp_line
			(start 0.12065 -0.2794)
			(end -0.12065 -0.2794)
			(stroke
				(width 0.1)
				(type default)
			)
			(layer "B.Fab")
		)
		(fp_line
			(start 0.12065 -0.305054)
			(end 0.12065 -0.2794)
			(stroke
				(width 0.1)
				(type default)
			)
			(layer "B.Fab")
		)
		(fp_line
			(start -0.120396 0.3048)
			(end -0.120396 0.2794)
			(stroke
				(width 0.1)
				(type default)
			)
			(layer "B.Fab")
		)
		(fp_line
			(start -0.120396 0.2794)
			(end 0.12065 0.2794)
			(stroke
				(width 0.1)
				(type default)
			)
			(layer "B.Fab")
		)
		(fp_line
			(start -0.12065 -0.2794)
			(end -0.12065 -0.3048)
			(stroke
				(width 0.1)
				(type default)
			)
			(layer "B.Fab")
		)
		(fp_line
			(start -0.12065 -0.3048)
			(end -0.67945 -0.3048)
			(stroke
				(width 0.1)
				(type default)
			)
			(layer "B.Fab")
		)
		(fp_line
			(start -0.67945 0.3048)
			(end -0.120396 0.3048)
			(stroke
				(width 0.1)
				(type default)
			)
			(layer "B.Fab")
		)
		(fp_line
			(start -0.67945 -0.3048)
			(end -0.67945 0.3048)
			(stroke
				(width 0.1)
				(type default)
			)
			(layer "B.Fab")
		)
		(pad "1" smd circle
			(at 0.40005 0)
			(size 0 0)
			(layers "B.Cu" "B.Mask" "B.Paste")
			(net "SPI_PEX2_RST_R_N")
		)
		(pad "2" smd circle
			(at -0.40005 0)
			(size 0 0)
			(layers "B.Cu" "B.Mask" "B.Paste")
			(net "GND")
		)
	)
	(footprint ""
		(layer "B.Cu")
		(at 140.894816 -204.949806)
		(property "Reference" "L6"
			(at 0 0 0)
			(layer "B.SilkS")
			(hide yes)
			(effects
				(font
					(size 1.27 1.27)
				)
				(justify mirror)
			)
		)
		(property "Value" ""
			(at 0 0 0)
			(layer "B.Fab")
			(effects
				(font
					(size 1.27 1.27)
				)
				(justify mirror)
			)
		)
		(duplicate_pad_numbers_are_jumpers no)
		(fp_line
			(start -1.27 0.5842)
			(end -1.27 -0.5842)
			(stroke
				(width 0.1524)
				(type default)
			)
			(layer "B.SilkS")
		)
		(fp_line
			(start -1.27 0.5842)
			(end 1.27 0.5842)
			(stroke
				(width 0.1524)
				(type default)
			)
			(layer "B.SilkS")
		)
		(fp_line
			(start 1.27 -0.5842)
			(end -1.27 -0.5842)
			(stroke
				(width 0.1524)
				(type default)
			)
			(layer "B.SilkS")
		)
		(fp_line
			(start 1.27 -0.5588)
			(end 1.27 -0.5842)
			(stroke
				(width 0.1524)
				(type default)
			)
			(layer "B.SilkS")
		)
		(fp_line
			(start 1.27 0.5842)
			(end 1.27 -0.5842)
			(stroke
				(width 0.1524)
				(type default)
			)
			(layer "B.SilkS")
		)
		(fp_line
			(start -1.1938 -0.406654)
			(end -1.1938 0.4064)
			(stroke
				(width 0.1)
				(type default)
			)
			(layer "B.Fab")
		)
		(fp_line
			(start -1.1938 0.4064)
			(end -0.9144 0.4064)
			(stroke
				(width 0.1)
				(type default)
			)
			(layer "B.Fab")
		)
		(fp_line
			(start -0.9144 -0.508)
			(end -0.9144 -0.406654)
			(stroke
				(width 0.1)
				(type default)
			)
			(layer "B.Fab")
		)
		(fp_line
			(start -0.9144 -0.406654)
			(end -1.1938 -0.406654)
			(stroke
				(width 0.1)
				(type default)
			)
			(layer "B.Fab")
		)
		(fp_line
			(start -0.9144 0.4064)
			(end -0.9144 0.508)
			(stroke
				(width 0.1)
				(type default)
			)
			(layer "B.Fab")
		)
		(fp_line
			(start -0.9144 0.508)
			(end 0.9144 0.508)
			(stroke
				(width 0.1)
				(type default)
			)
			(layer "B.Fab")
		)
		(fp_line
			(start 0.9144 -0.508)
			(end -0.9144 -0.508)
			(stroke
				(width 0.1)
				(type default)
			)
			(layer "B.Fab")
		)
		(fp_line
			(start 0.9144 -0.406654)
			(end 0.9144 -0.508)
			(stroke
				(width 0.1)
				(type default)
			)
			(layer "B.Fab")
		)
		(fp_line
			(start 0.9144 0.406654)
			(end 1.194308 0.406654)
			(stroke
				(width 0.1)
				(type default)
			)
			(layer "B.Fab")
		)
		(fp_line
			(start 0.9144 0.508)
			(end 0.9144 0.406654)
			(stroke
				(width 0.1)
				(type default)
			)
			(layer "B.Fab")
		)
		(fp_line
			(start 1.194308 -0.406654)
			(end 0.9144 -0.406654)
			(stroke
				(width 0.1)
				(type default)
			)
			(layer "B.Fab")
		)
		(fp_line
			(start 1.194308 0.406654)
			(end 1.194308 -0.406654)
			(stroke
				(width 0.1)
				(type default)
			)
			(layer "B.Fab")
		)
		(pad "1" smd rect
			(at 0.7366 0 270)
			(size 0.7112 0.8128)
			(layers "B.Cu" "B.Mask" "B.Paste")
			(net "P3V3_AUX")
		)
		(pad "2" smd rect
			(at -0.7366 0 270)
			(size 0.7112 0.8128)
			(layers "B.Cu" "B.Mask" "B.Paste")
			(net "P3V3_CLI_VPLL")
		)
	)
	(footprint ""
		(layer "B.Cu")
		(at 366.268 -237.744)
		(property "Reference" "R914"
			(at 0 0 0)
			(layer "B.SilkS")
			(hide yes)
			(effects
				(font
					(size 1.27 1.27)
				)
				(justify mirror)
			)
		)
		(property "Value" ""
			(at 0 0 0)
			(layer "B.Fab")
			(effects
				(font
					(size 1.27 1.27)
				)
				(justify mirror)
			)
		)
		(duplicate_pad_numbers_are_jumpers no)
		(fp_line
			(start -0.7874 -0.4064)
			(end -0.7874 0.4064)
			(stroke
				(width 0.1524)
				(type default)
			)
			(layer "B.SilkS")
		)
		(fp_line
			(start -0.7874 0.4064)
			(end 0.7874 0.4064)
			(stroke
				(width 0.1524)
				(type default)
			)
			(layer "B.SilkS")
		)
		(fp_line
			(start 0.7874 -0.4064)
			(end -0.7874 -0.4064)
			(stroke
				(width 0.1524)
				(type default)
			)
			(layer "B.SilkS")
		)
		(fp_line
			(start 0.7874 0.4064)
			(end 0.7874 -0.4064)
			(stroke
				(width 0.1524)
				(type default)
			)
			(layer "B.SilkS")
		)
		(fp_line
			(start -0.67945 -0.3048)
			(end -0.67945 0.3048)
			(stroke
				(width 0.1)
				(type default)
			)
			(layer "B.Fab")
		)
		(fp_line
			(start -0.67945 0.3048)
			(end -0.120396 0.3048)
			(stroke
				(width 0.1)
				(type default)
			)
			(layer "B.Fab")
		)
		(fp_line
			(start -0.12065 -0.3048)
			(end -0.67945 -0.3048)
			(stroke
				(width 0.1)
				(type default)
			)
			(layer "B.Fab")
		)
		(fp_line
			(start -0.12065 -0.2794)
			(end -0.12065 -0.3048)
			(stroke
				(width 0.1)
				(type default)
			)
			(layer "B.Fab")
		)
		(fp_line
			(start -0.120396 0.2794)
			(end 0.12065 0.2794)
			(stroke
				(width 0.1)
				(type default)
			)
			(layer "B.Fab")
		)
		(fp_line
			(start -0.120396 0.3048)
			(end -0.120396 0.2794)
			(stroke
				(width 0.1)
				(type default)
			)
			(layer "B.Fab")
		)
		(fp_line
			(start 0.12065 -0.305054)
			(end 0.12065 -0.2794)
			(stroke
				(width 0.1)
				(type default)
			)
			(layer "B.Fab")
		)
		(fp_line
			(start 0.12065 -0.2794)
			(end -0.12065 -0.2794)
			(stroke
				(width 0.1)
				(type default)
			)
			(layer "B.Fab")
		)
		(fp_line
			(start 0.12065 0.2794)
			(end 0.12065 0.3048)
			(stroke
				(width 0.1)
				(type default)
			)
			(layer "B.Fab")
		)
		(fp_line
			(start 0.12065 0.3048)
			(end 0.67945 0.3048)
			(stroke
				(width 0.1)
				(type default)
			)
			(layer "B.Fab")
		)
		(fp_line
			(start 0.67945 -0.305054)
			(end 0.12065 -0.305054)
			(stroke
				(width 0.1)
				(type default)
			)
			(layer "B.Fab")
		)
		(fp_line
			(start 0.67945 0.3048)
			(end 0.67945 -0.305054)
			(stroke
				(width 0.1)
				(type default)
			)
			(layer "B.Fab")
		)
		(pad "1" smd circle
			(at 0.40005 0 180)
			(size 0 0)
			(layers "B.Cu" "B.Mask" "B.Paste")
			(net "FT4232_SDB_EEPROM_R_SDA")
		)
		(pad "2" smd circle
			(at -0.40005 0 180)
			(size 0 0)
			(layers "B.Cu" "B.Mask" "B.Paste")
			(net "FT4232_SDB_EEPROM_SDA")
		)
	)
	(footprint ""
		(layer "B.Cu")
		(at 404.149814 -288.299906 90)
		(property "Reference" "C3454"
			(at 0 0 90)
			(layer "B.SilkS")
			(hide yes)
			(effects
				(font
					(size 1.27 1.27)
				)
				(justify mirror)
			)
		)
		(property "Value" ""
			(at 0 0 90)
			(layer "B.Fab")
			(effects
				(font
					(size 1.27 1.27)
				)
				(justify mirror)
			)
		)
		(duplicate_pad_numbers_are_jumpers no)
		(fp_line
			(start 0.299974 -0.150114)
			(end -0.299974 -0.150114)
			(stroke
				(width 0.1)
				(type default)
			)
			(layer "B.Fab")
		)
		(fp_line
			(start -0.299974 -0.150114)
			(end -0.299974 0.150114)
			(stroke
				(width 0.1)
				(type default)
			)
			(layer "B.Fab")
		)
		(fp_line
			(start 0.299974 0.150114)
			(end 0.299974 -0.150114)
			(stroke
				(width 0.1)
				(type default)
			)
			(layer "B.Fab")
		)
		(fp_line
			(start -0.299974 0.150114)
			(end 0.299974 0.150114)
			(stroke
				(width 0.1)
				(type default)
			)
			(layer "B.Fab")
		)
		(pad "1" smd rect
			(at 0.2667 0 270)
			(size 0.3048 0.381)
			(layers "B.Cu" "B.Mask" "B.Paste")
			(net "P1V25_PEX3")
		)
		(pad "2" smd rect
			(at -0.2667 0 270)
			(size 0.3048 0.381)
			(layers "B.Cu" "B.Mask" "B.Paste")
			(net "GND")
		)
	)
	(footprint ""
		(layer "B.Cu")
		(at 55.849774 -288.299906 90)
		(property "Reference" "C2933"
			(at 0 0 90)
			(layer "B.SilkS")
			(hide yes)
			(effects
				(font
					(size 1.27 1.27)
				)
				(justify mirror)
			)
		)
		(property "Value" ""
			(at 0 0 90)
			(layer "B.Fab")
			(effects
				(font
					(size 1.27 1.27)
				)
				(justify mirror)
			)
		)
		(duplicate_pad_numbers_are_jumpers no)
		(fp_line
			(start 0.299974 -0.150114)
			(end -0.299974 -0.150114)
			(stroke
				(width 0.1)
				(type default)
			)
			(layer "B.Fab")
		)
		(fp_line
			(start -0.299974 -0.150114)
			(end -0.299974 0.150114)
			(stroke
				(width 0.1)
				(type default)
			)
			(layer "B.Fab")
		)
		(fp_line
			(start 0.299974 0.150114)
			(end 0.299974 -0.150114)
			(stroke
				(width 0.1)
				(type default)
			)
			(layer "B.Fab")
		)
		(fp_line
			(start -0.299974 0.150114)
			(end 0.299974 0.150114)
			(stroke
				(width 0.1)
				(type default)
			)
			(layer "B.Fab")
		)
		(pad "1" smd rect
			(at 0.2667 0 270)
			(size 0.3048 0.381)
			(layers "B.Cu" "B.Mask" "B.Paste")
			(net "P1V25_PEX0")
		)
		(pad "2" smd rect
			(at -0.2667 0 270)
			(size 0.3048 0.381)
			(layers "B.Cu" "B.Mask" "B.Paste")
			(net "GND")
		)
	)
	(footprint ""
		(layer "B.Cu")
		(at 135.833866 -180.012594 180)
		(property "Reference" "C2659"
			(at 0 0 0)
			(layer "B.SilkS")
			(hide yes)
			(effects
				(font
					(size 1.27 1.27)
				)
				(justify mirror)
			)
		)
		(property "Value" ""
			(at 0 0 0)
			(layer "B.Fab")
			(effects
				(font
					(size 1.27 1.27)
				)
				(justify mirror)
			)
		)
		(duplicate_pad_numbers_are_jumpers no)
		(fp_line
			(start 0.7874 0.4064)
			(end 0.7874 -0.4064)
			(stroke
				(width 0.1524)
				(type default)
			)
			(layer "B.SilkS")
		)
		(fp_line
			(start 0.7874 -0.4064)
			(end -0.7874 -0.4064)
			(stroke
				(width 0.1524)
				(type default)
			)
			(layer "B.SilkS")
		)
		(fp_line
			(start -0.7874 0.4064)
			(end 0.7874 0.4064)
			(stroke
				(width 0.1524)
				(type default)
			)
			(layer "B.SilkS")
		)
		(fp_line
			(start -0.7874 -0.4064)
			(end -0.7874 0.4064)
			(stroke
				(width 0.1524)
				(type default)
			)
			(layer "B.SilkS")
		)
		(fp_line
			(start 0.67945 0.3048)
			(end 0.67945 -0.305054)
			(stroke
				(width 0.1)
				(type default)
			)
			(layer "B.Fab")
		)
		(fp_line
			(start 0.67945 -0.305054)
			(end 0.12065 -0.305054)
			(stroke
				(width 0.1)
				(type default)
			)
			(layer "B.Fab")
		)
		(fp_line
			(start 0.12065 0.3048)
			(end 0.67945 0.3048)
			(stroke
				(width 0.1)
				(type default)
			)
			(layer "B.Fab")
		)
		(fp_line
			(start 0.12065 0.2794)
			(end 0.12065 0.3048)
			(stroke
				(width 0.1)
				(type default)
			)
			(layer "B.Fab")
		)
		(fp_line
			(start 0.12065 -0.2794)
			(end -0.12065 -0.2794)
			(stroke
				(width 0.1)
				(type default)
			)
			(layer "B.Fab")
		)
		(fp_line
			(start 0.12065 -0.305054)
			(end 0.12065 -0.2794)
			(stroke
				(width 0.1)
				(type default)
			)
			(layer "B.Fab")
		)
		(fp_line
			(start -0.120396 0.3048)
			(end -0.120396 0.2794)
			(stroke
				(width 0.1)
				(type default)
			)
			(layer "B.Fab")
		)
		(fp_line
			(start -0.120396 0.2794)
			(end 0.12065 0.2794)
			(stroke
				(width 0.1)
				(type default)
			)
			(layer "B.Fab")
		)
		(fp_line
			(start -0.12065 -0.2794)
			(end -0.12065 -0.3048)
			(stroke
				(width 0.1)
				(type default)
			)
			(layer "B.Fab")
		)
		(fp_line
			(start -0.12065 -0.3048)
			(end -0.67945 -0.3048)
			(stroke
				(width 0.1)
				(type default)
			)
			(layer "B.Fab")
		)
		(fp_line
			(start -0.67945 0.3048)
			(end -0.120396 0.3048)
			(stroke
				(width 0.1)
				(type default)
			)
			(layer "B.Fab")
		)
		(fp_line
			(start -0.67945 -0.3048)
			(end -0.67945 0.3048)
			(stroke
				(width 0.1)
				(type default)
			)
			(layer "B.Fab")
		)
		(pad "1" smd circle
			(at 0.40005 0)
			(size 0 0)
			(layers "B.Cu" "B.Mask" "B.Paste")
			(net "P3V3_DB2000QL_VDD")
		)
		(pad "2" smd circle
			(at -0.40005 0)
			(size 0 0)
			(layers "B.Cu" "B.Mask" "B.Paste")
			(net "GND")
		)
	)
	(footprint ""
		(layer "B.Cu")
		(at 295.649904 -290.199826 90)
		(property "Reference" "C1748"
			(at 0 0 90)
			(layer "B.SilkS")
			(hide yes)
			(effects
				(font
					(size 1.27 1.27)
				)
				(justify mirror)
			)
		)
		(property "Value" ""
			(at 0 0 90)
			(layer "B.Fab")
			(effects
				(font
					(size 1.27 1.27)
				)
				(justify mirror)
			)
		)
		(duplicate_pad_numbers_are_jumpers no)
		(fp_line
			(start 0.299974 -0.150114)
			(end -0.299974 -0.150114)
			(stroke
				(width 0.1)
				(type default)
			)
			(layer "B.Fab")
		)
		(fp_line
			(start -0.299974 -0.150114)
			(end -0.299974 0.150114)
			(stroke
				(width 0.1)
				(type default)
			)
			(layer "B.Fab")
		)
		(fp_line
			(start 0.299974 0.150114)
			(end 0.299974 -0.150114)
			(stroke
				(width 0.1)
				(type default)
			)
			(layer "B.Fab")
		)
		(fp_line
			(start -0.299974 0.150114)
			(end 0.299974 0.150114)
			(stroke
				(width 0.1)
				(type default)
			)
			(layer "B.Fab")
		)
		(pad "1" smd rect
			(at 0.2667 0 270)
			(size 0.3048 0.381)
			(layers "B.Cu" "B.Mask" "B.Paste")
			(net "P0V8_SERDES_VDDA_PEX2")
		)
		(pad "2" smd rect
			(at -0.2667 0 270)
			(size 0.3048 0.381)
			(layers "B.Cu" "B.Mask" "B.Paste")
			(net "GND")
		)
	)
	(footprint ""
		(layer "B.Cu")
		(at 11.143234 -380.959106 90)
		(property "Reference" "C4469"
			(at 0 0 90)
			(layer "B.SilkS")
			(hide yes)
			(effects
				(font
					(size 1.27 1.27)
				)
				(justify mirror)
			)
		)
		(property "Value" ""
			(at 0 0 90)
			(layer "B.Fab")
			(effects
				(font
					(size 1.27 1.27)
				)
				(justify mirror)
			)
		)
		(duplicate_pad_numbers_are_jumpers no)
		(fp_line
			(start 0.7874 -0.4064)
			(end -0.7874 -0.4064)
			(stroke
				(width 0.1524)
				(type default)
			)
			(layer "B.SilkS")
		)
		(fp_line
			(start -0.7874 -0.4064)
			(end -0.7874 0.4064)
			(stroke
				(width 0.1524)
				(type default)
			)
			(layer "B.SilkS")
		)
		(fp_line
			(start 0.7874 0.4064)
			(end 0.7874 -0.4064)
			(stroke
				(width 0.1524)
				(type default)
			)
			(layer "B.SilkS")
		)
		(fp_line
			(start -0.7874 0.4064)
			(end 0.7874 0.4064)
			(stroke
				(width 0.1524)
				(type default)
			)
			(layer "B.SilkS")
		)
		(fp_line
			(start 0.67945 -0.305054)
			(end 0.12065 -0.305054)
			(stroke
				(width 0.1)
				(type default)
			)
			(layer "B.Fab")
		)
		(fp_line
			(start 0.12065 -0.305054)
			(end 0.12065 -0.2794)
			(stroke
				(width 0.1)
				(type default)
			)
			(layer "B.Fab")
		)
		(fp_line
			(start -0.12065 -0.3048)
			(end -0.67945 -0.3048)
			(stroke
				(width 0.1)
				(type default)
			)
			(layer "B.Fab")
		)
		(fp_line
			(start -0.67945 -0.3048)
			(end -0.67945 0.3048)
			(stroke
				(width 0.1)
				(type default)
			)
			(layer "B.Fab")
		)
		(fp_line
			(start 0.12065 -0.2794)
			(end -0.12065 -0.2794)
			(stroke
				(width 0.1)
				(type default)
			)
			(layer "B.Fab")
		)
		(fp_line
			(start -0.12065 -0.2794)
			(end -0.12065 -0.3048)
			(stroke
				(width 0.1)
				(type default)
			)
			(layer "B.Fab")
		)
		(fp_line
			(start 0.12065 0.2794)
			(end 0.12065 0.3048)
			(stroke
				(width 0.1)
				(type default)
			)
			(layer "B.Fab")
		)
		(fp_line
			(start -0.120396 0.2794)
			(end 0.12065 0.2794)
			(stroke
				(width 0.1)
				(type default)
			)
			(layer "B.Fab")
		)
		(fp_line
			(start 0.67945 0.3048)
			(end 0.67945 -0.305054)
			(stroke
				(width 0.1)
				(type default)
			)
			(layer "B.Fab")
		)
		(fp_line
			(start 0.12065 0.3048)
			(end 0.67945 0.3048)
			(stroke
				(width 0.1)
				(type default)
			)
			(layer "B.Fab")
		)
		(fp_line
			(start -0.120396 0.3048)
			(end -0.120396 0.2794)
			(stroke
				(width 0.1)
				(type default)
			)
			(layer "B.Fab")
		)
		(fp_line
			(start -0.67945 0.3048)
			(end -0.120396 0.3048)
			(stroke
				(width 0.1)
				(type default)
			)
			(layer "B.Fab")
		)
		(pad "1" smd circle
			(at 0.40005 0 270)
			(size 0 0)
			(layers "B.Cu" "B.Mask" "B.Paste")
			(net "P1V2_USB_8042")
		)
		(pad "2" smd circle
			(at -0.40005 0 270)
			(size 0 0)
			(layers "B.Cu" "B.Mask" "B.Paste")
			(net "GND")
		)
	)
	(footprint ""
		(layer "B.Cu")
		(at 291.84981 -292.099746 90)
		(property "Reference" "C1715"
			(at 0 0 90)
			(layer "B.SilkS")
			(hide yes)
			(effects
				(font
					(size 1.27 1.27)
				)
				(justify mirror)
			)
		)
		(property "Value" ""
			(at 0 0 90)
			(layer "B.Fab")
			(effects
				(font
					(size 1.27 1.27)
				)
				(justify mirror)
			)
		)
		(duplicate_pad_numbers_are_jumpers no)
		(fp_line
			(start 0.299974 -0.150114)
			(end -0.299974 -0.150114)
			(stroke
				(width 0.1)
				(type default)
			)
			(layer "B.Fab")
		)
		(fp_line
			(start -0.299974 -0.150114)
			(end -0.299974 0.150114)
			(stroke
				(width 0.1)
				(type default)
			)
			(layer "B.Fab")
		)
		(fp_line
			(start 0.299974 0.150114)
			(end 0.299974 -0.150114)
			(stroke
				(width 0.1)
				(type default)
			)
			(layer "B.Fab")
		)
		(fp_line
			(start -0.299974 0.150114)
			(end 0.299974 0.150114)
			(stroke
				(width 0.1)
				(type default)
			)
			(layer "B.Fab")
		)
		(pad "1" smd rect
			(at 0.2667 0 270)
			(size 0.3048 0.381)
			(layers "B.Cu" "B.Mask" "B.Paste")
			(net "P0V8_SERDES_VDDA_PEX2")
		)
		(pad "2" smd rect
			(at -0.2667 0 270)
			(size 0.3048 0.381)
			(layers "B.Cu" "B.Mask" "B.Paste")
			(net "GND")
		)
	)
	(footprint ""
		(layer "B.Cu")
		(at 174.800006 -299.699934 -90)
		(property "Reference" "C1449"
			(at 0 0 90)
			(layer "B.SilkS")
			(hide yes)
			(effects
				(font
					(size 1.27 1.27)
				)
				(justify mirror)
			)
		)
		(property "Value" ""
			(at 0 0 90)
			(layer "B.Fab")
			(effects
				(font
					(size 1.27 1.27)
				)
				(justify mirror)
			)
		)
		(duplicate_pad_numbers_are_jumpers no)
		(fp_line
			(start -0.299974 0.150114)
			(end 0.299974 0.150114)
			(stroke
				(width 0.1)
				(type default)
			)
			(layer "B.Fab")
		)
		(fp_line
			(start 0.299974 0.150114)
			(end 0.299974 -0.150114)
			(stroke
				(width 0.1)
				(type default)
			)
			(layer "B.Fab")
		)
		(fp_line
			(start -0.299974 -0.150114)
			(end -0.299974 0.150114)
			(stroke
				(width 0.1)
				(type default)
			)
			(layer "B.Fab")
		)
		(fp_line
			(start 0.299974 -0.150114)
			(end -0.299974 -0.150114)
			(stroke
				(width 0.1)
				(type default)
			)
			(layer "B.Fab")
		)
		(pad "1" smd rect
			(at 0.2667 0 90)
			(size 0.3048 0.381)
			(layers "B.Cu" "B.Mask" "B.Paste")
			(net "P0V8_SERDES_VDDA_PEX1")
		)
		(pad "2" smd rect
			(at -0.2667 0 90)
			(size 0.3048 0.381)
			(layers "B.Cu" "B.Mask" "B.Paste")
			(net "GND")
		)
	)
	(footprint ""
		(layer "B.Cu")
		(at 301.349918 -297.32478 180)
		(property "Reference" "C1674"
			(at 0 0 0)
			(layer "B.SilkS")
			(hide yes)
			(effects
				(font
					(size 1.27 1.27)
				)
				(justify mirror)
			)
		)
		(property "Value" ""
			(at 0 0 0)
			(layer "B.Fab")
			(effects
				(font
					(size 1.27 1.27)
				)
				(justify mirror)
			)
		)
		(duplicate_pad_numbers_are_jumpers no)
		(fp_line
			(start 0.299974 0.150114)
			(end 0.299974 -0.150114)
			(stroke
				(width 0.1)
				(type default)
			)
			(layer "B.Fab")
		)
		(fp_line
			(start 0.299974 -0.150114)
			(end -0.299974 -0.150114)
			(stroke
				(width 0.1)
				(type default)
			)
			(layer "B.Fab")
		)
		(fp_line
			(start -0.299974 0.150114)
			(end 0.299974 0.150114)
			(stroke
				(width 0.1)
				(type default)
			)
			(layer "B.Fab")
		)
		(fp_line
			(start -0.299974 -0.150114)
			(end -0.299974 0.150114)
			(stroke
				(width 0.1)
				(type default)
			)
			(layer "B.Fab")
		)
		(pad "1" smd rect
			(at 0.2667 0)
			(size 0.3048 0.381)
			(layers "B.Cu" "B.Mask" "B.Paste")
			(net "P0V8_SERDES_VDDA_PEX2")
		)
		(pad "2" smd rect
			(at -0.2667 0)
			(size 0.3048 0.381)
			(layers "B.Cu" "B.Mask" "B.Paste")
			(net "GND")
		)
	)
	(footprint ""
		(layer "B.Cu")
		(at 77.541882 -104.120696 180)
		(property "Reference" "R66"
			(at 0 0 0)
			(layer "B.SilkS")
			(hide yes)
			(effects
				(font
					(size 1.27 1.27)
				)
				(justify mirror)
			)
		)
		(property "Value" ""
			(at 0 0 0)
			(layer "B.Fab")
			(effects
				(font
					(size 1.27 1.27)
				)
				(justify mirror)
			)
		)
		(duplicate_pad_numbers_are_jumpers no)
		(fp_line
			(start 0.7874 0.4064)
			(end 0.7874 -0.4064)
			(stroke
				(width 0.1524)
				(type default)
			)
			(layer "B.SilkS")
		)
		(fp_line
			(start 0.7874 -0.4064)
			(end -0.7874 -0.4064)
			(stroke
				(width 0.1524)
				(type default)
			)
			(layer "B.SilkS")
		)
		(fp_line
			(start -0.7874 0.4064)
			(end 0.7874 0.4064)
			(stroke
				(width 0.1524)
				(type default)
			)
			(layer "B.SilkS")
		)
		(fp_line
			(start -0.7874 -0.4064)
			(end -0.7874 0.4064)
			(stroke
				(width 0.1524)
				(type default)
			)
			(layer "B.SilkS")
		)
		(fp_line
			(start 0.67945 0.3048)
			(end 0.67945 -0.305054)
			(stroke
				(width 0.1)
				(type default)
			)
			(layer "B.Fab")
		)
		(fp_line
			(start 0.67945 -0.305054)
			(end 0.12065 -0.305054)
			(stroke
				(width 0.1)
				(type default)
			)
			(layer "B.Fab")
		)
		(fp_line
			(start 0.12065 0.3048)
			(end 0.67945 0.3048)
			(stroke
				(width 0.1)
				(type default)
			)
			(layer "B.Fab")
		)
		(fp_line
			(start 0.12065 0.2794)
			(end 0.12065 0.3048)
			(stroke
				(width 0.1)
				(type default)
			)
			(layer "B.Fab")
		)
		(fp_line
			(start 0.12065 -0.2794)
			(end -0.12065 -0.2794)
			(stroke
				(width 0.1)
				(type default)
			)
			(layer "B.Fab")
		)
		(fp_line
			(start 0.12065 -0.305054)
			(end 0.12065 -0.2794)
			(stroke
				(width 0.1)
				(type default)
			)
			(layer "B.Fab")
		)
		(fp_line
			(start -0.120396 0.3048)
			(end -0.120396 0.2794)
			(stroke
				(width 0.1)
				(type default)
			)
			(layer "B.Fab")
		)
		(fp_line
			(start -0.120396 0.2794)
			(end 0.12065 0.2794)
			(stroke
				(width 0.1)
				(type default)
			)
			(layer "B.Fab")
		)
		(fp_line
			(start -0.12065 -0.2794)
			(end -0.12065 -0.3048)
			(stroke
				(width 0.1)
				(type default)
			)
			(layer "B.Fab")
		)
		(fp_line
			(start -0.12065 -0.3048)
			(end -0.67945 -0.3048)
			(stroke
				(width 0.1)
				(type default)
			)
			(layer "B.Fab")
		)
		(fp_line
			(start -0.67945 0.3048)
			(end -0.120396 0.3048)
			(stroke
				(width 0.1)
				(type default)
			)
			(layer "B.Fab")
		)
		(fp_line
			(start -0.67945 -0.3048)
			(end -0.67945 0.3048)
			(stroke
				(width 0.1)
				(type default)
			)
			(layer "B.Fab")
		)
		(pad "1" smd circle
			(at 0.40005 0)
			(size 0 0)
			(layers "B.Cu" "B.Mask" "B.Paste")
			(net "NCSI_NIC1_CRS_DV")
		)
		(pad "2" smd circle
			(at -0.40005 0)
			(size 0 0)
			(layers "B.Cu" "B.Mask" "B.Paste")
			(net "GND")
		)
	)
	(footprint ""
		(layer "B.Cu")
		(at 55.30215 -158.343092)
		(property "Reference" "C858"
			(at 0 0 0)
			(layer "B.SilkS")
			(hide yes)
			(effects
				(font
					(size 1.27 1.27)
				)
				(justify mirror)
			)
		)
		(property "Value" ""
			(at 0 0 0)
			(layer "B.Fab")
			(effects
				(font
					(size 1.27 1.27)
				)
				(justify mirror)
			)
		)
		(duplicate_pad_numbers_are_jumpers no)
		(fp_line
			(start -0.7874 -0.4064)
			(end -0.7874 0.4064)
			(stroke
				(width 0.1524)
				(type default)
			)
			(layer "B.SilkS")
		)
		(fp_line
			(start -0.7874 0.4064)
			(end 0.7874 0.4064)
			(stroke
				(width 0.1524)
				(type default)
			)
			(layer "B.SilkS")
		)
		(fp_line
			(start 0.7874 -0.4064)
			(end -0.7874 -0.4064)
			(stroke
				(width 0.1524)
				(type default)
			)
			(layer "B.SilkS")
		)
		(fp_line
			(start 0.7874 0.4064)
			(end 0.7874 -0.4064)
			(stroke
				(width 0.1524)
				(type default)
			)
			(layer "B.SilkS")
		)
		(fp_line
			(start -0.67945 -0.3048)
			(end -0.67945 0.3048)
			(stroke
				(width 0.1)
				(type default)
			)
			(layer "B.Fab")
		)
		(fp_line
			(start -0.67945 0.3048)
			(end -0.120396 0.3048)
			(stroke
				(width 0.1)
				(type default)
			)
			(layer "B.Fab")
		)
		(fp_line
			(start -0.12065 -0.3048)
			(end -0.67945 -0.3048)
			(stroke
				(width 0.1)
				(type default)
			)
			(layer "B.Fab")
		)
		(fp_line
			(start -0.12065 -0.2794)
			(end -0.12065 -0.3048)
			(stroke
				(width 0.1)
				(type default)
			)
			(layer "B.Fab")
		)
		(fp_line
			(start -0.120396 0.2794)
			(end 0.12065 0.2794)
			(stroke
				(width 0.1)
				(type default)
			)
			(layer "B.Fab")
		)
		(fp_line
			(start -0.120396 0.3048)
			(end -0.120396 0.2794)
			(stroke
				(width 0.1)
				(type default)
			)
			(layer "B.Fab")
		)
		(fp_line
			(start 0.12065 -0.305054)
			(end 0.12065 -0.2794)
			(stroke
				(width 0.1)
				(type default)
			)
			(layer "B.Fab")
		)
		(fp_line
			(start 0.12065 -0.2794)
			(end -0.12065 -0.2794)
			(stroke
				(width 0.1)
				(type default)
			)
			(layer "B.Fab")
		)
		(fp_line
			(start 0.12065 0.2794)
			(end 0.12065 0.3048)
			(stroke
				(width 0.1)
				(type default)
			)
			(layer "B.Fab")
		)
		(fp_line
			(start 0.12065 0.3048)
			(end 0.67945 0.3048)
			(stroke
				(width 0.1)
				(type default)
			)
			(layer "B.Fab")
		)
		(fp_line
			(start 0.67945 -0.305054)
			(end 0.12065 -0.305054)
			(stroke
				(width 0.1)
				(type default)
			)
			(layer "B.Fab")
		)
		(fp_line
			(start 0.67945 0.3048)
			(end 0.67945 -0.305054)
			(stroke
				(width 0.1)
				(type default)
			)
			(layer "B.Fab")
		)
		(pad "1" smd circle
			(at 0.40005 0 180)
			(size 0 0)
			(layers "B.Cu" "B.Mask" "B.Paste")
			(net "P3V3_AUX")
		)
		(pad "2" smd circle
			(at -0.40005 0 180)
			(size 0 0)
			(layers "B.Cu" "B.Mask" "B.Paste")
			(net "GND")
		)
	)
	(footprint ""
		(layer "B.Cu")
		(at 107.700064 -83.72856 -90)
		(property "Reference" "C2663"
			(at 0 0 90)
			(layer "B.SilkS")
			(hide yes)
			(effects
				(font
					(size 1.27 1.27)
				)
				(justify mirror)
			)
		)
		(property "Value" ""
			(at 0 0 90)
			(layer "B.Fab")
			(effects
				(font
					(size 1.27 1.27)
				)
				(justify mirror)
			)
		)
		(duplicate_pad_numbers_are_jumpers no)
		(fp_line
			(start -0.7874 0.4064)
			(end 0.7874 0.4064)
			(stroke
				(width 0.1524)
				(type default)
			)
			(layer "B.SilkS")
		)
		(fp_line
			(start 0.7874 0.4064)
			(end 0.7874 -0.4064)
			(stroke
				(width 0.1524)
				(type default)
			)
			(layer "B.SilkS")
		)
		(fp_line
			(start -0.7874 -0.4064)
			(end -0.7874 0.4064)
			(stroke
				(width 0.1524)
				(type default)
			)
			(layer "B.SilkS")
		)
		(fp_line
			(start 0.7874 -0.4064)
			(end -0.7874 -0.4064)
			(stroke
				(width 0.1524)
				(type default)
			)
			(layer "B.SilkS")
		)
		(fp_line
			(start -0.67945 0.3048)
			(end -0.120396 0.3048)
			(stroke
				(width 0.1)
				(type default)
			)
			(layer "B.Fab")
		)
		(fp_line
			(start -0.120396 0.3048)
			(end -0.120396 0.2794)
			(stroke
				(width 0.1)
				(type default)
			)
			(layer "B.Fab")
		)
		(fp_line
			(start 0.12065 0.3048)
			(end 0.67945 0.3048)
			(stroke
				(width 0.1)
				(type default)
			)
			(layer "B.Fab")
		)
		(fp_line
			(start 0.67945 0.3048)
			(end 0.67945 -0.305054)
			(stroke
				(width 0.1)
				(type default)
			)
			(layer "B.Fab")
		)
		(fp_line
			(start -0.120396 0.2794)
			(end 0.12065 0.2794)
			(stroke
				(width 0.1)
				(type default)
			)
			(layer "B.Fab")
		)
		(fp_line
			(start 0.12065 0.2794)
			(end 0.12065 0.3048)
			(stroke
				(width 0.1)
				(type default)
			)
			(layer "B.Fab")
		)
		(fp_line
			(start -0.12065 -0.2794)
			(end -0.12065 -0.3048)
			(stroke
				(width 0.1)
				(type default)
			)
			(layer "B.Fab")
		)
		(fp_line
			(start 0.12065 -0.2794)
			(end -0.12065 -0.2794)
			(stroke
				(width 0.1)
				(type default)
			)
			(layer "B.Fab")
		)
		(fp_line
			(start -0.67945 -0.3048)
			(end -0.67945 0.3048)
			(stroke
				(width 0.1)
				(type default)
			)
			(layer "B.Fab")
		)
		(fp_line
			(start -0.12065 -0.3048)
			(end -0.67945 -0.3048)
			(stroke
				(width 0.1)
				(type default)
			)
			(layer "B.Fab")
		)
		(fp_line
			(start 0.12065 -0.305054)
			(end 0.12065 -0.2794)
			(stroke
				(width 0.1)
				(type default)
			)
			(layer "B.Fab")
		)
		(fp_line
			(start 0.67945 -0.305054)
			(end 0.12065 -0.305054)
			(stroke
				(width 0.1)
				(type default)
			)
			(layer "B.Fab")
		)
		(pad "1" smd circle
			(at 0.40005 0 90)
			(size 0 0)
			(layers "B.Cu" "B.Mask" "B.Paste")
			(net "P3V3_VDD_9ZXL0851_0_7")
		)
		(pad "2" smd circle
			(at -0.40005 0 90)
			(size 0 0)
			(layers "B.Cu" "B.Mask" "B.Paste")
			(net "GND")
		)
	)
	(footprint ""
		(layer "B.Cu")
		(at 130.539744 -205.225142 180)
		(property "Reference" "R922"
			(at 0 0 0)
			(layer "B.SilkS")
			(hide yes)
			(effects
				(font
					(size 1.27 1.27)
				)
				(justify mirror)
			)
		)
		(property "Value" ""
			(at 0 0 0)
			(layer "B.Fab")
			(effects
				(font
					(size 1.27 1.27)
				)
				(justify mirror)
			)
		)
		(duplicate_pad_numbers_are_jumpers no)
		(fp_line
			(start 0.7874 0.4064)
			(end 0.7874 -0.4064)
			(stroke
				(width 0.1524)
				(type default)
			)
			(layer "B.SilkS")
		)
		(fp_line
			(start 0.7874 -0.4064)
			(end -0.7874 -0.4064)
			(stroke
				(width 0.1524)
				(type default)
			)
			(layer "B.SilkS")
		)
		(fp_line
			(start -0.7874 0.4064)
			(end 0.7874 0.4064)
			(stroke
				(width 0.1524)
				(type default)
			)
			(layer "B.SilkS")
		)
		(fp_line
			(start -0.7874 -0.4064)
			(end -0.7874 0.4064)
			(stroke
				(width 0.1524)
				(type default)
			)
			(layer "B.SilkS")
		)
		(fp_line
			(start 0.67945 0.3048)
			(end 0.67945 -0.305054)
			(stroke
				(width 0.1)
				(type default)
			)
			(layer "B.Fab")
		)
		(fp_line
			(start 0.67945 -0.305054)
			(end 0.12065 -0.305054)
			(stroke
				(width 0.1)
				(type default)
			)
			(layer "B.Fab")
		)
		(fp_line
			(start 0.12065 0.3048)
			(end 0.67945 0.3048)
			(stroke
				(width 0.1)
				(type default)
			)
			(layer "B.Fab")
		)
		(fp_line
			(start 0.12065 0.2794)
			(end 0.12065 0.3048)
			(stroke
				(width 0.1)
				(type default)
			)
			(layer "B.Fab")
		)
		(fp_line
			(start 0.12065 -0.2794)
			(end -0.12065 -0.2794)
			(stroke
				(width 0.1)
				(type default)
			)
			(layer "B.Fab")
		)
		(fp_line
			(start 0.12065 -0.305054)
			(end 0.12065 -0.2794)
			(stroke
				(width 0.1)
				(type default)
			)
			(layer "B.Fab")
		)
		(fp_line
			(start -0.120396 0.3048)
			(end -0.120396 0.2794)
			(stroke
				(width 0.1)
				(type default)
			)
			(layer "B.Fab")
		)
		(fp_line
			(start -0.120396 0.2794)
			(end 0.12065 0.2794)
			(stroke
				(width 0.1)
				(type default)
			)
			(layer "B.Fab")
		)
		(fp_line
			(start -0.12065 -0.2794)
			(end -0.12065 -0.3048)
			(stroke
				(width 0.1)
				(type default)
			)
			(layer "B.Fab")
		)
		(fp_line
			(start -0.12065 -0.3048)
			(end -0.67945 -0.3048)
			(stroke
				(width 0.1)
				(type default)
			)
			(layer "B.Fab")
		)
		(fp_line
			(start -0.67945 0.3048)
			(end -0.120396 0.3048)
			(stroke
				(width 0.1)
				(type default)
			)
			(layer "B.Fab")
		)
		(fp_line
			(start -0.67945 -0.3048)
			(end -0.67945 0.3048)
			(stroke
				(width 0.1)
				(type default)
			)
			(layer "B.Fab")
		)
		(pad "1" smd circle
			(at 0.40005 0)
			(size 0 0)
			(layers "B.Cu" "B.Mask" "B.Paste")
			(net "FT4232_CLI_EEPROM_R_SCL")
		)
		(pad "2" smd circle
			(at -0.40005 0)
			(size 0 0)
			(layers "B.Cu" "B.Mask" "B.Paste")
			(net "FT4232_CLI_EEPROM_SCL")
		)
	)
	(footprint ""
		(layer "B.Cu")
		(at 280.241502 -303.024794)
		(property "Reference" "C3343"
			(at 0 0 0)
			(layer "B.SilkS")
			(hide yes)
			(effects
				(font
					(size 1.27 1.27)
				)
				(justify mirror)
			)
		)
		(property "Value" ""
			(at 0 0 0)
			(layer "B.Fab")
			(effects
				(font
					(size 1.27 1.27)
				)
				(justify mirror)
			)
		)
		(duplicate_pad_numbers_are_jumpers no)
		(fp_line
			(start -0.299974 -0.150114)
			(end -0.299974 0.150114)
			(stroke
				(width 0.1)
				(type default)
			)
			(layer "B.Fab")
		)
		(fp_line
			(start -0.299974 0.150114)
			(end 0.299974 0.150114)
			(stroke
				(width 0.1)
				(type default)
			)
			(layer "B.Fab")
		)
		(fp_line
			(start 0.299974 -0.150114)
			(end -0.299974 -0.150114)
			(stroke
				(width 0.1)
				(type default)
			)
			(layer "B.Fab")
		)
		(fp_line
			(start 0.299974 0.150114)
			(end 0.299974 -0.150114)
			(stroke
				(width 0.1)
				(type default)
			)
			(layer "B.Fab")
		)
		(pad "1" smd rect
			(at 0.2667 0 180)
			(size 0.3048 0.381)
			(layers "B.Cu" "B.Mask" "B.Paste")
			(net "P1V8_VDDA_PEX2")
		)
		(pad "2" smd rect
			(at -0.2667 0 180)
			(size 0.3048 0.381)
			(layers "B.Cu" "B.Mask" "B.Paste")
			(net "GND")
		)
	)
	(footprint ""
		(layer "B.Cu")
		(at 210.458812 -223.61906)
		(property "Reference" "R6800"
			(at 0 0 0)
			(layer "B.SilkS")
			(hide yes)
			(effects
				(font
					(size 1.27 1.27)
				)
				(justify mirror)
			)
		)
		(property "Value" ""
			(at 0 0 0)
			(layer "B.Fab")
			(effects
				(font
					(size 1.27 1.27)
				)
				(justify mirror)
			)
		)
		(duplicate_pad_numbers_are_jumpers no)
		(fp_line
			(start -0.7874 -0.4064)
			(end -0.7874 0.4064)
			(stroke
				(width 0.1524)
				(type default)
			)
			(layer "B.SilkS")
		)
		(fp_line
			(start -0.7874 0.4064)
			(end 0.7874 0.4064)
			(stroke
				(width 0.1524)
				(type default)
			)
			(layer "B.SilkS")
		)
		(fp_line
			(start 0.7874 -0.4064)
			(end -0.7874 -0.4064)
			(stroke
				(width 0.1524)
				(type default)
			)
			(layer "B.SilkS")
		)
		(fp_line
			(start 0.7874 0.4064)
			(end 0.7874 -0.4064)
			(stroke
				(width 0.1524)
				(type default)
			)
			(layer "B.SilkS")
		)
		(fp_line
			(start -0.67945 -0.3048)
			(end -0.67945 0.3048)
			(stroke
				(width 0.1)
				(type default)
			)
			(layer "B.Fab")
		)
		(fp_line
			(start -0.67945 0.3048)
			(end -0.120396 0.3048)
			(stroke
				(width 0.1)
				(type default)
			)
			(layer "B.Fab")
		)
		(fp_line
			(start -0.12065 -0.3048)
			(end -0.67945 -0.3048)
			(stroke
				(width 0.1)
				(type default)
			)
			(layer "B.Fab")
		)
		(fp_line
			(start -0.12065 -0.2794)
			(end -0.12065 -0.3048)
			(stroke
				(width 0.1)
				(type default)
			)
			(layer "B.Fab")
		)
		(fp_line
			(start -0.120396 0.2794)
			(end 0.12065 0.2794)
			(stroke
				(width 0.1)
				(type default)
			)
			(layer "B.Fab")
		)
		(fp_line
			(start -0.120396 0.3048)
			(end -0.120396 0.2794)
			(stroke
				(width 0.1)
				(type default)
			)
			(layer "B.Fab")
		)
		(fp_line
			(start 0.12065 -0.305054)
			(end 0.12065 -0.2794)
			(stroke
				(width 0.1)
				(type default)
			)
			(layer "B.Fab")
		)
		(fp_line
			(start 0.12065 -0.2794)
			(end -0.12065 -0.2794)
			(stroke
				(width 0.1)
				(type default)
			)
			(layer "B.Fab")
		)
		(fp_line
			(start 0.12065 0.2794)
			(end 0.12065 0.3048)
			(stroke
				(width 0.1)
				(type default)
			)
			(layer "B.Fab")
		)
		(fp_line
			(start 0.12065 0.3048)
			(end 0.67945 0.3048)
			(stroke
				(width 0.1)
				(type default)
			)
			(layer "B.Fab")
		)
		(fp_line
			(start 0.67945 -0.305054)
			(end 0.12065 -0.305054)
			(stroke
				(width 0.1)
				(type default)
			)
			(layer "B.Fab")
		)
		(fp_line
			(start 0.67945 0.3048)
			(end 0.67945 -0.305054)
			(stroke
				(width 0.1)
				(type default)
			)
			(layer "B.Fab")
		)
		(pad "1" smd circle
			(at 0.40005 0 180)
			(size 0 0)
			(layers "B.Cu" "B.Mask" "B.Paste")
			(net "SMB_BIC_FPGA_SDA")
		)
		(pad "2" smd circle
			(at -0.40005 0 180)
			(size 0 0)
			(layers "B.Cu" "B.Mask" "B.Paste")
			(net "SMB_BIC_FPGA_R1_SDA")
		)
	)
	(footprint ""
		(layer "B.Cu")
		(at 349.272098 -283.818584 90)
		(property "Reference" "PR152"
			(at 0 0 90)
			(layer "B.SilkS")
			(hide yes)
			(effects
				(font
					(size 1.27 1.27)
				)
				(justify mirror)
			)
		)
		(property "Value" ""
			(at 0 0 90)
			(layer "B.Fab")
			(effects
				(font
					(size 1.27 1.27)
				)
				(justify mirror)
			)
		)
		(duplicate_pad_numbers_are_jumpers no)
		(fp_line
			(start 0.7874 -0.4064)
			(end -0.7874 -0.4064)
			(stroke
				(width 0.1524)
				(type default)
			)
			(layer "B.SilkS")
		)
		(fp_line
			(start -0.7874 -0.4064)
			(end -0.7874 0.4064)
			(stroke
				(width 0.1524)
				(type default)
			)
			(layer "B.SilkS")
		)
		(fp_line
			(start 0.7874 0.4064)
			(end 0.7874 -0.4064)
			(stroke
				(width 0.1524)
				(type default)
			)
			(layer "B.SilkS")
		)
		(fp_line
			(start -0.7874 0.4064)
			(end 0.7874 0.4064)
			(stroke
				(width 0.1524)
				(type default)
			)
			(layer "B.SilkS")
		)
		(fp_line
			(start 0.67945 -0.305054)
			(end 0.12065 -0.305054)
			(stroke
				(width 0.1)
				(type default)
			)
			(layer "B.Fab")
		)
		(fp_line
			(start 0.12065 -0.305054)
			(end 0.12065 -0.2794)
			(stroke
				(width 0.1)
				(type default)
			)
			(layer "B.Fab")
		)
		(fp_line
			(start -0.12065 -0.3048)
			(end -0.67945 -0.3048)
			(stroke
				(width 0.1)
				(type default)
			)
			(layer "B.Fab")
		)
		(fp_line
			(start -0.67945 -0.3048)
			(end -0.67945 0.3048)
			(stroke
				(width 0.1)
				(type default)
			)
			(layer "B.Fab")
		)
		(fp_line
			(start 0.12065 -0.2794)
			(end -0.12065 -0.2794)
			(stroke
				(width 0.1)
				(type default)
			)
			(layer "B.Fab")
		)
		(fp_line
			(start -0.12065 -0.2794)
			(end -0.12065 -0.3048)
			(stroke
				(width 0.1)
				(type default)
			)
			(layer "B.Fab")
		)
		(fp_line
			(start 0.12065 0.2794)
			(end 0.12065 0.3048)
			(stroke
				(width 0.1)
				(type default)
			)
			(layer "B.Fab")
		)
		(fp_line
			(start -0.120396 0.2794)
			(end 0.12065 0.2794)
			(stroke
				(width 0.1)
				(type default)
			)
			(layer "B.Fab")
		)
		(fp_line
			(start 0.67945 0.3048)
			(end 0.67945 -0.305054)
			(stroke
				(width 0.1)
				(type default)
			)
			(layer "B.Fab")
		)
		(fp_line
			(start 0.12065 0.3048)
			(end 0.67945 0.3048)
			(stroke
				(width 0.1)
				(type default)
			)
			(layer "B.Fab")
		)
		(fp_line
			(start -0.120396 0.3048)
			(end -0.120396 0.2794)
			(stroke
				(width 0.1)
				(type default)
			)
			(layer "B.Fab")
		)
		(fp_line
			(start -0.67945 0.3048)
			(end -0.120396 0.3048)
			(stroke
				(width 0.1)
				(type default)
			)
			(layer "B.Fab")
		)
		(pad "1" smd circle
			(at 0.40005 0 270)
			(size 0 0)
			(layers "B.Cu" "B.Mask" "B.Paste")
			(net "P0V8_PEX2_PVCC")
		)
		(pad "2" smd circle
			(at -0.40005 0 270)
			(size 0 0)
			(layers "B.Cu" "B.Mask" "B.Paste")
			(net "P0V8_PEX2_VCC2")
		)
	)
	(footprint ""
		(layer "B.Cu")
		(at 170.524932 -305.399948 -90)
		(property "Reference" "C3156"
			(at 0 0 90)
			(layer "B.SilkS")
			(hide yes)
			(effects
				(font
					(size 1.27 1.27)
				)
				(justify mirror)
			)
		)
		(property "Value" ""
			(at 0 0 90)
			(layer "B.Fab")
			(effects
				(font
					(size 1.27 1.27)
				)
				(justify mirror)
			)
		)
		(duplicate_pad_numbers_are_jumpers no)
		(fp_line
			(start -0.299974 0.150114)
			(end 0.299974 0.150114)
			(stroke
				(width 0.1)
				(type default)
			)
			(layer "B.Fab")
		)
		(fp_line
			(start 0.299974 0.150114)
			(end 0.299974 -0.150114)
			(stroke
				(width 0.1)
				(type default)
			)
			(layer "B.Fab")
		)
		(fp_line
			(start -0.299974 -0.150114)
			(end -0.299974 0.150114)
			(stroke
				(width 0.1)
				(type default)
			)
			(layer "B.Fab")
		)
		(fp_line
			(start 0.299974 -0.150114)
			(end -0.299974 -0.150114)
			(stroke
				(width 0.1)
				(type default)
			)
			(layer "B.Fab")
		)
		(pad "1" smd rect
			(at 0.2667 0 90)
			(size 0.3048 0.381)
			(layers "B.Cu" "B.Mask" "B.Paste")
			(net "P1V25_SERDES_VDDPLL_PEX1")
		)
		(pad "2" smd rect
			(at -0.2667 0 90)
			(size 0.3048 0.381)
			(layers "B.Cu" "B.Mask" "B.Paste")
			(net "GND")
		)
	)
	(footprint ""
		(layer "B.Cu")
		(at 124.331222 -201.93635 180)
		(property "Reference" "R918"
			(at 0 0 0)
			(layer "B.SilkS")
			(hide yes)
			(effects
				(font
					(size 1.27 1.27)
				)
				(justify mirror)
			)
		)
		(property "Value" ""
			(at 0 0 0)
			(layer "B.Fab")
			(effects
				(font
					(size 1.27 1.27)
				)
				(justify mirror)
			)
		)
		(duplicate_pad_numbers_are_jumpers no)
		(fp_line
			(start 0.7874 0.4064)
			(end 0.7874 -0.4064)
			(stroke
				(width 0.1524)
				(type default)
			)
			(layer "B.SilkS")
		)
		(fp_line
			(start 0.7874 -0.4064)
			(end -0.7874 -0.4064)
			(stroke
				(width 0.1524)
				(type default)
			)
			(layer "B.SilkS")
		)
		(fp_line
			(start -0.7874 0.4064)
			(end 0.7874 0.4064)
			(stroke
				(width 0.1524)
				(type default)
			)
			(layer "B.SilkS")
		)
		(fp_line
			(start -0.7874 -0.4064)
			(end -0.7874 0.4064)
			(stroke
				(width 0.1524)
				(type default)
			)
			(layer "B.SilkS")
		)
		(fp_line
			(start 0.67945 0.3048)
			(end 0.67945 -0.305054)
			(stroke
				(width 0.1)
				(type default)
			)
			(layer "B.Fab")
		)
		(fp_line
			(start 0.67945 -0.305054)
			(end 0.12065 -0.305054)
			(stroke
				(width 0.1)
				(type default)
			)
			(layer "B.Fab")
		)
		(fp_line
			(start 0.12065 0.3048)
			(end 0.67945 0.3048)
			(stroke
				(width 0.1)
				(type default)
			)
			(layer "B.Fab")
		)
		(fp_line
			(start 0.12065 0.2794)
			(end 0.12065 0.3048)
			(stroke
				(width 0.1)
				(type default)
			)
			(layer "B.Fab")
		)
		(fp_line
			(start 0.12065 -0.2794)
			(end -0.12065 -0.2794)
			(stroke
				(width 0.1)
				(type default)
			)
			(layer "B.Fab")
		)
		(fp_line
			(start 0.12065 -0.305054)
			(end 0.12065 -0.2794)
			(stroke
				(width 0.1)
				(type default)
			)
			(layer "B.Fab")
		)
		(fp_line
			(start -0.120396 0.3048)
			(end -0.120396 0.2794)
			(stroke
				(width 0.1)
				(type default)
			)
			(layer "B.Fab")
		)
		(fp_line
			(start -0.120396 0.2794)
			(end 0.12065 0.2794)
			(stroke
				(width 0.1)
				(type default)
			)
			(layer "B.Fab")
		)
		(fp_line
			(start -0.12065 -0.2794)
			(end -0.12065 -0.3048)
			(stroke
				(width 0.1)
				(type default)
			)
			(layer "B.Fab")
		)
		(fp_line
			(start -0.12065 -0.3048)
			(end -0.67945 -0.3048)
			(stroke
				(width 0.1)
				(type default)
			)
			(layer "B.Fab")
		)
		(fp_line
			(start -0.67945 0.3048)
			(end -0.120396 0.3048)
			(stroke
				(width 0.1)
				(type default)
			)
			(layer "B.Fab")
		)
		(fp_line
			(start -0.67945 -0.3048)
			(end -0.67945 0.3048)
			(stroke
				(width 0.1)
				(type default)
			)
			(layer "B.Fab")
		)
		(pad "1" smd circle
			(at 0.40005 0)
			(size 0 0)
			(layers "B.Cu" "B.Mask" "B.Paste")
			(net "FT4232_CLI_EEPROM_DO")
		)
		(pad "2" smd circle
			(at -0.40005 0)
			(size 0 0)
			(layers "B.Cu" "B.Mask" "B.Paste")
			(net "P3V3_AUX")
		)
	)
	(footprint ""
		(layer "B.Cu")
		(at 349.290894 -308.613556 90)
		(property "Reference" "C1667"
			(at 0 0 90)
			(layer "B.SilkS")
			(hide yes)
			(effects
				(font
					(size 1.27 1.27)
				)
				(justify mirror)
			)
		)
		(property "Value" ""
			(at 0 0 90)
			(layer "B.Fab")
			(effects
				(font
					(size 1.27 1.27)
				)
				(justify mirror)
			)
		)
		(duplicate_pad_numbers_are_jumpers no)
		(fp_line
			(start 1.2954 -0.5842)
			(end -1.2954 -0.5842)
			(stroke
				(width 0.1524)
				(type default)
			)
			(layer "B.SilkS")
		)
		(fp_line
			(start -1.2954 -0.5842)
			(end -1.2954 0.5842)
			(stroke
				(width 0.1524)
				(type default)
			)
			(layer "B.SilkS")
		)
		(fp_line
			(start 1.2954 0.5842)
			(end 1.2954 -0.5842)
			(stroke
				(width 0.1524)
				(type default)
			)
			(layer "B.SilkS")
		)
		(fp_line
			(start -1.2954 0.5842)
			(end 1.2954 0.5842)
			(stroke
				(width 0.1524)
				(type default)
			)
			(layer "B.SilkS")
		)
		(fp_line
			(start 0.8636 -0.4572)
			(end -0.8636 -0.4572)
			(stroke
				(width 0.1)
				(type default)
			)
			(layer "B.Fab")
		)
		(fp_line
			(start -0.8636 -0.4572)
			(end -0.8636 -0.4064)
			(stroke
				(width 0.1)
				(type default)
			)
			(layer "B.Fab")
		)
		(fp_line
			(start 1.1938 -0.4064)
			(end 0.8636 -0.4064)
			(stroke
				(width 0.1)
				(type default)
			)
			(layer "B.Fab")
		)
		(fp_line
			(start 0.8636 -0.4064)
			(end 0.8636 -0.4572)
			(stroke
				(width 0.1)
				(type default)
			)
			(layer "B.Fab")
		)
		(fp_line
			(start -0.8636 -0.4064)
			(end -1.1938 -0.4064)
			(stroke
				(width 0.1)
				(type default)
			)
			(layer "B.Fab")
		)
		(fp_line
			(start -1.1938 -0.4064)
			(end -1.1938 0.4064)
			(stroke
				(width 0.1)
				(type default)
			)
			(layer "B.Fab")
		)
		(fp_line
			(start 1.1938 0.4064)
			(end 1.1938 -0.4064)
			(stroke
				(width 0.1)
				(type default)
			)
			(layer "B.Fab")
		)
		(fp_line
			(start 0.8636 0.4064)
			(end 1.1938 0.4064)
			(stroke
				(width 0.1)
				(type default)
			)
			(layer "B.Fab")
		)
		(fp_line
			(start -0.8636 0.4064)
			(end -0.8636 0.4572)
			(stroke
				(width 0.1)
				(type default)
			)
			(layer "B.Fab")
		)
		(fp_line
			(start -1.1938 0.4064)
			(end -0.8636 0.4064)
			(stroke
				(width 0.1)
				(type default)
			)
			(layer "B.Fab")
		)
		(fp_line
			(start 0.8636 0.4572)
			(end 0.8636 0.4064)
			(stroke
				(width 0.1)
				(type default)
			)
			(layer "B.Fab")
		)
		(fp_line
			(start -0.8636 0.4572)
			(end 0.8636 0.4572)
			(stroke
				(width 0.1)
				(type default)
			)
			(layer "B.Fab")
		)
		(pad "1" smd rect
			(at 0.7366 0)
			(size 0.7112 0.8128)
			(layers "B.Cu" "B.Mask" "B.Paste")
			(net "P0V8_SERDES_VDDA_PEX2")
		)
		(pad "2" smd rect
			(at -0.7366 0)
			(size 0.7112 0.8128)
			(layers "B.Cu" "B.Mask" "B.Paste")
			(net "GND")
		)
	)
	(footprint ""
		(layer "B.Cu")
		(at 410.02204 -296.3926)
		(property "Reference" "C1897"
			(at 0 0 0)
			(layer "B.SilkS")
			(hide yes)
			(effects
				(font
					(size 1.27 1.27)
				)
				(justify mirror)
			)
		)
		(property "Value" ""
			(at 0 0 0)
			(layer "B.Fab")
			(effects
				(font
					(size 1.27 1.27)
				)
				(justify mirror)
			)
		)
		(duplicate_pad_numbers_are_jumpers no)
		(fp_line
			(start -0.299974 -0.150114)
			(end -0.299974 0.150114)
			(stroke
				(width 0.1)
				(type default)
			)
			(layer "B.Fab")
		)
		(fp_line
			(start -0.299974 0.150114)
			(end 0.299974 0.150114)
			(stroke
				(width 0.1)
				(type default)
			)
			(layer "B.Fab")
		)
		(fp_line
			(start 0.299974 -0.150114)
			(end -0.299974 -0.150114)
			(stroke
				(width 0.1)
				(type default)
			)
			(layer "B.Fab")
		)
		(fp_line
			(start 0.299974 0.150114)
			(end 0.299974 -0.150114)
			(stroke
				(width 0.1)
				(type default)
			)
			(layer "B.Fab")
		)
		(pad "1" smd rect
			(at 0.2667 0 180)
			(size 0.3048 0.381)
			(layers "B.Cu" "B.Mask" "B.Paste")
			(net "P0V8_PEX3")
		)
		(pad "2" smd rect
			(at -0.2667 0 180)
			(size 0.3048 0.381)
			(layers "B.Cu" "B.Mask" "B.Paste")
			(net "GND")
		)
	)
	(footprint ""
		(layer "B.Cu")
		(at 56.799988 -303.499774 -90)
		(property "Reference" "C2918"
			(at 0 0 90)
			(layer "B.SilkS")
			(hide yes)
			(effects
				(font
					(size 1.27 1.27)
				)
				(justify mirror)
			)
		)
		(property "Value" ""
			(at 0 0 90)
			(layer "B.Fab")
			(effects
				(font
					(size 1.27 1.27)
				)
				(justify mirror)
			)
		)
		(duplicate_pad_numbers_are_jumpers no)
		(fp_line
			(start -0.299974 0.150114)
			(end 0.299974 0.150114)
			(stroke
				(width 0.1)
				(type default)
			)
			(layer "B.Fab")
		)
		(fp_line
			(start 0.299974 0.150114)
			(end 0.299974 -0.150114)
			(stroke
				(width 0.1)
				(type default)
			)
			(layer "B.Fab")
		)
		(fp_line
			(start -0.299974 -0.150114)
			(end -0.299974 0.150114)
			(stroke
				(width 0.1)
				(type default)
			)
			(layer "B.Fab")
		)
		(fp_line
			(start 0.299974 -0.150114)
			(end -0.299974 -0.150114)
			(stroke
				(width 0.1)
				(type default)
			)
			(layer "B.Fab")
		)
		(pad "1" smd rect
			(at 0.2667 0 90)
			(size 0.3048 0.381)
			(layers "B.Cu" "B.Mask" "B.Paste")
			(net "P1V25_PEX0")
		)
		(pad "2" smd rect
			(at -0.2667 0 90)
			(size 0.3048 0.381)
			(layers "B.Cu" "B.Mask" "B.Paste")
			(net "GND")
		)
	)
	(footprint ""
		(layer "B.Cu")
		(at 182.87492 -305.399948 -90)
		(property "Reference" "C3137"
			(at 0 0 90)
			(layer "B.SilkS")
			(hide yes)
			(effects
				(font
					(size 1.27 1.27)
				)
				(justify mirror)
			)
		)
		(property "Value" ""
			(at 0 0 90)
			(layer "B.Fab")
			(effects
				(font
					(size 1.27 1.27)
				)
				(justify mirror)
			)
		)
		(duplicate_pad_numbers_are_jumpers no)
		(fp_line
			(start -0.299974 0.150114)
			(end 0.299974 0.150114)
			(stroke
				(width 0.1)
				(type default)
			)
			(layer "B.Fab")
		)
		(fp_line
			(start 0.299974 0.150114)
			(end 0.299974 -0.150114)
			(stroke
				(width 0.1)
				(type default)
			)
			(layer "B.Fab")
		)
		(fp_line
			(start -0.299974 -0.150114)
			(end -0.299974 0.150114)
			(stroke
				(width 0.1)
				(type default)
			)
			(layer "B.Fab")
		)
		(fp_line
			(start 0.299974 -0.150114)
			(end -0.299974 -0.150114)
			(stroke
				(width 0.1)
				(type default)
			)
			(layer "B.Fab")
		)
		(pad "1" smd rect
			(at 0.2667 0 90)
			(size 0.3048 0.381)
			(layers "B.Cu" "B.Mask" "B.Paste")
			(net "P1V25_SERDES_VDDPLL_PEX1")
		)
		(pad "2" smd rect
			(at -0.2667 0 90)
			(size 0.3048 0.381)
			(layers "B.Cu" "B.Mask" "B.Paste")
			(net "GND")
		)
	)
	(footprint ""
		(layer "B.Cu")
		(at 170.049952 -303.499774 -90)
		(property "Reference" "C3088"
			(at 0 0 90)
			(layer "B.SilkS")
			(hide yes)
			(effects
				(font
					(size 1.27 1.27)
				)
				(justify mirror)
			)
		)
		(property "Value" ""
			(at 0 0 90)
			(layer "B.Fab")
			(effects
				(font
					(size 1.27 1.27)
				)
				(justify mirror)
			)
		)
		(duplicate_pad_numbers_are_jumpers no)
		(fp_line
			(start -0.299974 0.150114)
			(end 0.299974 0.150114)
			(stroke
				(width 0.1)
				(type default)
			)
			(layer "B.Fab")
		)
		(fp_line
			(start 0.299974 0.150114)
			(end 0.299974 -0.150114)
			(stroke
				(width 0.1)
				(type default)
			)
			(layer "B.Fab")
		)
		(fp_line
			(start -0.299974 -0.150114)
			(end -0.299974 0.150114)
			(stroke
				(width 0.1)
				(type default)
			)
			(layer "B.Fab")
		)
		(fp_line
			(start 0.299974 -0.150114)
			(end -0.299974 -0.150114)
			(stroke
				(width 0.1)
				(type default)
			)
			(layer "B.Fab")
		)
		(pad "1" smd rect
			(at 0.2667 0 90)
			(size 0.3048 0.381)
			(layers "B.Cu" "B.Mask" "B.Paste")
			(net "P1V25_PEX1")
		)
		(pad "2" smd rect
			(at -0.2667 0 90)
			(size 0.3048 0.381)
			(layers "B.Cu" "B.Mask" "B.Paste")
			(net "GND")
		)
	)
	(footprint ""
		(layer "B.Cu")
		(at 156.273754 -295.79824 180)
		(property "Reference" "R3456"
			(at 0 0 0)
			(layer "B.SilkS")
			(hide yes)
			(effects
				(font
					(size 1.27 1.27)
				)
				(justify mirror)
			)
		)
		(property "Value" ""
			(at 0 0 0)
			(layer "B.Fab")
			(effects
				(font
					(size 1.27 1.27)
				)
				(justify mirror)
			)
		)
		(duplicate_pad_numbers_are_jumpers no)
		(fp_line
			(start 0.7874 0.4064)
			(end 0.7874 -0.4064)
			(stroke
				(width 0.1524)
				(type default)
			)
			(layer "B.SilkS")
		)
		(fp_line
			(start 0.7874 -0.4064)
			(end -0.7874 -0.4064)
			(stroke
				(width 0.1524)
				(type default)
			)
			(layer "B.SilkS")
		)
		(fp_line
			(start -0.7874 0.4064)
			(end 0.7874 0.4064)
			(stroke
				(width 0.1524)
				(type default)
			)
			(layer "B.SilkS")
		)
		(fp_line
			(start -0.7874 -0.4064)
			(end -0.7874 0.4064)
			(stroke
				(width 0.1524)
				(type default)
			)
			(layer "B.SilkS")
		)
		(fp_line
			(start 0.67945 0.3048)
			(end 0.67945 -0.305054)
			(stroke
				(width 0.1)
				(type default)
			)
			(layer "B.Fab")
		)
		(fp_line
			(start 0.67945 -0.305054)
			(end 0.12065 -0.305054)
			(stroke
				(width 0.1)
				(type default)
			)
			(layer "B.Fab")
		)
		(fp_line
			(start 0.12065 0.3048)
			(end 0.67945 0.3048)
			(stroke
				(width 0.1)
				(type default)
			)
			(layer "B.Fab")
		)
		(fp_line
			(start 0.12065 0.2794)
			(end 0.12065 0.3048)
			(stroke
				(width 0.1)
				(type default)
			)
			(layer "B.Fab")
		)
		(fp_line
			(start 0.12065 -0.2794)
			(end -0.12065 -0.2794)
			(stroke
				(width 0.1)
				(type default)
			)
			(layer "B.Fab")
		)
		(fp_line
			(start 0.12065 -0.305054)
			(end 0.12065 -0.2794)
			(stroke
				(width 0.1)
				(type default)
			)
			(layer "B.Fab")
		)
		(fp_line
			(start -0.120396 0.3048)
			(end -0.120396 0.2794)
			(stroke
				(width 0.1)
				(type default)
			)
			(layer "B.Fab")
		)
		(fp_line
			(start -0.120396 0.2794)
			(end 0.12065 0.2794)
			(stroke
				(width 0.1)
				(type default)
			)
			(layer "B.Fab")
		)
		(fp_line
			(start -0.12065 -0.2794)
			(end -0.12065 -0.3048)
			(stroke
				(width 0.1)
				(type default)
			)
			(layer "B.Fab")
		)
		(fp_line
			(start -0.12065 -0.3048)
			(end -0.67945 -0.3048)
			(stroke
				(width 0.1)
				(type default)
			)
			(layer "B.Fab")
		)
		(fp_line
			(start -0.67945 0.3048)
			(end -0.120396 0.3048)
			(stroke
				(width 0.1)
				(type default)
			)
			(layer "B.Fab")
		)
		(fp_line
			(start -0.67945 -0.3048)
			(end -0.67945 0.3048)
			(stroke
				(width 0.1)
				(type default)
			)
			(layer "B.Fab")
		)
		(pad "1" smd circle
			(at 0.40005 0)
			(size 0 0)
			(layers "B.Cu" "B.Mask" "B.Paste")
			(net "SPI_PEX1_SDIO0_R")
		)
		(pad "2" smd circle
			(at -0.40005 0)
			(size 0 0)
			(layers "B.Cu" "B.Mask" "B.Paste")
			(net "SPI_PEX1_SDIO0")
		)
	)
	(footprint ""
		(layer "B.Cu")
		(at 333.909416 -323.15531 -90)
		(property "Reference" "R6517"
			(at 0 0 90)
			(layer "B.SilkS")
			(hide yes)
			(effects
				(font
					(size 1.27 1.27)
				)
				(justify mirror)
			)
		)
		(property "Value" ""
			(at 0 0 90)
			(layer "B.Fab")
			(effects
				(font
					(size 1.27 1.27)
				)
				(justify mirror)
			)
		)
		(duplicate_pad_numbers_are_jumpers no)
		(fp_line
			(start -0.7874 0.4064)
			(end 0.7874 0.4064)
			(stroke
				(width 0.1524)
				(type default)
			)
			(layer "B.SilkS")
		)
		(fp_line
			(start 0.7874 0.4064)
			(end 0.7874 -0.4064)
			(stroke
				(width 0.1524)
				(type default)
			)
			(layer "B.SilkS")
		)
		(fp_line
			(start -0.7874 -0.4064)
			(end -0.7874 0.4064)
			(stroke
				(width 0.1524)
				(type default)
			)
			(layer "B.SilkS")
		)
		(fp_line
			(start 0.7874 -0.4064)
			(end -0.7874 -0.4064)
			(stroke
				(width 0.1524)
				(type default)
			)
			(layer "B.SilkS")
		)
		(fp_line
			(start -0.67945 0.3048)
			(end -0.120396 0.3048)
			(stroke
				(width 0.1)
				(type default)
			)
			(layer "B.Fab")
		)
		(fp_line
			(start -0.120396 0.3048)
			(end -0.120396 0.2794)
			(stroke
				(width 0.1)
				(type default)
			)
			(layer "B.Fab")
		)
		(fp_line
			(start 0.12065 0.3048)
			(end 0.67945 0.3048)
			(stroke
				(width 0.1)
				(type default)
			)
			(layer "B.Fab")
		)
		(fp_line
			(start 0.67945 0.3048)
			(end 0.67945 -0.305054)
			(stroke
				(width 0.1)
				(type default)
			)
			(layer "B.Fab")
		)
		(fp_line
			(start -0.120396 0.2794)
			(end 0.12065 0.2794)
			(stroke
				(width 0.1)
				(type default)
			)
			(layer "B.Fab")
		)
		(fp_line
			(start 0.12065 0.2794)
			(end 0.12065 0.3048)
			(stroke
				(width 0.1)
				(type default)
			)
			(layer "B.Fab")
		)
		(fp_line
			(start -0.12065 -0.2794)
			(end -0.12065 -0.3048)
			(stroke
				(width 0.1)
				(type default)
			)
			(layer "B.Fab")
		)
		(fp_line
			(start 0.12065 -0.2794)
			(end -0.12065 -0.2794)
			(stroke
				(width 0.1)
				(type default)
			)
			(layer "B.Fab")
		)
		(fp_line
			(start -0.67945 -0.3048)
			(end -0.67945 0.3048)
			(stroke
				(width 0.1)
				(type default)
			)
			(layer "B.Fab")
		)
		(fp_line
			(start -0.12065 -0.3048)
			(end -0.67945 -0.3048)
			(stroke
				(width 0.1)
				(type default)
			)
			(layer "B.Fab")
		)
		(fp_line
			(start 0.12065 -0.305054)
			(end 0.12065 -0.2794)
			(stroke
				(width 0.1)
				(type default)
			)
			(layer "B.Fab")
		)
		(fp_line
			(start 0.67945 -0.305054)
			(end 0.12065 -0.305054)
			(stroke
				(width 0.1)
				(type default)
			)
			(layer "B.Fab")
		)
		(pad "1" smd circle
			(at 0.40005 0 90)
			(size 0 0)
			(layers "B.Cu" "B.Mask" "B.Paste")
			(net "P0V8_SERDES_VDDA_PEX2")
		)
		(pad "2" smd circle
			(at -0.40005 0 90)
			(size 0 0)
			(layers "B.Cu" "B.Mask" "B.Paste")
			(net "P0V8_SERDES_VDDA_PEX2_C10")
		)
	)
	(footprint ""
		(layer "B.Cu")
		(at 301.141384 -286.874966)
		(property "Reference" "C3344"
			(at 0 0 0)
			(layer "B.SilkS")
			(hide yes)
			(effects
				(font
					(size 1.27 1.27)
				)
				(justify mirror)
			)
		)
		(property "Value" ""
			(at 0 0 0)
			(layer "B.Fab")
			(effects
				(font
					(size 1.27 1.27)
				)
				(justify mirror)
			)
		)
		(duplicate_pad_numbers_are_jumpers no)
		(fp_line
			(start -0.299974 -0.150114)
			(end -0.299974 0.150114)
			(stroke
				(width 0.1)
				(type default)
			)
			(layer "B.Fab")
		)
		(fp_line
			(start -0.299974 0.150114)
			(end 0.299974 0.150114)
			(stroke
				(width 0.1)
				(type default)
			)
			(layer "B.Fab")
		)
		(fp_line
			(start 0.299974 -0.150114)
			(end -0.299974 -0.150114)
			(stroke
				(width 0.1)
				(type default)
			)
			(layer "B.Fab")
		)
		(fp_line
			(start 0.299974 0.150114)
			(end 0.299974 -0.150114)
			(stroke
				(width 0.1)
				(type default)
			)
			(layer "B.Fab")
		)
		(pad "1" smd rect
			(at 0.2667 0 180)
			(size 0.3048 0.381)
			(layers "B.Cu" "B.Mask" "B.Paste")
			(net "P1V8_VDDA_PEX2")
		)
		(pad "2" smd rect
			(at -0.2667 0 180)
			(size 0.3048 0.381)
			(layers "B.Cu" "B.Mask" "B.Paste")
			(net "GND")
		)
	)
	(footprint ""
		(layer "B.Cu")
		(at 336.27441 -308.613556 90)
		(property "Reference" "C4316"
			(at 0 0 90)
			(layer "B.SilkS")
			(hide yes)
			(effects
				(font
					(size 1.27 1.27)
				)
				(justify mirror)
			)
		)
		(property "Value" ""
			(at 0 0 90)
			(layer "B.Fab")
			(effects
				(font
					(size 1.27 1.27)
				)
				(justify mirror)
			)
		)
		(duplicate_pad_numbers_are_jumpers no)
		(fp_line
			(start 1.2954 -0.5842)
			(end -1.2954 -0.5842)
			(stroke
				(width 0.1524)
				(type default)
			)
			(layer "B.SilkS")
		)
		(fp_line
			(start -1.2954 -0.5842)
			(end -1.2954 0.5842)
			(stroke
				(width 0.1524)
				(type default)
			)
			(layer "B.SilkS")
		)
		(fp_line
			(start 1.2954 0.5842)
			(end 1.2954 -0.5842)
			(stroke
				(width 0.1524)
				(type default)
			)
			(layer "B.SilkS")
		)
		(fp_line
			(start -1.2954 0.5842)
			(end 1.2954 0.5842)
			(stroke
				(width 0.1524)
				(type default)
			)
			(layer "B.SilkS")
		)
		(fp_line
			(start 0.8636 -0.4572)
			(end -0.8636 -0.4572)
			(stroke
				(width 0.1)
				(type default)
			)
			(layer "B.Fab")
		)
		(fp_line
			(start -0.8636 -0.4572)
			(end -0.8636 -0.4064)
			(stroke
				(width 0.1)
				(type default)
			)
			(layer "B.Fab")
		)
		(fp_line
			(start 1.1938 -0.4064)
			(end 0.8636 -0.4064)
			(stroke
				(width 0.1)
				(type default)
			)
			(layer "B.Fab")
		)
		(fp_line
			(start 0.8636 -0.4064)
			(end 0.8636 -0.4572)
			(stroke
				(width 0.1)
				(type default)
			)
			(layer "B.Fab")
		)
		(fp_line
			(start -0.8636 -0.4064)
			(end -1.1938 -0.4064)
			(stroke
				(width 0.1)
				(type default)
			)
			(layer "B.Fab")
		)
		(fp_line
			(start -1.1938 -0.4064)
			(end -1.1938 0.4064)
			(stroke
				(width 0.1)
				(type default)
			)
			(layer "B.Fab")
		)
		(fp_line
			(start 1.1938 0.4064)
			(end 1.1938 -0.4064)
			(stroke
				(width 0.1)
				(type default)
			)
			(layer "B.Fab")
		)
		(fp_line
			(start 0.8636 0.4064)
			(end 1.1938 0.4064)
			(stroke
				(width 0.1)
				(type default)
			)
			(layer "B.Fab")
		)
		(fp_line
			(start -0.8636 0.4064)
			(end -0.8636 0.4572)
			(stroke
				(width 0.1)
				(type default)
			)
			(layer "B.Fab")
		)
		(fp_line
			(start -1.1938 0.4064)
			(end -0.8636 0.4064)
			(stroke
				(width 0.1)
				(type default)
			)
			(layer "B.Fab")
		)
		(fp_line
			(start 0.8636 0.4572)
			(end 0.8636 0.4064)
			(stroke
				(width 0.1)
				(type default)
			)
			(layer "B.Fab")
		)
		(fp_line
			(start -0.8636 0.4572)
			(end 0.8636 0.4572)
			(stroke
				(width 0.1)
				(type default)
			)
			(layer "B.Fab")
		)
		(pad "1" smd rect
			(at 0.7366 0)
			(size 0.7112 0.8128)
			(layers "B.Cu" "B.Mask" "B.Paste")
			(net "P0V8_PEX2")
		)
		(pad "2" smd rect
			(at -0.7366 0)
			(size 0.7112 0.8128)
			(layers "B.Cu" "B.Mask" "B.Paste")
			(net "GND")
		)
	)
	(footprint ""
		(layer "B.Cu")
		(at 293.797228 -109.481366)
		(property "Reference" "R286"
			(at 0 0 0)
			(layer "B.SilkS")
			(hide yes)
			(effects
				(font
					(size 1.27 1.27)
				)
				(justify mirror)
			)
		)
		(property "Value" ""
			(at 0 0 0)
			(layer "B.Fab")
			(effects
				(font
					(size 1.27 1.27)
				)
				(justify mirror)
			)
		)
		(duplicate_pad_numbers_are_jumpers no)
		(fp_line
			(start -0.7874 -0.4064)
			(end -0.7874 0.4064)
			(stroke
				(width 0.1524)
				(type default)
			)
			(layer "B.SilkS")
		)
		(fp_line
			(start -0.7874 0.4064)
			(end 0.7874 0.4064)
			(stroke
				(width 0.1524)
				(type default)
			)
			(layer "B.SilkS")
		)
		(fp_line
			(start 0.7874 -0.4064)
			(end -0.7874 -0.4064)
			(stroke
				(width 0.1524)
				(type default)
			)
			(layer "B.SilkS")
		)
		(fp_line
			(start 0.7874 0.4064)
			(end 0.7874 -0.4064)
			(stroke
				(width 0.1524)
				(type default)
			)
			(layer "B.SilkS")
		)
		(fp_line
			(start -0.67945 -0.3048)
			(end -0.67945 0.3048)
			(stroke
				(width 0.1)
				(type default)
			)
			(layer "B.Fab")
		)
		(fp_line
			(start -0.67945 0.3048)
			(end -0.120396 0.3048)
			(stroke
				(width 0.1)
				(type default)
			)
			(layer "B.Fab")
		)
		(fp_line
			(start -0.12065 -0.3048)
			(end -0.67945 -0.3048)
			(stroke
				(width 0.1)
				(type default)
			)
			(layer "B.Fab")
		)
		(fp_line
			(start -0.12065 -0.2794)
			(end -0.12065 -0.3048)
			(stroke
				(width 0.1)
				(type default)
			)
			(layer "B.Fab")
		)
		(fp_line
			(start -0.120396 0.2794)
			(end 0.12065 0.2794)
			(stroke
				(width 0.1)
				(type default)
			)
			(layer "B.Fab")
		)
		(fp_line
			(start -0.120396 0.3048)
			(end -0.120396 0.2794)
			(stroke
				(width 0.1)
				(type default)
			)
			(layer "B.Fab")
		)
		(fp_line
			(start 0.12065 -0.305054)
			(end 0.12065 -0.2794)
			(stroke
				(width 0.1)
				(type default)
			)
			(layer "B.Fab")
		)
		(fp_line
			(start 0.12065 -0.2794)
			(end -0.12065 -0.2794)
			(stroke
				(width 0.1)
				(type default)
			)
			(layer "B.Fab")
		)
		(fp_line
			(start 0.12065 0.2794)
			(end 0.12065 0.3048)
			(stroke
				(width 0.1)
				(type default)
			)
			(layer "B.Fab")
		)
		(fp_line
			(start 0.12065 0.3048)
			(end 0.67945 0.3048)
			(stroke
				(width 0.1)
				(type default)
			)
			(layer "B.Fab")
		)
		(fp_line
			(start 0.67945 -0.305054)
			(end 0.12065 -0.305054)
			(stroke
				(width 0.1)
				(type default)
			)
			(layer "B.Fab")
		)
		(fp_line
			(start 0.67945 0.3048)
			(end 0.67945 -0.305054)
			(stroke
				(width 0.1)
				(type default)
			)
			(layer "B.Fab")
		)
		(pad "1" smd circle
			(at 0.40005 0 180)
			(size 0 0)
			(layers "B.Cu" "B.Mask" "B.Paste")
			(net "NIC5_BIF1_N")
		)
		(pad "2" smd circle
			(at -0.40005 0 180)
			(size 0 0)
			(layers "B.Cu" "B.Mask" "B.Paste")
			(net "P3V3_AUX")
		)
	)
	(footprint ""
		(layer "B.Cu")
		(at 167.220392 -296.37482)
		(property "Reference" "C1370"
			(at 0 0 0)
			(layer "B.SilkS")
			(hide yes)
			(effects
				(font
					(size 1.27 1.27)
				)
				(justify mirror)
			)
		)
		(property "Value" ""
			(at 0 0 0)
			(layer "B.Fab")
			(effects
				(font
					(size 1.27 1.27)
				)
				(justify mirror)
			)
		)
		(duplicate_pad_numbers_are_jumpers no)
		(fp_line
			(start -0.299974 -0.150114)
			(end -0.299974 0.150114)
			(stroke
				(width 0.1)
				(type default)
			)
			(layer "B.Fab")
		)
		(fp_line
			(start -0.299974 0.150114)
			(end 0.299974 0.150114)
			(stroke
				(width 0.1)
				(type default)
			)
			(layer "B.Fab")
		)
		(fp_line
			(start 0.299974 -0.150114)
			(end -0.299974 -0.150114)
			(stroke
				(width 0.1)
				(type default)
			)
			(layer "B.Fab")
		)
		(fp_line
			(start 0.299974 0.150114)
			(end 0.299974 -0.150114)
			(stroke
				(width 0.1)
				(type default)
			)
			(layer "B.Fab")
		)
		(pad "1" smd rect
			(at 0.2667 0 180)
			(size 0.3048 0.381)
			(layers "B.Cu" "B.Mask" "B.Paste")
			(net "P0V8_PEX1")
		)
		(pad "2" smd rect
			(at -0.2667 0 180)
			(size 0.3048 0.381)
			(layers "B.Cu" "B.Mask" "B.Paste")
			(net "GND")
		)
	)
	(footprint ""
		(layer "B.Cu")
		(at 424.120818 -114.35207 90)
		(property "Reference" "C960"
			(at 0 0 90)
			(layer "B.SilkS")
			(hide yes)
			(effects
				(font
					(size 1.27 1.27)
				)
				(justify mirror)
			)
		)
		(property "Value" ""
			(at 0 0 90)
			(layer "B.Fab")
			(effects
				(font
					(size 1.27 1.27)
				)
				(justify mirror)
			)
		)
		(duplicate_pad_numbers_are_jumpers no)
		(fp_line
			(start 0.7874 -0.4064)
			(end -0.7874 -0.4064)
			(stroke
				(width 0.1524)
				(type default)
			)
			(layer "B.SilkS")
		)
		(fp_line
			(start -0.7874 -0.4064)
			(end -0.7874 0.4064)
			(stroke
				(width 0.1524)
				(type default)
			)
			(layer "B.SilkS")
		)
		(fp_line
			(start 0.7874 0.4064)
			(end 0.7874 -0.4064)
			(stroke
				(width 0.1524)
				(type default)
			)
			(layer "B.SilkS")
		)
		(fp_line
			(start -0.7874 0.4064)
			(end 0.7874 0.4064)
			(stroke
				(width 0.1524)
				(type default)
			)
			(layer "B.SilkS")
		)
		(fp_line
			(start 0.67945 -0.305054)
			(end 0.12065 -0.305054)
			(stroke
				(width 0.1)
				(type default)
			)
			(layer "B.Fab")
		)
		(fp_line
			(start 0.12065 -0.305054)
			(end 0.12065 -0.2794)
			(stroke
				(width 0.1)
				(type default)
			)
			(layer "B.Fab")
		)
		(fp_line
			(start -0.12065 -0.3048)
			(end -0.67945 -0.3048)
			(stroke
				(width 0.1)
				(type default)
			)
			(layer "B.Fab")
		)
		(fp_line
			(start -0.67945 -0.3048)
			(end -0.67945 0.3048)
			(stroke
				(width 0.1)
				(type default)
			)
			(layer "B.Fab")
		)
		(fp_line
			(start 0.12065 -0.2794)
			(end -0.12065 -0.2794)
			(stroke
				(width 0.1)
				(type default)
			)
			(layer "B.Fab")
		)
		(fp_line
			(start -0.12065 -0.2794)
			(end -0.12065 -0.3048)
			(stroke
				(width 0.1)
				(type default)
			)
			(layer "B.Fab")
		)
		(fp_line
			(start 0.12065 0.2794)
			(end 0.12065 0.3048)
			(stroke
				(width 0.1)
				(type default)
			)
			(layer "B.Fab")
		)
		(fp_line
			(start -0.120396 0.2794)
			(end 0.12065 0.2794)
			(stroke
				(width 0.1)
				(type default)
			)
			(layer "B.Fab")
		)
		(fp_line
			(start 0.67945 0.3048)
			(end 0.67945 -0.305054)
			(stroke
				(width 0.1)
				(type default)
			)
			(layer "B.Fab")
		)
		(fp_line
			(start 0.12065 0.3048)
			(end 0.67945 0.3048)
			(stroke
				(width 0.1)
				(type default)
			)
			(layer "B.Fab")
		)
		(fp_line
			(start -0.120396 0.3048)
			(end -0.120396 0.2794)
			(stroke
				(width 0.1)
				(type default)
			)
			(layer "B.Fab")
		)
		(fp_line
			(start -0.67945 0.3048)
			(end -0.120396 0.3048)
			(stroke
				(width 0.1)
				(type default)
			)
			(layer "B.Fab")
		)
		(pad "1" smd circle
			(at 0.40005 0 270)
			(size 0 0)
			(layers "B.Cu" "B.Mask" "B.Paste")
			(net "P3V3_NIC7")
		)
		(pad "2" smd circle
			(at -0.40005 0 270)
			(size 0 0)
			(layers "B.Cu" "B.Mask" "B.Paste")
			(net "GND")
		)
	)
	(footprint ""
		(layer "B.Cu")
		(at 115.466114 -256.226564 90)
		(property "Reference" "PR98"
			(at 0 0 90)
			(layer "B.SilkS")
			(hide yes)
			(effects
				(font
					(size 1.27 1.27)
				)
				(justify mirror)
			)
		)
		(property "Value" ""
			(at 0 0 90)
			(layer "B.Fab")
			(effects
				(font
					(size 1.27 1.27)
				)
				(justify mirror)
			)
		)
		(duplicate_pad_numbers_are_jumpers no)
		(fp_line
			(start 0.7874 -0.4064)
			(end -0.7874 -0.4064)
			(stroke
				(width 0.1524)
				(type default)
			)
			(layer "B.SilkS")
		)
		(fp_line
			(start -0.7874 -0.4064)
			(end -0.7874 0.4064)
			(stroke
				(width 0.1524)
				(type default)
			)
			(layer "B.SilkS")
		)
		(fp_line
			(start 0.7874 0.4064)
			(end 0.7874 -0.4064)
			(stroke
				(width 0.1524)
				(type default)
			)
			(layer "B.SilkS")
		)
		(fp_line
			(start -0.7874 0.4064)
			(end 0.7874 0.4064)
			(stroke
				(width 0.1524)
				(type default)
			)
			(layer "B.SilkS")
		)
		(fp_line
			(start 0.67945 -0.305054)
			(end 0.12065 -0.305054)
			(stroke
				(width 0.1)
				(type default)
			)
			(layer "B.Fab")
		)
		(fp_line
			(start 0.12065 -0.305054)
			(end 0.12065 -0.2794)
			(stroke
				(width 0.1)
				(type default)
			)
			(layer "B.Fab")
		)
		(fp_line
			(start -0.12065 -0.3048)
			(end -0.67945 -0.3048)
			(stroke
				(width 0.1)
				(type default)
			)
			(layer "B.Fab")
		)
		(fp_line
			(start -0.67945 -0.3048)
			(end -0.67945 0.3048)
			(stroke
				(width 0.1)
				(type default)
			)
			(layer "B.Fab")
		)
		(fp_line
			(start 0.12065 -0.2794)
			(end -0.12065 -0.2794)
			(stroke
				(width 0.1)
				(type default)
			)
			(layer "B.Fab")
		)
		(fp_line
			(start -0.12065 -0.2794)
			(end -0.12065 -0.3048)
			(stroke
				(width 0.1)
				(type default)
			)
			(layer "B.Fab")
		)
		(fp_line
			(start 0.12065 0.2794)
			(end 0.12065 0.3048)
			(stroke
				(width 0.1)
				(type default)
			)
			(layer "B.Fab")
		)
		(fp_line
			(start -0.120396 0.2794)
			(end 0.12065 0.2794)
			(stroke
				(width 0.1)
				(type default)
			)
			(layer "B.Fab")
		)
		(fp_line
			(start 0.67945 0.3048)
			(end 0.67945 -0.305054)
			(stroke
				(width 0.1)
				(type default)
			)
			(layer "B.Fab")
		)
		(fp_line
			(start 0.12065 0.3048)
			(end 0.67945 0.3048)
			(stroke
				(width 0.1)
				(type default)
			)
			(layer "B.Fab")
		)
		(fp_line
			(start -0.120396 0.3048)
			(end -0.120396 0.2794)
			(stroke
				(width 0.1)
				(type default)
			)
			(layer "B.Fab")
		)
		(fp_line
			(start -0.67945 0.3048)
			(end -0.120396 0.3048)
			(stroke
				(width 0.1)
				(type default)
			)
			(layer "B.Fab")
		)
		(pad "1" smd circle
			(at 0.40005 0 270)
			(size 0 0)
			(layers "B.Cu" "B.Mask" "B.Paste")
			(net "P0V8_PEX0_VINSEN")
		)
		(pad "2" smd circle
			(at -0.40005 0 270)
			(size 0 0)
			(layers "B.Cu" "B.Mask" "B.Paste")
			(net "GND")
		)
	)
	(footprint ""
		(layer "B.Cu")
		(at 379.349 -80.772)
		(property "Reference" "R6304"
			(at 0 0 0)
			(layer "B.SilkS")
			(hide yes)
			(effects
				(font
					(size 1.27 1.27)
				)
				(justify mirror)
			)
		)
		(property "Value" ""
			(at 0 0 0)
			(layer "B.Fab")
			(effects
				(font
					(size 1.27 1.27)
				)
				(justify mirror)
			)
		)
		(duplicate_pad_numbers_are_jumpers no)
		(fp_line
			(start -0.7874 -0.4064)
			(end -0.7874 0.4064)
			(stroke
				(width 0.1524)
				(type default)
			)
			(layer "B.SilkS")
		)
		(fp_line
			(start -0.7874 0.4064)
			(end 0.7874 0.4064)
			(stroke
				(width 0.1524)
				(type default)
			)
			(layer "B.SilkS")
		)
		(fp_line
			(start 0.7874 -0.4064)
			(end -0.7874 -0.4064)
			(stroke
				(width 0.1524)
				(type default)
			)
			(layer "B.SilkS")
		)
		(fp_line
			(start 0.7874 0.4064)
			(end 0.7874 -0.4064)
			(stroke
				(width 0.1524)
				(type default)
			)
			(layer "B.SilkS")
		)
		(fp_line
			(start -0.67945 -0.3048)
			(end -0.67945 0.3048)
			(stroke
				(width 0.1)
				(type default)
			)
			(layer "B.Fab")
		)
		(fp_line
			(start -0.67945 0.3048)
			(end -0.120396 0.3048)
			(stroke
				(width 0.1)
				(type default)
			)
			(layer "B.Fab")
		)
		(fp_line
			(start -0.12065 -0.3048)
			(end -0.67945 -0.3048)
			(stroke
				(width 0.1)
				(type default)
			)
			(layer "B.Fab")
		)
		(fp_line
			(start -0.12065 -0.2794)
			(end -0.12065 -0.3048)
			(stroke
				(width 0.1)
				(type default)
			)
			(layer "B.Fab")
		)
		(fp_line
			(start -0.120396 0.2794)
			(end 0.12065 0.2794)
			(stroke
				(width 0.1)
				(type default)
			)
			(layer "B.Fab")
		)
		(fp_line
			(start -0.120396 0.3048)
			(end -0.120396 0.2794)
			(stroke
				(width 0.1)
				(type default)
			)
			(layer "B.Fab")
		)
		(fp_line
			(start 0.12065 -0.305054)
			(end 0.12065 -0.2794)
			(stroke
				(width 0.1)
				(type default)
			)
			(layer "B.Fab")
		)
		(fp_line
			(start 0.12065 -0.2794)
			(end -0.12065 -0.2794)
			(stroke
				(width 0.1)
				(type default)
			)
			(layer "B.Fab")
		)
		(fp_line
			(start 0.12065 0.2794)
			(end 0.12065 0.3048)
			(stroke
				(width 0.1)
				(type default)
			)
			(layer "B.Fab")
		)
		(fp_line
			(start 0.12065 0.3048)
			(end 0.67945 0.3048)
			(stroke
				(width 0.1)
				(type default)
			)
			(layer "B.Fab")
		)
		(fp_line
			(start 0.67945 -0.305054)
			(end 0.12065 -0.305054)
			(stroke
				(width 0.1)
				(type default)
			)
			(layer "B.Fab")
		)
		(fp_line
			(start 0.67945 0.3048)
			(end 0.67945 -0.305054)
			(stroke
				(width 0.1)
				(type default)
			)
			(layer "B.Fab")
		)
		(pad "1" smd circle
			(at 0.40005 0 180)
			(size 0 0)
			(layers "B.Cu" "B.Mask" "B.Paste")
			(net "SMB_BIC_I2C6_MUX_THERMAL_R2_SCL")
		)
		(pad "2" smd circle
			(at -0.40005 0 180)
			(size 0 0)
			(layers "B.Cu" "B.Mask" "B.Paste")
			(net "SMB_BIC_I2C6_MUX_THERMAL_R_SCL")
		)
	)
	(footprint ""
		(layer "B.Cu")
		(at 422.326816 -301.124874 -90)
		(property "Reference" "R1447"
			(at 0 0 90)
			(layer "B.SilkS")
			(hide yes)
			(effects
				(font
					(size 1.27 1.27)
				)
				(justify mirror)
			)
		)
		(property "Value" ""
			(at 0 0 90)
			(layer "B.Fab")
			(effects
				(font
					(size 1.27 1.27)
				)
				(justify mirror)
			)
		)
		(duplicate_pad_numbers_are_jumpers no)
		(fp_line
			(start -0.7874 0.4064)
			(end 0.7874 0.4064)
			(stroke
				(width 0.1524)
				(type default)
			)
			(layer "B.SilkS")
		)
		(fp_line
			(start 0.7874 0.4064)
			(end 0.7874 -0.4064)
			(stroke
				(width 0.1524)
				(type default)
			)
			(layer "B.SilkS")
		)
		(fp_line
			(start -0.7874 -0.4064)
			(end -0.7874 0.4064)
			(stroke
				(width 0.1524)
				(type default)
			)
			(layer "B.SilkS")
		)
		(fp_line
			(start 0.7874 -0.4064)
			(end -0.7874 -0.4064)
			(stroke
				(width 0.1524)
				(type default)
			)
			(layer "B.SilkS")
		)
		(fp_line
			(start -0.67945 0.3048)
			(end -0.120396 0.3048)
			(stroke
				(width 0.1)
				(type default)
			)
			(layer "B.Fab")
		)
		(fp_line
			(start -0.120396 0.3048)
			(end -0.120396 0.2794)
			(stroke
				(width 0.1)
				(type default)
			)
			(layer "B.Fab")
		)
		(fp_line
			(start 0.12065 0.3048)
			(end 0.67945 0.3048)
			(stroke
				(width 0.1)
				(type default)
			)
			(layer "B.Fab")
		)
		(fp_line
			(start 0.67945 0.3048)
			(end 0.67945 -0.305054)
			(stroke
				(width 0.1)
				(type default)
			)
			(layer "B.Fab")
		)
		(fp_line
			(start -0.120396 0.2794)
			(end 0.12065 0.2794)
			(stroke
				(width 0.1)
				(type default)
			)
			(layer "B.Fab")
		)
		(fp_line
			(start 0.12065 0.2794)
			(end 0.12065 0.3048)
			(stroke
				(width 0.1)
				(type default)
			)
			(layer "B.Fab")
		)
		(fp_line
			(start -0.12065 -0.2794)
			(end -0.12065 -0.3048)
			(stroke
				(width 0.1)
				(type default)
			)
			(layer "B.Fab")
		)
		(fp_line
			(start 0.12065 -0.2794)
			(end -0.12065 -0.2794)
			(stroke
				(width 0.1)
				(type default)
			)
			(layer "B.Fab")
		)
		(fp_line
			(start -0.67945 -0.3048)
			(end -0.67945 0.3048)
			(stroke
				(width 0.1)
				(type default)
			)
			(layer "B.Fab")
		)
		(fp_line
			(start -0.12065 -0.3048)
			(end -0.67945 -0.3048)
			(stroke
				(width 0.1)
				(type default)
			)
			(layer "B.Fab")
		)
		(fp_line
			(start 0.12065 -0.305054)
			(end 0.12065 -0.2794)
			(stroke
				(width 0.1)
				(type default)
			)
			(layer "B.Fab")
		)
		(fp_line
			(start 0.67945 -0.305054)
			(end 0.12065 -0.305054)
			(stroke
				(width 0.1)
				(type default)
			)
			(layer "B.Fab")
		)
		(pad "1" smd circle
			(at 0.40005 0 90)
			(size 0 0)
			(layers "B.Cu" "B.Mask" "B.Paste")
			(net "PEX3_ADCTEMP_VINP0")
		)
		(pad "2" smd circle
			(at -0.40005 0 90)
			(size 0 0)
			(layers "B.Cu" "B.Mask" "B.Paste")
			(net "GND")
		)
	)
	(footprint ""
		(layer "B.Cu")
		(at 278.554942 -301.0408)
		(property "Reference" "C3347"
			(at 0 0 0)
			(layer "B.SilkS")
			(hide yes)
			(effects
				(font
					(size 1.27 1.27)
				)
				(justify mirror)
			)
		)
		(property "Value" ""
			(at 0 0 0)
			(layer "B.Fab")
			(effects
				(font
					(size 1.27 1.27)
				)
				(justify mirror)
			)
		)
		(duplicate_pad_numbers_are_jumpers no)
		(fp_line
			(start -0.299974 -0.150114)
			(end -0.299974 0.150114)
			(stroke
				(width 0.1)
				(type default)
			)
			(layer "B.Fab")
		)
		(fp_line
			(start -0.299974 0.150114)
			(end 0.299974 0.150114)
			(stroke
				(width 0.1)
				(type default)
			)
			(layer "B.Fab")
		)
		(fp_line
			(start 0.299974 -0.150114)
			(end -0.299974 -0.150114)
			(stroke
				(width 0.1)
				(type default)
			)
			(layer "B.Fab")
		)
		(fp_line
			(start 0.299974 0.150114)
			(end 0.299974 -0.150114)
			(stroke
				(width 0.1)
				(type default)
			)
			(layer "B.Fab")
		)
		(pad "1" smd rect
			(at 0.2667 0 180)
			(size 0.3048 0.381)
			(layers "B.Cu" "B.Mask" "B.Paste")
			(net "P1V8_PEX")
		)
		(pad "2" smd rect
			(at -0.2667 0 180)
			(size 0.3048 0.381)
			(layers "B.Cu" "B.Mask" "B.Paste")
			(net "GND")
		)
	)
	(footprint ""
		(layer "B.Cu")
		(at 460.169006 -289.791648 180)
		(property "Reference" "PC998"
			(at 0 0 0)
			(layer "B.SilkS")
			(hide yes)
			(effects
				(font
					(size 1.27 1.27)
				)
				(justify mirror)
			)
		)
		(property "Value" ""
			(at 0 0 0)
			(layer "B.Fab")
			(effects
				(font
					(size 1.27 1.27)
				)
				(justify mirror)
			)
		)
		(duplicate_pad_numbers_are_jumpers no)
		(fp_line
			(start 1.524 0.762)
			(end 1.524 -0.762)
			(stroke
				(width 0.1524)
				(type default)
			)
			(layer "B.SilkS")
		)
		(fp_line
			(start 1.524 -0.762)
			(end -1.524 -0.762)
			(stroke
				(width 0.1524)
				(type default)
			)
			(layer "B.SilkS")
		)
		(fp_line
			(start -1.524 0.762)
			(end 1.524 0.762)
			(stroke
				(width 0.1524)
				(type default)
			)
			(layer "B.SilkS")
		)
		(fp_line
			(start -1.524 -0.762)
			(end -1.524 0.762)
			(stroke
				(width 0.1524)
				(type default)
			)
			(layer "B.SilkS")
		)
		(fp_line
			(start 1.1049 0.724916)
			(end -1.1049 0.724916)
			(stroke
				(width 0.1)
				(type default)
			)
			(layer "B.Fab")
		)
		(fp_line
			(start 1.1049 -0.724916)
			(end 1.1049 0.724916)
			(stroke
				(width 0.1)
				(type default)
			)
			(layer "B.Fab")
		)
		(fp_line
			(start -1.1049 0.724916)
			(end -1.1049 -0.724916)
			(stroke
				(width 0.1)
				(type default)
			)
			(layer "B.Fab")
		)
		(fp_line
			(start -1.1049 -0.724916)
			(end 1.1049 -0.724916)
			(stroke
				(width 0.1)
				(type default)
			)
			(layer "B.Fab")
		)
		(pad "1" smd rect
			(at 0.889 0 180)
			(size 1.016 1.27)
			(layers "B.Cu" "B.Mask" "B.Paste")
			(net "P1V25_PEX3_R")
		)
		(pad "2" smd rect
			(at -0.889 0 180)
			(size 1.016 1.27)
			(layers "B.Cu" "B.Mask" "B.Paste")
			(net "GND")
		)
	)
	(footprint ""
		(layer "B.Cu")
		(at 101.744272 -327.980294)
		(property "Reference" "C2695"
			(at 0 0 0)
			(layer "B.SilkS")
			(hide yes)
			(effects
				(font
					(size 1.27 1.27)
				)
				(justify mirror)
			)
		)
		(property "Value" ""
			(at 0 0 0)
			(layer "B.Fab")
			(effects
				(font
					(size 1.27 1.27)
				)
				(justify mirror)
			)
		)
		(duplicate_pad_numbers_are_jumpers no)
		(fp_line
			(start -1.524 -0.762)
			(end -1.524 0.762)
			(stroke
				(width 0.1524)
				(type default)
			)
			(layer "B.SilkS")
		)
		(fp_line
			(start -1.524 0.762)
			(end 1.524 0.762)
			(stroke
				(width 0.1524)
				(type default)
			)
			(layer "B.SilkS")
		)
		(fp_line
			(start 1.524 -0.762)
			(end -1.524 -0.762)
			(stroke
				(width 0.1524)
				(type default)
			)
			(layer "B.SilkS")
		)
		(fp_line
			(start 1.524 0.762)
			(end 1.524 -0.762)
			(stroke
				(width 0.1524)
				(type default)
			)
			(layer "B.SilkS")
		)
		(fp_line
			(start -1.1049 -0.724916)
			(end 1.1049 -0.724916)
			(stroke
				(width 0.1)
				(type default)
			)
			(layer "B.Fab")
		)
		(fp_line
			(start -1.1049 0.724916)
			(end -1.1049 -0.724916)
			(stroke
				(width 0.1)
				(type default)
			)
			(layer "B.Fab")
		)
		(fp_line
			(start 1.1049 -0.724916)
			(end 1.1049 0.724916)
			(stroke
				(width 0.1)
				(type default)
			)
			(layer "B.Fab")
		)
		(fp_line
			(start 1.1049 0.724916)
			(end -1.1049 0.724916)
			(stroke
				(width 0.1)
				(type default)
			)
			(layer "B.Fab")
		)
		(pad "1" smd rect
			(at 0.889 0)
			(size 1.016 1.27)
			(layers "B.Cu" "B.Mask" "B.Paste")
			(net "P3V3_CLK_BUFFER_9ZXL0451E_VZX3P3")
		)
		(pad "2" smd rect
			(at -0.889 0)
			(size 1.016 1.27)
			(layers "B.Cu" "B.Mask" "B.Paste")
			(net "GND")
		)
	)
	(footprint ""
		(layer "B.Cu")
		(at 350.614488 -308.613556 90)
		(property "Reference" "C1924"
			(at 0 0 90)
			(layer "B.SilkS")
			(hide yes)
			(effects
				(font
					(size 1.27 1.27)
				)
				(justify mirror)
			)
		)
		(property "Value" ""
			(at 0 0 90)
			(layer "B.Fab")
			(effects
				(font
					(size 1.27 1.27)
				)
				(justify mirror)
			)
		)
		(duplicate_pad_numbers_are_jumpers no)
		(fp_line
			(start 1.2954 -0.5842)
			(end -1.2954 -0.5842)
			(stroke
				(width 0.1524)
				(type default)
			)
			(layer "B.SilkS")
		)
		(fp_line
			(start -1.2954 -0.5842)
			(end -1.2954 0.5842)
			(stroke
				(width 0.1524)
				(type default)
			)
			(layer "B.SilkS")
		)
		(fp_line
			(start 1.2954 0.5842)
			(end 1.2954 -0.5842)
			(stroke
				(width 0.1524)
				(type default)
			)
			(layer "B.SilkS")
		)
		(fp_line
			(start -1.2954 0.5842)
			(end 1.2954 0.5842)
			(stroke
				(width 0.1524)
				(type default)
			)
			(layer "B.SilkS")
		)
		(fp_line
			(start 0.8636 -0.4572)
			(end -0.8636 -0.4572)
			(stroke
				(width 0.1)
				(type default)
			)
			(layer "B.Fab")
		)
		(fp_line
			(start -0.8636 -0.4572)
			(end -0.8636 -0.4064)
			(stroke
				(width 0.1)
				(type default)
			)
			(layer "B.Fab")
		)
		(fp_line
			(start 1.1938 -0.4064)
			(end 0.8636 -0.4064)
			(stroke
				(width 0.1)
				(type default)
			)
			(layer "B.Fab")
		)
		(fp_line
			(start 0.8636 -0.4064)
			(end 0.8636 -0.4572)
			(stroke
				(width 0.1)
				(type default)
			)
			(layer "B.Fab")
		)
		(fp_line
			(start -0.8636 -0.4064)
			(end -1.1938 -0.4064)
			(stroke
				(width 0.1)
				(type default)
			)
			(layer "B.Fab")
		)
		(fp_line
			(start -1.1938 -0.4064)
			(end -1.1938 0.4064)
			(stroke
				(width 0.1)
				(type default)
			)
			(layer "B.Fab")
		)
		(fp_line
			(start 1.1938 0.4064)
			(end 1.1938 -0.4064)
			(stroke
				(width 0.1)
				(type default)
			)
			(layer "B.Fab")
		)
		(fp_line
			(start 0.8636 0.4064)
			(end 1.1938 0.4064)
			(stroke
				(width 0.1)
				(type default)
			)
			(layer "B.Fab")
		)
		(fp_line
			(start -0.8636 0.4064)
			(end -0.8636 0.4572)
			(stroke
				(width 0.1)
				(type default)
			)
			(layer "B.Fab")
		)
		(fp_line
			(start -1.1938 0.4064)
			(end -0.8636 0.4064)
			(stroke
				(width 0.1)
				(type default)
			)
			(layer "B.Fab")
		)
		(fp_line
			(start 0.8636 0.4572)
			(end 0.8636 0.4064)
			(stroke
				(width 0.1)
				(type default)
			)
			(layer "B.Fab")
		)
		(fp_line
			(start -0.8636 0.4572)
			(end 0.8636 0.4572)
			(stroke
				(width 0.1)
				(type default)
			)
			(layer "B.Fab")
		)
		(pad "1" smd rect
			(at 0.7366 0)
			(size 0.7112 0.8128)
			(layers "B.Cu" "B.Mask" "B.Paste")
			(net "P0V8_SERDES_VDDA_PEX3")
		)
		(pad "2" smd rect
			(at -0.7366 0)
			(size 0.7112 0.8128)
			(layers "B.Cu" "B.Mask" "B.Paste")
			(net "GND")
		)
	)
	(footprint ""
		(layer "B.Cu")
		(at 399.400014 -290.199826 90)
		(property "Reference" "C1940"
			(at 0 0 90)
			(layer "B.SilkS")
			(hide yes)
			(effects
				(font
					(size 1.27 1.27)
				)
				(justify mirror)
			)
		)
		(property "Value" ""
			(at 0 0 90)
			(layer "B.Fab")
			(effects
				(font
					(size 1.27 1.27)
				)
				(justify mirror)
			)
		)
		(duplicate_pad_numbers_are_jumpers no)
		(fp_line
			(start 0.299974 -0.150114)
			(end -0.299974 -0.150114)
			(stroke
				(width 0.1)
				(type default)
			)
			(layer "B.Fab")
		)
		(fp_line
			(start -0.299974 -0.150114)
			(end -0.299974 0.150114)
			(stroke
				(width 0.1)
				(type default)
			)
			(layer "B.Fab")
		)
		(fp_line
			(start 0.299974 0.150114)
			(end 0.299974 -0.150114)
			(stroke
				(width 0.1)
				(type default)
			)
			(layer "B.Fab")
		)
		(fp_line
			(start -0.299974 0.150114)
			(end 0.299974 0.150114)
			(stroke
				(width 0.1)
				(type default)
			)
			(layer "B.Fab")
		)
		(pad "1" smd rect
			(at 0.2667 0 270)
			(size 0.3048 0.381)
			(layers "B.Cu" "B.Mask" "B.Paste")
			(net "P0V8_SERDES_VDDA_PEX3")
		)
		(pad "2" smd rect
			(at -0.2667 0 270)
			(size 0.3048 0.381)
			(layers "B.Cu" "B.Mask" "B.Paste")
			(net "GND")
		)
	)
	(footprint ""
		(layer "B.Cu")
		(at 128.432814 -177.14087)
		(property "Reference" "C2656"
			(at 0 0 0)
			(layer "B.SilkS")
			(hide yes)
			(effects
				(font
					(size 1.27 1.27)
				)
				(justify mirror)
			)
		)
		(property "Value" ""
			(at 0 0 0)
			(layer "B.Fab")
			(effects
				(font
					(size 1.27 1.27)
				)
				(justify mirror)
			)
		)
		(duplicate_pad_numbers_are_jumpers no)
		(fp_line
			(start -0.7874 -0.4064)
			(end -0.7874 0.4064)
			(stroke
				(width 0.1524)
				(type default)
			)
			(layer "B.SilkS")
		)
		(fp_line
			(start -0.7874 0.4064)
			(end 0.7874 0.4064)
			(stroke
				(width 0.1524)
				(type default)
			)
			(layer "B.SilkS")
		)
		(fp_line
			(start 0.7874 -0.4064)
			(end -0.7874 -0.4064)
			(stroke
				(width 0.1524)
				(type default)
			)
			(layer "B.SilkS")
		)
		(fp_line
			(start 0.7874 0.4064)
			(end 0.7874 -0.4064)
			(stroke
				(width 0.1524)
				(type default)
			)
			(layer "B.SilkS")
		)
		(fp_line
			(start -0.67945 -0.3048)
			(end -0.67945 0.3048)
			(stroke
				(width 0.1)
				(type default)
			)
			(layer "B.Fab")
		)
		(fp_line
			(start -0.67945 0.3048)
			(end -0.120396 0.3048)
			(stroke
				(width 0.1)
				(type default)
			)
			(layer "B.Fab")
		)
		(fp_line
			(start -0.12065 -0.3048)
			(end -0.67945 -0.3048)
			(stroke
				(width 0.1)
				(type default)
			)
			(layer "B.Fab")
		)
		(fp_line
			(start -0.12065 -0.2794)
			(end -0.12065 -0.3048)
			(stroke
				(width 0.1)
				(type default)
			)
			(layer "B.Fab")
		)
		(fp_line
			(start -0.120396 0.2794)
			(end 0.12065 0.2794)
			(stroke
				(width 0.1)
				(type default)
			)
			(layer "B.Fab")
		)
		(fp_line
			(start -0.120396 0.3048)
			(end -0.120396 0.2794)
			(stroke
				(width 0.1)
				(type default)
			)
			(layer "B.Fab")
		)
		(fp_line
			(start 0.12065 -0.305054)
			(end 0.12065 -0.2794)
			(stroke
				(width 0.1)
				(type default)
			)
			(layer "B.Fab")
		)
		(fp_line
			(start 0.12065 -0.2794)
			(end -0.12065 -0.2794)
			(stroke
				(width 0.1)
				(type default)
			)
			(layer "B.Fab")
		)
		(fp_line
			(start 0.12065 0.2794)
			(end 0.12065 0.3048)
			(stroke
				(width 0.1)
				(type default)
			)
			(layer "B.Fab")
		)
		(fp_line
			(start 0.12065 0.3048)
			(end 0.67945 0.3048)
			(stroke
				(width 0.1)
				(type default)
			)
			(layer "B.Fab")
		)
		(fp_line
			(start 0.67945 -0.305054)
			(end 0.12065 -0.305054)
			(stroke
				(width 0.1)
				(type default)
			)
			(layer "B.Fab")
		)
		(fp_line
			(start 0.67945 0.3048)
			(end 0.67945 -0.305054)
			(stroke
				(width 0.1)
				(type default)
			)
			(layer "B.Fab")
		)
		(pad "1" smd circle
			(at 0.40005 0 180)
			(size 0 0)
			(layers "B.Cu" "B.Mask" "B.Paste")
			(net "P3V3_DB2000QL_VDDR")
		)
		(pad "2" smd circle
			(at -0.40005 0 180)
			(size 0 0)
			(layers "B.Cu" "B.Mask" "B.Paste")
			(net "GND")
		)
	)
	(footprint ""
		(layer "B.Cu")
		(at 173.53026 -295.221914)
		(property "Reference" "C1355"
			(at 0 0 0)
			(layer "B.SilkS")
			(hide yes)
			(effects
				(font
					(size 1.27 1.27)
				)
				(justify mirror)
			)
		)
		(property "Value" ""
			(at 0 0 0)
			(layer "B.Fab")
			(effects
				(font
					(size 1.27 1.27)
				)
				(justify mirror)
			)
		)
		(duplicate_pad_numbers_are_jumpers no)
		(fp_line
			(start -1.2954 -0.5842)
			(end -1.2954 0.5842)
			(stroke
				(width 0.1524)
				(type default)
			)
			(layer "B.SilkS")
		)
		(fp_line
			(start -1.2954 0.5842)
			(end 1.2954 0.5842)
			(stroke
				(width 0.1524)
				(type default)
			)
			(layer "B.SilkS")
		)
		(fp_line
			(start 1.2954 -0.5842)
			(end -1.2954 -0.5842)
			(stroke
				(width 0.1524)
				(type default)
			)
			(layer "B.SilkS")
		)
		(fp_line
			(start 1.2954 0.5842)
			(end 1.2954 -0.5842)
			(stroke
				(width 0.1524)
				(type default)
			)
			(layer "B.SilkS")
		)
		(fp_line
			(start -1.1938 -0.4064)
			(end -1.1938 0.4064)
			(stroke
				(width 0.1)
				(type default)
			)
			(layer "B.Fab")
		)
		(fp_line
			(start -1.1938 0.4064)
			(end -0.8636 0.4064)
			(stroke
				(width 0.1)
				(type default)
			)
			(layer "B.Fab")
		)
		(fp_line
			(start -0.8636 -0.4572)
			(end -0.8636 -0.4064)
			(stroke
				(width 0.1)
				(type default)
			)
			(layer "B.Fab")
		)
		(fp_line
			(start -0.8636 -0.4064)
			(end -1.1938 -0.4064)
			(stroke
				(width 0.1)
				(type default)
			)
			(layer "B.Fab")
		)
		(fp_line
			(start -0.8636 0.4064)
			(end -0.8636 0.4572)
			(stroke
				(width 0.1)
				(type default)
			)
			(layer "B.Fab")
		)
		(fp_line
			(start -0.8636 0.4572)
			(end 0.8636 0.4572)
			(stroke
				(width 0.1)
				(type default)
			)
			(layer "B.Fab")
		)
		(fp_line
			(start 0.8636 -0.4572)
			(end -0.8636 -0.4572)
			(stroke
				(width 0.1)
				(type default)
			)
			(layer "B.Fab")
		)
		(fp_line
			(start 0.8636 -0.4064)
			(end 0.8636 -0.4572)
			(stroke
				(width 0.1)
				(type default)
			)
			(layer "B.Fab")
		)
		(fp_line
			(start 0.8636 0.4064)
			(end 1.1938 0.4064)
			(stroke
				(width 0.1)
				(type default)
			)
			(layer "B.Fab")
		)
		(fp_line
			(start 0.8636 0.4572)
			(end 0.8636 0.4064)
			(stroke
				(width 0.1)
				(type default)
			)
			(layer "B.Fab")
		)
		(fp_line
			(start 1.1938 -0.4064)
			(end 0.8636 -0.4064)
			(stroke
				(width 0.1)
				(type default)
			)
			(layer "B.Fab")
		)
		(fp_line
			(start 1.1938 0.4064)
			(end 1.1938 -0.4064)
			(stroke
				(width 0.1)
				(type default)
			)
			(layer "B.Fab")
		)
		(pad "1" smd rect
			(at 0.7366 0 270)
			(size 0.7112 0.8128)
			(layers "B.Cu" "B.Mask" "B.Paste")
			(net "P0V8_PEX1")
		)
		(pad "2" smd rect
			(at -0.7366 0 270)
			(size 0.7112 0.8128)
			(layers "B.Cu" "B.Mask" "B.Paste")
			(net "GND")
		)
	)
	(footprint ""
		(layer "B.Cu")
		(at 344.778838 -281.024838 90)
		(property "Reference" "PC160"
			(at 0 0 90)
			(layer "B.SilkS")
			(hide yes)
			(effects
				(font
					(size 1.27 1.27)
				)
				(justify mirror)
			)
		)
		(property "Value" ""
			(at 0 0 90)
			(layer "B.Fab")
			(effects
				(font
					(size 1.27 1.27)
				)
				(justify mirror)
			)
		)
		(duplicate_pad_numbers_are_jumpers no)
		(fp_line
			(start 1.524 -0.762)
			(end -1.524 -0.762)
			(stroke
				(width 0.1524)
				(type default)
			)
			(layer "B.SilkS")
		)
		(fp_line
			(start -1.524 -0.762)
			(end -1.524 0.762)
			(stroke
				(width 0.1524)
				(type default)
			)
			(layer "B.SilkS")
		)
		(fp_line
			(start 1.524 0.762)
			(end 1.524 -0.762)
			(stroke
				(width 0.1524)
				(type default)
			)
			(layer "B.SilkS")
		)
		(fp_line
			(start -1.524 0.762)
			(end 1.524 0.762)
			(stroke
				(width 0.1524)
				(type default)
			)
			(layer "B.SilkS")
		)
		(fp_line
			(start 1.1049 -0.724916)
			(end 1.1049 0.724916)
			(stroke
				(width 0.1)
				(type default)
			)
			(layer "B.Fab")
		)
		(fp_line
			(start -1.1049 -0.724916)
			(end 1.1049 -0.724916)
			(stroke
				(width 0.1)
				(type default)
			)
			(layer "B.Fab")
		)
		(fp_line
			(start 1.1049 0.724916)
			(end -1.1049 0.724916)
			(stroke
				(width 0.1)
				(type default)
			)
			(layer "B.Fab")
		)
		(fp_line
			(start -1.1049 0.724916)
			(end -1.1049 -0.724916)
			(stroke
				(width 0.1)
				(type default)
			)
			(layer "B.Fab")
		)
		(pad "1" smd rect
			(at 0.889 0 90)
			(size 1.016 1.27)
			(layers "B.Cu" "B.Mask" "B.Paste")
			(net "SW_P12V_P0V8_PEX2_FLT")
		)
		(pad "2" smd rect
			(at -0.889 0 90)
			(size 1.016 1.27)
			(layers "B.Cu" "B.Mask" "B.Paste")
			(net "GND")
		)
	)
	(footprint ""
		(layer "B.Cu")
		(at 228.531928 -284.252162 180)
		(property "Reference" "PC234"
			(at 0 0 0)
			(layer "B.SilkS")
			(hide yes)
			(effects
				(font
					(size 1.27 1.27)
				)
				(justify mirror)
			)
		)
		(property "Value" ""
			(at 0 0 0)
			(layer "B.Fab")
			(effects
				(font
					(size 1.27 1.27)
				)
				(justify mirror)
			)
		)
		(duplicate_pad_numbers_are_jumpers no)
		(fp_line
			(start 1.524 0.762)
			(end 1.524 -0.762)
			(stroke
				(width 0.1524)
				(type default)
			)
			(layer "B.SilkS")
		)
		(fp_line
			(start 1.524 -0.762)
			(end -1.524 -0.762)
			(stroke
				(width 0.1524)
				(type default)
			)
			(layer "B.SilkS")
		)
		(fp_line
			(start -1.524 0.762)
			(end 1.524 0.762)
			(stroke
				(width 0.1524)
				(type default)
			)
			(layer "B.SilkS")
		)
		(fp_line
			(start -1.524 -0.762)
			(end -1.524 0.762)
			(stroke
				(width 0.1524)
				(type default)
			)
			(layer "B.SilkS")
		)
		(fp_line
			(start 1.1049 0.724916)
			(end -1.1049 0.724916)
			(stroke
				(width 0.1)
				(type default)
			)
			(layer "B.Fab")
		)
		(fp_line
			(start 1.1049 -0.724916)
			(end 1.1049 0.724916)
			(stroke
				(width 0.1)
				(type default)
			)
			(layer "B.Fab")
		)
		(fp_line
			(start -1.1049 0.724916)
			(end -1.1049 -0.724916)
			(stroke
				(width 0.1)
				(type default)
			)
			(layer "B.Fab")
		)
		(fp_line
			(start -1.1049 -0.724916)
			(end 1.1049 -0.724916)
			(stroke
				(width 0.1)
				(type default)
			)
			(layer "B.Fab")
		)
		(pad "1" smd rect
			(at 0.889 0 180)
			(size 1.016 1.27)
			(layers "B.Cu" "B.Mask" "B.Paste")
			(net "P1V25_PEX1_R")
		)
		(pad "2" smd rect
			(at -0.889 0 180)
			(size 1.016 1.27)
			(layers "B.Cu" "B.Mask" "B.Paste")
			(net "GND")
		)
	)
	(footprint ""
		(layer "B.Cu")
		(at 320.60642 -83.123278 180)
		(property "Reference" "R1764"
			(at 0 0 0)
			(layer "B.SilkS")
			(hide yes)
			(effects
				(font
					(size 1.27 1.27)
				)
				(justify mirror)
			)
		)
		(property "Value" ""
			(at 0 0 0)
			(layer "B.Fab")
			(effects
				(font
					(size 1.27 1.27)
				)
				(justify mirror)
			)
		)
		(duplicate_pad_numbers_are_jumpers no)
		(fp_line
			(start 0.7874 0.4064)
			(end 0.7874 -0.4064)
			(stroke
				(width 0.1524)
				(type default)
			)
			(layer "B.SilkS")
		)
		(fp_line
			(start 0.7874 -0.4064)
			(end -0.7874 -0.4064)
			(stroke
				(width 0.1524)
				(type default)
			)
			(layer "B.SilkS")
		)
		(fp_line
			(start -0.7874 0.4064)
			(end 0.7874 0.4064)
			(stroke
				(width 0.1524)
				(type default)
			)
			(layer "B.SilkS")
		)
		(fp_line
			(start -0.7874 -0.4064)
			(end -0.7874 0.4064)
			(stroke
				(width 0.1524)
				(type default)
			)
			(layer "B.SilkS")
		)
		(fp_line
			(start 0.67945 0.3048)
			(end 0.67945 -0.305054)
			(stroke
				(width 0.1)
				(type default)
			)
			(layer "B.Fab")
		)
		(fp_line
			(start 0.67945 -0.305054)
			(end 0.12065 -0.305054)
			(stroke
				(width 0.1)
				(type default)
			)
			(layer "B.Fab")
		)
		(fp_line
			(start 0.12065 0.3048)
			(end 0.67945 0.3048)
			(stroke
				(width 0.1)
				(type default)
			)
			(layer "B.Fab")
		)
		(fp_line
			(start 0.12065 0.2794)
			(end 0.12065 0.3048)
			(stroke
				(width 0.1)
				(type default)
			)
			(layer "B.Fab")
		)
		(fp_line
			(start 0.12065 -0.2794)
			(end -0.12065 -0.2794)
			(stroke
				(width 0.1)
				(type default)
			)
			(layer "B.Fab")
		)
		(fp_line
			(start 0.12065 -0.305054)
			(end 0.12065 -0.2794)
			(stroke
				(width 0.1)
				(type default)
			)
			(layer "B.Fab")
		)
		(fp_line
			(start -0.120396 0.3048)
			(end -0.120396 0.2794)
			(stroke
				(width 0.1)
				(type default)
			)
			(layer "B.Fab")
		)
		(fp_line
			(start -0.120396 0.2794)
			(end 0.12065 0.2794)
			(stroke
				(width 0.1)
				(type default)
			)
			(layer "B.Fab")
		)
		(fp_line
			(start -0.12065 -0.2794)
			(end -0.12065 -0.3048)
			(stroke
				(width 0.1)
				(type default)
			)
			(layer "B.Fab")
		)
		(fp_line
			(start -0.12065 -0.3048)
			(end -0.67945 -0.3048)
			(stroke
				(width 0.1)
				(type default)
			)
			(layer "B.Fab")
		)
		(fp_line
			(start -0.67945 0.3048)
			(end -0.120396 0.3048)
			(stroke
				(width 0.1)
				(type default)
			)
			(layer "B.Fab")
		)
		(fp_line
			(start -0.67945 -0.3048)
			(end -0.67945 0.3048)
			(stroke
				(width 0.1)
				(type default)
			)
			(layer "B.Fab")
		)
		(pad "1" smd circle
			(at 0.40005 0)
			(size 0 0)
			(layers "B.Cu" "B.Mask" "B.Paste")
			(net "P3V3_AUX")
		)
		(pad "2" smd circle
			(at -0.40005 0)
			(size 0 0)
			(layers "B.Cu" "B.Mask" "B.Paste")
			(net "SMB_BIC_I2C6_MUX_FRU_R_SCL")
		)
	)
	(footprint ""
		(layer "B.Cu")
		(at 226.19716 -266.873228 180)
		(property "Reference" "R6130"
			(at 0 0 0)
			(layer "B.SilkS")
			(hide yes)
			(effects
				(font
					(size 1.27 1.27)
				)
				(justify mirror)
			)
		)
		(property "Value" ""
			(at 0 0 0)
			(layer "B.Fab")
			(effects
				(font
					(size 1.27 1.27)
				)
				(justify mirror)
			)
		)
		(duplicate_pad_numbers_are_jumpers no)
		(fp_line
			(start 2.576322 1.1303)
			(end 2.576322 -1.1303)
			(stroke
				(width 0.1524)
				(type default)
			)
			(layer "B.SilkS")
		)
		(fp_line
			(start 2.576322 -1.1303)
			(end -2.576322 -1.1303)
			(stroke
				(width 0.1524)
				(type default)
			)
			(layer "B.SilkS")
		)
		(fp_line
			(start -2.576322 1.1303)
			(end 2.576322 1.1303)
			(stroke
				(width 0.1524)
				(type default)
			)
			(layer "B.SilkS")
		)
		(fp_line
			(start -2.576322 -1.1303)
			(end -2.576322 1.1303)
			(stroke
				(width 0.1524)
				(type default)
			)
			(layer "B.SilkS")
		)
		(fp_line
			(start 1.649984 0.899922)
			(end -1.649984 0.899922)
			(stroke
				(width 0.1)
				(type default)
			)
			(layer "B.Fab")
		)
		(fp_line
			(start 1.649984 -0.899922)
			(end 1.649984 0.899922)
			(stroke
				(width 0.1)
				(type default)
			)
			(layer "B.Fab")
		)
		(fp_line
			(start -1.649984 0.899922)
			(end -1.649984 -0.899922)
			(stroke
				(width 0.1)
				(type default)
			)
			(layer "B.Fab")
		)
		(fp_line
			(start -1.649984 -0.899922)
			(end 1.649984 -0.899922)
			(stroke
				(width 0.1)
				(type default)
			)
			(layer "B.Fab")
		)
		(pad "1A" smd rect
			(at 1.700022 0)
			(size 1.4986 2.0066)
			(layers "B.Cu" "B.Mask" "B.Paste")
			(net "P1V25_PEX1")
		)
		(pad "1B" smd rect
			(at 1.077722 0)
			(size 0.254 0.508)
			(layers "B.Cu" "B.Mask" "B.Paste")
			(net "P1V25_PEX1")
		)
		(pad "2A" smd rect
			(at -1.700022 0)
			(size 1.4986 2.0066)
			(layers "B.Cu" "B.Mask" "B.Paste")
			(net "P1V25_SERDES_VDDPLL_PEX1")
		)
		(pad "2B" smd rect
			(at -1.077722 0)
			(size 0.254 0.508)
			(layers "B.Cu" "B.Mask" "B.Paste")
			(net "P1V25_SERDES_VDDPLL_PEX1")
		)
	)
	(footprint ""
		(layer "B.Cu")
		(at 61.074808 -293.99992 90)
		(property "Reference" "C1135"
			(at 0 0 90)
			(layer "B.SilkS")
			(hide yes)
			(effects
				(font
					(size 1.27 1.27)
				)
				(justify mirror)
			)
		)
		(property "Value" ""
			(at 0 0 90)
			(layer "B.Fab")
			(effects
				(font
					(size 1.27 1.27)
				)
				(justify mirror)
			)
		)
		(duplicate_pad_numbers_are_jumpers no)
		(fp_line
			(start 0.299974 -0.150114)
			(end -0.299974 -0.150114)
			(stroke
				(width 0.1)
				(type default)
			)
			(layer "B.Fab")
		)
		(fp_line
			(start -0.299974 -0.150114)
			(end -0.299974 0.150114)
			(stroke
				(width 0.1)
				(type default)
			)
			(layer "B.Fab")
		)
		(fp_line
			(start 0.299974 0.150114)
			(end 0.299974 -0.150114)
			(stroke
				(width 0.1)
				(type default)
			)
			(layer "B.Fab")
		)
		(fp_line
			(start -0.299974 0.150114)
			(end 0.299974 0.150114)
			(stroke
				(width 0.1)
				(type default)
			)
			(layer "B.Fab")
		)
		(pad "1" smd rect
			(at 0.2667 0 270)
			(size 0.3048 0.381)
			(layers "B.Cu" "B.Mask" "B.Paste")
			(net "P0V8_PEX0")
		)
		(pad "2" smd rect
			(at -0.2667 0 270)
			(size 0.3048 0.381)
			(layers "B.Cu" "B.Mask" "B.Paste")
			(net "GND")
		)
	)
	(footprint ""
		(layer "B.Cu")
		(at 278.935942 -291.624766)
		(property "Reference" "C3407"
			(at 0 0 0)
			(layer "B.SilkS")
			(hide yes)
			(effects
				(font
					(size 1.27 1.27)
				)
				(justify mirror)
			)
		)
		(property "Value" ""
			(at 0 0 0)
			(layer "B.Fab")
			(effects
				(font
					(size 1.27 1.27)
				)
				(justify mirror)
			)
		)
		(duplicate_pad_numbers_are_jumpers no)
		(fp_line
			(start -0.299974 -0.150114)
			(end -0.299974 0.150114)
			(stroke
				(width 0.1)
				(type default)
			)
			(layer "B.Fab")
		)
		(fp_line
			(start -0.299974 0.150114)
			(end 0.299974 0.150114)
			(stroke
				(width 0.1)
				(type default)
			)
			(layer "B.Fab")
		)
		(fp_line
			(start 0.299974 -0.150114)
			(end -0.299974 -0.150114)
			(stroke
				(width 0.1)
				(type default)
			)
			(layer "B.Fab")
		)
		(fp_line
			(start 0.299974 0.150114)
			(end 0.299974 -0.150114)
			(stroke
				(width 0.1)
				(type default)
			)
			(layer "B.Fab")
		)
		(pad "1" smd rect
			(at 0.2667 0 180)
			(size 0.3048 0.381)
			(layers "B.Cu" "B.Mask" "B.Paste")
			(net "PCEPLL7_VDDA18_PEX2")
		)
		(pad "2" smd rect
			(at -0.2667 0 180)
			(size 0.3048 0.381)
			(layers "B.Cu" "B.Mask" "B.Paste")
			(net "GND")
		)
	)
	(footprint ""
		(layer "B.Cu")
		(at 406.049988 -303.499774 -90)
		(property "Reference" "C3430"
			(at 0 0 90)
			(layer "B.SilkS")
			(hide yes)
			(effects
				(font
					(size 1.27 1.27)
				)
				(justify mirror)
			)
		)
		(property "Value" ""
			(at 0 0 90)
			(layer "B.Fab")
			(effects
				(font
					(size 1.27 1.27)
				)
				(justify mirror)
			)
		)
		(duplicate_pad_numbers_are_jumpers no)
		(fp_line
			(start -0.299974 0.150114)
			(end 0.299974 0.150114)
			(stroke
				(width 0.1)
				(type default)
			)
			(layer "B.Fab")
		)
		(fp_line
			(start 0.299974 0.150114)
			(end 0.299974 -0.150114)
			(stroke
				(width 0.1)
				(type default)
			)
			(layer "B.Fab")
		)
		(fp_line
			(start -0.299974 -0.150114)
			(end -0.299974 0.150114)
			(stroke
				(width 0.1)
				(type default)
			)
			(layer "B.Fab")
		)
		(fp_line
			(start 0.299974 -0.150114)
			(end -0.299974 -0.150114)
			(stroke
				(width 0.1)
				(type default)
			)
			(layer "B.Fab")
		)
		(pad "1" smd rect
			(at 0.2667 0 90)
			(size 0.3048 0.381)
			(layers "B.Cu" "B.Mask" "B.Paste")
			(net "P1V25_PEX3")
		)
		(pad "2" smd rect
			(at -0.2667 0 90)
			(size 0.3048 0.381)
			(layers "B.Cu" "B.Mask" "B.Paste")
			(net "GND")
		)
	)
	(footprint ""
		(layer "B.Cu")
		(at 162.4457 -292.57498)
		(property "Reference" "C3230"
			(at 0 0 0)
			(layer "B.SilkS")
			(hide yes)
			(effects
				(font
					(size 1.27 1.27)
				)
				(justify mirror)
			)
		)
		(property "Value" ""
			(at 0 0 0)
			(layer "B.Fab")
			(effects
				(font
					(size 1.27 1.27)
				)
				(justify mirror)
			)
		)
		(duplicate_pad_numbers_are_jumpers no)
		(fp_line
			(start -0.299974 -0.150114)
			(end -0.299974 0.150114)
			(stroke
				(width 0.1)
				(type default)
			)
			(layer "B.Fab")
		)
		(fp_line
			(start -0.299974 0.150114)
			(end 0.299974 0.150114)
			(stroke
				(width 0.1)
				(type default)
			)
			(layer "B.Fab")
		)
		(fp_line
			(start 0.299974 -0.150114)
			(end -0.299974 -0.150114)
			(stroke
				(width 0.1)
				(type default)
			)
			(layer "B.Fab")
		)
		(fp_line
			(start 0.299974 0.150114)
			(end 0.299974 -0.150114)
			(stroke
				(width 0.1)
				(type default)
			)
			(layer "B.Fab")
		)
		(pad "1" smd rect
			(at 0.2667 0 180)
			(size 0.3048 0.381)
			(layers "B.Cu" "B.Mask" "B.Paste")
			(net "PCEPLL6_VDDA18_PEX1")
		)
		(pad "2" smd rect
			(at -0.2667 0 180)
			(size 0.3048 0.381)
			(layers "B.Cu" "B.Mask" "B.Paste")
			(net "GND")
		)
	)
	(footprint ""
		(layer "B.Cu")
		(at 343.694004 -218.787218 -90)
		(property "Reference" "C2062"
			(at 0 0 90)
			(layer "B.SilkS")
			(hide yes)
			(effects
				(font
					(size 1.27 1.27)
				)
				(justify mirror)
			)
		)
		(property "Value" ""
			(at 0 0 90)
			(layer "B.Fab")
			(effects
				(font
					(size 1.27 1.27)
				)
				(justify mirror)
			)
		)
		(duplicate_pad_numbers_are_jumpers no)
		(fp_line
			(start -0.69215 0.2921)
			(end 0.69215 0.2921)
			(stroke
				(width 0.1524)
				(type default)
			)
			(layer "B.SilkS")
		)
		(fp_line
			(start 0.69215 0.2921)
			(end 0.69215 -0.2921)
			(stroke
				(width 0.1524)
				(type default)
			)
			(layer "B.SilkS")
		)
		(fp_line
			(start -0.69215 -0.2921)
			(end -0.69215 0.2921)
			(stroke
				(width 0.1524)
				(type default)
			)
			(layer "B.SilkS")
		)
		(fp_line
			(start 0.69215 -0.2921)
			(end -0.69215 -0.2921)
			(stroke
				(width 0.1524)
				(type default)
			)
			(layer "B.SilkS")
		)
		(fp_line
			(start -0.51435 0.2794)
			(end 0.51435 0.2794)
			(stroke
				(width 0.1)
				(type default)
			)
			(layer "B.Fab")
		)
		(fp_line
			(start 0.51435 0.2794)
			(end 0.51435 -0.2794)
			(stroke
				(width 0.1)
				(type default)
			)
			(layer "B.Fab")
		)
		(fp_line
			(start -0.51435 -0.2794)
			(end -0.51435 0.2794)
			(stroke
				(width 0.1)
				(type default)
			)
			(layer "B.Fab")
		)
		(fp_line
			(start 0.51435 -0.2794)
			(end -0.51435 -0.2794)
			(stroke
				(width 0.1)
				(type default)
			)
			(layer "B.Fab")
		)
		(pad "1" smd circle
			(at 0.40005 0 90)
			(size 0 0)
			(layers "B.Cu" "B.Mask" "B.Paste")
			(net "P3V3_VCC_FPGA_CORE")
		)
		(pad "2" smd circle
			(at -0.40005 0 90)
			(size 0 0)
			(layers "B.Cu" "B.Mask" "B.Paste")
			(net "GND")
		)
		(zone
			(layer "B.Cu")
			(hatch none 0.5)
			(connect_pads
				(clearance 0)
			)
			(min_thickness 0.25)
			(keepout
				(tracks not_allowed)
				(vias allowed)
				(pads allowed)
				(copperpour not_allowed)
				(footprints allowed)
			)
			(placement
				(enabled no)
				(sheetname "")
			)
			(fill
				(thermal_gap 0.5)
				(thermal_bridge_width 0.5)
				(island_removal_mode 0)
			)
			(polygon
				(pts
					(xy 343.606374 -218.596718) (xy 343.548208 -218.688158) (xy 343.548208 -218.887548) (xy 343.606374 -218.977718)
					(xy 343.781634 -218.977718) (xy 343.840054 -218.887548) (xy 343.840054 -218.688158) (xy 343.781888 -218.596718)
				)
			)
		)
	)
	(footprint ""
		(layer "B.Cu")
		(at 295.706038 -202.16114 90)
		(property "Reference" "R1038"
			(at 0 0 90)
			(layer "B.SilkS")
			(hide yes)
			(effects
				(font
					(size 1.27 1.27)
				)
				(justify mirror)
			)
		)
		(property "Value" ""
			(at 0 0 90)
			(layer "B.Fab")
			(effects
				(font
					(size 1.27 1.27)
				)
				(justify mirror)
			)
		)
		(duplicate_pad_numbers_are_jumpers no)
		(fp_line
			(start 0.7874 -0.4064)
			(end -0.7874 -0.4064)
			(stroke
				(width 0.1524)
				(type default)
			)
			(layer "B.SilkS")
		)
		(fp_line
			(start -0.7874 -0.4064)
			(end -0.7874 0.4064)
			(stroke
				(width 0.1524)
				(type default)
			)
			(layer "B.SilkS")
		)
		(fp_line
			(start 0.7874 0.4064)
			(end 0.7874 -0.4064)
			(stroke
				(width 0.1524)
				(type default)
			)
			(layer "B.SilkS")
		)
		(fp_line
			(start -0.7874 0.4064)
			(end 0.7874 0.4064)
			(stroke
				(width 0.1524)
				(type default)
			)
			(layer "B.SilkS")
		)
		(fp_line
			(start 0.67945 -0.305054)
			(end 0.12065 -0.305054)
			(stroke
				(width 0.1)
				(type default)
			)
			(layer "B.Fab")
		)
		(fp_line
			(start 0.12065 -0.305054)
			(end 0.12065 -0.2794)
			(stroke
				(width 0.1)
				(type default)
			)
			(layer "B.Fab")
		)
		(fp_line
			(start -0.12065 -0.3048)
			(end -0.67945 -0.3048)
			(stroke
				(width 0.1)
				(type default)
			)
			(layer "B.Fab")
		)
		(fp_line
			(start -0.67945 -0.3048)
			(end -0.67945 0.3048)
			(stroke
				(width 0.1)
				(type default)
			)
			(layer "B.Fab")
		)
		(fp_line
			(start 0.12065 -0.2794)
			(end -0.12065 -0.2794)
			(stroke
				(width 0.1)
				(type default)
			)
			(layer "B.Fab")
		)
		(fp_line
			(start -0.12065 -0.2794)
			(end -0.12065 -0.3048)
			(stroke
				(width 0.1)
				(type default)
			)
			(layer "B.Fab")
		)
		(fp_line
			(start 0.12065 0.2794)
			(end 0.12065 0.3048)
			(stroke
				(width 0.1)
				(type default)
			)
			(layer "B.Fab")
		)
		(fp_line
			(start -0.120396 0.2794)
			(end 0.12065 0.2794)
			(stroke
				(width 0.1)
				(type default)
			)
			(layer "B.Fab")
		)
		(fp_line
			(start 0.67945 0.3048)
			(end 0.67945 -0.305054)
			(stroke
				(width 0.1)
				(type default)
			)
			(layer "B.Fab")
		)
		(fp_line
			(start 0.12065 0.3048)
			(end 0.67945 0.3048)
			(stroke
				(width 0.1)
				(type default)
			)
			(layer "B.Fab")
		)
		(fp_line
			(start -0.120396 0.3048)
			(end -0.120396 0.2794)
			(stroke
				(width 0.1)
				(type default)
			)
			(layer "B.Fab")
		)
		(fp_line
			(start -0.67945 0.3048)
			(end -0.120396 0.3048)
			(stroke
				(width 0.1)
				(type default)
			)
			(layer "B.Fab")
		)
		(pad "1" smd circle
			(at 0.40005 0 270)
			(size 0 0)
			(layers "B.Cu" "B.Mask" "B.Paste")
			(net "SPI_BIC1_CLK_LS23_DIR2")
		)
		(pad "2" smd circle
			(at -0.40005 0 270)
			(size 0 0)
			(layers "B.Cu" "B.Mask" "B.Paste")
			(net "P1V8_PEX")
		)
	)
	(footprint ""
		(layer "B.Cu")
		(at 44.449746 -294.94988)
		(property "Reference" "C3005"
			(at 0 0 0)
			(layer "B.SilkS")
			(hide yes)
			(effects
				(font
					(size 1.27 1.27)
				)
				(justify mirror)
			)
		)
		(property "Value" ""
			(at 0 0 0)
			(layer "B.Fab")
			(effects
				(font
					(size 1.27 1.27)
				)
				(justify mirror)
			)
		)
		(duplicate_pad_numbers_are_jumpers no)
		(fp_line
			(start -0.299974 -0.150114)
			(end -0.299974 0.150114)
			(stroke
				(width 0.1)
				(type default)
			)
			(layer "B.Fab")
		)
		(fp_line
			(start -0.299974 0.150114)
			(end 0.299974 0.150114)
			(stroke
				(width 0.1)
				(type default)
			)
			(layer "B.Fab")
		)
		(fp_line
			(start 0.299974 -0.150114)
			(end -0.299974 -0.150114)
			(stroke
				(width 0.1)
				(type default)
			)
			(layer "B.Fab")
		)
		(fp_line
			(start 0.299974 0.150114)
			(end 0.299974 -0.150114)
			(stroke
				(width 0.1)
				(type default)
			)
			(layer "B.Fab")
		)
		(pad "1" smd rect
			(at 0.2667 0 180)
			(size 0.3048 0.381)
			(layers "B.Cu" "B.Mask" "B.Paste")
			(net "P1V8_PEX")
		)
		(pad "2" smd rect
			(at -0.2667 0 180)
			(size 0.3048 0.381)
			(layers "B.Cu" "B.Mask" "B.Paste")
			(net "GND")
		)
	)
	(footprint ""
		(layer "B.Cu")
		(at 334.489044 -213.593934)
		(property "Reference" "C2075"
			(at 0 0 0)
			(layer "B.SilkS")
			(hide yes)
			(effects
				(font
					(size 1.27 1.27)
				)
				(justify mirror)
			)
		)
		(property "Value" ""
			(at 0 0 0)
			(layer "B.Fab")
			(effects
				(font
					(size 1.27 1.27)
				)
				(justify mirror)
			)
		)
		(duplicate_pad_numbers_are_jumpers no)
		(fp_line
			(start -0.69215 -0.2921)
			(end -0.69215 0.2921)
			(stroke
				(width 0.1524)
				(type default)
			)
			(layer "B.SilkS")
		)
		(fp_line
			(start -0.69215 0.2921)
			(end 0.69215 0.2921)
			(stroke
				(width 0.1524)
				(type default)
			)
			(layer "B.SilkS")
		)
		(fp_line
			(start 0.69215 -0.2921)
			(end -0.69215 -0.2921)
			(stroke
				(width 0.1524)
				(type default)
			)
			(layer "B.SilkS")
		)
		(fp_line
			(start 0.69215 0.2921)
			(end 0.69215 -0.2921)
			(stroke
				(width 0.1524)
				(type default)
			)
			(layer "B.SilkS")
		)
		(fp_line
			(start -0.51435 -0.2794)
			(end -0.51435 0.2794)
			(stroke
				(width 0.1)
				(type default)
			)
			(layer "B.Fab")
		)
		(fp_line
			(start -0.51435 0.2794)
			(end 0.51435 0.2794)
			(stroke
				(width 0.1)
				(type default)
			)
			(layer "B.Fab")
		)
		(fp_line
			(start 0.51435 -0.2794)
			(end -0.51435 -0.2794)
			(stroke
				(width 0.1)
				(type default)
			)
			(layer "B.Fab")
		)
		(fp_line
			(start 0.51435 0.2794)
			(end 0.51435 -0.2794)
			(stroke
				(width 0.1)
				(type default)
			)
			(layer "B.Fab")
		)
		(pad "1" smd circle
			(at 0.40005 0 180)
			(size 0 0)
			(layers "B.Cu" "B.Mask" "B.Paste")
			(net "P3V3_FPGA_VCCIO3")
		)
		(pad "2" smd circle
			(at -0.40005 0 180)
			(size 0 0)
			(layers "B.Cu" "B.Mask" "B.Paste")
			(net "GND")
		)
		(zone
			(layer "B.Cu")
			(hatch none 0.5)
			(connect_pads
				(clearance 0)
			)
			(min_thickness 0.25)
			(keepout
				(tracks not_allowed)
				(vias allowed)
				(pads allowed)
				(copperpour not_allowed)
				(footprints allowed)
			)
			(placement
				(enabled no)
				(sheetname "")
			)
			(fill
				(thermal_gap 0.5)
				(thermal_bridge_width 0.5)
				(island_removal_mode 0)
			)
			(polygon
				(pts
					(xy 334.679544 -213.506304) (xy 334.588104 -213.448138) (xy 334.388714 -213.448138) (xy 334.298544 -213.506304)
					(xy 334.298544 -213.681564) (xy 334.388714 -213.739984) (xy 334.588104 -213.739984) (xy 334.679544 -213.681818)
				)
			)
		)
	)
	(footprint ""
		(layer "B.Cu")
		(at 212.507576 -218.316048 -90)
		(property "Reference" "R4879"
			(at 0 0 90)
			(layer "B.SilkS")
			(hide yes)
			(effects
				(font
					(size 1.27 1.27)
				)
				(justify mirror)
			)
		)
		(property "Value" ""
			(at 0 0 90)
			(layer "B.Fab")
			(effects
				(font
					(size 1.27 1.27)
				)
				(justify mirror)
			)
		)
		(duplicate_pad_numbers_are_jumpers no)
		(fp_line
			(start -0.7874 0.4064)
			(end 0.7874 0.4064)
			(stroke
				(width 0.1524)
				(type default)
			)
			(layer "B.SilkS")
		)
		(fp_line
			(start 0.7874 0.4064)
			(end 0.7874 -0.4064)
			(stroke
				(width 0.1524)
				(type default)
			)
			(layer "B.SilkS")
		)
		(fp_line
			(start -0.7874 -0.4064)
			(end -0.7874 0.4064)
			(stroke
				(width 0.1524)
				(type default)
			)
			(layer "B.SilkS")
		)
		(fp_line
			(start 0.7874 -0.4064)
			(end -0.7874 -0.4064)
			(stroke
				(width 0.1524)
				(type default)
			)
			(layer "B.SilkS")
		)
		(fp_line
			(start -0.67945 0.3048)
			(end -0.120396 0.3048)
			(stroke
				(width 0.1)
				(type default)
			)
			(layer "B.Fab")
		)
		(fp_line
			(start -0.120396 0.3048)
			(end -0.120396 0.2794)
			(stroke
				(width 0.1)
				(type default)
			)
			(layer "B.Fab")
		)
		(fp_line
			(start 0.12065 0.3048)
			(end 0.67945 0.3048)
			(stroke
				(width 0.1)
				(type default)
			)
			(layer "B.Fab")
		)
		(fp_line
			(start 0.67945 0.3048)
			(end 0.67945 -0.305054)
			(stroke
				(width 0.1)
				(type default)
			)
			(layer "B.Fab")
		)
		(fp_line
			(start -0.120396 0.2794)
			(end 0.12065 0.2794)
			(stroke
				(width 0.1)
				(type default)
			)
			(layer "B.Fab")
		)
		(fp_line
			(start 0.12065 0.2794)
			(end 0.12065 0.3048)
			(stroke
				(width 0.1)
				(type default)
			)
			(layer "B.Fab")
		)
		(fp_line
			(start -0.12065 -0.2794)
			(end -0.12065 -0.3048)
			(stroke
				(width 0.1)
				(type default)
			)
			(layer "B.Fab")
		)
		(fp_line
			(start 0.12065 -0.2794)
			(end -0.12065 -0.2794)
			(stroke
				(width 0.1)
				(type default)
			)
			(layer "B.Fab")
		)
		(fp_line
			(start -0.67945 -0.3048)
			(end -0.67945 0.3048)
			(stroke
				(width 0.1)
				(type default)
			)
			(layer "B.Fab")
		)
		(fp_line
			(start -0.12065 -0.3048)
			(end -0.67945 -0.3048)
			(stroke
				(width 0.1)
				(type default)
			)
			(layer "B.Fab")
		)
		(fp_line
			(start 0.12065 -0.305054)
			(end 0.12065 -0.2794)
			(stroke
				(width 0.1)
				(type default)
			)
			(layer "B.Fab")
		)
		(fp_line
			(start 0.67945 -0.305054)
			(end 0.12065 -0.305054)
			(stroke
				(width 0.1)
				(type default)
			)
			(layer "B.Fab")
		)
		(pad "1" smd circle
			(at 0.40005 0 90)
			(size 0 0)
			(layers "B.Cu" "B.Mask" "B.Paste")
			(net "P1V2_AUX")
		)
		(pad "2" smd circle
			(at -0.40005 0 90)
			(size 0 0)
			(layers "B.Cu" "B.Mask" "B.Paste")
			(net "SMB_NIC7_SCL")
		)
	)
	(footprint ""
		(layer "B.Cu")
		(at 293.921942 -197.499732 -90)
		(property "Reference" "U64"
			(at 1.5367 -2.25933 270)
			(unlocked yes)
			(layer "B.SilkS")
			(effects
				(font
					(size 0.7874 0.5842)
					(thickness 0.1524)
				)
				(justify mirror)
			)
		)
		(property "Value" ""
			(at 0 0 90)
			(layer "B.Fab")
			(effects
				(font
					(size 1.27 1.27)
				)
				(justify mirror)
			)
		)
		(duplicate_pad_numbers_are_jumpers no)
		(fp_line
			(start -2.036064 1.525016)
			(end 2.038096 1.525016)
			(stroke
				(width 0.1524)
				(type default)
			)
			(layer "B.SilkS")
		)
		(fp_line
			(start 2.038096 1.525016)
			(end 2.038096 -1.525016)
			(stroke
				(width 0.1524)
				(type default)
			)
			(layer "B.SilkS")
		)
		(fp_line
			(start 0 -0.6604)
			(end -0.4572 -1.4986)
			(stroke
				(width 0.1524)
				(type default)
			)
			(layer "B.SilkS")
		)
		(fp_line
			(start 0.508 -1.524)
			(end 0 -0.6604)
			(stroke
				(width 0.1524)
				(type default)
			)
			(layer "B.SilkS")
		)
		(fp_line
			(start -2.036064 -1.525016)
			(end -2.036064 1.525016)
			(stroke
				(width 0.1524)
				(type default)
			)
			(layer "B.SilkS")
		)
		(fp_line
			(start 2.038096 -1.525016)
			(end -2.036064 -1.525016)
			(stroke
				(width 0.1524)
				(type default)
			)
			(layer "B.SilkS")
		)
		(fp_poly
			(pts
				(xy 2.71272 -0.592328) (xy 2.71272 -1.217168) (xy 2.159 -0.889)
			)
			(stroke
				(width 0)
				(type default)
			)
			(fill yes)
			(layer "B.SilkS")
		)
		(fp_line
			(start -0.87503 1.525016)
			(end 0.87503 1.525016)
			(stroke
				(width 0.1)
				(type default)
			)
			(layer "B.Fab")
		)
		(fp_line
			(start 0.87503 1.525016)
			(end 0.87503 -1.525016)
			(stroke
				(width 0.1)
				(type default)
			)
			(layer "B.Fab")
		)
		(fp_line
			(start -0.87503 -1.525016)
			(end -0.87503 1.525016)
			(stroke
				(width 0.1)
				(type default)
			)
			(layer "B.Fab")
		)
		(fp_line
			(start 0.87503 -1.525016)
			(end -0.87503 -1.525016)
			(stroke
				(width 0.1)
				(type default)
			)
			(layer "B.Fab")
		)
		(fp_poly
			(pts
				(xy 2.71272 -0.592328) (xy 2.71272 -1.217168) (xy 2.159 -0.889)
			)
			(stroke
				(width 0)
				(type default)
			)
			(fill yes)
			(layer "B.Fab")
		)
		(pad "1" smd rect
			(at 1.35001 -0.94996 180)
			(size 0.6096 1.0668)
			(layers "B.Cu" "B.Mask" "B.Paste")
			(net "SEL_FLASH_PEX2_BUF_R")
		)
		(pad "2" smd rect
			(at 1.35001 0 180)
			(size 0.6096 1.0668)
			(layers "B.Cu" "B.Mask" "B.Paste")
			(net "SEL_FLASH_PEX3_BUF_R")
		)
		(pad "3" smd rect
			(at 1.35001 0.94996 180)
			(size 0.6096 1.0668)
			(layers "B.Cu" "B.Mask" "B.Paste")
			(net "GND")
		)
		(pad "4" smd rect
			(at -1.35001 0.94996 180)
			(size 0.6096 1.0668)
			(layers "B.Cu" "B.Mask" "B.Paste")
			(net "SPI_BIC1_LS23_EN")
		)
		(pad "5" smd rect
			(at -1.35001 -0.94996 180)
			(size 0.6096 1.0668)
			(layers "B.Cu" "B.Mask" "B.Paste")
			(net "P3V3_AUX")
		)
	)
	(footprint ""
		(layer "B.Cu")
		(at 77.541882 -98.021648 180)
		(property "Reference" "R64"
			(at 0 0 0)
			(layer "B.SilkS")
			(hide yes)
			(effects
				(font
					(size 1.27 1.27)
				)
				(justify mirror)
			)
		)
		(property "Value" ""
			(at 0 0 0)
			(layer "B.Fab")
			(effects
				(font
					(size 1.27 1.27)
				)
				(justify mirror)
			)
		)
		(duplicate_pad_numbers_are_jumpers no)
		(fp_line
			(start 0.7874 0.4064)
			(end 0.7874 -0.4064)
			(stroke
				(width 0.1524)
				(type default)
			)
			(layer "B.SilkS")
		)
		(fp_line
			(start 0.7874 -0.4064)
			(end -0.7874 -0.4064)
			(stroke
				(width 0.1524)
				(type default)
			)
			(layer "B.SilkS")
		)
		(fp_line
			(start -0.7874 0.4064)
			(end 0.7874 0.4064)
			(stroke
				(width 0.1524)
				(type default)
			)
			(layer "B.SilkS")
		)
		(fp_line
			(start -0.7874 -0.4064)
			(end -0.7874 0.4064)
			(stroke
				(width 0.1524)
				(type default)
			)
			(layer "B.SilkS")
		)
		(fp_line
			(start 0.67945 0.3048)
			(end 0.67945 -0.305054)
			(stroke
				(width 0.1)
				(type default)
			)
			(layer "B.Fab")
		)
		(fp_line
			(start 0.67945 -0.305054)
			(end 0.12065 -0.305054)
			(stroke
				(width 0.1)
				(type default)
			)
			(layer "B.Fab")
		)
		(fp_line
			(start 0.12065 0.3048)
			(end 0.67945 0.3048)
			(stroke
				(width 0.1)
				(type default)
			)
			(layer "B.Fab")
		)
		(fp_line
			(start 0.12065 0.2794)
			(end 0.12065 0.3048)
			(stroke
				(width 0.1)
				(type default)
			)
			(layer "B.Fab")
		)
		(fp_line
			(start 0.12065 -0.2794)
			(end -0.12065 -0.2794)
			(stroke
				(width 0.1)
				(type default)
			)
			(layer "B.Fab")
		)
		(fp_line
			(start 0.12065 -0.305054)
			(end 0.12065 -0.2794)
			(stroke
				(width 0.1)
				(type default)
			)
			(layer "B.Fab")
		)
		(fp_line
			(start -0.120396 0.3048)
			(end -0.120396 0.2794)
			(stroke
				(width 0.1)
				(type default)
			)
			(layer "B.Fab")
		)
		(fp_line
			(start -0.120396 0.2794)
			(end 0.12065 0.2794)
			(stroke
				(width 0.1)
				(type default)
			)
			(layer "B.Fab")
		)
		(fp_line
			(start -0.12065 -0.2794)
			(end -0.12065 -0.3048)
			(stroke
				(width 0.1)
				(type default)
			)
			(layer "B.Fab")
		)
		(fp_line
			(start -0.12065 -0.3048)
			(end -0.67945 -0.3048)
			(stroke
				(width 0.1)
				(type default)
			)
			(layer "B.Fab")
		)
		(fp_line
			(start -0.67945 0.3048)
			(end -0.120396 0.3048)
			(stroke
				(width 0.1)
				(type default)
			)
			(layer "B.Fab")
		)
		(fp_line
			(start -0.67945 -0.3048)
			(end -0.67945 0.3048)
			(stroke
				(width 0.1)
				(type default)
			)
			(layer "B.Fab")
		)
		(pad "1" smd circle
			(at 0.40005 0)
			(size 0 0)
			(layers "B.Cu" "B.Mask" "B.Paste")
			(net "NIC1_DATA_OUT")
		)
		(pad "2" smd circle
			(at -0.40005 0)
			(size 0 0)
			(layers "B.Cu" "B.Mask" "B.Paste")
			(net "GND")
		)
	)
	(footprint ""
		(layer "B.Cu")
		(at 405.100028 -303.499774 -90)
		(property "Reference" "C3435"
			(at 0 0 90)
			(layer "B.SilkS")
			(hide yes)
			(effects
				(font
					(size 1.27 1.27)
				)
				(justify mirror)
			)
		)
		(property "Value" ""
			(at 0 0 90)
			(layer "B.Fab")
			(effects
				(font
					(size 1.27 1.27)
				)
				(justify mirror)
			)
		)
		(duplicate_pad_numbers_are_jumpers no)
		(fp_line
			(start -0.299974 0.150114)
			(end 0.299974 0.150114)
			(stroke
				(width 0.1)
				(type default)
			)
			(layer "B.Fab")
		)
		(fp_line
			(start 0.299974 0.150114)
			(end 0.299974 -0.150114)
			(stroke
				(width 0.1)
				(type default)
			)
			(layer "B.Fab")
		)
		(fp_line
			(start -0.299974 -0.150114)
			(end -0.299974 0.150114)
			(stroke
				(width 0.1)
				(type default)
			)
			(layer "B.Fab")
		)
		(fp_line
			(start 0.299974 -0.150114)
			(end -0.299974 -0.150114)
			(stroke
				(width 0.1)
				(type default)
			)
			(layer "B.Fab")
		)
		(pad "1" smd rect
			(at 0.2667 0 90)
			(size 0.3048 0.381)
			(layers "B.Cu" "B.Mask" "B.Paste")
			(net "P1V25_PEX3")
		)
		(pad "2" smd rect
			(at -0.2667 0 90)
			(size 0.3048 0.381)
			(layers "B.Cu" "B.Mask" "B.Paste")
			(net "GND")
		)
	)
	(footprint ""
		(layer "B.Cu")
		(at 394.65504 -299.212)
		(property "Reference" "C3548"
			(at 0 0 0)
			(layer "B.SilkS")
			(hide yes)
			(effects
				(font
					(size 1.27 1.27)
				)
				(justify mirror)
			)
		)
		(property "Value" ""
			(at 0 0 0)
			(layer "B.Fab")
			(effects
				(font
					(size 1.27 1.27)
				)
				(justify mirror)
			)
		)
		(duplicate_pad_numbers_are_jumpers no)
		(fp_line
			(start -0.299974 -0.150114)
			(end -0.299974 0.150114)
			(stroke
				(width 0.1)
				(type default)
			)
			(layer "B.Fab")
		)
		(fp_line
			(start -0.299974 0.150114)
			(end 0.299974 0.150114)
			(stroke
				(width 0.1)
				(type default)
			)
			(layer "B.Fab")
		)
		(fp_line
			(start 0.299974 -0.150114)
			(end -0.299974 -0.150114)
			(stroke
				(width 0.1)
				(type default)
			)
			(layer "B.Fab")
		)
		(fp_line
			(start 0.299974 0.150114)
			(end 0.299974 -0.150114)
			(stroke
				(width 0.1)
				(type default)
			)
			(layer "B.Fab")
		)
		(pad "1" smd rect
			(at 0.2667 0 180)
			(size 0.3048 0.381)
			(layers "B.Cu" "B.Mask" "B.Paste")
			(net "PCEPLL1_VDDA18_PEX3")
		)
		(pad "2" smd rect
			(at -0.2667 0 180)
			(size 0.3048 0.381)
			(layers "B.Cu" "B.Mask" "B.Paste")
			(net "GND")
		)
	)
	(footprint ""
		(layer "B.Cu")
		(at 52.999894 -299.699934 -90)
		(property "Reference" "C1190"
			(at 0 0 90)
			(layer "B.SilkS")
			(hide yes)
			(effects
				(font
					(size 1.27 1.27)
				)
				(justify mirror)
			)
		)
		(property "Value" ""
			(at 0 0 90)
			(layer "B.Fab")
			(effects
				(font
					(size 1.27 1.27)
				)
				(justify mirror)
			)
		)
		(duplicate_pad_numbers_are_jumpers no)
		(fp_line
			(start -0.299974 0.150114)
			(end 0.299974 0.150114)
			(stroke
				(width 0.1)
				(type default)
			)
			(layer "B.Fab")
		)
		(fp_line
			(start 0.299974 0.150114)
			(end 0.299974 -0.150114)
			(stroke
				(width 0.1)
				(type default)
			)
			(layer "B.Fab")
		)
		(fp_line
			(start -0.299974 -0.150114)
			(end -0.299974 0.150114)
			(stroke
				(width 0.1)
				(type default)
			)
			(layer "B.Fab")
		)
		(fp_line
			(start 0.299974 -0.150114)
			(end -0.299974 -0.150114)
			(stroke
				(width 0.1)
				(type default)
			)
			(layer "B.Fab")
		)
		(pad "1" smd rect
			(at 0.2667 0 90)
			(size 0.3048 0.381)
			(layers "B.Cu" "B.Mask" "B.Paste")
			(net "P0V8_SERDES_VDDA_PEX0")
		)
		(pad "2" smd rect
			(at -0.2667 0 90)
			(size 0.3048 0.381)
			(layers "B.Cu" "B.Mask" "B.Paste")
			(net "GND")
		)
	)
	(footprint ""
		(layer "B.Cu")
		(at 230.416354 -150.431246 90)
		(property "Reference" "C2788"
			(at 0 0 90)
			(layer "B.SilkS")
			(hide yes)
			(effects
				(font
					(size 1.27 1.27)
				)
				(justify mirror)
			)
		)
		(property "Value" ""
			(at 0 0 90)
			(layer "B.Fab")
			(effects
				(font
					(size 1.27 1.27)
				)
				(justify mirror)
			)
		)
		(duplicate_pad_numbers_are_jumpers no)
		(fp_line
			(start 0.7874 -0.4064)
			(end -0.7874 -0.4064)
			(stroke
				(width 0.1524)
				(type default)
			)
			(layer "B.SilkS")
		)
		(fp_line
			(start -0.7874 -0.4064)
			(end -0.7874 0.4064)
			(stroke
				(width 0.1524)
				(type default)
			)
			(layer "B.SilkS")
		)
		(fp_line
			(start 0.7874 0.4064)
			(end 0.7874 -0.4064)
			(stroke
				(width 0.1524)
				(type default)
			)
			(layer "B.SilkS")
		)
		(fp_line
			(start -0.7874 0.4064)
			(end 0.7874 0.4064)
			(stroke
				(width 0.1524)
				(type default)
			)
			(layer "B.SilkS")
		)
		(fp_line
			(start 0.67945 -0.305054)
			(end 0.12065 -0.305054)
			(stroke
				(width 0.1)
				(type default)
			)
			(layer "B.Fab")
		)
		(fp_line
			(start 0.12065 -0.305054)
			(end 0.12065 -0.2794)
			(stroke
				(width 0.1)
				(type default)
			)
			(layer "B.Fab")
		)
		(fp_line
			(start -0.12065 -0.3048)
			(end -0.67945 -0.3048)
			(stroke
				(width 0.1)
				(type default)
			)
			(layer "B.Fab")
		)
		(fp_line
			(start -0.67945 -0.3048)
			(end -0.67945 0.3048)
			(stroke
				(width 0.1)
				(type default)
			)
			(layer "B.Fab")
		)
		(fp_line
			(start 0.12065 -0.2794)
			(end -0.12065 -0.2794)
			(stroke
				(width 0.1)
				(type default)
			)
			(layer "B.Fab")
		)
		(fp_line
			(start -0.12065 -0.2794)
			(end -0.12065 -0.3048)
			(stroke
				(width 0.1)
				(type default)
			)
			(layer "B.Fab")
		)
		(fp_line
			(start 0.12065 0.2794)
			(end 0.12065 0.3048)
			(stroke
				(width 0.1)
				(type default)
			)
			(layer "B.Fab")
		)
		(fp_line
			(start -0.120396 0.2794)
			(end 0.12065 0.2794)
			(stroke
				(width 0.1)
				(type default)
			)
			(layer "B.Fab")
		)
		(fp_line
			(start 0.67945 0.3048)
			(end 0.67945 -0.305054)
			(stroke
				(width 0.1)
				(type default)
			)
			(layer "B.Fab")
		)
		(fp_line
			(start 0.12065 0.3048)
			(end 0.67945 0.3048)
			(stroke
				(width 0.1)
				(type default)
			)
			(layer "B.Fab")
		)
		(fp_line
			(start -0.120396 0.3048)
			(end -0.120396 0.2794)
			(stroke
				(width 0.1)
				(type default)
			)
			(layer "B.Fab")
		)
		(fp_line
			(start -0.67945 0.3048)
			(end -0.120396 0.3048)
			(stroke
				(width 0.1)
				(type default)
			)
			(layer "B.Fab")
		)
		(pad "1" smd circle
			(at 0.40005 0 270)
			(size 0 0)
			(layers "B.Cu" "B.Mask" "B.Paste")
			(net "P3V3_CLK_GEN_VDD_CK440_PEX")
		)
		(pad "2" smd circle
			(at -0.40005 0 270)
			(size 0 0)
			(layers "B.Cu" "B.Mask" "B.Paste")
			(net "GND")
		)
	)
	(footprint ""
		(layer "B.Cu")
		(at 64.399922 -290.199826 90)
		(property "Reference" "C1236"
			(at 0 0 90)
			(layer "B.SilkS")
			(hide yes)
			(effects
				(font
					(size 1.27 1.27)
				)
				(justify mirror)
			)
		)
		(property "Value" ""
			(at 0 0 90)
			(layer "B.Fab")
			(effects
				(font
					(size 1.27 1.27)
				)
				(justify mirror)
			)
		)
		(duplicate_pad_numbers_are_jumpers no)
		(fp_line
			(start 0.299974 -0.150114)
			(end -0.299974 -0.150114)
			(stroke
				(width 0.1)
				(type default)
			)
			(layer "B.Fab")
		)
		(fp_line
			(start -0.299974 -0.150114)
			(end -0.299974 0.150114)
			(stroke
				(width 0.1)
				(type default)
			)
			(layer "B.Fab")
		)
		(fp_line
			(start 0.299974 0.150114)
			(end 0.299974 -0.150114)
			(stroke
				(width 0.1)
				(type default)
			)
			(layer "B.Fab")
		)
		(fp_line
			(start -0.299974 0.150114)
			(end 0.299974 0.150114)
			(stroke
				(width 0.1)
				(type default)
			)
			(layer "B.Fab")
		)
		(pad "1" smd rect
			(at 0.2667 0 270)
			(size 0.3048 0.381)
			(layers "B.Cu" "B.Mask" "B.Paste")
			(net "P0V8_SERDES_VDDA_PEX0")
		)
		(pad "2" smd rect
			(at -0.2667 0 270)
			(size 0.3048 0.381)
			(layers "B.Cu" "B.Mask" "B.Paste")
			(net "GND")
		)
	)
	(footprint ""
		(layer "B.Cu")
		(at 297.549824 -299.699934 -90)
		(property "Reference" "C1693"
			(at 0 0 90)
			(layer "B.SilkS")
			(hide yes)
			(effects
				(font
					(size 1.27 1.27)
				)
				(justify mirror)
			)
		)
		(property "Value" ""
			(at 0 0 90)
			(layer "B.Fab")
			(effects
				(font
					(size 1.27 1.27)
				)
				(justify mirror)
			)
		)
		(duplicate_pad_numbers_are_jumpers no)
		(fp_line
			(start -0.299974 0.150114)
			(end 0.299974 0.150114)
			(stroke
				(width 0.1)
				(type default)
			)
			(layer "B.Fab")
		)
		(fp_line
			(start 0.299974 0.150114)
			(end 0.299974 -0.150114)
			(stroke
				(width 0.1)
				(type default)
			)
			(layer "B.Fab")
		)
		(fp_line
			(start -0.299974 -0.150114)
			(end -0.299974 0.150114)
			(stroke
				(width 0.1)
				(type default)
			)
			(layer "B.Fab")
		)
		(fp_line
			(start 0.299974 -0.150114)
			(end -0.299974 -0.150114)
			(stroke
				(width 0.1)
				(type default)
			)
			(layer "B.Fab")
		)
		(pad "1" smd rect
			(at 0.2667 0 90)
			(size 0.3048 0.381)
			(layers "B.Cu" "B.Mask" "B.Paste")
			(net "P0V8_SERDES_VDDA_PEX2")
		)
		(pad "2" smd rect
			(at -0.2667 0 90)
			(size 0.3048 0.381)
			(layers "B.Cu" "B.Mask" "B.Paste")
			(net "GND")
		)
	)
	(footprint ""
		(layer "B.Cu")
		(at 287.064704 -140.931138 180)
		(property "Reference" "U28"
			(at -0.39243 1.870964 0)
			(unlocked yes)
			(layer "B.SilkS")
			(effects
				(font
					(size 0.7874 0.5842)
					(thickness 0.1524)
				)
				(justify mirror)
			)
		)
		(property "Value" ""
			(at 0 0 0)
			(layer "B.Fab")
			(effects
				(font
					(size 1.27 1.27)
				)
				(justify mirror)
			)
		)
		(duplicate_pad_numbers_are_jumpers no)
		(fp_line
			(start 1.3462 1.1938)
			(end -1.3462 1.1938)
			(stroke
				(width 0.1524)
				(type default)
			)
			(layer "B.SilkS")
		)
		(fp_line
			(start 1.3462 -1.1938)
			(end 1.3462 1.1684)
			(stroke
				(width 0.1524)
				(type default)
			)
			(layer "B.SilkS")
		)
		(fp_line
			(start -1.3462 1.1938)
			(end -1.3462 -1.1938)
			(stroke
				(width 0.1524)
				(type default)
			)
			(layer "B.SilkS")
		)
		(fp_line
			(start -1.3462 -1.1938)
			(end 1.3462 -1.1938)
			(stroke
				(width 0.1524)
				(type default)
			)
			(layer "B.SilkS")
		)
		(fp_poly
			(pts
				(xy 1.447038 -0.760476) (xy 2.052066 -0.457962) (xy 2.052066 -1.06299)
			)
			(stroke
				(width 0)
				(type default)
			)
			(fill yes)
			(layer "B.SilkS")
		)
		(fp_line
			(start 0.674878 1.124966)
			(end -0.674878 1.124966)
			(stroke
				(width 0.1)
				(type default)
			)
			(layer "B.Fab")
		)
		(fp_line
			(start 0.674878 -1.124966)
			(end 0.674878 1.124966)
			(stroke
				(width 0.1)
				(type default)
			)
			(layer "B.Fab")
		)
		(fp_line
			(start -0.674878 1.124966)
			(end -0.674878 -1.124966)
			(stroke
				(width 0.1)
				(type default)
			)
			(layer "B.Fab")
		)
		(fp_line
			(start -0.674878 -1.124966)
			(end 0.674878 -1.124966)
			(stroke
				(width 0.1)
				(type default)
			)
			(layer "B.Fab")
		)
		(fp_poly
			(pts
				(xy 1.447038 -0.760476) (xy 2.052066 -0.457962) (xy 2.052066 -1.06299)
			)
			(stroke
				(width 0)
				(type default)
			)
			(fill yes)
			(layer "B.Fab")
		)
		(pad "1" smd rect
			(at 0.899922 -0.750062)
			(size 0.6096 0.6096)
			(layers "B.Cu" "B.Mask" "B.Paste")
			(net "NIC4_AUX_PWR_EN_R")
		)
		(pad "2" smd rect
			(at 0.899922 0 270)
			(size 0.4064 0.6096)
			(layers "B.Cu" "B.Mask" "B.Paste")
			(net "RST_SMB_NIC4_MUX_N")
		)
		(pad "3" smd rect
			(at 0.899922 0.750062)
			(size 0.6096 0.6096)
			(layers "B.Cu" "B.Mask" "B.Paste")
			(net "GND")
		)
		(pad "4" smd rect
			(at -0.899922 0.750062)
			(size 0.6096 0.6096)
			(layers "B.Cu" "B.Mask" "B.Paste")
			(net "RST_SMB_NIC4_MUX_ISO_N")
		)
		(pad "5" smd rect
			(at -0.899922 -0.750062)
			(size 0.6096 0.6096)
			(layers "B.Cu" "B.Mask" "B.Paste")
			(net "P3V3_AUX")
		)
	)
	(footprint ""
		(layer "B.Cu")
		(at 133.018276 -308.580028 90)
		(property "Reference" "C4260"
			(at 0 0 90)
			(layer "B.SilkS")
			(hide yes)
			(effects
				(font
					(size 1.27 1.27)
				)
				(justify mirror)
			)
		)
		(property "Value" ""
			(at 0 0 90)
			(layer "B.Fab")
			(effects
				(font
					(size 1.27 1.27)
				)
				(justify mirror)
			)
		)
		(duplicate_pad_numbers_are_jumpers no)
		(fp_line
			(start 1.2954 -0.5842)
			(end -1.2954 -0.5842)
			(stroke
				(width 0.1524)
				(type default)
			)
			(layer "B.SilkS")
		)
		(fp_line
			(start -1.2954 -0.5842)
			(end -1.2954 0.5842)
			(stroke
				(width 0.1524)
				(type default)
			)
			(layer "B.SilkS")
		)
		(fp_line
			(start 1.2954 0.5842)
			(end 1.2954 -0.5842)
			(stroke
				(width 0.1524)
				(type default)
			)
			(layer "B.SilkS")
		)
		(fp_line
			(start -1.2954 0.5842)
			(end 1.2954 0.5842)
			(stroke
				(width 0.1524)
				(type default)
			)
			(layer "B.SilkS")
		)
		(fp_line
			(start 0.8636 -0.4572)
			(end -0.8636 -0.4572)
			(stroke
				(width 0.1)
				(type default)
			)
			(layer "B.Fab")
		)
		(fp_line
			(start -0.8636 -0.4572)
			(end -0.8636 -0.4064)
			(stroke
				(width 0.1)
				(type default)
			)
			(layer "B.Fab")
		)
		(fp_line
			(start 1.1938 -0.4064)
			(end 0.8636 -0.4064)
			(stroke
				(width 0.1)
				(type default)
			)
			(layer "B.Fab")
		)
		(fp_line
			(start 0.8636 -0.4064)
			(end 0.8636 -0.4572)
			(stroke
				(width 0.1)
				(type default)
			)
			(layer "B.Fab")
		)
		(fp_line
			(start -0.8636 -0.4064)
			(end -1.1938 -0.4064)
			(stroke
				(width 0.1)
				(type default)
			)
			(layer "B.Fab")
		)
		(fp_line
			(start -1.1938 -0.4064)
			(end -1.1938 0.4064)
			(stroke
				(width 0.1)
				(type default)
			)
			(layer "B.Fab")
		)
		(fp_line
			(start 1.1938 0.4064)
			(end 1.1938 -0.4064)
			(stroke
				(width 0.1)
				(type default)
			)
			(layer "B.Fab")
		)
		(fp_line
			(start 0.8636 0.4064)
			(end 1.1938 0.4064)
			(stroke
				(width 0.1)
				(type default)
			)
			(layer "B.Fab")
		)
		(fp_line
			(start -0.8636 0.4064)
			(end -0.8636 0.4572)
			(stroke
				(width 0.1)
				(type default)
			)
			(layer "B.Fab")
		)
		(fp_line
			(start -1.1938 0.4064)
			(end -0.8636 0.4064)
			(stroke
				(width 0.1)
				(type default)
			)
			(layer "B.Fab")
		)
		(fp_line
			(start 0.8636 0.4572)
			(end 0.8636 0.4064)
			(stroke
				(width 0.1)
				(type default)
			)
			(layer "B.Fab")
		)
		(fp_line
			(start -0.8636 0.4572)
			(end 0.8636 0.4572)
			(stroke
				(width 0.1)
				(type default)
			)
			(layer "B.Fab")
		)
		(pad "1" smd rect
			(at 0.7366 0)
			(size 0.7112 0.8128)
			(layers "B.Cu" "B.Mask" "B.Paste")
			(net "P0V8_PEX1")
		)
		(pad "2" smd rect
			(at -0.7366 0)
			(size 0.7112 0.8128)
			(layers "B.Cu" "B.Mask" "B.Paste")
			(net "GND")
		)
	)
	(footprint ""
		(layer "B.Cu")
		(at 228.578664 -204.44206 -90)
		(property "Reference" "R5282"
			(at 0 0 90)
			(layer "B.SilkS")
			(hide yes)
			(effects
				(font
					(size 1.27 1.27)
				)
				(justify mirror)
			)
		)
		(property "Value" ""
			(at 0 0 90)
			(layer "B.Fab")
			(effects
				(font
					(size 1.27 1.27)
				)
				(justify mirror)
			)
		)
		(duplicate_pad_numbers_are_jumpers no)
		(fp_line
			(start -0.7874 0.4064)
			(end 0.7874 0.4064)
			(stroke
				(width 0.1524)
				(type default)
			)
			(layer "B.SilkS")
		)
		(fp_line
			(start 0.7874 0.4064)
			(end 0.7874 -0.4064)
			(stroke
				(width 0.1524)
				(type default)
			)
			(layer "B.SilkS")
		)
		(fp_line
			(start -0.7874 -0.4064)
			(end -0.7874 0.4064)
			(stroke
				(width 0.1524)
				(type default)
			)
			(layer "B.SilkS")
		)
		(fp_line
			(start 0.7874 -0.4064)
			(end -0.7874 -0.4064)
			(stroke
				(width 0.1524)
				(type default)
			)
			(layer "B.SilkS")
		)
		(fp_line
			(start -0.67945 0.3048)
			(end -0.120396 0.3048)
			(stroke
				(width 0.1)
				(type default)
			)
			(layer "B.Fab")
		)
		(fp_line
			(start -0.120396 0.3048)
			(end -0.120396 0.2794)
			(stroke
				(width 0.1)
				(type default)
			)
			(layer "B.Fab")
		)
		(fp_line
			(start 0.12065 0.3048)
			(end 0.67945 0.3048)
			(stroke
				(width 0.1)
				(type default)
			)
			(layer "B.Fab")
		)
		(fp_line
			(start 0.67945 0.3048)
			(end 0.67945 -0.305054)
			(stroke
				(width 0.1)
				(type default)
			)
			(layer "B.Fab")
		)
		(fp_line
			(start -0.120396 0.2794)
			(end 0.12065 0.2794)
			(stroke
				(width 0.1)
				(type default)
			)
			(layer "B.Fab")
		)
		(fp_line
			(start 0.12065 0.2794)
			(end 0.12065 0.3048)
			(stroke
				(width 0.1)
				(type default)
			)
			(layer "B.Fab")
		)
		(fp_line
			(start -0.12065 -0.2794)
			(end -0.12065 -0.3048)
			(stroke
				(width 0.1)
				(type default)
			)
			(layer "B.Fab")
		)
		(fp_line
			(start 0.12065 -0.2794)
			(end -0.12065 -0.2794)
			(stroke
				(width 0.1)
				(type default)
			)
			(layer "B.Fab")
		)
		(fp_line
			(start -0.67945 -0.3048)
			(end -0.67945 0.3048)
			(stroke
				(width 0.1)
				(type default)
			)
			(layer "B.Fab")
		)
		(fp_line
			(start -0.12065 -0.3048)
			(end -0.67945 -0.3048)
			(stroke
				(width 0.1)
				(type default)
			)
			(layer "B.Fab")
		)
		(fp_line
			(start 0.12065 -0.305054)
			(end 0.12065 -0.2794)
			(stroke
				(width 0.1)
				(type default)
			)
			(layer "B.Fab")
		)
		(fp_line
			(start 0.67945 -0.305054)
			(end 0.12065 -0.305054)
			(stroke
				(width 0.1)
				(type default)
			)
			(layer "B.Fab")
		)
		(pad "1" smd circle
			(at 0.40005 0 90)
			(size 0 0)
			(layers "B.Cu" "B.Mask" "B.Paste")
			(net "GND")
		)
		(pad "2" smd circle
			(at -0.40005 0 90)
			(size 0 0)
			(layers "B.Cu" "B.Mask" "B.Paste")
			(net "JTAG_BIC_TCK_R")
		)
	)
	(footprint ""
		(layer "B.Cu")
		(at 186.200034 -288.774886 180)
		(property "Reference" "C3176"
			(at 0 0 0)
			(layer "B.SilkS")
			(hide yes)
			(effects
				(font
					(size 1.27 1.27)
				)
				(justify mirror)
			)
		)
		(property "Value" ""
			(at 0 0 0)
			(layer "B.Fab")
			(effects
				(font
					(size 1.27 1.27)
				)
				(justify mirror)
			)
		)
		(duplicate_pad_numbers_are_jumpers no)
		(fp_line
			(start 0.299974 0.150114)
			(end 0.299974 -0.150114)
			(stroke
				(width 0.1)
				(type default)
			)
			(layer "B.Fab")
		)
		(fp_line
			(start 0.299974 -0.150114)
			(end -0.299974 -0.150114)
			(stroke
				(width 0.1)
				(type default)
			)
			(layer "B.Fab")
		)
		(fp_line
			(start -0.299974 0.150114)
			(end 0.299974 0.150114)
			(stroke
				(width 0.1)
				(type default)
			)
			(layer "B.Fab")
		)
		(fp_line
			(start -0.299974 -0.150114)
			(end -0.299974 0.150114)
			(stroke
				(width 0.1)
				(type default)
			)
			(layer "B.Fab")
		)
		(pad "1" smd rect
			(at 0.2667 0)
			(size 0.3048 0.381)
			(layers "B.Cu" "B.Mask" "B.Paste")
			(net "P1V8_PEX")
		)
		(pad "2" smd rect
			(at -0.2667 0)
			(size 0.3048 0.381)
			(layers "B.Cu" "B.Mask" "B.Paste")
			(net "GND")
		)
	)
	(footprint ""
		(layer "B.Cu")
		(at 232.397046 -154.143202 -90)
		(property "Reference" "C2785"
			(at 0 0 90)
			(layer "B.SilkS")
			(hide yes)
			(effects
				(font
					(size 1.27 1.27)
				)
				(justify mirror)
			)
		)
		(property "Value" ""
			(at 0 0 90)
			(layer "B.Fab")
			(effects
				(font
					(size 1.27 1.27)
				)
				(justify mirror)
			)
		)
		(duplicate_pad_numbers_are_jumpers no)
		(fp_line
			(start -1.2954 0.5842)
			(end 1.2954 0.5842)
			(stroke
				(width 0.1524)
				(type default)
			)
			(layer "B.SilkS")
		)
		(fp_line
			(start 1.2954 0.5842)
			(end 1.2954 -0.5842)
			(stroke
				(width 0.1524)
				(type default)
			)
			(layer "B.SilkS")
		)
		(fp_line
			(start -1.2954 -0.5842)
			(end -1.2954 0.5842)
			(stroke
				(width 0.1524)
				(type default)
			)
			(layer "B.SilkS")
		)
		(fp_line
			(start 1.2954 -0.5842)
			(end -1.2954 -0.5842)
			(stroke
				(width 0.1524)
				(type default)
			)
			(layer "B.SilkS")
		)
		(fp_line
			(start -0.8636 0.4572)
			(end 0.8636 0.4572)
			(stroke
				(width 0.1)
				(type default)
			)
			(layer "B.Fab")
		)
		(fp_line
			(start 0.8636 0.4572)
			(end 0.8636 0.4064)
			(stroke
				(width 0.1)
				(type default)
			)
			(layer "B.Fab")
		)
		(fp_line
			(start -1.1938 0.4064)
			(end -0.8636 0.4064)
			(stroke
				(width 0.1)
				(type default)
			)
			(layer "B.Fab")
		)
		(fp_line
			(start -0.8636 0.4064)
			(end -0.8636 0.4572)
			(stroke
				(width 0.1)
				(type default)
			)
			(layer "B.Fab")
		)
		(fp_line
			(start 0.8636 0.4064)
			(end 1.1938 0.4064)
			(stroke
				(width 0.1)
				(type default)
			)
			(layer "B.Fab")
		)
		(fp_line
			(start 1.1938 0.4064)
			(end 1.1938 -0.4064)
			(stroke
				(width 0.1)
				(type default)
			)
			(layer "B.Fab")
		)
		(fp_line
			(start -1.1938 -0.4064)
			(end -1.1938 0.4064)
			(stroke
				(width 0.1)
				(type default)
			)
			(layer "B.Fab")
		)
		(fp_line
			(start -0.8636 -0.4064)
			(end -1.1938 -0.4064)
			(stroke
				(width 0.1)
				(type default)
			)
			(layer "B.Fab")
		)
		(fp_line
			(start 0.8636 -0.4064)
			(end 0.8636 -0.4572)
			(stroke
				(width 0.1)
				(type default)
			)
			(layer "B.Fab")
		)
		(fp_line
			(start 1.1938 -0.4064)
			(end 0.8636 -0.4064)
			(stroke
				(width 0.1)
				(type default)
			)
			(layer "B.Fab")
		)
		(fp_line
			(start -0.8636 -0.4572)
			(end -0.8636 -0.4064)
			(stroke
				(width 0.1)
				(type default)
			)
			(layer "B.Fab")
		)
		(fp_line
			(start 0.8636 -0.4572)
			(end -0.8636 -0.4572)
			(stroke
				(width 0.1)
				(type default)
			)
			(layer "B.Fab")
		)
		(pad "1" smd rect
			(at 0.7366 0 180)
			(size 0.7112 0.8128)
			(layers "B.Cu" "B.Mask" "B.Paste")
			(net "P3V3_CLK_GEN_VDD_CK440_PEX")
		)
		(pad "2" smd rect
			(at -0.7366 0 180)
			(size 0.7112 0.8128)
			(layers "B.Cu" "B.Mask" "B.Paste")
			(net "GND")
		)
	)
	(footprint ""
		(layer "B.Cu")
		(at 55.849774 -292.099746 90)
		(property "Reference" "C1201"
			(at 0 0 90)
			(layer "B.SilkS")
			(hide yes)
			(effects
				(font
					(size 1.27 1.27)
				)
				(justify mirror)
			)
		)
		(property "Value" ""
			(at 0 0 90)
			(layer "B.Fab")
			(effects
				(font
					(size 1.27 1.27)
				)
				(justify mirror)
			)
		)
		(duplicate_pad_numbers_are_jumpers no)
		(fp_line
			(start 0.299974 -0.150114)
			(end -0.299974 -0.150114)
			(stroke
				(width 0.1)
				(type default)
			)
			(layer "B.Fab")
		)
		(fp_line
			(start -0.299974 -0.150114)
			(end -0.299974 0.150114)
			(stroke
				(width 0.1)
				(type default)
			)
			(layer "B.Fab")
		)
		(fp_line
			(start 0.299974 0.150114)
			(end 0.299974 -0.150114)
			(stroke
				(width 0.1)
				(type default)
			)
			(layer "B.Fab")
		)
		(fp_line
			(start -0.299974 0.150114)
			(end 0.299974 0.150114)
			(stroke
				(width 0.1)
				(type default)
			)
			(layer "B.Fab")
		)
		(pad "1" smd rect
			(at 0.2667 0 270)
			(size 0.3048 0.381)
			(layers "B.Cu" "B.Mask" "B.Paste")
			(net "P0V8_SERDES_VDDA_PEX0")
		)
		(pad "2" smd rect
			(at -0.2667 0 270)
			(size 0.3048 0.381)
			(layers "B.Cu" "B.Mask" "B.Paste")
			(net "GND")
		)
	)
	(footprint ""
		(layer "B.Cu")
		(at 351.926906 -308.613556 90)
		(property "Reference" "C1923"
			(at 0 0 90)
			(layer "B.SilkS")
			(hide yes)
			(effects
				(font
					(size 1.27 1.27)
				)
				(justify mirror)
			)
		)
		(property "Value" ""
			(at 0 0 90)
			(layer "B.Fab")
			(effects
				(font
					(size 1.27 1.27)
				)
				(justify mirror)
			)
		)
		(duplicate_pad_numbers_are_jumpers no)
		(fp_line
			(start 1.2954 -0.5842)
			(end -1.2954 -0.5842)
			(stroke
				(width 0.1524)
				(type default)
			)
			(layer "B.SilkS")
		)
		(fp_line
			(start -1.2954 -0.5842)
			(end -1.2954 0.5842)
			(stroke
				(width 0.1524)
				(type default)
			)
			(layer "B.SilkS")
		)
		(fp_line
			(start 1.2954 0.5842)
			(end 1.2954 -0.5842)
			(stroke
				(width 0.1524)
				(type default)
			)
			(layer "B.SilkS")
		)
		(fp_line
			(start -1.2954 0.5842)
			(end 1.2954 0.5842)
			(stroke
				(width 0.1524)
				(type default)
			)
			(layer "B.SilkS")
		)
		(fp_line
			(start 0.8636 -0.4572)
			(end -0.8636 -0.4572)
			(stroke
				(width 0.1)
				(type default)
			)
			(layer "B.Fab")
		)
		(fp_line
			(start -0.8636 -0.4572)
			(end -0.8636 -0.4064)
			(stroke
				(width 0.1)
				(type default)
			)
			(layer "B.Fab")
		)
		(fp_line
			(start 1.1938 -0.4064)
			(end 0.8636 -0.4064)
			(stroke
				(width 0.1)
				(type default)
			)
			(layer "B.Fab")
		)
		(fp_line
			(start 0.8636 -0.4064)
			(end 0.8636 -0.4572)
			(stroke
				(width 0.1)
				(type default)
			)
			(layer "B.Fab")
		)
		(fp_line
			(start -0.8636 -0.4064)
			(end -1.1938 -0.4064)
			(stroke
				(width 0.1)
				(type default)
			)
			(layer "B.Fab")
		)
		(fp_line
			(start -1.1938 -0.4064)
			(end -1.1938 0.4064)
			(stroke
				(width 0.1)
				(type default)
			)
			(layer "B.Fab")
		)
		(fp_line
			(start 1.1938 0.4064)
			(end 1.1938 -0.4064)
			(stroke
				(width 0.1)
				(type default)
			)
			(layer "B.Fab")
		)
		(fp_line
			(start 0.8636 0.4064)
			(end 1.1938 0.4064)
			(stroke
				(width 0.1)
				(type default)
			)
			(layer "B.Fab")
		)
		(fp_line
			(start -0.8636 0.4064)
			(end -0.8636 0.4572)
			(stroke
				(width 0.1)
				(type default)
			)
			(layer "B.Fab")
		)
		(fp_line
			(start -1.1938 0.4064)
			(end -0.8636 0.4064)
			(stroke
				(width 0.1)
				(type default)
			)
			(layer "B.Fab")
		)
		(fp_line
			(start 0.8636 0.4572)
			(end 0.8636 0.4064)
			(stroke
				(width 0.1)
				(type default)
			)
			(layer "B.Fab")
		)
		(fp_line
			(start -0.8636 0.4572)
			(end 0.8636 0.4572)
			(stroke
				(width 0.1)
				(type default)
			)
			(layer "B.Fab")
		)
		(pad "1" smd rect
			(at 0.7366 0)
			(size 0.7112 0.8128)
			(layers "B.Cu" "B.Mask" "B.Paste")
			(net "P0V8_SERDES_VDDA_PEX3")
		)
		(pad "2" smd rect
			(at -0.7366 0)
			(size 0.7112 0.8128)
			(layers "B.Cu" "B.Mask" "B.Paste")
			(net "GND")
		)
	)
	(footprint ""
		(layer "B.Cu")
		(at 415.101278 -305.399948 -90)
		(property "Reference" "C3484"
			(at 0 0 90)
			(layer "B.SilkS")
			(hide yes)
			(effects
				(font
					(size 1.27 1.27)
				)
				(justify mirror)
			)
		)
		(property "Value" ""
			(at 0 0 90)
			(layer "B.Fab")
			(effects
				(font
					(size 1.27 1.27)
				)
				(justify mirror)
			)
		)
		(duplicate_pad_numbers_are_jumpers no)
		(fp_line
			(start -0.299974 0.150114)
			(end 0.299974 0.150114)
			(stroke
				(width 0.1)
				(type default)
			)
			(layer "B.Fab")
		)
		(fp_line
			(start 0.299974 0.150114)
			(end 0.299974 -0.150114)
			(stroke
				(width 0.1)
				(type default)
			)
			(layer "B.Fab")
		)
		(fp_line
			(start -0.299974 -0.150114)
			(end -0.299974 0.150114)
			(stroke
				(width 0.1)
				(type default)
			)
			(layer "B.Fab")
		)
		(fp_line
			(start 0.299974 -0.150114)
			(end -0.299974 -0.150114)
			(stroke
				(width 0.1)
				(type default)
			)
			(layer "B.Fab")
		)
		(pad "1" smd rect
			(at 0.2667 0 90)
			(size 0.3048 0.381)
			(layers "B.Cu" "B.Mask" "B.Paste")
			(net "P1V25_SERDES_VDDPLL_PEX3")
		)
		(pad "2" smd rect
			(at -0.2667 0 90)
			(size 0.3048 0.381)
			(layers "B.Cu" "B.Mask" "B.Paste")
			(net "GND")
		)
	)
	(footprint ""
		(layer "B.Cu")
		(at 348.750128 -326.934322 -90)
		(property "Reference" "C4313"
			(at 0 0 90)
			(layer "B.SilkS")
			(hide yes)
			(effects
				(font
					(size 1.27 1.27)
				)
				(justify mirror)
			)
		)
		(property "Value" ""
			(at 0 0 90)
			(layer "B.Fab")
			(effects
				(font
					(size 1.27 1.27)
				)
				(justify mirror)
			)
		)
		(duplicate_pad_numbers_are_jumpers no)
		(fp_line
			(start -1.2954 0.5842)
			(end 1.2954 0.5842)
			(stroke
				(width 0.1524)
				(type default)
			)
			(layer "B.SilkS")
		)
		(fp_line
			(start 1.2954 0.5842)
			(end 1.2954 -0.5842)
			(stroke
				(width 0.1524)
				(type default)
			)
			(layer "B.SilkS")
		)
		(fp_line
			(start -1.2954 -0.5842)
			(end -1.2954 0.5842)
			(stroke
				(width 0.1524)
				(type default)
			)
			(layer "B.SilkS")
		)
		(fp_line
			(start 1.2954 -0.5842)
			(end -1.2954 -0.5842)
			(stroke
				(width 0.1524)
				(type default)
			)
			(layer "B.SilkS")
		)
		(fp_line
			(start -0.8636 0.4572)
			(end 0.8636 0.4572)
			(stroke
				(width 0.1)
				(type default)
			)
			(layer "B.Fab")
		)
		(fp_line
			(start 0.8636 0.4572)
			(end 0.8636 0.4064)
			(stroke
				(width 0.1)
				(type default)
			)
			(layer "B.Fab")
		)
		(fp_line
			(start -1.1938 0.4064)
			(end -0.8636 0.4064)
			(stroke
				(width 0.1)
				(type default)
			)
			(layer "B.Fab")
		)
		(fp_line
			(start -0.8636 0.4064)
			(end -0.8636 0.4572)
			(stroke
				(width 0.1)
				(type default)
			)
			(layer "B.Fab")
		)
		(fp_line
			(start 0.8636 0.4064)
			(end 1.1938 0.4064)
			(stroke
				(width 0.1)
				(type default)
			)
			(layer "B.Fab")
		)
		(fp_line
			(start 1.1938 0.4064)
			(end 1.1938 -0.4064)
			(stroke
				(width 0.1)
				(type default)
			)
			(layer "B.Fab")
		)
		(fp_line
			(start -1.1938 -0.4064)
			(end -1.1938 0.4064)
			(stroke
				(width 0.1)
				(type default)
			)
			(layer "B.Fab")
		)
		(fp_line
			(start -0.8636 -0.4064)
			(end -1.1938 -0.4064)
			(stroke
				(width 0.1)
				(type default)
			)
			(layer "B.Fab")
		)
		(fp_line
			(start 0.8636 -0.4064)
			(end 0.8636 -0.4572)
			(stroke
				(width 0.1)
				(type default)
			)
			(layer "B.Fab")
		)
		(fp_line
			(start 1.1938 -0.4064)
			(end 0.8636 -0.4064)
			(stroke
				(width 0.1)
				(type default)
			)
			(layer "B.Fab")
		)
		(fp_line
			(start -0.8636 -0.4572)
			(end -0.8636 -0.4064)
			(stroke
				(width 0.1)
				(type default)
			)
			(layer "B.Fab")
		)
		(fp_line
			(start 0.8636 -0.4572)
			(end -0.8636 -0.4572)
			(stroke
				(width 0.1)
				(type default)
			)
			(layer "B.Fab")
		)
		(pad "1" smd rect
			(at 0.7366 0 180)
			(size 0.7112 0.8128)
			(layers "B.Cu" "B.Mask" "B.Paste")
			(net "P0V8_SERDES_VDDA_PEX2_C3")
		)
		(pad "2" smd rect
			(at -0.7366 0 180)
			(size 0.7112 0.8128)
			(layers "B.Cu" "B.Mask" "B.Paste")
			(net "GND")
		)
	)
	(footprint ""
		(layer "B.Cu")
		(at 406.402032 -376.492262 90)
		(property "Reference" "R6277"
			(at 0 0 90)
			(layer "B.SilkS")
			(hide yes)
			(effects
				(font
					(size 1.27 1.27)
				)
				(justify mirror)
			)
		)
		(property "Value" ""
			(at 0 0 90)
			(layer "B.Fab")
			(effects
				(font
					(size 1.27 1.27)
				)
				(justify mirror)
			)
		)
		(duplicate_pad_numbers_are_jumpers no)
		(fp_line
			(start 0.7874 -0.4064)
			(end -0.7874 -0.4064)
			(stroke
				(width 0.1524)
				(type default)
			)
			(layer "B.SilkS")
		)
		(fp_line
			(start -0.7874 -0.4064)
			(end -0.7874 0.4064)
			(stroke
				(width 0.1524)
				(type default)
			)
			(layer "B.SilkS")
		)
		(fp_line
			(start 0.7874 0.4064)
			(end 0.7874 -0.4064)
			(stroke
				(width 0.1524)
				(type default)
			)
			(layer "B.SilkS")
		)
		(fp_line
			(start -0.7874 0.4064)
			(end 0.7874 0.4064)
			(stroke
				(width 0.1524)
				(type default)
			)
			(layer "B.SilkS")
		)
		(fp_line
			(start 0.67945 -0.305054)
			(end 0.12065 -0.305054)
			(stroke
				(width 0.1)
				(type default)
			)
			(layer "B.Fab")
		)
		(fp_line
			(start 0.12065 -0.305054)
			(end 0.12065 -0.2794)
			(stroke
				(width 0.1)
				(type default)
			)
			(layer "B.Fab")
		)
		(fp_line
			(start -0.12065 -0.3048)
			(end -0.67945 -0.3048)
			(stroke
				(width 0.1)
				(type default)
			)
			(layer "B.Fab")
		)
		(fp_line
			(start -0.67945 -0.3048)
			(end -0.67945 0.3048)
			(stroke
				(width 0.1)
				(type default)
			)
			(layer "B.Fab")
		)
		(fp_line
			(start 0.12065 -0.2794)
			(end -0.12065 -0.2794)
			(stroke
				(width 0.1)
				(type default)
			)
			(layer "B.Fab")
		)
		(fp_line
			(start -0.12065 -0.2794)
			(end -0.12065 -0.3048)
			(stroke
				(width 0.1)
				(type default)
			)
			(layer "B.Fab")
		)
		(fp_line
			(start 0.12065 0.2794)
			(end 0.12065 0.3048)
			(stroke
				(width 0.1)
				(type default)
			)
			(layer "B.Fab")
		)
		(fp_line
			(start -0.120396 0.2794)
			(end 0.12065 0.2794)
			(stroke
				(width 0.1)
				(type default)
			)
			(layer "B.Fab")
		)
		(fp_line
			(start 0.67945 0.3048)
			(end 0.67945 -0.305054)
			(stroke
				(width 0.1)
				(type default)
			)
			(layer "B.Fab")
		)
		(fp_line
			(start 0.12065 0.3048)
			(end 0.67945 0.3048)
			(stroke
				(width 0.1)
				(type default)
			)
			(layer "B.Fab")
		)
		(fp_line
			(start -0.120396 0.3048)
			(end -0.120396 0.2794)
			(stroke
				(width 0.1)
				(type default)
			)
			(layer "B.Fab")
		)
		(fp_line
			(start -0.67945 0.3048)
			(end -0.120396 0.3048)
			(stroke
				(width 0.1)
				(type default)
			)
			(layer "B.Fab")
		)
		(pad "1" smd circle
			(at 0.40005 0 270)
			(size 0 0)
			(layers "B.Cu" "B.Mask" "B.Paste")
			(net "I3C_MB_BMC_R_SDA")
		)
		(pad "2" smd circle
			(at -0.40005 0 270)
			(size 0 0)
			(layers "B.Cu" "B.Mask" "B.Paste")
			(net "SMB_MB_I3C_ISO_SDA")
		)
	)
	(footprint ""
		(layer "B.Cu")
		(at 295.649904 -288.299906 90)
		(property "Reference" "C3276"
			(at 0 0 90)
			(layer "B.SilkS")
			(hide yes)
			(effects
				(font
					(size 1.27 1.27)
				)
				(justify mirror)
			)
		)
		(property "Value" ""
			(at 0 0 90)
			(layer "B.Fab")
			(effects
				(font
					(size 1.27 1.27)
				)
				(justify mirror)
			)
		)
		(duplicate_pad_numbers_are_jumpers no)
		(fp_line
			(start 0.299974 -0.150114)
			(end -0.299974 -0.150114)
			(stroke
				(width 0.1)
				(type default)
			)
			(layer "B.Fab")
		)
		(fp_line
			(start -0.299974 -0.150114)
			(end -0.299974 0.150114)
			(stroke
				(width 0.1)
				(type default)
			)
			(layer "B.Fab")
		)
		(fp_line
			(start 0.299974 0.150114)
			(end 0.299974 -0.150114)
			(stroke
				(width 0.1)
				(type default)
			)
			(layer "B.Fab")
		)
		(fp_line
			(start -0.299974 0.150114)
			(end 0.299974 0.150114)
			(stroke
				(width 0.1)
				(type default)
			)
			(layer "B.Fab")
		)
		(pad "1" smd rect
			(at 0.2667 0 270)
			(size 0.3048 0.381)
			(layers "B.Cu" "B.Mask" "B.Paste")
			(net "P1V25_PEX2")
		)
		(pad "2" smd rect
			(at -0.2667 0 270)
			(size 0.3048 0.381)
			(layers "B.Cu" "B.Mask" "B.Paste")
			(net "GND")
		)
	)
	(footprint ""
		(layer "B.Cu")
		(at 285.199836 -301.599854 -90)
		(property "Reference" "C1687"
			(at 0 0 90)
			(layer "B.SilkS")
			(hide yes)
			(effects
				(font
					(size 1.27 1.27)
				)
				(justify mirror)
			)
		)
		(property "Value" ""
			(at 0 0 90)
			(layer "B.Fab")
			(effects
				(font
					(size 1.27 1.27)
				)
				(justify mirror)
			)
		)
		(duplicate_pad_numbers_are_jumpers no)
		(fp_line
			(start -0.299974 0.150114)
			(end 0.299974 0.150114)
			(stroke
				(width 0.1)
				(type default)
			)
			(layer "B.Fab")
		)
		(fp_line
			(start 0.299974 0.150114)
			(end 0.299974 -0.150114)
			(stroke
				(width 0.1)
				(type default)
			)
			(layer "B.Fab")
		)
		(fp_line
			(start -0.299974 -0.150114)
			(end -0.299974 0.150114)
			(stroke
				(width 0.1)
				(type default)
			)
			(layer "B.Fab")
		)
		(fp_line
			(start 0.299974 -0.150114)
			(end -0.299974 -0.150114)
			(stroke
				(width 0.1)
				(type default)
			)
			(layer "B.Fab")
		)
		(pad "1" smd rect
			(at 0.2667 0 90)
			(size 0.3048 0.381)
			(layers "B.Cu" "B.Mask" "B.Paste")
			(net "P0V8_SERDES_VDDA_PEX2")
		)
		(pad "2" smd rect
			(at -0.2667 0 90)
			(size 0.3048 0.381)
			(layers "B.Cu" "B.Mask" "B.Paste")
			(net "GND")
		)
	)
	(footprint ""
		(layer "B.Cu")
		(at 188.308234 -300.174914 180)
		(property "Reference" "C3164"
			(at 0 0 0)
			(layer "B.SilkS")
			(hide yes)
			(effects
				(font
					(size 1.27 1.27)
				)
				(justify mirror)
			)
		)
		(property "Value" ""
			(at 0 0 0)
			(layer "B.Fab")
			(effects
				(font
					(size 1.27 1.27)
				)
				(justify mirror)
			)
		)
		(duplicate_pad_numbers_are_jumpers no)
		(fp_line
			(start 0.299974 0.150114)
			(end 0.299974 -0.150114)
			(stroke
				(width 0.1)
				(type default)
			)
			(layer "B.Fab")
		)
		(fp_line
			(start 0.299974 -0.150114)
			(end -0.299974 -0.150114)
			(stroke
				(width 0.1)
				(type default)
			)
			(layer "B.Fab")
		)
		(fp_line
			(start -0.299974 0.150114)
			(end 0.299974 0.150114)
			(stroke
				(width 0.1)
				(type default)
			)
			(layer "B.Fab")
		)
		(fp_line
			(start -0.299974 -0.150114)
			(end -0.299974 0.150114)
			(stroke
				(width 0.1)
				(type default)
			)
			(layer "B.Fab")
		)
		(pad "1" smd rect
			(at 0.2667 0)
			(size 0.3048 0.381)
			(layers "B.Cu" "B.Mask" "B.Paste")
			(net "P1V8_VDDA_PEX1")
		)
		(pad "2" smd rect
			(at -0.2667 0)
			(size 0.3048 0.381)
			(layers "B.Cu" "B.Mask" "B.Paste")
			(net "GND")
		)
	)
	(footprint ""
		(layer "B.Cu")
		(at 232.823512 -234.728004 90)
		(property "Reference" "R6186"
			(at 0 0 90)
			(layer "B.SilkS")
			(hide yes)
			(effects
				(font
					(size 1.27 1.27)
				)
				(justify mirror)
			)
		)
		(property "Value" ""
			(at 0 0 90)
			(layer "B.Fab")
			(effects
				(font
					(size 1.27 1.27)
				)
				(justify mirror)
			)
		)
		(duplicate_pad_numbers_are_jumpers no)
		(fp_line
			(start 0.7874 -0.4064)
			(end -0.7874 -0.4064)
			(stroke
				(width 0.1524)
				(type default)
			)
			(layer "B.SilkS")
		)
		(fp_line
			(start -0.7874 -0.4064)
			(end -0.7874 0.4064)
			(stroke
				(width 0.1524)
				(type default)
			)
			(layer "B.SilkS")
		)
		(fp_line
			(start 0.7874 0.4064)
			(end 0.7874 -0.4064)
			(stroke
				(width 0.1524)
				(type default)
			)
			(layer "B.SilkS")
		)
		(fp_line
			(start -0.7874 0.4064)
			(end 0.7874 0.4064)
			(stroke
				(width 0.1524)
				(type default)
			)
			(layer "B.SilkS")
		)
		(fp_line
			(start 0.67945 -0.305054)
			(end 0.12065 -0.305054)
			(stroke
				(width 0.1)
				(type default)
			)
			(layer "B.Fab")
		)
		(fp_line
			(start 0.12065 -0.305054)
			(end 0.12065 -0.2794)
			(stroke
				(width 0.1)
				(type default)
			)
			(layer "B.Fab")
		)
		(fp_line
			(start -0.12065 -0.3048)
			(end -0.67945 -0.3048)
			(stroke
				(width 0.1)
				(type default)
			)
			(layer "B.Fab")
		)
		(fp_line
			(start -0.67945 -0.3048)
			(end -0.67945 0.3048)
			(stroke
				(width 0.1)
				(type default)
			)
			(layer "B.Fab")
		)
		(fp_line
			(start 0.12065 -0.2794)
			(end -0.12065 -0.2794)
			(stroke
				(width 0.1)
				(type default)
			)
			(layer "B.Fab")
		)
		(fp_line
			(start -0.12065 -0.2794)
			(end -0.12065 -0.3048)
			(stroke
				(width 0.1)
				(type default)
			)
			(layer "B.Fab")
		)
		(fp_line
			(start 0.12065 0.2794)
			(end 0.12065 0.3048)
			(stroke
				(width 0.1)
				(type default)
			)
			(layer "B.Fab")
		)
		(fp_line
			(start -0.120396 0.2794)
			(end 0.12065 0.2794)
			(stroke
				(width 0.1)
				(type default)
			)
			(layer "B.Fab")
		)
		(fp_line
			(start 0.67945 0.3048)
			(end 0.67945 -0.305054)
			(stroke
				(width 0.1)
				(type default)
			)
			(layer "B.Fab")
		)
		(fp_line
			(start 0.12065 0.3048)
			(end 0.67945 0.3048)
			(stroke
				(width 0.1)
				(type default)
			)
			(layer "B.Fab")
		)
		(fp_line
			(start -0.120396 0.3048)
			(end -0.120396 0.2794)
			(stroke
				(width 0.1)
				(type default)
			)
			(layer "B.Fab")
		)
		(fp_line
			(start -0.67945 0.3048)
			(end -0.120396 0.3048)
			(stroke
				(width 0.1)
				(type default)
			)
			(layer "B.Fab")
		)
		(pad "1" smd circle
			(at 0.40005 0 270)
			(size 0 0)
			(layers "B.Cu" "B.Mask" "B.Paste")
			(net "GND")
		)
		(pad "2" smd circle
			(at -0.40005 0 270)
			(size 0 0)
			(layers "B.Cu" "B.Mask" "B.Paste")
			(net "SSD4_PWRDIS_BIC_R")
		)
	)
	(footprint ""
		(layer "B.Cu")
		(at 29.741622 -226.78263 180)
		(property "Reference" "R6162"
			(at 0 0 0)
			(layer "B.SilkS")
			(hide yes)
			(effects
				(font
					(size 1.27 1.27)
				)
				(justify mirror)
			)
		)
		(property "Value" ""
			(at 0 0 0)
			(layer "B.Fab")
			(effects
				(font
					(size 1.27 1.27)
				)
				(justify mirror)
			)
		)
		(duplicate_pad_numbers_are_jumpers no)
		(fp_line
			(start 0.7874 0.4064)
			(end 0.7874 -0.4064)
			(stroke
				(width 0.1524)
				(type default)
			)
			(layer "B.SilkS")
		)
		(fp_line
			(start 0.7874 -0.4064)
			(end -0.7874 -0.4064)
			(stroke
				(width 0.1524)
				(type default)
			)
			(layer "B.SilkS")
		)
		(fp_line
			(start -0.7874 0.4064)
			(end 0.7874 0.4064)
			(stroke
				(width 0.1524)
				(type default)
			)
			(layer "B.SilkS")
		)
		(fp_line
			(start -0.7874 -0.4064)
			(end -0.7874 0.4064)
			(stroke
				(width 0.1524)
				(type default)
			)
			(layer "B.SilkS")
		)
		(fp_line
			(start 0.67945 0.3048)
			(end 0.67945 -0.305054)
			(stroke
				(width 0.1)
				(type default)
			)
			(layer "B.Fab")
		)
		(fp_line
			(start 0.67945 -0.305054)
			(end 0.12065 -0.305054)
			(stroke
				(width 0.1)
				(type default)
			)
			(layer "B.Fab")
		)
		(fp_line
			(start 0.12065 0.3048)
			(end 0.67945 0.3048)
			(stroke
				(width 0.1)
				(type default)
			)
			(layer "B.Fab")
		)
		(fp_line
			(start 0.12065 0.2794)
			(end 0.12065 0.3048)
			(stroke
				(width 0.1)
				(type default)
			)
			(layer "B.Fab")
		)
		(fp_line
			(start 0.12065 -0.2794)
			(end -0.12065 -0.2794)
			(stroke
				(width 0.1)
				(type default)
			)
			(layer "B.Fab")
		)
		(fp_line
			(start 0.12065 -0.305054)
			(end 0.12065 -0.2794)
			(stroke
				(width 0.1)
				(type default)
			)
			(layer "B.Fab")
		)
		(fp_line
			(start -0.120396 0.3048)
			(end -0.120396 0.2794)
			(stroke
				(width 0.1)
				(type default)
			)
			(layer "B.Fab")
		)
		(fp_line
			(start -0.120396 0.2794)
			(end 0.12065 0.2794)
			(stroke
				(width 0.1)
				(type default)
			)
			(layer "B.Fab")
		)
		(fp_line
			(start -0.12065 -0.2794)
			(end -0.12065 -0.3048)
			(stroke
				(width 0.1)
				(type default)
			)
			(layer "B.Fab")
		)
		(fp_line
			(start -0.12065 -0.3048)
			(end -0.67945 -0.3048)
			(stroke
				(width 0.1)
				(type default)
			)
			(layer "B.Fab")
		)
		(fp_line
			(start -0.67945 0.3048)
			(end -0.120396 0.3048)
			(stroke
				(width 0.1)
				(type default)
			)
			(layer "B.Fab")
		)
		(fp_line
			(start -0.67945 -0.3048)
			(end -0.67945 0.3048)
			(stroke
				(width 0.1)
				(type default)
			)
			(layer "B.Fab")
		)
		(pad "1" smd circle
			(at 0.40005 0)
			(size 0 0)
			(layers "B.Cu" "B.Mask" "B.Paste")
			(net "SPI_PEX0_RST_R_N")
		)
		(pad "2" smd circle
			(at -0.40005 0)
			(size 0 0)
			(layers "B.Cu" "B.Mask" "B.Paste")
			(net "SPI_PEX0_RST_N")
		)
	)
	(footprint ""
		(layer "B.Cu")
		(at 298.276518 -111.334042 180)
		(property "Reference" "R291"
			(at 0 0 0)
			(layer "B.SilkS")
			(hide yes)
			(effects
				(font
					(size 1.27 1.27)
				)
				(justify mirror)
			)
		)
		(property "Value" ""
			(at 0 0 0)
			(layer "B.Fab")
			(effects
				(font
					(size 1.27 1.27)
				)
				(justify mirror)
			)
		)
		(duplicate_pad_numbers_are_jumpers no)
		(fp_line
			(start 0.7874 0.4064)
			(end 0.7874 -0.4064)
			(stroke
				(width 0.1524)
				(type default)
			)
			(layer "B.SilkS")
		)
		(fp_line
			(start 0.7874 -0.4064)
			(end -0.7874 -0.4064)
			(stroke
				(width 0.1524)
				(type default)
			)
			(layer "B.SilkS")
		)
		(fp_line
			(start -0.7874 0.4064)
			(end 0.7874 0.4064)
			(stroke
				(width 0.1524)
				(type default)
			)
			(layer "B.SilkS")
		)
		(fp_line
			(start -0.7874 -0.4064)
			(end -0.7874 0.4064)
			(stroke
				(width 0.1524)
				(type default)
			)
			(layer "B.SilkS")
		)
		(fp_line
			(start 0.67945 0.3048)
			(end 0.67945 -0.305054)
			(stroke
				(width 0.1)
				(type default)
			)
			(layer "B.Fab")
		)
		(fp_line
			(start 0.67945 -0.305054)
			(end 0.12065 -0.305054)
			(stroke
				(width 0.1)
				(type default)
			)
			(layer "B.Fab")
		)
		(fp_line
			(start 0.12065 0.3048)
			(end 0.67945 0.3048)
			(stroke
				(width 0.1)
				(type default)
			)
			(layer "B.Fab")
		)
		(fp_line
			(start 0.12065 0.2794)
			(end 0.12065 0.3048)
			(stroke
				(width 0.1)
				(type default)
			)
			(layer "B.Fab")
		)
		(fp_line
			(start 0.12065 -0.2794)
			(end -0.12065 -0.2794)
			(stroke
				(width 0.1)
				(type default)
			)
			(layer "B.Fab")
		)
		(fp_line
			(start 0.12065 -0.305054)
			(end 0.12065 -0.2794)
			(stroke
				(width 0.1)
				(type default)
			)
			(layer "B.Fab")
		)
		(fp_line
			(start -0.120396 0.3048)
			(end -0.120396 0.2794)
			(stroke
				(width 0.1)
				(type default)
			)
			(layer "B.Fab")
		)
		(fp_line
			(start -0.120396 0.2794)
			(end 0.12065 0.2794)
			(stroke
				(width 0.1)
				(type default)
			)
			(layer "B.Fab")
		)
		(fp_line
			(start -0.12065 -0.2794)
			(end -0.12065 -0.3048)
			(stroke
				(width 0.1)
				(type default)
			)
			(layer "B.Fab")
		)
		(fp_line
			(start -0.12065 -0.3048)
			(end -0.67945 -0.3048)
			(stroke
				(width 0.1)
				(type default)
			)
			(layer "B.Fab")
		)
		(fp_line
			(start -0.67945 0.3048)
			(end -0.120396 0.3048)
			(stroke
				(width 0.1)
				(type default)
			)
			(layer "B.Fab")
		)
		(fp_line
			(start -0.67945 -0.3048)
			(end -0.67945 0.3048)
			(stroke
				(width 0.1)
				(type default)
			)
			(layer "B.Fab")
		)
		(pad "1" smd circle
			(at 0.40005 0)
			(size 0 0)
			(layers "B.Cu" "B.Mask" "B.Paste")
			(net "RST_SMB_NIC_MUX_R_N")
		)
		(pad "2" smd circle
			(at -0.40005 0)
			(size 0 0)
			(layers "B.Cu" "B.Mask" "B.Paste")
			(net "RST_SMB_NIC5_MUX_N")
		)
	)
	(footprint ""
		(layer "B.Cu")
		(at 256.351532 -84.604352 180)
		(property "Reference" "C2651"
			(at 0 0 0)
			(layer "B.SilkS")
			(hide yes)
			(effects
				(font
					(size 1.27 1.27)
				)
				(justify mirror)
			)
		)
		(property "Value" ""
			(at 0 0 0)
			(layer "B.Fab")
			(effects
				(font
					(size 1.27 1.27)
				)
				(justify mirror)
			)
		)
		(duplicate_pad_numbers_are_jumpers no)
		(fp_line
			(start 0.7874 0.4064)
			(end 0.7874 -0.4064)
			(stroke
				(width 0.1524)
				(type default)
			)
			(layer "B.SilkS")
		)
		(fp_line
			(start 0.7874 -0.4064)
			(end -0.7874 -0.4064)
			(stroke
				(width 0.1524)
				(type default)
			)
			(layer "B.SilkS")
		)
		(fp_line
			(start -0.7874 0.4064)
			(end 0.7874 0.4064)
			(stroke
				(width 0.1524)
				(type default)
			)
			(layer "B.SilkS")
		)
		(fp_line
			(start -0.7874 -0.4064)
			(end -0.7874 0.4064)
			(stroke
				(width 0.1524)
				(type default)
			)
			(layer "B.SilkS")
		)
		(fp_line
			(start 0.67945 0.3048)
			(end 0.67945 -0.305054)
			(stroke
				(width 0.1)
				(type default)
			)
			(layer "B.Fab")
		)
		(fp_line
			(start 0.67945 -0.305054)
			(end 0.12065 -0.305054)
			(stroke
				(width 0.1)
				(type default)
			)
			(layer "B.Fab")
		)
		(fp_line
			(start 0.12065 0.3048)
			(end 0.67945 0.3048)
			(stroke
				(width 0.1)
				(type default)
			)
			(layer "B.Fab")
		)
		(fp_line
			(start 0.12065 0.2794)
			(end 0.12065 0.3048)
			(stroke
				(width 0.1)
				(type default)
			)
			(layer "B.Fab")
		)
		(fp_line
			(start 0.12065 -0.2794)
			(end -0.12065 -0.2794)
			(stroke
				(width 0.1)
				(type default)
			)
			(layer "B.Fab")
		)
		(fp_line
			(start 0.12065 -0.305054)
			(end 0.12065 -0.2794)
			(stroke
				(width 0.1)
				(type default)
			)
			(layer "B.Fab")
		)
		(fp_line
			(start -0.120396 0.3048)
			(end -0.120396 0.2794)
			(stroke
				(width 0.1)
				(type default)
			)
			(layer "B.Fab")
		)
		(fp_line
			(start -0.120396 0.2794)
			(end 0.12065 0.2794)
			(stroke
				(width 0.1)
				(type default)
			)
			(layer "B.Fab")
		)
		(fp_line
			(start -0.12065 -0.2794)
			(end -0.12065 -0.3048)
			(stroke
				(width 0.1)
				(type default)
			)
			(layer "B.Fab")
		)
		(fp_line
			(start -0.12065 -0.3048)
			(end -0.67945 -0.3048)
			(stroke
				(width 0.1)
				(type default)
			)
			(layer "B.Fab")
		)
		(fp_line
			(start -0.67945 0.3048)
			(end -0.120396 0.3048)
			(stroke
				(width 0.1)
				(type default)
			)
			(layer "B.Fab")
		)
		(fp_line
			(start -0.67945 -0.3048)
			(end -0.67945 0.3048)
			(stroke
				(width 0.1)
				(type default)
			)
			(layer "B.Fab")
		)
		(pad "1" smd circle
			(at 0.40005 0)
			(size 0 0)
			(layers "B.Cu" "B.Mask" "B.Paste")
			(net "P3V3_CLK_GEN_VDDPT_CK440")
		)
		(pad "2" smd circle
			(at -0.40005 0)
			(size 0 0)
			(layers "B.Cu" "B.Mask" "B.Paste")
			(net "GND")
		)
	)
	(footprint ""
		(layer "B.Cu")
		(at 298.499784 -288.299906 90)
		(property "Reference" "C3270"
			(at 0 0 90)
			(layer "B.SilkS")
			(hide yes)
			(effects
				(font
					(size 1.27 1.27)
				)
				(justify mirror)
			)
		)
		(property "Value" ""
			(at 0 0 90)
			(layer "B.Fab")
			(effects
				(font
					(size 1.27 1.27)
				)
				(justify mirror)
			)
		)
		(duplicate_pad_numbers_are_jumpers no)
		(fp_line
			(start 0.299974 -0.150114)
			(end -0.299974 -0.150114)
			(stroke
				(width 0.1)
				(type default)
			)
			(layer "B.Fab")
		)
		(fp_line
			(start -0.299974 -0.150114)
			(end -0.299974 0.150114)
			(stroke
				(width 0.1)
				(type default)
			)
			(layer "B.Fab")
		)
		(fp_line
			(start 0.299974 0.150114)
			(end 0.299974 -0.150114)
			(stroke
				(width 0.1)
				(type default)
			)
			(layer "B.Fab")
		)
		(fp_line
			(start -0.299974 0.150114)
			(end 0.299974 0.150114)
			(stroke
				(width 0.1)
				(type default)
			)
			(layer "B.Fab")
		)
		(pad "1" smd rect
			(at 0.2667 0 270)
			(size 0.3048 0.381)
			(layers "B.Cu" "B.Mask" "B.Paste")
			(net "P1V25_PEX2")
		)
		(pad "2" smd rect
			(at -0.2667 0 270)
			(size 0.3048 0.381)
			(layers "B.Cu" "B.Mask" "B.Paste")
			(net "GND")
		)
	)
	(footprint ""
		(layer "B.Cu")
		(at 130.168904 -293.660068 90)
		(property "Reference" "PC104"
			(at 0 0 90)
			(layer "B.SilkS")
			(hide yes)
			(effects
				(font
					(size 1.27 1.27)
				)
				(justify mirror)
			)
		)
		(property "Value" ""
			(at 0 0 90)
			(layer "B.Fab")
			(effects
				(font
					(size 1.27 1.27)
				)
				(justify mirror)
			)
		)
		(duplicate_pad_numbers_are_jumpers no)
		(fp_line
			(start 4.84378 -2.150618)
			(end 4.53898 -2.150618)
			(stroke
				(width 0.1524)
				(type default)
			)
			(layer "B.SilkS")
		)
		(fp_line
			(start 4.84378 -2.150618)
			(end 4.842256 2.163064)
			(stroke
				(width 0.1524)
				(type default)
			)
			(layer "B.SilkS")
		)
		(fp_line
			(start 4.69138 -2.150618)
			(end 4.692396 2.161032)
			(stroke
				(width 0.1524)
				(type default)
			)
			(layer "B.SilkS")
		)
		(fp_line
			(start 4.53898 -2.150618)
			(end 4.539742 2.152142)
			(stroke
				(width 0.1524)
				(type default)
			)
			(layer "B.SilkS")
		)
		(fp_line
			(start 4.53898 -2.15011)
			(end -4.53898 -2.15011)
			(stroke
				(width 0.1524)
				(type default)
			)
			(layer "B.SilkS")
		)
		(fp_line
			(start -4.53898 -2.15011)
			(end -4.53898 2.15011)
			(stroke
				(width 0.1524)
				(type default)
			)
			(layer "B.SilkS")
		)
		(fp_line
			(start 4.53898 2.15011)
			(end 4.53898 -2.15011)
			(stroke
				(width 0.1524)
				(type default)
			)
			(layer "B.SilkS")
		)
		(fp_line
			(start -4.53898 2.15011)
			(end 4.53898 2.15011)
			(stroke
				(width 0.1524)
				(type default)
			)
			(layer "B.SilkS")
		)
		(fp_line
			(start 4.83108 2.150364)
			(end 4.447794 2.149348)
			(stroke
				(width 0.1524)
				(type default)
			)
			(layer "B.SilkS")
		)
		(fp_line
			(start 3.64998 -2.15011)
			(end -3.64998 -2.15011)
			(stroke
				(width 0.1)
				(type default)
			)
			(layer "B.Fab")
		)
		(fp_line
			(start -3.64998 -2.15011)
			(end -3.64998 2.15011)
			(stroke
				(width 0.1)
				(type default)
			)
			(layer "B.Fab")
		)
		(fp_line
			(start 3.64998 2.15011)
			(end 3.64998 -2.15011)
			(stroke
				(width 0.1)
				(type default)
			)
			(layer "B.Fab")
		)
		(fp_line
			(start -3.64998 2.15011)
			(end 3.64998 2.15011)
			(stroke
				(width 0.1)
				(type default)
			)
			(layer "B.Fab")
		)
		(fp_text user "+"
			(at 6.214872 -0.337058 90)
			(unlocked yes)
			(layer "B.SilkS")
			(effects
				(font
					(size 1.905 1.4224)
					(thickness 0.1524)
				)
				(justify left mirror)
			)
		)
		(fp_text user "-"
			(at -4.313174 -0.094488 90)
			(unlocked yes)
			(layer "B.SilkS")
			(effects
				(font
					(size 1.905 1.4224)
					(thickness 0.1524)
				)
				(justify left mirror)
			)
		)
		(fp_text user "+"
			(at 6.214872 -0.337058 90)
			(unlocked yes)
			(layer "B.Fab")
			(effects
				(font
					(size 1.905 1.4224)
					(thickness 0.1524)
				)
				(justify left mirror)
			)
		)
		(fp_text user "-"
			(at -4.313174 -0.094488 90)
			(unlocked yes)
			(layer "B.Fab")
			(effects
				(font
					(size 1.905 1.4224)
					(thickness 0.1524)
				)
				(justify left mirror)
			)
		)
		(pad "1" smd rect
			(at 3.199892 0 270)
			(size 2.413 2.8194)
			(layers "B.Cu" "B.Mask" "B.Paste")
			(net "P0V8_PEX1")
		)
		(pad "2" smd rect
			(at -3.199892 0 270)
			(size 2.413 2.8194)
			(layers "B.Cu" "B.Mask" "B.Paste")
			(net "GND")
		)
	)
	(footprint ""
		(layer "B.Cu")
		(at 104.178608 -357.366062 -90)
		(property "Reference" "C4178"
			(at 0 0 90)
			(layer "B.SilkS")
			(hide yes)
			(effects
				(font
					(size 1.27 1.27)
				)
				(justify mirror)
			)
		)
		(property "Value" ""
			(at 0 0 90)
			(layer "B.Fab")
			(effects
				(font
					(size 1.27 1.27)
				)
				(justify mirror)
			)
		)
		(duplicate_pad_numbers_are_jumpers no)
		(fp_line
			(start -0.7874 0.4064)
			(end 0.7874 0.4064)
			(stroke
				(width 0.1524)
				(type default)
			)
			(layer "B.SilkS")
		)
		(fp_line
			(start 0.7874 0.4064)
			(end 0.7874 -0.4064)
			(stroke
				(width 0.1524)
				(type default)
			)
			(layer "B.SilkS")
		)
		(fp_line
			(start -0.7874 -0.4064)
			(end -0.7874 0.4064)
			(stroke
				(width 0.1524)
				(type default)
			)
			(layer "B.SilkS")
		)
		(fp_line
			(start 0.7874 -0.4064)
			(end -0.7874 -0.4064)
			(stroke
				(width 0.1524)
				(type default)
			)
			(layer "B.SilkS")
		)
		(fp_line
			(start -0.67945 0.3048)
			(end -0.120396 0.3048)
			(stroke
				(width 0.1)
				(type default)
			)
			(layer "B.Fab")
		)
		(fp_line
			(start -0.120396 0.3048)
			(end -0.120396 0.2794)
			(stroke
				(width 0.1)
				(type default)
			)
			(layer "B.Fab")
		)
		(fp_line
			(start 0.12065 0.3048)
			(end 0.67945 0.3048)
			(stroke
				(width 0.1)
				(type default)
			)
			(layer "B.Fab")
		)
		(fp_line
			(start 0.67945 0.3048)
			(end 0.67945 -0.305054)
			(stroke
				(width 0.1)
				(type default)
			)
			(layer "B.Fab")
		)
		(fp_line
			(start -0.120396 0.2794)
			(end 0.12065 0.2794)
			(stroke
				(width 0.1)
				(type default)
			)
			(layer "B.Fab")
		)
		(fp_line
			(start 0.12065 0.2794)
			(end 0.12065 0.3048)
			(stroke
				(width 0.1)
				(type default)
			)
			(layer "B.Fab")
		)
		(fp_line
			(start -0.12065 -0.2794)
			(end -0.12065 -0.3048)
			(stroke
				(width 0.1)
				(type default)
			)
			(layer "B.Fab")
		)
		(fp_line
			(start 0.12065 -0.2794)
			(end -0.12065 -0.2794)
			(stroke
				(width 0.1)
				(type default)
			)
			(layer "B.Fab")
		)
		(fp_line
			(start -0.67945 -0.3048)
			(end -0.67945 0.3048)
			(stroke
				(width 0.1)
				(type default)
			)
			(layer "B.Fab")
		)
		(fp_line
			(start -0.12065 -0.3048)
			(end -0.67945 -0.3048)
			(stroke
				(width 0.1)
				(type default)
			)
			(layer "B.Fab")
		)
		(fp_line
			(start 0.12065 -0.305054)
			(end 0.12065 -0.2794)
			(stroke
				(width 0.1)
				(type default)
			)
			(layer "B.Fab")
		)
		(fp_line
			(start 0.67945 -0.305054)
			(end 0.12065 -0.305054)
			(stroke
				(width 0.1)
				(type default)
			)
			(layer "B.Fab")
		)
		(pad "1" smd circle
			(at 0.40005 0 90)
			(size 0 0)
			(layers "B.Cu" "B.Mask" "B.Paste")
			(net "P3V3_CLK_BUFFER_9ZXL0451E_S3_VZX3P3")
		)
		(pad "2" smd circle
			(at -0.40005 0 90)
			(size 0 0)
			(layers "B.Cu" "B.Mask" "B.Paste")
			(net "GND")
		)
	)
	(footprint ""
		(layer "B.Cu")
		(at 176.699926 -299.699934 -90)
		(property "Reference" "C1492"
			(at 0 0 90)
			(layer "B.SilkS")
			(hide yes)
			(effects
				(font
					(size 1.27 1.27)
				)
				(justify mirror)
			)
		)
		(property "Value" ""
			(at 0 0 90)
			(layer "B.Fab")
			(effects
				(font
					(size 1.27 1.27)
				)
				(justify mirror)
			)
		)
		(duplicate_pad_numbers_are_jumpers no)
		(fp_line
			(start -0.299974 0.150114)
			(end 0.299974 0.150114)
			(stroke
				(width 0.1)
				(type default)
			)
			(layer "B.Fab")
		)
		(fp_line
			(start 0.299974 0.150114)
			(end 0.299974 -0.150114)
			(stroke
				(width 0.1)
				(type default)
			)
			(layer "B.Fab")
		)
		(fp_line
			(start -0.299974 -0.150114)
			(end -0.299974 0.150114)
			(stroke
				(width 0.1)
				(type default)
			)
			(layer "B.Fab")
		)
		(fp_line
			(start 0.299974 -0.150114)
			(end -0.299974 -0.150114)
			(stroke
				(width 0.1)
				(type default)
			)
			(layer "B.Fab")
		)
		(pad "1" smd rect
			(at 0.2667 0 90)
			(size 0.3048 0.381)
			(layers "B.Cu" "B.Mask" "B.Paste")
			(net "P0V8_SERDES_VDDA_PEX1")
		)
		(pad "2" smd rect
			(at -0.2667 0 90)
			(size 0.3048 0.381)
			(layers "B.Cu" "B.Mask" "B.Paste")
			(net "GND")
		)
	)
	(footprint ""
		(layer "B.Cu")
		(at 298.499784 -301.599854 -90)
		(property "Reference" "C1692"
			(at 0 0 90)
			(layer "B.SilkS")
			(hide yes)
			(effects
				(font
					(size 1.27 1.27)
				)
				(justify mirror)
			)
		)
		(property "Value" ""
			(at 0 0 90)
			(layer "B.Fab")
			(effects
				(font
					(size 1.27 1.27)
				)
				(justify mirror)
			)
		)
		(duplicate_pad_numbers_are_jumpers no)
		(fp_line
			(start -0.299974 0.150114)
			(end 0.299974 0.150114)
			(stroke
				(width 0.1)
				(type default)
			)
			(layer "B.Fab")
		)
		(fp_line
			(start 0.299974 0.150114)
			(end 0.299974 -0.150114)
			(stroke
				(width 0.1)
				(type default)
			)
			(layer "B.Fab")
		)
		(fp_line
			(start -0.299974 -0.150114)
			(end -0.299974 0.150114)
			(stroke
				(width 0.1)
				(type default)
			)
			(layer "B.Fab")
		)
		(fp_line
			(start 0.299974 -0.150114)
			(end -0.299974 -0.150114)
			(stroke
				(width 0.1)
				(type default)
			)
			(layer "B.Fab")
		)
		(pad "1" smd rect
			(at 0.2667 0 90)
			(size 0.3048 0.381)
			(layers "B.Cu" "B.Mask" "B.Paste")
			(net "P0V8_SERDES_VDDA_PEX2")
		)
		(pad "2" smd rect
			(at -0.2667 0 90)
			(size 0.3048 0.381)
			(layers "B.Cu" "B.Mask" "B.Paste")
			(net "GND")
		)
	)
	(footprint ""
		(layer "B.Cu")
		(at 287.574736 -297.79976 90)
		(property "Reference" "C1664"
			(at 0 0 90)
			(layer "B.SilkS")
			(hide yes)
			(effects
				(font
					(size 1.27 1.27)
				)
				(justify mirror)
			)
		)
		(property "Value" ""
			(at 0 0 90)
			(layer "B.Fab")
			(effects
				(font
					(size 1.27 1.27)
				)
				(justify mirror)
			)
		)
		(duplicate_pad_numbers_are_jumpers no)
		(fp_line
			(start 0.299974 -0.150114)
			(end -0.299974 -0.150114)
			(stroke
				(width 0.1)
				(type default)
			)
			(layer "B.Fab")
		)
		(fp_line
			(start -0.299974 -0.150114)
			(end -0.299974 0.150114)
			(stroke
				(width 0.1)
				(type default)
			)
			(layer "B.Fab")
		)
		(fp_line
			(start 0.299974 0.150114)
			(end 0.299974 -0.150114)
			(stroke
				(width 0.1)
				(type default)
			)
			(layer "B.Fab")
		)
		(fp_line
			(start -0.299974 0.150114)
			(end 0.299974 0.150114)
			(stroke
				(width 0.1)
				(type default)
			)
			(layer "B.Fab")
		)
		(pad "1" smd rect
			(at 0.2667 0 270)
			(size 0.3048 0.381)
			(layers "B.Cu" "B.Mask" "B.Paste")
			(net "P0V8_PEX2")
		)
		(pad "2" smd rect
			(at -0.2667 0 270)
			(size 0.3048 0.381)
			(layers "B.Cu" "B.Mask" "B.Paste")
			(net "GND")
		)
	)
	(footprint ""
		(layer "B.Cu")
		(at 337.488022 -319.420494 -90)
		(property "Reference" "R5793"
			(at 0 0 90)
			(layer "B.SilkS")
			(hide yes)
			(effects
				(font
					(size 1.27 1.27)
				)
				(justify mirror)
			)
		)
		(property "Value" ""
			(at 0 0 90)
			(layer "B.Fab")
			(effects
				(font
					(size 1.27 1.27)
				)
				(justify mirror)
			)
		)
		(duplicate_pad_numbers_are_jumpers no)
		(fp_line
			(start -2.576322 1.1303)
			(end 2.576322 1.1303)
			(stroke
				(width 0.1524)
				(type default)
			)
			(layer "B.SilkS")
		)
		(fp_line
			(start 2.576322 1.1303)
			(end 2.576322 -1.1303)
			(stroke
				(width 0.1524)
				(type default)
			)
			(layer "B.SilkS")
		)
		(fp_line
			(start -2.576322 -1.1303)
			(end -2.576322 1.1303)
			(stroke
				(width 0.1524)
				(type default)
			)
			(layer "B.SilkS")
		)
		(fp_line
			(start 2.576322 -1.1303)
			(end -2.576322 -1.1303)
			(stroke
				(width 0.1524)
				(type default)
			)
			(layer "B.SilkS")
		)
		(fp_line
			(start -1.649984 0.899922)
			(end -1.649984 -0.899922)
			(stroke
				(width 0.1)
				(type default)
			)
			(layer "B.Fab")
		)
		(fp_line
			(start 1.649984 0.899922)
			(end -1.649984 0.899922)
			(stroke
				(width 0.1)
				(type default)
			)
			(layer "B.Fab")
		)
		(fp_line
			(start -1.649984 -0.899922)
			(end 1.649984 -0.899922)
			(stroke
				(width 0.1)
				(type default)
			)
			(layer "B.Fab")
		)
		(fp_line
			(start 1.649984 -0.899922)
			(end 1.649984 0.899922)
			(stroke
				(width 0.1)
				(type default)
			)
			(layer "B.Fab")
		)
		(pad "1A" smd rect
			(at 1.700022 0 90)
			(size 1.4986 2.0066)
			(layers "B.Cu" "B.Mask" "B.Paste")
			(net "P0V8_PEX2")
		)
		(pad "1B" smd rect
			(at 1.077722 0 90)
			(size 0.254 0.508)
			(layers "B.Cu" "B.Mask" "B.Paste")
			(net "P0V8_PEX2")
		)
		(pad "2A" smd rect
			(at -1.700022 0 90)
			(size 1.4986 2.0066)
			(layers "B.Cu" "B.Mask" "B.Paste")
			(net "P0V8_SERDES_VDDA_PEX2")
		)
		(pad "2B" smd rect
			(at -1.077722 0 90)
			(size 0.254 0.508)
			(layers "B.Cu" "B.Mask" "B.Paste")
			(net "P0V8_SERDES_VDDA_PEX2")
		)
	)
	(footprint ""
		(layer "B.Cu")
		(at 243.3193 -205.19517 180)
		(property "Reference" "C2016"
			(at 0 0 0)
			(layer "B.SilkS")
			(hide yes)
			(effects
				(font
					(size 1.27 1.27)
				)
				(justify mirror)
			)
		)
		(property "Value" ""
			(at 0 0 0)
			(layer "B.Fab")
			(effects
				(font
					(size 1.27 1.27)
				)
				(justify mirror)
			)
		)
		(duplicate_pad_numbers_are_jumpers no)
		(fp_line
			(start 1.2954 0.5842)
			(end 1.2954 -0.5842)
			(stroke
				(width 0.1524)
				(type default)
			)
			(layer "B.SilkS")
		)
		(fp_line
			(start 1.2954 -0.5842)
			(end -1.2954 -0.5842)
			(stroke
				(width 0.1524)
				(type default)
			)
			(layer "B.SilkS")
		)
		(fp_line
			(start -1.2954 0.5842)
			(end 1.2954 0.5842)
			(stroke
				(width 0.1524)
				(type default)
			)
			(layer "B.SilkS")
		)
		(fp_line
			(start -1.2954 -0.5842)
			(end -1.2954 0.5842)
			(stroke
				(width 0.1524)
				(type default)
			)
			(layer "B.SilkS")
		)
		(fp_line
			(start 1.1938 0.4064)
			(end 1.1938 -0.4064)
			(stroke
				(width 0.1)
				(type default)
			)
			(layer "B.Fab")
		)
		(fp_line
			(start 1.1938 -0.4064)
			(end 0.8636 -0.4064)
			(stroke
				(width 0.1)
				(type default)
			)
			(layer "B.Fab")
		)
		(fp_line
			(start 0.8636 0.4572)
			(end 0.8636 0.4064)
			(stroke
				(width 0.1)
				(type default)
			)
			(layer "B.Fab")
		)
		(fp_line
			(start 0.8636 0.4064)
			(end 1.1938 0.4064)
			(stroke
				(width 0.1)
				(type default)
			)
			(layer "B.Fab")
		)
		(fp_line
			(start 0.8636 -0.4064)
			(end 0.8636 -0.4572)
			(stroke
				(width 0.1)
				(type default)
			)
			(layer "B.Fab")
		)
		(fp_line
			(start 0.8636 -0.4572)
			(end -0.8636 -0.4572)
			(stroke
				(width 0.1)
				(type default)
			)
			(layer "B.Fab")
		)
		(fp_line
			(start -0.8636 0.4572)
			(end 0.8636 0.4572)
			(stroke
				(width 0.1)
				(type default)
			)
			(layer "B.Fab")
		)
		(fp_line
			(start -0.8636 0.4064)
			(end -0.8636 0.4572)
			(stroke
				(width 0.1)
				(type default)
			)
			(layer "B.Fab")
		)
		(fp_line
			(start -0.8636 -0.4064)
			(end -1.1938 -0.4064)
			(stroke
				(width 0.1)
				(type default)
			)
			(layer "B.Fab")
		)
		(fp_line
			(start -0.8636 -0.4572)
			(end -0.8636 -0.4064)
			(stroke
				(width 0.1)
				(type default)
			)
			(layer "B.Fab")
		)
		(fp_line
			(start -1.1938 0.4064)
			(end -0.8636 0.4064)
			(stroke
				(width 0.1)
				(type default)
			)
			(layer "B.Fab")
		)
		(fp_line
			(start -1.1938 -0.4064)
			(end -1.1938 0.4064)
			(stroke
				(width 0.1)
				(type default)
			)
			(layer "B.Fab")
		)
		(pad "1" smd rect
			(at 0.7366 0 90)
			(size 0.7112 0.8128)
			(layers "B.Cu" "B.Mask" "B.Paste")
			(net "P1V2_AUX")
		)
		(pad "2" smd rect
			(at -0.7366 0 90)
			(size 0.7112 0.8128)
			(layers "B.Cu" "B.Mask" "B.Paste")
			(net "GND")
		)
	)
	(footprint ""
		(layer "B.Cu")
		(at 351.645982 -143.51 180)
		(property "Reference" "R4792"
			(at 0 0 0)
			(layer "B.SilkS")
			(hide yes)
			(effects
				(font
					(size 1.27 1.27)
				)
				(justify mirror)
			)
		)
		(property "Value" ""
			(at 0 0 0)
			(layer "B.Fab")
			(effects
				(font
					(size 1.27 1.27)
				)
				(justify mirror)
			)
		)
		(duplicate_pad_numbers_are_jumpers no)
		(fp_line
			(start 0.7874 0.4064)
			(end 0.7874 -0.4064)
			(stroke
				(width 0.1524)
				(type default)
			)
			(layer "B.SilkS")
		)
		(fp_line
			(start 0.7874 -0.4064)
			(end -0.7874 -0.4064)
			(stroke
				(width 0.1524)
				(type default)
			)
			(layer "B.SilkS")
		)
		(fp_line
			(start -0.7874 0.4064)
			(end 0.7874 0.4064)
			(stroke
				(width 0.1524)
				(type default)
			)
			(layer "B.SilkS")
		)
		(fp_line
			(start -0.7874 -0.4064)
			(end -0.7874 0.4064)
			(stroke
				(width 0.1524)
				(type default)
			)
			(layer "B.SilkS")
		)
		(fp_line
			(start 0.67945 0.3048)
			(end 0.67945 -0.305054)
			(stroke
				(width 0.1)
				(type default)
			)
			(layer "B.Fab")
		)
		(fp_line
			(start 0.67945 -0.305054)
			(end 0.12065 -0.305054)
			(stroke
				(width 0.1)
				(type default)
			)
			(layer "B.Fab")
		)
		(fp_line
			(start 0.12065 0.3048)
			(end 0.67945 0.3048)
			(stroke
				(width 0.1)
				(type default)
			)
			(layer "B.Fab")
		)
		(fp_line
			(start 0.12065 0.2794)
			(end 0.12065 0.3048)
			(stroke
				(width 0.1)
				(type default)
			)
			(layer "B.Fab")
		)
		(fp_line
			(start 0.12065 -0.2794)
			(end -0.12065 -0.2794)
			(stroke
				(width 0.1)
				(type default)
			)
			(layer "B.Fab")
		)
		(fp_line
			(start 0.12065 -0.305054)
			(end 0.12065 -0.2794)
			(stroke
				(width 0.1)
				(type default)
			)
			(layer "B.Fab")
		)
		(fp_line
			(start -0.120396 0.3048)
			(end -0.120396 0.2794)
			(stroke
				(width 0.1)
				(type default)
			)
			(layer "B.Fab")
		)
		(fp_line
			(start -0.120396 0.2794)
			(end 0.12065 0.2794)
			(stroke
				(width 0.1)
				(type default)
			)
			(layer "B.Fab")
		)
		(fp_line
			(start -0.12065 -0.2794)
			(end -0.12065 -0.3048)
			(stroke
				(width 0.1)
				(type default)
			)
			(layer "B.Fab")
		)
		(fp_line
			(start -0.12065 -0.3048)
			(end -0.67945 -0.3048)
			(stroke
				(width 0.1)
				(type default)
			)
			(layer "B.Fab")
		)
		(fp_line
			(start -0.67945 0.3048)
			(end -0.120396 0.3048)
			(stroke
				(width 0.1)
				(type default)
			)
			(layer "B.Fab")
		)
		(fp_line
			(start -0.67945 -0.3048)
			(end -0.67945 0.3048)
			(stroke
				(width 0.1)
				(type default)
			)
			(layer "B.Fab")
		)
		(pad "1" smd circle
			(at 0.40005 0)
			(size 0 0)
			(layers "B.Cu" "B.Mask" "B.Paste")
			(net "P3V3_AUX")
		)
		(pad "2" smd circle
			(at -0.40005 0)
			(size 0 0)
			(layers "B.Cu" "B.Mask" "B.Paste")
			(net "NIC7_PEX_PWR_EN_R")
		)
	)
	(footprint ""
		(layer "B.Cu")
		(at 129.780284 -284.796738 -90)
		(property "Reference" "PC114"
			(at 0 0 90)
			(layer "B.SilkS")
			(hide yes)
			(effects
				(font
					(size 1.27 1.27)
				)
				(justify mirror)
			)
		)
		(property "Value" ""
			(at 0 0 90)
			(layer "B.Fab")
			(effects
				(font
					(size 1.27 1.27)
				)
				(justify mirror)
			)
		)
		(duplicate_pad_numbers_are_jumpers no)
		(fp_line
			(start -1.524 0.762)
			(end 1.524 0.762)
			(stroke
				(width 0.1524)
				(type default)
			)
			(layer "B.SilkS")
		)
		(fp_line
			(start 1.524 0.762)
			(end 1.524 -0.762)
			(stroke
				(width 0.1524)
				(type default)
			)
			(layer "B.SilkS")
		)
		(fp_line
			(start -1.524 -0.762)
			(end -1.524 0.762)
			(stroke
				(width 0.1524)
				(type default)
			)
			(layer "B.SilkS")
		)
		(fp_line
			(start 1.524 -0.762)
			(end -1.524 -0.762)
			(stroke
				(width 0.1524)
				(type default)
			)
			(layer "B.SilkS")
		)
		(fp_line
			(start -1.1049 0.724916)
			(end -1.1049 -0.724916)
			(stroke
				(width 0.1)
				(type default)
			)
			(layer "B.Fab")
		)
		(fp_line
			(start 1.1049 0.724916)
			(end -1.1049 0.724916)
			(stroke
				(width 0.1)
				(type default)
			)
			(layer "B.Fab")
		)
		(fp_line
			(start -1.1049 -0.724916)
			(end 1.1049 -0.724916)
			(stroke
				(width 0.1)
				(type default)
			)
			(layer "B.Fab")
		)
		(fp_line
			(start 1.1049 -0.724916)
			(end 1.1049 0.724916)
			(stroke
				(width 0.1)
				(type default)
			)
			(layer "B.Fab")
		)
		(pad "1" smd rect
			(at 0.889 0 270)
			(size 1.016 1.27)
			(layers "B.Cu" "B.Mask" "B.Paste")
			(net "SW_P12V_P0V8_PEX1_FLT")
		)
		(pad "2" smd rect
			(at -0.889 0 270)
			(size 1.016 1.27)
			(layers "B.Cu" "B.Mask" "B.Paste")
			(net "GND")
		)
	)
	(footprint ""
		(layer "B.Cu")
		(at 405.145748 -296.37482)
		(property "Reference" "C1875"
			(at 0 0 0)
			(layer "B.SilkS")
			(hide yes)
			(effects
				(font
					(size 1.27 1.27)
				)
				(justify mirror)
			)
		)
		(property "Value" ""
			(at 0 0 0)
			(layer "B.Fab")
			(effects
				(font
					(size 1.27 1.27)
				)
				(justify mirror)
			)
		)
		(duplicate_pad_numbers_are_jumpers no)
		(fp_line
			(start -0.299974 -0.150114)
			(end -0.299974 0.150114)
			(stroke
				(width 0.1)
				(type default)
			)
			(layer "B.Fab")
		)
		(fp_line
			(start -0.299974 0.150114)
			(end 0.299974 0.150114)
			(stroke
				(width 0.1)
				(type default)
			)
			(layer "B.Fab")
		)
		(fp_line
			(start 0.299974 -0.150114)
			(end -0.299974 -0.150114)
			(stroke
				(width 0.1)
				(type default)
			)
			(layer "B.Fab")
		)
		(fp_line
			(start 0.299974 0.150114)
			(end 0.299974 -0.150114)
			(stroke
				(width 0.1)
				(type default)
			)
			(layer "B.Fab")
		)
		(pad "1" smd rect
			(at 0.2667 0 180)
			(size 0.3048 0.381)
			(layers "B.Cu" "B.Mask" "B.Paste")
			(net "P0V8_PEX3")
		)
		(pad "2" smd rect
			(at -0.2667 0 180)
			(size 0.3048 0.381)
			(layers "B.Cu" "B.Mask" "B.Paste")
			(net "GND")
		)
	)
	(footprint ""
		(layer "B.Cu")
		(at 109.682788 -285.580328 -90)
		(property "Reference" "PR7175"
			(at 0 0 90)
			(layer "B.SilkS")
			(hide yes)
			(effects
				(font
					(size 1.27 1.27)
				)
				(justify mirror)
			)
		)
		(property "Value" ""
			(at 0 0 90)
			(layer "B.Fab")
			(effects
				(font
					(size 1.27 1.27)
				)
				(justify mirror)
			)
		)
		(duplicate_pad_numbers_are_jumpers no)
		(fp_line
			(start -0.7874 0.4064)
			(end 0.7874 0.4064)
			(stroke
				(width 0.1524)
				(type default)
			)
			(layer "B.SilkS")
		)
		(fp_line
			(start 0.7874 0.4064)
			(end 0.7874 -0.4064)
			(stroke
				(width 0.1524)
				(type default)
			)
			(layer "B.SilkS")
		)
		(fp_line
			(start -0.7874 -0.4064)
			(end -0.7874 0.4064)
			(stroke
				(width 0.1524)
				(type default)
			)
			(layer "B.SilkS")
		)
		(fp_line
			(start 0.7874 -0.4064)
			(end -0.7874 -0.4064)
			(stroke
				(width 0.1524)
				(type default)
			)
			(layer "B.SilkS")
		)
		(fp_line
			(start -0.67945 0.3048)
			(end -0.120396 0.3048)
			(stroke
				(width 0.1)
				(type default)
			)
			(layer "B.Fab")
		)
		(fp_line
			(start -0.120396 0.3048)
			(end -0.120396 0.2794)
			(stroke
				(width 0.1)
				(type default)
			)
			(layer "B.Fab")
		)
		(fp_line
			(start 0.12065 0.3048)
			(end 0.67945 0.3048)
			(stroke
				(width 0.1)
				(type default)
			)
			(layer "B.Fab")
		)
		(fp_line
			(start 0.67945 0.3048)
			(end 0.67945 -0.305054)
			(stroke
				(width 0.1)
				(type default)
			)
			(layer "B.Fab")
		)
		(fp_line
			(start -0.120396 0.2794)
			(end 0.12065 0.2794)
			(stroke
				(width 0.1)
				(type default)
			)
			(layer "B.Fab")
		)
		(fp_line
			(start 0.12065 0.2794)
			(end 0.12065 0.3048)
			(stroke
				(width 0.1)
				(type default)
			)
			(layer "B.Fab")
		)
		(fp_line
			(start -0.12065 -0.2794)
			(end -0.12065 -0.3048)
			(stroke
				(width 0.1)
				(type default)
			)
			(layer "B.Fab")
		)
		(fp_line
			(start 0.12065 -0.2794)
			(end -0.12065 -0.2794)
			(stroke
				(width 0.1)
				(type default)
			)
			(layer "B.Fab")
		)
		(fp_line
			(start -0.67945 -0.3048)
			(end -0.67945 0.3048)
			(stroke
				(width 0.1)
				(type default)
			)
			(layer "B.Fab")
		)
		(fp_line
			(start -0.12065 -0.3048)
			(end -0.67945 -0.3048)
			(stroke
				(width 0.1)
				(type default)
			)
			(layer "B.Fab")
		)
		(fp_line
			(start 0.12065 -0.305054)
			(end 0.12065 -0.2794)
			(stroke
				(width 0.1)
				(type default)
			)
			(layer "B.Fab")
		)
		(fp_line
			(start 0.67945 -0.305054)
			(end 0.12065 -0.305054)
			(stroke
				(width 0.1)
				(type default)
			)
			(layer "B.Fab")
		)
		(pad "1" smd circle
			(at 0.40005 0 90)
			(size 0 0)
			(layers "B.Cu" "B.Mask" "B.Paste")
			(net "P0V8_PEX0_PVCC")
		)
		(pad "2" smd circle
			(at -0.40005 0 90)
			(size 0 0)
			(layers "B.Cu" "B.Mask" "B.Paste")
			(net "P5V_AUX")
		)
	)
	(footprint ""
		(layer "B.Cu")
		(at 407.949908 -299.699934 -90)
		(property "Reference" "C1976"
			(at 0 0 90)
			(layer "B.SilkS")
			(hide yes)
			(effects
				(font
					(size 1.27 1.27)
				)
				(justify mirror)
			)
		)
		(property "Value" ""
			(at 0 0 90)
			(layer "B.Fab")
			(effects
				(font
					(size 1.27 1.27)
				)
				(justify mirror)
			)
		)
		(duplicate_pad_numbers_are_jumpers no)
		(fp_line
			(start -0.299974 0.150114)
			(end 0.299974 0.150114)
			(stroke
				(width 0.1)
				(type default)
			)
			(layer "B.Fab")
		)
		(fp_line
			(start 0.299974 0.150114)
			(end 0.299974 -0.150114)
			(stroke
				(width 0.1)
				(type default)
			)
			(layer "B.Fab")
		)
		(fp_line
			(start -0.299974 -0.150114)
			(end -0.299974 0.150114)
			(stroke
				(width 0.1)
				(type default)
			)
			(layer "B.Fab")
		)
		(fp_line
			(start 0.299974 -0.150114)
			(end -0.299974 -0.150114)
			(stroke
				(width 0.1)
				(type default)
			)
			(layer "B.Fab")
		)
		(pad "1" smd rect
			(at 0.2667 0 90)
			(size 0.3048 0.381)
			(layers "B.Cu" "B.Mask" "B.Paste")
			(net "P0V8_SERDES_VDDA_PEX3")
		)
		(pad "2" smd rect
			(at -0.2667 0 90)
			(size 0.3048 0.381)
			(layers "B.Cu" "B.Mask" "B.Paste")
			(net "GND")
		)
	)
	(footprint ""
		(layer "B.Cu")
		(at 219.301314 -98.61423 180)
		(property "Reference" "R5621"
			(at 0 0 0)
			(layer "B.SilkS")
			(hide yes)
			(effects
				(font
					(size 1.27 1.27)
				)
				(justify mirror)
			)
		)
		(property "Value" ""
			(at 0 0 0)
			(layer "B.Fab")
			(effects
				(font
					(size 1.27 1.27)
				)
				(justify mirror)
			)
		)
		(duplicate_pad_numbers_are_jumpers no)
		(fp_line
			(start 0.7874 0.4064)
			(end 0.7874 -0.4064)
			(stroke
				(width 0.1524)
				(type default)
			)
			(layer "B.SilkS")
		)
		(fp_line
			(start 0.7874 -0.4064)
			(end -0.7874 -0.4064)
			(stroke
				(width 0.1524)
				(type default)
			)
			(layer "B.SilkS")
		)
		(fp_line
			(start -0.7874 0.4064)
			(end 0.7874 0.4064)
			(stroke
				(width 0.1524)
				(type default)
			)
			(layer "B.SilkS")
		)
		(fp_line
			(start -0.7874 -0.4064)
			(end -0.7874 0.4064)
			(stroke
				(width 0.1524)
				(type default)
			)
			(layer "B.SilkS")
		)
		(fp_line
			(start 0.67945 0.3048)
			(end 0.67945 -0.305054)
			(stroke
				(width 0.1)
				(type default)
			)
			(layer "B.Fab")
		)
		(fp_line
			(start 0.67945 -0.305054)
			(end 0.12065 -0.305054)
			(stroke
				(width 0.1)
				(type default)
			)
			(layer "B.Fab")
		)
		(fp_line
			(start 0.12065 0.3048)
			(end 0.67945 0.3048)
			(stroke
				(width 0.1)
				(type default)
			)
			(layer "B.Fab")
		)
		(fp_line
			(start 0.12065 0.2794)
			(end 0.12065 0.3048)
			(stroke
				(width 0.1)
				(type default)
			)
			(layer "B.Fab")
		)
		(fp_line
			(start 0.12065 -0.2794)
			(end -0.12065 -0.2794)
			(stroke
				(width 0.1)
				(type default)
			)
			(layer "B.Fab")
		)
		(fp_line
			(start 0.12065 -0.305054)
			(end 0.12065 -0.2794)
			(stroke
				(width 0.1)
				(type default)
			)
			(layer "B.Fab")
		)
		(fp_line
			(start -0.120396 0.3048)
			(end -0.120396 0.2794)
			(stroke
				(width 0.1)
				(type default)
			)
			(layer "B.Fab")
		)
		(fp_line
			(start -0.120396 0.2794)
			(end 0.12065 0.2794)
			(stroke
				(width 0.1)
				(type default)
			)
			(layer "B.Fab")
		)
		(fp_line
			(start -0.12065 -0.2794)
			(end -0.12065 -0.3048)
			(stroke
				(width 0.1)
				(type default)
			)
			(layer "B.Fab")
		)
		(fp_line
			(start -0.12065 -0.3048)
			(end -0.67945 -0.3048)
			(stroke
				(width 0.1)
				(type default)
			)
			(layer "B.Fab")
		)
		(fp_line
			(start -0.67945 0.3048)
			(end -0.120396 0.3048)
			(stroke
				(width 0.1)
				(type default)
			)
			(layer "B.Fab")
		)
		(fp_line
			(start -0.67945 -0.3048)
			(end -0.67945 0.3048)
			(stroke
				(width 0.1)
				(type default)
			)
			(layer "B.Fab")
		)
		(pad "1" smd circle
			(at 0.40005 0)
			(size 0 0)
			(layers "B.Cu" "B.Mask" "B.Paste")
			(net "NIC3_ADC_A0")
		)
		(pad "2" smd circle
			(at -0.40005 0)
			(size 0 0)
			(layers "B.Cu" "B.Mask" "B.Paste")
			(net "SMB_NIC3_ADC_SCL")
		)
	)
	(footprint ""
		(layer "B.Cu")
		(at 173.850046 -299.699934 -90)
		(property "Reference" "C1463"
			(at 0 0 90)
			(layer "B.SilkS")
			(hide yes)
			(effects
				(font
					(size 1.27 1.27)
				)
				(justify mirror)
			)
		)
		(property "Value" ""
			(at 0 0 90)
			(layer "B.Fab")
			(effects
				(font
					(size 1.27 1.27)
				)
				(justify mirror)
			)
		)
		(duplicate_pad_numbers_are_jumpers no)
		(fp_line
			(start -0.299974 0.150114)
			(end 0.299974 0.150114)
			(stroke
				(width 0.1)
				(type default)
			)
			(layer "B.Fab")
		)
		(fp_line
			(start 0.299974 0.150114)
			(end 0.299974 -0.150114)
			(stroke
				(width 0.1)
				(type default)
			)
			(layer "B.Fab")
		)
		(fp_line
			(start -0.299974 -0.150114)
			(end -0.299974 0.150114)
			(stroke
				(width 0.1)
				(type default)
			)
			(layer "B.Fab")
		)
		(fp_line
			(start 0.299974 -0.150114)
			(end -0.299974 -0.150114)
			(stroke
				(width 0.1)
				(type default)
			)
			(layer "B.Fab")
		)
		(pad "1" smd rect
			(at 0.2667 0 90)
			(size 0.3048 0.381)
			(layers "B.Cu" "B.Mask" "B.Paste")
			(net "P0V8_SERDES_VDDA_PEX1")
		)
		(pad "2" smd rect
			(at -0.2667 0 90)
			(size 0.3048 0.381)
			(layers "B.Cu" "B.Mask" "B.Paste")
			(net "GND")
		)
	)
	(footprint ""
		(layer "B.Cu")
		(at 112.672114 -258.004564 90)
		(property "Reference" "PR93"
			(at 0 0 90)
			(layer "B.SilkS")
			(hide yes)
			(effects
				(font
					(size 1.27 1.27)
				)
				(justify mirror)
			)
		)
		(property "Value" ""
			(at 0 0 90)
			(layer "B.Fab")
			(effects
				(font
					(size 1.27 1.27)
				)
				(justify mirror)
			)
		)
		(duplicate_pad_numbers_are_jumpers no)
		(fp_line
			(start 0.7874 -0.4064)
			(end -0.7874 -0.4064)
			(stroke
				(width 0.1524)
				(type default)
			)
			(layer "B.SilkS")
		)
		(fp_line
			(start -0.7874 -0.4064)
			(end -0.7874 0.4064)
			(stroke
				(width 0.1524)
				(type default)
			)
			(layer "B.SilkS")
		)
		(fp_line
			(start 0.7874 0.4064)
			(end 0.7874 -0.4064)
			(stroke
				(width 0.1524)
				(type default)
			)
			(layer "B.SilkS")
		)
		(fp_line
			(start -0.7874 0.4064)
			(end 0.7874 0.4064)
			(stroke
				(width 0.1524)
				(type default)
			)
			(layer "B.SilkS")
		)
		(fp_line
			(start 0.67945 -0.305054)
			(end 0.12065 -0.305054)
			(stroke
				(width 0.1)
				(type default)
			)
			(layer "B.Fab")
		)
		(fp_line
			(start 0.12065 -0.305054)
			(end 0.12065 -0.2794)
			(stroke
				(width 0.1)
				(type default)
			)
			(layer "B.Fab")
		)
		(fp_line
			(start -0.12065 -0.3048)
			(end -0.67945 -0.3048)
			(stroke
				(width 0.1)
				(type default)
			)
			(layer "B.Fab")
		)
		(fp_line
			(start -0.67945 -0.3048)
			(end -0.67945 0.3048)
			(stroke
				(width 0.1)
				(type default)
			)
			(layer "B.Fab")
		)
		(fp_line
			(start 0.12065 -0.2794)
			(end -0.12065 -0.2794)
			(stroke
				(width 0.1)
				(type default)
			)
			(layer "B.Fab")
		)
		(fp_line
			(start -0.12065 -0.2794)
			(end -0.12065 -0.3048)
			(stroke
				(width 0.1)
				(type default)
			)
			(layer "B.Fab")
		)
		(fp_line
			(start 0.12065 0.2794)
			(end 0.12065 0.3048)
			(stroke
				(width 0.1)
				(type default)
			)
			(layer "B.Fab")
		)
		(fp_line
			(start -0.120396 0.2794)
			(end 0.12065 0.2794)
			(stroke
				(width 0.1)
				(type default)
			)
			(layer "B.Fab")
		)
		(fp_line
			(start 0.67945 0.3048)
			(end 0.67945 -0.305054)
			(stroke
				(width 0.1)
				(type default)
			)
			(layer "B.Fab")
		)
		(fp_line
			(start 0.12065 0.3048)
			(end 0.67945 0.3048)
			(stroke
				(width 0.1)
				(type default)
			)
			(layer "B.Fab")
		)
		(fp_line
			(start -0.120396 0.3048)
			(end -0.120396 0.2794)
			(stroke
				(width 0.1)
				(type default)
			)
			(layer "B.Fab")
		)
		(fp_line
			(start -0.67945 0.3048)
			(end -0.120396 0.3048)
			(stroke
				(width 0.1)
				(type default)
			)
			(layer "B.Fab")
		)
		(pad "1" smd circle
			(at 0.40005 0 270)
			(size 0 0)
			(layers "B.Cu" "B.Mask" "B.Paste")
			(net "P12V_AUX")
		)
		(pad "2" smd circle
			(at -0.40005 0 270)
			(size 0 0)
			(layers "B.Cu" "B.Mask" "B.Paste")
			(net "P0V8_PEX0_IINSEN")
		)
	)
	(footprint ""
		(layer "B.Cu")
		(at 237.631986 -356.165658)
		(property "Reference" "PR7145"
			(at 0 0 0)
			(layer "B.SilkS")
			(hide yes)
			(effects
				(font
					(size 1.27 1.27)
				)
				(justify mirror)
			)
		)
		(property "Value" ""
			(at 0 0 0)
			(layer "B.Fab")
			(effects
				(font
					(size 1.27 1.27)
				)
				(justify mirror)
			)
		)
		(duplicate_pad_numbers_are_jumpers no)
		(fp_line
			(start -0.7874 -0.4064)
			(end -0.7874 0.4064)
			(stroke
				(width 0.1524)
				(type default)
			)
			(layer "B.SilkS")
		)
		(fp_line
			(start -0.7874 0.4064)
			(end 0.7874 0.4064)
			(stroke
				(width 0.1524)
				(type default)
			)
			(layer "B.SilkS")
		)
		(fp_line
			(start 0.7874 -0.4064)
			(end -0.7874 -0.4064)
			(stroke
				(width 0.1524)
				(type default)
			)
			(layer "B.SilkS")
		)
		(fp_line
			(start 0.7874 0.4064)
			(end 0.7874 -0.4064)
			(stroke
				(width 0.1524)
				(type default)
			)
			(layer "B.SilkS")
		)
		(fp_line
			(start -0.67945 -0.3048)
			(end -0.67945 0.3048)
			(stroke
				(width 0.1)
				(type default)
			)
			(layer "B.Fab")
		)
		(fp_line
			(start -0.67945 0.3048)
			(end -0.120396 0.3048)
			(stroke
				(width 0.1)
				(type default)
			)
			(layer "B.Fab")
		)
		(fp_line
			(start -0.12065 -0.3048)
			(end -0.67945 -0.3048)
			(stroke
				(width 0.1)
				(type default)
			)
			(layer "B.Fab")
		)
		(fp_line
			(start -0.12065 -0.2794)
			(end -0.12065 -0.3048)
			(stroke
				(width 0.1)
				(type default)
			)
			(layer "B.Fab")
		)
		(fp_line
			(start -0.120396 0.2794)
			(end 0.12065 0.2794)
			(stroke
				(width 0.1)
				(type default)
			)
			(layer "B.Fab")
		)
		(fp_line
			(start -0.120396 0.3048)
			(end -0.120396 0.2794)
			(stroke
				(width 0.1)
				(type default)
			)
			(layer "B.Fab")
		)
		(fp_line
			(start 0.12065 -0.305054)
			(end 0.12065 -0.2794)
			(stroke
				(width 0.1)
				(type default)
			)
			(layer "B.Fab")
		)
		(fp_line
			(start 0.12065 -0.2794)
			(end -0.12065 -0.2794)
			(stroke
				(width 0.1)
				(type default)
			)
			(layer "B.Fab")
		)
		(fp_line
			(start 0.12065 0.2794)
			(end 0.12065 0.3048)
			(stroke
				(width 0.1)
				(type default)
			)
			(layer "B.Fab")
		)
		(fp_line
			(start 0.12065 0.3048)
			(end 0.67945 0.3048)
			(stroke
				(width 0.1)
				(type default)
			)
			(layer "B.Fab")
		)
		(fp_line
			(start 0.67945 -0.305054)
			(end 0.12065 -0.305054)
			(stroke
				(width 0.1)
				(type default)
			)
			(layer "B.Fab")
		)
		(fp_line
			(start 0.67945 0.3048)
			(end 0.67945 -0.305054)
			(stroke
				(width 0.1)
				(type default)
			)
			(layer "B.Fab")
		)
		(pad "1" smd circle
			(at 0.40005 0 180)
			(size 0 0)
			(layers "B.Cu" "B.Mask" "B.Paste")
			(net "P12V_HSC_ADC_P")
		)
		(pad "2" smd circle
			(at -0.40005 0 180)
			(size 0 0)
			(layers "B.Cu" "B.Mask" "B.Paste")
			(net "P12V_HSC_SENSE2_R1_P")
		)
	)
	(footprint ""
		(layer "B.Cu")
		(at 283.299916 -292.099746 90)
		(property "Reference" "C1685"
			(at 0 0 90)
			(layer "B.SilkS")
			(hide yes)
			(effects
				(font
					(size 1.27 1.27)
				)
				(justify mirror)
			)
		)
		(property "Value" ""
			(at 0 0 90)
			(layer "B.Fab")
			(effects
				(font
					(size 1.27 1.27)
				)
				(justify mirror)
			)
		)
		(duplicate_pad_numbers_are_jumpers no)
		(fp_line
			(start 0.299974 -0.150114)
			(end -0.299974 -0.150114)
			(stroke
				(width 0.1)
				(type default)
			)
			(layer "B.Fab")
		)
		(fp_line
			(start -0.299974 -0.150114)
			(end -0.299974 0.150114)
			(stroke
				(width 0.1)
				(type default)
			)
			(layer "B.Fab")
		)
		(fp_line
			(start 0.299974 0.150114)
			(end 0.299974 -0.150114)
			(stroke
				(width 0.1)
				(type default)
			)
			(layer "B.Fab")
		)
		(fp_line
			(start -0.299974 0.150114)
			(end 0.299974 0.150114)
			(stroke
				(width 0.1)
				(type default)
			)
			(layer "B.Fab")
		)
		(pad "1" smd rect
			(at 0.2667 0 270)
			(size 0.3048 0.381)
			(layers "B.Cu" "B.Mask" "B.Paste")
			(net "P0V8_SERDES_VDDA_PEX2")
		)
		(pad "2" smd rect
			(at -0.2667 0 270)
			(size 0.3048 0.381)
			(layers "B.Cu" "B.Mask" "B.Paste")
			(net "GND")
		)
	)
	(footprint ""
		(layer "B.Cu")
		(at 344.8939 -223.187006 180)
		(property "Reference" "C2034"
			(at 0 0 0)
			(layer "B.SilkS")
			(hide yes)
			(effects
				(font
					(size 1.27 1.27)
				)
				(justify mirror)
			)
		)
		(property "Value" ""
			(at 0 0 0)
			(layer "B.Fab")
			(effects
				(font
					(size 1.27 1.27)
				)
				(justify mirror)
			)
		)
		(duplicate_pad_numbers_are_jumpers no)
		(fp_line
			(start 0.69215 0.2921)
			(end 0.69215 -0.2921)
			(stroke
				(width 0.1524)
				(type default)
			)
			(layer "B.SilkS")
		)
		(fp_line
			(start 0.69215 -0.2921)
			(end -0.69215 -0.2921)
			(stroke
				(width 0.1524)
				(type default)
			)
			(layer "B.SilkS")
		)
		(fp_line
			(start -0.69215 0.2921)
			(end 0.69215 0.2921)
			(stroke
				(width 0.1524)
				(type default)
			)
			(layer "B.SilkS")
		)
		(fp_line
			(start -0.69215 -0.2921)
			(end -0.69215 0.2921)
			(stroke
				(width 0.1524)
				(type default)
			)
			(layer "B.SilkS")
		)
		(fp_line
			(start 0.51435 0.2794)
			(end 0.51435 -0.2794)
			(stroke
				(width 0.1)
				(type default)
			)
			(layer "B.Fab")
		)
		(fp_line
			(start 0.51435 -0.2794)
			(end -0.51435 -0.2794)
			(stroke
				(width 0.1)
				(type default)
			)
			(layer "B.Fab")
		)
		(fp_line
			(start -0.51435 0.2794)
			(end 0.51435 0.2794)
			(stroke
				(width 0.1)
				(type default)
			)
			(layer "B.Fab")
		)
		(fp_line
			(start -0.51435 -0.2794)
			(end -0.51435 0.2794)
			(stroke
				(width 0.1)
				(type default)
			)
			(layer "B.Fab")
		)
		(pad "1" smd circle
			(at 0.40005 0)
			(size 0 0)
			(layers "B.Cu" "B.Mask" "B.Paste")
			(net "P3V3_FPGA_VCCIO0")
		)
		(pad "2" smd circle
			(at -0.40005 0)
			(size 0 0)
			(layers "B.Cu" "B.Mask" "B.Paste")
			(net "GND")
		)
		(zone
			(layer "B.Cu")
			(hatch none 0.5)
			(connect_pads
				(clearance 0)
			)
			(min_thickness 0.25)
			(keepout
				(tracks not_allowed)
				(vias allowed)
				(pads allowed)
				(copperpour not_allowed)
				(footprints allowed)
			)
			(placement
				(enabled no)
				(sheetname "")
			)
			(fill
				(thermal_gap 0.5)
				(thermal_bridge_width 0.5)
				(island_removal_mode 0)
			)
			(polygon
				(pts
					(xy 344.7034 -223.274636) (xy 344.79484 -223.332802) (xy 344.99423 -223.332802) (xy 345.0844 -223.274636)
					(xy 345.0844 -223.099376) (xy 344.99423 -223.040956) (xy 344.79484 -223.040956) (xy 344.7034 -223.099122)
				)
			)
		)
	)
	(footprint ""
		(layer "B.Cu")
		(at 300.012354 -234.958636 90)
		(property "Reference" "R1864"
			(at 0 0 90)
			(layer "B.SilkS")
			(hide yes)
			(effects
				(font
					(size 1.27 1.27)
				)
				(justify mirror)
			)
		)
		(property "Value" ""
			(at 0 0 90)
			(layer "B.Fab")
			(effects
				(font
					(size 1.27 1.27)
				)
				(justify mirror)
			)
		)
		(duplicate_pad_numbers_are_jumpers no)
		(fp_line
			(start 0.7874 -0.4064)
			(end -0.7874 -0.4064)
			(stroke
				(width 0.1524)
				(type default)
			)
			(layer "B.SilkS")
		)
		(fp_line
			(start -0.7874 -0.4064)
			(end -0.7874 0.4064)
			(stroke
				(width 0.1524)
				(type default)
			)
			(layer "B.SilkS")
		)
		(fp_line
			(start 0.7874 0.4064)
			(end 0.7874 -0.4064)
			(stroke
				(width 0.1524)
				(type default)
			)
			(layer "B.SilkS")
		)
		(fp_line
			(start -0.7874 0.4064)
			(end 0.7874 0.4064)
			(stroke
				(width 0.1524)
				(type default)
			)
			(layer "B.SilkS")
		)
		(fp_line
			(start 0.67945 -0.305054)
			(end 0.12065 -0.305054)
			(stroke
				(width 0.1)
				(type default)
			)
			(layer "B.Fab")
		)
		(fp_line
			(start 0.12065 -0.305054)
			(end 0.12065 -0.2794)
			(stroke
				(width 0.1)
				(type default)
			)
			(layer "B.Fab")
		)
		(fp_line
			(start -0.12065 -0.3048)
			(end -0.67945 -0.3048)
			(stroke
				(width 0.1)
				(type default)
			)
			(layer "B.Fab")
		)
		(fp_line
			(start -0.67945 -0.3048)
			(end -0.67945 0.3048)
			(stroke
				(width 0.1)
				(type default)
			)
			(layer "B.Fab")
		)
		(fp_line
			(start 0.12065 -0.2794)
			(end -0.12065 -0.2794)
			(stroke
				(width 0.1)
				(type default)
			)
			(layer "B.Fab")
		)
		(fp_line
			(start -0.12065 -0.2794)
			(end -0.12065 -0.3048)
			(stroke
				(width 0.1)
				(type default)
			)
			(layer "B.Fab")
		)
		(fp_line
			(start 0.12065 0.2794)
			(end 0.12065 0.3048)
			(stroke
				(width 0.1)
				(type default)
			)
			(layer "B.Fab")
		)
		(fp_line
			(start -0.120396 0.2794)
			(end 0.12065 0.2794)
			(stroke
				(width 0.1)
				(type default)
			)
			(layer "B.Fab")
		)
		(fp_line
			(start 0.67945 0.3048)
			(end 0.67945 -0.305054)
			(stroke
				(width 0.1)
				(type default)
			)
			(layer "B.Fab")
		)
		(fp_line
			(start 0.12065 0.3048)
			(end 0.67945 0.3048)
			(stroke
				(width 0.1)
				(type default)
			)
			(layer "B.Fab")
		)
		(fp_line
			(start -0.120396 0.3048)
			(end -0.120396 0.2794)
			(stroke
				(width 0.1)
				(type default)
			)
			(layer "B.Fab")
		)
		(fp_line
			(start -0.67945 0.3048)
			(end -0.120396 0.3048)
			(stroke
				(width 0.1)
				(type default)
			)
			(layer "B.Fab")
		)
		(pad "1" smd circle
			(at 0.40005 0 270)
			(size 0 0)
			(layers "B.Cu" "B.Mask" "B.Paste")
			(net "RST_GPU_PERST_0_N")
		)
		(pad "2" smd circle
			(at -0.40005 0 270)
			(size 0 0)
			(layers "B.Cu" "B.Mask" "B.Paste")
			(net "RST_GPU_PERST_0_R_N")
		)
	)
	(footprint ""
		(layer "B.Cu")
		(at 276.649688 -299.224954)
		(property "Reference" "C3355"
			(at 0 0 0)
			(layer "B.SilkS")
			(hide yes)
			(effects
				(font
					(size 1.27 1.27)
				)
				(justify mirror)
			)
		)
		(property "Value" ""
			(at 0 0 0)
			(layer "B.Fab")
			(effects
				(font
					(size 1.27 1.27)
				)
				(justify mirror)
			)
		)
		(duplicate_pad_numbers_are_jumpers no)
		(fp_line
			(start -0.299974 -0.150114)
			(end -0.299974 0.150114)
			(stroke
				(width 0.1)
				(type default)
			)
			(layer "B.Fab")
		)
		(fp_line
			(start -0.299974 0.150114)
			(end 0.299974 0.150114)
			(stroke
				(width 0.1)
				(type default)
			)
			(layer "B.Fab")
		)
		(fp_line
			(start 0.299974 -0.150114)
			(end -0.299974 -0.150114)
			(stroke
				(width 0.1)
				(type default)
			)
			(layer "B.Fab")
		)
		(fp_line
			(start 0.299974 0.150114)
			(end 0.299974 -0.150114)
			(stroke
				(width 0.1)
				(type default)
			)
			(layer "B.Fab")
		)
		(pad "1" smd rect
			(at 0.2667 0 180)
			(size 0.3048 0.381)
			(layers "B.Cu" "B.Mask" "B.Paste")
			(net "P1V8_VDDA_PEX2")
		)
		(pad "2" smd rect
			(at -0.2667 0 180)
			(size 0.3048 0.381)
			(layers "B.Cu" "B.Mask" "B.Paste")
			(net "GND")
		)
	)
	(footprint ""
		(layer "B.Cu")
		(at 131.389882 -183.790082)
		(property "Reference" "R1082"
			(at 0 0 0)
			(layer "B.SilkS")
			(hide yes)
			(effects
				(font
					(size 1.27 1.27)
				)
				(justify mirror)
			)
		)
		(property "Value" ""
			(at 0 0 0)
			(layer "B.Fab")
			(effects
				(font
					(size 1.27 1.27)
				)
				(justify mirror)
			)
		)
		(duplicate_pad_numbers_are_jumpers no)
		(fp_line
			(start -1.2954 -0.5842)
			(end -1.2954 0.5842)
			(stroke
				(width 0.1524)
				(type default)
			)
			(layer "B.SilkS")
		)
		(fp_line
			(start -1.2954 0.5842)
			(end 1.2954 0.5842)
			(stroke
				(width 0.1524)
				(type default)
			)
			(layer "B.SilkS")
		)
		(fp_line
			(start 1.2954 -0.5842)
			(end -1.2954 -0.5842)
			(stroke
				(width 0.1524)
				(type default)
			)
			(layer "B.SilkS")
		)
		(fp_line
			(start 1.2954 0.5842)
			(end 1.2954 -0.5842)
			(stroke
				(width 0.1524)
				(type default)
			)
			(layer "B.SilkS")
		)
		(fp_line
			(start -1.1938 -0.406654)
			(end -1.1938 0.4064)
			(stroke
				(width 0.1)
				(type default)
			)
			(layer "B.Fab")
		)
		(fp_line
			(start -1.1938 0.4064)
			(end -0.8636 0.4064)
			(stroke
				(width 0.1)
				(type default)
			)
			(layer "B.Fab")
		)
		(fp_line
			(start -0.8636 -0.4572)
			(end -0.8636 -0.406654)
			(stroke
				(width 0.1)
				(type default)
			)
			(layer "B.Fab")
		)
		(fp_line
			(start -0.8636 -0.406654)
			(end -1.1938 -0.406654)
			(stroke
				(width 0.1)
				(type default)
			)
			(layer "B.Fab")
		)
		(fp_line
			(start -0.8636 0.4064)
			(end -0.8636 0.4572)
			(stroke
				(width 0.1)
				(type default)
			)
			(layer "B.Fab")
		)
		(fp_line
			(start -0.8636 0.4572)
			(end 0.8636 0.4572)
			(stroke
				(width 0.1)
				(type default)
			)
			(layer "B.Fab")
		)
		(fp_line
			(start 0.8636 -0.4572)
			(end -0.8636 -0.4572)
			(stroke
				(width 0.1)
				(type default)
			)
			(layer "B.Fab")
		)
		(fp_line
			(start 0.8636 -0.406654)
			(end 0.8636 -0.4572)
			(stroke
				(width 0.1)
				(type default)
			)
			(layer "B.Fab")
		)
		(fp_line
			(start 0.8636 0.4064)
			(end 1.1938 0.4064)
			(stroke
				(width 0.1)
				(type default)
			)
			(layer "B.Fab")
		)
		(fp_line
			(start 0.8636 0.4318)
			(end 0.8636 0.4064)
			(stroke
				(width 0.1)
				(type default)
			)
			(layer "B.Fab")
		)
		(fp_line
			(start 0.8636 0.4572)
			(end 0.8636 0.4318)
			(stroke
				(width 0.1)
				(type default)
			)
			(layer "B.Fab")
		)
		(fp_line
			(start 1.1938 -0.406654)
			(end 0.8636 -0.406654)
			(stroke
				(width 0.1)
				(type default)
			)
			(layer "B.Fab")
		)
		(fp_line
			(start 1.1938 0.4064)
			(end 1.1938 -0.406654)
			(stroke
				(width 0.1)
				(type default)
			)
			(layer "B.Fab")
		)
		(pad "1" smd rect
			(at 0.7366 0 270)
			(size 0.7112 0.8128)
			(layers "B.Cu" "B.Mask" "B.Paste")
			(net "P3V3_DB2000QL_VDDA")
		)
		(pad "2" smd rect
			(at -0.7366 0 270)
			(size 0.7112 0.8128)
			(layers "B.Cu" "B.Mask" "B.Paste")
			(net "P3V3_DB2000QL_FB_VDD")
		)
	)
	(footprint ""
		(layer "B.Cu")
		(at 289.94989 -290.199826 90)
		(property "Reference" "C1750"
			(at 0 0 90)
			(layer "B.SilkS")
			(hide yes)
			(effects
				(font
					(size 1.27 1.27)
				)
				(justify mirror)
			)
		)
		(property "Value" ""
			(at 0 0 90)
			(layer "B.Fab")
			(effects
				(font
					(size 1.27 1.27)
				)
				(justify mirror)
			)
		)
		(duplicate_pad_numbers_are_jumpers no)
		(fp_line
			(start 0.299974 -0.150114)
			(end -0.299974 -0.150114)
			(stroke
				(width 0.1)
				(type default)
			)
			(layer "B.Fab")
		)
		(fp_line
			(start -0.299974 -0.150114)
			(end -0.299974 0.150114)
			(stroke
				(width 0.1)
				(type default)
			)
			(layer "B.Fab")
		)
		(fp_line
			(start 0.299974 0.150114)
			(end 0.299974 -0.150114)
			(stroke
				(width 0.1)
				(type default)
			)
			(layer "B.Fab")
		)
		(fp_line
			(start -0.299974 0.150114)
			(end 0.299974 0.150114)
			(stroke
				(width 0.1)
				(type default)
			)
			(layer "B.Fab")
		)
		(pad "1" smd rect
			(at 0.2667 0 270)
			(size 0.3048 0.381)
			(layers "B.Cu" "B.Mask" "B.Paste")
			(net "P0V8_SERDES_VDDA_PEX2")
		)
		(pad "2" smd rect
			(at -0.2667 0 270)
			(size 0.3048 0.381)
			(layers "B.Cu" "B.Mask" "B.Paste")
			(net "GND")
		)
	)
	(footprint ""
		(layer "B.Cu")
		(at 109.543088 -352.812604)
		(property "Reference" "R6380"
			(at 0 0 0)
			(layer "B.SilkS")
			(hide yes)
			(effects
				(font
					(size 1.27 1.27)
				)
				(justify mirror)
			)
		)
		(property "Value" ""
			(at 0 0 0)
			(layer "B.Fab")
			(effects
				(font
					(size 1.27 1.27)
				)
				(justify mirror)
			)
		)
		(duplicate_pad_numbers_are_jumpers no)
		(fp_line
			(start -0.7874 -0.4064)
			(end -0.7874 0.4064)
			(stroke
				(width 0.1524)
				(type default)
			)
			(layer "B.SilkS")
		)
		(fp_line
			(start -0.7874 0.4064)
			(end 0.7874 0.4064)
			(stroke
				(width 0.1524)
				(type default)
			)
			(layer "B.SilkS")
		)
		(fp_line
			(start 0.7874 -0.4064)
			(end -0.7874 -0.4064)
			(stroke
				(width 0.1524)
				(type default)
			)
			(layer "B.SilkS")
		)
		(fp_line
			(start 0.7874 0.4064)
			(end 0.7874 -0.4064)
			(stroke
				(width 0.1524)
				(type default)
			)
			(layer "B.SilkS")
		)
		(fp_line
			(start -0.67945 -0.3048)
			(end -0.67945 0.3048)
			(stroke
				(width 0.1)
				(type default)
			)
			(layer "B.Fab")
		)
		(fp_line
			(start -0.67945 0.3048)
			(end -0.120396 0.3048)
			(stroke
				(width 0.1)
				(type default)
			)
			(layer "B.Fab")
		)
		(fp_line
			(start -0.12065 -0.3048)
			(end -0.67945 -0.3048)
			(stroke
				(width 0.1)
				(type default)
			)
			(layer "B.Fab")
		)
		(fp_line
			(start -0.12065 -0.2794)
			(end -0.12065 -0.3048)
			(stroke
				(width 0.1)
				(type default)
			)
			(layer "B.Fab")
		)
		(fp_line
			(start -0.120396 0.2794)
			(end 0.12065 0.2794)
			(stroke
				(width 0.1)
				(type default)
			)
			(layer "B.Fab")
		)
		(fp_line
			(start -0.120396 0.3048)
			(end -0.120396 0.2794)
			(stroke
				(width 0.1)
				(type default)
			)
			(layer "B.Fab")
		)
		(fp_line
			(start 0.12065 -0.305054)
			(end 0.12065 -0.2794)
			(stroke
				(width 0.1)
				(type default)
			)
			(layer "B.Fab")
		)
		(fp_line
			(start 0.12065 -0.2794)
			(end -0.12065 -0.2794)
			(stroke
				(width 0.1)
				(type default)
			)
			(layer "B.Fab")
		)
		(fp_line
			(start 0.12065 0.2794)
			(end 0.12065 0.3048)
			(stroke
				(width 0.1)
				(type default)
			)
			(layer "B.Fab")
		)
		(fp_line
			(start 0.12065 0.3048)
			(end 0.67945 0.3048)
			(stroke
				(width 0.1)
				(type default)
			)
			(layer "B.Fab")
		)
		(fp_line
			(start 0.67945 -0.305054)
			(end 0.12065 -0.305054)
			(stroke
				(width 0.1)
				(type default)
			)
			(layer "B.Fab")
		)
		(fp_line
			(start 0.67945 0.3048)
			(end 0.67945 -0.305054)
			(stroke
				(width 0.1)
				(type default)
			)
			(layer "B.Fab")
		)
		(pad "1" smd circle
			(at 0.40005 0 180)
			(size 0 0)
			(layers "B.Cu" "B.Mask" "B.Paste")
			(net "CLK_100M_DB800ZL_PEX3_S3_R_DP")
		)
		(pad "2" smd circle
			(at -0.40005 0 180)
			(size 0 0)
			(layers "B.Cu" "B.Mask" "B.Paste")
			(net "CLK_100M_DB800ZL_PEX3_S3_DP")
		)
	)
	(footprint ""
		(layer "B.Cu")
		(at 411.750002 -301.599854 -90)
		(property "Reference" "C1980"
			(at 0 0 90)
			(layer "B.SilkS")
			(hide yes)
			(effects
				(font
					(size 1.27 1.27)
				)
				(justify mirror)
			)
		)
		(property "Value" ""
			(at 0 0 90)
			(layer "B.Fab")
			(effects
				(font
					(size 1.27 1.27)
				)
				(justify mirror)
			)
		)
		(duplicate_pad_numbers_are_jumpers no)
		(fp_line
			(start -0.299974 0.150114)
			(end 0.299974 0.150114)
			(stroke
				(width 0.1)
				(type default)
			)
			(layer "B.Fab")
		)
		(fp_line
			(start 0.299974 0.150114)
			(end 0.299974 -0.150114)
			(stroke
				(width 0.1)
				(type default)
			)
			(layer "B.Fab")
		)
		(fp_line
			(start -0.299974 -0.150114)
			(end -0.299974 0.150114)
			(stroke
				(width 0.1)
				(type default)
			)
			(layer "B.Fab")
		)
		(fp_line
			(start 0.299974 -0.150114)
			(end -0.299974 -0.150114)
			(stroke
				(width 0.1)
				(type default)
			)
			(layer "B.Fab")
		)
		(pad "1" smd rect
			(at 0.2667 0 90)
			(size 0.3048 0.381)
			(layers "B.Cu" "B.Mask" "B.Paste")
			(net "P0V8_SERDES_VDDA_PEX3")
		)
		(pad "2" smd rect
			(at -0.2667 0 90)
			(size 0.3048 0.381)
			(layers "B.Cu" "B.Mask" "B.Paste")
			(net "GND")
		)
	)
	(footprint ""
		(layer "B.Cu")
		(at 168.150032 -288.299906 90)
		(property "Reference" "C3098"
			(at 0 0 90)
			(layer "B.SilkS")
			(hide yes)
			(effects
				(font
					(size 1.27 1.27)
				)
				(justify mirror)
			)
		)
		(property "Value" ""
			(at 0 0 90)
			(layer "B.Fab")
			(effects
				(font
					(size 1.27 1.27)
				)
				(justify mirror)
			)
		)
		(duplicate_pad_numbers_are_jumpers no)
		(fp_line
			(start 0.299974 -0.150114)
			(end -0.299974 -0.150114)
			(stroke
				(width 0.1)
				(type default)
			)
			(layer "B.Fab")
		)
		(fp_line
			(start -0.299974 -0.150114)
			(end -0.299974 0.150114)
			(stroke
				(width 0.1)
				(type default)
			)
			(layer "B.Fab")
		)
		(fp_line
			(start 0.299974 0.150114)
			(end 0.299974 -0.150114)
			(stroke
				(width 0.1)
				(type default)
			)
			(layer "B.Fab")
		)
		(fp_line
			(start -0.299974 0.150114)
			(end 0.299974 0.150114)
			(stroke
				(width 0.1)
				(type default)
			)
			(layer "B.Fab")
		)
		(pad "1" smd rect
			(at 0.2667 0 270)
			(size 0.3048 0.381)
			(layers "B.Cu" "B.Mask" "B.Paste")
			(net "P1V25_PEX1")
		)
		(pad "2" smd rect
			(at -0.2667 0 270)
			(size 0.3048 0.381)
			(layers "B.Cu" "B.Mask" "B.Paste")
			(net "GND")
		)
	)
	(footprint ""
		(layer "B.Cu")
		(at 330.729336 -219.452952 180)
		(property "Reference" "R5640"
			(at 0 0 0)
			(layer "B.SilkS")
			(hide yes)
			(effects
				(font
					(size 1.27 1.27)
				)
				(justify mirror)
			)
		)
		(property "Value" ""
			(at 0 0 0)
			(layer "B.Fab")
			(effects
				(font
					(size 1.27 1.27)
				)
				(justify mirror)
			)
		)
		(duplicate_pad_numbers_are_jumpers no)
		(fp_line
			(start 1.2954 0.5842)
			(end 1.2954 -0.5842)
			(stroke
				(width 0.1524)
				(type default)
			)
			(layer "B.SilkS")
		)
		(fp_line
			(start 1.2954 -0.5842)
			(end -1.2954 -0.5842)
			(stroke
				(width 0.1524)
				(type default)
			)
			(layer "B.SilkS")
		)
		(fp_line
			(start -1.2954 0.5842)
			(end 1.2954 0.5842)
			(stroke
				(width 0.1524)
				(type default)
			)
			(layer "B.SilkS")
		)
		(fp_line
			(start -1.2954 -0.5842)
			(end -1.2954 0.5842)
			(stroke
				(width 0.1524)
				(type default)
			)
			(layer "B.SilkS")
		)
		(fp_line
			(start 1.1938 0.4064)
			(end 1.1938 -0.406654)
			(stroke
				(width 0.1)
				(type default)
			)
			(layer "B.Fab")
		)
		(fp_line
			(start 1.1938 -0.406654)
			(end 0.8636 -0.406654)
			(stroke
				(width 0.1)
				(type default)
			)
			(layer "B.Fab")
		)
		(fp_line
			(start 0.8636 0.4572)
			(end 0.8636 0.4318)
			(stroke
				(width 0.1)
				(type default)
			)
			(layer "B.Fab")
		)
		(fp_line
			(start 0.8636 0.4318)
			(end 0.8636 0.4064)
			(stroke
				(width 0.1)
				(type default)
			)
			(layer "B.Fab")
		)
		(fp_line
			(start 0.8636 0.4064)
			(end 1.1938 0.4064)
			(stroke
				(width 0.1)
				(type default)
			)
			(layer "B.Fab")
		)
		(fp_line
			(start 0.8636 -0.406654)
			(end 0.8636 -0.4572)
			(stroke
				(width 0.1)
				(type default)
			)
			(layer "B.Fab")
		)
		(fp_line
			(start 0.8636 -0.4572)
			(end -0.8636 -0.4572)
			(stroke
				(width 0.1)
				(type default)
			)
			(layer "B.Fab")
		)
		(fp_line
			(start -0.8636 0.4572)
			(end 0.8636 0.4572)
			(stroke
				(width 0.1)
				(type default)
			)
			(layer "B.Fab")
		)
		(fp_line
			(start -0.8636 0.4064)
			(end -0.8636 0.4572)
			(stroke
				(width 0.1)
				(type default)
			)
			(layer "B.Fab")
		)
		(fp_line
			(start -0.8636 -0.406654)
			(end -1.1938 -0.406654)
			(stroke
				(width 0.1)
				(type default)
			)
			(layer "B.Fab")
		)
		(fp_line
			(start -0.8636 -0.4572)
			(end -0.8636 -0.406654)
			(stroke
				(width 0.1)
				(type default)
			)
			(layer "B.Fab")
		)
		(fp_line
			(start -1.1938 0.4064)
			(end -0.8636 0.4064)
			(stroke
				(width 0.1)
				(type default)
			)
			(layer "B.Fab")
		)
		(fp_line
			(start -1.1938 -0.406654)
			(end -1.1938 0.4064)
			(stroke
				(width 0.1)
				(type default)
			)
			(layer "B.Fab")
		)
		(pad "1" smd rect
			(at 0.7366 0 90)
			(size 0.7112 0.8128)
			(layers "B.Cu" "B.Mask" "B.Paste")
			(net "P3V3_AUX")
		)
		(pad "2" smd rect
			(at -0.7366 0 90)
			(size 0.7112 0.8128)
			(layers "B.Cu" "B.Mask" "B.Paste")
			(net "P3V3_FPGA_VCCIO4")
		)
	)
	(footprint ""
		(layer "B.Cu")
		(at 56.799988 -288.299906 90)
		(property "Reference" "C2942"
			(at 0 0 90)
			(layer "B.SilkS")
			(hide yes)
			(effects
				(font
					(size 1.27 1.27)
				)
				(justify mirror)
			)
		)
		(property "Value" ""
			(at 0 0 90)
			(layer "B.Fab")
			(effects
				(font
					(size 1.27 1.27)
				)
				(justify mirror)
			)
		)
		(duplicate_pad_numbers_are_jumpers no)
		(fp_line
			(start 0.299974 -0.150114)
			(end -0.299974 -0.150114)
			(stroke
				(width 0.1)
				(type default)
			)
			(layer "B.Fab")
		)
		(fp_line
			(start -0.299974 -0.150114)
			(end -0.299974 0.150114)
			(stroke
				(width 0.1)
				(type default)
			)
			(layer "B.Fab")
		)
		(fp_line
			(start 0.299974 0.150114)
			(end 0.299974 -0.150114)
			(stroke
				(width 0.1)
				(type default)
			)
			(layer "B.Fab")
		)
		(fp_line
			(start -0.299974 0.150114)
			(end 0.299974 0.150114)
			(stroke
				(width 0.1)
				(type default)
			)
			(layer "B.Fab")
		)
		(pad "1" smd rect
			(at 0.2667 0 270)
			(size 0.3048 0.381)
			(layers "B.Cu" "B.Mask" "B.Paste")
			(net "P1V25_PEX0")
		)
		(pad "2" smd rect
			(at -0.2667 0 270)
			(size 0.3048 0.381)
			(layers "B.Cu" "B.Mask" "B.Paste")
			(net "GND")
		)
	)
	(footprint ""
		(layer "B.Cu")
		(at 117.06479 -255.86055 180)
		(property "Reference" "PC44"
			(at 0 0 0)
			(layer "B.SilkS")
			(hide yes)
			(effects
				(font
					(size 1.27 1.27)
				)
				(justify mirror)
			)
		)
		(property "Value" ""
			(at 0 0 0)
			(layer "B.Fab")
			(effects
				(font
					(size 1.27 1.27)
				)
				(justify mirror)
			)
		)
		(duplicate_pad_numbers_are_jumpers no)
		(fp_line
			(start 0.7874 0.4064)
			(end 0.7874 -0.4064)
			(stroke
				(width 0.1524)
				(type default)
			)
			(layer "B.SilkS")
		)
		(fp_line
			(start 0.7874 -0.4064)
			(end -0.7874 -0.4064)
			(stroke
				(width 0.1524)
				(type default)
			)
			(layer "B.SilkS")
		)
		(fp_line
			(start -0.7874 0.4064)
			(end 0.7874 0.4064)
			(stroke
				(width 0.1524)
				(type default)
			)
			(layer "B.SilkS")
		)
		(fp_line
			(start -0.7874 -0.4064)
			(end -0.7874 0.4064)
			(stroke
				(width 0.1524)
				(type default)
			)
			(layer "B.SilkS")
		)
		(fp_line
			(start 0.67945 0.3048)
			(end 0.67945 -0.305054)
			(stroke
				(width 0.1)
				(type default)
			)
			(layer "B.Fab")
		)
		(fp_line
			(start 0.67945 -0.305054)
			(end 0.12065 -0.305054)
			(stroke
				(width 0.1)
				(type default)
			)
			(layer "B.Fab")
		)
		(fp_line
			(start 0.12065 0.3048)
			(end 0.67945 0.3048)
			(stroke
				(width 0.1)
				(type default)
			)
			(layer "B.Fab")
		)
		(fp_line
			(start 0.12065 0.2794)
			(end 0.12065 0.3048)
			(stroke
				(width 0.1)
				(type default)
			)
			(layer "B.Fab")
		)
		(fp_line
			(start 0.12065 -0.2794)
			(end -0.12065 -0.2794)
			(stroke
				(width 0.1)
				(type default)
			)
			(layer "B.Fab")
		)
		(fp_line
			(start 0.12065 -0.305054)
			(end 0.12065 -0.2794)
			(stroke
				(width 0.1)
				(type default)
			)
			(layer "B.Fab")
		)
		(fp_line
			(start -0.120396 0.3048)
			(end -0.120396 0.2794)
			(stroke
				(width 0.1)
				(type default)
			)
			(layer "B.Fab")
		)
		(fp_line
			(start -0.120396 0.2794)
			(end 0.12065 0.2794)
			(stroke
				(width 0.1)
				(type default)
			)
			(layer "B.Fab")
		)
		(fp_line
			(start -0.12065 -0.2794)
			(end -0.12065 -0.3048)
			(stroke
				(width 0.1)
				(type default)
			)
			(layer "B.Fab")
		)
		(fp_line
			(start -0.12065 -0.3048)
			(end -0.67945 -0.3048)
			(stroke
				(width 0.1)
				(type default)
			)
			(layer "B.Fab")
		)
		(fp_line
			(start -0.67945 0.3048)
			(end -0.120396 0.3048)
			(stroke
				(width 0.1)
				(type default)
			)
			(layer "B.Fab")
		)
		(fp_line
			(start -0.67945 -0.3048)
			(end -0.67945 0.3048)
			(stroke
				(width 0.1)
				(type default)
			)
			(layer "B.Fab")
		)
		(pad "1" smd circle
			(at 0.40005 0)
			(size 0 0)
			(layers "B.Cu" "B.Mask" "B.Paste")
			(net "P0V8_PEX0_VDD")
		)
		(pad "2" smd circle
			(at -0.40005 0)
			(size 0 0)
			(layers "B.Cu" "B.Mask" "B.Paste")
			(net "GND")
		)
	)
	(footprint ""
		(layer "B.Cu")
		(at 346.65031 -258.004564 -90)
		(property "Reference" "PC134"
			(at 0 0 90)
			(layer "B.SilkS")
			(hide yes)
			(effects
				(font
					(size 1.27 1.27)
				)
				(justify mirror)
			)
		)
		(property "Value" ""
			(at 0 0 90)
			(layer "B.Fab")
			(effects
				(font
					(size 1.27 1.27)
				)
				(justify mirror)
			)
		)
		(duplicate_pad_numbers_are_jumpers no)
		(fp_line
			(start -0.7874 0.4064)
			(end 0.7874 0.4064)
			(stroke
				(width 0.1524)
				(type default)
			)
			(layer "B.SilkS")
		)
		(fp_line
			(start 0.7874 0.4064)
			(end 0.7874 -0.4064)
			(stroke
				(width 0.1524)
				(type default)
			)
			(layer "B.SilkS")
		)
		(fp_line
			(start -0.7874 -0.4064)
			(end -0.7874 0.4064)
			(stroke
				(width 0.1524)
				(type default)
			)
			(layer "B.SilkS")
		)
		(fp_line
			(start 0.7874 -0.4064)
			(end -0.7874 -0.4064)
			(stroke
				(width 0.1524)
				(type default)
			)
			(layer "B.SilkS")
		)
		(fp_line
			(start -0.67945 0.3048)
			(end -0.120396 0.3048)
			(stroke
				(width 0.1)
				(type default)
			)
			(layer "B.Fab")
		)
		(fp_line
			(start -0.120396 0.3048)
			(end -0.120396 0.2794)
			(stroke
				(width 0.1)
				(type default)
			)
			(layer "B.Fab")
		)
		(fp_line
			(start 0.12065 0.3048)
			(end 0.67945 0.3048)
			(stroke
				(width 0.1)
				(type default)
			)
			(layer "B.Fab")
		)
		(fp_line
			(start 0.67945 0.3048)
			(end 0.67945 -0.305054)
			(stroke
				(width 0.1)
				(type default)
			)
			(layer "B.Fab")
		)
		(fp_line
			(start -0.120396 0.2794)
			(end 0.12065 0.2794)
			(stroke
				(width 0.1)
				(type default)
			)
			(layer "B.Fab")
		)
		(fp_line
			(start 0.12065 0.2794)
			(end 0.12065 0.3048)
			(stroke
				(width 0.1)
				(type default)
			)
			(layer "B.Fab")
		)
		(fp_line
			(start -0.12065 -0.2794)
			(end -0.12065 -0.3048)
			(stroke
				(width 0.1)
				(type default)
			)
			(layer "B.Fab")
		)
		(fp_line
			(start 0.12065 -0.2794)
			(end -0.12065 -0.2794)
			(stroke
				(width 0.1)
				(type default)
			)
			(layer "B.Fab")
		)
		(fp_line
			(start -0.67945 -0.3048)
			(end -0.67945 0.3048)
			(stroke
				(width 0.1)
				(type default)
			)
			(layer "B.Fab")
		)
		(fp_line
			(start -0.12065 -0.3048)
			(end -0.67945 -0.3048)
			(stroke
				(width 0.1)
				(type default)
			)
			(layer "B.Fab")
		)
		(fp_line
			(start 0.12065 -0.305054)
			(end 0.12065 -0.2794)
			(stroke
				(width 0.1)
				(type default)
			)
			(layer "B.Fab")
		)
		(fp_line
			(start 0.67945 -0.305054)
			(end 0.12065 -0.305054)
			(stroke
				(width 0.1)
				(type default)
			)
			(layer "B.Fab")
		)
		(pad "1" smd circle
			(at 0.40005 0 90)
			(size 0 0)
			(layers "B.Cu" "B.Mask" "B.Paste")
			(net "P0V8_PEX2_IINSEN")
		)
		(pad "2" smd circle
			(at -0.40005 0 90)
			(size 0 0)
			(layers "B.Cu" "B.Mask" "B.Paste")
			(net "GND")
		)
	)
	(footprint ""
		(layer "B.Cu")
		(at 424.02379 -291.624766 90)
		(property "Reference" "R998"
			(at 0 0 90)
			(layer "B.SilkS")
			(hide yes)
			(effects
				(font
					(size 1.27 1.27)
				)
				(justify mirror)
			)
		)
		(property "Value" ""
			(at 0 0 90)
			(layer "B.Fab")
			(effects
				(font
					(size 1.27 1.27)
				)
				(justify mirror)
			)
		)
		(duplicate_pad_numbers_are_jumpers no)
		(fp_line
			(start 0.7874 -0.4064)
			(end -0.7874 -0.4064)
			(stroke
				(width 0.1524)
				(type default)
			)
			(layer "B.SilkS")
		)
		(fp_line
			(start -0.7874 -0.4064)
			(end -0.7874 0.4064)
			(stroke
				(width 0.1524)
				(type default)
			)
			(layer "B.SilkS")
		)
		(fp_line
			(start 0.7874 0.4064)
			(end 0.7874 -0.4064)
			(stroke
				(width 0.1524)
				(type default)
			)
			(layer "B.SilkS")
		)
		(fp_line
			(start -0.7874 0.4064)
			(end 0.7874 0.4064)
			(stroke
				(width 0.1524)
				(type default)
			)
			(layer "B.SilkS")
		)
		(fp_line
			(start 0.67945 -0.305054)
			(end 0.12065 -0.305054)
			(stroke
				(width 0.1)
				(type default)
			)
			(layer "B.Fab")
		)
		(fp_line
			(start 0.12065 -0.305054)
			(end 0.12065 -0.2794)
			(stroke
				(width 0.1)
				(type default)
			)
			(layer "B.Fab")
		)
		(fp_line
			(start -0.12065 -0.3048)
			(end -0.67945 -0.3048)
			(stroke
				(width 0.1)
				(type default)
			)
			(layer "B.Fab")
		)
		(fp_line
			(start -0.67945 -0.3048)
			(end -0.67945 0.3048)
			(stroke
				(width 0.1)
				(type default)
			)
			(layer "B.Fab")
		)
		(fp_line
			(start 0.12065 -0.2794)
			(end -0.12065 -0.2794)
			(stroke
				(width 0.1)
				(type default)
			)
			(layer "B.Fab")
		)
		(fp_line
			(start -0.12065 -0.2794)
			(end -0.12065 -0.3048)
			(stroke
				(width 0.1)
				(type default)
			)
			(layer "B.Fab")
		)
		(fp_line
			(start 0.12065 0.2794)
			(end 0.12065 0.3048)
			(stroke
				(width 0.1)
				(type default)
			)
			(layer "B.Fab")
		)
		(fp_line
			(start -0.120396 0.2794)
			(end 0.12065 0.2794)
			(stroke
				(width 0.1)
				(type default)
			)
			(layer "B.Fab")
		)
		(fp_line
			(start 0.67945 0.3048)
			(end 0.67945 -0.305054)
			(stroke
				(width 0.1)
				(type default)
			)
			(layer "B.Fab")
		)
		(fp_line
			(start 0.12065 0.3048)
			(end 0.67945 0.3048)
			(stroke
				(width 0.1)
				(type default)
			)
			(layer "B.Fab")
		)
		(fp_line
			(start -0.120396 0.3048)
			(end -0.120396 0.2794)
			(stroke
				(width 0.1)
				(type default)
			)
			(layer "B.Fab")
		)
		(fp_line
			(start -0.67945 0.3048)
			(end -0.120396 0.3048)
			(stroke
				(width 0.1)
				(type default)
			)
			(layer "B.Fab")
		)
		(pad "1" smd circle
			(at 0.40005 0 270)
			(size 0 0)
			(layers "B.Cu" "B.Mask" "B.Paste")
			(net "UART_PEX3_CLI_TX")
		)
		(pad "2" smd circle
			(at -0.40005 0 270)
			(size 0 0)
			(layers "B.Cu" "B.Mask" "B.Paste")
			(net "UART_PEX3_CLI_R_TX")
		)
	)
	(footprint ""
		(layer "B.Cu")
		(at 340.423246 -87.875364)
		(property "Reference" "C2677"
			(at 0 0 0)
			(layer "B.SilkS")
			(hide yes)
			(effects
				(font
					(size 1.27 1.27)
				)
				(justify mirror)
			)
		)
		(property "Value" ""
			(at 0 0 0)
			(layer "B.Fab")
			(effects
				(font
					(size 1.27 1.27)
				)
				(justify mirror)
			)
		)
		(duplicate_pad_numbers_are_jumpers no)
		(fp_line
			(start -0.7874 -0.4064)
			(end -0.7874 0.4064)
			(stroke
				(width 0.1524)
				(type default)
			)
			(layer "B.SilkS")
		)
		(fp_line
			(start -0.7874 0.4064)
			(end 0.7874 0.4064)
			(stroke
				(width 0.1524)
				(type default)
			)
			(layer "B.SilkS")
		)
		(fp_line
			(start 0.7874 -0.4064)
			(end -0.7874 -0.4064)
			(stroke
				(width 0.1524)
				(type default)
			)
			(layer "B.SilkS")
		)
		(fp_line
			(start 0.7874 0.4064)
			(end 0.7874 -0.4064)
			(stroke
				(width 0.1524)
				(type default)
			)
			(layer "B.SilkS")
		)
		(fp_line
			(start -0.67945 -0.3048)
			(end -0.67945 0.3048)
			(stroke
				(width 0.1)
				(type default)
			)
			(layer "B.Fab")
		)
		(fp_line
			(start -0.67945 0.3048)
			(end -0.120396 0.3048)
			(stroke
				(width 0.1)
				(type default)
			)
			(layer "B.Fab")
		)
		(fp_line
			(start -0.12065 -0.3048)
			(end -0.67945 -0.3048)
			(stroke
				(width 0.1)
				(type default)
			)
			(layer "B.Fab")
		)
		(fp_line
			(start -0.12065 -0.2794)
			(end -0.12065 -0.3048)
			(stroke
				(width 0.1)
				(type default)
			)
			(layer "B.Fab")
		)
		(fp_line
			(start -0.120396 0.2794)
			(end 0.12065 0.2794)
			(stroke
				(width 0.1)
				(type default)
			)
			(layer "B.Fab")
		)
		(fp_line
			(start -0.120396 0.3048)
			(end -0.120396 0.2794)
			(stroke
				(width 0.1)
				(type default)
			)
			(layer "B.Fab")
		)
		(fp_line
			(start 0.12065 -0.305054)
			(end 0.12065 -0.2794)
			(stroke
				(width 0.1)
				(type default)
			)
			(layer "B.Fab")
		)
		(fp_line
			(start 0.12065 -0.2794)
			(end -0.12065 -0.2794)
			(stroke
				(width 0.1)
				(type default)
			)
			(layer "B.Fab")
		)
		(fp_line
			(start 0.12065 0.2794)
			(end 0.12065 0.3048)
			(stroke
				(width 0.1)
				(type default)
			)
			(layer "B.Fab")
		)
		(fp_line
			(start 0.12065 0.3048)
			(end 0.67945 0.3048)
			(stroke
				(width 0.1)
				(type default)
			)
			(layer "B.Fab")
		)
		(fp_line
			(start 0.67945 -0.305054)
			(end 0.12065 -0.305054)
			(stroke
				(width 0.1)
				(type default)
			)
			(layer "B.Fab")
		)
		(fp_line
			(start 0.67945 0.3048)
			(end 0.67945 -0.305054)
			(stroke
				(width 0.1)
				(type default)
			)
			(layer "B.Fab")
		)
		(pad "1" smd circle
			(at 0.40005 0 180)
			(size 0 0)
			(layers "B.Cu" "B.Mask" "B.Paste")
			(net "P3V3_VDD_9ZXL0851_8_15")
		)
		(pad "2" smd circle
			(at -0.40005 0 180)
			(size 0 0)
			(layers "B.Cu" "B.Mask" "B.Paste")
			(net "GND")
		)
	)
	(footprint ""
		(layer "B.Cu")
		(at 301.449232 -115.613434 -90)
		(property "Reference" "U33"
			(at 0.690118 4.357116 0)
			(unlocked yes)
			(layer "B.SilkS")
			(effects
				(font
					(size 0.7874 0.5842)
					(thickness 0.1524)
				)
				(justify mirror)
			)
		)
		(property "Value" ""
			(at 0 0 90)
			(layer "B.Fab")
			(effects
				(font
					(size 1.27 1.27)
				)
				(justify mirror)
			)
		)
		(duplicate_pad_numbers_are_jumpers no)
		(fp_line
			(start -1.3462 1.1938)
			(end -1.3462 -1.1938)
			(stroke
				(width 0.1524)
				(type default)
			)
			(layer "B.SilkS")
		)
		(fp_line
			(start 1.3462 1.1938)
			(end -1.3462 1.1938)
			(stroke
				(width 0.1524)
				(type default)
			)
			(layer "B.SilkS")
		)
		(fp_line
			(start -1.3462 -1.1938)
			(end 1.3462 -1.1938)
			(stroke
				(width 0.1524)
				(type default)
			)
			(layer "B.SilkS")
		)
		(fp_line
			(start 1.3462 -1.1938)
			(end 1.3462 1.1684)
			(stroke
				(width 0.1524)
				(type default)
			)
			(layer "B.SilkS")
		)
		(fp_poly
			(pts
				(xy 1.447038 -0.760476) (xy 2.052066 -0.457962) (xy 2.052066 -1.06299)
			)
			(stroke
				(width 0)
				(type default)
			)
			(fill yes)
			(layer "B.SilkS")
		)
		(fp_line
			(start -0.674878 1.124966)
			(end -0.674878 -1.124966)
			(stroke
				(width 0.1)
				(type default)
			)
			(layer "B.Fab")
		)
		(fp_line
			(start 0.674878 1.124966)
			(end -0.674878 1.124966)
			(stroke
				(width 0.1)
				(type default)
			)
			(layer "B.Fab")
		)
		(fp_line
			(start -0.674878 -1.124966)
			(end 0.674878 -1.124966)
			(stroke
				(width 0.1)
				(type default)
			)
			(layer "B.Fab")
		)
		(fp_line
			(start 0.674878 -1.124966)
			(end 0.674878 1.124966)
			(stroke
				(width 0.1)
				(type default)
			)
			(layer "B.Fab")
		)
		(fp_poly
			(pts
				(xy 1.447038 -0.760476) (xy 2.052066 -0.457962) (xy 2.052066 -1.06299)
			)
			(stroke
				(width 0)
				(type default)
			)
			(fill yes)
			(layer "B.Fab")
		)
		(pad "1" smd rect
			(at 0.899922 -0.750062 90)
			(size 0.6096 0.6096)
			(layers "B.Cu" "B.Mask" "B.Paste")
			(net "NIC5_AUX_PWR_EN_R")
		)
		(pad "2" smd rect
			(at 0.899922 0)
			(size 0.4064 0.6096)
			(layers "B.Cu" "B.Mask" "B.Paste")
			(net "RST_SMB_NIC5_MUX_N")
		)
		(pad "3" smd rect
			(at 0.899922 0.750062 90)
			(size 0.6096 0.6096)
			(layers "B.Cu" "B.Mask" "B.Paste")
			(net "GND")
		)
		(pad "4" smd rect
			(at -0.899922 0.750062 90)
			(size 0.6096 0.6096)
			(layers "B.Cu" "B.Mask" "B.Paste")
			(net "RST_SMB_NIC5_MUX_ISO_N")
		)
		(pad "5" smd rect
			(at -0.899922 -0.750062 90)
			(size 0.6096 0.6096)
			(layers "B.Cu" "B.Mask" "B.Paste")
			(net "P3V3_AUX")
		)
	)
	(footprint ""
		(layer "B.Cu")
		(at 131.129278 -211.242148)
		(property "Reference" "C2611"
			(at 0 0 0)
			(layer "B.SilkS")
			(hide yes)
			(effects
				(font
					(size 1.27 1.27)
				)
				(justify mirror)
			)
		)
		(property "Value" ""
			(at 0 0 0)
			(layer "B.Fab")
			(effects
				(font
					(size 1.27 1.27)
				)
				(justify mirror)
			)
		)
		(duplicate_pad_numbers_are_jumpers no)
		(fp_line
			(start -0.7874 -0.4064)
			(end -0.7874 0.4064)
			(stroke
				(width 0.1524)
				(type default)
			)
			(layer "B.SilkS")
		)
		(fp_line
			(start -0.7874 0.4064)
			(end 0.7874 0.4064)
			(stroke
				(width 0.1524)
				(type default)
			)
			(layer "B.SilkS")
		)
		(fp_line
			(start 0.7874 -0.4064)
			(end -0.7874 -0.4064)
			(stroke
				(width 0.1524)
				(type default)
			)
			(layer "B.SilkS")
		)
		(fp_line
			(start 0.7874 0.4064)
			(end 0.7874 -0.4064)
			(stroke
				(width 0.1524)
				(type default)
			)
			(layer "B.SilkS")
		)
		(fp_line
			(start -0.67945 -0.3048)
			(end -0.67945 0.3048)
			(stroke
				(width 0.1)
				(type default)
			)
			(layer "B.Fab")
		)
		(fp_line
			(start -0.67945 0.3048)
			(end -0.120396 0.3048)
			(stroke
				(width 0.1)
				(type default)
			)
			(layer "B.Fab")
		)
		(fp_line
			(start -0.12065 -0.3048)
			(end -0.67945 -0.3048)
			(stroke
				(width 0.1)
				(type default)
			)
			(layer "B.Fab")
		)
		(fp_line
			(start -0.12065 -0.2794)
			(end -0.12065 -0.3048)
			(stroke
				(width 0.1)
				(type default)
			)
			(layer "B.Fab")
		)
		(fp_line
			(start -0.120396 0.2794)
			(end 0.12065 0.2794)
			(stroke
				(width 0.1)
				(type default)
			)
			(layer "B.Fab")
		)
		(fp_line
			(start -0.120396 0.3048)
			(end -0.120396 0.2794)
			(stroke
				(width 0.1)
				(type default)
			)
			(layer "B.Fab")
		)
		(fp_line
			(start 0.12065 -0.305054)
			(end 0.12065 -0.2794)
			(stroke
				(width 0.1)
				(type default)
			)
			(layer "B.Fab")
		)
		(fp_line
			(start 0.12065 -0.2794)
			(end -0.12065 -0.2794)
			(stroke
				(width 0.1)
				(type default)
			)
			(layer "B.Fab")
		)
		(fp_line
			(start 0.12065 0.2794)
			(end 0.12065 0.3048)
			(stroke
				(width 0.1)
				(type default)
			)
			(layer "B.Fab")
		)
		(fp_line
			(start 0.12065 0.3048)
			(end 0.67945 0.3048)
			(stroke
				(width 0.1)
				(type default)
			)
			(layer "B.Fab")
		)
		(fp_line
			(start 0.67945 -0.305054)
			(end 0.12065 -0.305054)
			(stroke
				(width 0.1)
				(type default)
			)
			(layer "B.Fab")
		)
		(fp_line
			(start 0.67945 0.3048)
			(end 0.67945 -0.305054)
			(stroke
				(width 0.1)
				(type default)
			)
			(layer "B.Fab")
		)
		(pad "1" smd circle
			(at 0.40005 0 180)
			(size 0 0)
			(layers "B.Cu" "B.Mask" "B.Paste")
			(net "GND")
		)
		(pad "2" smd circle
			(at -0.40005 0 180)
			(size 0 0)
			(layers "B.Cu" "B.Mask" "B.Paste")
			(net "P1V8_PEX")
		)
	)
	(footprint ""
		(layer "B.Cu")
		(at 393.629642 -360.387138 180)
		(property "Reference" "R5472"
			(at 0 0 0)
			(layer "B.SilkS")
			(hide yes)
			(effects
				(font
					(size 1.27 1.27)
				)
				(justify mirror)
			)
		)
		(property "Value" ""
			(at 0 0 0)
			(layer "B.Fab")
			(effects
				(font
					(size 1.27 1.27)
				)
				(justify mirror)
			)
		)
		(duplicate_pad_numbers_are_jumpers no)
		(fp_line
			(start 0.7874 0.4064)
			(end 0.7874 -0.4064)
			(stroke
				(width 0.1524)
				(type default)
			)
			(layer "B.SilkS")
		)
		(fp_line
			(start 0.7874 -0.4064)
			(end -0.7874 -0.4064)
			(stroke
				(width 0.1524)
				(type default)
			)
			(layer "B.SilkS")
		)
		(fp_line
			(start -0.7874 0.4064)
			(end 0.7874 0.4064)
			(stroke
				(width 0.1524)
				(type default)
			)
			(layer "B.SilkS")
		)
		(fp_line
			(start -0.7874 -0.4064)
			(end -0.7874 0.4064)
			(stroke
				(width 0.1524)
				(type default)
			)
			(layer "B.SilkS")
		)
		(fp_line
			(start 0.67945 0.3048)
			(end 0.67945 -0.305054)
			(stroke
				(width 0.1)
				(type default)
			)
			(layer "B.Fab")
		)
		(fp_line
			(start 0.67945 -0.305054)
			(end 0.12065 -0.305054)
			(stroke
				(width 0.1)
				(type default)
			)
			(layer "B.Fab")
		)
		(fp_line
			(start 0.12065 0.3048)
			(end 0.67945 0.3048)
			(stroke
				(width 0.1)
				(type default)
			)
			(layer "B.Fab")
		)
		(fp_line
			(start 0.12065 0.2794)
			(end 0.12065 0.3048)
			(stroke
				(width 0.1)
				(type default)
			)
			(layer "B.Fab")
		)
		(fp_line
			(start 0.12065 -0.2794)
			(end -0.12065 -0.2794)
			(stroke
				(width 0.1)
				(type default)
			)
			(layer "B.Fab")
		)
		(fp_line
			(start 0.12065 -0.305054)
			(end 0.12065 -0.2794)
			(stroke
				(width 0.1)
				(type default)
			)
			(layer "B.Fab")
		)
		(fp_line
			(start -0.120396 0.3048)
			(end -0.120396 0.2794)
			(stroke
				(width 0.1)
				(type default)
			)
			(layer "B.Fab")
		)
		(fp_line
			(start -0.120396 0.2794)
			(end 0.12065 0.2794)
			(stroke
				(width 0.1)
				(type default)
			)
			(layer "B.Fab")
		)
		(fp_line
			(start -0.12065 -0.2794)
			(end -0.12065 -0.3048)
			(stroke
				(width 0.1)
				(type default)
			)
			(layer "B.Fab")
		)
		(fp_line
			(start -0.12065 -0.3048)
			(end -0.67945 -0.3048)
			(stroke
				(width 0.1)
				(type default)
			)
			(layer "B.Fab")
		)
		(fp_line
			(start -0.67945 0.3048)
			(end -0.120396 0.3048)
			(stroke
				(width 0.1)
				(type default)
			)
			(layer "B.Fab")
		)
		(fp_line
			(start -0.67945 -0.3048)
			(end -0.67945 0.3048)
			(stroke
				(width 0.1)
				(type default)
			)
			(layer "B.Fab")
		)
		(pad "1" smd circle
			(at 0.40005 0)
			(size 0 0)
			(layers "B.Cu" "B.Mask" "B.Paste")
			(net "UART_MB_BIC_R_RX")
		)
		(pad "2" smd circle
			(at -0.40005 0)
			(size 0 0)
			(layers "B.Cu" "B.Mask" "B.Paste")
			(net "UART_MB_BIC_RX")
		)
	)
	(footprint ""
		(layer "B.Cu")
		(at 196.689218 -368.95786 90)
		(property "Reference" "R6250"
			(at 0 0 90)
			(layer "B.SilkS")
			(hide yes)
			(effects
				(font
					(size 1.27 1.27)
				)
				(justify mirror)
			)
		)
		(property "Value" ""
			(at 0 0 90)
			(layer "B.Fab")
			(effects
				(font
					(size 1.27 1.27)
				)
				(justify mirror)
			)
		)
		(duplicate_pad_numbers_are_jumpers no)
		(fp_line
			(start 0.7874 -0.4064)
			(end -0.7874 -0.4064)
			(stroke
				(width 0.1524)
				(type default)
			)
			(layer "B.SilkS")
		)
		(fp_line
			(start -0.7874 -0.4064)
			(end -0.7874 0.4064)
			(stroke
				(width 0.1524)
				(type default)
			)
			(layer "B.SilkS")
		)
		(fp_line
			(start 0.7874 0.4064)
			(end 0.7874 -0.4064)
			(stroke
				(width 0.1524)
				(type default)
			)
			(layer "B.SilkS")
		)
		(fp_line
			(start -0.7874 0.4064)
			(end 0.7874 0.4064)
			(stroke
				(width 0.1524)
				(type default)
			)
			(layer "B.SilkS")
		)
		(fp_line
			(start 0.67945 -0.305054)
			(end 0.12065 -0.305054)
			(stroke
				(width 0.1)
				(type default)
			)
			(layer "B.Fab")
		)
		(fp_line
			(start 0.12065 -0.305054)
			(end 0.12065 -0.2794)
			(stroke
				(width 0.1)
				(type default)
			)
			(layer "B.Fab")
		)
		(fp_line
			(start -0.12065 -0.3048)
			(end -0.67945 -0.3048)
			(stroke
				(width 0.1)
				(type default)
			)
			(layer "B.Fab")
		)
		(fp_line
			(start -0.67945 -0.3048)
			(end -0.67945 0.3048)
			(stroke
				(width 0.1)
				(type default)
			)
			(layer "B.Fab")
		)
		(fp_line
			(start 0.12065 -0.2794)
			(end -0.12065 -0.2794)
			(stroke
				(width 0.1)
				(type default)
			)
			(layer "B.Fab")
		)
		(fp_line
			(start -0.12065 -0.2794)
			(end -0.12065 -0.3048)
			(stroke
				(width 0.1)
				(type default)
			)
			(layer "B.Fab")
		)
		(fp_line
			(start 0.12065 0.2794)
			(end 0.12065 0.3048)
			(stroke
				(width 0.1)
				(type default)
			)
			(layer "B.Fab")
		)
		(fp_line
			(start -0.120396 0.2794)
			(end 0.12065 0.2794)
			(stroke
				(width 0.1)
				(type default)
			)
			(layer "B.Fab")
		)
		(fp_line
			(start 0.67945 0.3048)
			(end 0.67945 -0.305054)
			(stroke
				(width 0.1)
				(type default)
			)
			(layer "B.Fab")
		)
		(fp_line
			(start 0.12065 0.3048)
			(end 0.67945 0.3048)
			(stroke
				(width 0.1)
				(type default)
			)
			(layer "B.Fab")
		)
		(fp_line
			(start -0.120396 0.3048)
			(end -0.120396 0.2794)
			(stroke
				(width 0.1)
				(type default)
			)
			(layer "B.Fab")
		)
		(fp_line
			(start -0.67945 0.3048)
			(end -0.120396 0.3048)
			(stroke
				(width 0.1)
				(type default)
			)
			(layer "B.Fab")
		)
		(pad "1" smd circle
			(at 0.40005 0 270)
			(size 0 0)
			(layers "B.Cu" "B.Mask" "B.Paste")
			(net "FM_HSC_PWROK")
		)
		(pad "2" smd circle
			(at -0.40005 0 270)
			(size 0 0)
			(layers "B.Cu" "B.Mask" "B.Paste")
			(net "AGND_HSC")
		)
	)
	(footprint ""
		(layer "B.Cu")
		(at 404.56993 -305.399948 -90)
		(property "Reference" "C3488"
			(at 0 0 90)
			(layer "B.SilkS")
			(hide yes)
			(effects
				(font
					(size 1.27 1.27)
				)
				(justify mirror)
			)
		)
		(property "Value" ""
			(at 0 0 90)
			(layer "B.Fab")
			(effects
				(font
					(size 1.27 1.27)
				)
				(justify mirror)
			)
		)
		(duplicate_pad_numbers_are_jumpers no)
		(fp_line
			(start -0.299974 0.150114)
			(end 0.299974 0.150114)
			(stroke
				(width 0.1)
				(type default)
			)
			(layer "B.Fab")
		)
		(fp_line
			(start 0.299974 0.150114)
			(end 0.299974 -0.150114)
			(stroke
				(width 0.1)
				(type default)
			)
			(layer "B.Fab")
		)
		(fp_line
			(start -0.299974 -0.150114)
			(end -0.299974 0.150114)
			(stroke
				(width 0.1)
				(type default)
			)
			(layer "B.Fab")
		)
		(fp_line
			(start 0.299974 -0.150114)
			(end -0.299974 -0.150114)
			(stroke
				(width 0.1)
				(type default)
			)
			(layer "B.Fab")
		)
		(pad "1" smd rect
			(at 0.2667 0 90)
			(size 0.3048 0.381)
			(layers "B.Cu" "B.Mask" "B.Paste")
			(net "P1V25_SERDES_VDDPLL_PEX3")
		)
		(pad "2" smd rect
			(at -0.2667 0 90)
			(size 0.3048 0.381)
			(layers "B.Cu" "B.Mask" "B.Paste")
			(net "GND")
		)
	)
	(footprint ""
		(layer "B.Cu")
		(at 392.749786 -293.04996)
		(property "Reference" "C3522"
			(at 0 0 0)
			(layer "B.SilkS")
			(hide yes)
			(effects
				(font
					(size 1.27 1.27)
				)
				(justify mirror)
			)
		)
		(property "Value" ""
			(at 0 0 0)
			(layer "B.Fab")
			(effects
				(font
					(size 1.27 1.27)
				)
				(justify mirror)
			)
		)
		(duplicate_pad_numbers_are_jumpers no)
		(fp_line
			(start -0.299974 -0.150114)
			(end -0.299974 0.150114)
			(stroke
				(width 0.1)
				(type default)
			)
			(layer "B.Fab")
		)
		(fp_line
			(start -0.299974 0.150114)
			(end 0.299974 0.150114)
			(stroke
				(width 0.1)
				(type default)
			)
			(layer "B.Fab")
		)
		(fp_line
			(start 0.299974 -0.150114)
			(end -0.299974 -0.150114)
			(stroke
				(width 0.1)
				(type default)
			)
			(layer "B.Fab")
		)
		(fp_line
			(start 0.299974 0.150114)
			(end 0.299974 -0.150114)
			(stroke
				(width 0.1)
				(type default)
			)
			(layer "B.Fab")
		)
		(pad "1" smd rect
			(at 0.2667 0 180)
			(size 0.3048 0.381)
			(layers "B.Cu" "B.Mask" "B.Paste")
			(net "P1V8_PEX")
		)
		(pad "2" smd rect
			(at -0.2667 0 180)
			(size 0.3048 0.381)
			(layers "B.Cu" "B.Mask" "B.Paste")
			(net "GND")
		)
	)
	(footprint ""
		(layer "B.Cu")
		(at 402.249894 -303.499774 -90)
		(property "Reference" "C3436"
			(at 0 0 90)
			(layer "B.SilkS")
			(hide yes)
			(effects
				(font
					(size 1.27 1.27)
				)
				(justify mirror)
			)
		)
		(property "Value" ""
			(at 0 0 90)
			(layer "B.Fab")
			(effects
				(font
					(size 1.27 1.27)
				)
				(justify mirror)
			)
		)
		(duplicate_pad_numbers_are_jumpers no)
		(fp_line
			(start -0.299974 0.150114)
			(end 0.299974 0.150114)
			(stroke
				(width 0.1)
				(type default)
			)
			(layer "B.Fab")
		)
		(fp_line
			(start 0.299974 0.150114)
			(end 0.299974 -0.150114)
			(stroke
				(width 0.1)
				(type default)
			)
			(layer "B.Fab")
		)
		(fp_line
			(start -0.299974 -0.150114)
			(end -0.299974 0.150114)
			(stroke
				(width 0.1)
				(type default)
			)
			(layer "B.Fab")
		)
		(fp_line
			(start 0.299974 -0.150114)
			(end -0.299974 -0.150114)
			(stroke
				(width 0.1)
				(type default)
			)
			(layer "B.Fab")
		)
		(pad "1" smd rect
			(at 0.2667 0 90)
			(size 0.3048 0.381)
			(layers "B.Cu" "B.Mask" "B.Paste")
			(net "P1V25_PEX3")
		)
		(pad "2" smd rect
			(at -0.2667 0 90)
			(size 0.3048 0.381)
			(layers "B.Cu" "B.Mask" "B.Paste")
			(net "GND")
		)
	)
	(footprint ""
		(layer "B.Cu")
		(at 140.774166 -222.299276 180)
		(property "Reference" "C2308"
			(at 0 0 0)
			(layer "B.SilkS")
			(hide yes)
			(effects
				(font
					(size 1.27 1.27)
				)
				(justify mirror)
			)
		)
		(property "Value" ""
			(at 0 0 0)
			(layer "B.Fab")
			(effects
				(font
					(size 1.27 1.27)
				)
				(justify mirror)
			)
		)
		(duplicate_pad_numbers_are_jumpers no)
		(fp_line
			(start 0.7874 0.4064)
			(end 0.7874 -0.4064)
			(stroke
				(width 0.1524)
				(type default)
			)
			(layer "B.SilkS")
		)
		(fp_line
			(start 0.7874 -0.4064)
			(end -0.7874 -0.4064)
			(stroke
				(width 0.1524)
				(type default)
			)
			(layer "B.SilkS")
		)
		(fp_line
			(start -0.7874 0.4064)
			(end 0.7874 0.4064)
			(stroke
				(width 0.1524)
				(type default)
			)
			(layer "B.SilkS")
		)
		(fp_line
			(start -0.7874 -0.4064)
			(end -0.7874 0.4064)
			(stroke
				(width 0.1524)
				(type default)
			)
			(layer "B.SilkS")
		)
		(fp_line
			(start 0.67945 0.3048)
			(end 0.67945 -0.305054)
			(stroke
				(width 0.1)
				(type default)
			)
			(layer "B.Fab")
		)
		(fp_line
			(start 0.67945 -0.305054)
			(end 0.12065 -0.305054)
			(stroke
				(width 0.1)
				(type default)
			)
			(layer "B.Fab")
		)
		(fp_line
			(start 0.12065 0.3048)
			(end 0.67945 0.3048)
			(stroke
				(width 0.1)
				(type default)
			)
			(layer "B.Fab")
		)
		(fp_line
			(start 0.12065 0.2794)
			(end 0.12065 0.3048)
			(stroke
				(width 0.1)
				(type default)
			)
			(layer "B.Fab")
		)
		(fp_line
			(start 0.12065 -0.2794)
			(end -0.12065 -0.2794)
			(stroke
				(width 0.1)
				(type default)
			)
			(layer "B.Fab")
		)
		(fp_line
			(start 0.12065 -0.305054)
			(end 0.12065 -0.2794)
			(stroke
				(width 0.1)
				(type default)
			)
			(layer "B.Fab")
		)
		(fp_line
			(start -0.120396 0.3048)
			(end -0.120396 0.2794)
			(stroke
				(width 0.1)
				(type default)
			)
			(layer "B.Fab")
		)
		(fp_line
			(start -0.120396 0.2794)
			(end 0.12065 0.2794)
			(stroke
				(width 0.1)
				(type default)
			)
			(layer "B.Fab")
		)
		(fp_line
			(start -0.12065 -0.2794)
			(end -0.12065 -0.3048)
			(stroke
				(width 0.1)
				(type default)
			)
			(layer "B.Fab")
		)
		(fp_line
			(start -0.12065 -0.3048)
			(end -0.67945 -0.3048)
			(stroke
				(width 0.1)
				(type default)
			)
			(layer "B.Fab")
		)
		(fp_line
			(start -0.67945 0.3048)
			(end -0.120396 0.3048)
			(stroke
				(width 0.1)
				(type default)
			)
			(layer "B.Fab")
		)
		(fp_line
			(start -0.67945 -0.3048)
			(end -0.67945 0.3048)
			(stroke
				(width 0.1)
				(type default)
			)
			(layer "B.Fab")
		)
		(pad "1" smd circle
			(at 0.40005 0)
			(size 0 0)
			(layers "B.Cu" "B.Mask" "B.Paste")
			(net "GND")
		)
		(pad "2" smd circle
			(at -0.40005 0)
			(size 0 0)
			(layers "B.Cu" "B.Mask" "B.Paste")
			(net "P1V8_PEX")
		)
	)
	(footprint ""
		(layer "B.Cu")
		(at 57.749948 -292.099746 90)
		(property "Reference" "C1200"
			(at 0 0 90)
			(layer "B.SilkS")
			(hide yes)
			(effects
				(font
					(size 1.27 1.27)
				)
				(justify mirror)
			)
		)
		(property "Value" ""
			(at 0 0 90)
			(layer "B.Fab")
			(effects
				(font
					(size 1.27 1.27)
				)
				(justify mirror)
			)
		)
		(duplicate_pad_numbers_are_jumpers no)
		(fp_line
			(start 0.299974 -0.150114)
			(end -0.299974 -0.150114)
			(stroke
				(width 0.1)
				(type default)
			)
			(layer "B.Fab")
		)
		(fp_line
			(start -0.299974 -0.150114)
			(end -0.299974 0.150114)
			(stroke
				(width 0.1)
				(type default)
			)
			(layer "B.Fab")
		)
		(fp_line
			(start 0.299974 0.150114)
			(end 0.299974 -0.150114)
			(stroke
				(width 0.1)
				(type default)
			)
			(layer "B.Fab")
		)
		(fp_line
			(start -0.299974 0.150114)
			(end 0.299974 0.150114)
			(stroke
				(width 0.1)
				(type default)
			)
			(layer "B.Fab")
		)
		(pad "1" smd rect
			(at 0.2667 0 270)
			(size 0.3048 0.381)
			(layers "B.Cu" "B.Mask" "B.Paste")
			(net "P0V8_SERDES_VDDA_PEX0")
		)
		(pad "2" smd rect
			(at -0.2667 0 270)
			(size 0.3048 0.381)
			(layers "B.Cu" "B.Mask" "B.Paste")
			(net "GND")
		)
	)
	(footprint ""
		(layer "B.Cu")
		(at 289.47491 -286.399732 90)
		(property "Reference" "C3300"
			(at 0 0 90)
			(layer "B.SilkS")
			(hide yes)
			(effects
				(font
					(size 1.27 1.27)
				)
				(justify mirror)
			)
		)
		(property "Value" ""
			(at 0 0 90)
			(layer "B.Fab")
			(effects
				(font
					(size 1.27 1.27)
				)
				(justify mirror)
			)
		)
		(duplicate_pad_numbers_are_jumpers no)
		(fp_line
			(start 0.299974 -0.150114)
			(end -0.299974 -0.150114)
			(stroke
				(width 0.1)
				(type default)
			)
			(layer "B.Fab")
		)
		(fp_line
			(start -0.299974 -0.150114)
			(end -0.299974 0.150114)
			(stroke
				(width 0.1)
				(type default)
			)
			(layer "B.Fab")
		)
		(fp_line
			(start 0.299974 0.150114)
			(end 0.299974 -0.150114)
			(stroke
				(width 0.1)
				(type default)
			)
			(layer "B.Fab")
		)
		(fp_line
			(start -0.299974 0.150114)
			(end 0.299974 0.150114)
			(stroke
				(width 0.1)
				(type default)
			)
			(layer "B.Fab")
		)
		(pad "1" smd rect
			(at 0.2667 0 270)
			(size 0.3048 0.381)
			(layers "B.Cu" "B.Mask" "B.Paste")
			(net "P1V25_SERDES_VDDPLL_PEX2")
		)
		(pad "2" smd rect
			(at -0.2667 0 270)
			(size 0.3048 0.381)
			(layers "B.Cu" "B.Mask" "B.Paste")
			(net "GND")
		)
	)
	(footprint ""
		(layer "B.Cu")
		(at 110.953042 -332.70571 180)
		(property "Reference" "C2702"
			(at 0 0 0)
			(layer "B.SilkS")
			(hide yes)
			(effects
				(font
					(size 1.27 1.27)
				)
				(justify mirror)
			)
		)
		(property "Value" ""
			(at 0 0 0)
			(layer "B.Fab")
			(effects
				(font
					(size 1.27 1.27)
				)
				(justify mirror)
			)
		)
		(duplicate_pad_numbers_are_jumpers no)
		(fp_line
			(start 0.7874 0.4064)
			(end 0.7874 -0.4064)
			(stroke
				(width 0.1524)
				(type default)
			)
			(layer "B.SilkS")
		)
		(fp_line
			(start 0.7874 -0.4064)
			(end -0.7874 -0.4064)
			(stroke
				(width 0.1524)
				(type default)
			)
			(layer "B.SilkS")
		)
		(fp_line
			(start -0.7874 0.4064)
			(end 0.7874 0.4064)
			(stroke
				(width 0.1524)
				(type default)
			)
			(layer "B.SilkS")
		)
		(fp_line
			(start -0.7874 -0.4064)
			(end -0.7874 0.4064)
			(stroke
				(width 0.1524)
				(type default)
			)
			(layer "B.SilkS")
		)
		(fp_line
			(start 0.67945 0.3048)
			(end 0.67945 -0.305054)
			(stroke
				(width 0.1)
				(type default)
			)
			(layer "B.Fab")
		)
		(fp_line
			(start 0.67945 -0.305054)
			(end 0.12065 -0.305054)
			(stroke
				(width 0.1)
				(type default)
			)
			(layer "B.Fab")
		)
		(fp_line
			(start 0.12065 0.3048)
			(end 0.67945 0.3048)
			(stroke
				(width 0.1)
				(type default)
			)
			(layer "B.Fab")
		)
		(fp_line
			(start 0.12065 0.2794)
			(end 0.12065 0.3048)
			(stroke
				(width 0.1)
				(type default)
			)
			(layer "B.Fab")
		)
		(fp_line
			(start 0.12065 -0.2794)
			(end -0.12065 -0.2794)
			(stroke
				(width 0.1)
				(type default)
			)
			(layer "B.Fab")
		)
		(fp_line
			(start 0.12065 -0.305054)
			(end 0.12065 -0.2794)
			(stroke
				(width 0.1)
				(type default)
			)
			(layer "B.Fab")
		)
		(fp_line
			(start -0.120396 0.3048)
			(end -0.120396 0.2794)
			(stroke
				(width 0.1)
				(type default)
			)
			(layer "B.Fab")
		)
		(fp_line
			(start -0.120396 0.2794)
			(end 0.12065 0.2794)
			(stroke
				(width 0.1)
				(type default)
			)
			(layer "B.Fab")
		)
		(fp_line
			(start -0.12065 -0.2794)
			(end -0.12065 -0.3048)
			(stroke
				(width 0.1)
				(type default)
			)
			(layer "B.Fab")
		)
		(fp_line
			(start -0.12065 -0.3048)
			(end -0.67945 -0.3048)
			(stroke
				(width 0.1)
				(type default)
			)
			(layer "B.Fab")
		)
		(fp_line
			(start -0.67945 0.3048)
			(end -0.120396 0.3048)
			(stroke
				(width 0.1)
				(type default)
			)
			(layer "B.Fab")
		)
		(fp_line
			(start -0.67945 -0.3048)
			(end -0.67945 0.3048)
			(stroke
				(width 0.1)
				(type default)
			)
			(layer "B.Fab")
		)
		(pad "1" smd circle
			(at 0.40005 0)
			(size 0 0)
			(layers "B.Cu" "B.Mask" "B.Paste")
			(net "P3V3_CLK_BUFFER_9ZXL0451E_VZX3P3A")
		)
		(pad "2" smd circle
			(at -0.40005 0)
			(size 0 0)
			(layers "B.Cu" "B.Mask" "B.Paste")
			(net "GND")
		)
	)
	(footprint ""
		(layer "B.Cu")
		(at 292.79977 -292.099746 90)
		(property "Reference" "C1725"
			(at 0 0 90)
			(layer "B.SilkS")
			(hide yes)
			(effects
				(font
					(size 1.27 1.27)
				)
				(justify mirror)
			)
		)
		(property "Value" ""
			(at 0 0 90)
			(layer "B.Fab")
			(effects
				(font
					(size 1.27 1.27)
				)
				(justify mirror)
			)
		)
		(duplicate_pad_numbers_are_jumpers no)
		(fp_line
			(start 0.299974 -0.150114)
			(end -0.299974 -0.150114)
			(stroke
				(width 0.1)
				(type default)
			)
			(layer "B.Fab")
		)
		(fp_line
			(start -0.299974 -0.150114)
			(end -0.299974 0.150114)
			(stroke
				(width 0.1)
				(type default)
			)
			(layer "B.Fab")
		)
		(fp_line
			(start 0.299974 0.150114)
			(end 0.299974 -0.150114)
			(stroke
				(width 0.1)
				(type default)
			)
			(layer "B.Fab")
		)
		(fp_line
			(start -0.299974 0.150114)
			(end 0.299974 0.150114)
			(stroke
				(width 0.1)
				(type default)
			)
			(layer "B.Fab")
		)
		(pad "1" smd rect
			(at 0.2667 0 270)
			(size 0.3048 0.381)
			(layers "B.Cu" "B.Mask" "B.Paste")
			(net "P0V8_SERDES_VDDA_PEX2")
		)
		(pad "2" smd rect
			(at -0.2667 0 270)
			(size 0.3048 0.381)
			(layers "B.Cu" "B.Mask" "B.Paste")
			(net "GND")
		)
	)
	(footprint ""
		(layer "B.Cu")
		(at 301.607474 -223.599502 -90)
		(property "Reference" "R1868"
			(at 0 0 90)
			(layer "B.SilkS")
			(hide yes)
			(effects
				(font
					(size 1.27 1.27)
				)
				(justify mirror)
			)
		)
		(property "Value" ""
			(at 0 0 90)
			(layer "B.Fab")
			(effects
				(font
					(size 1.27 1.27)
				)
				(justify mirror)
			)
		)
		(duplicate_pad_numbers_are_jumpers no)
		(fp_line
			(start -0.7874 0.4064)
			(end 0.7874 0.4064)
			(stroke
				(width 0.1524)
				(type default)
			)
			(layer "B.SilkS")
		)
		(fp_line
			(start 0.7874 0.4064)
			(end 0.7874 -0.4064)
			(stroke
				(width 0.1524)
				(type default)
			)
			(layer "B.SilkS")
		)
		(fp_line
			(start -0.7874 -0.4064)
			(end -0.7874 0.4064)
			(stroke
				(width 0.1524)
				(type default)
			)
			(layer "B.SilkS")
		)
		(fp_line
			(start 0.7874 -0.4064)
			(end -0.7874 -0.4064)
			(stroke
				(width 0.1524)
				(type default)
			)
			(layer "B.SilkS")
		)
		(fp_line
			(start -0.67945 0.3048)
			(end -0.120396 0.3048)
			(stroke
				(width 0.1)
				(type default)
			)
			(layer "B.Fab")
		)
		(fp_line
			(start -0.120396 0.3048)
			(end -0.120396 0.2794)
			(stroke
				(width 0.1)
				(type default)
			)
			(layer "B.Fab")
		)
		(fp_line
			(start 0.12065 0.3048)
			(end 0.67945 0.3048)
			(stroke
				(width 0.1)
				(type default)
			)
			(layer "B.Fab")
		)
		(fp_line
			(start 0.67945 0.3048)
			(end 0.67945 -0.305054)
			(stroke
				(width 0.1)
				(type default)
			)
			(layer "B.Fab")
		)
		(fp_line
			(start -0.120396 0.2794)
			(end 0.12065 0.2794)
			(stroke
				(width 0.1)
				(type default)
			)
			(layer "B.Fab")
		)
		(fp_line
			(start 0.12065 0.2794)
			(end 0.12065 0.3048)
			(stroke
				(width 0.1)
				(type default)
			)
			(layer "B.Fab")
		)
		(fp_line
			(start -0.12065 -0.2794)
			(end -0.12065 -0.3048)
			(stroke
				(width 0.1)
				(type default)
			)
			(layer "B.Fab")
		)
		(fp_line
			(start 0.12065 -0.2794)
			(end -0.12065 -0.2794)
			(stroke
				(width 0.1)
				(type default)
			)
			(layer "B.Fab")
		)
		(fp_line
			(start -0.67945 -0.3048)
			(end -0.67945 0.3048)
			(stroke
				(width 0.1)
				(type default)
			)
			(layer "B.Fab")
		)
		(fp_line
			(start -0.12065 -0.3048)
			(end -0.67945 -0.3048)
			(stroke
				(width 0.1)
				(type default)
			)
			(layer "B.Fab")
		)
		(fp_line
			(start 0.12065 -0.305054)
			(end 0.12065 -0.2794)
			(stroke
				(width 0.1)
				(type default)
			)
			(layer "B.Fab")
		)
		(fp_line
			(start 0.67945 -0.305054)
			(end 0.12065 -0.305054)
			(stroke
				(width 0.1)
				(type default)
			)
			(layer "B.Fab")
		)
		(pad "1" smd circle
			(at 0.40005 0 90)
			(size 0 0)
			(layers "B.Cu" "B.Mask" "B.Paste")
			(net "RST_GPU_PERST_2_N")
		)
		(pad "2" smd circle
			(at -0.40005 0 90)
			(size 0 0)
			(layers "B.Cu" "B.Mask" "B.Paste")
			(net "RST_GPU_PERST_2_R_N")
		)
	)
	(footprint ""
		(layer "B.Cu")
		(at 217.235786 -217.286586 180)
		(property "Reference" "C3621"
			(at 0 0 0)
			(layer "B.SilkS")
			(hide yes)
			(effects
				(font
					(size 1.27 1.27)
				)
				(justify mirror)
			)
		)
		(property "Value" ""
			(at 0 0 0)
			(layer "B.Fab")
			(effects
				(font
					(size 1.27 1.27)
				)
				(justify mirror)
			)
		)
		(duplicate_pad_numbers_are_jumpers no)
		(fp_line
			(start 0.7874 0.4064)
			(end 0.7874 -0.4064)
			(stroke
				(width 0.1524)
				(type default)
			)
			(layer "B.SilkS")
		)
		(fp_line
			(start 0.7874 -0.4064)
			(end -0.7874 -0.4064)
			(stroke
				(width 0.1524)
				(type default)
			)
			(layer "B.SilkS")
		)
		(fp_line
			(start -0.7874 0.4064)
			(end 0.7874 0.4064)
			(stroke
				(width 0.1524)
				(type default)
			)
			(layer "B.SilkS")
		)
		(fp_line
			(start -0.7874 -0.4064)
			(end -0.7874 0.4064)
			(stroke
				(width 0.1524)
				(type default)
			)
			(layer "B.SilkS")
		)
		(fp_line
			(start 0.67945 0.3048)
			(end 0.67945 -0.305054)
			(stroke
				(width 0.1)
				(type default)
			)
			(layer "B.Fab")
		)
		(fp_line
			(start 0.67945 -0.305054)
			(end 0.12065 -0.305054)
			(stroke
				(width 0.1)
				(type default)
			)
			(layer "B.Fab")
		)
		(fp_line
			(start 0.12065 0.3048)
			(end 0.67945 0.3048)
			(stroke
				(width 0.1)
				(type default)
			)
			(layer "B.Fab")
		)
		(fp_line
			(start 0.12065 0.2794)
			(end 0.12065 0.3048)
			(stroke
				(width 0.1)
				(type default)
			)
			(layer "B.Fab")
		)
		(fp_line
			(start 0.12065 -0.2794)
			(end -0.12065 -0.2794)
			(stroke
				(width 0.1)
				(type default)
			)
			(layer "B.Fab")
		)
		(fp_line
			(start 0.12065 -0.305054)
			(end 0.12065 -0.2794)
			(stroke
				(width 0.1)
				(type default)
			)
			(layer "B.Fab")
		)
		(fp_line
			(start -0.120396 0.3048)
			(end -0.120396 0.2794)
			(stroke
				(width 0.1)
				(type default)
			)
			(layer "B.Fab")
		)
		(fp_line
			(start -0.120396 0.2794)
			(end 0.12065 0.2794)
			(stroke
				(width 0.1)
				(type default)
			)
			(layer "B.Fab")
		)
		(fp_line
			(start -0.12065 -0.2794)
			(end -0.12065 -0.3048)
			(stroke
				(width 0.1)
				(type default)
			)
			(layer "B.Fab")
		)
		(fp_line
			(start -0.12065 -0.3048)
			(end -0.67945 -0.3048)
			(stroke
				(width 0.1)
				(type default)
			)
			(layer "B.Fab")
		)
		(fp_line
			(start -0.67945 0.3048)
			(end -0.120396 0.3048)
			(stroke
				(width 0.1)
				(type default)
			)
			(layer "B.Fab")
		)
		(fp_line
			(start -0.67945 -0.3048)
			(end -0.67945 0.3048)
			(stroke
				(width 0.1)
				(type default)
			)
			(layer "B.Fab")
		)
		(pad "1" smd circle
			(at 0.40005 0)
			(size 0 0)
			(layers "B.Cu" "B.Mask" "B.Paste")
			(net "GND")
		)
		(pad "2" smd circle
			(at -0.40005 0)
			(size 0 0)
			(layers "B.Cu" "B.Mask" "B.Paste")
			(net "PECI_VDD")
		)
	)
	(footprint ""
		(layer "B.Cu")
		(at 45.864272 -142.795752 180)
		(property "Reference" "C847"
			(at 0 0 0)
			(layer "B.SilkS")
			(hide yes)
			(effects
				(font
					(size 1.27 1.27)
				)
				(justify mirror)
			)
		)
		(property "Value" ""
			(at 0 0 0)
			(layer "B.Fab")
			(effects
				(font
					(size 1.27 1.27)
				)
				(justify mirror)
			)
		)
		(duplicate_pad_numbers_are_jumpers no)
		(fp_line
			(start 0.299974 0.150114)
			(end 0.299974 -0.150114)
			(stroke
				(width 0.1)
				(type default)
			)
			(layer "B.Fab")
		)
		(fp_line
			(start 0.299974 -0.150114)
			(end -0.299974 -0.150114)
			(stroke
				(width 0.1)
				(type default)
			)
			(layer "B.Fab")
		)
		(fp_line
			(start -0.299974 0.150114)
			(end 0.299974 0.150114)
			(stroke
				(width 0.1)
				(type default)
			)
			(layer "B.Fab")
		)
		(fp_line
			(start -0.299974 -0.150114)
			(end -0.299974 0.150114)
			(stroke
				(width 0.1)
				(type default)
			)
			(layer "B.Fab")
		)
		(pad "1" smd rect
			(at 0.2667 0)
			(size 0.3048 0.381)
			(layers "B.Cu" "B.Mask" "B.Paste")
			(net "P12V_NIC0")
		)
		(pad "2" smd rect
			(at -0.2667 0)
			(size 0.3048 0.381)
			(layers "B.Cu" "B.Mask" "B.Paste")
			(net "GND")
		)
	)
	(footprint ""
		(layer "B.Cu")
		(at 402.249894 -292.099746 90)
		(property "Reference" "C1981"
			(at 0 0 90)
			(layer "B.SilkS")
			(hide yes)
			(effects
				(font
					(size 1.27 1.27)
				)
				(justify mirror)
			)
		)
		(property "Value" ""
			(at 0 0 90)
			(layer "B.Fab")
			(effects
				(font
					(size 1.27 1.27)
				)
				(justify mirror)
			)
		)
		(duplicate_pad_numbers_are_jumpers no)
		(fp_line
			(start 0.299974 -0.150114)
			(end -0.299974 -0.150114)
			(stroke
				(width 0.1)
				(type default)
			)
			(layer "B.Fab")
		)
		(fp_line
			(start -0.299974 -0.150114)
			(end -0.299974 0.150114)
			(stroke
				(width 0.1)
				(type default)
			)
			(layer "B.Fab")
		)
		(fp_line
			(start 0.299974 0.150114)
			(end 0.299974 -0.150114)
			(stroke
				(width 0.1)
				(type default)
			)
			(layer "B.Fab")
		)
		(fp_line
			(start -0.299974 0.150114)
			(end 0.299974 0.150114)
			(stroke
				(width 0.1)
				(type default)
			)
			(layer "B.Fab")
		)
		(pad "1" smd rect
			(at 0.2667 0 270)
			(size 0.3048 0.381)
			(layers "B.Cu" "B.Mask" "B.Paste")
			(net "P0V8_SERDES_VDDA_PEX3")
		)
		(pad "2" smd rect
			(at -0.2667 0 270)
			(size 0.3048 0.381)
			(layers "B.Cu" "B.Mask" "B.Paste")
			(net "GND")
		)
	)
	(footprint ""
		(layer "B.Cu")
		(at 169.574972 -293.99992 -90)
		(property "Reference" "C1390"
			(at 0 0 90)
			(layer "B.SilkS")
			(hide yes)
			(effects
				(font
					(size 1.27 1.27)
				)
				(justify mirror)
			)
		)
		(property "Value" ""
			(at 0 0 90)
			(layer "B.Fab")
			(effects
				(font
					(size 1.27 1.27)
				)
				(justify mirror)
			)
		)
		(duplicate_pad_numbers_are_jumpers no)
		(fp_line
			(start -0.299974 0.150114)
			(end 0.299974 0.150114)
			(stroke
				(width 0.1)
				(type default)
			)
			(layer "B.Fab")
		)
		(fp_line
			(start 0.299974 0.150114)
			(end 0.299974 -0.150114)
			(stroke
				(width 0.1)
				(type default)
			)
			(layer "B.Fab")
		)
		(fp_line
			(start -0.299974 -0.150114)
			(end -0.299974 0.150114)
			(stroke
				(width 0.1)
				(type default)
			)
			(layer "B.Fab")
		)
		(fp_line
			(start 0.299974 -0.150114)
			(end -0.299974 -0.150114)
			(stroke
				(width 0.1)
				(type default)
			)
			(layer "B.Fab")
		)
		(pad "1" smd rect
			(at 0.2667 0 90)
			(size 0.3048 0.381)
			(layers "B.Cu" "B.Mask" "B.Paste")
			(net "P0V8_PEX1")
		)
		(pad "2" smd rect
			(at -0.2667 0 90)
			(size 0.3048 0.381)
			(layers "B.Cu" "B.Mask" "B.Paste")
			(net "GND")
		)
	)
	(footprint ""
		(layer "B.Cu")
		(at 228.651054 -289.856926 180)
		(property "Reference" "PC990"
			(at 0 0 0)
			(layer "B.SilkS")
			(hide yes)
			(effects
				(font
					(size 1.27 1.27)
				)
				(justify mirror)
			)
		)
		(property "Value" ""
			(at 0 0 0)
			(layer "B.Fab")
			(effects
				(font
					(size 1.27 1.27)
				)
				(justify mirror)
			)
		)
		(duplicate_pad_numbers_are_jumpers no)
		(fp_line
			(start 1.524 0.762)
			(end 1.524 -0.762)
			(stroke
				(width 0.1524)
				(type default)
			)
			(layer "B.SilkS")
		)
		(fp_line
			(start 1.524 -0.762)
			(end -1.524 -0.762)
			(stroke
				(width 0.1524)
				(type default)
			)
			(layer "B.SilkS")
		)
		(fp_line
			(start -1.524 0.762)
			(end 1.524 0.762)
			(stroke
				(width 0.1524)
				(type default)
			)
			(layer "B.SilkS")
		)
		(fp_line
			(start -1.524 -0.762)
			(end -1.524 0.762)
			(stroke
				(width 0.1524)
				(type default)
			)
			(layer "B.SilkS")
		)
		(fp_line
			(start 1.1049 0.724916)
			(end -1.1049 0.724916)
			(stroke
				(width 0.1)
				(type default)
			)
			(layer "B.Fab")
		)
		(fp_line
			(start 1.1049 -0.724916)
			(end 1.1049 0.724916)
			(stroke
				(width 0.1)
				(type default)
			)
			(layer "B.Fab")
		)
		(fp_line
			(start -1.1049 0.724916)
			(end -1.1049 -0.724916)
			(stroke
				(width 0.1)
				(type default)
			)
			(layer "B.Fab")
		)
		(fp_line
			(start -1.1049 -0.724916)
			(end 1.1049 -0.724916)
			(stroke
				(width 0.1)
				(type default)
			)
			(layer "B.Fab")
		)
		(pad "1" smd rect
			(at 0.889 0 180)
			(size 1.016 1.27)
			(layers "B.Cu" "B.Mask" "B.Paste")
			(net "P1V25_PEX1_R")
		)
		(pad "2" smd rect
			(at -0.889 0 180)
			(size 1.016 1.27)
			(layers "B.Cu" "B.Mask" "B.Paste")
			(net "GND")
		)
	)
	(footprint ""
		(layer "B.Cu")
		(at 213.106 -207.899 -90)
		(property "Reference" "R6306"
			(at 0 0 90)
			(layer "B.SilkS")
			(hide yes)
			(effects
				(font
					(size 1.27 1.27)
				)
				(justify mirror)
			)
		)
		(property "Value" ""
			(at 0 0 90)
			(layer "B.Fab")
			(effects
				(font
					(size 1.27 1.27)
				)
				(justify mirror)
			)
		)
		(duplicate_pad_numbers_are_jumpers no)
		(fp_line
			(start -0.7874 0.4064)
			(end 0.7874 0.4064)
			(stroke
				(width 0.1524)
				(type default)
			)
			(layer "B.SilkS")
		)
		(fp_line
			(start 0.7874 0.4064)
			(end 0.7874 -0.4064)
			(stroke
				(width 0.1524)
				(type default)
			)
			(layer "B.SilkS")
		)
		(fp_line
			(start -0.7874 -0.4064)
			(end -0.7874 0.4064)
			(stroke
				(width 0.1524)
				(type default)
			)
			(layer "B.SilkS")
		)
		(fp_line
			(start 0.7874 -0.4064)
			(end -0.7874 -0.4064)
			(stroke
				(width 0.1524)
				(type default)
			)
			(layer "B.SilkS")
		)
		(fp_line
			(start -0.67945 0.3048)
			(end -0.120396 0.3048)
			(stroke
				(width 0.1)
				(type default)
			)
			(layer "B.Fab")
		)
		(fp_line
			(start -0.120396 0.3048)
			(end -0.120396 0.2794)
			(stroke
				(width 0.1)
				(type default)
			)
			(layer "B.Fab")
		)
		(fp_line
			(start 0.12065 0.3048)
			(end 0.67945 0.3048)
			(stroke
				(width 0.1)
				(type default)
			)
			(layer "B.Fab")
		)
		(fp_line
			(start 0.67945 0.3048)
			(end 0.67945 -0.305054)
			(stroke
				(width 0.1)
				(type default)
			)
			(layer "B.Fab")
		)
		(fp_line
			(start -0.120396 0.2794)
			(end 0.12065 0.2794)
			(stroke
				(width 0.1)
				(type default)
			)
			(layer "B.Fab")
		)
		(fp_line
			(start 0.12065 0.2794)
			(end 0.12065 0.3048)
			(stroke
				(width 0.1)
				(type default)
			)
			(layer "B.Fab")
		)
		(fp_line
			(start -0.12065 -0.2794)
			(end -0.12065 -0.3048)
			(stroke
				(width 0.1)
				(type default)
			)
			(layer "B.Fab")
		)
		(fp_line
			(start 0.12065 -0.2794)
			(end -0.12065 -0.2794)
			(stroke
				(width 0.1)
				(type default)
			)
			(layer "B.Fab")
		)
		(fp_line
			(start -0.67945 -0.3048)
			(end -0.67945 0.3048)
			(stroke
				(width 0.1)
				(type default)
			)
			(layer "B.Fab")
		)
		(fp_line
			(start -0.12065 -0.3048)
			(end -0.67945 -0.3048)
			(stroke
				(width 0.1)
				(type default)
			)
			(layer "B.Fab")
		)
		(fp_line
			(start 0.12065 -0.305054)
			(end 0.12065 -0.2794)
			(stroke
				(width 0.1)
				(type default)
			)
			(layer "B.Fab")
		)
		(fp_line
			(start 0.67945 -0.305054)
			(end 0.12065 -0.305054)
			(stroke
				(width 0.1)
				(type default)
			)
			(layer "B.Fab")
		)
		(pad "1" smd circle
			(at 0.40005 0 90)
			(size 0 0)
			(layers "B.Cu" "B.Mask" "B.Paste")
			(net "SMB_NIC4_LS_SDA")
		)
		(pad "2" smd circle
			(at -0.40005 0 90)
			(size 0 0)
			(layers "B.Cu" "B.Mask" "B.Paste")
			(net "SMB_NIC4_LS_R_SDA")
		)
	)
	(footprint ""
		(layer "B.Cu")
		(at 185.250074 -302.074834)
		(property "Reference" "C3166"
			(at 0 0 0)
			(layer "B.SilkS")
			(hide yes)
			(effects
				(font
					(size 1.27 1.27)
				)
				(justify mirror)
			)
		)
		(property "Value" ""
			(at 0 0 0)
			(layer "B.Fab")
			(effects
				(font
					(size 1.27 1.27)
				)
				(justify mirror)
			)
		)
		(duplicate_pad_numbers_are_jumpers no)
		(fp_line
			(start -0.299974 -0.150114)
			(end -0.299974 0.150114)
			(stroke
				(width 0.1)
				(type default)
			)
			(layer "B.Fab")
		)
		(fp_line
			(start -0.299974 0.150114)
			(end 0.299974 0.150114)
			(stroke
				(width 0.1)
				(type default)
			)
			(layer "B.Fab")
		)
		(fp_line
			(start 0.299974 -0.150114)
			(end -0.299974 -0.150114)
			(stroke
				(width 0.1)
				(type default)
			)
			(layer "B.Fab")
		)
		(fp_line
			(start 0.299974 0.150114)
			(end 0.299974 -0.150114)
			(stroke
				(width 0.1)
				(type default)
			)
			(layer "B.Fab")
		)
		(pad "1" smd rect
			(at 0.2667 0 180)
			(size 0.3048 0.381)
			(layers "B.Cu" "B.Mask" "B.Paste")
			(net "P1V8_PEX")
		)
		(pad "2" smd rect
			(at -0.2667 0 180)
			(size 0.3048 0.381)
			(layers "B.Cu" "B.Mask" "B.Paste")
			(net "GND")
		)
	)
	(footprint ""
		(layer "B.Cu")
		(at 235.000546 -353.273614 180)
		(property "Reference" "PR7157"
			(at 0 0 0)
			(layer "B.SilkS")
			(hide yes)
			(effects
				(font
					(size 1.27 1.27)
				)
				(justify mirror)
			)
		)
		(property "Value" ""
			(at 0 0 0)
			(layer "B.Fab")
			(effects
				(font
					(size 1.27 1.27)
				)
				(justify mirror)
			)
		)
		(duplicate_pad_numbers_are_jumpers no)
		(fp_line
			(start 0.7874 0.4064)
			(end 0.7874 -0.4064)
			(stroke
				(width 0.1524)
				(type default)
			)
			(layer "B.SilkS")
		)
		(fp_line
			(start 0.7874 -0.4064)
			(end -0.7874 -0.4064)
			(stroke
				(width 0.1524)
				(type default)
			)
			(layer "B.SilkS")
		)
		(fp_line
			(start -0.7874 0.4064)
			(end 0.7874 0.4064)
			(stroke
				(width 0.1524)
				(type default)
			)
			(layer "B.SilkS")
		)
		(fp_line
			(start -0.7874 -0.4064)
			(end -0.7874 0.4064)
			(stroke
				(width 0.1524)
				(type default)
			)
			(layer "B.SilkS")
		)
		(fp_line
			(start 0.67945 0.3048)
			(end 0.67945 -0.305054)
			(stroke
				(width 0.1)
				(type default)
			)
			(layer "B.Fab")
		)
		(fp_line
			(start 0.67945 -0.305054)
			(end 0.12065 -0.305054)
			(stroke
				(width 0.1)
				(type default)
			)
			(layer "B.Fab")
		)
		(fp_line
			(start 0.12065 0.3048)
			(end 0.67945 0.3048)
			(stroke
				(width 0.1)
				(type default)
			)
			(layer "B.Fab")
		)
		(fp_line
			(start 0.12065 0.2794)
			(end 0.12065 0.3048)
			(stroke
				(width 0.1)
				(type default)
			)
			(layer "B.Fab")
		)
		(fp_line
			(start 0.12065 -0.2794)
			(end -0.12065 -0.2794)
			(stroke
				(width 0.1)
				(type default)
			)
			(layer "B.Fab")
		)
		(fp_line
			(start 0.12065 -0.305054)
			(end 0.12065 -0.2794)
			(stroke
				(width 0.1)
				(type default)
			)
			(layer "B.Fab")
		)
		(fp_line
			(start -0.120396 0.3048)
			(end -0.120396 0.2794)
			(stroke
				(width 0.1)
				(type default)
			)
			(layer "B.Fab")
		)
		(fp_line
			(start -0.120396 0.2794)
			(end 0.12065 0.2794)
			(stroke
				(width 0.1)
				(type default)
			)
			(layer "B.Fab")
		)
		(fp_line
			(start -0.12065 -0.2794)
			(end -0.12065 -0.3048)
			(stroke
				(width 0.1)
				(type default)
			)
			(layer "B.Fab")
		)
		(fp_line
			(start -0.12065 -0.3048)
			(end -0.67945 -0.3048)
			(stroke
				(width 0.1)
				(type default)
			)
			(layer "B.Fab")
		)
		(fp_line
			(start -0.67945 0.3048)
			(end -0.120396 0.3048)
			(stroke
				(width 0.1)
				(type default)
			)
			(layer "B.Fab")
		)
		(fp_line
			(start -0.67945 -0.3048)
			(end -0.67945 0.3048)
			(stroke
				(width 0.1)
				(type default)
			)
			(layer "B.Fab")
		)
		(pad "1" smd circle
			(at 0.40005 0)
			(size 0 0)
			(layers "B.Cu" "B.Mask" "B.Paste")
			(net "P12V_HSC_SENSE2_N")
		)
		(pad "2" smd circle
			(at -0.40005 0)
			(size 0 0)
			(layers "B.Cu" "B.Mask" "B.Paste")
			(net "P12V_HSC_SENSE2_R2_N")
		)
	)
	(footprint ""
		(layer "B.Cu")
		(at 62.499748 -299.699934 -90)
		(property "Reference" "C1227"
			(at 0 0 90)
			(layer "B.SilkS")
			(hide yes)
			(effects
				(font
					(size 1.27 1.27)
				)
				(justify mirror)
			)
		)
		(property "Value" ""
			(at 0 0 90)
			(layer "B.Fab")
			(effects
				(font
					(size 1.27 1.27)
				)
				(justify mirror)
			)
		)
		(duplicate_pad_numbers_are_jumpers no)
		(fp_line
			(start -0.299974 0.150114)
			(end 0.299974 0.150114)
			(stroke
				(width 0.1)
				(type default)
			)
			(layer "B.Fab")
		)
		(fp_line
			(start 0.299974 0.150114)
			(end 0.299974 -0.150114)
			(stroke
				(width 0.1)
				(type default)
			)
			(layer "B.Fab")
		)
		(fp_line
			(start -0.299974 -0.150114)
			(end -0.299974 0.150114)
			(stroke
				(width 0.1)
				(type default)
			)
			(layer "B.Fab")
		)
		(fp_line
			(start 0.299974 -0.150114)
			(end -0.299974 -0.150114)
			(stroke
				(width 0.1)
				(type default)
			)
			(layer "B.Fab")
		)
		(pad "1" smd rect
			(at 0.2667 0 90)
			(size 0.3048 0.381)
			(layers "B.Cu" "B.Mask" "B.Paste")
			(net "P0V8_SERDES_VDDA_PEX0")
		)
		(pad "2" smd rect
			(at -0.2667 0 90)
			(size 0.3048 0.381)
			(layers "B.Cu" "B.Mask" "B.Paste")
			(net "GND")
		)
	)
	(footprint ""
		(layer "B.Cu")
		(at 452.08444 -292.562788)
		(property "Reference" "PC1001"
			(at 0 0 0)
			(layer "B.SilkS")
			(hide yes)
			(effects
				(font
					(size 1.27 1.27)
				)
				(justify mirror)
			)
		)
		(property "Value" ""
			(at 0 0 0)
			(layer "B.Fab")
			(effects
				(font
					(size 1.27 1.27)
				)
				(justify mirror)
			)
		)
		(duplicate_pad_numbers_are_jumpers no)
		(fp_line
			(start -1.524 -0.762)
			(end -1.524 0.762)
			(stroke
				(width 0.1524)
				(type default)
			)
			(layer "B.SilkS")
		)
		(fp_line
			(start -1.524 0.762)
			(end 1.524 0.762)
			(stroke
				(width 0.1524)
				(type default)
			)
			(layer "B.SilkS")
		)
		(fp_line
			(start 1.524 -0.762)
			(end -1.524 -0.762)
			(stroke
				(width 0.1524)
				(type default)
			)
			(layer "B.SilkS")
		)
		(fp_line
			(start 1.524 0.762)
			(end 1.524 -0.762)
			(stroke
				(width 0.1524)
				(type default)
			)
			(layer "B.SilkS")
		)
		(fp_line
			(start -1.1049 -0.724916)
			(end 1.1049 -0.724916)
			(stroke
				(width 0.1)
				(type default)
			)
			(layer "B.Fab")
		)
		(fp_line
			(start -1.1049 0.724916)
			(end -1.1049 -0.724916)
			(stroke
				(width 0.1)
				(type default)
			)
			(layer "B.Fab")
		)
		(fp_line
			(start 1.1049 -0.724916)
			(end 1.1049 0.724916)
			(stroke
				(width 0.1)
				(type default)
			)
			(layer "B.Fab")
		)
		(fp_line
			(start 1.1049 0.724916)
			(end -1.1049 0.724916)
			(stroke
				(width 0.1)
				(type default)
			)
			(layer "B.Fab")
		)
		(pad "1" smd rect
			(at 0.889 0)
			(size 1.016 1.27)
			(layers "B.Cu" "B.Mask" "B.Paste")
			(net "P1V25_PEX3_R")
		)
		(pad "2" smd rect
			(at -0.889 0)
			(size 1.016 1.27)
			(layers "B.Cu" "B.Mask" "B.Paste")
			(net "GND")
		)
	)
	(footprint ""
		(layer "B.Cu")
		(at 253.798578 -221.081092)
		(property "Reference" "R3483"
			(at 0 0 0)
			(layer "B.SilkS")
			(hide yes)
			(effects
				(font
					(size 1.27 1.27)
				)
				(justify mirror)
			)
		)
		(property "Value" ""
			(at 0 0 0)
			(layer "B.Fab")
			(effects
				(font
					(size 1.27 1.27)
				)
				(justify mirror)
			)
		)
		(duplicate_pad_numbers_are_jumpers no)
		(fp_line
			(start -0.7874 -0.4064)
			(end -0.7874 0.4064)
			(stroke
				(width 0.1524)
				(type default)
			)
			(layer "B.SilkS")
		)
		(fp_line
			(start -0.7874 0.4064)
			(end 0.7874 0.4064)
			(stroke
				(width 0.1524)
				(type default)
			)
			(layer "B.SilkS")
		)
		(fp_line
			(start 0.7874 -0.4064)
			(end -0.7874 -0.4064)
			(stroke
				(width 0.1524)
				(type default)
			)
			(layer "B.SilkS")
		)
		(fp_line
			(start 0.7874 0.4064)
			(end 0.7874 -0.4064)
			(stroke
				(width 0.1524)
				(type default)
			)
			(layer "B.SilkS")
		)
		(fp_line
			(start -0.67945 -0.3048)
			(end -0.67945 0.3048)
			(stroke
				(width 0.1)
				(type default)
			)
			(layer "B.Fab")
		)
		(fp_line
			(start -0.67945 0.3048)
			(end -0.120396 0.3048)
			(stroke
				(width 0.1)
				(type default)
			)
			(layer "B.Fab")
		)
		(fp_line
			(start -0.12065 -0.3048)
			(end -0.67945 -0.3048)
			(stroke
				(width 0.1)
				(type default)
			)
			(layer "B.Fab")
		)
		(fp_line
			(start -0.12065 -0.2794)
			(end -0.12065 -0.3048)
			(stroke
				(width 0.1)
				(type default)
			)
			(layer "B.Fab")
		)
		(fp_line
			(start -0.120396 0.2794)
			(end 0.12065 0.2794)
			(stroke
				(width 0.1)
				(type default)
			)
			(layer "B.Fab")
		)
		(fp_line
			(start -0.120396 0.3048)
			(end -0.120396 0.2794)
			(stroke
				(width 0.1)
				(type default)
			)
			(layer "B.Fab")
		)
		(fp_line
			(start 0.12065 -0.305054)
			(end 0.12065 -0.2794)
			(stroke
				(width 0.1)
				(type default)
			)
			(layer "B.Fab")
		)
		(fp_line
			(start 0.12065 -0.2794)
			(end -0.12065 -0.2794)
			(stroke
				(width 0.1)
				(type default)
			)
			(layer "B.Fab")
		)
		(fp_line
			(start 0.12065 0.2794)
			(end 0.12065 0.3048)
			(stroke
				(width 0.1)
				(type default)
			)
			(layer "B.Fab")
		)
		(fp_line
			(start 0.12065 0.3048)
			(end 0.67945 0.3048)
			(stroke
				(width 0.1)
				(type default)
			)
			(layer "B.Fab")
		)
		(fp_line
			(start 0.67945 -0.305054)
			(end 0.12065 -0.305054)
			(stroke
				(width 0.1)
				(type default)
			)
			(layer "B.Fab")
		)
		(fp_line
			(start 0.67945 0.3048)
			(end 0.67945 -0.305054)
			(stroke
				(width 0.1)
				(type default)
			)
			(layer "B.Fab")
		)
		(pad "1" smd circle
			(at 0.40005 0 180)
			(size 0 0)
			(layers "B.Cu" "B.Mask" "B.Paste")
			(net "SPI_PEX2_SDIO0_MUX")
		)
		(pad "2" smd circle
			(at -0.40005 0 180)
			(size 0 0)
			(layers "B.Cu" "B.Mask" "B.Paste")
			(net "SPI_PEX2_SDIO0_MUX_R")
		)
	)
	(footprint ""
		(layer "B.Cu")
		(at 56.200802 -161.074862 -90)
		(property "Reference" "R50"
			(at 0 0 90)
			(layer "B.SilkS")
			(hide yes)
			(effects
				(font
					(size 1.27 1.27)
				)
				(justify mirror)
			)
		)
		(property "Value" ""
			(at 0 0 90)
			(layer "B.Fab")
			(effects
				(font
					(size 1.27 1.27)
				)
				(justify mirror)
			)
		)
		(duplicate_pad_numbers_are_jumpers no)
		(fp_line
			(start -0.7874 0.4064)
			(end 0.7874 0.4064)
			(stroke
				(width 0.1524)
				(type default)
			)
			(layer "B.SilkS")
		)
		(fp_line
			(start 0.7874 0.4064)
			(end 0.7874 -0.4064)
			(stroke
				(width 0.1524)
				(type default)
			)
			(layer "B.SilkS")
		)
		(fp_line
			(start -0.7874 -0.4064)
			(end -0.7874 0.4064)
			(stroke
				(width 0.1524)
				(type default)
			)
			(layer "B.SilkS")
		)
		(fp_line
			(start 0.7874 -0.4064)
			(end -0.7874 -0.4064)
			(stroke
				(width 0.1524)
				(type default)
			)
			(layer "B.SilkS")
		)
		(fp_line
			(start -0.67945 0.3048)
			(end -0.120396 0.3048)
			(stroke
				(width 0.1)
				(type default)
			)
			(layer "B.Fab")
		)
		(fp_line
			(start -0.120396 0.3048)
			(end -0.120396 0.2794)
			(stroke
				(width 0.1)
				(type default)
			)
			(layer "B.Fab")
		)
		(fp_line
			(start 0.12065 0.3048)
			(end 0.67945 0.3048)
			(stroke
				(width 0.1)
				(type default)
			)
			(layer "B.Fab")
		)
		(fp_line
			(start 0.67945 0.3048)
			(end 0.67945 -0.305054)
			(stroke
				(width 0.1)
				(type default)
			)
			(layer "B.Fab")
		)
		(fp_line
			(start -0.120396 0.2794)
			(end 0.12065 0.2794)
			(stroke
				(width 0.1)
				(type default)
			)
			(layer "B.Fab")
		)
		(fp_line
			(start 0.12065 0.2794)
			(end 0.12065 0.3048)
			(stroke
				(width 0.1)
				(type default)
			)
			(layer "B.Fab")
		)
		(fp_line
			(start -0.12065 -0.2794)
			(end -0.12065 -0.3048)
			(stroke
				(width 0.1)
				(type default)
			)
			(layer "B.Fab")
		)
		(fp_line
			(start 0.12065 -0.2794)
			(end -0.12065 -0.2794)
			(stroke
				(width 0.1)
				(type default)
			)
			(layer "B.Fab")
		)
		(fp_line
			(start -0.67945 -0.3048)
			(end -0.67945 0.3048)
			(stroke
				(width 0.1)
				(type default)
			)
			(layer "B.Fab")
		)
		(fp_line
			(start -0.12065 -0.3048)
			(end -0.67945 -0.3048)
			(stroke
				(width 0.1)
				(type default)
			)
			(layer "B.Fab")
		)
		(fp_line
			(start 0.12065 -0.305054)
			(end 0.12065 -0.2794)
			(stroke
				(width 0.1)
				(type default)
			)
			(layer "B.Fab")
		)
		(fp_line
			(start 0.67945 -0.305054)
			(end 0.12065 -0.305054)
			(stroke
				(width 0.1)
				(type default)
			)
			(layer "B.Fab")
		)
		(pad "1" smd circle
			(at 0.40005 0 90)
			(size 0 0)
			(layers "B.Cu" "B.Mask" "B.Paste")
			(net "P3V3_AUX")
		)
		(pad "2" smd circle
			(at -0.40005 0 90)
			(size 0 0)
			(layers "B.Cu" "B.Mask" "B.Paste")
			(net "HP_NIC0_HSC_PWRGD_N")
		)
	)
	(footprint ""
		(layer "B.Cu")
		(at 285.619952 -305.399948 -90)
		(property "Reference" "C3325"
			(at 0 0 90)
			(layer "B.SilkS")
			(hide yes)
			(effects
				(font
					(size 1.27 1.27)
				)
				(justify mirror)
			)
		)
		(property "Value" ""
			(at 0 0 90)
			(layer "B.Fab")
			(effects
				(font
					(size 1.27 1.27)
				)
				(justify mirror)
			)
		)
		(duplicate_pad_numbers_are_jumpers no)
		(fp_line
			(start -0.299974 0.150114)
			(end 0.299974 0.150114)
			(stroke
				(width 0.1)
				(type default)
			)
			(layer "B.Fab")
		)
		(fp_line
			(start 0.299974 0.150114)
			(end 0.299974 -0.150114)
			(stroke
				(width 0.1)
				(type default)
			)
			(layer "B.Fab")
		)
		(fp_line
			(start -0.299974 -0.150114)
			(end -0.299974 0.150114)
			(stroke
				(width 0.1)
				(type default)
			)
			(layer "B.Fab")
		)
		(fp_line
			(start 0.299974 -0.150114)
			(end -0.299974 -0.150114)
			(stroke
				(width 0.1)
				(type default)
			)
			(layer "B.Fab")
		)
		(pad "1" smd rect
			(at 0.2667 0 90)
			(size 0.3048 0.381)
			(layers "B.Cu" "B.Mask" "B.Paste")
			(net "P1V25_SERDES_VDDPLL_PEX2")
		)
		(pad "2" smd rect
			(at -0.2667 0 90)
			(size 0.3048 0.381)
			(layers "B.Cu" "B.Mask" "B.Paste")
			(net "GND")
		)
	)
	(footprint ""
		(layer "B.Cu")
		(at 131.075176 -221.640908 90)
		(property "Reference" "R3465"
			(at 0 0 90)
			(layer "B.SilkS")
			(hide yes)
			(effects
				(font
					(size 1.27 1.27)
				)
				(justify mirror)
			)
		)
		(property "Value" ""
			(at 0 0 90)
			(layer "B.Fab")
			(effects
				(font
					(size 1.27 1.27)
				)
				(justify mirror)
			)
		)
		(duplicate_pad_numbers_are_jumpers no)
		(fp_line
			(start 0.7874 -0.4064)
			(end -0.7874 -0.4064)
			(stroke
				(width 0.1524)
				(type default)
			)
			(layer "B.SilkS")
		)
		(fp_line
			(start -0.7874 -0.4064)
			(end -0.7874 0.4064)
			(stroke
				(width 0.1524)
				(type default)
			)
			(layer "B.SilkS")
		)
		(fp_line
			(start 0.7874 0.4064)
			(end 0.7874 -0.4064)
			(stroke
				(width 0.1524)
				(type default)
			)
			(layer "B.SilkS")
		)
		(fp_line
			(start -0.7874 0.4064)
			(end 0.7874 0.4064)
			(stroke
				(width 0.1524)
				(type default)
			)
			(layer "B.SilkS")
		)
		(fp_line
			(start 0.67945 -0.305054)
			(end 0.12065 -0.305054)
			(stroke
				(width 0.1)
				(type default)
			)
			(layer "B.Fab")
		)
		(fp_line
			(start 0.12065 -0.305054)
			(end 0.12065 -0.2794)
			(stroke
				(width 0.1)
				(type default)
			)
			(layer "B.Fab")
		)
		(fp_line
			(start -0.12065 -0.3048)
			(end -0.67945 -0.3048)
			(stroke
				(width 0.1)
				(type default)
			)
			(layer "B.Fab")
		)
		(fp_line
			(start -0.67945 -0.3048)
			(end -0.67945 0.3048)
			(stroke
				(width 0.1)
				(type default)
			)
			(layer "B.Fab")
		)
		(fp_line
			(start 0.12065 -0.2794)
			(end -0.12065 -0.2794)
			(stroke
				(width 0.1)
				(type default)
			)
			(layer "B.Fab")
		)
		(fp_line
			(start -0.12065 -0.2794)
			(end -0.12065 -0.3048)
			(stroke
				(width 0.1)
				(type default)
			)
			(layer "B.Fab")
		)
		(fp_line
			(start 0.12065 0.2794)
			(end 0.12065 0.3048)
			(stroke
				(width 0.1)
				(type default)
			)
			(layer "B.Fab")
		)
		(fp_line
			(start -0.120396 0.2794)
			(end 0.12065 0.2794)
			(stroke
				(width 0.1)
				(type default)
			)
			(layer "B.Fab")
		)
		(fp_line
			(start 0.67945 0.3048)
			(end 0.67945 -0.305054)
			(stroke
				(width 0.1)
				(type default)
			)
			(layer "B.Fab")
		)
		(fp_line
			(start 0.12065 0.3048)
			(end 0.67945 0.3048)
			(stroke
				(width 0.1)
				(type default)
			)
			(layer "B.Fab")
		)
		(fp_line
			(start -0.120396 0.3048)
			(end -0.120396 0.2794)
			(stroke
				(width 0.1)
				(type default)
			)
			(layer "B.Fab")
		)
		(fp_line
			(start -0.67945 0.3048)
			(end -0.120396 0.3048)
			(stroke
				(width 0.1)
				(type default)
			)
			(layer "B.Fab")
		)
		(pad "1" smd circle
			(at 0.40005 0 270)
			(size 0 0)
			(layers "B.Cu" "B.Mask" "B.Paste")
			(net "SPI_PEX1_CLK_MUX")
		)
		(pad "2" smd circle
			(at -0.40005 0 270)
			(size 0 0)
			(layers "B.Cu" "B.Mask" "B.Paste")
			(net "SPI_PEX1_CLK_MUX_R")
		)
	)
	(footprint ""
		(layer "B.Cu")
		(at 228.189536 -150.44293 90)
		(property "Reference" "C2804"
			(at 0 0 90)
			(layer "B.SilkS")
			(hide yes)
			(effects
				(font
					(size 1.27 1.27)
				)
				(justify mirror)
			)
		)
		(property "Value" ""
			(at 0 0 90)
			(layer "B.Fab")
			(effects
				(font
					(size 1.27 1.27)
				)
				(justify mirror)
			)
		)
		(duplicate_pad_numbers_are_jumpers no)
		(fp_line
			(start 0.7874 -0.4064)
			(end -0.7874 -0.4064)
			(stroke
				(width 0.1524)
				(type default)
			)
			(layer "B.SilkS")
		)
		(fp_line
			(start -0.7874 -0.4064)
			(end -0.7874 0.4064)
			(stroke
				(width 0.1524)
				(type default)
			)
			(layer "B.SilkS")
		)
		(fp_line
			(start 0.7874 0.4064)
			(end 0.7874 -0.4064)
			(stroke
				(width 0.1524)
				(type default)
			)
			(layer "B.SilkS")
		)
		(fp_line
			(start -0.7874 0.4064)
			(end 0.7874 0.4064)
			(stroke
				(width 0.1524)
				(type default)
			)
			(layer "B.SilkS")
		)
		(fp_line
			(start 0.67945 -0.305054)
			(end 0.12065 -0.305054)
			(stroke
				(width 0.1)
				(type default)
			)
			(layer "B.Fab")
		)
		(fp_line
			(start 0.12065 -0.305054)
			(end 0.12065 -0.2794)
			(stroke
				(width 0.1)
				(type default)
			)
			(layer "B.Fab")
		)
		(fp_line
			(start -0.12065 -0.3048)
			(end -0.67945 -0.3048)
			(stroke
				(width 0.1)
				(type default)
			)
			(layer "B.Fab")
		)
		(fp_line
			(start -0.67945 -0.3048)
			(end -0.67945 0.3048)
			(stroke
				(width 0.1)
				(type default)
			)
			(layer "B.Fab")
		)
		(fp_line
			(start 0.12065 -0.2794)
			(end -0.12065 -0.2794)
			(stroke
				(width 0.1)
				(type default)
			)
			(layer "B.Fab")
		)
		(fp_line
			(start -0.12065 -0.2794)
			(end -0.12065 -0.3048)
			(stroke
				(width 0.1)
				(type default)
			)
			(layer "B.Fab")
		)
		(fp_line
			(start 0.12065 0.2794)
			(end 0.12065 0.3048)
			(stroke
				(width 0.1)
				(type default)
			)
			(layer "B.Fab")
		)
		(fp_line
			(start -0.120396 0.2794)
			(end 0.12065 0.2794)
			(stroke
				(width 0.1)
				(type default)
			)
			(layer "B.Fab")
		)
		(fp_line
			(start 0.67945 0.3048)
			(end 0.67945 -0.305054)
			(stroke
				(width 0.1)
				(type default)
			)
			(layer "B.Fab")
		)
		(fp_line
			(start 0.12065 0.3048)
			(end 0.67945 0.3048)
			(stroke
				(width 0.1)
				(type default)
			)
			(layer "B.Fab")
		)
		(fp_line
			(start -0.120396 0.3048)
			(end -0.120396 0.2794)
			(stroke
				(width 0.1)
				(type default)
			)
			(layer "B.Fab")
		)
		(fp_line
			(start -0.67945 0.3048)
			(end -0.120396 0.3048)
			(stroke
				(width 0.1)
				(type default)
			)
			(layer "B.Fab")
		)
		(pad "1" smd circle
			(at 0.40005 0 270)
			(size 0 0)
			(layers "B.Cu" "B.Mask" "B.Paste")
			(net "P3V3_CLK_GEN_VDDMXCK_CK440_PEX")
		)
		(pad "2" smd circle
			(at -0.40005 0 270)
			(size 0 0)
			(layers "B.Cu" "B.Mask" "B.Paste")
			(net "GND")
		)
	)
	(footprint ""
		(layer "B.Cu")
		(at 162.4457 -296.37482)
		(property "Reference" "C3203"
			(at 0 0 0)
			(layer "B.SilkS")
			(hide yes)
			(effects
				(font
					(size 1.27 1.27)
				)
				(justify mirror)
			)
		)
		(property "Value" ""
			(at 0 0 0)
			(layer "B.Fab")
			(effects
				(font
					(size 1.27 1.27)
				)
				(justify mirror)
			)
		)
		(duplicate_pad_numbers_are_jumpers no)
		(fp_line
			(start -0.299974 -0.150114)
			(end -0.299974 0.150114)
			(stroke
				(width 0.1)
				(type default)
			)
			(layer "B.Fab")
		)
		(fp_line
			(start -0.299974 0.150114)
			(end 0.299974 0.150114)
			(stroke
				(width 0.1)
				(type default)
			)
			(layer "B.Fab")
		)
		(fp_line
			(start 0.299974 -0.150114)
			(end -0.299974 -0.150114)
			(stroke
				(width 0.1)
				(type default)
			)
			(layer "B.Fab")
		)
		(fp_line
			(start 0.299974 0.150114)
			(end 0.299974 -0.150114)
			(stroke
				(width 0.1)
				(type default)
			)
			(layer "B.Fab")
		)
		(pad "1" smd rect
			(at 0.2667 0 180)
			(size 0.3048 0.381)
			(layers "B.Cu" "B.Mask" "B.Paste")
			(net "PCEPLL2_VDDA18_PEX1")
		)
		(pad "2" smd rect
			(at -0.2667 0 180)
			(size 0.3048 0.381)
			(layers "B.Cu" "B.Mask" "B.Paste")
			(net "GND")
		)
	)
	(footprint ""
		(layer "B.Cu")
		(at 296.992802 -445.151764 180)
		(property "Reference" "X81"
			(at 0.1778 -1.92913 180)
			(unlocked yes)
			(layer "B.SilkS")
			(effects
				(font
					(size 0.7874 0.5842)
					(thickness 0.1524)
				)
				(justify left mirror)
			)
		)
		(property "Value" ""
			(at 0 0 0)
			(layer "B.Fab")
			(effects
				(font
					(size 1.27 1.27)
				)
				(justify mirror)
			)
		)
		(property "Device Type" "TP_TDR_4P_FTS_MPKT4_H025P0200_IO_TP15_TP_TDR_4P_DIP"
			(at -1.30175 1.27 90)
			(unlocked yes)
			(layer "B.Fab")
			(hide yes)
			(effects
				(font
					(size 0.635 0.4064)
					(thickness 0.1524)
				)
				(justify mirror)
			)
		)
		(property "User Part Number" "TP15"
			(at -1.30175 1.27 90)
			(unlocked yes)
			(layer "Cmts.User")
			(hide yes)
			(effects
				(font
					(size 0.635 0.4064)
					(thickness 0.1524)
				)
				(justify mirror)
			)
		)
		(duplicate_pad_numbers_are_jumpers no)
		(fp_line
			(start 0 3.81)
			(end -2.54 3.81)
			(stroke
				(width 0.1524)
				(type default)
			)
			(layer "B.SilkS")
		)
		(fp_line
			(start 0 3.175)
			(end 0 3.81)
			(stroke
				(width 0.1524)
				(type default)
			)
			(layer "B.SilkS")
		)
		(fp_line
			(start 0 0.635)
			(end 0 1.905)
			(stroke
				(width 0.1524)
				(type default)
			)
			(layer "B.SilkS")
		)
		(fp_line
			(start 0 -1.27)
			(end 0 -0.635)
			(stroke
				(width 0.1524)
				(type default)
			)
			(layer "B.SilkS")
		)
		(fp_line
			(start -2.54 3.81)
			(end -2.54 3.6703)
			(stroke
				(width 0.1524)
				(type default)
			)
			(layer "B.SilkS")
		)
		(fp_line
			(start -2.54 1.4097)
			(end -2.54 1.1303)
			(stroke
				(width 0.1524)
				(type default)
			)
			(layer "B.SilkS")
		)
		(fp_line
			(start -2.54 -1.1303)
			(end -2.54 -1.27)
			(stroke
				(width 0.1524)
				(type default)
			)
			(layer "B.SilkS")
		)
		(fp_line
			(start -2.54 -1.27)
			(end 0 -1.27)
			(stroke
				(width 0.1524)
				(type default)
			)
			(layer "B.SilkS")
		)
		(fp_poly
			(pts
				(xy 0.761746 0) (xy 2.285746 -0.762) (xy 2.285746 0.762)
			)
			(stroke
				(width 0)
				(type default)
			)
			(fill yes)
			(layer "B.SilkS")
		)
		(fp_line
			(start 0 3.81)
			(end -2.54 3.81)
			(stroke
				(width 0.1)
				(type default)
			)
			(layer "B.Fab")
		)
		(fp_line
			(start 0 -1.27)
			(end 0 3.81)
			(stroke
				(width 0.1)
				(type default)
			)
			(layer "B.Fab")
		)
		(fp_line
			(start -2.54 3.81)
			(end -2.54 -1.27)
			(stroke
				(width 0.1)
				(type default)
			)
			(layer "B.Fab")
		)
		(fp_line
			(start -2.54 -1.27)
			(end 0 -1.27)
			(stroke
				(width 0.1)
				(type default)
			)
			(layer "B.Fab")
		)
		(fp_poly
			(pts
				(xy 0.761746 0) (xy 2.285746 -0.762) (xy 2.285746 0.762)
			)
			(stroke
				(width 0)
				(type default)
			)
			(fill yes)
			(layer "B.Fab")
		)
		(pad "1" thru_hole circle
			(at 0 0)
			(size 1.0033 1.0033)
			(drill 0.249936)
			(layers "*.Cu" "*.Mask")
			(remove_unused_layers no)
			(net "TDR_DIFF_100_BOT_DIN")
			(clearance 0.10795)
			(padstack
				(mode front_inner_back)
				(layer "Inner"
					(shape circle)
					(size 0.8001 0.8001)
					(clearance 0.1524)
				)
				(layer "B.Cu"
					(shape circle)
					(size 1.0033 1.0033)
					(thermal_gap 0.10795)
					(clearance 0.10795)
				)
			)
		)
		(pad "2" thru_hole circle
			(at -2.54 0)
			(size 1.9939 1.9939)
			(drill 0.249936)
			(layers "*.Cu" "*.Mask")
			(remove_unused_layers no)
			(net "COUPON_GND1")
			(clearance 0.10795)
			(padstack
				(mode front_inner_back)
				(layer "Inner"
					(shape circle)
					(size 0.8001 0.8001)
					(clearance 0.1524)
				)
				(layer "B.Cu"
					(shape circle)
					(size 1.9939 1.9939)
					(thermal_gap 0.10795)
					(clearance 0.10795)
				)
			)
		)
		(pad "3" thru_hole circle
			(at -2.54 2.54)
			(size 1.9939 1.9939)
			(drill 0.249936)
			(layers "*.Cu" "*.Mask")
			(remove_unused_layers no)
			(net "COUPON_GND1")
			(clearance 0.10795)
			(padstack
				(mode front_inner_back)
				(layer "Inner"
					(shape circle)
					(size 0.8001 0.8001)
					(clearance 0.1524)
				)
				(layer "B.Cu"
					(shape circle)
					(size 1.9939 1.9939)
					(thermal_gap 0.10795)
					(clearance 0.10795)
				)
			)
		)
		(pad "4" thru_hole circle
			(at 0 2.54)
			(size 1.0033 1.0033)
			(drill 0.249936)
			(layers "*.Cu" "*.Mask")
			(remove_unused_layers no)
			(net "TDR_DIFF_100_BOT_DIP")
			(clearance 0.10795)
			(padstack
				(mode front_inner_back)
				(layer "Inner"
					(shape circle)
					(size 0.8001 0.8001)
					(clearance 0.1524)
				)
				(layer "B.Cu"
					(shape circle)
					(size 1.0033 1.0033)
					(thermal_gap 0.10795)
					(clearance 0.10795)
				)
			)
		)
	)
	(footprint ""
		(layer "B.Cu")
		(at 405.393652 -376.492262 90)
		(property "Reference" "R6278"
			(at 0 0 90)
			(layer "B.SilkS")
			(hide yes)
			(effects
				(font
					(size 1.27 1.27)
				)
				(justify mirror)
			)
		)
		(property "Value" ""
			(at 0 0 90)
			(layer "B.Fab")
			(effects
				(font
					(size 1.27 1.27)
				)
				(justify mirror)
			)
		)
		(duplicate_pad_numbers_are_jumpers no)
		(fp_line
			(start 0.7874 -0.4064)
			(end -0.7874 -0.4064)
			(stroke
				(width 0.1524)
				(type default)
			)
			(layer "B.SilkS")
		)
		(fp_line
			(start -0.7874 -0.4064)
			(end -0.7874 0.4064)
			(stroke
				(width 0.1524)
				(type default)
			)
			(layer "B.SilkS")
		)
		(fp_line
			(start 0.7874 0.4064)
			(end 0.7874 -0.4064)
			(stroke
				(width 0.1524)
				(type default)
			)
			(layer "B.SilkS")
		)
		(fp_line
			(start -0.7874 0.4064)
			(end 0.7874 0.4064)
			(stroke
				(width 0.1524)
				(type default)
			)
			(layer "B.SilkS")
		)
		(fp_line
			(start 0.67945 -0.305054)
			(end 0.12065 -0.305054)
			(stroke
				(width 0.1)
				(type default)
			)
			(layer "B.Fab")
		)
		(fp_line
			(start 0.12065 -0.305054)
			(end 0.12065 -0.2794)
			(stroke
				(width 0.1)
				(type default)
			)
			(layer "B.Fab")
		)
		(fp_line
			(start -0.12065 -0.3048)
			(end -0.67945 -0.3048)
			(stroke
				(width 0.1)
				(type default)
			)
			(layer "B.Fab")
		)
		(fp_line
			(start -0.67945 -0.3048)
			(end -0.67945 0.3048)
			(stroke
				(width 0.1)
				(type default)
			)
			(layer "B.Fab")
		)
		(fp_line
			(start 0.12065 -0.2794)
			(end -0.12065 -0.2794)
			(stroke
				(width 0.1)
				(type default)
			)
			(layer "B.Fab")
		)
		(fp_line
			(start -0.12065 -0.2794)
			(end -0.12065 -0.3048)
			(stroke
				(width 0.1)
				(type default)
			)
			(layer "B.Fab")
		)
		(fp_line
			(start 0.12065 0.2794)
			(end 0.12065 0.3048)
			(stroke
				(width 0.1)
				(type default)
			)
			(layer "B.Fab")
		)
		(fp_line
			(start -0.120396 0.2794)
			(end 0.12065 0.2794)
			(stroke
				(width 0.1)
				(type default)
			)
			(layer "B.Fab")
		)
		(fp_line
			(start 0.67945 0.3048)
			(end 0.67945 -0.305054)
			(stroke
				(width 0.1)
				(type default)
			)
			(layer "B.Fab")
		)
		(fp_line
			(start 0.12065 0.3048)
			(end 0.67945 0.3048)
			(stroke
				(width 0.1)
				(type default)
			)
			(layer "B.Fab")
		)
		(fp_line
			(start -0.120396 0.3048)
			(end -0.120396 0.2794)
			(stroke
				(width 0.1)
				(type default)
			)
			(layer "B.Fab")
		)
		(fp_line
			(start -0.67945 0.3048)
			(end -0.120396 0.3048)
			(stroke
				(width 0.1)
				(type default)
			)
			(layer "B.Fab")
		)
		(pad "1" smd circle
			(at 0.40005 0 270)
			(size 0 0)
			(layers "B.Cu" "B.Mask" "B.Paste")
			(net "I3C_MB_BMC_R_SCL")
		)
		(pad "2" smd circle
			(at -0.40005 0 270)
			(size 0 0)
			(layers "B.Cu" "B.Mask" "B.Paste")
			(net "SMB_MB_I3C_ISO_SCL")
		)
	)
	(footprint ""
		(layer "B.Cu")
		(at 117.847364 -282.04033 90)
		(property "Reference" "PR105"
			(at 0 0 90)
			(layer "B.SilkS")
			(hide yes)
			(effects
				(font
					(size 1.27 1.27)
				)
				(justify mirror)
			)
		)
		(property "Value" ""
			(at 0 0 90)
			(layer "B.Fab")
			(effects
				(font
					(size 1.27 1.27)
				)
				(justify mirror)
			)
		)
		(duplicate_pad_numbers_are_jumpers no)
		(fp_line
			(start 0.7874 -0.4064)
			(end -0.7874 -0.4064)
			(stroke
				(width 0.1524)
				(type default)
			)
			(layer "B.SilkS")
		)
		(fp_line
			(start -0.7874 -0.4064)
			(end -0.7874 0.4064)
			(stroke
				(width 0.1524)
				(type default)
			)
			(layer "B.SilkS")
		)
		(fp_line
			(start 0.7874 0.4064)
			(end 0.7874 -0.4064)
			(stroke
				(width 0.1524)
				(type default)
			)
			(layer "B.SilkS")
		)
		(fp_line
			(start -0.7874 0.4064)
			(end 0.7874 0.4064)
			(stroke
				(width 0.1524)
				(type default)
			)
			(layer "B.SilkS")
		)
		(fp_line
			(start 0.67945 -0.305054)
			(end 0.12065 -0.305054)
			(stroke
				(width 0.1)
				(type default)
			)
			(layer "B.Fab")
		)
		(fp_line
			(start 0.12065 -0.305054)
			(end 0.12065 -0.2794)
			(stroke
				(width 0.1)
				(type default)
			)
			(layer "B.Fab")
		)
		(fp_line
			(start -0.12065 -0.3048)
			(end -0.67945 -0.3048)
			(stroke
				(width 0.1)
				(type default)
			)
			(layer "B.Fab")
		)
		(fp_line
			(start -0.67945 -0.3048)
			(end -0.67945 0.3048)
			(stroke
				(width 0.1)
				(type default)
			)
			(layer "B.Fab")
		)
		(fp_line
			(start 0.12065 -0.2794)
			(end -0.12065 -0.2794)
			(stroke
				(width 0.1)
				(type default)
			)
			(layer "B.Fab")
		)
		(fp_line
			(start -0.12065 -0.2794)
			(end -0.12065 -0.3048)
			(stroke
				(width 0.1)
				(type default)
			)
			(layer "B.Fab")
		)
		(fp_line
			(start 0.12065 0.2794)
			(end 0.12065 0.3048)
			(stroke
				(width 0.1)
				(type default)
			)
			(layer "B.Fab")
		)
		(fp_line
			(start -0.120396 0.2794)
			(end 0.12065 0.2794)
			(stroke
				(width 0.1)
				(type default)
			)
			(layer "B.Fab")
		)
		(fp_line
			(start 0.67945 0.3048)
			(end 0.67945 -0.305054)
			(stroke
				(width 0.1)
				(type default)
			)
			(layer "B.Fab")
		)
		(fp_line
			(start 0.12065 0.3048)
			(end 0.67945 0.3048)
			(stroke
				(width 0.1)
				(type default)
			)
			(layer "B.Fab")
		)
		(fp_line
			(start -0.120396 0.3048)
			(end -0.120396 0.2794)
			(stroke
				(width 0.1)
				(type default)
			)
			(layer "B.Fab")
		)
		(fp_line
			(start -0.67945 0.3048)
			(end -0.120396 0.3048)
			(stroke
				(width 0.1)
				(type default)
			)
			(layer "B.Fab")
		)
		(pad "1" smd circle
			(at 0.40005 0 270)
			(size 0 0)
			(layers "B.Cu" "B.Mask" "B.Paste")
			(net "SW_P0V8_PEX0_VOS2")
		)
		(pad "2" smd circle
			(at -0.40005 0 270)
			(size 0 0)
			(layers "B.Cu" "B.Mask" "B.Paste")
			(net "P0V8_PEX0")
		)
	)
	(footprint ""
		(layer "B.Cu")
		(at 53.949854 -290.199826 90)
		(property "Reference" "C1206"
			(at 0 0 90)
			(layer "B.SilkS")
			(hide yes)
			(effects
				(font
					(size 1.27 1.27)
				)
				(justify mirror)
			)
		)
		(property "Value" ""
			(at 0 0 90)
			(layer "B.Fab")
			(effects
				(font
					(size 1.27 1.27)
				)
				(justify mirror)
			)
		)
		(duplicate_pad_numbers_are_jumpers no)
		(fp_line
			(start 0.299974 -0.150114)
			(end -0.299974 -0.150114)
			(stroke
				(width 0.1)
				(type default)
			)
			(layer "B.Fab")
		)
		(fp_line
			(start -0.299974 -0.150114)
			(end -0.299974 0.150114)
			(stroke
				(width 0.1)
				(type default)
			)
			(layer "B.Fab")
		)
		(fp_line
			(start 0.299974 0.150114)
			(end 0.299974 -0.150114)
			(stroke
				(width 0.1)
				(type default)
			)
			(layer "B.Fab")
		)
		(fp_line
			(start -0.299974 0.150114)
			(end 0.299974 0.150114)
			(stroke
				(width 0.1)
				(type default)
			)
			(layer "B.Fab")
		)
		(pad "1" smd rect
			(at 0.2667 0 270)
			(size 0.3048 0.381)
			(layers "B.Cu" "B.Mask" "B.Paste")
			(net "P0V8_SERDES_VDDA_PEX0")
		)
		(pad "2" smd rect
			(at -0.2667 0 270)
			(size 0.3048 0.381)
			(layers "B.Cu" "B.Mask" "B.Paste")
			(net "GND")
		)
	)
	(footprint ""
		(layer "B.Cu")
		(at 348.328488 -304.157634)
		(property "Reference" "PR127"
			(at 0 0 0)
			(layer "B.SilkS")
			(hide yes)
			(effects
				(font
					(size 1.27 1.27)
				)
				(justify mirror)
			)
		)
		(property "Value" ""
			(at 0 0 0)
			(layer "B.Fab")
			(effects
				(font
					(size 1.27 1.27)
				)
				(justify mirror)
			)
		)
		(duplicate_pad_numbers_are_jumpers no)
		(fp_line
			(start -0.7874 -0.4064)
			(end -0.7874 0.4064)
			(stroke
				(width 0.1524)
				(type default)
			)
			(layer "B.SilkS")
		)
		(fp_line
			(start -0.7874 0.4064)
			(end 0.7874 0.4064)
			(stroke
				(width 0.1524)
				(type default)
			)
			(layer "B.SilkS")
		)
		(fp_line
			(start 0.7874 -0.4064)
			(end -0.7874 -0.4064)
			(stroke
				(width 0.1524)
				(type default)
			)
			(layer "B.SilkS")
		)
		(fp_line
			(start 0.7874 0.4064)
			(end 0.7874 -0.4064)
			(stroke
				(width 0.1524)
				(type default)
			)
			(layer "B.SilkS")
		)
		(fp_line
			(start -0.67945 -0.3048)
			(end -0.67945 0.3048)
			(stroke
				(width 0.1)
				(type default)
			)
			(layer "B.Fab")
		)
		(fp_line
			(start -0.67945 0.3048)
			(end -0.120396 0.3048)
			(stroke
				(width 0.1)
				(type default)
			)
			(layer "B.Fab")
		)
		(fp_line
			(start -0.12065 -0.3048)
			(end -0.67945 -0.3048)
			(stroke
				(width 0.1)
				(type default)
			)
			(layer "B.Fab")
		)
		(fp_line
			(start -0.12065 -0.2794)
			(end -0.12065 -0.3048)
			(stroke
				(width 0.1)
				(type default)
			)
			(layer "B.Fab")
		)
		(fp_line
			(start -0.120396 0.2794)
			(end 0.12065 0.2794)
			(stroke
				(width 0.1)
				(type default)
			)
			(layer "B.Fab")
		)
		(fp_line
			(start -0.120396 0.3048)
			(end -0.120396 0.2794)
			(stroke
				(width 0.1)
				(type default)
			)
			(layer "B.Fab")
		)
		(fp_line
			(start 0.12065 -0.305054)
			(end 0.12065 -0.2794)
			(stroke
				(width 0.1)
				(type default)
			)
			(layer "B.Fab")
		)
		(fp_line
			(start 0.12065 -0.2794)
			(end -0.12065 -0.2794)
			(stroke
				(width 0.1)
				(type default)
			)
			(layer "B.Fab")
		)
		(fp_line
			(start 0.12065 0.2794)
			(end 0.12065 0.3048)
			(stroke
				(width 0.1)
				(type default)
			)
			(layer "B.Fab")
		)
		(fp_line
			(start 0.12065 0.3048)
			(end 0.67945 0.3048)
			(stroke
				(width 0.1)
				(type default)
			)
			(layer "B.Fab")
		)
		(fp_line
			(start 0.67945 -0.305054)
			(end 0.12065 -0.305054)
			(stroke
				(width 0.1)
				(type default)
			)
			(layer "B.Fab")
		)
		(fp_line
			(start 0.67945 0.3048)
			(end 0.67945 -0.305054)
			(stroke
				(width 0.1)
				(type default)
			)
			(layer "B.Fab")
		)
		(pad "1" smd circle
			(at 0.40005 0 180)
			(size 0 0)
			(layers "B.Cu" "B.Mask" "B.Paste")
			(net "SH_P0V8_PEX2_RGND2")
		)
		(pad "2" smd circle
			(at -0.40005 0 180)
			(size 0 0)
			(layers "B.Cu" "B.Mask" "B.Paste")
			(net "GND")
		)
	)
	(footprint ""
		(layer "B.Cu")
		(at 295.649904 -292.099746 90)
		(property "Reference" "C1720"
			(at 0 0 90)
			(layer "B.SilkS")
			(hide yes)
			(effects
				(font
					(size 1.27 1.27)
				)
				(justify mirror)
			)
		)
		(property "Value" ""
			(at 0 0 90)
			(layer "B.Fab")
			(effects
				(font
					(size 1.27 1.27)
				)
				(justify mirror)
			)
		)
		(duplicate_pad_numbers_are_jumpers no)
		(fp_line
			(start 0.299974 -0.150114)
			(end -0.299974 -0.150114)
			(stroke
				(width 0.1)
				(type default)
			)
			(layer "B.Fab")
		)
		(fp_line
			(start -0.299974 -0.150114)
			(end -0.299974 0.150114)
			(stroke
				(width 0.1)
				(type default)
			)
			(layer "B.Fab")
		)
		(fp_line
			(start 0.299974 0.150114)
			(end 0.299974 -0.150114)
			(stroke
				(width 0.1)
				(type default)
			)
			(layer "B.Fab")
		)
		(fp_line
			(start -0.299974 0.150114)
			(end 0.299974 0.150114)
			(stroke
				(width 0.1)
				(type default)
			)
			(layer "B.Fab")
		)
		(pad "1" smd rect
			(at 0.2667 0 270)
			(size 0.3048 0.381)
			(layers "B.Cu" "B.Mask" "B.Paste")
			(net "P0V8_SERDES_VDDA_PEX2")
		)
		(pad "2" smd rect
			(at -0.2667 0 270)
			(size 0.3048 0.381)
			(layers "B.Cu" "B.Mask" "B.Paste")
			(net "GND")
		)
	)
	(footprint ""
		(layer "B.Cu")
		(at 63.470282 -296.37482)
		(property "Reference" "C1130"
			(at 0 0 0)
			(layer "B.SilkS")
			(hide yes)
			(effects
				(font
					(size 1.27 1.27)
				)
				(justify mirror)
			)
		)
		(property "Value" ""
			(at 0 0 0)
			(layer "B.Fab")
			(effects
				(font
					(size 1.27 1.27)
				)
				(justify mirror)
			)
		)
		(duplicate_pad_numbers_are_jumpers no)
		(fp_line
			(start -0.299974 -0.150114)
			(end -0.299974 0.150114)
			(stroke
				(width 0.1)
				(type default)
			)
			(layer "B.Fab")
		)
		(fp_line
			(start -0.299974 0.150114)
			(end 0.299974 0.150114)
			(stroke
				(width 0.1)
				(type default)
			)
			(layer "B.Fab")
		)
		(fp_line
			(start 0.299974 -0.150114)
			(end -0.299974 -0.150114)
			(stroke
				(width 0.1)
				(type default)
			)
			(layer "B.Fab")
		)
		(fp_line
			(start 0.299974 0.150114)
			(end 0.299974 -0.150114)
			(stroke
				(width 0.1)
				(type default)
			)
			(layer "B.Fab")
		)
		(pad "1" smd rect
			(at 0.2667 0 180)
			(size 0.3048 0.381)
			(layers "B.Cu" "B.Mask" "B.Paste")
			(net "P0V8_PEX0")
		)
		(pad "2" smd rect
			(at -0.2667 0 180)
			(size 0.3048 0.381)
			(layers "B.Cu" "B.Mask" "B.Paste")
			(net "GND")
		)
	)
	(footprint ""
		(layer "B.Cu")
		(at 104.135174 -390.013444 -90)
		(property "Reference" "C3629"
			(at 0 0 90)
			(layer "B.SilkS")
			(hide yes)
			(effects
				(font
					(size 1.27 1.27)
				)
				(justify mirror)
			)
		)
		(property "Value" ""
			(at 0 0 90)
			(layer "B.Fab")
			(effects
				(font
					(size 1.27 1.27)
				)
				(justify mirror)
			)
		)
		(duplicate_pad_numbers_are_jumpers no)
		(fp_line
			(start -0.7874 0.4064)
			(end 0.7874 0.4064)
			(stroke
				(width 0.1524)
				(type default)
			)
			(layer "B.SilkS")
		)
		(fp_line
			(start 0.7874 0.4064)
			(end 0.7874 -0.4064)
			(stroke
				(width 0.1524)
				(type default)
			)
			(layer "B.SilkS")
		)
		(fp_line
			(start -0.7874 -0.4064)
			(end -0.7874 0.4064)
			(stroke
				(width 0.1524)
				(type default)
			)
			(layer "B.SilkS")
		)
		(fp_line
			(start 0.7874 -0.4064)
			(end -0.7874 -0.4064)
			(stroke
				(width 0.1524)
				(type default)
			)
			(layer "B.SilkS")
		)
		(fp_line
			(start -0.67945 0.3048)
			(end -0.120396 0.3048)
			(stroke
				(width 0.1)
				(type default)
			)
			(layer "B.Fab")
		)
		(fp_line
			(start -0.120396 0.3048)
			(end -0.120396 0.2794)
			(stroke
				(width 0.1)
				(type default)
			)
			(layer "B.Fab")
		)
		(fp_line
			(start 0.12065 0.3048)
			(end 0.67945 0.3048)
			(stroke
				(width 0.1)
				(type default)
			)
			(layer "B.Fab")
		)
		(fp_line
			(start 0.67945 0.3048)
			(end 0.67945 -0.305054)
			(stroke
				(width 0.1)
				(type default)
			)
			(layer "B.Fab")
		)
		(fp_line
			(start -0.120396 0.2794)
			(end 0.12065 0.2794)
			(stroke
				(width 0.1)
				(type default)
			)
			(layer "B.Fab")
		)
		(fp_line
			(start 0.12065 0.2794)
			(end 0.12065 0.3048)
			(stroke
				(width 0.1)
				(type default)
			)
			(layer "B.Fab")
		)
		(fp_line
			(start -0.12065 -0.2794)
			(end -0.12065 -0.3048)
			(stroke
				(width 0.1)
				(type default)
			)
			(layer "B.Fab")
		)
		(fp_line
			(start 0.12065 -0.2794)
			(end -0.12065 -0.2794)
			(stroke
				(width 0.1)
				(type default)
			)
			(layer "B.Fab")
		)
		(fp_line
			(start -0.67945 -0.3048)
			(end -0.67945 0.3048)
			(stroke
				(width 0.1)
				(type default)
			)
			(layer "B.Fab")
		)
		(fp_line
			(start -0.12065 -0.3048)
			(end -0.67945 -0.3048)
			(stroke
				(width 0.1)
				(type default)
			)
			(layer "B.Fab")
		)
		(fp_line
			(start 0.12065 -0.305054)
			(end 0.12065 -0.2794)
			(stroke
				(width 0.1)
				(type default)
			)
			(layer "B.Fab")
		)
		(fp_line
			(start 0.67945 -0.305054)
			(end 0.12065 -0.305054)
			(stroke
				(width 0.1)
				(type default)
			)
			(layer "B.Fab")
		)
		(pad "1" smd circle
			(at 0.40005 0 90)
			(size 0 0)
			(layers "B.Cu" "B.Mask" "B.Paste")
			(net "P3V3_BIC_USB_HUB")
		)
		(pad "2" smd circle
			(at -0.40005 0 90)
			(size 0 0)
			(layers "B.Cu" "B.Mask" "B.Paste")
			(net "GND")
		)
	)
	(footprint ""
		(layer "B.Cu")
		(at 176.224946 -293.99992 -90)
		(property "Reference" "C1406"
			(at 0 0 90)
			(layer "B.SilkS")
			(hide yes)
			(effects
				(font
					(size 1.27 1.27)
				)
				(justify mirror)
			)
		)
		(property "Value" ""
			(at 0 0 90)
			(layer "B.Fab")
			(effects
				(font
					(size 1.27 1.27)
				)
				(justify mirror)
			)
		)
		(duplicate_pad_numbers_are_jumpers no)
		(fp_line
			(start -0.299974 0.150114)
			(end 0.299974 0.150114)
			(stroke
				(width 0.1)
				(type default)
			)
			(layer "B.Fab")
		)
		(fp_line
			(start 0.299974 0.150114)
			(end 0.299974 -0.150114)
			(stroke
				(width 0.1)
				(type default)
			)
			(layer "B.Fab")
		)
		(fp_line
			(start -0.299974 -0.150114)
			(end -0.299974 0.150114)
			(stroke
				(width 0.1)
				(type default)
			)
			(layer "B.Fab")
		)
		(fp_line
			(start 0.299974 -0.150114)
			(end -0.299974 -0.150114)
			(stroke
				(width 0.1)
				(type default)
			)
			(layer "B.Fab")
		)
		(pad "1" smd rect
			(at 0.2667 0 90)
			(size 0.3048 0.381)
			(layers "B.Cu" "B.Mask" "B.Paste")
			(net "P0V8_PEX1")
		)
		(pad "2" smd rect
			(at -0.2667 0 90)
			(size 0.3048 0.381)
			(layers "B.Cu" "B.Mask" "B.Paste")
			(net "GND")
		)
	)
	(footprint ""
		(layer "B.Cu")
		(at 62.974982 -286.399732 90)
		(property "Reference" "C2969"
			(at 0 0 90)
			(layer "B.SilkS")
			(hide yes)
			(effects
				(font
					(size 1.27 1.27)
				)
				(justify mirror)
			)
		)
		(property "Value" ""
			(at 0 0 90)
			(layer "B.Fab")
			(effects
				(font
					(size 1.27 1.27)
				)
				(justify mirror)
			)
		)
		(duplicate_pad_numbers_are_jumpers no)
		(fp_line
			(start 0.299974 -0.150114)
			(end -0.299974 -0.150114)
			(stroke
				(width 0.1)
				(type default)
			)
			(layer "B.Fab")
		)
		(fp_line
			(start -0.299974 -0.150114)
			(end -0.299974 0.150114)
			(stroke
				(width 0.1)
				(type default)
			)
			(layer "B.Fab")
		)
		(fp_line
			(start 0.299974 0.150114)
			(end 0.299974 -0.150114)
			(stroke
				(width 0.1)
				(type default)
			)
			(layer "B.Fab")
		)
		(fp_line
			(start -0.299974 0.150114)
			(end 0.299974 0.150114)
			(stroke
				(width 0.1)
				(type default)
			)
			(layer "B.Fab")
		)
		(pad "1" smd rect
			(at 0.2667 0 270)
			(size 0.3048 0.381)
			(layers "B.Cu" "B.Mask" "B.Paste")
			(net "P1V25_SERDES_VDDPLL_PEX0")
		)
		(pad "2" smd rect
			(at -0.2667 0 270)
			(size 0.3048 0.381)
			(layers "B.Cu" "B.Mask" "B.Paste")
			(net "GND")
		)
	)
	(footprint ""
		(layer "B.Cu")
		(at 400.824954 -293.99992 90)
		(property "Reference" "C1903"
			(at 0 0 90)
			(layer "B.SilkS")
			(hide yes)
			(effects
				(font
					(size 1.27 1.27)
				)
				(justify mirror)
			)
		)
		(property "Value" ""
			(at 0 0 90)
			(layer "B.Fab")
			(effects
				(font
					(size 1.27 1.27)
				)
				(justify mirror)
			)
		)
		(duplicate_pad_numbers_are_jumpers no)
		(fp_line
			(start 0.299974 -0.150114)
			(end -0.299974 -0.150114)
			(stroke
				(width 0.1)
				(type default)
			)
			(layer "B.Fab")
		)
		(fp_line
			(start -0.299974 -0.150114)
			(end -0.299974 0.150114)
			(stroke
				(width 0.1)
				(type default)
			)
			(layer "B.Fab")
		)
		(fp_line
			(start 0.299974 0.150114)
			(end 0.299974 -0.150114)
			(stroke
				(width 0.1)
				(type default)
			)
			(layer "B.Fab")
		)
		(fp_line
			(start -0.299974 0.150114)
			(end 0.299974 0.150114)
			(stroke
				(width 0.1)
				(type default)
			)
			(layer "B.Fab")
		)
		(pad "1" smd rect
			(at 0.2667 0 270)
			(size 0.3048 0.381)
			(layers "B.Cu" "B.Mask" "B.Paste")
			(net "P0V8_PEX3")
		)
		(pad "2" smd rect
			(at -0.2667 0 270)
			(size 0.3048 0.381)
			(layers "B.Cu" "B.Mask" "B.Paste")
			(net "GND")
		)
	)
	(footprint ""
		(layer "B.Cu")
		(at 305.149758 -295.89984 180)
		(property "Reference" "C3316"
			(at 0 0 0)
			(layer "B.SilkS")
			(hide yes)
			(effects
				(font
					(size 1.27 1.27)
				)
				(justify mirror)
			)
		)
		(property "Value" ""
			(at 0 0 0)
			(layer "B.Fab")
			(effects
				(font
					(size 1.27 1.27)
				)
				(justify mirror)
			)
		)
		(duplicate_pad_numbers_are_jumpers no)
		(fp_line
			(start 0.299974 0.150114)
			(end 0.299974 -0.150114)
			(stroke
				(width 0.1)
				(type default)
			)
			(layer "B.Fab")
		)
		(fp_line
			(start 0.299974 -0.150114)
			(end -0.299974 -0.150114)
			(stroke
				(width 0.1)
				(type default)
			)
			(layer "B.Fab")
		)
		(fp_line
			(start -0.299974 0.150114)
			(end 0.299974 0.150114)
			(stroke
				(width 0.1)
				(type default)
			)
			(layer "B.Fab")
		)
		(fp_line
			(start -0.299974 -0.150114)
			(end -0.299974 0.150114)
			(stroke
				(width 0.1)
				(type default)
			)
			(layer "B.Fab")
		)
		(pad "1" smd rect
			(at 0.2667 0)
			(size 0.3048 0.381)
			(layers "B.Cu" "B.Mask" "B.Paste")
			(net "P1V25_SERDES_VDDPLL_PEX2")
		)
		(pad "2" smd rect
			(at -0.2667 0)
			(size 0.3048 0.381)
			(layers "B.Cu" "B.Mask" "B.Paste")
			(net "GND")
		)
	)
	(footprint ""
		(layer "B.Cu")
		(at 223.761046 -153.127202 90)
		(property "Reference" "L81"
			(at 0 0 90)
			(layer "B.SilkS")
			(hide yes)
			(effects
				(font
					(size 1.27 1.27)
				)
				(justify mirror)
			)
		)
		(property "Value" ""
			(at 0 0 90)
			(layer "B.Fab")
			(effects
				(font
					(size 1.27 1.27)
				)
				(justify mirror)
			)
		)
		(duplicate_pad_numbers_are_jumpers no)
		(fp_line
			(start 1.63576 -0.8128)
			(end -1.63576 -0.8128)
			(stroke
				(width 0.1524)
				(type default)
			)
			(layer "B.SilkS")
		)
		(fp_line
			(start 1.63576 -0.8128)
			(end 1.63576 0.8128)
			(stroke
				(width 0.1524)
				(type default)
			)
			(layer "B.SilkS")
		)
		(fp_line
			(start -1.63576 -0.8128)
			(end -1.63576 0.8128)
			(stroke
				(width 0.1524)
				(type default)
			)
			(layer "B.SilkS")
		)
		(fp_line
			(start -1.63576 0.8128)
			(end 1.63576 0.8128)
			(stroke
				(width 0.1524)
				(type default)
			)
			(layer "B.SilkS")
		)
		(fp_line
			(start 1.56083 -0.738632)
			(end 1.56083 0.7366)
			(stroke
				(width 0.1)
				(type default)
			)
			(layer "B.Fab")
		)
		(fp_line
			(start -1.560576 -0.738632)
			(end 1.56083 -0.738632)
			(stroke
				(width 0.1)
				(type default)
			)
			(layer "B.Fab")
		)
		(fp_line
			(start 1.56083 0.7366)
			(end 1.524 0.7366)
			(stroke
				(width 0.1)
				(type default)
			)
			(layer "B.Fab")
		)
		(fp_line
			(start 1.524 0.7366)
			(end -1.524 0.7366)
			(stroke
				(width 0.1)
				(type default)
			)
			(layer "B.Fab")
		)
		(fp_line
			(start -1.524 0.7366)
			(end -1.560576 0.7366)
			(stroke
				(width 0.1)
				(type default)
			)
			(layer "B.Fab")
		)
		(fp_line
			(start -1.560576 0.7366)
			(end -1.560576 -0.738632)
			(stroke
				(width 0.1)
				(type default)
			)
			(layer "B.Fab")
		)
		(pad "1" smd rect
			(at 0.94996 0 90)
			(size 1.1176 1.3716)
			(layers "B.Cu" "B.Mask" "B.Paste")
			(net "P3V3")
		)
		(pad "2" smd rect
			(at -0.94996 0 90)
			(size 1.1176 1.3716)
			(layers "B.Cu" "B.Mask" "B.Paste")
			(net "P3V3_CLK_GEN_VDDMXCK_CK440_PEX")
		)
	)
	(footprint ""
		(layer "B.Cu")
		(at 395.03604 -298.27474)
		(property "Reference" "C3591"
			(at 0 0 0)
			(layer "B.SilkS")
			(hide yes)
			(effects
				(font
					(size 1.27 1.27)
				)
				(justify mirror)
			)
		)
		(property "Value" ""
			(at 0 0 0)
			(layer "B.Fab")
			(effects
				(font
					(size 1.27 1.27)
				)
				(justify mirror)
			)
		)
		(duplicate_pad_numbers_are_jumpers no)
		(fp_line
			(start -0.299974 -0.150114)
			(end -0.299974 0.150114)
			(stroke
				(width 0.1)
				(type default)
			)
			(layer "B.Fab")
		)
		(fp_line
			(start -0.299974 0.150114)
			(end 0.299974 0.150114)
			(stroke
				(width 0.1)
				(type default)
			)
			(layer "B.Fab")
		)
		(fp_line
			(start 0.299974 -0.150114)
			(end -0.299974 -0.150114)
			(stroke
				(width 0.1)
				(type default)
			)
			(layer "B.Fab")
		)
		(fp_line
			(start 0.299974 0.150114)
			(end 0.299974 -0.150114)
			(stroke
				(width 0.1)
				(type default)
			)
			(layer "B.Fab")
		)
		(pad "1" smd rect
			(at 0.2667 0 180)
			(size 0.3048 0.381)
			(layers "B.Cu" "B.Mask" "B.Paste")
			(net "SYSPLL_VDDA18_PEX3")
		)
		(pad "2" smd rect
			(at -0.2667 0 180)
			(size 0.3048 0.381)
			(layers "B.Cu" "B.Mask" "B.Paste")
			(net "GND")
		)
	)
	(footprint ""
		(layer "B.Cu")
		(at 394.164312 -143.608552 180)
		(property "Reference" "C938"
			(at 0 0 0)
			(layer "B.SilkS")
			(hide yes)
			(effects
				(font
					(size 1.27 1.27)
				)
				(justify mirror)
			)
		)
		(property "Value" ""
			(at 0 0 0)
			(layer "B.Fab")
			(effects
				(font
					(size 1.27 1.27)
				)
				(justify mirror)
			)
		)
		(duplicate_pad_numbers_are_jumpers no)
		(fp_line
			(start 0.299974 0.150114)
			(end 0.299974 -0.150114)
			(stroke
				(width 0.1)
				(type default)
			)
			(layer "B.Fab")
		)
		(fp_line
			(start 0.299974 -0.150114)
			(end -0.299974 -0.150114)
			(stroke
				(width 0.1)
				(type default)
			)
			(layer "B.Fab")
		)
		(fp_line
			(start -0.299974 0.150114)
			(end 0.299974 0.150114)
			(stroke
				(width 0.1)
				(type default)
			)
			(layer "B.Fab")
		)
		(fp_line
			(start -0.299974 -0.150114)
			(end -0.299974 0.150114)
			(stroke
				(width 0.1)
				(type default)
			)
			(layer "B.Fab")
		)
		(pad "1" smd rect
			(at 0.2667 0)
			(size 0.3048 0.381)
			(layers "B.Cu" "B.Mask" "B.Paste")
			(net "P12V_NIC6")
		)
		(pad "2" smd rect
			(at -0.2667 0)
			(size 0.3048 0.381)
			(layers "B.Cu" "B.Mask" "B.Paste")
			(net "GND")
		)
	)
	(footprint ""
		(layer "B.Cu")
		(at 458.073506 -250.20524)
		(property "Reference" "R6587"
			(at 0 0 0)
			(layer "B.SilkS")
			(hide yes)
			(effects
				(font
					(size 1.27 1.27)
				)
				(justify mirror)
			)
		)
		(property "Value" ""
			(at 0 0 0)
			(layer "B.Fab")
			(effects
				(font
					(size 1.27 1.27)
				)
				(justify mirror)
			)
		)
		(duplicate_pad_numbers_are_jumpers no)
		(fp_line
			(start -0.7874 -0.4064)
			(end -0.7874 0.4064)
			(stroke
				(width 0.1524)
				(type default)
			)
			(layer "B.SilkS")
		)
		(fp_line
			(start -0.7874 0.4064)
			(end 0.7874 0.4064)
			(stroke
				(width 0.1524)
				(type default)
			)
			(layer "B.SilkS")
		)
		(fp_line
			(start 0.7874 -0.4064)
			(end -0.7874 -0.4064)
			(stroke
				(width 0.1524)
				(type default)
			)
			(layer "B.SilkS")
		)
		(fp_line
			(start 0.7874 0.4064)
			(end 0.7874 -0.4064)
			(stroke
				(width 0.1524)
				(type default)
			)
			(layer "B.SilkS")
		)
		(fp_line
			(start -0.67945 -0.3048)
			(end -0.67945 0.3048)
			(stroke
				(width 0.1)
				(type default)
			)
			(layer "B.Fab")
		)
		(fp_line
			(start -0.67945 0.3048)
			(end -0.120396 0.3048)
			(stroke
				(width 0.1)
				(type default)
			)
			(layer "B.Fab")
		)
		(fp_line
			(start -0.12065 -0.3048)
			(end -0.67945 -0.3048)
			(stroke
				(width 0.1)
				(type default)
			)
			(layer "B.Fab")
		)
		(fp_line
			(start -0.12065 -0.2794)
			(end -0.12065 -0.3048)
			(stroke
				(width 0.1)
				(type default)
			)
			(layer "B.Fab")
		)
		(fp_line
			(start -0.120396 0.2794)
			(end 0.12065 0.2794)
			(stroke
				(width 0.1)
				(type default)
			)
			(layer "B.Fab")
		)
		(fp_line
			(start -0.120396 0.3048)
			(end -0.120396 0.2794)
			(stroke
				(width 0.1)
				(type default)
			)
			(layer "B.Fab")
		)
		(fp_line
			(start 0.12065 -0.305054)
			(end 0.12065 -0.2794)
			(stroke
				(width 0.1)
				(type default)
			)
			(layer "B.Fab")
		)
		(fp_line
			(start 0.12065 -0.2794)
			(end -0.12065 -0.2794)
			(stroke
				(width 0.1)
				(type default)
			)
			(layer "B.Fab")
		)
		(fp_line
			(start 0.12065 0.2794)
			(end 0.12065 0.3048)
			(stroke
				(width 0.1)
				(type default)
			)
			(layer "B.Fab")
		)
		(fp_line
			(start 0.12065 0.3048)
			(end 0.67945 0.3048)
			(stroke
				(width 0.1)
				(type default)
			)
			(layer "B.Fab")
		)
		(fp_line
			(start 0.67945 -0.305054)
			(end 0.12065 -0.305054)
			(stroke
				(width 0.1)
				(type default)
			)
			(layer "B.Fab")
		)
		(fp_line
			(start 0.67945 0.3048)
			(end 0.67945 -0.305054)
			(stroke
				(width 0.1)
				(type default)
			)
			(layer "B.Fab")
		)
		(pad "1" smd circle
			(at 0.40005 0 180)
			(size 0 0)
			(layers "B.Cu" "B.Mask" "B.Paste")
			(net "P3V3_AUX")
		)
		(pad "2" smd circle
			(at -0.40005 0 180)
			(size 0 0)
			(layers "B.Cu" "B.Mask" "B.Paste")
			(net "PWRGD_PEX3_P1V8_PLL")
		)
	)
	(footprint ""
		(layer "B.Cu")
		(at 104.601264 -308.580028 90)
		(property "Reference" "C4197"
			(at 0 0 90)
			(layer "B.SilkS")
			(hide yes)
			(effects
				(font
					(size 1.27 1.27)
				)
				(justify mirror)
			)
		)
		(property "Value" ""
			(at 0 0 90)
			(layer "B.Fab")
			(effects
				(font
					(size 1.27 1.27)
				)
				(justify mirror)
			)
		)
		(duplicate_pad_numbers_are_jumpers no)
		(fp_line
			(start 1.2954 -0.5842)
			(end -1.2954 -0.5842)
			(stroke
				(width 0.1524)
				(type default)
			)
			(layer "B.SilkS")
		)
		(fp_line
			(start -1.2954 -0.5842)
			(end -1.2954 0.5842)
			(stroke
				(width 0.1524)
				(type default)
			)
			(layer "B.SilkS")
		)
		(fp_line
			(start 1.2954 0.5842)
			(end 1.2954 -0.5842)
			(stroke
				(width 0.1524)
				(type default)
			)
			(layer "B.SilkS")
		)
		(fp_line
			(start -1.2954 0.5842)
			(end 1.2954 0.5842)
			(stroke
				(width 0.1524)
				(type default)
			)
			(layer "B.SilkS")
		)
		(fp_line
			(start 0.8636 -0.4572)
			(end -0.8636 -0.4572)
			(stroke
				(width 0.1)
				(type default)
			)
			(layer "B.Fab")
		)
		(fp_line
			(start -0.8636 -0.4572)
			(end -0.8636 -0.4064)
			(stroke
				(width 0.1)
				(type default)
			)
			(layer "B.Fab")
		)
		(fp_line
			(start 1.1938 -0.4064)
			(end 0.8636 -0.4064)
			(stroke
				(width 0.1)
				(type default)
			)
			(layer "B.Fab")
		)
		(fp_line
			(start 0.8636 -0.4064)
			(end 0.8636 -0.4572)
			(stroke
				(width 0.1)
				(type default)
			)
			(layer "B.Fab")
		)
		(fp_line
			(start -0.8636 -0.4064)
			(end -1.1938 -0.4064)
			(stroke
				(width 0.1)
				(type default)
			)
			(layer "B.Fab")
		)
		(fp_line
			(start -1.1938 -0.4064)
			(end -1.1938 0.4064)
			(stroke
				(width 0.1)
				(type default)
			)
			(layer "B.Fab")
		)
		(fp_line
			(start 1.1938 0.4064)
			(end 1.1938 -0.4064)
			(stroke
				(width 0.1)
				(type default)
			)
			(layer "B.Fab")
		)
		(fp_line
			(start 0.8636 0.4064)
			(end 1.1938 0.4064)
			(stroke
				(width 0.1)
				(type default)
			)
			(layer "B.Fab")
		)
		(fp_line
			(start -0.8636 0.4064)
			(end -0.8636 0.4572)
			(stroke
				(width 0.1)
				(type default)
			)
			(layer "B.Fab")
		)
		(fp_line
			(start -1.1938 0.4064)
			(end -0.8636 0.4064)
			(stroke
				(width 0.1)
				(type default)
			)
			(layer "B.Fab")
		)
		(fp_line
			(start 0.8636 0.4572)
			(end 0.8636 0.4064)
			(stroke
				(width 0.1)
				(type default)
			)
			(layer "B.Fab")
		)
		(fp_line
			(start -0.8636 0.4572)
			(end 0.8636 0.4572)
			(stroke
				(width 0.1)
				(type default)
			)
			(layer "B.Fab")
		)
		(pad "1" smd rect
			(at 0.7366 0)
			(size 0.7112 0.8128)
			(layers "B.Cu" "B.Mask" "B.Paste")
			(net "P0V8_PEX0")
		)
		(pad "2" smd rect
			(at -0.7366 0)
			(size 0.7112 0.8128)
			(layers "B.Cu" "B.Mask" "B.Paste")
			(net "GND")
		)
	)
	(footprint ""
		(layer "B.Cu")
		(at 351.645982 -156.337 180)
		(property "Reference" "R4797"
			(at 0 0 0)
			(layer "B.SilkS")
			(hide yes)
			(effects
				(font
					(size 1.27 1.27)
				)
				(justify mirror)
			)
		)
		(property "Value" ""
			(at 0 0 0)
			(layer "B.Fab")
			(effects
				(font
					(size 1.27 1.27)
				)
				(justify mirror)
			)
		)
		(duplicate_pad_numbers_are_jumpers no)
		(fp_line
			(start 0.7874 0.4064)
			(end 0.7874 -0.4064)
			(stroke
				(width 0.1524)
				(type default)
			)
			(layer "B.SilkS")
		)
		(fp_line
			(start 0.7874 -0.4064)
			(end -0.7874 -0.4064)
			(stroke
				(width 0.1524)
				(type default)
			)
			(layer "B.SilkS")
		)
		(fp_line
			(start -0.7874 0.4064)
			(end 0.7874 0.4064)
			(stroke
				(width 0.1524)
				(type default)
			)
			(layer "B.SilkS")
		)
		(fp_line
			(start -0.7874 -0.4064)
			(end -0.7874 0.4064)
			(stroke
				(width 0.1524)
				(type default)
			)
			(layer "B.SilkS")
		)
		(fp_line
			(start 0.67945 0.3048)
			(end 0.67945 -0.305054)
			(stroke
				(width 0.1)
				(type default)
			)
			(layer "B.Fab")
		)
		(fp_line
			(start 0.67945 -0.305054)
			(end 0.12065 -0.305054)
			(stroke
				(width 0.1)
				(type default)
			)
			(layer "B.Fab")
		)
		(fp_line
			(start 0.12065 0.3048)
			(end 0.67945 0.3048)
			(stroke
				(width 0.1)
				(type default)
			)
			(layer "B.Fab")
		)
		(fp_line
			(start 0.12065 0.2794)
			(end 0.12065 0.3048)
			(stroke
				(width 0.1)
				(type default)
			)
			(layer "B.Fab")
		)
		(fp_line
			(start 0.12065 -0.2794)
			(end -0.12065 -0.2794)
			(stroke
				(width 0.1)
				(type default)
			)
			(layer "B.Fab")
		)
		(fp_line
			(start 0.12065 -0.305054)
			(end 0.12065 -0.2794)
			(stroke
				(width 0.1)
				(type default)
			)
			(layer "B.Fab")
		)
		(fp_line
			(start -0.120396 0.3048)
			(end -0.120396 0.2794)
			(stroke
				(width 0.1)
				(type default)
			)
			(layer "B.Fab")
		)
		(fp_line
			(start -0.120396 0.2794)
			(end 0.12065 0.2794)
			(stroke
				(width 0.1)
				(type default)
			)
			(layer "B.Fab")
		)
		(fp_line
			(start -0.12065 -0.2794)
			(end -0.12065 -0.3048)
			(stroke
				(width 0.1)
				(type default)
			)
			(layer "B.Fab")
		)
		(fp_line
			(start -0.12065 -0.3048)
			(end -0.67945 -0.3048)
			(stroke
				(width 0.1)
				(type default)
			)
			(layer "B.Fab")
		)
		(fp_line
			(start -0.67945 0.3048)
			(end -0.120396 0.3048)
			(stroke
				(width 0.1)
				(type default)
			)
			(layer "B.Fab")
		)
		(fp_line
			(start -0.67945 -0.3048)
			(end -0.67945 0.3048)
			(stroke
				(width 0.1)
				(type default)
			)
			(layer "B.Fab")
		)
		(pad "1" smd circle
			(at 0.40005 0)
			(size 0 0)
			(layers "B.Cu" "B.Mask" "B.Paste")
			(net "P3V3_AUX")
		)
		(pad "2" smd circle
			(at -0.40005 0)
			(size 0 0)
			(layers "B.Cu" "B.Mask" "B.Paste")
			(net "RST_PEX_NIC6_PERST_R_N")
		)
	)
	(footprint ""
		(layer "B.Cu")
		(at 183.3499 -296.37482)
		(property "Reference" "C1448"
			(at 0 0 0)
			(layer "B.SilkS")
			(hide yes)
			(effects
				(font
					(size 1.27 1.27)
				)
				(justify mirror)
			)
		)
		(property "Value" ""
			(at 0 0 0)
			(layer "B.Fab")
			(effects
				(font
					(size 1.27 1.27)
				)
				(justify mirror)
			)
		)
		(duplicate_pad_numbers_are_jumpers no)
		(fp_line
			(start -0.299974 -0.150114)
			(end -0.299974 0.150114)
			(stroke
				(width 0.1)
				(type default)
			)
			(layer "B.Fab")
		)
		(fp_line
			(start -0.299974 0.150114)
			(end 0.299974 0.150114)
			(stroke
				(width 0.1)
				(type default)
			)
			(layer "B.Fab")
		)
		(fp_line
			(start 0.299974 -0.150114)
			(end -0.299974 -0.150114)
			(stroke
				(width 0.1)
				(type default)
			)
			(layer "B.Fab")
		)
		(fp_line
			(start 0.299974 0.150114)
			(end 0.299974 -0.150114)
			(stroke
				(width 0.1)
				(type default)
			)
			(layer "B.Fab")
		)
		(pad "1" smd rect
			(at 0.2667 0 180)
			(size 0.3048 0.381)
			(layers "B.Cu" "B.Mask" "B.Paste")
			(net "P0V8_SERDES_VDDA_PEX1")
		)
		(pad "2" smd rect
			(at -0.2667 0 180)
			(size 0.3048 0.381)
			(layers "B.Cu" "B.Mask" "B.Paste")
			(net "GND")
		)
	)
	(footprint ""
		(layer "B.Cu")
		(at 219.519246 -223.251268)
		(property "Reference" "R6803"
			(at 0 0 0)
			(layer "B.SilkS")
			(hide yes)
			(effects
				(font
					(size 1.27 1.27)
				)
				(justify mirror)
			)
		)
		(property "Value" ""
			(at 0 0 0)
			(layer "B.Fab")
			(effects
				(font
					(size 1.27 1.27)
				)
				(justify mirror)
			)
		)
		(duplicate_pad_numbers_are_jumpers no)
		(fp_line
			(start -0.7874 -0.4064)
			(end -0.7874 0.4064)
			(stroke
				(width 0.1524)
				(type default)
			)
			(layer "B.SilkS")
		)
		(fp_line
			(start -0.7874 0.4064)
			(end 0.7874 0.4064)
			(stroke
				(width 0.1524)
				(type default)
			)
			(layer "B.SilkS")
		)
		(fp_line
			(start 0.7874 -0.4064)
			(end -0.7874 -0.4064)
			(stroke
				(width 0.1524)
				(type default)
			)
			(layer "B.SilkS")
		)
		(fp_line
			(start 0.7874 0.4064)
			(end 0.7874 -0.4064)
			(stroke
				(width 0.1524)
				(type default)
			)
			(layer "B.SilkS")
		)
		(fp_line
			(start -0.67945 -0.3048)
			(end -0.67945 0.3048)
			(stroke
				(width 0.1)
				(type default)
			)
			(layer "B.Fab")
		)
		(fp_line
			(start -0.67945 0.3048)
			(end -0.120396 0.3048)
			(stroke
				(width 0.1)
				(type default)
			)
			(layer "B.Fab")
		)
		(fp_line
			(start -0.12065 -0.3048)
			(end -0.67945 -0.3048)
			(stroke
				(width 0.1)
				(type default)
			)
			(layer "B.Fab")
		)
		(fp_line
			(start -0.12065 -0.2794)
			(end -0.12065 -0.3048)
			(stroke
				(width 0.1)
				(type default)
			)
			(layer "B.Fab")
		)
		(fp_line
			(start -0.120396 0.2794)
			(end 0.12065 0.2794)
			(stroke
				(width 0.1)
				(type default)
			)
			(layer "B.Fab")
		)
		(fp_line
			(start -0.120396 0.3048)
			(end -0.120396 0.2794)
			(stroke
				(width 0.1)
				(type default)
			)
			(layer "B.Fab")
		)
		(fp_line
			(start 0.12065 -0.305054)
			(end 0.12065 -0.2794)
			(stroke
				(width 0.1)
				(type default)
			)
			(layer "B.Fab")
		)
		(fp_line
			(start 0.12065 -0.2794)
			(end -0.12065 -0.2794)
			(stroke
				(width 0.1)
				(type default)
			)
			(layer "B.Fab")
		)
		(fp_line
			(start 0.12065 0.2794)
			(end 0.12065 0.3048)
			(stroke
				(width 0.1)
				(type default)
			)
			(layer "B.Fab")
		)
		(fp_line
			(start 0.12065 0.3048)
			(end 0.67945 0.3048)
			(stroke
				(width 0.1)
				(type default)
			)
			(layer "B.Fab")
		)
		(fp_line
			(start 0.67945 -0.305054)
			(end 0.12065 -0.305054)
			(stroke
				(width 0.1)
				(type default)
			)
			(layer "B.Fab")
		)
		(fp_line
			(start 0.67945 0.3048)
			(end 0.67945 -0.305054)
			(stroke
				(width 0.1)
				(type default)
			)
			(layer "B.Fab")
		)
		(pad "1" smd circle
			(at 0.40005 0 180)
			(size 0 0)
			(layers "B.Cu" "B.Mask" "B.Paste")
			(net "SMB_BIC_FPGA_R2_SDA")
		)
		(pad "2" smd circle
			(at -0.40005 0 180)
			(size 0 0)
			(layers "B.Cu" "B.Mask" "B.Paste")
			(net "SMB_BIC_FPGA_SDA")
		)
	)
	(footprint ""
		(layer "B.Cu")
		(at 125.872748 -204.342238 180)
		(property "Reference" "U99"
			(at 0.119888 2.274062 0)
			(unlocked yes)
			(layer "B.SilkS")
			(effects
				(font
					(size 0.7874 0.5842)
					(thickness 0.1524)
				)
				(justify mirror)
			)
		)
		(property "Value" ""
			(at 0 0 0)
			(layer "B.Fab")
			(effects
				(font
					(size 1.27 1.27)
				)
				(justify mirror)
			)
		)
		(duplicate_pad_numbers_are_jumpers no)
		(fp_line
			(start 2.085848 1.549908)
			(end 2.085848 -1.549908)
			(stroke
				(width 0.1524)
				(type default)
			)
			(layer "B.SilkS")
		)
		(fp_line
			(start 2.085848 -1.549908)
			(end 0.695198 -1.549908)
			(stroke
				(width 0.1524)
				(type default)
			)
			(layer "B.SilkS")
		)
		(fp_line
			(start 0.695198 -1.549908)
			(end 0 -0.85471)
			(stroke
				(width 0.1524)
				(type default)
			)
			(layer "B.SilkS")
		)
		(fp_line
			(start 0 -0.85471)
			(end -0.695198 -1.549908)
			(stroke
				(width 0.1524)
				(type default)
			)
			(layer "B.SilkS")
		)
		(fp_line
			(start -0.695198 -1.549908)
			(end -2.085848 -1.549908)
			(stroke
				(width 0.1524)
				(type default)
			)
			(layer "B.SilkS")
		)
		(fp_line
			(start -2.085848 1.549908)
			(end 2.085848 1.549908)
			(stroke
				(width 0.1524)
				(type default)
			)
			(layer "B.SilkS")
		)
		(fp_line
			(start -2.085848 -1.549908)
			(end -2.085848 1.549908)
			(stroke
				(width 0.1524)
				(type default)
			)
			(layer "B.SilkS")
		)
		(fp_poly
			(pts
				(xy 3.432048 -1.45796) (xy 3.432048 -0.44196) (xy 2.416048 -0.94996)
			)
			(stroke
				(width 0)
				(type default)
			)
			(fill yes)
			(layer "B.SilkS")
		)
		(fp_line
			(start 0.899922 1.549908)
			(end 0.899922 -1.549908)
			(stroke
				(width 0.1)
				(type default)
			)
			(layer "B.Fab")
		)
		(fp_line
			(start 0.899922 -1.549908)
			(end -0.899922 -1.549908)
			(stroke
				(width 0.1)
				(type default)
			)
			(layer "B.Fab")
		)
		(fp_line
			(start -0.899922 1.549908)
			(end 0.899922 1.549908)
			(stroke
				(width 0.1)
				(type default)
			)
			(layer "B.Fab")
		)
		(fp_line
			(start -0.899922 -1.549908)
			(end -0.899922 1.549908)
			(stroke
				(width 0.1)
				(type default)
			)
			(layer "B.Fab")
		)
		(fp_poly
			(pts
				(xy 3.432048 -1.45796) (xy 3.432048 -0.44196) (xy 2.416048 -0.94996)
			)
			(stroke
				(width 0)
				(type default)
			)
			(fill yes)
			(layer "B.Fab")
		)
		(pad "1" smd rect
			(at 1.400048 -0.94996 90)
			(size 0.6096 1.1176)
			(layers "B.Cu" "B.Mask" "B.Paste")
			(net "FT4232_CLI_EEPROM_DO")
		)
		(pad "2" smd rect
			(at 1.400048 0 90)
			(size 0.6096 1.1176)
			(layers "B.Cu" "B.Mask" "B.Paste")
			(net "GND")
		)
		(pad "3" smd rect
			(at 1.400048 0.94996 90)
			(size 0.6096 1.1176)
			(layers "B.Cu" "B.Mask" "B.Paste")
			(net "FT4232_CLI_EEPROM_R_SDA")
		)
		(pad "4" smd rect
			(at -1.400048 0.94996 90)
			(size 0.6096 1.1176)
			(layers "B.Cu" "B.Mask" "B.Paste")
			(net "FT4232_CLI_EEPROM_R_SCL")
		)
		(pad "5" smd rect
			(at -1.400048 0 90)
			(size 0.6096 1.1176)
			(layers "B.Cu" "B.Mask" "B.Paste")
			(net "FT4232_CLI_EEPROM_R_CS")
		)
		(pad "6" smd rect
			(at -1.400048 -0.94996 90)
			(size 0.6096 1.1176)
			(layers "B.Cu" "B.Mask" "B.Paste")
			(net "P3V3_AUX")
		)
	)
	(footprint ""
		(layer "B.Cu")
		(at 177.858166 -296.37482)
		(property "Reference" "C1374"
			(at 0 0 0)
			(layer "B.SilkS")
			(hide yes)
			(effects
				(font
					(size 1.27 1.27)
				)
				(justify mirror)
			)
		)
		(property "Value" ""
			(at 0 0 0)
			(layer "B.Fab")
			(effects
				(font
					(size 1.27 1.27)
				)
				(justify mirror)
			)
		)
		(duplicate_pad_numbers_are_jumpers no)
		(fp_line
			(start -0.299974 -0.150114)
			(end -0.299974 0.150114)
			(stroke
				(width 0.1)
				(type default)
			)
			(layer "B.Fab")
		)
		(fp_line
			(start -0.299974 0.150114)
			(end 0.299974 0.150114)
			(stroke
				(width 0.1)
				(type default)
			)
			(layer "B.Fab")
		)
		(fp_line
			(start 0.299974 -0.150114)
			(end -0.299974 -0.150114)
			(stroke
				(width 0.1)
				(type default)
			)
			(layer "B.Fab")
		)
		(fp_line
			(start 0.299974 0.150114)
			(end 0.299974 -0.150114)
			(stroke
				(width 0.1)
				(type default)
			)
			(layer "B.Fab")
		)
		(pad "1" smd rect
			(at 0.2667 0 180)
			(size 0.3048 0.381)
			(layers "B.Cu" "B.Mask" "B.Paste")
			(net "P0V8_PEX1")
		)
		(pad "2" smd rect
			(at -0.2667 0 180)
			(size 0.3048 0.381)
			(layers "B.Cu" "B.Mask" "B.Paste")
			(net "GND")
		)
	)
	(footprint ""
		(layer "B.Cu")
		(at 401.774914 -297.79976 90)
		(property "Reference" "C1881"
			(at 0 0 90)
			(layer "B.SilkS")
			(hide yes)
			(effects
				(font
					(size 1.27 1.27)
				)
				(justify mirror)
			)
		)
		(property "Value" ""
			(at 0 0 90)
			(layer "B.Fab")
			(effects
				(font
					(size 1.27 1.27)
				)
				(justify mirror)
			)
		)
		(duplicate_pad_numbers_are_jumpers no)
		(fp_line
			(start 0.299974 -0.150114)
			(end -0.299974 -0.150114)
			(stroke
				(width 0.1)
				(type default)
			)
			(layer "B.Fab")
		)
		(fp_line
			(start -0.299974 -0.150114)
			(end -0.299974 0.150114)
			(stroke
				(width 0.1)
				(type default)
			)
			(layer "B.Fab")
		)
		(fp_line
			(start 0.299974 0.150114)
			(end 0.299974 -0.150114)
			(stroke
				(width 0.1)
				(type default)
			)
			(layer "B.Fab")
		)
		(fp_line
			(start -0.299974 0.150114)
			(end 0.299974 0.150114)
			(stroke
				(width 0.1)
				(type default)
			)
			(layer "B.Fab")
		)
		(pad "1" smd rect
			(at 0.2667 0 270)
			(size 0.3048 0.381)
			(layers "B.Cu" "B.Mask" "B.Paste")
			(net "P0V8_PEX3")
		)
		(pad "2" smd rect
			(at -0.2667 0 270)
			(size 0.3048 0.381)
			(layers "B.Cu" "B.Mask" "B.Paste")
			(net "GND")
		)
	)
	(footprint ""
		(layer "B.Cu")
		(at 345.710002 -293.660068 90)
		(property "Reference" "PC151"
			(at 0 0 90)
			(layer "B.SilkS")
			(hide yes)
			(effects
				(font
					(size 1.27 1.27)
				)
				(justify mirror)
			)
		)
		(property "Value" ""
			(at 0 0 90)
			(layer "B.Fab")
			(effects
				(font
					(size 1.27 1.27)
				)
				(justify mirror)
			)
		)
		(duplicate_pad_numbers_are_jumpers no)
		(fp_line
			(start 4.84378 -2.150618)
			(end 4.53898 -2.150618)
			(stroke
				(width 0.1524)
				(type default)
			)
			(layer "B.SilkS")
		)
		(fp_line
			(start 4.84378 -2.150618)
			(end 4.842256 2.163064)
			(stroke
				(width 0.1524)
				(type default)
			)
			(layer "B.SilkS")
		)
		(fp_line
			(start 4.69138 -2.150618)
			(end 4.692396 2.161032)
			(stroke
				(width 0.1524)
				(type default)
			)
			(layer "B.SilkS")
		)
		(fp_line
			(start 4.53898 -2.150618)
			(end 4.539742 2.152142)
			(stroke
				(width 0.1524)
				(type default)
			)
			(layer "B.SilkS")
		)
		(fp_line
			(start 4.53898 -2.15011)
			(end -4.53898 -2.15011)
			(stroke
				(width 0.1524)
				(type default)
			)
			(layer "B.SilkS")
		)
		(fp_line
			(start -4.53898 -2.15011)
			(end -4.53898 2.15011)
			(stroke
				(width 0.1524)
				(type default)
			)
			(layer "B.SilkS")
		)
		(fp_line
			(start 4.53898 2.15011)
			(end 4.53898 -2.15011)
			(stroke
				(width 0.1524)
				(type default)
			)
			(layer "B.SilkS")
		)
		(fp_line
			(start -4.53898 2.15011)
			(end 4.53898 2.15011)
			(stroke
				(width 0.1524)
				(type default)
			)
			(layer "B.SilkS")
		)
		(fp_line
			(start 4.83108 2.150364)
			(end 4.447794 2.149348)
			(stroke
				(width 0.1524)
				(type default)
			)
			(layer "B.SilkS")
		)
		(fp_line
			(start 3.64998 -2.15011)
			(end -3.64998 -2.15011)
			(stroke
				(width 0.1)
				(type default)
			)
			(layer "B.Fab")
		)
		(fp_line
			(start -3.64998 -2.15011)
			(end -3.64998 2.15011)
			(stroke
				(width 0.1)
				(type default)
			)
			(layer "B.Fab")
		)
		(fp_line
			(start 3.64998 2.15011)
			(end 3.64998 -2.15011)
			(stroke
				(width 0.1)
				(type default)
			)
			(layer "B.Fab")
		)
		(fp_line
			(start -3.64998 2.15011)
			(end 3.64998 2.15011)
			(stroke
				(width 0.1)
				(type default)
			)
			(layer "B.Fab")
		)
		(fp_text user "+"
			(at 6.214872 -0.337058 90)
			(unlocked yes)
			(layer "B.SilkS")
			(effects
				(font
					(size 1.905 1.4224)
					(thickness 0.1524)
				)
				(justify left mirror)
			)
		)
		(fp_text user "-"
			(at -4.313174 -0.094488 90)
			(unlocked yes)
			(layer "B.SilkS")
			(effects
				(font
					(size 1.905 1.4224)
					(thickness 0.1524)
				)
				(justify left mirror)
			)
		)
		(fp_text user "+"
			(at 6.214872 -0.337058 90)
			(unlocked yes)
			(layer "B.Fab")
			(effects
				(font
					(size 1.905 1.4224)
					(thickness 0.1524)
				)
				(justify left mirror)
			)
		)
		(fp_text user "-"
			(at -4.313174 -0.094488 90)
			(unlocked yes)
			(layer "B.Fab")
			(effects
				(font
					(size 1.905 1.4224)
					(thickness 0.1524)
				)
				(justify left mirror)
			)
		)
		(pad "1" smd rect
			(at 3.199892 0 270)
			(size 2.413 2.8194)
			(layers "B.Cu" "B.Mask" "B.Paste")
			(net "P0V8_PEX2")
		)
		(pad "2" smd rect
			(at -3.199892 0 270)
			(size 2.413 2.8194)
			(layers "B.Cu" "B.Mask" "B.Paste")
			(net "GND")
		)
	)
	(footprint ""
		(layer "B.Cu")
		(at 225.19894 -192.959482 -90)
		(property "Reference" "R1026"
			(at 0 0 90)
			(layer "B.SilkS")
			(hide yes)
			(effects
				(font
					(size 1.27 1.27)
				)
				(justify mirror)
			)
		)
		(property "Value" ""
			(at 0 0 90)
			(layer "B.Fab")
			(effects
				(font
					(size 1.27 1.27)
				)
				(justify mirror)
			)
		)
		(duplicate_pad_numbers_are_jumpers no)
		(fp_line
			(start -0.7874 0.4064)
			(end 0.7874 0.4064)
			(stroke
				(width 0.1524)
				(type default)
			)
			(layer "B.SilkS")
		)
		(fp_line
			(start 0.7874 0.4064)
			(end 0.7874 -0.4064)
			(stroke
				(width 0.1524)
				(type default)
			)
			(layer "B.SilkS")
		)
		(fp_line
			(start -0.7874 -0.4064)
			(end -0.7874 0.4064)
			(stroke
				(width 0.1524)
				(type default)
			)
			(layer "B.SilkS")
		)
		(fp_line
			(start 0.7874 -0.4064)
			(end -0.7874 -0.4064)
			(stroke
				(width 0.1524)
				(type default)
			)
			(layer "B.SilkS")
		)
		(fp_line
			(start -0.67945 0.3048)
			(end -0.120396 0.3048)
			(stroke
				(width 0.1)
				(type default)
			)
			(layer "B.Fab")
		)
		(fp_line
			(start -0.120396 0.3048)
			(end -0.120396 0.2794)
			(stroke
				(width 0.1)
				(type default)
			)
			(layer "B.Fab")
		)
		(fp_line
			(start 0.12065 0.3048)
			(end 0.67945 0.3048)
			(stroke
				(width 0.1)
				(type default)
			)
			(layer "B.Fab")
		)
		(fp_line
			(start 0.67945 0.3048)
			(end 0.67945 -0.305054)
			(stroke
				(width 0.1)
				(type default)
			)
			(layer "B.Fab")
		)
		(fp_line
			(start -0.120396 0.2794)
			(end 0.12065 0.2794)
			(stroke
				(width 0.1)
				(type default)
			)
			(layer "B.Fab")
		)
		(fp_line
			(start 0.12065 0.2794)
			(end 0.12065 0.3048)
			(stroke
				(width 0.1)
				(type default)
			)
			(layer "B.Fab")
		)
		(fp_line
			(start -0.12065 -0.2794)
			(end -0.12065 -0.3048)
			(stroke
				(width 0.1)
				(type default)
			)
			(layer "B.Fab")
		)
		(fp_line
			(start 0.12065 -0.2794)
			(end -0.12065 -0.2794)
			(stroke
				(width 0.1)
				(type default)
			)
			(layer "B.Fab")
		)
		(fp_line
			(start -0.67945 -0.3048)
			(end -0.67945 0.3048)
			(stroke
				(width 0.1)
				(type default)
			)
			(layer "B.Fab")
		)
		(fp_line
			(start -0.12065 -0.3048)
			(end -0.67945 -0.3048)
			(stroke
				(width 0.1)
				(type default)
			)
			(layer "B.Fab")
		)
		(fp_line
			(start 0.12065 -0.305054)
			(end 0.12065 -0.2794)
			(stroke
				(width 0.1)
				(type default)
			)
			(layer "B.Fab")
		)
		(fp_line
			(start 0.67945 -0.305054)
			(end 0.12065 -0.305054)
			(stroke
				(width 0.1)
				(type default)
			)
			(layer "B.Fab")
		)
		(pad "1" smd circle
			(at 0.40005 0 90)
			(size 0 0)
			(layers "B.Cu" "B.Mask" "B.Paste")
			(net "SPI2_CLK_BUF")
		)
		(pad "2" smd circle
			(at -0.40005 0 90)
			(size 0 0)
			(layers "B.Cu" "B.Mask" "B.Paste")
			(net "SPI_BIC1_CLK_R2")
		)
	)
	(footprint ""
		(layer "B.Cu")
		(at 117.071902 -283.818584 90)
		(property "Reference" "PR103"
			(at 0 0 90)
			(layer "B.SilkS")
			(hide yes)
			(effects
				(font
					(size 1.27 1.27)
				)
				(justify mirror)
			)
		)
		(property "Value" ""
			(at 0 0 90)
			(layer "B.Fab")
			(effects
				(font
					(size 1.27 1.27)
				)
				(justify mirror)
			)
		)
		(duplicate_pad_numbers_are_jumpers no)
		(fp_line
			(start 0.7874 -0.4064)
			(end -0.7874 -0.4064)
			(stroke
				(width 0.1524)
				(type default)
			)
			(layer "B.SilkS")
		)
		(fp_line
			(start -0.7874 -0.4064)
			(end -0.7874 0.4064)
			(stroke
				(width 0.1524)
				(type default)
			)
			(layer "B.SilkS")
		)
		(fp_line
			(start 0.7874 0.4064)
			(end 0.7874 -0.4064)
			(stroke
				(width 0.1524)
				(type default)
			)
			(layer "B.SilkS")
		)
		(fp_line
			(start -0.7874 0.4064)
			(end 0.7874 0.4064)
			(stroke
				(width 0.1524)
				(type default)
			)
			(layer "B.SilkS")
		)
		(fp_line
			(start 0.67945 -0.305054)
			(end 0.12065 -0.305054)
			(stroke
				(width 0.1)
				(type default)
			)
			(layer "B.Fab")
		)
		(fp_line
			(start 0.12065 -0.305054)
			(end 0.12065 -0.2794)
			(stroke
				(width 0.1)
				(type default)
			)
			(layer "B.Fab")
		)
		(fp_line
			(start -0.12065 -0.3048)
			(end -0.67945 -0.3048)
			(stroke
				(width 0.1)
				(type default)
			)
			(layer "B.Fab")
		)
		(fp_line
			(start -0.67945 -0.3048)
			(end -0.67945 0.3048)
			(stroke
				(width 0.1)
				(type default)
			)
			(layer "B.Fab")
		)
		(fp_line
			(start 0.12065 -0.2794)
			(end -0.12065 -0.2794)
			(stroke
				(width 0.1)
				(type default)
			)
			(layer "B.Fab")
		)
		(fp_line
			(start -0.12065 -0.2794)
			(end -0.12065 -0.3048)
			(stroke
				(width 0.1)
				(type default)
			)
			(layer "B.Fab")
		)
		(fp_line
			(start 0.12065 0.2794)
			(end 0.12065 0.3048)
			(stroke
				(width 0.1)
				(type default)
			)
			(layer "B.Fab")
		)
		(fp_line
			(start -0.120396 0.2794)
			(end 0.12065 0.2794)
			(stroke
				(width 0.1)
				(type default)
			)
			(layer "B.Fab")
		)
		(fp_line
			(start 0.67945 0.3048)
			(end 0.67945 -0.305054)
			(stroke
				(width 0.1)
				(type default)
			)
			(layer "B.Fab")
		)
		(fp_line
			(start 0.12065 0.3048)
			(end 0.67945 0.3048)
			(stroke
				(width 0.1)
				(type default)
			)
			(layer "B.Fab")
		)
		(fp_line
			(start -0.120396 0.3048)
			(end -0.120396 0.2794)
			(stroke
				(width 0.1)
				(type default)
			)
			(layer "B.Fab")
		)
		(fp_line
			(start -0.67945 0.3048)
			(end -0.120396 0.3048)
			(stroke
				(width 0.1)
				(type default)
			)
			(layer "B.Fab")
		)
		(pad "1" smd circle
			(at 0.40005 0 270)
			(size 0 0)
			(layers "B.Cu" "B.Mask" "B.Paste")
			(net "P0V8_PEX0_PVCC")
		)
		(pad "2" smd circle
			(at -0.40005 0 270)
			(size 0 0)
			(layers "B.Cu" "B.Mask" "B.Paste")
			(net "P0V8_PEX0_VCC2")
		)
	)
	(footprint ""
		(layer "B.Cu")
		(at 346.016326 -326.945498 -90)
		(property "Reference" "C4325"
			(at 0 0 90)
			(layer "B.SilkS")
			(hide yes)
			(effects
				(font
					(size 1.27 1.27)
				)
				(justify mirror)
			)
		)
		(property "Value" ""
			(at 0 0 90)
			(layer "B.Fab")
			(effects
				(font
					(size 1.27 1.27)
				)
				(justify mirror)
			)
		)
		(duplicate_pad_numbers_are_jumpers no)
		(fp_line
			(start -1.2954 0.5842)
			(end 1.2954 0.5842)
			(stroke
				(width 0.1524)
				(type default)
			)
			(layer "B.SilkS")
		)
		(fp_line
			(start 1.2954 0.5842)
			(end 1.2954 -0.5842)
			(stroke
				(width 0.1524)
				(type default)
			)
			(layer "B.SilkS")
		)
		(fp_line
			(start -1.2954 -0.5842)
			(end -1.2954 0.5842)
			(stroke
				(width 0.1524)
				(type default)
			)
			(layer "B.SilkS")
		)
		(fp_line
			(start 1.2954 -0.5842)
			(end -1.2954 -0.5842)
			(stroke
				(width 0.1524)
				(type default)
			)
			(layer "B.SilkS")
		)
		(fp_line
			(start -0.8636 0.4572)
			(end 0.8636 0.4572)
			(stroke
				(width 0.1)
				(type default)
			)
			(layer "B.Fab")
		)
		(fp_line
			(start 0.8636 0.4572)
			(end 0.8636 0.4064)
			(stroke
				(width 0.1)
				(type default)
			)
			(layer "B.Fab")
		)
		(fp_line
			(start -1.1938 0.4064)
			(end -0.8636 0.4064)
			(stroke
				(width 0.1)
				(type default)
			)
			(layer "B.Fab")
		)
		(fp_line
			(start -0.8636 0.4064)
			(end -0.8636 0.4572)
			(stroke
				(width 0.1)
				(type default)
			)
			(layer "B.Fab")
		)
		(fp_line
			(start 0.8636 0.4064)
			(end 1.1938 0.4064)
			(stroke
				(width 0.1)
				(type default)
			)
			(layer "B.Fab")
		)
		(fp_line
			(start 1.1938 0.4064)
			(end 1.1938 -0.4064)
			(stroke
				(width 0.1)
				(type default)
			)
			(layer "B.Fab")
		)
		(fp_line
			(start -1.1938 -0.4064)
			(end -1.1938 0.4064)
			(stroke
				(width 0.1)
				(type default)
			)
			(layer "B.Fab")
		)
		(fp_line
			(start -0.8636 -0.4064)
			(end -1.1938 -0.4064)
			(stroke
				(width 0.1)
				(type default)
			)
			(layer "B.Fab")
		)
		(fp_line
			(start 0.8636 -0.4064)
			(end 0.8636 -0.4572)
			(stroke
				(width 0.1)
				(type default)
			)
			(layer "B.Fab")
		)
		(fp_line
			(start 1.1938 -0.4064)
			(end 0.8636 -0.4064)
			(stroke
				(width 0.1)
				(type default)
			)
			(layer "B.Fab")
		)
		(fp_line
			(start -0.8636 -0.4572)
			(end -0.8636 -0.4064)
			(stroke
				(width 0.1)
				(type default)
			)
			(layer "B.Fab")
		)
		(fp_line
			(start 0.8636 -0.4572)
			(end -0.8636 -0.4572)
			(stroke
				(width 0.1)
				(type default)
			)
			(layer "B.Fab")
		)
		(pad "1" smd rect
			(at 0.7366 0 180)
			(size 0.7112 0.8128)
			(layers "B.Cu" "B.Mask" "B.Paste")
			(net "P0V8_SERDES_VDDA_PEX2_C7")
		)
		(pad "2" smd rect
			(at -0.7366 0 180)
			(size 0.7112 0.8128)
			(layers "B.Cu" "B.Mask" "B.Paste")
			(net "GND")
		)
	)
	(footprint ""
		(layer "B.Cu")
		(at 292.651942 -296.3926 180)
		(property "Reference" "C1637"
			(at 0 0 0)
			(layer "B.SilkS")
			(hide yes)
			(effects
				(font
					(size 1.27 1.27)
				)
				(justify mirror)
			)
		)
		(property "Value" ""
			(at 0 0 0)
			(layer "B.Fab")
			(effects
				(font
					(size 1.27 1.27)
				)
				(justify mirror)
			)
		)
		(duplicate_pad_numbers_are_jumpers no)
		(fp_line
			(start 0.299974 0.150114)
			(end 0.299974 -0.150114)
			(stroke
				(width 0.1)
				(type default)
			)
			(layer "B.Fab")
		)
		(fp_line
			(start 0.299974 -0.150114)
			(end -0.299974 -0.150114)
			(stroke
				(width 0.1)
				(type default)
			)
			(layer "B.Fab")
		)
		(fp_line
			(start -0.299974 0.150114)
			(end 0.299974 0.150114)
			(stroke
				(width 0.1)
				(type default)
			)
			(layer "B.Fab")
		)
		(fp_line
			(start -0.299974 -0.150114)
			(end -0.299974 0.150114)
			(stroke
				(width 0.1)
				(type default)
			)
			(layer "B.Fab")
		)
		(pad "1" smd rect
			(at 0.2667 0)
			(size 0.3048 0.381)
			(layers "B.Cu" "B.Mask" "B.Paste")
			(net "P0V8_PEX2")
		)
		(pad "2" smd rect
			(at -0.2667 0)
			(size 0.3048 0.381)
			(layers "B.Cu" "B.Mask" "B.Paste")
			(net "GND")
		)
	)
	(footprint ""
		(layer "B.Cu")
		(at 238.61649 -208.886552 -90)
		(property "Reference" "L147"
			(at 0 0 90)
			(layer "B.SilkS")
			(hide yes)
			(effects
				(font
					(size 1.27 1.27)
				)
				(justify mirror)
			)
		)
		(property "Value" ""
			(at 0 0 90)
			(layer "B.Fab")
			(effects
				(font
					(size 1.27 1.27)
				)
				(justify mirror)
			)
		)
		(duplicate_pad_numbers_are_jumpers no)
		(fp_line
			(start -1.27 0.5842)
			(end 1.27 0.5842)
			(stroke
				(width 0.1524)
				(type default)
			)
			(layer "B.SilkS")
		)
		(fp_line
			(start -1.27 0.5842)
			(end -1.27 -0.5842)
			(stroke
				(width 0.1524)
				(type default)
			)
			(layer "B.SilkS")
		)
		(fp_line
			(start 1.27 0.5842)
			(end 1.27 -0.5842)
			(stroke
				(width 0.1524)
				(type default)
			)
			(layer "B.SilkS")
		)
		(fp_line
			(start 1.27 -0.5588)
			(end 1.27 -0.5842)
			(stroke
				(width 0.1524)
				(type default)
			)
			(layer "B.SilkS")
		)
		(fp_line
			(start 1.27 -0.5842)
			(end -1.27 -0.5842)
			(stroke
				(width 0.1524)
				(type default)
			)
			(layer "B.SilkS")
		)
		(fp_line
			(start -0.9144 0.508)
			(end 0.9144 0.508)
			(stroke
				(width 0.1)
				(type default)
			)
			(layer "B.Fab")
		)
		(fp_line
			(start 0.9144 0.508)
			(end 0.9144 0.406654)
			(stroke
				(width 0.1)
				(type default)
			)
			(layer "B.Fab")
		)
		(fp_line
			(start 0.9144 0.406654)
			(end 1.194308 0.406654)
			(stroke
				(width 0.1)
				(type default)
			)
			(layer "B.Fab")
		)
		(fp_line
			(start 1.194308 0.406654)
			(end 1.194308 -0.406654)
			(stroke
				(width 0.1)
				(type default)
			)
			(layer "B.Fab")
		)
		(fp_line
			(start -1.1938 0.4064)
			(end -0.9144 0.4064)
			(stroke
				(width 0.1)
				(type default)
			)
			(layer "B.Fab")
		)
		(fp_line
			(start -0.9144 0.4064)
			(end -0.9144 0.508)
			(stroke
				(width 0.1)
				(type default)
			)
			(layer "B.Fab")
		)
		(fp_line
			(start -1.1938 -0.406654)
			(end -1.1938 0.4064)
			(stroke
				(width 0.1)
				(type default)
			)
			(layer "B.Fab")
		)
		(fp_line
			(start -0.9144 -0.406654)
			(end -1.1938 -0.406654)
			(stroke
				(width 0.1)
				(type default)
			)
			(layer "B.Fab")
		)
		(fp_line
			(start 0.9144 -0.406654)
			(end 0.9144 -0.508)
			(stroke
				(width 0.1)
				(type default)
			)
			(layer "B.Fab")
		)
		(fp_line
			(start 1.194308 -0.406654)
			(end 0.9144 -0.406654)
			(stroke
				(width 0.1)
				(type default)
			)
			(layer "B.Fab")
		)
		(fp_line
			(start -0.9144 -0.508)
			(end -0.9144 -0.406654)
			(stroke
				(width 0.1)
				(type default)
			)
			(layer "B.Fab")
		)
		(fp_line
			(start 0.9144 -0.508)
			(end -0.9144 -0.508)
			(stroke
				(width 0.1)
				(type default)
			)
			(layer "B.Fab")
		)
		(pad "1" smd rect
			(at 0.7366 0 180)
			(size 0.7112 0.8128)
			(layers "B.Cu" "B.Mask" "B.Paste")
			(net "P3V3_AUX")
		)
		(pad "2" smd rect
			(at -0.7366 0 180)
			(size 0.7112 0.8128)
			(layers "B.Cu" "B.Mask" "B.Paste")
			(net "P3V3_BIC_USB2AV33")
		)
	)
	(footprint ""
		(layer "B.Cu")
		(at 181.44998 -292.099746 90)
		(property "Reference" "C1422"
			(at 0 0 90)
			(layer "B.SilkS")
			(hide yes)
			(effects
				(font
					(size 1.27 1.27)
				)
				(justify mirror)
			)
		)
		(property "Value" ""
			(at 0 0 90)
			(layer "B.Fab")
			(effects
				(font
					(size 1.27 1.27)
				)
				(justify mirror)
			)
		)
		(duplicate_pad_numbers_are_jumpers no)
		(fp_line
			(start 0.299974 -0.150114)
			(end -0.299974 -0.150114)
			(stroke
				(width 0.1)
				(type default)
			)
			(layer "B.Fab")
		)
		(fp_line
			(start -0.299974 -0.150114)
			(end -0.299974 0.150114)
			(stroke
				(width 0.1)
				(type default)
			)
			(layer "B.Fab")
		)
		(fp_line
			(start 0.299974 0.150114)
			(end 0.299974 -0.150114)
			(stroke
				(width 0.1)
				(type default)
			)
			(layer "B.Fab")
		)
		(fp_line
			(start -0.299974 0.150114)
			(end 0.299974 0.150114)
			(stroke
				(width 0.1)
				(type default)
			)
			(layer "B.Fab")
		)
		(pad "1" smd rect
			(at 0.2667 0 270)
			(size 0.3048 0.381)
			(layers "B.Cu" "B.Mask" "B.Paste")
			(net "P0V8_SERDES_VDDA_PEX1")
		)
		(pad "2" smd rect
			(at -0.2667 0 270)
			(size 0.3048 0.381)
			(layers "B.Cu" "B.Mask" "B.Paste")
			(net "GND")
		)
	)
	(footprint ""
		(layer "B.Cu")
		(at 75.72375 -289.724846 90)
		(property "Reference" "R933"
			(at 0 0 90)
			(layer "B.SilkS")
			(hide yes)
			(effects
				(font
					(size 1.27 1.27)
				)
				(justify mirror)
			)
		)
		(property "Value" ""
			(at 0 0 90)
			(layer "B.Fab")
			(effects
				(font
					(size 1.27 1.27)
				)
				(justify mirror)
			)
		)
		(duplicate_pad_numbers_are_jumpers no)
		(fp_line
			(start 0.7874 -0.4064)
			(end -0.7874 -0.4064)
			(stroke
				(width 0.1524)
				(type default)
			)
			(layer "B.SilkS")
		)
		(fp_line
			(start -0.7874 -0.4064)
			(end -0.7874 0.4064)
			(stroke
				(width 0.1524)
				(type default)
			)
			(layer "B.SilkS")
		)
		(fp_line
			(start 0.7874 0.4064)
			(end 0.7874 -0.4064)
			(stroke
				(width 0.1524)
				(type default)
			)
			(layer "B.SilkS")
		)
		(fp_line
			(start -0.7874 0.4064)
			(end 0.7874 0.4064)
			(stroke
				(width 0.1524)
				(type default)
			)
			(layer "B.SilkS")
		)
		(fp_line
			(start 0.67945 -0.305054)
			(end 0.12065 -0.305054)
			(stroke
				(width 0.1)
				(type default)
			)
			(layer "B.Fab")
		)
		(fp_line
			(start 0.12065 -0.305054)
			(end 0.12065 -0.2794)
			(stroke
				(width 0.1)
				(type default)
			)
			(layer "B.Fab")
		)
		(fp_line
			(start -0.12065 -0.3048)
			(end -0.67945 -0.3048)
			(stroke
				(width 0.1)
				(type default)
			)
			(layer "B.Fab")
		)
		(fp_line
			(start -0.67945 -0.3048)
			(end -0.67945 0.3048)
			(stroke
				(width 0.1)
				(type default)
			)
			(layer "B.Fab")
		)
		(fp_line
			(start 0.12065 -0.2794)
			(end -0.12065 -0.2794)
			(stroke
				(width 0.1)
				(type default)
			)
			(layer "B.Fab")
		)
		(fp_line
			(start -0.12065 -0.2794)
			(end -0.12065 -0.3048)
			(stroke
				(width 0.1)
				(type default)
			)
			(layer "B.Fab")
		)
		(fp_line
			(start 0.12065 0.2794)
			(end 0.12065 0.3048)
			(stroke
				(width 0.1)
				(type default)
			)
			(layer "B.Fab")
		)
		(fp_line
			(start -0.120396 0.2794)
			(end 0.12065 0.2794)
			(stroke
				(width 0.1)
				(type default)
			)
			(layer "B.Fab")
		)
		(fp_line
			(start 0.67945 0.3048)
			(end 0.67945 -0.305054)
			(stroke
				(width 0.1)
				(type default)
			)
			(layer "B.Fab")
		)
		(fp_line
			(start 0.12065 0.3048)
			(end 0.67945 0.3048)
			(stroke
				(width 0.1)
				(type default)
			)
			(layer "B.Fab")
		)
		(fp_line
			(start -0.120396 0.3048)
			(end -0.120396 0.2794)
			(stroke
				(width 0.1)
				(type default)
			)
			(layer "B.Fab")
		)
		(fp_line
			(start -0.67945 0.3048)
			(end -0.120396 0.3048)
			(stroke
				(width 0.1)
				(type default)
			)
			(layer "B.Fab")
		)
		(pad "1" smd circle
			(at 0.40005 0 270)
			(size 0 0)
			(layers "B.Cu" "B.Mask" "B.Paste")
			(net "UART_PEX0_SDB_TX")
		)
		(pad "2" smd circle
			(at -0.40005 0 270)
			(size 0 0)
			(layers "B.Cu" "B.Mask" "B.Paste")
			(net "UART_PEX0_SDB_R_TX")
		)
	)
	(footprint ""
		(layer "B.Cu")
		(at 116.27739 -254.55372 180)
		(property "Reference" "PR65"
			(at 0 0 0)
			(layer "B.SilkS")
			(hide yes)
			(effects
				(font
					(size 1.27 1.27)
				)
				(justify mirror)
			)
		)
		(property "Value" ""
			(at 0 0 0)
			(layer "B.Fab")
			(effects
				(font
					(size 1.27 1.27)
				)
				(justify mirror)
			)
		)
		(duplicate_pad_numbers_are_jumpers no)
		(fp_line
			(start 0.7874 0.4064)
			(end 0.7874 -0.4064)
			(stroke
				(width 0.1524)
				(type default)
			)
			(layer "B.SilkS")
		)
		(fp_line
			(start 0.7874 -0.4064)
			(end -0.7874 -0.4064)
			(stroke
				(width 0.1524)
				(type default)
			)
			(layer "B.SilkS")
		)
		(fp_line
			(start -0.7874 0.4064)
			(end 0.7874 0.4064)
			(stroke
				(width 0.1524)
				(type default)
			)
			(layer "B.SilkS")
		)
		(fp_line
			(start -0.7874 -0.4064)
			(end -0.7874 0.4064)
			(stroke
				(width 0.1524)
				(type default)
			)
			(layer "B.SilkS")
		)
		(fp_line
			(start 0.67945 0.3048)
			(end 0.67945 -0.305054)
			(stroke
				(width 0.1)
				(type default)
			)
			(layer "B.Fab")
		)
		(fp_line
			(start 0.67945 -0.305054)
			(end 0.12065 -0.305054)
			(stroke
				(width 0.1)
				(type default)
			)
			(layer "B.Fab")
		)
		(fp_line
			(start 0.12065 0.3048)
			(end 0.67945 0.3048)
			(stroke
				(width 0.1)
				(type default)
			)
			(layer "B.Fab")
		)
		(fp_line
			(start 0.12065 0.2794)
			(end 0.12065 0.3048)
			(stroke
				(width 0.1)
				(type default)
			)
			(layer "B.Fab")
		)
		(fp_line
			(start 0.12065 -0.2794)
			(end -0.12065 -0.2794)
			(stroke
				(width 0.1)
				(type default)
			)
			(layer "B.Fab")
		)
		(fp_line
			(start 0.12065 -0.305054)
			(end 0.12065 -0.2794)
			(stroke
				(width 0.1)
				(type default)
			)
			(layer "B.Fab")
		)
		(fp_line
			(start -0.120396 0.3048)
			(end -0.120396 0.2794)
			(stroke
				(width 0.1)
				(type default)
			)
			(layer "B.Fab")
		)
		(fp_line
			(start -0.120396 0.2794)
			(end 0.12065 0.2794)
			(stroke
				(width 0.1)
				(type default)
			)
			(layer "B.Fab")
		)
		(fp_line
			(start -0.12065 -0.2794)
			(end -0.12065 -0.3048)
			(stroke
				(width 0.1)
				(type default)
			)
			(layer "B.Fab")
		)
		(fp_line
			(start -0.12065 -0.3048)
			(end -0.67945 -0.3048)
			(stroke
				(width 0.1)
				(type default)
			)
			(layer "B.Fab")
		)
		(fp_line
			(start -0.67945 0.3048)
			(end -0.120396 0.3048)
			(stroke
				(width 0.1)
				(type default)
			)
			(layer "B.Fab")
		)
		(fp_line
			(start -0.67945 -0.3048)
			(end -0.67945 0.3048)
			(stroke
				(width 0.1)
				(type default)
			)
			(layer "B.Fab")
		)
		(pad "1" smd circle
			(at 0.40005 0)
			(size 0 0)
			(layers "B.Cu" "B.Mask" "B.Paste")
			(net "P3V3_AUX")
		)
		(pad "2" smd circle
			(at -0.40005 0)
			(size 0 0)
			(layers "B.Cu" "B.Mask" "B.Paste")
			(net "P0V8_PEX0_VDD")
		)
	)
	(footprint ""
		(layer "B.Cu")
		(at 169.120312 -296.37482)
		(property "Reference" "C1364"
			(at 0 0 0)
			(layer "B.SilkS")
			(hide yes)
			(effects
				(font
					(size 1.27 1.27)
				)
				(justify mirror)
			)
		)
		(property "Value" ""
			(at 0 0 0)
			(layer "B.Fab")
			(effects
				(font
					(size 1.27 1.27)
				)
				(justify mirror)
			)
		)
		(duplicate_pad_numbers_are_jumpers no)
		(fp_line
			(start -0.299974 -0.150114)
			(end -0.299974 0.150114)
			(stroke
				(width 0.1)
				(type default)
			)
			(layer "B.Fab")
		)
		(fp_line
			(start -0.299974 0.150114)
			(end 0.299974 0.150114)
			(stroke
				(width 0.1)
				(type default)
			)
			(layer "B.Fab")
		)
		(fp_line
			(start 0.299974 -0.150114)
			(end -0.299974 -0.150114)
			(stroke
				(width 0.1)
				(type default)
			)
			(layer "B.Fab")
		)
		(fp_line
			(start 0.299974 0.150114)
			(end 0.299974 -0.150114)
			(stroke
				(width 0.1)
				(type default)
			)
			(layer "B.Fab")
		)
		(pad "1" smd rect
			(at 0.2667 0 180)
			(size 0.3048 0.381)
			(layers "B.Cu" "B.Mask" "B.Paste")
			(net "P0V8_PEX1")
		)
		(pad "2" smd rect
			(at -0.2667 0 180)
			(size 0.3048 0.381)
			(layers "B.Cu" "B.Mask" "B.Paste")
			(net "GND")
		)
	)
	(footprint ""
		(layer "B.Cu")
		(at 71.290688 -118.711218 180)
		(property "Reference" "R75"
			(at 0 0 0)
			(layer "B.SilkS")
			(hide yes)
			(effects
				(font
					(size 1.27 1.27)
				)
				(justify mirror)
			)
		)
		(property "Value" ""
			(at 0 0 0)
			(layer "B.Fab")
			(effects
				(font
					(size 1.27 1.27)
				)
				(justify mirror)
			)
		)
		(duplicate_pad_numbers_are_jumpers no)
		(fp_line
			(start 0.7874 0.4064)
			(end 0.7874 -0.4064)
			(stroke
				(width 0.1524)
				(type default)
			)
			(layer "B.SilkS")
		)
		(fp_line
			(start 0.7874 -0.4064)
			(end -0.7874 -0.4064)
			(stroke
				(width 0.1524)
				(type default)
			)
			(layer "B.SilkS")
		)
		(fp_line
			(start -0.7874 0.4064)
			(end 0.7874 0.4064)
			(stroke
				(width 0.1524)
				(type default)
			)
			(layer "B.SilkS")
		)
		(fp_line
			(start -0.7874 -0.4064)
			(end -0.7874 0.4064)
			(stroke
				(width 0.1524)
				(type default)
			)
			(layer "B.SilkS")
		)
		(fp_line
			(start 0.67945 0.3048)
			(end 0.67945 -0.305054)
			(stroke
				(width 0.1)
				(type default)
			)
			(layer "B.Fab")
		)
		(fp_line
			(start 0.67945 -0.305054)
			(end 0.12065 -0.305054)
			(stroke
				(width 0.1)
				(type default)
			)
			(layer "B.Fab")
		)
		(fp_line
			(start 0.12065 0.3048)
			(end 0.67945 0.3048)
			(stroke
				(width 0.1)
				(type default)
			)
			(layer "B.Fab")
		)
		(fp_line
			(start 0.12065 0.2794)
			(end 0.12065 0.3048)
			(stroke
				(width 0.1)
				(type default)
			)
			(layer "B.Fab")
		)
		(fp_line
			(start 0.12065 -0.2794)
			(end -0.12065 -0.2794)
			(stroke
				(width 0.1)
				(type default)
			)
			(layer "B.Fab")
		)
		(fp_line
			(start 0.12065 -0.305054)
			(end 0.12065 -0.2794)
			(stroke
				(width 0.1)
				(type default)
			)
			(layer "B.Fab")
		)
		(fp_line
			(start -0.120396 0.3048)
			(end -0.120396 0.2794)
			(stroke
				(width 0.1)
				(type default)
			)
			(layer "B.Fab")
		)
		(fp_line
			(start -0.120396 0.2794)
			(end 0.12065 0.2794)
			(stroke
				(width 0.1)
				(type default)
			)
			(layer "B.Fab")
		)
		(fp_line
			(start -0.12065 -0.2794)
			(end -0.12065 -0.3048)
			(stroke
				(width 0.1)
				(type default)
			)
			(layer "B.Fab")
		)
		(fp_line
			(start -0.12065 -0.3048)
			(end -0.67945 -0.3048)
			(stroke
				(width 0.1)
				(type default)
			)
			(layer "B.Fab")
		)
		(fp_line
			(start -0.67945 0.3048)
			(end -0.120396 0.3048)
			(stroke
				(width 0.1)
				(type default)
			)
			(layer "B.Fab")
		)
		(fp_line
			(start -0.67945 -0.3048)
			(end -0.67945 0.3048)
			(stroke
				(width 0.1)
				(type default)
			)
			(layer "B.Fab")
		)
		(pad "1" smd circle
			(at 0.40005 0)
			(size 0 0)
			(layers "B.Cu" "B.Mask" "B.Paste")
			(net "NIC1_AUX_PWR_EN")
		)
		(pad "2" smd circle
			(at -0.40005 0)
			(size 0 0)
			(layers "B.Cu" "B.Mask" "B.Paste")
			(net "GND")
		)
	)
	(footprint ""
		(layer "B.Cu")
		(at 219.939362 -288.197544)
		(property "Reference" "PC233"
			(at 0 0 0)
			(layer "B.SilkS")
			(hide yes)
			(effects
				(font
					(size 1.27 1.27)
				)
				(justify mirror)
			)
		)
		(property "Value" ""
			(at 0 0 0)
			(layer "B.Fab")
			(effects
				(font
					(size 1.27 1.27)
				)
				(justify mirror)
			)
		)
		(duplicate_pad_numbers_are_jumpers no)
		(fp_line
			(start -1.524 -0.762)
			(end -1.524 0.762)
			(stroke
				(width 0.1524)
				(type default)
			)
			(layer "B.SilkS")
		)
		(fp_line
			(start -1.524 0.762)
			(end 1.524 0.762)
			(stroke
				(width 0.1524)
				(type default)
			)
			(layer "B.SilkS")
		)
		(fp_line
			(start 1.524 -0.762)
			(end -1.524 -0.762)
			(stroke
				(width 0.1524)
				(type default)
			)
			(layer "B.SilkS")
		)
		(fp_line
			(start 1.524 0.762)
			(end 1.524 -0.762)
			(stroke
				(width 0.1524)
				(type default)
			)
			(layer "B.SilkS")
		)
		(fp_line
			(start -1.1049 -0.724916)
			(end 1.1049 -0.724916)
			(stroke
				(width 0.1)
				(type default)
			)
			(layer "B.Fab")
		)
		(fp_line
			(start -1.1049 0.724916)
			(end -1.1049 -0.724916)
			(stroke
				(width 0.1)
				(type default)
			)
			(layer "B.Fab")
		)
		(fp_line
			(start 1.1049 -0.724916)
			(end 1.1049 0.724916)
			(stroke
				(width 0.1)
				(type default)
			)
			(layer "B.Fab")
		)
		(fp_line
			(start 1.1049 0.724916)
			(end -1.1049 0.724916)
			(stroke
				(width 0.1)
				(type default)
			)
			(layer "B.Fab")
		)
		(pad "1" smd rect
			(at 0.889 0)
			(size 1.016 1.27)
			(layers "B.Cu" "B.Mask" "B.Paste")
			(net "P1V25_PEX1_R")
		)
		(pad "2" smd rect
			(at -0.889 0)
			(size 1.016 1.27)
			(layers "B.Cu" "B.Mask" "B.Paste")
			(net "GND")
		)
	)
	(footprint ""
		(layer "B.Cu")
		(at 178.599846 -290.199826 90)
		(property "Reference" "C1491"
			(at 0 0 90)
			(layer "B.SilkS")
			(hide yes)
			(effects
				(font
					(size 1.27 1.27)
				)
				(justify mirror)
			)
		)
		(property "Value" ""
			(at 0 0 90)
			(layer "B.Fab")
			(effects
				(font
					(size 1.27 1.27)
				)
				(justify mirror)
			)
		)
		(duplicate_pad_numbers_are_jumpers no)
		(fp_line
			(start 0.299974 -0.150114)
			(end -0.299974 -0.150114)
			(stroke
				(width 0.1)
				(type default)
			)
			(layer "B.Fab")
		)
		(fp_line
			(start -0.299974 -0.150114)
			(end -0.299974 0.150114)
			(stroke
				(width 0.1)
				(type default)
			)
			(layer "B.Fab")
		)
		(fp_line
			(start 0.299974 0.150114)
			(end 0.299974 -0.150114)
			(stroke
				(width 0.1)
				(type default)
			)
			(layer "B.Fab")
		)
		(fp_line
			(start -0.299974 0.150114)
			(end 0.299974 0.150114)
			(stroke
				(width 0.1)
				(type default)
			)
			(layer "B.Fab")
		)
		(pad "1" smd rect
			(at 0.2667 0 270)
			(size 0.3048 0.381)
			(layers "B.Cu" "B.Mask" "B.Paste")
			(net "P0V8_SERDES_VDDA_PEX1")
		)
		(pad "2" smd rect
			(at -0.2667 0 270)
			(size 0.3048 0.381)
			(layers "B.Cu" "B.Mask" "B.Paste")
			(net "GND")
		)
	)
	(footprint ""
		(layer "B.Cu")
		(at 331.408532 -212.34019)
		(property "Reference" "C2053"
			(at 0 0 0)
			(layer "B.SilkS")
			(hide yes)
			(effects
				(font
					(size 1.27 1.27)
				)
				(justify mirror)
			)
		)
		(property "Value" ""
			(at 0 0 0)
			(layer "B.Fab")
			(effects
				(font
					(size 1.27 1.27)
				)
				(justify mirror)
			)
		)
		(duplicate_pad_numbers_are_jumpers no)
		(fp_line
			(start -0.69215 -0.2921)
			(end -0.69215 0.2921)
			(stroke
				(width 0.1524)
				(type default)
			)
			(layer "B.SilkS")
		)
		(fp_line
			(start -0.69215 0.2921)
			(end 0.69215 0.2921)
			(stroke
				(width 0.1524)
				(type default)
			)
			(layer "B.SilkS")
		)
		(fp_line
			(start 0.69215 -0.2921)
			(end -0.69215 -0.2921)
			(stroke
				(width 0.1524)
				(type default)
			)
			(layer "B.SilkS")
		)
		(fp_line
			(start 0.69215 0.2921)
			(end 0.69215 -0.2921)
			(stroke
				(width 0.1524)
				(type default)
			)
			(layer "B.SilkS")
		)
		(fp_line
			(start -0.51435 -0.2794)
			(end -0.51435 0.2794)
			(stroke
				(width 0.1)
				(type default)
			)
			(layer "B.Fab")
		)
		(fp_line
			(start -0.51435 0.2794)
			(end 0.51435 0.2794)
			(stroke
				(width 0.1)
				(type default)
			)
			(layer "B.Fab")
		)
		(fp_line
			(start 0.51435 -0.2794)
			(end -0.51435 -0.2794)
			(stroke
				(width 0.1)
				(type default)
			)
			(layer "B.Fab")
		)
		(fp_line
			(start 0.51435 0.2794)
			(end 0.51435 -0.2794)
			(stroke
				(width 0.1)
				(type default)
			)
			(layer "B.Fab")
		)
		(pad "1" smd circle
			(at 0.40005 0 180)
			(size 0 0)
			(layers "B.Cu" "B.Mask" "B.Paste")
			(net "P3V3_FPGA_VCCIO2")
		)
		(pad "2" smd circle
			(at -0.40005 0 180)
			(size 0 0)
			(layers "B.Cu" "B.Mask" "B.Paste")
			(net "GND")
		)
		(zone
			(layer "B.Cu")
			(hatch none 0.5)
			(connect_pads
				(clearance 0)
			)
			(min_thickness 0.25)
			(keepout
				(tracks not_allowed)
				(vias allowed)
				(pads allowed)
				(copperpour not_allowed)
				(footprints allowed)
			)
			(placement
				(enabled no)
				(sheetname "")
			)
			(fill
				(thermal_gap 0.5)
				(thermal_bridge_width 0.5)
				(island_removal_mode 0)
			)
			(polygon
				(pts
					(xy 331.599032 -212.25256) (xy 331.507592 -212.194394) (xy 331.308202 -212.194394) (xy 331.218032 -212.25256)
					(xy 331.218032 -212.42782) (xy 331.308202 -212.48624) (xy 331.507592 -212.48624) (xy 331.599032 -212.428074)
				)
			)
		)
	)
	(footprint ""
		(layer "B.Cu")
		(at 56.799988 -299.699934 -90)
		(property "Reference" "C1205"
			(at 0 0 90)
			(layer "B.SilkS")
			(hide yes)
			(effects
				(font
					(size 1.27 1.27)
				)
				(justify mirror)
			)
		)
		(property "Value" ""
			(at 0 0 90)
			(layer "B.Fab")
			(effects
				(font
					(size 1.27 1.27)
				)
				(justify mirror)
			)
		)
		(duplicate_pad_numbers_are_jumpers no)
		(fp_line
			(start -0.299974 0.150114)
			(end 0.299974 0.150114)
			(stroke
				(width 0.1)
				(type default)
			)
			(layer "B.Fab")
		)
		(fp_line
			(start 0.299974 0.150114)
			(end 0.299974 -0.150114)
			(stroke
				(width 0.1)
				(type default)
			)
			(layer "B.Fab")
		)
		(fp_line
			(start -0.299974 -0.150114)
			(end -0.299974 0.150114)
			(stroke
				(width 0.1)
				(type default)
			)
			(layer "B.Fab")
		)
		(fp_line
			(start 0.299974 -0.150114)
			(end -0.299974 -0.150114)
			(stroke
				(width 0.1)
				(type default)
			)
			(layer "B.Fab")
		)
		(pad "1" smd rect
			(at 0.2667 0 90)
			(size 0.3048 0.381)
			(layers "B.Cu" "B.Mask" "B.Paste")
			(net "P0V8_SERDES_VDDA_PEX0")
		)
		(pad "2" smd rect
			(at -0.2667 0 90)
			(size 0.3048 0.381)
			(layers "B.Cu" "B.Mask" "B.Paste")
			(net "GND")
		)
	)
	(footprint ""
		(layer "B.Cu")
		(at 410.799788 -288.299906 90)
		(property "Reference" "C3446"
			(at 0 0 90)
			(layer "B.SilkS")
			(hide yes)
			(effects
				(font
					(size 1.27 1.27)
				)
				(justify mirror)
			)
		)
		(property "Value" ""
			(at 0 0 90)
			(layer "B.Fab")
			(effects
				(font
					(size 1.27 1.27)
				)
				(justify mirror)
			)
		)
		(duplicate_pad_numbers_are_jumpers no)
		(fp_line
			(start 0.299974 -0.150114)
			(end -0.299974 -0.150114)
			(stroke
				(width 0.1)
				(type default)
			)
			(layer "B.Fab")
		)
		(fp_line
			(start -0.299974 -0.150114)
			(end -0.299974 0.150114)
			(stroke
				(width 0.1)
				(type default)
			)
			(layer "B.Fab")
		)
		(fp_line
			(start 0.299974 0.150114)
			(end 0.299974 -0.150114)
			(stroke
				(width 0.1)
				(type default)
			)
			(layer "B.Fab")
		)
		(fp_line
			(start -0.299974 0.150114)
			(end 0.299974 0.150114)
			(stroke
				(width 0.1)
				(type default)
			)
			(layer "B.Fab")
		)
		(pad "1" smd rect
			(at 0.2667 0 270)
			(size 0.3048 0.381)
			(layers "B.Cu" "B.Mask" "B.Paste")
			(net "P1V25_PEX3")
		)
		(pad "2" smd rect
			(at -0.2667 0 270)
			(size 0.3048 0.381)
			(layers "B.Cu" "B.Mask" "B.Paste")
			(net "GND")
		)
	)
	(footprint ""
		(layer "B.Cu")
		(at 412.699962 -288.299906 90)
		(property "Reference" "C3443"
			(at 0 0 90)
			(layer "B.SilkS")
			(hide yes)
			(effects
				(font
					(size 1.27 1.27)
				)
				(justify mirror)
			)
		)
		(property "Value" ""
			(at 0 0 90)
			(layer "B.Fab")
			(effects
				(font
					(size 1.27 1.27)
				)
				(justify mirror)
			)
		)
		(duplicate_pad_numbers_are_jumpers no)
		(fp_line
			(start 0.299974 -0.150114)
			(end -0.299974 -0.150114)
			(stroke
				(width 0.1)
				(type default)
			)
			(layer "B.Fab")
		)
		(fp_line
			(start -0.299974 -0.150114)
			(end -0.299974 0.150114)
			(stroke
				(width 0.1)
				(type default)
			)
			(layer "B.Fab")
		)
		(fp_line
			(start 0.299974 0.150114)
			(end 0.299974 -0.150114)
			(stroke
				(width 0.1)
				(type default)
			)
			(layer "B.Fab")
		)
		(fp_line
			(start -0.299974 0.150114)
			(end 0.299974 0.150114)
			(stroke
				(width 0.1)
				(type default)
			)
			(layer "B.Fab")
		)
		(pad "1" smd rect
			(at 0.2667 0 270)
			(size 0.3048 0.381)
			(layers "B.Cu" "B.Mask" "B.Paste")
			(net "P1V25_PEX3")
		)
		(pad "2" smd rect
			(at -0.2667 0 270)
			(size 0.3048 0.381)
			(layers "B.Cu" "B.Mask" "B.Paste")
			(net "GND")
		)
	)
	(footprint ""
		(layer "B.Cu")
		(at 102.853236 -81.655666 -90)
		(property "Reference" "L13"
			(at 0 0 90)
			(layer "B.SilkS")
			(hide yes)
			(effects
				(font
					(size 1.27 1.27)
				)
				(justify mirror)
			)
		)
		(property "Value" ""
			(at 0 0 90)
			(layer "B.Fab")
			(effects
				(font
					(size 1.27 1.27)
				)
				(justify mirror)
			)
		)
		(duplicate_pad_numbers_are_jumpers no)
		(fp_line
			(start -1.27 0.5842)
			(end 1.27 0.5842)
			(stroke
				(width 0.1524)
				(type default)
			)
			(layer "B.SilkS")
		)
		(fp_line
			(start -1.27 0.5842)
			(end -1.27 -0.5842)
			(stroke
				(width 0.1524)
				(type default)
			)
			(layer "B.SilkS")
		)
		(fp_line
			(start 1.27 0.5842)
			(end 1.27 -0.5842)
			(stroke
				(width 0.1524)
				(type default)
			)
			(layer "B.SilkS")
		)
		(fp_line
			(start 1.27 -0.5588)
			(end 1.27 -0.5842)
			(stroke
				(width 0.1524)
				(type default)
			)
			(layer "B.SilkS")
		)
		(fp_line
			(start 1.27 -0.5842)
			(end -1.27 -0.5842)
			(stroke
				(width 0.1524)
				(type default)
			)
			(layer "B.SilkS")
		)
		(fp_line
			(start -0.9144 0.508)
			(end 0.9144 0.508)
			(stroke
				(width 0.1)
				(type default)
			)
			(layer "B.Fab")
		)
		(fp_line
			(start 0.9144 0.508)
			(end 0.9144 0.406654)
			(stroke
				(width 0.1)
				(type default)
			)
			(layer "B.Fab")
		)
		(fp_line
			(start 0.9144 0.406654)
			(end 1.194308 0.406654)
			(stroke
				(width 0.1)
				(type default)
			)
			(layer "B.Fab")
		)
		(fp_line
			(start 1.194308 0.406654)
			(end 1.194308 -0.406654)
			(stroke
				(width 0.1)
				(type default)
			)
			(layer "B.Fab")
		)
		(fp_line
			(start -1.1938 0.4064)
			(end -0.9144 0.4064)
			(stroke
				(width 0.1)
				(type default)
			)
			(layer "B.Fab")
		)
		(fp_line
			(start -0.9144 0.4064)
			(end -0.9144 0.508)
			(stroke
				(width 0.1)
				(type default)
			)
			(layer "B.Fab")
		)
		(fp_line
			(start -1.1938 -0.406654)
			(end -1.1938 0.4064)
			(stroke
				(width 0.1)
				(type default)
			)
			(layer "B.Fab")
		)
		(fp_line
			(start -0.9144 -0.406654)
			(end -1.1938 -0.406654)
			(stroke
				(width 0.1)
				(type default)
			)
			(layer "B.Fab")
		)
		(fp_line
			(start 0.9144 -0.406654)
			(end 0.9144 -0.508)
			(stroke
				(width 0.1)
				(type default)
			)
			(layer "B.Fab")
		)
		(fp_line
			(start 1.194308 -0.406654)
			(end 0.9144 -0.406654)
			(stroke
				(width 0.1)
				(type default)
			)
			(layer "B.Fab")
		)
		(fp_line
			(start -0.9144 -0.508)
			(end -0.9144 -0.406654)
			(stroke
				(width 0.1)
				(type default)
			)
			(layer "B.Fab")
		)
		(fp_line
			(start 0.9144 -0.508)
			(end -0.9144 -0.508)
			(stroke
				(width 0.1)
				(type default)
			)
			(layer "B.Fab")
		)
		(pad "1" smd rect
			(at 0.7366 0 180)
			(size 0.7112 0.8128)
			(layers "B.Cu" "B.Mask" "B.Paste")
			(net "P3V3")
		)
		(pad "2" smd rect
			(at -0.7366 0 180)
			(size 0.7112 0.8128)
			(layers "B.Cu" "B.Mask" "B.Paste")
			(net "P3V3_VDD_9ZXL0851_0_7")
		)
	)
	(footprint ""
		(layer "B.Cu")
		(at 298.024804 -286.399732 90)
		(property "Reference" "C3324"
			(at 0 0 90)
			(layer "B.SilkS")
			(hide yes)
			(effects
				(font
					(size 1.27 1.27)
				)
				(justify mirror)
			)
		)
		(property "Value" ""
			(at 0 0 90)
			(layer "B.Fab")
			(effects
				(font
					(size 1.27 1.27)
				)
				(justify mirror)
			)
		)
		(duplicate_pad_numbers_are_jumpers no)
		(fp_line
			(start 0.299974 -0.150114)
			(end -0.299974 -0.150114)
			(stroke
				(width 0.1)
				(type default)
			)
			(layer "B.Fab")
		)
		(fp_line
			(start -0.299974 -0.150114)
			(end -0.299974 0.150114)
			(stroke
				(width 0.1)
				(type default)
			)
			(layer "B.Fab")
		)
		(fp_line
			(start 0.299974 0.150114)
			(end 0.299974 -0.150114)
			(stroke
				(width 0.1)
				(type default)
			)
			(layer "B.Fab")
		)
		(fp_line
			(start -0.299974 0.150114)
			(end 0.299974 0.150114)
			(stroke
				(width 0.1)
				(type default)
			)
			(layer "B.Fab")
		)
		(pad "1" smd rect
			(at 0.2667 0 270)
			(size 0.3048 0.381)
			(layers "B.Cu" "B.Mask" "B.Paste")
			(net "P1V25_SERDES_VDDPLL_PEX2")
		)
		(pad "2" smd rect
			(at -0.2667 0 270)
			(size 0.3048 0.381)
			(layers "B.Cu" "B.Mask" "B.Paste")
			(net "GND")
		)
	)
	(footprint ""
		(layer "B.Cu")
		(at 449.830698 -272.697194)
		(property "Reference" "C4391"
			(at 0 0 0)
			(layer "B.SilkS")
			(hide yes)
			(effects
				(font
					(size 1.27 1.27)
				)
				(justify mirror)
			)
		)
		(property "Value" ""
			(at 0 0 0)
			(layer "B.Fab")
			(effects
				(font
					(size 1.27 1.27)
				)
				(justify mirror)
			)
		)
		(duplicate_pad_numbers_are_jumpers no)
		(fp_line
			(start -0.299974 -0.150114)
			(end -0.299974 0.150114)
			(stroke
				(width 0.1)
				(type default)
			)
			(layer "B.Fab")
		)
		(fp_line
			(start -0.299974 0.150114)
			(end 0.299974 0.150114)
			(stroke
				(width 0.1)
				(type default)
			)
			(layer "B.Fab")
		)
		(fp_line
			(start 0.299974 -0.150114)
			(end -0.299974 -0.150114)
			(stroke
				(width 0.1)
				(type default)
			)
			(layer "B.Fab")
		)
		(fp_line
			(start 0.299974 0.150114)
			(end 0.299974 -0.150114)
			(stroke
				(width 0.1)
				(type default)
			)
			(layer "B.Fab")
		)
		(pad "1" smd rect
			(at 0.2667 0 180)
			(size 0.3048 0.381)
			(layers "B.Cu" "B.Mask" "B.Paste")
			(net "P1V25_PEX3")
		)
		(pad "2" smd rect
			(at -0.2667 0 180)
			(size 0.3048 0.381)
			(layers "B.Cu" "B.Mask" "B.Paste")
			(net "GND")
		)
	)
	(footprint ""
		(layer "B.Cu")
		(at 293.74973 -299.699934 -90)
		(property "Reference" "C1745"
			(at 0 0 90)
			(layer "B.SilkS")
			(hide yes)
			(effects
				(font
					(size 1.27 1.27)
				)
				(justify mirror)
			)
		)
		(property "Value" ""
			(at 0 0 90)
			(layer "B.Fab")
			(effects
				(font
					(size 1.27 1.27)
				)
				(justify mirror)
			)
		)
		(duplicate_pad_numbers_are_jumpers no)
		(fp_line
			(start -0.299974 0.150114)
			(end 0.299974 0.150114)
			(stroke
				(width 0.1)
				(type default)
			)
			(layer "B.Fab")
		)
		(fp_line
			(start 0.299974 0.150114)
			(end 0.299974 -0.150114)
			(stroke
				(width 0.1)
				(type default)
			)
			(layer "B.Fab")
		)
		(fp_line
			(start -0.299974 -0.150114)
			(end -0.299974 0.150114)
			(stroke
				(width 0.1)
				(type default)
			)
			(layer "B.Fab")
		)
		(fp_line
			(start 0.299974 -0.150114)
			(end -0.299974 -0.150114)
			(stroke
				(width 0.1)
				(type default)
			)
			(layer "B.Fab")
		)
		(pad "1" smd rect
			(at 0.2667 0 90)
			(size 0.3048 0.381)
			(layers "B.Cu" "B.Mask" "B.Paste")
			(net "P0V8_SERDES_VDDA_PEX2")
		)
		(pad "2" smd rect
			(at -0.2667 0 90)
			(size 0.3048 0.381)
			(layers "B.Cu" "B.Mask" "B.Paste")
			(net "GND")
		)
	)
	(footprint ""
		(layer "B.Cu")
		(at 301.349918 -300.174914 180)
		(property "Reference" "C3362"
			(at 0 0 0)
			(layer "B.SilkS")
			(hide yes)
			(effects
				(font
					(size 1.27 1.27)
				)
				(justify mirror)
			)
		)
		(property "Value" ""
			(at 0 0 0)
			(layer "B.Fab")
			(effects
				(font
					(size 1.27 1.27)
				)
				(justify mirror)
			)
		)
		(duplicate_pad_numbers_are_jumpers no)
		(fp_line
			(start 0.299974 0.150114)
			(end 0.299974 -0.150114)
			(stroke
				(width 0.1)
				(type default)
			)
			(layer "B.Fab")
		)
		(fp_line
			(start 0.299974 -0.150114)
			(end -0.299974 -0.150114)
			(stroke
				(width 0.1)
				(type default)
			)
			(layer "B.Fab")
		)
		(fp_line
			(start -0.299974 0.150114)
			(end 0.299974 0.150114)
			(stroke
				(width 0.1)
				(type default)
			)
			(layer "B.Fab")
		)
		(fp_line
			(start -0.299974 -0.150114)
			(end -0.299974 0.150114)
			(stroke
				(width 0.1)
				(type default)
			)
			(layer "B.Fab")
		)
		(pad "1" smd rect
			(at 0.2667 0)
			(size 0.3048 0.381)
			(layers "B.Cu" "B.Mask" "B.Paste")
			(net "P1V8_VDDA_PEX2")
		)
		(pad "2" smd rect
			(at -0.2667 0)
			(size 0.3048 0.381)
			(layers "B.Cu" "B.Mask" "B.Paste")
			(net "GND")
		)
	)
	(footprint ""
		(layer "B.Cu")
		(at 167.675052 -305.399948 -90)
		(property "Reference" "C3157"
			(at 0 0 90)
			(layer "B.SilkS")
			(hide yes)
			(effects
				(font
					(size 1.27 1.27)
				)
				(justify mirror)
			)
		)
		(property "Value" ""
			(at 0 0 90)
			(layer "B.Fab")
			(effects
				(font
					(size 1.27 1.27)
				)
				(justify mirror)
			)
		)
		(duplicate_pad_numbers_are_jumpers no)
		(fp_line
			(start -0.299974 0.150114)
			(end 0.299974 0.150114)
			(stroke
				(width 0.1)
				(type default)
			)
			(layer "B.Fab")
		)
		(fp_line
			(start 0.299974 0.150114)
			(end 0.299974 -0.150114)
			(stroke
				(width 0.1)
				(type default)
			)
			(layer "B.Fab")
		)
		(fp_line
			(start -0.299974 -0.150114)
			(end -0.299974 0.150114)
			(stroke
				(width 0.1)
				(type default)
			)
			(layer "B.Fab")
		)
		(fp_line
			(start 0.299974 -0.150114)
			(end -0.299974 -0.150114)
			(stroke
				(width 0.1)
				(type default)
			)
			(layer "B.Fab")
		)
		(pad "1" smd rect
			(at 0.2667 0 90)
			(size 0.3048 0.381)
			(layers "B.Cu" "B.Mask" "B.Paste")
			(net "P1V25_SERDES_VDDPLL_PEX1")
		)
		(pad "2" smd rect
			(at -0.2667 0 90)
			(size 0.3048 0.381)
			(layers "B.Cu" "B.Mask" "B.Paste")
			(net "GND")
		)
	)
	(footprint ""
		(layer "B.Cu")
		(at 276.649688 -295.89984)
		(property "Reference" "C3352"
			(at 0 0 0)
			(layer "B.SilkS")
			(hide yes)
			(effects
				(font
					(size 1.27 1.27)
				)
				(justify mirror)
			)
		)
		(property "Value" ""
			(at 0 0 0)
			(layer "B.Fab")
			(effects
				(font
					(size 1.27 1.27)
				)
				(justify mirror)
			)
		)
		(duplicate_pad_numbers_are_jumpers no)
		(fp_line
			(start -0.299974 -0.150114)
			(end -0.299974 0.150114)
			(stroke
				(width 0.1)
				(type default)
			)
			(layer "B.Fab")
		)
		(fp_line
			(start -0.299974 0.150114)
			(end 0.299974 0.150114)
			(stroke
				(width 0.1)
				(type default)
			)
			(layer "B.Fab")
		)
		(fp_line
			(start 0.299974 -0.150114)
			(end -0.299974 -0.150114)
			(stroke
				(width 0.1)
				(type default)
			)
			(layer "B.Fab")
		)
		(fp_line
			(start 0.299974 0.150114)
			(end 0.299974 -0.150114)
			(stroke
				(width 0.1)
				(type default)
			)
			(layer "B.Fab")
		)
		(pad "1" smd rect
			(at 0.2667 0 180)
			(size 0.3048 0.381)
			(layers "B.Cu" "B.Mask" "B.Paste")
			(net "P1V8_PEX")
		)
		(pad "2" smd rect
			(at -0.2667 0 180)
			(size 0.3048 0.381)
			(layers "B.Cu" "B.Mask" "B.Paste")
			(net "GND")
		)
	)
	(footprint ""
		(layer "B.Cu")
		(at 225.564954 -145.169128 180)
		(property "Reference" "C2798"
			(at 0 0 0)
			(layer "B.SilkS")
			(hide yes)
			(effects
				(font
					(size 1.27 1.27)
				)
				(justify mirror)
			)
		)
		(property "Value" ""
			(at 0 0 0)
			(layer "B.Fab")
			(effects
				(font
					(size 1.27 1.27)
				)
				(justify mirror)
			)
		)
		(duplicate_pad_numbers_are_jumpers no)
		(fp_line
			(start 0.7874 0.4064)
			(end 0.7874 -0.4064)
			(stroke
				(width 0.1524)
				(type default)
			)
			(layer "B.SilkS")
		)
		(fp_line
			(start 0.7874 -0.4064)
			(end -0.7874 -0.4064)
			(stroke
				(width 0.1524)
				(type default)
			)
			(layer "B.SilkS")
		)
		(fp_line
			(start -0.7874 0.4064)
			(end 0.7874 0.4064)
			(stroke
				(width 0.1524)
				(type default)
			)
			(layer "B.SilkS")
		)
		(fp_line
			(start -0.7874 -0.4064)
			(end -0.7874 0.4064)
			(stroke
				(width 0.1524)
				(type default)
			)
			(layer "B.SilkS")
		)
		(fp_line
			(start 0.67945 0.3048)
			(end 0.67945 -0.305054)
			(stroke
				(width 0.1)
				(type default)
			)
			(layer "B.Fab")
		)
		(fp_line
			(start 0.67945 -0.305054)
			(end 0.12065 -0.305054)
			(stroke
				(width 0.1)
				(type default)
			)
			(layer "B.Fab")
		)
		(fp_line
			(start 0.12065 0.3048)
			(end 0.67945 0.3048)
			(stroke
				(width 0.1)
				(type default)
			)
			(layer "B.Fab")
		)
		(fp_line
			(start 0.12065 0.2794)
			(end 0.12065 0.3048)
			(stroke
				(width 0.1)
				(type default)
			)
			(layer "B.Fab")
		)
		(fp_line
			(start 0.12065 -0.2794)
			(end -0.12065 -0.2794)
			(stroke
				(width 0.1)
				(type default)
			)
			(layer "B.Fab")
		)
		(fp_line
			(start 0.12065 -0.305054)
			(end 0.12065 -0.2794)
			(stroke
				(width 0.1)
				(type default)
			)
			(layer "B.Fab")
		)
		(fp_line
			(start -0.120396 0.3048)
			(end -0.120396 0.2794)
			(stroke
				(width 0.1)
				(type default)
			)
			(layer "B.Fab")
		)
		(fp_line
			(start -0.120396 0.2794)
			(end 0.12065 0.2794)
			(stroke
				(width 0.1)
				(type default)
			)
			(layer "B.Fab")
		)
		(fp_line
			(start -0.12065 -0.2794)
			(end -0.12065 -0.3048)
			(stroke
				(width 0.1)
				(type default)
			)
			(layer "B.Fab")
		)
		(fp_line
			(start -0.12065 -0.3048)
			(end -0.67945 -0.3048)
			(stroke
				(width 0.1)
				(type default)
			)
			(layer "B.Fab")
		)
		(fp_line
			(start -0.67945 0.3048)
			(end -0.120396 0.3048)
			(stroke
				(width 0.1)
				(type default)
			)
			(layer "B.Fab")
		)
		(fp_line
			(start -0.67945 -0.3048)
			(end -0.67945 0.3048)
			(stroke
				(width 0.1)
				(type default)
			)
			(layer "B.Fab")
		)
		(pad "1" smd circle
			(at 0.40005 0)
			(size 0 0)
			(layers "B.Cu" "B.Mask" "B.Paste")
			(net "P3V3_CLK_GEN_VDDA25M_CK440_PEX")
		)
		(pad "2" smd circle
			(at -0.40005 0)
			(size 0 0)
			(layers "B.Cu" "B.Mask" "B.Paste")
			(net "GND")
		)
	)
	(footprint ""
		(layer "B.Cu")
		(at 421.700198 -109.251496)
		(property "Reference" "C953"
			(at 0 0 0)
			(layer "B.SilkS")
			(hide yes)
			(effects
				(font
					(size 1.27 1.27)
				)
				(justify mirror)
			)
		)
		(property "Value" ""
			(at 0 0 0)
			(layer "B.Fab")
			(effects
				(font
					(size 1.27 1.27)
				)
				(justify mirror)
			)
		)
		(duplicate_pad_numbers_are_jumpers no)
		(fp_line
			(start -0.299974 -0.150114)
			(end -0.299974 0.150114)
			(stroke
				(width 0.1)
				(type default)
			)
			(layer "B.Fab")
		)
		(fp_line
			(start -0.299974 0.150114)
			(end 0.299974 0.150114)
			(stroke
				(width 0.1)
				(type default)
			)
			(layer "B.Fab")
		)
		(fp_line
			(start 0.299974 -0.150114)
			(end -0.299974 -0.150114)
			(stroke
				(width 0.1)
				(type default)
			)
			(layer "B.Fab")
		)
		(fp_line
			(start 0.299974 0.150114)
			(end 0.299974 -0.150114)
			(stroke
				(width 0.1)
				(type default)
			)
			(layer "B.Fab")
		)
		(pad "1" smd rect
			(at 0.2667 0 180)
			(size 0.3048 0.381)
			(layers "B.Cu" "B.Mask" "B.Paste")
			(net "P12V_NIC7")
		)
		(pad "2" smd rect
			(at -0.2667 0 180)
			(size 0.3048 0.381)
			(layers "B.Cu" "B.Mask" "B.Paste")
			(net "GND")
		)
	)
	(footprint ""
		(layer "B.Cu")
		(at 345.76131 -258.004564 90)
		(property "Reference" "PR145"
			(at 0 0 90)
			(layer "B.SilkS")
			(hide yes)
			(effects
				(font
					(size 1.27 1.27)
				)
				(justify mirror)
			)
		)
		(property "Value" ""
			(at 0 0 90)
			(layer "B.Fab")
			(effects
				(font
					(size 1.27 1.27)
				)
				(justify mirror)
			)
		)
		(duplicate_pad_numbers_are_jumpers no)
		(fp_line
			(start 0.7874 -0.4064)
			(end -0.7874 -0.4064)
			(stroke
				(width 0.1524)
				(type default)
			)
			(layer "B.SilkS")
		)
		(fp_line
			(start -0.7874 -0.4064)
			(end -0.7874 0.4064)
			(stroke
				(width 0.1524)
				(type default)
			)
			(layer "B.SilkS")
		)
		(fp_line
			(start 0.7874 0.4064)
			(end 0.7874 -0.4064)
			(stroke
				(width 0.1524)
				(type default)
			)
			(layer "B.SilkS")
		)
		(fp_line
			(start -0.7874 0.4064)
			(end 0.7874 0.4064)
			(stroke
				(width 0.1524)
				(type default)
			)
			(layer "B.SilkS")
		)
		(fp_line
			(start 0.67945 -0.305054)
			(end 0.12065 -0.305054)
			(stroke
				(width 0.1)
				(type default)
			)
			(layer "B.Fab")
		)
		(fp_line
			(start 0.12065 -0.305054)
			(end 0.12065 -0.2794)
			(stroke
				(width 0.1)
				(type default)
			)
			(layer "B.Fab")
		)
		(fp_line
			(start -0.12065 -0.3048)
			(end -0.67945 -0.3048)
			(stroke
				(width 0.1)
				(type default)
			)
			(layer "B.Fab")
		)
		(fp_line
			(start -0.67945 -0.3048)
			(end -0.67945 0.3048)
			(stroke
				(width 0.1)
				(type default)
			)
			(layer "B.Fab")
		)
		(fp_line
			(start 0.12065 -0.2794)
			(end -0.12065 -0.2794)
			(stroke
				(width 0.1)
				(type default)
			)
			(layer "B.Fab")
		)
		(fp_line
			(start -0.12065 -0.2794)
			(end -0.12065 -0.3048)
			(stroke
				(width 0.1)
				(type default)
			)
			(layer "B.Fab")
		)
		(fp_line
			(start 0.12065 0.2794)
			(end 0.12065 0.3048)
			(stroke
				(width 0.1)
				(type default)
			)
			(layer "B.Fab")
		)
		(fp_line
			(start -0.120396 0.2794)
			(end 0.12065 0.2794)
			(stroke
				(width 0.1)
				(type default)
			)
			(layer "B.Fab")
		)
		(fp_line
			(start 0.67945 0.3048)
			(end 0.67945 -0.305054)
			(stroke
				(width 0.1)
				(type default)
			)
			(layer "B.Fab")
		)
		(fp_line
			(start 0.12065 0.3048)
			(end 0.67945 0.3048)
			(stroke
				(width 0.1)
				(type default)
			)
			(layer "B.Fab")
		)
		(fp_line
			(start -0.120396 0.3048)
			(end -0.120396 0.2794)
			(stroke
				(width 0.1)
				(type default)
			)
			(layer "B.Fab")
		)
		(fp_line
			(start -0.67945 0.3048)
			(end -0.120396 0.3048)
			(stroke
				(width 0.1)
				(type default)
			)
			(layer "B.Fab")
		)
		(pad "1" smd circle
			(at 0.40005 0 270)
			(size 0 0)
			(layers "B.Cu" "B.Mask" "B.Paste")
			(net "P5V_AUX")
		)
		(pad "2" smd circle
			(at -0.40005 0 270)
			(size 0 0)
			(layers "B.Cu" "B.Mask" "B.Paste")
			(net "P0V8_PEX2_IINSEN")
		)
	)
	(footprint ""
		(layer "B.Cu")
		(at 167.200072 -301.599854 -90)
		(property "Reference" "C1443"
			(at 0 0 90)
			(layer "B.SilkS")
			(hide yes)
			(effects
				(font
					(size 1.27 1.27)
				)
				(justify mirror)
			)
		)
		(property "Value" ""
			(at 0 0 90)
			(layer "B.Fab")
			(effects
				(font
					(size 1.27 1.27)
				)
				(justify mirror)
			)
		)
		(duplicate_pad_numbers_are_jumpers no)
		(fp_line
			(start -0.299974 0.150114)
			(end 0.299974 0.150114)
			(stroke
				(width 0.1)
				(type default)
			)
			(layer "B.Fab")
		)
		(fp_line
			(start 0.299974 0.150114)
			(end 0.299974 -0.150114)
			(stroke
				(width 0.1)
				(type default)
			)
			(layer "B.Fab")
		)
		(fp_line
			(start -0.299974 -0.150114)
			(end -0.299974 0.150114)
			(stroke
				(width 0.1)
				(type default)
			)
			(layer "B.Fab")
		)
		(fp_line
			(start 0.299974 -0.150114)
			(end -0.299974 -0.150114)
			(stroke
				(width 0.1)
				(type default)
			)
			(layer "B.Fab")
		)
		(pad "1" smd rect
			(at 0.2667 0 90)
			(size 0.3048 0.381)
			(layers "B.Cu" "B.Mask" "B.Paste")
			(net "P0V8_SERDES_VDDA_PEX1")
		)
		(pad "2" smd rect
			(at -0.2667 0 90)
			(size 0.3048 0.381)
			(layers "B.Cu" "B.Mask" "B.Paste")
			(net "GND")
		)
	)
	(footprint ""
		(layer "B.Cu")
		(at 64.874902 -293.99992 90)
		(property "Reference" "C1144"
			(at 0 0 90)
			(layer "B.SilkS")
			(hide yes)
			(effects
				(font
					(size 1.27 1.27)
				)
				(justify mirror)
			)
		)
		(property "Value" ""
			(at 0 0 90)
			(layer "B.Fab")
			(effects
				(font
					(size 1.27 1.27)
				)
				(justify mirror)
			)
		)
		(duplicate_pad_numbers_are_jumpers no)
		(fp_line
			(start 0.299974 -0.150114)
			(end -0.299974 -0.150114)
			(stroke
				(width 0.1)
				(type default)
			)
			(layer "B.Fab")
		)
		(fp_line
			(start -0.299974 -0.150114)
			(end -0.299974 0.150114)
			(stroke
				(width 0.1)
				(type default)
			)
			(layer "B.Fab")
		)
		(fp_line
			(start 0.299974 0.150114)
			(end 0.299974 -0.150114)
			(stroke
				(width 0.1)
				(type default)
			)
			(layer "B.Fab")
		)
		(fp_line
			(start -0.299974 0.150114)
			(end 0.299974 0.150114)
			(stroke
				(width 0.1)
				(type default)
			)
			(layer "B.Fab")
		)
		(pad "1" smd rect
			(at 0.2667 0 270)
			(size 0.3048 0.381)
			(layers "B.Cu" "B.Mask" "B.Paste")
			(net "P0V8_PEX0")
		)
		(pad "2" smd rect
			(at -0.2667 0 270)
			(size 0.3048 0.381)
			(layers "B.Cu" "B.Mask" "B.Paste")
			(net "GND")
		)
	)
	(footprint ""
		(layer "B.Cu")
		(at 63.449962 -301.599854 -90)
		(property "Reference" "C1213"
			(at 0 0 90)
			(layer "B.SilkS")
			(hide yes)
			(effects
				(font
					(size 1.27 1.27)
				)
				(justify mirror)
			)
		)
		(property "Value" ""
			(at 0 0 90)
			(layer "B.Fab")
			(effects
				(font
					(size 1.27 1.27)
				)
				(justify mirror)
			)
		)
		(duplicate_pad_numbers_are_jumpers no)
		(fp_line
			(start -0.299974 0.150114)
			(end 0.299974 0.150114)
			(stroke
				(width 0.1)
				(type default)
			)
			(layer "B.Fab")
		)
		(fp_line
			(start 0.299974 0.150114)
			(end 0.299974 -0.150114)
			(stroke
				(width 0.1)
				(type default)
			)
			(layer "B.Fab")
		)
		(fp_line
			(start -0.299974 -0.150114)
			(end -0.299974 0.150114)
			(stroke
				(width 0.1)
				(type default)
			)
			(layer "B.Fab")
		)
		(fp_line
			(start 0.299974 -0.150114)
			(end -0.299974 -0.150114)
			(stroke
				(width 0.1)
				(type default)
			)
			(layer "B.Fab")
		)
		(pad "1" smd rect
			(at 0.2667 0 90)
			(size 0.3048 0.381)
			(layers "B.Cu" "B.Mask" "B.Paste")
			(net "P0V8_SERDES_VDDA_PEX0")
		)
		(pad "2" smd rect
			(at -0.2667 0 90)
			(size 0.3048 0.381)
			(layers "B.Cu" "B.Mask" "B.Paste")
			(net "GND")
		)
	)
	(footprint ""
		(layer "B.Cu")
		(at 224.763076 -200.984104 90)
		(property "Reference" "R461"
			(at 0 0 90)
			(layer "B.SilkS")
			(hide yes)
			(effects
				(font
					(size 1.27 1.27)
				)
				(justify mirror)
			)
		)
		(property "Value" ""
			(at 0 0 90)
			(layer "B.Fab")
			(effects
				(font
					(size 1.27 1.27)
				)
				(justify mirror)
			)
		)
		(duplicate_pad_numbers_are_jumpers no)
		(fp_line
			(start 0.7874 -0.4064)
			(end -0.7874 -0.4064)
			(stroke
				(width 0.1524)
				(type default)
			)
			(layer "B.SilkS")
		)
		(fp_line
			(start -0.7874 -0.4064)
			(end -0.7874 0.4064)
			(stroke
				(width 0.1524)
				(type default)
			)
			(layer "B.SilkS")
		)
		(fp_line
			(start 0.7874 0.4064)
			(end 0.7874 -0.4064)
			(stroke
				(width 0.1524)
				(type default)
			)
			(layer "B.SilkS")
		)
		(fp_line
			(start -0.7874 0.4064)
			(end 0.7874 0.4064)
			(stroke
				(width 0.1524)
				(type default)
			)
			(layer "B.SilkS")
		)
		(fp_line
			(start 0.67945 -0.305054)
			(end 0.12065 -0.305054)
			(stroke
				(width 0.1)
				(type default)
			)
			(layer "B.Fab")
		)
		(fp_line
			(start 0.12065 -0.305054)
			(end 0.12065 -0.2794)
			(stroke
				(width 0.1)
				(type default)
			)
			(layer "B.Fab")
		)
		(fp_line
			(start -0.12065 -0.3048)
			(end -0.67945 -0.3048)
			(stroke
				(width 0.1)
				(type default)
			)
			(layer "B.Fab")
		)
		(fp_line
			(start -0.67945 -0.3048)
			(end -0.67945 0.3048)
			(stroke
				(width 0.1)
				(type default)
			)
			(layer "B.Fab")
		)
		(fp_line
			(start 0.12065 -0.2794)
			(end -0.12065 -0.2794)
			(stroke
				(width 0.1)
				(type default)
			)
			(layer "B.Fab")
		)
		(fp_line
			(start -0.12065 -0.2794)
			(end -0.12065 -0.3048)
			(stroke
				(width 0.1)
				(type default)
			)
			(layer "B.Fab")
		)
		(fp_line
			(start 0.12065 0.2794)
			(end 0.12065 0.3048)
			(stroke
				(width 0.1)
				(type default)
			)
			(layer "B.Fab")
		)
		(fp_line
			(start -0.120396 0.2794)
			(end 0.12065 0.2794)
			(stroke
				(width 0.1)
				(type default)
			)
			(layer "B.Fab")
		)
		(fp_line
			(start 0.67945 0.3048)
			(end 0.67945 -0.305054)
			(stroke
				(width 0.1)
				(type default)
			)
			(layer "B.Fab")
		)
		(fp_line
			(start 0.12065 0.3048)
			(end 0.67945 0.3048)
			(stroke
				(width 0.1)
				(type default)
			)
			(layer "B.Fab")
		)
		(fp_line
			(start -0.120396 0.3048)
			(end -0.120396 0.2794)
			(stroke
				(width 0.1)
				(type default)
			)
			(layer "B.Fab")
		)
		(fp_line
			(start -0.67945 0.3048)
			(end -0.120396 0.3048)
			(stroke
				(width 0.1)
				(type default)
			)
			(layer "B.Fab")
		)
		(pad "1" smd circle
			(at 0.40005 0 270)
			(size 0 0)
			(layers "B.Cu" "B.Mask" "B.Paste")
			(net "SPI_BIC1_MISO")
		)
		(pad "2" smd circle
			(at -0.40005 0 270)
			(size 0 0)
			(layers "B.Cu" "B.Mask" "B.Paste")
			(net "SPI_BIC1_MISO_R")
		)
	)
	(footprint ""
		(layer "B.Cu")
		(at 282.824936 -286.399732 90)
		(property "Reference" "C3294"
			(at 0 0 90)
			(layer "B.SilkS")
			(hide yes)
			(effects
				(font
					(size 1.27 1.27)
				)
				(justify mirror)
			)
		)
		(property "Value" ""
			(at 0 0 90)
			(layer "B.Fab")
			(effects
				(font
					(size 1.27 1.27)
				)
				(justify mirror)
			)
		)
		(duplicate_pad_numbers_are_jumpers no)
		(fp_line
			(start 0.299974 -0.150114)
			(end -0.299974 -0.150114)
			(stroke
				(width 0.1)
				(type default)
			)
			(layer "B.Fab")
		)
		(fp_line
			(start -0.299974 -0.150114)
			(end -0.299974 0.150114)
			(stroke
				(width 0.1)
				(type default)
			)
			(layer "B.Fab")
		)
		(fp_line
			(start 0.299974 0.150114)
			(end 0.299974 -0.150114)
			(stroke
				(width 0.1)
				(type default)
			)
			(layer "B.Fab")
		)
		(fp_line
			(start -0.299974 0.150114)
			(end 0.299974 0.150114)
			(stroke
				(width 0.1)
				(type default)
			)
			(layer "B.Fab")
		)
		(pad "1" smd rect
			(at 0.2667 0 270)
			(size 0.3048 0.381)
			(layers "B.Cu" "B.Mask" "B.Paste")
			(net "P1V25_SERDES_VDDPLL_PEX2")
		)
		(pad "2" smd rect
			(at -0.2667 0 270)
			(size 0.3048 0.381)
			(layers "B.Cu" "B.Mask" "B.Paste")
			(net "GND")
		)
	)
	(footprint ""
		(layer "B.Cu")
		(at 291.46119 -205.776068 180)
		(property "Reference" "R1044"
			(at 0 0 0)
			(layer "B.SilkS")
			(hide yes)
			(effects
				(font
					(size 1.27 1.27)
				)
				(justify mirror)
			)
		)
		(property "Value" ""
			(at 0 0 0)
			(layer "B.Fab")
			(effects
				(font
					(size 1.27 1.27)
				)
				(justify mirror)
			)
		)
		(duplicate_pad_numbers_are_jumpers no)
		(fp_line
			(start 0.7874 0.4064)
			(end 0.7874 -0.4064)
			(stroke
				(width 0.1524)
				(type default)
			)
			(layer "B.SilkS")
		)
		(fp_line
			(start 0.7874 -0.4064)
			(end -0.7874 -0.4064)
			(stroke
				(width 0.1524)
				(type default)
			)
			(layer "B.SilkS")
		)
		(fp_line
			(start -0.7874 0.4064)
			(end 0.7874 0.4064)
			(stroke
				(width 0.1524)
				(type default)
			)
			(layer "B.SilkS")
		)
		(fp_line
			(start -0.7874 -0.4064)
			(end -0.7874 0.4064)
			(stroke
				(width 0.1524)
				(type default)
			)
			(layer "B.SilkS")
		)
		(fp_line
			(start 0.67945 0.3048)
			(end 0.67945 -0.305054)
			(stroke
				(width 0.1)
				(type default)
			)
			(layer "B.Fab")
		)
		(fp_line
			(start 0.67945 -0.305054)
			(end 0.12065 -0.305054)
			(stroke
				(width 0.1)
				(type default)
			)
			(layer "B.Fab")
		)
		(fp_line
			(start 0.12065 0.3048)
			(end 0.67945 0.3048)
			(stroke
				(width 0.1)
				(type default)
			)
			(layer "B.Fab")
		)
		(fp_line
			(start 0.12065 0.2794)
			(end 0.12065 0.3048)
			(stroke
				(width 0.1)
				(type default)
			)
			(layer "B.Fab")
		)
		(fp_line
			(start 0.12065 -0.2794)
			(end -0.12065 -0.2794)
			(stroke
				(width 0.1)
				(type default)
			)
			(layer "B.Fab")
		)
		(fp_line
			(start 0.12065 -0.305054)
			(end 0.12065 -0.2794)
			(stroke
				(width 0.1)
				(type default)
			)
			(layer "B.Fab")
		)
		(fp_line
			(start -0.120396 0.3048)
			(end -0.120396 0.2794)
			(stroke
				(width 0.1)
				(type default)
			)
			(layer "B.Fab")
		)
		(fp_line
			(start -0.120396 0.2794)
			(end 0.12065 0.2794)
			(stroke
				(width 0.1)
				(type default)
			)
			(layer "B.Fab")
		)
		(fp_line
			(start -0.12065 -0.2794)
			(end -0.12065 -0.3048)
			(stroke
				(width 0.1)
				(type default)
			)
			(layer "B.Fab")
		)
		(fp_line
			(start -0.12065 -0.3048)
			(end -0.67945 -0.3048)
			(stroke
				(width 0.1)
				(type default)
			)
			(layer "B.Fab")
		)
		(fp_line
			(start -0.67945 0.3048)
			(end -0.120396 0.3048)
			(stroke
				(width 0.1)
				(type default)
			)
			(layer "B.Fab")
		)
		(fp_line
			(start -0.67945 -0.3048)
			(end -0.67945 0.3048)
			(stroke
				(width 0.1)
				(type default)
			)
			(layer "B.Fab")
		)
		(pad "1" smd circle
			(at 0.40005 0)
			(size 0 0)
			(layers "B.Cu" "B.Mask" "B.Paste")
			(net "GND")
		)
		(pad "2" smd circle
			(at -0.40005 0)
			(size 0 0)
			(layers "B.Cu" "B.Mask" "B.Paste")
			(net "SPI_BIC1_MISO_LS23_DIR4")
		)
	)
	(footprint ""
		(layer "B.Cu")
		(at 39.699946 -288.774886 -90)
		(property "Reference" "R3434"
			(at 0 0 90)
			(layer "B.SilkS")
			(hide yes)
			(effects
				(font
					(size 1.27 1.27)
				)
				(justify mirror)
			)
		)
		(property "Value" ""
			(at 0 0 90)
			(layer "B.Fab")
			(effects
				(font
					(size 1.27 1.27)
				)
				(justify mirror)
			)
		)
		(duplicate_pad_numbers_are_jumpers no)
		(fp_line
			(start -0.7874 0.4064)
			(end 0.7874 0.4064)
			(stroke
				(width 0.1524)
				(type default)
			)
			(layer "B.SilkS")
		)
		(fp_line
			(start 0.7874 0.4064)
			(end 0.7874 -0.4064)
			(stroke
				(width 0.1524)
				(type default)
			)
			(layer "B.SilkS")
		)
		(fp_line
			(start -0.7874 -0.4064)
			(end -0.7874 0.4064)
			(stroke
				(width 0.1524)
				(type default)
			)
			(layer "B.SilkS")
		)
		(fp_line
			(start 0.7874 -0.4064)
			(end -0.7874 -0.4064)
			(stroke
				(width 0.1524)
				(type default)
			)
			(layer "B.SilkS")
		)
		(fp_line
			(start -0.67945 0.3048)
			(end -0.120396 0.3048)
			(stroke
				(width 0.1)
				(type default)
			)
			(layer "B.Fab")
		)
		(fp_line
			(start -0.120396 0.3048)
			(end -0.120396 0.2794)
			(stroke
				(width 0.1)
				(type default)
			)
			(layer "B.Fab")
		)
		(fp_line
			(start 0.12065 0.3048)
			(end 0.67945 0.3048)
			(stroke
				(width 0.1)
				(type default)
			)
			(layer "B.Fab")
		)
		(fp_line
			(start 0.67945 0.3048)
			(end 0.67945 -0.305054)
			(stroke
				(width 0.1)
				(type default)
			)
			(layer "B.Fab")
		)
		(fp_line
			(start -0.120396 0.2794)
			(end 0.12065 0.2794)
			(stroke
				(width 0.1)
				(type default)
			)
			(layer "B.Fab")
		)
		(fp_line
			(start 0.12065 0.2794)
			(end 0.12065 0.3048)
			(stroke
				(width 0.1)
				(type default)
			)
			(layer "B.Fab")
		)
		(fp_line
			(start -0.12065 -0.2794)
			(end -0.12065 -0.3048)
			(stroke
				(width 0.1)
				(type default)
			)
			(layer "B.Fab")
		)
		(fp_line
			(start 0.12065 -0.2794)
			(end -0.12065 -0.2794)
			(stroke
				(width 0.1)
				(type default)
			)
			(layer "B.Fab")
		)
		(fp_line
			(start -0.67945 -0.3048)
			(end -0.67945 0.3048)
			(stroke
				(width 0.1)
				(type default)
			)
			(layer "B.Fab")
		)
		(fp_line
			(start -0.12065 -0.3048)
			(end -0.67945 -0.3048)
			(stroke
				(width 0.1)
				(type default)
			)
			(layer "B.Fab")
		)
		(fp_line
			(start 0.12065 -0.305054)
			(end 0.12065 -0.2794)
			(stroke
				(width 0.1)
				(type default)
			)
			(layer "B.Fab")
		)
		(fp_line
			(start 0.67945 -0.305054)
			(end 0.12065 -0.305054)
			(stroke
				(width 0.1)
				(type default)
			)
			(layer "B.Fab")
		)
		(pad "1" smd circle
			(at 0.40005 0 90)
			(size 0 0)
			(layers "B.Cu" "B.Mask" "B.Paste")
			(net "SPI_PEX0_SDIO3_R")
		)
		(pad "2" smd circle
			(at -0.40005 0 90)
			(size 0 0)
			(layers "B.Cu" "B.Mask" "B.Paste")
			(net "SPI_PEX0_SDIO3")
		)
	)
	(footprint ""
		(layer "B.Cu")
		(at 61.549788 -288.299906 90)
		(property "Reference" "C2923"
			(at 0 0 90)
			(layer "B.SilkS")
			(hide yes)
			(effects
				(font
					(size 1.27 1.27)
				)
				(justify mirror)
			)
		)
		(property "Value" ""
			(at 0 0 90)
			(layer "B.Fab")
			(effects
				(font
					(size 1.27 1.27)
				)
				(justify mirror)
			)
		)
		(duplicate_pad_numbers_are_jumpers no)
		(fp_line
			(start 0.299974 -0.150114)
			(end -0.299974 -0.150114)
			(stroke
				(width 0.1)
				(type default)
			)
			(layer "B.Fab")
		)
		(fp_line
			(start -0.299974 -0.150114)
			(end -0.299974 0.150114)
			(stroke
				(width 0.1)
				(type default)
			)
			(layer "B.Fab")
		)
		(fp_line
			(start 0.299974 0.150114)
			(end 0.299974 -0.150114)
			(stroke
				(width 0.1)
				(type default)
			)
			(layer "B.Fab")
		)
		(fp_line
			(start -0.299974 0.150114)
			(end 0.299974 0.150114)
			(stroke
				(width 0.1)
				(type default)
			)
			(layer "B.Fab")
		)
		(pad "1" smd rect
			(at 0.2667 0 270)
			(size 0.3048 0.381)
			(layers "B.Cu" "B.Mask" "B.Paste")
			(net "P1V25_PEX0")
		)
		(pad "2" smd rect
			(at -0.2667 0 270)
			(size 0.3048 0.381)
			(layers "B.Cu" "B.Mask" "B.Paste")
			(net "GND")
		)
	)
	(footprint ""
		(layer "B.Cu")
		(at 187.149994 -293.52494 180)
		(property "Reference" "C3110"
			(at 0 0 0)
			(layer "B.SilkS")
			(hide yes)
			(effects
				(font
					(size 1.27 1.27)
				)
				(justify mirror)
			)
		)
		(property "Value" ""
			(at 0 0 0)
			(layer "B.Fab")
			(effects
				(font
					(size 1.27 1.27)
				)
				(justify mirror)
			)
		)
		(duplicate_pad_numbers_are_jumpers no)
		(fp_line
			(start 0.299974 0.150114)
			(end 0.299974 -0.150114)
			(stroke
				(width 0.1)
				(type default)
			)
			(layer "B.Fab")
		)
		(fp_line
			(start 0.299974 -0.150114)
			(end -0.299974 -0.150114)
			(stroke
				(width 0.1)
				(type default)
			)
			(layer "B.Fab")
		)
		(fp_line
			(start -0.299974 0.150114)
			(end 0.299974 0.150114)
			(stroke
				(width 0.1)
				(type default)
			)
			(layer "B.Fab")
		)
		(fp_line
			(start -0.299974 -0.150114)
			(end -0.299974 0.150114)
			(stroke
				(width 0.1)
				(type default)
			)
			(layer "B.Fab")
		)
		(pad "1" smd rect
			(at 0.2667 0)
			(size 0.3048 0.381)
			(layers "B.Cu" "B.Mask" "B.Paste")
			(net "P1V25_PEX1")
		)
		(pad "2" smd rect
			(at -0.2667 0)
			(size 0.3048 0.381)
			(layers "B.Cu" "B.Mask" "B.Paste")
			(net "GND")
		)
	)
	(footprint ""
		(layer "B.Cu")
		(at 67.751198 -305.399948 -90)
		(property "Reference" "C2980"
			(at 0 0 90)
			(layer "B.SilkS")
			(hide yes)
			(effects
				(font
					(size 1.27 1.27)
				)
				(justify mirror)
			)
		)
		(property "Value" ""
			(at 0 0 90)
			(layer "B.Fab")
			(effects
				(font
					(size 1.27 1.27)
				)
				(justify mirror)
			)
		)
		(duplicate_pad_numbers_are_jumpers no)
		(fp_line
			(start -0.299974 0.150114)
			(end 0.299974 0.150114)
			(stroke
				(width 0.1)
				(type default)
			)
			(layer "B.Fab")
		)
		(fp_line
			(start 0.299974 0.150114)
			(end 0.299974 -0.150114)
			(stroke
				(width 0.1)
				(type default)
			)
			(layer "B.Fab")
		)
		(fp_line
			(start -0.299974 -0.150114)
			(end -0.299974 0.150114)
			(stroke
				(width 0.1)
				(type default)
			)
			(layer "B.Fab")
		)
		(fp_line
			(start 0.299974 -0.150114)
			(end -0.299974 -0.150114)
			(stroke
				(width 0.1)
				(type default)
			)
			(layer "B.Fab")
		)
		(pad "1" smd rect
			(at 0.2667 0 90)
			(size 0.3048 0.381)
			(layers "B.Cu" "B.Mask" "B.Paste")
			(net "P1V25_SERDES_VDDPLL_PEX0")
		)
		(pad "2" smd rect
			(at -0.2667 0 90)
			(size 0.3048 0.381)
			(layers "B.Cu" "B.Mask" "B.Paste")
			(net "GND")
		)
	)
	(footprint ""
		(layer "B.Cu")
		(at 105.207562 -358.724708 90)
		(property "Reference" "R6378"
			(at 0 0 90)
			(layer "B.SilkS")
			(hide yes)
			(effects
				(font
					(size 1.27 1.27)
				)
				(justify mirror)
			)
		)
		(property "Value" ""
			(at 0 0 90)
			(layer "B.Fab")
			(effects
				(font
					(size 1.27 1.27)
				)
				(justify mirror)
			)
		)
		(duplicate_pad_numbers_are_jumpers no)
		(fp_line
			(start 0.7874 -0.4064)
			(end -0.7874 -0.4064)
			(stroke
				(width 0.1524)
				(type default)
			)
			(layer "B.SilkS")
		)
		(fp_line
			(start -0.7874 -0.4064)
			(end -0.7874 0.4064)
			(stroke
				(width 0.1524)
				(type default)
			)
			(layer "B.SilkS")
		)
		(fp_line
			(start 0.7874 0.4064)
			(end 0.7874 -0.4064)
			(stroke
				(width 0.1524)
				(type default)
			)
			(layer "B.SilkS")
		)
		(fp_line
			(start -0.7874 0.4064)
			(end 0.7874 0.4064)
			(stroke
				(width 0.1524)
				(type default)
			)
			(layer "B.SilkS")
		)
		(fp_line
			(start 0.67945 -0.305054)
			(end 0.12065 -0.305054)
			(stroke
				(width 0.1)
				(type default)
			)
			(layer "B.Fab")
		)
		(fp_line
			(start 0.12065 -0.305054)
			(end 0.12065 -0.2794)
			(stroke
				(width 0.1)
				(type default)
			)
			(layer "B.Fab")
		)
		(fp_line
			(start -0.12065 -0.3048)
			(end -0.67945 -0.3048)
			(stroke
				(width 0.1)
				(type default)
			)
			(layer "B.Fab")
		)
		(fp_line
			(start -0.67945 -0.3048)
			(end -0.67945 0.3048)
			(stroke
				(width 0.1)
				(type default)
			)
			(layer "B.Fab")
		)
		(fp_line
			(start 0.12065 -0.2794)
			(end -0.12065 -0.2794)
			(stroke
				(width 0.1)
				(type default)
			)
			(layer "B.Fab")
		)
		(fp_line
			(start -0.12065 -0.2794)
			(end -0.12065 -0.3048)
			(stroke
				(width 0.1)
				(type default)
			)
			(layer "B.Fab")
		)
		(fp_line
			(start 0.12065 0.2794)
			(end 0.12065 0.3048)
			(stroke
				(width 0.1)
				(type default)
			)
			(layer "B.Fab")
		)
		(fp_line
			(start -0.120396 0.2794)
			(end 0.12065 0.2794)
			(stroke
				(width 0.1)
				(type default)
			)
			(layer "B.Fab")
		)
		(fp_line
			(start 0.67945 0.3048)
			(end 0.67945 -0.305054)
			(stroke
				(width 0.1)
				(type default)
			)
			(layer "B.Fab")
		)
		(fp_line
			(start 0.12065 0.3048)
			(end 0.67945 0.3048)
			(stroke
				(width 0.1)
				(type default)
			)
			(layer "B.Fab")
		)
		(fp_line
			(start -0.120396 0.3048)
			(end -0.120396 0.2794)
			(stroke
				(width 0.1)
				(type default)
			)
			(layer "B.Fab")
		)
		(fp_line
			(start -0.67945 0.3048)
			(end -0.120396 0.3048)
			(stroke
				(width 0.1)
				(type default)
			)
			(layer "B.Fab")
		)
		(pad "1" smd circle
			(at 0.40005 0 270)
			(size 0 0)
			(layers "B.Cu" "B.Mask" "B.Paste")
			(net "CLK_100M_DB800ZL_PEX2_S3_R_DP")
		)
		(pad "2" smd circle
			(at -0.40005 0 270)
			(size 0 0)
			(layers "B.Cu" "B.Mask" "B.Paste")
			(net "CLK_100M_DB800ZL_PEX2_S3_DP")
		)
	)
	(footprint ""
		(layer "B.Cu")
		(at 302.299878 -288.774886 180)
		(property "Reference" "C3351"
			(at 0 0 0)
			(layer "B.SilkS")
			(hide yes)
			(effects
				(font
					(size 1.27 1.27)
				)
				(justify mirror)
			)
		)
		(property "Value" ""
			(at 0 0 0)
			(layer "B.Fab")
			(effects
				(font
					(size 1.27 1.27)
				)
				(justify mirror)
			)
		)
		(duplicate_pad_numbers_are_jumpers no)
		(fp_line
			(start 0.299974 0.150114)
			(end 0.299974 -0.150114)
			(stroke
				(width 0.1)
				(type default)
			)
			(layer "B.Fab")
		)
		(fp_line
			(start 0.299974 -0.150114)
			(end -0.299974 -0.150114)
			(stroke
				(width 0.1)
				(type default)
			)
			(layer "B.Fab")
		)
		(fp_line
			(start -0.299974 0.150114)
			(end 0.299974 0.150114)
			(stroke
				(width 0.1)
				(type default)
			)
			(layer "B.Fab")
		)
		(fp_line
			(start -0.299974 -0.150114)
			(end -0.299974 0.150114)
			(stroke
				(width 0.1)
				(type default)
			)
			(layer "B.Fab")
		)
		(pad "1" smd rect
			(at 0.2667 0)
			(size 0.3048 0.381)
			(layers "B.Cu" "B.Mask" "B.Paste")
			(net "P1V8_PEX")
		)
		(pad "2" smd rect
			(at -0.2667 0)
			(size 0.3048 0.381)
			(layers "B.Cu" "B.Mask" "B.Paste")
			(net "GND")
		)
	)
	(footprint ""
		(layer "B.Cu")
		(at 397.44904 -301.0154 180)
		(property "Reference" "C1873"
			(at 0 0 0)
			(layer "B.SilkS")
			(hide yes)
			(effects
				(font
					(size 1.27 1.27)
				)
				(justify mirror)
			)
		)
		(property "Value" ""
			(at 0 0 0)
			(layer "B.Fab")
			(effects
				(font
					(size 1.27 1.27)
				)
				(justify mirror)
			)
		)
		(duplicate_pad_numbers_are_jumpers no)
		(fp_line
			(start 0.299974 0.150114)
			(end 0.299974 -0.150114)
			(stroke
				(width 0.1)
				(type default)
			)
			(layer "B.Fab")
		)
		(fp_line
			(start 0.299974 -0.150114)
			(end -0.299974 -0.150114)
			(stroke
				(width 0.1)
				(type default)
			)
			(layer "B.Fab")
		)
		(fp_line
			(start -0.299974 0.150114)
			(end 0.299974 0.150114)
			(stroke
				(width 0.1)
				(type default)
			)
			(layer "B.Fab")
		)
		(fp_line
			(start -0.299974 -0.150114)
			(end -0.299974 0.150114)
			(stroke
				(width 0.1)
				(type default)
			)
			(layer "B.Fab")
		)
		(pad "1" smd rect
			(at 0.2667 0)
			(size 0.3048 0.381)
			(layers "B.Cu" "B.Mask" "B.Paste")
			(net "P0V8_PEX3")
		)
		(pad "2" smd rect
			(at -0.2667 0)
			(size 0.3048 0.381)
			(layers "B.Cu" "B.Mask" "B.Paste")
			(net "GND")
		)
	)
	(footprint ""
		(layer "B.Cu")
		(at 167.675052 -286.399732 90)
		(property "Reference" "C3144"
			(at 0 0 90)
			(layer "B.SilkS")
			(hide yes)
			(effects
				(font
					(size 1.27 1.27)
				)
				(justify mirror)
			)
		)
		(property "Value" ""
			(at 0 0 90)
			(layer "B.Fab")
			(effects
				(font
					(size 1.27 1.27)
				)
				(justify mirror)
			)
		)
		(duplicate_pad_numbers_are_jumpers no)
		(fp_line
			(start 0.299974 -0.150114)
			(end -0.299974 -0.150114)
			(stroke
				(width 0.1)
				(type default)
			)
			(layer "B.Fab")
		)
		(fp_line
			(start -0.299974 -0.150114)
			(end -0.299974 0.150114)
			(stroke
				(width 0.1)
				(type default)
			)
			(layer "B.Fab")
		)
		(fp_line
			(start 0.299974 0.150114)
			(end 0.299974 -0.150114)
			(stroke
				(width 0.1)
				(type default)
			)
			(layer "B.Fab")
		)
		(fp_line
			(start -0.299974 0.150114)
			(end 0.299974 0.150114)
			(stroke
				(width 0.1)
				(type default)
			)
			(layer "B.Fab")
		)
		(pad "1" smd rect
			(at 0.2667 0 270)
			(size 0.3048 0.381)
			(layers "B.Cu" "B.Mask" "B.Paste")
			(net "P1V25_SERDES_VDDPLL_PEX1")
		)
		(pad "2" smd rect
			(at -0.2667 0 270)
			(size 0.3048 0.381)
			(layers "B.Cu" "B.Mask" "B.Paste")
			(net "GND")
		)
	)
	(footprint ""
		(layer "B.Cu")
		(at 19.67611 -222.214186)
		(property "Reference" "R3449"
			(at 0 0 0)
			(layer "B.SilkS")
			(hide yes)
			(effects
				(font
					(size 1.27 1.27)
				)
				(justify mirror)
			)
		)
		(property "Value" ""
			(at 0 0 0)
			(layer "B.Fab")
			(effects
				(font
					(size 1.27 1.27)
				)
				(justify mirror)
			)
		)
		(duplicate_pad_numbers_are_jumpers no)
		(fp_line
			(start -0.7874 -0.4064)
			(end -0.7874 0.4064)
			(stroke
				(width 0.1524)
				(type default)
			)
			(layer "B.SilkS")
		)
		(fp_line
			(start -0.7874 0.4064)
			(end 0.7874 0.4064)
			(stroke
				(width 0.1524)
				(type default)
			)
			(layer "B.SilkS")
		)
		(fp_line
			(start 0.7874 -0.4064)
			(end -0.7874 -0.4064)
			(stroke
				(width 0.1524)
				(type default)
			)
			(layer "B.SilkS")
		)
		(fp_line
			(start 0.7874 0.4064)
			(end 0.7874 -0.4064)
			(stroke
				(width 0.1524)
				(type default)
			)
			(layer "B.SilkS")
		)
		(fp_line
			(start -0.67945 -0.3048)
			(end -0.67945 0.3048)
			(stroke
				(width 0.1)
				(type default)
			)
			(layer "B.Fab")
		)
		(fp_line
			(start -0.67945 0.3048)
			(end -0.120396 0.3048)
			(stroke
				(width 0.1)
				(type default)
			)
			(layer "B.Fab")
		)
		(fp_line
			(start -0.12065 -0.3048)
			(end -0.67945 -0.3048)
			(stroke
				(width 0.1)
				(type default)
			)
			(layer "B.Fab")
		)
		(fp_line
			(start -0.12065 -0.2794)
			(end -0.12065 -0.3048)
			(stroke
				(width 0.1)
				(type default)
			)
			(layer "B.Fab")
		)
		(fp_line
			(start -0.120396 0.2794)
			(end 0.12065 0.2794)
			(stroke
				(width 0.1)
				(type default)
			)
			(layer "B.Fab")
		)
		(fp_line
			(start -0.120396 0.3048)
			(end -0.120396 0.2794)
			(stroke
				(width 0.1)
				(type default)
			)
			(layer "B.Fab")
		)
		(fp_line
			(start 0.12065 -0.305054)
			(end 0.12065 -0.2794)
			(stroke
				(width 0.1)
				(type default)
			)
			(layer "B.Fab")
		)
		(fp_line
			(start 0.12065 -0.2794)
			(end -0.12065 -0.2794)
			(stroke
				(width 0.1)
				(type default)
			)
			(layer "B.Fab")
		)
		(fp_line
			(start 0.12065 0.2794)
			(end 0.12065 0.3048)
			(stroke
				(width 0.1)
				(type default)
			)
			(layer "B.Fab")
		)
		(fp_line
			(start 0.12065 0.3048)
			(end 0.67945 0.3048)
			(stroke
				(width 0.1)
				(type default)
			)
			(layer "B.Fab")
		)
		(fp_line
			(start 0.67945 -0.305054)
			(end 0.12065 -0.305054)
			(stroke
				(width 0.1)
				(type default)
			)
			(layer "B.Fab")
		)
		(fp_line
			(start 0.67945 0.3048)
			(end 0.67945 -0.305054)
			(stroke
				(width 0.1)
				(type default)
			)
			(layer "B.Fab")
		)
		(pad "1" smd circle
			(at 0.40005 0 180)
			(size 0 0)
			(layers "B.Cu" "B.Mask" "B.Paste")
			(net "SPI_PEX0_SDIO0_MUX")
		)
		(pad "2" smd circle
			(at -0.40005 0 180)
			(size 0 0)
			(layers "B.Cu" "B.Mask" "B.Paste")
			(net "SPI_PEX0_SDIO0_MUX_R")
		)
	)
	(footprint ""
		(layer "B.Cu")
		(at 25.134824 -259.341112)
		(property "Reference" "C3072"
			(at 0 0 0)
			(layer "B.SilkS")
			(hide yes)
			(effects
				(font
					(size 1.27 1.27)
				)
				(justify mirror)
			)
		)
		(property "Value" ""
			(at 0 0 0)
			(layer "B.Fab")
			(effects
				(font
					(size 1.27 1.27)
				)
				(justify mirror)
			)
		)
		(duplicate_pad_numbers_are_jumpers no)
		(fp_line
			(start -0.299974 -0.150114)
			(end -0.299974 0.150114)
			(stroke
				(width 0.1)
				(type default)
			)
			(layer "B.Fab")
		)
		(fp_line
			(start -0.299974 0.150114)
			(end 0.299974 0.150114)
			(stroke
				(width 0.1)
				(type default)
			)
			(layer "B.Fab")
		)
		(fp_line
			(start 0.299974 -0.150114)
			(end -0.299974 -0.150114)
			(stroke
				(width 0.1)
				(type default)
			)
			(layer "B.Fab")
		)
		(fp_line
			(start 0.299974 0.150114)
			(end 0.299974 -0.150114)
			(stroke
				(width 0.1)
				(type default)
			)
			(layer "B.Fab")
		)
		(pad "1" smd rect
			(at 0.2667 0 180)
			(size 0.3048 0.381)
			(layers "B.Cu" "B.Mask" "B.Paste")
			(net "P1V8_VDDA_PEX0")
		)
		(pad "2" smd rect
			(at -0.2667 0 180)
			(size 0.3048 0.381)
			(layers "B.Cu" "B.Mask" "B.Paste")
			(net "GND")
		)
	)
	(footprint ""
		(layer "B.Cu")
		(at 339.693758 -220.387164 -90)
		(property "Reference" "C2083"
			(at 0 0 90)
			(layer "B.SilkS")
			(hide yes)
			(effects
				(font
					(size 1.27 1.27)
				)
				(justify mirror)
			)
		)
		(property "Value" ""
			(at 0 0 90)
			(layer "B.Fab")
			(effects
				(font
					(size 1.27 1.27)
				)
				(justify mirror)
			)
		)
		(duplicate_pad_numbers_are_jumpers no)
		(fp_line
			(start -0.69215 0.2921)
			(end 0.69215 0.2921)
			(stroke
				(width 0.1524)
				(type default)
			)
			(layer "B.SilkS")
		)
		(fp_line
			(start 0.69215 0.2921)
			(end 0.69215 -0.2921)
			(stroke
				(width 0.1524)
				(type default)
			)
			(layer "B.SilkS")
		)
		(fp_line
			(start -0.69215 -0.2921)
			(end -0.69215 0.2921)
			(stroke
				(width 0.1524)
				(type default)
			)
			(layer "B.SilkS")
		)
		(fp_line
			(start 0.69215 -0.2921)
			(end -0.69215 -0.2921)
			(stroke
				(width 0.1524)
				(type default)
			)
			(layer "B.SilkS")
		)
		(fp_line
			(start -0.51435 0.2794)
			(end 0.51435 0.2794)
			(stroke
				(width 0.1)
				(type default)
			)
			(layer "B.Fab")
		)
		(fp_line
			(start 0.51435 0.2794)
			(end 0.51435 -0.2794)
			(stroke
				(width 0.1)
				(type default)
			)
			(layer "B.Fab")
		)
		(fp_line
			(start -0.51435 -0.2794)
			(end -0.51435 0.2794)
			(stroke
				(width 0.1)
				(type default)
			)
			(layer "B.Fab")
		)
		(fp_line
			(start 0.51435 -0.2794)
			(end -0.51435 -0.2794)
			(stroke
				(width 0.1)
				(type default)
			)
			(layer "B.Fab")
		)
		(pad "1" smd circle
			(at 0.40005 0 90)
			(size 0 0)
			(layers "B.Cu" "B.Mask" "B.Paste")
			(net "P3V3_FPGA_VCCIO4")
		)
		(pad "2" smd circle
			(at -0.40005 0 90)
			(size 0 0)
			(layers "B.Cu" "B.Mask" "B.Paste")
			(net "GND")
		)
		(zone
			(layer "B.Cu")
			(hatch none 0.5)
			(connect_pads
				(clearance 0)
			)
			(min_thickness 0.25)
			(keepout
				(tracks not_allowed)
				(vias allowed)
				(pads allowed)
				(copperpour not_allowed)
				(footprints allowed)
			)
			(placement
				(enabled no)
				(sheetname "")
			)
			(fill
				(thermal_gap 0.5)
				(thermal_bridge_width 0.5)
				(island_removal_mode 0)
			)
			(polygon
				(pts
					(xy 339.606128 -220.196664) (xy 339.547962 -220.288104) (xy 339.547962 -220.487494) (xy 339.606128 -220.577664)
					(xy 339.781388 -220.577664) (xy 339.839808 -220.487494) (xy 339.839808 -220.288104) (xy 339.781642 -220.196664)
				)
			)
		)
	)
	(footprint ""
		(layer "B.Cu")
		(at 239.264698 -217.330528 -90)
		(property "Reference" "R4854"
			(at 0 0 90)
			(layer "B.SilkS")
			(hide yes)
			(effects
				(font
					(size 1.27 1.27)
				)
				(justify mirror)
			)
		)
		(property "Value" ""
			(at 0 0 90)
			(layer "B.Fab")
			(effects
				(font
					(size 1.27 1.27)
				)
				(justify mirror)
			)
		)
		(duplicate_pad_numbers_are_jumpers no)
		(fp_line
			(start -0.7874 0.4064)
			(end 0.7874 0.4064)
			(stroke
				(width 0.1524)
				(type default)
			)
			(layer "B.SilkS")
		)
		(fp_line
			(start 0.7874 0.4064)
			(end 0.7874 -0.4064)
			(stroke
				(width 0.1524)
				(type default)
			)
			(layer "B.SilkS")
		)
		(fp_line
			(start -0.7874 -0.4064)
			(end -0.7874 0.4064)
			(stroke
				(width 0.1524)
				(type default)
			)
			(layer "B.SilkS")
		)
		(fp_line
			(start 0.7874 -0.4064)
			(end -0.7874 -0.4064)
			(stroke
				(width 0.1524)
				(type default)
			)
			(layer "B.SilkS")
		)
		(fp_line
			(start -0.67945 0.3048)
			(end -0.120396 0.3048)
			(stroke
				(width 0.1)
				(type default)
			)
			(layer "B.Fab")
		)
		(fp_line
			(start -0.120396 0.3048)
			(end -0.120396 0.2794)
			(stroke
				(width 0.1)
				(type default)
			)
			(layer "B.Fab")
		)
		(fp_line
			(start 0.12065 0.3048)
			(end 0.67945 0.3048)
			(stroke
				(width 0.1)
				(type default)
			)
			(layer "B.Fab")
		)
		(fp_line
			(start 0.67945 0.3048)
			(end 0.67945 -0.305054)
			(stroke
				(width 0.1)
				(type default)
			)
			(layer "B.Fab")
		)
		(fp_line
			(start -0.120396 0.2794)
			(end 0.12065 0.2794)
			(stroke
				(width 0.1)
				(type default)
			)
			(layer "B.Fab")
		)
		(fp_line
			(start 0.12065 0.2794)
			(end 0.12065 0.3048)
			(stroke
				(width 0.1)
				(type default)
			)
			(layer "B.Fab")
		)
		(fp_line
			(start -0.12065 -0.2794)
			(end -0.12065 -0.3048)
			(stroke
				(width 0.1)
				(type default)
			)
			(layer "B.Fab")
		)
		(fp_line
			(start 0.12065 -0.2794)
			(end -0.12065 -0.2794)
			(stroke
				(width 0.1)
				(type default)
			)
			(layer "B.Fab")
		)
		(fp_line
			(start -0.67945 -0.3048)
			(end -0.67945 0.3048)
			(stroke
				(width 0.1)
				(type default)
			)
			(layer "B.Fab")
		)
		(fp_line
			(start -0.12065 -0.3048)
			(end -0.67945 -0.3048)
			(stroke
				(width 0.1)
				(type default)
			)
			(layer "B.Fab")
		)
		(fp_line
			(start 0.12065 -0.305054)
			(end 0.12065 -0.2794)
			(stroke
				(width 0.1)
				(type default)
			)
			(layer "B.Fab")
		)
		(fp_line
			(start 0.67945 -0.305054)
			(end 0.12065 -0.305054)
			(stroke
				(width 0.1)
				(type default)
			)
			(layer "B.Fab")
		)
		(pad "1" smd circle
			(at 0.40005 0 90)
			(size 0 0)
			(layers "B.Cu" "B.Mask" "B.Paste")
			(net "P1V2_AUX")
		)
		(pad "2" smd circle
			(at -0.40005 0 90)
			(size 0 0)
			(layers "B.Cu" "B.Mask" "B.Paste")
			(net "P1V2_BIC_ADCVREFREXT0")
		)
	)
	(footprint ""
		(layer "B.Cu")
		(at 238.514382 -215.740742 180)
		(property "Reference" "L1"
			(at 0 0 0)
			(layer "B.SilkS")
			(hide yes)
			(effects
				(font
					(size 1.27 1.27)
				)
				(justify mirror)
			)
		)
		(property "Value" ""
			(at 0 0 0)
			(layer "B.Fab")
			(effects
				(font
					(size 1.27 1.27)
				)
				(justify mirror)
			)
		)
		(duplicate_pad_numbers_are_jumpers no)
		(fp_line
			(start 1.27 0.5842)
			(end 1.27 -0.5842)
			(stroke
				(width 0.1524)
				(type default)
			)
			(layer "B.SilkS")
		)
		(fp_line
			(start 1.27 -0.5588)
			(end 1.27 -0.5842)
			(stroke
				(width 0.1524)
				(type default)
			)
			(layer "B.SilkS")
		)
		(fp_line
			(start 1.27 -0.5842)
			(end -1.27 -0.5842)
			(stroke
				(width 0.1524)
				(type default)
			)
			(layer "B.SilkS")
		)
		(fp_line
			(start -1.27 0.5842)
			(end 1.27 0.5842)
			(stroke
				(width 0.1524)
				(type default)
			)
			(layer "B.SilkS")
		)
		(fp_line
			(start -1.27 0.5842)
			(end -1.27 -0.5842)
			(stroke
				(width 0.1524)
				(type default)
			)
			(layer "B.SilkS")
		)
		(fp_line
			(start 1.194308 0.406654)
			(end 1.194308 -0.406654)
			(stroke
				(width 0.1)
				(type default)
			)
			(layer "B.Fab")
		)
		(fp_line
			(start 1.194308 -0.406654)
			(end 0.9144 -0.406654)
			(stroke
				(width 0.1)
				(type default)
			)
			(layer "B.Fab")
		)
		(fp_line
			(start 0.9144 0.508)
			(end 0.9144 0.406654)
			(stroke
				(width 0.1)
				(type default)
			)
			(layer "B.Fab")
		)
		(fp_line
			(start 0.9144 0.406654)
			(end 1.194308 0.406654)
			(stroke
				(width 0.1)
				(type default)
			)
			(layer "B.Fab")
		)
		(fp_line
			(start 0.9144 -0.406654)
			(end 0.9144 -0.508)
			(stroke
				(width 0.1)
				(type default)
			)
			(layer "B.Fab")
		)
		(fp_line
			(start 0.9144 -0.508)
			(end -0.9144 -0.508)
			(stroke
				(width 0.1)
				(type default)
			)
			(layer "B.Fab")
		)
		(fp_line
			(start -0.9144 0.508)
			(end 0.9144 0.508)
			(stroke
				(width 0.1)
				(type default)
			)
			(layer "B.Fab")
		)
		(fp_line
			(start -0.9144 0.4064)
			(end -0.9144 0.508)
			(stroke
				(width 0.1)
				(type default)
			)
			(layer "B.Fab")
		)
		(fp_line
			(start -0.9144 -0.406654)
			(end -1.1938 -0.406654)
			(stroke
				(width 0.1)
				(type default)
			)
			(layer "B.Fab")
		)
		(fp_line
			(start -0.9144 -0.508)
			(end -0.9144 -0.406654)
			(stroke
				(width 0.1)
				(type default)
			)
			(layer "B.Fab")
		)
		(fp_line
			(start -1.1938 0.4064)
			(end -0.9144 0.4064)
			(stroke
				(width 0.1)
				(type default)
			)
			(layer "B.Fab")
		)
		(fp_line
			(start -1.1938 -0.406654)
			(end -1.1938 0.4064)
			(stroke
				(width 0.1)
				(type default)
			)
			(layer "B.Fab")
		)
		(pad "1" smd rect
			(at 0.7366 0 90)
			(size 0.7112 0.8128)
			(layers "B.Cu" "B.Mask" "B.Paste")
			(net "P1V2_BIC_PLL")
		)
		(pad "2" smd rect
			(at -0.7366 0 90)
			(size 0.7112 0.8128)
			(layers "B.Cu" "B.Mask" "B.Paste")
			(net "P1V2_AUX")
		)
	)
	(footprint ""
		(layer "B.Cu")
		(at 156.157168 -291.72662 180)
		(property "Reference" "R3452"
			(at 0 0 0)
			(layer "B.SilkS")
			(hide yes)
			(effects
				(font
					(size 1.27 1.27)
				)
				(justify mirror)
			)
		)
		(property "Value" ""
			(at 0 0 0)
			(layer "B.Fab")
			(effects
				(font
					(size 1.27 1.27)
				)
				(justify mirror)
			)
		)
		(duplicate_pad_numbers_are_jumpers no)
		(fp_line
			(start 0.7874 0.4064)
			(end 0.7874 -0.4064)
			(stroke
				(width 0.1524)
				(type default)
			)
			(layer "B.SilkS")
		)
		(fp_line
			(start 0.7874 -0.4064)
			(end -0.7874 -0.4064)
			(stroke
				(width 0.1524)
				(type default)
			)
			(layer "B.SilkS")
		)
		(fp_line
			(start -0.7874 0.4064)
			(end 0.7874 0.4064)
			(stroke
				(width 0.1524)
				(type default)
			)
			(layer "B.SilkS")
		)
		(fp_line
			(start -0.7874 -0.4064)
			(end -0.7874 0.4064)
			(stroke
				(width 0.1524)
				(type default)
			)
			(layer "B.SilkS")
		)
		(fp_line
			(start 0.67945 0.3048)
			(end 0.67945 -0.305054)
			(stroke
				(width 0.1)
				(type default)
			)
			(layer "B.Fab")
		)
		(fp_line
			(start 0.67945 -0.305054)
			(end 0.12065 -0.305054)
			(stroke
				(width 0.1)
				(type default)
			)
			(layer "B.Fab")
		)
		(fp_line
			(start 0.12065 0.3048)
			(end 0.67945 0.3048)
			(stroke
				(width 0.1)
				(type default)
			)
			(layer "B.Fab")
		)
		(fp_line
			(start 0.12065 0.2794)
			(end 0.12065 0.3048)
			(stroke
				(width 0.1)
				(type default)
			)
			(layer "B.Fab")
		)
		(fp_line
			(start 0.12065 -0.2794)
			(end -0.12065 -0.2794)
			(stroke
				(width 0.1)
				(type default)
			)
			(layer "B.Fab")
		)
		(fp_line
			(start 0.12065 -0.305054)
			(end 0.12065 -0.2794)
			(stroke
				(width 0.1)
				(type default)
			)
			(layer "B.Fab")
		)
		(fp_line
			(start -0.120396 0.3048)
			(end -0.120396 0.2794)
			(stroke
				(width 0.1)
				(type default)
			)
			(layer "B.Fab")
		)
		(fp_line
			(start -0.120396 0.2794)
			(end 0.12065 0.2794)
			(stroke
				(width 0.1)
				(type default)
			)
			(layer "B.Fab")
		)
		(fp_line
			(start -0.12065 -0.2794)
			(end -0.12065 -0.3048)
			(stroke
				(width 0.1)
				(type default)
			)
			(layer "B.Fab")
		)
		(fp_line
			(start -0.12065 -0.3048)
			(end -0.67945 -0.3048)
			(stroke
				(width 0.1)
				(type default)
			)
			(layer "B.Fab")
		)
		(fp_line
			(start -0.67945 0.3048)
			(end -0.120396 0.3048)
			(stroke
				(width 0.1)
				(type default)
			)
			(layer "B.Fab")
		)
		(fp_line
			(start -0.67945 -0.3048)
			(end -0.67945 0.3048)
			(stroke
				(width 0.1)
				(type default)
			)
			(layer "B.Fab")
		)
		(pad "1" smd circle
			(at 0.40005 0)
			(size 0 0)
			(layers "B.Cu" "B.Mask" "B.Paste")
			(net "SPI_PEX1_CLK_R")
		)
		(pad "2" smd circle
			(at -0.40005 0)
			(size 0 0)
			(layers "B.Cu" "B.Mask" "B.Paste")
			(net "SPI_PEX1_CLK")
		)
	)
	(footprint ""
		(layer "B.Cu")
		(at 177.174906 -297.79976 -90)
		(property "Reference" "C1411"
			(at 0 0 90)
			(layer "B.SilkS")
			(hide yes)
			(effects
				(font
					(size 1.27 1.27)
				)
				(justify mirror)
			)
		)
		(property "Value" ""
			(at 0 0 90)
			(layer "B.Fab")
			(effects
				(font
					(size 1.27 1.27)
				)
				(justify mirror)
			)
		)
		(duplicate_pad_numbers_are_jumpers no)
		(fp_line
			(start -0.299974 0.150114)
			(end 0.299974 0.150114)
			(stroke
				(width 0.1)
				(type default)
			)
			(layer "B.Fab")
		)
		(fp_line
			(start 0.299974 0.150114)
			(end 0.299974 -0.150114)
			(stroke
				(width 0.1)
				(type default)
			)
			(layer "B.Fab")
		)
		(fp_line
			(start -0.299974 -0.150114)
			(end -0.299974 0.150114)
			(stroke
				(width 0.1)
				(type default)
			)
			(layer "B.Fab")
		)
		(fp_line
			(start 0.299974 -0.150114)
			(end -0.299974 -0.150114)
			(stroke
				(width 0.1)
				(type default)
			)
			(layer "B.Fab")
		)
		(pad "1" smd rect
			(at 0.2667 0 90)
			(size 0.3048 0.381)
			(layers "B.Cu" "B.Mask" "B.Paste")
			(net "P0V8_PEX1")
		)
		(pad "2" smd rect
			(at -0.2667 0 90)
			(size 0.3048 0.381)
			(layers "B.Cu" "B.Mask" "B.Paste")
			(net "GND")
		)
	)
	(footprint ""
		(layer "B.Cu")
		(at 180.50002 -299.699934 -90)
		(property "Reference" "C1460"
			(at 0 0 90)
			(layer "B.SilkS")
			(hide yes)
			(effects
				(font
					(size 1.27 1.27)
				)
				(justify mirror)
			)
		)
		(property "Value" ""
			(at 0 0 90)
			(layer "B.Fab")
			(effects
				(font
					(size 1.27 1.27)
				)
				(justify mirror)
			)
		)
		(duplicate_pad_numbers_are_jumpers no)
		(fp_line
			(start -0.299974 0.150114)
			(end 0.299974 0.150114)
			(stroke
				(width 0.1)
				(type default)
			)
			(layer "B.Fab")
		)
		(fp_line
			(start 0.299974 0.150114)
			(end 0.299974 -0.150114)
			(stroke
				(width 0.1)
				(type default)
			)
			(layer "B.Fab")
		)
		(fp_line
			(start -0.299974 -0.150114)
			(end -0.299974 0.150114)
			(stroke
				(width 0.1)
				(type default)
			)
			(layer "B.Fab")
		)
		(fp_line
			(start 0.299974 -0.150114)
			(end -0.299974 -0.150114)
			(stroke
				(width 0.1)
				(type default)
			)
			(layer "B.Fab")
		)
		(pad "1" smd rect
			(at 0.2667 0 90)
			(size 0.3048 0.381)
			(layers "B.Cu" "B.Mask" "B.Paste")
			(net "P0V8_SERDES_VDDA_PEX1")
		)
		(pad "2" smd rect
			(at -0.2667 0 90)
			(size 0.3048 0.381)
			(layers "B.Cu" "B.Mask" "B.Paste")
			(net "GND")
		)
	)
	(footprint ""
		(layer "B.Cu")
		(at 293.301166 -305.399948 -90)
		(property "Reference" "C3322"
			(at 0 0 90)
			(layer "B.SilkS")
			(hide yes)
			(effects
				(font
					(size 1.27 1.27)
				)
				(justify mirror)
			)
		)
		(property "Value" ""
			(at 0 0 90)
			(layer "B.Fab")
			(effects
				(font
					(size 1.27 1.27)
				)
				(justify mirror)
			)
		)
		(duplicate_pad_numbers_are_jumpers no)
		(fp_line
			(start -0.299974 0.150114)
			(end 0.299974 0.150114)
			(stroke
				(width 0.1)
				(type default)
			)
			(layer "B.Fab")
		)
		(fp_line
			(start 0.299974 0.150114)
			(end 0.299974 -0.150114)
			(stroke
				(width 0.1)
				(type default)
			)
			(layer "B.Fab")
		)
		(fp_line
			(start -0.299974 -0.150114)
			(end -0.299974 0.150114)
			(stroke
				(width 0.1)
				(type default)
			)
			(layer "B.Fab")
		)
		(fp_line
			(start 0.299974 -0.150114)
			(end -0.299974 -0.150114)
			(stroke
				(width 0.1)
				(type default)
			)
			(layer "B.Fab")
		)
		(pad "1" smd rect
			(at 0.2667 0 90)
			(size 0.3048 0.381)
			(layers "B.Cu" "B.Mask" "B.Paste")
			(net "P1V25_SERDES_VDDPLL_PEX2")
		)
		(pad "2" smd rect
			(at -0.2667 0 90)
			(size 0.3048 0.381)
			(layers "B.Cu" "B.Mask" "B.Paste")
			(net "GND")
		)
	)
	(footprint ""
		(layer "B.Cu")
		(at 55.849774 -299.699934 -90)
		(property "Reference" "C1216"
			(at 0 0 90)
			(layer "B.SilkS")
			(hide yes)
			(effects
				(font
					(size 1.27 1.27)
				)
				(justify mirror)
			)
		)
		(property "Value" ""
			(at 0 0 90)
			(layer "B.Fab")
			(effects
				(font
					(size 1.27 1.27)
				)
				(justify mirror)
			)
		)
		(duplicate_pad_numbers_are_jumpers no)
		(fp_line
			(start -0.299974 0.150114)
			(end 0.299974 0.150114)
			(stroke
				(width 0.1)
				(type default)
			)
			(layer "B.Fab")
		)
		(fp_line
			(start 0.299974 0.150114)
			(end 0.299974 -0.150114)
			(stroke
				(width 0.1)
				(type default)
			)
			(layer "B.Fab")
		)
		(fp_line
			(start -0.299974 -0.150114)
			(end -0.299974 0.150114)
			(stroke
				(width 0.1)
				(type default)
			)
			(layer "B.Fab")
		)
		(fp_line
			(start 0.299974 -0.150114)
			(end -0.299974 -0.150114)
			(stroke
				(width 0.1)
				(type default)
			)
			(layer "B.Fab")
		)
		(pad "1" smd rect
			(at 0.2667 0 90)
			(size 0.3048 0.381)
			(layers "B.Cu" "B.Mask" "B.Paste")
			(net "P0V8_SERDES_VDDA_PEX0")
		)
		(pad "2" smd rect
			(at -0.2667 0 90)
			(size 0.3048 0.381)
			(layers "B.Cu" "B.Mask" "B.Paste")
			(net "GND")
		)
	)
	(footprint ""
		(layer "B.Cu")
		(at 224.501964 -208.78546 -90)
		(property "Reference" "R4898"
			(at 0 0 90)
			(layer "B.SilkS")
			(hide yes)
			(effects
				(font
					(size 1.27 1.27)
				)
				(justify mirror)
			)
		)
		(property "Value" ""
			(at 0 0 90)
			(layer "B.Fab")
			(effects
				(font
					(size 1.27 1.27)
				)
				(justify mirror)
			)
		)
		(duplicate_pad_numbers_are_jumpers no)
		(fp_line
			(start -0.7874 0.4064)
			(end 0.7874 0.4064)
			(stroke
				(width 0.1524)
				(type default)
			)
			(layer "B.SilkS")
		)
		(fp_line
			(start 0.7874 0.4064)
			(end 0.7874 -0.4064)
			(stroke
				(width 0.1524)
				(type default)
			)
			(layer "B.SilkS")
		)
		(fp_line
			(start -0.7874 -0.4064)
			(end -0.7874 0.4064)
			(stroke
				(width 0.1524)
				(type default)
			)
			(layer "B.SilkS")
		)
		(fp_line
			(start 0.7874 -0.4064)
			(end -0.7874 -0.4064)
			(stroke
				(width 0.1524)
				(type default)
			)
			(layer "B.SilkS")
		)
		(fp_line
			(start -0.67945 0.3048)
			(end -0.120396 0.3048)
			(stroke
				(width 0.1)
				(type default)
			)
			(layer "B.Fab")
		)
		(fp_line
			(start -0.120396 0.3048)
			(end -0.120396 0.2794)
			(stroke
				(width 0.1)
				(type default)
			)
			(layer "B.Fab")
		)
		(fp_line
			(start 0.12065 0.3048)
			(end 0.67945 0.3048)
			(stroke
				(width 0.1)
				(type default)
			)
			(layer "B.Fab")
		)
		(fp_line
			(start 0.67945 0.3048)
			(end 0.67945 -0.305054)
			(stroke
				(width 0.1)
				(type default)
			)
			(layer "B.Fab")
		)
		(fp_line
			(start -0.120396 0.2794)
			(end 0.12065 0.2794)
			(stroke
				(width 0.1)
				(type default)
			)
			(layer "B.Fab")
		)
		(fp_line
			(start 0.12065 0.2794)
			(end 0.12065 0.3048)
			(stroke
				(width 0.1)
				(type default)
			)
			(layer "B.Fab")
		)
		(fp_line
			(start -0.12065 -0.2794)
			(end -0.12065 -0.3048)
			(stroke
				(width 0.1)
				(type default)
			)
			(layer "B.Fab")
		)
		(fp_line
			(start 0.12065 -0.2794)
			(end -0.12065 -0.2794)
			(stroke
				(width 0.1)
				(type default)
			)
			(layer "B.Fab")
		)
		(fp_line
			(start -0.67945 -0.3048)
			(end -0.67945 0.3048)
			(stroke
				(width 0.1)
				(type default)
			)
			(layer "B.Fab")
		)
		(fp_line
			(start -0.12065 -0.3048)
			(end -0.67945 -0.3048)
			(stroke
				(width 0.1)
				(type default)
			)
			(layer "B.Fab")
		)
		(fp_line
			(start 0.12065 -0.305054)
			(end 0.12065 -0.2794)
			(stroke
				(width 0.1)
				(type default)
			)
			(layer "B.Fab")
		)
		(fp_line
			(start 0.67945 -0.305054)
			(end 0.12065 -0.305054)
			(stroke
				(width 0.1)
				(type default)
			)
			(layer "B.Fab")
		)
		(pad "1" smd circle
			(at 0.40005 0 90)
			(size 0 0)
			(layers "B.Cu" "B.Mask" "B.Paste")
			(net "JTAG_BIC_EN_R")
		)
		(pad "2" smd circle
			(at -0.40005 0 90)
			(size 0 0)
			(layers "B.Cu" "B.Mask" "B.Paste")
			(net "JTAG_BIC_EN")
		)
	)
	(footprint ""
		(layer "B.Cu")
		(at 46.355 -299.212)
		(property "Reference" "C3026"
			(at 0 0 0)
			(layer "B.SilkS")
			(hide yes)
			(effects
				(font
					(size 1.27 1.27)
				)
				(justify mirror)
			)
		)
		(property "Value" ""
			(at 0 0 0)
			(layer "B.Fab")
			(effects
				(font
					(size 1.27 1.27)
				)
				(justify mirror)
			)
		)
		(duplicate_pad_numbers_are_jumpers no)
		(fp_line
			(start -0.299974 -0.150114)
			(end -0.299974 0.150114)
			(stroke
				(width 0.1)
				(type default)
			)
			(layer "B.Fab")
		)
		(fp_line
			(start -0.299974 0.150114)
			(end 0.299974 0.150114)
			(stroke
				(width 0.1)
				(type default)
			)
			(layer "B.Fab")
		)
		(fp_line
			(start 0.299974 -0.150114)
			(end -0.299974 -0.150114)
			(stroke
				(width 0.1)
				(type default)
			)
			(layer "B.Fab")
		)
		(fp_line
			(start 0.299974 0.150114)
			(end 0.299974 -0.150114)
			(stroke
				(width 0.1)
				(type default)
			)
			(layer "B.Fab")
		)
		(pad "1" smd rect
			(at 0.2667 0 180)
			(size 0.3048 0.381)
			(layers "B.Cu" "B.Mask" "B.Paste")
			(net "PCEPLL1_VDDA18_PEX0")
		)
		(pad "2" smd rect
			(at -0.2667 0 180)
			(size 0.3048 0.381)
			(layers "B.Cu" "B.Mask" "B.Paste")
			(net "GND")
		)
	)
	(footprint ""
		(layer "B.Cu")
		(at 227.549964 -208.78546 -90)
		(property "Reference" "R4895"
			(at 0 0 90)
			(layer "B.SilkS")
			(hide yes)
			(effects
				(font
					(size 1.27 1.27)
				)
				(justify mirror)
			)
		)
		(property "Value" ""
			(at 0 0 90)
			(layer "B.Fab")
			(effects
				(font
					(size 1.27 1.27)
				)
				(justify mirror)
			)
		)
		(duplicate_pad_numbers_are_jumpers no)
		(fp_line
			(start -0.7874 0.4064)
			(end 0.7874 0.4064)
			(stroke
				(width 0.1524)
				(type default)
			)
			(layer "B.SilkS")
		)
		(fp_line
			(start 0.7874 0.4064)
			(end 0.7874 -0.4064)
			(stroke
				(width 0.1524)
				(type default)
			)
			(layer "B.SilkS")
		)
		(fp_line
			(start -0.7874 -0.4064)
			(end -0.7874 0.4064)
			(stroke
				(width 0.1524)
				(type default)
			)
			(layer "B.SilkS")
		)
		(fp_line
			(start 0.7874 -0.4064)
			(end -0.7874 -0.4064)
			(stroke
				(width 0.1524)
				(type default)
			)
			(layer "B.SilkS")
		)
		(fp_line
			(start -0.67945 0.3048)
			(end -0.120396 0.3048)
			(stroke
				(width 0.1)
				(type default)
			)
			(layer "B.Fab")
		)
		(fp_line
			(start -0.120396 0.3048)
			(end -0.120396 0.2794)
			(stroke
				(width 0.1)
				(type default)
			)
			(layer "B.Fab")
		)
		(fp_line
			(start 0.12065 0.3048)
			(end 0.67945 0.3048)
			(stroke
				(width 0.1)
				(type default)
			)
			(layer "B.Fab")
		)
		(fp_line
			(start 0.67945 0.3048)
			(end 0.67945 -0.305054)
			(stroke
				(width 0.1)
				(type default)
			)
			(layer "B.Fab")
		)
		(fp_line
			(start -0.120396 0.2794)
			(end 0.12065 0.2794)
			(stroke
				(width 0.1)
				(type default)
			)
			(layer "B.Fab")
		)
		(fp_line
			(start 0.12065 0.2794)
			(end 0.12065 0.3048)
			(stroke
				(width 0.1)
				(type default)
			)
			(layer "B.Fab")
		)
		(fp_line
			(start -0.12065 -0.2794)
			(end -0.12065 -0.3048)
			(stroke
				(width 0.1)
				(type default)
			)
			(layer "B.Fab")
		)
		(fp_line
			(start 0.12065 -0.2794)
			(end -0.12065 -0.2794)
			(stroke
				(width 0.1)
				(type default)
			)
			(layer "B.Fab")
		)
		(fp_line
			(start -0.67945 -0.3048)
			(end -0.67945 0.3048)
			(stroke
				(width 0.1)
				(type default)
			)
			(layer "B.Fab")
		)
		(fp_line
			(start -0.12065 -0.3048)
			(end -0.67945 -0.3048)
			(stroke
				(width 0.1)
				(type default)
			)
			(layer "B.Fab")
		)
		(fp_line
			(start 0.12065 -0.305054)
			(end 0.12065 -0.2794)
			(stroke
				(width 0.1)
				(type default)
			)
			(layer "B.Fab")
		)
		(fp_line
			(start 0.67945 -0.305054)
			(end 0.12065 -0.305054)
			(stroke
				(width 0.1)
				(type default)
			)
			(layer "B.Fab")
		)
		(pad "1" smd circle
			(at 0.40005 0 90)
			(size 0 0)
			(layers "B.Cu" "B.Mask" "B.Paste")
			(net "JTAG_BIC_TCK_R")
		)
		(pad "2" smd circle
			(at -0.40005 0 90)
			(size 0 0)
			(layers "B.Cu" "B.Mask" "B.Paste")
			(net "JTAG_BIC_TCK")
		)
	)
	(footprint ""
		(layer "B.Cu")
		(at 350.598994 -324.936358 -90)
		(property "Reference" "C4367"
			(at 0 0 90)
			(layer "B.SilkS")
			(hide yes)
			(effects
				(font
					(size 1.27 1.27)
				)
				(justify mirror)
			)
		)
		(property "Value" ""
			(at 0 0 90)
			(layer "B.Fab")
			(effects
				(font
					(size 1.27 1.27)
				)
				(justify mirror)
			)
		)
		(duplicate_pad_numbers_are_jumpers no)
		(fp_line
			(start -1.2954 0.5842)
			(end 1.2954 0.5842)
			(stroke
				(width 0.1524)
				(type default)
			)
			(layer "B.SilkS")
		)
		(fp_line
			(start 1.2954 0.5842)
			(end 1.2954 -0.5842)
			(stroke
				(width 0.1524)
				(type default)
			)
			(layer "B.SilkS")
		)
		(fp_line
			(start -1.2954 -0.5842)
			(end -1.2954 0.5842)
			(stroke
				(width 0.1524)
				(type default)
			)
			(layer "B.SilkS")
		)
		(fp_line
			(start 1.2954 -0.5842)
			(end -1.2954 -0.5842)
			(stroke
				(width 0.1524)
				(type default)
			)
			(layer "B.SilkS")
		)
		(fp_line
			(start -0.8636 0.4572)
			(end 0.8636 0.4572)
			(stroke
				(width 0.1)
				(type default)
			)
			(layer "B.Fab")
		)
		(fp_line
			(start 0.8636 0.4572)
			(end 0.8636 0.4064)
			(stroke
				(width 0.1)
				(type default)
			)
			(layer "B.Fab")
		)
		(fp_line
			(start -1.1938 0.4064)
			(end -0.8636 0.4064)
			(stroke
				(width 0.1)
				(type default)
			)
			(layer "B.Fab")
		)
		(fp_line
			(start -0.8636 0.4064)
			(end -0.8636 0.4572)
			(stroke
				(width 0.1)
				(type default)
			)
			(layer "B.Fab")
		)
		(fp_line
			(start 0.8636 0.4064)
			(end 1.1938 0.4064)
			(stroke
				(width 0.1)
				(type default)
			)
			(layer "B.Fab")
		)
		(fp_line
			(start 1.1938 0.4064)
			(end 1.1938 -0.4064)
			(stroke
				(width 0.1)
				(type default)
			)
			(layer "B.Fab")
		)
		(fp_line
			(start -1.1938 -0.4064)
			(end -1.1938 0.4064)
			(stroke
				(width 0.1)
				(type default)
			)
			(layer "B.Fab")
		)
		(fp_line
			(start -0.8636 -0.4064)
			(end -1.1938 -0.4064)
			(stroke
				(width 0.1)
				(type default)
			)
			(layer "B.Fab")
		)
		(fp_line
			(start 0.8636 -0.4064)
			(end 0.8636 -0.4572)
			(stroke
				(width 0.1)
				(type default)
			)
			(layer "B.Fab")
		)
		(fp_line
			(start 1.1938 -0.4064)
			(end 0.8636 -0.4064)
			(stroke
				(width 0.1)
				(type default)
			)
			(layer "B.Fab")
		)
		(fp_line
			(start -0.8636 -0.4572)
			(end -0.8636 -0.4064)
			(stroke
				(width 0.1)
				(type default)
			)
			(layer "B.Fab")
		)
		(fp_line
			(start 0.8636 -0.4572)
			(end -0.8636 -0.4572)
			(stroke
				(width 0.1)
				(type default)
			)
			(layer "B.Fab")
		)
		(pad "1" smd rect
			(at 0.7366 0 180)
			(size 0.7112 0.8128)
			(layers "B.Cu" "B.Mask" "B.Paste")
			(net "P0V8_SERDES_VDDA_PEX3_C1")
		)
		(pad "2" smd rect
			(at -0.7366 0 180)
			(size 0.7112 0.8128)
			(layers "B.Cu" "B.Mask" "B.Paste")
			(net "GND")
		)
	)
	(footprint ""
		(layer "B.Cu")
		(at 102.655878 -390.013444 -90)
		(property "Reference" "C3633"
			(at 0 0 90)
			(layer "B.SilkS")
			(hide yes)
			(effects
				(font
					(size 1.27 1.27)
				)
				(justify mirror)
			)
		)
		(property "Value" ""
			(at 0 0 90)
			(layer "B.Fab")
			(effects
				(font
					(size 1.27 1.27)
				)
				(justify mirror)
			)
		)
		(duplicate_pad_numbers_are_jumpers no)
		(fp_line
			(start -0.7874 0.4064)
			(end 0.7874 0.4064)
			(stroke
				(width 0.1524)
				(type default)
			)
			(layer "B.SilkS")
		)
		(fp_line
			(start 0.7874 0.4064)
			(end 0.7874 -0.4064)
			(stroke
				(width 0.1524)
				(type default)
			)
			(layer "B.SilkS")
		)
		(fp_line
			(start -0.7874 -0.4064)
			(end -0.7874 0.4064)
			(stroke
				(width 0.1524)
				(type default)
			)
			(layer "B.SilkS")
		)
		(fp_line
			(start 0.7874 -0.4064)
			(end -0.7874 -0.4064)
			(stroke
				(width 0.1524)
				(type default)
			)
			(layer "B.SilkS")
		)
		(fp_line
			(start -0.67945 0.3048)
			(end -0.120396 0.3048)
			(stroke
				(width 0.1)
				(type default)
			)
			(layer "B.Fab")
		)
		(fp_line
			(start -0.120396 0.3048)
			(end -0.120396 0.2794)
			(stroke
				(width 0.1)
				(type default)
			)
			(layer "B.Fab")
		)
		(fp_line
			(start 0.12065 0.3048)
			(end 0.67945 0.3048)
			(stroke
				(width 0.1)
				(type default)
			)
			(layer "B.Fab")
		)
		(fp_line
			(start 0.67945 0.3048)
			(end 0.67945 -0.305054)
			(stroke
				(width 0.1)
				(type default)
			)
			(layer "B.Fab")
		)
		(fp_line
			(start -0.120396 0.2794)
			(end 0.12065 0.2794)
			(stroke
				(width 0.1)
				(type default)
			)
			(layer "B.Fab")
		)
		(fp_line
			(start 0.12065 0.2794)
			(end 0.12065 0.3048)
			(stroke
				(width 0.1)
				(type default)
			)
			(layer "B.Fab")
		)
		(fp_line
			(start -0.12065 -0.2794)
			(end -0.12065 -0.3048)
			(stroke
				(width 0.1)
				(type default)
			)
			(layer "B.Fab")
		)
		(fp_line
			(start 0.12065 -0.2794)
			(end -0.12065 -0.2794)
			(stroke
				(width 0.1)
				(type default)
			)
			(layer "B.Fab")
		)
		(fp_line
			(start -0.67945 -0.3048)
			(end -0.67945 0.3048)
			(stroke
				(width 0.1)
				(type default)
			)
			(layer "B.Fab")
		)
		(fp_line
			(start -0.12065 -0.3048)
			(end -0.67945 -0.3048)
			(stroke
				(width 0.1)
				(type default)
			)
			(layer "B.Fab")
		)
		(fp_line
			(start 0.12065 -0.305054)
			(end 0.12065 -0.2794)
			(stroke
				(width 0.1)
				(type default)
			)
			(layer "B.Fab")
		)
		(fp_line
			(start 0.67945 -0.305054)
			(end 0.12065 -0.305054)
			(stroke
				(width 0.1)
				(type default)
			)
			(layer "B.Fab")
		)
		(pad "1" smd circle
			(at 0.40005 0 90)
			(size 0 0)
			(layers "B.Cu" "B.Mask" "B.Paste")
			(net "P3V3_BIC_USB_HUB")
		)
		(pad "2" smd circle
			(at -0.40005 0 90)
			(size 0 0)
			(layers "B.Cu" "B.Mask" "B.Paste")
			(net "GND")
		)
	)
	(footprint ""
		(layer "B.Cu")
		(at 67.249802 -299.699934 -90)
		(property "Reference" "C1170"
			(at 0 0 90)
			(layer "B.SilkS")
			(hide yes)
			(effects
				(font
					(size 1.27 1.27)
				)
				(justify mirror)
			)
		)
		(property "Value" ""
			(at 0 0 90)
			(layer "B.Fab")
			(effects
				(font
					(size 1.27 1.27)
				)
				(justify mirror)
			)
		)
		(duplicate_pad_numbers_are_jumpers no)
		(fp_line
			(start -0.299974 0.150114)
			(end 0.299974 0.150114)
			(stroke
				(width 0.1)
				(type default)
			)
			(layer "B.Fab")
		)
		(fp_line
			(start 0.299974 0.150114)
			(end 0.299974 -0.150114)
			(stroke
				(width 0.1)
				(type default)
			)
			(layer "B.Fab")
		)
		(fp_line
			(start -0.299974 -0.150114)
			(end -0.299974 0.150114)
			(stroke
				(width 0.1)
				(type default)
			)
			(layer "B.Fab")
		)
		(fp_line
			(start 0.299974 -0.150114)
			(end -0.299974 -0.150114)
			(stroke
				(width 0.1)
				(type default)
			)
			(layer "B.Fab")
		)
		(pad "1" smd rect
			(at 0.2667 0 90)
			(size 0.3048 0.381)
			(layers "B.Cu" "B.Mask" "B.Paste")
			(net "P0V8_SERDES_VDDA_PEX0")
		)
		(pad "2" smd rect
			(at -0.2667 0 90)
			(size 0.3048 0.381)
			(layers "B.Cu" "B.Mask" "B.Paste")
			(net "GND")
		)
	)
	(footprint ""
		(layer "B.Cu")
		(at 292.79977 -299.699934 -90)
		(property "Reference" "C1713"
			(at 0 0 90)
			(layer "B.SilkS")
			(hide yes)
			(effects
				(font
					(size 1.27 1.27)
				)
				(justify mirror)
			)
		)
		(property "Value" ""
			(at 0 0 90)
			(layer "B.Fab")
			(effects
				(font
					(size 1.27 1.27)
				)
				(justify mirror)
			)
		)
		(duplicate_pad_numbers_are_jumpers no)
		(fp_line
			(start -0.299974 0.150114)
			(end 0.299974 0.150114)
			(stroke
				(width 0.1)
				(type default)
			)
			(layer "B.Fab")
		)
		(fp_line
			(start 0.299974 0.150114)
			(end 0.299974 -0.150114)
			(stroke
				(width 0.1)
				(type default)
			)
			(layer "B.Fab")
		)
		(fp_line
			(start -0.299974 -0.150114)
			(end -0.299974 0.150114)
			(stroke
				(width 0.1)
				(type default)
			)
			(layer "B.Fab")
		)
		(fp_line
			(start 0.299974 -0.150114)
			(end -0.299974 -0.150114)
			(stroke
				(width 0.1)
				(type default)
			)
			(layer "B.Fab")
		)
		(pad "1" smd rect
			(at 0.2667 0 90)
			(size 0.3048 0.381)
			(layers "B.Cu" "B.Mask" "B.Paste")
			(net "P0V8_SERDES_VDDA_PEX2")
		)
		(pad "2" smd rect
			(at -0.2667 0 90)
			(size 0.3048 0.381)
			(layers "B.Cu" "B.Mask" "B.Paste")
			(net "GND")
		)
	)
	(footprint ""
		(layer "B.Cu")
		(at 112.85728 -313.620404 180)
		(property "Reference" "R5784"
			(at 0 0 0)
			(layer "B.SilkS")
			(hide yes)
			(effects
				(font
					(size 1.27 1.27)
				)
				(justify mirror)
			)
		)
		(property "Value" ""
			(at 0 0 0)
			(layer "B.Fab")
			(effects
				(font
					(size 1.27 1.27)
				)
				(justify mirror)
			)
		)
		(duplicate_pad_numbers_are_jumpers no)
		(fp_line
			(start 2.576322 1.1303)
			(end 2.576322 -1.1303)
			(stroke
				(width 0.1524)
				(type default)
			)
			(layer "B.SilkS")
		)
		(fp_line
			(start 2.576322 -1.1303)
			(end -2.576322 -1.1303)
			(stroke
				(width 0.1524)
				(type default)
			)
			(layer "B.SilkS")
		)
		(fp_line
			(start -2.576322 1.1303)
			(end 2.576322 1.1303)
			(stroke
				(width 0.1524)
				(type default)
			)
			(layer "B.SilkS")
		)
		(fp_line
			(start -2.576322 -1.1303)
			(end -2.576322 1.1303)
			(stroke
				(width 0.1524)
				(type default)
			)
			(layer "B.SilkS")
		)
		(fp_line
			(start 1.649984 0.899922)
			(end -1.649984 0.899922)
			(stroke
				(width 0.1)
				(type default)
			)
			(layer "B.Fab")
		)
		(fp_line
			(start 1.649984 -0.899922)
			(end 1.649984 0.899922)
			(stroke
				(width 0.1)
				(type default)
			)
			(layer "B.Fab")
		)
		(fp_line
			(start -1.649984 0.899922)
			(end -1.649984 -0.899922)
			(stroke
				(width 0.1)
				(type default)
			)
			(layer "B.Fab")
		)
		(fp_line
			(start -1.649984 -0.899922)
			(end 1.649984 -0.899922)
			(stroke
				(width 0.1)
				(type default)
			)
			(layer "B.Fab")
		)
		(pad "1A" smd rect
			(at 1.700022 0)
			(size 1.4986 2.0066)
			(layers "B.Cu" "B.Mask" "B.Paste")
			(net "P0V8_PEX0")
		)
		(pad "1B" smd rect
			(at 1.077722 0)
			(size 0.254 0.508)
			(layers "B.Cu" "B.Mask" "B.Paste")
			(net "P0V8_PEX0")
		)
		(pad "2A" smd rect
			(at -1.700022 0)
			(size 1.4986 2.0066)
			(layers "B.Cu" "B.Mask" "B.Paste")
			(net "P0V8_SERDES_VDDA_PEX0")
		)
		(pad "2B" smd rect
			(at -1.077722 0)
			(size 0.254 0.508)
			(layers "B.Cu" "B.Mask" "B.Paste")
			(net "P0V8_SERDES_VDDA_PEX0")
		)
	)
	(footprint ""
		(layer "B.Cu")
		(at 275.163788 -285.853632)
		(property "Reference" "C3338"
			(at 0 0 0)
			(layer "B.SilkS")
			(hide yes)
			(effects
				(font
					(size 1.27 1.27)
				)
				(justify mirror)
			)
		)
		(property "Value" ""
			(at 0 0 0)
			(layer "B.Fab")
			(effects
				(font
					(size 1.27 1.27)
				)
				(justify mirror)
			)
		)
		(duplicate_pad_numbers_are_jumpers no)
		(fp_line
			(start -1.2954 -0.5842)
			(end -1.2954 0.5842)
			(stroke
				(width 0.1524)
				(type default)
			)
			(layer "B.SilkS")
		)
		(fp_line
			(start -1.2954 0.5842)
			(end 1.2954 0.5842)
			(stroke
				(width 0.1524)
				(type default)
			)
			(layer "B.SilkS")
		)
		(fp_line
			(start 1.2954 -0.5842)
			(end -1.2954 -0.5842)
			(stroke
				(width 0.1524)
				(type default)
			)
			(layer "B.SilkS")
		)
		(fp_line
			(start 1.2954 0.5842)
			(end 1.2954 -0.5842)
			(stroke
				(width 0.1524)
				(type default)
			)
			(layer "B.SilkS")
		)
		(fp_line
			(start -1.1938 -0.4064)
			(end -1.1938 0.4064)
			(stroke
				(width 0.1)
				(type default)
			)
			(layer "B.Fab")
		)
		(fp_line
			(start -1.1938 0.4064)
			(end -0.8636 0.4064)
			(stroke
				(width 0.1)
				(type default)
			)
			(layer "B.Fab")
		)
		(fp_line
			(start -0.8636 -0.4572)
			(end -0.8636 -0.4064)
			(stroke
				(width 0.1)
				(type default)
			)
			(layer "B.Fab")
		)
		(fp_line
			(start -0.8636 -0.4064)
			(end -1.1938 -0.4064)
			(stroke
				(width 0.1)
				(type default)
			)
			(layer "B.Fab")
		)
		(fp_line
			(start -0.8636 0.4064)
			(end -0.8636 0.4572)
			(stroke
				(width 0.1)
				(type default)
			)
			(layer "B.Fab")
		)
		(fp_line
			(start -0.8636 0.4572)
			(end 0.8636 0.4572)
			(stroke
				(width 0.1)
				(type default)
			)
			(layer "B.Fab")
		)
		(fp_line
			(start 0.8636 -0.4572)
			(end -0.8636 -0.4572)
			(stroke
				(width 0.1)
				(type default)
			)
			(layer "B.Fab")
		)
		(fp_line
			(start 0.8636 -0.4064)
			(end 0.8636 -0.4572)
			(stroke
				(width 0.1)
				(type default)
			)
			(layer "B.Fab")
		)
		(fp_line
			(start 0.8636 0.4064)
			(end 1.1938 0.4064)
			(stroke
				(width 0.1)
				(type default)
			)
			(layer "B.Fab")
		)
		(fp_line
			(start 0.8636 0.4572)
			(end 0.8636 0.4064)
			(stroke
				(width 0.1)
				(type default)
			)
			(layer "B.Fab")
		)
		(fp_line
			(start 1.1938 -0.4064)
			(end 0.8636 -0.4064)
			(stroke
				(width 0.1)
				(type default)
			)
			(layer "B.Fab")
		)
		(fp_line
			(start 1.1938 0.4064)
			(end 1.1938 -0.4064)
			(stroke
				(width 0.1)
				(type default)
			)
			(layer "B.Fab")
		)
		(pad "1" smd rect
			(at 0.7366 0 270)
			(size 0.7112 0.8128)
			(layers "B.Cu" "B.Mask" "B.Paste")
			(net "P1V8_PEX")
		)
		(pad "2" smd rect
			(at -0.7366 0 270)
			(size 0.7112 0.8128)
			(layers "B.Cu" "B.Mask" "B.Paste")
			(net "GND")
		)
	)
	(footprint ""
		(layer "B.Cu")
		(at 233.498644 -231.225598 -90)
		(property "Reference" "R4516"
			(at 0 0 90)
			(layer "B.SilkS")
			(hide yes)
			(effects
				(font
					(size 1.27 1.27)
				)
				(justify mirror)
			)
		)
		(property "Value" ""
			(at 0 0 90)
			(layer "B.Fab")
			(effects
				(font
					(size 1.27 1.27)
				)
				(justify mirror)
			)
		)
		(duplicate_pad_numbers_are_jumpers no)
		(fp_line
			(start -0.7874 0.4064)
			(end 0.7874 0.4064)
			(stroke
				(width 0.1524)
				(type default)
			)
			(layer "B.SilkS")
		)
		(fp_line
			(start 0.7874 0.4064)
			(end 0.7874 -0.4064)
			(stroke
				(width 0.1524)
				(type default)
			)
			(layer "B.SilkS")
		)
		(fp_line
			(start -0.7874 -0.4064)
			(end -0.7874 0.4064)
			(stroke
				(width 0.1524)
				(type default)
			)
			(layer "B.SilkS")
		)
		(fp_line
			(start 0.7874 -0.4064)
			(end -0.7874 -0.4064)
			(stroke
				(width 0.1524)
				(type default)
			)
			(layer "B.SilkS")
		)
		(fp_line
			(start -0.67945 0.3048)
			(end -0.120396 0.3048)
			(stroke
				(width 0.1)
				(type default)
			)
			(layer "B.Fab")
		)
		(fp_line
			(start -0.120396 0.3048)
			(end -0.120396 0.2794)
			(stroke
				(width 0.1)
				(type default)
			)
			(layer "B.Fab")
		)
		(fp_line
			(start 0.12065 0.3048)
			(end 0.67945 0.3048)
			(stroke
				(width 0.1)
				(type default)
			)
			(layer "B.Fab")
		)
		(fp_line
			(start 0.67945 0.3048)
			(end 0.67945 -0.305054)
			(stroke
				(width 0.1)
				(type default)
			)
			(layer "B.Fab")
		)
		(fp_line
			(start -0.120396 0.2794)
			(end 0.12065 0.2794)
			(stroke
				(width 0.1)
				(type default)
			)
			(layer "B.Fab")
		)
		(fp_line
			(start 0.12065 0.2794)
			(end 0.12065 0.3048)
			(stroke
				(width 0.1)
				(type default)
			)
			(layer "B.Fab")
		)
		(fp_line
			(start -0.12065 -0.2794)
			(end -0.12065 -0.3048)
			(stroke
				(width 0.1)
				(type default)
			)
			(layer "B.Fab")
		)
		(fp_line
			(start 0.12065 -0.2794)
			(end -0.12065 -0.2794)
			(stroke
				(width 0.1)
				(type default)
			)
			(layer "B.Fab")
		)
		(fp_line
			(start -0.67945 -0.3048)
			(end -0.67945 0.3048)
			(stroke
				(width 0.1)
				(type default)
			)
			(layer "B.Fab")
		)
		(fp_line
			(start -0.12065 -0.3048)
			(end -0.67945 -0.3048)
			(stroke
				(width 0.1)
				(type default)
			)
			(layer "B.Fab")
		)
		(fp_line
			(start 0.12065 -0.305054)
			(end 0.12065 -0.2794)
			(stroke
				(width 0.1)
				(type default)
			)
			(layer "B.Fab")
		)
		(fp_line
			(start 0.67945 -0.305054)
			(end 0.12065 -0.305054)
			(stroke
				(width 0.1)
				(type default)
			)
			(layer "B.Fab")
		)
		(pad "1" smd circle
			(at 0.40005 0 90)
			(size 0 0)
			(layers "B.Cu" "B.Mask" "B.Paste")
			(net "SSD2_PWRDIS_BIC")
		)
		(pad "2" smd circle
			(at -0.40005 0 90)
			(size 0 0)
			(layers "B.Cu" "B.Mask" "B.Paste")
			(net "SSD2_PWRDIS_BIC_R")
		)
	)
	(footprint ""
		(layer "B.Cu")
		(at 306.226718 -301.124874 -90)
		(property "Reference" "R1380"
			(at 0 0 90)
			(layer "B.SilkS")
			(hide yes)
			(effects
				(font
					(size 1.27 1.27)
				)
				(justify mirror)
			)
		)
		(property "Value" ""
			(at 0 0 90)
			(layer "B.Fab")
			(effects
				(font
					(size 1.27 1.27)
				)
				(justify mirror)
			)
		)
		(duplicate_pad_numbers_are_jumpers no)
		(fp_line
			(start -0.7874 0.4064)
			(end 0.7874 0.4064)
			(stroke
				(width 0.1524)
				(type default)
			)
			(layer "B.SilkS")
		)
		(fp_line
			(start 0.7874 0.4064)
			(end 0.7874 -0.4064)
			(stroke
				(width 0.1524)
				(type default)
			)
			(layer "B.SilkS")
		)
		(fp_line
			(start -0.7874 -0.4064)
			(end -0.7874 0.4064)
			(stroke
				(width 0.1524)
				(type default)
			)
			(layer "B.SilkS")
		)
		(fp_line
			(start 0.7874 -0.4064)
			(end -0.7874 -0.4064)
			(stroke
				(width 0.1524)
				(type default)
			)
			(layer "B.SilkS")
		)
		(fp_line
			(start -0.67945 0.3048)
			(end -0.120396 0.3048)
			(stroke
				(width 0.1)
				(type default)
			)
			(layer "B.Fab")
		)
		(fp_line
			(start -0.120396 0.3048)
			(end -0.120396 0.2794)
			(stroke
				(width 0.1)
				(type default)
			)
			(layer "B.Fab")
		)
		(fp_line
			(start 0.12065 0.3048)
			(end 0.67945 0.3048)
			(stroke
				(width 0.1)
				(type default)
			)
			(layer "B.Fab")
		)
		(fp_line
			(start 0.67945 0.3048)
			(end 0.67945 -0.305054)
			(stroke
				(width 0.1)
				(type default)
			)
			(layer "B.Fab")
		)
		(fp_line
			(start -0.120396 0.2794)
			(end 0.12065 0.2794)
			(stroke
				(width 0.1)
				(type default)
			)
			(layer "B.Fab")
		)
		(fp_line
			(start 0.12065 0.2794)
			(end 0.12065 0.3048)
			(stroke
				(width 0.1)
				(type default)
			)
			(layer "B.Fab")
		)
		(fp_line
			(start -0.12065 -0.2794)
			(end -0.12065 -0.3048)
			(stroke
				(width 0.1)
				(type default)
			)
			(layer "B.Fab")
		)
		(fp_line
			(start 0.12065 -0.2794)
			(end -0.12065 -0.2794)
			(stroke
				(width 0.1)
				(type default)
			)
			(layer "B.Fab")
		)
		(fp_line
			(start -0.67945 -0.3048)
			(end -0.67945 0.3048)
			(stroke
				(width 0.1)
				(type default)
			)
			(layer "B.Fab")
		)
		(fp_line
			(start -0.12065 -0.3048)
			(end -0.67945 -0.3048)
			(stroke
				(width 0.1)
				(type default)
			)
			(layer "B.Fab")
		)
		(fp_line
			(start 0.12065 -0.305054)
			(end 0.12065 -0.2794)
			(stroke
				(width 0.1)
				(type default)
			)
			(layer "B.Fab")
		)
		(fp_line
			(start 0.67945 -0.305054)
			(end 0.12065 -0.305054)
			(stroke
				(width 0.1)
				(type default)
			)
			(layer "B.Fab")
		)
		(pad "1" smd circle
			(at 0.40005 0 90)
			(size 0 0)
			(layers "B.Cu" "B.Mask" "B.Paste")
			(net "PEX2_ADCTEMP_VINP0")
		)
		(pad "2" smd circle
			(at -0.40005 0 90)
			(size 0 0)
			(layers "B.Cu" "B.Mask" "B.Paste")
			(net "GND")
		)
	)
	(footprint ""
		(layer "B.Cu")
		(at 286.149796 -290.199826 90)
		(property "Reference" "C1730"
			(at 0 0 90)
			(layer "B.SilkS")
			(hide yes)
			(effects
				(font
					(size 1.27 1.27)
				)
				(justify mirror)
			)
		)
		(property "Value" ""
			(at 0 0 90)
			(layer "B.Fab")
			(effects
				(font
					(size 1.27 1.27)
				)
				(justify mirror)
			)
		)
		(duplicate_pad_numbers_are_jumpers no)
		(fp_line
			(start 0.299974 -0.150114)
			(end -0.299974 -0.150114)
			(stroke
				(width 0.1)
				(type default)
			)
			(layer "B.Fab")
		)
		(fp_line
			(start -0.299974 -0.150114)
			(end -0.299974 0.150114)
			(stroke
				(width 0.1)
				(type default)
			)
			(layer "B.Fab")
		)
		(fp_line
			(start 0.299974 0.150114)
			(end 0.299974 -0.150114)
			(stroke
				(width 0.1)
				(type default)
			)
			(layer "B.Fab")
		)
		(fp_line
			(start -0.299974 0.150114)
			(end 0.299974 0.150114)
			(stroke
				(width 0.1)
				(type default)
			)
			(layer "B.Fab")
		)
		(pad "1" smd rect
			(at 0.2667 0 270)
			(size 0.3048 0.381)
			(layers "B.Cu" "B.Mask" "B.Paste")
			(net "P0V8_SERDES_VDDA_PEX2")
		)
		(pad "2" smd rect
			(at -0.2667 0 270)
			(size 0.3048 0.381)
			(layers "B.Cu" "B.Mask" "B.Paste")
			(net "GND")
		)
	)
	(footprint ""
		(layer "B.Cu")
		(at 322.360798 -83.123278 180)
		(property "Reference" "R1780"
			(at 0 0 0)
			(layer "B.SilkS")
			(hide yes)
			(effects
				(font
					(size 1.27 1.27)
				)
				(justify mirror)
			)
		)
		(property "Value" ""
			(at 0 0 0)
			(layer "B.Fab")
			(effects
				(font
					(size 1.27 1.27)
				)
				(justify mirror)
			)
		)
		(duplicate_pad_numbers_are_jumpers no)
		(fp_line
			(start 0.7874 0.4064)
			(end 0.7874 -0.4064)
			(stroke
				(width 0.1524)
				(type default)
			)
			(layer "B.SilkS")
		)
		(fp_line
			(start 0.7874 -0.4064)
			(end -0.7874 -0.4064)
			(stroke
				(width 0.1524)
				(type default)
			)
			(layer "B.SilkS")
		)
		(fp_line
			(start -0.7874 0.4064)
			(end 0.7874 0.4064)
			(stroke
				(width 0.1524)
				(type default)
			)
			(layer "B.SilkS")
		)
		(fp_line
			(start -0.7874 -0.4064)
			(end -0.7874 0.4064)
			(stroke
				(width 0.1524)
				(type default)
			)
			(layer "B.SilkS")
		)
		(fp_line
			(start 0.67945 0.3048)
			(end 0.67945 -0.305054)
			(stroke
				(width 0.1)
				(type default)
			)
			(layer "B.Fab")
		)
		(fp_line
			(start 0.67945 -0.305054)
			(end 0.12065 -0.305054)
			(stroke
				(width 0.1)
				(type default)
			)
			(layer "B.Fab")
		)
		(fp_line
			(start 0.12065 0.3048)
			(end 0.67945 0.3048)
			(stroke
				(width 0.1)
				(type default)
			)
			(layer "B.Fab")
		)
		(fp_line
			(start 0.12065 0.2794)
			(end 0.12065 0.3048)
			(stroke
				(width 0.1)
				(type default)
			)
			(layer "B.Fab")
		)
		(fp_line
			(start 0.12065 -0.2794)
			(end -0.12065 -0.2794)
			(stroke
				(width 0.1)
				(type default)
			)
			(layer "B.Fab")
		)
		(fp_line
			(start 0.12065 -0.305054)
			(end 0.12065 -0.2794)
			(stroke
				(width 0.1)
				(type default)
			)
			(layer "B.Fab")
		)
		(fp_line
			(start -0.120396 0.3048)
			(end -0.120396 0.2794)
			(stroke
				(width 0.1)
				(type default)
			)
			(layer "B.Fab")
		)
		(fp_line
			(start -0.120396 0.2794)
			(end 0.12065 0.2794)
			(stroke
				(width 0.1)
				(type default)
			)
			(layer "B.Fab")
		)
		(fp_line
			(start -0.12065 -0.2794)
			(end -0.12065 -0.3048)
			(stroke
				(width 0.1)
				(type default)
			)
			(layer "B.Fab")
		)
		(fp_line
			(start -0.12065 -0.3048)
			(end -0.67945 -0.3048)
			(stroke
				(width 0.1)
				(type default)
			)
			(layer "B.Fab")
		)
		(fp_line
			(start -0.67945 0.3048)
			(end -0.120396 0.3048)
			(stroke
				(width 0.1)
				(type default)
			)
			(layer "B.Fab")
		)
		(fp_line
			(start -0.67945 -0.3048)
			(end -0.67945 0.3048)
			(stroke
				(width 0.1)
				(type default)
			)
			(layer "B.Fab")
		)
		(pad "1" smd circle
			(at 0.40005 0)
			(size 0 0)
			(layers "B.Cu" "B.Mask" "B.Paste")
			(net "SMB_BIC_I2C6_MUX_FRU_R_SCL")
		)
		(pad "2" smd circle
			(at -0.40005 0)
			(size 0 0)
			(layers "B.Cu" "B.Mask" "B.Paste")
			(net "SMB_BIC_I2C6_MUX_FRU_SCL")
		)
	)
	(footprint ""
		(layer "B.Cu")
		(at 426.801788 -295.422066 180)
		(property "Reference" "C3424"
			(at 0 0 0)
			(layer "B.SilkS")
			(hide yes)
			(effects
				(font
					(size 1.27 1.27)
				)
				(justify mirror)
			)
		)
		(property "Value" ""
			(at 0 0 0)
			(layer "B.Fab")
			(effects
				(font
					(size 1.27 1.27)
				)
				(justify mirror)
			)
		)
		(duplicate_pad_numbers_are_jumpers no)
		(fp_line
			(start 1.2954 0.5842)
			(end 1.2954 -0.5842)
			(stroke
				(width 0.1524)
				(type default)
			)
			(layer "B.SilkS")
		)
		(fp_line
			(start 1.2954 -0.5842)
			(end -1.2954 -0.5842)
			(stroke
				(width 0.1524)
				(type default)
			)
			(layer "B.SilkS")
		)
		(fp_line
			(start -1.2954 0.5842)
			(end 1.2954 0.5842)
			(stroke
				(width 0.1524)
				(type default)
			)
			(layer "B.SilkS")
		)
		(fp_line
			(start -1.2954 -0.5842)
			(end -1.2954 0.5842)
			(stroke
				(width 0.1524)
				(type default)
			)
			(layer "B.SilkS")
		)
		(fp_line
			(start 1.1938 0.4064)
			(end 1.1938 -0.4064)
			(stroke
				(width 0.1)
				(type default)
			)
			(layer "B.Fab")
		)
		(fp_line
			(start 1.1938 -0.4064)
			(end 0.8636 -0.4064)
			(stroke
				(width 0.1)
				(type default)
			)
			(layer "B.Fab")
		)
		(fp_line
			(start 0.8636 0.4572)
			(end 0.8636 0.4064)
			(stroke
				(width 0.1)
				(type default)
			)
			(layer "B.Fab")
		)
		(fp_line
			(start 0.8636 0.4064)
			(end 1.1938 0.4064)
			(stroke
				(width 0.1)
				(type default)
			)
			(layer "B.Fab")
		)
		(fp_line
			(start 0.8636 -0.4064)
			(end 0.8636 -0.4572)
			(stroke
				(width 0.1)
				(type default)
			)
			(layer "B.Fab")
		)
		(fp_line
			(start 0.8636 -0.4572)
			(end -0.8636 -0.4572)
			(stroke
				(width 0.1)
				(type default)
			)
			(layer "B.Fab")
		)
		(fp_line
			(start -0.8636 0.4572)
			(end 0.8636 0.4572)
			(stroke
				(width 0.1)
				(type default)
			)
			(layer "B.Fab")
		)
		(fp_line
			(start -0.8636 0.4064)
			(end -0.8636 0.4572)
			(stroke
				(width 0.1)
				(type default)
			)
			(layer "B.Fab")
		)
		(fp_line
			(start -0.8636 -0.4064)
			(end -1.1938 -0.4064)
			(stroke
				(width 0.1)
				(type default)
			)
			(layer "B.Fab")
		)
		(fp_line
			(start -0.8636 -0.4572)
			(end -0.8636 -0.4064)
			(stroke
				(width 0.1)
				(type default)
			)
			(layer "B.Fab")
		)
		(fp_line
			(start -1.1938 0.4064)
			(end -0.8636 0.4064)
			(stroke
				(width 0.1)
				(type default)
			)
			(layer "B.Fab")
		)
		(fp_line
			(start -1.1938 -0.4064)
			(end -1.1938 0.4064)
			(stroke
				(width 0.1)
				(type default)
			)
			(layer "B.Fab")
		)
		(pad "1" smd rect
			(at 0.7366 0 90)
			(size 0.7112 0.8128)
			(layers "B.Cu" "B.Mask" "B.Paste")
			(net "P1V25_PEX3")
		)
		(pad "2" smd rect
			(at -0.7366 0 90)
			(size 0.7112 0.8128)
			(layers "B.Cu" "B.Mask" "B.Paste")
			(net "GND")
		)
	)
	(footprint ""
		(layer "B.Cu")
		(at 213.801198 -220.322902)
		(property "Reference" "R4888"
			(at 0 0 0)
			(layer "B.SilkS")
			(hide yes)
			(effects
				(font
					(size 1.27 1.27)
				)
				(justify mirror)
			)
		)
		(property "Value" ""
			(at 0 0 0)
			(layer "B.Fab")
			(effects
				(font
					(size 1.27 1.27)
				)
				(justify mirror)
			)
		)
		(duplicate_pad_numbers_are_jumpers no)
		(fp_line
			(start -0.7874 -0.4064)
			(end -0.7874 0.4064)
			(stroke
				(width 0.1524)
				(type default)
			)
			(layer "B.SilkS")
		)
		(fp_line
			(start -0.7874 0.4064)
			(end 0.7874 0.4064)
			(stroke
				(width 0.1524)
				(type default)
			)
			(layer "B.SilkS")
		)
		(fp_line
			(start 0.7874 -0.4064)
			(end -0.7874 -0.4064)
			(stroke
				(width 0.1524)
				(type default)
			)
			(layer "B.SilkS")
		)
		(fp_line
			(start 0.7874 0.4064)
			(end 0.7874 -0.4064)
			(stroke
				(width 0.1524)
				(type default)
			)
			(layer "B.SilkS")
		)
		(fp_line
			(start -0.67945 -0.3048)
			(end -0.67945 0.3048)
			(stroke
				(width 0.1)
				(type default)
			)
			(layer "B.Fab")
		)
		(fp_line
			(start -0.67945 0.3048)
			(end -0.120396 0.3048)
			(stroke
				(width 0.1)
				(type default)
			)
			(layer "B.Fab")
		)
		(fp_line
			(start -0.12065 -0.3048)
			(end -0.67945 -0.3048)
			(stroke
				(width 0.1)
				(type default)
			)
			(layer "B.Fab")
		)
		(fp_line
			(start -0.12065 -0.2794)
			(end -0.12065 -0.3048)
			(stroke
				(width 0.1)
				(type default)
			)
			(layer "B.Fab")
		)
		(fp_line
			(start -0.120396 0.2794)
			(end 0.12065 0.2794)
			(stroke
				(width 0.1)
				(type default)
			)
			(layer "B.Fab")
		)
		(fp_line
			(start -0.120396 0.3048)
			(end -0.120396 0.2794)
			(stroke
				(width 0.1)
				(type default)
			)
			(layer "B.Fab")
		)
		(fp_line
			(start 0.12065 -0.305054)
			(end 0.12065 -0.2794)
			(stroke
				(width 0.1)
				(type default)
			)
			(layer "B.Fab")
		)
		(fp_line
			(start 0.12065 -0.2794)
			(end -0.12065 -0.2794)
			(stroke
				(width 0.1)
				(type default)
			)
			(layer "B.Fab")
		)
		(fp_line
			(start 0.12065 0.2794)
			(end 0.12065 0.3048)
			(stroke
				(width 0.1)
				(type default)
			)
			(layer "B.Fab")
		)
		(fp_line
			(start 0.12065 0.3048)
			(end 0.67945 0.3048)
			(stroke
				(width 0.1)
				(type default)
			)
			(layer "B.Fab")
		)
		(fp_line
			(start 0.67945 -0.305054)
			(end 0.12065 -0.305054)
			(stroke
				(width 0.1)
				(type default)
			)
			(layer "B.Fab")
		)
		(fp_line
			(start 0.67945 0.3048)
			(end 0.67945 -0.305054)
			(stroke
				(width 0.1)
				(type default)
			)
			(layer "B.Fab")
		)
		(pad "1" smd circle
			(at 0.40005 0 180)
			(size 0 0)
			(layers "B.Cu" "B.Mask" "B.Paste")
			(net "SMB_PEX_R_SDA")
		)
		(pad "2" smd circle
			(at -0.40005 0 180)
			(size 0 0)
			(layers "B.Cu" "B.Mask" "B.Paste")
			(net "P3V3_AUX")
		)
	)
	(footprint ""
		(layer "B.Cu")
		(at 101.223318 -389.9408 180)
		(property "Reference" "C3630"
			(at 0 0 0)
			(layer "B.SilkS")
			(hide yes)
			(effects
				(font
					(size 1.27 1.27)
				)
				(justify mirror)
			)
		)
		(property "Value" ""
			(at 0 0 0)
			(layer "B.Fab")
			(effects
				(font
					(size 1.27 1.27)
				)
				(justify mirror)
			)
		)
		(duplicate_pad_numbers_are_jumpers no)
		(fp_line
			(start 0.7874 0.4064)
			(end 0.7874 -0.4064)
			(stroke
				(width 0.1524)
				(type default)
			)
			(layer "B.SilkS")
		)
		(fp_line
			(start 0.7874 -0.4064)
			(end -0.7874 -0.4064)
			(stroke
				(width 0.1524)
				(type default)
			)
			(layer "B.SilkS")
		)
		(fp_line
			(start -0.7874 0.4064)
			(end 0.7874 0.4064)
			(stroke
				(width 0.1524)
				(type default)
			)
			(layer "B.SilkS")
		)
		(fp_line
			(start -0.7874 -0.4064)
			(end -0.7874 0.4064)
			(stroke
				(width 0.1524)
				(type default)
			)
			(layer "B.SilkS")
		)
		(fp_line
			(start 0.67945 0.3048)
			(end 0.67945 -0.305054)
			(stroke
				(width 0.1)
				(type default)
			)
			(layer "B.Fab")
		)
		(fp_line
			(start 0.67945 -0.305054)
			(end 0.12065 -0.305054)
			(stroke
				(width 0.1)
				(type default)
			)
			(layer "B.Fab")
		)
		(fp_line
			(start 0.12065 0.3048)
			(end 0.67945 0.3048)
			(stroke
				(width 0.1)
				(type default)
			)
			(layer "B.Fab")
		)
		(fp_line
			(start 0.12065 0.2794)
			(end 0.12065 0.3048)
			(stroke
				(width 0.1)
				(type default)
			)
			(layer "B.Fab")
		)
		(fp_line
			(start 0.12065 -0.2794)
			(end -0.12065 -0.2794)
			(stroke
				(width 0.1)
				(type default)
			)
			(layer "B.Fab")
		)
		(fp_line
			(start 0.12065 -0.305054)
			(end 0.12065 -0.2794)
			(stroke
				(width 0.1)
				(type default)
			)
			(layer "B.Fab")
		)
		(fp_line
			(start -0.120396 0.3048)
			(end -0.120396 0.2794)
			(stroke
				(width 0.1)
				(type default)
			)
			(layer "B.Fab")
		)
		(fp_line
			(start -0.120396 0.2794)
			(end 0.12065 0.2794)
			(stroke
				(width 0.1)
				(type default)
			)
			(layer "B.Fab")
		)
		(fp_line
			(start -0.12065 -0.2794)
			(end -0.12065 -0.3048)
			(stroke
				(width 0.1)
				(type default)
			)
			(layer "B.Fab")
		)
		(fp_line
			(start -0.12065 -0.3048)
			(end -0.67945 -0.3048)
			(stroke
				(width 0.1)
				(type default)
			)
			(layer "B.Fab")
		)
		(fp_line
			(start -0.67945 0.3048)
			(end -0.120396 0.3048)
			(stroke
				(width 0.1)
				(type default)
			)
			(layer "B.Fab")
		)
		(fp_line
			(start -0.67945 -0.3048)
			(end -0.67945 0.3048)
			(stroke
				(width 0.1)
				(type default)
			)
			(layer "B.Fab")
		)
		(pad "1" smd circle
			(at 0.40005 0)
			(size 0 0)
			(layers "B.Cu" "B.Mask" "B.Paste")
			(net "P3V3_BIC_USB_HUB")
		)
		(pad "2" smd circle
			(at -0.40005 0)
			(size 0 0)
			(layers "B.Cu" "B.Mask" "B.Paste")
			(net "GND")
		)
	)
	(footprint ""
		(layer "B.Cu")
		(at 385.943602 -237.29696)
		(property "Reference" "L4"
			(at 0 0 0)
			(layer "B.SilkS")
			(hide yes)
			(effects
				(font
					(size 1.27 1.27)
				)
				(justify mirror)
			)
		)
		(property "Value" ""
			(at 0 0 0)
			(layer "B.Fab")
			(effects
				(font
					(size 1.27 1.27)
				)
				(justify mirror)
			)
		)
		(duplicate_pad_numbers_are_jumpers no)
		(fp_line
			(start -1.27 0.5842)
			(end -1.27 -0.5842)
			(stroke
				(width 0.1524)
				(type default)
			)
			(layer "B.SilkS")
		)
		(fp_line
			(start -1.27 0.5842)
			(end 1.27 0.5842)
			(stroke
				(width 0.1524)
				(type default)
			)
			(layer "B.SilkS")
		)
		(fp_line
			(start 1.27 -0.5842)
			(end -1.27 -0.5842)
			(stroke
				(width 0.1524)
				(type default)
			)
			(layer "B.SilkS")
		)
		(fp_line
			(start 1.27 -0.5588)
			(end 1.27 -0.5842)
			(stroke
				(width 0.1524)
				(type default)
			)
			(layer "B.SilkS")
		)
		(fp_line
			(start 1.27 0.5842)
			(end 1.27 -0.5842)
			(stroke
				(width 0.1524)
				(type default)
			)
			(layer "B.SilkS")
		)
		(fp_line
			(start -1.1938 -0.406654)
			(end -1.1938 0.4064)
			(stroke
				(width 0.1)
				(type default)
			)
			(layer "B.Fab")
		)
		(fp_line
			(start -1.1938 0.4064)
			(end -0.9144 0.4064)
			(stroke
				(width 0.1)
				(type default)
			)
			(layer "B.Fab")
		)
		(fp_line
			(start -0.9144 -0.508)
			(end -0.9144 -0.406654)
			(stroke
				(width 0.1)
				(type default)
			)
			(layer "B.Fab")
		)
		(fp_line
			(start -0.9144 -0.406654)
			(end -1.1938 -0.406654)
			(stroke
				(width 0.1)
				(type default)
			)
			(layer "B.Fab")
		)
		(fp_line
			(start -0.9144 0.4064)
			(end -0.9144 0.508)
			(stroke
				(width 0.1)
				(type default)
			)
			(layer "B.Fab")
		)
		(fp_line
			(start -0.9144 0.508)
			(end 0.9144 0.508)
			(stroke
				(width 0.1)
				(type default)
			)
			(layer "B.Fab")
		)
		(fp_line
			(start 0.9144 -0.508)
			(end -0.9144 -0.508)
			(stroke
				(width 0.1)
				(type default)
			)
			(layer "B.Fab")
		)
		(fp_line
			(start 0.9144 -0.406654)
			(end 0.9144 -0.508)
			(stroke
				(width 0.1)
				(type default)
			)
			(layer "B.Fab")
		)
		(fp_line
			(start 0.9144 0.406654)
			(end 1.194308 0.406654)
			(stroke
				(width 0.1)
				(type default)
			)
			(layer "B.Fab")
		)
		(fp_line
			(start 0.9144 0.508)
			(end 0.9144 0.406654)
			(stroke
				(width 0.1)
				(type default)
			)
			(layer "B.Fab")
		)
		(fp_line
			(start 1.194308 -0.406654)
			(end 0.9144 -0.406654)
			(stroke
				(width 0.1)
				(type default)
			)
			(layer "B.Fab")
		)
		(fp_line
			(start 1.194308 0.406654)
			(end 1.194308 -0.406654)
			(stroke
				(width 0.1)
				(type default)
			)
			(layer "B.Fab")
		)
		(pad "1" smd rect
			(at 0.7366 0 270)
			(size 0.7112 0.8128)
			(layers "B.Cu" "B.Mask" "B.Paste")
			(net "P3V3_AUX")
		)
		(pad "2" smd rect
			(at -0.7366 0 270)
			(size 0.7112 0.8128)
			(layers "B.Cu" "B.Mask" "B.Paste")
			(net "P3V3_SDB_VPLL")
		)
	)
	(footprint ""
		(layer "B.Cu")
		(at 272.373598 -295.79824 180)
		(property "Reference" "R3475"
			(at 0 0 0)
			(layer "B.SilkS")
			(hide yes)
			(effects
				(font
					(size 1.27 1.27)
				)
				(justify mirror)
			)
		)
		(property "Value" ""
			(at 0 0 0)
			(layer "B.Fab")
			(effects
				(font
					(size 1.27 1.27)
				)
				(justify mirror)
			)
		)
		(duplicate_pad_numbers_are_jumpers no)
		(fp_line
			(start 0.7874 0.4064)
			(end 0.7874 -0.4064)
			(stroke
				(width 0.1524)
				(type default)
			)
			(layer "B.SilkS")
		)
		(fp_line
			(start 0.7874 -0.4064)
			(end -0.7874 -0.4064)
			(stroke
				(width 0.1524)
				(type default)
			)
			(layer "B.SilkS")
		)
		(fp_line
			(start -0.7874 0.4064)
			(end 0.7874 0.4064)
			(stroke
				(width 0.1524)
				(type default)
			)
			(layer "B.SilkS")
		)
		(fp_line
			(start -0.7874 -0.4064)
			(end -0.7874 0.4064)
			(stroke
				(width 0.1524)
				(type default)
			)
			(layer "B.SilkS")
		)
		(fp_line
			(start 0.67945 0.3048)
			(end 0.67945 -0.305054)
			(stroke
				(width 0.1)
				(type default)
			)
			(layer "B.Fab")
		)
		(fp_line
			(start 0.67945 -0.305054)
			(end 0.12065 -0.305054)
			(stroke
				(width 0.1)
				(type default)
			)
			(layer "B.Fab")
		)
		(fp_line
			(start 0.12065 0.3048)
			(end 0.67945 0.3048)
			(stroke
				(width 0.1)
				(type default)
			)
			(layer "B.Fab")
		)
		(fp_line
			(start 0.12065 0.2794)
			(end 0.12065 0.3048)
			(stroke
				(width 0.1)
				(type default)
			)
			(layer "B.Fab")
		)
		(fp_line
			(start 0.12065 -0.2794)
			(end -0.12065 -0.2794)
			(stroke
				(width 0.1)
				(type default)
			)
			(layer "B.Fab")
		)
		(fp_line
			(start 0.12065 -0.305054)
			(end 0.12065 -0.2794)
			(stroke
				(width 0.1)
				(type default)
			)
			(layer "B.Fab")
		)
		(fp_line
			(start -0.120396 0.3048)
			(end -0.120396 0.2794)
			(stroke
				(width 0.1)
				(type default)
			)
			(layer "B.Fab")
		)
		(fp_line
			(start -0.120396 0.2794)
			(end 0.12065 0.2794)
			(stroke
				(width 0.1)
				(type default)
			)
			(layer "B.Fab")
		)
		(fp_line
			(start -0.12065 -0.2794)
			(end -0.12065 -0.3048)
			(stroke
				(width 0.1)
				(type default)
			)
			(layer "B.Fab")
		)
		(fp_line
			(start -0.12065 -0.3048)
			(end -0.67945 -0.3048)
			(stroke
				(width 0.1)
				(type default)
			)
			(layer "B.Fab")
		)
		(fp_line
			(start -0.67945 0.3048)
			(end -0.120396 0.3048)
			(stroke
				(width 0.1)
				(type default)
			)
			(layer "B.Fab")
		)
		(fp_line
			(start -0.67945 -0.3048)
			(end -0.67945 0.3048)
			(stroke
				(width 0.1)
				(type default)
			)
			(layer "B.Fab")
		)
		(pad "1" smd circle
			(at 0.40005 0)
			(size 0 0)
			(layers "B.Cu" "B.Mask" "B.Paste")
			(net "SPI_PEX2_SDIO0_R")
		)
		(pad "2" smd circle
			(at -0.40005 0)
			(size 0 0)
			(layers "B.Cu" "B.Mask" "B.Paste")
			(net "SPI_PEX2_SDIO0")
		)
	)
	(footprint ""
		(layer "B.Cu")
		(at 340.339426 -85.597746)
		(property "Reference" "C2678"
			(at 0 0 0)
			(layer "B.SilkS")
			(hide yes)
			(effects
				(font
					(size 1.27 1.27)
				)
				(justify mirror)
			)
		)
		(property "Value" ""
			(at 0 0 0)
			(layer "B.Fab")
			(effects
				(font
					(size 1.27 1.27)
				)
				(justify mirror)
			)
		)
		(duplicate_pad_numbers_are_jumpers no)
		(fp_line
			(start -0.7874 -0.4064)
			(end -0.7874 0.4064)
			(stroke
				(width 0.1524)
				(type default)
			)
			(layer "B.SilkS")
		)
		(fp_line
			(start -0.7874 0.4064)
			(end 0.7874 0.4064)
			(stroke
				(width 0.1524)
				(type default)
			)
			(layer "B.SilkS")
		)
		(fp_line
			(start 0.7874 -0.4064)
			(end -0.7874 -0.4064)
			(stroke
				(width 0.1524)
				(type default)
			)
			(layer "B.SilkS")
		)
		(fp_line
			(start 0.7874 0.4064)
			(end 0.7874 -0.4064)
			(stroke
				(width 0.1524)
				(type default)
			)
			(layer "B.SilkS")
		)
		(fp_line
			(start -0.67945 -0.3048)
			(end -0.67945 0.3048)
			(stroke
				(width 0.1)
				(type default)
			)
			(layer "B.Fab")
		)
		(fp_line
			(start -0.67945 0.3048)
			(end -0.120396 0.3048)
			(stroke
				(width 0.1)
				(type default)
			)
			(layer "B.Fab")
		)
		(fp_line
			(start -0.12065 -0.3048)
			(end -0.67945 -0.3048)
			(stroke
				(width 0.1)
				(type default)
			)
			(layer "B.Fab")
		)
		(fp_line
			(start -0.12065 -0.2794)
			(end -0.12065 -0.3048)
			(stroke
				(width 0.1)
				(type default)
			)
			(layer "B.Fab")
		)
		(fp_line
			(start -0.120396 0.2794)
			(end 0.12065 0.2794)
			(stroke
				(width 0.1)
				(type default)
			)
			(layer "B.Fab")
		)
		(fp_line
			(start -0.120396 0.3048)
			(end -0.120396 0.2794)
			(stroke
				(width 0.1)
				(type default)
			)
			(layer "B.Fab")
		)
		(fp_line
			(start 0.12065 -0.305054)
			(end 0.12065 -0.2794)
			(stroke
				(width 0.1)
				(type default)
			)
			(layer "B.Fab")
		)
		(fp_line
			(start 0.12065 -0.2794)
			(end -0.12065 -0.2794)
			(stroke
				(width 0.1)
				(type default)
			)
			(layer "B.Fab")
		)
		(fp_line
			(start 0.12065 0.2794)
			(end 0.12065 0.3048)
			(stroke
				(width 0.1)
				(type default)
			)
			(layer "B.Fab")
		)
		(fp_line
			(start 0.12065 0.3048)
			(end 0.67945 0.3048)
			(stroke
				(width 0.1)
				(type default)
			)
			(layer "B.Fab")
		)
		(fp_line
			(start 0.67945 -0.305054)
			(end 0.12065 -0.305054)
			(stroke
				(width 0.1)
				(type default)
			)
			(layer "B.Fab")
		)
		(fp_line
			(start 0.67945 0.3048)
			(end 0.67945 -0.305054)
			(stroke
				(width 0.1)
				(type default)
			)
			(layer "B.Fab")
		)
		(pad "1" smd circle
			(at 0.40005 0 180)
			(size 0 0)
			(layers "B.Cu" "B.Mask" "B.Paste")
			(net "P3V3_VDD_9ZXL0851_8_15")
		)
		(pad "2" smd circle
			(at -0.40005 0 180)
			(size 0 0)
			(layers "B.Cu" "B.Mask" "B.Paste")
			(net "GND")
		)
	)
	(footprint ""
		(layer "B.Cu")
		(at 388.473696 -296.9514 180)
		(property "Reference" "R3493"
			(at 0 0 0)
			(layer "B.SilkS")
			(hide yes)
			(effects
				(font
					(size 1.27 1.27)
				)
				(justify mirror)
			)
		)
		(property "Value" ""
			(at 0 0 0)
			(layer "B.Fab")
			(effects
				(font
					(size 1.27 1.27)
				)
				(justify mirror)
			)
		)
		(duplicate_pad_numbers_are_jumpers no)
		(fp_line
			(start 0.7874 0.4064)
			(end 0.7874 -0.4064)
			(stroke
				(width 0.1524)
				(type default)
			)
			(layer "B.SilkS")
		)
		(fp_line
			(start 0.7874 -0.4064)
			(end -0.7874 -0.4064)
			(stroke
				(width 0.1524)
				(type default)
			)
			(layer "B.SilkS")
		)
		(fp_line
			(start -0.7874 0.4064)
			(end 0.7874 0.4064)
			(stroke
				(width 0.1524)
				(type default)
			)
			(layer "B.SilkS")
		)
		(fp_line
			(start -0.7874 -0.4064)
			(end -0.7874 0.4064)
			(stroke
				(width 0.1524)
				(type default)
			)
			(layer "B.SilkS")
		)
		(fp_line
			(start 0.67945 0.3048)
			(end 0.67945 -0.305054)
			(stroke
				(width 0.1)
				(type default)
			)
			(layer "B.Fab")
		)
		(fp_line
			(start 0.67945 -0.305054)
			(end 0.12065 -0.305054)
			(stroke
				(width 0.1)
				(type default)
			)
			(layer "B.Fab")
		)
		(fp_line
			(start 0.12065 0.3048)
			(end 0.67945 0.3048)
			(stroke
				(width 0.1)
				(type default)
			)
			(layer "B.Fab")
		)
		(fp_line
			(start 0.12065 0.2794)
			(end 0.12065 0.3048)
			(stroke
				(width 0.1)
				(type default)
			)
			(layer "B.Fab")
		)
		(fp_line
			(start 0.12065 -0.2794)
			(end -0.12065 -0.2794)
			(stroke
				(width 0.1)
				(type default)
			)
			(layer "B.Fab")
		)
		(fp_line
			(start 0.12065 -0.305054)
			(end 0.12065 -0.2794)
			(stroke
				(width 0.1)
				(type default)
			)
			(layer "B.Fab")
		)
		(fp_line
			(start -0.120396 0.3048)
			(end -0.120396 0.2794)
			(stroke
				(width 0.1)
				(type default)
			)
			(layer "B.Fab")
		)
		(fp_line
			(start -0.120396 0.2794)
			(end 0.12065 0.2794)
			(stroke
				(width 0.1)
				(type default)
			)
			(layer "B.Fab")
		)
		(fp_line
			(start -0.12065 -0.2794)
			(end -0.12065 -0.3048)
			(stroke
				(width 0.1)
				(type default)
			)
			(layer "B.Fab")
		)
		(fp_line
			(start -0.12065 -0.3048)
			(end -0.67945 -0.3048)
			(stroke
				(width 0.1)
				(type default)
			)
			(layer "B.Fab")
		)
		(fp_line
			(start -0.67945 0.3048)
			(end -0.120396 0.3048)
			(stroke
				(width 0.1)
				(type default)
			)
			(layer "B.Fab")
		)
		(fp_line
			(start -0.67945 -0.3048)
			(end -0.67945 0.3048)
			(stroke
				(width 0.1)
				(type default)
			)
			(layer "B.Fab")
		)
		(pad "1" smd circle
			(at 0.40005 0)
			(size 0 0)
			(layers "B.Cu" "B.Mask" "B.Paste")
			(net "SPI_PEX3_SDIO1_R")
		)
		(pad "2" smd circle
			(at -0.40005 0)
			(size 0 0)
			(layers "B.Cu" "B.Mask" "B.Paste")
			(net "SPI_PEX3_SDIO1")
		)
	)
	(footprint ""
		(layer "B.Cu")
		(at 177.174906 -293.99992 90)
		(property "Reference" "C1396"
			(at 0 0 90)
			(layer "B.SilkS")
			(hide yes)
			(effects
				(font
					(size 1.27 1.27)
				)
				(justify mirror)
			)
		)
		(property "Value" ""
			(at 0 0 90)
			(layer "B.Fab")
			(effects
				(font
					(size 1.27 1.27)
				)
				(justify mirror)
			)
		)
		(duplicate_pad_numbers_are_jumpers no)
		(fp_line
			(start 0.299974 -0.150114)
			(end -0.299974 -0.150114)
			(stroke
				(width 0.1)
				(type default)
			)
			(layer "B.Fab")
		)
		(fp_line
			(start -0.299974 -0.150114)
			(end -0.299974 0.150114)
			(stroke
				(width 0.1)
				(type default)
			)
			(layer "B.Fab")
		)
		(fp_line
			(start 0.299974 0.150114)
			(end 0.299974 -0.150114)
			(stroke
				(width 0.1)
				(type default)
			)
			(layer "B.Fab")
		)
		(fp_line
			(start -0.299974 0.150114)
			(end 0.299974 0.150114)
			(stroke
				(width 0.1)
				(type default)
			)
			(layer "B.Fab")
		)
		(pad "1" smd rect
			(at 0.2667 0 270)
			(size 0.3048 0.381)
			(layers "B.Cu" "B.Mask" "B.Paste")
			(net "P0V8_PEX1")
		)
		(pad "2" smd rect
			(at -0.2667 0 270)
			(size 0.3048 0.381)
			(layers "B.Cu" "B.Mask" "B.Paste")
			(net "GND")
		)
	)
	(footprint ""
		(layer "B.Cu")
		(at 54.899814 -299.699934 -90)
		(property "Reference" "C1220"
			(at 0 0 90)
			(layer "B.SilkS")
			(hide yes)
			(effects
				(font
					(size 1.27 1.27)
				)
				(justify mirror)
			)
		)
		(property "Value" ""
			(at 0 0 90)
			(layer "B.Fab")
			(effects
				(font
					(size 1.27 1.27)
				)
				(justify mirror)
			)
		)
		(duplicate_pad_numbers_are_jumpers no)
		(fp_line
			(start -0.299974 0.150114)
			(end 0.299974 0.150114)
			(stroke
				(width 0.1)
				(type default)
			)
			(layer "B.Fab")
		)
		(fp_line
			(start 0.299974 0.150114)
			(end 0.299974 -0.150114)
			(stroke
				(width 0.1)
				(type default)
			)
			(layer "B.Fab")
		)
		(fp_line
			(start -0.299974 -0.150114)
			(end -0.299974 0.150114)
			(stroke
				(width 0.1)
				(type default)
			)
			(layer "B.Fab")
		)
		(fp_line
			(start 0.299974 -0.150114)
			(end -0.299974 -0.150114)
			(stroke
				(width 0.1)
				(type default)
			)
			(layer "B.Fab")
		)
		(pad "1" smd rect
			(at 0.2667 0 90)
			(size 0.3048 0.381)
			(layers "B.Cu" "B.Mask" "B.Paste")
			(net "P0V8_SERDES_VDDA_PEX0")
		)
		(pad "2" smd rect
			(at -0.2667 0 90)
			(size 0.3048 0.381)
			(layers "B.Cu" "B.Mask" "B.Paste")
			(net "GND")
		)
	)
	(footprint ""
		(layer "B.Cu")
		(at 56.845708 -296.37482)
		(property "Reference" "C1109"
			(at 0 0 0)
			(layer "B.SilkS")
			(hide yes)
			(effects
				(font
					(size 1.27 1.27)
				)
				(justify mirror)
			)
		)
		(property "Value" ""
			(at 0 0 0)
			(layer "B.Fab")
			(effects
				(font
					(size 1.27 1.27)
				)
				(justify mirror)
			)
		)
		(duplicate_pad_numbers_are_jumpers no)
		(fp_line
			(start -0.299974 -0.150114)
			(end -0.299974 0.150114)
			(stroke
				(width 0.1)
				(type default)
			)
			(layer "B.Fab")
		)
		(fp_line
			(start -0.299974 0.150114)
			(end 0.299974 0.150114)
			(stroke
				(width 0.1)
				(type default)
			)
			(layer "B.Fab")
		)
		(fp_line
			(start 0.299974 -0.150114)
			(end -0.299974 -0.150114)
			(stroke
				(width 0.1)
				(type default)
			)
			(layer "B.Fab")
		)
		(fp_line
			(start 0.299974 0.150114)
			(end 0.299974 -0.150114)
			(stroke
				(width 0.1)
				(type default)
			)
			(layer "B.Fab")
		)
		(pad "1" smd rect
			(at 0.2667 0 180)
			(size 0.3048 0.381)
			(layers "B.Cu" "B.Mask" "B.Paste")
			(net "P0V8_PEX0")
		)
		(pad "2" smd rect
			(at -0.2667 0 180)
			(size 0.3048 0.381)
			(layers "B.Cu" "B.Mask" "B.Paste")
			(net "GND")
		)
	)
	(footprint ""
		(layer "B.Cu")
		(at 290.89985 -301.599854 -90)
		(property "Reference" "C1683"
			(at 0 0 90)
			(layer "B.SilkS")
			(hide yes)
			(effects
				(font
					(size 1.27 1.27)
				)
				(justify mirror)
			)
		)
		(property "Value" ""
			(at 0 0 90)
			(layer "B.Fab")
			(effects
				(font
					(size 1.27 1.27)
				)
				(justify mirror)
			)
		)
		(duplicate_pad_numbers_are_jumpers no)
		(fp_line
			(start -0.299974 0.150114)
			(end 0.299974 0.150114)
			(stroke
				(width 0.1)
				(type default)
			)
			(layer "B.Fab")
		)
		(fp_line
			(start 0.299974 0.150114)
			(end 0.299974 -0.150114)
			(stroke
				(width 0.1)
				(type default)
			)
			(layer "B.Fab")
		)
		(fp_line
			(start -0.299974 -0.150114)
			(end -0.299974 0.150114)
			(stroke
				(width 0.1)
				(type default)
			)
			(layer "B.Fab")
		)
		(fp_line
			(start 0.299974 -0.150114)
			(end -0.299974 -0.150114)
			(stroke
				(width 0.1)
				(type default)
			)
			(layer "B.Fab")
		)
		(pad "1" smd rect
			(at 0.2667 0 90)
			(size 0.3048 0.381)
			(layers "B.Cu" "B.Mask" "B.Paste")
			(net "P0V8_SERDES_VDDA_PEX2")
		)
		(pad "2" smd rect
			(at -0.2667 0 90)
			(size 0.3048 0.381)
			(layers "B.Cu" "B.Mask" "B.Paste")
			(net "GND")
		)
	)
	(footprint ""
		(layer "B.Cu")
		(at 290.92017 -296.37482)
		(property "Reference" "C1631"
			(at 0 0 0)
			(layer "B.SilkS")
			(hide yes)
			(effects
				(font
					(size 1.27 1.27)
				)
				(justify mirror)
			)
		)
		(property "Value" ""
			(at 0 0 0)
			(layer "B.Fab")
			(effects
				(font
					(size 1.27 1.27)
				)
				(justify mirror)
			)
		)
		(duplicate_pad_numbers_are_jumpers no)
		(fp_line
			(start -0.299974 -0.150114)
			(end -0.299974 0.150114)
			(stroke
				(width 0.1)
				(type default)
			)
			(layer "B.Fab")
		)
		(fp_line
			(start -0.299974 0.150114)
			(end 0.299974 0.150114)
			(stroke
				(width 0.1)
				(type default)
			)
			(layer "B.Fab")
		)
		(fp_line
			(start 0.299974 -0.150114)
			(end -0.299974 -0.150114)
			(stroke
				(width 0.1)
				(type default)
			)
			(layer "B.Fab")
		)
		(fp_line
			(start 0.299974 0.150114)
			(end 0.299974 -0.150114)
			(stroke
				(width 0.1)
				(type default)
			)
			(layer "B.Fab")
		)
		(pad "1" smd rect
			(at 0.2667 0 180)
			(size 0.3048 0.381)
			(layers "B.Cu" "B.Mask" "B.Paste")
			(net "P0V8_PEX2")
		)
		(pad "2" smd rect
			(at -0.2667 0 180)
			(size 0.3048 0.381)
			(layers "B.Cu" "B.Mask" "B.Paste")
			(net "GND")
		)
	)
	(footprint ""
		(layer "B.Cu")
		(at 117.257322 -325.186294 -90)
		(property "Reference" "C4202"
			(at 0 0 90)
			(layer "B.SilkS")
			(hide yes)
			(effects
				(font
					(size 1.27 1.27)
				)
				(justify mirror)
			)
		)
		(property "Value" ""
			(at 0 0 90)
			(layer "B.Fab")
			(effects
				(font
					(size 1.27 1.27)
				)
				(justify mirror)
			)
		)
		(duplicate_pad_numbers_are_jumpers no)
		(fp_line
			(start -1.2954 0.5842)
			(end 1.2954 0.5842)
			(stroke
				(width 0.1524)
				(type default)
			)
			(layer "B.SilkS")
		)
		(fp_line
			(start 1.2954 0.5842)
			(end 1.2954 -0.5842)
			(stroke
				(width 0.1524)
				(type default)
			)
			(layer "B.SilkS")
		)
		(fp_line
			(start -1.2954 -0.5842)
			(end -1.2954 0.5842)
			(stroke
				(width 0.1524)
				(type default)
			)
			(layer "B.SilkS")
		)
		(fp_line
			(start 1.2954 -0.5842)
			(end -1.2954 -0.5842)
			(stroke
				(width 0.1524)
				(type default)
			)
			(layer "B.SilkS")
		)
		(fp_line
			(start -0.8636 0.4572)
			(end 0.8636 0.4572)
			(stroke
				(width 0.1)
				(type default)
			)
			(layer "B.Fab")
		)
		(fp_line
			(start 0.8636 0.4572)
			(end 0.8636 0.4064)
			(stroke
				(width 0.1)
				(type default)
			)
			(layer "B.Fab")
		)
		(fp_line
			(start -1.1938 0.4064)
			(end -0.8636 0.4064)
			(stroke
				(width 0.1)
				(type default)
			)
			(layer "B.Fab")
		)
		(fp_line
			(start -0.8636 0.4064)
			(end -0.8636 0.4572)
			(stroke
				(width 0.1)
				(type default)
			)
			(layer "B.Fab")
		)
		(fp_line
			(start 0.8636 0.4064)
			(end 1.1938 0.4064)
			(stroke
				(width 0.1)
				(type default)
			)
			(layer "B.Fab")
		)
		(fp_line
			(start 1.1938 0.4064)
			(end 1.1938 -0.4064)
			(stroke
				(width 0.1)
				(type default)
			)
			(layer "B.Fab")
		)
		(fp_line
			(start -1.1938 -0.4064)
			(end -1.1938 0.4064)
			(stroke
				(width 0.1)
				(type default)
			)
			(layer "B.Fab")
		)
		(fp_line
			(start -0.8636 -0.4064)
			(end -1.1938 -0.4064)
			(stroke
				(width 0.1)
				(type default)
			)
			(layer "B.Fab")
		)
		(fp_line
			(start 0.8636 -0.4064)
			(end 0.8636 -0.4572)
			(stroke
				(width 0.1)
				(type default)
			)
			(layer "B.Fab")
		)
		(fp_line
			(start 1.1938 -0.4064)
			(end 0.8636 -0.4064)
			(stroke
				(width 0.1)
				(type default)
			)
			(layer "B.Fab")
		)
		(fp_line
			(start -0.8636 -0.4572)
			(end -0.8636 -0.4064)
			(stroke
				(width 0.1)
				(type default)
			)
			(layer "B.Fab")
		)
		(fp_line
			(start 0.8636 -0.4572)
			(end -0.8636 -0.4572)
			(stroke
				(width 0.1)
				(type default)
			)
			(layer "B.Fab")
		)
		(pad "1" smd rect
			(at 0.7366 0 180)
			(size 0.7112 0.8128)
			(layers "B.Cu" "B.Mask" "B.Paste")
			(net "P0V8_SERDES_VDDA_PEX0_C0")
		)
		(pad "2" smd rect
			(at -0.7366 0 180)
			(size 0.7112 0.8128)
			(layers "B.Cu" "B.Mask" "B.Paste")
			(net "GND")
		)
	)
	(footprint ""
		(layer "B.Cu")
		(at 111.089186 -284.796738 -90)
		(property "Reference" "PC79"
			(at 0 0 90)
			(layer "B.SilkS")
			(hide yes)
			(effects
				(font
					(size 1.27 1.27)
				)
				(justify mirror)
			)
		)
		(property "Value" ""
			(at 0 0 90)
			(layer "B.Fab")
			(effects
				(font
					(size 1.27 1.27)
				)
				(justify mirror)
			)
		)
		(duplicate_pad_numbers_are_jumpers no)
		(fp_line
			(start -1.524 0.762)
			(end 1.524 0.762)
			(stroke
				(width 0.1524)
				(type default)
			)
			(layer "B.SilkS")
		)
		(fp_line
			(start 1.524 0.762)
			(end 1.524 -0.762)
			(stroke
				(width 0.1524)
				(type default)
			)
			(layer "B.SilkS")
		)
		(fp_line
			(start -1.524 -0.762)
			(end -1.524 0.762)
			(stroke
				(width 0.1524)
				(type default)
			)
			(layer "B.SilkS")
		)
		(fp_line
			(start 1.524 -0.762)
			(end -1.524 -0.762)
			(stroke
				(width 0.1524)
				(type default)
			)
			(layer "B.SilkS")
		)
		(fp_line
			(start -1.1049 0.724916)
			(end -1.1049 -0.724916)
			(stroke
				(width 0.1)
				(type default)
			)
			(layer "B.Fab")
		)
		(fp_line
			(start 1.1049 0.724916)
			(end -1.1049 0.724916)
			(stroke
				(width 0.1)
				(type default)
			)
			(layer "B.Fab")
		)
		(fp_line
			(start -1.1049 -0.724916)
			(end 1.1049 -0.724916)
			(stroke
				(width 0.1)
				(type default)
			)
			(layer "B.Fab")
		)
		(fp_line
			(start 1.1049 -0.724916)
			(end 1.1049 0.724916)
			(stroke
				(width 0.1)
				(type default)
			)
			(layer "B.Fab")
		)
		(pad "1" smd rect
			(at 0.889 0 270)
			(size 1.016 1.27)
			(layers "B.Cu" "B.Mask" "B.Paste")
			(net "SW_P12V_P0V8_PEX0_FLT")
		)
		(pad "2" smd rect
			(at -0.889 0 270)
			(size 1.016 1.27)
			(layers "B.Cu" "B.Mask" "B.Paste")
			(net "GND")
		)
	)
	(footprint ""
		(layer "B.Cu")
		(at 405.730202 -295.221914)
		(property "Reference" "C1867"
			(at 0 0 0)
			(layer "B.SilkS")
			(hide yes)
			(effects
				(font
					(size 1.27 1.27)
				)
				(justify mirror)
			)
		)
		(property "Value" ""
			(at 0 0 0)
			(layer "B.Fab")
			(effects
				(font
					(size 1.27 1.27)
				)
				(justify mirror)
			)
		)
		(duplicate_pad_numbers_are_jumpers no)
		(fp_line
			(start -1.2954 -0.5842)
			(end -1.2954 0.5842)
			(stroke
				(width 0.1524)
				(type default)
			)
			(layer "B.SilkS")
		)
		(fp_line
			(start -1.2954 0.5842)
			(end 1.2954 0.5842)
			(stroke
				(width 0.1524)
				(type default)
			)
			(layer "B.SilkS")
		)
		(fp_line
			(start 1.2954 -0.5842)
			(end -1.2954 -0.5842)
			(stroke
				(width 0.1524)
				(type default)
			)
			(layer "B.SilkS")
		)
		(fp_line
			(start 1.2954 0.5842)
			(end 1.2954 -0.5842)
			(stroke
				(width 0.1524)
				(type default)
			)
			(layer "B.SilkS")
		)
		(fp_line
			(start -1.1938 -0.4064)
			(end -1.1938 0.4064)
			(stroke
				(width 0.1)
				(type default)
			)
			(layer "B.Fab")
		)
		(fp_line
			(start -1.1938 0.4064)
			(end -0.8636 0.4064)
			(stroke
				(width 0.1)
				(type default)
			)
			(layer "B.Fab")
		)
		(fp_line
			(start -0.8636 -0.4572)
			(end -0.8636 -0.4064)
			(stroke
				(width 0.1)
				(type default)
			)
			(layer "B.Fab")
		)
		(fp_line
			(start -0.8636 -0.4064)
			(end -1.1938 -0.4064)
			(stroke
				(width 0.1)
				(type default)
			)
			(layer "B.Fab")
		)
		(fp_line
			(start -0.8636 0.4064)
			(end -0.8636 0.4572)
			(stroke
				(width 0.1)
				(type default)
			)
			(layer "B.Fab")
		)
		(fp_line
			(start -0.8636 0.4572)
			(end 0.8636 0.4572)
			(stroke
				(width 0.1)
				(type default)
			)
			(layer "B.Fab")
		)
		(fp_line
			(start 0.8636 -0.4572)
			(end -0.8636 -0.4572)
			(stroke
				(width 0.1)
				(type default)
			)
			(layer "B.Fab")
		)
		(fp_line
			(start 0.8636 -0.4064)
			(end 0.8636 -0.4572)
			(stroke
				(width 0.1)
				(type default)
			)
			(layer "B.Fab")
		)
		(fp_line
			(start 0.8636 0.4064)
			(end 1.1938 0.4064)
			(stroke
				(width 0.1)
				(type default)
			)
			(layer "B.Fab")
		)
		(fp_line
			(start 0.8636 0.4572)
			(end 0.8636 0.4064)
			(stroke
				(width 0.1)
				(type default)
			)
			(layer "B.Fab")
		)
		(fp_line
			(start 1.1938 -0.4064)
			(end 0.8636 -0.4064)
			(stroke
				(width 0.1)
				(type default)
			)
			(layer "B.Fab")
		)
		(fp_line
			(start 1.1938 0.4064)
			(end 1.1938 -0.4064)
			(stroke
				(width 0.1)
				(type default)
			)
			(layer "B.Fab")
		)
		(pad "1" smd rect
			(at 0.7366 0 270)
			(size 0.7112 0.8128)
			(layers "B.Cu" "B.Mask" "B.Paste")
			(net "P0V8_PEX3")
		)
		(pad "2" smd rect
			(at -0.7366 0 270)
			(size 0.7112 0.8128)
			(layers "B.Cu" "B.Mask" "B.Paste")
			(net "GND")
		)
	)
	(footprint ""
		(layer "B.Cu")
		(at 14.312392 -453.121014)
		(property "Reference" "X64"
			(at -0.9017 -2.08407 180)
			(unlocked yes)
			(layer "B.SilkS")
			(effects
				(font
					(size 0.7874 0.5842)
					(thickness 0.1524)
				)
				(justify mirror)
			)
		)
		(property "Value" ""
			(at 0 0 0)
			(layer "B.Fab")
			(effects
				(font
					(size 1.27 1.27)
				)
				(justify mirror)
			)
		)
		(property "User Part Number" "TP15"
			(at -1.30175 1.27 270)
			(unlocked yes)
			(layer "Cmts.User")
			(hide yes)
			(effects
				(font
					(size 0.635 0.4064)
					(thickness 0.1524)
				)
				(justify mirror)
			)
		)
		(property "Device Type" "TP_TDR_4P_FTS_MPKT4_H025P0200_IO_TP15_TP_TDR_4P_DIP"
			(at -1.30175 1.27 270)
			(unlocked yes)
			(layer "B.Fab")
			(hide yes)
			(effects
				(font
					(size 0.635 0.4064)
					(thickness 0.1524)
				)
				(justify mirror)
			)
		)
		(duplicate_pad_numbers_are_jumpers no)
		(fp_line
			(start -2.54 -1.27)
			(end 0 -1.27)
			(stroke
				(width 0.1524)
				(type default)
			)
			(layer "B.SilkS")
		)
		(fp_line
			(start -2.54 -1.1303)
			(end -2.54 -1.27)
			(stroke
				(width 0.1524)
				(type default)
			)
			(layer "B.SilkS")
		)
		(fp_line
			(start -2.54 1.4097)
			(end -2.54 1.1303)
			(stroke
				(width 0.1524)
				(type default)
			)
			(layer "B.SilkS")
		)
		(fp_line
			(start -2.54 3.81)
			(end -2.54 3.6703)
			(stroke
				(width 0.1524)
				(type default)
			)
			(layer "B.SilkS")
		)
		(fp_line
			(start 0 -1.27)
			(end 0 -0.635)
			(stroke
				(width 0.1524)
				(type default)
			)
			(layer "B.SilkS")
		)
		(fp_line
			(start 0 0.635)
			(end 0 1.905)
			(stroke
				(width 0.1524)
				(type default)
			)
			(layer "B.SilkS")
		)
		(fp_line
			(start 0 3.175)
			(end 0 3.81)
			(stroke
				(width 0.1524)
				(type default)
			)
			(layer "B.SilkS")
		)
		(fp_line
			(start 0 3.81)
			(end -2.54 3.81)
			(stroke
				(width 0.1524)
				(type default)
			)
			(layer "B.SilkS")
		)
		(fp_poly
			(pts
				(xy 0.761746 0) (xy 2.285746 -0.762) (xy 2.285746 0.762)
			)
			(stroke
				(width 0)
				(type default)
			)
			(fill yes)
			(layer "B.SilkS")
		)
		(fp_line
			(start -2.54 -1.27)
			(end 0 -1.27)
			(stroke
				(width 0.1)
				(type default)
			)
			(layer "B.Fab")
		)
		(fp_line
			(start -2.54 3.81)
			(end -2.54 -1.27)
			(stroke
				(width 0.1)
				(type default)
			)
			(layer "B.Fab")
		)
		(fp_line
			(start 0 -1.27)
			(end 0 3.81)
			(stroke
				(width 0.1)
				(type default)
			)
			(layer "B.Fab")
		)
		(fp_line
			(start 0 3.81)
			(end -2.54 3.81)
			(stroke
				(width 0.1)
				(type default)
			)
			(layer "B.Fab")
		)
		(fp_poly
			(pts
				(xy 0.761746 0) (xy 2.285746 -0.762) (xy 2.285746 0.762)
			)
			(stroke
				(width 0)
				(type default)
			)
			(fill yes)
			(layer "B.Fab")
		)
		(pad "1" thru_hole circle
			(at 0 0 180)
			(size 1.0033 1.0033)
			(drill 0.249936)
			(layers "*.Cu" "*.Mask")
			(remove_unused_layers no)
			(net "TDR_DIFF_85_IN6_DIP")
			(clearance 0.10795)
			(padstack
				(mode front_inner_back)
				(layer "Inner"
					(shape circle)
					(size 0.8001 0.8001)
					(clearance 0.1524)
				)
				(layer "B.Cu"
					(shape circle)
					(size 1.0033 1.0033)
					(thermal_gap 0.10795)
					(clearance 0.10795)
				)
			)
		)
		(pad "2" thru_hole circle
			(at -2.54 0 180)
			(size 1.9939 1.9939)
			(drill 0.249936)
			(layers "*.Cu" "*.Mask")
			(remove_unused_layers no)
			(net "COUPON_GND1")
			(clearance 0.10795)
			(padstack
				(mode front_inner_back)
				(layer "Inner"
					(shape circle)
					(size 0.8001 0.8001)
					(clearance 0.1524)
				)
				(layer "B.Cu"
					(shape circle)
					(size 1.9939 1.9939)
					(thermal_gap 0.10795)
					(clearance 0.10795)
				)
			)
		)
		(pad "3" thru_hole circle
			(at -2.54 2.54 180)
			(size 1.9939 1.9939)
			(drill 0.249936)
			(layers "*.Cu" "*.Mask")
			(remove_unused_layers no)
			(net "COUPON_GND1")
			(clearance 0.10795)
			(padstack
				(mode front_inner_back)
				(layer "Inner"
					(shape circle)
					(size 0.8001 0.8001)
					(clearance 0.1524)
				)
				(layer "B.Cu"
					(shape circle)
					(size 1.9939 1.9939)
					(thermal_gap 0.10795)
					(clearance 0.10795)
				)
			)
		)
		(pad "4" thru_hole circle
			(at 0 2.54 180)
			(size 1.0033 1.0033)
			(drill 0.249936)
			(layers "*.Cu" "*.Mask")
			(remove_unused_layers no)
			(net "TDR_DIFF_85_IN6_DIN")
			(clearance 0.10795)
			(padstack
				(mode front_inner_back)
				(layer "Inner"
					(shape circle)
					(size 0.8001 0.8001)
					(clearance 0.1524)
				)
				(layer "B.Cu"
					(shape circle)
					(size 1.0033 1.0033)
					(thermal_gap 0.10795)
					(clearance 0.10795)
				)
			)
		)
	)
	(footprint ""
		(layer "B.Cu")
		(at 398.925034 -286.399732 90)
		(property "Reference" "C3472"
			(at 0 0 90)
			(layer "B.SilkS")
			(hide yes)
			(effects
				(font
					(size 1.27 1.27)
				)
				(justify mirror)
			)
		)
		(property "Value" ""
			(at 0 0 90)
			(layer "B.Fab")
			(effects
				(font
					(size 1.27 1.27)
				)
				(justify mirror)
			)
		)
		(duplicate_pad_numbers_are_jumpers no)
		(fp_line
			(start 0.299974 -0.150114)
			(end -0.299974 -0.150114)
			(stroke
				(width 0.1)
				(type default)
			)
			(layer "B.Fab")
		)
		(fp_line
			(start -0.299974 -0.150114)
			(end -0.299974 0.150114)
			(stroke
				(width 0.1)
				(type default)
			)
			(layer "B.Fab")
		)
		(fp_line
			(start 0.299974 0.150114)
			(end 0.299974 -0.150114)
			(stroke
				(width 0.1)
				(type default)
			)
			(layer "B.Fab")
		)
		(fp_line
			(start -0.299974 0.150114)
			(end 0.299974 0.150114)
			(stroke
				(width 0.1)
				(type default)
			)
			(layer "B.Fab")
		)
		(pad "1" smd rect
			(at 0.2667 0 270)
			(size 0.3048 0.381)
			(layers "B.Cu" "B.Mask" "B.Paste")
			(net "P1V25_SERDES_VDDPLL_PEX3")
		)
		(pad "2" smd rect
			(at -0.2667 0 270)
			(size 0.3048 0.381)
			(layers "B.Cu" "B.Mask" "B.Paste")
			(net "GND")
		)
	)
	(footprint ""
		(layer "B.Cu")
		(at 66.299842 -292.099746 90)
		(property "Reference" "C1195"
			(at 0 0 90)
			(layer "B.SilkS")
			(hide yes)
			(effects
				(font
					(size 1.27 1.27)
				)
				(justify mirror)
			)
		)
		(property "Value" ""
			(at 0 0 90)
			(layer "B.Fab")
			(effects
				(font
					(size 1.27 1.27)
				)
				(justify mirror)
			)
		)
		(duplicate_pad_numbers_are_jumpers no)
		(fp_line
			(start 0.299974 -0.150114)
			(end -0.299974 -0.150114)
			(stroke
				(width 0.1)
				(type default)
			)
			(layer "B.Fab")
		)
		(fp_line
			(start -0.299974 -0.150114)
			(end -0.299974 0.150114)
			(stroke
				(width 0.1)
				(type default)
			)
			(layer "B.Fab")
		)
		(fp_line
			(start 0.299974 0.150114)
			(end 0.299974 -0.150114)
			(stroke
				(width 0.1)
				(type default)
			)
			(layer "B.Fab")
		)
		(fp_line
			(start -0.299974 0.150114)
			(end 0.299974 0.150114)
			(stroke
				(width 0.1)
				(type default)
			)
			(layer "B.Fab")
		)
		(pad "1" smd rect
			(at 0.2667 0 270)
			(size 0.3048 0.381)
			(layers "B.Cu" "B.Mask" "B.Paste")
			(net "P0V8_SERDES_VDDA_PEX0")
		)
		(pad "2" smd rect
			(at -0.2667 0 270)
			(size 0.3048 0.381)
			(layers "B.Cu" "B.Mask" "B.Paste")
			(net "GND")
		)
	)
	(footprint ""
		(layer "B.Cu")
		(at 121.619772 -284.796738 -90)
		(property "Reference" "PC94"
			(at 0 0 90)
			(layer "B.SilkS")
			(hide yes)
			(effects
				(font
					(size 1.27 1.27)
				)
				(justify mirror)
			)
		)
		(property "Value" ""
			(at 0 0 90)
			(layer "B.Fab")
			(effects
				(font
					(size 1.27 1.27)
				)
				(justify mirror)
			)
		)
		(duplicate_pad_numbers_are_jumpers no)
		(fp_line
			(start -1.524 0.762)
			(end 1.524 0.762)
			(stroke
				(width 0.1524)
				(type default)
			)
			(layer "B.SilkS")
		)
		(fp_line
			(start 1.524 0.762)
			(end 1.524 -0.762)
			(stroke
				(width 0.1524)
				(type default)
			)
			(layer "B.SilkS")
		)
		(fp_line
			(start -1.524 -0.762)
			(end -1.524 0.762)
			(stroke
				(width 0.1524)
				(type default)
			)
			(layer "B.SilkS")
		)
		(fp_line
			(start 1.524 -0.762)
			(end -1.524 -0.762)
			(stroke
				(width 0.1524)
				(type default)
			)
			(layer "B.SilkS")
		)
		(fp_line
			(start -1.1049 0.724916)
			(end -1.1049 -0.724916)
			(stroke
				(width 0.1)
				(type default)
			)
			(layer "B.Fab")
		)
		(fp_line
			(start 1.1049 0.724916)
			(end -1.1049 0.724916)
			(stroke
				(width 0.1)
				(type default)
			)
			(layer "B.Fab")
		)
		(fp_line
			(start -1.1049 -0.724916)
			(end 1.1049 -0.724916)
			(stroke
				(width 0.1)
				(type default)
			)
			(layer "B.Fab")
		)
		(fp_line
			(start 1.1049 -0.724916)
			(end 1.1049 0.724916)
			(stroke
				(width 0.1)
				(type default)
			)
			(layer "B.Fab")
		)
		(pad "1" smd rect
			(at 0.889 0 270)
			(size 1.016 1.27)
			(layers "B.Cu" "B.Mask" "B.Paste")
			(net "SW_P12V_P0V8_PEX1_FLT")
		)
		(pad "2" smd rect
			(at -0.889 0 270)
			(size 1.016 1.27)
			(layers "B.Cu" "B.Mask" "B.Paste")
			(net "GND")
		)
	)
	(footprint ""
		(layer "B.Cu")
		(at 211.553298 -371.77726 180)
		(property "Reference" "PR21"
			(at 0 0 0)
			(layer "B.SilkS")
			(hide yes)
			(effects
				(font
					(size 1.27 1.27)
				)
				(justify mirror)
			)
		)
		(property "Value" ""
			(at 0 0 0)
			(layer "B.Fab")
			(effects
				(font
					(size 1.27 1.27)
				)
				(justify mirror)
			)
		)
		(duplicate_pad_numbers_are_jumpers no)
		(fp_line
			(start 0.7874 0.4064)
			(end 0.7874 -0.4064)
			(stroke
				(width 0.1524)
				(type default)
			)
			(layer "B.SilkS")
		)
		(fp_line
			(start 0.7874 -0.4064)
			(end -0.7874 -0.4064)
			(stroke
				(width 0.1524)
				(type default)
			)
			(layer "B.SilkS")
		)
		(fp_line
			(start -0.7874 0.4064)
			(end 0.7874 0.4064)
			(stroke
				(width 0.1524)
				(type default)
			)
			(layer "B.SilkS")
		)
		(fp_line
			(start -0.7874 -0.4064)
			(end -0.7874 0.4064)
			(stroke
				(width 0.1524)
				(type default)
			)
			(layer "B.SilkS")
		)
		(fp_line
			(start 0.67945 0.3048)
			(end 0.67945 -0.305054)
			(stroke
				(width 0.1)
				(type default)
			)
			(layer "B.Fab")
		)
		(fp_line
			(start 0.67945 -0.305054)
			(end 0.12065 -0.305054)
			(stroke
				(width 0.1)
				(type default)
			)
			(layer "B.Fab")
		)
		(fp_line
			(start 0.12065 0.3048)
			(end 0.67945 0.3048)
			(stroke
				(width 0.1)
				(type default)
			)
			(layer "B.Fab")
		)
		(fp_line
			(start 0.12065 0.2794)
			(end 0.12065 0.3048)
			(stroke
				(width 0.1)
				(type default)
			)
			(layer "B.Fab")
		)
		(fp_line
			(start 0.12065 -0.2794)
			(end -0.12065 -0.2794)
			(stroke
				(width 0.1)
				(type default)
			)
			(layer "B.Fab")
		)
		(fp_line
			(start 0.12065 -0.305054)
			(end 0.12065 -0.2794)
			(stroke
				(width 0.1)
				(type default)
			)
			(layer "B.Fab")
		)
		(fp_line
			(start -0.120396 0.3048)
			(end -0.120396 0.2794)
			(stroke
				(width 0.1)
				(type default)
			)
			(layer "B.Fab")
		)
		(fp_line
			(start -0.120396 0.2794)
			(end 0.12065 0.2794)
			(stroke
				(width 0.1)
				(type default)
			)
			(layer "B.Fab")
		)
		(fp_line
			(start -0.12065 -0.2794)
			(end -0.12065 -0.3048)
			(stroke
				(width 0.1)
				(type default)
			)
			(layer "B.Fab")
		)
		(fp_line
			(start -0.12065 -0.3048)
			(end -0.67945 -0.3048)
			(stroke
				(width 0.1)
				(type default)
			)
			(layer "B.Fab")
		)
		(fp_line
			(start -0.67945 0.3048)
			(end -0.120396 0.3048)
			(stroke
				(width 0.1)
				(type default)
			)
			(layer "B.Fab")
		)
		(fp_line
			(start -0.67945 -0.3048)
			(end -0.67945 0.3048)
			(stroke
				(width 0.1)
				(type default)
			)
			(layer "B.Fab")
		)
		(pad "1" smd circle
			(at 0.40005 0)
			(size 0 0)
			(layers "B.Cu" "B.Mask" "B.Paste")
			(net "HSC_FLT_TYPE")
		)
		(pad "2" smd circle
			(at -0.40005 0)
			(size 0 0)
			(layers "B.Cu" "B.Mask" "B.Paste")
			(net "HSC_FLT_TYPE_R")
		)
	)
	(footprint ""
		(layer "B.Cu")
		(at 168.625012 -305.399948 -90)
		(property "Reference" "C3155"
			(at 0 0 90)
			(layer "B.SilkS")
			(hide yes)
			(effects
				(font
					(size 1.27 1.27)
				)
				(justify mirror)
			)
		)
		(property "Value" ""
			(at 0 0 90)
			(layer "B.Fab")
			(effects
				(font
					(size 1.27 1.27)
				)
				(justify mirror)
			)
		)
		(duplicate_pad_numbers_are_jumpers no)
		(fp_line
			(start -0.299974 0.150114)
			(end 0.299974 0.150114)
			(stroke
				(width 0.1)
				(type default)
			)
			(layer "B.Fab")
		)
		(fp_line
			(start 0.299974 0.150114)
			(end 0.299974 -0.150114)
			(stroke
				(width 0.1)
				(type default)
			)
			(layer "B.Fab")
		)
		(fp_line
			(start -0.299974 -0.150114)
			(end -0.299974 0.150114)
			(stroke
				(width 0.1)
				(type default)
			)
			(layer "B.Fab")
		)
		(fp_line
			(start 0.299974 -0.150114)
			(end -0.299974 -0.150114)
			(stroke
				(width 0.1)
				(type default)
			)
			(layer "B.Fab")
		)
		(pad "1" smd rect
			(at 0.2667 0 90)
			(size 0.3048 0.381)
			(layers "B.Cu" "B.Mask" "B.Paste")
			(net "P1V25_SERDES_VDDPLL_PEX1")
		)
		(pad "2" smd rect
			(at -0.2667 0 90)
			(size 0.3048 0.381)
			(layers "B.Cu" "B.Mask" "B.Paste")
			(net "GND")
		)
	)
	(footprint ""
		(layer "B.Cu")
		(at 276.649688 -293.99992)
		(property "Reference" "C3335"
			(at 0 0 0)
			(layer "B.SilkS")
			(hide yes)
			(effects
				(font
					(size 1.27 1.27)
				)
				(justify mirror)
			)
		)
		(property "Value" ""
			(at 0 0 0)
			(layer "B.Fab")
			(effects
				(font
					(size 1.27 1.27)
				)
				(justify mirror)
			)
		)
		(duplicate_pad_numbers_are_jumpers no)
		(fp_line
			(start -0.299974 -0.150114)
			(end -0.299974 0.150114)
			(stroke
				(width 0.1)
				(type default)
			)
			(layer "B.Fab")
		)
		(fp_line
			(start -0.299974 0.150114)
			(end 0.299974 0.150114)
			(stroke
				(width 0.1)
				(type default)
			)
			(layer "B.Fab")
		)
		(fp_line
			(start 0.299974 -0.150114)
			(end -0.299974 -0.150114)
			(stroke
				(width 0.1)
				(type default)
			)
			(layer "B.Fab")
		)
		(fp_line
			(start 0.299974 0.150114)
			(end 0.299974 -0.150114)
			(stroke
				(width 0.1)
				(type default)
			)
			(layer "B.Fab")
		)
		(pad "1" smd rect
			(at 0.2667 0 180)
			(size 0.3048 0.381)
			(layers "B.Cu" "B.Mask" "B.Paste")
			(net "P1V8_PEX")
		)
		(pad "2" smd rect
			(at -0.2667 0 180)
			(size 0.3048 0.381)
			(layers "B.Cu" "B.Mask" "B.Paste")
			(net "GND")
		)
	)
	(footprint ""
		(layer "B.Cu")
		(at 68.199762 -298.27474 180)
		(property "Reference" "C1126"
			(at 0 0 0)
			(layer "B.SilkS")
			(hide yes)
			(effects
				(font
					(size 1.27 1.27)
				)
				(justify mirror)
			)
		)
		(property "Value" ""
			(at 0 0 0)
			(layer "B.Fab")
			(effects
				(font
					(size 1.27 1.27)
				)
				(justify mirror)
			)
		)
		(duplicate_pad_numbers_are_jumpers no)
		(fp_line
			(start 0.299974 0.150114)
			(end 0.299974 -0.150114)
			(stroke
				(width 0.1)
				(type default)
			)
			(layer "B.Fab")
		)
		(fp_line
			(start 0.299974 -0.150114)
			(end -0.299974 -0.150114)
			(stroke
				(width 0.1)
				(type default)
			)
			(layer "B.Fab")
		)
		(fp_line
			(start -0.299974 0.150114)
			(end 0.299974 0.150114)
			(stroke
				(width 0.1)
				(type default)
			)
			(layer "B.Fab")
		)
		(fp_line
			(start -0.299974 -0.150114)
			(end -0.299974 0.150114)
			(stroke
				(width 0.1)
				(type default)
			)
			(layer "B.Fab")
		)
		(pad "1" smd rect
			(at 0.2667 0)
			(size 0.3048 0.381)
			(layers "B.Cu" "B.Mask" "B.Paste")
			(net "P0V8_PEX0")
		)
		(pad "2" smd rect
			(at -0.2667 0)
			(size 0.3048 0.381)
			(layers "B.Cu" "B.Mask" "B.Paste")
			(net "GND")
		)
	)
	(footprint ""
		(layer "B.Cu")
		(at 108.441236 -303.649634 -90)
		(property "Reference" "PC84"
			(at 0 0 90)
			(layer "B.SilkS")
			(hide yes)
			(effects
				(font
					(size 1.27 1.27)
				)
				(justify mirror)
			)
		)
		(property "Value" ""
			(at 0 0 90)
			(layer "B.Fab")
			(effects
				(font
					(size 1.27 1.27)
				)
				(justify mirror)
			)
		)
		(duplicate_pad_numbers_are_jumpers no)
		(fp_line
			(start -1.524 0.762)
			(end 1.524 0.762)
			(stroke
				(width 0.1524)
				(type default)
			)
			(layer "B.SilkS")
		)
		(fp_line
			(start 1.524 0.762)
			(end 1.524 -0.762)
			(stroke
				(width 0.1524)
				(type default)
			)
			(layer "B.SilkS")
		)
		(fp_line
			(start -1.524 -0.762)
			(end -1.524 0.762)
			(stroke
				(width 0.1524)
				(type default)
			)
			(layer "B.SilkS")
		)
		(fp_line
			(start 1.524 -0.762)
			(end -1.524 -0.762)
			(stroke
				(width 0.1524)
				(type default)
			)
			(layer "B.SilkS")
		)
		(fp_line
			(start -1.1049 0.724916)
			(end -1.1049 -0.724916)
			(stroke
				(width 0.1)
				(type default)
			)
			(layer "B.Fab")
		)
		(fp_line
			(start 1.1049 0.724916)
			(end -1.1049 0.724916)
			(stroke
				(width 0.1)
				(type default)
			)
			(layer "B.Fab")
		)
		(fp_line
			(start -1.1049 -0.724916)
			(end 1.1049 -0.724916)
			(stroke
				(width 0.1)
				(type default)
			)
			(layer "B.Fab")
		)
		(fp_line
			(start 1.1049 -0.724916)
			(end 1.1049 0.724916)
			(stroke
				(width 0.1)
				(type default)
			)
			(layer "B.Fab")
		)
		(pad "1" smd rect
			(at 0.889 0 270)
			(size 1.016 1.27)
			(layers "B.Cu" "B.Mask" "B.Paste")
			(net "P0V8_PEX0")
		)
		(pad "2" smd rect
			(at -0.889 0 270)
			(size 1.016 1.27)
			(layers "B.Cu" "B.Mask" "B.Paste")
			(net "GND")
		)
	)
	(footprint ""
		(layer "B.Cu")
		(at 225.857308 -146.631152 180)
		(property "Reference" "C2802"
			(at 0 0 0)
			(layer "B.SilkS")
			(hide yes)
			(effects
				(font
					(size 1.27 1.27)
				)
				(justify mirror)
			)
		)
		(property "Value" ""
			(at 0 0 0)
			(layer "B.Fab")
			(effects
				(font
					(size 1.27 1.27)
				)
				(justify mirror)
			)
		)
		(duplicate_pad_numbers_are_jumpers no)
		(fp_line
			(start 0.7874 0.4064)
			(end 0.7874 -0.4064)
			(stroke
				(width 0.1524)
				(type default)
			)
			(layer "B.SilkS")
		)
		(fp_line
			(start 0.7874 -0.4064)
			(end -0.7874 -0.4064)
			(stroke
				(width 0.1524)
				(type default)
			)
			(layer "B.SilkS")
		)
		(fp_line
			(start -0.7874 0.4064)
			(end 0.7874 0.4064)
			(stroke
				(width 0.1524)
				(type default)
			)
			(layer "B.SilkS")
		)
		(fp_line
			(start -0.7874 -0.4064)
			(end -0.7874 0.4064)
			(stroke
				(width 0.1524)
				(type default)
			)
			(layer "B.SilkS")
		)
		(fp_line
			(start 0.67945 0.3048)
			(end 0.67945 -0.305054)
			(stroke
				(width 0.1)
				(type default)
			)
			(layer "B.Fab")
		)
		(fp_line
			(start 0.67945 -0.305054)
			(end 0.12065 -0.305054)
			(stroke
				(width 0.1)
				(type default)
			)
			(layer "B.Fab")
		)
		(fp_line
			(start 0.12065 0.3048)
			(end 0.67945 0.3048)
			(stroke
				(width 0.1)
				(type default)
			)
			(layer "B.Fab")
		)
		(fp_line
			(start 0.12065 0.2794)
			(end 0.12065 0.3048)
			(stroke
				(width 0.1)
				(type default)
			)
			(layer "B.Fab")
		)
		(fp_line
			(start 0.12065 -0.2794)
			(end -0.12065 -0.2794)
			(stroke
				(width 0.1)
				(type default)
			)
			(layer "B.Fab")
		)
		(fp_line
			(start 0.12065 -0.305054)
			(end 0.12065 -0.2794)
			(stroke
				(width 0.1)
				(type default)
			)
			(layer "B.Fab")
		)
		(fp_line
			(start -0.120396 0.3048)
			(end -0.120396 0.2794)
			(stroke
				(width 0.1)
				(type default)
			)
			(layer "B.Fab")
		)
		(fp_line
			(start -0.120396 0.2794)
			(end 0.12065 0.2794)
			(stroke
				(width 0.1)
				(type default)
			)
			(layer "B.Fab")
		)
		(fp_line
			(start -0.12065 -0.2794)
			(end -0.12065 -0.3048)
			(stroke
				(width 0.1)
				(type default)
			)
			(layer "B.Fab")
		)
		(fp_line
			(start -0.12065 -0.3048)
			(end -0.67945 -0.3048)
			(stroke
				(width 0.1)
				(type default)
			)
			(layer "B.Fab")
		)
		(fp_line
			(start -0.67945 0.3048)
			(end -0.120396 0.3048)
			(stroke
				(width 0.1)
				(type default)
			)
			(layer "B.Fab")
		)
		(fp_line
			(start -0.67945 -0.3048)
			(end -0.67945 0.3048)
			(stroke
				(width 0.1)
				(type default)
			)
			(layer "B.Fab")
		)
		(pad "1" smd circle
			(at 0.40005 0)
			(size 0 0)
			(layers "B.Cu" "B.Mask" "B.Paste")
			(net "P3V3_CLK_GEN_VDDMXCK_CK440_PEX")
		)
		(pad "2" smd circle
			(at -0.40005 0)
			(size 0 0)
			(layers "B.Cu" "B.Mask" "B.Paste")
			(net "GND")
		)
	)
	(footprint ""
		(layer "B.Cu")
		(at 410.351224 -305.399948 -90)
		(property "Reference" "C3486"
			(at 0 0 90)
			(layer "B.SilkS")
			(hide yes)
			(effects
				(font
					(size 1.27 1.27)
				)
				(justify mirror)
			)
		)
		(property "Value" ""
			(at 0 0 90)
			(layer "B.Fab")
			(effects
				(font
					(size 1.27 1.27)
				)
				(justify mirror)
			)
		)
		(duplicate_pad_numbers_are_jumpers no)
		(fp_line
			(start -0.299974 0.150114)
			(end 0.299974 0.150114)
			(stroke
				(width 0.1)
				(type default)
			)
			(layer "B.Fab")
		)
		(fp_line
			(start 0.299974 0.150114)
			(end 0.299974 -0.150114)
			(stroke
				(width 0.1)
				(type default)
			)
			(layer "B.Fab")
		)
		(fp_line
			(start -0.299974 -0.150114)
			(end -0.299974 0.150114)
			(stroke
				(width 0.1)
				(type default)
			)
			(layer "B.Fab")
		)
		(fp_line
			(start 0.299974 -0.150114)
			(end -0.299974 -0.150114)
			(stroke
				(width 0.1)
				(type default)
			)
			(layer "B.Fab")
		)
		(pad "1" smd rect
			(at 0.2667 0 90)
			(size 0.3048 0.381)
			(layers "B.Cu" "B.Mask" "B.Paste")
			(net "P1V25_SERDES_VDDPLL_PEX3")
		)
		(pad "2" smd rect
			(at -0.2667 0 90)
			(size 0.3048 0.381)
			(layers "B.Cu" "B.Mask" "B.Paste")
			(net "GND")
		)
	)
	(footprint ""
		(layer "B.Cu")
		(at 366.46993 -308.677818 90)
		(property "Reference" "C4363"
			(at 0 0 90)
			(layer "B.SilkS")
			(hide yes)
			(effects
				(font
					(size 1.27 1.27)
				)
				(justify mirror)
			)
		)
		(property "Value" ""
			(at 0 0 90)
			(layer "B.Fab")
			(effects
				(font
					(size 1.27 1.27)
				)
				(justify mirror)
			)
		)
		(duplicate_pad_numbers_are_jumpers no)
		(fp_line
			(start 0.299974 -0.150114)
			(end -0.299974 -0.150114)
			(stroke
				(width 0.1)
				(type default)
			)
			(layer "B.Fab")
		)
		(fp_line
			(start -0.299974 -0.150114)
			(end -0.299974 0.150114)
			(stroke
				(width 0.1)
				(type default)
			)
			(layer "B.Fab")
		)
		(fp_line
			(start 0.299974 0.150114)
			(end 0.299974 -0.150114)
			(stroke
				(width 0.1)
				(type default)
			)
			(layer "B.Fab")
		)
		(fp_line
			(start -0.299974 0.150114)
			(end 0.299974 0.150114)
			(stroke
				(width 0.1)
				(type default)
			)
			(layer "B.Fab")
		)
		(pad "1" smd rect
			(at 0.2667 0 270)
			(size 0.3048 0.381)
			(layers "B.Cu" "B.Mask" "B.Paste")
			(net "P0V8_PEX3")
		)
		(pad "2" smd rect
			(at -0.2667 0 270)
			(size 0.3048 0.381)
			(layers "B.Cu" "B.Mask" "B.Paste")
			(net "GND")
		)
	)
	(footprint ""
		(layer "B.Cu")
		(at 281.399742 -299.2755 180)
		(property "Reference" "C1634"
			(at 0 0 0)
			(layer "B.SilkS")
			(hide yes)
			(effects
				(font
					(size 1.27 1.27)
				)
				(justify mirror)
			)
		)
		(property "Value" ""
			(at 0 0 0)
			(layer "B.Fab")
			(effects
				(font
					(size 1.27 1.27)
				)
				(justify mirror)
			)
		)
		(duplicate_pad_numbers_are_jumpers no)
		(fp_line
			(start 0.299974 0.150114)
			(end 0.299974 -0.150114)
			(stroke
				(width 0.1)
				(type default)
			)
			(layer "B.Fab")
		)
		(fp_line
			(start 0.299974 -0.150114)
			(end -0.299974 -0.150114)
			(stroke
				(width 0.1)
				(type default)
			)
			(layer "B.Fab")
		)
		(fp_line
			(start -0.299974 0.150114)
			(end 0.299974 0.150114)
			(stroke
				(width 0.1)
				(type default)
			)
			(layer "B.Fab")
		)
		(fp_line
			(start -0.299974 -0.150114)
			(end -0.299974 0.150114)
			(stroke
				(width 0.1)
				(type default)
			)
			(layer "B.Fab")
		)
		(pad "1" smd rect
			(at 0.2667 0)
			(size 0.3048 0.381)
			(layers "B.Cu" "B.Mask" "B.Paste")
			(net "P0V8_PEX2")
		)
		(pad "2" smd rect
			(at -0.2667 0)
			(size 0.3048 0.381)
			(layers "B.Cu" "B.Mask" "B.Paste")
			(net "GND")
		)
	)
	(footprint ""
		(layer "B.Cu")
		(at 288.99993 -292.099746 90)
		(property "Reference" "C1726"
			(at 0 0 90)
			(layer "B.SilkS")
			(hide yes)
			(effects
				(font
					(size 1.27 1.27)
				)
				(justify mirror)
			)
		)
		(property "Value" ""
			(at 0 0 90)
			(layer "B.Fab")
			(effects
				(font
					(size 1.27 1.27)
				)
				(justify mirror)
			)
		)
		(duplicate_pad_numbers_are_jumpers no)
		(fp_line
			(start 0.299974 -0.150114)
			(end -0.299974 -0.150114)
			(stroke
				(width 0.1)
				(type default)
			)
			(layer "B.Fab")
		)
		(fp_line
			(start -0.299974 -0.150114)
			(end -0.299974 0.150114)
			(stroke
				(width 0.1)
				(type default)
			)
			(layer "B.Fab")
		)
		(fp_line
			(start 0.299974 0.150114)
			(end 0.299974 -0.150114)
			(stroke
				(width 0.1)
				(type default)
			)
			(layer "B.Fab")
		)
		(fp_line
			(start -0.299974 0.150114)
			(end 0.299974 0.150114)
			(stroke
				(width 0.1)
				(type default)
			)
			(layer "B.Fab")
		)
		(pad "1" smd rect
			(at 0.2667 0 270)
			(size 0.3048 0.381)
			(layers "B.Cu" "B.Mask" "B.Paste")
			(net "P0V8_SERDES_VDDA_PEX2")
		)
		(pad "2" smd rect
			(at -0.2667 0 270)
			(size 0.3048 0.381)
			(layers "B.Cu" "B.Mask" "B.Paste")
			(net "GND")
		)
	)
	(footprint ""
		(layer "B.Cu")
		(at 55.31993 -305.399948 -90)
		(property "Reference" "C2976"
			(at 0 0 90)
			(layer "B.SilkS")
			(hide yes)
			(effects
				(font
					(size 1.27 1.27)
				)
				(justify mirror)
			)
		)
		(property "Value" ""
			(at 0 0 90)
			(layer "B.Fab")
			(effects
				(font
					(size 1.27 1.27)
				)
				(justify mirror)
			)
		)
		(duplicate_pad_numbers_are_jumpers no)
		(fp_line
			(start -0.299974 0.150114)
			(end 0.299974 0.150114)
			(stroke
				(width 0.1)
				(type default)
			)
			(layer "B.Fab")
		)
		(fp_line
			(start 0.299974 0.150114)
			(end 0.299974 -0.150114)
			(stroke
				(width 0.1)
				(type default)
			)
			(layer "B.Fab")
		)
		(fp_line
			(start -0.299974 -0.150114)
			(end -0.299974 0.150114)
			(stroke
				(width 0.1)
				(type default)
			)
			(layer "B.Fab")
		)
		(fp_line
			(start 0.299974 -0.150114)
			(end -0.299974 -0.150114)
			(stroke
				(width 0.1)
				(type default)
			)
			(layer "B.Fab")
		)
		(pad "1" smd rect
			(at 0.2667 0 90)
			(size 0.3048 0.381)
			(layers "B.Cu" "B.Mask" "B.Paste")
			(net "P1V25_SERDES_VDDPLL_PEX0")
		)
		(pad "2" smd rect
			(at -0.2667 0 90)
			(size 0.3048 0.381)
			(layers "B.Cu" "B.Mask" "B.Paste")
			(net "GND")
		)
	)
	(footprint ""
		(layer "B.Cu")
		(at 251.830586 -195.26885)
		(property "Reference" "R5283"
			(at 0 0 0)
			(layer "B.SilkS")
			(hide yes)
			(effects
				(font
					(size 1.27 1.27)
				)
				(justify mirror)
			)
		)
		(property "Value" ""
			(at 0 0 0)
			(layer "B.Fab")
			(effects
				(font
					(size 1.27 1.27)
				)
				(justify mirror)
			)
		)
		(duplicate_pad_numbers_are_jumpers no)
		(fp_line
			(start -0.7874 -0.4064)
			(end -0.7874 0.4064)
			(stroke
				(width 0.1524)
				(type default)
			)
			(layer "B.SilkS")
		)
		(fp_line
			(start -0.7874 0.4064)
			(end 0.7874 0.4064)
			(stroke
				(width 0.1524)
				(type default)
			)
			(layer "B.SilkS")
		)
		(fp_line
			(start 0.7874 -0.4064)
			(end -0.7874 -0.4064)
			(stroke
				(width 0.1524)
				(type default)
			)
			(layer "B.SilkS")
		)
		(fp_line
			(start 0.7874 0.4064)
			(end 0.7874 -0.4064)
			(stroke
				(width 0.1524)
				(type default)
			)
			(layer "B.SilkS")
		)
		(fp_line
			(start -0.67945 -0.3048)
			(end -0.67945 0.3048)
			(stroke
				(width 0.1)
				(type default)
			)
			(layer "B.Fab")
		)
		(fp_line
			(start -0.67945 0.3048)
			(end -0.120396 0.3048)
			(stroke
				(width 0.1)
				(type default)
			)
			(layer "B.Fab")
		)
		(fp_line
			(start -0.12065 -0.3048)
			(end -0.67945 -0.3048)
			(stroke
				(width 0.1)
				(type default)
			)
			(layer "B.Fab")
		)
		(fp_line
			(start -0.12065 -0.2794)
			(end -0.12065 -0.3048)
			(stroke
				(width 0.1)
				(type default)
			)
			(layer "B.Fab")
		)
		(fp_line
			(start -0.120396 0.2794)
			(end 0.12065 0.2794)
			(stroke
				(width 0.1)
				(type default)
			)
			(layer "B.Fab")
		)
		(fp_line
			(start -0.120396 0.3048)
			(end -0.120396 0.2794)
			(stroke
				(width 0.1)
				(type default)
			)
			(layer "B.Fab")
		)
		(fp_line
			(start 0.12065 -0.305054)
			(end 0.12065 -0.2794)
			(stroke
				(width 0.1)
				(type default)
			)
			(layer "B.Fab")
		)
		(fp_line
			(start 0.12065 -0.2794)
			(end -0.12065 -0.2794)
			(stroke
				(width 0.1)
				(type default)
			)
			(layer "B.Fab")
		)
		(fp_line
			(start 0.12065 0.2794)
			(end 0.12065 0.3048)
			(stroke
				(width 0.1)
				(type default)
			)
			(layer "B.Fab")
		)
		(fp_line
			(start 0.12065 0.3048)
			(end 0.67945 0.3048)
			(stroke
				(width 0.1)
				(type default)
			)
			(layer "B.Fab")
		)
		(fp_line
			(start 0.67945 -0.305054)
			(end 0.12065 -0.305054)
			(stroke
				(width 0.1)
				(type default)
			)
			(layer "B.Fab")
		)
		(fp_line
			(start 0.67945 0.3048)
			(end 0.67945 -0.305054)
			(stroke
				(width 0.1)
				(type default)
			)
			(layer "B.Fab")
		)
		(pad "1" smd circle
			(at 0.40005 0 180)
			(size 0 0)
			(layers "B.Cu" "B.Mask" "B.Paste")
			(net "P3V3_AUX")
		)
		(pad "2" smd circle
			(at -0.40005 0 180)
			(size 0 0)
			(layers "B.Cu" "B.Mask" "B.Paste")
			(net "JTAG_BIC_TCK_R")
		)
	)
	(footprint ""
		(layer "B.Cu")
		(at 229.715822 -143.815054 -90)
		(property "Reference" "C2795"
			(at 0 0 90)
			(layer "B.SilkS")
			(hide yes)
			(effects
				(font
					(size 1.27 1.27)
				)
				(justify mirror)
			)
		)
		(property "Value" ""
			(at 0 0 90)
			(layer "B.Fab")
			(effects
				(font
					(size 1.27 1.27)
				)
				(justify mirror)
			)
		)
		(duplicate_pad_numbers_are_jumpers no)
		(fp_line
			(start -0.7874 0.4064)
			(end 0.7874 0.4064)
			(stroke
				(width 0.1524)
				(type default)
			)
			(layer "B.SilkS")
		)
		(fp_line
			(start 0.7874 0.4064)
			(end 0.7874 -0.4064)
			(stroke
				(width 0.1524)
				(type default)
			)
			(layer "B.SilkS")
		)
		(fp_line
			(start -0.7874 -0.4064)
			(end -0.7874 0.4064)
			(stroke
				(width 0.1524)
				(type default)
			)
			(layer "B.SilkS")
		)
		(fp_line
			(start 0.7874 -0.4064)
			(end -0.7874 -0.4064)
			(stroke
				(width 0.1524)
				(type default)
			)
			(layer "B.SilkS")
		)
		(fp_line
			(start -0.67945 0.3048)
			(end -0.120396 0.3048)
			(stroke
				(width 0.1)
				(type default)
			)
			(layer "B.Fab")
		)
		(fp_line
			(start -0.120396 0.3048)
			(end -0.120396 0.2794)
			(stroke
				(width 0.1)
				(type default)
			)
			(layer "B.Fab")
		)
		(fp_line
			(start 0.12065 0.3048)
			(end 0.67945 0.3048)
			(stroke
				(width 0.1)
				(type default)
			)
			(layer "B.Fab")
		)
		(fp_line
			(start 0.67945 0.3048)
			(end 0.67945 -0.305054)
			(stroke
				(width 0.1)
				(type default)
			)
			(layer "B.Fab")
		)
		(fp_line
			(start -0.120396 0.2794)
			(end 0.12065 0.2794)
			(stroke
				(width 0.1)
				(type default)
			)
			(layer "B.Fab")
		)
		(fp_line
			(start 0.12065 0.2794)
			(end 0.12065 0.3048)
			(stroke
				(width 0.1)
				(type default)
			)
			(layer "B.Fab")
		)
		(fp_line
			(start -0.12065 -0.2794)
			(end -0.12065 -0.3048)
			(stroke
				(width 0.1)
				(type default)
			)
			(layer "B.Fab")
		)
		(fp_line
			(start 0.12065 -0.2794)
			(end -0.12065 -0.2794)
			(stroke
				(width 0.1)
				(type default)
			)
			(layer "B.Fab")
		)
		(fp_line
			(start -0.67945 -0.3048)
			(end -0.67945 0.3048)
			(stroke
				(width 0.1)
				(type default)
			)
			(layer "B.Fab")
		)
		(fp_line
			(start -0.12065 -0.3048)
			(end -0.67945 -0.3048)
			(stroke
				(width 0.1)
				(type default)
			)
			(layer "B.Fab")
		)
		(fp_line
			(start 0.12065 -0.305054)
			(end 0.12065 -0.2794)
			(stroke
				(width 0.1)
				(type default)
			)
			(layer "B.Fab")
		)
		(fp_line
			(start 0.67945 -0.305054)
			(end 0.12065 -0.305054)
			(stroke
				(width 0.1)
				(type default)
			)
			(layer "B.Fab")
		)
		(pad "1" smd circle
			(at 0.40005 0 90)
			(size 0 0)
			(layers "B.Cu" "B.Mask" "B.Paste")
			(net "P3V3_CLK_GEN_VDDXTAL_CK440_PEX")
		)
		(pad "2" smd circle
			(at -0.40005 0 90)
			(size 0 0)
			(layers "B.Cu" "B.Mask" "B.Paste")
			(net "GND")
		)
	)
	(footprint ""
		(layer "B.Cu")
		(at 331.183996 -215.05418 180)
		(property "Reference" "R5639"
			(at 0 0 0)
			(layer "B.SilkS")
			(hide yes)
			(effects
				(font
					(size 1.27 1.27)
				)
				(justify mirror)
			)
		)
		(property "Value" ""
			(at 0 0 0)
			(layer "B.Fab")
			(effects
				(font
					(size 1.27 1.27)
				)
				(justify mirror)
			)
		)
		(duplicate_pad_numbers_are_jumpers no)
		(fp_line
			(start 1.2954 0.5842)
			(end 1.2954 -0.5842)
			(stroke
				(width 0.1524)
				(type default)
			)
			(layer "B.SilkS")
		)
		(fp_line
			(start 1.2954 -0.5842)
			(end -1.2954 -0.5842)
			(stroke
				(width 0.1524)
				(type default)
			)
			(layer "B.SilkS")
		)
		(fp_line
			(start -1.2954 0.5842)
			(end 1.2954 0.5842)
			(stroke
				(width 0.1524)
				(type default)
			)
			(layer "B.SilkS")
		)
		(fp_line
			(start -1.2954 -0.5842)
			(end -1.2954 0.5842)
			(stroke
				(width 0.1524)
				(type default)
			)
			(layer "B.SilkS")
		)
		(fp_line
			(start 1.1938 0.4064)
			(end 1.1938 -0.406654)
			(stroke
				(width 0.1)
				(type default)
			)
			(layer "B.Fab")
		)
		(fp_line
			(start 1.1938 -0.406654)
			(end 0.8636 -0.406654)
			(stroke
				(width 0.1)
				(type default)
			)
			(layer "B.Fab")
		)
		(fp_line
			(start 0.8636 0.4572)
			(end 0.8636 0.4318)
			(stroke
				(width 0.1)
				(type default)
			)
			(layer "B.Fab")
		)
		(fp_line
			(start 0.8636 0.4318)
			(end 0.8636 0.4064)
			(stroke
				(width 0.1)
				(type default)
			)
			(layer "B.Fab")
		)
		(fp_line
			(start 0.8636 0.4064)
			(end 1.1938 0.4064)
			(stroke
				(width 0.1)
				(type default)
			)
			(layer "B.Fab")
		)
		(fp_line
			(start 0.8636 -0.406654)
			(end 0.8636 -0.4572)
			(stroke
				(width 0.1)
				(type default)
			)
			(layer "B.Fab")
		)
		(fp_line
			(start 0.8636 -0.4572)
			(end -0.8636 -0.4572)
			(stroke
				(width 0.1)
				(type default)
			)
			(layer "B.Fab")
		)
		(fp_line
			(start -0.8636 0.4572)
			(end 0.8636 0.4572)
			(stroke
				(width 0.1)
				(type default)
			)
			(layer "B.Fab")
		)
		(fp_line
			(start -0.8636 0.4064)
			(end -0.8636 0.4572)
			(stroke
				(width 0.1)
				(type default)
			)
			(layer "B.Fab")
		)
		(fp_line
			(start -0.8636 -0.406654)
			(end -1.1938 -0.406654)
			(stroke
				(width 0.1)
				(type default)
			)
			(layer "B.Fab")
		)
		(fp_line
			(start -0.8636 -0.4572)
			(end -0.8636 -0.406654)
			(stroke
				(width 0.1)
				(type default)
			)
			(layer "B.Fab")
		)
		(fp_line
			(start -1.1938 0.4064)
			(end -0.8636 0.4064)
			(stroke
				(width 0.1)
				(type default)
			)
			(layer "B.Fab")
		)
		(fp_line
			(start -1.1938 -0.406654)
			(end -1.1938 0.4064)
			(stroke
				(width 0.1)
				(type default)
			)
			(layer "B.Fab")
		)
		(pad "1" smd rect
			(at 0.7366 0 90)
			(size 0.7112 0.8128)
			(layers "B.Cu" "B.Mask" "B.Paste")
			(net "P3V3_AUX")
		)
		(pad "2" smd rect
			(at -0.7366 0 90)
			(size 0.7112 0.8128)
			(layers "B.Cu" "B.Mask" "B.Paste")
			(net "P3V3_FPGA_VCCIO3")
		)
	)
	(footprint ""
		(layer "B.Cu")
		(at 175.749966 -301.599854 -90)
		(property "Reference" "C1470"
			(at 0 0 90)
			(layer "B.SilkS")
			(hide yes)
			(effects
				(font
					(size 1.27 1.27)
				)
				(justify mirror)
			)
		)
		(property "Value" ""
			(at 0 0 90)
			(layer "B.Fab")
			(effects
				(font
					(size 1.27 1.27)
				)
				(justify mirror)
			)
		)
		(duplicate_pad_numbers_are_jumpers no)
		(fp_line
			(start -0.299974 0.150114)
			(end 0.299974 0.150114)
			(stroke
				(width 0.1)
				(type default)
			)
			(layer "B.Fab")
		)
		(fp_line
			(start 0.299974 0.150114)
			(end 0.299974 -0.150114)
			(stroke
				(width 0.1)
				(type default)
			)
			(layer "B.Fab")
		)
		(fp_line
			(start -0.299974 -0.150114)
			(end -0.299974 0.150114)
			(stroke
				(width 0.1)
				(type default)
			)
			(layer "B.Fab")
		)
		(fp_line
			(start 0.299974 -0.150114)
			(end -0.299974 -0.150114)
			(stroke
				(width 0.1)
				(type default)
			)
			(layer "B.Fab")
		)
		(pad "1" smd rect
			(at 0.2667 0 90)
			(size 0.3048 0.381)
			(layers "B.Cu" "B.Mask" "B.Paste")
			(net "P0V8_SERDES_VDDA_PEX1")
		)
		(pad "2" smd rect
			(at -0.2667 0 90)
			(size 0.3048 0.381)
			(layers "B.Cu" "B.Mask" "B.Paste")
			(net "GND")
		)
	)
	(footprint ""
		(layer "B.Cu")
		(at 226.19716 -266.794996 180)
		(property "Reference" "L98"
			(at 0 0 0)
			(layer "B.SilkS")
			(hide yes)
			(effects
				(font
					(size 1.27 1.27)
				)
				(justify mirror)
			)
		)
		(property "Value" ""
			(at 0 0 0)
			(layer "B.Fab")
			(effects
				(font
					(size 1.27 1.27)
				)
				(justify mirror)
			)
		)
		(duplicate_pad_numbers_are_jumpers no)
		(fp_line
			(start 2.248154 4.9911)
			(end -2.248154 4.9911)
			(stroke
				(width 0.1524)
				(type default)
			)
			(layer "B.SilkS")
		)
		(fp_line
			(start 2.248154 1.768094)
			(end 2.248154 4.9911)
			(stroke
				(width 0.1524)
				(type default)
			)
			(layer "B.SilkS")
		)
		(fp_line
			(start 2.248154 -4.9911)
			(end 2.248154 -2.036064)
			(stroke
				(width 0.1524)
				(type default)
			)
			(layer "B.SilkS")
		)
		(fp_line
			(start -2.248154 4.9911)
			(end -2.248154 1.768094)
			(stroke
				(width 0.1524)
				(type default)
			)
			(layer "B.SilkS")
		)
		(fp_line
			(start -2.248154 -2.036064)
			(end -2.248154 -4.9911)
			(stroke
				(width 0.1524)
				(type default)
			)
			(layer "B.SilkS")
		)
		(fp_line
			(start -2.248154 -4.9911)
			(end 2.248154 -4.9911)
			(stroke
				(width 0.1524)
				(type default)
			)
			(layer "B.SilkS")
		)
		(fp_line
			(start 1.700022 0.899922)
			(end -1.700022 0.899922)
			(stroke
				(width 0.1)
				(type default)
			)
			(layer "B.Fab")
		)
		(fp_line
			(start 1.700022 -0.899922)
			(end 1.700022 0.899922)
			(stroke
				(width 0.1)
				(type default)
			)
			(layer "B.Fab")
		)
		(fp_line
			(start -1.700022 0.899922)
			(end -1.700022 -0.899922)
			(stroke
				(width 0.1)
				(type default)
			)
			(layer "B.Fab")
		)
		(fp_line
			(start -1.700022 -0.899922)
			(end 1.700022 -0.899922)
			(stroke
				(width 0.1)
				(type default)
			)
			(layer "B.Fab")
		)
		(pad "1" smd rect
			(at 1.575054 0)
			(size 1.1684 9.8044)
			(layers "B.Cu" "B.Mask" "B.Paste")
			(net "P1V25_PEX1")
		)
		(pad "2" smd rect
			(at -1.575054 0)
			(size 1.1684 9.8044)
			(layers "B.Cu" "B.Mask" "B.Paste")
			(net "P1V25_SERDES_VDDPLL_PEX1")
		)
	)
	(footprint ""
		(layer "B.Cu")
		(at 327.523856 -224.955354)
		(property "Reference" "R6179"
			(at 0 0 0)
			(layer "B.SilkS")
			(hide yes)
			(effects
				(font
					(size 1.27 1.27)
				)
				(justify mirror)
			)
		)
		(property "Value" ""
			(at 0 0 0)
			(layer "B.Fab")
			(effects
				(font
					(size 1.27 1.27)
				)
				(justify mirror)
			)
		)
		(duplicate_pad_numbers_are_jumpers no)
		(fp_line
			(start -0.7874 -0.4064)
			(end -0.7874 0.4064)
			(stroke
				(width 0.1524)
				(type default)
			)
			(layer "B.SilkS")
		)
		(fp_line
			(start -0.7874 0.4064)
			(end 0.7874 0.4064)
			(stroke
				(width 0.1524)
				(type default)
			)
			(layer "B.SilkS")
		)
		(fp_line
			(start 0.7874 -0.4064)
			(end -0.7874 -0.4064)
			(stroke
				(width 0.1524)
				(type default)
			)
			(layer "B.SilkS")
		)
		(fp_line
			(start 0.7874 0.4064)
			(end 0.7874 -0.4064)
			(stroke
				(width 0.1524)
				(type default)
			)
			(layer "B.SilkS")
		)
		(fp_line
			(start -0.67945 -0.3048)
			(end -0.67945 0.3048)
			(stroke
				(width 0.1)
				(type default)
			)
			(layer "B.Fab")
		)
		(fp_line
			(start -0.67945 0.3048)
			(end -0.120396 0.3048)
			(stroke
				(width 0.1)
				(type default)
			)
			(layer "B.Fab")
		)
		(fp_line
			(start -0.12065 -0.3048)
			(end -0.67945 -0.3048)
			(stroke
				(width 0.1)
				(type default)
			)
			(layer "B.Fab")
		)
		(fp_line
			(start -0.12065 -0.2794)
			(end -0.12065 -0.3048)
			(stroke
				(width 0.1)
				(type default)
			)
			(layer "B.Fab")
		)
		(fp_line
			(start -0.120396 0.2794)
			(end 0.12065 0.2794)
			(stroke
				(width 0.1)
				(type default)
			)
			(layer "B.Fab")
		)
		(fp_line
			(start -0.120396 0.3048)
			(end -0.120396 0.2794)
			(stroke
				(width 0.1)
				(type default)
			)
			(layer "B.Fab")
		)
		(fp_line
			(start 0.12065 -0.305054)
			(end 0.12065 -0.2794)
			(stroke
				(width 0.1)
				(type default)
			)
			(layer "B.Fab")
		)
		(fp_line
			(start 0.12065 -0.2794)
			(end -0.12065 -0.2794)
			(stroke
				(width 0.1)
				(type default)
			)
			(layer "B.Fab")
		)
		(fp_line
			(start 0.12065 0.2794)
			(end 0.12065 0.3048)
			(stroke
				(width 0.1)
				(type default)
			)
			(layer "B.Fab")
		)
		(fp_line
			(start 0.12065 0.3048)
			(end 0.67945 0.3048)
			(stroke
				(width 0.1)
				(type default)
			)
			(layer "B.Fab")
		)
		(fp_line
			(start 0.67945 -0.305054)
			(end 0.12065 -0.305054)
			(stroke
				(width 0.1)
				(type default)
			)
			(layer "B.Fab")
		)
		(fp_line
			(start 0.67945 0.3048)
			(end 0.67945 -0.305054)
			(stroke
				(width 0.1)
				(type default)
			)
			(layer "B.Fab")
		)
		(pad "1" smd circle
			(at 0.40005 0 180)
			(size 0 0)
			(layers "B.Cu" "B.Mask" "B.Paste")
			(net "PWR_EN_P3V3_R")
		)
		(pad "2" smd circle
			(at -0.40005 0 180)
			(size 0 0)
			(layers "B.Cu" "B.Mask" "B.Paste")
			(net "GND")
		)
	)
	(footprint ""
		(layer "B.Cu")
		(at 285.199836 -303.499774 -90)
		(property "Reference" "C3260"
			(at 0 0 90)
			(layer "B.SilkS")
			(hide yes)
			(effects
				(font
					(size 1.27 1.27)
				)
				(justify mirror)
			)
		)
		(property "Value" ""
			(at 0 0 90)
			(layer "B.Fab")
			(effects
				(font
					(size 1.27 1.27)
				)
				(justify mirror)
			)
		)
		(duplicate_pad_numbers_are_jumpers no)
		(fp_line
			(start -0.299974 0.150114)
			(end 0.299974 0.150114)
			(stroke
				(width 0.1)
				(type default)
			)
			(layer "B.Fab")
		)
		(fp_line
			(start 0.299974 0.150114)
			(end 0.299974 -0.150114)
			(stroke
				(width 0.1)
				(type default)
			)
			(layer "B.Fab")
		)
		(fp_line
			(start -0.299974 -0.150114)
			(end -0.299974 0.150114)
			(stroke
				(width 0.1)
				(type default)
			)
			(layer "B.Fab")
		)
		(fp_line
			(start 0.299974 -0.150114)
			(end -0.299974 -0.150114)
			(stroke
				(width 0.1)
				(type default)
			)
			(layer "B.Fab")
		)
		(pad "1" smd rect
			(at 0.2667 0 90)
			(size 0.3048 0.381)
			(layers "B.Cu" "B.Mask" "B.Paste")
			(net "P1V25_PEX2")
		)
		(pad "2" smd rect
			(at -0.2667 0 90)
			(size 0.3048 0.381)
			(layers "B.Cu" "B.Mask" "B.Paste")
			(net "GND")
		)
	)
	(footprint ""
		(layer "B.Cu")
		(at 284.724856 -293.99992 90)
		(property "Reference" "C1625"
			(at 0 0 90)
			(layer "B.SilkS")
			(hide yes)
			(effects
				(font
					(size 1.27 1.27)
				)
				(justify mirror)
			)
		)
		(property "Value" ""
			(at 0 0 90)
			(layer "B.Fab")
			(effects
				(font
					(size 1.27 1.27)
				)
				(justify mirror)
			)
		)
		(duplicate_pad_numbers_are_jumpers no)
		(fp_line
			(start 0.299974 -0.150114)
			(end -0.299974 -0.150114)
			(stroke
				(width 0.1)
				(type default)
			)
			(layer "B.Fab")
		)
		(fp_line
			(start -0.299974 -0.150114)
			(end -0.299974 0.150114)
			(stroke
				(width 0.1)
				(type default)
			)
			(layer "B.Fab")
		)
		(fp_line
			(start 0.299974 0.150114)
			(end 0.299974 -0.150114)
			(stroke
				(width 0.1)
				(type default)
			)
			(layer "B.Fab")
		)
		(fp_line
			(start -0.299974 0.150114)
			(end 0.299974 0.150114)
			(stroke
				(width 0.1)
				(type default)
			)
			(layer "B.Fab")
		)
		(pad "1" smd rect
			(at 0.2667 0 270)
			(size 0.3048 0.381)
			(layers "B.Cu" "B.Mask" "B.Paste")
			(net "P0V8_PEX2")
		)
		(pad "2" smd rect
			(at -0.2667 0 270)
			(size 0.3048 0.381)
			(layers "B.Cu" "B.Mask" "B.Paste")
			(net "GND")
		)
	)
	(footprint ""
		(layer "B.Cu")
		(at 189.500002 -112.604296)
		(property "Reference" "C895"
			(at 0 0 0)
			(layer "B.SilkS")
			(hide yes)
			(effects
				(font
					(size 1.27 1.27)
				)
				(justify mirror)
			)
		)
		(property "Value" ""
			(at 0 0 0)
			(layer "B.Fab")
			(effects
				(font
					(size 1.27 1.27)
				)
				(justify mirror)
			)
		)
		(duplicate_pad_numbers_are_jumpers no)
		(fp_line
			(start -0.299974 -0.150114)
			(end -0.299974 0.150114)
			(stroke
				(width 0.1)
				(type default)
			)
			(layer "B.Fab")
		)
		(fp_line
			(start -0.299974 0.150114)
			(end 0.299974 0.150114)
			(stroke
				(width 0.1)
				(type default)
			)
			(layer "B.Fab")
		)
		(fp_line
			(start 0.299974 -0.150114)
			(end -0.299974 -0.150114)
			(stroke
				(width 0.1)
				(type default)
			)
			(layer "B.Fab")
		)
		(fp_line
			(start 0.299974 0.150114)
			(end 0.299974 -0.150114)
			(stroke
				(width 0.1)
				(type default)
			)
			(layer "B.Fab")
		)
		(pad "1" smd rect
			(at 0.2667 0 180)
			(size 0.3048 0.381)
			(layers "B.Cu" "B.Mask" "B.Paste")
			(net "P12V_NIC3")
		)
		(pad "2" smd rect
			(at -0.2667 0 180)
			(size 0.3048 0.381)
			(layers "B.Cu" "B.Mask" "B.Paste")
			(net "GND")
		)
	)
	(footprint ""
		(layer "B.Cu")
		(at 67.249802 -301.599854 -90)
		(property "Reference" "C1171"
			(at 0 0 90)
			(layer "B.SilkS")
			(hide yes)
			(effects
				(font
					(size 1.27 1.27)
				)
				(justify mirror)
			)
		)
		(property "Value" ""
			(at 0 0 90)
			(layer "B.Fab")
			(effects
				(font
					(size 1.27 1.27)
				)
				(justify mirror)
			)
		)
		(duplicate_pad_numbers_are_jumpers no)
		(fp_line
			(start -0.299974 0.150114)
			(end 0.299974 0.150114)
			(stroke
				(width 0.1)
				(type default)
			)
			(layer "B.Fab")
		)
		(fp_line
			(start 0.299974 0.150114)
			(end 0.299974 -0.150114)
			(stroke
				(width 0.1)
				(type default)
			)
			(layer "B.Fab")
		)
		(fp_line
			(start -0.299974 -0.150114)
			(end -0.299974 0.150114)
			(stroke
				(width 0.1)
				(type default)
			)
			(layer "B.Fab")
		)
		(fp_line
			(start 0.299974 -0.150114)
			(end -0.299974 -0.150114)
			(stroke
				(width 0.1)
				(type default)
			)
			(layer "B.Fab")
		)
		(pad "1" smd rect
			(at 0.2667 0 90)
			(size 0.3048 0.381)
			(layers "B.Cu" "B.Mask" "B.Paste")
			(net "P0V8_SERDES_VDDA_PEX0")
		)
		(pad "2" smd rect
			(at -0.2667 0 90)
			(size 0.3048 0.381)
			(layers "B.Cu" "B.Mask" "B.Paste")
			(net "GND")
		)
	)
	(footprint ""
		(layer "B.Cu")
		(at 162.4457 -295.275)
		(property "Reference" "C3217"
			(at 0 0 0)
			(layer "B.SilkS")
			(hide yes)
			(effects
				(font
					(size 1.27 1.27)
				)
				(justify mirror)
			)
		)
		(property "Value" ""
			(at 0 0 0)
			(layer "B.Fab")
			(effects
				(font
					(size 1.27 1.27)
				)
				(justify mirror)
			)
		)
		(duplicate_pad_numbers_are_jumpers no)
		(fp_line
			(start -0.299974 -0.150114)
			(end -0.299974 0.150114)
			(stroke
				(width 0.1)
				(type default)
			)
			(layer "B.Fab")
		)
		(fp_line
			(start -0.299974 0.150114)
			(end 0.299974 0.150114)
			(stroke
				(width 0.1)
				(type default)
			)
			(layer "B.Fab")
		)
		(fp_line
			(start 0.299974 -0.150114)
			(end -0.299974 -0.150114)
			(stroke
				(width 0.1)
				(type default)
			)
			(layer "B.Fab")
		)
		(fp_line
			(start 0.299974 0.150114)
			(end 0.299974 -0.150114)
			(stroke
				(width 0.1)
				(type default)
			)
			(layer "B.Fab")
		)
		(pad "1" smd rect
			(at 0.2667 0 180)
			(size 0.3048 0.381)
			(layers "B.Cu" "B.Mask" "B.Paste")
			(net "PCEPLL4_VDDA18_PEX1")
		)
		(pad "2" smd rect
			(at -0.2667 0 180)
			(size 0.3048 0.381)
			(layers "B.Cu" "B.Mask" "B.Paste")
			(net "GND")
		)
	)
	(footprint ""
		(layer "B.Cu")
		(at 341.293704 -220.38691 90)
		(property "Reference" "C2067"
			(at 0 0 90)
			(layer "B.SilkS")
			(hide yes)
			(effects
				(font
					(size 1.27 1.27)
				)
				(justify mirror)
			)
		)
		(property "Value" ""
			(at 0 0 90)
			(layer "B.Fab")
			(effects
				(font
					(size 1.27 1.27)
				)
				(justify mirror)
			)
		)
		(duplicate_pad_numbers_are_jumpers no)
		(fp_line
			(start 0.69215 -0.2921)
			(end -0.69215 -0.2921)
			(stroke
				(width 0.1524)
				(type default)
			)
			(layer "B.SilkS")
		)
		(fp_line
			(start -0.69215 -0.2921)
			(end -0.69215 0.2921)
			(stroke
				(width 0.1524)
				(type default)
			)
			(layer "B.SilkS")
		)
		(fp_line
			(start 0.69215 0.2921)
			(end 0.69215 -0.2921)
			(stroke
				(width 0.1524)
				(type default)
			)
			(layer "B.SilkS")
		)
		(fp_line
			(start -0.69215 0.2921)
			(end 0.69215 0.2921)
			(stroke
				(width 0.1524)
				(type default)
			)
			(layer "B.SilkS")
		)
		(fp_line
			(start 0.51435 -0.2794)
			(end -0.51435 -0.2794)
			(stroke
				(width 0.1)
				(type default)
			)
			(layer "B.Fab")
		)
		(fp_line
			(start -0.51435 -0.2794)
			(end -0.51435 0.2794)
			(stroke
				(width 0.1)
				(type default)
			)
			(layer "B.Fab")
		)
		(fp_line
			(start 0.51435 0.2794)
			(end 0.51435 -0.2794)
			(stroke
				(width 0.1)
				(type default)
			)
			(layer "B.Fab")
		)
		(fp_line
			(start -0.51435 0.2794)
			(end 0.51435 0.2794)
			(stroke
				(width 0.1)
				(type default)
			)
			(layer "B.Fab")
		)
		(pad "1" smd circle
			(at 0.40005 0 270)
			(size 0 0)
			(layers "B.Cu" "B.Mask" "B.Paste")
			(net "P3V3_VCC_FPGA_CORE")
		)
		(pad "2" smd circle
			(at -0.40005 0 270)
			(size 0 0)
			(layers "B.Cu" "B.Mask" "B.Paste")
			(net "GND")
		)
		(zone
			(layer "B.Cu")
			(hatch none 0.5)
			(connect_pads
				(clearance 0)
			)
			(min_thickness 0.25)
			(keepout
				(tracks not_allowed)
				(vias allowed)
				(pads allowed)
				(copperpour not_allowed)
				(footprints allowed)
			)
			(placement
				(enabled no)
				(sheetname "")
			)
			(fill
				(thermal_gap 0.5)
				(thermal_bridge_width 0.5)
				(island_removal_mode 0)
			)
			(polygon
				(pts
					(xy 341.381334 -220.57741) (xy 341.4395 -220.48597) (xy 341.4395 -220.28658) (xy 341.381334 -220.19641)
					(xy 341.206074 -220.19641) (xy 341.147654 -220.28658) (xy 341.147654 -220.48597) (xy 341.20582 -220.57741)
				)
			)
		)
	)
	(footprint ""
		(layer "B.Cu")
		(at 169.099992 -292.099746 90)
		(property "Reference" "C1435"
			(at 0 0 90)
			(layer "B.SilkS")
			(hide yes)
			(effects
				(font
					(size 1.27 1.27)
				)
				(justify mirror)
			)
		)
		(property "Value" ""
			(at 0 0 90)
			(layer "B.Fab")
			(effects
				(font
					(size 1.27 1.27)
				)
				(justify mirror)
			)
		)
		(duplicate_pad_numbers_are_jumpers no)
		(fp_line
			(start 0.299974 -0.150114)
			(end -0.299974 -0.150114)
			(stroke
				(width 0.1)
				(type default)
			)
			(layer "B.Fab")
		)
		(fp_line
			(start -0.299974 -0.150114)
			(end -0.299974 0.150114)
			(stroke
				(width 0.1)
				(type default)
			)
			(layer "B.Fab")
		)
		(fp_line
			(start 0.299974 0.150114)
			(end 0.299974 -0.150114)
			(stroke
				(width 0.1)
				(type default)
			)
			(layer "B.Fab")
		)
		(fp_line
			(start -0.299974 0.150114)
			(end 0.299974 0.150114)
			(stroke
				(width 0.1)
				(type default)
			)
			(layer "B.Fab")
		)
		(pad "1" smd rect
			(at 0.2667 0 270)
			(size 0.3048 0.381)
			(layers "B.Cu" "B.Mask" "B.Paste")
			(net "P0V8_SERDES_VDDA_PEX1")
		)
		(pad "2" smd rect
			(at -0.2667 0 270)
			(size 0.3048 0.381)
			(layers "B.Cu" "B.Mask" "B.Paste")
			(net "GND")
		)
	)
	(footprint ""
		(layer "B.Cu")
		(at 58.699908 -301.599854 -90)
		(property "Reference" "C1181"
			(at 0 0 90)
			(layer "B.SilkS")
			(hide yes)
			(effects
				(font
					(size 1.27 1.27)
				)
				(justify mirror)
			)
		)
		(property "Value" ""
			(at 0 0 90)
			(layer "B.Fab")
			(effects
				(font
					(size 1.27 1.27)
				)
				(justify mirror)
			)
		)
		(duplicate_pad_numbers_are_jumpers no)
		(fp_line
			(start -0.299974 0.150114)
			(end 0.299974 0.150114)
			(stroke
				(width 0.1)
				(type default)
			)
			(layer "B.Fab")
		)
		(fp_line
			(start 0.299974 0.150114)
			(end 0.299974 -0.150114)
			(stroke
				(width 0.1)
				(type default)
			)
			(layer "B.Fab")
		)
		(fp_line
			(start -0.299974 -0.150114)
			(end -0.299974 0.150114)
			(stroke
				(width 0.1)
				(type default)
			)
			(layer "B.Fab")
		)
		(fp_line
			(start 0.299974 -0.150114)
			(end -0.299974 -0.150114)
			(stroke
				(width 0.1)
				(type default)
			)
			(layer "B.Fab")
		)
		(pad "1" smd rect
			(at 0.2667 0 90)
			(size 0.3048 0.381)
			(layers "B.Cu" "B.Mask" "B.Paste")
			(net "P0V8_SERDES_VDDA_PEX0")
		)
		(pad "2" smd rect
			(at -0.2667 0 90)
			(size 0.3048 0.381)
			(layers "B.Cu" "B.Mask" "B.Paste")
			(net "GND")
		)
	)
	(footprint ""
		(layer "B.Cu")
		(at 225.530664 -204.44206 90)
		(property "Reference" "R5475"
			(at 0 0 90)
			(layer "B.SilkS")
			(hide yes)
			(effects
				(font
					(size 1.27 1.27)
				)
				(justify mirror)
			)
		)
		(property "Value" ""
			(at 0 0 90)
			(layer "B.Fab")
			(effects
				(font
					(size 1.27 1.27)
				)
				(justify mirror)
			)
		)
		(duplicate_pad_numbers_are_jumpers no)
		(fp_line
			(start 0.7874 -0.4064)
			(end -0.7874 -0.4064)
			(stroke
				(width 0.1524)
				(type default)
			)
			(layer "B.SilkS")
		)
		(fp_line
			(start -0.7874 -0.4064)
			(end -0.7874 0.4064)
			(stroke
				(width 0.1524)
				(type default)
			)
			(layer "B.SilkS")
		)
		(fp_line
			(start 0.7874 0.4064)
			(end 0.7874 -0.4064)
			(stroke
				(width 0.1524)
				(type default)
			)
			(layer "B.SilkS")
		)
		(fp_line
			(start -0.7874 0.4064)
			(end 0.7874 0.4064)
			(stroke
				(width 0.1524)
				(type default)
			)
			(layer "B.SilkS")
		)
		(fp_line
			(start 0.67945 -0.305054)
			(end 0.12065 -0.305054)
			(stroke
				(width 0.1)
				(type default)
			)
			(layer "B.Fab")
		)
		(fp_line
			(start 0.12065 -0.305054)
			(end 0.12065 -0.2794)
			(stroke
				(width 0.1)
				(type default)
			)
			(layer "B.Fab")
		)
		(fp_line
			(start -0.12065 -0.3048)
			(end -0.67945 -0.3048)
			(stroke
				(width 0.1)
				(type default)
			)
			(layer "B.Fab")
		)
		(fp_line
			(start -0.67945 -0.3048)
			(end -0.67945 0.3048)
			(stroke
				(width 0.1)
				(type default)
			)
			(layer "B.Fab")
		)
		(fp_line
			(start 0.12065 -0.2794)
			(end -0.12065 -0.2794)
			(stroke
				(width 0.1)
				(type default)
			)
			(layer "B.Fab")
		)
		(fp_line
			(start -0.12065 -0.2794)
			(end -0.12065 -0.3048)
			(stroke
				(width 0.1)
				(type default)
			)
			(layer "B.Fab")
		)
		(fp_line
			(start 0.12065 0.2794)
			(end 0.12065 0.3048)
			(stroke
				(width 0.1)
				(type default)
			)
			(layer "B.Fab")
		)
		(fp_line
			(start -0.120396 0.2794)
			(end 0.12065 0.2794)
			(stroke
				(width 0.1)
				(type default)
			)
			(layer "B.Fab")
		)
		(fp_line
			(start 0.67945 0.3048)
			(end 0.67945 -0.305054)
			(stroke
				(width 0.1)
				(type default)
			)
			(layer "B.Fab")
		)
		(fp_line
			(start 0.12065 0.3048)
			(end 0.67945 0.3048)
			(stroke
				(width 0.1)
				(type default)
			)
			(layer "B.Fab")
		)
		(fp_line
			(start -0.120396 0.3048)
			(end -0.120396 0.2794)
			(stroke
				(width 0.1)
				(type default)
			)
			(layer "B.Fab")
		)
		(fp_line
			(start -0.67945 0.3048)
			(end -0.120396 0.3048)
			(stroke
				(width 0.1)
				(type default)
			)
			(layer "B.Fab")
		)
		(pad "1" smd circle
			(at 0.40005 0 270)
			(size 0 0)
			(layers "B.Cu" "B.Mask" "B.Paste")
			(net "RST_SMB_FIO_R_N")
		)
		(pad "2" smd circle
			(at -0.40005 0 270)
			(size 0 0)
			(layers "B.Cu" "B.Mask" "B.Paste")
			(net "P3V3_AUX")
		)
	)
	(footprint ""
		(layer "B.Cu")
		(at 421.700198 -111.791496)
		(property "Reference" "C952"
			(at 0 0 0)
			(layer "B.SilkS")
			(hide yes)
			(effects
				(font
					(size 1.27 1.27)
				)
				(justify mirror)
			)
		)
		(property "Value" ""
			(at 0 0 0)
			(layer "B.Fab")
			(effects
				(font
					(size 1.27 1.27)
				)
				(justify mirror)
			)
		)
		(duplicate_pad_numbers_are_jumpers no)
		(fp_line
			(start -0.299974 -0.150114)
			(end -0.299974 0.150114)
			(stroke
				(width 0.1)
				(type default)
			)
			(layer "B.Fab")
		)
		(fp_line
			(start -0.299974 0.150114)
			(end 0.299974 0.150114)
			(stroke
				(width 0.1)
				(type default)
			)
			(layer "B.Fab")
		)
		(fp_line
			(start 0.299974 -0.150114)
			(end -0.299974 -0.150114)
			(stroke
				(width 0.1)
				(type default)
			)
			(layer "B.Fab")
		)
		(fp_line
			(start 0.299974 0.150114)
			(end 0.299974 -0.150114)
			(stroke
				(width 0.1)
				(type default)
			)
			(layer "B.Fab")
		)
		(pad "1" smd rect
			(at 0.2667 0 180)
			(size 0.3048 0.381)
			(layers "B.Cu" "B.Mask" "B.Paste")
			(net "P12V_NIC7")
		)
		(pad "2" smd rect
			(at -0.2667 0 180)
			(size 0.3048 0.381)
			(layers "B.Cu" "B.Mask" "B.Paste")
			(net "GND")
		)
	)
	(footprint ""
		(layer "B.Cu")
		(at 217.235786 -214.238586 180)
		(property "Reference" "R5290"
			(at 0 0 0)
			(layer "B.SilkS")
			(hide yes)
			(effects
				(font
					(size 1.27 1.27)
				)
				(justify mirror)
			)
		)
		(property "Value" ""
			(at 0 0 0)
			(layer "B.Fab")
			(effects
				(font
					(size 1.27 1.27)
				)
				(justify mirror)
			)
		)
		(duplicate_pad_numbers_are_jumpers no)
		(fp_line
			(start 0.7874 0.4064)
			(end 0.7874 -0.4064)
			(stroke
				(width 0.1524)
				(type default)
			)
			(layer "B.SilkS")
		)
		(fp_line
			(start 0.7874 -0.4064)
			(end -0.7874 -0.4064)
			(stroke
				(width 0.1524)
				(type default)
			)
			(layer "B.SilkS")
		)
		(fp_line
			(start -0.7874 0.4064)
			(end 0.7874 0.4064)
			(stroke
				(width 0.1524)
				(type default)
			)
			(layer "B.SilkS")
		)
		(fp_line
			(start -0.7874 -0.4064)
			(end -0.7874 0.4064)
			(stroke
				(width 0.1524)
				(type default)
			)
			(layer "B.SilkS")
		)
		(fp_line
			(start 0.67945 0.3048)
			(end 0.67945 -0.305054)
			(stroke
				(width 0.1)
				(type default)
			)
			(layer "B.Fab")
		)
		(fp_line
			(start 0.67945 -0.305054)
			(end 0.12065 -0.305054)
			(stroke
				(width 0.1)
				(type default)
			)
			(layer "B.Fab")
		)
		(fp_line
			(start 0.12065 0.3048)
			(end 0.67945 0.3048)
			(stroke
				(width 0.1)
				(type default)
			)
			(layer "B.Fab")
		)
		(fp_line
			(start 0.12065 0.2794)
			(end 0.12065 0.3048)
			(stroke
				(width 0.1)
				(type default)
			)
			(layer "B.Fab")
		)
		(fp_line
			(start 0.12065 -0.2794)
			(end -0.12065 -0.2794)
			(stroke
				(width 0.1)
				(type default)
			)
			(layer "B.Fab")
		)
		(fp_line
			(start 0.12065 -0.305054)
			(end 0.12065 -0.2794)
			(stroke
				(width 0.1)
				(type default)
			)
			(layer "B.Fab")
		)
		(fp_line
			(start -0.120396 0.3048)
			(end -0.120396 0.2794)
			(stroke
				(width 0.1)
				(type default)
			)
			(layer "B.Fab")
		)
		(fp_line
			(start -0.120396 0.2794)
			(end 0.12065 0.2794)
			(stroke
				(width 0.1)
				(type default)
			)
			(layer "B.Fab")
		)
		(fp_line
			(start -0.12065 -0.2794)
			(end -0.12065 -0.3048)
			(stroke
				(width 0.1)
				(type default)
			)
			(layer "B.Fab")
		)
		(fp_line
			(start -0.12065 -0.3048)
			(end -0.67945 -0.3048)
			(stroke
				(width 0.1)
				(type default)
			)
			(layer "B.Fab")
		)
		(fp_line
			(start -0.67945 0.3048)
			(end -0.120396 0.3048)
			(stroke
				(width 0.1)
				(type default)
			)
			(layer "B.Fab")
		)
		(fp_line
			(start -0.67945 -0.3048)
			(end -0.67945 0.3048)
			(stroke
				(width 0.1)
				(type default)
			)
			(layer "B.Fab")
		)
		(pad "1" smd circle
			(at 0.40005 0)
			(size 0 0)
			(layers "B.Cu" "B.Mask" "B.Paste")
			(net "RST_BIC_SELF_HW_RST_R_N")
		)
		(pad "2" smd circle
			(at -0.40005 0)
			(size 0 0)
			(layers "B.Cu" "B.Mask" "B.Paste")
			(net "RST_BIC_SELF_HW_RST_N")
		)
	)
	(footprint ""
		(layer "B.Cu")
		(at 278.554942 -294.4749)
		(property "Reference" "C3392"
			(at 0 0 0)
			(layer "B.SilkS")
			(hide yes)
			(effects
				(font
					(size 1.27 1.27)
				)
				(justify mirror)
			)
		)
		(property "Value" ""
			(at 0 0 0)
			(layer "B.Fab")
			(effects
				(font
					(size 1.27 1.27)
				)
				(justify mirror)
			)
		)
		(duplicate_pad_numbers_are_jumpers no)
		(fp_line
			(start -0.299974 -0.150114)
			(end -0.299974 0.150114)
			(stroke
				(width 0.1)
				(type default)
			)
			(layer "B.Fab")
		)
		(fp_line
			(start -0.299974 0.150114)
			(end 0.299974 0.150114)
			(stroke
				(width 0.1)
				(type default)
			)
			(layer "B.Fab")
		)
		(fp_line
			(start 0.299974 -0.150114)
			(end -0.299974 -0.150114)
			(stroke
				(width 0.1)
				(type default)
			)
			(layer "B.Fab")
		)
		(fp_line
			(start 0.299974 0.150114)
			(end 0.299974 -0.150114)
			(stroke
				(width 0.1)
				(type default)
			)
			(layer "B.Fab")
		)
		(pad "1" smd rect
			(at 0.2667 0 180)
			(size 0.3048 0.381)
			(layers "B.Cu" "B.Mask" "B.Paste")
			(net "PCEPLL4_VDDA18_PEX2")
		)
		(pad "2" smd rect
			(at -0.2667 0 180)
			(size 0.3048 0.381)
			(layers "B.Cu" "B.Mask" "B.Paste")
			(net "GND")
		)
	)
	(footprint ""
		(layer "B.Cu")
		(at 268.102334 -364.97895 90)
		(property "Reference" "PR6612"
			(at 0 0 90)
			(layer "B.SilkS")
			(hide yes)
			(effects
				(font
					(size 1.27 1.27)
				)
				(justify mirror)
			)
		)
		(property "Value" ""
			(at 0 0 90)
			(layer "B.Fab")
			(effects
				(font
					(size 1.27 1.27)
				)
				(justify mirror)
			)
		)
		(duplicate_pad_numbers_are_jumpers no)
		(fp_line
			(start 0.7874 -0.4064)
			(end -0.7874 -0.4064)
			(stroke
				(width 0.1524)
				(type default)
			)
			(layer "B.SilkS")
		)
		(fp_line
			(start -0.7874 -0.4064)
			(end -0.7874 0.4064)
			(stroke
				(width 0.1524)
				(type default)
			)
			(layer "B.SilkS")
		)
		(fp_line
			(start 0.7874 0.4064)
			(end 0.7874 -0.4064)
			(stroke
				(width 0.1524)
				(type default)
			)
			(layer "B.SilkS")
		)
		(fp_line
			(start -0.7874 0.4064)
			(end 0.7874 0.4064)
			(stroke
				(width 0.1524)
				(type default)
			)
			(layer "B.SilkS")
		)
		(fp_line
			(start 0.67945 -0.305054)
			(end 0.12065 -0.305054)
			(stroke
				(width 0.1)
				(type default)
			)
			(layer "B.Fab")
		)
		(fp_line
			(start 0.12065 -0.305054)
			(end 0.12065 -0.2794)
			(stroke
				(width 0.1)
				(type default)
			)
			(layer "B.Fab")
		)
		(fp_line
			(start -0.12065 -0.3048)
			(end -0.67945 -0.3048)
			(stroke
				(width 0.1)
				(type default)
			)
			(layer "B.Fab")
		)
		(fp_line
			(start -0.67945 -0.3048)
			(end -0.67945 0.3048)
			(stroke
				(width 0.1)
				(type default)
			)
			(layer "B.Fab")
		)
		(fp_line
			(start 0.12065 -0.2794)
			(end -0.12065 -0.2794)
			(stroke
				(width 0.1)
				(type default)
			)
			(layer "B.Fab")
		)
		(fp_line
			(start -0.12065 -0.2794)
			(end -0.12065 -0.3048)
			(stroke
				(width 0.1)
				(type default)
			)
			(layer "B.Fab")
		)
		(fp_line
			(start 0.12065 0.2794)
			(end 0.12065 0.3048)
			(stroke
				(width 0.1)
				(type default)
			)
			(layer "B.Fab")
		)
		(fp_line
			(start -0.120396 0.2794)
			(end 0.12065 0.2794)
			(stroke
				(width 0.1)
				(type default)
			)
			(layer "B.Fab")
		)
		(fp_line
			(start 0.67945 0.3048)
			(end 0.67945 -0.305054)
			(stroke
				(width 0.1)
				(type default)
			)
			(layer "B.Fab")
		)
		(fp_line
			(start 0.12065 0.3048)
			(end 0.67945 0.3048)
			(stroke
				(width 0.1)
				(type default)
			)
			(layer "B.Fab")
		)
		(fp_line
			(start -0.120396 0.3048)
			(end -0.120396 0.2794)
			(stroke
				(width 0.1)
				(type default)
			)
			(layer "B.Fab")
		)
		(fp_line
			(start -0.67945 0.3048)
			(end -0.120396 0.3048)
			(stroke
				(width 0.1)
				(type default)
			)
			(layer "B.Fab")
		)
		(pad "1" smd circle
			(at 0.40005 0 270)
			(size 0 0)
			(layers "B.Cu" "B.Mask" "B.Paste")
			(net "P12V_HSC_GATE_RC")
		)
		(pad "2" smd circle
			(at -0.40005 0 270)
			(size 0 0)
			(layers "B.Cu" "B.Mask" "B.Paste")
			(net "P12V_AUX")
		)
	)
	(footprint ""
		(layer "B.Cu")
		(at 13.472668 -284.2514 180)
		(property "Reference" "PC212"
			(at 0 0 0)
			(layer "B.SilkS")
			(hide yes)
			(effects
				(font
					(size 1.27 1.27)
				)
				(justify mirror)
			)
		)
		(property "Value" ""
			(at 0 0 0)
			(layer "B.Fab")
			(effects
				(font
					(size 1.27 1.27)
				)
				(justify mirror)
			)
		)
		(duplicate_pad_numbers_are_jumpers no)
		(fp_line
			(start 1.524 0.762)
			(end 1.524 -0.762)
			(stroke
				(width 0.1524)
				(type default)
			)
			(layer "B.SilkS")
		)
		(fp_line
			(start 1.524 -0.762)
			(end -1.524 -0.762)
			(stroke
				(width 0.1524)
				(type default)
			)
			(layer "B.SilkS")
		)
		(fp_line
			(start -1.524 0.762)
			(end 1.524 0.762)
			(stroke
				(width 0.1524)
				(type default)
			)
			(layer "B.SilkS")
		)
		(fp_line
			(start -1.524 -0.762)
			(end -1.524 0.762)
			(stroke
				(width 0.1524)
				(type default)
			)
			(layer "B.SilkS")
		)
		(fp_line
			(start 1.1049 0.724916)
			(end -1.1049 0.724916)
			(stroke
				(width 0.1)
				(type default)
			)
			(layer "B.Fab")
		)
		(fp_line
			(start 1.1049 -0.724916)
			(end 1.1049 0.724916)
			(stroke
				(width 0.1)
				(type default)
			)
			(layer "B.Fab")
		)
		(fp_line
			(start -1.1049 0.724916)
			(end -1.1049 -0.724916)
			(stroke
				(width 0.1)
				(type default)
			)
			(layer "B.Fab")
		)
		(fp_line
			(start -1.1049 -0.724916)
			(end 1.1049 -0.724916)
			(stroke
				(width 0.1)
				(type default)
			)
			(layer "B.Fab")
		)
		(pad "1" smd rect
			(at 0.889 0 180)
			(size 1.016 1.27)
			(layers "B.Cu" "B.Mask" "B.Paste")
			(net "P1V25_PEX0_R")
		)
		(pad "2" smd rect
			(at -0.889 0 180)
			(size 1.016 1.27)
			(layers "B.Cu" "B.Mask" "B.Paste")
			(net "GND")
		)
	)
	(footprint ""
		(layer "B.Cu")
		(at 60.599828 -301.599854 -90)
		(property "Reference" "C1226"
			(at 0 0 90)
			(layer "B.SilkS")
			(hide yes)
			(effects
				(font
					(size 1.27 1.27)
				)
				(justify mirror)
			)
		)
		(property "Value" ""
			(at 0 0 90)
			(layer "B.Fab")
			(effects
				(font
					(size 1.27 1.27)
				)
				(justify mirror)
			)
		)
		(duplicate_pad_numbers_are_jumpers no)
		(fp_line
			(start -0.299974 0.150114)
			(end 0.299974 0.150114)
			(stroke
				(width 0.1)
				(type default)
			)
			(layer "B.Fab")
		)
		(fp_line
			(start 0.299974 0.150114)
			(end 0.299974 -0.150114)
			(stroke
				(width 0.1)
				(type default)
			)
			(layer "B.Fab")
		)
		(fp_line
			(start -0.299974 -0.150114)
			(end -0.299974 0.150114)
			(stroke
				(width 0.1)
				(type default)
			)
			(layer "B.Fab")
		)
		(fp_line
			(start 0.299974 -0.150114)
			(end -0.299974 -0.150114)
			(stroke
				(width 0.1)
				(type default)
			)
			(layer "B.Fab")
		)
		(pad "1" smd rect
			(at 0.2667 0 90)
			(size 0.3048 0.381)
			(layers "B.Cu" "B.Mask" "B.Paste")
			(net "P0V8_SERDES_VDDA_PEX0")
		)
		(pad "2" smd rect
			(at -0.2667 0 90)
			(size 0.3048 0.381)
			(layers "B.Cu" "B.Mask" "B.Paste")
			(net "GND")
		)
	)
	(footprint ""
		(layer "B.Cu")
		(at 24.711406 -222.299276 180)
		(property "Reference" "C2217"
			(at 0 0 0)
			(layer "B.SilkS")
			(hide yes)
			(effects
				(font
					(size 1.27 1.27)
				)
				(justify mirror)
			)
		)
		(property "Value" ""
			(at 0 0 0)
			(layer "B.Fab")
			(effects
				(font
					(size 1.27 1.27)
				)
				(justify mirror)
			)
		)
		(duplicate_pad_numbers_are_jumpers no)
		(fp_line
			(start 0.7874 0.4064)
			(end 0.7874 -0.4064)
			(stroke
				(width 0.1524)
				(type default)
			)
			(layer "B.SilkS")
		)
		(fp_line
			(start 0.7874 -0.4064)
			(end -0.7874 -0.4064)
			(stroke
				(width 0.1524)
				(type default)
			)
			(layer "B.SilkS")
		)
		(fp_line
			(start -0.7874 0.4064)
			(end 0.7874 0.4064)
			(stroke
				(width 0.1524)
				(type default)
			)
			(layer "B.SilkS")
		)
		(fp_line
			(start -0.7874 -0.4064)
			(end -0.7874 0.4064)
			(stroke
				(width 0.1524)
				(type default)
			)
			(layer "B.SilkS")
		)
		(fp_line
			(start 0.67945 0.3048)
			(end 0.67945 -0.305054)
			(stroke
				(width 0.1)
				(type default)
			)
			(layer "B.Fab")
		)
		(fp_line
			(start 0.67945 -0.305054)
			(end 0.12065 -0.305054)
			(stroke
				(width 0.1)
				(type default)
			)
			(layer "B.Fab")
		)
		(fp_line
			(start 0.12065 0.3048)
			(end 0.67945 0.3048)
			(stroke
				(width 0.1)
				(type default)
			)
			(layer "B.Fab")
		)
		(fp_line
			(start 0.12065 0.2794)
			(end 0.12065 0.3048)
			(stroke
				(width 0.1)
				(type default)
			)
			(layer "B.Fab")
		)
		(fp_line
			(start 0.12065 -0.2794)
			(end -0.12065 -0.2794)
			(stroke
				(width 0.1)
				(type default)
			)
			(layer "B.Fab")
		)
		(fp_line
			(start 0.12065 -0.305054)
			(end 0.12065 -0.2794)
			(stroke
				(width 0.1)
				(type default)
			)
			(layer "B.Fab")
		)
		(fp_line
			(start -0.120396 0.3048)
			(end -0.120396 0.2794)
			(stroke
				(width 0.1)
				(type default)
			)
			(layer "B.Fab")
		)
		(fp_line
			(start -0.120396 0.2794)
			(end 0.12065 0.2794)
			(stroke
				(width 0.1)
				(type default)
			)
			(layer "B.Fab")
		)
		(fp_line
			(start -0.12065 -0.2794)
			(end -0.12065 -0.3048)
			(stroke
				(width 0.1)
				(type default)
			)
			(layer "B.Fab")
		)
		(fp_line
			(start -0.12065 -0.3048)
			(end -0.67945 -0.3048)
			(stroke
				(width 0.1)
				(type default)
			)
			(layer "B.Fab")
		)
		(fp_line
			(start -0.67945 0.3048)
			(end -0.120396 0.3048)
			(stroke
				(width 0.1)
				(type default)
			)
			(layer "B.Fab")
		)
		(fp_line
			(start -0.67945 -0.3048)
			(end -0.67945 0.3048)
			(stroke
				(width 0.1)
				(type default)
			)
			(layer "B.Fab")
		)
		(pad "1" smd circle
			(at 0.40005 0)
			(size 0 0)
			(layers "B.Cu" "B.Mask" "B.Paste")
			(net "GND")
		)
		(pad "2" smd circle
			(at -0.40005 0)
			(size 0 0)
			(layers "B.Cu" "B.Mask" "B.Paste")
			(net "P1V8_PEX")
		)
	)
	(footprint ""
		(layer "B.Cu")
		(at 69.624956 -305.608228 -90)
		(property "Reference" "C2998"
			(at 0 0 90)
			(layer "B.SilkS")
			(hide yes)
			(effects
				(font
					(size 1.27 1.27)
				)
				(justify mirror)
			)
		)
		(property "Value" ""
			(at 0 0 90)
			(layer "B.Fab")
			(effects
				(font
					(size 1.27 1.27)
				)
				(justify mirror)
			)
		)
		(duplicate_pad_numbers_are_jumpers no)
		(fp_line
			(start -0.299974 0.150114)
			(end 0.299974 0.150114)
			(stroke
				(width 0.1)
				(type default)
			)
			(layer "B.Fab")
		)
		(fp_line
			(start 0.299974 0.150114)
			(end 0.299974 -0.150114)
			(stroke
				(width 0.1)
				(type default)
			)
			(layer "B.Fab")
		)
		(fp_line
			(start -0.299974 -0.150114)
			(end -0.299974 0.150114)
			(stroke
				(width 0.1)
				(type default)
			)
			(layer "B.Fab")
		)
		(fp_line
			(start 0.299974 -0.150114)
			(end -0.299974 -0.150114)
			(stroke
				(width 0.1)
				(type default)
			)
			(layer "B.Fab")
		)
		(pad "1" smd rect
			(at 0.2667 0 90)
			(size 0.3048 0.381)
			(layers "B.Cu" "B.Mask" "B.Paste")
			(net "P1V8_VDDA_PEX0")
		)
		(pad "2" smd rect
			(at -0.2667 0 90)
			(size 0.3048 0.381)
			(layers "B.Cu" "B.Mask" "B.Paste")
			(net "GND")
		)
	)
	(footprint ""
		(layer "B.Cu")
		(at 128.241044 -180.02377)
		(property "Reference" "R1124"
			(at 0 0 0)
			(layer "B.SilkS")
			(hide yes)
			(effects
				(font
					(size 1.27 1.27)
				)
				(justify mirror)
			)
		)
		(property "Value" ""
			(at 0 0 0)
			(layer "B.Fab")
			(effects
				(font
					(size 1.27 1.27)
				)
				(justify mirror)
			)
		)
		(duplicate_pad_numbers_are_jumpers no)
		(fp_line
			(start -0.7874 -0.4064)
			(end -0.7874 0.4064)
			(stroke
				(width 0.1524)
				(type default)
			)
			(layer "B.SilkS")
		)
		(fp_line
			(start -0.7874 0.4064)
			(end 0.7874 0.4064)
			(stroke
				(width 0.1524)
				(type default)
			)
			(layer "B.SilkS")
		)
		(fp_line
			(start 0.7874 -0.4064)
			(end -0.7874 -0.4064)
			(stroke
				(width 0.1524)
				(type default)
			)
			(layer "B.SilkS")
		)
		(fp_line
			(start 0.7874 0.4064)
			(end 0.7874 -0.4064)
			(stroke
				(width 0.1524)
				(type default)
			)
			(layer "B.SilkS")
		)
		(fp_line
			(start -0.67945 -0.3048)
			(end -0.67945 0.3048)
			(stroke
				(width 0.1)
				(type default)
			)
			(layer "B.Fab")
		)
		(fp_line
			(start -0.67945 0.3048)
			(end -0.120396 0.3048)
			(stroke
				(width 0.1)
				(type default)
			)
			(layer "B.Fab")
		)
		(fp_line
			(start -0.12065 -0.3048)
			(end -0.67945 -0.3048)
			(stroke
				(width 0.1)
				(type default)
			)
			(layer "B.Fab")
		)
		(fp_line
			(start -0.12065 -0.2794)
			(end -0.12065 -0.3048)
			(stroke
				(width 0.1)
				(type default)
			)
			(layer "B.Fab")
		)
		(fp_line
			(start -0.120396 0.2794)
			(end 0.12065 0.2794)
			(stroke
				(width 0.1)
				(type default)
			)
			(layer "B.Fab")
		)
		(fp_line
			(start -0.120396 0.3048)
			(end -0.120396 0.2794)
			(stroke
				(width 0.1)
				(type default)
			)
			(layer "B.Fab")
		)
		(fp_line
			(start 0.12065 -0.305054)
			(end 0.12065 -0.2794)
			(stroke
				(width 0.1)
				(type default)
			)
			(layer "B.Fab")
		)
		(fp_line
			(start 0.12065 -0.2794)
			(end -0.12065 -0.2794)
			(stroke
				(width 0.1)
				(type default)
			)
			(layer "B.Fab")
		)
		(fp_line
			(start 0.12065 0.2794)
			(end 0.12065 0.3048)
			(stroke
				(width 0.1)
				(type default)
			)
			(layer "B.Fab")
		)
		(fp_line
			(start 0.12065 0.3048)
			(end 0.67945 0.3048)
			(stroke
				(width 0.1)
				(type default)
			)
			(layer "B.Fab")
		)
		(fp_line
			(start 0.67945 -0.305054)
			(end 0.12065 -0.305054)
			(stroke
				(width 0.1)
				(type default)
			)
			(layer "B.Fab")
		)
		(fp_line
			(start 0.67945 0.3048)
			(end 0.67945 -0.305054)
			(stroke
				(width 0.1)
				(type default)
			)
			(layer "B.Fab")
		)
		(pad "1" smd circle
			(at 0.40005 0 180)
			(size 0 0)
			(layers "B.Cu" "B.Mask" "B.Paste")
			(net "FM_DB2000QL_VSBEN")
		)
		(pad "2" smd circle
			(at -0.40005 0 180)
			(size 0 0)
			(layers "B.Cu" "B.Mask" "B.Paste")
			(net "P3V3")
		)
	)
	(footprint ""
		(layer "B.Cu")
		(at 180.975 -293.99992 90)
		(property "Reference" "C1409"
			(at 0 0 90)
			(layer "B.SilkS")
			(hide yes)
			(effects
				(font
					(size 1.27 1.27)
				)
				(justify mirror)
			)
		)
		(property "Value" ""
			(at 0 0 90)
			(layer "B.Fab")
			(effects
				(font
					(size 1.27 1.27)
				)
				(justify mirror)
			)
		)
		(duplicate_pad_numbers_are_jumpers no)
		(fp_line
			(start 0.299974 -0.150114)
			(end -0.299974 -0.150114)
			(stroke
				(width 0.1)
				(type default)
			)
			(layer "B.Fab")
		)
		(fp_line
			(start -0.299974 -0.150114)
			(end -0.299974 0.150114)
			(stroke
				(width 0.1)
				(type default)
			)
			(layer "B.Fab")
		)
		(fp_line
			(start 0.299974 0.150114)
			(end 0.299974 -0.150114)
			(stroke
				(width 0.1)
				(type default)
			)
			(layer "B.Fab")
		)
		(fp_line
			(start -0.299974 0.150114)
			(end 0.299974 0.150114)
			(stroke
				(width 0.1)
				(type default)
			)
			(layer "B.Fab")
		)
		(pad "1" smd rect
			(at 0.2667 0 270)
			(size 0.3048 0.381)
			(layers "B.Cu" "B.Mask" "B.Paste")
			(net "P0V8_PEX1")
		)
		(pad "2" smd rect
			(at -0.2667 0 270)
			(size 0.3048 0.381)
			(layers "B.Cu" "B.Mask" "B.Paste")
			(net "GND")
		)
	)
	(footprint ""
		(layer "B.Cu")
		(at 309.741824 -97.005648 180)
		(property "Reference" "R267"
			(at 0 0 0)
			(layer "B.SilkS")
			(hide yes)
			(effects
				(font
					(size 1.27 1.27)
				)
				(justify mirror)
			)
		)
		(property "Value" ""
			(at 0 0 0)
			(layer "B.Fab")
			(effects
				(font
					(size 1.27 1.27)
				)
				(justify mirror)
			)
		)
		(duplicate_pad_numbers_are_jumpers no)
		(fp_line
			(start 0.7874 0.4064)
			(end 0.7874 -0.4064)
			(stroke
				(width 0.1524)
				(type default)
			)
			(layer "B.SilkS")
		)
		(fp_line
			(start 0.7874 -0.4064)
			(end -0.7874 -0.4064)
			(stroke
				(width 0.1524)
				(type default)
			)
			(layer "B.SilkS")
		)
		(fp_line
			(start -0.7874 0.4064)
			(end 0.7874 0.4064)
			(stroke
				(width 0.1524)
				(type default)
			)
			(layer "B.SilkS")
		)
		(fp_line
			(start -0.7874 -0.4064)
			(end -0.7874 0.4064)
			(stroke
				(width 0.1524)
				(type default)
			)
			(layer "B.SilkS")
		)
		(fp_line
			(start 0.67945 0.3048)
			(end 0.67945 -0.305054)
			(stroke
				(width 0.1)
				(type default)
			)
			(layer "B.Fab")
		)
		(fp_line
			(start 0.67945 -0.305054)
			(end 0.12065 -0.305054)
			(stroke
				(width 0.1)
				(type default)
			)
			(layer "B.Fab")
		)
		(fp_line
			(start 0.12065 0.3048)
			(end 0.67945 0.3048)
			(stroke
				(width 0.1)
				(type default)
			)
			(layer "B.Fab")
		)
		(fp_line
			(start 0.12065 0.2794)
			(end 0.12065 0.3048)
			(stroke
				(width 0.1)
				(type default)
			)
			(layer "B.Fab")
		)
		(fp_line
			(start 0.12065 -0.2794)
			(end -0.12065 -0.2794)
			(stroke
				(width 0.1)
				(type default)
			)
			(layer "B.Fab")
		)
		(fp_line
			(start 0.12065 -0.305054)
			(end 0.12065 -0.2794)
			(stroke
				(width 0.1)
				(type default)
			)
			(layer "B.Fab")
		)
		(fp_line
			(start -0.120396 0.3048)
			(end -0.120396 0.2794)
			(stroke
				(width 0.1)
				(type default)
			)
			(layer "B.Fab")
		)
		(fp_line
			(start -0.120396 0.2794)
			(end 0.12065 0.2794)
			(stroke
				(width 0.1)
				(type default)
			)
			(layer "B.Fab")
		)
		(fp_line
			(start -0.12065 -0.2794)
			(end -0.12065 -0.3048)
			(stroke
				(width 0.1)
				(type default)
			)
			(layer "B.Fab")
		)
		(fp_line
			(start -0.12065 -0.3048)
			(end -0.67945 -0.3048)
			(stroke
				(width 0.1)
				(type default)
			)
			(layer "B.Fab")
		)
		(fp_line
			(start -0.67945 0.3048)
			(end -0.120396 0.3048)
			(stroke
				(width 0.1)
				(type default)
			)
			(layer "B.Fab")
		)
		(fp_line
			(start -0.67945 -0.3048)
			(end -0.67945 0.3048)
			(stroke
				(width 0.1)
				(type default)
			)
			(layer "B.Fab")
		)
		(pad "1" smd circle
			(at 0.40005 0)
			(size 0 0)
			(layers "B.Cu" "B.Mask" "B.Paste")
			(net "NIC5_DATA_IN")
		)
		(pad "2" smd circle
			(at -0.40005 0)
			(size 0 0)
			(layers "B.Cu" "B.Mask" "B.Paste")
			(net "P3V3_NIC5")
		)
	)
	(footprint ""
		(layer "B.Cu")
		(at 100.154994 -331.03185 180)
		(property "Reference" "R1228"
			(at 0 0 0)
			(layer "B.SilkS")
			(hide yes)
			(effects
				(font
					(size 1.27 1.27)
				)
				(justify mirror)
			)
		)
		(property "Value" ""
			(at 0 0 0)
			(layer "B.Fab")
			(effects
				(font
					(size 1.27 1.27)
				)
				(justify mirror)
			)
		)
		(duplicate_pad_numbers_are_jumpers no)
		(fp_line
			(start 0.7874 0.4064)
			(end 0.7874 -0.4064)
			(stroke
				(width 0.1524)
				(type default)
			)
			(layer "B.SilkS")
		)
		(fp_line
			(start 0.7874 -0.4064)
			(end -0.7874 -0.4064)
			(stroke
				(width 0.1524)
				(type default)
			)
			(layer "B.SilkS")
		)
		(fp_line
			(start -0.7874 0.4064)
			(end 0.7874 0.4064)
			(stroke
				(width 0.1524)
				(type default)
			)
			(layer "B.SilkS")
		)
		(fp_line
			(start -0.7874 -0.4064)
			(end -0.7874 0.4064)
			(stroke
				(width 0.1524)
				(type default)
			)
			(layer "B.SilkS")
		)
		(fp_line
			(start 0.67945 0.3048)
			(end 0.67945 -0.305054)
			(stroke
				(width 0.1)
				(type default)
			)
			(layer "B.Fab")
		)
		(fp_line
			(start 0.67945 -0.305054)
			(end 0.12065 -0.305054)
			(stroke
				(width 0.1)
				(type default)
			)
			(layer "B.Fab")
		)
		(fp_line
			(start 0.12065 0.3048)
			(end 0.67945 0.3048)
			(stroke
				(width 0.1)
				(type default)
			)
			(layer "B.Fab")
		)
		(fp_line
			(start 0.12065 0.2794)
			(end 0.12065 0.3048)
			(stroke
				(width 0.1)
				(type default)
			)
			(layer "B.Fab")
		)
		(fp_line
			(start 0.12065 -0.2794)
			(end -0.12065 -0.2794)
			(stroke
				(width 0.1)
				(type default)
			)
			(layer "B.Fab")
		)
		(fp_line
			(start 0.12065 -0.305054)
			(end 0.12065 -0.2794)
			(stroke
				(width 0.1)
				(type default)
			)
			(layer "B.Fab")
		)
		(fp_line
			(start -0.120396 0.3048)
			(end -0.120396 0.2794)
			(stroke
				(width 0.1)
				(type default)
			)
			(layer "B.Fab")
		)
		(fp_line
			(start -0.120396 0.2794)
			(end 0.12065 0.2794)
			(stroke
				(width 0.1)
				(type default)
			)
			(layer "B.Fab")
		)
		(fp_line
			(start -0.12065 -0.2794)
			(end -0.12065 -0.3048)
			(stroke
				(width 0.1)
				(type default)
			)
			(layer "B.Fab")
		)
		(fp_line
			(start -0.12065 -0.3048)
			(end -0.67945 -0.3048)
			(stroke
				(width 0.1)
				(type default)
			)
			(layer "B.Fab")
		)
		(fp_line
			(start -0.67945 0.3048)
			(end -0.120396 0.3048)
			(stroke
				(width 0.1)
				(type default)
			)
			(layer "B.Fab")
		)
		(fp_line
			(start -0.67945 -0.3048)
			(end -0.67945 0.3048)
			(stroke
				(width 0.1)
				(type default)
			)
			(layer "B.Fab")
		)
		(pad "1" smd circle
			(at 0.40005 0)
			(size 0 0)
			(layers "B.Cu" "B.Mask" "B.Paste")
			(net "CLK_100M_DB800ZL_PEX1_S0_R_DN")
		)
		(pad "2" smd circle
			(at -0.40005 0)
			(size 0 0)
			(layers "B.Cu" "B.Mask" "B.Paste")
			(net "CLK_100M_DB800ZL_PEX1_S0_DN")
		)
	)
	(footprint ""
		(layer "B.Cu")
		(at 199.049386 -259.311648 90)
		(property "Reference" "R6336"
			(at 0 0 90)
			(layer "B.SilkS")
			(hide yes)
			(effects
				(font
					(size 1.27 1.27)
				)
				(justify mirror)
			)
		)
		(property "Value" ""
			(at 0 0 90)
			(layer "B.Fab")
			(effects
				(font
					(size 1.27 1.27)
				)
				(justify mirror)
			)
		)
		(duplicate_pad_numbers_are_jumpers no)
		(fp_line
			(start 0.7874 -0.4064)
			(end -0.7874 -0.4064)
			(stroke
				(width 0.1524)
				(type default)
			)
			(layer "B.SilkS")
		)
		(fp_line
			(start -0.7874 -0.4064)
			(end -0.7874 0.4064)
			(stroke
				(width 0.1524)
				(type default)
			)
			(layer "B.SilkS")
		)
		(fp_line
			(start 0.7874 0.4064)
			(end 0.7874 -0.4064)
			(stroke
				(width 0.1524)
				(type default)
			)
			(layer "B.SilkS")
		)
		(fp_line
			(start -0.7874 0.4064)
			(end 0.7874 0.4064)
			(stroke
				(width 0.1524)
				(type default)
			)
			(layer "B.SilkS")
		)
		(fp_line
			(start 0.67945 -0.305054)
			(end 0.12065 -0.305054)
			(stroke
				(width 0.1)
				(type default)
			)
			(layer "B.Fab")
		)
		(fp_line
			(start 0.12065 -0.305054)
			(end 0.12065 -0.2794)
			(stroke
				(width 0.1)
				(type default)
			)
			(layer "B.Fab")
		)
		(fp_line
			(start -0.12065 -0.3048)
			(end -0.67945 -0.3048)
			(stroke
				(width 0.1)
				(type default)
			)
			(layer "B.Fab")
		)
		(fp_line
			(start -0.67945 -0.3048)
			(end -0.67945 0.3048)
			(stroke
				(width 0.1)
				(type default)
			)
			(layer "B.Fab")
		)
		(fp_line
			(start 0.12065 -0.2794)
			(end -0.12065 -0.2794)
			(stroke
				(width 0.1)
				(type default)
			)
			(layer "B.Fab")
		)
		(fp_line
			(start -0.12065 -0.2794)
			(end -0.12065 -0.3048)
			(stroke
				(width 0.1)
				(type default)
			)
			(layer "B.Fab")
		)
		(fp_line
			(start 0.12065 0.2794)
			(end 0.12065 0.3048)
			(stroke
				(width 0.1)
				(type default)
			)
			(layer "B.Fab")
		)
		(fp_line
			(start -0.120396 0.2794)
			(end 0.12065 0.2794)
			(stroke
				(width 0.1)
				(type default)
			)
			(layer "B.Fab")
		)
		(fp_line
			(start 0.67945 0.3048)
			(end 0.67945 -0.305054)
			(stroke
				(width 0.1)
				(type default)
			)
			(layer "B.Fab")
		)
		(fp_line
			(start 0.12065 0.3048)
			(end 0.67945 0.3048)
			(stroke
				(width 0.1)
				(type default)
			)
			(layer "B.Fab")
		)
		(fp_line
			(start -0.120396 0.3048)
			(end -0.120396 0.2794)
			(stroke
				(width 0.1)
				(type default)
			)
			(layer "B.Fab")
		)
		(fp_line
			(start -0.67945 0.3048)
			(end -0.120396 0.3048)
			(stroke
				(width 0.1)
				(type default)
			)
			(layer "B.Fab")
		)
		(pad "1" smd circle
			(at 0.40005 0 270)
			(size 0 0)
			(layers "B.Cu" "B.Mask" "B.Paste")
			(net "P1V8_PEX")
		)
		(pad "2" smd circle
			(at -0.40005 0 270)
			(size 0 0)
			(layers "B.Cu" "B.Mask" "B.Paste")
			(net "PEX_MUX_A0")
		)
	)
	(footprint ""
		(layer "B.Cu")
		(at 100.832412 -380.45009)
		(property "Reference" "R1835"
			(at 0 0 0)
			(layer "B.SilkS")
			(hide yes)
			(effects
				(font
					(size 1.27 1.27)
				)
				(justify mirror)
			)
		)
		(property "Value" ""
			(at 0 0 0)
			(layer "B.Fab")
			(effects
				(font
					(size 1.27 1.27)
				)
				(justify mirror)
			)
		)
		(duplicate_pad_numbers_are_jumpers no)
		(fp_line
			(start -0.7874 -0.4064)
			(end -0.7874 0.4064)
			(stroke
				(width 0.1524)
				(type default)
			)
			(layer "B.SilkS")
		)
		(fp_line
			(start -0.7874 0.4064)
			(end 0.7874 0.4064)
			(stroke
				(width 0.1524)
				(type default)
			)
			(layer "B.SilkS")
		)
		(fp_line
			(start 0.7874 -0.4064)
			(end -0.7874 -0.4064)
			(stroke
				(width 0.1524)
				(type default)
			)
			(layer "B.SilkS")
		)
		(fp_line
			(start 0.7874 0.4064)
			(end 0.7874 -0.4064)
			(stroke
				(width 0.1524)
				(type default)
			)
			(layer "B.SilkS")
		)
		(fp_line
			(start -0.67945 -0.3048)
			(end -0.67945 0.3048)
			(stroke
				(width 0.1)
				(type default)
			)
			(layer "B.Fab")
		)
		(fp_line
			(start -0.67945 0.3048)
			(end -0.120396 0.3048)
			(stroke
				(width 0.1)
				(type default)
			)
			(layer "B.Fab")
		)
		(fp_line
			(start -0.12065 -0.3048)
			(end -0.67945 -0.3048)
			(stroke
				(width 0.1)
				(type default)
			)
			(layer "B.Fab")
		)
		(fp_line
			(start -0.12065 -0.2794)
			(end -0.12065 -0.3048)
			(stroke
				(width 0.1)
				(type default)
			)
			(layer "B.Fab")
		)
		(fp_line
			(start -0.120396 0.2794)
			(end 0.12065 0.2794)
			(stroke
				(width 0.1)
				(type default)
			)
			(layer "B.Fab")
		)
		(fp_line
			(start -0.120396 0.3048)
			(end -0.120396 0.2794)
			(stroke
				(width 0.1)
				(type default)
			)
			(layer "B.Fab")
		)
		(fp_line
			(start 0.12065 -0.305054)
			(end 0.12065 -0.2794)
			(stroke
				(width 0.1)
				(type default)
			)
			(layer "B.Fab")
		)
		(fp_line
			(start 0.12065 -0.2794)
			(end -0.12065 -0.2794)
			(stroke
				(width 0.1)
				(type default)
			)
			(layer "B.Fab")
		)
		(fp_line
			(start 0.12065 0.2794)
			(end 0.12065 0.3048)
			(stroke
				(width 0.1)
				(type default)
			)
			(layer "B.Fab")
		)
		(fp_line
			(start 0.12065 0.3048)
			(end 0.67945 0.3048)
			(stroke
				(width 0.1)
				(type default)
			)
			(layer "B.Fab")
		)
		(fp_line
			(start 0.67945 -0.305054)
			(end 0.12065 -0.305054)
			(stroke
				(width 0.1)
				(type default)
			)
			(layer "B.Fab")
		)
		(fp_line
			(start 0.67945 0.3048)
			(end 0.67945 -0.305054)
			(stroke
				(width 0.1)
				(type default)
			)
			(layer "B.Fab")
		)
		(pad "1" smd circle
			(at 0.40005 0 180)
			(size 0 0)
			(layers "B.Cu" "B.Mask" "B.Paste")
			(net "SMB_GPU_1_R_SCL")
		)
		(pad "2" smd circle
			(at -0.40005 0 180)
			(size 0 0)
			(layers "B.Cu" "B.Mask" "B.Paste")
			(net "SMB_GPU_1_SCL")
		)
	)
	(footprint ""
		(layer "B.Cu")
		(at 109.621828 -355.2952 180)
		(property "Reference" "C4177"
			(at 0 0 0)
			(layer "B.SilkS")
			(hide yes)
			(effects
				(font
					(size 1.27 1.27)
				)
				(justify mirror)
			)
		)
		(property "Value" ""
			(at 0 0 0)
			(layer "B.Fab")
			(effects
				(font
					(size 1.27 1.27)
				)
				(justify mirror)
			)
		)
		(duplicate_pad_numbers_are_jumpers no)
		(fp_line
			(start 0.7874 0.4064)
			(end 0.7874 -0.4064)
			(stroke
				(width 0.1524)
				(type default)
			)
			(layer "B.SilkS")
		)
		(fp_line
			(start 0.7874 -0.4064)
			(end -0.7874 -0.4064)
			(stroke
				(width 0.1524)
				(type default)
			)
			(layer "B.SilkS")
		)
		(fp_line
			(start -0.7874 0.4064)
			(end 0.7874 0.4064)
			(stroke
				(width 0.1524)
				(type default)
			)
			(layer "B.SilkS")
		)
		(fp_line
			(start -0.7874 -0.4064)
			(end -0.7874 0.4064)
			(stroke
				(width 0.1524)
				(type default)
			)
			(layer "B.SilkS")
		)
		(fp_line
			(start 0.67945 0.3048)
			(end 0.67945 -0.305054)
			(stroke
				(width 0.1)
				(type default)
			)
			(layer "B.Fab")
		)
		(fp_line
			(start 0.67945 -0.305054)
			(end 0.12065 -0.305054)
			(stroke
				(width 0.1)
				(type default)
			)
			(layer "B.Fab")
		)
		(fp_line
			(start 0.12065 0.3048)
			(end 0.67945 0.3048)
			(stroke
				(width 0.1)
				(type default)
			)
			(layer "B.Fab")
		)
		(fp_line
			(start 0.12065 0.2794)
			(end 0.12065 0.3048)
			(stroke
				(width 0.1)
				(type default)
			)
			(layer "B.Fab")
		)
		(fp_line
			(start 0.12065 -0.2794)
			(end -0.12065 -0.2794)
			(stroke
				(width 0.1)
				(type default)
			)
			(layer "B.Fab")
		)
		(fp_line
			(start 0.12065 -0.305054)
			(end 0.12065 -0.2794)
			(stroke
				(width 0.1)
				(type default)
			)
			(layer "B.Fab")
		)
		(fp_line
			(start -0.120396 0.3048)
			(end -0.120396 0.2794)
			(stroke
				(width 0.1)
				(type default)
			)
			(layer "B.Fab")
		)
		(fp_line
			(start -0.120396 0.2794)
			(end 0.12065 0.2794)
			(stroke
				(width 0.1)
				(type default)
			)
			(layer "B.Fab")
		)
		(fp_line
			(start -0.12065 -0.2794)
			(end -0.12065 -0.3048)
			(stroke
				(width 0.1)
				(type default)
			)
			(layer "B.Fab")
		)
		(fp_line
			(start -0.12065 -0.3048)
			(end -0.67945 -0.3048)
			(stroke
				(width 0.1)
				(type default)
			)
			(layer "B.Fab")
		)
		(fp_line
			(start -0.67945 0.3048)
			(end -0.120396 0.3048)
			(stroke
				(width 0.1)
				(type default)
			)
			(layer "B.Fab")
		)
		(fp_line
			(start -0.67945 -0.3048)
			(end -0.67945 0.3048)
			(stroke
				(width 0.1)
				(type default)
			)
			(layer "B.Fab")
		)
		(pad "1" smd circle
			(at 0.40005 0)
			(size 0 0)
			(layers "B.Cu" "B.Mask" "B.Paste")
			(net "P3V3_CLK_BUFFER_9ZXL0451E_S3_VZX3P3")
		)
		(pad "2" smd circle
			(at -0.40005 0)
			(size 0 0)
			(layers "B.Cu" "B.Mask" "B.Paste")
			(net "GND")
		)
	)
	(footprint ""
		(layer "B.Cu")
		(at 414.599882 -303.499774 -90)
		(property "Reference" "C3425"
			(at 0 0 90)
			(layer "B.SilkS")
			(hide yes)
			(effects
				(font
					(size 1.27 1.27)
				)
				(justify mirror)
			)
		)
		(property "Value" ""
			(at 0 0 90)
			(layer "B.Fab")
			(effects
				(font
					(size 1.27 1.27)
				)
				(justify mirror)
			)
		)
		(duplicate_pad_numbers_are_jumpers no)
		(fp_line
			(start -0.299974 0.150114)
			(end 0.299974 0.150114)
			(stroke
				(width 0.1)
				(type default)
			)
			(layer "B.Fab")
		)
		(fp_line
			(start 0.299974 0.150114)
			(end 0.299974 -0.150114)
			(stroke
				(width 0.1)
				(type default)
			)
			(layer "B.Fab")
		)
		(fp_line
			(start -0.299974 -0.150114)
			(end -0.299974 0.150114)
			(stroke
				(width 0.1)
				(type default)
			)
			(layer "B.Fab")
		)
		(fp_line
			(start 0.299974 -0.150114)
			(end -0.299974 -0.150114)
			(stroke
				(width 0.1)
				(type default)
			)
			(layer "B.Fab")
		)
		(pad "1" smd rect
			(at 0.2667 0 90)
			(size 0.3048 0.381)
			(layers "B.Cu" "B.Mask" "B.Paste")
			(net "P1V25_PEX3")
		)
		(pad "2" smd rect
			(at -0.2667 0 90)
			(size 0.3048 0.381)
			(layers "B.Cu" "B.Mask" "B.Paste")
			(net "GND")
		)
	)
	(footprint ""
		(layer "B.Cu")
		(at 396.07744 -299.5422 90)
		(property "Reference" "C3545"
			(at 0 0 90)
			(layer "B.SilkS")
			(hide yes)
			(effects
				(font
					(size 1.27 1.27)
				)
				(justify mirror)
			)
		)
		(property "Value" ""
			(at 0 0 90)
			(layer "B.Fab")
			(effects
				(font
					(size 1.27 1.27)
				)
				(justify mirror)
			)
		)
		(duplicate_pad_numbers_are_jumpers no)
		(fp_line
			(start 0.299974 -0.150114)
			(end -0.299974 -0.150114)
			(stroke
				(width 0.1)
				(type default)
			)
			(layer "B.Fab")
		)
		(fp_line
			(start -0.299974 -0.150114)
			(end -0.299974 0.150114)
			(stroke
				(width 0.1)
				(type default)
			)
			(layer "B.Fab")
		)
		(fp_line
			(start 0.299974 0.150114)
			(end 0.299974 -0.150114)
			(stroke
				(width 0.1)
				(type default)
			)
			(layer "B.Fab")
		)
		(fp_line
			(start -0.299974 0.150114)
			(end 0.299974 0.150114)
			(stroke
				(width 0.1)
				(type default)
			)
			(layer "B.Fab")
		)
		(pad "1" smd rect
			(at 0.2667 0 270)
			(size 0.3048 0.381)
			(layers "B.Cu" "B.Mask" "B.Paste")
			(net "PCEPLL0_VDDA18_PEX3")
		)
		(pad "2" smd rect
			(at -0.2667 0 270)
			(size 0.3048 0.381)
			(layers "B.Cu" "B.Mask" "B.Paste")
			(net "GND")
		)
	)
	(footprint ""
		(layer "B.Cu")
		(at 340.140798 -89.602818)
		(property "Reference" "C2679"
			(at 0 0 0)
			(layer "B.SilkS")
			(hide yes)
			(effects
				(font
					(size 1.27 1.27)
				)
				(justify mirror)
			)
		)
		(property "Value" ""
			(at 0 0 0)
			(layer "B.Fab")
			(effects
				(font
					(size 1.27 1.27)
				)
				(justify mirror)
			)
		)
		(duplicate_pad_numbers_are_jumpers no)
		(fp_line
			(start -0.7874 -0.4064)
			(end -0.7874 0.4064)
			(stroke
				(width 0.1524)
				(type default)
			)
			(layer "B.SilkS")
		)
		(fp_line
			(start -0.7874 0.4064)
			(end 0.7874 0.4064)
			(stroke
				(width 0.1524)
				(type default)
			)
			(layer "B.SilkS")
		)
		(fp_line
			(start 0.7874 -0.4064)
			(end -0.7874 -0.4064)
			(stroke
				(width 0.1524)
				(type default)
			)
			(layer "B.SilkS")
		)
		(fp_line
			(start 0.7874 0.4064)
			(end 0.7874 -0.4064)
			(stroke
				(width 0.1524)
				(type default)
			)
			(layer "B.SilkS")
		)
		(fp_line
			(start -0.67945 -0.3048)
			(end -0.67945 0.3048)
			(stroke
				(width 0.1)
				(type default)
			)
			(layer "B.Fab")
		)
		(fp_line
			(start -0.67945 0.3048)
			(end -0.120396 0.3048)
			(stroke
				(width 0.1)
				(type default)
			)
			(layer "B.Fab")
		)
		(fp_line
			(start -0.12065 -0.3048)
			(end -0.67945 -0.3048)
			(stroke
				(width 0.1)
				(type default)
			)
			(layer "B.Fab")
		)
		(fp_line
			(start -0.12065 -0.2794)
			(end -0.12065 -0.3048)
			(stroke
				(width 0.1)
				(type default)
			)
			(layer "B.Fab")
		)
		(fp_line
			(start -0.120396 0.2794)
			(end 0.12065 0.2794)
			(stroke
				(width 0.1)
				(type default)
			)
			(layer "B.Fab")
		)
		(fp_line
			(start -0.120396 0.3048)
			(end -0.120396 0.2794)
			(stroke
				(width 0.1)
				(type default)
			)
			(layer "B.Fab")
		)
		(fp_line
			(start 0.12065 -0.305054)
			(end 0.12065 -0.2794)
			(stroke
				(width 0.1)
				(type default)
			)
			(layer "B.Fab")
		)
		(fp_line
			(start 0.12065 -0.2794)
			(end -0.12065 -0.2794)
			(stroke
				(width 0.1)
				(type default)
			)
			(layer "B.Fab")
		)
		(fp_line
			(start 0.12065 0.2794)
			(end 0.12065 0.3048)
			(stroke
				(width 0.1)
				(type default)
			)
			(layer "B.Fab")
		)
		(fp_line
			(start 0.12065 0.3048)
			(end 0.67945 0.3048)
			(stroke
				(width 0.1)
				(type default)
			)
			(layer "B.Fab")
		)
		(fp_line
			(start 0.67945 -0.305054)
			(end 0.12065 -0.305054)
			(stroke
				(width 0.1)
				(type default)
			)
			(layer "B.Fab")
		)
		(fp_line
			(start 0.67945 0.3048)
			(end 0.67945 -0.305054)
			(stroke
				(width 0.1)
				(type default)
			)
			(layer "B.Fab")
		)
		(pad "1" smd circle
			(at 0.40005 0 180)
			(size 0 0)
			(layers "B.Cu" "B.Mask" "B.Paste")
			(net "P3V3_VDD_9ZXL0851_8_15")
		)
		(pad "2" smd circle
			(at -0.40005 0 180)
			(size 0 0)
			(layers "B.Cu" "B.Mask" "B.Paste")
			(net "GND")
		)
	)
	(footprint ""
		(layer "B.Cu")
		(at 341.111586 -283.818584 90)
		(property "Reference" "PR148"
			(at 0 0 90)
			(layer "B.SilkS")
			(hide yes)
			(effects
				(font
					(size 1.27 1.27)
				)
				(justify mirror)
			)
		)
		(property "Value" ""
			(at 0 0 90)
			(layer "B.Fab")
			(effects
				(font
					(size 1.27 1.27)
				)
				(justify mirror)
			)
		)
		(duplicate_pad_numbers_are_jumpers no)
		(fp_line
			(start 0.7874 -0.4064)
			(end -0.7874 -0.4064)
			(stroke
				(width 0.1524)
				(type default)
			)
			(layer "B.SilkS")
		)
		(fp_line
			(start -0.7874 -0.4064)
			(end -0.7874 0.4064)
			(stroke
				(width 0.1524)
				(type default)
			)
			(layer "B.SilkS")
		)
		(fp_line
			(start 0.7874 0.4064)
			(end 0.7874 -0.4064)
			(stroke
				(width 0.1524)
				(type default)
			)
			(layer "B.SilkS")
		)
		(fp_line
			(start -0.7874 0.4064)
			(end 0.7874 0.4064)
			(stroke
				(width 0.1524)
				(type default)
			)
			(layer "B.SilkS")
		)
		(fp_line
			(start 0.67945 -0.305054)
			(end 0.12065 -0.305054)
			(stroke
				(width 0.1)
				(type default)
			)
			(layer "B.Fab")
		)
		(fp_line
			(start 0.12065 -0.305054)
			(end 0.12065 -0.2794)
			(stroke
				(width 0.1)
				(type default)
			)
			(layer "B.Fab")
		)
		(fp_line
			(start -0.12065 -0.3048)
			(end -0.67945 -0.3048)
			(stroke
				(width 0.1)
				(type default)
			)
			(layer "B.Fab")
		)
		(fp_line
			(start -0.67945 -0.3048)
			(end -0.67945 0.3048)
			(stroke
				(width 0.1)
				(type default)
			)
			(layer "B.Fab")
		)
		(fp_line
			(start 0.12065 -0.2794)
			(end -0.12065 -0.2794)
			(stroke
				(width 0.1)
				(type default)
			)
			(layer "B.Fab")
		)
		(fp_line
			(start -0.12065 -0.2794)
			(end -0.12065 -0.3048)
			(stroke
				(width 0.1)
				(type default)
			)
			(layer "B.Fab")
		)
		(fp_line
			(start 0.12065 0.2794)
			(end 0.12065 0.3048)
			(stroke
				(width 0.1)
				(type default)
			)
			(layer "B.Fab")
		)
		(fp_line
			(start -0.120396 0.2794)
			(end 0.12065 0.2794)
			(stroke
				(width 0.1)
				(type default)
			)
			(layer "B.Fab")
		)
		(fp_line
			(start 0.67945 0.3048)
			(end 0.67945 -0.305054)
			(stroke
				(width 0.1)
				(type default)
			)
			(layer "B.Fab")
		)
		(fp_line
			(start 0.12065 0.3048)
			(end 0.67945 0.3048)
			(stroke
				(width 0.1)
				(type default)
			)
			(layer "B.Fab")
		)
		(fp_line
			(start -0.120396 0.3048)
			(end -0.120396 0.2794)
			(stroke
				(width 0.1)
				(type default)
			)
			(layer "B.Fab")
		)
		(fp_line
			(start -0.67945 0.3048)
			(end -0.120396 0.3048)
			(stroke
				(width 0.1)
				(type default)
			)
			(layer "B.Fab")
		)
		(pad "1" smd circle
			(at 0.40005 0 270)
			(size 0 0)
			(layers "B.Cu" "B.Mask" "B.Paste")
			(net "P0V8_PEX2_PVCC")
		)
		(pad "2" smd circle
			(at -0.40005 0 270)
			(size 0 0)
			(layers "B.Cu" "B.Mask" "B.Paste")
			(net "P0V8_PEX2_VCC1")
		)
	)
	(footprint ""
		(layer "B.Cu")
		(at 222.27413 -200.984104 90)
		(property "Reference" "R460"
			(at 0 0 90)
			(layer "B.SilkS")
			(hide yes)
			(effects
				(font
					(size 1.27 1.27)
				)
				(justify mirror)
			)
		)
		(property "Value" ""
			(at 0 0 90)
			(layer "B.Fab")
			(effects
				(font
					(size 1.27 1.27)
				)
				(justify mirror)
			)
		)
		(duplicate_pad_numbers_are_jumpers no)
		(fp_line
			(start 0.7874 -0.4064)
			(end -0.7874 -0.4064)
			(stroke
				(width 0.1524)
				(type default)
			)
			(layer "B.SilkS")
		)
		(fp_line
			(start -0.7874 -0.4064)
			(end -0.7874 0.4064)
			(stroke
				(width 0.1524)
				(type default)
			)
			(layer "B.SilkS")
		)
		(fp_line
			(start 0.7874 0.4064)
			(end 0.7874 -0.4064)
			(stroke
				(width 0.1524)
				(type default)
			)
			(layer "B.SilkS")
		)
		(fp_line
			(start -0.7874 0.4064)
			(end 0.7874 0.4064)
			(stroke
				(width 0.1524)
				(type default)
			)
			(layer "B.SilkS")
		)
		(fp_line
			(start 0.67945 -0.305054)
			(end 0.12065 -0.305054)
			(stroke
				(width 0.1)
				(type default)
			)
			(layer "B.Fab")
		)
		(fp_line
			(start 0.12065 -0.305054)
			(end 0.12065 -0.2794)
			(stroke
				(width 0.1)
				(type default)
			)
			(layer "B.Fab")
		)
		(fp_line
			(start -0.12065 -0.3048)
			(end -0.67945 -0.3048)
			(stroke
				(width 0.1)
				(type default)
			)
			(layer "B.Fab")
		)
		(fp_line
			(start -0.67945 -0.3048)
			(end -0.67945 0.3048)
			(stroke
				(width 0.1)
				(type default)
			)
			(layer "B.Fab")
		)
		(fp_line
			(start 0.12065 -0.2794)
			(end -0.12065 -0.2794)
			(stroke
				(width 0.1)
				(type default)
			)
			(layer "B.Fab")
		)
		(fp_line
			(start -0.12065 -0.2794)
			(end -0.12065 -0.3048)
			(stroke
				(width 0.1)
				(type default)
			)
			(layer "B.Fab")
		)
		(fp_line
			(start 0.12065 0.2794)
			(end 0.12065 0.3048)
			(stroke
				(width 0.1)
				(type default)
			)
			(layer "B.Fab")
		)
		(fp_line
			(start -0.120396 0.2794)
			(end 0.12065 0.2794)
			(stroke
				(width 0.1)
				(type default)
			)
			(layer "B.Fab")
		)
		(fp_line
			(start 0.67945 0.3048)
			(end 0.67945 -0.305054)
			(stroke
				(width 0.1)
				(type default)
			)
			(layer "B.Fab")
		)
		(fp_line
			(start 0.12065 0.3048)
			(end 0.67945 0.3048)
			(stroke
				(width 0.1)
				(type default)
			)
			(layer "B.Fab")
		)
		(fp_line
			(start -0.120396 0.3048)
			(end -0.120396 0.2794)
			(stroke
				(width 0.1)
				(type default)
			)
			(layer "B.Fab")
		)
		(fp_line
			(start -0.67945 0.3048)
			(end -0.120396 0.3048)
			(stroke
				(width 0.1)
				(type default)
			)
			(layer "B.Fab")
		)
		(pad "1" smd circle
			(at 0.40005 0 270)
			(size 0 0)
			(layers "B.Cu" "B.Mask" "B.Paste")
			(net "SPI_BIC1_MOSI")
		)
		(pad "2" smd circle
			(at -0.40005 0 270)
			(size 0 0)
			(layers "B.Cu" "B.Mask" "B.Paste")
			(net "SPI_BIC1_MOSI_R")
		)
	)
	(footprint ""
		(layer "B.Cu")
		(at 413.649922 -288.299906 90)
		(property "Reference" "C3444"
			(at 0 0 90)
			(layer "B.SilkS")
			(hide yes)
			(effects
				(font
					(size 1.27 1.27)
				)
				(justify mirror)
			)
		)
		(property "Value" ""
			(at 0 0 90)
			(layer "B.Fab")
			(effects
				(font
					(size 1.27 1.27)
				)
				(justify mirror)
			)
		)
		(duplicate_pad_numbers_are_jumpers no)
		(fp_line
			(start 0.299974 -0.150114)
			(end -0.299974 -0.150114)
			(stroke
				(width 0.1)
				(type default)
			)
			(layer "B.Fab")
		)
		(fp_line
			(start -0.299974 -0.150114)
			(end -0.299974 0.150114)
			(stroke
				(width 0.1)
				(type default)
			)
			(layer "B.Fab")
		)
		(fp_line
			(start 0.299974 0.150114)
			(end 0.299974 -0.150114)
			(stroke
				(width 0.1)
				(type default)
			)
			(layer "B.Fab")
		)
		(fp_line
			(start -0.299974 0.150114)
			(end 0.299974 0.150114)
			(stroke
				(width 0.1)
				(type default)
			)
			(layer "B.Fab")
		)
		(pad "1" smd rect
			(at 0.2667 0 270)
			(size 0.3048 0.381)
			(layers "B.Cu" "B.Mask" "B.Paste")
			(net "P1V25_PEX3")
		)
		(pad "2" smd rect
			(at -0.2667 0 270)
			(size 0.3048 0.381)
			(layers "B.Cu" "B.Mask" "B.Paste")
			(net "GND")
		)
	)
	(footprint ""
		(layer "B.Cu")
		(at 99.055428 -377.387612)
		(property "Reference" "R1831"
			(at 0 0 0)
			(layer "B.SilkS")
			(hide yes)
			(effects
				(font
					(size 1.27 1.27)
				)
				(justify mirror)
			)
		)
		(property "Value" ""
			(at 0 0 0)
			(layer "B.Fab")
			(effects
				(font
					(size 1.27 1.27)
				)
				(justify mirror)
			)
		)
		(duplicate_pad_numbers_are_jumpers no)
		(fp_line
			(start -0.7874 -0.4064)
			(end -0.7874 0.4064)
			(stroke
				(width 0.1524)
				(type default)
			)
			(layer "B.SilkS")
		)
		(fp_line
			(start -0.7874 0.4064)
			(end 0.7874 0.4064)
			(stroke
				(width 0.1524)
				(type default)
			)
			(layer "B.SilkS")
		)
		(fp_line
			(start 0.7874 -0.4064)
			(end -0.7874 -0.4064)
			(stroke
				(width 0.1524)
				(type default)
			)
			(layer "B.SilkS")
		)
		(fp_line
			(start 0.7874 0.4064)
			(end 0.7874 -0.4064)
			(stroke
				(width 0.1524)
				(type default)
			)
			(layer "B.SilkS")
		)
		(fp_line
			(start -0.67945 -0.3048)
			(end -0.67945 0.3048)
			(stroke
				(width 0.1)
				(type default)
			)
			(layer "B.Fab")
		)
		(fp_line
			(start -0.67945 0.3048)
			(end -0.120396 0.3048)
			(stroke
				(width 0.1)
				(type default)
			)
			(layer "B.Fab")
		)
		(fp_line
			(start -0.12065 -0.3048)
			(end -0.67945 -0.3048)
			(stroke
				(width 0.1)
				(type default)
			)
			(layer "B.Fab")
		)
		(fp_line
			(start -0.12065 -0.2794)
			(end -0.12065 -0.3048)
			(stroke
				(width 0.1)
				(type default)
			)
			(layer "B.Fab")
		)
		(fp_line
			(start -0.120396 0.2794)
			(end 0.12065 0.2794)
			(stroke
				(width 0.1)
				(type default)
			)
			(layer "B.Fab")
		)
		(fp_line
			(start -0.120396 0.3048)
			(end -0.120396 0.2794)
			(stroke
				(width 0.1)
				(type default)
			)
			(layer "B.Fab")
		)
		(fp_line
			(start 0.12065 -0.305054)
			(end 0.12065 -0.2794)
			(stroke
				(width 0.1)
				(type default)
			)
			(layer "B.Fab")
		)
		(fp_line
			(start 0.12065 -0.2794)
			(end -0.12065 -0.2794)
			(stroke
				(width 0.1)
				(type default)
			)
			(layer "B.Fab")
		)
		(fp_line
			(start 0.12065 0.2794)
			(end 0.12065 0.3048)
			(stroke
				(width 0.1)
				(type default)
			)
			(layer "B.Fab")
		)
		(fp_line
			(start 0.12065 0.3048)
			(end 0.67945 0.3048)
			(stroke
				(width 0.1)
				(type default)
			)
			(layer "B.Fab")
		)
		(fp_line
			(start 0.67945 -0.305054)
			(end 0.12065 -0.305054)
			(stroke
				(width 0.1)
				(type default)
			)
			(layer "B.Fab")
		)
		(fp_line
			(start 0.67945 0.3048)
			(end 0.67945 -0.305054)
			(stroke
				(width 0.1)
				(type default)
			)
			(layer "B.Fab")
		)
		(pad "1" smd circle
			(at 0.40005 0 180)
			(size 0 0)
			(layers "B.Cu" "B.Mask" "B.Paste")
			(net "SMB_GPU_2_R_SCL")
		)
		(pad "2" smd circle
			(at -0.40005 0 180)
			(size 0 0)
			(layers "B.Cu" "B.Mask" "B.Paste")
			(net "SMB_GPU_2_SCL")
		)
	)
	(footprint ""
		(layer "B.Cu")
		(at 3.065272 -274.646644)
		(property "Reference" "C4233"
			(at 0 0 0)
			(layer "B.SilkS")
			(hide yes)
			(effects
				(font
					(size 1.27 1.27)
				)
				(justify mirror)
			)
		)
		(property "Value" ""
			(at 0 0 0)
			(layer "B.Fab")
			(effects
				(font
					(size 1.27 1.27)
				)
				(justify mirror)
			)
		)
		(duplicate_pad_numbers_are_jumpers no)
		(fp_line
			(start -1.2954 -0.5842)
			(end -1.2954 0.5842)
			(stroke
				(width 0.1524)
				(type default)
			)
			(layer "B.SilkS")
		)
		(fp_line
			(start -1.2954 0.5842)
			(end 1.2954 0.5842)
			(stroke
				(width 0.1524)
				(type default)
			)
			(layer "B.SilkS")
		)
		(fp_line
			(start 1.2954 -0.5842)
			(end -1.2954 -0.5842)
			(stroke
				(width 0.1524)
				(type default)
			)
			(layer "B.SilkS")
		)
		(fp_line
			(start 1.2954 0.5842)
			(end 1.2954 -0.5842)
			(stroke
				(width 0.1524)
				(type default)
			)
			(layer "B.SilkS")
		)
		(fp_line
			(start -1.1938 -0.4064)
			(end -1.1938 0.4064)
			(stroke
				(width 0.1)
				(type default)
			)
			(layer "B.Fab")
		)
		(fp_line
			(start -1.1938 0.4064)
			(end -0.8636 0.4064)
			(stroke
				(width 0.1)
				(type default)
			)
			(layer "B.Fab")
		)
		(fp_line
			(start -0.8636 -0.4572)
			(end -0.8636 -0.4064)
			(stroke
				(width 0.1)
				(type default)
			)
			(layer "B.Fab")
		)
		(fp_line
			(start -0.8636 -0.4064)
			(end -1.1938 -0.4064)
			(stroke
				(width 0.1)
				(type default)
			)
			(layer "B.Fab")
		)
		(fp_line
			(start -0.8636 0.4064)
			(end -0.8636 0.4572)
			(stroke
				(width 0.1)
				(type default)
			)
			(layer "B.Fab")
		)
		(fp_line
			(start -0.8636 0.4572)
			(end 0.8636 0.4572)
			(stroke
				(width 0.1)
				(type default)
			)
			(layer "B.Fab")
		)
		(fp_line
			(start 0.8636 -0.4572)
			(end -0.8636 -0.4572)
			(stroke
				(width 0.1)
				(type default)
			)
			(layer "B.Fab")
		)
		(fp_line
			(start 0.8636 -0.4064)
			(end 0.8636 -0.4572)
			(stroke
				(width 0.1)
				(type default)
			)
			(layer "B.Fab")
		)
		(fp_line
			(start 0.8636 0.4064)
			(end 1.1938 0.4064)
			(stroke
				(width 0.1)
				(type default)
			)
			(layer "B.Fab")
		)
		(fp_line
			(start 0.8636 0.4572)
			(end 0.8636 0.4064)
			(stroke
				(width 0.1)
				(type default)
			)
			(layer "B.Fab")
		)
		(fp_line
			(start 1.1938 -0.4064)
			(end 0.8636 -0.4064)
			(stroke
				(width 0.1)
				(type default)
			)
			(layer "B.Fab")
		)
		(fp_line
			(start 1.1938 0.4064)
			(end 1.1938 -0.4064)
			(stroke
				(width 0.1)
				(type default)
			)
			(layer "B.Fab")
		)
		(pad "1" smd rect
			(at 0.7366 0 270)
			(size 0.7112 0.8128)
			(layers "B.Cu" "B.Mask" "B.Paste")
			(net "P1V25_PEX0")
		)
		(pad "2" smd rect
			(at -0.7366 0 270)
			(size 0.7112 0.8128)
			(layers "B.Cu" "B.Mask" "B.Paste")
			(net "GND")
		)
	)
	(footprint ""
		(layer "B.Cu")
		(at 383.683002 -222.590106)
		(property "Reference" "U100"
			(at 1.016 -1.80213 0)
			(unlocked yes)
			(layer "B.SilkS")
			(effects
				(font
					(size 0.7874 0.5842)
					(thickness 0.1524)
				)
				(justify mirror)
			)
		)
		(property "Value" ""
			(at 0 0 0)
			(layer "B.Fab")
			(effects
				(font
					(size 1.27 1.27)
				)
				(justify mirror)
			)
		)
		(duplicate_pad_numbers_are_jumpers no)
		(fp_line
			(start -1.7272 -1.1176)
			(end -1.7272 1.1176)
			(stroke
				(width 0.1524)
				(type default)
			)
			(layer "B.SilkS")
		)
		(fp_line
			(start -1.7272 -1.1176)
			(end -0.254 -1.1176)
			(stroke
				(width 0.1524)
				(type default)
			)
			(layer "B.SilkS")
		)
		(fp_line
			(start -1.7272 1.1176)
			(end 1.7272 1.1176)
			(stroke
				(width 0.1524)
				(type default)
			)
			(layer "B.SilkS")
		)
		(fp_line
			(start -0.254 -1.1176)
			(end 0 -0.7366)
			(stroke
				(width 0.1524)
				(type default)
			)
			(layer "B.SilkS")
		)
		(fp_line
			(start 0 -0.7366)
			(end 0.254 -1.1176)
			(stroke
				(width 0.1524)
				(type default)
			)
			(layer "B.SilkS")
		)
		(fp_line
			(start 0.254 -1.1176)
			(end 1.7272 -1.1176)
			(stroke
				(width 0.1524)
				(type default)
			)
			(layer "B.SilkS")
		)
		(fp_line
			(start 1.7272 1.1176)
			(end 1.7272 -1.1176)
			(stroke
				(width 0.1524)
				(type default)
			)
			(layer "B.SilkS")
		)
		(fp_poly
			(pts
				(xy 1.9558 -0.649986) (xy 2.7178 -0.268986) (xy 2.7178 -1.030986)
			)
			(stroke
				(width 0)
				(type default)
			)
			(fill yes)
			(layer "B.SilkS")
		)
		(fp_line
			(start -1.5748 -1.1176)
			(end 1.5748 -1.1176)
			(stroke
				(width 0.1)
				(type default)
			)
			(layer "B.Fab")
		)
		(fp_line
			(start -1.5748 1.1176)
			(end -1.5748 -1.1176)
			(stroke
				(width 0.1)
				(type default)
			)
			(layer "B.Fab")
		)
		(fp_line
			(start 1.5748 -1.1176)
			(end 1.5748 1.1176)
			(stroke
				(width 0.1)
				(type default)
			)
			(layer "B.Fab")
		)
		(fp_line
			(start 1.5748 1.1176)
			(end -1.5748 1.1176)
			(stroke
				(width 0.1)
				(type default)
			)
			(layer "B.Fab")
		)
		(fp_poly
			(pts
				(xy 1.9558 -0.649986) (xy 2.7178 -0.268986) (xy 2.7178 -1.030986)
			)
			(stroke
				(width 0)
				(type default)
			)
			(fill yes)
			(layer "B.Fab")
		)
		(pad "1" smd rect
			(at 0.999998 -0.649986 270)
			(size 0.3556 1.1176)
			(layers "B.Cu" "B.Mask" "B.Paste")
			(net "UART_PEX0_SDB_R_RX")
		)
		(pad "2" smd rect
			(at 0.999998 0 270)
			(size 0.3556 1.1176)
			(layers "B.Cu" "B.Mask" "B.Paste")
			(net "GND")
		)
		(pad "3" smd rect
			(at 0.999998 0.649986 270)
			(size 0.3556 1.1176)
			(layers "B.Cu" "B.Mask" "B.Paste")
			(net "UART_PEX1_SDB_R_RX")
		)
		(pad "4" smd rect
			(at -0.999998 0.649986 270)
			(size 0.3556 1.1176)
			(layers "B.Cu" "B.Mask" "B.Paste")
			(net "UART_PEX1_SDB_BUF_R_RX")
		)
		(pad "5" smd rect
			(at -0.999998 0 270)
			(size 0.3556 1.1176)
			(layers "B.Cu" "B.Mask" "B.Paste")
			(net "P3V3_AUX")
		)
		(pad "6" smd rect
			(at -0.999998 -0.649986 270)
			(size 0.3556 1.1176)
			(layers "B.Cu" "B.Mask" "B.Paste")
			(net "UART_PEX0_SDB_BUF_R_RX")
		)
	)
	(footprint ""
		(layer "B.Cu")
		(at 256.282952 -220.932756 90)
		(property "Reference" "R3479"
			(at 0 0 90)
			(layer "B.SilkS")
			(hide yes)
			(effects
				(font
					(size 1.27 1.27)
				)
				(justify mirror)
			)
		)
		(property "Value" ""
			(at 0 0 90)
			(layer "B.Fab")
			(effects
				(font
					(size 1.27 1.27)
				)
				(justify mirror)
			)
		)
		(duplicate_pad_numbers_are_jumpers no)
		(fp_line
			(start 0.7874 -0.4064)
			(end -0.7874 -0.4064)
			(stroke
				(width 0.1524)
				(type default)
			)
			(layer "B.SilkS")
		)
		(fp_line
			(start -0.7874 -0.4064)
			(end -0.7874 0.4064)
			(stroke
				(width 0.1524)
				(type default)
			)
			(layer "B.SilkS")
		)
		(fp_line
			(start 0.7874 0.4064)
			(end 0.7874 -0.4064)
			(stroke
				(width 0.1524)
				(type default)
			)
			(layer "B.SilkS")
		)
		(fp_line
			(start -0.7874 0.4064)
			(end 0.7874 0.4064)
			(stroke
				(width 0.1524)
				(type default)
			)
			(layer "B.SilkS")
		)
		(fp_line
			(start 0.67945 -0.305054)
			(end 0.12065 -0.305054)
			(stroke
				(width 0.1)
				(type default)
			)
			(layer "B.Fab")
		)
		(fp_line
			(start 0.12065 -0.305054)
			(end 0.12065 -0.2794)
			(stroke
				(width 0.1)
				(type default)
			)
			(layer "B.Fab")
		)
		(fp_line
			(start -0.12065 -0.3048)
			(end -0.67945 -0.3048)
			(stroke
				(width 0.1)
				(type default)
			)
			(layer "B.Fab")
		)
		(fp_line
			(start -0.67945 -0.3048)
			(end -0.67945 0.3048)
			(stroke
				(width 0.1)
				(type default)
			)
			(layer "B.Fab")
		)
		(fp_line
			(start 0.12065 -0.2794)
			(end -0.12065 -0.2794)
			(stroke
				(width 0.1)
				(type default)
			)
			(layer "B.Fab")
		)
		(fp_line
			(start -0.12065 -0.2794)
			(end -0.12065 -0.3048)
			(stroke
				(width 0.1)
				(type default)
			)
			(layer "B.Fab")
		)
		(fp_line
			(start 0.12065 0.2794)
			(end 0.12065 0.3048)
			(stroke
				(width 0.1)
				(type default)
			)
			(layer "B.Fab")
		)
		(fp_line
			(start -0.120396 0.2794)
			(end 0.12065 0.2794)
			(stroke
				(width 0.1)
				(type default)
			)
			(layer "B.Fab")
		)
		(fp_line
			(start 0.67945 0.3048)
			(end 0.67945 -0.305054)
			(stroke
				(width 0.1)
				(type default)
			)
			(layer "B.Fab")
		)
		(fp_line
			(start 0.12065 0.3048)
			(end 0.67945 0.3048)
			(stroke
				(width 0.1)
				(type default)
			)
			(layer "B.Fab")
		)
		(fp_line
			(start -0.120396 0.3048)
			(end -0.120396 0.2794)
			(stroke
				(width 0.1)
				(type default)
			)
			(layer "B.Fab")
		)
		(fp_line
			(start -0.67945 0.3048)
			(end -0.120396 0.3048)
			(stroke
				(width 0.1)
				(type default)
			)
			(layer "B.Fab")
		)
		(pad "1" smd circle
			(at 0.40005 0 270)
			(size 0 0)
			(layers "B.Cu" "B.Mask" "B.Paste")
			(net "SPI_PEX2_SDIO3_R")
		)
		(pad "2" smd circle
			(at -0.40005 0 270)
			(size 0 0)
			(layers "B.Cu" "B.Mask" "B.Paste")
			(net "SPI_PEX2_SDIO3_R1")
		)
	)
	(footprint ""
		(layer "B.Cu")
		(at 64.874902 -286.399732 90)
		(property "Reference" "C2965"
			(at 0 0 90)
			(layer "B.SilkS")
			(hide yes)
			(effects
				(font
					(size 1.27 1.27)
				)
				(justify mirror)
			)
		)
		(property "Value" ""
			(at 0 0 90)
			(layer "B.Fab")
			(effects
				(font
					(size 1.27 1.27)
				)
				(justify mirror)
			)
		)
		(duplicate_pad_numbers_are_jumpers no)
		(fp_line
			(start 0.299974 -0.150114)
			(end -0.299974 -0.150114)
			(stroke
				(width 0.1)
				(type default)
			)
			(layer "B.Fab")
		)
		(fp_line
			(start -0.299974 -0.150114)
			(end -0.299974 0.150114)
			(stroke
				(width 0.1)
				(type default)
			)
			(layer "B.Fab")
		)
		(fp_line
			(start 0.299974 0.150114)
			(end 0.299974 -0.150114)
			(stroke
				(width 0.1)
				(type default)
			)
			(layer "B.Fab")
		)
		(fp_line
			(start -0.299974 0.150114)
			(end 0.299974 0.150114)
			(stroke
				(width 0.1)
				(type default)
			)
			(layer "B.Fab")
		)
		(pad "1" smd rect
			(at 0.2667 0 270)
			(size 0.3048 0.381)
			(layers "B.Cu" "B.Mask" "B.Paste")
			(net "P1V25_SERDES_VDDPLL_PEX0")
		)
		(pad "2" smd rect
			(at -0.2667 0 270)
			(size 0.3048 0.381)
			(layers "B.Cu" "B.Mask" "B.Paste")
			(net "GND")
		)
	)
	(footprint ""
		(layer "B.Cu")
		(at 281.399742 -290.674806 180)
		(property "Reference" "C1614"
			(at 0 0 0)
			(layer "B.SilkS")
			(hide yes)
			(effects
				(font
					(size 1.27 1.27)
				)
				(justify mirror)
			)
		)
		(property "Value" ""
			(at 0 0 0)
			(layer "B.Fab")
			(effects
				(font
					(size 1.27 1.27)
				)
				(justify mirror)
			)
		)
		(duplicate_pad_numbers_are_jumpers no)
		(fp_line
			(start 0.299974 0.150114)
			(end 0.299974 -0.150114)
			(stroke
				(width 0.1)
				(type default)
			)
			(layer "B.Fab")
		)
		(fp_line
			(start 0.299974 -0.150114)
			(end -0.299974 -0.150114)
			(stroke
				(width 0.1)
				(type default)
			)
			(layer "B.Fab")
		)
		(fp_line
			(start -0.299974 0.150114)
			(end 0.299974 0.150114)
			(stroke
				(width 0.1)
				(type default)
			)
			(layer "B.Fab")
		)
		(fp_line
			(start -0.299974 -0.150114)
			(end -0.299974 0.150114)
			(stroke
				(width 0.1)
				(type default)
			)
			(layer "B.Fab")
		)
		(pad "1" smd rect
			(at 0.2667 0)
			(size 0.3048 0.381)
			(layers "B.Cu" "B.Mask" "B.Paste")
			(net "P0V8_PEX2")
		)
		(pad "2" smd rect
			(at -0.2667 0)
			(size 0.3048 0.381)
			(layers "B.Cu" "B.Mask" "B.Paste")
			(net "GND")
		)
	)
	(footprint ""
		(layer "B.Cu")
		(at 259.16763 -87.046054 90)
		(property "Reference" "C2646"
			(at 0 0 90)
			(layer "B.SilkS")
			(hide yes)
			(effects
				(font
					(size 1.27 1.27)
				)
				(justify mirror)
			)
		)
		(property "Value" ""
			(at 0 0 90)
			(layer "B.Fab")
			(effects
				(font
					(size 1.27 1.27)
				)
				(justify mirror)
			)
		)
		(duplicate_pad_numbers_are_jumpers no)
		(fp_line
			(start 0.7874 -0.4064)
			(end -0.7874 -0.4064)
			(stroke
				(width 0.1524)
				(type default)
			)
			(layer "B.SilkS")
		)
		(fp_line
			(start -0.7874 -0.4064)
			(end -0.7874 0.4064)
			(stroke
				(width 0.1524)
				(type default)
			)
			(layer "B.SilkS")
		)
		(fp_line
			(start 0.7874 0.4064)
			(end 0.7874 -0.4064)
			(stroke
				(width 0.1524)
				(type default)
			)
			(layer "B.SilkS")
		)
		(fp_line
			(start -0.7874 0.4064)
			(end 0.7874 0.4064)
			(stroke
				(width 0.1524)
				(type default)
			)
			(layer "B.SilkS")
		)
		(fp_line
			(start 0.67945 -0.305054)
			(end 0.12065 -0.305054)
			(stroke
				(width 0.1)
				(type default)
			)
			(layer "B.Fab")
		)
		(fp_line
			(start 0.12065 -0.305054)
			(end 0.12065 -0.2794)
			(stroke
				(width 0.1)
				(type default)
			)
			(layer "B.Fab")
		)
		(fp_line
			(start -0.12065 -0.3048)
			(end -0.67945 -0.3048)
			(stroke
				(width 0.1)
				(type default)
			)
			(layer "B.Fab")
		)
		(fp_line
			(start -0.67945 -0.3048)
			(end -0.67945 0.3048)
			(stroke
				(width 0.1)
				(type default)
			)
			(layer "B.Fab")
		)
		(fp_line
			(start 0.12065 -0.2794)
			(end -0.12065 -0.2794)
			(stroke
				(width 0.1)
				(type default)
			)
			(layer "B.Fab")
		)
		(fp_line
			(start -0.12065 -0.2794)
			(end -0.12065 -0.3048)
			(stroke
				(width 0.1)
				(type default)
			)
			(layer "B.Fab")
		)
		(fp_line
			(start 0.12065 0.2794)
			(end 0.12065 0.3048)
			(stroke
				(width 0.1)
				(type default)
			)
			(layer "B.Fab")
		)
		(fp_line
			(start -0.120396 0.2794)
			(end 0.12065 0.2794)
			(stroke
				(width 0.1)
				(type default)
			)
			(layer "B.Fab")
		)
		(fp_line
			(start 0.67945 0.3048)
			(end 0.67945 -0.305054)
			(stroke
				(width 0.1)
				(type default)
			)
			(layer "B.Fab")
		)
		(fp_line
			(start 0.12065 0.3048)
			(end 0.67945 0.3048)
			(stroke
				(width 0.1)
				(type default)
			)
			(layer "B.Fab")
		)
		(fp_line
			(start -0.120396 0.3048)
			(end -0.120396 0.2794)
			(stroke
				(width 0.1)
				(type default)
			)
			(layer "B.Fab")
		)
		(fp_line
			(start -0.67945 0.3048)
			(end -0.120396 0.3048)
			(stroke
				(width 0.1)
				(type default)
			)
			(layer "B.Fab")
		)
		(pad "1" smd circle
			(at 0.40005 0 270)
			(size 0 0)
			(layers "B.Cu" "B.Mask" "B.Paste")
			(net "P3V3_CLK_GEN_VDDMXCK_CK440")
		)
		(pad "2" smd circle
			(at -0.40005 0 270)
			(size 0 0)
			(layers "B.Cu" "B.Mask" "B.Paste")
			(net "GND")
		)
	)
	(footprint ""
		(layer "B.Cu")
		(at 343.289382 -284.796738 -90)
		(property "Reference" "PC161"
			(at 0 0 90)
			(layer "B.SilkS")
			(hide yes)
			(effects
				(font
					(size 1.27 1.27)
				)
				(justify mirror)
			)
		)
		(property "Value" ""
			(at 0 0 90)
			(layer "B.Fab")
			(effects
				(font
					(size 1.27 1.27)
				)
				(justify mirror)
			)
		)
		(duplicate_pad_numbers_are_jumpers no)
		(fp_line
			(start -1.524 0.762)
			(end 1.524 0.762)
			(stroke
				(width 0.1524)
				(type default)
			)
			(layer "B.SilkS")
		)
		(fp_line
			(start 1.524 0.762)
			(end 1.524 -0.762)
			(stroke
				(width 0.1524)
				(type default)
			)
			(layer "B.SilkS")
		)
		(fp_line
			(start -1.524 -0.762)
			(end -1.524 0.762)
			(stroke
				(width 0.1524)
				(type default)
			)
			(layer "B.SilkS")
		)
		(fp_line
			(start 1.524 -0.762)
			(end -1.524 -0.762)
			(stroke
				(width 0.1524)
				(type default)
			)
			(layer "B.SilkS")
		)
		(fp_line
			(start -1.1049 0.724916)
			(end -1.1049 -0.724916)
			(stroke
				(width 0.1)
				(type default)
			)
			(layer "B.Fab")
		)
		(fp_line
			(start 1.1049 0.724916)
			(end -1.1049 0.724916)
			(stroke
				(width 0.1)
				(type default)
			)
			(layer "B.Fab")
		)
		(fp_line
			(start -1.1049 -0.724916)
			(end 1.1049 -0.724916)
			(stroke
				(width 0.1)
				(type default)
			)
			(layer "B.Fab")
		)
		(fp_line
			(start 1.1049 -0.724916)
			(end 1.1049 0.724916)
			(stroke
				(width 0.1)
				(type default)
			)
			(layer "B.Fab")
		)
		(pad "1" smd rect
			(at 0.889 0 270)
			(size 1.016 1.27)
			(layers "B.Cu" "B.Mask" "B.Paste")
			(net "SW_P12V_P0V8_PEX2_FLT")
		)
		(pad "2" smd rect
			(at -0.889 0 270)
			(size 1.016 1.27)
			(layers "B.Cu" "B.Mask" "B.Paste")
			(net "GND")
		)
	)
	(footprint ""
		(layer "B.Cu")
		(at 129.486914 -182.604664 90)
		(property "Reference" "R1122"
			(at 0 0 90)
			(layer "B.SilkS")
			(hide yes)
			(effects
				(font
					(size 1.27 1.27)
				)
				(justify mirror)
			)
		)
		(property "Value" ""
			(at 0 0 90)
			(layer "B.Fab")
			(effects
				(font
					(size 1.27 1.27)
				)
				(justify mirror)
			)
		)
		(duplicate_pad_numbers_are_jumpers no)
		(fp_line
			(start 0.7874 -0.4064)
			(end -0.7874 -0.4064)
			(stroke
				(width 0.1524)
				(type default)
			)
			(layer "B.SilkS")
		)
		(fp_line
			(start -0.7874 -0.4064)
			(end -0.7874 0.4064)
			(stroke
				(width 0.1524)
				(type default)
			)
			(layer "B.SilkS")
		)
		(fp_line
			(start 0.7874 0.4064)
			(end 0.7874 -0.4064)
			(stroke
				(width 0.1524)
				(type default)
			)
			(layer "B.SilkS")
		)
		(fp_line
			(start -0.7874 0.4064)
			(end 0.7874 0.4064)
			(stroke
				(width 0.1524)
				(type default)
			)
			(layer "B.SilkS")
		)
		(fp_line
			(start 0.67945 -0.305054)
			(end 0.12065 -0.305054)
			(stroke
				(width 0.1)
				(type default)
			)
			(layer "B.Fab")
		)
		(fp_line
			(start 0.12065 -0.305054)
			(end 0.12065 -0.2794)
			(stroke
				(width 0.1)
				(type default)
			)
			(layer "B.Fab")
		)
		(fp_line
			(start -0.12065 -0.3048)
			(end -0.67945 -0.3048)
			(stroke
				(width 0.1)
				(type default)
			)
			(layer "B.Fab")
		)
		(fp_line
			(start -0.67945 -0.3048)
			(end -0.67945 0.3048)
			(stroke
				(width 0.1)
				(type default)
			)
			(layer "B.Fab")
		)
		(fp_line
			(start 0.12065 -0.2794)
			(end -0.12065 -0.2794)
			(stroke
				(width 0.1)
				(type default)
			)
			(layer "B.Fab")
		)
		(fp_line
			(start -0.12065 -0.2794)
			(end -0.12065 -0.3048)
			(stroke
				(width 0.1)
				(type default)
			)
			(layer "B.Fab")
		)
		(fp_line
			(start 0.12065 0.2794)
			(end 0.12065 0.3048)
			(stroke
				(width 0.1)
				(type default)
			)
			(layer "B.Fab")
		)
		(fp_line
			(start -0.120396 0.2794)
			(end 0.12065 0.2794)
			(stroke
				(width 0.1)
				(type default)
			)
			(layer "B.Fab")
		)
		(fp_line
			(start 0.67945 0.3048)
			(end 0.67945 -0.305054)
			(stroke
				(width 0.1)
				(type default)
			)
			(layer "B.Fab")
		)
		(fp_line
			(start 0.12065 0.3048)
			(end 0.67945 0.3048)
			(stroke
				(width 0.1)
				(type default)
			)
			(layer "B.Fab")
		)
		(fp_line
			(start -0.120396 0.3048)
			(end -0.120396 0.2794)
			(stroke
				(width 0.1)
				(type default)
			)
			(layer "B.Fab")
		)
		(fp_line
			(start -0.67945 0.3048)
			(end -0.120396 0.3048)
			(stroke
				(width 0.1)
				(type default)
			)
			(layer "B.Fab")
		)
		(pad "1" smd circle
			(at 0.40005 0 270)
			(size 0 0)
			(layers "B.Cu" "B.Mask" "B.Paste")
			(net "GND")
		)
		(pad "2" smd circle
			(at -0.40005 0 270)
			(size 0 0)
			(layers "B.Cu" "B.Mask" "B.Paste")
			(net "FM_DB2000QL_SMB_SA0")
		)
	)
	(footprint ""
		(layer "B.Cu")
		(at 116.128292 -303.141634 180)
		(property "Reference" "PR76"
			(at 0 0 0)
			(layer "B.SilkS")
			(hide yes)
			(effects
				(font
					(size 1.27 1.27)
				)
				(justify mirror)
			)
		)
		(property "Value" ""
			(at 0 0 0)
			(layer "B.Fab")
			(effects
				(font
					(size 1.27 1.27)
				)
				(justify mirror)
			)
		)
		(duplicate_pad_numbers_are_jumpers no)
		(fp_line
			(start 0.7874 0.4064)
			(end 0.7874 -0.4064)
			(stroke
				(width 0.1524)
				(type default)
			)
			(layer "B.SilkS")
		)
		(fp_line
			(start 0.7874 -0.4064)
			(end -0.7874 -0.4064)
			(stroke
				(width 0.1524)
				(type default)
			)
			(layer "B.SilkS")
		)
		(fp_line
			(start -0.7874 0.4064)
			(end 0.7874 0.4064)
			(stroke
				(width 0.1524)
				(type default)
			)
			(layer "B.SilkS")
		)
		(fp_line
			(start -0.7874 -0.4064)
			(end -0.7874 0.4064)
			(stroke
				(width 0.1524)
				(type default)
			)
			(layer "B.SilkS")
		)
		(fp_line
			(start 0.67945 0.3048)
			(end 0.67945 -0.305054)
			(stroke
				(width 0.1)
				(type default)
			)
			(layer "B.Fab")
		)
		(fp_line
			(start 0.67945 -0.305054)
			(end 0.12065 -0.305054)
			(stroke
				(width 0.1)
				(type default)
			)
			(layer "B.Fab")
		)
		(fp_line
			(start 0.12065 0.3048)
			(end 0.67945 0.3048)
			(stroke
				(width 0.1)
				(type default)
			)
			(layer "B.Fab")
		)
		(fp_line
			(start 0.12065 0.2794)
			(end 0.12065 0.3048)
			(stroke
				(width 0.1)
				(type default)
			)
			(layer "B.Fab")
		)
		(fp_line
			(start 0.12065 -0.2794)
			(end -0.12065 -0.2794)
			(stroke
				(width 0.1)
				(type default)
			)
			(layer "B.Fab")
		)
		(fp_line
			(start 0.12065 -0.305054)
			(end 0.12065 -0.2794)
			(stroke
				(width 0.1)
				(type default)
			)
			(layer "B.Fab")
		)
		(fp_line
			(start -0.120396 0.3048)
			(end -0.120396 0.2794)
			(stroke
				(width 0.1)
				(type default)
			)
			(layer "B.Fab")
		)
		(fp_line
			(start -0.120396 0.2794)
			(end 0.12065 0.2794)
			(stroke
				(width 0.1)
				(type default)
			)
			(layer "B.Fab")
		)
		(fp_line
			(start -0.12065 -0.2794)
			(end -0.12065 -0.3048)
			(stroke
				(width 0.1)
				(type default)
			)
			(layer "B.Fab")
		)
		(fp_line
			(start -0.12065 -0.3048)
			(end -0.67945 -0.3048)
			(stroke
				(width 0.1)
				(type default)
			)
			(layer "B.Fab")
		)
		(fp_line
			(start -0.67945 0.3048)
			(end -0.120396 0.3048)
			(stroke
				(width 0.1)
				(type default)
			)
			(layer "B.Fab")
		)
		(fp_line
			(start -0.67945 -0.3048)
			(end -0.67945 0.3048)
			(stroke
				(width 0.1)
				(type default)
			)
			(layer "B.Fab")
		)
		(pad "1" smd circle
			(at 0.40005 0)
			(size 0 0)
			(layers "B.Cu" "B.Mask" "B.Paste")
			(net "P0V8_PEX0")
		)
		(pad "2" smd circle
			(at -0.40005 0)
			(size 0 0)
			(layers "B.Cu" "B.Mask" "B.Paste")
			(net "SH_P0V8_PEX0_VSEN0_L")
		)
	)
	(footprint ""
		(layer "B.Cu")
		(at 288.049716 -301.599854 -90)
		(property "Reference" "C1733"
			(at 0 0 90)
			(layer "B.SilkS")
			(hide yes)
			(effects
				(font
					(size 1.27 1.27)
				)
				(justify mirror)
			)
		)
		(property "Value" ""
			(at 0 0 90)
			(layer "B.Fab")
			(effects
				(font
					(size 1.27 1.27)
				)
				(justify mirror)
			)
		)
		(duplicate_pad_numbers_are_jumpers no)
		(fp_line
			(start -0.299974 0.150114)
			(end 0.299974 0.150114)
			(stroke
				(width 0.1)
				(type default)
			)
			(layer "B.Fab")
		)
		(fp_line
			(start 0.299974 0.150114)
			(end 0.299974 -0.150114)
			(stroke
				(width 0.1)
				(type default)
			)
			(layer "B.Fab")
		)
		(fp_line
			(start -0.299974 -0.150114)
			(end -0.299974 0.150114)
			(stroke
				(width 0.1)
				(type default)
			)
			(layer "B.Fab")
		)
		(fp_line
			(start 0.299974 -0.150114)
			(end -0.299974 -0.150114)
			(stroke
				(width 0.1)
				(type default)
			)
			(layer "B.Fab")
		)
		(pad "1" smd rect
			(at 0.2667 0 90)
			(size 0.3048 0.381)
			(layers "B.Cu" "B.Mask" "B.Paste")
			(net "P0V8_SERDES_VDDA_PEX2")
		)
		(pad "2" smd rect
			(at -0.2667 0 90)
			(size 0.3048 0.381)
			(layers "B.Cu" "B.Mask" "B.Paste")
			(net "GND")
		)
	)
	(footprint ""
		(layer "B.Cu")
		(at 227.067618 -220.704156 180)
		(property "Reference" "C3624"
			(at 0 0 0)
			(layer "B.SilkS")
			(hide yes)
			(effects
				(font
					(size 1.27 1.27)
				)
				(justify mirror)
			)
		)
		(property "Value" ""
			(at 0 0 0)
			(layer "B.Fab")
			(effects
				(font
					(size 1.27 1.27)
				)
				(justify mirror)
			)
		)
		(duplicate_pad_numbers_are_jumpers no)
		(fp_line
			(start 0.69215 0.2921)
			(end 0.69215 -0.2921)
			(stroke
				(width 0.1524)
				(type default)
			)
			(layer "B.SilkS")
		)
		(fp_line
			(start 0.69215 -0.2921)
			(end -0.69215 -0.2921)
			(stroke
				(width 0.1524)
				(type default)
			)
			(layer "B.SilkS")
		)
		(fp_line
			(start -0.69215 0.2921)
			(end 0.69215 0.2921)
			(stroke
				(width 0.1524)
				(type default)
			)
			(layer "B.SilkS")
		)
		(fp_line
			(start -0.69215 -0.2921)
			(end -0.69215 0.2921)
			(stroke
				(width 0.1524)
				(type default)
			)
			(layer "B.SilkS")
		)
		(fp_line
			(start 0.51435 0.2794)
			(end 0.51435 -0.2794)
			(stroke
				(width 0.1)
				(type default)
			)
			(layer "B.Fab")
		)
		(fp_line
			(start 0.51435 -0.2794)
			(end -0.51435 -0.2794)
			(stroke
				(width 0.1)
				(type default)
			)
			(layer "B.Fab")
		)
		(fp_line
			(start -0.51435 0.2794)
			(end 0.51435 0.2794)
			(stroke
				(width 0.1)
				(type default)
			)
			(layer "B.Fab")
		)
		(fp_line
			(start -0.51435 -0.2794)
			(end -0.51435 0.2794)
			(stroke
				(width 0.1)
				(type default)
			)
			(layer "B.Fab")
		)
		(pad "1" smd circle
			(at 0.40005 0)
			(size 0 0)
			(layers "B.Cu" "B.Mask" "B.Paste")
			(net "P3V3_AUX")
		)
		(pad "2" smd circle
			(at -0.40005 0)
			(size 0 0)
			(layers "B.Cu" "B.Mask" "B.Paste")
			(net "GND")
		)
		(zone
			(layer "B.Cu")
			(hatch none 0.5)
			(connect_pads
				(clearance 0)
			)
			(min_thickness 0.25)
			(keepout
				(tracks not_allowed)
				(vias allowed)
				(pads allowed)
				(copperpour not_allowed)
				(footprints allowed)
			)
			(placement
				(enabled no)
				(sheetname "")
			)
			(fill
				(thermal_gap 0.5)
				(thermal_bridge_width 0.5)
				(island_removal_mode 0)
			)
			(polygon
				(pts
					(xy 226.877118 -220.791786) (xy 226.968558 -220.849952) (xy 227.167948 -220.849952) (xy 227.258118 -220.791786)
					(xy 227.258118 -220.616526) (xy 227.167948 -220.558106) (xy 226.968558 -220.558106) (xy 226.877118 -220.616272)
				)
			)
		)
	)
	(footprint ""
		(layer "B.Cu")
		(at 170.999912 -292.099746 90)
		(property "Reference" "C1456"
			(at 0 0 90)
			(layer "B.SilkS")
			(hide yes)
			(effects
				(font
					(size 1.27 1.27)
				)
				(justify mirror)
			)
		)
		(property "Value" ""
			(at 0 0 90)
			(layer "B.Fab")
			(effects
				(font
					(size 1.27 1.27)
				)
				(justify mirror)
			)
		)
		(duplicate_pad_numbers_are_jumpers no)
		(fp_line
			(start 0.299974 -0.150114)
			(end -0.299974 -0.150114)
			(stroke
				(width 0.1)
				(type default)
			)
			(layer "B.Fab")
		)
		(fp_line
			(start -0.299974 -0.150114)
			(end -0.299974 0.150114)
			(stroke
				(width 0.1)
				(type default)
			)
			(layer "B.Fab")
		)
		(fp_line
			(start 0.299974 0.150114)
			(end 0.299974 -0.150114)
			(stroke
				(width 0.1)
				(type default)
			)
			(layer "B.Fab")
		)
		(fp_line
			(start -0.299974 0.150114)
			(end 0.299974 0.150114)
			(stroke
				(width 0.1)
				(type default)
			)
			(layer "B.Fab")
		)
		(pad "1" smd rect
			(at 0.2667 0 270)
			(size 0.3048 0.381)
			(layers "B.Cu" "B.Mask" "B.Paste")
			(net "P0V8_SERDES_VDDA_PEX1")
		)
		(pad "2" smd rect
			(at -0.2667 0 270)
			(size 0.3048 0.381)
			(layers "B.Cu" "B.Mask" "B.Paste")
			(net "GND")
		)
	)
	(footprint ""
		(layer "B.Cu")
		(at 394.42644 -139.8016 180)
		(property "Reference" "C945"
			(at 0 0 0)
			(layer "B.SilkS")
			(hide yes)
			(effects
				(font
					(size 1.27 1.27)
				)
				(justify mirror)
			)
		)
		(property "Value" ""
			(at 0 0 0)
			(layer "B.Fab")
			(effects
				(font
					(size 1.27 1.27)
				)
				(justify mirror)
			)
		)
		(duplicate_pad_numbers_are_jumpers no)
		(fp_line
			(start 0.7874 0.4064)
			(end 0.7874 -0.4064)
			(stroke
				(width 0.1524)
				(type default)
			)
			(layer "B.SilkS")
		)
		(fp_line
			(start 0.7874 -0.4064)
			(end -0.7874 -0.4064)
			(stroke
				(width 0.1524)
				(type default)
			)
			(layer "B.SilkS")
		)
		(fp_line
			(start -0.7874 0.4064)
			(end 0.7874 0.4064)
			(stroke
				(width 0.1524)
				(type default)
			)
			(layer "B.SilkS")
		)
		(fp_line
			(start -0.7874 -0.4064)
			(end -0.7874 0.4064)
			(stroke
				(width 0.1524)
				(type default)
			)
			(layer "B.SilkS")
		)
		(fp_line
			(start 0.67945 0.3048)
			(end 0.67945 -0.305054)
			(stroke
				(width 0.1)
				(type default)
			)
			(layer "B.Fab")
		)
		(fp_line
			(start 0.67945 -0.305054)
			(end 0.12065 -0.305054)
			(stroke
				(width 0.1)
				(type default)
			)
			(layer "B.Fab")
		)
		(fp_line
			(start 0.12065 0.3048)
			(end 0.67945 0.3048)
			(stroke
				(width 0.1)
				(type default)
			)
			(layer "B.Fab")
		)
		(fp_line
			(start 0.12065 0.2794)
			(end 0.12065 0.3048)
			(stroke
				(width 0.1)
				(type default)
			)
			(layer "B.Fab")
		)
		(fp_line
			(start 0.12065 -0.2794)
			(end -0.12065 -0.2794)
			(stroke
				(width 0.1)
				(type default)
			)
			(layer "B.Fab")
		)
		(fp_line
			(start 0.12065 -0.305054)
			(end 0.12065 -0.2794)
			(stroke
				(width 0.1)
				(type default)
			)
			(layer "B.Fab")
		)
		(fp_line
			(start -0.120396 0.3048)
			(end -0.120396 0.2794)
			(stroke
				(width 0.1)
				(type default)
			)
			(layer "B.Fab")
		)
		(fp_line
			(start -0.120396 0.2794)
			(end 0.12065 0.2794)
			(stroke
				(width 0.1)
				(type default)
			)
			(layer "B.Fab")
		)
		(fp_line
			(start -0.12065 -0.2794)
			(end -0.12065 -0.3048)
			(stroke
				(width 0.1)
				(type default)
			)
			(layer "B.Fab")
		)
		(fp_line
			(start -0.12065 -0.3048)
			(end -0.67945 -0.3048)
			(stroke
				(width 0.1)
				(type default)
			)
			(layer "B.Fab")
		)
		(fp_line
			(start -0.67945 0.3048)
			(end -0.120396 0.3048)
			(stroke
				(width 0.1)
				(type default)
			)
			(layer "B.Fab")
		)
		(fp_line
			(start -0.67945 -0.3048)
			(end -0.67945 0.3048)
			(stroke
				(width 0.1)
				(type default)
			)
			(layer "B.Fab")
		)
		(pad "1" smd circle
			(at 0.40005 0)
			(size 0 0)
			(layers "B.Cu" "B.Mask" "B.Paste")
			(net "P3V3_NIC6")
		)
		(pad "2" smd circle
			(at -0.40005 0)
			(size 0 0)
			(layers "B.Cu" "B.Mask" "B.Paste")
			(net "GND")
		)
	)
	(footprint ""
		(layer "B.Cu")
		(at 398.925034 -297.79976 -90)
		(property "Reference" "C1905"
			(at 0 0 90)
			(layer "B.SilkS")
			(hide yes)
			(effects
				(font
					(size 1.27 1.27)
				)
				(justify mirror)
			)
		)
		(property "Value" ""
			(at 0 0 90)
			(layer "B.Fab")
			(effects
				(font
					(size 1.27 1.27)
				)
				(justify mirror)
			)
		)
		(duplicate_pad_numbers_are_jumpers no)
		(fp_line
			(start -0.299974 0.150114)
			(end 0.299974 0.150114)
			(stroke
				(width 0.1)
				(type default)
			)
			(layer "B.Fab")
		)
		(fp_line
			(start 0.299974 0.150114)
			(end 0.299974 -0.150114)
			(stroke
				(width 0.1)
				(type default)
			)
			(layer "B.Fab")
		)
		(fp_line
			(start -0.299974 -0.150114)
			(end -0.299974 0.150114)
			(stroke
				(width 0.1)
				(type default)
			)
			(layer "B.Fab")
		)
		(fp_line
			(start 0.299974 -0.150114)
			(end -0.299974 -0.150114)
			(stroke
				(width 0.1)
				(type default)
			)
			(layer "B.Fab")
		)
		(pad "1" smd rect
			(at 0.2667 0 90)
			(size 0.3048 0.381)
			(layers "B.Cu" "B.Mask" "B.Paste")
			(net "P0V8_PEX3")
		)
		(pad "2" smd rect
			(at -0.2667 0 90)
			(size 0.3048 0.381)
			(layers "B.Cu" "B.Mask" "B.Paste")
			(net "GND")
		)
	)
	(footprint ""
		(layer "B.Cu")
		(at 52.524914 -297.79976 -90)
		(property "Reference" "C1122"
			(at 0 0 90)
			(layer "B.SilkS")
			(hide yes)
			(effects
				(font
					(size 1.27 1.27)
				)
				(justify mirror)
			)
		)
		(property "Value" ""
			(at 0 0 90)
			(layer "B.Fab")
			(effects
				(font
					(size 1.27 1.27)
				)
				(justify mirror)
			)
		)
		(duplicate_pad_numbers_are_jumpers no)
		(fp_line
			(start -0.299974 0.150114)
			(end 0.299974 0.150114)
			(stroke
				(width 0.1)
				(type default)
			)
			(layer "B.Fab")
		)
		(fp_line
			(start 0.299974 0.150114)
			(end 0.299974 -0.150114)
			(stroke
				(width 0.1)
				(type default)
			)
			(layer "B.Fab")
		)
		(fp_line
			(start -0.299974 -0.150114)
			(end -0.299974 0.150114)
			(stroke
				(width 0.1)
				(type default)
			)
			(layer "B.Fab")
		)
		(fp_line
			(start 0.299974 -0.150114)
			(end -0.299974 -0.150114)
			(stroke
				(width 0.1)
				(type default)
			)
			(layer "B.Fab")
		)
		(pad "1" smd rect
			(at 0.2667 0 90)
			(size 0.3048 0.381)
			(layers "B.Cu" "B.Mask" "B.Paste")
			(net "P0V8_PEX0")
		)
		(pad "2" smd rect
			(at -0.2667 0 90)
			(size 0.3048 0.381)
			(layers "B.Cu" "B.Mask" "B.Paste")
			(net "GND")
		)
	)
	(footprint ""
		(layer "B.Cu")
		(at 242.110768 8.076692)
		(property "Reference" "DE12T_2"
			(at 2.694432 3.303778 0)
			(unlocked yes)
			(layer "B.SilkS")
			(effects
				(font
					(size 0.7874 0.5842)
					(thickness 0.1524)
				)
				(justify left mirror)
			)
		)
		(property "Value" ""
			(at 0 0 0)
			(layer "B.Fab")
			(effects
				(font
					(size 1.27 1.27)
				)
				(justify mirror)
			)
		)
		(duplicate_pad_numbers_are_jumpers no)
		(fp_line
			(start -1.2192 -2.1082)
			(end -1.2192 2.1082)
			(stroke
				(width 0.1524)
				(type default)
			)
			(layer "B.SilkS")
		)
		(fp_line
			(start -1.2192 2.1082)
			(end 1.2192 2.1082)
			(stroke
				(width 0.1524)
				(type default)
			)
			(layer "B.SilkS")
		)
		(fp_line
			(start 1.2192 -2.1082)
			(end -1.2192 -2.1082)
			(stroke
				(width 0.1524)
				(type default)
			)
			(layer "B.SilkS")
		)
		(fp_line
			(start 1.2192 2.1082)
			(end 1.2192 -2.1082)
			(stroke
				(width 0.1524)
				(type default)
			)
			(layer "B.SilkS")
		)
		(pad "" np_thru_hole circle
			(at -3.4671 -1.27 270)
			(size 1.0414 1.0414)
			(drill 1.0414)
			(layers "*.Cu" "*.Mask")
			(clearance 0.381)
			(thermal_gap 0.381)
		)
		(pad "" np_thru_hole circle
			(at -3.4671 1.27 270)
			(size 1.0414 1.0414)
			(drill 1.0414)
			(layers "*.Cu" "*.Mask")
			(clearance 0.381)
			(thermal_gap 0.381)
		)
		(pad "" np_thru_hole circle
			(at 2.8829 -1.27 270)
			(size 1.0414 1.0414)
			(drill 1.0414)
			(layers "*.Cu" "*.Mask")
			(clearance 0.381)
			(thermal_gap 0.381)
		)
		(pad "" np_thru_hole circle
			(at 2.8829 1.27 270)
			(size 1.0414 1.0414)
			(drill 1.0414)
			(layers "*.Cu" "*.Mask")
			(clearance 0.381)
			(thermal_gap 0.381)
		)
		(pad "1" smd rect
			(at -0.8255 -0.249936 270)
			(size 0.3048 0.508)
			(layers "B.Cu" "B.Mask" "B.Paste")
			(net "85_10INCH_BOTTOM_DN")
		)
		(pad "2" smd rect
			(at -0.8255 0.249936 270)
			(size 0.3048 0.508)
			(layers "B.Cu" "B.Mask" "B.Paste")
			(net "85_10INCH_BOTTOM_DP")
		)
		(pad "3" smd circle
			(at 0 0 180)
			(size 0 0)
			(layers "B.Cu" "B.Mask" "B.Paste")
			(net "COUPON_GND2")
		)
		(zone
			(layers "F.Cu" "B.Cu" "In1.Cu" "In2.Cu" "In3.Cu" "In4.Cu" "In5.Cu" "In6.Cu"
				"In7.Cu" "In8.Cu" "In9.Cu" "In10.Cu" "In11.Cu" "In12.Cu" "In13.Cu" "In14.Cu"
				"In15.Cu" "In16.Cu"
			)
			(hatch none 0.5)
			(connect_pads
				(clearance 0)
			)
			(min_thickness 0.25)
			(keepout
				(tracks not_allowed)
				(vias allowed)
				(pads allowed)
				(copperpour not_allowed)
				(footprints allowed)
			)
			(placement
				(enabled no)
				(sheetname "")
			)
			(fill
				(thermal_gap 0.5)
				(thermal_bridge_width 0.5)
				(island_removal_mode 0)
			)
			(polygon
				(pts
					(arc
						(start 239.570768 6.806692)
						(mid 237.716568 6.806692)
						(end 239.570768 6.806692)
					)
				)
			)
		)
		(zone
			(layers "F.Cu" "B.Cu" "In1.Cu" "In2.Cu" "In3.Cu" "In4.Cu" "In5.Cu" "In6.Cu"
				"In7.Cu" "In8.Cu" "In9.Cu" "In10.Cu" "In11.Cu" "In12.Cu" "In13.Cu" "In14.Cu"
				"In15.Cu" "In16.Cu"
			)
			(hatch none 0.5)
			(connect_pads
				(clearance 0)
			)
			(min_thickness 0.25)
			(keepout
				(tracks not_allowed)
				(vias allowed)
				(pads allowed)
				(copperpour not_allowed)
				(footprints allowed)
			)
			(placement
				(enabled no)
				(sheetname "")
			)
			(fill
				(thermal_gap 0.5)
				(thermal_bridge_width 0.5)
				(island_removal_mode 0)
			)
			(polygon
				(pts
					(arc
						(start 239.570768 9.346692)
						(mid 237.716568 9.346692)
						(end 239.570768 9.346692)
					)
				)
			)
		)
		(zone
			(layers "F.Cu" "B.Cu" "In1.Cu" "In2.Cu" "In3.Cu" "In4.Cu" "In5.Cu" "In6.Cu"
				"In7.Cu" "In8.Cu" "In9.Cu" "In10.Cu" "In11.Cu" "In12.Cu" "In13.Cu" "In14.Cu"
				"In15.Cu" "In16.Cu"
			)
			(hatch none 0.5)
			(connect_pads
				(clearance 0)
			)
			(min_thickness 0.25)
			(keepout
				(tracks not_allowed)
				(vias allowed)
				(pads allowed)
				(copperpour not_allowed)
				(footprints allowed)
			)
			(placement
				(enabled no)
				(sheetname "")
			)
			(fill
				(thermal_gap 0.5)
				(thermal_bridge_width 0.5)
				(island_removal_mode 0)
			)
			(polygon
				(pts
					(arc
						(start 245.920768 6.806692)
						(mid 244.066568 6.806692)
						(end 245.920768 6.806692)
					)
				)
			)
		)
		(zone
			(layers "F.Cu" "B.Cu" "In1.Cu" "In2.Cu" "In3.Cu" "In4.Cu" "In5.Cu" "In6.Cu"
				"In7.Cu" "In8.Cu" "In9.Cu" "In10.Cu" "In11.Cu" "In12.Cu" "In13.Cu" "In14.Cu"
				"In15.Cu" "In16.Cu"
			)
			(hatch none 0.5)
			(connect_pads
				(clearance 0)
			)
			(min_thickness 0.25)
			(keepout
				(tracks not_allowed)
				(vias allowed)
				(pads allowed)
				(copperpour not_allowed)
				(footprints allowed)
			)
			(placement
				(enabled no)
				(sheetname "")
			)
			(fill
				(thermal_gap 0.5)
				(thermal_bridge_width 0.5)
				(island_removal_mode 0)
			)
			(polygon
				(pts
					(arc
						(start 245.920768 9.346692)
						(mid 244.066568 9.346692)
						(end 245.920768 9.346692)
					)
				)
			)
		)
		(zone
			(layer "B.Cu")
			(hatch none 0.5)
			(connect_pads
				(clearance 0)
			)
			(min_thickness 0.25)
			(keepout
				(tracks not_allowed)
				(vias allowed)
				(pads allowed)
				(copperpour not_allowed)
				(footprints allowed)
			)
			(placement
				(enabled no)
				(sheetname "")
			)
			(fill
				(thermal_gap 0.5)
				(thermal_bridge_width 0.5)
				(island_removal_mode 0)
			)
			(polygon
				(pts
					(xy 240.993168 7.528052) (xy 240.993168 7.623556) (xy 241.590068 7.623556) (xy 241.590068 8.029956)
					(xy 240.993168 8.029956) (xy 240.993168 8.123428) (xy 241.590068 8.123428) (xy 241.590068 8.529828)
					(xy 240.993168 8.529828) (xy 240.993168 8.625332) (xy 241.691668 8.625332) (xy 241.691668 7.528052)
				)
			)
		)
	)
	(footprint ""
		(layer "B.Cu")
		(at 140.559282 -226.535996 -90)
		(property "Reference" "R3468"
			(at 0 0 90)
			(layer "B.SilkS")
			(hide yes)
			(effects
				(font
					(size 1.27 1.27)
				)
				(justify mirror)
			)
		)
		(property "Value" ""
			(at 0 0 90)
			(layer "B.Fab")
			(effects
				(font
					(size 1.27 1.27)
				)
				(justify mirror)
			)
		)
		(duplicate_pad_numbers_are_jumpers no)
		(fp_line
			(start -0.7874 0.4064)
			(end 0.7874 0.4064)
			(stroke
				(width 0.1524)
				(type default)
			)
			(layer "B.SilkS")
		)
		(fp_line
			(start 0.7874 0.4064)
			(end 0.7874 -0.4064)
			(stroke
				(width 0.1524)
				(type default)
			)
			(layer "B.SilkS")
		)
		(fp_line
			(start -0.7874 -0.4064)
			(end -0.7874 0.4064)
			(stroke
				(width 0.1524)
				(type default)
			)
			(layer "B.SilkS")
		)
		(fp_line
			(start 0.7874 -0.4064)
			(end -0.7874 -0.4064)
			(stroke
				(width 0.1524)
				(type default)
			)
			(layer "B.SilkS")
		)
		(fp_line
			(start -0.67945 0.3048)
			(end -0.120396 0.3048)
			(stroke
				(width 0.1)
				(type default)
			)
			(layer "B.Fab")
		)
		(fp_line
			(start -0.120396 0.3048)
			(end -0.120396 0.2794)
			(stroke
				(width 0.1)
				(type default)
			)
			(layer "B.Fab")
		)
		(fp_line
			(start 0.12065 0.3048)
			(end 0.67945 0.3048)
			(stroke
				(width 0.1)
				(type default)
			)
			(layer "B.Fab")
		)
		(fp_line
			(start 0.67945 0.3048)
			(end 0.67945 -0.305054)
			(stroke
				(width 0.1)
				(type default)
			)
			(layer "B.Fab")
		)
		(fp_line
			(start -0.120396 0.2794)
			(end 0.12065 0.2794)
			(stroke
				(width 0.1)
				(type default)
			)
			(layer "B.Fab")
		)
		(fp_line
			(start 0.12065 0.2794)
			(end 0.12065 0.3048)
			(stroke
				(width 0.1)
				(type default)
			)
			(layer "B.Fab")
		)
		(fp_line
			(start -0.12065 -0.2794)
			(end -0.12065 -0.3048)
			(stroke
				(width 0.1)
				(type default)
			)
			(layer "B.Fab")
		)
		(fp_line
			(start 0.12065 -0.2794)
			(end -0.12065 -0.2794)
			(stroke
				(width 0.1)
				(type default)
			)
			(layer "B.Fab")
		)
		(fp_line
			(start -0.67945 -0.3048)
			(end -0.67945 0.3048)
			(stroke
				(width 0.1)
				(type default)
			)
			(layer "B.Fab")
		)
		(fp_line
			(start -0.12065 -0.3048)
			(end -0.67945 -0.3048)
			(stroke
				(width 0.1)
				(type default)
			)
			(layer "B.Fab")
		)
		(fp_line
			(start 0.12065 -0.305054)
			(end 0.12065 -0.2794)
			(stroke
				(width 0.1)
				(type default)
			)
			(layer "B.Fab")
		)
		(fp_line
			(start 0.67945 -0.305054)
			(end 0.12065 -0.305054)
			(stroke
				(width 0.1)
				(type default)
			)
			(layer "B.Fab")
		)
		(pad "1" smd circle
			(at 0.40005 0 90)
			(size 0 0)
			(layers "B.Cu" "B.Mask" "B.Paste")
			(net "P1V8_PEX")
		)
		(pad "2" smd circle
			(at -0.40005 0 90)
			(size 0 0)
			(layers "B.Cu" "B.Mask" "B.Paste")
			(net "SPI_PEX1_CS_MUX_R_N")
		)
	)
	(footprint ""
		(layer "B.Cu")
		(at 169.099992 -290.199826 90)
		(property "Reference" "C1431"
			(at 0 0 90)
			(layer "B.SilkS")
			(hide yes)
			(effects
				(font
					(size 1.27 1.27)
				)
				(justify mirror)
			)
		)
		(property "Value" ""
			(at 0 0 90)
			(layer "B.Fab")
			(effects
				(font
					(size 1.27 1.27)
				)
				(justify mirror)
			)
		)
		(duplicate_pad_numbers_are_jumpers no)
		(fp_line
			(start 0.299974 -0.150114)
			(end -0.299974 -0.150114)
			(stroke
				(width 0.1)
				(type default)
			)
			(layer "B.Fab")
		)
		(fp_line
			(start -0.299974 -0.150114)
			(end -0.299974 0.150114)
			(stroke
				(width 0.1)
				(type default)
			)
			(layer "B.Fab")
		)
		(fp_line
			(start 0.299974 0.150114)
			(end 0.299974 -0.150114)
			(stroke
				(width 0.1)
				(type default)
			)
			(layer "B.Fab")
		)
		(fp_line
			(start -0.299974 0.150114)
			(end 0.299974 0.150114)
			(stroke
				(width 0.1)
				(type default)
			)
			(layer "B.Fab")
		)
		(pad "1" smd rect
			(at 0.2667 0 270)
			(size 0.3048 0.381)
			(layers "B.Cu" "B.Mask" "B.Paste")
			(net "P0V8_SERDES_VDDA_PEX1")
		)
		(pad "2" smd rect
			(at -0.2667 0 270)
			(size 0.3048 0.381)
			(layers "B.Cu" "B.Mask" "B.Paste")
			(net "GND")
		)
	)
	(footprint ""
		(layer "B.Cu")
		(at 345.293442 -220.38691 90)
		(property "Reference" "C2046"
			(at 0 0 90)
			(layer "B.SilkS")
			(hide yes)
			(effects
				(font
					(size 1.27 1.27)
				)
				(justify mirror)
			)
		)
		(property "Value" ""
			(at 0 0 90)
			(layer "B.Fab")
			(effects
				(font
					(size 1.27 1.27)
				)
				(justify mirror)
			)
		)
		(duplicate_pad_numbers_are_jumpers no)
		(fp_line
			(start 0.69215 -0.2921)
			(end -0.69215 -0.2921)
			(stroke
				(width 0.1524)
				(type default)
			)
			(layer "B.SilkS")
		)
		(fp_line
			(start -0.69215 -0.2921)
			(end -0.69215 0.2921)
			(stroke
				(width 0.1524)
				(type default)
			)
			(layer "B.SilkS")
		)
		(fp_line
			(start 0.69215 0.2921)
			(end 0.69215 -0.2921)
			(stroke
				(width 0.1524)
				(type default)
			)
			(layer "B.SilkS")
		)
		(fp_line
			(start -0.69215 0.2921)
			(end 0.69215 0.2921)
			(stroke
				(width 0.1524)
				(type default)
			)
			(layer "B.SilkS")
		)
		(fp_line
			(start 0.51435 -0.2794)
			(end -0.51435 -0.2794)
			(stroke
				(width 0.1)
				(type default)
			)
			(layer "B.Fab")
		)
		(fp_line
			(start -0.51435 -0.2794)
			(end -0.51435 0.2794)
			(stroke
				(width 0.1)
				(type default)
			)
			(layer "B.Fab")
		)
		(fp_line
			(start 0.51435 0.2794)
			(end 0.51435 -0.2794)
			(stroke
				(width 0.1)
				(type default)
			)
			(layer "B.Fab")
		)
		(fp_line
			(start -0.51435 0.2794)
			(end 0.51435 0.2794)
			(stroke
				(width 0.1)
				(type default)
			)
			(layer "B.Fab")
		)
		(pad "1" smd circle
			(at 0.40005 0 270)
			(size 0 0)
			(layers "B.Cu" "B.Mask" "B.Paste")
			(net "P3V3_FPGA_VCCIO1")
		)
		(pad "2" smd circle
			(at -0.40005 0 270)
			(size 0 0)
			(layers "B.Cu" "B.Mask" "B.Paste")
			(net "GND")
		)
		(zone
			(layer "B.Cu")
			(hatch none 0.5)
			(connect_pads
				(clearance 0)
			)
			(min_thickness 0.25)
			(keepout
				(tracks not_allowed)
				(vias allowed)
				(pads allowed)
				(copperpour not_allowed)
				(footprints allowed)
			)
			(placement
				(enabled no)
				(sheetname "")
			)
			(fill
				(thermal_gap 0.5)
				(thermal_bridge_width 0.5)
				(island_removal_mode 0)
			)
			(polygon
				(pts
					(xy 345.381072 -220.57741) (xy 345.439238 -220.48597) (xy 345.439238 -220.28658) (xy 345.381072 -220.19641)
					(xy 345.205812 -220.19641) (xy 345.147392 -220.28658) (xy 345.147392 -220.48597) (xy 345.205558 -220.57741)
				)
			)
		)
	)
	(footprint ""
		(layer "B.Cu")
		(at 290.370006 -305.399948 -90)
		(property "Reference" "C3330"
			(at 0 0 90)
			(layer "B.SilkS")
			(hide yes)
			(effects
				(font
					(size 1.27 1.27)
				)
				(justify mirror)
			)
		)
		(property "Value" ""
			(at 0 0 90)
			(layer "B.Fab")
			(effects
				(font
					(size 1.27 1.27)
				)
				(justify mirror)
			)
		)
		(duplicate_pad_numbers_are_jumpers no)
		(fp_line
			(start -0.299974 0.150114)
			(end 0.299974 0.150114)
			(stroke
				(width 0.1)
				(type default)
			)
			(layer "B.Fab")
		)
		(fp_line
			(start 0.299974 0.150114)
			(end 0.299974 -0.150114)
			(stroke
				(width 0.1)
				(type default)
			)
			(layer "B.Fab")
		)
		(fp_line
			(start -0.299974 -0.150114)
			(end -0.299974 0.150114)
			(stroke
				(width 0.1)
				(type default)
			)
			(layer "B.Fab")
		)
		(fp_line
			(start 0.299974 -0.150114)
			(end -0.299974 -0.150114)
			(stroke
				(width 0.1)
				(type default)
			)
			(layer "B.Fab")
		)
		(pad "1" smd rect
			(at 0.2667 0 90)
			(size 0.3048 0.381)
			(layers "B.Cu" "B.Mask" "B.Paste")
			(net "P1V25_SERDES_VDDPLL_PEX2")
		)
		(pad "2" smd rect
			(at -0.2667 0 90)
			(size 0.3048 0.381)
			(layers "B.Cu" "B.Mask" "B.Paste")
			(net "GND")
		)
	)
	(footprint ""
		(layer "B.Cu")
		(at 419.349936 -296.37482 180)
		(property "Reference" "C3459"
			(at 0 0 0)
			(layer "B.SilkS")
			(hide yes)
			(effects
				(font
					(size 1.27 1.27)
				)
				(justify mirror)
			)
		)
		(property "Value" ""
			(at 0 0 0)
			(layer "B.Fab")
			(effects
				(font
					(size 1.27 1.27)
				)
				(justify mirror)
			)
		)
		(duplicate_pad_numbers_are_jumpers no)
		(fp_line
			(start 0.299974 0.150114)
			(end 0.299974 -0.150114)
			(stroke
				(width 0.1)
				(type default)
			)
			(layer "B.Fab")
		)
		(fp_line
			(start 0.299974 -0.150114)
			(end -0.299974 -0.150114)
			(stroke
				(width 0.1)
				(type default)
			)
			(layer "B.Fab")
		)
		(fp_line
			(start -0.299974 0.150114)
			(end 0.299974 0.150114)
			(stroke
				(width 0.1)
				(type default)
			)
			(layer "B.Fab")
		)
		(fp_line
			(start -0.299974 -0.150114)
			(end -0.299974 0.150114)
			(stroke
				(width 0.1)
				(type default)
			)
			(layer "B.Fab")
		)
		(pad "1" smd rect
			(at 0.2667 0)
			(size 0.3048 0.381)
			(layers "B.Cu" "B.Mask" "B.Paste")
			(net "P1V25_PEX3")
		)
		(pad "2" smd rect
			(at -0.2667 0)
			(size 0.3048 0.381)
			(layers "B.Cu" "B.Mask" "B.Paste")
			(net "GND")
		)
	)
	(footprint ""
		(layer "B.Cu")
		(at 193.641726 -101.069648 180)
		(property "Reference" "R178"
			(at 0 0 0)
			(layer "B.SilkS")
			(hide yes)
			(effects
				(font
					(size 1.27 1.27)
				)
				(justify mirror)
			)
		)
		(property "Value" ""
			(at 0 0 0)
			(layer "B.Fab")
			(effects
				(font
					(size 1.27 1.27)
				)
				(justify mirror)
			)
		)
		(duplicate_pad_numbers_are_jumpers no)
		(fp_line
			(start 0.7874 0.4064)
			(end 0.7874 -0.4064)
			(stroke
				(width 0.1524)
				(type default)
			)
			(layer "B.SilkS")
		)
		(fp_line
			(start 0.7874 -0.4064)
			(end -0.7874 -0.4064)
			(stroke
				(width 0.1524)
				(type default)
			)
			(layer "B.SilkS")
		)
		(fp_line
			(start -0.7874 0.4064)
			(end 0.7874 0.4064)
			(stroke
				(width 0.1524)
				(type default)
			)
			(layer "B.SilkS")
		)
		(fp_line
			(start -0.7874 -0.4064)
			(end -0.7874 0.4064)
			(stroke
				(width 0.1524)
				(type default)
			)
			(layer "B.SilkS")
		)
		(fp_line
			(start 0.67945 0.3048)
			(end 0.67945 -0.305054)
			(stroke
				(width 0.1)
				(type default)
			)
			(layer "B.Fab")
		)
		(fp_line
			(start 0.67945 -0.305054)
			(end 0.12065 -0.305054)
			(stroke
				(width 0.1)
				(type default)
			)
			(layer "B.Fab")
		)
		(fp_line
			(start 0.12065 0.3048)
			(end 0.67945 0.3048)
			(stroke
				(width 0.1)
				(type default)
			)
			(layer "B.Fab")
		)
		(fp_line
			(start 0.12065 0.2794)
			(end 0.12065 0.3048)
			(stroke
				(width 0.1)
				(type default)
			)
			(layer "B.Fab")
		)
		(fp_line
			(start 0.12065 -0.2794)
			(end -0.12065 -0.2794)
			(stroke
				(width 0.1)
				(type default)
			)
			(layer "B.Fab")
		)
		(fp_line
			(start 0.12065 -0.305054)
			(end 0.12065 -0.2794)
			(stroke
				(width 0.1)
				(type default)
			)
			(layer "B.Fab")
		)
		(fp_line
			(start -0.120396 0.3048)
			(end -0.120396 0.2794)
			(stroke
				(width 0.1)
				(type default)
			)
			(layer "B.Fab")
		)
		(fp_line
			(start -0.120396 0.2794)
			(end 0.12065 0.2794)
			(stroke
				(width 0.1)
				(type default)
			)
			(layer "B.Fab")
		)
		(fp_line
			(start -0.12065 -0.2794)
			(end -0.12065 -0.3048)
			(stroke
				(width 0.1)
				(type default)
			)
			(layer "B.Fab")
		)
		(fp_line
			(start -0.12065 -0.3048)
			(end -0.67945 -0.3048)
			(stroke
				(width 0.1)
				(type default)
			)
			(layer "B.Fab")
		)
		(fp_line
			(start -0.67945 0.3048)
			(end -0.120396 0.3048)
			(stroke
				(width 0.1)
				(type default)
			)
			(layer "B.Fab")
		)
		(fp_line
			(start -0.67945 -0.3048)
			(end -0.67945 0.3048)
			(stroke
				(width 0.1)
				(type default)
			)
			(layer "B.Fab")
		)
		(pad "1" smd circle
			(at 0.40005 0)
			(size 0 0)
			(layers "B.Cu" "B.Mask" "B.Paste")
			(net "NIC3_SLOT_ID0")
		)
		(pad "2" smd circle
			(at -0.40005 0)
			(size 0 0)
			(layers "B.Cu" "B.Mask" "B.Paste")
			(net "P3V3_NIC3")
		)
	)
	(footprint ""
		(layer "B.Cu")
		(at 224.08261 -279.57907 180)
		(property "Reference" "C4278"
			(at 0 0 0)
			(layer "B.SilkS")
			(hide yes)
			(effects
				(font
					(size 1.27 1.27)
				)
				(justify mirror)
			)
		)
		(property "Value" ""
			(at 0 0 0)
			(layer "B.Fab")
			(effects
				(font
					(size 1.27 1.27)
				)
				(justify mirror)
			)
		)
		(duplicate_pad_numbers_are_jumpers no)
		(fp_line
			(start 0.299974 0.150114)
			(end 0.299974 -0.150114)
			(stroke
				(width 0.1)
				(type default)
			)
			(layer "B.Fab")
		)
		(fp_line
			(start 0.299974 -0.150114)
			(end -0.299974 -0.150114)
			(stroke
				(width 0.1)
				(type default)
			)
			(layer "B.Fab")
		)
		(fp_line
			(start -0.299974 0.150114)
			(end 0.299974 0.150114)
			(stroke
				(width 0.1)
				(type default)
			)
			(layer "B.Fab")
		)
		(fp_line
			(start -0.299974 -0.150114)
			(end -0.299974 0.150114)
			(stroke
				(width 0.1)
				(type default)
			)
			(layer "B.Fab")
		)
		(pad "1" smd rect
			(at 0.2667 0)
			(size 0.3048 0.381)
			(layers "B.Cu" "B.Mask" "B.Paste")
			(net "P1V25_PEX1")
		)
		(pad "2" smd rect
			(at -0.2667 0)
			(size 0.3048 0.381)
			(layers "B.Cu" "B.Mask" "B.Paste")
			(net "GND")
		)
	)
	(footprint ""
		(layer "B.Cu")
		(at 400.349974 -299.699934 -90)
		(property "Reference" "C1956"
			(at 0 0 90)
			(layer "B.SilkS")
			(hide yes)
			(effects
				(font
					(size 1.27 1.27)
				)
				(justify mirror)
			)
		)
		(property "Value" ""
			(at 0 0 90)
			(layer "B.Fab")
			(effects
				(font
					(size 1.27 1.27)
				)
				(justify mirror)
			)
		)
		(duplicate_pad_numbers_are_jumpers no)
		(fp_line
			(start -0.299974 0.150114)
			(end 0.299974 0.150114)
			(stroke
				(width 0.1)
				(type default)
			)
			(layer "B.Fab")
		)
		(fp_line
			(start 0.299974 0.150114)
			(end 0.299974 -0.150114)
			(stroke
				(width 0.1)
				(type default)
			)
			(layer "B.Fab")
		)
		(fp_line
			(start -0.299974 -0.150114)
			(end -0.299974 0.150114)
			(stroke
				(width 0.1)
				(type default)
			)
			(layer "B.Fab")
		)
		(fp_line
			(start 0.299974 -0.150114)
			(end -0.299974 -0.150114)
			(stroke
				(width 0.1)
				(type default)
			)
			(layer "B.Fab")
		)
		(pad "1" smd rect
			(at 0.2667 0 90)
			(size 0.3048 0.381)
			(layers "B.Cu" "B.Mask" "B.Paste")
			(net "P0V8_SERDES_VDDA_PEX3")
		)
		(pad "2" smd rect
			(at -0.2667 0 90)
			(size 0.3048 0.381)
			(layers "B.Cu" "B.Mask" "B.Paste")
			(net "GND")
		)
	)
	(footprint ""
		(layer "B.Cu")
		(at 406.999948 -299.699934 -90)
		(property "Reference" "C1964"
			(at 0 0 90)
			(layer "B.SilkS")
			(hide yes)
			(effects
				(font
					(size 1.27 1.27)
				)
				(justify mirror)
			)
		)
		(property "Value" ""
			(at 0 0 90)
			(layer "B.Fab")
			(effects
				(font
					(size 1.27 1.27)
				)
				(justify mirror)
			)
		)
		(duplicate_pad_numbers_are_jumpers no)
		(fp_line
			(start -0.299974 0.150114)
			(end 0.299974 0.150114)
			(stroke
				(width 0.1)
				(type default)
			)
			(layer "B.Fab")
		)
		(fp_line
			(start 0.299974 0.150114)
			(end 0.299974 -0.150114)
			(stroke
				(width 0.1)
				(type default)
			)
			(layer "B.Fab")
		)
		(fp_line
			(start -0.299974 -0.150114)
			(end -0.299974 0.150114)
			(stroke
				(width 0.1)
				(type default)
			)
			(layer "B.Fab")
		)
		(fp_line
			(start 0.299974 -0.150114)
			(end -0.299974 -0.150114)
			(stroke
				(width 0.1)
				(type default)
			)
			(layer "B.Fab")
		)
		(pad "1" smd rect
			(at 0.2667 0 90)
			(size 0.3048 0.381)
			(layers "B.Cu" "B.Mask" "B.Paste")
			(net "P0V8_SERDES_VDDA_PEX3")
		)
		(pad "2" smd rect
			(at -0.2667 0 90)
			(size 0.3048 0.381)
			(layers "B.Cu" "B.Mask" "B.Paste")
			(net "GND")
		)
	)
	(footprint ""
		(layer "B.Cu")
		(at 365.931196 -283.818584 90)
		(property "Reference" "PR160"
			(at 0 0 90)
			(layer "B.SilkS")
			(hide yes)
			(effects
				(font
					(size 1.27 1.27)
				)
				(justify mirror)
			)
		)
		(property "Value" ""
			(at 0 0 90)
			(layer "B.Fab")
			(effects
				(font
					(size 1.27 1.27)
				)
				(justify mirror)
			)
		)
		(duplicate_pad_numbers_are_jumpers no)
		(fp_line
			(start 0.7874 -0.4064)
			(end -0.7874 -0.4064)
			(stroke
				(width 0.1524)
				(type default)
			)
			(layer "B.SilkS")
		)
		(fp_line
			(start -0.7874 -0.4064)
			(end -0.7874 0.4064)
			(stroke
				(width 0.1524)
				(type default)
			)
			(layer "B.SilkS")
		)
		(fp_line
			(start 0.7874 0.4064)
			(end 0.7874 -0.4064)
			(stroke
				(width 0.1524)
				(type default)
			)
			(layer "B.SilkS")
		)
		(fp_line
			(start -0.7874 0.4064)
			(end 0.7874 0.4064)
			(stroke
				(width 0.1524)
				(type default)
			)
			(layer "B.SilkS")
		)
		(fp_line
			(start 0.67945 -0.305054)
			(end 0.12065 -0.305054)
			(stroke
				(width 0.1)
				(type default)
			)
			(layer "B.Fab")
		)
		(fp_line
			(start 0.12065 -0.305054)
			(end 0.12065 -0.2794)
			(stroke
				(width 0.1)
				(type default)
			)
			(layer "B.Fab")
		)
		(fp_line
			(start -0.12065 -0.3048)
			(end -0.67945 -0.3048)
			(stroke
				(width 0.1)
				(type default)
			)
			(layer "B.Fab")
		)
		(fp_line
			(start -0.67945 -0.3048)
			(end -0.67945 0.3048)
			(stroke
				(width 0.1)
				(type default)
			)
			(layer "B.Fab")
		)
		(fp_line
			(start 0.12065 -0.2794)
			(end -0.12065 -0.2794)
			(stroke
				(width 0.1)
				(type default)
			)
			(layer "B.Fab")
		)
		(fp_line
			(start -0.12065 -0.2794)
			(end -0.12065 -0.3048)
			(stroke
				(width 0.1)
				(type default)
			)
			(layer "B.Fab")
		)
		(fp_line
			(start 0.12065 0.2794)
			(end 0.12065 0.3048)
			(stroke
				(width 0.1)
				(type default)
			)
			(layer "B.Fab")
		)
		(fp_line
			(start -0.120396 0.2794)
			(end 0.12065 0.2794)
			(stroke
				(width 0.1)
				(type default)
			)
			(layer "B.Fab")
		)
		(fp_line
			(start 0.67945 0.3048)
			(end 0.67945 -0.305054)
			(stroke
				(width 0.1)
				(type default)
			)
			(layer "B.Fab")
		)
		(fp_line
			(start 0.12065 0.3048)
			(end 0.67945 0.3048)
			(stroke
				(width 0.1)
				(type default)
			)
			(layer "B.Fab")
		)
		(fp_line
			(start -0.120396 0.3048)
			(end -0.120396 0.2794)
			(stroke
				(width 0.1)
				(type default)
			)
			(layer "B.Fab")
		)
		(fp_line
			(start -0.67945 0.3048)
			(end -0.120396 0.3048)
			(stroke
				(width 0.1)
				(type default)
			)
			(layer "B.Fab")
		)
		(pad "1" smd circle
			(at 0.40005 0 270)
			(size 0 0)
			(layers "B.Cu" "B.Mask" "B.Paste")
			(net "P0V8_PEX3_PVCC")
		)
		(pad "2" smd circle
			(at -0.40005 0 270)
			(size 0 0)
			(layers "B.Cu" "B.Mask" "B.Paste")
			(net "P0V8_PEX3_VCC2")
		)
	)
	(footprint ""
		(layer "B.Cu")
		(at 372.48211 -228.346 90)
		(property "Reference" "R3500"
			(at 0 0 90)
			(layer "B.SilkS")
			(hide yes)
			(effects
				(font
					(size 1.27 1.27)
				)
				(justify mirror)
			)
		)
		(property "Value" ""
			(at 0 0 90)
			(layer "B.Fab")
			(effects
				(font
					(size 1.27 1.27)
				)
				(justify mirror)
			)
		)
		(duplicate_pad_numbers_are_jumpers no)
		(fp_line
			(start 0.7874 -0.4064)
			(end -0.7874 -0.4064)
			(stroke
				(width 0.1524)
				(type default)
			)
			(layer "B.SilkS")
		)
		(fp_line
			(start -0.7874 -0.4064)
			(end -0.7874 0.4064)
			(stroke
				(width 0.1524)
				(type default)
			)
			(layer "B.SilkS")
		)
		(fp_line
			(start 0.7874 0.4064)
			(end 0.7874 -0.4064)
			(stroke
				(width 0.1524)
				(type default)
			)
			(layer "B.SilkS")
		)
		(fp_line
			(start -0.7874 0.4064)
			(end 0.7874 0.4064)
			(stroke
				(width 0.1524)
				(type default)
			)
			(layer "B.SilkS")
		)
		(fp_line
			(start 0.67945 -0.305054)
			(end 0.12065 -0.305054)
			(stroke
				(width 0.1)
				(type default)
			)
			(layer "B.Fab")
		)
		(fp_line
			(start 0.12065 -0.305054)
			(end 0.12065 -0.2794)
			(stroke
				(width 0.1)
				(type default)
			)
			(layer "B.Fab")
		)
		(fp_line
			(start -0.12065 -0.3048)
			(end -0.67945 -0.3048)
			(stroke
				(width 0.1)
				(type default)
			)
			(layer "B.Fab")
		)
		(fp_line
			(start -0.67945 -0.3048)
			(end -0.67945 0.3048)
			(stroke
				(width 0.1)
				(type default)
			)
			(layer "B.Fab")
		)
		(fp_line
			(start 0.12065 -0.2794)
			(end -0.12065 -0.2794)
			(stroke
				(width 0.1)
				(type default)
			)
			(layer "B.Fab")
		)
		(fp_line
			(start -0.12065 -0.2794)
			(end -0.12065 -0.3048)
			(stroke
				(width 0.1)
				(type default)
			)
			(layer "B.Fab")
		)
		(fp_line
			(start 0.12065 0.2794)
			(end 0.12065 0.3048)
			(stroke
				(width 0.1)
				(type default)
			)
			(layer "B.Fab")
		)
		(fp_line
			(start -0.120396 0.2794)
			(end 0.12065 0.2794)
			(stroke
				(width 0.1)
				(type default)
			)
			(layer "B.Fab")
		)
		(fp_line
			(start 0.67945 0.3048)
			(end 0.67945 -0.305054)
			(stroke
				(width 0.1)
				(type default)
			)
			(layer "B.Fab")
		)
		(fp_line
			(start 0.12065 0.3048)
			(end 0.67945 0.3048)
			(stroke
				(width 0.1)
				(type default)
			)
			(layer "B.Fab")
		)
		(fp_line
			(start -0.120396 0.3048)
			(end -0.120396 0.2794)
			(stroke
				(width 0.1)
				(type default)
			)
			(layer "B.Fab")
		)
		(fp_line
			(start -0.67945 0.3048)
			(end -0.120396 0.3048)
			(stroke
				(width 0.1)
				(type default)
			)
			(layer "B.Fab")
		)
		(pad "1" smd circle
			(at 0.40005 0 270)
			(size 0 0)
			(layers "B.Cu" "B.Mask" "B.Paste")
			(net "SPI_PEX3_CS_MUX_N")
		)
		(pad "2" smd circle
			(at -0.40005 0 270)
			(size 0 0)
			(layers "B.Cu" "B.Mask" "B.Paste")
			(net "SPI_PEX3_CS_MUX_R_N")
		)
	)
	(footprint ""
		(layer "B.Cu")
		(at 179.55006 -301.599854 -90)
		(property "Reference" "C1482"
			(at 0 0 90)
			(layer "B.SilkS")
			(hide yes)
			(effects
				(font
					(size 1.27 1.27)
				)
				(justify mirror)
			)
		)
		(property "Value" ""
			(at 0 0 90)
			(layer "B.Fab")
			(effects
				(font
					(size 1.27 1.27)
				)
				(justify mirror)
			)
		)
		(duplicate_pad_numbers_are_jumpers no)
		(fp_line
			(start -0.299974 0.150114)
			(end 0.299974 0.150114)
			(stroke
				(width 0.1)
				(type default)
			)
			(layer "B.Fab")
		)
		(fp_line
			(start 0.299974 0.150114)
			(end 0.299974 -0.150114)
			(stroke
				(width 0.1)
				(type default)
			)
			(layer "B.Fab")
		)
		(fp_line
			(start -0.299974 -0.150114)
			(end -0.299974 0.150114)
			(stroke
				(width 0.1)
				(type default)
			)
			(layer "B.Fab")
		)
		(fp_line
			(start 0.299974 -0.150114)
			(end -0.299974 -0.150114)
			(stroke
				(width 0.1)
				(type default)
			)
			(layer "B.Fab")
		)
		(pad "1" smd rect
			(at 0.2667 0 90)
			(size 0.3048 0.381)
			(layers "B.Cu" "B.Mask" "B.Paste")
			(net "P0V8_SERDES_VDDA_PEX1")
		)
		(pad "2" smd rect
			(at -0.2667 0 90)
			(size 0.3048 0.381)
			(layers "B.Cu" "B.Mask" "B.Paste")
			(net "GND")
		)
	)
	(footprint ""
		(layer "B.Cu")
		(at 415.549842 -288.299906 90)
		(property "Reference" "C3441"
			(at 0 0 90)
			(layer "B.SilkS")
			(hide yes)
			(effects
				(font
					(size 1.27 1.27)
				)
				(justify mirror)
			)
		)
		(property "Value" ""
			(at 0 0 90)
			(layer "B.Fab")
			(effects
				(font
					(size 1.27 1.27)
				)
				(justify mirror)
			)
		)
		(duplicate_pad_numbers_are_jumpers no)
		(fp_line
			(start 0.299974 -0.150114)
			(end -0.299974 -0.150114)
			(stroke
				(width 0.1)
				(type default)
			)
			(layer "B.Fab")
		)
		(fp_line
			(start -0.299974 -0.150114)
			(end -0.299974 0.150114)
			(stroke
				(width 0.1)
				(type default)
			)
			(layer "B.Fab")
		)
		(fp_line
			(start 0.299974 0.150114)
			(end 0.299974 -0.150114)
			(stroke
				(width 0.1)
				(type default)
			)
			(layer "B.Fab")
		)
		(fp_line
			(start -0.299974 0.150114)
			(end 0.299974 0.150114)
			(stroke
				(width 0.1)
				(type default)
			)
			(layer "B.Fab")
		)
		(pad "1" smd rect
			(at 0.2667 0 270)
			(size 0.3048 0.381)
			(layers "B.Cu" "B.Mask" "B.Paste")
			(net "P1V25_PEX3")
		)
		(pad "2" smd rect
			(at -0.2667 0 270)
			(size 0.3048 0.381)
			(layers "B.Cu" "B.Mask" "B.Paste")
			(net "GND")
		)
	)
	(footprint ""
		(layer "B.Cu")
		(at 299.449744 -296.37482)
		(property "Reference" "C1675"
			(at 0 0 0)
			(layer "B.SilkS")
			(hide yes)
			(effects
				(font
					(size 1.27 1.27)
				)
				(justify mirror)
			)
		)
		(property "Value" ""
			(at 0 0 0)
			(layer "B.Fab")
			(effects
				(font
					(size 1.27 1.27)
				)
				(justify mirror)
			)
		)
		(duplicate_pad_numbers_are_jumpers no)
		(fp_line
			(start -0.299974 -0.150114)
			(end -0.299974 0.150114)
			(stroke
				(width 0.1)
				(type default)
			)
			(layer "B.Fab")
		)
		(fp_line
			(start -0.299974 0.150114)
			(end 0.299974 0.150114)
			(stroke
				(width 0.1)
				(type default)
			)
			(layer "B.Fab")
		)
		(fp_line
			(start 0.299974 -0.150114)
			(end -0.299974 -0.150114)
			(stroke
				(width 0.1)
				(type default)
			)
			(layer "B.Fab")
		)
		(fp_line
			(start 0.299974 0.150114)
			(end 0.299974 -0.150114)
			(stroke
				(width 0.1)
				(type default)
			)
			(layer "B.Fab")
		)
		(pad "1" smd rect
			(at 0.2667 0 180)
			(size 0.3048 0.381)
			(layers "B.Cu" "B.Mask" "B.Paste")
			(net "P0V8_SERDES_VDDA_PEX2")
		)
		(pad "2" smd rect
			(at -0.2667 0 180)
			(size 0.3048 0.381)
			(layers "B.Cu" "B.Mask" "B.Paste")
			(net "GND")
		)
	)
	(footprint ""
		(layer "B.Cu")
		(at 41.538906 -288.774886 90)
		(property "Reference" "R6157"
			(at 0 0 90)
			(layer "B.SilkS")
			(hide yes)
			(effects
				(font
					(size 1.27 1.27)
				)
				(justify mirror)
			)
		)
		(property "Value" ""
			(at 0 0 90)
			(layer "B.Fab")
			(effects
				(font
					(size 1.27 1.27)
				)
				(justify mirror)
			)
		)
		(duplicate_pad_numbers_are_jumpers no)
		(fp_line
			(start 0.7874 -0.4064)
			(end -0.7874 -0.4064)
			(stroke
				(width 0.1524)
				(type default)
			)
			(layer "B.SilkS")
		)
		(fp_line
			(start -0.7874 -0.4064)
			(end -0.7874 0.4064)
			(stroke
				(width 0.1524)
				(type default)
			)
			(layer "B.SilkS")
		)
		(fp_line
			(start 0.7874 0.4064)
			(end 0.7874 -0.4064)
			(stroke
				(width 0.1524)
				(type default)
			)
			(layer "B.SilkS")
		)
		(fp_line
			(start -0.7874 0.4064)
			(end 0.7874 0.4064)
			(stroke
				(width 0.1524)
				(type default)
			)
			(layer "B.SilkS")
		)
		(fp_line
			(start 0.67945 -0.305054)
			(end 0.12065 -0.305054)
			(stroke
				(width 0.1)
				(type default)
			)
			(layer "B.Fab")
		)
		(fp_line
			(start 0.12065 -0.305054)
			(end 0.12065 -0.2794)
			(stroke
				(width 0.1)
				(type default)
			)
			(layer "B.Fab")
		)
		(fp_line
			(start -0.12065 -0.3048)
			(end -0.67945 -0.3048)
			(stroke
				(width 0.1)
				(type default)
			)
			(layer "B.Fab")
		)
		(fp_line
			(start -0.67945 -0.3048)
			(end -0.67945 0.3048)
			(stroke
				(width 0.1)
				(type default)
			)
			(layer "B.Fab")
		)
		(fp_line
			(start 0.12065 -0.2794)
			(end -0.12065 -0.2794)
			(stroke
				(width 0.1)
				(type default)
			)
			(layer "B.Fab")
		)
		(fp_line
			(start -0.12065 -0.2794)
			(end -0.12065 -0.3048)
			(stroke
				(width 0.1)
				(type default)
			)
			(layer "B.Fab")
		)
		(fp_line
			(start 0.12065 0.2794)
			(end 0.12065 0.3048)
			(stroke
				(width 0.1)
				(type default)
			)
			(layer "B.Fab")
		)
		(fp_line
			(start -0.120396 0.2794)
			(end 0.12065 0.2794)
			(stroke
				(width 0.1)
				(type default)
			)
			(layer "B.Fab")
		)
		(fp_line
			(start 0.67945 0.3048)
			(end 0.67945 -0.305054)
			(stroke
				(width 0.1)
				(type default)
			)
			(layer "B.Fab")
		)
		(fp_line
			(start 0.12065 0.3048)
			(end 0.67945 0.3048)
			(stroke
				(width 0.1)
				(type default)
			)
			(layer "B.Fab")
		)
		(fp_line
			(start -0.120396 0.3048)
			(end -0.120396 0.2794)
			(stroke
				(width 0.1)
				(type default)
			)
			(layer "B.Fab")
		)
		(fp_line
			(start -0.67945 0.3048)
			(end -0.120396 0.3048)
			(stroke
				(width 0.1)
				(type default)
			)
			(layer "B.Fab")
		)
		(pad "1" smd circle
			(at 0.40005 0 270)
			(size 0 0)
			(layers "B.Cu" "B.Mask" "B.Paste")
			(net "SPI_PEX0_CS_N")
		)
		(pad "2" smd circle
			(at -0.40005 0 270)
			(size 0 0)
			(layers "B.Cu" "B.Mask" "B.Paste")
			(net "P1V8_PEX")
		)
	)
	(footprint ""
		(layer "B.Cu")
		(at 62.499748 -303.499774 -90)
		(property "Reference" "C2907"
			(at 0 0 90)
			(layer "B.SilkS")
			(hide yes)
			(effects
				(font
					(size 1.27 1.27)
				)
				(justify mirror)
			)
		)
		(property "Value" ""
			(at 0 0 90)
			(layer "B.Fab")
			(effects
				(font
					(size 1.27 1.27)
				)
				(justify mirror)
			)
		)
		(duplicate_pad_numbers_are_jumpers no)
		(fp_line
			(start -0.299974 0.150114)
			(end 0.299974 0.150114)
			(stroke
				(width 0.1)
				(type default)
			)
			(layer "B.Fab")
		)
		(fp_line
			(start 0.299974 0.150114)
			(end 0.299974 -0.150114)
			(stroke
				(width 0.1)
				(type default)
			)
			(layer "B.Fab")
		)
		(fp_line
			(start -0.299974 -0.150114)
			(end -0.299974 0.150114)
			(stroke
				(width 0.1)
				(type default)
			)
			(layer "B.Fab")
		)
		(fp_line
			(start 0.299974 -0.150114)
			(end -0.299974 -0.150114)
			(stroke
				(width 0.1)
				(type default)
			)
			(layer "B.Fab")
		)
		(pad "1" smd rect
			(at 0.2667 0 90)
			(size 0.3048 0.381)
			(layers "B.Cu" "B.Mask" "B.Paste")
			(net "P1V25_PEX0")
		)
		(pad "2" smd rect
			(at -0.2667 0 90)
			(size 0.3048 0.381)
			(layers "B.Cu" "B.Mask" "B.Paste")
			(net "GND")
		)
	)
	(footprint ""
		(layer "B.Cu")
		(at 16.257778 -310.154066 90)
		(property "Reference" "R4435"
			(at 0 0 90)
			(layer "B.SilkS")
			(hide yes)
			(effects
				(font
					(size 1.27 1.27)
				)
				(justify mirror)
			)
		)
		(property "Value" ""
			(at 0 0 90)
			(layer "B.Fab")
			(effects
				(font
					(size 1.27 1.27)
				)
				(justify mirror)
			)
		)
		(duplicate_pad_numbers_are_jumpers no)
		(fp_line
			(start 0.7874 -0.4064)
			(end -0.7874 -0.4064)
			(stroke
				(width 0.1524)
				(type default)
			)
			(layer "B.SilkS")
		)
		(fp_line
			(start -0.7874 -0.4064)
			(end -0.7874 0.4064)
			(stroke
				(width 0.1524)
				(type default)
			)
			(layer "B.SilkS")
		)
		(fp_line
			(start 0.7874 0.4064)
			(end 0.7874 -0.4064)
			(stroke
				(width 0.1524)
				(type default)
			)
			(layer "B.SilkS")
		)
		(fp_line
			(start -0.7874 0.4064)
			(end 0.7874 0.4064)
			(stroke
				(width 0.1524)
				(type default)
			)
			(layer "B.SilkS")
		)
		(fp_line
			(start 0.67945 -0.305054)
			(end 0.12065 -0.305054)
			(stroke
				(width 0.1)
				(type default)
			)
			(layer "B.Fab")
		)
		(fp_line
			(start 0.12065 -0.305054)
			(end 0.12065 -0.2794)
			(stroke
				(width 0.1)
				(type default)
			)
			(layer "B.Fab")
		)
		(fp_line
			(start -0.12065 -0.3048)
			(end -0.67945 -0.3048)
			(stroke
				(width 0.1)
				(type default)
			)
			(layer "B.Fab")
		)
		(fp_line
			(start -0.67945 -0.3048)
			(end -0.67945 0.3048)
			(stroke
				(width 0.1)
				(type default)
			)
			(layer "B.Fab")
		)
		(fp_line
			(start 0.12065 -0.2794)
			(end -0.12065 -0.2794)
			(stroke
				(width 0.1)
				(type default)
			)
			(layer "B.Fab")
		)
		(fp_line
			(start -0.12065 -0.2794)
			(end -0.12065 -0.3048)
			(stroke
				(width 0.1)
				(type default)
			)
			(layer "B.Fab")
		)
		(fp_line
			(start 0.12065 0.2794)
			(end 0.12065 0.3048)
			(stroke
				(width 0.1)
				(type default)
			)
			(layer "B.Fab")
		)
		(fp_line
			(start -0.120396 0.2794)
			(end 0.12065 0.2794)
			(stroke
				(width 0.1)
				(type default)
			)
			(layer "B.Fab")
		)
		(fp_line
			(start 0.67945 0.3048)
			(end 0.67945 -0.305054)
			(stroke
				(width 0.1)
				(type default)
			)
			(layer "B.Fab")
		)
		(fp_line
			(start 0.12065 0.3048)
			(end 0.67945 0.3048)
			(stroke
				(width 0.1)
				(type default)
			)
			(layer "B.Fab")
		)
		(fp_line
			(start -0.120396 0.3048)
			(end -0.120396 0.2794)
			(stroke
				(width 0.1)
				(type default)
			)
			(layer "B.Fab")
		)
		(fp_line
			(start -0.67945 0.3048)
			(end -0.120396 0.3048)
			(stroke
				(width 0.1)
				(type default)
			)
			(layer "B.Fab")
		)
		(pad "1" smd circle
			(at 0.40005 0 270)
			(size 0 0)
			(layers "B.Cu" "B.Mask" "B.Paste")
			(net "PWRGD_P1V25_PEX0_R")
		)
		(pad "2" smd circle
			(at -0.40005 0 270)
			(size 0 0)
			(layers "B.Cu" "B.Mask" "B.Paste")
			(net "PWRGD_P1V25_PEX0")
		)
	)
	(footprint ""
		(layer "B.Cu")
		(at 156.273754 -296.9514 180)
		(property "Reference" "R3455"
			(at 0 0 0)
			(layer "B.SilkS")
			(hide yes)
			(effects
				(font
					(size 1.27 1.27)
				)
				(justify mirror)
			)
		)
		(property "Value" ""
			(at 0 0 0)
			(layer "B.Fab")
			(effects
				(font
					(size 1.27 1.27)
				)
				(justify mirror)
			)
		)
		(duplicate_pad_numbers_are_jumpers no)
		(fp_line
			(start 0.7874 0.4064)
			(end 0.7874 -0.4064)
			(stroke
				(width 0.1524)
				(type default)
			)
			(layer "B.SilkS")
		)
		(fp_line
			(start 0.7874 -0.4064)
			(end -0.7874 -0.4064)
			(stroke
				(width 0.1524)
				(type default)
			)
			(layer "B.SilkS")
		)
		(fp_line
			(start -0.7874 0.4064)
			(end 0.7874 0.4064)
			(stroke
				(width 0.1524)
				(type default)
			)
			(layer "B.SilkS")
		)
		(fp_line
			(start -0.7874 -0.4064)
			(end -0.7874 0.4064)
			(stroke
				(width 0.1524)
				(type default)
			)
			(layer "B.SilkS")
		)
		(fp_line
			(start 0.67945 0.3048)
			(end 0.67945 -0.305054)
			(stroke
				(width 0.1)
				(type default)
			)
			(layer "B.Fab")
		)
		(fp_line
			(start 0.67945 -0.305054)
			(end 0.12065 -0.305054)
			(stroke
				(width 0.1)
				(type default)
			)
			(layer "B.Fab")
		)
		(fp_line
			(start 0.12065 0.3048)
			(end 0.67945 0.3048)
			(stroke
				(width 0.1)
				(type default)
			)
			(layer "B.Fab")
		)
		(fp_line
			(start 0.12065 0.2794)
			(end 0.12065 0.3048)
			(stroke
				(width 0.1)
				(type default)
			)
			(layer "B.Fab")
		)
		(fp_line
			(start 0.12065 -0.2794)
			(end -0.12065 -0.2794)
			(stroke
				(width 0.1)
				(type default)
			)
			(layer "B.Fab")
		)
		(fp_line
			(start 0.12065 -0.305054)
			(end 0.12065 -0.2794)
			(stroke
				(width 0.1)
				(type default)
			)
			(layer "B.Fab")
		)
		(fp_line
			(start -0.120396 0.3048)
			(end -0.120396 0.2794)
			(stroke
				(width 0.1)
				(type default)
			)
			(layer "B.Fab")
		)
		(fp_line
			(start -0.120396 0.2794)
			(end 0.12065 0.2794)
			(stroke
				(width 0.1)
				(type default)
			)
			(layer "B.Fab")
		)
		(fp_line
			(start -0.12065 -0.2794)
			(end -0.12065 -0.3048)
			(stroke
				(width 0.1)
				(type default)
			)
			(layer "B.Fab")
		)
		(fp_line
			(start -0.12065 -0.3048)
			(end -0.67945 -0.3048)
			(stroke
				(width 0.1)
				(type default)
			)
			(layer "B.Fab")
		)
		(fp_line
			(start -0.67945 0.3048)
			(end -0.120396 0.3048)
			(stroke
				(width 0.1)
				(type default)
			)
			(layer "B.Fab")
		)
		(fp_line
			(start -0.67945 -0.3048)
			(end -0.67945 0.3048)
			(stroke
				(width 0.1)
				(type default)
			)
			(layer "B.Fab")
		)
		(pad "1" smd circle
			(at 0.40005 0)
			(size 0 0)
			(layers "B.Cu" "B.Mask" "B.Paste")
			(net "SPI_PEX1_SDIO1_R")
		)
		(pad "2" smd circle
			(at -0.40005 0)
			(size 0 0)
			(layers "B.Cu" "B.Mask" "B.Paste")
			(net "SPI_PEX1_SDIO1")
		)
	)
	(footprint ""
		(layer "B.Cu")
		(at 410.799788 -303.499774 -90)
		(property "Reference" "C3429"
			(at 0 0 90)
			(layer "B.SilkS")
			(hide yes)
			(effects
				(font
					(size 1.27 1.27)
				)
				(justify mirror)
			)
		)
		(property "Value" ""
			(at 0 0 90)
			(layer "B.Fab")
			(effects
				(font
					(size 1.27 1.27)
				)
				(justify mirror)
			)
		)
		(duplicate_pad_numbers_are_jumpers no)
		(fp_line
			(start -0.299974 0.150114)
			(end 0.299974 0.150114)
			(stroke
				(width 0.1)
				(type default)
			)
			(layer "B.Fab")
		)
		(fp_line
			(start 0.299974 0.150114)
			(end 0.299974 -0.150114)
			(stroke
				(width 0.1)
				(type default)
			)
			(layer "B.Fab")
		)
		(fp_line
			(start -0.299974 -0.150114)
			(end -0.299974 0.150114)
			(stroke
				(width 0.1)
				(type default)
			)
			(layer "B.Fab")
		)
		(fp_line
			(start 0.299974 -0.150114)
			(end -0.299974 -0.150114)
			(stroke
				(width 0.1)
				(type default)
			)
			(layer "B.Fab")
		)
		(pad "1" smd rect
			(at 0.2667 0 90)
			(size 0.3048 0.381)
			(layers "B.Cu" "B.Mask" "B.Paste")
			(net "P1V25_PEX3")
		)
		(pad "2" smd rect
			(at -0.2667 0 90)
			(size 0.3048 0.381)
			(layers "B.Cu" "B.Mask" "B.Paste")
			(net "GND")
		)
	)
	(footprint ""
		(layer "B.Cu")
		(at 410.799788 -301.599854 -90)
		(property "Reference" "C1967"
			(at 0 0 90)
			(layer "B.SilkS")
			(hide yes)
			(effects
				(font
					(size 1.27 1.27)
				)
				(justify mirror)
			)
		)
		(property "Value" ""
			(at 0 0 90)
			(layer "B.Fab")
			(effects
				(font
					(size 1.27 1.27)
				)
				(justify mirror)
			)
		)
		(duplicate_pad_numbers_are_jumpers no)
		(fp_line
			(start -0.299974 0.150114)
			(end 0.299974 0.150114)
			(stroke
				(width 0.1)
				(type default)
			)
			(layer "B.Fab")
		)
		(fp_line
			(start 0.299974 0.150114)
			(end 0.299974 -0.150114)
			(stroke
				(width 0.1)
				(type default)
			)
			(layer "B.Fab")
		)
		(fp_line
			(start -0.299974 -0.150114)
			(end -0.299974 0.150114)
			(stroke
				(width 0.1)
				(type default)
			)
			(layer "B.Fab")
		)
		(fp_line
			(start 0.299974 -0.150114)
			(end -0.299974 -0.150114)
			(stroke
				(width 0.1)
				(type default)
			)
			(layer "B.Fab")
		)
		(pad "1" smd rect
			(at 0.2667 0 90)
			(size 0.3048 0.381)
			(layers "B.Cu" "B.Mask" "B.Paste")
			(net "P0V8_SERDES_VDDA_PEX3")
		)
		(pad "2" smd rect
			(at -0.2667 0 90)
			(size 0.3048 0.381)
			(layers "B.Cu" "B.Mask" "B.Paste")
			(net "GND")
		)
	)
	(footprint ""
		(layer "B.Cu")
		(at 357.770684 -283.818584 90)
		(property "Reference" "PR156"
			(at 0 0 90)
			(layer "B.SilkS")
			(hide yes)
			(effects
				(font
					(size 1.27 1.27)
				)
				(justify mirror)
			)
		)
		(property "Value" ""
			(at 0 0 90)
			(layer "B.Fab")
			(effects
				(font
					(size 1.27 1.27)
				)
				(justify mirror)
			)
		)
		(duplicate_pad_numbers_are_jumpers no)
		(fp_line
			(start 0.7874 -0.4064)
			(end -0.7874 -0.4064)
			(stroke
				(width 0.1524)
				(type default)
			)
			(layer "B.SilkS")
		)
		(fp_line
			(start -0.7874 -0.4064)
			(end -0.7874 0.4064)
			(stroke
				(width 0.1524)
				(type default)
			)
			(layer "B.SilkS")
		)
		(fp_line
			(start 0.7874 0.4064)
			(end 0.7874 -0.4064)
			(stroke
				(width 0.1524)
				(type default)
			)
			(layer "B.SilkS")
		)
		(fp_line
			(start -0.7874 0.4064)
			(end 0.7874 0.4064)
			(stroke
				(width 0.1524)
				(type default)
			)
			(layer "B.SilkS")
		)
		(fp_line
			(start 0.67945 -0.305054)
			(end 0.12065 -0.305054)
			(stroke
				(width 0.1)
				(type default)
			)
			(layer "B.Fab")
		)
		(fp_line
			(start 0.12065 -0.305054)
			(end 0.12065 -0.2794)
			(stroke
				(width 0.1)
				(type default)
			)
			(layer "B.Fab")
		)
		(fp_line
			(start -0.12065 -0.3048)
			(end -0.67945 -0.3048)
			(stroke
				(width 0.1)
				(type default)
			)
			(layer "B.Fab")
		)
		(fp_line
			(start -0.67945 -0.3048)
			(end -0.67945 0.3048)
			(stroke
				(width 0.1)
				(type default)
			)
			(layer "B.Fab")
		)
		(fp_line
			(start 0.12065 -0.2794)
			(end -0.12065 -0.2794)
			(stroke
				(width 0.1)
				(type default)
			)
			(layer "B.Fab")
		)
		(fp_line
			(start -0.12065 -0.2794)
			(end -0.12065 -0.3048)
			(stroke
				(width 0.1)
				(type default)
			)
			(layer "B.Fab")
		)
		(fp_line
			(start 0.12065 0.2794)
			(end 0.12065 0.3048)
			(stroke
				(width 0.1)
				(type default)
			)
			(layer "B.Fab")
		)
		(fp_line
			(start -0.120396 0.2794)
			(end 0.12065 0.2794)
			(stroke
				(width 0.1)
				(type default)
			)
			(layer "B.Fab")
		)
		(fp_line
			(start 0.67945 0.3048)
			(end 0.67945 -0.305054)
			(stroke
				(width 0.1)
				(type default)
			)
			(layer "B.Fab")
		)
		(fp_line
			(start 0.12065 0.3048)
			(end 0.67945 0.3048)
			(stroke
				(width 0.1)
				(type default)
			)
			(layer "B.Fab")
		)
		(fp_line
			(start -0.120396 0.3048)
			(end -0.120396 0.2794)
			(stroke
				(width 0.1)
				(type default)
			)
			(layer "B.Fab")
		)
		(fp_line
			(start -0.67945 0.3048)
			(end -0.120396 0.3048)
			(stroke
				(width 0.1)
				(type default)
			)
			(layer "B.Fab")
		)
		(pad "1" smd circle
			(at 0.40005 0 270)
			(size 0 0)
			(layers "B.Cu" "B.Mask" "B.Paste")
			(net "P0V8_PEX3_PVCC")
		)
		(pad "2" smd circle
			(at -0.40005 0 270)
			(size 0 0)
			(layers "B.Cu" "B.Mask" "B.Paste")
			(net "P0V8_PEX3_VCC1")
		)
	)
	(footprint ""
		(layer "B.Cu")
		(at 108.711238 -285.576518 -90)
		(property "Reference" "PR7176"
			(at 0 0 90)
			(layer "B.SilkS")
			(hide yes)
			(effects
				(font
					(size 1.27 1.27)
				)
				(justify mirror)
			)
		)
		(property "Value" ""
			(at 0 0 90)
			(layer "B.Fab")
			(effects
				(font
					(size 1.27 1.27)
				)
				(justify mirror)
			)
		)
		(duplicate_pad_numbers_are_jumpers no)
		(fp_line
			(start -0.7874 0.4064)
			(end 0.7874 0.4064)
			(stroke
				(width 0.1524)
				(type default)
			)
			(layer "B.SilkS")
		)
		(fp_line
			(start 0.7874 0.4064)
			(end 0.7874 -0.4064)
			(stroke
				(width 0.1524)
				(type default)
			)
			(layer "B.SilkS")
		)
		(fp_line
			(start -0.7874 -0.4064)
			(end -0.7874 0.4064)
			(stroke
				(width 0.1524)
				(type default)
			)
			(layer "B.SilkS")
		)
		(fp_line
			(start 0.7874 -0.4064)
			(end -0.7874 -0.4064)
			(stroke
				(width 0.1524)
				(type default)
			)
			(layer "B.SilkS")
		)
		(fp_line
			(start -0.67945 0.3048)
			(end -0.120396 0.3048)
			(stroke
				(width 0.1)
				(type default)
			)
			(layer "B.Fab")
		)
		(fp_line
			(start -0.120396 0.3048)
			(end -0.120396 0.2794)
			(stroke
				(width 0.1)
				(type default)
			)
			(layer "B.Fab")
		)
		(fp_line
			(start 0.12065 0.3048)
			(end 0.67945 0.3048)
			(stroke
				(width 0.1)
				(type default)
			)
			(layer "B.Fab")
		)
		(fp_line
			(start 0.67945 0.3048)
			(end 0.67945 -0.305054)
			(stroke
				(width 0.1)
				(type default)
			)
			(layer "B.Fab")
		)
		(fp_line
			(start -0.120396 0.2794)
			(end 0.12065 0.2794)
			(stroke
				(width 0.1)
				(type default)
			)
			(layer "B.Fab")
		)
		(fp_line
			(start 0.12065 0.2794)
			(end 0.12065 0.3048)
			(stroke
				(width 0.1)
				(type default)
			)
			(layer "B.Fab")
		)
		(fp_line
			(start -0.12065 -0.2794)
			(end -0.12065 -0.3048)
			(stroke
				(width 0.1)
				(type default)
			)
			(layer "B.Fab")
		)
		(fp_line
			(start 0.12065 -0.2794)
			(end -0.12065 -0.2794)
			(stroke
				(width 0.1)
				(type default)
			)
			(layer "B.Fab")
		)
		(fp_line
			(start -0.67945 -0.3048)
			(end -0.67945 0.3048)
			(stroke
				(width 0.1)
				(type default)
			)
			(layer "B.Fab")
		)
		(fp_line
			(start -0.12065 -0.3048)
			(end -0.67945 -0.3048)
			(stroke
				(width 0.1)
				(type default)
			)
			(layer "B.Fab")
		)
		(fp_line
			(start 0.12065 -0.305054)
			(end 0.12065 -0.2794)
			(stroke
				(width 0.1)
				(type default)
			)
			(layer "B.Fab")
		)
		(fp_line
			(start 0.67945 -0.305054)
			(end 0.12065 -0.305054)
			(stroke
				(width 0.1)
				(type default)
			)
			(layer "B.Fab")
		)
		(pad "1" smd circle
			(at 0.40005 0 90)
			(size 0 0)
			(layers "B.Cu" "B.Mask" "B.Paste")
			(net "P0V8_PEX0_PVCC")
		)
		(pad "2" smd circle
			(at -0.40005 0 90)
			(size 0 0)
			(layers "B.Cu" "B.Mask" "B.Paste")
			(net "P3V3_AUX")
		)
	)
	(footprint ""
		(layer "B.Cu")
		(at 449.83781 -275.872956)
		(property "Reference" "C4387"
			(at 0 0 0)
			(layer "B.SilkS")
			(hide yes)
			(effects
				(font
					(size 1.27 1.27)
				)
				(justify mirror)
			)
		)
		(property "Value" ""
			(at 0 0 0)
			(layer "B.Fab")
			(effects
				(font
					(size 1.27 1.27)
				)
				(justify mirror)
			)
		)
		(duplicate_pad_numbers_are_jumpers no)
		(fp_line
			(start -1.2954 -0.5842)
			(end -1.2954 0.5842)
			(stroke
				(width 0.1524)
				(type default)
			)
			(layer "B.SilkS")
		)
		(fp_line
			(start -1.2954 0.5842)
			(end 1.2954 0.5842)
			(stroke
				(width 0.1524)
				(type default)
			)
			(layer "B.SilkS")
		)
		(fp_line
			(start 1.2954 -0.5842)
			(end -1.2954 -0.5842)
			(stroke
				(width 0.1524)
				(type default)
			)
			(layer "B.SilkS")
		)
		(fp_line
			(start 1.2954 0.5842)
			(end 1.2954 -0.5842)
			(stroke
				(width 0.1524)
				(type default)
			)
			(layer "B.SilkS")
		)
		(fp_line
			(start -1.1938 -0.4064)
			(end -1.1938 0.4064)
			(stroke
				(width 0.1)
				(type default)
			)
			(layer "B.Fab")
		)
		(fp_line
			(start -1.1938 0.4064)
			(end -0.8636 0.4064)
			(stroke
				(width 0.1)
				(type default)
			)
			(layer "B.Fab")
		)
		(fp_line
			(start -0.8636 -0.4572)
			(end -0.8636 -0.4064)
			(stroke
				(width 0.1)
				(type default)
			)
			(layer "B.Fab")
		)
		(fp_line
			(start -0.8636 -0.4064)
			(end -1.1938 -0.4064)
			(stroke
				(width 0.1)
				(type default)
			)
			(layer "B.Fab")
		)
		(fp_line
			(start -0.8636 0.4064)
			(end -0.8636 0.4572)
			(stroke
				(width 0.1)
				(type default)
			)
			(layer "B.Fab")
		)
		(fp_line
			(start -0.8636 0.4572)
			(end 0.8636 0.4572)
			(stroke
				(width 0.1)
				(type default)
			)
			(layer "B.Fab")
		)
		(fp_line
			(start 0.8636 -0.4572)
			(end -0.8636 -0.4572)
			(stroke
				(width 0.1)
				(type default)
			)
			(layer "B.Fab")
		)
		(fp_line
			(start 0.8636 -0.4064)
			(end 0.8636 -0.4572)
			(stroke
				(width 0.1)
				(type default)
			)
			(layer "B.Fab")
		)
		(fp_line
			(start 0.8636 0.4064)
			(end 1.1938 0.4064)
			(stroke
				(width 0.1)
				(type default)
			)
			(layer "B.Fab")
		)
		(fp_line
			(start 0.8636 0.4572)
			(end 0.8636 0.4064)
			(stroke
				(width 0.1)
				(type default)
			)
			(layer "B.Fab")
		)
		(fp_line
			(start 1.1938 -0.4064)
			(end 0.8636 -0.4064)
			(stroke
				(width 0.1)
				(type default)
			)
			(layer "B.Fab")
		)
		(fp_line
			(start 1.1938 0.4064)
			(end 1.1938 -0.4064)
			(stroke
				(width 0.1)
				(type default)
			)
			(layer "B.Fab")
		)
		(pad "1" smd rect
			(at 0.7366 0 270)
			(size 0.7112 0.8128)
			(layers "B.Cu" "B.Mask" "B.Paste")
			(net "P1V25_PEX3")
		)
		(pad "2" smd rect
			(at -0.7366 0 270)
			(size 0.7112 0.8128)
			(layers "B.Cu" "B.Mask" "B.Paste")
			(net "GND")
		)
	)
	(footprint ""
		(layer "B.Cu")
		(at 159.523684 -286.018732)
		(property "Reference" "C3161"
			(at 0 0 0)
			(layer "B.SilkS")
			(hide yes)
			(effects
				(font
					(size 1.27 1.27)
				)
				(justify mirror)
			)
		)
		(property "Value" ""
			(at 0 0 0)
			(layer "B.Fab")
			(effects
				(font
					(size 1.27 1.27)
				)
				(justify mirror)
			)
		)
		(duplicate_pad_numbers_are_jumpers no)
		(fp_line
			(start -1.2954 -0.5842)
			(end -1.2954 0.5842)
			(stroke
				(width 0.1524)
				(type default)
			)
			(layer "B.SilkS")
		)
		(fp_line
			(start -1.2954 0.5842)
			(end 1.2954 0.5842)
			(stroke
				(width 0.1524)
				(type default)
			)
			(layer "B.SilkS")
		)
		(fp_line
			(start 1.2954 -0.5842)
			(end -1.2954 -0.5842)
			(stroke
				(width 0.1524)
				(type default)
			)
			(layer "B.SilkS")
		)
		(fp_line
			(start 1.2954 0.5842)
			(end 1.2954 -0.5842)
			(stroke
				(width 0.1524)
				(type default)
			)
			(layer "B.SilkS")
		)
		(fp_line
			(start -1.1938 -0.4064)
			(end -1.1938 0.4064)
			(stroke
				(width 0.1)
				(type default)
			)
			(layer "B.Fab")
		)
		(fp_line
			(start -1.1938 0.4064)
			(end -0.8636 0.4064)
			(stroke
				(width 0.1)
				(type default)
			)
			(layer "B.Fab")
		)
		(fp_line
			(start -0.8636 -0.4572)
			(end -0.8636 -0.4064)
			(stroke
				(width 0.1)
				(type default)
			)
			(layer "B.Fab")
		)
		(fp_line
			(start -0.8636 -0.4064)
			(end -1.1938 -0.4064)
			(stroke
				(width 0.1)
				(type default)
			)
			(layer "B.Fab")
		)
		(fp_line
			(start -0.8636 0.4064)
			(end -0.8636 0.4572)
			(stroke
				(width 0.1)
				(type default)
			)
			(layer "B.Fab")
		)
		(fp_line
			(start -0.8636 0.4572)
			(end 0.8636 0.4572)
			(stroke
				(width 0.1)
				(type default)
			)
			(layer "B.Fab")
		)
		(fp_line
			(start 0.8636 -0.4572)
			(end -0.8636 -0.4572)
			(stroke
				(width 0.1)
				(type default)
			)
			(layer "B.Fab")
		)
		(fp_line
			(start 0.8636 -0.4064)
			(end 0.8636 -0.4572)
			(stroke
				(width 0.1)
				(type default)
			)
			(layer "B.Fab")
		)
		(fp_line
			(start 0.8636 0.4064)
			(end 1.1938 0.4064)
			(stroke
				(width 0.1)
				(type default)
			)
			(layer "B.Fab")
		)
		(fp_line
			(start 0.8636 0.4572)
			(end 0.8636 0.4064)
			(stroke
				(width 0.1)
				(type default)
			)
			(layer "B.Fab")
		)
		(fp_line
			(start 1.1938 -0.4064)
			(end 0.8636 -0.4064)
			(stroke
				(width 0.1)
				(type default)
			)
			(layer "B.Fab")
		)
		(fp_line
			(start 1.1938 0.4064)
			(end 1.1938 -0.4064)
			(stroke
				(width 0.1)
				(type default)
			)
			(layer "B.Fab")
		)
		(pad "1" smd rect
			(at 0.7366 0 270)
			(size 0.7112 0.8128)
			(layers "B.Cu" "B.Mask" "B.Paste")
			(net "P1V8_PEX")
		)
		(pad "2" smd rect
			(at -0.7366 0 270)
			(size 0.7112 0.8128)
			(layers "B.Cu" "B.Mask" "B.Paste")
			(net "GND")
		)
	)
	(footprint ""
		(layer "B.Cu")
		(at 292.79977 -301.599854 -90)
		(property "Reference" "C1716"
			(at 0 0 90)
			(layer "B.SilkS")
			(hide yes)
			(effects
				(font
					(size 1.27 1.27)
				)
				(justify mirror)
			)
		)
		(property "Value" ""
			(at 0 0 90)
			(layer "B.Fab")
			(effects
				(font
					(size 1.27 1.27)
				)
				(justify mirror)
			)
		)
		(duplicate_pad_numbers_are_jumpers no)
		(fp_line
			(start -0.299974 0.150114)
			(end 0.299974 0.150114)
			(stroke
				(width 0.1)
				(type default)
			)
			(layer "B.Fab")
		)
		(fp_line
			(start 0.299974 0.150114)
			(end 0.299974 -0.150114)
			(stroke
				(width 0.1)
				(type default)
			)
			(layer "B.Fab")
		)
		(fp_line
			(start -0.299974 -0.150114)
			(end -0.299974 0.150114)
			(stroke
				(width 0.1)
				(type default)
			)
			(layer "B.Fab")
		)
		(fp_line
			(start 0.299974 -0.150114)
			(end -0.299974 -0.150114)
			(stroke
				(width 0.1)
				(type default)
			)
			(layer "B.Fab")
		)
		(pad "1" smd rect
			(at 0.2667 0 90)
			(size 0.3048 0.381)
			(layers "B.Cu" "B.Mask" "B.Paste")
			(net "P0V8_SERDES_VDDA_PEX2")
		)
		(pad "2" smd rect
			(at -0.2667 0 90)
			(size 0.3048 0.381)
			(layers "B.Cu" "B.Mask" "B.Paste")
			(net "GND")
		)
	)
	(footprint ""
		(layer "B.Cu")
		(at 100.90023 -323.111622 180)
		(property "Reference" "PJ18"
			(at 0 0 0)
			(layer "B.SilkS")
			(hide yes)
			(effects
				(font
					(size 1.27 1.27)
				)
				(justify mirror)
			)
		)
		(property "Value" ""
			(at 0 0 0)
			(layer "B.Fab")
			(effects
				(font
					(size 1.27 1.27)
				)
				(justify mirror)
			)
		)
		(duplicate_pad_numbers_are_jumpers no)
		(pad "1" smd circle
			(at 0.40005 0 270)
			(size 0 0)
			(layers "B.Cu" "B.Mask" "B.Paste")
			(net "VSENSE_P0V8_PEX0_SKT_VSEN")
		)
		(pad "2" smd rect
			(at -0.40005 0 180)
			(size 0.4572 0.508)
			(layers "B.Cu" "B.Mask" "B.Paste")
			(net "SH_P0V8_PEX0_VSEN0_L")
		)
		(zone
			(layer "B.Cu")
			(hatch none 0.5)
			(connect_pads
				(clearance 0)
			)
			(min_thickness 0.25)
			(keepout
				(tracks allowed)
				(vias not_allowed)
				(pads allowed)
				(copperpour not_allowed)
				(footprints allowed)
			)
			(placement
				(enabled no)
				(sheetname "")
			)
			(fill
				(thermal_gap 0.5)
				(thermal_bridge_width 0.5)
				(island_removal_mode 0)
			)
			(polygon
				(pts
					(xy 101.58603 -323.416422) (xy 101.58603 -322.806822) (xy 100.21443 -322.806822) (xy 100.21443 -323.416422)
				)
			)
		)
	)
	(footprint ""
		(layer "B.Cu")
		(at 68.941442 -287.824926)
		(property "Reference" "C2997"
			(at 0 0 0)
			(layer "B.SilkS")
			(hide yes)
			(effects
				(font
					(size 1.27 1.27)
				)
				(justify mirror)
			)
		)
		(property "Value" ""
			(at 0 0 0)
			(layer "B.Fab")
			(effects
				(font
					(size 1.27 1.27)
				)
				(justify mirror)
			)
		)
		(duplicate_pad_numbers_are_jumpers no)
		(fp_line
			(start -0.299974 -0.150114)
			(end -0.299974 0.150114)
			(stroke
				(width 0.1)
				(type default)
			)
			(layer "B.Fab")
		)
		(fp_line
			(start -0.299974 0.150114)
			(end 0.299974 0.150114)
			(stroke
				(width 0.1)
				(type default)
			)
			(layer "B.Fab")
		)
		(fp_line
			(start 0.299974 -0.150114)
			(end -0.299974 -0.150114)
			(stroke
				(width 0.1)
				(type default)
			)
			(layer "B.Fab")
		)
		(fp_line
			(start 0.299974 0.150114)
			(end 0.299974 -0.150114)
			(stroke
				(width 0.1)
				(type default)
			)
			(layer "B.Fab")
		)
		(pad "1" smd rect
			(at 0.2667 0 180)
			(size 0.3048 0.381)
			(layers "B.Cu" "B.Mask" "B.Paste")
			(net "P1V8_VDDA_PEX0")
		)
		(pad "2" smd rect
			(at -0.2667 0 180)
			(size 0.3048 0.381)
			(layers "B.Cu" "B.Mask" "B.Paste")
			(net "GND")
		)
	)
	(footprint ""
		(layer "B.Cu")
		(at 46.355 -295.2623)
		(property "Reference" "C3043"
			(at 0 0 0)
			(layer "B.SilkS")
			(hide yes)
			(effects
				(font
					(size 1.27 1.27)
				)
				(justify mirror)
			)
		)
		(property "Value" ""
			(at 0 0 0)
			(layer "B.Fab")
			(effects
				(font
					(size 1.27 1.27)
				)
				(justify mirror)
			)
		)
		(duplicate_pad_numbers_are_jumpers no)
		(fp_line
			(start -0.299974 -0.150114)
			(end -0.299974 0.150114)
			(stroke
				(width 0.1)
				(type default)
			)
			(layer "B.Fab")
		)
		(fp_line
			(start -0.299974 0.150114)
			(end 0.299974 0.150114)
			(stroke
				(width 0.1)
				(type default)
			)
			(layer "B.Fab")
		)
		(fp_line
			(start 0.299974 -0.150114)
			(end -0.299974 -0.150114)
			(stroke
				(width 0.1)
				(type default)
			)
			(layer "B.Fab")
		)
		(fp_line
			(start 0.299974 0.150114)
			(end 0.299974 -0.150114)
			(stroke
				(width 0.1)
				(type default)
			)
			(layer "B.Fab")
		)
		(pad "1" smd rect
			(at 0.2667 0 180)
			(size 0.3048 0.381)
			(layers "B.Cu" "B.Mask" "B.Paste")
			(net "PCEPLL4_VDDA18_PEX0")
		)
		(pad "2" smd rect
			(at -0.2667 0 180)
			(size 0.3048 0.381)
			(layers "B.Cu" "B.Mask" "B.Paste")
			(net "GND")
		)
	)
	(footprint ""
		(layer "B.Cu")
		(at 160.549844 -297.815)
		(property "Reference" "C3181"
			(at 0 0 0)
			(layer "B.SilkS")
			(hide yes)
			(effects
				(font
					(size 1.27 1.27)
				)
				(justify mirror)
			)
		)
		(property "Value" ""
			(at 0 0 0)
			(layer "B.Fab")
			(effects
				(font
					(size 1.27 1.27)
				)
				(justify mirror)
			)
		)
		(duplicate_pad_numbers_are_jumpers no)
		(fp_line
			(start -0.299974 -0.150114)
			(end -0.299974 0.150114)
			(stroke
				(width 0.1)
				(type default)
			)
			(layer "B.Fab")
		)
		(fp_line
			(start -0.299974 0.150114)
			(end 0.299974 0.150114)
			(stroke
				(width 0.1)
				(type default)
			)
			(layer "B.Fab")
		)
		(fp_line
			(start 0.299974 -0.150114)
			(end -0.299974 -0.150114)
			(stroke
				(width 0.1)
				(type default)
			)
			(layer "B.Fab")
		)
		(fp_line
			(start 0.299974 0.150114)
			(end 0.299974 -0.150114)
			(stroke
				(width 0.1)
				(type default)
			)
			(layer "B.Fab")
		)
		(pad "1" smd rect
			(at 0.2667 0 180)
			(size 0.3048 0.381)
			(layers "B.Cu" "B.Mask" "B.Paste")
			(net "P1V8_VDDA_PEX1")
		)
		(pad "2" smd rect
			(at -0.2667 0 180)
			(size 0.3048 0.381)
			(layers "B.Cu" "B.Mask" "B.Paste")
			(net "GND")
		)
	)
	(footprint ""
		(layer "B.Cu")
		(at 234.993434 -352.307906 180)
		(property "Reference" "PR7156"
			(at 0 0 0)
			(layer "B.SilkS")
			(hide yes)
			(effects
				(font
					(size 1.27 1.27)
				)
				(justify mirror)
			)
		)
		(property "Value" ""
			(at 0 0 0)
			(layer "B.Fab")
			(effects
				(font
					(size 1.27 1.27)
				)
				(justify mirror)
			)
		)
		(duplicate_pad_numbers_are_jumpers no)
		(fp_line
			(start 0.7874 0.4064)
			(end 0.7874 -0.4064)
			(stroke
				(width 0.1524)
				(type default)
			)
			(layer "B.SilkS")
		)
		(fp_line
			(start 0.7874 -0.4064)
			(end -0.7874 -0.4064)
			(stroke
				(width 0.1524)
				(type default)
			)
			(layer "B.SilkS")
		)
		(fp_line
			(start -0.7874 0.4064)
			(end 0.7874 0.4064)
			(stroke
				(width 0.1524)
				(type default)
			)
			(layer "B.SilkS")
		)
		(fp_line
			(start -0.7874 -0.4064)
			(end -0.7874 0.4064)
			(stroke
				(width 0.1524)
				(type default)
			)
			(layer "B.SilkS")
		)
		(fp_line
			(start 0.67945 0.3048)
			(end 0.67945 -0.305054)
			(stroke
				(width 0.1)
				(type default)
			)
			(layer "B.Fab")
		)
		(fp_line
			(start 0.67945 -0.305054)
			(end 0.12065 -0.305054)
			(stroke
				(width 0.1)
				(type default)
			)
			(layer "B.Fab")
		)
		(fp_line
			(start 0.12065 0.3048)
			(end 0.67945 0.3048)
			(stroke
				(width 0.1)
				(type default)
			)
			(layer "B.Fab")
		)
		(fp_line
			(start 0.12065 0.2794)
			(end 0.12065 0.3048)
			(stroke
				(width 0.1)
				(type default)
			)
			(layer "B.Fab")
		)
		(fp_line
			(start 0.12065 -0.2794)
			(end -0.12065 -0.2794)
			(stroke
				(width 0.1)
				(type default)
			)
			(layer "B.Fab")
		)
		(fp_line
			(start 0.12065 -0.305054)
			(end 0.12065 -0.2794)
			(stroke
				(width 0.1)
				(type default)
			)
			(layer "B.Fab")
		)
		(fp_line
			(start -0.120396 0.3048)
			(end -0.120396 0.2794)
			(stroke
				(width 0.1)
				(type default)
			)
			(layer "B.Fab")
		)
		(fp_line
			(start -0.120396 0.2794)
			(end 0.12065 0.2794)
			(stroke
				(width 0.1)
				(type default)
			)
			(layer "B.Fab")
		)
		(fp_line
			(start -0.12065 -0.2794)
			(end -0.12065 -0.3048)
			(stroke
				(width 0.1)
				(type default)
			)
			(layer "B.Fab")
		)
		(fp_line
			(start -0.12065 -0.3048)
			(end -0.67945 -0.3048)
			(stroke
				(width 0.1)
				(type default)
			)
			(layer "B.Fab")
		)
		(fp_line
			(start -0.67945 0.3048)
			(end -0.120396 0.3048)
			(stroke
				(width 0.1)
				(type default)
			)
			(layer "B.Fab")
		)
		(fp_line
			(start -0.67945 -0.3048)
			(end -0.67945 0.3048)
			(stroke
				(width 0.1)
				(type default)
			)
			(layer "B.Fab")
		)
		(pad "1" smd circle
			(at 0.40005 0)
			(size 0 0)
			(layers "B.Cu" "B.Mask" "B.Paste")
			(net "P12V_HSC_SENSE2_N")
		)
		(pad "2" smd circle
			(at -0.40005 0)
			(size 0 0)
			(layers "B.Cu" "B.Mask" "B.Paste")
			(net "P12V_HSC_SENSE2_R1_N")
		)
	)
	(footprint ""
		(layer "B.Cu")
		(at 342.493854 -213.587076 180)
		(property "Reference" "C2051"
			(at 0 0 0)
			(layer "B.SilkS")
			(hide yes)
			(effects
				(font
					(size 1.27 1.27)
				)
				(justify mirror)
			)
		)
		(property "Value" ""
			(at 0 0 0)
			(layer "B.Fab")
			(effects
				(font
					(size 1.27 1.27)
				)
				(justify mirror)
			)
		)
		(duplicate_pad_numbers_are_jumpers no)
		(fp_line
			(start 0.69215 0.2921)
			(end 0.69215 -0.2921)
			(stroke
				(width 0.1524)
				(type default)
			)
			(layer "B.SilkS")
		)
		(fp_line
			(start 0.69215 -0.2921)
			(end -0.69215 -0.2921)
			(stroke
				(width 0.1524)
				(type default)
			)
			(layer "B.SilkS")
		)
		(fp_line
			(start -0.69215 0.2921)
			(end 0.69215 0.2921)
			(stroke
				(width 0.1524)
				(type default)
			)
			(layer "B.SilkS")
		)
		(fp_line
			(start -0.69215 -0.2921)
			(end -0.69215 0.2921)
			(stroke
				(width 0.1524)
				(type default)
			)
			(layer "B.SilkS")
		)
		(fp_line
			(start 0.51435 0.2794)
			(end 0.51435 -0.2794)
			(stroke
				(width 0.1)
				(type default)
			)
			(layer "B.Fab")
		)
		(fp_line
			(start 0.51435 -0.2794)
			(end -0.51435 -0.2794)
			(stroke
				(width 0.1)
				(type default)
			)
			(layer "B.Fab")
		)
		(fp_line
			(start -0.51435 0.2794)
			(end 0.51435 0.2794)
			(stroke
				(width 0.1)
				(type default)
			)
			(layer "B.Fab")
		)
		(fp_line
			(start -0.51435 -0.2794)
			(end -0.51435 0.2794)
			(stroke
				(width 0.1)
				(type default)
			)
			(layer "B.Fab")
		)
		(pad "1" smd circle
			(at 0.40005 0)
			(size 0 0)
			(layers "B.Cu" "B.Mask" "B.Paste")
			(net "P3V3_FPGA_VCCIO2")
		)
		(pad "2" smd circle
			(at -0.40005 0)
			(size 0 0)
			(layers "B.Cu" "B.Mask" "B.Paste")
			(net "GND")
		)
		(zone
			(layer "B.Cu")
			(hatch none 0.5)
			(connect_pads
				(clearance 0)
			)
			(min_thickness 0.25)
			(keepout
				(tracks not_allowed)
				(vias allowed)
				(pads allowed)
				(copperpour not_allowed)
				(footprints allowed)
			)
			(placement
				(enabled no)
				(sheetname "")
			)
			(fill
				(thermal_gap 0.5)
				(thermal_bridge_width 0.5)
				(island_removal_mode 0)
			)
			(polygon
				(pts
					(xy 342.303354 -213.674706) (xy 342.394794 -213.732872) (xy 342.594184 -213.732872) (xy 342.684354 -213.674706)
					(xy 342.684354 -213.499446) (xy 342.594184 -213.441026) (xy 342.394794 -213.441026) (xy 342.303354 -213.499192)
				)
			)
		)
	)
	(footprint ""
		(layer "B.Cu")
		(at 415.074862 -297.79976 -90)
		(property "Reference" "C1948"
			(at 0 0 90)
			(layer "B.SilkS")
			(hide yes)
			(effects
				(font
					(size 1.27 1.27)
				)
				(justify mirror)
			)
		)
		(property "Value" ""
			(at 0 0 90)
			(layer "B.Fab")
			(effects
				(font
					(size 1.27 1.27)
				)
				(justify mirror)
			)
		)
		(duplicate_pad_numbers_are_jumpers no)
		(fp_line
			(start -0.299974 0.150114)
			(end 0.299974 0.150114)
			(stroke
				(width 0.1)
				(type default)
			)
			(layer "B.Fab")
		)
		(fp_line
			(start 0.299974 0.150114)
			(end 0.299974 -0.150114)
			(stroke
				(width 0.1)
				(type default)
			)
			(layer "B.Fab")
		)
		(fp_line
			(start -0.299974 -0.150114)
			(end -0.299974 0.150114)
			(stroke
				(width 0.1)
				(type default)
			)
			(layer "B.Fab")
		)
		(fp_line
			(start 0.299974 -0.150114)
			(end -0.299974 -0.150114)
			(stroke
				(width 0.1)
				(type default)
			)
			(layer "B.Fab")
		)
		(pad "1" smd rect
			(at 0.2667 0 90)
			(size 0.3048 0.381)
			(layers "B.Cu" "B.Mask" "B.Paste")
			(net "P0V8_SERDES_VDDA_PEX3")
		)
		(pad "2" smd rect
			(at -0.2667 0 90)
			(size 0.3048 0.381)
			(layers "B.Cu" "B.Mask" "B.Paste")
			(net "GND")
		)
	)
	(footprint ""
		(layer "B.Cu")
		(at 449.810378 -273.486118)
		(property "Reference" "C4404"
			(at 0 0 0)
			(layer "B.SilkS")
			(hide yes)
			(effects
				(font
					(size 1.27 1.27)
				)
				(justify mirror)
			)
		)
		(property "Value" ""
			(at 0 0 0)
			(layer "B.Fab")
			(effects
				(font
					(size 1.27 1.27)
				)
				(justify mirror)
			)
		)
		(duplicate_pad_numbers_are_jumpers no)
		(fp_line
			(start -0.299974 -0.150114)
			(end -0.299974 0.150114)
			(stroke
				(width 0.1)
				(type default)
			)
			(layer "B.Fab")
		)
		(fp_line
			(start -0.299974 0.150114)
			(end 0.299974 0.150114)
			(stroke
				(width 0.1)
				(type default)
			)
			(layer "B.Fab")
		)
		(fp_line
			(start 0.299974 -0.150114)
			(end -0.299974 -0.150114)
			(stroke
				(width 0.1)
				(type default)
			)
			(layer "B.Fab")
		)
		(fp_line
			(start 0.299974 0.150114)
			(end 0.299974 -0.150114)
			(stroke
				(width 0.1)
				(type default)
			)
			(layer "B.Fab")
		)
		(pad "1" smd rect
			(at 0.2667 0 180)
			(size 0.3048 0.381)
			(layers "B.Cu" "B.Mask" "B.Paste")
			(net "P1V25_PEX3")
		)
		(pad "2" smd rect
			(at -0.2667 0 180)
			(size 0.3048 0.381)
			(layers "B.Cu" "B.Mask" "B.Paste")
			(net "GND")
		)
	)
	(footprint ""
		(layer "B.Cu")
		(at 182.39994 -303.499774 -90)
		(property "Reference" "C3086"
			(at 0 0 90)
			(layer "B.SilkS")
			(hide yes)
			(effects
				(font
					(size 1.27 1.27)
				)
				(justify mirror)
			)
		)
		(property "Value" ""
			(at 0 0 90)
			(layer "B.Fab")
			(effects
				(font
					(size 1.27 1.27)
				)
				(justify mirror)
			)
		)
		(duplicate_pad_numbers_are_jumpers no)
		(fp_line
			(start -0.299974 0.150114)
			(end 0.299974 0.150114)
			(stroke
				(width 0.1)
				(type default)
			)
			(layer "B.Fab")
		)
		(fp_line
			(start 0.299974 0.150114)
			(end 0.299974 -0.150114)
			(stroke
				(width 0.1)
				(type default)
			)
			(layer "B.Fab")
		)
		(fp_line
			(start -0.299974 -0.150114)
			(end -0.299974 0.150114)
			(stroke
				(width 0.1)
				(type default)
			)
			(layer "B.Fab")
		)
		(fp_line
			(start 0.299974 -0.150114)
			(end -0.299974 -0.150114)
			(stroke
				(width 0.1)
				(type default)
			)
			(layer "B.Fab")
		)
		(pad "1" smd rect
			(at 0.2667 0 90)
			(size 0.3048 0.381)
			(layers "B.Cu" "B.Mask" "B.Paste")
			(net "P1V25_PEX1")
		)
		(pad "2" smd rect
			(at -0.2667 0 90)
			(size 0.3048 0.381)
			(layers "B.Cu" "B.Mask" "B.Paste")
			(net "GND")
		)
	)
	(footprint ""
		(layer "B.Cu")
		(at 173.375066 -297.79976 90)
		(property "Reference" "C1407"
			(at 0 0 90)
			(layer "B.SilkS")
			(hide yes)
			(effects
				(font
					(size 1.27 1.27)
				)
				(justify mirror)
			)
		)
		(property "Value" ""
			(at 0 0 90)
			(layer "B.Fab")
			(effects
				(font
					(size 1.27 1.27)
				)
				(justify mirror)
			)
		)
		(duplicate_pad_numbers_are_jumpers no)
		(fp_line
			(start 0.299974 -0.150114)
			(end -0.299974 -0.150114)
			(stroke
				(width 0.1)
				(type default)
			)
			(layer "B.Fab")
		)
		(fp_line
			(start -0.299974 -0.150114)
			(end -0.299974 0.150114)
			(stroke
				(width 0.1)
				(type default)
			)
			(layer "B.Fab")
		)
		(fp_line
			(start 0.299974 0.150114)
			(end 0.299974 -0.150114)
			(stroke
				(width 0.1)
				(type default)
			)
			(layer "B.Fab")
		)
		(fp_line
			(start -0.299974 0.150114)
			(end 0.299974 0.150114)
			(stroke
				(width 0.1)
				(type default)
			)
			(layer "B.Fab")
		)
		(pad "1" smd rect
			(at 0.2667 0 270)
			(size 0.3048 0.381)
			(layers "B.Cu" "B.Mask" "B.Paste")
			(net "P0V8_PEX1")
		)
		(pad "2" smd rect
			(at -0.2667 0 270)
			(size 0.3048 0.381)
			(layers "B.Cu" "B.Mask" "B.Paste")
			(net "GND")
		)
	)
	(footprint ""
		(layer "B.Cu")
		(at 171.949872 -290.199826 90)
		(property "Reference" "C1452"
			(at 0 0 90)
			(layer "B.SilkS")
			(hide yes)
			(effects
				(font
					(size 1.27 1.27)
				)
				(justify mirror)
			)
		)
		(property "Value" ""
			(at 0 0 90)
			(layer "B.Fab")
			(effects
				(font
					(size 1.27 1.27)
				)
				(justify mirror)
			)
		)
		(duplicate_pad_numbers_are_jumpers no)
		(fp_line
			(start 0.299974 -0.150114)
			(end -0.299974 -0.150114)
			(stroke
				(width 0.1)
				(type default)
			)
			(layer "B.Fab")
		)
		(fp_line
			(start -0.299974 -0.150114)
			(end -0.299974 0.150114)
			(stroke
				(width 0.1)
				(type default)
			)
			(layer "B.Fab")
		)
		(fp_line
			(start 0.299974 0.150114)
			(end 0.299974 -0.150114)
			(stroke
				(width 0.1)
				(type default)
			)
			(layer "B.Fab")
		)
		(fp_line
			(start -0.299974 0.150114)
			(end 0.299974 0.150114)
			(stroke
				(width 0.1)
				(type default)
			)
			(layer "B.Fab")
		)
		(pad "1" smd rect
			(at 0.2667 0 270)
			(size 0.3048 0.381)
			(layers "B.Cu" "B.Mask" "B.Paste")
			(net "P0V8_SERDES_VDDA_PEX1")
		)
		(pad "2" smd rect
			(at -0.2667 0 270)
			(size 0.3048 0.381)
			(layers "B.Cu" "B.Mask" "B.Paste")
			(net "GND")
		)
	)
	(footprint ""
		(layer "B.Cu")
		(at 4.893818 -290.24707)
		(property "Reference" "PC987"
			(at 0 0 0)
			(layer "B.SilkS")
			(hide yes)
			(effects
				(font
					(size 1.27 1.27)
				)
				(justify mirror)
			)
		)
		(property "Value" ""
			(at 0 0 0)
			(layer "B.Fab")
			(effects
				(font
					(size 1.27 1.27)
				)
				(justify mirror)
			)
		)
		(duplicate_pad_numbers_are_jumpers no)
		(fp_line
			(start -1.524 -0.762)
			(end -1.524 0.762)
			(stroke
				(width 0.1524)
				(type default)
			)
			(layer "B.SilkS")
		)
		(fp_line
			(start -1.524 0.762)
			(end 1.524 0.762)
			(stroke
				(width 0.1524)
				(type default)
			)
			(layer "B.SilkS")
		)
		(fp_line
			(start 1.524 -0.762)
			(end -1.524 -0.762)
			(stroke
				(width 0.1524)
				(type default)
			)
			(layer "B.SilkS")
		)
		(fp_line
			(start 1.524 0.762)
			(end 1.524 -0.762)
			(stroke
				(width 0.1524)
				(type default)
			)
			(layer "B.SilkS")
		)
		(fp_line
			(start -1.1049 -0.724916)
			(end 1.1049 -0.724916)
			(stroke
				(width 0.1)
				(type default)
			)
			(layer "B.Fab")
		)
		(fp_line
			(start -1.1049 0.724916)
			(end -1.1049 -0.724916)
			(stroke
				(width 0.1)
				(type default)
			)
			(layer "B.Fab")
		)
		(fp_line
			(start 1.1049 -0.724916)
			(end 1.1049 0.724916)
			(stroke
				(width 0.1)
				(type default)
			)
			(layer "B.Fab")
		)
		(fp_line
			(start 1.1049 0.724916)
			(end -1.1049 0.724916)
			(stroke
				(width 0.1)
				(type default)
			)
			(layer "B.Fab")
		)
		(pad "1" smd rect
			(at 0.889 0)
			(size 1.016 1.27)
			(layers "B.Cu" "B.Mask" "B.Paste")
			(net "P1V25_PEX0_R")
		)
		(pad "2" smd rect
			(at -0.889 0)
			(size 1.016 1.27)
			(layers "B.Cu" "B.Mask" "B.Paste")
			(net "GND")
		)
	)
	(footprint ""
		(layer "B.Cu")
		(at 350.012 -207.772 -90)
		(property "Reference" "R5503"
			(at 0 0 90)
			(layer "B.SilkS")
			(hide yes)
			(effects
				(font
					(size 1.27 1.27)
				)
				(justify mirror)
			)
		)
		(property "Value" ""
			(at 0 0 90)
			(layer "B.Fab")
			(effects
				(font
					(size 1.27 1.27)
				)
				(justify mirror)
			)
		)
		(duplicate_pad_numbers_are_jumpers no)
		(fp_line
			(start -0.7874 0.4064)
			(end 0.7874 0.4064)
			(stroke
				(width 0.1524)
				(type default)
			)
			(layer "B.SilkS")
		)
		(fp_line
			(start 0.7874 0.4064)
			(end 0.7874 -0.4064)
			(stroke
				(width 0.1524)
				(type default)
			)
			(layer "B.SilkS")
		)
		(fp_line
			(start -0.7874 -0.4064)
			(end -0.7874 0.4064)
			(stroke
				(width 0.1524)
				(type default)
			)
			(layer "B.SilkS")
		)
		(fp_line
			(start 0.7874 -0.4064)
			(end -0.7874 -0.4064)
			(stroke
				(width 0.1524)
				(type default)
			)
			(layer "B.SilkS")
		)
		(fp_line
			(start -0.67945 0.3048)
			(end -0.120396 0.3048)
			(stroke
				(width 0.1)
				(type default)
			)
			(layer "B.Fab")
		)
		(fp_line
			(start -0.120396 0.3048)
			(end -0.120396 0.2794)
			(stroke
				(width 0.1)
				(type default)
			)
			(layer "B.Fab")
		)
		(fp_line
			(start 0.12065 0.3048)
			(end 0.67945 0.3048)
			(stroke
				(width 0.1)
				(type default)
			)
			(layer "B.Fab")
		)
		(fp_line
			(start 0.67945 0.3048)
			(end 0.67945 -0.305054)
			(stroke
				(width 0.1)
				(type default)
			)
			(layer "B.Fab")
		)
		(fp_line
			(start -0.120396 0.2794)
			(end 0.12065 0.2794)
			(stroke
				(width 0.1)
				(type default)
			)
			(layer "B.Fab")
		)
		(fp_line
			(start 0.12065 0.2794)
			(end 0.12065 0.3048)
			(stroke
				(width 0.1)
				(type default)
			)
			(layer "B.Fab")
		)
		(fp_line
			(start -0.12065 -0.2794)
			(end -0.12065 -0.3048)
			(stroke
				(width 0.1)
				(type default)
			)
			(layer "B.Fab")
		)
		(fp_line
			(start 0.12065 -0.2794)
			(end -0.12065 -0.2794)
			(stroke
				(width 0.1)
				(type default)
			)
			(layer "B.Fab")
		)
		(fp_line
			(start -0.67945 -0.3048)
			(end -0.67945 0.3048)
			(stroke
				(width 0.1)
				(type default)
			)
			(layer "B.Fab")
		)
		(fp_line
			(start -0.12065 -0.3048)
			(end -0.67945 -0.3048)
			(stroke
				(width 0.1)
				(type default)
			)
			(layer "B.Fab")
		)
		(fp_line
			(start 0.12065 -0.305054)
			(end 0.12065 -0.2794)
			(stroke
				(width 0.1)
				(type default)
			)
			(layer "B.Fab")
		)
		(fp_line
			(start 0.67945 -0.305054)
			(end 0.12065 -0.305054)
			(stroke
				(width 0.1)
				(type default)
			)
			(layer "B.Fab")
		)
		(pad "1" smd circle
			(at 0.40005 0 90)
			(size 0 0)
			(layers "B.Cu" "B.Mask" "B.Paste")
			(net "P3V3_AUX")
		)
		(pad "2" smd circle
			(at -0.40005 0 90)
			(size 0 0)
			(layers "B.Cu" "B.Mask" "B.Paste")
			(net "RST_FPGA_BIC_N")
		)
	)
	(footprint ""
		(layer "B.Cu")
		(at 281.755342 -155.0416)
		(property "Reference" "R231"
			(at 0 0 0)
			(layer "B.SilkS")
			(hide yes)
			(effects
				(font
					(size 1.27 1.27)
				)
				(justify mirror)
			)
		)
		(property "Value" ""
			(at 0 0 0)
			(layer "B.Fab")
			(effects
				(font
					(size 1.27 1.27)
				)
				(justify mirror)
			)
		)
		(duplicate_pad_numbers_are_jumpers no)
		(fp_line
			(start -0.7874 -0.4064)
			(end -0.7874 0.4064)
			(stroke
				(width 0.1524)
				(type default)
			)
			(layer "B.SilkS")
		)
		(fp_line
			(start -0.7874 0.4064)
			(end 0.7874 0.4064)
			(stroke
				(width 0.1524)
				(type default)
			)
			(layer "B.SilkS")
		)
		(fp_line
			(start 0.7874 -0.4064)
			(end -0.7874 -0.4064)
			(stroke
				(width 0.1524)
				(type default)
			)
			(layer "B.SilkS")
		)
		(fp_line
			(start 0.7874 0.4064)
			(end 0.7874 -0.4064)
			(stroke
				(width 0.1524)
				(type default)
			)
			(layer "B.SilkS")
		)
		(fp_line
			(start -0.67945 -0.3048)
			(end -0.67945 0.3048)
			(stroke
				(width 0.1)
				(type default)
			)
			(layer "B.Fab")
		)
		(fp_line
			(start -0.67945 0.3048)
			(end -0.120396 0.3048)
			(stroke
				(width 0.1)
				(type default)
			)
			(layer "B.Fab")
		)
		(fp_line
			(start -0.12065 -0.3048)
			(end -0.67945 -0.3048)
			(stroke
				(width 0.1)
				(type default)
			)
			(layer "B.Fab")
		)
		(fp_line
			(start -0.12065 -0.2794)
			(end -0.12065 -0.3048)
			(stroke
				(width 0.1)
				(type default)
			)
			(layer "B.Fab")
		)
		(fp_line
			(start -0.120396 0.2794)
			(end 0.12065 0.2794)
			(stroke
				(width 0.1)
				(type default)
			)
			(layer "B.Fab")
		)
		(fp_line
			(start -0.120396 0.3048)
			(end -0.120396 0.2794)
			(stroke
				(width 0.1)
				(type default)
			)
			(layer "B.Fab")
		)
		(fp_line
			(start 0.12065 -0.305054)
			(end 0.12065 -0.2794)
			(stroke
				(width 0.1)
				(type default)
			)
			(layer "B.Fab")
		)
		(fp_line
			(start 0.12065 -0.2794)
			(end -0.12065 -0.2794)
			(stroke
				(width 0.1)
				(type default)
			)
			(layer "B.Fab")
		)
		(fp_line
			(start 0.12065 0.2794)
			(end 0.12065 0.3048)
			(stroke
				(width 0.1)
				(type default)
			)
			(layer "B.Fab")
		)
		(fp_line
			(start 0.12065 0.3048)
			(end 0.67945 0.3048)
			(stroke
				(width 0.1)
				(type default)
			)
			(layer "B.Fab")
		)
		(fp_line
			(start 0.67945 -0.305054)
			(end 0.12065 -0.305054)
			(stroke
				(width 0.1)
				(type default)
			)
			(layer "B.Fab")
		)
		(fp_line
			(start 0.67945 0.3048)
			(end 0.67945 -0.305054)
			(stroke
				(width 0.1)
				(type default)
			)
			(layer "B.Fab")
		)
		(pad "1" smd circle
			(at 0.40005 0 180)
			(size 0 0)
			(layers "B.Cu" "B.Mask" "B.Paste")
			(net "NIC4_SLOT_ID1")
		)
		(pad "2" smd circle
			(at -0.40005 0 180)
			(size 0 0)
			(layers "B.Cu" "B.Mask" "B.Paste")
			(net "P3V3_NIC4")
		)
	)
	(footprint ""
		(layer "B.Cu")
		(at 301.536354 -234.958636 -90)
		(property "Reference" "R1863"
			(at 0 0 90)
			(layer "B.SilkS")
			(hide yes)
			(effects
				(font
					(size 1.27 1.27)
				)
				(justify mirror)
			)
		)
		(property "Value" ""
			(at 0 0 90)
			(layer "B.Fab")
			(effects
				(font
					(size 1.27 1.27)
				)
				(justify mirror)
			)
		)
		(duplicate_pad_numbers_are_jumpers no)
		(fp_line
			(start -0.7874 0.4064)
			(end 0.7874 0.4064)
			(stroke
				(width 0.1524)
				(type default)
			)
			(layer "B.SilkS")
		)
		(fp_line
			(start 0.7874 0.4064)
			(end 0.7874 -0.4064)
			(stroke
				(width 0.1524)
				(type default)
			)
			(layer "B.SilkS")
		)
		(fp_line
			(start -0.7874 -0.4064)
			(end -0.7874 0.4064)
			(stroke
				(width 0.1524)
				(type default)
			)
			(layer "B.SilkS")
		)
		(fp_line
			(start 0.7874 -0.4064)
			(end -0.7874 -0.4064)
			(stroke
				(width 0.1524)
				(type default)
			)
			(layer "B.SilkS")
		)
		(fp_line
			(start -0.67945 0.3048)
			(end -0.120396 0.3048)
			(stroke
				(width 0.1)
				(type default)
			)
			(layer "B.Fab")
		)
		(fp_line
			(start -0.120396 0.3048)
			(end -0.120396 0.2794)
			(stroke
				(width 0.1)
				(type default)
			)
			(layer "B.Fab")
		)
		(fp_line
			(start 0.12065 0.3048)
			(end 0.67945 0.3048)
			(stroke
				(width 0.1)
				(type default)
			)
			(layer "B.Fab")
		)
		(fp_line
			(start 0.67945 0.3048)
			(end 0.67945 -0.305054)
			(stroke
				(width 0.1)
				(type default)
			)
			(layer "B.Fab")
		)
		(fp_line
			(start -0.120396 0.2794)
			(end 0.12065 0.2794)
			(stroke
				(width 0.1)
				(type default)
			)
			(layer "B.Fab")
		)
		(fp_line
			(start 0.12065 0.2794)
			(end 0.12065 0.3048)
			(stroke
				(width 0.1)
				(type default)
			)
			(layer "B.Fab")
		)
		(fp_line
			(start -0.12065 -0.2794)
			(end -0.12065 -0.3048)
			(stroke
				(width 0.1)
				(type default)
			)
			(layer "B.Fab")
		)
		(fp_line
			(start 0.12065 -0.2794)
			(end -0.12065 -0.2794)
			(stroke
				(width 0.1)
				(type default)
			)
			(layer "B.Fab")
		)
		(fp_line
			(start -0.67945 -0.3048)
			(end -0.67945 0.3048)
			(stroke
				(width 0.1)
				(type default)
			)
			(layer "B.Fab")
		)
		(fp_line
			(start -0.12065 -0.3048)
			(end -0.67945 -0.3048)
			(stroke
				(width 0.1)
				(type default)
			)
			(layer "B.Fab")
		)
		(fp_line
			(start 0.12065 -0.305054)
			(end 0.12065 -0.2794)
			(stroke
				(width 0.1)
				(type default)
			)
			(layer "B.Fab")
		)
		(fp_line
			(start 0.67945 -0.305054)
			(end 0.12065 -0.305054)
			(stroke
				(width 0.1)
				(type default)
			)
			(layer "B.Fab")
		)
		(pad "1" smd circle
			(at 0.40005 0 90)
			(size 0 0)
			(layers "B.Cu" "B.Mask" "B.Paste")
			(net "P3V3_AUX")
		)
		(pad "2" smd circle
			(at -0.40005 0 90)
			(size 0 0)
			(layers "B.Cu" "B.Mask" "B.Paste")
			(net "RST_GPU_PERST_2_BUF_N")
		)
	)
	(footprint ""
		(layer "B.Cu")
		(at 305.6001 -112.604296)
		(property "Reference" "C922"
			(at 0 0 0)
			(layer "B.SilkS")
			(hide yes)
			(effects
				(font
					(size 1.27 1.27)
				)
				(justify mirror)
			)
		)
		(property "Value" ""
			(at 0 0 0)
			(layer "B.Fab")
			(effects
				(font
					(size 1.27 1.27)
				)
				(justify mirror)
			)
		)
		(duplicate_pad_numbers_are_jumpers no)
		(fp_line
			(start -0.299974 -0.150114)
			(end -0.299974 0.150114)
			(stroke
				(width 0.1)
				(type default)
			)
			(layer "B.Fab")
		)
		(fp_line
			(start -0.299974 0.150114)
			(end 0.299974 0.150114)
			(stroke
				(width 0.1)
				(type default)
			)
			(layer "B.Fab")
		)
		(fp_line
			(start 0.299974 -0.150114)
			(end -0.299974 -0.150114)
			(stroke
				(width 0.1)
				(type default)
			)
			(layer "B.Fab")
		)
		(fp_line
			(start 0.299974 0.150114)
			(end 0.299974 -0.150114)
			(stroke
				(width 0.1)
				(type default)
			)
			(layer "B.Fab")
		)
		(pad "1" smd rect
			(at 0.2667 0 180)
			(size 0.3048 0.381)
			(layers "B.Cu" "B.Mask" "B.Paste")
			(net "P12V_NIC5")
		)
		(pad "2" smd rect
			(at -0.2667 0 180)
			(size 0.3048 0.381)
			(layers "B.Cu" "B.Mask" "B.Paste")
			(net "GND")
		)
	)
	(footprint ""
		(layer "B.Cu")
		(at 138.947906 -173.846744 -90)
		(property "Reference" "L12"
			(at 0 0 90)
			(layer "B.SilkS")
			(hide yes)
			(effects
				(font
					(size 1.27 1.27)
				)
				(justify mirror)
			)
		)
		(property "Value" ""
			(at 0 0 90)
			(layer "B.Fab")
			(effects
				(font
					(size 1.27 1.27)
				)
				(justify mirror)
			)
		)
		(duplicate_pad_numbers_are_jumpers no)
		(fp_line
			(start -1.27 0.5842)
			(end 1.27 0.5842)
			(stroke
				(width 0.1524)
				(type default)
			)
			(layer "B.SilkS")
		)
		(fp_line
			(start -1.27 0.5842)
			(end -1.27 -0.5842)
			(stroke
				(width 0.1524)
				(type default)
			)
			(layer "B.SilkS")
		)
		(fp_line
			(start 1.27 0.5842)
			(end 1.27 -0.5842)
			(stroke
				(width 0.1524)
				(type default)
			)
			(layer "B.SilkS")
		)
		(fp_line
			(start 1.27 -0.5588)
			(end 1.27 -0.5842)
			(stroke
				(width 0.1524)
				(type default)
			)
			(layer "B.SilkS")
		)
		(fp_line
			(start 1.27 -0.5842)
			(end -1.27 -0.5842)
			(stroke
				(width 0.1524)
				(type default)
			)
			(layer "B.SilkS")
		)
		(fp_line
			(start -0.9144 0.508)
			(end 0.9144 0.508)
			(stroke
				(width 0.1)
				(type default)
			)
			(layer "B.Fab")
		)
		(fp_line
			(start 0.9144 0.508)
			(end 0.9144 0.406654)
			(stroke
				(width 0.1)
				(type default)
			)
			(layer "B.Fab")
		)
		(fp_line
			(start 0.9144 0.406654)
			(end 1.194308 0.406654)
			(stroke
				(width 0.1)
				(type default)
			)
			(layer "B.Fab")
		)
		(fp_line
			(start 1.194308 0.406654)
			(end 1.194308 -0.406654)
			(stroke
				(width 0.1)
				(type default)
			)
			(layer "B.Fab")
		)
		(fp_line
			(start -1.1938 0.4064)
			(end -0.9144 0.4064)
			(stroke
				(width 0.1)
				(type default)
			)
			(layer "B.Fab")
		)
		(fp_line
			(start -0.9144 0.4064)
			(end -0.9144 0.508)
			(stroke
				(width 0.1)
				(type default)
			)
			(layer "B.Fab")
		)
		(fp_line
			(start -1.1938 -0.406654)
			(end -1.1938 0.4064)
			(stroke
				(width 0.1)
				(type default)
			)
			(layer "B.Fab")
		)
		(fp_line
			(start -0.9144 -0.406654)
			(end -1.1938 -0.406654)
			(stroke
				(width 0.1)
				(type default)
			)
			(layer "B.Fab")
		)
		(fp_line
			(start 0.9144 -0.406654)
			(end 0.9144 -0.508)
			(stroke
				(width 0.1)
				(type default)
			)
			(layer "B.Fab")
		)
		(fp_line
			(start 1.194308 -0.406654)
			(end 0.9144 -0.406654)
			(stroke
				(width 0.1)
				(type default)
			)
			(layer "B.Fab")
		)
		(fp_line
			(start -0.9144 -0.508)
			(end -0.9144 -0.406654)
			(stroke
				(width 0.1)
				(type default)
			)
			(layer "B.Fab")
		)
		(fp_line
			(start 0.9144 -0.508)
			(end -0.9144 -0.508)
			(stroke
				(width 0.1)
				(type default)
			)
			(layer "B.Fab")
		)
		(pad "1" smd rect
			(at 0.7366 0 180)
			(size 0.7112 0.8128)
			(layers "B.Cu" "B.Mask" "B.Paste")
			(net "P3V3")
		)
		(pad "2" smd rect
			(at -0.7366 0 180)
			(size 0.7112 0.8128)
			(layers "B.Cu" "B.Mask" "B.Paste")
			(net "P3V3_DB2000QL_VDD")
		)
	)
	(footprint ""
		(layer "B.Cu")
		(at 118.456964 -316.868048)
		(property "Reference" "C4252"
			(at 0 0 0)
			(layer "B.SilkS")
			(hide yes)
			(effects
				(font
					(size 1.27 1.27)
				)
				(justify mirror)
			)
		)
		(property "Value" ""
			(at 0 0 0)
			(layer "B.Fab")
			(effects
				(font
					(size 1.27 1.27)
				)
				(justify mirror)
			)
		)
		(duplicate_pad_numbers_are_jumpers no)
		(fp_line
			(start -0.299974 -0.150114)
			(end -0.299974 0.150114)
			(stroke
				(width 0.1)
				(type default)
			)
			(layer "B.Fab")
		)
		(fp_line
			(start -0.299974 0.150114)
			(end 0.299974 0.150114)
			(stroke
				(width 0.1)
				(type default)
			)
			(layer "B.Fab")
		)
		(fp_line
			(start 0.299974 -0.150114)
			(end -0.299974 -0.150114)
			(stroke
				(width 0.1)
				(type default)
			)
			(layer "B.Fab")
		)
		(fp_line
			(start 0.299974 0.150114)
			(end 0.299974 -0.150114)
			(stroke
				(width 0.1)
				(type default)
			)
			(layer "B.Fab")
		)
		(pad "1" smd rect
			(at 0.2667 0 180)
			(size 0.3048 0.381)
			(layers "B.Cu" "B.Mask" "B.Paste")
			(net "P0V8_SERDES_VDDA_PEX1")
		)
		(pad "2" smd rect
			(at -0.2667 0 180)
			(size 0.3048 0.381)
			(layers "B.Cu" "B.Mask" "B.Paste")
			(net "GND")
		)
	)
	(footprint ""
		(layer "B.Cu")
		(at 305.109626 -239.976406 90)
		(property "Reference" "R4107"
			(at 0 0 90)
			(layer "B.SilkS")
			(hide yes)
			(effects
				(font
					(size 1.27 1.27)
				)
				(justify mirror)
			)
		)
		(property "Value" ""
			(at 0 0 90)
			(layer "B.Fab")
			(effects
				(font
					(size 1.27 1.27)
				)
				(justify mirror)
			)
		)
		(duplicate_pad_numbers_are_jumpers no)
		(fp_line
			(start 0.7874 -0.4064)
			(end -0.7874 -0.4064)
			(stroke
				(width 0.1524)
				(type default)
			)
			(layer "B.SilkS")
		)
		(fp_line
			(start -0.7874 -0.4064)
			(end -0.7874 0.4064)
			(stroke
				(width 0.1524)
				(type default)
			)
			(layer "B.SilkS")
		)
		(fp_line
			(start 0.7874 0.4064)
			(end 0.7874 -0.4064)
			(stroke
				(width 0.1524)
				(type default)
			)
			(layer "B.SilkS")
		)
		(fp_line
			(start -0.7874 0.4064)
			(end 0.7874 0.4064)
			(stroke
				(width 0.1524)
				(type default)
			)
			(layer "B.SilkS")
		)
		(fp_line
			(start 0.67945 -0.305054)
			(end 0.12065 -0.305054)
			(stroke
				(width 0.1)
				(type default)
			)
			(layer "B.Fab")
		)
		(fp_line
			(start 0.12065 -0.305054)
			(end 0.12065 -0.2794)
			(stroke
				(width 0.1)
				(type default)
			)
			(layer "B.Fab")
		)
		(fp_line
			(start -0.12065 -0.3048)
			(end -0.67945 -0.3048)
			(stroke
				(width 0.1)
				(type default)
			)
			(layer "B.Fab")
		)
		(fp_line
			(start -0.67945 -0.3048)
			(end -0.67945 0.3048)
			(stroke
				(width 0.1)
				(type default)
			)
			(layer "B.Fab")
		)
		(fp_line
			(start 0.12065 -0.2794)
			(end -0.12065 -0.2794)
			(stroke
				(width 0.1)
				(type default)
			)
			(layer "B.Fab")
		)
		(fp_line
			(start -0.12065 -0.2794)
			(end -0.12065 -0.3048)
			(stroke
				(width 0.1)
				(type default)
			)
			(layer "B.Fab")
		)
		(fp_line
			(start 0.12065 0.2794)
			(end 0.12065 0.3048)
			(stroke
				(width 0.1)
				(type default)
			)
			(layer "B.Fab")
		)
		(fp_line
			(start -0.120396 0.2794)
			(end 0.12065 0.2794)
			(stroke
				(width 0.1)
				(type default)
			)
			(layer "B.Fab")
		)
		(fp_line
			(start 0.67945 0.3048)
			(end 0.67945 -0.305054)
			(stroke
				(width 0.1)
				(type default)
			)
			(layer "B.Fab")
		)
		(fp_line
			(start 0.12065 0.3048)
			(end 0.67945 0.3048)
			(stroke
				(width 0.1)
				(type default)
			)
			(layer "B.Fab")
		)
		(fp_line
			(start -0.120396 0.3048)
			(end -0.120396 0.2794)
			(stroke
				(width 0.1)
				(type default)
			)
			(layer "B.Fab")
		)
		(fp_line
			(start -0.67945 0.3048)
			(end -0.120396 0.3048)
			(stroke
				(width 0.1)
				(type default)
			)
			(layer "B.Fab")
		)
		(pad "1" smd circle
			(at 0.40005 0 270)
			(size 0 0)
			(layers "B.Cu" "B.Mask" "B.Paste")
			(net "SMB_MB_BMC_ISO_SCL")
		)
		(pad "2" smd circle
			(at -0.40005 0 270)
			(size 0 0)
			(layers "B.Cu" "B.Mask" "B.Paste")
			(net "SMB_MB_R_SCL")
		)
	)
	(footprint ""
		(layer "B.Cu")
		(at 169.730166 -295.221914)
		(property "Reference" "C1356"
			(at 0 0 0)
			(layer "B.SilkS")
			(hide yes)
			(effects
				(font
					(size 1.27 1.27)
				)
				(justify mirror)
			)
		)
		(property "Value" ""
			(at 0 0 0)
			(layer "B.Fab")
			(effects
				(font
					(size 1.27 1.27)
				)
				(justify mirror)
			)
		)
		(duplicate_pad_numbers_are_jumpers no)
		(fp_line
			(start -1.2954 -0.5842)
			(end -1.2954 0.5842)
			(stroke
				(width 0.1524)
				(type default)
			)
			(layer "B.SilkS")
		)
		(fp_line
			(start -1.2954 0.5842)
			(end 1.2954 0.5842)
			(stroke
				(width 0.1524)
				(type default)
			)
			(layer "B.SilkS")
		)
		(fp_line
			(start 1.2954 -0.5842)
			(end -1.2954 -0.5842)
			(stroke
				(width 0.1524)
				(type default)
			)
			(layer "B.SilkS")
		)
		(fp_line
			(start 1.2954 0.5842)
			(end 1.2954 -0.5842)
			(stroke
				(width 0.1524)
				(type default)
			)
			(layer "B.SilkS")
		)
		(fp_line
			(start -1.1938 -0.4064)
			(end -1.1938 0.4064)
			(stroke
				(width 0.1)
				(type default)
			)
			(layer "B.Fab")
		)
		(fp_line
			(start -1.1938 0.4064)
			(end -0.8636 0.4064)
			(stroke
				(width 0.1)
				(type default)
			)
			(layer "B.Fab")
		)
		(fp_line
			(start -0.8636 -0.4572)
			(end -0.8636 -0.4064)
			(stroke
				(width 0.1)
				(type default)
			)
			(layer "B.Fab")
		)
		(fp_line
			(start -0.8636 -0.4064)
			(end -1.1938 -0.4064)
			(stroke
				(width 0.1)
				(type default)
			)
			(layer "B.Fab")
		)
		(fp_line
			(start -0.8636 0.4064)
			(end -0.8636 0.4572)
			(stroke
				(width 0.1)
				(type default)
			)
			(layer "B.Fab")
		)
		(fp_line
			(start -0.8636 0.4572)
			(end 0.8636 0.4572)
			(stroke
				(width 0.1)
				(type default)
			)
			(layer "B.Fab")
		)
		(fp_line
			(start 0.8636 -0.4572)
			(end -0.8636 -0.4572)
			(stroke
				(width 0.1)
				(type default)
			)
			(layer "B.Fab")
		)
		(fp_line
			(start 0.8636 -0.4064)
			(end 0.8636 -0.4572)
			(stroke
				(width 0.1)
				(type default)
			)
			(layer "B.Fab")
		)
		(fp_line
			(start 0.8636 0.4064)
			(end 1.1938 0.4064)
			(stroke
				(width 0.1)
				(type default)
			)
			(layer "B.Fab")
		)
		(fp_line
			(start 0.8636 0.4572)
			(end 0.8636 0.4064)
			(stroke
				(width 0.1)
				(type default)
			)
			(layer "B.Fab")
		)
		(fp_line
			(start 1.1938 -0.4064)
			(end 0.8636 -0.4064)
			(stroke
				(width 0.1)
				(type default)
			)
			(layer "B.Fab")
		)
		(fp_line
			(start 1.1938 0.4064)
			(end 1.1938 -0.4064)
			(stroke
				(width 0.1)
				(type default)
			)
			(layer "B.Fab")
		)
		(pad "1" smd rect
			(at 0.7366 0 270)
			(size 0.7112 0.8128)
			(layers "B.Cu" "B.Mask" "B.Paste")
			(net "P0V8_PEX1")
		)
		(pad "2" smd rect
			(at -0.7366 0 270)
			(size 0.7112 0.8128)
			(layers "B.Cu" "B.Mask" "B.Paste")
			(net "GND")
		)
	)
	(footprint ""
		(layer "B.Cu")
		(at 411.275022 -286.399732 90)
		(property "Reference" "C3503"
			(at 0 0 90)
			(layer "B.SilkS")
			(hide yes)
			(effects
				(font
					(size 1.27 1.27)
				)
				(justify mirror)
			)
		)
		(property "Value" ""
			(at 0 0 90)
			(layer "B.Fab")
			(effects
				(font
					(size 1.27 1.27)
				)
				(justify mirror)
			)
		)
		(duplicate_pad_numbers_are_jumpers no)
		(fp_line
			(start 0.299974 -0.150114)
			(end -0.299974 -0.150114)
			(stroke
				(width 0.1)
				(type default)
			)
			(layer "B.Fab")
		)
		(fp_line
			(start -0.299974 -0.150114)
			(end -0.299974 0.150114)
			(stroke
				(width 0.1)
				(type default)
			)
			(layer "B.Fab")
		)
		(fp_line
			(start 0.299974 0.150114)
			(end 0.299974 -0.150114)
			(stroke
				(width 0.1)
				(type default)
			)
			(layer "B.Fab")
		)
		(fp_line
			(start -0.299974 0.150114)
			(end 0.299974 0.150114)
			(stroke
				(width 0.1)
				(type default)
			)
			(layer "B.Fab")
		)
		(pad "1" smd rect
			(at 0.2667 0 270)
			(size 0.3048 0.381)
			(layers "B.Cu" "B.Mask" "B.Paste")
			(net "P1V25_SERDES_VDDPLL_PEX3")
		)
		(pad "2" smd rect
			(at -0.2667 0 270)
			(size 0.3048 0.381)
			(layers "B.Cu" "B.Mask" "B.Paste")
			(net "GND")
		)
	)
	(footprint ""
		(layer "B.Cu")
		(at 417.241482 -286.874966)
		(property "Reference" "C3520"
			(at 0 0 0)
			(layer "B.SilkS")
			(hide yes)
			(effects
				(font
					(size 1.27 1.27)
				)
				(justify mirror)
			)
		)
		(property "Value" ""
			(at 0 0 0)
			(layer "B.Fab")
			(effects
				(font
					(size 1.27 1.27)
				)
				(justify mirror)
			)
		)
		(duplicate_pad_numbers_are_jumpers no)
		(fp_line
			(start -0.299974 -0.150114)
			(end -0.299974 0.150114)
			(stroke
				(width 0.1)
				(type default)
			)
			(layer "B.Fab")
		)
		(fp_line
			(start -0.299974 0.150114)
			(end 0.299974 0.150114)
			(stroke
				(width 0.1)
				(type default)
			)
			(layer "B.Fab")
		)
		(fp_line
			(start 0.299974 -0.150114)
			(end -0.299974 -0.150114)
			(stroke
				(width 0.1)
				(type default)
			)
			(layer "B.Fab")
		)
		(fp_line
			(start 0.299974 0.150114)
			(end 0.299974 -0.150114)
			(stroke
				(width 0.1)
				(type default)
			)
			(layer "B.Fab")
		)
		(pad "1" smd rect
			(at 0.2667 0 180)
			(size 0.3048 0.381)
			(layers "B.Cu" "B.Mask" "B.Paste")
			(net "P1V8_VDDA_PEX3")
		)
		(pad "2" smd rect
			(at -0.2667 0 180)
			(size 0.3048 0.381)
			(layers "B.Cu" "B.Mask" "B.Paste")
			(net "GND")
		)
	)
	(footprint ""
		(layer "B.Cu")
		(at 324.540118 -229.913942)
		(property "Reference" "R5892"
			(at 0 0 0)
			(layer "B.SilkS")
			(hide yes)
			(effects
				(font
					(size 1.27 1.27)
				)
				(justify mirror)
			)
		)
		(property "Value" ""
			(at 0 0 0)
			(layer "B.Fab")
			(effects
				(font
					(size 1.27 1.27)
				)
				(justify mirror)
			)
		)
		(duplicate_pad_numbers_are_jumpers no)
		(fp_line
			(start -0.7874 -0.4064)
			(end -0.7874 0.4064)
			(stroke
				(width 0.1524)
				(type default)
			)
			(layer "B.SilkS")
		)
		(fp_line
			(start -0.7874 0.4064)
			(end 0.7874 0.4064)
			(stroke
				(width 0.1524)
				(type default)
			)
			(layer "B.SilkS")
		)
		(fp_line
			(start 0.7874 -0.4064)
			(end -0.7874 -0.4064)
			(stroke
				(width 0.1524)
				(type default)
			)
			(layer "B.SilkS")
		)
		(fp_line
			(start 0.7874 0.4064)
			(end 0.7874 -0.4064)
			(stroke
				(width 0.1524)
				(type default)
			)
			(layer "B.SilkS")
		)
		(fp_line
			(start -0.67945 -0.3048)
			(end -0.67945 0.3048)
			(stroke
				(width 0.1)
				(type default)
			)
			(layer "B.Fab")
		)
		(fp_line
			(start -0.67945 0.3048)
			(end -0.120396 0.3048)
			(stroke
				(width 0.1)
				(type default)
			)
			(layer "B.Fab")
		)
		(fp_line
			(start -0.12065 -0.3048)
			(end -0.67945 -0.3048)
			(stroke
				(width 0.1)
				(type default)
			)
			(layer "B.Fab")
		)
		(fp_line
			(start -0.12065 -0.2794)
			(end -0.12065 -0.3048)
			(stroke
				(width 0.1)
				(type default)
			)
			(layer "B.Fab")
		)
		(fp_line
			(start -0.120396 0.2794)
			(end 0.12065 0.2794)
			(stroke
				(width 0.1)
				(type default)
			)
			(layer "B.Fab")
		)
		(fp_line
			(start -0.120396 0.3048)
			(end -0.120396 0.2794)
			(stroke
				(width 0.1)
				(type default)
			)
			(layer "B.Fab")
		)
		(fp_line
			(start 0.12065 -0.305054)
			(end 0.12065 -0.2794)
			(stroke
				(width 0.1)
				(type default)
			)
			(layer "B.Fab")
		)
		(fp_line
			(start 0.12065 -0.2794)
			(end -0.12065 -0.2794)
			(stroke
				(width 0.1)
				(type default)
			)
			(layer "B.Fab")
		)
		(fp_line
			(start 0.12065 0.2794)
			(end 0.12065 0.3048)
			(stroke
				(width 0.1)
				(type default)
			)
			(layer "B.Fab")
		)
		(fp_line
			(start 0.12065 0.3048)
			(end 0.67945 0.3048)
			(stroke
				(width 0.1)
				(type default)
			)
			(layer "B.Fab")
		)
		(fp_line
			(start 0.67945 -0.305054)
			(end 0.12065 -0.305054)
			(stroke
				(width 0.1)
				(type default)
			)
			(layer "B.Fab")
		)
		(fp_line
			(start 0.67945 0.3048)
			(end 0.67945 -0.305054)
			(stroke
				(width 0.1)
				(type default)
			)
			(layer "B.Fab")
		)
		(pad "1" smd circle
			(at 0.40005 0 180)
			(size 0 0)
			(layers "B.Cu" "B.Mask" "B.Paste")
			(net "P3V3_LED")
		)
		(pad "2" smd circle
			(at -0.40005 0 180)
			(size 0 0)
			(layers "B.Cu" "B.Mask" "B.Paste")
			(net "FPGA_DEBUG_LED")
		)
	)
	(footprint ""
		(layer "B.Cu")
		(at 260.58368 -80.982312 -90)
		(property "Reference" "C2632"
			(at 0 0 90)
			(layer "B.SilkS")
			(hide yes)
			(effects
				(font
					(size 1.27 1.27)
				)
				(justify mirror)
			)
		)
		(property "Value" ""
			(at 0 0 90)
			(layer "B.Fab")
			(effects
				(font
					(size 1.27 1.27)
				)
				(justify mirror)
			)
		)
		(duplicate_pad_numbers_are_jumpers no)
		(fp_line
			(start -0.7874 0.4064)
			(end 0.7874 0.4064)
			(stroke
				(width 0.1524)
				(type default)
			)
			(layer "B.SilkS")
		)
		(fp_line
			(start 0.7874 0.4064)
			(end 0.7874 -0.4064)
			(stroke
				(width 0.1524)
				(type default)
			)
			(layer "B.SilkS")
		)
		(fp_line
			(start -0.7874 -0.4064)
			(end -0.7874 0.4064)
			(stroke
				(width 0.1524)
				(type default)
			)
			(layer "B.SilkS")
		)
		(fp_line
			(start 0.7874 -0.4064)
			(end -0.7874 -0.4064)
			(stroke
				(width 0.1524)
				(type default)
			)
			(layer "B.SilkS")
		)
		(fp_line
			(start -0.67945 0.3048)
			(end -0.120396 0.3048)
			(stroke
				(width 0.1)
				(type default)
			)
			(layer "B.Fab")
		)
		(fp_line
			(start -0.120396 0.3048)
			(end -0.120396 0.2794)
			(stroke
				(width 0.1)
				(type default)
			)
			(layer "B.Fab")
		)
		(fp_line
			(start 0.12065 0.3048)
			(end 0.67945 0.3048)
			(stroke
				(width 0.1)
				(type default)
			)
			(layer "B.Fab")
		)
		(fp_line
			(start 0.67945 0.3048)
			(end 0.67945 -0.305054)
			(stroke
				(width 0.1)
				(type default)
			)
			(layer "B.Fab")
		)
		(fp_line
			(start -0.120396 0.2794)
			(end 0.12065 0.2794)
			(stroke
				(width 0.1)
				(type default)
			)
			(layer "B.Fab")
		)
		(fp_line
			(start 0.12065 0.2794)
			(end 0.12065 0.3048)
			(stroke
				(width 0.1)
				(type default)
			)
			(layer "B.Fab")
		)
		(fp_line
			(start -0.12065 -0.2794)
			(end -0.12065 -0.3048)
			(stroke
				(width 0.1)
				(type default)
			)
			(layer "B.Fab")
		)
		(fp_line
			(start 0.12065 -0.2794)
			(end -0.12065 -0.2794)
			(stroke
				(width 0.1)
				(type default)
			)
			(layer "B.Fab")
		)
		(fp_line
			(start -0.67945 -0.3048)
			(end -0.67945 0.3048)
			(stroke
				(width 0.1)
				(type default)
			)
			(layer "B.Fab")
		)
		(fp_line
			(start -0.12065 -0.3048)
			(end -0.67945 -0.3048)
			(stroke
				(width 0.1)
				(type default)
			)
			(layer "B.Fab")
		)
		(fp_line
			(start 0.12065 -0.305054)
			(end 0.12065 -0.2794)
			(stroke
				(width 0.1)
				(type default)
			)
			(layer "B.Fab")
		)
		(fp_line
			(start 0.67945 -0.305054)
			(end 0.12065 -0.305054)
			(stroke
				(width 0.1)
				(type default)
			)
			(layer "B.Fab")
		)
		(pad "1" smd circle
			(at 0.40005 0 90)
			(size 0 0)
			(layers "B.Cu" "B.Mask" "B.Paste")
			(net "P3V3_CLK_GEN_VDD_CK440")
		)
		(pad "2" smd circle
			(at -0.40005 0 90)
			(size 0 0)
			(layers "B.Cu" "B.Mask" "B.Paste")
			(net "GND")
		)
	)
	(footprint ""
		(layer "B.Cu")
		(at 169.099992 -288.299906 90)
		(property "Reference" "C3115"
			(at 0 0 90)
			(layer "B.SilkS")
			(hide yes)
			(effects
				(font
					(size 1.27 1.27)
				)
				(justify mirror)
			)
		)
		(property "Value" ""
			(at 0 0 90)
			(layer "B.Fab")
			(effects
				(font
					(size 1.27 1.27)
				)
				(justify mirror)
			)
		)
		(duplicate_pad_numbers_are_jumpers no)
		(fp_line
			(start 0.299974 -0.150114)
			(end -0.299974 -0.150114)
			(stroke
				(width 0.1)
				(type default)
			)
			(layer "B.Fab")
		)
		(fp_line
			(start -0.299974 -0.150114)
			(end -0.299974 0.150114)
			(stroke
				(width 0.1)
				(type default)
			)
			(layer "B.Fab")
		)
		(fp_line
			(start 0.299974 0.150114)
			(end 0.299974 -0.150114)
			(stroke
				(width 0.1)
				(type default)
			)
			(layer "B.Fab")
		)
		(fp_line
			(start -0.299974 0.150114)
			(end 0.299974 0.150114)
			(stroke
				(width 0.1)
				(type default)
			)
			(layer "B.Fab")
		)
		(pad "1" smd rect
			(at 0.2667 0 270)
			(size 0.3048 0.381)
			(layers "B.Cu" "B.Mask" "B.Paste")
			(net "P1V25_PEX1")
		)
		(pad "2" smd rect
			(at -0.2667 0 270)
			(size 0.3048 0.381)
			(layers "B.Cu" "B.Mask" "B.Paste")
			(net "GND")
		)
	)
	(footprint ""
		(layer "B.Cu")
		(at 413.174942 -297.79976 -90)
		(property "Reference" "C1912"
			(at 0 0 90)
			(layer "B.SilkS")
			(hide yes)
			(effects
				(font
					(size 1.27 1.27)
				)
				(justify mirror)
			)
		)
		(property "Value" ""
			(at 0 0 90)
			(layer "B.Fab")
			(effects
				(font
					(size 1.27 1.27)
				)
				(justify mirror)
			)
		)
		(duplicate_pad_numbers_are_jumpers no)
		(fp_line
			(start -0.299974 0.150114)
			(end 0.299974 0.150114)
			(stroke
				(width 0.1)
				(type default)
			)
			(layer "B.Fab")
		)
		(fp_line
			(start 0.299974 0.150114)
			(end 0.299974 -0.150114)
			(stroke
				(width 0.1)
				(type default)
			)
			(layer "B.Fab")
		)
		(fp_line
			(start -0.299974 -0.150114)
			(end -0.299974 0.150114)
			(stroke
				(width 0.1)
				(type default)
			)
			(layer "B.Fab")
		)
		(fp_line
			(start 0.299974 -0.150114)
			(end -0.299974 -0.150114)
			(stroke
				(width 0.1)
				(type default)
			)
			(layer "B.Fab")
		)
		(pad "1" smd rect
			(at 0.2667 0 90)
			(size 0.3048 0.381)
			(layers "B.Cu" "B.Mask" "B.Paste")
			(net "P0V8_PEX3")
		)
		(pad "2" smd rect
			(at -0.2667 0 90)
			(size 0.3048 0.381)
			(layers "B.Cu" "B.Mask" "B.Paste")
			(net "GND")
		)
	)
	(footprint ""
		(layer "B.Cu")
		(at 347.091 -233.553 90)
		(property "Reference" "R3580"
			(at 0 0 90)
			(layer "B.SilkS")
			(hide yes)
			(effects
				(font
					(size 1.27 1.27)
				)
				(justify mirror)
			)
		)
		(property "Value" ""
			(at 0 0 90)
			(layer "B.Fab")
			(effects
				(font
					(size 1.27 1.27)
				)
				(justify mirror)
			)
		)
		(duplicate_pad_numbers_are_jumpers no)
		(fp_line
			(start 0.7874 -0.4064)
			(end -0.7874 -0.4064)
			(stroke
				(width 0.1524)
				(type default)
			)
			(layer "B.SilkS")
		)
		(fp_line
			(start -0.7874 -0.4064)
			(end -0.7874 0.4064)
			(stroke
				(width 0.1524)
				(type default)
			)
			(layer "B.SilkS")
		)
		(fp_line
			(start 0.7874 0.4064)
			(end 0.7874 -0.4064)
			(stroke
				(width 0.1524)
				(type default)
			)
			(layer "B.SilkS")
		)
		(fp_line
			(start -0.7874 0.4064)
			(end 0.7874 0.4064)
			(stroke
				(width 0.1524)
				(type default)
			)
			(layer "B.SilkS")
		)
		(fp_line
			(start 0.67945 -0.305054)
			(end 0.12065 -0.305054)
			(stroke
				(width 0.1)
				(type default)
			)
			(layer "B.Fab")
		)
		(fp_line
			(start 0.12065 -0.305054)
			(end 0.12065 -0.2794)
			(stroke
				(width 0.1)
				(type default)
			)
			(layer "B.Fab")
		)
		(fp_line
			(start -0.12065 -0.3048)
			(end -0.67945 -0.3048)
			(stroke
				(width 0.1)
				(type default)
			)
			(layer "B.Fab")
		)
		(fp_line
			(start -0.67945 -0.3048)
			(end -0.67945 0.3048)
			(stroke
				(width 0.1)
				(type default)
			)
			(layer "B.Fab")
		)
		(fp_line
			(start 0.12065 -0.2794)
			(end -0.12065 -0.2794)
			(stroke
				(width 0.1)
				(type default)
			)
			(layer "B.Fab")
		)
		(fp_line
			(start -0.12065 -0.2794)
			(end -0.12065 -0.3048)
			(stroke
				(width 0.1)
				(type default)
			)
			(layer "B.Fab")
		)
		(fp_line
			(start 0.12065 0.2794)
			(end 0.12065 0.3048)
			(stroke
				(width 0.1)
				(type default)
			)
			(layer "B.Fab")
		)
		(fp_line
			(start -0.120396 0.2794)
			(end 0.12065 0.2794)
			(stroke
				(width 0.1)
				(type default)
			)
			(layer "B.Fab")
		)
		(fp_line
			(start 0.67945 0.3048)
			(end 0.67945 -0.305054)
			(stroke
				(width 0.1)
				(type default)
			)
			(layer "B.Fab")
		)
		(fp_line
			(start 0.12065 0.3048)
			(end 0.67945 0.3048)
			(stroke
				(width 0.1)
				(type default)
			)
			(layer "B.Fab")
		)
		(fp_line
			(start -0.120396 0.3048)
			(end -0.120396 0.2794)
			(stroke
				(width 0.1)
				(type default)
			)
			(layer "B.Fab")
		)
		(fp_line
			(start -0.67945 0.3048)
			(end -0.120396 0.3048)
			(stroke
				(width 0.1)
				(type default)
			)
			(layer "B.Fab")
		)
		(pad "1" smd circle
			(at 0.40005 0 270)
			(size 0 0)
			(layers "B.Cu" "B.Mask" "B.Paste")
			(net "RST_SSD6_PERST_R_N")
		)
		(pad "2" smd circle
			(at -0.40005 0 270)
			(size 0 0)
			(layers "B.Cu" "B.Mask" "B.Paste")
			(net "RST_SSD6_PERST_N")
		)
	)
	(footprint ""
		(layer "B.Cu")
		(at 46.736 -298.27474)
		(property "Reference" "C3069"
			(at 0 0 0)
			(layer "B.SilkS")
			(hide yes)
			(effects
				(font
					(size 1.27 1.27)
				)
				(justify mirror)
			)
		)
		(property "Value" ""
			(at 0 0 0)
			(layer "B.Fab")
			(effects
				(font
					(size 1.27 1.27)
				)
				(justify mirror)
			)
		)
		(duplicate_pad_numbers_are_jumpers no)
		(fp_line
			(start -0.299974 -0.150114)
			(end -0.299974 0.150114)
			(stroke
				(width 0.1)
				(type default)
			)
			(layer "B.Fab")
		)
		(fp_line
			(start -0.299974 0.150114)
			(end 0.299974 0.150114)
			(stroke
				(width 0.1)
				(type default)
			)
			(layer "B.Fab")
		)
		(fp_line
			(start 0.299974 -0.150114)
			(end -0.299974 -0.150114)
			(stroke
				(width 0.1)
				(type default)
			)
			(layer "B.Fab")
		)
		(fp_line
			(start 0.299974 0.150114)
			(end 0.299974 -0.150114)
			(stroke
				(width 0.1)
				(type default)
			)
			(layer "B.Fab")
		)
		(pad "1" smd rect
			(at 0.2667 0 180)
			(size 0.3048 0.381)
			(layers "B.Cu" "B.Mask" "B.Paste")
			(net "SYSPLL_VDDA18_PEX0")
		)
		(pad "2" smd rect
			(at -0.2667 0 180)
			(size 0.3048 0.381)
			(layers "B.Cu" "B.Mask" "B.Paste")
			(net "GND")
		)
	)
	(footprint ""
		(layer "B.Cu")
		(at 50.165 -301.599854 -90)
		(property "Reference" "C1179"
			(at 0 0 90)
			(layer "B.SilkS")
			(hide yes)
			(effects
				(font
					(size 1.27 1.27)
				)
				(justify mirror)
			)
		)
		(property "Value" ""
			(at 0 0 90)
			(layer "B.Fab")
			(effects
				(font
					(size 1.27 1.27)
				)
				(justify mirror)
			)
		)
		(duplicate_pad_numbers_are_jumpers no)
		(fp_line
			(start -0.299974 0.150114)
			(end 0.299974 0.150114)
			(stroke
				(width 0.1)
				(type default)
			)
			(layer "B.Fab")
		)
		(fp_line
			(start 0.299974 0.150114)
			(end 0.299974 -0.150114)
			(stroke
				(width 0.1)
				(type default)
			)
			(layer "B.Fab")
		)
		(fp_line
			(start -0.299974 -0.150114)
			(end -0.299974 0.150114)
			(stroke
				(width 0.1)
				(type default)
			)
			(layer "B.Fab")
		)
		(fp_line
			(start 0.299974 -0.150114)
			(end -0.299974 -0.150114)
			(stroke
				(width 0.1)
				(type default)
			)
			(layer "B.Fab")
		)
		(pad "1" smd rect
			(at 0.2667 0 90)
			(size 0.3048 0.381)
			(layers "B.Cu" "B.Mask" "B.Paste")
			(net "P0V8_SERDES_VDDA_PEX0")
		)
		(pad "2" smd rect
			(at -0.2667 0 90)
			(size 0.3048 0.381)
			(layers "B.Cu" "B.Mask" "B.Paste")
			(net "GND")
		)
	)
	(footprint ""
		(layer "B.Cu")
		(at 250.272296 -345.517724 -90)
		(property "Reference" "R6823"
			(at 0 0 90)
			(layer "B.SilkS")
			(hide yes)
			(effects
				(font
					(size 1.27 1.27)
				)
				(justify mirror)
			)
		)
		(property "Value" ""
			(at 0 0 90)
			(layer "B.Fab")
			(effects
				(font
					(size 1.27 1.27)
				)
				(justify mirror)
			)
		)
		(duplicate_pad_numbers_are_jumpers no)
		(fp_line
			(start -0.7874 0.4064)
			(end 0.7874 0.4064)
			(stroke
				(width 0.1524)
				(type default)
			)
			(layer "B.SilkS")
		)
		(fp_line
			(start 0.7874 0.4064)
			(end 0.7874 -0.4064)
			(stroke
				(width 0.1524)
				(type default)
			)
			(layer "B.SilkS")
		)
		(fp_line
			(start -0.7874 -0.4064)
			(end -0.7874 0.4064)
			(stroke
				(width 0.1524)
				(type default)
			)
			(layer "B.SilkS")
		)
		(fp_line
			(start 0.7874 -0.4064)
			(end -0.7874 -0.4064)
			(stroke
				(width 0.1524)
				(type default)
			)
			(layer "B.SilkS")
		)
		(fp_line
			(start -0.67945 0.3048)
			(end -0.120396 0.3048)
			(stroke
				(width 0.1)
				(type default)
			)
			(layer "B.Fab")
		)
		(fp_line
			(start -0.120396 0.3048)
			(end -0.120396 0.2794)
			(stroke
				(width 0.1)
				(type default)
			)
			(layer "B.Fab")
		)
		(fp_line
			(start 0.12065 0.3048)
			(end 0.67945 0.3048)
			(stroke
				(width 0.1)
				(type default)
			)
			(layer "B.Fab")
		)
		(fp_line
			(start 0.67945 0.3048)
			(end 0.67945 -0.305054)
			(stroke
				(width 0.1)
				(type default)
			)
			(layer "B.Fab")
		)
		(fp_line
			(start -0.120396 0.2794)
			(end 0.12065 0.2794)
			(stroke
				(width 0.1)
				(type default)
			)
			(layer "B.Fab")
		)
		(fp_line
			(start 0.12065 0.2794)
			(end 0.12065 0.3048)
			(stroke
				(width 0.1)
				(type default)
			)
			(layer "B.Fab")
		)
		(fp_line
			(start -0.12065 -0.2794)
			(end -0.12065 -0.3048)
			(stroke
				(width 0.1)
				(type default)
			)
			(layer "B.Fab")
		)
		(fp_line
			(start 0.12065 -0.2794)
			(end -0.12065 -0.2794)
			(stroke
				(width 0.1)
				(type default)
			)
			(layer "B.Fab")
		)
		(fp_line
			(start -0.67945 -0.3048)
			(end -0.67945 0.3048)
			(stroke
				(width 0.1)
				(type default)
			)
			(layer "B.Fab")
		)
		(fp_line
			(start -0.12065 -0.3048)
			(end -0.67945 -0.3048)
			(stroke
				(width 0.1)
				(type default)
			)
			(layer "B.Fab")
		)
		(fp_line
			(start 0.12065 -0.305054)
			(end 0.12065 -0.2794)
			(stroke
				(width 0.1)
				(type default)
			)
			(layer "B.Fab")
		)
		(fp_line
			(start 0.67945 -0.305054)
			(end 0.12065 -0.305054)
			(stroke
				(width 0.1)
				(type default)
			)
			(layer "B.Fab")
		)
		(pad "1" smd circle
			(at 0.40005 0 90)
			(size 0 0)
			(layers "B.Cu" "B.Mask" "B.Paste")
			(net "HSC_TYPE_ADC_R")
		)
		(pad "2" smd circle
			(at -0.40005 0 90)
			(size 0 0)
			(layers "B.Cu" "B.Mask" "B.Paste")
			(net "P12V_AUX")
		)
	)
	(footprint ""
		(layer "B.Cu")
		(at 453.754744 -279.673558 180)
		(property "Reference" "C4401"
			(at 0 0 0)
			(layer "B.SilkS")
			(hide yes)
			(effects
				(font
					(size 1.27 1.27)
				)
				(justify mirror)
			)
		)
		(property "Value" ""
			(at 0 0 0)
			(layer "B.Fab")
			(effects
				(font
					(size 1.27 1.27)
				)
				(justify mirror)
			)
		)
		(duplicate_pad_numbers_are_jumpers no)
		(fp_line
			(start 1.2954 0.5842)
			(end 1.2954 -0.5842)
			(stroke
				(width 0.1524)
				(type default)
			)
			(layer "B.SilkS")
		)
		(fp_line
			(start 1.2954 -0.5842)
			(end -1.2954 -0.5842)
			(stroke
				(width 0.1524)
				(type default)
			)
			(layer "B.SilkS")
		)
		(fp_line
			(start -1.2954 0.5842)
			(end 1.2954 0.5842)
			(stroke
				(width 0.1524)
				(type default)
			)
			(layer "B.SilkS")
		)
		(fp_line
			(start -1.2954 -0.5842)
			(end -1.2954 0.5842)
			(stroke
				(width 0.1524)
				(type default)
			)
			(layer "B.SilkS")
		)
		(fp_line
			(start 1.1938 0.4064)
			(end 1.1938 -0.4064)
			(stroke
				(width 0.1)
				(type default)
			)
			(layer "B.Fab")
		)
		(fp_line
			(start 1.1938 -0.4064)
			(end 0.8636 -0.4064)
			(stroke
				(width 0.1)
				(type default)
			)
			(layer "B.Fab")
		)
		(fp_line
			(start 0.8636 0.4572)
			(end 0.8636 0.4064)
			(stroke
				(width 0.1)
				(type default)
			)
			(layer "B.Fab")
		)
		(fp_line
			(start 0.8636 0.4064)
			(end 1.1938 0.4064)
			(stroke
				(width 0.1)
				(type default)
			)
			(layer "B.Fab")
		)
		(fp_line
			(start 0.8636 -0.4064)
			(end 0.8636 -0.4572)
			(stroke
				(width 0.1)
				(type default)
			)
			(layer "B.Fab")
		)
		(fp_line
			(start 0.8636 -0.4572)
			(end -0.8636 -0.4572)
			(stroke
				(width 0.1)
				(type default)
			)
			(layer "B.Fab")
		)
		(fp_line
			(start -0.8636 0.4572)
			(end 0.8636 0.4572)
			(stroke
				(width 0.1)
				(type default)
			)
			(layer "B.Fab")
		)
		(fp_line
			(start -0.8636 0.4064)
			(end -0.8636 0.4572)
			(stroke
				(width 0.1)
				(type default)
			)
			(layer "B.Fab")
		)
		(fp_line
			(start -0.8636 -0.4064)
			(end -1.1938 -0.4064)
			(stroke
				(width 0.1)
				(type default)
			)
			(layer "B.Fab")
		)
		(fp_line
			(start -0.8636 -0.4572)
			(end -0.8636 -0.4064)
			(stroke
				(width 0.1)
				(type default)
			)
			(layer "B.Fab")
		)
		(fp_line
			(start -1.1938 0.4064)
			(end -0.8636 0.4064)
			(stroke
				(width 0.1)
				(type default)
			)
			(layer "B.Fab")
		)
		(fp_line
			(start -1.1938 -0.4064)
			(end -1.1938 0.4064)
			(stroke
				(width 0.1)
				(type default)
			)
			(layer "B.Fab")
		)
		(pad "1" smd rect
			(at 0.7366 0 90)
			(size 0.7112 0.8128)
			(layers "B.Cu" "B.Mask" "B.Paste")
			(net "P1V25_PEX3")
		)
		(pad "2" smd rect
			(at -0.7366 0 90)
			(size 0.7112 0.8128)
			(layers "B.Cu" "B.Mask" "B.Paste")
			(net "GND")
		)
	)
	(footprint ""
		(layer "B.Cu")
		(at 409.401264 -305.399948 -90)
		(property "Reference" "C3496"
			(at 0 0 90)
			(layer "B.SilkS")
			(hide yes)
			(effects
				(font
					(size 1.27 1.27)
				)
				(justify mirror)
			)
		)
		(property "Value" ""
			(at 0 0 90)
			(layer "B.Fab")
			(effects
				(font
					(size 1.27 1.27)
				)
				(justify mirror)
			)
		)
		(duplicate_pad_numbers_are_jumpers no)
		(fp_line
			(start -0.299974 0.150114)
			(end 0.299974 0.150114)
			(stroke
				(width 0.1)
				(type default)
			)
			(layer "B.Fab")
		)
		(fp_line
			(start 0.299974 0.150114)
			(end 0.299974 -0.150114)
			(stroke
				(width 0.1)
				(type default)
			)
			(layer "B.Fab")
		)
		(fp_line
			(start -0.299974 -0.150114)
			(end -0.299974 0.150114)
			(stroke
				(width 0.1)
				(type default)
			)
			(layer "B.Fab")
		)
		(fp_line
			(start 0.299974 -0.150114)
			(end -0.299974 -0.150114)
			(stroke
				(width 0.1)
				(type default)
			)
			(layer "B.Fab")
		)
		(pad "1" smd rect
			(at 0.2667 0 90)
			(size 0.3048 0.381)
			(layers "B.Cu" "B.Mask" "B.Paste")
			(net "P1V25_SERDES_VDDPLL_PEX3")
		)
		(pad "2" smd rect
			(at -0.2667 0 90)
			(size 0.3048 0.381)
			(layers "B.Cu" "B.Mask" "B.Paste")
			(net "GND")
		)
	)
	(footprint ""
		(layer "B.Cu")
		(at 289.94989 -292.099746 90)
		(property "Reference" "C1708"
			(at 0 0 90)
			(layer "B.SilkS")
			(hide yes)
			(effects
				(font
					(size 1.27 1.27)
				)
				(justify mirror)
			)
		)
		(property "Value" ""
			(at 0 0 90)
			(layer "B.Fab")
			(effects
				(font
					(size 1.27 1.27)
				)
				(justify mirror)
			)
		)
		(duplicate_pad_numbers_are_jumpers no)
		(fp_line
			(start 0.299974 -0.150114)
			(end -0.299974 -0.150114)
			(stroke
				(width 0.1)
				(type default)
			)
			(layer "B.Fab")
		)
		(fp_line
			(start -0.299974 -0.150114)
			(end -0.299974 0.150114)
			(stroke
				(width 0.1)
				(type default)
			)
			(layer "B.Fab")
		)
		(fp_line
			(start 0.299974 0.150114)
			(end 0.299974 -0.150114)
			(stroke
				(width 0.1)
				(type default)
			)
			(layer "B.Fab")
		)
		(fp_line
			(start -0.299974 0.150114)
			(end 0.299974 0.150114)
			(stroke
				(width 0.1)
				(type default)
			)
			(layer "B.Fab")
		)
		(pad "1" smd rect
			(at 0.2667 0 270)
			(size 0.3048 0.381)
			(layers "B.Cu" "B.Mask" "B.Paste")
			(net "P0V8_SERDES_VDDA_PEX2")
		)
		(pad "2" smd rect
			(at -0.2667 0 270)
			(size 0.3048 0.381)
			(layers "B.Cu" "B.Mask" "B.Paste")
			(net "GND")
		)
	)
	(footprint ""
		(layer "B.Cu")
		(at 392.749786 -298.27474)
		(property "Reference" "C3533"
			(at 0 0 0)
			(layer "B.SilkS")
			(hide yes)
			(effects
				(font
					(size 1.27 1.27)
				)
				(justify mirror)
			)
		)
		(property "Value" ""
			(at 0 0 0)
			(layer "B.Fab")
			(effects
				(font
					(size 1.27 1.27)
				)
				(justify mirror)
			)
		)
		(duplicate_pad_numbers_are_jumpers no)
		(fp_line
			(start -0.299974 -0.150114)
			(end -0.299974 0.150114)
			(stroke
				(width 0.1)
				(type default)
			)
			(layer "B.Fab")
		)
		(fp_line
			(start -0.299974 0.150114)
			(end 0.299974 0.150114)
			(stroke
				(width 0.1)
				(type default)
			)
			(layer "B.Fab")
		)
		(fp_line
			(start 0.299974 -0.150114)
			(end -0.299974 -0.150114)
			(stroke
				(width 0.1)
				(type default)
			)
			(layer "B.Fab")
		)
		(fp_line
			(start 0.299974 0.150114)
			(end 0.299974 -0.150114)
			(stroke
				(width 0.1)
				(type default)
			)
			(layer "B.Fab")
		)
		(pad "1" smd rect
			(at 0.2667 0 180)
			(size 0.3048 0.381)
			(layers "B.Cu" "B.Mask" "B.Paste")
			(net "P1V8_VDDA_PEX3")
		)
		(pad "2" smd rect
			(at -0.2667 0 180)
			(size 0.3048 0.381)
			(layers "B.Cu" "B.Mask" "B.Paste")
			(net "GND")
		)
	)
	(footprint ""
		(layer "B.Cu")
		(at 160.549844 -293.04996)
		(property "Reference" "C3178"
			(at 0 0 0)
			(layer "B.SilkS")
			(hide yes)
			(effects
				(font
					(size 1.27 1.27)
				)
				(justify mirror)
			)
		)
		(property "Value" ""
			(at 0 0 0)
			(layer "B.Fab")
			(effects
				(font
					(size 1.27 1.27)
				)
				(justify mirror)
			)
		)
		(duplicate_pad_numbers_are_jumpers no)
		(fp_line
			(start -0.299974 -0.150114)
			(end -0.299974 0.150114)
			(stroke
				(width 0.1)
				(type default)
			)
			(layer "B.Fab")
		)
		(fp_line
			(start -0.299974 0.150114)
			(end 0.299974 0.150114)
			(stroke
				(width 0.1)
				(type default)
			)
			(layer "B.Fab")
		)
		(fp_line
			(start 0.299974 -0.150114)
			(end -0.299974 -0.150114)
			(stroke
				(width 0.1)
				(type default)
			)
			(layer "B.Fab")
		)
		(fp_line
			(start 0.299974 0.150114)
			(end 0.299974 -0.150114)
			(stroke
				(width 0.1)
				(type default)
			)
			(layer "B.Fab")
		)
		(pad "1" smd rect
			(at 0.2667 0 180)
			(size 0.3048 0.381)
			(layers "B.Cu" "B.Mask" "B.Paste")
			(net "P1V8_PEX")
		)
		(pad "2" smd rect
			(at -0.2667 0 180)
			(size 0.3048 0.381)
			(layers "B.Cu" "B.Mask" "B.Paste")
			(net "GND")
		)
	)
	(footprint ""
		(layer "B.Cu")
		(at 176.699926 -303.499774 -90)
		(property "Reference" "C3089"
			(at 0 0 90)
			(layer "B.SilkS")
			(hide yes)
			(effects
				(font
					(size 1.27 1.27)
				)
				(justify mirror)
			)
		)
		(property "Value" ""
			(at 0 0 90)
			(layer "B.Fab")
			(effects
				(font
					(size 1.27 1.27)
				)
				(justify mirror)
			)
		)
		(duplicate_pad_numbers_are_jumpers no)
		(fp_line
			(start -0.299974 0.150114)
			(end 0.299974 0.150114)
			(stroke
				(width 0.1)
				(type default)
			)
			(layer "B.Fab")
		)
		(fp_line
			(start 0.299974 0.150114)
			(end 0.299974 -0.150114)
			(stroke
				(width 0.1)
				(type default)
			)
			(layer "B.Fab")
		)
		(fp_line
			(start -0.299974 -0.150114)
			(end -0.299974 0.150114)
			(stroke
				(width 0.1)
				(type default)
			)
			(layer "B.Fab")
		)
		(fp_line
			(start 0.299974 -0.150114)
			(end -0.299974 -0.150114)
			(stroke
				(width 0.1)
				(type default)
			)
			(layer "B.Fab")
		)
		(pad "1" smd rect
			(at 0.2667 0 90)
			(size 0.3048 0.381)
			(layers "B.Cu" "B.Mask" "B.Paste")
			(net "P1V25_PEX1")
		)
		(pad "2" smd rect
			(at -0.2667 0 90)
			(size 0.3048 0.381)
			(layers "B.Cu" "B.Mask" "B.Paste")
			(net "GND")
		)
	)
	(footprint ""
		(layer "B.Cu")
		(at 303.249838 -298.27474 180)
		(property "Reference" "C3277"
			(at 0 0 0)
			(layer "B.SilkS")
			(hide yes)
			(effects
				(font
					(size 1.27 1.27)
				)
				(justify mirror)
			)
		)
		(property "Value" ""
			(at 0 0 0)
			(layer "B.Fab")
			(effects
				(font
					(size 1.27 1.27)
				)
				(justify mirror)
			)
		)
		(duplicate_pad_numbers_are_jumpers no)
		(fp_line
			(start 0.299974 0.150114)
			(end 0.299974 -0.150114)
			(stroke
				(width 0.1)
				(type default)
			)
			(layer "B.Fab")
		)
		(fp_line
			(start 0.299974 -0.150114)
			(end -0.299974 -0.150114)
			(stroke
				(width 0.1)
				(type default)
			)
			(layer "B.Fab")
		)
		(fp_line
			(start -0.299974 0.150114)
			(end 0.299974 0.150114)
			(stroke
				(width 0.1)
				(type default)
			)
			(layer "B.Fab")
		)
		(fp_line
			(start -0.299974 -0.150114)
			(end -0.299974 0.150114)
			(stroke
				(width 0.1)
				(type default)
			)
			(layer "B.Fab")
		)
		(pad "1" smd rect
			(at 0.2667 0)
			(size 0.3048 0.381)
			(layers "B.Cu" "B.Mask" "B.Paste")
			(net "P1V25_PEX2")
		)
		(pad "2" smd rect
			(at -0.2667 0)
			(size 0.3048 0.381)
			(layers "B.Cu" "B.Mask" "B.Paste")
			(net "GND")
		)
	)
	(footprint ""
		(layer "B.Cu")
		(at 294.69969 -288.299906 90)
		(property "Reference" "C3287"
			(at 0 0 90)
			(layer "B.SilkS")
			(hide yes)
			(effects
				(font
					(size 1.27 1.27)
				)
				(justify mirror)
			)
		)
		(property "Value" ""
			(at 0 0 90)
			(layer "B.Fab")
			(effects
				(font
					(size 1.27 1.27)
				)
				(justify mirror)
			)
		)
		(duplicate_pad_numbers_are_jumpers no)
		(fp_line
			(start 0.299974 -0.150114)
			(end -0.299974 -0.150114)
			(stroke
				(width 0.1)
				(type default)
			)
			(layer "B.Fab")
		)
		(fp_line
			(start -0.299974 -0.150114)
			(end -0.299974 0.150114)
			(stroke
				(width 0.1)
				(type default)
			)
			(layer "B.Fab")
		)
		(fp_line
			(start 0.299974 0.150114)
			(end 0.299974 -0.150114)
			(stroke
				(width 0.1)
				(type default)
			)
			(layer "B.Fab")
		)
		(fp_line
			(start -0.299974 0.150114)
			(end 0.299974 0.150114)
			(stroke
				(width 0.1)
				(type default)
			)
			(layer "B.Fab")
		)
		(pad "1" smd rect
			(at 0.2667 0 270)
			(size 0.3048 0.381)
			(layers "B.Cu" "B.Mask" "B.Paste")
			(net "P1V25_PEX2")
		)
		(pad "2" smd rect
			(at -0.2667 0 270)
			(size 0.3048 0.381)
			(layers "B.Cu" "B.Mask" "B.Paste")
			(net "GND")
		)
	)
	(footprint ""
		(layer "B.Cu")
		(at 345.059 -233.553 90)
		(property "Reference" "R3564"
			(at 0 0 90)
			(layer "B.SilkS")
			(hide yes)
			(effects
				(font
					(size 1.27 1.27)
				)
				(justify mirror)
			)
		)
		(property "Value" ""
			(at 0 0 90)
			(layer "B.Fab")
			(effects
				(font
					(size 1.27 1.27)
				)
				(justify mirror)
			)
		)
		(duplicate_pad_numbers_are_jumpers no)
		(fp_line
			(start 0.7874 -0.4064)
			(end -0.7874 -0.4064)
			(stroke
				(width 0.1524)
				(type default)
			)
			(layer "B.SilkS")
		)
		(fp_line
			(start -0.7874 -0.4064)
			(end -0.7874 0.4064)
			(stroke
				(width 0.1524)
				(type default)
			)
			(layer "B.SilkS")
		)
		(fp_line
			(start 0.7874 0.4064)
			(end 0.7874 -0.4064)
			(stroke
				(width 0.1524)
				(type default)
			)
			(layer "B.SilkS")
		)
		(fp_line
			(start -0.7874 0.4064)
			(end 0.7874 0.4064)
			(stroke
				(width 0.1524)
				(type default)
			)
			(layer "B.SilkS")
		)
		(fp_line
			(start 0.67945 -0.305054)
			(end 0.12065 -0.305054)
			(stroke
				(width 0.1)
				(type default)
			)
			(layer "B.Fab")
		)
		(fp_line
			(start 0.12065 -0.305054)
			(end 0.12065 -0.2794)
			(stroke
				(width 0.1)
				(type default)
			)
			(layer "B.Fab")
		)
		(fp_line
			(start -0.12065 -0.3048)
			(end -0.67945 -0.3048)
			(stroke
				(width 0.1)
				(type default)
			)
			(layer "B.Fab")
		)
		(fp_line
			(start -0.67945 -0.3048)
			(end -0.67945 0.3048)
			(stroke
				(width 0.1)
				(type default)
			)
			(layer "B.Fab")
		)
		(fp_line
			(start 0.12065 -0.2794)
			(end -0.12065 -0.2794)
			(stroke
				(width 0.1)
				(type default)
			)
			(layer "B.Fab")
		)
		(fp_line
			(start -0.12065 -0.2794)
			(end -0.12065 -0.3048)
			(stroke
				(width 0.1)
				(type default)
			)
			(layer "B.Fab")
		)
		(fp_line
			(start 0.12065 0.2794)
			(end 0.12065 0.3048)
			(stroke
				(width 0.1)
				(type default)
			)
			(layer "B.Fab")
		)
		(fp_line
			(start -0.120396 0.2794)
			(end 0.12065 0.2794)
			(stroke
				(width 0.1)
				(type default)
			)
			(layer "B.Fab")
		)
		(fp_line
			(start 0.67945 0.3048)
			(end 0.67945 -0.305054)
			(stroke
				(width 0.1)
				(type default)
			)
			(layer "B.Fab")
		)
		(fp_line
			(start 0.12065 0.3048)
			(end 0.67945 0.3048)
			(stroke
				(width 0.1)
				(type default)
			)
			(layer "B.Fab")
		)
		(fp_line
			(start -0.120396 0.3048)
			(end -0.120396 0.2794)
			(stroke
				(width 0.1)
				(type default)
			)
			(layer "B.Fab")
		)
		(fp_line
			(start -0.67945 0.3048)
			(end -0.120396 0.3048)
			(stroke
				(width 0.1)
				(type default)
			)
			(layer "B.Fab")
		)
		(pad "1" smd circle
			(at 0.40005 0 270)
			(size 0 0)
			(layers "B.Cu" "B.Mask" "B.Paste")
			(net "SSD5_PWR_EN_R")
		)
		(pad "2" smd circle
			(at -0.40005 0 270)
			(size 0 0)
			(layers "B.Cu" "B.Mask" "B.Paste")
			(net "SSD5_PWR_EN")
		)
	)
	(footprint ""
		(layer "B.Cu")
		(at 350.58731 -257.699764 180)
		(property "Reference" "PC133"
			(at 0 0 0)
			(layer "B.SilkS")
			(hide yes)
			(effects
				(font
					(size 1.27 1.27)
				)
				(justify mirror)
			)
		)
		(property "Value" ""
			(at 0 0 0)
			(layer "B.Fab")
			(effects
				(font
					(size 1.27 1.27)
				)
				(justify mirror)
			)
		)
		(duplicate_pad_numbers_are_jumpers no)
		(fp_line
			(start 0.7874 0.4064)
			(end 0.7874 -0.4064)
			(stroke
				(width 0.1524)
				(type default)
			)
			(layer "B.SilkS")
		)
		(fp_line
			(start 0.7874 -0.4064)
			(end -0.7874 -0.4064)
			(stroke
				(width 0.1524)
				(type default)
			)
			(layer "B.SilkS")
		)
		(fp_line
			(start -0.7874 0.4064)
			(end 0.7874 0.4064)
			(stroke
				(width 0.1524)
				(type default)
			)
			(layer "B.SilkS")
		)
		(fp_line
			(start -0.7874 -0.4064)
			(end -0.7874 0.4064)
			(stroke
				(width 0.1524)
				(type default)
			)
			(layer "B.SilkS")
		)
		(fp_line
			(start 0.67945 0.3048)
			(end 0.67945 -0.305054)
			(stroke
				(width 0.1)
				(type default)
			)
			(layer "B.Fab")
		)
		(fp_line
			(start 0.67945 -0.305054)
			(end 0.12065 -0.305054)
			(stroke
				(width 0.1)
				(type default)
			)
			(layer "B.Fab")
		)
		(fp_line
			(start 0.12065 0.3048)
			(end 0.67945 0.3048)
			(stroke
				(width 0.1)
				(type default)
			)
			(layer "B.Fab")
		)
		(fp_line
			(start 0.12065 0.2794)
			(end 0.12065 0.3048)
			(stroke
				(width 0.1)
				(type default)
			)
			(layer "B.Fab")
		)
		(fp_line
			(start 0.12065 -0.2794)
			(end -0.12065 -0.2794)
			(stroke
				(width 0.1)
				(type default)
			)
			(layer "B.Fab")
		)
		(fp_line
			(start 0.12065 -0.305054)
			(end 0.12065 -0.2794)
			(stroke
				(width 0.1)
				(type default)
			)
			(layer "B.Fab")
		)
		(fp_line
			(start -0.120396 0.3048)
			(end -0.120396 0.2794)
			(stroke
				(width 0.1)
				(type default)
			)
			(layer "B.Fab")
		)
		(fp_line
			(start -0.120396 0.2794)
			(end 0.12065 0.2794)
			(stroke
				(width 0.1)
				(type default)
			)
			(layer "B.Fab")
		)
		(fp_line
			(start -0.12065 -0.2794)
			(end -0.12065 -0.3048)
			(stroke
				(width 0.1)
				(type default)
			)
			(layer "B.Fab")
		)
		(fp_line
			(start -0.12065 -0.3048)
			(end -0.67945 -0.3048)
			(stroke
				(width 0.1)
				(type default)
			)
			(layer "B.Fab")
		)
		(fp_line
			(start -0.67945 0.3048)
			(end -0.120396 0.3048)
			(stroke
				(width 0.1)
				(type default)
			)
			(layer "B.Fab")
		)
		(fp_line
			(start -0.67945 -0.3048)
			(end -0.67945 0.3048)
			(stroke
				(width 0.1)
				(type default)
			)
			(layer "B.Fab")
		)
		(pad "1" smd circle
			(at 0.40005 0)
			(size 0 0)
			(layers "B.Cu" "B.Mask" "B.Paste")
			(net "P0V8_PEX3_TSEN_R")
		)
		(pad "2" smd circle
			(at -0.40005 0)
			(size 0 0)
			(layers "B.Cu" "B.Mask" "B.Paste")
			(net "GND")
		)
	)
	(footprint ""
		(layer "B.Cu")
		(at 362.3691 -293.660068 90)
		(property "Reference" "PC184"
			(at 0 0 90)
			(layer "B.SilkS")
			(hide yes)
			(effects
				(font
					(size 1.27 1.27)
				)
				(justify mirror)
			)
		)
		(property "Value" ""
			(at 0 0 90)
			(layer "B.Fab")
			(effects
				(font
					(size 1.27 1.27)
				)
				(justify mirror)
			)
		)
		(duplicate_pad_numbers_are_jumpers no)
		(fp_line
			(start 4.84378 -2.150618)
			(end 4.53898 -2.150618)
			(stroke
				(width 0.1524)
				(type default)
			)
			(layer "B.SilkS")
		)
		(fp_line
			(start 4.84378 -2.150618)
			(end 4.842256 2.163064)
			(stroke
				(width 0.1524)
				(type default)
			)
			(layer "B.SilkS")
		)
		(fp_line
			(start 4.69138 -2.150618)
			(end 4.692396 2.161032)
			(stroke
				(width 0.1524)
				(type default)
			)
			(layer "B.SilkS")
		)
		(fp_line
			(start 4.53898 -2.150618)
			(end 4.539742 2.152142)
			(stroke
				(width 0.1524)
				(type default)
			)
			(layer "B.SilkS")
		)
		(fp_line
			(start 4.53898 -2.15011)
			(end -4.53898 -2.15011)
			(stroke
				(width 0.1524)
				(type default)
			)
			(layer "B.SilkS")
		)
		(fp_line
			(start -4.53898 -2.15011)
			(end -4.53898 2.15011)
			(stroke
				(width 0.1524)
				(type default)
			)
			(layer "B.SilkS")
		)
		(fp_line
			(start 4.53898 2.15011)
			(end 4.53898 -2.15011)
			(stroke
				(width 0.1524)
				(type default)
			)
			(layer "B.SilkS")
		)
		(fp_line
			(start -4.53898 2.15011)
			(end 4.53898 2.15011)
			(stroke
				(width 0.1524)
				(type default)
			)
			(layer "B.SilkS")
		)
		(fp_line
			(start 4.83108 2.150364)
			(end 4.447794 2.149348)
			(stroke
				(width 0.1524)
				(type default)
			)
			(layer "B.SilkS")
		)
		(fp_line
			(start 3.64998 -2.15011)
			(end -3.64998 -2.15011)
			(stroke
				(width 0.1)
				(type default)
			)
			(layer "B.Fab")
		)
		(fp_line
			(start -3.64998 -2.15011)
			(end -3.64998 2.15011)
			(stroke
				(width 0.1)
				(type default)
			)
			(layer "B.Fab")
		)
		(fp_line
			(start 3.64998 2.15011)
			(end 3.64998 -2.15011)
			(stroke
				(width 0.1)
				(type default)
			)
			(layer "B.Fab")
		)
		(fp_line
			(start -3.64998 2.15011)
			(end 3.64998 2.15011)
			(stroke
				(width 0.1)
				(type default)
			)
			(layer "B.Fab")
		)
		(fp_text user "+"
			(at 6.214872 -0.337058 90)
			(unlocked yes)
			(layer "B.SilkS")
			(effects
				(font
					(size 1.905 1.4224)
					(thickness 0.1524)
				)
				(justify left mirror)
			)
		)
		(fp_text user "-"
			(at -4.313174 -0.094488 90)
			(unlocked yes)
			(layer "B.SilkS")
			(effects
				(font
					(size 1.905 1.4224)
					(thickness 0.1524)
				)
				(justify left mirror)
			)
		)
		(fp_text user "+"
			(at 6.214872 -0.337058 90)
			(unlocked yes)
			(layer "B.Fab")
			(effects
				(font
					(size 1.905 1.4224)
					(thickness 0.1524)
				)
				(justify left mirror)
			)
		)
		(fp_text user "-"
			(at -4.313174 -0.094488 90)
			(unlocked yes)
			(layer "B.Fab")
			(effects
				(font
					(size 1.905 1.4224)
					(thickness 0.1524)
				)
				(justify left mirror)
			)
		)
		(pad "1" smd rect
			(at 3.199892 0 270)
			(size 2.413 2.8194)
			(layers "B.Cu" "B.Mask" "B.Paste")
			(net "P0V8_PEX3")
		)
		(pad "2" smd rect
			(at -3.199892 0 270)
			(size 2.413 2.8194)
			(layers "B.Cu" "B.Mask" "B.Paste")
			(net "GND")
		)
	)
	(footprint ""
		(layer "B.Cu")
		(at 189.500002 -109.251496)
		(property "Reference" "C893"
			(at 0 0 0)
			(layer "B.SilkS")
			(hide yes)
			(effects
				(font
					(size 1.27 1.27)
				)
				(justify mirror)
			)
		)
		(property "Value" ""
			(at 0 0 0)
			(layer "B.Fab")
			(effects
				(font
					(size 1.27 1.27)
				)
				(justify mirror)
			)
		)
		(duplicate_pad_numbers_are_jumpers no)
		(fp_line
			(start -0.299974 -0.150114)
			(end -0.299974 0.150114)
			(stroke
				(width 0.1)
				(type default)
			)
			(layer "B.Fab")
		)
		(fp_line
			(start -0.299974 0.150114)
			(end 0.299974 0.150114)
			(stroke
				(width 0.1)
				(type default)
			)
			(layer "B.Fab")
		)
		(fp_line
			(start 0.299974 -0.150114)
			(end -0.299974 -0.150114)
			(stroke
				(width 0.1)
				(type default)
			)
			(layer "B.Fab")
		)
		(fp_line
			(start 0.299974 0.150114)
			(end 0.299974 -0.150114)
			(stroke
				(width 0.1)
				(type default)
			)
			(layer "B.Fab")
		)
		(pad "1" smd rect
			(at 0.2667 0 180)
			(size 0.3048 0.381)
			(layers "B.Cu" "B.Mask" "B.Paste")
			(net "P12V_NIC3")
		)
		(pad "2" smd rect
			(at -0.2667 0 180)
			(size 0.3048 0.381)
			(layers "B.Cu" "B.Mask" "B.Paste")
			(net "GND")
		)
	)
	(footprint ""
		(layer "B.Cu")
		(at 161.964116 -145.284952 180)
		(property "Reference" "C881"
			(at 0 0 0)
			(layer "B.SilkS")
			(hide yes)
			(effects
				(font
					(size 1.27 1.27)
				)
				(justify mirror)
			)
		)
		(property "Value" ""
			(at 0 0 0)
			(layer "B.Fab")
			(effects
				(font
					(size 1.27 1.27)
				)
				(justify mirror)
			)
		)
		(duplicate_pad_numbers_are_jumpers no)
		(fp_line
			(start 0.299974 0.150114)
			(end 0.299974 -0.150114)
			(stroke
				(width 0.1)
				(type default)
			)
			(layer "B.Fab")
		)
		(fp_line
			(start 0.299974 -0.150114)
			(end -0.299974 -0.150114)
			(stroke
				(width 0.1)
				(type default)
			)
			(layer "B.Fab")
		)
		(fp_line
			(start -0.299974 0.150114)
			(end 0.299974 0.150114)
			(stroke
				(width 0.1)
				(type default)
			)
			(layer "B.Fab")
		)
		(fp_line
			(start -0.299974 -0.150114)
			(end -0.299974 0.150114)
			(stroke
				(width 0.1)
				(type default)
			)
			(layer "B.Fab")
		)
		(pad "1" smd rect
			(at 0.2667 0)
			(size 0.3048 0.381)
			(layers "B.Cu" "B.Mask" "B.Paste")
			(net "P12V_NIC2")
		)
		(pad "2" smd rect
			(at -0.2667 0)
			(size 0.3048 0.381)
			(layers "B.Cu" "B.Mask" "B.Paste")
			(net "GND")
		)
	)
	(footprint ""
		(layer "B.Cu")
		(at 61.074808 -286.399732 90)
		(property "Reference" "C2960"
			(at 0 0 90)
			(layer "B.SilkS")
			(hide yes)
			(effects
				(font
					(size 1.27 1.27)
				)
				(justify mirror)
			)
		)
		(property "Value" ""
			(at 0 0 90)
			(layer "B.Fab")
			(effects
				(font
					(size 1.27 1.27)
				)
				(justify mirror)
			)
		)
		(duplicate_pad_numbers_are_jumpers no)
		(fp_line
			(start 0.299974 -0.150114)
			(end -0.299974 -0.150114)
			(stroke
				(width 0.1)
				(type default)
			)
			(layer "B.Fab")
		)
		(fp_line
			(start -0.299974 -0.150114)
			(end -0.299974 0.150114)
			(stroke
				(width 0.1)
				(type default)
			)
			(layer "B.Fab")
		)
		(fp_line
			(start 0.299974 0.150114)
			(end 0.299974 -0.150114)
			(stroke
				(width 0.1)
				(type default)
			)
			(layer "B.Fab")
		)
		(fp_line
			(start -0.299974 0.150114)
			(end 0.299974 0.150114)
			(stroke
				(width 0.1)
				(type default)
			)
			(layer "B.Fab")
		)
		(pad "1" smd rect
			(at 0.2667 0 270)
			(size 0.3048 0.381)
			(layers "B.Cu" "B.Mask" "B.Paste")
			(net "P1V25_SERDES_VDDPLL_PEX0")
		)
		(pad "2" smd rect
			(at -0.2667 0 270)
			(size 0.3048 0.381)
			(layers "B.Cu" "B.Mask" "B.Paste")
			(net "GND")
		)
	)
	(footprint ""
		(layer "B.Cu")
		(at 406.049988 -290.199826 90)
		(property "Reference" "C1971"
			(at 0 0 90)
			(layer "B.SilkS")
			(hide yes)
			(effects
				(font
					(size 1.27 1.27)
				)
				(justify mirror)
			)
		)
		(property "Value" ""
			(at 0 0 90)
			(layer "B.Fab")
			(effects
				(font
					(size 1.27 1.27)
				)
				(justify mirror)
			)
		)
		(duplicate_pad_numbers_are_jumpers no)
		(fp_line
			(start 0.299974 -0.150114)
			(end -0.299974 -0.150114)
			(stroke
				(width 0.1)
				(type default)
			)
			(layer "B.Fab")
		)
		(fp_line
			(start -0.299974 -0.150114)
			(end -0.299974 0.150114)
			(stroke
				(width 0.1)
				(type default)
			)
			(layer "B.Fab")
		)
		(fp_line
			(start 0.299974 0.150114)
			(end 0.299974 -0.150114)
			(stroke
				(width 0.1)
				(type default)
			)
			(layer "B.Fab")
		)
		(fp_line
			(start -0.299974 0.150114)
			(end 0.299974 0.150114)
			(stroke
				(width 0.1)
				(type default)
			)
			(layer "B.Fab")
		)
		(pad "1" smd rect
			(at 0.2667 0 270)
			(size 0.3048 0.381)
			(layers "B.Cu" "B.Mask" "B.Paste")
			(net "P0V8_SERDES_VDDA_PEX3")
		)
		(pad "2" smd rect
			(at -0.2667 0 270)
			(size 0.3048 0.381)
			(layers "B.Cu" "B.Mask" "B.Paste")
			(net "GND")
		)
	)
	(footprint ""
		(layer "B.Cu")
		(at 149.352254 -207.784192 -90)
		(property "Reference" "R980"
			(at 0 0 90)
			(layer "B.SilkS")
			(hide yes)
			(effects
				(font
					(size 1.27 1.27)
				)
				(justify mirror)
			)
		)
		(property "Value" ""
			(at 0 0 90)
			(layer "B.Fab")
			(effects
				(font
					(size 1.27 1.27)
				)
				(justify mirror)
			)
		)
		(duplicate_pad_numbers_are_jumpers no)
		(fp_line
			(start -0.7874 0.4064)
			(end 0.7874 0.4064)
			(stroke
				(width 0.1524)
				(type default)
			)
			(layer "B.SilkS")
		)
		(fp_line
			(start 0.7874 0.4064)
			(end 0.7874 -0.4064)
			(stroke
				(width 0.1524)
				(type default)
			)
			(layer "B.SilkS")
		)
		(fp_line
			(start -0.7874 -0.4064)
			(end -0.7874 0.4064)
			(stroke
				(width 0.1524)
				(type default)
			)
			(layer "B.SilkS")
		)
		(fp_line
			(start 0.7874 -0.4064)
			(end -0.7874 -0.4064)
			(stroke
				(width 0.1524)
				(type default)
			)
			(layer "B.SilkS")
		)
		(fp_line
			(start -0.67945 0.3048)
			(end -0.120396 0.3048)
			(stroke
				(width 0.1)
				(type default)
			)
			(layer "B.Fab")
		)
		(fp_line
			(start -0.120396 0.3048)
			(end -0.120396 0.2794)
			(stroke
				(width 0.1)
				(type default)
			)
			(layer "B.Fab")
		)
		(fp_line
			(start 0.12065 0.3048)
			(end 0.67945 0.3048)
			(stroke
				(width 0.1)
				(type default)
			)
			(layer "B.Fab")
		)
		(fp_line
			(start 0.67945 0.3048)
			(end 0.67945 -0.305054)
			(stroke
				(width 0.1)
				(type default)
			)
			(layer "B.Fab")
		)
		(fp_line
			(start -0.120396 0.2794)
			(end 0.12065 0.2794)
			(stroke
				(width 0.1)
				(type default)
			)
			(layer "B.Fab")
		)
		(fp_line
			(start 0.12065 0.2794)
			(end 0.12065 0.3048)
			(stroke
				(width 0.1)
				(type default)
			)
			(layer "B.Fab")
		)
		(fp_line
			(start -0.12065 -0.2794)
			(end -0.12065 -0.3048)
			(stroke
				(width 0.1)
				(type default)
			)
			(layer "B.Fab")
		)
		(fp_line
			(start 0.12065 -0.2794)
			(end -0.12065 -0.2794)
			(stroke
				(width 0.1)
				(type default)
			)
			(layer "B.Fab")
		)
		(fp_line
			(start -0.67945 -0.3048)
			(end -0.67945 0.3048)
			(stroke
				(width 0.1)
				(type default)
			)
			(layer "B.Fab")
		)
		(fp_line
			(start -0.12065 -0.3048)
			(end -0.67945 -0.3048)
			(stroke
				(width 0.1)
				(type default)
			)
			(layer "B.Fab")
		)
		(fp_line
			(start 0.12065 -0.305054)
			(end 0.12065 -0.2794)
			(stroke
				(width 0.1)
				(type default)
			)
			(layer "B.Fab")
		)
		(fp_line
			(start 0.67945 -0.305054)
			(end 0.12065 -0.305054)
			(stroke
				(width 0.1)
				(type default)
			)
			(layer "B.Fab")
		)
		(pad "1" smd circle
			(at 0.40005 0 90)
			(size 0 0)
			(layers "B.Cu" "B.Mask" "B.Paste")
			(net "UART_PEX0_CLI_BUF_R_RX")
		)
		(pad "2" smd circle
			(at -0.40005 0 90)
			(size 0 0)
			(layers "B.Cu" "B.Mask" "B.Paste")
			(net "UART_PEX0_CLI_BUF_RX")
		)
	)
	(footprint ""
		(layer "B.Cu")
		(at 173.375066 -286.399732 90)
		(property "Reference" "C3125"
			(at 0 0 90)
			(layer "B.SilkS")
			(hide yes)
			(effects
				(font
					(size 1.27 1.27)
				)
				(justify mirror)
			)
		)
		(property "Value" ""
			(at 0 0 90)
			(layer "B.Fab")
			(effects
				(font
					(size 1.27 1.27)
				)
				(justify mirror)
			)
		)
		(duplicate_pad_numbers_are_jumpers no)
		(fp_line
			(start 0.299974 -0.150114)
			(end -0.299974 -0.150114)
			(stroke
				(width 0.1)
				(type default)
			)
			(layer "B.Fab")
		)
		(fp_line
			(start -0.299974 -0.150114)
			(end -0.299974 0.150114)
			(stroke
				(width 0.1)
				(type default)
			)
			(layer "B.Fab")
		)
		(fp_line
			(start 0.299974 0.150114)
			(end 0.299974 -0.150114)
			(stroke
				(width 0.1)
				(type default)
			)
			(layer "B.Fab")
		)
		(fp_line
			(start -0.299974 0.150114)
			(end 0.299974 0.150114)
			(stroke
				(width 0.1)
				(type default)
			)
			(layer "B.Fab")
		)
		(pad "1" smd rect
			(at 0.2667 0 270)
			(size 0.3048 0.381)
			(layers "B.Cu" "B.Mask" "B.Paste")
			(net "P1V25_SERDES_VDDPLL_PEX1")
		)
		(pad "2" smd rect
			(at -0.2667 0 270)
			(size 0.3048 0.381)
			(layers "B.Cu" "B.Mask" "B.Paste")
			(net "GND")
		)
	)
	(footprint ""
		(layer "B.Cu")
		(at 398.925034 -293.99992 90)
		(property "Reference" "C1915"
			(at 0 0 90)
			(layer "B.SilkS")
			(hide yes)
			(effects
				(font
					(size 1.27 1.27)
				)
				(justify mirror)
			)
		)
		(property "Value" ""
			(at 0 0 90)
			(layer "B.Fab")
			(effects
				(font
					(size 1.27 1.27)
				)
				(justify mirror)
			)
		)
		(duplicate_pad_numbers_are_jumpers no)
		(fp_line
			(start 0.299974 -0.150114)
			(end -0.299974 -0.150114)
			(stroke
				(width 0.1)
				(type default)
			)
			(layer "B.Fab")
		)
		(fp_line
			(start -0.299974 -0.150114)
			(end -0.299974 0.150114)
			(stroke
				(width 0.1)
				(type default)
			)
			(layer "B.Fab")
		)
		(fp_line
			(start 0.299974 0.150114)
			(end 0.299974 -0.150114)
			(stroke
				(width 0.1)
				(type default)
			)
			(layer "B.Fab")
		)
		(fp_line
			(start -0.299974 0.150114)
			(end 0.299974 0.150114)
			(stroke
				(width 0.1)
				(type default)
			)
			(layer "B.Fab")
		)
		(pad "1" smd rect
			(at 0.2667 0 270)
			(size 0.3048 0.381)
			(layers "B.Cu" "B.Mask" "B.Paste")
			(net "P0V8_PEX3")
		)
		(pad "2" smd rect
			(at -0.2667 0 270)
			(size 0.3048 0.381)
			(layers "B.Cu" "B.Mask" "B.Paste")
			(net "GND")
		)
	)
	(footprint ""
		(layer "B.Cu")
		(at 255.63068 -88.634316)
		(property "Reference" "C2642"
			(at 0 0 0)
			(layer "B.SilkS")
			(hide yes)
			(effects
				(font
					(size 1.27 1.27)
				)
				(justify mirror)
			)
		)
		(property "Value" ""
			(at 0 0 0)
			(layer "B.Fab")
			(effects
				(font
					(size 1.27 1.27)
				)
				(justify mirror)
			)
		)
		(duplicate_pad_numbers_are_jumpers no)
		(fp_line
			(start -1.2954 -0.5842)
			(end -1.2954 0.5842)
			(stroke
				(width 0.1524)
				(type default)
			)
			(layer "B.SilkS")
		)
		(fp_line
			(start -1.2954 0.5842)
			(end 1.2954 0.5842)
			(stroke
				(width 0.1524)
				(type default)
			)
			(layer "B.SilkS")
		)
		(fp_line
			(start 1.2954 -0.5842)
			(end -1.2954 -0.5842)
			(stroke
				(width 0.1524)
				(type default)
			)
			(layer "B.SilkS")
		)
		(fp_line
			(start 1.2954 0.5842)
			(end 1.2954 -0.5842)
			(stroke
				(width 0.1524)
				(type default)
			)
			(layer "B.SilkS")
		)
		(fp_line
			(start -1.1938 -0.4064)
			(end -1.1938 0.4064)
			(stroke
				(width 0.1)
				(type default)
			)
			(layer "B.Fab")
		)
		(fp_line
			(start -1.1938 0.4064)
			(end -0.8636 0.4064)
			(stroke
				(width 0.1)
				(type default)
			)
			(layer "B.Fab")
		)
		(fp_line
			(start -0.8636 -0.4572)
			(end -0.8636 -0.4064)
			(stroke
				(width 0.1)
				(type default)
			)
			(layer "B.Fab")
		)
		(fp_line
			(start -0.8636 -0.4064)
			(end -1.1938 -0.4064)
			(stroke
				(width 0.1)
				(type default)
			)
			(layer "B.Fab")
		)
		(fp_line
			(start -0.8636 0.4064)
			(end -0.8636 0.4572)
			(stroke
				(width 0.1)
				(type default)
			)
			(layer "B.Fab")
		)
		(fp_line
			(start -0.8636 0.4572)
			(end 0.8636 0.4572)
			(stroke
				(width 0.1)
				(type default)
			)
			(layer "B.Fab")
		)
		(fp_line
			(start 0.8636 -0.4572)
			(end -0.8636 -0.4572)
			(stroke
				(width 0.1)
				(type default)
			)
			(layer "B.Fab")
		)
		(fp_line
			(start 0.8636 -0.4064)
			(end 0.8636 -0.4572)
			(stroke
				(width 0.1)
				(type default)
			)
			(layer "B.Fab")
		)
		(fp_line
			(start 0.8636 0.4064)
			(end 1.1938 0.4064)
			(stroke
				(width 0.1)
				(type default)
			)
			(layer "B.Fab")
		)
		(fp_line
			(start 0.8636 0.4572)
			(end 0.8636 0.4064)
			(stroke
				(width 0.1)
				(type default)
			)
			(layer "B.Fab")
		)
		(fp_line
			(start 1.1938 -0.4064)
			(end 0.8636 -0.4064)
			(stroke
				(width 0.1)
				(type default)
			)
			(layer "B.Fab")
		)
		(fp_line
			(start 1.1938 0.4064)
			(end 1.1938 -0.4064)
			(stroke
				(width 0.1)
				(type default)
			)
			(layer "B.Fab")
		)
		(pad "1" smd rect
			(at 0.7366 0 270)
			(size 0.7112 0.8128)
			(layers "B.Cu" "B.Mask" "B.Paste")
			(net "P3V3_CLK_GEN_VDDA25M_CK440")
		)
		(pad "2" smd rect
			(at -0.7366 0 270)
			(size 0.7112 0.8128)
			(layers "B.Cu" "B.Mask" "B.Paste")
			(net "GND")
		)
	)
	(footprint ""
		(layer "B.Cu")
		(at 256.87401 -223.315276 180)
		(property "Reference" "C2406"
			(at 0 0 0)
			(layer "B.SilkS")
			(hide yes)
			(effects
				(font
					(size 1.27 1.27)
				)
				(justify mirror)
			)
		)
		(property "Value" ""
			(at 0 0 0)
			(layer "B.Fab")
			(effects
				(font
					(size 1.27 1.27)
				)
				(justify mirror)
			)
		)
		(duplicate_pad_numbers_are_jumpers no)
		(fp_line
			(start 0.7874 0.4064)
			(end 0.7874 -0.4064)
			(stroke
				(width 0.1524)
				(type default)
			)
			(layer "B.SilkS")
		)
		(fp_line
			(start 0.7874 -0.4064)
			(end -0.7874 -0.4064)
			(stroke
				(width 0.1524)
				(type default)
			)
			(layer "B.SilkS")
		)
		(fp_line
			(start -0.7874 0.4064)
			(end 0.7874 0.4064)
			(stroke
				(width 0.1524)
				(type default)
			)
			(layer "B.SilkS")
		)
		(fp_line
			(start -0.7874 -0.4064)
			(end -0.7874 0.4064)
			(stroke
				(width 0.1524)
				(type default)
			)
			(layer "B.SilkS")
		)
		(fp_line
			(start 0.67945 0.3048)
			(end 0.67945 -0.305054)
			(stroke
				(width 0.1)
				(type default)
			)
			(layer "B.Fab")
		)
		(fp_line
			(start 0.67945 -0.305054)
			(end 0.12065 -0.305054)
			(stroke
				(width 0.1)
				(type default)
			)
			(layer "B.Fab")
		)
		(fp_line
			(start 0.12065 0.3048)
			(end 0.67945 0.3048)
			(stroke
				(width 0.1)
				(type default)
			)
			(layer "B.Fab")
		)
		(fp_line
			(start 0.12065 0.2794)
			(end 0.12065 0.3048)
			(stroke
				(width 0.1)
				(type default)
			)
			(layer "B.Fab")
		)
		(fp_line
			(start 0.12065 -0.2794)
			(end -0.12065 -0.2794)
			(stroke
				(width 0.1)
				(type default)
			)
			(layer "B.Fab")
		)
		(fp_line
			(start 0.12065 -0.305054)
			(end 0.12065 -0.2794)
			(stroke
				(width 0.1)
				(type default)
			)
			(layer "B.Fab")
		)
		(fp_line
			(start -0.120396 0.3048)
			(end -0.120396 0.2794)
			(stroke
				(width 0.1)
				(type default)
			)
			(layer "B.Fab")
		)
		(fp_line
			(start -0.120396 0.2794)
			(end 0.12065 0.2794)
			(stroke
				(width 0.1)
				(type default)
			)
			(layer "B.Fab")
		)
		(fp_line
			(start -0.12065 -0.2794)
			(end -0.12065 -0.3048)
			(stroke
				(width 0.1)
				(type default)
			)
			(layer "B.Fab")
		)
		(fp_line
			(start -0.12065 -0.3048)
			(end -0.67945 -0.3048)
			(stroke
				(width 0.1)
				(type default)
			)
			(layer "B.Fab")
		)
		(fp_line
			(start -0.67945 0.3048)
			(end -0.120396 0.3048)
			(stroke
				(width 0.1)
				(type default)
			)
			(layer "B.Fab")
		)
		(fp_line
			(start -0.67945 -0.3048)
			(end -0.67945 0.3048)
			(stroke
				(width 0.1)
				(type default)
			)
			(layer "B.Fab")
		)
		(pad "1" smd circle
			(at 0.40005 0)
			(size 0 0)
			(layers "B.Cu" "B.Mask" "B.Paste")
			(net "GND")
		)
		(pad "2" smd circle
			(at -0.40005 0)
			(size 0 0)
			(layers "B.Cu" "B.Mask" "B.Paste")
			(net "P1V8_PEX")
		)
	)
	(footprint ""
		(layer "B.Cu")
		(at 163.874958 -300.858174 -90)
		(property "Reference" "C3196"
			(at 0 0 90)
			(layer "B.SilkS")
			(hide yes)
			(effects
				(font
					(size 1.27 1.27)
				)
				(justify mirror)
			)
		)
		(property "Value" ""
			(at 0 0 90)
			(layer "B.Fab")
			(effects
				(font
					(size 1.27 1.27)
				)
				(justify mirror)
			)
		)
		(duplicate_pad_numbers_are_jumpers no)
		(fp_line
			(start -0.299974 0.150114)
			(end 0.299974 0.150114)
			(stroke
				(width 0.1)
				(type default)
			)
			(layer "B.Fab")
		)
		(fp_line
			(start 0.299974 0.150114)
			(end 0.299974 -0.150114)
			(stroke
				(width 0.1)
				(type default)
			)
			(layer "B.Fab")
		)
		(fp_line
			(start -0.299974 -0.150114)
			(end -0.299974 0.150114)
			(stroke
				(width 0.1)
				(type default)
			)
			(layer "B.Fab")
		)
		(fp_line
			(start 0.299974 -0.150114)
			(end -0.299974 -0.150114)
			(stroke
				(width 0.1)
				(type default)
			)
			(layer "B.Fab")
		)
		(pad "1" smd rect
			(at 0.2667 0 90)
			(size 0.3048 0.381)
			(layers "B.Cu" "B.Mask" "B.Paste")
			(net "PCEPLL0_VDDA18_PEX1")
		)
		(pad "2" smd rect
			(at -0.2667 0 90)
			(size 0.3048 0.381)
			(layers "B.Cu" "B.Mask" "B.Paste")
			(net "GND")
		)
	)
	(footprint ""
		(layer "B.Cu")
		(at 238.106712 -52.507642 90)
		(property "Reference" "C2893"
			(at 0 0 90)
			(layer "B.SilkS")
			(hide yes)
			(effects
				(font
					(size 1.27 1.27)
				)
				(justify mirror)
			)
		)
		(property "Value" ""
			(at 0 0 90)
			(layer "B.Fab")
			(effects
				(font
					(size 1.27 1.27)
				)
				(justify mirror)
			)
		)
		(duplicate_pad_numbers_are_jumpers no)
		(fp_line
			(start 0.7874 -0.4064)
			(end -0.7874 -0.4064)
			(stroke
				(width 0.1524)
				(type default)
			)
			(layer "B.SilkS")
		)
		(fp_line
			(start -0.7874 -0.4064)
			(end -0.7874 0.4064)
			(stroke
				(width 0.1524)
				(type default)
			)
			(layer "B.SilkS")
		)
		(fp_line
			(start 0.7874 0.4064)
			(end 0.7874 -0.4064)
			(stroke
				(width 0.1524)
				(type default)
			)
			(layer "B.SilkS")
		)
		(fp_line
			(start -0.7874 0.4064)
			(end 0.7874 0.4064)
			(stroke
				(width 0.1524)
				(type default)
			)
			(layer "B.SilkS")
		)
		(fp_line
			(start 0.67945 -0.305054)
			(end 0.12065 -0.305054)
			(stroke
				(width 0.1)
				(type default)
			)
			(layer "B.Fab")
		)
		(fp_line
			(start 0.12065 -0.305054)
			(end 0.12065 -0.2794)
			(stroke
				(width 0.1)
				(type default)
			)
			(layer "B.Fab")
		)
		(fp_line
			(start -0.12065 -0.3048)
			(end -0.67945 -0.3048)
			(stroke
				(width 0.1)
				(type default)
			)
			(layer "B.Fab")
		)
		(fp_line
			(start -0.67945 -0.3048)
			(end -0.67945 0.3048)
			(stroke
				(width 0.1)
				(type default)
			)
			(layer "B.Fab")
		)
		(fp_line
			(start 0.12065 -0.2794)
			(end -0.12065 -0.2794)
			(stroke
				(width 0.1)
				(type default)
			)
			(layer "B.Fab")
		)
		(fp_line
			(start -0.12065 -0.2794)
			(end -0.12065 -0.3048)
			(stroke
				(width 0.1)
				(type default)
			)
			(layer "B.Fab")
		)
		(fp_line
			(start 0.12065 0.2794)
			(end 0.12065 0.3048)
			(stroke
				(width 0.1)
				(type default)
			)
			(layer "B.Fab")
		)
		(fp_line
			(start -0.120396 0.2794)
			(end 0.12065 0.2794)
			(stroke
				(width 0.1)
				(type default)
			)
			(layer "B.Fab")
		)
		(fp_line
			(start 0.67945 0.3048)
			(end 0.67945 -0.305054)
			(stroke
				(width 0.1)
				(type default)
			)
			(layer "B.Fab")
		)
		(fp_line
			(start 0.12065 0.3048)
			(end 0.67945 0.3048)
			(stroke
				(width 0.1)
				(type default)
			)
			(layer "B.Fab")
		)
		(fp_line
			(start -0.120396 0.3048)
			(end -0.120396 0.2794)
			(stroke
				(width 0.1)
				(type default)
			)
			(layer "B.Fab")
		)
		(fp_line
			(start -0.67945 0.3048)
			(end -0.120396 0.3048)
			(stroke
				(width 0.1)
				(type default)
			)
			(layer "B.Fab")
		)
		(pad "1" smd circle
			(at 0.40005 0 270)
			(size 0 0)
			(layers "B.Cu" "B.Mask" "B.Paste")
			(net "SSD8_AUX_P3V3_EN_R")
		)
		(pad "2" smd circle
			(at -0.40005 0 270)
			(size 0 0)
			(layers "B.Cu" "B.Mask" "B.Paste")
			(net "GND")
		)
	)
	(footprint ""
		(layer "B.Cu")
		(at 334.49387 -224.786952)
		(property "Reference" "C2085"
			(at 0 0 0)
			(layer "B.SilkS")
			(hide yes)
			(effects
				(font
					(size 1.27 1.27)
				)
				(justify mirror)
			)
		)
		(property "Value" ""
			(at 0 0 0)
			(layer "B.Fab")
			(effects
				(font
					(size 1.27 1.27)
				)
				(justify mirror)
			)
		)
		(duplicate_pad_numbers_are_jumpers no)
		(fp_line
			(start -0.69215 -0.2921)
			(end -0.69215 0.2921)
			(stroke
				(width 0.1524)
				(type default)
			)
			(layer "B.SilkS")
		)
		(fp_line
			(start -0.69215 0.2921)
			(end 0.69215 0.2921)
			(stroke
				(width 0.1524)
				(type default)
			)
			(layer "B.SilkS")
		)
		(fp_line
			(start 0.69215 -0.2921)
			(end -0.69215 -0.2921)
			(stroke
				(width 0.1524)
				(type default)
			)
			(layer "B.SilkS")
		)
		(fp_line
			(start 0.69215 0.2921)
			(end 0.69215 -0.2921)
			(stroke
				(width 0.1524)
				(type default)
			)
			(layer "B.SilkS")
		)
		(fp_line
			(start -0.51435 -0.2794)
			(end -0.51435 0.2794)
			(stroke
				(width 0.1)
				(type default)
			)
			(layer "B.Fab")
		)
		(fp_line
			(start -0.51435 0.2794)
			(end 0.51435 0.2794)
			(stroke
				(width 0.1)
				(type default)
			)
			(layer "B.Fab")
		)
		(fp_line
			(start 0.51435 -0.2794)
			(end -0.51435 -0.2794)
			(stroke
				(width 0.1)
				(type default)
			)
			(layer "B.Fab")
		)
		(fp_line
			(start 0.51435 0.2794)
			(end 0.51435 -0.2794)
			(stroke
				(width 0.1)
				(type default)
			)
			(layer "B.Fab")
		)
		(pad "1" smd circle
			(at 0.40005 0 180)
			(size 0 0)
			(layers "B.Cu" "B.Mask" "B.Paste")
			(net "P3V3_FPGA_VCCIO5")
		)
		(pad "2" smd circle
			(at -0.40005 0 180)
			(size 0 0)
			(layers "B.Cu" "B.Mask" "B.Paste")
			(net "GND")
		)
		(zone
			(layer "B.Cu")
			(hatch none 0.5)
			(connect_pads
				(clearance 0)
			)
			(min_thickness 0.25)
			(keepout
				(tracks not_allowed)
				(vias allowed)
				(pads allowed)
				(copperpour not_allowed)
				(footprints allowed)
			)
			(placement
				(enabled no)
				(sheetname "")
			)
			(fill
				(thermal_gap 0.5)
				(thermal_bridge_width 0.5)
				(island_removal_mode 0)
			)
			(polygon
				(pts
					(xy 334.68437 -224.699322) (xy 334.59293 -224.641156) (xy 334.39354 -224.641156) (xy 334.30337 -224.699322)
					(xy 334.30337 -224.874582) (xy 334.39354 -224.933002) (xy 334.59293 -224.933002) (xy 334.68437 -224.874836)
				)
			)
		)
	)
	(footprint ""
		(layer "B.Cu")
		(at 232.651046 -144.618202 90)
		(property "Reference" "C2789"
			(at 0 0 90)
			(layer "B.SilkS")
			(hide yes)
			(effects
				(font
					(size 1.27 1.27)
				)
				(justify mirror)
			)
		)
		(property "Value" ""
			(at 0 0 90)
			(layer "B.Fab")
			(effects
				(font
					(size 1.27 1.27)
				)
				(justify mirror)
			)
		)
		(duplicate_pad_numbers_are_jumpers no)
		(fp_line
			(start 1.2954 -0.5842)
			(end -1.2954 -0.5842)
			(stroke
				(width 0.1524)
				(type default)
			)
			(layer "B.SilkS")
		)
		(fp_line
			(start -1.2954 -0.5842)
			(end -1.2954 0.5842)
			(stroke
				(width 0.1524)
				(type default)
			)
			(layer "B.SilkS")
		)
		(fp_line
			(start 1.2954 0.5842)
			(end 1.2954 -0.5842)
			(stroke
				(width 0.1524)
				(type default)
			)
			(layer "B.SilkS")
		)
		(fp_line
			(start -1.2954 0.5842)
			(end 1.2954 0.5842)
			(stroke
				(width 0.1524)
				(type default)
			)
			(layer "B.SilkS")
		)
		(fp_line
			(start 0.8636 -0.4572)
			(end -0.8636 -0.4572)
			(stroke
				(width 0.1)
				(type default)
			)
			(layer "B.Fab")
		)
		(fp_line
			(start -0.8636 -0.4572)
			(end -0.8636 -0.4064)
			(stroke
				(width 0.1)
				(type default)
			)
			(layer "B.Fab")
		)
		(fp_line
			(start 1.1938 -0.4064)
			(end 0.8636 -0.4064)
			(stroke
				(width 0.1)
				(type default)
			)
			(layer "B.Fab")
		)
		(fp_line
			(start 0.8636 -0.4064)
			(end 0.8636 -0.4572)
			(stroke
				(width 0.1)
				(type default)
			)
			(layer "B.Fab")
		)
		(fp_line
			(start -0.8636 -0.4064)
			(end -1.1938 -0.4064)
			(stroke
				(width 0.1)
				(type default)
			)
			(layer "B.Fab")
		)
		(fp_line
			(start -1.1938 -0.4064)
			(end -1.1938 0.4064)
			(stroke
				(width 0.1)
				(type default)
			)
			(layer "B.Fab")
		)
		(fp_line
			(start 1.1938 0.4064)
			(end 1.1938 -0.4064)
			(stroke
				(width 0.1)
				(type default)
			)
			(layer "B.Fab")
		)
		(fp_line
			(start 0.8636 0.4064)
			(end 1.1938 0.4064)
			(stroke
				(width 0.1)
				(type default)
			)
			(layer "B.Fab")
		)
		(fp_line
			(start -0.8636 0.4064)
			(end -0.8636 0.4572)
			(stroke
				(width 0.1)
				(type default)
			)
			(layer "B.Fab")
		)
		(fp_line
			(start -1.1938 0.4064)
			(end -0.8636 0.4064)
			(stroke
				(width 0.1)
				(type default)
			)
			(layer "B.Fab")
		)
		(fp_line
			(start 0.8636 0.4572)
			(end 0.8636 0.4064)
			(stroke
				(width 0.1)
				(type default)
			)
			(layer "B.Fab")
		)
		(fp_line
			(start -0.8636 0.4572)
			(end 0.8636 0.4572)
			(stroke
				(width 0.1)
				(type default)
			)
			(layer "B.Fab")
		)
		(pad "1" smd rect
			(at 0.7366 0)
			(size 0.7112 0.8128)
			(layers "B.Cu" "B.Mask" "B.Paste")
			(net "P3V3_CLK_GEN_VDDA100M_CK440_PEX")
		)
		(pad "2" smd rect
			(at -0.7366 0)
			(size 0.7112 0.8128)
			(layers "B.Cu" "B.Mask" "B.Paste")
			(net "GND")
		)
	)
	(footprint ""
		(layer "B.Cu")
		(at 310.70169 -295.422066 180)
		(property "Reference" "C3253"
			(at 0 0 0)
			(layer "B.SilkS")
			(hide yes)
			(effects
				(font
					(size 1.27 1.27)
				)
				(justify mirror)
			)
		)
		(property "Value" ""
			(at 0 0 0)
			(layer "B.Fab")
			(effects
				(font
					(size 1.27 1.27)
				)
				(justify mirror)
			)
		)
		(duplicate_pad_numbers_are_jumpers no)
		(fp_line
			(start 1.2954 0.5842)
			(end 1.2954 -0.5842)
			(stroke
				(width 0.1524)
				(type default)
			)
			(layer "B.SilkS")
		)
		(fp_line
			(start 1.2954 -0.5842)
			(end -1.2954 -0.5842)
			(stroke
				(width 0.1524)
				(type default)
			)
			(layer "B.SilkS")
		)
		(fp_line
			(start -1.2954 0.5842)
			(end 1.2954 0.5842)
			(stroke
				(width 0.1524)
				(type default)
			)
			(layer "B.SilkS")
		)
		(fp_line
			(start -1.2954 -0.5842)
			(end -1.2954 0.5842)
			(stroke
				(width 0.1524)
				(type default)
			)
			(layer "B.SilkS")
		)
		(fp_line
			(start 1.1938 0.4064)
			(end 1.1938 -0.4064)
			(stroke
				(width 0.1)
				(type default)
			)
			(layer "B.Fab")
		)
		(fp_line
			(start 1.1938 -0.4064)
			(end 0.8636 -0.4064)
			(stroke
				(width 0.1)
				(type default)
			)
			(layer "B.Fab")
		)
		(fp_line
			(start 0.8636 0.4572)
			(end 0.8636 0.4064)
			(stroke
				(width 0.1)
				(type default)
			)
			(layer "B.Fab")
		)
		(fp_line
			(start 0.8636 0.4064)
			(end 1.1938 0.4064)
			(stroke
				(width 0.1)
				(type default)
			)
			(layer "B.Fab")
		)
		(fp_line
			(start 0.8636 -0.4064)
			(end 0.8636 -0.4572)
			(stroke
				(width 0.1)
				(type default)
			)
			(layer "B.Fab")
		)
		(fp_line
			(start 0.8636 -0.4572)
			(end -0.8636 -0.4572)
			(stroke
				(width 0.1)
				(type default)
			)
			(layer "B.Fab")
		)
		(fp_line
			(start -0.8636 0.4572)
			(end 0.8636 0.4572)
			(stroke
				(width 0.1)
				(type default)
			)
			(layer "B.Fab")
		)
		(fp_line
			(start -0.8636 0.4064)
			(end -0.8636 0.4572)
			(stroke
				(width 0.1)
				(type default)
			)
			(layer "B.Fab")
		)
		(fp_line
			(start -0.8636 -0.4064)
			(end -1.1938 -0.4064)
			(stroke
				(width 0.1)
				(type default)
			)
			(layer "B.Fab")
		)
		(fp_line
			(start -0.8636 -0.4572)
			(end -0.8636 -0.4064)
			(stroke
				(width 0.1)
				(type default)
			)
			(layer "B.Fab")
		)
		(fp_line
			(start -1.1938 0.4064)
			(end -0.8636 0.4064)
			(stroke
				(width 0.1)
				(type default)
			)
			(layer "B.Fab")
		)
		(fp_line
			(start -1.1938 -0.4064)
			(end -1.1938 0.4064)
			(stroke
				(width 0.1)
				(type default)
			)
			(layer "B.Fab")
		)
		(pad "1" smd rect
			(at 0.7366 0 90)
			(size 0.7112 0.8128)
			(layers "B.Cu" "B.Mask" "B.Paste")
			(net "P1V25_PEX2")
		)
		(pad "2" smd rect
			(at -0.7366 0 90)
			(size 0.7112 0.8128)
			(layers "B.Cu" "B.Mask" "B.Paste")
			(net "GND")
		)
	)
	(footprint ""
		(layer "B.Cu")
		(at 166.725092 -286.399732 90)
		(property "Reference" "C3120"
			(at 0 0 90)
			(layer "B.SilkS")
			(hide yes)
			(effects
				(font
					(size 1.27 1.27)
				)
				(justify mirror)
			)
		)
		(property "Value" ""
			(at 0 0 90)
			(layer "B.Fab")
			(effects
				(font
					(size 1.27 1.27)
				)
				(justify mirror)
			)
		)
		(duplicate_pad_numbers_are_jumpers no)
		(fp_line
			(start 0.299974 -0.150114)
			(end -0.299974 -0.150114)
			(stroke
				(width 0.1)
				(type default)
			)
			(layer "B.Fab")
		)
		(fp_line
			(start -0.299974 -0.150114)
			(end -0.299974 0.150114)
			(stroke
				(width 0.1)
				(type default)
			)
			(layer "B.Fab")
		)
		(fp_line
			(start 0.299974 0.150114)
			(end 0.299974 -0.150114)
			(stroke
				(width 0.1)
				(type default)
			)
			(layer "B.Fab")
		)
		(fp_line
			(start -0.299974 0.150114)
			(end 0.299974 0.150114)
			(stroke
				(width 0.1)
				(type default)
			)
			(layer "B.Fab")
		)
		(pad "1" smd rect
			(at 0.2667 0 270)
			(size 0.3048 0.381)
			(layers "B.Cu" "B.Mask" "B.Paste")
			(net "P1V25_SERDES_VDDPLL_PEX1")
		)
		(pad "2" smd rect
			(at -0.2667 0 270)
			(size 0.3048 0.381)
			(layers "B.Cu" "B.Mask" "B.Paste")
			(net "GND")
		)
	)
	(footprint ""
		(layer "B.Cu")
		(at 200.058274 -259.311648 -90)
		(property "Reference" "R6339"
			(at 0 0 90)
			(layer "B.SilkS")
			(hide yes)
			(effects
				(font
					(size 1.27 1.27)
				)
				(justify mirror)
			)
		)
		(property "Value" ""
			(at 0 0 90)
			(layer "B.Fab")
			(effects
				(font
					(size 1.27 1.27)
				)
				(justify mirror)
			)
		)
		(duplicate_pad_numbers_are_jumpers no)
		(fp_line
			(start -0.7874 0.4064)
			(end 0.7874 0.4064)
			(stroke
				(width 0.1524)
				(type default)
			)
			(layer "B.SilkS")
		)
		(fp_line
			(start 0.7874 0.4064)
			(end 0.7874 -0.4064)
			(stroke
				(width 0.1524)
				(type default)
			)
			(layer "B.SilkS")
		)
		(fp_line
			(start -0.7874 -0.4064)
			(end -0.7874 0.4064)
			(stroke
				(width 0.1524)
				(type default)
			)
			(layer "B.SilkS")
		)
		(fp_line
			(start 0.7874 -0.4064)
			(end -0.7874 -0.4064)
			(stroke
				(width 0.1524)
				(type default)
			)
			(layer "B.SilkS")
		)
		(fp_line
			(start -0.67945 0.3048)
			(end -0.120396 0.3048)
			(stroke
				(width 0.1)
				(type default)
			)
			(layer "B.Fab")
		)
		(fp_line
			(start -0.120396 0.3048)
			(end -0.120396 0.2794)
			(stroke
				(width 0.1)
				(type default)
			)
			(layer "B.Fab")
		)
		(fp_line
			(start 0.12065 0.3048)
			(end 0.67945 0.3048)
			(stroke
				(width 0.1)
				(type default)
			)
			(layer "B.Fab")
		)
		(fp_line
			(start 0.67945 0.3048)
			(end 0.67945 -0.305054)
			(stroke
				(width 0.1)
				(type default)
			)
			(layer "B.Fab")
		)
		(fp_line
			(start -0.120396 0.2794)
			(end 0.12065 0.2794)
			(stroke
				(width 0.1)
				(type default)
			)
			(layer "B.Fab")
		)
		(fp_line
			(start 0.12065 0.2794)
			(end 0.12065 0.3048)
			(stroke
				(width 0.1)
				(type default)
			)
			(layer "B.Fab")
		)
		(fp_line
			(start -0.12065 -0.2794)
			(end -0.12065 -0.3048)
			(stroke
				(width 0.1)
				(type default)
			)
			(layer "B.Fab")
		)
		(fp_line
			(start 0.12065 -0.2794)
			(end -0.12065 -0.2794)
			(stroke
				(width 0.1)
				(type default)
			)
			(layer "B.Fab")
		)
		(fp_line
			(start -0.67945 -0.3048)
			(end -0.67945 0.3048)
			(stroke
				(width 0.1)
				(type default)
			)
			(layer "B.Fab")
		)
		(fp_line
			(start -0.12065 -0.3048)
			(end -0.67945 -0.3048)
			(stroke
				(width 0.1)
				(type default)
			)
			(layer "B.Fab")
		)
		(fp_line
			(start 0.12065 -0.305054)
			(end 0.12065 -0.2794)
			(stroke
				(width 0.1)
				(type default)
			)
			(layer "B.Fab")
		)
		(fp_line
			(start 0.67945 -0.305054)
			(end 0.12065 -0.305054)
			(stroke
				(width 0.1)
				(type default)
			)
			(layer "B.Fab")
		)
		(pad "1" smd circle
			(at 0.40005 0 90)
			(size 0 0)
			(layers "B.Cu" "B.Mask" "B.Paste")
			(net "PEX_MUX_A0")
		)
		(pad "2" smd circle
			(at -0.40005 0 90)
			(size 0 0)
			(layers "B.Cu" "B.Mask" "B.Paste")
			(net "GND")
		)
	)
	(footprint ""
		(layer "B.Cu")
		(at 451.298056 -266.996672)
		(property "Reference" "R6138"
			(at 0 0 0)
			(layer "B.SilkS")
			(hide yes)
			(effects
				(font
					(size 1.27 1.27)
				)
				(justify mirror)
			)
		)
		(property "Value" ""
			(at 0 0 0)
			(layer "B.Fab")
			(effects
				(font
					(size 1.27 1.27)
				)
				(justify mirror)
			)
		)
		(duplicate_pad_numbers_are_jumpers no)
		(fp_line
			(start -2.576322 -1.1303)
			(end -2.576322 1.1303)
			(stroke
				(width 0.1524)
				(type default)
			)
			(layer "B.SilkS")
		)
		(fp_line
			(start -2.576322 1.1303)
			(end 2.576322 1.1303)
			(stroke
				(width 0.1524)
				(type default)
			)
			(layer "B.SilkS")
		)
		(fp_line
			(start 2.576322 -1.1303)
			(end -2.576322 -1.1303)
			(stroke
				(width 0.1524)
				(type default)
			)
			(layer "B.SilkS")
		)
		(fp_line
			(start 2.576322 1.1303)
			(end 2.576322 -1.1303)
			(stroke
				(width 0.1524)
				(type default)
			)
			(layer "B.SilkS")
		)
		(fp_line
			(start -1.649984 -0.899922)
			(end 1.649984 -0.899922)
			(stroke
				(width 0.1)
				(type default)
			)
			(layer "B.Fab")
		)
		(fp_line
			(start -1.649984 0.899922)
			(end -1.649984 -0.899922)
			(stroke
				(width 0.1)
				(type default)
			)
			(layer "B.Fab")
		)
		(fp_line
			(start 1.649984 -0.899922)
			(end 1.649984 0.899922)
			(stroke
				(width 0.1)
				(type default)
			)
			(layer "B.Fab")
		)
		(fp_line
			(start 1.649984 0.899922)
			(end -1.649984 0.899922)
			(stroke
				(width 0.1)
				(type default)
			)
			(layer "B.Fab")
		)
		(pad "1A" smd rect
			(at 1.700022 0 180)
			(size 1.4986 2.0066)
			(layers "B.Cu" "B.Mask" "B.Paste")
			(net "P1V25_PEX3")
		)
		(pad "1B" smd rect
			(at 1.077722 0 180)
			(size 0.254 0.508)
			(layers "B.Cu" "B.Mask" "B.Paste")
			(net "P1V25_PEX3")
		)
		(pad "2A" smd rect
			(at -1.700022 0 180)
			(size 1.4986 2.0066)
			(layers "B.Cu" "B.Mask" "B.Paste")
			(net "P1V25_SERDES_VDDPLL_PEX3")
		)
		(pad "2B" smd rect
			(at -1.077722 0 180)
			(size 0.254 0.508)
			(layers "B.Cu" "B.Mask" "B.Paste")
			(net "P1V25_SERDES_VDDPLL_PEX3")
		)
	)
	(footprint ""
		(layer "B.Cu")
		(at 15.365222 -383.98069 180)
		(property "Reference" "C4476"
			(at 0 0 0)
			(layer "B.SilkS")
			(hide yes)
			(effects
				(font
					(size 1.27 1.27)
				)
				(justify mirror)
			)
		)
		(property "Value" ""
			(at 0 0 0)
			(layer "B.Fab")
			(effects
				(font
					(size 1.27 1.27)
				)
				(justify mirror)
			)
		)
		(duplicate_pad_numbers_are_jumpers no)
		(fp_line
			(start 0.7874 0.4064)
			(end 0.7874 -0.4064)
			(stroke
				(width 0.1524)
				(type default)
			)
			(layer "B.SilkS")
		)
		(fp_line
			(start 0.7874 -0.4064)
			(end -0.7874 -0.4064)
			(stroke
				(width 0.1524)
				(type default)
			)
			(layer "B.SilkS")
		)
		(fp_line
			(start -0.7874 0.4064)
			(end 0.7874 0.4064)
			(stroke
				(width 0.1524)
				(type default)
			)
			(layer "B.SilkS")
		)
		(fp_line
			(start -0.7874 -0.4064)
			(end -0.7874 0.4064)
			(stroke
				(width 0.1524)
				(type default)
			)
			(layer "B.SilkS")
		)
		(fp_line
			(start 0.67945 0.3048)
			(end 0.67945 -0.305054)
			(stroke
				(width 0.1)
				(type default)
			)
			(layer "B.Fab")
		)
		(fp_line
			(start 0.67945 -0.305054)
			(end 0.12065 -0.305054)
			(stroke
				(width 0.1)
				(type default)
			)
			(layer "B.Fab")
		)
		(fp_line
			(start 0.12065 0.3048)
			(end 0.67945 0.3048)
			(stroke
				(width 0.1)
				(type default)
			)
			(layer "B.Fab")
		)
		(fp_line
			(start 0.12065 0.2794)
			(end 0.12065 0.3048)
			(stroke
				(width 0.1)
				(type default)
			)
			(layer "B.Fab")
		)
		(fp_line
			(start 0.12065 -0.2794)
			(end -0.12065 -0.2794)
			(stroke
				(width 0.1)
				(type default)
			)
			(layer "B.Fab")
		)
		(fp_line
			(start 0.12065 -0.305054)
			(end 0.12065 -0.2794)
			(stroke
				(width 0.1)
				(type default)
			)
			(layer "B.Fab")
		)
		(fp_line
			(start -0.120396 0.3048)
			(end -0.120396 0.2794)
			(stroke
				(width 0.1)
				(type default)
			)
			(layer "B.Fab")
		)
		(fp_line
			(start -0.120396 0.2794)
			(end 0.12065 0.2794)
			(stroke
				(width 0.1)
				(type default)
			)
			(layer "B.Fab")
		)
		(fp_line
			(start -0.12065 -0.2794)
			(end -0.12065 -0.3048)
			(stroke
				(width 0.1)
				(type default)
			)
			(layer "B.Fab")
		)
		(fp_line
			(start -0.12065 -0.3048)
			(end -0.67945 -0.3048)
			(stroke
				(width 0.1)
				(type default)
			)
			(layer "B.Fab")
		)
		(fp_line
			(start -0.67945 0.3048)
			(end -0.120396 0.3048)
			(stroke
				(width 0.1)
				(type default)
			)
			(layer "B.Fab")
		)
		(fp_line
			(start -0.67945 -0.3048)
			(end -0.67945 0.3048)
			(stroke
				(width 0.1)
				(type default)
			)
			(layer "B.Fab")
		)
		(pad "1" smd circle
			(at 0.40005 0)
			(size 0 0)
			(layers "B.Cu" "B.Mask" "B.Paste")
			(net "P1V2_USB_8042")
		)
		(pad "2" smd circle
			(at -0.40005 0)
			(size 0 0)
			(layers "B.Cu" "B.Mask" "B.Paste")
			(net "GND")
		)
	)
	(footprint ""
		(layer "B.Cu")
		(at 62.499748 -292.099746 90)
		(property "Reference" "C1230"
			(at 0 0 90)
			(layer "B.SilkS")
			(hide yes)
			(effects
				(font
					(size 1.27 1.27)
				)
				(justify mirror)
			)
		)
		(property "Value" ""
			(at 0 0 90)
			(layer "B.Fab")
			(effects
				(font
					(size 1.27 1.27)
				)
				(justify mirror)
			)
		)
		(duplicate_pad_numbers_are_jumpers no)
		(fp_line
			(start 0.299974 -0.150114)
			(end -0.299974 -0.150114)
			(stroke
				(width 0.1)
				(type default)
			)
			(layer "B.Fab")
		)
		(fp_line
			(start -0.299974 -0.150114)
			(end -0.299974 0.150114)
			(stroke
				(width 0.1)
				(type default)
			)
			(layer "B.Fab")
		)
		(fp_line
			(start 0.299974 0.150114)
			(end 0.299974 -0.150114)
			(stroke
				(width 0.1)
				(type default)
			)
			(layer "B.Fab")
		)
		(fp_line
			(start -0.299974 0.150114)
			(end 0.299974 0.150114)
			(stroke
				(width 0.1)
				(type default)
			)
			(layer "B.Fab")
		)
		(pad "1" smd rect
			(at 0.2667 0 270)
			(size 0.3048 0.381)
			(layers "B.Cu" "B.Mask" "B.Paste")
			(net "P0V8_SERDES_VDDA_PEX0")
		)
		(pad "2" smd rect
			(at -0.2667 0 270)
			(size 0.3048 0.381)
			(layers "B.Cu" "B.Mask" "B.Paste")
			(net "GND")
		)
	)
	(footprint ""
		(layer "B.Cu")
		(at 413.649922 -303.499774 -90)
		(property "Reference" "C3426"
			(at 0 0 90)
			(layer "B.SilkS")
			(hide yes)
			(effects
				(font
					(size 1.27 1.27)
				)
				(justify mirror)
			)
		)
		(property "Value" ""
			(at 0 0 90)
			(layer "B.Fab")
			(effects
				(font
					(size 1.27 1.27)
				)
				(justify mirror)
			)
		)
		(duplicate_pad_numbers_are_jumpers no)
		(fp_line
			(start -0.299974 0.150114)
			(end 0.299974 0.150114)
			(stroke
				(width 0.1)
				(type default)
			)
			(layer "B.Fab")
		)
		(fp_line
			(start 0.299974 0.150114)
			(end 0.299974 -0.150114)
			(stroke
				(width 0.1)
				(type default)
			)
			(layer "B.Fab")
		)
		(fp_line
			(start -0.299974 -0.150114)
			(end -0.299974 0.150114)
			(stroke
				(width 0.1)
				(type default)
			)
			(layer "B.Fab")
		)
		(fp_line
			(start 0.299974 -0.150114)
			(end -0.299974 -0.150114)
			(stroke
				(width 0.1)
				(type default)
			)
			(layer "B.Fab")
		)
		(pad "1" smd rect
			(at 0.2667 0 90)
			(size 0.3048 0.381)
			(layers "B.Cu" "B.Mask" "B.Paste")
			(net "P1V25_PEX3")
		)
		(pad "2" smd rect
			(at -0.2667 0 90)
			(size 0.3048 0.381)
			(layers "B.Cu" "B.Mask" "B.Paste")
			(net "GND")
		)
	)
	(footprint ""
		(layer "B.Cu")
		(at 102.782878 -337.481672 -90)
		(property "Reference" "C2696"
			(at 0 0 90)
			(layer "B.SilkS")
			(hide yes)
			(effects
				(font
					(size 1.27 1.27)
				)
				(justify mirror)
			)
		)
		(property "Value" ""
			(at 0 0 90)
			(layer "B.Fab")
			(effects
				(font
					(size 1.27 1.27)
				)
				(justify mirror)
			)
		)
		(duplicate_pad_numbers_are_jumpers no)
		(fp_line
			(start -0.7874 0.4064)
			(end 0.7874 0.4064)
			(stroke
				(width 0.1524)
				(type default)
			)
			(layer "B.SilkS")
		)
		(fp_line
			(start 0.7874 0.4064)
			(end 0.7874 -0.4064)
			(stroke
				(width 0.1524)
				(type default)
			)
			(layer "B.SilkS")
		)
		(fp_line
			(start -0.7874 -0.4064)
			(end -0.7874 0.4064)
			(stroke
				(width 0.1524)
				(type default)
			)
			(layer "B.SilkS")
		)
		(fp_line
			(start 0.7874 -0.4064)
			(end -0.7874 -0.4064)
			(stroke
				(width 0.1524)
				(type default)
			)
			(layer "B.SilkS")
		)
		(fp_line
			(start -0.67945 0.3048)
			(end -0.120396 0.3048)
			(stroke
				(width 0.1)
				(type default)
			)
			(layer "B.Fab")
		)
		(fp_line
			(start -0.120396 0.3048)
			(end -0.120396 0.2794)
			(stroke
				(width 0.1)
				(type default)
			)
			(layer "B.Fab")
		)
		(fp_line
			(start 0.12065 0.3048)
			(end 0.67945 0.3048)
			(stroke
				(width 0.1)
				(type default)
			)
			(layer "B.Fab")
		)
		(fp_line
			(start 0.67945 0.3048)
			(end 0.67945 -0.305054)
			(stroke
				(width 0.1)
				(type default)
			)
			(layer "B.Fab")
		)
		(fp_line
			(start -0.120396 0.2794)
			(end 0.12065 0.2794)
			(stroke
				(width 0.1)
				(type default)
			)
			(layer "B.Fab")
		)
		(fp_line
			(start 0.12065 0.2794)
			(end 0.12065 0.3048)
			(stroke
				(width 0.1)
				(type default)
			)
			(layer "B.Fab")
		)
		(fp_line
			(start -0.12065 -0.2794)
			(end -0.12065 -0.3048)
			(stroke
				(width 0.1)
				(type default)
			)
			(layer "B.Fab")
		)
		(fp_line
			(start 0.12065 -0.2794)
			(end -0.12065 -0.2794)
			(stroke
				(width 0.1)
				(type default)
			)
			(layer "B.Fab")
		)
		(fp_line
			(start -0.67945 -0.3048)
			(end -0.67945 0.3048)
			(stroke
				(width 0.1)
				(type default)
			)
			(layer "B.Fab")
		)
		(fp_line
			(start -0.12065 -0.3048)
			(end -0.67945 -0.3048)
			(stroke
				(width 0.1)
				(type default)
			)
			(layer "B.Fab")
		)
		(fp_line
			(start 0.12065 -0.305054)
			(end 0.12065 -0.2794)
			(stroke
				(width 0.1)
				(type default)
			)
			(layer "B.Fab")
		)
		(fp_line
			(start 0.67945 -0.305054)
			(end 0.12065 -0.305054)
			(stroke
				(width 0.1)
				(type default)
			)
			(layer "B.Fab")
		)
		(pad "1" smd circle
			(at 0.40005 0 90)
			(size 0 0)
			(layers "B.Cu" "B.Mask" "B.Paste")
			(net "P3V3_CLK_BUFFER_9ZXL0451E_VZX3P3")
		)
		(pad "2" smd circle
			(at -0.40005 0 90)
			(size 0 0)
			(layers "B.Cu" "B.Mask" "B.Paste")
			(net "GND")
		)
	)
	(footprint ""
		(layer "B.Cu")
		(at 408.899868 -303.499774 -90)
		(property "Reference" "C3434"
			(at 0 0 90)
			(layer "B.SilkS")
			(hide yes)
			(effects
				(font
					(size 1.27 1.27)
				)
				(justify mirror)
			)
		)
		(property "Value" ""
			(at 0 0 90)
			(layer "B.Fab")
			(effects
				(font
					(size 1.27 1.27)
				)
				(justify mirror)
			)
		)
		(duplicate_pad_numbers_are_jumpers no)
		(fp_line
			(start -0.299974 0.150114)
			(end 0.299974 0.150114)
			(stroke
				(width 0.1)
				(type default)
			)
			(layer "B.Fab")
		)
		(fp_line
			(start 0.299974 0.150114)
			(end 0.299974 -0.150114)
			(stroke
				(width 0.1)
				(type default)
			)
			(layer "B.Fab")
		)
		(fp_line
			(start -0.299974 -0.150114)
			(end -0.299974 0.150114)
			(stroke
				(width 0.1)
				(type default)
			)
			(layer "B.Fab")
		)
		(fp_line
			(start 0.299974 -0.150114)
			(end -0.299974 -0.150114)
			(stroke
				(width 0.1)
				(type default)
			)
			(layer "B.Fab")
		)
		(pad "1" smd rect
			(at 0.2667 0 90)
			(size 0.3048 0.381)
			(layers "B.Cu" "B.Mask" "B.Paste")
			(net "P1V25_PEX3")
		)
		(pad "2" smd rect
			(at -0.2667 0 90)
			(size 0.3048 0.381)
			(layers "B.Cu" "B.Mask" "B.Paste")
			(net "GND")
		)
	)
	(footprint ""
		(layer "B.Cu")
		(at 222.726758 -279.910032 -90)
		(property "Reference" "C4292"
			(at 0 0 90)
			(layer "B.SilkS")
			(hide yes)
			(effects
				(font
					(size 1.27 1.27)
				)
				(justify mirror)
			)
		)
		(property "Value" ""
			(at 0 0 90)
			(layer "B.Fab")
			(effects
				(font
					(size 1.27 1.27)
				)
				(justify mirror)
			)
		)
		(duplicate_pad_numbers_are_jumpers no)
		(fp_line
			(start -0.299974 0.150114)
			(end 0.299974 0.150114)
			(stroke
				(width 0.1)
				(type default)
			)
			(layer "B.Fab")
		)
		(fp_line
			(start 0.299974 0.150114)
			(end 0.299974 -0.150114)
			(stroke
				(width 0.1)
				(type default)
			)
			(layer "B.Fab")
		)
		(fp_line
			(start -0.299974 -0.150114)
			(end -0.299974 0.150114)
			(stroke
				(width 0.1)
				(type default)
			)
			(layer "B.Fab")
		)
		(fp_line
			(start 0.299974 -0.150114)
			(end -0.299974 -0.150114)
			(stroke
				(width 0.1)
				(type default)
			)
			(layer "B.Fab")
		)
		(pad "1" smd rect
			(at 0.2667 0 90)
			(size 0.3048 0.381)
			(layers "B.Cu" "B.Mask" "B.Paste")
			(net "P1V25_PEX1")
		)
		(pad "2" smd rect
			(at -0.2667 0 90)
			(size 0.3048 0.381)
			(layers "B.Cu" "B.Mask" "B.Paste")
			(net "GND")
		)
	)
	(footprint ""
		(layer "B.Cu")
		(at 388.473696 -295.79824 180)
		(property "Reference" "R3494"
			(at 0 0 0)
			(layer "B.SilkS")
			(hide yes)
			(effects
				(font
					(size 1.27 1.27)
				)
				(justify mirror)
			)
		)
		(property "Value" ""
			(at 0 0 0)
			(layer "B.Fab")
			(effects
				(font
					(size 1.27 1.27)
				)
				(justify mirror)
			)
		)
		(duplicate_pad_numbers_are_jumpers no)
		(fp_line
			(start 0.7874 0.4064)
			(end 0.7874 -0.4064)
			(stroke
				(width 0.1524)
				(type default)
			)
			(layer "B.SilkS")
		)
		(fp_line
			(start 0.7874 -0.4064)
			(end -0.7874 -0.4064)
			(stroke
				(width 0.1524)
				(type default)
			)
			(layer "B.SilkS")
		)
		(fp_line
			(start -0.7874 0.4064)
			(end 0.7874 0.4064)
			(stroke
				(width 0.1524)
				(type default)
			)
			(layer "B.SilkS")
		)
		(fp_line
			(start -0.7874 -0.4064)
			(end -0.7874 0.4064)
			(stroke
				(width 0.1524)
				(type default)
			)
			(layer "B.SilkS")
		)
		(fp_line
			(start 0.67945 0.3048)
			(end 0.67945 -0.305054)
			(stroke
				(width 0.1)
				(type default)
			)
			(layer "B.Fab")
		)
		(fp_line
			(start 0.67945 -0.305054)
			(end 0.12065 -0.305054)
			(stroke
				(width 0.1)
				(type default)
			)
			(layer "B.Fab")
		)
		(fp_line
			(start 0.12065 0.3048)
			(end 0.67945 0.3048)
			(stroke
				(width 0.1)
				(type default)
			)
			(layer "B.Fab")
		)
		(fp_line
			(start 0.12065 0.2794)
			(end 0.12065 0.3048)
			(stroke
				(width 0.1)
				(type default)
			)
			(layer "B.Fab")
		)
		(fp_line
			(start 0.12065 -0.2794)
			(end -0.12065 -0.2794)
			(stroke
				(width 0.1)
				(type default)
			)
			(layer "B.Fab")
		)
		(fp_line
			(start 0.12065 -0.305054)
			(end 0.12065 -0.2794)
			(stroke
				(width 0.1)
				(type default)
			)
			(layer "B.Fab")
		)
		(fp_line
			(start -0.120396 0.3048)
			(end -0.120396 0.2794)
			(stroke
				(width 0.1)
				(type default)
			)
			(layer "B.Fab")
		)
		(fp_line
			(start -0.120396 0.2794)
			(end 0.12065 0.2794)
			(stroke
				(width 0.1)
				(type default)
			)
			(layer "B.Fab")
		)
		(fp_line
			(start -0.12065 -0.2794)
			(end -0.12065 -0.3048)
			(stroke
				(width 0.1)
				(type default)
			)
			(layer "B.Fab")
		)
		(fp_line
			(start -0.12065 -0.3048)
			(end -0.67945 -0.3048)
			(stroke
				(width 0.1)
				(type default)
			)
			(layer "B.Fab")
		)
		(fp_line
			(start -0.67945 0.3048)
			(end -0.120396 0.3048)
			(stroke
				(width 0.1)
				(type default)
			)
			(layer "B.Fab")
		)
		(fp_line
			(start -0.67945 -0.3048)
			(end -0.67945 0.3048)
			(stroke
				(width 0.1)
				(type default)
			)
			(layer "B.Fab")
		)
		(pad "1" smd circle
			(at 0.40005 0)
			(size 0 0)
			(layers "B.Cu" "B.Mask" "B.Paste")
			(net "SPI_PEX3_SDIO0_R")
		)
		(pad "2" smd circle
			(at -0.40005 0)
			(size 0 0)
			(layers "B.Cu" "B.Mask" "B.Paste")
			(net "SPI_PEX3_SDIO0")
		)
	)
	(footprint ""
		(layer "B.Cu")
		(at 63.924942 -286.399732 90)
		(property "Reference" "C2968"
			(at 0 0 90)
			(layer "B.SilkS")
			(hide yes)
			(effects
				(font
					(size 1.27 1.27)
				)
				(justify mirror)
			)
		)
		(property "Value" ""
			(at 0 0 90)
			(layer "B.Fab")
			(effects
				(font
					(size 1.27 1.27)
				)
				(justify mirror)
			)
		)
		(duplicate_pad_numbers_are_jumpers no)
		(fp_line
			(start 0.299974 -0.150114)
			(end -0.299974 -0.150114)
			(stroke
				(width 0.1)
				(type default)
			)
			(layer "B.Fab")
		)
		(fp_line
			(start -0.299974 -0.150114)
			(end -0.299974 0.150114)
			(stroke
				(width 0.1)
				(type default)
			)
			(layer "B.Fab")
		)
		(fp_line
			(start 0.299974 0.150114)
			(end 0.299974 -0.150114)
			(stroke
				(width 0.1)
				(type default)
			)
			(layer "B.Fab")
		)
		(fp_line
			(start -0.299974 0.150114)
			(end 0.299974 0.150114)
			(stroke
				(width 0.1)
				(type default)
			)
			(layer "B.Fab")
		)
		(pad "1" smd rect
			(at 0.2667 0 270)
			(size 0.3048 0.381)
			(layers "B.Cu" "B.Mask" "B.Paste")
			(net "P1V25_SERDES_VDDPLL_PEX0")
		)
		(pad "2" smd rect
			(at -0.2667 0 270)
			(size 0.3048 0.381)
			(layers "B.Cu" "B.Mask" "B.Paste")
			(net "GND")
		)
	)
	(footprint ""
		(layer "B.Cu")
		(at 279.977342 -300.7995 -90)
		(property "Reference" "C3370"
			(at 0 0 90)
			(layer "B.SilkS")
			(hide yes)
			(effects
				(font
					(size 1.27 1.27)
				)
				(justify mirror)
			)
		)
		(property "Value" ""
			(at 0 0 90)
			(layer "B.Fab")
			(effects
				(font
					(size 1.27 1.27)
				)
				(justify mirror)
			)
		)
		(duplicate_pad_numbers_are_jumpers no)
		(fp_line
			(start -0.299974 0.150114)
			(end 0.299974 0.150114)
			(stroke
				(width 0.1)
				(type default)
			)
			(layer "B.Fab")
		)
		(fp_line
			(start 0.299974 0.150114)
			(end 0.299974 -0.150114)
			(stroke
				(width 0.1)
				(type default)
			)
			(layer "B.Fab")
		)
		(fp_line
			(start -0.299974 -0.150114)
			(end -0.299974 0.150114)
			(stroke
				(width 0.1)
				(type default)
			)
			(layer "B.Fab")
		)
		(fp_line
			(start 0.299974 -0.150114)
			(end -0.299974 -0.150114)
			(stroke
				(width 0.1)
				(type default)
			)
			(layer "B.Fab")
		)
		(pad "1" smd rect
			(at 0.2667 0 90)
			(size 0.3048 0.381)
			(layers "B.Cu" "B.Mask" "B.Paste")
			(net "PCEPLL0_VDDA18_PEX2")
		)
		(pad "2" smd rect
			(at -0.2667 0 90)
			(size 0.3048 0.381)
			(layers "B.Cu" "B.Mask" "B.Paste")
			(net "GND")
		)
	)
	(footprint ""
		(layer "B.Cu")
		(at 217.665808 -276.672294)
		(property "Reference" "C4275"
			(at 0 0 0)
			(layer "B.SilkS")
			(hide yes)
			(effects
				(font
					(size 1.27 1.27)
				)
				(justify mirror)
			)
		)
		(property "Value" ""
			(at 0 0 0)
			(layer "B.Fab")
			(effects
				(font
					(size 1.27 1.27)
				)
				(justify mirror)
			)
		)
		(duplicate_pad_numbers_are_jumpers no)
		(fp_line
			(start -1.2954 -0.5842)
			(end -1.2954 0.5842)
			(stroke
				(width 0.1524)
				(type default)
			)
			(layer "B.SilkS")
		)
		(fp_line
			(start -1.2954 0.5842)
			(end 1.2954 0.5842)
			(stroke
				(width 0.1524)
				(type default)
			)
			(layer "B.SilkS")
		)
		(fp_line
			(start 1.2954 -0.5842)
			(end -1.2954 -0.5842)
			(stroke
				(width 0.1524)
				(type default)
			)
			(layer "B.SilkS")
		)
		(fp_line
			(start 1.2954 0.5842)
			(end 1.2954 -0.5842)
			(stroke
				(width 0.1524)
				(type default)
			)
			(layer "B.SilkS")
		)
		(fp_line
			(start -1.1938 -0.4064)
			(end -1.1938 0.4064)
			(stroke
				(width 0.1)
				(type default)
			)
			(layer "B.Fab")
		)
		(fp_line
			(start -1.1938 0.4064)
			(end -0.8636 0.4064)
			(stroke
				(width 0.1)
				(type default)
			)
			(layer "B.Fab")
		)
		(fp_line
			(start -0.8636 -0.4572)
			(end -0.8636 -0.4064)
			(stroke
				(width 0.1)
				(type default)
			)
			(layer "B.Fab")
		)
		(fp_line
			(start -0.8636 -0.4064)
			(end -1.1938 -0.4064)
			(stroke
				(width 0.1)
				(type default)
			)
			(layer "B.Fab")
		)
		(fp_line
			(start -0.8636 0.4064)
			(end -0.8636 0.4572)
			(stroke
				(width 0.1)
				(type default)
			)
			(layer "B.Fab")
		)
		(fp_line
			(start -0.8636 0.4572)
			(end 0.8636 0.4572)
			(stroke
				(width 0.1)
				(type default)
			)
			(layer "B.Fab")
		)
		(fp_line
			(start 0.8636 -0.4572)
			(end -0.8636 -0.4572)
			(stroke
				(width 0.1)
				(type default)
			)
			(layer "B.Fab")
		)
		(fp_line
			(start 0.8636 -0.4064)
			(end 0.8636 -0.4572)
			(stroke
				(width 0.1)
				(type default)
			)
			(layer "B.Fab")
		)
		(fp_line
			(start 0.8636 0.4064)
			(end 1.1938 0.4064)
			(stroke
				(width 0.1)
				(type default)
			)
			(layer "B.Fab")
		)
		(fp_line
			(start 0.8636 0.4572)
			(end 0.8636 0.4064)
			(stroke
				(width 0.1)
				(type default)
			)
			(layer "B.Fab")
		)
		(fp_line
			(start 1.1938 -0.4064)
			(end 0.8636 -0.4064)
			(stroke
				(width 0.1)
				(type default)
			)
			(layer "B.Fab")
		)
		(fp_line
			(start 1.1938 0.4064)
			(end 1.1938 -0.4064)
			(stroke
				(width 0.1)
				(type default)
			)
			(layer "B.Fab")
		)
		(pad "1" smd rect
			(at 0.7366 0 270)
			(size 0.7112 0.8128)
			(layers "B.Cu" "B.Mask" "B.Paste")
			(net "P1V25_PEX1")
		)
		(pad "2" smd rect
			(at -0.7366 0 270)
			(size 0.7112 0.8128)
			(layers "B.Cu" "B.Mask" "B.Paste")
			(net "GND")
		)
	)
	(footprint ""
		(layer "B.Cu")
		(at 22.507702 -173.1772 180)
		(property "Reference" "R4429"
			(at 0 0 0)
			(layer "B.SilkS")
			(hide yes)
			(effects
				(font
					(size 1.27 1.27)
				)
				(justify mirror)
			)
		)
		(property "Value" ""
			(at 0 0 0)
			(layer "B.Fab")
			(effects
				(font
					(size 1.27 1.27)
				)
				(justify mirror)
			)
		)
		(duplicate_pad_numbers_are_jumpers no)
		(fp_line
			(start 0.7874 0.4064)
			(end 0.7874 -0.4064)
			(stroke
				(width 0.1524)
				(type default)
			)
			(layer "B.SilkS")
		)
		(fp_line
			(start 0.7874 -0.4064)
			(end -0.7874 -0.4064)
			(stroke
				(width 0.1524)
				(type default)
			)
			(layer "B.SilkS")
		)
		(fp_line
			(start -0.7874 0.4064)
			(end 0.7874 0.4064)
			(stroke
				(width 0.1524)
				(type default)
			)
			(layer "B.SilkS")
		)
		(fp_line
			(start -0.7874 -0.4064)
			(end -0.7874 0.4064)
			(stroke
				(width 0.1524)
				(type default)
			)
			(layer "B.SilkS")
		)
		(fp_line
			(start 0.67945 0.3048)
			(end 0.67945 -0.305054)
			(stroke
				(width 0.1)
				(type default)
			)
			(layer "B.Fab")
		)
		(fp_line
			(start 0.67945 -0.305054)
			(end 0.12065 -0.305054)
			(stroke
				(width 0.1)
				(type default)
			)
			(layer "B.Fab")
		)
		(fp_line
			(start 0.12065 0.3048)
			(end 0.67945 0.3048)
			(stroke
				(width 0.1)
				(type default)
			)
			(layer "B.Fab")
		)
		(fp_line
			(start 0.12065 0.2794)
			(end 0.12065 0.3048)
			(stroke
				(width 0.1)
				(type default)
			)
			(layer "B.Fab")
		)
		(fp_line
			(start 0.12065 -0.2794)
			(end -0.12065 -0.2794)
			(stroke
				(width 0.1)
				(type default)
			)
			(layer "B.Fab")
		)
		(fp_line
			(start 0.12065 -0.305054)
			(end 0.12065 -0.2794)
			(stroke
				(width 0.1)
				(type default)
			)
			(layer "B.Fab")
		)
		(fp_line
			(start -0.120396 0.3048)
			(end -0.120396 0.2794)
			(stroke
				(width 0.1)
				(type default)
			)
			(layer "B.Fab")
		)
		(fp_line
			(start -0.120396 0.2794)
			(end 0.12065 0.2794)
			(stroke
				(width 0.1)
				(type default)
			)
			(layer "B.Fab")
		)
		(fp_line
			(start -0.12065 -0.2794)
			(end -0.12065 -0.3048)
			(stroke
				(width 0.1)
				(type default)
			)
			(layer "B.Fab")
		)
		(fp_line
			(start -0.12065 -0.3048)
			(end -0.67945 -0.3048)
			(stroke
				(width 0.1)
				(type default)
			)
			(layer "B.Fab")
		)
		(fp_line
			(start -0.67945 0.3048)
			(end -0.120396 0.3048)
			(stroke
				(width 0.1)
				(type default)
			)
			(layer "B.Fab")
		)
		(fp_line
			(start -0.67945 -0.3048)
			(end -0.67945 0.3048)
			(stroke
				(width 0.1)
				(type default)
			)
			(layer "B.Fab")
		)
		(pad "1" smd circle
			(at 0.40005 0)
			(size 0 0)
			(layers "B.Cu" "B.Mask" "B.Paste")
			(net "PWRGD_P5V_AUX")
		)
		(pad "2" smd circle
			(at -0.40005 0)
			(size 0 0)
			(layers "B.Cu" "B.Mask" "B.Paste")
			(net "PWRGD_P5V_AUX_R")
		)
	)
	(footprint ""
		(layer "B.Cu")
		(at 409.849828 -288.299906 90)
		(property "Reference" "C3447"
			(at 0 0 90)
			(layer "B.SilkS")
			(hide yes)
			(effects
				(font
					(size 1.27 1.27)
				)
				(justify mirror)
			)
		)
		(property "Value" ""
			(at 0 0 90)
			(layer "B.Fab")
			(effects
				(font
					(size 1.27 1.27)
				)
				(justify mirror)
			)
		)
		(duplicate_pad_numbers_are_jumpers no)
		(fp_line
			(start 0.299974 -0.150114)
			(end -0.299974 -0.150114)
			(stroke
				(width 0.1)
				(type default)
			)
			(layer "B.Fab")
		)
		(fp_line
			(start -0.299974 -0.150114)
			(end -0.299974 0.150114)
			(stroke
				(width 0.1)
				(type default)
			)
			(layer "B.Fab")
		)
		(fp_line
			(start 0.299974 0.150114)
			(end 0.299974 -0.150114)
			(stroke
				(width 0.1)
				(type default)
			)
			(layer "B.Fab")
		)
		(fp_line
			(start -0.299974 0.150114)
			(end 0.299974 0.150114)
			(stroke
				(width 0.1)
				(type default)
			)
			(layer "B.Fab")
		)
		(pad "1" smd rect
			(at 0.2667 0 270)
			(size 0.3048 0.381)
			(layers "B.Cu" "B.Mask" "B.Paste")
			(net "P1V25_PEX3")
		)
		(pad "2" smd rect
			(at -0.2667 0 270)
			(size 0.3048 0.381)
			(layers "B.Cu" "B.Mask" "B.Paste")
			(net "GND")
		)
	)
	(footprint ""
		(layer "B.Cu")
		(at 278.326342 -139.8016 180)
		(property "Reference" "C914"
			(at 0 0 0)
			(layer "B.SilkS")
			(hide yes)
			(effects
				(font
					(size 1.27 1.27)
				)
				(justify mirror)
			)
		)
		(property "Value" ""
			(at 0 0 0)
			(layer "B.Fab")
			(effects
				(font
					(size 1.27 1.27)
				)
				(justify mirror)
			)
		)
		(duplicate_pad_numbers_are_jumpers no)
		(fp_line
			(start 0.7874 0.4064)
			(end 0.7874 -0.4064)
			(stroke
				(width 0.1524)
				(type default)
			)
			(layer "B.SilkS")
		)
		(fp_line
			(start 0.7874 -0.4064)
			(end -0.7874 -0.4064)
			(stroke
				(width 0.1524)
				(type default)
			)
			(layer "B.SilkS")
		)
		(fp_line
			(start -0.7874 0.4064)
			(end 0.7874 0.4064)
			(stroke
				(width 0.1524)
				(type default)
			)
			(layer "B.SilkS")
		)
		(fp_line
			(start -0.7874 -0.4064)
			(end -0.7874 0.4064)
			(stroke
				(width 0.1524)
				(type default)
			)
			(layer "B.SilkS")
		)
		(fp_line
			(start 0.67945 0.3048)
			(end 0.67945 -0.305054)
			(stroke
				(width 0.1)
				(type default)
			)
			(layer "B.Fab")
		)
		(fp_line
			(start 0.67945 -0.305054)
			(end 0.12065 -0.305054)
			(stroke
				(width 0.1)
				(type default)
			)
			(layer "B.Fab")
		)
		(fp_line
			(start 0.12065 0.3048)
			(end 0.67945 0.3048)
			(stroke
				(width 0.1)
				(type default)
			)
			(layer "B.Fab")
		)
		(fp_line
			(start 0.12065 0.2794)
			(end 0.12065 0.3048)
			(stroke
				(width 0.1)
				(type default)
			)
			(layer "B.Fab")
		)
		(fp_line
			(start 0.12065 -0.2794)
			(end -0.12065 -0.2794)
			(stroke
				(width 0.1)
				(type default)
			)
			(layer "B.Fab")
		)
		(fp_line
			(start 0.12065 -0.305054)
			(end 0.12065 -0.2794)
			(stroke
				(width 0.1)
				(type default)
			)
			(layer "B.Fab")
		)
		(fp_line
			(start -0.120396 0.3048)
			(end -0.120396 0.2794)
			(stroke
				(width 0.1)
				(type default)
			)
			(layer "B.Fab")
		)
		(fp_line
			(start -0.120396 0.2794)
			(end 0.12065 0.2794)
			(stroke
				(width 0.1)
				(type default)
			)
			(layer "B.Fab")
		)
		(fp_line
			(start -0.12065 -0.2794)
			(end -0.12065 -0.3048)
			(stroke
				(width 0.1)
				(type default)
			)
			(layer "B.Fab")
		)
		(fp_line
			(start -0.12065 -0.3048)
			(end -0.67945 -0.3048)
			(stroke
				(width 0.1)
				(type default)
			)
			(layer "B.Fab")
		)
		(fp_line
			(start -0.67945 0.3048)
			(end -0.120396 0.3048)
			(stroke
				(width 0.1)
				(type default)
			)
			(layer "B.Fab")
		)
		(fp_line
			(start -0.67945 -0.3048)
			(end -0.67945 0.3048)
			(stroke
				(width 0.1)
				(type default)
			)
			(layer "B.Fab")
		)
		(pad "1" smd circle
			(at 0.40005 0)
			(size 0 0)
			(layers "B.Cu" "B.Mask" "B.Paste")
			(net "P3V3_NIC4")
		)
		(pad "2" smd circle
			(at -0.40005 0)
			(size 0 0)
			(layers "B.Cu" "B.Mask" "B.Paste")
			(net "GND")
		)
	)
	(footprint ""
		(layer "B.Cu")
		(at 408.899868 -299.699934 -90)
		(property "Reference" "C1943"
			(at 0 0 90)
			(layer "B.SilkS")
			(hide yes)
			(effects
				(font
					(size 1.27 1.27)
				)
				(justify mirror)
			)
		)
		(property "Value" ""
			(at 0 0 90)
			(layer "B.Fab")
			(effects
				(font
					(size 1.27 1.27)
				)
				(justify mirror)
			)
		)
		(duplicate_pad_numbers_are_jumpers no)
		(fp_line
			(start -0.299974 0.150114)
			(end 0.299974 0.150114)
			(stroke
				(width 0.1)
				(type default)
			)
			(layer "B.Fab")
		)
		(fp_line
			(start 0.299974 0.150114)
			(end 0.299974 -0.150114)
			(stroke
				(width 0.1)
				(type default)
			)
			(layer "B.Fab")
		)
		(fp_line
			(start -0.299974 -0.150114)
			(end -0.299974 0.150114)
			(stroke
				(width 0.1)
				(type default)
			)
			(layer "B.Fab")
		)
		(fp_line
			(start 0.299974 -0.150114)
			(end -0.299974 -0.150114)
			(stroke
				(width 0.1)
				(type default)
			)
			(layer "B.Fab")
		)
		(pad "1" smd rect
			(at 0.2667 0 90)
			(size 0.3048 0.381)
			(layers "B.Cu" "B.Mask" "B.Paste")
			(net "P0V8_SERDES_VDDA_PEX3")
		)
		(pad "2" smd rect
			(at -0.2667 0 90)
			(size 0.3048 0.381)
			(layers "B.Cu" "B.Mask" "B.Paste")
			(net "GND")
		)
	)
	(footprint ""
		(layer "B.Cu")
		(at 293.74973 -292.099746 90)
		(property "Reference" "C1742"
			(at 0 0 90)
			(layer "B.SilkS")
			(hide yes)
			(effects
				(font
					(size 1.27 1.27)
				)
				(justify mirror)
			)
		)
		(property "Value" ""
			(at 0 0 90)
			(layer "B.Fab")
			(effects
				(font
					(size 1.27 1.27)
				)
				(justify mirror)
			)
		)
		(duplicate_pad_numbers_are_jumpers no)
		(fp_line
			(start 0.299974 -0.150114)
			(end -0.299974 -0.150114)
			(stroke
				(width 0.1)
				(type default)
			)
			(layer "B.Fab")
		)
		(fp_line
			(start -0.299974 -0.150114)
			(end -0.299974 0.150114)
			(stroke
				(width 0.1)
				(type default)
			)
			(layer "B.Fab")
		)
		(fp_line
			(start 0.299974 0.150114)
			(end 0.299974 -0.150114)
			(stroke
				(width 0.1)
				(type default)
			)
			(layer "B.Fab")
		)
		(fp_line
			(start -0.299974 0.150114)
			(end 0.299974 0.150114)
			(stroke
				(width 0.1)
				(type default)
			)
			(layer "B.Fab")
		)
		(pad "1" smd rect
			(at 0.2667 0 270)
			(size 0.3048 0.381)
			(layers "B.Cu" "B.Mask" "B.Paste")
			(net "P0V8_SERDES_VDDA_PEX2")
		)
		(pad "2" smd rect
			(at -0.2667 0 270)
			(size 0.3048 0.381)
			(layers "B.Cu" "B.Mask" "B.Paste")
			(net "GND")
		)
	)
	(footprint ""
		(layer "B.Cu")
		(at 424.02379 -289.724846 90)
		(property "Reference" "R969"
			(at 0 0 90)
			(layer "B.SilkS")
			(hide yes)
			(effects
				(font
					(size 1.27 1.27)
				)
				(justify mirror)
			)
		)
		(property "Value" ""
			(at 0 0 90)
			(layer "B.Fab")
			(effects
				(font
					(size 1.27 1.27)
				)
				(justify mirror)
			)
		)
		(duplicate_pad_numbers_are_jumpers no)
		(fp_line
			(start 0.7874 -0.4064)
			(end -0.7874 -0.4064)
			(stroke
				(width 0.1524)
				(type default)
			)
			(layer "B.SilkS")
		)
		(fp_line
			(start -0.7874 -0.4064)
			(end -0.7874 0.4064)
			(stroke
				(width 0.1524)
				(type default)
			)
			(layer "B.SilkS")
		)
		(fp_line
			(start 0.7874 0.4064)
			(end 0.7874 -0.4064)
			(stroke
				(width 0.1524)
				(type default)
			)
			(layer "B.SilkS")
		)
		(fp_line
			(start -0.7874 0.4064)
			(end 0.7874 0.4064)
			(stroke
				(width 0.1524)
				(type default)
			)
			(layer "B.SilkS")
		)
		(fp_line
			(start 0.67945 -0.305054)
			(end 0.12065 -0.305054)
			(stroke
				(width 0.1)
				(type default)
			)
			(layer "B.Fab")
		)
		(fp_line
			(start 0.12065 -0.305054)
			(end 0.12065 -0.2794)
			(stroke
				(width 0.1)
				(type default)
			)
			(layer "B.Fab")
		)
		(fp_line
			(start -0.12065 -0.3048)
			(end -0.67945 -0.3048)
			(stroke
				(width 0.1)
				(type default)
			)
			(layer "B.Fab")
		)
		(fp_line
			(start -0.67945 -0.3048)
			(end -0.67945 0.3048)
			(stroke
				(width 0.1)
				(type default)
			)
			(layer "B.Fab")
		)
		(fp_line
			(start 0.12065 -0.2794)
			(end -0.12065 -0.2794)
			(stroke
				(width 0.1)
				(type default)
			)
			(layer "B.Fab")
		)
		(fp_line
			(start -0.12065 -0.2794)
			(end -0.12065 -0.3048)
			(stroke
				(width 0.1)
				(type default)
			)
			(layer "B.Fab")
		)
		(fp_line
			(start 0.12065 0.2794)
			(end 0.12065 0.3048)
			(stroke
				(width 0.1)
				(type default)
			)
			(layer "B.Fab")
		)
		(fp_line
			(start -0.120396 0.2794)
			(end 0.12065 0.2794)
			(stroke
				(width 0.1)
				(type default)
			)
			(layer "B.Fab")
		)
		(fp_line
			(start 0.67945 0.3048)
			(end 0.67945 -0.305054)
			(stroke
				(width 0.1)
				(type default)
			)
			(layer "B.Fab")
		)
		(fp_line
			(start 0.12065 0.3048)
			(end 0.67945 0.3048)
			(stroke
				(width 0.1)
				(type default)
			)
			(layer "B.Fab")
		)
		(fp_line
			(start -0.120396 0.3048)
			(end -0.120396 0.2794)
			(stroke
				(width 0.1)
				(type default)
			)
			(layer "B.Fab")
		)
		(fp_line
			(start -0.67945 0.3048)
			(end -0.120396 0.3048)
			(stroke
				(width 0.1)
				(type default)
			)
			(layer "B.Fab")
		)
		(pad "1" smd circle
			(at 0.40005 0 270)
			(size 0 0)
			(layers "B.Cu" "B.Mask" "B.Paste")
			(net "UART_PEX3_SDB_TX")
		)
		(pad "2" smd circle
			(at -0.40005 0 270)
			(size 0 0)
			(layers "B.Cu" "B.Mask" "B.Paste")
			(net "UART_PEX3_SDB_R_TX")
		)
	)
	(footprint ""
		(layer "B.Cu")
		(at 248.940574 -91.918028 90)
		(property "Reference" "R1077"
			(at 0 0 90)
			(layer "B.SilkS")
			(hide yes)
			(effects
				(font
					(size 1.27 1.27)
				)
				(justify mirror)
			)
		)
		(property "Value" ""
			(at 0 0 90)
			(layer "B.Fab")
			(effects
				(font
					(size 1.27 1.27)
				)
				(justify mirror)
			)
		)
		(duplicate_pad_numbers_are_jumpers no)
		(fp_line
			(start 0.7874 -0.4064)
			(end -0.7874 -0.4064)
			(stroke
				(width 0.1524)
				(type default)
			)
			(layer "B.SilkS")
		)
		(fp_line
			(start -0.7874 -0.4064)
			(end -0.7874 0.4064)
			(stroke
				(width 0.1524)
				(type default)
			)
			(layer "B.SilkS")
		)
		(fp_line
			(start 0.7874 0.4064)
			(end 0.7874 -0.4064)
			(stroke
				(width 0.1524)
				(type default)
			)
			(layer "B.SilkS")
		)
		(fp_line
			(start -0.7874 0.4064)
			(end 0.7874 0.4064)
			(stroke
				(width 0.1524)
				(type default)
			)
			(layer "B.SilkS")
		)
		(fp_line
			(start 0.67945 -0.305054)
			(end 0.12065 -0.305054)
			(stroke
				(width 0.1)
				(type default)
			)
			(layer "B.Fab")
		)
		(fp_line
			(start 0.12065 -0.305054)
			(end 0.12065 -0.2794)
			(stroke
				(width 0.1)
				(type default)
			)
			(layer "B.Fab")
		)
		(fp_line
			(start -0.12065 -0.3048)
			(end -0.67945 -0.3048)
			(stroke
				(width 0.1)
				(type default)
			)
			(layer "B.Fab")
		)
		(fp_line
			(start -0.67945 -0.3048)
			(end -0.67945 0.3048)
			(stroke
				(width 0.1)
				(type default)
			)
			(layer "B.Fab")
		)
		(fp_line
			(start 0.12065 -0.2794)
			(end -0.12065 -0.2794)
			(stroke
				(width 0.1)
				(type default)
			)
			(layer "B.Fab")
		)
		(fp_line
			(start -0.12065 -0.2794)
			(end -0.12065 -0.3048)
			(stroke
				(width 0.1)
				(type default)
			)
			(layer "B.Fab")
		)
		(fp_line
			(start 0.12065 0.2794)
			(end 0.12065 0.3048)
			(stroke
				(width 0.1)
				(type default)
			)
			(layer "B.Fab")
		)
		(fp_line
			(start -0.120396 0.2794)
			(end 0.12065 0.2794)
			(stroke
				(width 0.1)
				(type default)
			)
			(layer "B.Fab")
		)
		(fp_line
			(start 0.67945 0.3048)
			(end 0.67945 -0.305054)
			(stroke
				(width 0.1)
				(type default)
			)
			(layer "B.Fab")
		)
		(fp_line
			(start 0.12065 0.3048)
			(end 0.67945 0.3048)
			(stroke
				(width 0.1)
				(type default)
			)
			(layer "B.Fab")
		)
		(fp_line
			(start -0.120396 0.3048)
			(end -0.120396 0.2794)
			(stroke
				(width 0.1)
				(type default)
			)
			(layer "B.Fab")
		)
		(fp_line
			(start -0.67945 0.3048)
			(end -0.120396 0.3048)
			(stroke
				(width 0.1)
				(type default)
			)
			(layer "B.Fab")
		)
		(pad "1" smd circle
			(at 0.40005 0 270)
			(size 0 0)
			(layers "B.Cu" "B.Mask" "B.Paste")
			(net "P3V3")
		)
		(pad "2" smd circle
			(at -0.40005 0 270)
			(size 0 0)
			(layers "B.Cu" "B.Mask" "B.Paste")
			(net "PU_CLK_PFT_LOST_N")
		)
	)
	(footprint ""
		(layer "B.Cu")
		(at 347.428312 -323.15531 -90)
		(property "Reference" "R6513"
			(at 0 0 90)
			(layer "B.SilkS")
			(hide yes)
			(effects
				(font
					(size 1.27 1.27)
				)
				(justify mirror)
			)
		)
		(property "Value" ""
			(at 0 0 90)
			(layer "B.Fab")
			(effects
				(font
					(size 1.27 1.27)
				)
				(justify mirror)
			)
		)
		(duplicate_pad_numbers_are_jumpers no)
		(fp_line
			(start -0.7874 0.4064)
			(end 0.7874 0.4064)
			(stroke
				(width 0.1524)
				(type default)
			)
			(layer "B.SilkS")
		)
		(fp_line
			(start 0.7874 0.4064)
			(end 0.7874 -0.4064)
			(stroke
				(width 0.1524)
				(type default)
			)
			(layer "B.SilkS")
		)
		(fp_line
			(start -0.7874 -0.4064)
			(end -0.7874 0.4064)
			(stroke
				(width 0.1524)
				(type default)
			)
			(layer "B.SilkS")
		)
		(fp_line
			(start 0.7874 -0.4064)
			(end -0.7874 -0.4064)
			(stroke
				(width 0.1524)
				(type default)
			)
			(layer "B.SilkS")
		)
		(fp_line
			(start -0.67945 0.3048)
			(end -0.120396 0.3048)
			(stroke
				(width 0.1)
				(type default)
			)
			(layer "B.Fab")
		)
		(fp_line
			(start -0.120396 0.3048)
			(end -0.120396 0.2794)
			(stroke
				(width 0.1)
				(type default)
			)
			(layer "B.Fab")
		)
		(fp_line
			(start 0.12065 0.3048)
			(end 0.67945 0.3048)
			(stroke
				(width 0.1)
				(type default)
			)
			(layer "B.Fab")
		)
		(fp_line
			(start 0.67945 0.3048)
			(end 0.67945 -0.305054)
			(stroke
				(width 0.1)
				(type default)
			)
			(layer "B.Fab")
		)
		(fp_line
			(start -0.120396 0.2794)
			(end 0.12065 0.2794)
			(stroke
				(width 0.1)
				(type default)
			)
			(layer "B.Fab")
		)
		(fp_line
			(start 0.12065 0.2794)
			(end 0.12065 0.3048)
			(stroke
				(width 0.1)
				(type default)
			)
			(layer "B.Fab")
		)
		(fp_line
			(start -0.12065 -0.2794)
			(end -0.12065 -0.3048)
			(stroke
				(width 0.1)
				(type default)
			)
			(layer "B.Fab")
		)
		(fp_line
			(start 0.12065 -0.2794)
			(end -0.12065 -0.2794)
			(stroke
				(width 0.1)
				(type default)
			)
			(layer "B.Fab")
		)
		(fp_line
			(start -0.67945 -0.3048)
			(end -0.67945 0.3048)
			(stroke
				(width 0.1)
				(type default)
			)
			(layer "B.Fab")
		)
		(fp_line
			(start -0.12065 -0.3048)
			(end -0.67945 -0.3048)
			(stroke
				(width 0.1)
				(type default)
			)
			(layer "B.Fab")
		)
		(fp_line
			(start 0.12065 -0.305054)
			(end 0.12065 -0.2794)
			(stroke
				(width 0.1)
				(type default)
			)
			(layer "B.Fab")
		)
		(fp_line
			(start 0.67945 -0.305054)
			(end 0.12065 -0.305054)
			(stroke
				(width 0.1)
				(type default)
			)
			(layer "B.Fab")
		)
		(pad "1" smd circle
			(at 0.40005 0 90)
			(size 0 0)
			(layers "B.Cu" "B.Mask" "B.Paste")
			(net "P0V8_SERDES_VDDA_PEX2")
		)
		(pad "2" smd circle
			(at -0.40005 0 90)
			(size 0 0)
			(layers "B.Cu" "B.Mask" "B.Paste")
			(net "P0V8_SERDES_VDDA_PEX2_C6")
		)
	)
	(footprint ""
		(layer "B.Cu")
		(at 210.749896 -218.308936 180)
		(property "Reference" "C2145"
			(at 0 0 0)
			(layer "B.SilkS")
			(hide yes)
			(effects
				(font
					(size 1.27 1.27)
				)
				(justify mirror)
			)
		)
		(property "Value" ""
			(at 0 0 0)
			(layer "B.Fab")
			(effects
				(font
					(size 1.27 1.27)
				)
				(justify mirror)
			)
		)
		(duplicate_pad_numbers_are_jumpers no)
		(fp_line
			(start 0.7874 0.4064)
			(end 0.7874 -0.4064)
			(stroke
				(width 0.1524)
				(type default)
			)
			(layer "B.SilkS")
		)
		(fp_line
			(start 0.7874 -0.4064)
			(end -0.7874 -0.4064)
			(stroke
				(width 0.1524)
				(type default)
			)
			(layer "B.SilkS")
		)
		(fp_line
			(start -0.7874 0.4064)
			(end 0.7874 0.4064)
			(stroke
				(width 0.1524)
				(type default)
			)
			(layer "B.SilkS")
		)
		(fp_line
			(start -0.7874 -0.4064)
			(end -0.7874 0.4064)
			(stroke
				(width 0.1524)
				(type default)
			)
			(layer "B.SilkS")
		)
		(fp_line
			(start 0.67945 0.3048)
			(end 0.67945 -0.305054)
			(stroke
				(width 0.1)
				(type default)
			)
			(layer "B.Fab")
		)
		(fp_line
			(start 0.67945 -0.305054)
			(end 0.12065 -0.305054)
			(stroke
				(width 0.1)
				(type default)
			)
			(layer "B.Fab")
		)
		(fp_line
			(start 0.12065 0.3048)
			(end 0.67945 0.3048)
			(stroke
				(width 0.1)
				(type default)
			)
			(layer "B.Fab")
		)
		(fp_line
			(start 0.12065 0.2794)
			(end 0.12065 0.3048)
			(stroke
				(width 0.1)
				(type default)
			)
			(layer "B.Fab")
		)
		(fp_line
			(start 0.12065 -0.2794)
			(end -0.12065 -0.2794)
			(stroke
				(width 0.1)
				(type default)
			)
			(layer "B.Fab")
		)
		(fp_line
			(start 0.12065 -0.305054)
			(end 0.12065 -0.2794)
			(stroke
				(width 0.1)
				(type default)
			)
			(layer "B.Fab")
		)
		(fp_line
			(start -0.120396 0.3048)
			(end -0.120396 0.2794)
			(stroke
				(width 0.1)
				(type default)
			)
			(layer "B.Fab")
		)
		(fp_line
			(start -0.120396 0.2794)
			(end 0.12065 0.2794)
			(stroke
				(width 0.1)
				(type default)
			)
			(layer "B.Fab")
		)
		(fp_line
			(start -0.12065 -0.2794)
			(end -0.12065 -0.3048)
			(stroke
				(width 0.1)
				(type default)
			)
			(layer "B.Fab")
		)
		(fp_line
			(start -0.12065 -0.3048)
			(end -0.67945 -0.3048)
			(stroke
				(width 0.1)
				(type default)
			)
			(layer "B.Fab")
		)
		(fp_line
			(start -0.67945 0.3048)
			(end -0.120396 0.3048)
			(stroke
				(width 0.1)
				(type default)
			)
			(layer "B.Fab")
		)
		(fp_line
			(start -0.67945 -0.3048)
			(end -0.67945 0.3048)
			(stroke
				(width 0.1)
				(type default)
			)
			(layer "B.Fab")
		)
		(pad "1" smd circle
			(at 0.40005 0)
			(size 0 0)
			(layers "B.Cu" "B.Mask" "B.Paste")
			(net "GND")
		)
		(pad "2" smd circle
			(at -0.40005 0)
			(size 0 0)
			(layers "B.Cu" "B.Mask" "B.Paste")
			(net "USB_DEBUG_RST_BTN_R_N")
		)
	)
	(footprint ""
		(layer "B.Cu")
		(at 116.224558 -282.166822 90)
		(property "Reference" "R6763"
			(at 0 0 90)
			(layer "B.SilkS")
			(hide yes)
			(effects
				(font
					(size 1.27 1.27)
				)
				(justify mirror)
			)
		)
		(property "Value" ""
			(at 0 0 90)
			(layer "B.Fab")
			(effects
				(font
					(size 1.27 1.27)
				)
				(justify mirror)
			)
		)
		(duplicate_pad_numbers_are_jumpers no)
		(fp_line
			(start 0.7874 -0.4064)
			(end -0.7874 -0.4064)
			(stroke
				(width 0.1524)
				(type default)
			)
			(layer "B.SilkS")
		)
		(fp_line
			(start -0.7874 -0.4064)
			(end -0.7874 0.4064)
			(stroke
				(width 0.1524)
				(type default)
			)
			(layer "B.SilkS")
		)
		(fp_line
			(start 0.7874 0.4064)
			(end 0.7874 -0.4064)
			(stroke
				(width 0.1524)
				(type default)
			)
			(layer "B.SilkS")
		)
		(fp_line
			(start -0.7874 0.4064)
			(end 0.7874 0.4064)
			(stroke
				(width 0.1524)
				(type default)
			)
			(layer "B.SilkS")
		)
		(fp_line
			(start 0.67945 -0.305054)
			(end 0.12065 -0.305054)
			(stroke
				(width 0.1)
				(type default)
			)
			(layer "B.Fab")
		)
		(fp_line
			(start 0.12065 -0.305054)
			(end 0.12065 -0.2794)
			(stroke
				(width 0.1)
				(type default)
			)
			(layer "B.Fab")
		)
		(fp_line
			(start -0.12065 -0.3048)
			(end -0.67945 -0.3048)
			(stroke
				(width 0.1)
				(type default)
			)
			(layer "B.Fab")
		)
		(fp_line
			(start -0.67945 -0.3048)
			(end -0.67945 0.3048)
			(stroke
				(width 0.1)
				(type default)
			)
			(layer "B.Fab")
		)
		(fp_line
			(start 0.12065 -0.2794)
			(end -0.12065 -0.2794)
			(stroke
				(width 0.1)
				(type default)
			)
			(layer "B.Fab")
		)
		(fp_line
			(start -0.12065 -0.2794)
			(end -0.12065 -0.3048)
			(stroke
				(width 0.1)
				(type default)
			)
			(layer "B.Fab")
		)
		(fp_line
			(start 0.12065 0.2794)
			(end 0.12065 0.3048)
			(stroke
				(width 0.1)
				(type default)
			)
			(layer "B.Fab")
		)
		(fp_line
			(start -0.120396 0.2794)
			(end 0.12065 0.2794)
			(stroke
				(width 0.1)
				(type default)
			)
			(layer "B.Fab")
		)
		(fp_line
			(start 0.67945 0.3048)
			(end 0.67945 -0.305054)
			(stroke
				(width 0.1)
				(type default)
			)
			(layer "B.Fab")
		)
		(fp_line
			(start 0.12065 0.3048)
			(end 0.67945 0.3048)
			(stroke
				(width 0.1)
				(type default)
			)
			(layer "B.Fab")
		)
		(fp_line
			(start -0.120396 0.3048)
			(end -0.120396 0.2794)
			(stroke
				(width 0.1)
				(type default)
			)
			(layer "B.Fab")
		)
		(fp_line
			(start -0.67945 0.3048)
			(end -0.120396 0.3048)
			(stroke
				(width 0.1)
				(type default)
			)
			(layer "B.Fab")
		)
		(pad "1" smd circle
			(at 0.40005 0 270)
			(size 0 0)
			(layers "B.Cu" "B.Mask" "B.Paste")
			(net "P0V8_PEX0_VCC2")
		)
		(pad "2" smd circle
			(at -0.40005 0 270)
			(size 0 0)
			(layers "B.Cu" "B.Mask" "B.Paste")
			(net "P0V8_PEX0_EN2")
		)
	)
	(footprint ""
		(layer "B.Cu")
		(at 62.051184 -305.399948 -90)
		(property "Reference" "C2964"
			(at 0 0 90)
			(layer "B.SilkS")
			(hide yes)
			(effects
				(font
					(size 1.27 1.27)
				)
				(justify mirror)
			)
		)
		(property "Value" ""
			(at 0 0 90)
			(layer "B.Fab")
			(effects
				(font
					(size 1.27 1.27)
				)
				(justify mirror)
			)
		)
		(duplicate_pad_numbers_are_jumpers no)
		(fp_line
			(start -0.299974 0.150114)
			(end 0.299974 0.150114)
			(stroke
				(width 0.1)
				(type default)
			)
			(layer "B.Fab")
		)
		(fp_line
			(start 0.299974 0.150114)
			(end 0.299974 -0.150114)
			(stroke
				(width 0.1)
				(type default)
			)
			(layer "B.Fab")
		)
		(fp_line
			(start -0.299974 -0.150114)
			(end -0.299974 0.150114)
			(stroke
				(width 0.1)
				(type default)
			)
			(layer "B.Fab")
		)
		(fp_line
			(start 0.299974 -0.150114)
			(end -0.299974 -0.150114)
			(stroke
				(width 0.1)
				(type default)
			)
			(layer "B.Fab")
		)
		(pad "1" smd rect
			(at 0.2667 0 90)
			(size 0.3048 0.381)
			(layers "B.Cu" "B.Mask" "B.Paste")
			(net "P1V25_SERDES_VDDPLL_PEX0")
		)
		(pad "2" smd rect
			(at -0.2667 0 90)
			(size 0.3048 0.381)
			(layers "B.Cu" "B.Mask" "B.Paste")
			(net "GND")
		)
	)
	(footprint ""
		(layer "B.Cu")
		(at 162.4457 -297.32478)
		(property "Reference" "C3202"
			(at 0 0 0)
			(layer "B.SilkS")
			(hide yes)
			(effects
				(font
					(size 1.27 1.27)
				)
				(justify mirror)
			)
		)
		(property "Value" ""
			(at 0 0 0)
			(layer "B.Fab")
			(effects
				(font
					(size 1.27 1.27)
				)
				(justify mirror)
			)
		)
		(duplicate_pad_numbers_are_jumpers no)
		(fp_line
			(start -0.299974 -0.150114)
			(end -0.299974 0.150114)
			(stroke
				(width 0.1)
				(type default)
			)
			(layer "B.Fab")
		)
		(fp_line
			(start -0.299974 0.150114)
			(end 0.299974 0.150114)
			(stroke
				(width 0.1)
				(type default)
			)
			(layer "B.Fab")
		)
		(fp_line
			(start 0.299974 -0.150114)
			(end -0.299974 -0.150114)
			(stroke
				(width 0.1)
				(type default)
			)
			(layer "B.Fab")
		)
		(fp_line
			(start 0.299974 0.150114)
			(end 0.299974 -0.150114)
			(stroke
				(width 0.1)
				(type default)
			)
			(layer "B.Fab")
		)
		(pad "1" smd rect
			(at 0.2667 0 180)
			(size 0.3048 0.381)
			(layers "B.Cu" "B.Mask" "B.Paste")
			(net "PCEPLL2_VDDA18_PEX1")
		)
		(pad "2" smd rect
			(at -0.2667 0 180)
			(size 0.3048 0.381)
			(layers "B.Cu" "B.Mask" "B.Paste")
			(net "GND")
		)
	)
	(footprint ""
		(layer "B.Cu")
		(at 111.743236 -303.649634 -90)
		(property "Reference" "PR9"
			(at 0 0 90)
			(layer "B.SilkS")
			(hide yes)
			(effects
				(font
					(size 1.27 1.27)
				)
				(justify mirror)
			)
		)
		(property "Value" ""
			(at 0 0 90)
			(layer "B.Fab")
			(effects
				(font
					(size 1.27 1.27)
				)
				(justify mirror)
			)
		)
		(duplicate_pad_numbers_are_jumpers no)
		(fp_line
			(start -1.2954 0.5842)
			(end 1.2954 0.5842)
			(stroke
				(width 0.1524)
				(type default)
			)
			(layer "B.SilkS")
		)
		(fp_line
			(start 1.2954 0.5842)
			(end 1.2954 -0.5842)
			(stroke
				(width 0.1524)
				(type default)
			)
			(layer "B.SilkS")
		)
		(fp_line
			(start -1.2954 -0.5842)
			(end -1.2954 0.5842)
			(stroke
				(width 0.1524)
				(type default)
			)
			(layer "B.SilkS")
		)
		(fp_line
			(start 1.2954 -0.5842)
			(end -1.2954 -0.5842)
			(stroke
				(width 0.1524)
				(type default)
			)
			(layer "B.SilkS")
		)
		(fp_line
			(start -0.8636 0.4572)
			(end 0.8636 0.4572)
			(stroke
				(width 0.1)
				(type default)
			)
			(layer "B.Fab")
		)
		(fp_line
			(start 0.8636 0.4572)
			(end 0.8636 0.4318)
			(stroke
				(width 0.1)
				(type default)
			)
			(layer "B.Fab")
		)
		(fp_line
			(start 0.8636 0.4318)
			(end 0.8636 0.4064)
			(stroke
				(width 0.1)
				(type default)
			)
			(layer "B.Fab")
		)
		(fp_line
			(start -1.1938 0.4064)
			(end -0.8636 0.4064)
			(stroke
				(width 0.1)
				(type default)
			)
			(layer "B.Fab")
		)
		(fp_line
			(start -0.8636 0.4064)
			(end -0.8636 0.4572)
			(stroke
				(width 0.1)
				(type default)
			)
			(layer "B.Fab")
		)
		(fp_line
			(start 0.8636 0.4064)
			(end 1.1938 0.4064)
			(stroke
				(width 0.1)
				(type default)
			)
			(layer "B.Fab")
		)
		(fp_line
			(start 1.1938 0.4064)
			(end 1.1938 -0.406654)
			(stroke
				(width 0.1)
				(type default)
			)
			(layer "B.Fab")
		)
		(fp_line
			(start -1.1938 -0.406654)
			(end -1.1938 0.4064)
			(stroke
				(width 0.1)
				(type default)
			)
			(layer "B.Fab")
		)
		(fp_line
			(start -0.8636 -0.406654)
			(end -1.1938 -0.406654)
			(stroke
				(width 0.1)
				(type default)
			)
			(layer "B.Fab")
		)
		(fp_line
			(start 0.8636 -0.406654)
			(end 0.8636 -0.4572)
			(stroke
				(width 0.1)
				(type default)
			)
			(layer "B.Fab")
		)
		(fp_line
			(start 1.1938 -0.406654)
			(end 0.8636 -0.406654)
			(stroke
				(width 0.1)
				(type default)
			)
			(layer "B.Fab")
		)
		(fp_line
			(start -0.8636 -0.4572)
			(end -0.8636 -0.406654)
			(stroke
				(width 0.1)
				(type default)
			)
			(layer "B.Fab")
		)
		(fp_line
			(start 0.8636 -0.4572)
			(end -0.8636 -0.4572)
			(stroke
				(width 0.1)
				(type default)
			)
			(layer "B.Fab")
		)
		(pad "1" smd rect
			(at 0.7366 0 180)
			(size 0.7112 0.8128)
			(layers "B.Cu" "B.Mask" "B.Paste")
			(net "P0V8_PEX0")
		)
		(pad "2" smd rect
			(at -0.7366 0 180)
			(size 0.7112 0.8128)
			(layers "B.Cu" "B.Mask" "B.Paste")
			(net "GND")
		)
	)
	(footprint ""
		(layer "B.Cu")
		(at 109.63148 -282.060142 90)
		(property "Reference" "PR101"
			(at 0 0 90)
			(layer "B.SilkS")
			(hide yes)
			(effects
				(font
					(size 1.27 1.27)
				)
				(justify mirror)
			)
		)
		(property "Value" ""
			(at 0 0 90)
			(layer "B.Fab")
			(effects
				(font
					(size 1.27 1.27)
				)
				(justify mirror)
			)
		)
		(duplicate_pad_numbers_are_jumpers no)
		(fp_line
			(start 0.7874 -0.4064)
			(end -0.7874 -0.4064)
			(stroke
				(width 0.1524)
				(type default)
			)
			(layer "B.SilkS")
		)
		(fp_line
			(start -0.7874 -0.4064)
			(end -0.7874 0.4064)
			(stroke
				(width 0.1524)
				(type default)
			)
			(layer "B.SilkS")
		)
		(fp_line
			(start 0.7874 0.4064)
			(end 0.7874 -0.4064)
			(stroke
				(width 0.1524)
				(type default)
			)
			(layer "B.SilkS")
		)
		(fp_line
			(start -0.7874 0.4064)
			(end 0.7874 0.4064)
			(stroke
				(width 0.1524)
				(type default)
			)
			(layer "B.SilkS")
		)
		(fp_line
			(start 0.67945 -0.305054)
			(end 0.12065 -0.305054)
			(stroke
				(width 0.1)
				(type default)
			)
			(layer "B.Fab")
		)
		(fp_line
			(start 0.12065 -0.305054)
			(end 0.12065 -0.2794)
			(stroke
				(width 0.1)
				(type default)
			)
			(layer "B.Fab")
		)
		(fp_line
			(start -0.12065 -0.3048)
			(end -0.67945 -0.3048)
			(stroke
				(width 0.1)
				(type default)
			)
			(layer "B.Fab")
		)
		(fp_line
			(start -0.67945 -0.3048)
			(end -0.67945 0.3048)
			(stroke
				(width 0.1)
				(type default)
			)
			(layer "B.Fab")
		)
		(fp_line
			(start 0.12065 -0.2794)
			(end -0.12065 -0.2794)
			(stroke
				(width 0.1)
				(type default)
			)
			(layer "B.Fab")
		)
		(fp_line
			(start -0.12065 -0.2794)
			(end -0.12065 -0.3048)
			(stroke
				(width 0.1)
				(type default)
			)
			(layer "B.Fab")
		)
		(fp_line
			(start 0.12065 0.2794)
			(end 0.12065 0.3048)
			(stroke
				(width 0.1)
				(type default)
			)
			(layer "B.Fab")
		)
		(fp_line
			(start -0.120396 0.2794)
			(end 0.12065 0.2794)
			(stroke
				(width 0.1)
				(type default)
			)
			(layer "B.Fab")
		)
		(fp_line
			(start 0.67945 0.3048)
			(end 0.67945 -0.305054)
			(stroke
				(width 0.1)
				(type default)
			)
			(layer "B.Fab")
		)
		(fp_line
			(start 0.12065 0.3048)
			(end 0.67945 0.3048)
			(stroke
				(width 0.1)
				(type default)
			)
			(layer "B.Fab")
		)
		(fp_line
			(start -0.120396 0.3048)
			(end -0.120396 0.2794)
			(stroke
				(width 0.1)
				(type default)
			)
			(layer "B.Fab")
		)
		(fp_line
			(start -0.67945 0.3048)
			(end -0.120396 0.3048)
			(stroke
				(width 0.1)
				(type default)
			)
			(layer "B.Fab")
		)
		(pad "1" smd circle
			(at 0.40005 0 270)
			(size 0 0)
			(layers "B.Cu" "B.Mask" "B.Paste")
			(net "SW_P0V8_PEX0_VOS1")
		)
		(pad "2" smd circle
			(at -0.40005 0 270)
			(size 0 0)
			(layers "B.Cu" "B.Mask" "B.Paste")
			(net "P0V8_PEX0")
		)
	)
	(footprint ""
		(layer "B.Cu")
		(at 419.141656 -300.174914)
		(property "Reference" "C3511"
			(at 0 0 0)
			(layer "B.SilkS")
			(hide yes)
			(effects
				(font
					(size 1.27 1.27)
				)
				(justify mirror)
			)
		)
		(property "Value" ""
			(at 0 0 0)
			(layer "B.Fab")
			(effects
				(font
					(size 1.27 1.27)
				)
				(justify mirror)
			)
		)
		(duplicate_pad_numbers_are_jumpers no)
		(fp_line
			(start -0.299974 -0.150114)
			(end -0.299974 0.150114)
			(stroke
				(width 0.1)
				(type default)
			)
			(layer "B.Fab")
		)
		(fp_line
			(start -0.299974 0.150114)
			(end 0.299974 0.150114)
			(stroke
				(width 0.1)
				(type default)
			)
			(layer "B.Fab")
		)
		(fp_line
			(start 0.299974 -0.150114)
			(end -0.299974 -0.150114)
			(stroke
				(width 0.1)
				(type default)
			)
			(layer "B.Fab")
		)
		(fp_line
			(start 0.299974 0.150114)
			(end 0.299974 -0.150114)
			(stroke
				(width 0.1)
				(type default)
			)
			(layer "B.Fab")
		)
		(pad "1" smd rect
			(at 0.2667 0 180)
			(size 0.3048 0.381)
			(layers "B.Cu" "B.Mask" "B.Paste")
			(net "P1V8_VDDA_PEX3")
		)
		(pad "2" smd rect
			(at -0.2667 0 180)
			(size 0.3048 0.381)
			(layers "B.Cu" "B.Mask" "B.Paste")
			(net "GND")
		)
	)
	(footprint ""
		(layer "B.Cu")
		(at 303.041558 -300.174914)
		(property "Reference" "C3337"
			(at 0 0 0)
			(layer "B.SilkS")
			(hide yes)
			(effects
				(font
					(size 1.27 1.27)
				)
				(justify mirror)
			)
		)
		(property "Value" ""
			(at 0 0 0)
			(layer "B.Fab")
			(effects
				(font
					(size 1.27 1.27)
				)
				(justify mirror)
			)
		)
		(duplicate_pad_numbers_are_jumpers no)
		(fp_line
			(start -0.299974 -0.150114)
			(end -0.299974 0.150114)
			(stroke
				(width 0.1)
				(type default)
			)
			(layer "B.Fab")
		)
		(fp_line
			(start -0.299974 0.150114)
			(end 0.299974 0.150114)
			(stroke
				(width 0.1)
				(type default)
			)
			(layer "B.Fab")
		)
		(fp_line
			(start 0.299974 -0.150114)
			(end -0.299974 -0.150114)
			(stroke
				(width 0.1)
				(type default)
			)
			(layer "B.Fab")
		)
		(fp_line
			(start 0.299974 0.150114)
			(end 0.299974 -0.150114)
			(stroke
				(width 0.1)
				(type default)
			)
			(layer "B.Fab")
		)
		(pad "1" smd rect
			(at 0.2667 0 180)
			(size 0.3048 0.381)
			(layers "B.Cu" "B.Mask" "B.Paste")
			(net "P1V8_VDDA_PEX2")
		)
		(pad "2" smd rect
			(at -0.2667 0 180)
			(size 0.3048 0.381)
			(layers "B.Cu" "B.Mask" "B.Paste")
			(net "GND")
		)
	)
	(footprint ""
		(layer "B.Cu")
		(at 242.447318 -266.873228 180)
		(property "Reference" "R6135"
			(at 0 0 0)
			(layer "B.SilkS")
			(hide yes)
			(effects
				(font
					(size 1.27 1.27)
				)
				(justify mirror)
			)
		)
		(property "Value" ""
			(at 0 0 0)
			(layer "B.Fab")
			(effects
				(font
					(size 1.27 1.27)
				)
				(justify mirror)
			)
		)
		(duplicate_pad_numbers_are_jumpers no)
		(fp_line
			(start 2.576322 1.1303)
			(end 2.576322 -1.1303)
			(stroke
				(width 0.1524)
				(type default)
			)
			(layer "B.SilkS")
		)
		(fp_line
			(start 2.576322 -1.1303)
			(end -2.576322 -1.1303)
			(stroke
				(width 0.1524)
				(type default)
			)
			(layer "B.SilkS")
		)
		(fp_line
			(start -2.576322 1.1303)
			(end 2.576322 1.1303)
			(stroke
				(width 0.1524)
				(type default)
			)
			(layer "B.SilkS")
		)
		(fp_line
			(start -2.576322 -1.1303)
			(end -2.576322 1.1303)
			(stroke
				(width 0.1524)
				(type default)
			)
			(layer "B.SilkS")
		)
		(fp_line
			(start 1.649984 0.899922)
			(end -1.649984 0.899922)
			(stroke
				(width 0.1)
				(type default)
			)
			(layer "B.Fab")
		)
		(fp_line
			(start 1.649984 -0.899922)
			(end 1.649984 0.899922)
			(stroke
				(width 0.1)
				(type default)
			)
			(layer "B.Fab")
		)
		(fp_line
			(start -1.649984 0.899922)
			(end -1.649984 -0.899922)
			(stroke
				(width 0.1)
				(type default)
			)
			(layer "B.Fab")
		)
		(fp_line
			(start -1.649984 -0.899922)
			(end 1.649984 -0.899922)
			(stroke
				(width 0.1)
				(type default)
			)
			(layer "B.Fab")
		)
		(pad "1A" smd rect
			(at 1.700022 0)
			(size 1.4986 2.0066)
			(layers "B.Cu" "B.Mask" "B.Paste")
			(net "P1V25_PEX2")
		)
		(pad "1B" smd rect
			(at 1.077722 0)
			(size 0.254 0.508)
			(layers "B.Cu" "B.Mask" "B.Paste")
			(net "P1V25_PEX2")
		)
		(pad "2A" smd rect
			(at -1.700022 0)
			(size 1.4986 2.0066)
			(layers "B.Cu" "B.Mask" "B.Paste")
			(net "P1V25_SERDES_VDDPLL_PEX2")
		)
		(pad "2B" smd rect
			(at -1.077722 0)
			(size 0.254 0.508)
			(layers "B.Cu" "B.Mask" "B.Paste")
			(net "P1V25_SERDES_VDDPLL_PEX2")
		)
	)
	(footprint ""
		(layer "B.Cu")
		(at 61.549788 -292.099746 90)
		(property "Reference" "C1207"
			(at 0 0 90)
			(layer "B.SilkS")
			(hide yes)
			(effects
				(font
					(size 1.27 1.27)
				)
				(justify mirror)
			)
		)
		(property "Value" ""
			(at 0 0 90)
			(layer "B.Fab")
			(effects
				(font
					(size 1.27 1.27)
				)
				(justify mirror)
			)
		)
		(duplicate_pad_numbers_are_jumpers no)
		(fp_line
			(start 0.299974 -0.150114)
			(end -0.299974 -0.150114)
			(stroke
				(width 0.1)
				(type default)
			)
			(layer "B.Fab")
		)
		(fp_line
			(start -0.299974 -0.150114)
			(end -0.299974 0.150114)
			(stroke
				(width 0.1)
				(type default)
			)
			(layer "B.Fab")
		)
		(fp_line
			(start 0.299974 0.150114)
			(end 0.299974 -0.150114)
			(stroke
				(width 0.1)
				(type default)
			)
			(layer "B.Fab")
		)
		(fp_line
			(start -0.299974 0.150114)
			(end 0.299974 0.150114)
			(stroke
				(width 0.1)
				(type default)
			)
			(layer "B.Fab")
		)
		(pad "1" smd rect
			(at 0.2667 0 270)
			(size 0.3048 0.381)
			(layers "B.Cu" "B.Mask" "B.Paste")
			(net "P0V8_SERDES_VDDA_PEX0")
		)
		(pad "2" smd rect
			(at -0.2667 0 270)
			(size 0.3048 0.381)
			(layers "B.Cu" "B.Mask" "B.Paste")
			(net "GND")
		)
	)
	(footprint ""
		(layer "B.Cu")
		(at 359.94848 -284.796738 -90)
		(property "Reference" "PC176"
			(at 0 0 90)
			(layer "B.SilkS")
			(hide yes)
			(effects
				(font
					(size 1.27 1.27)
				)
				(justify mirror)
			)
		)
		(property "Value" ""
			(at 0 0 90)
			(layer "B.Fab")
			(effects
				(font
					(size 1.27 1.27)
				)
				(justify mirror)
			)
		)
		(duplicate_pad_numbers_are_jumpers no)
		(fp_line
			(start -1.524 0.762)
			(end 1.524 0.762)
			(stroke
				(width 0.1524)
				(type default)
			)
			(layer "B.SilkS")
		)
		(fp_line
			(start 1.524 0.762)
			(end 1.524 -0.762)
			(stroke
				(width 0.1524)
				(type default)
			)
			(layer "B.SilkS")
		)
		(fp_line
			(start -1.524 -0.762)
			(end -1.524 0.762)
			(stroke
				(width 0.1524)
				(type default)
			)
			(layer "B.SilkS")
		)
		(fp_line
			(start 1.524 -0.762)
			(end -1.524 -0.762)
			(stroke
				(width 0.1524)
				(type default)
			)
			(layer "B.SilkS")
		)
		(fp_line
			(start -1.1049 0.724916)
			(end -1.1049 -0.724916)
			(stroke
				(width 0.1)
				(type default)
			)
			(layer "B.Fab")
		)
		(fp_line
			(start 1.1049 0.724916)
			(end -1.1049 0.724916)
			(stroke
				(width 0.1)
				(type default)
			)
			(layer "B.Fab")
		)
		(fp_line
			(start -1.1049 -0.724916)
			(end 1.1049 -0.724916)
			(stroke
				(width 0.1)
				(type default)
			)
			(layer "B.Fab")
		)
		(fp_line
			(start 1.1049 -0.724916)
			(end 1.1049 0.724916)
			(stroke
				(width 0.1)
				(type default)
			)
			(layer "B.Fab")
		)
		(pad "1" smd rect
			(at 0.889 0 270)
			(size 1.016 1.27)
			(layers "B.Cu" "B.Mask" "B.Paste")
			(net "SW_P12V_P0V8_PEX3_FLT")
		)
		(pad "2" smd rect
			(at -0.889 0 270)
			(size 1.016 1.27)
			(layers "B.Cu" "B.Mask" "B.Paste")
			(net "GND")
		)
	)
	(footprint ""
		(layer "B.Cu")
		(at 329.692 -226.5172 180)
		(property "Reference" "R3107"
			(at 0 0 0)
			(layer "B.SilkS")
			(hide yes)
			(effects
				(font
					(size 1.27 1.27)
				)
				(justify mirror)
			)
		)
		(property "Value" ""
			(at 0 0 0)
			(layer "B.Fab")
			(effects
				(font
					(size 1.27 1.27)
				)
				(justify mirror)
			)
		)
		(duplicate_pad_numbers_are_jumpers no)
		(fp_line
			(start 0.7874 0.4064)
			(end 0.7874 -0.4064)
			(stroke
				(width 0.1524)
				(type default)
			)
			(layer "B.SilkS")
		)
		(fp_line
			(start 0.7874 -0.4064)
			(end -0.7874 -0.4064)
			(stroke
				(width 0.1524)
				(type default)
			)
			(layer "B.SilkS")
		)
		(fp_line
			(start -0.7874 0.4064)
			(end 0.7874 0.4064)
			(stroke
				(width 0.1524)
				(type default)
			)
			(layer "B.SilkS")
		)
		(fp_line
			(start -0.7874 -0.4064)
			(end -0.7874 0.4064)
			(stroke
				(width 0.1524)
				(type default)
			)
			(layer "B.SilkS")
		)
		(fp_line
			(start 0.67945 0.3048)
			(end 0.67945 -0.305054)
			(stroke
				(width 0.1)
				(type default)
			)
			(layer "B.Fab")
		)
		(fp_line
			(start 0.67945 -0.305054)
			(end 0.12065 -0.305054)
			(stroke
				(width 0.1)
				(type default)
			)
			(layer "B.Fab")
		)
		(fp_line
			(start 0.12065 0.3048)
			(end 0.67945 0.3048)
			(stroke
				(width 0.1)
				(type default)
			)
			(layer "B.Fab")
		)
		(fp_line
			(start 0.12065 0.2794)
			(end 0.12065 0.3048)
			(stroke
				(width 0.1)
				(type default)
			)
			(layer "B.Fab")
		)
		(fp_line
			(start 0.12065 -0.2794)
			(end -0.12065 -0.2794)
			(stroke
				(width 0.1)
				(type default)
			)
			(layer "B.Fab")
		)
		(fp_line
			(start 0.12065 -0.305054)
			(end 0.12065 -0.2794)
			(stroke
				(width 0.1)
				(type default)
			)
			(layer "B.Fab")
		)
		(fp_line
			(start -0.120396 0.3048)
			(end -0.120396 0.2794)
			(stroke
				(width 0.1)
				(type default)
			)
			(layer "B.Fab")
		)
		(fp_line
			(start -0.120396 0.2794)
			(end 0.12065 0.2794)
			(stroke
				(width 0.1)
				(type default)
			)
			(layer "B.Fab")
		)
		(fp_line
			(start -0.12065 -0.2794)
			(end -0.12065 -0.3048)
			(stroke
				(width 0.1)
				(type default)
			)
			(layer "B.Fab")
		)
		(fp_line
			(start -0.12065 -0.3048)
			(end -0.67945 -0.3048)
			(stroke
				(width 0.1)
				(type default)
			)
			(layer "B.Fab")
		)
		(fp_line
			(start -0.67945 0.3048)
			(end -0.120396 0.3048)
			(stroke
				(width 0.1)
				(type default)
			)
			(layer "B.Fab")
		)
		(fp_line
			(start -0.67945 -0.3048)
			(end -0.67945 0.3048)
			(stroke
				(width 0.1)
				(type default)
			)
			(layer "B.Fab")
		)
		(pad "1" smd circle
			(at 0.40005 0)
			(size 0 0)
			(layers "B.Cu" "B.Mask" "B.Paste")
			(net "PWRGD_P3V3_AUX_R")
		)
		(pad "2" smd circle
			(at -0.40005 0)
			(size 0 0)
			(layers "B.Cu" "B.Mask" "B.Paste")
			(net "PWR_EN_P1V2_AUX_R")
		)
	)
	(footprint ""
		(layer "B.Cu")
		(at 109.85119 -335.481676 -90)
		(property "Reference" "R1223"
			(at 0 0 90)
			(layer "B.SilkS")
			(hide yes)
			(effects
				(font
					(size 1.27 1.27)
				)
				(justify mirror)
			)
		)
		(property "Value" ""
			(at 0 0 90)
			(layer "B.Fab")
			(effects
				(font
					(size 1.27 1.27)
				)
				(justify mirror)
			)
		)
		(duplicate_pad_numbers_are_jumpers no)
		(fp_line
			(start -0.7874 0.4064)
			(end 0.7874 0.4064)
			(stroke
				(width 0.1524)
				(type default)
			)
			(layer "B.SilkS")
		)
		(fp_line
			(start 0.7874 0.4064)
			(end 0.7874 -0.4064)
			(stroke
				(width 0.1524)
				(type default)
			)
			(layer "B.SilkS")
		)
		(fp_line
			(start -0.7874 -0.4064)
			(end -0.7874 0.4064)
			(stroke
				(width 0.1524)
				(type default)
			)
			(layer "B.SilkS")
		)
		(fp_line
			(start 0.7874 -0.4064)
			(end -0.7874 -0.4064)
			(stroke
				(width 0.1524)
				(type default)
			)
			(layer "B.SilkS")
		)
		(fp_line
			(start -0.67945 0.3048)
			(end -0.120396 0.3048)
			(stroke
				(width 0.1)
				(type default)
			)
			(layer "B.Fab")
		)
		(fp_line
			(start -0.120396 0.3048)
			(end -0.120396 0.2794)
			(stroke
				(width 0.1)
				(type default)
			)
			(layer "B.Fab")
		)
		(fp_line
			(start 0.12065 0.3048)
			(end 0.67945 0.3048)
			(stroke
				(width 0.1)
				(type default)
			)
			(layer "B.Fab")
		)
		(fp_line
			(start 0.67945 0.3048)
			(end 0.67945 -0.305054)
			(stroke
				(width 0.1)
				(type default)
			)
			(layer "B.Fab")
		)
		(fp_line
			(start -0.120396 0.2794)
			(end 0.12065 0.2794)
			(stroke
				(width 0.1)
				(type default)
			)
			(layer "B.Fab")
		)
		(fp_line
			(start 0.12065 0.2794)
			(end 0.12065 0.3048)
			(stroke
				(width 0.1)
				(type default)
			)
			(layer "B.Fab")
		)
		(fp_line
			(start -0.12065 -0.2794)
			(end -0.12065 -0.3048)
			(stroke
				(width 0.1)
				(type default)
			)
			(layer "B.Fab")
		)
		(fp_line
			(start 0.12065 -0.2794)
			(end -0.12065 -0.2794)
			(stroke
				(width 0.1)
				(type default)
			)
			(layer "B.Fab")
		)
		(fp_line
			(start -0.67945 -0.3048)
			(end -0.67945 0.3048)
			(stroke
				(width 0.1)
				(type default)
			)
			(layer "B.Fab")
		)
		(fp_line
			(start -0.12065 -0.3048)
			(end -0.67945 -0.3048)
			(stroke
				(width 0.1)
				(type default)
			)
			(layer "B.Fab")
		)
		(fp_line
			(start 0.12065 -0.305054)
			(end 0.12065 -0.2794)
			(stroke
				(width 0.1)
				(type default)
			)
			(layer "B.Fab")
		)
		(fp_line
			(start 0.67945 -0.305054)
			(end 0.12065 -0.305054)
			(stroke
				(width 0.1)
				(type default)
			)
			(layer "B.Fab")
		)
		(pad "1" smd circle
			(at 0.40005 0 90)
			(size 0 0)
			(layers "B.Cu" "B.Mask" "B.Paste")
			(net "PU_9ZXL0451E_HBW")
		)
		(pad "2" smd circle
			(at -0.40005 0 90)
			(size 0 0)
			(layers "B.Cu" "B.Mask" "B.Paste")
			(net "GND")
		)
	)
	(footprint ""
		(layer "B.Cu")
		(at 55.374794 -286.399732 90)
		(property "Reference" "C2955"
			(at 0 0 90)
			(layer "B.SilkS")
			(hide yes)
			(effects
				(font
					(size 1.27 1.27)
				)
				(justify mirror)
			)
		)
		(property "Value" ""
			(at 0 0 90)
			(layer "B.Fab")
			(effects
				(font
					(size 1.27 1.27)
				)
				(justify mirror)
			)
		)
		(duplicate_pad_numbers_are_jumpers no)
		(fp_line
			(start 0.299974 -0.150114)
			(end -0.299974 -0.150114)
			(stroke
				(width 0.1)
				(type default)
			)
			(layer "B.Fab")
		)
		(fp_line
			(start -0.299974 -0.150114)
			(end -0.299974 0.150114)
			(stroke
				(width 0.1)
				(type default)
			)
			(layer "B.Fab")
		)
		(fp_line
			(start 0.299974 0.150114)
			(end 0.299974 -0.150114)
			(stroke
				(width 0.1)
				(type default)
			)
			(layer "B.Fab")
		)
		(fp_line
			(start -0.299974 0.150114)
			(end 0.299974 0.150114)
			(stroke
				(width 0.1)
				(type default)
			)
			(layer "B.Fab")
		)
		(pad "1" smd rect
			(at 0.2667 0 270)
			(size 0.3048 0.381)
			(layers "B.Cu" "B.Mask" "B.Paste")
			(net "P1V25_SERDES_VDDPLL_PEX0")
		)
		(pad "2" smd rect
			(at -0.2667 0 270)
			(size 0.3048 0.381)
			(layers "B.Cu" "B.Mask" "B.Paste")
			(net "GND")
		)
	)
	(footprint ""
		(layer "B.Cu")
		(at 170.049952 -292.099746 90)
		(property "Reference" "C1490"
			(at 0 0 90)
			(layer "B.SilkS")
			(hide yes)
			(effects
				(font
					(size 1.27 1.27)
				)
				(justify mirror)
			)
		)
		(property "Value" ""
			(at 0 0 90)
			(layer "B.Fab")
			(effects
				(font
					(size 1.27 1.27)
				)
				(justify mirror)
			)
		)
		(duplicate_pad_numbers_are_jumpers no)
		(fp_line
			(start 0.299974 -0.150114)
			(end -0.299974 -0.150114)
			(stroke
				(width 0.1)
				(type default)
			)
			(layer "B.Fab")
		)
		(fp_line
			(start -0.299974 -0.150114)
			(end -0.299974 0.150114)
			(stroke
				(width 0.1)
				(type default)
			)
			(layer "B.Fab")
		)
		(fp_line
			(start 0.299974 0.150114)
			(end 0.299974 -0.150114)
			(stroke
				(width 0.1)
				(type default)
			)
			(layer "B.Fab")
		)
		(fp_line
			(start -0.299974 0.150114)
			(end 0.299974 0.150114)
			(stroke
				(width 0.1)
				(type default)
			)
			(layer "B.Fab")
		)
		(pad "1" smd rect
			(at 0.2667 0 270)
			(size 0.3048 0.381)
			(layers "B.Cu" "B.Mask" "B.Paste")
			(net "P0V8_SERDES_VDDA_PEX1")
		)
		(pad "2" smd rect
			(at -0.2667 0 270)
			(size 0.3048 0.381)
			(layers "B.Cu" "B.Mask" "B.Paste")
			(net "GND")
		)
	)
	(footprint ""
		(layer "B.Cu")
		(at 399.400014 -303.499774 -90)
		(property "Reference" "C3438"
			(at 0 0 90)
			(layer "B.SilkS")
			(hide yes)
			(effects
				(font
					(size 1.27 1.27)
				)
				(justify mirror)
			)
		)
		(property "Value" ""
			(at 0 0 90)
			(layer "B.Fab")
			(effects
				(font
					(size 1.27 1.27)
				)
				(justify mirror)
			)
		)
		(duplicate_pad_numbers_are_jumpers no)
		(fp_line
			(start -0.299974 0.150114)
			(end 0.299974 0.150114)
			(stroke
				(width 0.1)
				(type default)
			)
			(layer "B.Fab")
		)
		(fp_line
			(start 0.299974 0.150114)
			(end 0.299974 -0.150114)
			(stroke
				(width 0.1)
				(type default)
			)
			(layer "B.Fab")
		)
		(fp_line
			(start -0.299974 -0.150114)
			(end -0.299974 0.150114)
			(stroke
				(width 0.1)
				(type default)
			)
			(layer "B.Fab")
		)
		(fp_line
			(start 0.299974 -0.150114)
			(end -0.299974 -0.150114)
			(stroke
				(width 0.1)
				(type default)
			)
			(layer "B.Fab")
		)
		(pad "1" smd rect
			(at 0.2667 0 90)
			(size 0.3048 0.381)
			(layers "B.Cu" "B.Mask" "B.Paste")
			(net "P1V25_PEX3")
		)
		(pad "2" smd rect
			(at -0.2667 0 90)
			(size 0.3048 0.381)
			(layers "B.Cu" "B.Mask" "B.Paste")
			(net "GND")
		)
	)
	(footprint ""
		(layer "B.Cu")
		(at 358.440736 -321.84594 -90)
		(property "Reference" "R6537"
			(at 0 0 90)
			(layer "B.SilkS")
			(hide yes)
			(effects
				(font
					(size 1.27 1.27)
				)
				(justify mirror)
			)
		)
		(property "Value" ""
			(at 0 0 90)
			(layer "B.Fab")
			(effects
				(font
					(size 1.27 1.27)
				)
				(justify mirror)
			)
		)
		(duplicate_pad_numbers_are_jumpers no)
		(fp_line
			(start -0.7874 0.4064)
			(end 0.7874 0.4064)
			(stroke
				(width 0.1524)
				(type default)
			)
			(layer "B.SilkS")
		)
		(fp_line
			(start 0.7874 0.4064)
			(end 0.7874 -0.4064)
			(stroke
				(width 0.1524)
				(type default)
			)
			(layer "B.SilkS")
		)
		(fp_line
			(start -0.7874 -0.4064)
			(end -0.7874 0.4064)
			(stroke
				(width 0.1524)
				(type default)
			)
			(layer "B.SilkS")
		)
		(fp_line
			(start 0.7874 -0.4064)
			(end -0.7874 -0.4064)
			(stroke
				(width 0.1524)
				(type default)
			)
			(layer "B.SilkS")
		)
		(fp_line
			(start -0.67945 0.3048)
			(end -0.120396 0.3048)
			(stroke
				(width 0.1)
				(type default)
			)
			(layer "B.Fab")
		)
		(fp_line
			(start -0.120396 0.3048)
			(end -0.120396 0.2794)
			(stroke
				(width 0.1)
				(type default)
			)
			(layer "B.Fab")
		)
		(fp_line
			(start 0.12065 0.3048)
			(end 0.67945 0.3048)
			(stroke
				(width 0.1)
				(type default)
			)
			(layer "B.Fab")
		)
		(fp_line
			(start 0.67945 0.3048)
			(end 0.67945 -0.305054)
			(stroke
				(width 0.1)
				(type default)
			)
			(layer "B.Fab")
		)
		(fp_line
			(start -0.120396 0.2794)
			(end 0.12065 0.2794)
			(stroke
				(width 0.1)
				(type default)
			)
			(layer "B.Fab")
		)
		(fp_line
			(start 0.12065 0.2794)
			(end 0.12065 0.3048)
			(stroke
				(width 0.1)
				(type default)
			)
			(layer "B.Fab")
		)
		(fp_line
			(start -0.12065 -0.2794)
			(end -0.12065 -0.3048)
			(stroke
				(width 0.1)
				(type default)
			)
			(layer "B.Fab")
		)
		(fp_line
			(start 0.12065 -0.2794)
			(end -0.12065 -0.2794)
			(stroke
				(width 0.1)
				(type default)
			)
			(layer "B.Fab")
		)
		(fp_line
			(start -0.67945 -0.3048)
			(end -0.67945 0.3048)
			(stroke
				(width 0.1)
				(type default)
			)
			(layer "B.Fab")
		)
		(fp_line
			(start -0.12065 -0.3048)
			(end -0.67945 -0.3048)
			(stroke
				(width 0.1)
				(type default)
			)
			(layer "B.Fab")
		)
		(fp_line
			(start 0.12065 -0.305054)
			(end 0.12065 -0.2794)
			(stroke
				(width 0.1)
				(type default)
			)
			(layer "B.Fab")
		)
		(fp_line
			(start 0.67945 -0.305054)
			(end 0.12065 -0.305054)
			(stroke
				(width 0.1)
				(type default)
			)
			(layer "B.Fab")
		)
		(pad "1" smd circle
			(at 0.40005 0 90)
			(size 0 0)
			(layers "B.Cu" "B.Mask" "B.Paste")
			(net "P0V8_SERDES_VDDA_PEX3")
		)
		(pad "2" smd circle
			(at -0.40005 0 90)
			(size 0 0)
			(layers "B.Cu" "B.Mask" "B.Paste")
			(net "P0V8_SERDES_VDDA_PEX3_C2")
		)
	)
	(footprint ""
		(layer "B.Cu")
		(at 71.049896 -297.32478 180)
		(property "Reference" "C2911"
			(at 0 0 0)
			(layer "B.SilkS")
			(hide yes)
			(effects
				(font
					(size 1.27 1.27)
				)
				(justify mirror)
			)
		)
		(property "Value" ""
			(at 0 0 0)
			(layer "B.Fab")
			(effects
				(font
					(size 1.27 1.27)
				)
				(justify mirror)
			)
		)
		(duplicate_pad_numbers_are_jumpers no)
		(fp_line
			(start 0.299974 0.150114)
			(end 0.299974 -0.150114)
			(stroke
				(width 0.1)
				(type default)
			)
			(layer "B.Fab")
		)
		(fp_line
			(start 0.299974 -0.150114)
			(end -0.299974 -0.150114)
			(stroke
				(width 0.1)
				(type default)
			)
			(layer "B.Fab")
		)
		(fp_line
			(start -0.299974 0.150114)
			(end 0.299974 0.150114)
			(stroke
				(width 0.1)
				(type default)
			)
			(layer "B.Fab")
		)
		(fp_line
			(start -0.299974 -0.150114)
			(end -0.299974 0.150114)
			(stroke
				(width 0.1)
				(type default)
			)
			(layer "B.Fab")
		)
		(pad "1" smd rect
			(at 0.2667 0)
			(size 0.3048 0.381)
			(layers "B.Cu" "B.Mask" "B.Paste")
			(net "P1V25_PEX0")
		)
		(pad "2" smd rect
			(at -0.2667 0)
			(size 0.3048 0.381)
			(layers "B.Cu" "B.Mask" "B.Paste")
			(net "GND")
		)
	)
	(footprint ""
		(layer "B.Cu")
		(at 175.749966 -288.299906 90)
		(property "Reference" "C3099"
			(at 0 0 90)
			(layer "B.SilkS")
			(hide yes)
			(effects
				(font
					(size 1.27 1.27)
				)
				(justify mirror)
			)
		)
		(property "Value" ""
			(at 0 0 90)
			(layer "B.Fab")
			(effects
				(font
					(size 1.27 1.27)
				)
				(justify mirror)
			)
		)
		(duplicate_pad_numbers_are_jumpers no)
		(fp_line
			(start 0.299974 -0.150114)
			(end -0.299974 -0.150114)
			(stroke
				(width 0.1)
				(type default)
			)
			(layer "B.Fab")
		)
		(fp_line
			(start -0.299974 -0.150114)
			(end -0.299974 0.150114)
			(stroke
				(width 0.1)
				(type default)
			)
			(layer "B.Fab")
		)
		(fp_line
			(start 0.299974 0.150114)
			(end 0.299974 -0.150114)
			(stroke
				(width 0.1)
				(type default)
			)
			(layer "B.Fab")
		)
		(fp_line
			(start -0.299974 0.150114)
			(end 0.299974 0.150114)
			(stroke
				(width 0.1)
				(type default)
			)
			(layer "B.Fab")
		)
		(pad "1" smd rect
			(at 0.2667 0 270)
			(size 0.3048 0.381)
			(layers "B.Cu" "B.Mask" "B.Paste")
			(net "P1V25_PEX1")
		)
		(pad "2" smd rect
			(at -0.2667 0 270)
			(size 0.3048 0.381)
			(layers "B.Cu" "B.Mask" "B.Paste")
			(net "GND")
		)
	)
	(footprint ""
		(layer "B.Cu")
		(at 176.491646 -296.37482 180)
		(property "Reference" "C1373"
			(at 0 0 0)
			(layer "B.SilkS")
			(hide yes)
			(effects
				(font
					(size 1.27 1.27)
				)
				(justify mirror)
			)
		)
		(property "Value" ""
			(at 0 0 0)
			(layer "B.Fab")
			(effects
				(font
					(size 1.27 1.27)
				)
				(justify mirror)
			)
		)
		(duplicate_pad_numbers_are_jumpers no)
		(fp_line
			(start 0.299974 0.150114)
			(end 0.299974 -0.150114)
			(stroke
				(width 0.1)
				(type default)
			)
			(layer "B.Fab")
		)
		(fp_line
			(start 0.299974 -0.150114)
			(end -0.299974 -0.150114)
			(stroke
				(width 0.1)
				(type default)
			)
			(layer "B.Fab")
		)
		(fp_line
			(start -0.299974 0.150114)
			(end 0.299974 0.150114)
			(stroke
				(width 0.1)
				(type default)
			)
			(layer "B.Fab")
		)
		(fp_line
			(start -0.299974 -0.150114)
			(end -0.299974 0.150114)
			(stroke
				(width 0.1)
				(type default)
			)
			(layer "B.Fab")
		)
		(pad "1" smd rect
			(at 0.2667 0)
			(size 0.3048 0.381)
			(layers "B.Cu" "B.Mask" "B.Paste")
			(net "P0V8_PEX1")
		)
		(pad "2" smd rect
			(at -0.2667 0)
			(size 0.3048 0.381)
			(layers "B.Cu" "B.Mask" "B.Paste")
			(net "GND")
		)
	)
	(footprint ""
		(layer "B.Cu")
		(at 171.474892 -286.399732 90)
		(property "Reference" "C3133"
			(at 0 0 90)
			(layer "B.SilkS")
			(hide yes)
			(effects
				(font
					(size 1.27 1.27)
				)
				(justify mirror)
			)
		)
		(property "Value" ""
			(at 0 0 90)
			(layer "B.Fab")
			(effects
				(font
					(size 1.27 1.27)
				)
				(justify mirror)
			)
		)
		(duplicate_pad_numbers_are_jumpers no)
		(fp_line
			(start 0.299974 -0.150114)
			(end -0.299974 -0.150114)
			(stroke
				(width 0.1)
				(type default)
			)
			(layer "B.Fab")
		)
		(fp_line
			(start -0.299974 -0.150114)
			(end -0.299974 0.150114)
			(stroke
				(width 0.1)
				(type default)
			)
			(layer "B.Fab")
		)
		(fp_line
			(start 0.299974 0.150114)
			(end 0.299974 -0.150114)
			(stroke
				(width 0.1)
				(type default)
			)
			(layer "B.Fab")
		)
		(fp_line
			(start -0.299974 0.150114)
			(end 0.299974 0.150114)
			(stroke
				(width 0.1)
				(type default)
			)
			(layer "B.Fab")
		)
		(pad "1" smd rect
			(at 0.2667 0 270)
			(size 0.3048 0.381)
			(layers "B.Cu" "B.Mask" "B.Paste")
			(net "P1V25_SERDES_VDDPLL_PEX1")
		)
		(pad "2" smd rect
			(at -0.2667 0 270)
			(size 0.3048 0.381)
			(layers "B.Cu" "B.Mask" "B.Paste")
			(net "GND")
		)
	)
	(footprint ""
		(layer "B.Cu")
		(at 62.974728 -293.99992 90)
		(property "Reference" "C1142"
			(at 0 0 90)
			(layer "B.SilkS")
			(hide yes)
			(effects
				(font
					(size 1.27 1.27)
				)
				(justify mirror)
			)
		)
		(property "Value" ""
			(at 0 0 90)
			(layer "B.Fab")
			(effects
				(font
					(size 1.27 1.27)
				)
				(justify mirror)
			)
		)
		(duplicate_pad_numbers_are_jumpers no)
		(fp_line
			(start 0.299974 -0.150114)
			(end -0.299974 -0.150114)
			(stroke
				(width 0.1)
				(type default)
			)
			(layer "B.Fab")
		)
		(fp_line
			(start -0.299974 -0.150114)
			(end -0.299974 0.150114)
			(stroke
				(width 0.1)
				(type default)
			)
			(layer "B.Fab")
		)
		(fp_line
			(start 0.299974 0.150114)
			(end 0.299974 -0.150114)
			(stroke
				(width 0.1)
				(type default)
			)
			(layer "B.Fab")
		)
		(fp_line
			(start -0.299974 0.150114)
			(end 0.299974 0.150114)
			(stroke
				(width 0.1)
				(type default)
			)
			(layer "B.Fab")
		)
		(pad "1" smd rect
			(at 0.2667 0 270)
			(size 0.3048 0.381)
			(layers "B.Cu" "B.Mask" "B.Paste")
			(net "P0V8_PEX0")
		)
		(pad "2" smd rect
			(at -0.2667 0 270)
			(size 0.3048 0.381)
			(layers "B.Cu" "B.Mask" "B.Paste")
			(net "GND")
		)
	)
	(footprint ""
		(layer "B.Cu")
		(at 251.918216 -227.084382 90)
		(property "Reference" "U67"
			(at -1.990598 3.22961 270)
			(unlocked yes)
			(layer "B.SilkS")
			(effects
				(font
					(size 0.7874 0.5842)
					(thickness 0.1524)
				)
				(justify mirror)
			)
		)
		(property "Value" ""
			(at 0 0 90)
			(layer "B.Fab")
			(effects
				(font
					(size 1.27 1.27)
				)
				(justify mirror)
			)
		)
		(duplicate_pad_numbers_are_jumpers no)
		(fp_line
			(start 1.8288 -2.4892)
			(end 0.5588 -2.4892)
			(stroke
				(width 0.1524)
				(type default)
			)
			(layer "B.SilkS")
		)
		(fp_line
			(start 0.5588 -2.4892)
			(end 0 -1.9304)
			(stroke
				(width 0.1524)
				(type default)
			)
			(layer "B.SilkS")
		)
		(fp_line
			(start -0.5588 -2.4892)
			(end -1.8288 -2.4892)
			(stroke
				(width 0.1524)
				(type default)
			)
			(layer "B.SilkS")
		)
		(fp_line
			(start -1.8288 -2.4892)
			(end -1.8161 2.4892)
			(stroke
				(width 0.1524)
				(type default)
			)
			(layer "B.SilkS")
		)
		(fp_line
			(start 0 -1.9304)
			(end -0.5588 -2.4892)
			(stroke
				(width 0.1524)
				(type default)
			)
			(layer "B.SilkS")
		)
		(fp_line
			(start 1.8288 2.4892)
			(end 1.8288 -2.4892)
			(stroke
				(width 0.1524)
				(type default)
			)
			(layer "B.SilkS")
		)
		(fp_line
			(start -1.8161 2.4892)
			(end 1.8288 2.4892)
			(stroke
				(width 0.1524)
				(type default)
			)
			(layer "B.SilkS")
		)
		(fp_poly
			(pts
				(xy 4.23672 -1.989328) (xy 4.23672 -2.614168) (xy 3.683 -2.286)
			)
			(stroke
				(width 0)
				(type default)
			)
			(fill yes)
			(layer "B.SilkS")
		)
		(fp_line
			(start 1.9939 -2.4892)
			(end -1.9939 -2.4892)
			(stroke
				(width 0.1)
				(type default)
			)
			(layer "B.Fab")
		)
		(fp_line
			(start -1.9939 -2.4892)
			(end -1.9939 -2.3876)
			(stroke
				(width 0.1)
				(type default)
			)
			(layer "B.Fab")
		)
		(fp_line
			(start 3.0988 -2.3876)
			(end 1.9939 -2.3876)
			(stroke
				(width 0.1)
				(type default)
			)
			(layer "B.Fab")
		)
		(fp_line
			(start 1.9939 -2.3876)
			(end 1.9939 -2.4892)
			(stroke
				(width 0.1)
				(type default)
			)
			(layer "B.Fab")
		)
		(fp_line
			(start 1.9939 -2.3876)
			(end 1.9812 -2.3876)
			(stroke
				(width 0.1)
				(type default)
			)
			(layer "B.Fab")
		)
		(fp_line
			(start -1.9939 -2.3876)
			(end -3.0988 -2.3876)
			(stroke
				(width 0.1)
				(type default)
			)
			(layer "B.Fab")
		)
		(fp_line
			(start -1.9939 -2.3876)
			(end -1.9939 2.3876)
			(stroke
				(width 0.1)
				(type default)
			)
			(layer "B.Fab")
		)
		(fp_line
			(start -3.0988 -2.3876)
			(end -3.0988 2.3876)
			(stroke
				(width 0.1)
				(type default)
			)
			(layer "B.Fab")
		)
		(fp_line
			(start -3.0988 -2.3876)
			(end -3.0988 2.3876)
			(stroke
				(width 0.1)
				(type default)
			)
			(layer "B.Fab")
		)
		(fp_line
			(start 3.0988 2.3876)
			(end 3.0988 -2.3876)
			(stroke
				(width 0.1)
				(type default)
			)
			(layer "B.Fab")
		)
		(fp_line
			(start 3.0988 2.3876)
			(end 3.0988 -2.3876)
			(stroke
				(width 0.1)
				(type default)
			)
			(layer "B.Fab")
		)
		(fp_line
			(start 1.9939 2.3876)
			(end 1.9939 -2.3876)
			(stroke
				(width 0.1)
				(type default)
			)
			(layer "B.Fab")
		)
		(fp_line
			(start 1.9939 2.3876)
			(end 3.0988 2.3876)
			(stroke
				(width 0.1)
				(type default)
			)
			(layer "B.Fab")
		)
		(fp_line
			(start -1.9939 2.3876)
			(end -1.9939 2.4892)
			(stroke
				(width 0.1)
				(type default)
			)
			(layer "B.Fab")
		)
		(fp_line
			(start -3.0988 2.3876)
			(end -1.9939 2.3876)
			(stroke
				(width 0.1)
				(type default)
			)
			(layer "B.Fab")
		)
		(fp_line
			(start 1.9939 2.4892)
			(end 1.9939 2.3876)
			(stroke
				(width 0.1)
				(type default)
			)
			(layer "B.Fab")
		)
		(fp_line
			(start -1.9939 2.4892)
			(end 1.9939 2.4892)
			(stroke
				(width 0.1)
				(type default)
			)
			(layer "B.Fab")
		)
		(fp_line
			(start -1.9939 2.4892)
			(end -2.0066 2.4892)
			(stroke
				(width 0.1)
				(type default)
			)
			(layer "B.Fab")
		)
		(fp_line
			(start -1.9939 2.5019)
			(end -1.9939 2.4892)
			(stroke
				(width 0.1)
				(type default)
			)
			(layer "B.Fab")
		)
		(fp_poly
			(pts
				(xy 4.23672 -1.989328) (xy 4.23672 -2.614168) (xy 3.683 -2.286)
			)
			(stroke
				(width 0)
				(type default)
			)
			(fill yes)
			(layer "B.Fab")
		)
		(pad "1" smd rect
			(at 2.7432 -2.2225)
			(size 0.3556 1.5494)
			(layers "B.Cu" "B.Mask" "B.Paste")
			(net "SEL_FLASH_PEX2_BUF_R")
		)
		(pad "2" smd rect
			(at 2.7432 -1.5875)
			(size 0.3556 1.5494)
			(layers "B.Cu" "B.Mask" "B.Paste")
			(net "SPI_PEX2_CS_R_N")
		)
		(pad "3" smd rect
			(at 2.7432 -0.9525)
			(size 0.3556 1.5494)
			(layers "B.Cu" "B.Mask" "B.Paste")
			(net "SPI_BIC1_CS0_LS23_R1_N")
		)
		(pad "4" smd rect
			(at 2.7432 -0.3175)
			(size 0.3556 1.5494)
			(layers "B.Cu" "B.Mask" "B.Paste")
			(net "SPI_PEX2_CS_MUX_N")
		)
		(pad "5" smd rect
			(at 2.7432 0.3175)
			(size 0.3556 1.5494)
			(layers "B.Cu" "B.Mask" "B.Paste")
			(net "SPI_PEX2_CLK_R")
		)
		(pad "6" smd rect
			(at 2.7432 0.9525)
			(size 0.3556 1.5494)
			(layers "B.Cu" "B.Mask" "B.Paste")
			(net "SPI_BIC1_CLK_LS23_R1")
		)
		(pad "7" smd rect
			(at 2.7432 1.5875)
			(size 0.3556 1.5494)
			(layers "B.Cu" "B.Mask" "B.Paste")
			(net "SPI_PEX2_CLK_MUX")
		)
		(pad "8" smd rect
			(at 2.7432 2.2225)
			(size 0.3556 1.5494)
			(layers "B.Cu" "B.Mask" "B.Paste")
			(net "GND")
		)
		(pad "9" smd rect
			(at -2.7432 2.2225)
			(size 0.3556 1.5494)
			(layers "B.Cu" "B.Mask" "B.Paste")
			(net "SPI_PEX2_SDIO0_MUX")
		)
		(pad "10" smd rect
			(at -2.7432 1.5875)
			(size 0.3556 1.5494)
			(layers "B.Cu" "B.Mask" "B.Paste")
			(net "SPI_BIC1_MOSI_LS23_R1")
		)
		(pad "11" smd rect
			(at -2.7432 0.9525)
			(size 0.3556 1.5494)
			(layers "B.Cu" "B.Mask" "B.Paste")
			(net "SPI_PEX2_SDIO0_R")
		)
		(pad "12" smd rect
			(at -2.7432 0.3175)
			(size 0.3556 1.5494)
			(layers "B.Cu" "B.Mask" "B.Paste")
			(net "SPI_PEX2_SDIO1_MUX")
		)
		(pad "13" smd rect
			(at -2.7432 -0.3175)
			(size 0.3556 1.5494)
			(layers "B.Cu" "B.Mask" "B.Paste")
			(net "SPI_BIC1_MISO_LS23_R1")
		)
		(pad "14" smd rect
			(at -2.7432 -0.9525)
			(size 0.3556 1.5494)
			(layers "B.Cu" "B.Mask" "B.Paste")
			(net "SPI_PEX2_SDIO1_R")
		)
		(pad "15" smd rect
			(at -2.7432 -1.5875)
			(size 0.3556 1.5494)
			(layers "B.Cu" "B.Mask" "B.Paste")
			(net "SPI_MUX_PEX2_EN_N")
		)
		(pad "16" smd rect
			(at -2.7432 -2.2225)
			(size 0.3556 1.5494)
			(layers "B.Cu" "B.Mask" "B.Paste")
			(net "P3V3_AUX")
		)
	)
	(footprint ""
		(layer "B.Cu")
		(at 112.033812 -321.36334 -90)
		(property "Reference" "R6451"
			(at 0 0 90)
			(layer "B.SilkS")
			(hide yes)
			(effects
				(font
					(size 1.27 1.27)
				)
				(justify mirror)
			)
		)
		(property "Value" ""
			(at 0 0 90)
			(layer "B.Fab")
			(effects
				(font
					(size 1.27 1.27)
				)
				(justify mirror)
			)
		)
		(duplicate_pad_numbers_are_jumpers no)
		(fp_line
			(start -0.7874 0.4064)
			(end 0.7874 0.4064)
			(stroke
				(width 0.1524)
				(type default)
			)
			(layer "B.SilkS")
		)
		(fp_line
			(start 0.7874 0.4064)
			(end 0.7874 -0.4064)
			(stroke
				(width 0.1524)
				(type default)
			)
			(layer "B.SilkS")
		)
		(fp_line
			(start -0.7874 -0.4064)
			(end -0.7874 0.4064)
			(stroke
				(width 0.1524)
				(type default)
			)
			(layer "B.SilkS")
		)
		(fp_line
			(start 0.7874 -0.4064)
			(end -0.7874 -0.4064)
			(stroke
				(width 0.1524)
				(type default)
			)
			(layer "B.SilkS")
		)
		(fp_line
			(start -0.67945 0.3048)
			(end -0.120396 0.3048)
			(stroke
				(width 0.1)
				(type default)
			)
			(layer "B.Fab")
		)
		(fp_line
			(start -0.120396 0.3048)
			(end -0.120396 0.2794)
			(stroke
				(width 0.1)
				(type default)
			)
			(layer "B.Fab")
		)
		(fp_line
			(start 0.12065 0.3048)
			(end 0.67945 0.3048)
			(stroke
				(width 0.1)
				(type default)
			)
			(layer "B.Fab")
		)
		(fp_line
			(start 0.67945 0.3048)
			(end 0.67945 -0.305054)
			(stroke
				(width 0.1)
				(type default)
			)
			(layer "B.Fab")
		)
		(fp_line
			(start -0.120396 0.2794)
			(end 0.12065 0.2794)
			(stroke
				(width 0.1)
				(type default)
			)
			(layer "B.Fab")
		)
		(fp_line
			(start 0.12065 0.2794)
			(end 0.12065 0.3048)
			(stroke
				(width 0.1)
				(type default)
			)
			(layer "B.Fab")
		)
		(fp_line
			(start -0.12065 -0.2794)
			(end -0.12065 -0.3048)
			(stroke
				(width 0.1)
				(type default)
			)
			(layer "B.Fab")
		)
		(fp_line
			(start 0.12065 -0.2794)
			(end -0.12065 -0.2794)
			(stroke
				(width 0.1)
				(type default)
			)
			(layer "B.Fab")
		)
		(fp_line
			(start -0.67945 -0.3048)
			(end -0.67945 0.3048)
			(stroke
				(width 0.1)
				(type default)
			)
			(layer "B.Fab")
		)
		(fp_line
			(start -0.12065 -0.3048)
			(end -0.67945 -0.3048)
			(stroke
				(width 0.1)
				(type default)
			)
			(layer "B.Fab")
		)
		(fp_line
			(start 0.12065 -0.305054)
			(end 0.12065 -0.2794)
			(stroke
				(width 0.1)
				(type default)
			)
			(layer "B.Fab")
		)
		(fp_line
			(start 0.67945 -0.305054)
			(end 0.12065 -0.305054)
			(stroke
				(width 0.1)
				(type default)
			)
			(layer "B.Fab")
		)
		(pad "1" smd circle
			(at 0.40005 0 90)
			(size 0 0)
			(layers "B.Cu" "B.Mask" "B.Paste")
			(net "P0V8_SERDES_VDDA_PEX0")
		)
		(pad "2" smd circle
			(at -0.40005 0 90)
			(size 0 0)
			(layers "B.Cu" "B.Mask" "B.Paste")
			(net "P0V8_SERDES_VDDA_PEX0_C2")
		)
	)
	(footprint ""
		(layer "B.Cu")
		(at 51.574954 -286.399732 90)
		(property "Reference" "C2985"
			(at 0 0 90)
			(layer "B.SilkS")
			(hide yes)
			(effects
				(font
					(size 1.27 1.27)
				)
				(justify mirror)
			)
		)
		(property "Value" ""
			(at 0 0 90)
			(layer "B.Fab")
			(effects
				(font
					(size 1.27 1.27)
				)
				(justify mirror)
			)
		)
		(duplicate_pad_numbers_are_jumpers no)
		(fp_line
			(start 0.299974 -0.150114)
			(end -0.299974 -0.150114)
			(stroke
				(width 0.1)
				(type default)
			)
			(layer "B.Fab")
		)
		(fp_line
			(start -0.299974 -0.150114)
			(end -0.299974 0.150114)
			(stroke
				(width 0.1)
				(type default)
			)
			(layer "B.Fab")
		)
		(fp_line
			(start 0.299974 0.150114)
			(end 0.299974 -0.150114)
			(stroke
				(width 0.1)
				(type default)
			)
			(layer "B.Fab")
		)
		(fp_line
			(start -0.299974 0.150114)
			(end 0.299974 0.150114)
			(stroke
				(width 0.1)
				(type default)
			)
			(layer "B.Fab")
		)
		(pad "1" smd rect
			(at 0.2667 0 270)
			(size 0.3048 0.381)
			(layers "B.Cu" "B.Mask" "B.Paste")
			(net "P1V25_SERDES_VDDPLL_PEX0")
		)
		(pad "2" smd rect
			(at -0.2667 0 270)
			(size 0.3048 0.381)
			(layers "B.Cu" "B.Mask" "B.Paste")
			(net "GND")
		)
	)
	(footprint ""
		(layer "B.Cu")
		(at 236.234732 -292.533832)
		(property "Reference" "PC996"
			(at 0 0 0)
			(layer "B.SilkS")
			(hide yes)
			(effects
				(font
					(size 1.27 1.27)
				)
				(justify mirror)
			)
		)
		(property "Value" ""
			(at 0 0 0)
			(layer "B.Fab")
			(effects
				(font
					(size 1.27 1.27)
				)
				(justify mirror)
			)
		)
		(duplicate_pad_numbers_are_jumpers no)
		(fp_line
			(start -1.524 -0.762)
			(end -1.524 0.762)
			(stroke
				(width 0.1524)
				(type default)
			)
			(layer "B.SilkS")
		)
		(fp_line
			(start -1.524 0.762)
			(end 1.524 0.762)
			(stroke
				(width 0.1524)
				(type default)
			)
			(layer "B.SilkS")
		)
		(fp_line
			(start 1.524 -0.762)
			(end -1.524 -0.762)
			(stroke
				(width 0.1524)
				(type default)
			)
			(layer "B.SilkS")
		)
		(fp_line
			(start 1.524 0.762)
			(end 1.524 -0.762)
			(stroke
				(width 0.1524)
				(type default)
			)
			(layer "B.SilkS")
		)
		(fp_line
			(start -1.1049 -0.724916)
			(end 1.1049 -0.724916)
			(stroke
				(width 0.1)
				(type default)
			)
			(layer "B.Fab")
		)
		(fp_line
			(start -1.1049 0.724916)
			(end -1.1049 -0.724916)
			(stroke
				(width 0.1)
				(type default)
			)
			(layer "B.Fab")
		)
		(fp_line
			(start 1.1049 -0.724916)
			(end 1.1049 0.724916)
			(stroke
				(width 0.1)
				(type default)
			)
			(layer "B.Fab")
		)
		(fp_line
			(start 1.1049 0.724916)
			(end -1.1049 0.724916)
			(stroke
				(width 0.1)
				(type default)
			)
			(layer "B.Fab")
		)
		(pad "1" smd rect
			(at 0.889 0)
			(size 1.016 1.27)
			(layers "B.Cu" "B.Mask" "B.Paste")
			(net "P1V25_PEX2_R")
		)
		(pad "2" smd rect
			(at -0.889 0)
			(size 1.016 1.27)
			(layers "B.Cu" "B.Mask" "B.Paste")
			(net "GND")
		)
	)
	(footprint ""
		(layer "B.Cu")
		(at 16.19123 -223.937068 90)
		(property "Reference" "R3442"
			(at 0 0 90)
			(layer "B.SilkS")
			(hide yes)
			(effects
				(font
					(size 1.27 1.27)
				)
				(justify mirror)
			)
		)
		(property "Value" ""
			(at 0 0 90)
			(layer "B.Fab")
			(effects
				(font
					(size 1.27 1.27)
				)
				(justify mirror)
			)
		)
		(duplicate_pad_numbers_are_jumpers no)
		(fp_line
			(start 0.7874 -0.4064)
			(end -0.7874 -0.4064)
			(stroke
				(width 0.1524)
				(type default)
			)
			(layer "B.SilkS")
		)
		(fp_line
			(start -0.7874 -0.4064)
			(end -0.7874 0.4064)
			(stroke
				(width 0.1524)
				(type default)
			)
			(layer "B.SilkS")
		)
		(fp_line
			(start 0.7874 0.4064)
			(end 0.7874 -0.4064)
			(stroke
				(width 0.1524)
				(type default)
			)
			(layer "B.SilkS")
		)
		(fp_line
			(start -0.7874 0.4064)
			(end 0.7874 0.4064)
			(stroke
				(width 0.1524)
				(type default)
			)
			(layer "B.SilkS")
		)
		(fp_line
			(start 0.67945 -0.305054)
			(end 0.12065 -0.305054)
			(stroke
				(width 0.1)
				(type default)
			)
			(layer "B.Fab")
		)
		(fp_line
			(start 0.12065 -0.305054)
			(end 0.12065 -0.2794)
			(stroke
				(width 0.1)
				(type default)
			)
			(layer "B.Fab")
		)
		(fp_line
			(start -0.12065 -0.3048)
			(end -0.67945 -0.3048)
			(stroke
				(width 0.1)
				(type default)
			)
			(layer "B.Fab")
		)
		(fp_line
			(start -0.67945 -0.3048)
			(end -0.67945 0.3048)
			(stroke
				(width 0.1)
				(type default)
			)
			(layer "B.Fab")
		)
		(fp_line
			(start 0.12065 -0.2794)
			(end -0.12065 -0.2794)
			(stroke
				(width 0.1)
				(type default)
			)
			(layer "B.Fab")
		)
		(fp_line
			(start -0.12065 -0.2794)
			(end -0.12065 -0.3048)
			(stroke
				(width 0.1)
				(type default)
			)
			(layer "B.Fab")
		)
		(fp_line
			(start 0.12065 0.2794)
			(end 0.12065 0.3048)
			(stroke
				(width 0.1)
				(type default)
			)
			(layer "B.Fab")
		)
		(fp_line
			(start -0.120396 0.2794)
			(end 0.12065 0.2794)
			(stroke
				(width 0.1)
				(type default)
			)
			(layer "B.Fab")
		)
		(fp_line
			(start 0.67945 0.3048)
			(end 0.67945 -0.305054)
			(stroke
				(width 0.1)
				(type default)
			)
			(layer "B.Fab")
		)
		(fp_line
			(start 0.12065 0.3048)
			(end 0.67945 0.3048)
			(stroke
				(width 0.1)
				(type default)
			)
			(layer "B.Fab")
		)
		(fp_line
			(start -0.120396 0.3048)
			(end -0.120396 0.2794)
			(stroke
				(width 0.1)
				(type default)
			)
			(layer "B.Fab")
		)
		(fp_line
			(start -0.67945 0.3048)
			(end -0.120396 0.3048)
			(stroke
				(width 0.1)
				(type default)
			)
			(layer "B.Fab")
		)
		(pad "1" smd circle
			(at 0.40005 0 270)
			(size 0 0)
			(layers "B.Cu" "B.Mask" "B.Paste")
			(net "SPI_MUX_PEX0_EN_N")
		)
		(pad "2" smd circle
			(at -0.40005 0 270)
			(size 0 0)
			(layers "B.Cu" "B.Mask" "B.Paste")
			(net "GND")
		)
	)
	(footprint ""
		(layer "B.Cu")
		(at 104.38257 -81.78419 90)
		(property "Reference" "C2662"
			(at 0 0 90)
			(layer "B.SilkS")
			(hide yes)
			(effects
				(font
					(size 1.27 1.27)
				)
				(justify mirror)
			)
		)
		(property "Value" ""
			(at 0 0 90)
			(layer "B.Fab")
			(effects
				(font
					(size 1.27 1.27)
				)
				(justify mirror)
			)
		)
		(duplicate_pad_numbers_are_jumpers no)
		(fp_line
			(start 1.524 -0.762)
			(end -1.524 -0.762)
			(stroke
				(width 0.1524)
				(type default)
			)
			(layer "B.SilkS")
		)
		(fp_line
			(start -1.524 -0.762)
			(end -1.524 0.762)
			(stroke
				(width 0.1524)
				(type default)
			)
			(layer "B.SilkS")
		)
		(fp_line
			(start 1.524 0.762)
			(end 1.524 -0.762)
			(stroke
				(width 0.1524)
				(type default)
			)
			(layer "B.SilkS")
		)
		(fp_line
			(start -1.524 0.762)
			(end 1.524 0.762)
			(stroke
				(width 0.1524)
				(type default)
			)
			(layer "B.SilkS")
		)
		(fp_line
			(start 1.1049 -0.724916)
			(end 1.1049 0.724916)
			(stroke
				(width 0.1)
				(type default)
			)
			(layer "B.Fab")
		)
		(fp_line
			(start -1.1049 -0.724916)
			(end 1.1049 -0.724916)
			(stroke
				(width 0.1)
				(type default)
			)
			(layer "B.Fab")
		)
		(fp_line
			(start 1.1049 0.724916)
			(end -1.1049 0.724916)
			(stroke
				(width 0.1)
				(type default)
			)
			(layer "B.Fab")
		)
		(fp_line
			(start -1.1049 0.724916)
			(end -1.1049 -0.724916)
			(stroke
				(width 0.1)
				(type default)
			)
			(layer "B.Fab")
		)
		(pad "1" smd rect
			(at 0.889 0 90)
			(size 1.016 1.27)
			(layers "B.Cu" "B.Mask" "B.Paste")
			(net "P3V3_VDD_9ZXL0851_0_7")
		)
		(pad "2" smd rect
			(at -0.889 0 90)
			(size 1.016 1.27)
			(layers "B.Cu" "B.Mask" "B.Paste")
			(net "GND")
		)
	)
	(footprint ""
		(layer "B.Cu")
		(at 292.32479 -297.79976 90)
		(property "Reference" "C1651"
			(at 0 0 90)
			(layer "B.SilkS")
			(hide yes)
			(effects
				(font
					(size 1.27 1.27)
				)
				(justify mirror)
			)
		)
		(property "Value" ""
			(at 0 0 90)
			(layer "B.Fab")
			(effects
				(font
					(size 1.27 1.27)
				)
				(justify mirror)
			)
		)
		(duplicate_pad_numbers_are_jumpers no)
		(fp_line
			(start 0.299974 -0.150114)
			(end -0.299974 -0.150114)
			(stroke
				(width 0.1)
				(type default)
			)
			(layer "B.Fab")
		)
		(fp_line
			(start -0.299974 -0.150114)
			(end -0.299974 0.150114)
			(stroke
				(width 0.1)
				(type default)
			)
			(layer "B.Fab")
		)
		(fp_line
			(start 0.299974 0.150114)
			(end 0.299974 -0.150114)
			(stroke
				(width 0.1)
				(type default)
			)
			(layer "B.Fab")
		)
		(fp_line
			(start -0.299974 0.150114)
			(end 0.299974 0.150114)
			(stroke
				(width 0.1)
				(type default)
			)
			(layer "B.Fab")
		)
		(pad "1" smd rect
			(at 0.2667 0 270)
			(size 0.3048 0.381)
			(layers "B.Cu" "B.Mask" "B.Paste")
			(net "P0V8_PEX2")
		)
		(pad "2" smd rect
			(at -0.2667 0 270)
			(size 0.3048 0.381)
			(layers "B.Cu" "B.Mask" "B.Paste")
			(net "GND")
		)
	)
	(footprint ""
		(layer "B.Cu")
		(at 406.470104 -305.399948 -90)
		(property "Reference" "C3497"
			(at 0 0 90)
			(layer "B.SilkS")
			(hide yes)
			(effects
				(font
					(size 1.27 1.27)
				)
				(justify mirror)
			)
		)
		(property "Value" ""
			(at 0 0 90)
			(layer "B.Fab")
			(effects
				(font
					(size 1.27 1.27)
				)
				(justify mirror)
			)
		)
		(duplicate_pad_numbers_are_jumpers no)
		(fp_line
			(start -0.299974 0.150114)
			(end 0.299974 0.150114)
			(stroke
				(width 0.1)
				(type default)
			)
			(layer "B.Fab")
		)
		(fp_line
			(start 0.299974 0.150114)
			(end 0.299974 -0.150114)
			(stroke
				(width 0.1)
				(type default)
			)
			(layer "B.Fab")
		)
		(fp_line
			(start -0.299974 -0.150114)
			(end -0.299974 0.150114)
			(stroke
				(width 0.1)
				(type default)
			)
			(layer "B.Fab")
		)
		(fp_line
			(start 0.299974 -0.150114)
			(end -0.299974 -0.150114)
			(stroke
				(width 0.1)
				(type default)
			)
			(layer "B.Fab")
		)
		(pad "1" smd rect
			(at 0.2667 0 90)
			(size 0.3048 0.381)
			(layers "B.Cu" "B.Mask" "B.Paste")
			(net "P1V25_SERDES_VDDPLL_PEX3")
		)
		(pad "2" smd rect
			(at -0.2667 0 90)
			(size 0.3048 0.381)
			(layers "B.Cu" "B.Mask" "B.Paste")
			(net "GND")
		)
	)
	(footprint ""
		(layer "B.Cu")
		(at 231.86771 -220.704156)
		(property "Reference" "C3611"
			(at 0 0 0)
			(layer "B.SilkS")
			(hide yes)
			(effects
				(font
					(size 1.27 1.27)
				)
				(justify mirror)
			)
		)
		(property "Value" ""
			(at 0 0 0)
			(layer "B.Fab")
			(effects
				(font
					(size 1.27 1.27)
				)
				(justify mirror)
			)
		)
		(duplicate_pad_numbers_are_jumpers no)
		(fp_line
			(start -0.69215 -0.2921)
			(end -0.69215 0.2921)
			(stroke
				(width 0.1524)
				(type default)
			)
			(layer "B.SilkS")
		)
		(fp_line
			(start -0.69215 0.2921)
			(end 0.69215 0.2921)
			(stroke
				(width 0.1524)
				(type default)
			)
			(layer "B.SilkS")
		)
		(fp_line
			(start 0.69215 -0.2921)
			(end -0.69215 -0.2921)
			(stroke
				(width 0.1524)
				(type default)
			)
			(layer "B.SilkS")
		)
		(fp_line
			(start 0.69215 0.2921)
			(end 0.69215 -0.2921)
			(stroke
				(width 0.1524)
				(type default)
			)
			(layer "B.SilkS")
		)
		(fp_line
			(start -0.51435 -0.2794)
			(end -0.51435 0.2794)
			(stroke
				(width 0.1)
				(type default)
			)
			(layer "B.Fab")
		)
		(fp_line
			(start -0.51435 0.2794)
			(end 0.51435 0.2794)
			(stroke
				(width 0.1)
				(type default)
			)
			(layer "B.Fab")
		)
		(fp_line
			(start 0.51435 -0.2794)
			(end -0.51435 -0.2794)
			(stroke
				(width 0.1)
				(type default)
			)
			(layer "B.Fab")
		)
		(fp_line
			(start 0.51435 0.2794)
			(end 0.51435 -0.2794)
			(stroke
				(width 0.1)
				(type default)
			)
			(layer "B.Fab")
		)
		(pad "1" smd circle
			(at 0.40005 0 180)
			(size 0 0)
			(layers "B.Cu" "B.Mask" "B.Paste")
			(net "P3V3_BIC_ADCAV33")
		)
		(pad "2" smd circle
			(at -0.40005 0 180)
			(size 0 0)
			(layers "B.Cu" "B.Mask" "B.Paste")
			(net "GND")
		)
		(zone
			(layer "B.Cu")
			(hatch none 0.5)
			(connect_pads
				(clearance 0)
			)
			(min_thickness 0.25)
			(keepout
				(tracks not_allowed)
				(vias allowed)
				(pads allowed)
				(copperpour not_allowed)
				(footprints allowed)
			)
			(placement
				(enabled no)
				(sheetname "")
			)
			(fill
				(thermal_gap 0.5)
				(thermal_bridge_width 0.5)
				(island_removal_mode 0)
			)
			(polygon
				(pts
					(xy 232.05821 -220.616526) (xy 231.96677 -220.55836) (xy 231.76738 -220.55836) (xy 231.67721 -220.616526)
					(xy 231.67721 -220.791786) (xy 231.76738 -220.850206) (xy 231.96677 -220.850206) (xy 232.05821 -220.79204)
				)
			)
		)
	)
	(footprint ""
		(layer "B.Cu")
		(at 400.349974 -292.099746 90)
		(property "Reference" "C1942"
			(at 0 0 90)
			(layer "B.SilkS")
			(hide yes)
			(effects
				(font
					(size 1.27 1.27)
				)
				(justify mirror)
			)
		)
		(property "Value" ""
			(at 0 0 90)
			(layer "B.Fab")
			(effects
				(font
					(size 1.27 1.27)
				)
				(justify mirror)
			)
		)
		(duplicate_pad_numbers_are_jumpers no)
		(fp_line
			(start 0.299974 -0.150114)
			(end -0.299974 -0.150114)
			(stroke
				(width 0.1)
				(type default)
			)
			(layer "B.Fab")
		)
		(fp_line
			(start -0.299974 -0.150114)
			(end -0.299974 0.150114)
			(stroke
				(width 0.1)
				(type default)
			)
			(layer "B.Fab")
		)
		(fp_line
			(start 0.299974 0.150114)
			(end 0.299974 -0.150114)
			(stroke
				(width 0.1)
				(type default)
			)
			(layer "B.Fab")
		)
		(fp_line
			(start -0.299974 0.150114)
			(end 0.299974 0.150114)
			(stroke
				(width 0.1)
				(type default)
			)
			(layer "B.Fab")
		)
		(pad "1" smd rect
			(at 0.2667 0 270)
			(size 0.3048 0.381)
			(layers "B.Cu" "B.Mask" "B.Paste")
			(net "P0V8_SERDES_VDDA_PEX3")
		)
		(pad "2" smd rect
			(at -0.2667 0 270)
			(size 0.3048 0.381)
			(layers "B.Cu" "B.Mask" "B.Paste")
			(net "GND")
		)
	)
	(footprint ""
		(layer "B.Cu")
		(at 139.275058 -228.346 90)
		(property "Reference" "R3460"
			(at 0 0 90)
			(layer "B.SilkS")
			(hide yes)
			(effects
				(font
					(size 1.27 1.27)
				)
				(justify mirror)
			)
		)
		(property "Value" ""
			(at 0 0 90)
			(layer "B.Fab")
			(effects
				(font
					(size 1.27 1.27)
				)
				(justify mirror)
			)
		)
		(duplicate_pad_numbers_are_jumpers no)
		(fp_line
			(start 0.7874 -0.4064)
			(end -0.7874 -0.4064)
			(stroke
				(width 0.1524)
				(type default)
			)
			(layer "B.SilkS")
		)
		(fp_line
			(start -0.7874 -0.4064)
			(end -0.7874 0.4064)
			(stroke
				(width 0.1524)
				(type default)
			)
			(layer "B.SilkS")
		)
		(fp_line
			(start 0.7874 0.4064)
			(end 0.7874 -0.4064)
			(stroke
				(width 0.1524)
				(type default)
			)
			(layer "B.SilkS")
		)
		(fp_line
			(start -0.7874 0.4064)
			(end 0.7874 0.4064)
			(stroke
				(width 0.1524)
				(type default)
			)
			(layer "B.SilkS")
		)
		(fp_line
			(start 0.67945 -0.305054)
			(end 0.12065 -0.305054)
			(stroke
				(width 0.1)
				(type default)
			)
			(layer "B.Fab")
		)
		(fp_line
			(start 0.12065 -0.305054)
			(end 0.12065 -0.2794)
			(stroke
				(width 0.1)
				(type default)
			)
			(layer "B.Fab")
		)
		(fp_line
			(start -0.12065 -0.3048)
			(end -0.67945 -0.3048)
			(stroke
				(width 0.1)
				(type default)
			)
			(layer "B.Fab")
		)
		(fp_line
			(start -0.67945 -0.3048)
			(end -0.67945 0.3048)
			(stroke
				(width 0.1)
				(type default)
			)
			(layer "B.Fab")
		)
		(fp_line
			(start 0.12065 -0.2794)
			(end -0.12065 -0.2794)
			(stroke
				(width 0.1)
				(type default)
			)
			(layer "B.Fab")
		)
		(fp_line
			(start -0.12065 -0.2794)
			(end -0.12065 -0.3048)
			(stroke
				(width 0.1)
				(type default)
			)
			(layer "B.Fab")
		)
		(fp_line
			(start 0.12065 0.2794)
			(end 0.12065 0.3048)
			(stroke
				(width 0.1)
				(type default)
			)
			(layer "B.Fab")
		)
		(fp_line
			(start -0.120396 0.2794)
			(end 0.12065 0.2794)
			(stroke
				(width 0.1)
				(type default)
			)
			(layer "B.Fab")
		)
		(fp_line
			(start 0.67945 0.3048)
			(end 0.67945 -0.305054)
			(stroke
				(width 0.1)
				(type default)
			)
			(layer "B.Fab")
		)
		(fp_line
			(start 0.12065 0.3048)
			(end 0.67945 0.3048)
			(stroke
				(width 0.1)
				(type default)
			)
			(layer "B.Fab")
		)
		(fp_line
			(start -0.120396 0.3048)
			(end -0.120396 0.2794)
			(stroke
				(width 0.1)
				(type default)
			)
			(layer "B.Fab")
		)
		(fp_line
			(start -0.67945 0.3048)
			(end -0.120396 0.3048)
			(stroke
				(width 0.1)
				(type default)
			)
			(layer "B.Fab")
		)
		(pad "1" smd circle
			(at 0.40005 0 270)
			(size 0 0)
			(layers "B.Cu" "B.Mask" "B.Paste")
			(net "SPI_PEX1_SDIO1_MUX_R")
		)
		(pad "2" smd circle
			(at -0.40005 0 270)
			(size 0 0)
			(layers "B.Cu" "B.Mask" "B.Paste")
			(net "SPI_PEX1_SDIO1_MUX")
		)
	)
	(footprint ""
		(layer "B.Cu")
		(at 181.92496 -297.79976 90)
		(property "Reference" "C1369"
			(at 0 0 90)
			(layer "B.SilkS")
			(hide yes)
			(effects
				(font
					(size 1.27 1.27)
				)
				(justify mirror)
			)
		)
		(property "Value" ""
			(at 0 0 90)
			(layer "B.Fab")
			(effects
				(font
					(size 1.27 1.27)
				)
				(justify mirror)
			)
		)
		(duplicate_pad_numbers_are_jumpers no)
		(fp_line
			(start 0.299974 -0.150114)
			(end -0.299974 -0.150114)
			(stroke
				(width 0.1)
				(type default)
			)
			(layer "B.Fab")
		)
		(fp_line
			(start -0.299974 -0.150114)
			(end -0.299974 0.150114)
			(stroke
				(width 0.1)
				(type default)
			)
			(layer "B.Fab")
		)
		(fp_line
			(start 0.299974 0.150114)
			(end 0.299974 -0.150114)
			(stroke
				(width 0.1)
				(type default)
			)
			(layer "B.Fab")
		)
		(fp_line
			(start -0.299974 0.150114)
			(end 0.299974 0.150114)
			(stroke
				(width 0.1)
				(type default)
			)
			(layer "B.Fab")
		)
		(pad "1" smd rect
			(at 0.2667 0 270)
			(size 0.3048 0.381)
			(layers "B.Cu" "B.Mask" "B.Paste")
			(net "P0V8_PEX1")
		)
		(pad "2" smd rect
			(at -0.2667 0 270)
			(size 0.3048 0.381)
			(layers "B.Cu" "B.Mask" "B.Paste")
			(net "GND")
		)
	)
	(footprint ""
		(layer "B.Cu")
		(at 305.149758 -297.79976 180)
		(property "Reference" "C3295"
			(at 0 0 0)
			(layer "B.SilkS")
			(hide yes)
			(effects
				(font
					(size 1.27 1.27)
				)
				(justify mirror)
			)
		)
		(property "Value" ""
			(at 0 0 0)
			(layer "B.Fab")
			(effects
				(font
					(size 1.27 1.27)
				)
				(justify mirror)
			)
		)
		(duplicate_pad_numbers_are_jumpers no)
		(fp_line
			(start 0.299974 0.150114)
			(end 0.299974 -0.150114)
			(stroke
				(width 0.1)
				(type default)
			)
			(layer "B.Fab")
		)
		(fp_line
			(start 0.299974 -0.150114)
			(end -0.299974 -0.150114)
			(stroke
				(width 0.1)
				(type default)
			)
			(layer "B.Fab")
		)
		(fp_line
			(start -0.299974 0.150114)
			(end 0.299974 0.150114)
			(stroke
				(width 0.1)
				(type default)
			)
			(layer "B.Fab")
		)
		(fp_line
			(start -0.299974 -0.150114)
			(end -0.299974 0.150114)
			(stroke
				(width 0.1)
				(type default)
			)
			(layer "B.Fab")
		)
		(pad "1" smd rect
			(at 0.2667 0)
			(size 0.3048 0.381)
			(layers "B.Cu" "B.Mask" "B.Paste")
			(net "P1V25_SERDES_VDDPLL_PEX2")
		)
		(pad "2" smd rect
			(at -0.2667 0)
			(size 0.3048 0.381)
			(layers "B.Cu" "B.Mask" "B.Paste")
			(net "GND")
		)
	)
	(footprint ""
		(layer "B.Cu")
		(at 379.365002 -221.066106)
		(property "Reference" "R930"
			(at 0 0 0)
			(layer "B.SilkS")
			(hide yes)
			(effects
				(font
					(size 1.27 1.27)
				)
				(justify mirror)
			)
		)
		(property "Value" ""
			(at 0 0 0)
			(layer "B.Fab")
			(effects
				(font
					(size 1.27 1.27)
				)
				(justify mirror)
			)
		)
		(duplicate_pad_numbers_are_jumpers no)
		(fp_line
			(start -0.7874 -0.4064)
			(end -0.7874 0.4064)
			(stroke
				(width 0.1524)
				(type default)
			)
			(layer "B.SilkS")
		)
		(fp_line
			(start -0.7874 0.4064)
			(end 0.7874 0.4064)
			(stroke
				(width 0.1524)
				(type default)
			)
			(layer "B.SilkS")
		)
		(fp_line
			(start 0.7874 -0.4064)
			(end -0.7874 -0.4064)
			(stroke
				(width 0.1524)
				(type default)
			)
			(layer "B.SilkS")
		)
		(fp_line
			(start 0.7874 0.4064)
			(end 0.7874 -0.4064)
			(stroke
				(width 0.1524)
				(type default)
			)
			(layer "B.SilkS")
		)
		(fp_line
			(start -0.67945 -0.3048)
			(end -0.67945 0.3048)
			(stroke
				(width 0.1)
				(type default)
			)
			(layer "B.Fab")
		)
		(fp_line
			(start -0.67945 0.3048)
			(end -0.120396 0.3048)
			(stroke
				(width 0.1)
				(type default)
			)
			(layer "B.Fab")
		)
		(fp_line
			(start -0.12065 -0.3048)
			(end -0.67945 -0.3048)
			(stroke
				(width 0.1)
				(type default)
			)
			(layer "B.Fab")
		)
		(fp_line
			(start -0.12065 -0.2794)
			(end -0.12065 -0.3048)
			(stroke
				(width 0.1)
				(type default)
			)
			(layer "B.Fab")
		)
		(fp_line
			(start -0.120396 0.2794)
			(end 0.12065 0.2794)
			(stroke
				(width 0.1)
				(type default)
			)
			(layer "B.Fab")
		)
		(fp_line
			(start -0.120396 0.3048)
			(end -0.120396 0.2794)
			(stroke
				(width 0.1)
				(type default)
			)
			(layer "B.Fab")
		)
		(fp_line
			(start 0.12065 -0.305054)
			(end 0.12065 -0.2794)
			(stroke
				(width 0.1)
				(type default)
			)
			(layer "B.Fab")
		)
		(fp_line
			(start 0.12065 -0.2794)
			(end -0.12065 -0.2794)
			(stroke
				(width 0.1)
				(type default)
			)
			(layer "B.Fab")
		)
		(fp_line
			(start 0.12065 0.2794)
			(end 0.12065 0.3048)
			(stroke
				(width 0.1)
				(type default)
			)
			(layer "B.Fab")
		)
		(fp_line
			(start 0.12065 0.3048)
			(end 0.67945 0.3048)
			(stroke
				(width 0.1)
				(type default)
			)
			(layer "B.Fab")
		)
		(fp_line
			(start 0.67945 -0.305054)
			(end 0.12065 -0.305054)
			(stroke
				(width 0.1)
				(type default)
			)
			(layer "B.Fab")
		)
		(fp_line
			(start 0.67945 0.3048)
			(end 0.67945 -0.305054)
			(stroke
				(width 0.1)
				(type default)
			)
			(layer "B.Fab")
		)
		(pad "1" smd circle
			(at 0.40005 0 180)
			(size 0 0)
			(layers "B.Cu" "B.Mask" "B.Paste")
			(net "UART_PEX1_SDB_BUF_R_RX")
		)
		(pad "2" smd circle
			(at -0.40005 0 180)
			(size 0 0)
			(layers "B.Cu" "B.Mask" "B.Paste")
			(net "UART_PEX1_SDB_BUF_RX")
		)
	)
	(footprint ""
		(layer "B.Cu")
		(at 106.314494 -331.550518)
		(property "Reference" "U118"
			(at 8.03529 -1.243584 0)
			(unlocked yes)
			(layer "B.SilkS")
			(effects
				(font
					(size 0.7874 0.5842)
					(thickness 0.1524)
				)
				(justify mirror)
			)
		)
		(property "Value" ""
			(at 0 0 0)
			(layer "B.Fab")
			(effects
				(font
					(size 1.27 1.27)
				)
				(justify mirror)
			)
		)
		(duplicate_pad_numbers_are_jumpers no)
		(fp_line
			(start -2.500122 -2.500122)
			(end -2.01676 -2.500122)
			(stroke
				(width 0.1524)
				(type default)
			)
			(layer "B.SilkS")
		)
		(fp_line
			(start -2.500122 -2.01676)
			(end -2.500122 -2.500122)
			(stroke
				(width 0.1524)
				(type default)
			)
			(layer "B.SilkS")
		)
		(fp_line
			(start -2.500122 2.500122)
			(end -2.500122 2.01676)
			(stroke
				(width 0.1524)
				(type default)
			)
			(layer "B.SilkS")
		)
		(fp_line
			(start -2.01676 2.500122)
			(end -2.500122 2.500122)
			(stroke
				(width 0.1524)
				(type default)
			)
			(layer "B.SilkS")
		)
		(fp_line
			(start 2.01676 -2.500122)
			(end 2.500122 -2.500122)
			(stroke
				(width 0.1524)
				(type default)
			)
			(layer "B.SilkS")
		)
		(fp_line
			(start 2.500122 -2.500122)
			(end 2.500122 -2.01676)
			(stroke
				(width 0.1524)
				(type default)
			)
			(layer "B.SilkS")
		)
		(fp_line
			(start 2.500122 2.01676)
			(end 2.500122 2.500122)
			(stroke
				(width 0.1524)
				(type default)
			)
			(layer "B.SilkS")
		)
		(fp_line
			(start 2.500122 2.500122)
			(end 2.01676 2.500122)
			(stroke
				(width 0.1524)
				(type default)
			)
			(layer "B.SilkS")
		)
		(fp_poly
			(pts
				(xy 2.54508 -2.02819) (xy 3.812794 -2.450846) (xy 2.967736 -3.295904)
			)
			(stroke
				(width 0)
				(type default)
			)
			(fill yes)
			(layer "B.SilkS")
		)
		(fp_line
			(start -2.500122 -2.500122)
			(end 2.500122 -2.500122)
			(stroke
				(width 0.1)
				(type default)
			)
			(layer "B.Fab")
		)
		(fp_line
			(start -2.500122 2.500122)
			(end -2.500122 -2.500122)
			(stroke
				(width 0.1)
				(type default)
			)
			(layer "B.Fab")
		)
		(fp_line
			(start 2.500122 -2.500122)
			(end 2.500122 2.500122)
			(stroke
				(width 0.1)
				(type default)
			)
			(layer "B.Fab")
		)
		(fp_line
			(start 2.500122 2.500122)
			(end -2.500122 2.500122)
			(stroke
				(width 0.1)
				(type default)
			)
			(layer "B.Fab")
		)
		(fp_poly
			(pts
				(xy 3.044698 -1.75006) (xy 4.240022 -1.152398) (xy 4.240022 -2.347722)
			)
			(stroke
				(width 0)
				(type default)
			)
			(fill yes)
			(layer "B.Fab")
		)
		(pad "1" smd rect
			(at 2.3749 -1.75006 270)
			(size 0.254 0.5588)
			(layers "B.Cu" "B.Mask" "B.Paste")
			(net "FM_CLK_EN_R")
		)
		(pad "2" smd rect
			(at 2.3749 -1.249934 270)
			(size 0.254 0.5588)
			(layers "B.Cu" "B.Mask" "B.Paste")
			(net "P3V3_CLK_BUFFER_9ZXL0451E_VZX3P3A")
		)
		(pad "3" smd rect
			(at 2.3749 -0.750062 270)
			(size 0.254 0.5588)
			(layers "B.Cu" "B.Mask" "B.Paste")
			(net "CLK_100M_MB_0_R_DP")
		)
		(pad "4" smd rect
			(at 2.3749 -0.249936 270)
			(size 0.254 0.5588)
			(layers "B.Cu" "B.Mask" "B.Paste")
			(net "CLK_100M_MB_0_R_DN")
		)
		(pad "5" smd rect
			(at 2.3749 0.249936 270)
			(size 0.254 0.5588)
			(layers "B.Cu" "B.Mask" "B.Paste")
			(net "SMB_9ZXL0451E_ADDR0")
		)
		(pad "6" smd rect
			(at 2.3749 0.750062 270)
			(size 0.254 0.5588)
			(layers "B.Cu" "B.Mask" "B.Paste")
			(net "SMB_BMC_9FGL0451E_SDA")
		)
		(pad "7" smd rect
			(at 2.3749 1.249934 270)
			(size 0.254 0.5588)
			(layers "B.Cu" "B.Mask" "B.Paste")
			(net "SMB_BMC_9FGL0451E_SCL")
		)
		(pad "8" smd rect
			(at 2.3749 1.75006 270)
			(size 0.254 0.5588)
			(layers "B.Cu" "B.Mask" "B.Paste")
			(net "Net_4354")
		)
		(pad "9" smd rect
			(at 1.75006 2.3749 180)
			(size 0.254 0.5588)
			(layers "B.Cu" "B.Mask" "B.Paste")
			(net "Net_4353")
		)
		(pad "10" smd rect
			(at 1.249934 2.3749 180)
			(size 0.254 0.5588)
			(layers "B.Cu" "B.Mask" "B.Paste")
			(net "Net_4355")
		)
		(pad "11" smd rect
			(at 0.750062 2.3749 180)
			(size 0.254 0.5588)
			(layers "B.Cu" "B.Mask" "B.Paste")
			(net "Net_4356")
		)
		(pad "12" smd rect
			(at 0.249936 2.3749 180)
			(size 0.254 0.5588)
			(layers "B.Cu" "B.Mask" "B.Paste")
			(net "P3V3_CLK_BUFFER_9ZXL0451E_VZX3P3")
		)
		(pad "13" smd rect
			(at -0.249936 2.3749 180)
			(size 0.254 0.5588)
			(layers "B.Cu" "B.Mask" "B.Paste")
			(net "CLK_100M_DB800ZL_PEX0_S0_DP")
		)
		(pad "14" smd rect
			(at -0.750062 2.3749 180)
			(size 0.254 0.5588)
			(layers "B.Cu" "B.Mask" "B.Paste")
			(net "CLK_100M_DB800ZL_PEX0_S0_DN")
		)
		(pad "15" smd rect
			(at -1.249934 2.3749 180)
			(size 0.254 0.5588)
			(layers "B.Cu" "B.Mask" "B.Paste")
			(net "PEX_REF_CLK_BUFFER_EN_N")
		)
		(pad "16" smd rect
			(at -1.75006 2.3749 180)
			(size 0.254 0.5588)
			(layers "B.Cu" "B.Mask" "B.Paste")
			(net "P3V3_CLK_BUFFER_9ZXL0451E_VZX3P3")
		)
		(pad "17" smd rect
			(at -2.3749 1.75006 90)
			(size 0.254 0.5588)
			(layers "B.Cu" "B.Mask" "B.Paste")
			(net "Net_4357")
		)
		(pad "18" smd rect
			(at -2.3749 1.249934 90)
			(size 0.254 0.5588)
			(layers "B.Cu" "B.Mask" "B.Paste")
			(net "PEX_REF_CLK_BUFFER_EN_N")
		)
		(pad "19" smd rect
			(at -2.3749 0.750062 90)
			(size 0.254 0.5588)
			(layers "B.Cu" "B.Mask" "B.Paste")
			(net "CLK_100M_DB800ZL_PEX1_S0_DP")
		)
		(pad "20" smd rect
			(at -2.3749 0.249936 90)
			(size 0.254 0.5588)
			(layers "B.Cu" "B.Mask" "B.Paste")
			(net "CLK_100M_DB800ZL_PEX1_S0_DN")
		)
		(pad "21" smd rect
			(at -2.3749 -0.249936 90)
			(size 0.254 0.5588)
			(layers "B.Cu" "B.Mask" "B.Paste")
			(net "P3V3_CLK_BUFFER_9ZXL0451E_VZX3P3")
		)
		(pad "22" smd rect
			(at -2.3749 -0.750062 90)
			(size 0.254 0.5588)
			(layers "B.Cu" "B.Mask" "B.Paste")
			(net "CLK_100M_DB800ZL_PEX2_S0_DP")
		)
		(pad "23" smd rect
			(at -2.3749 -1.249934 90)
			(size 0.254 0.5588)
			(layers "B.Cu" "B.Mask" "B.Paste")
			(net "CLK_100M_DB800ZL_PEX2_S0_DN")
		)
		(pad "24" smd rect
			(at -2.3749 -1.75006 90)
			(size 0.254 0.5588)
			(layers "B.Cu" "B.Mask" "B.Paste")
			(net "PEX_REF_CLK_BUFFER_EN_N")
		)
		(pad "25" smd rect
			(at -1.75006 -2.3749)
			(size 0.254 0.5588)
			(layers "B.Cu" "B.Mask" "B.Paste")
			(net "P3V3_CLK_BUFFER_9ZXL0451E_VZX3P3")
		)
		(pad "26" smd rect
			(at -1.249934 -2.3749)
			(size 0.254 0.5588)
			(layers "B.Cu" "B.Mask" "B.Paste")
			(net "PEX_REF_CLK_BUFFER_EN_N")
		)
		(pad "27" smd rect
			(at -0.750062 -2.3749)
			(size 0.254 0.5588)
			(layers "B.Cu" "B.Mask" "B.Paste")
			(net "CLK_100M_DB800ZL_PEX3_S0_DP")
		)
		(pad "28" smd rect
			(at -0.249936 -2.3749)
			(size 0.254 0.5588)
			(layers "B.Cu" "B.Mask" "B.Paste")
			(net "CLK_100M_DB800ZL_PEX3_S0_DN")
		)
		(pad "29" smd rect
			(at 0.249936 -2.3749)
			(size 0.254 0.5588)
			(layers "B.Cu" "B.Mask" "B.Paste")
			(net "P3V3_CLK_BUFFER_9ZXL0451E_VZX3P3")
		)
		(pad "30" smd rect
			(at 0.750062 -2.3749)
			(size 0.254 0.5588)
			(layers "B.Cu" "B.Mask" "B.Paste")
			(net "Net_4358")
		)
		(pad "31" smd rect
			(at 1.249934 -2.3749)
			(size 0.254 0.5588)
			(layers "B.Cu" "B.Mask" "B.Paste")
			(net "P3V3_CLK_BUFFER_9ZXL0451E_VZX3P3A")
		)
		(pad "32" smd rect
			(at 1.75006 -2.3749)
			(size 0.254 0.5588)
			(layers "B.Cu" "B.Mask" "B.Paste")
			(net "PU_9ZXL0451E_HBW")
		)
		(pad "33" smd rect
			(at 0 0 180)
			(size 3.1496 3.1496)
			(layers "B.Cu" "B.Mask" "B.Paste")
			(net "GND")
		)
		(zone
			(layer "B.Cu")
			(hatch none 0.5)
			(connect_pads
				(clearance 0)
			)
			(min_thickness 0.25)
			(keepout
				(tracks not_allowed)
				(vias allowed)
				(pads allowed)
				(copperpour not_allowed)
				(footprints allowed)
			)
			(placement
				(enabled no)
				(sheetname "")
			)
			(fill
				(thermal_gap 0.5)
				(thermal_bridge_width 0.5)
				(island_removal_mode 0)
			)
			(polygon
				(pts
					(xy 108.359194 -329.505818) (xy 108.359194 -332.775052) (xy 107.940094 -332.775052) (xy 107.940094 -329.924918)
					(xy 104.688894 -329.924918) (xy 104.688894 -333.176118) (xy 107.940094 -333.176118) (xy 107.940094 -332.800452)
					(xy 108.359194 -332.800452) (xy 108.359194 -333.595218) (xy 104.269794 -333.595218) (xy 104.269794 -329.505818)
				)
			)
		)
	)
	(footprint ""
		(layer "B.Cu")
		(at 70.099936 -289.724846 180)
		(property "Reference" "C3003"
			(at 0 0 0)
			(layer "B.SilkS")
			(hide yes)
			(effects
				(font
					(size 1.27 1.27)
				)
				(justify mirror)
			)
		)
		(property "Value" ""
			(at 0 0 0)
			(layer "B.Fab")
			(effects
				(font
					(size 1.27 1.27)
				)
				(justify mirror)
			)
		)
		(duplicate_pad_numbers_are_jumpers no)
		(fp_line
			(start 0.299974 0.150114)
			(end 0.299974 -0.150114)
			(stroke
				(width 0.1)
				(type default)
			)
			(layer "B.Fab")
		)
		(fp_line
			(start 0.299974 -0.150114)
			(end -0.299974 -0.150114)
			(stroke
				(width 0.1)
				(type default)
			)
			(layer "B.Fab")
		)
		(fp_line
			(start -0.299974 0.150114)
			(end 0.299974 0.150114)
			(stroke
				(width 0.1)
				(type default)
			)
			(layer "B.Fab")
		)
		(fp_line
			(start -0.299974 -0.150114)
			(end -0.299974 0.150114)
			(stroke
				(width 0.1)
				(type default)
			)
			(layer "B.Fab")
		)
		(pad "1" smd rect
			(at 0.2667 0)
			(size 0.3048 0.381)
			(layers "B.Cu" "B.Mask" "B.Paste")
			(net "P1V8_PEX")
		)
		(pad "2" smd rect
			(at -0.2667 0)
			(size 0.3048 0.381)
			(layers "B.Cu" "B.Mask" "B.Paste")
			(net "GND")
		)
	)
	(footprint ""
		(layer "B.Cu")
		(at 329.692 -224.4852)
		(property "Reference" "R4166"
			(at 0 0 0)
			(layer "B.SilkS")
			(hide yes)
			(effects
				(font
					(size 1.27 1.27)
				)
				(justify mirror)
			)
		)
		(property "Value" ""
			(at 0 0 0)
			(layer "B.Fab")
			(effects
				(font
					(size 1.27 1.27)
				)
				(justify mirror)
			)
		)
		(duplicate_pad_numbers_are_jumpers no)
		(fp_line
			(start -0.7874 -0.4064)
			(end -0.7874 0.4064)
			(stroke
				(width 0.1524)
				(type default)
			)
			(layer "B.SilkS")
		)
		(fp_line
			(start -0.7874 0.4064)
			(end 0.7874 0.4064)
			(stroke
				(width 0.1524)
				(type default)
			)
			(layer "B.SilkS")
		)
		(fp_line
			(start 0.7874 -0.4064)
			(end -0.7874 -0.4064)
			(stroke
				(width 0.1524)
				(type default)
			)
			(layer "B.SilkS")
		)
		(fp_line
			(start 0.7874 0.4064)
			(end 0.7874 -0.4064)
			(stroke
				(width 0.1524)
				(type default)
			)
			(layer "B.SilkS")
		)
		(fp_line
			(start -0.67945 -0.3048)
			(end -0.67945 0.3048)
			(stroke
				(width 0.1)
				(type default)
			)
			(layer "B.Fab")
		)
		(fp_line
			(start -0.67945 0.3048)
			(end -0.120396 0.3048)
			(stroke
				(width 0.1)
				(type default)
			)
			(layer "B.Fab")
		)
		(fp_line
			(start -0.12065 -0.3048)
			(end -0.67945 -0.3048)
			(stroke
				(width 0.1)
				(type default)
			)
			(layer "B.Fab")
		)
		(fp_line
			(start -0.12065 -0.2794)
			(end -0.12065 -0.3048)
			(stroke
				(width 0.1)
				(type default)
			)
			(layer "B.Fab")
		)
		(fp_line
			(start -0.120396 0.2794)
			(end 0.12065 0.2794)
			(stroke
				(width 0.1)
				(type default)
			)
			(layer "B.Fab")
		)
		(fp_line
			(start -0.120396 0.3048)
			(end -0.120396 0.2794)
			(stroke
				(width 0.1)
				(type default)
			)
			(layer "B.Fab")
		)
		(fp_line
			(start 0.12065 -0.305054)
			(end 0.12065 -0.2794)
			(stroke
				(width 0.1)
				(type default)
			)
			(layer "B.Fab")
		)
		(fp_line
			(start 0.12065 -0.2794)
			(end -0.12065 -0.2794)
			(stroke
				(width 0.1)
				(type default)
			)
			(layer "B.Fab")
		)
		(fp_line
			(start 0.12065 0.2794)
			(end 0.12065 0.3048)
			(stroke
				(width 0.1)
				(type default)
			)
			(layer "B.Fab")
		)
		(fp_line
			(start 0.12065 0.3048)
			(end 0.67945 0.3048)
			(stroke
				(width 0.1)
				(type default)
			)
			(layer "B.Fab")
		)
		(fp_line
			(start 0.67945 -0.305054)
			(end 0.12065 -0.305054)
			(stroke
				(width 0.1)
				(type default)
			)
			(layer "B.Fab")
		)
		(fp_line
			(start 0.67945 0.3048)
			(end 0.67945 -0.305054)
			(stroke
				(width 0.1)
				(type default)
			)
			(layer "B.Fab")
		)
		(pad "1" smd circle
			(at 0.40005 0 180)
			(size 0 0)
			(layers "B.Cu" "B.Mask" "B.Paste")
			(net "PWR_EN_P3V3")
		)
		(pad "2" smd circle
			(at -0.40005 0 180)
			(size 0 0)
			(layers "B.Cu" "B.Mask" "B.Paste")
			(net "PWR_EN_P3V3_R")
		)
	)
	(footprint ""
		(layer "B.Cu")
		(at 425.841922 -101.069648 180)
		(property "Reference" "R382"
			(at 0 0 0)
			(layer "B.SilkS")
			(hide yes)
			(effects
				(font
					(size 1.27 1.27)
				)
				(justify mirror)
			)
		)
		(property "Value" ""
			(at 0 0 0)
			(layer "B.Fab")
			(effects
				(font
					(size 1.27 1.27)
				)
				(justify mirror)
			)
		)
		(duplicate_pad_numbers_are_jumpers no)
		(fp_line
			(start 0.7874 0.4064)
			(end 0.7874 -0.4064)
			(stroke
				(width 0.1524)
				(type default)
			)
			(layer "B.SilkS")
		)
		(fp_line
			(start 0.7874 -0.4064)
			(end -0.7874 -0.4064)
			(stroke
				(width 0.1524)
				(type default)
			)
			(layer "B.SilkS")
		)
		(fp_line
			(start -0.7874 0.4064)
			(end 0.7874 0.4064)
			(stroke
				(width 0.1524)
				(type default)
			)
			(layer "B.SilkS")
		)
		(fp_line
			(start -0.7874 -0.4064)
			(end -0.7874 0.4064)
			(stroke
				(width 0.1524)
				(type default)
			)
			(layer "B.SilkS")
		)
		(fp_line
			(start 0.67945 0.3048)
			(end 0.67945 -0.305054)
			(stroke
				(width 0.1)
				(type default)
			)
			(layer "B.Fab")
		)
		(fp_line
			(start 0.67945 -0.305054)
			(end 0.12065 -0.305054)
			(stroke
				(width 0.1)
				(type default)
			)
			(layer "B.Fab")
		)
		(fp_line
			(start 0.12065 0.3048)
			(end 0.67945 0.3048)
			(stroke
				(width 0.1)
				(type default)
			)
			(layer "B.Fab")
		)
		(fp_line
			(start 0.12065 0.2794)
			(end 0.12065 0.3048)
			(stroke
				(width 0.1)
				(type default)
			)
			(layer "B.Fab")
		)
		(fp_line
			(start 0.12065 -0.2794)
			(end -0.12065 -0.2794)
			(stroke
				(width 0.1)
				(type default)
			)
			(layer "B.Fab")
		)
		(fp_line
			(start 0.12065 -0.305054)
			(end 0.12065 -0.2794)
			(stroke
				(width 0.1)
				(type default)
			)
			(layer "B.Fab")
		)
		(fp_line
			(start -0.120396 0.3048)
			(end -0.120396 0.2794)
			(stroke
				(width 0.1)
				(type default)
			)
			(layer "B.Fab")
		)
		(fp_line
			(start -0.120396 0.2794)
			(end 0.12065 0.2794)
			(stroke
				(width 0.1)
				(type default)
			)
			(layer "B.Fab")
		)
		(fp_line
			(start -0.12065 -0.2794)
			(end -0.12065 -0.3048)
			(stroke
				(width 0.1)
				(type default)
			)
			(layer "B.Fab")
		)
		(fp_line
			(start -0.12065 -0.3048)
			(end -0.67945 -0.3048)
			(stroke
				(width 0.1)
				(type default)
			)
			(layer "B.Fab")
		)
		(fp_line
			(start -0.67945 0.3048)
			(end -0.120396 0.3048)
			(stroke
				(width 0.1)
				(type default)
			)
			(layer "B.Fab")
		)
		(fp_line
			(start -0.67945 -0.3048)
			(end -0.67945 0.3048)
			(stroke
				(width 0.1)
				(type default)
			)
			(layer "B.Fab")
		)
		(pad "1" smd circle
			(at 0.40005 0)
			(size 0 0)
			(layers "B.Cu" "B.Mask" "B.Paste")
			(net "NIC7_SLOT_ID0")
		)
		(pad "2" smd circle
			(at -0.40005 0)
			(size 0 0)
			(layers "B.Cu" "B.Mask" "B.Paste")
			(net "P3V3_NIC7")
		)
	)
	(footprint ""
		(layer "B.Cu")
		(at 54.899814 -303.499774 -90)
		(property "Reference" "C2912"
			(at 0 0 90)
			(layer "B.SilkS")
			(hide yes)
			(effects
				(font
					(size 1.27 1.27)
				)
				(justify mirror)
			)
		)
		(property "Value" ""
			(at 0 0 90)
			(layer "B.Fab")
			(effects
				(font
					(size 1.27 1.27)
				)
				(justify mirror)
			)
		)
		(duplicate_pad_numbers_are_jumpers no)
		(fp_line
			(start -0.299974 0.150114)
			(end 0.299974 0.150114)
			(stroke
				(width 0.1)
				(type default)
			)
			(layer "B.Fab")
		)
		(fp_line
			(start 0.299974 0.150114)
			(end 0.299974 -0.150114)
			(stroke
				(width 0.1)
				(type default)
			)
			(layer "B.Fab")
		)
		(fp_line
			(start -0.299974 -0.150114)
			(end -0.299974 0.150114)
			(stroke
				(width 0.1)
				(type default)
			)
			(layer "B.Fab")
		)
		(fp_line
			(start 0.299974 -0.150114)
			(end -0.299974 -0.150114)
			(stroke
				(width 0.1)
				(type default)
			)
			(layer "B.Fab")
		)
		(pad "1" smd rect
			(at 0.2667 0 90)
			(size 0.3048 0.381)
			(layers "B.Cu" "B.Mask" "B.Paste")
			(net "P1V25_PEX0")
		)
		(pad "2" smd rect
			(at -0.2667 0 90)
			(size 0.3048 0.381)
			(layers "B.Cu" "B.Mask" "B.Paste")
			(net "GND")
		)
	)
	(footprint ""
		(layer "B.Cu")
		(at 296.599864 -303.499774 -90)
		(property "Reference" "C3267"
			(at 0 0 90)
			(layer "B.SilkS")
			(hide yes)
			(effects
				(font
					(size 1.27 1.27)
				)
				(justify mirror)
			)
		)
		(property "Value" ""
			(at 0 0 90)
			(layer "B.Fab")
			(effects
				(font
					(size 1.27 1.27)
				)
				(justify mirror)
			)
		)
		(duplicate_pad_numbers_are_jumpers no)
		(fp_line
			(start -0.299974 0.150114)
			(end 0.299974 0.150114)
			(stroke
				(width 0.1)
				(type default)
			)
			(layer "B.Fab")
		)
		(fp_line
			(start 0.299974 0.150114)
			(end 0.299974 -0.150114)
			(stroke
				(width 0.1)
				(type default)
			)
			(layer "B.Fab")
		)
		(fp_line
			(start -0.299974 -0.150114)
			(end -0.299974 0.150114)
			(stroke
				(width 0.1)
				(type default)
			)
			(layer "B.Fab")
		)
		(fp_line
			(start 0.299974 -0.150114)
			(end -0.299974 -0.150114)
			(stroke
				(width 0.1)
				(type default)
			)
			(layer "B.Fab")
		)
		(pad "1" smd rect
			(at 0.2667 0 90)
			(size 0.3048 0.381)
			(layers "B.Cu" "B.Mask" "B.Paste")
			(net "P1V25_PEX2")
		)
		(pad "2" smd rect
			(at -0.2667 0 90)
			(size 0.3048 0.381)
			(layers "B.Cu" "B.Mask" "B.Paste")
			(net "GND")
		)
	)
	(footprint ""
		(layer "B.Cu")
		(at 297.549824 -290.199826 90)
		(property "Reference" "C1678"
			(at 0 0 90)
			(layer "B.SilkS")
			(hide yes)
			(effects
				(font
					(size 1.27 1.27)
				)
				(justify mirror)
			)
		)
		(property "Value" ""
			(at 0 0 90)
			(layer "B.Fab")
			(effects
				(font
					(size 1.27 1.27)
				)
				(justify mirror)
			)
		)
		(duplicate_pad_numbers_are_jumpers no)
		(fp_line
			(start 0.299974 -0.150114)
			(end -0.299974 -0.150114)
			(stroke
				(width 0.1)
				(type default)
			)
			(layer "B.Fab")
		)
		(fp_line
			(start -0.299974 -0.150114)
			(end -0.299974 0.150114)
			(stroke
				(width 0.1)
				(type default)
			)
			(layer "B.Fab")
		)
		(fp_line
			(start 0.299974 0.150114)
			(end 0.299974 -0.150114)
			(stroke
				(width 0.1)
				(type default)
			)
			(layer "B.Fab")
		)
		(fp_line
			(start -0.299974 0.150114)
			(end 0.299974 0.150114)
			(stroke
				(width 0.1)
				(type default)
			)
			(layer "B.Fab")
		)
		(pad "1" smd rect
			(at 0.2667 0 270)
			(size 0.3048 0.381)
			(layers "B.Cu" "B.Mask" "B.Paste")
			(net "P0V8_SERDES_VDDA_PEX2")
		)
		(pad "2" smd rect
			(at -0.2667 0 270)
			(size 0.3048 0.381)
			(layers "B.Cu" "B.Mask" "B.Paste")
			(net "GND")
		)
	)
	(footprint ""
		(layer "B.Cu")
		(at 160.549844 -294.94988)
		(property "Reference" "C3179"
			(at 0 0 0)
			(layer "B.SilkS")
			(hide yes)
			(effects
				(font
					(size 1.27 1.27)
				)
				(justify mirror)
			)
		)
		(property "Value" ""
			(at 0 0 0)
			(layer "B.Fab")
			(effects
				(font
					(size 1.27 1.27)
				)
				(justify mirror)
			)
		)
		(duplicate_pad_numbers_are_jumpers no)
		(fp_line
			(start -0.299974 -0.150114)
			(end -0.299974 0.150114)
			(stroke
				(width 0.1)
				(type default)
			)
			(layer "B.Fab")
		)
		(fp_line
			(start -0.299974 0.150114)
			(end 0.299974 0.150114)
			(stroke
				(width 0.1)
				(type default)
			)
			(layer "B.Fab")
		)
		(fp_line
			(start 0.299974 -0.150114)
			(end -0.299974 -0.150114)
			(stroke
				(width 0.1)
				(type default)
			)
			(layer "B.Fab")
		)
		(fp_line
			(start 0.299974 0.150114)
			(end 0.299974 -0.150114)
			(stroke
				(width 0.1)
				(type default)
			)
			(layer "B.Fab")
		)
		(pad "1" smd rect
			(at 0.2667 0 180)
			(size 0.3048 0.381)
			(layers "B.Cu" "B.Mask" "B.Paste")
			(net "P1V8_PEX")
		)
		(pad "2" smd rect
			(at -0.2667 0 180)
			(size 0.3048 0.381)
			(layers "B.Cu" "B.Mask" "B.Paste")
			(net "GND")
		)
	)
	(footprint ""
		(layer "B.Cu")
		(at 60.151264 -305.399948 -90)
		(property "Reference" "C2975"
			(at 0 0 90)
			(layer "B.SilkS")
			(hide yes)
			(effects
				(font
					(size 1.27 1.27)
				)
				(justify mirror)
			)
		)
		(property "Value" ""
			(at 0 0 90)
			(layer "B.Fab")
			(effects
				(font
					(size 1.27 1.27)
				)
				(justify mirror)
			)
		)
		(duplicate_pad_numbers_are_jumpers no)
		(fp_line
			(start -0.299974 0.150114)
			(end 0.299974 0.150114)
			(stroke
				(width 0.1)
				(type default)
			)
			(layer "B.Fab")
		)
		(fp_line
			(start 0.299974 0.150114)
			(end 0.299974 -0.150114)
			(stroke
				(width 0.1)
				(type default)
			)
			(layer "B.Fab")
		)
		(fp_line
			(start -0.299974 -0.150114)
			(end -0.299974 0.150114)
			(stroke
				(width 0.1)
				(type default)
			)
			(layer "B.Fab")
		)
		(fp_line
			(start 0.299974 -0.150114)
			(end -0.299974 -0.150114)
			(stroke
				(width 0.1)
				(type default)
			)
			(layer "B.Fab")
		)
		(pad "1" smd rect
			(at 0.2667 0 90)
			(size 0.3048 0.381)
			(layers "B.Cu" "B.Mask" "B.Paste")
			(net "P1V25_SERDES_VDDPLL_PEX0")
		)
		(pad "2" smd rect
			(at -0.2667 0 90)
			(size 0.3048 0.381)
			(layers "B.Cu" "B.Mask" "B.Paste")
			(net "GND")
		)
	)
	(footprint ""
		(layer "B.Cu")
		(at 161.964116 -144.421352 180)
		(property "Reference" "C880"
			(at 0 0 0)
			(layer "B.SilkS")
			(hide yes)
			(effects
				(font
					(size 1.27 1.27)
				)
				(justify mirror)
			)
		)
		(property "Value" ""
			(at 0 0 0)
			(layer "B.Fab")
			(effects
				(font
					(size 1.27 1.27)
				)
				(justify mirror)
			)
		)
		(duplicate_pad_numbers_are_jumpers no)
		(fp_line
			(start 0.299974 0.150114)
			(end 0.299974 -0.150114)
			(stroke
				(width 0.1)
				(type default)
			)
			(layer "B.Fab")
		)
		(fp_line
			(start 0.299974 -0.150114)
			(end -0.299974 -0.150114)
			(stroke
				(width 0.1)
				(type default)
			)
			(layer "B.Fab")
		)
		(fp_line
			(start -0.299974 0.150114)
			(end 0.299974 0.150114)
			(stroke
				(width 0.1)
				(type default)
			)
			(layer "B.Fab")
		)
		(fp_line
			(start -0.299974 -0.150114)
			(end -0.299974 0.150114)
			(stroke
				(width 0.1)
				(type default)
			)
			(layer "B.Fab")
		)
		(pad "1" smd rect
			(at 0.2667 0)
			(size 0.3048 0.381)
			(layers "B.Cu" "B.Mask" "B.Paste")
			(net "P12V_NIC2")
		)
		(pad "2" smd rect
			(at -0.2667 0)
			(size 0.3048 0.381)
			(layers "B.Cu" "B.Mask" "B.Paste")
			(net "GND")
		)
	)
	(footprint ""
		(layer "B.Cu")
		(at 281.755342 -151.9936)
		(property "Reference" "R222"
			(at 0 0 0)
			(layer "B.SilkS")
			(hide yes)
			(effects
				(font
					(size 1.27 1.27)
				)
				(justify mirror)
			)
		)
		(property "Value" ""
			(at 0 0 0)
			(layer "B.Fab")
			(effects
				(font
					(size 1.27 1.27)
				)
				(justify mirror)
			)
		)
		(duplicate_pad_numbers_are_jumpers no)
		(fp_line
			(start -0.7874 -0.4064)
			(end -0.7874 0.4064)
			(stroke
				(width 0.1524)
				(type default)
			)
			(layer "B.SilkS")
		)
		(fp_line
			(start -0.7874 0.4064)
			(end 0.7874 0.4064)
			(stroke
				(width 0.1524)
				(type default)
			)
			(layer "B.SilkS")
		)
		(fp_line
			(start 0.7874 -0.4064)
			(end -0.7874 -0.4064)
			(stroke
				(width 0.1524)
				(type default)
			)
			(layer "B.SilkS")
		)
		(fp_line
			(start 0.7874 0.4064)
			(end 0.7874 -0.4064)
			(stroke
				(width 0.1524)
				(type default)
			)
			(layer "B.SilkS")
		)
		(fp_line
			(start -0.67945 -0.3048)
			(end -0.67945 0.3048)
			(stroke
				(width 0.1)
				(type default)
			)
			(layer "B.Fab")
		)
		(fp_line
			(start -0.67945 0.3048)
			(end -0.120396 0.3048)
			(stroke
				(width 0.1)
				(type default)
			)
			(layer "B.Fab")
		)
		(fp_line
			(start -0.12065 -0.3048)
			(end -0.67945 -0.3048)
			(stroke
				(width 0.1)
				(type default)
			)
			(layer "B.Fab")
		)
		(fp_line
			(start -0.12065 -0.2794)
			(end -0.12065 -0.3048)
			(stroke
				(width 0.1)
				(type default)
			)
			(layer "B.Fab")
		)
		(fp_line
			(start -0.120396 0.2794)
			(end 0.12065 0.2794)
			(stroke
				(width 0.1)
				(type default)
			)
			(layer "B.Fab")
		)
		(fp_line
			(start -0.120396 0.3048)
			(end -0.120396 0.2794)
			(stroke
				(width 0.1)
				(type default)
			)
			(layer "B.Fab")
		)
		(fp_line
			(start 0.12065 -0.305054)
			(end 0.12065 -0.2794)
			(stroke
				(width 0.1)
				(type default)
			)
			(layer "B.Fab")
		)
		(fp_line
			(start 0.12065 -0.2794)
			(end -0.12065 -0.2794)
			(stroke
				(width 0.1)
				(type default)
			)
			(layer "B.Fab")
		)
		(fp_line
			(start 0.12065 0.2794)
			(end 0.12065 0.3048)
			(stroke
				(width 0.1)
				(type default)
			)
			(layer "B.Fab")
		)
		(fp_line
			(start 0.12065 0.3048)
			(end 0.67945 0.3048)
			(stroke
				(width 0.1)
				(type default)
			)
			(layer "B.Fab")
		)
		(fp_line
			(start 0.67945 -0.305054)
			(end 0.12065 -0.305054)
			(stroke
				(width 0.1)
				(type default)
			)
			(layer "B.Fab")
		)
		(fp_line
			(start 0.67945 0.3048)
			(end 0.67945 -0.305054)
			(stroke
				(width 0.1)
				(type default)
			)
			(layer "B.Fab")
		)
		(pad "1" smd circle
			(at 0.40005 0 180)
			(size 0 0)
			(layers "B.Cu" "B.Mask" "B.Paste")
			(net "NCSI_NIC4_TXD0")
		)
		(pad "2" smd circle
			(at -0.40005 0 180)
			(size 0 0)
			(layers "B.Cu" "B.Mask" "B.Paste")
			(net "GND")
		)
	)
	(footprint ""
		(layer "B.Cu")
		(at 140.37691 -214.964772 -90)
		(property "Reference" "R993"
			(at 0 0 90)
			(layer "B.SilkS")
			(hide yes)
			(effects
				(font
					(size 1.27 1.27)
				)
				(justify mirror)
			)
		)
		(property "Value" ""
			(at 0 0 90)
			(layer "B.Fab")
			(effects
				(font
					(size 1.27 1.27)
				)
				(justify mirror)
			)
		)
		(duplicate_pad_numbers_are_jumpers no)
		(fp_line
			(start -0.7874 0.4064)
			(end 0.7874 0.4064)
			(stroke
				(width 0.1524)
				(type default)
			)
			(layer "B.SilkS")
		)
		(fp_line
			(start 0.7874 0.4064)
			(end 0.7874 -0.4064)
			(stroke
				(width 0.1524)
				(type default)
			)
			(layer "B.SilkS")
		)
		(fp_line
			(start -0.7874 -0.4064)
			(end -0.7874 0.4064)
			(stroke
				(width 0.1524)
				(type default)
			)
			(layer "B.SilkS")
		)
		(fp_line
			(start 0.7874 -0.4064)
			(end -0.7874 -0.4064)
			(stroke
				(width 0.1524)
				(type default)
			)
			(layer "B.SilkS")
		)
		(fp_line
			(start -0.67945 0.3048)
			(end -0.120396 0.3048)
			(stroke
				(width 0.1)
				(type default)
			)
			(layer "B.Fab")
		)
		(fp_line
			(start -0.120396 0.3048)
			(end -0.120396 0.2794)
			(stroke
				(width 0.1)
				(type default)
			)
			(layer "B.Fab")
		)
		(fp_line
			(start 0.12065 0.3048)
			(end 0.67945 0.3048)
			(stroke
				(width 0.1)
				(type default)
			)
			(layer "B.Fab")
		)
		(fp_line
			(start 0.67945 0.3048)
			(end 0.67945 -0.305054)
			(stroke
				(width 0.1)
				(type default)
			)
			(layer "B.Fab")
		)
		(fp_line
			(start -0.120396 0.2794)
			(end 0.12065 0.2794)
			(stroke
				(width 0.1)
				(type default)
			)
			(layer "B.Fab")
		)
		(fp_line
			(start 0.12065 0.2794)
			(end 0.12065 0.3048)
			(stroke
				(width 0.1)
				(type default)
			)
			(layer "B.Fab")
		)
		(fp_line
			(start -0.12065 -0.2794)
			(end -0.12065 -0.3048)
			(stroke
				(width 0.1)
				(type default)
			)
			(layer "B.Fab")
		)
		(fp_line
			(start 0.12065 -0.2794)
			(end -0.12065 -0.2794)
			(stroke
				(width 0.1)
				(type default)
			)
			(layer "B.Fab")
		)
		(fp_line
			(start -0.67945 -0.3048)
			(end -0.67945 0.3048)
			(stroke
				(width 0.1)
				(type default)
			)
			(layer "B.Fab")
		)
		(fp_line
			(start -0.12065 -0.3048)
			(end -0.67945 -0.3048)
			(stroke
				(width 0.1)
				(type default)
			)
			(layer "B.Fab")
		)
		(fp_line
			(start 0.12065 -0.305054)
			(end 0.12065 -0.2794)
			(stroke
				(width 0.1)
				(type default)
			)
			(layer "B.Fab")
		)
		(fp_line
			(start 0.67945 -0.305054)
			(end 0.12065 -0.305054)
			(stroke
				(width 0.1)
				(type default)
			)
			(layer "B.Fab")
		)
		(pad "1" smd circle
			(at 0.40005 0 90)
			(size 0 0)
			(layers "B.Cu" "B.Mask" "B.Paste")
			(net "UART_PEX3_CLI_BUF_R_RX")
		)
		(pad "2" smd circle
			(at -0.40005 0 90)
			(size 0 0)
			(layers "B.Cu" "B.Mask" "B.Paste")
			(net "UART_PEX3_CLI_BUF_RX")
		)
	)
	(footprint ""
		(layer "B.Cu")
		(at 366.268 -236.601)
		(property "Reference" "R915"
			(at 0 0 0)
			(layer "B.SilkS")
			(hide yes)
			(effects
				(font
					(size 1.27 1.27)
				)
				(justify mirror)
			)
		)
		(property "Value" ""
			(at 0 0 0)
			(layer "B.Fab")
			(effects
				(font
					(size 1.27 1.27)
				)
				(justify mirror)
			)
		)
		(duplicate_pad_numbers_are_jumpers no)
		(fp_line
			(start -0.7874 -0.4064)
			(end -0.7874 0.4064)
			(stroke
				(width 0.1524)
				(type default)
			)
			(layer "B.SilkS")
		)
		(fp_line
			(start -0.7874 0.4064)
			(end 0.7874 0.4064)
			(stroke
				(width 0.1524)
				(type default)
			)
			(layer "B.SilkS")
		)
		(fp_line
			(start 0.7874 -0.4064)
			(end -0.7874 -0.4064)
			(stroke
				(width 0.1524)
				(type default)
			)
			(layer "B.SilkS")
		)
		(fp_line
			(start 0.7874 0.4064)
			(end 0.7874 -0.4064)
			(stroke
				(width 0.1524)
				(type default)
			)
			(layer "B.SilkS")
		)
		(fp_line
			(start -0.67945 -0.3048)
			(end -0.67945 0.3048)
			(stroke
				(width 0.1)
				(type default)
			)
			(layer "B.Fab")
		)
		(fp_line
			(start -0.67945 0.3048)
			(end -0.120396 0.3048)
			(stroke
				(width 0.1)
				(type default)
			)
			(layer "B.Fab")
		)
		(fp_line
			(start -0.12065 -0.3048)
			(end -0.67945 -0.3048)
			(stroke
				(width 0.1)
				(type default)
			)
			(layer "B.Fab")
		)
		(fp_line
			(start -0.12065 -0.2794)
			(end -0.12065 -0.3048)
			(stroke
				(width 0.1)
				(type default)
			)
			(layer "B.Fab")
		)
		(fp_line
			(start -0.120396 0.2794)
			(end 0.12065 0.2794)
			(stroke
				(width 0.1)
				(type default)
			)
			(layer "B.Fab")
		)
		(fp_line
			(start -0.120396 0.3048)
			(end -0.120396 0.2794)
			(stroke
				(width 0.1)
				(type default)
			)
			(layer "B.Fab")
		)
		(fp_line
			(start 0.12065 -0.305054)
			(end 0.12065 -0.2794)
			(stroke
				(width 0.1)
				(type default)
			)
			(layer "B.Fab")
		)
		(fp_line
			(start 0.12065 -0.2794)
			(end -0.12065 -0.2794)
			(stroke
				(width 0.1)
				(type default)
			)
			(layer "B.Fab")
		)
		(fp_line
			(start 0.12065 0.2794)
			(end 0.12065 0.3048)
			(stroke
				(width 0.1)
				(type default)
			)
			(layer "B.Fab")
		)
		(fp_line
			(start 0.12065 0.3048)
			(end 0.67945 0.3048)
			(stroke
				(width 0.1)
				(type default)
			)
			(layer "B.Fab")
		)
		(fp_line
			(start 0.67945 -0.305054)
			(end 0.12065 -0.305054)
			(stroke
				(width 0.1)
				(type default)
			)
			(layer "B.Fab")
		)
		(fp_line
			(start 0.67945 0.3048)
			(end 0.67945 -0.305054)
			(stroke
				(width 0.1)
				(type default)
			)
			(layer "B.Fab")
		)
		(pad "1" smd circle
			(at 0.40005 0 180)
			(size 0 0)
			(layers "B.Cu" "B.Mask" "B.Paste")
			(net "FT4232_SDB_EEPROM_R_SDA")
		)
		(pad "2" smd circle
			(at -0.40005 0 180)
			(size 0 0)
			(layers "B.Cu" "B.Mask" "B.Paste")
			(net "FT4232_SDB_EEPROM_DO")
		)
	)
	(footprint ""
		(layer "B.Cu")
		(at 114.450114 -258.004564 -90)
		(property "Reference" "PC54"
			(at 0 0 90)
			(layer "B.SilkS")
			(hide yes)
			(effects
				(font
					(size 1.27 1.27)
				)
				(justify mirror)
			)
		)
		(property "Value" ""
			(at 0 0 90)
			(layer "B.Fab")
			(effects
				(font
					(size 1.27 1.27)
				)
				(justify mirror)
			)
		)
		(duplicate_pad_numbers_are_jumpers no)
		(fp_line
			(start -0.7874 0.4064)
			(end 0.7874 0.4064)
			(stroke
				(width 0.1524)
				(type default)
			)
			(layer "B.SilkS")
		)
		(fp_line
			(start 0.7874 0.4064)
			(end 0.7874 -0.4064)
			(stroke
				(width 0.1524)
				(type default)
			)
			(layer "B.SilkS")
		)
		(fp_line
			(start -0.7874 -0.4064)
			(end -0.7874 0.4064)
			(stroke
				(width 0.1524)
				(type default)
			)
			(layer "B.SilkS")
		)
		(fp_line
			(start 0.7874 -0.4064)
			(end -0.7874 -0.4064)
			(stroke
				(width 0.1524)
				(type default)
			)
			(layer "B.SilkS")
		)
		(fp_line
			(start -0.67945 0.3048)
			(end -0.120396 0.3048)
			(stroke
				(width 0.1)
				(type default)
			)
			(layer "B.Fab")
		)
		(fp_line
			(start -0.120396 0.3048)
			(end -0.120396 0.2794)
			(stroke
				(width 0.1)
				(type default)
			)
			(layer "B.Fab")
		)
		(fp_line
			(start 0.12065 0.3048)
			(end 0.67945 0.3048)
			(stroke
				(width 0.1)
				(type default)
			)
			(layer "B.Fab")
		)
		(fp_line
			(start 0.67945 0.3048)
			(end 0.67945 -0.305054)
			(stroke
				(width 0.1)
				(type default)
			)
			(layer "B.Fab")
		)
		(fp_line
			(start -0.120396 0.2794)
			(end 0.12065 0.2794)
			(stroke
				(width 0.1)
				(type default)
			)
			(layer "B.Fab")
		)
		(fp_line
			(start 0.12065 0.2794)
			(end 0.12065 0.3048)
			(stroke
				(width 0.1)
				(type default)
			)
			(layer "B.Fab")
		)
		(fp_line
			(start -0.12065 -0.2794)
			(end -0.12065 -0.3048)
			(stroke
				(width 0.1)
				(type default)
			)
			(layer "B.Fab")
		)
		(fp_line
			(start 0.12065 -0.2794)
			(end -0.12065 -0.2794)
			(stroke
				(width 0.1)
				(type default)
			)
			(layer "B.Fab")
		)
		(fp_line
			(start -0.67945 -0.3048)
			(end -0.67945 0.3048)
			(stroke
				(width 0.1)
				(type default)
			)
			(layer "B.Fab")
		)
		(fp_line
			(start -0.12065 -0.3048)
			(end -0.67945 -0.3048)
			(stroke
				(width 0.1)
				(type default)
			)
			(layer "B.Fab")
		)
		(fp_line
			(start 0.12065 -0.305054)
			(end 0.12065 -0.2794)
			(stroke
				(width 0.1)
				(type default)
			)
			(layer "B.Fab")
		)
		(fp_line
			(start 0.67945 -0.305054)
			(end 0.12065 -0.305054)
			(stroke
				(width 0.1)
				(type default)
			)
			(layer "B.Fab")
		)
		(pad "1" smd circle
			(at 0.40005 0 90)
			(size 0 0)
			(layers "B.Cu" "B.Mask" "B.Paste")
			(net "P0V8_PEX0_IINSEN")
		)
		(pad "2" smd circle
			(at -0.40005 0 90)
			(size 0 0)
			(layers "B.Cu" "B.Mask" "B.Paste")
			(net "GND")
		)
	)
	(footprint ""
		(layer "B.Cu")
		(at 285.83001 -295.221914)
		(property "Reference" "C1611"
			(at 0 0 0)
			(layer "B.SilkS")
			(hide yes)
			(effects
				(font
					(size 1.27 1.27)
				)
				(justify mirror)
			)
		)
		(property "Value" ""
			(at 0 0 0)
			(layer "B.Fab")
			(effects
				(font
					(size 1.27 1.27)
				)
				(justify mirror)
			)
		)
		(duplicate_pad_numbers_are_jumpers no)
		(fp_line
			(start -1.2954 -0.5842)
			(end -1.2954 0.5842)
			(stroke
				(width 0.1524)
				(type default)
			)
			(layer "B.SilkS")
		)
		(fp_line
			(start -1.2954 0.5842)
			(end 1.2954 0.5842)
			(stroke
				(width 0.1524)
				(type default)
			)
			(layer "B.SilkS")
		)
		(fp_line
			(start 1.2954 -0.5842)
			(end -1.2954 -0.5842)
			(stroke
				(width 0.1524)
				(type default)
			)
			(layer "B.SilkS")
		)
		(fp_line
			(start 1.2954 0.5842)
			(end 1.2954 -0.5842)
			(stroke
				(width 0.1524)
				(type default)
			)
			(layer "B.SilkS")
		)
		(fp_line
			(start -1.1938 -0.4064)
			(end -1.1938 0.4064)
			(stroke
				(width 0.1)
				(type default)
			)
			(layer "B.Fab")
		)
		(fp_line
			(start -1.1938 0.4064)
			(end -0.8636 0.4064)
			(stroke
				(width 0.1)
				(type default)
			)
			(layer "B.Fab")
		)
		(fp_line
			(start -0.8636 -0.4572)
			(end -0.8636 -0.4064)
			(stroke
				(width 0.1)
				(type default)
			)
			(layer "B.Fab")
		)
		(fp_line
			(start -0.8636 -0.4064)
			(end -1.1938 -0.4064)
			(stroke
				(width 0.1)
				(type default)
			)
			(layer "B.Fab")
		)
		(fp_line
			(start -0.8636 0.4064)
			(end -0.8636 0.4572)
			(stroke
				(width 0.1)
				(type default)
			)
			(layer "B.Fab")
		)
		(fp_line
			(start -0.8636 0.4572)
			(end 0.8636 0.4572)
			(stroke
				(width 0.1)
				(type default)
			)
			(layer "B.Fab")
		)
		(fp_line
			(start 0.8636 -0.4572)
			(end -0.8636 -0.4572)
			(stroke
				(width 0.1)
				(type default)
			)
			(layer "B.Fab")
		)
		(fp_line
			(start 0.8636 -0.4064)
			(end 0.8636 -0.4572)
			(stroke
				(width 0.1)
				(type default)
			)
			(layer "B.Fab")
		)
		(fp_line
			(start 0.8636 0.4064)
			(end 1.1938 0.4064)
			(stroke
				(width 0.1)
				(type default)
			)
			(layer "B.Fab")
		)
		(fp_line
			(start 0.8636 0.4572)
			(end 0.8636 0.4064)
			(stroke
				(width 0.1)
				(type default)
			)
			(layer "B.Fab")
		)
		(fp_line
			(start 1.1938 -0.4064)
			(end 0.8636 -0.4064)
			(stroke
				(width 0.1)
				(type default)
			)
			(layer "B.Fab")
		)
		(fp_line
			(start 1.1938 0.4064)
			(end 1.1938 -0.4064)
			(stroke
				(width 0.1)
				(type default)
			)
			(layer "B.Fab")
		)
		(pad "1" smd rect
			(at 0.7366 0 270)
			(size 0.7112 0.8128)
			(layers "B.Cu" "B.Mask" "B.Paste")
			(net "P0V8_PEX2")
		)
		(pad "2" smd rect
			(at -0.7366 0 270)
			(size 0.7112 0.8128)
			(layers "B.Cu" "B.Mask" "B.Paste")
			(net "GND")
		)
	)
	(footprint ""
		(layer "B.Cu")
		(at 219.939362 -285.911544)
		(property "Reference" "PC232"
			(at 0 0 0)
			(layer "B.SilkS")
			(hide yes)
			(effects
				(font
					(size 1.27 1.27)
				)
				(justify mirror)
			)
		)
		(property "Value" ""
			(at 0 0 0)
			(layer "B.Fab")
			(effects
				(font
					(size 1.27 1.27)
				)
				(justify mirror)
			)
		)
		(duplicate_pad_numbers_are_jumpers no)
		(fp_line
			(start -1.524 -0.762)
			(end -1.524 0.762)
			(stroke
				(width 0.1524)
				(type default)
			)
			(layer "B.SilkS")
		)
		(fp_line
			(start -1.524 0.762)
			(end 1.524 0.762)
			(stroke
				(width 0.1524)
				(type default)
			)
			(layer "B.SilkS")
		)
		(fp_line
			(start 1.524 -0.762)
			(end -1.524 -0.762)
			(stroke
				(width 0.1524)
				(type default)
			)
			(layer "B.SilkS")
		)
		(fp_line
			(start 1.524 0.762)
			(end 1.524 -0.762)
			(stroke
				(width 0.1524)
				(type default)
			)
			(layer "B.SilkS")
		)
		(fp_line
			(start -1.1049 -0.724916)
			(end 1.1049 -0.724916)
			(stroke
				(width 0.1)
				(type default)
			)
			(layer "B.Fab")
		)
		(fp_line
			(start -1.1049 0.724916)
			(end -1.1049 -0.724916)
			(stroke
				(width 0.1)
				(type default)
			)
			(layer "B.Fab")
		)
		(fp_line
			(start 1.1049 -0.724916)
			(end 1.1049 0.724916)
			(stroke
				(width 0.1)
				(type default)
			)
			(layer "B.Fab")
		)
		(fp_line
			(start 1.1049 0.724916)
			(end -1.1049 0.724916)
			(stroke
				(width 0.1)
				(type default)
			)
			(layer "B.Fab")
		)
		(pad "1" smd rect
			(at 0.889 0)
			(size 1.016 1.27)
			(layers "B.Cu" "B.Mask" "B.Paste")
			(net "P1V25_PEX1_R")
		)
		(pad "2" smd rect
			(at -0.889 0)
			(size 1.016 1.27)
			(layers "B.Cu" "B.Mask" "B.Paste")
			(net "GND")
		)
	)
	(footprint ""
		(layer "B.Cu")
		(at 354.659184 -321.15125 -90)
		(property "Reference" "R6544"
			(at 0 0 90)
			(layer "B.SilkS")
			(hide yes)
			(effects
				(font
					(size 1.27 1.27)
				)
				(justify mirror)
			)
		)
		(property "Value" ""
			(at 0 0 90)
			(layer "B.Fab")
			(effects
				(font
					(size 1.27 1.27)
				)
				(justify mirror)
			)
		)
		(duplicate_pad_numbers_are_jumpers no)
		(fp_line
			(start -0.7874 0.4064)
			(end 0.7874 0.4064)
			(stroke
				(width 0.1524)
				(type default)
			)
			(layer "B.SilkS")
		)
		(fp_line
			(start 0.7874 0.4064)
			(end 0.7874 -0.4064)
			(stroke
				(width 0.1524)
				(type default)
			)
			(layer "B.SilkS")
		)
		(fp_line
			(start -0.7874 -0.4064)
			(end -0.7874 0.4064)
			(stroke
				(width 0.1524)
				(type default)
			)
			(layer "B.SilkS")
		)
		(fp_line
			(start 0.7874 -0.4064)
			(end -0.7874 -0.4064)
			(stroke
				(width 0.1524)
				(type default)
			)
			(layer "B.SilkS")
		)
		(fp_line
			(start -0.67945 0.3048)
			(end -0.120396 0.3048)
			(stroke
				(width 0.1)
				(type default)
			)
			(layer "B.Fab")
		)
		(fp_line
			(start -0.120396 0.3048)
			(end -0.120396 0.2794)
			(stroke
				(width 0.1)
				(type default)
			)
			(layer "B.Fab")
		)
		(fp_line
			(start 0.12065 0.3048)
			(end 0.67945 0.3048)
			(stroke
				(width 0.1)
				(type default)
			)
			(layer "B.Fab")
		)
		(fp_line
			(start 0.67945 0.3048)
			(end 0.67945 -0.305054)
			(stroke
				(width 0.1)
				(type default)
			)
			(layer "B.Fab")
		)
		(fp_line
			(start -0.120396 0.2794)
			(end 0.12065 0.2794)
			(stroke
				(width 0.1)
				(type default)
			)
			(layer "B.Fab")
		)
		(fp_line
			(start 0.12065 0.2794)
			(end 0.12065 0.3048)
			(stroke
				(width 0.1)
				(type default)
			)
			(layer "B.Fab")
		)
		(fp_line
			(start -0.12065 -0.2794)
			(end -0.12065 -0.3048)
			(stroke
				(width 0.1)
				(type default)
			)
			(layer "B.Fab")
		)
		(fp_line
			(start 0.12065 -0.2794)
			(end -0.12065 -0.2794)
			(stroke
				(width 0.1)
				(type default)
			)
			(layer "B.Fab")
		)
		(fp_line
			(start -0.67945 -0.3048)
			(end -0.67945 0.3048)
			(stroke
				(width 0.1)
				(type default)
			)
			(layer "B.Fab")
		)
		(fp_line
			(start -0.12065 -0.3048)
			(end -0.67945 -0.3048)
			(stroke
				(width 0.1)
				(type default)
			)
			(layer "B.Fab")
		)
		(fp_line
			(start 0.12065 -0.305054)
			(end 0.12065 -0.2794)
			(stroke
				(width 0.1)
				(type default)
			)
			(layer "B.Fab")
		)
		(fp_line
			(start 0.67945 -0.305054)
			(end 0.12065 -0.305054)
			(stroke
				(width 0.1)
				(type default)
			)
			(layer "B.Fab")
		)
		(pad "1" smd circle
			(at 0.40005 0 90)
			(size 0 0)
			(layers "B.Cu" "B.Mask" "B.Paste")
			(net "P0V8_SERDES_VDDA_PEX3")
		)
		(pad "2" smd circle
			(at -0.40005 0 90)
			(size 0 0)
			(layers "B.Cu" "B.Mask" "B.Paste")
			(net "P0V8_SERDES_VDDA_PEX3_C7")
		)
	)
	(footprint ""
		(layer "B.Cu")
		(at 287.099756 -299.699934 -90)
		(property "Reference" "C1723"
			(at 0 0 90)
			(layer "B.SilkS")
			(hide yes)
			(effects
				(font
					(size 1.27 1.27)
				)
				(justify mirror)
			)
		)
		(property "Value" ""
			(at 0 0 90)
			(layer "B.Fab")
			(effects
				(font
					(size 1.27 1.27)
				)
				(justify mirror)
			)
		)
		(duplicate_pad_numbers_are_jumpers no)
		(fp_line
			(start -0.299974 0.150114)
			(end 0.299974 0.150114)
			(stroke
				(width 0.1)
				(type default)
			)
			(layer "B.Fab")
		)
		(fp_line
			(start 0.299974 0.150114)
			(end 0.299974 -0.150114)
			(stroke
				(width 0.1)
				(type default)
			)
			(layer "B.Fab")
		)
		(fp_line
			(start -0.299974 -0.150114)
			(end -0.299974 0.150114)
			(stroke
				(width 0.1)
				(type default)
			)
			(layer "B.Fab")
		)
		(fp_line
			(start 0.299974 -0.150114)
			(end -0.299974 -0.150114)
			(stroke
				(width 0.1)
				(type default)
			)
			(layer "B.Fab")
		)
		(pad "1" smd rect
			(at 0.2667 0 90)
			(size 0.3048 0.381)
			(layers "B.Cu" "B.Mask" "B.Paste")
			(net "P0V8_SERDES_VDDA_PEX2")
		)
		(pad "2" smd rect
			(at -0.2667 0 90)
			(size 0.3048 0.381)
			(layers "B.Cu" "B.Mask" "B.Paste")
			(net "GND")
		)
	)
	(footprint ""
		(layer "B.Cu")
		(at 102.629208 -394.194538 90)
		(property "Reference" "C3632"
			(at 0 0 90)
			(layer "B.SilkS")
			(hide yes)
			(effects
				(font
					(size 1.27 1.27)
				)
				(justify mirror)
			)
		)
		(property "Value" ""
			(at 0 0 90)
			(layer "B.Fab")
			(effects
				(font
					(size 1.27 1.27)
				)
				(justify mirror)
			)
		)
		(duplicate_pad_numbers_are_jumpers no)
		(fp_line
			(start 0.7874 -0.4064)
			(end -0.7874 -0.4064)
			(stroke
				(width 0.1524)
				(type default)
			)
			(layer "B.SilkS")
		)
		(fp_line
			(start -0.7874 -0.4064)
			(end -0.7874 0.4064)
			(stroke
				(width 0.1524)
				(type default)
			)
			(layer "B.SilkS")
		)
		(fp_line
			(start 0.7874 0.4064)
			(end 0.7874 -0.4064)
			(stroke
				(width 0.1524)
				(type default)
			)
			(layer "B.SilkS")
		)
		(fp_line
			(start -0.7874 0.4064)
			(end 0.7874 0.4064)
			(stroke
				(width 0.1524)
				(type default)
			)
			(layer "B.SilkS")
		)
		(fp_line
			(start 0.67945 -0.305054)
			(end 0.12065 -0.305054)
			(stroke
				(width 0.1)
				(type default)
			)
			(layer "B.Fab")
		)
		(fp_line
			(start 0.12065 -0.305054)
			(end 0.12065 -0.2794)
			(stroke
				(width 0.1)
				(type default)
			)
			(layer "B.Fab")
		)
		(fp_line
			(start -0.12065 -0.3048)
			(end -0.67945 -0.3048)
			(stroke
				(width 0.1)
				(type default)
			)
			(layer "B.Fab")
		)
		(fp_line
			(start -0.67945 -0.3048)
			(end -0.67945 0.3048)
			(stroke
				(width 0.1)
				(type default)
			)
			(layer "B.Fab")
		)
		(fp_line
			(start 0.12065 -0.2794)
			(end -0.12065 -0.2794)
			(stroke
				(width 0.1)
				(type default)
			)
			(layer "B.Fab")
		)
		(fp_line
			(start -0.12065 -0.2794)
			(end -0.12065 -0.3048)
			(stroke
				(width 0.1)
				(type default)
			)
			(layer "B.Fab")
		)
		(fp_line
			(start 0.12065 0.2794)
			(end 0.12065 0.3048)
			(stroke
				(width 0.1)
				(type default)
			)
			(layer "B.Fab")
		)
		(fp_line
			(start -0.120396 0.2794)
			(end 0.12065 0.2794)
			(stroke
				(width 0.1)
				(type default)
			)
			(layer "B.Fab")
		)
		(fp_line
			(start 0.67945 0.3048)
			(end 0.67945 -0.305054)
			(stroke
				(width 0.1)
				(type default)
			)
			(layer "B.Fab")
		)
		(fp_line
			(start 0.12065 0.3048)
			(end 0.67945 0.3048)
			(stroke
				(width 0.1)
				(type default)
			)
			(layer "B.Fab")
		)
		(fp_line
			(start -0.120396 0.3048)
			(end -0.120396 0.2794)
			(stroke
				(width 0.1)
				(type default)
			)
			(layer "B.Fab")
		)
		(fp_line
			(start -0.67945 0.3048)
			(end -0.120396 0.3048)
			(stroke
				(width 0.1)
				(type default)
			)
			(layer "B.Fab")
		)
		(pad "1" smd circle
			(at 0.40005 0 270)
			(size 0 0)
			(layers "B.Cu" "B.Mask" "B.Paste")
			(net "P3V3_BIC_USB_HUB")
		)
		(pad "2" smd circle
			(at -0.40005 0 270)
			(size 0 0)
			(layers "B.Cu" "B.Mask" "B.Paste")
			(net "GND")
		)
	)
	(footprint ""
		(layer "B.Cu")
		(at 378.079 -244.729 180)
		(property "Reference" "R936"
			(at 0 0 0)
			(layer "B.SilkS")
			(hide yes)
			(effects
				(font
					(size 1.27 1.27)
				)
				(justify mirror)
			)
		)
		(property "Value" ""
			(at 0 0 0)
			(layer "B.Fab")
			(effects
				(font
					(size 1.27 1.27)
				)
				(justify mirror)
			)
		)
		(duplicate_pad_numbers_are_jumpers no)
		(fp_line
			(start 0.7874 0.4064)
			(end 0.7874 -0.4064)
			(stroke
				(width 0.1524)
				(type default)
			)
			(layer "B.SilkS")
		)
		(fp_line
			(start 0.7874 -0.4064)
			(end -0.7874 -0.4064)
			(stroke
				(width 0.1524)
				(type default)
			)
			(layer "B.SilkS")
		)
		(fp_line
			(start -0.7874 0.4064)
			(end 0.7874 0.4064)
			(stroke
				(width 0.1524)
				(type default)
			)
			(layer "B.SilkS")
		)
		(fp_line
			(start -0.7874 -0.4064)
			(end -0.7874 0.4064)
			(stroke
				(width 0.1524)
				(type default)
			)
			(layer "B.SilkS")
		)
		(fp_line
			(start 0.67945 0.3048)
			(end 0.67945 -0.305054)
			(stroke
				(width 0.1)
				(type default)
			)
			(layer "B.Fab")
		)
		(fp_line
			(start 0.67945 -0.305054)
			(end 0.12065 -0.305054)
			(stroke
				(width 0.1)
				(type default)
			)
			(layer "B.Fab")
		)
		(fp_line
			(start 0.12065 0.3048)
			(end 0.67945 0.3048)
			(stroke
				(width 0.1)
				(type default)
			)
			(layer "B.Fab")
		)
		(fp_line
			(start 0.12065 0.2794)
			(end 0.12065 0.3048)
			(stroke
				(width 0.1)
				(type default)
			)
			(layer "B.Fab")
		)
		(fp_line
			(start 0.12065 -0.2794)
			(end -0.12065 -0.2794)
			(stroke
				(width 0.1)
				(type default)
			)
			(layer "B.Fab")
		)
		(fp_line
			(start 0.12065 -0.305054)
			(end 0.12065 -0.2794)
			(stroke
				(width 0.1)
				(type default)
			)
			(layer "B.Fab")
		)
		(fp_line
			(start -0.120396 0.3048)
			(end -0.120396 0.2794)
			(stroke
				(width 0.1)
				(type default)
			)
			(layer "B.Fab")
		)
		(fp_line
			(start -0.120396 0.2794)
			(end 0.12065 0.2794)
			(stroke
				(width 0.1)
				(type default)
			)
			(layer "B.Fab")
		)
		(fp_line
			(start -0.12065 -0.2794)
			(end -0.12065 -0.3048)
			(stroke
				(width 0.1)
				(type default)
			)
			(layer "B.Fab")
		)
		(fp_line
			(start -0.12065 -0.3048)
			(end -0.67945 -0.3048)
			(stroke
				(width 0.1)
				(type default)
			)
			(layer "B.Fab")
		)
		(fp_line
			(start -0.67945 0.3048)
			(end -0.120396 0.3048)
			(stroke
				(width 0.1)
				(type default)
			)
			(layer "B.Fab")
		)
		(fp_line
			(start -0.67945 -0.3048)
			(end -0.67945 0.3048)
			(stroke
				(width 0.1)
				(type default)
			)
			(layer "B.Fab")
		)
		(pad "1" smd circle
			(at 0.40005 0)
			(size 0 0)
			(layers "B.Cu" "B.Mask" "B.Paste")
			(net "UART_PEX1_SDB_BUF_R_TX")
		)
		(pad "2" smd circle
			(at -0.40005 0)
			(size 0 0)
			(layers "B.Cu" "B.Mask" "B.Paste")
			(net "UART_PEX1_SDB_BUF_TX")
		)
	)
	(footprint ""
		(layer "B.Cu")
		(at 189.371478 -115.608608)
		(property "Reference" "C899"
			(at 0 0 0)
			(layer "B.SilkS")
			(hide yes)
			(effects
				(font
					(size 1.27 1.27)
				)
				(justify mirror)
			)
		)
		(property "Value" ""
			(at 0 0 0)
			(layer "B.Fab")
			(effects
				(font
					(size 1.27 1.27)
				)
				(justify mirror)
			)
		)
		(duplicate_pad_numbers_are_jumpers no)
		(fp_line
			(start -0.7874 -0.4064)
			(end -0.7874 0.4064)
			(stroke
				(width 0.1524)
				(type default)
			)
			(layer "B.SilkS")
		)
		(fp_line
			(start -0.7874 0.4064)
			(end 0.7874 0.4064)
			(stroke
				(width 0.1524)
				(type default)
			)
			(layer "B.SilkS")
		)
		(fp_line
			(start 0.7874 -0.4064)
			(end -0.7874 -0.4064)
			(stroke
				(width 0.1524)
				(type default)
			)
			(layer "B.SilkS")
		)
		(fp_line
			(start 0.7874 0.4064)
			(end 0.7874 -0.4064)
			(stroke
				(width 0.1524)
				(type default)
			)
			(layer "B.SilkS")
		)
		(fp_line
			(start -0.67945 -0.3048)
			(end -0.67945 0.3048)
			(stroke
				(width 0.1)
				(type default)
			)
			(layer "B.Fab")
		)
		(fp_line
			(start -0.67945 0.3048)
			(end -0.120396 0.3048)
			(stroke
				(width 0.1)
				(type default)
			)
			(layer "B.Fab")
		)
		(fp_line
			(start -0.12065 -0.3048)
			(end -0.67945 -0.3048)
			(stroke
				(width 0.1)
				(type default)
			)
			(layer "B.Fab")
		)
		(fp_line
			(start -0.12065 -0.2794)
			(end -0.12065 -0.3048)
			(stroke
				(width 0.1)
				(type default)
			)
			(layer "B.Fab")
		)
		(fp_line
			(start -0.120396 0.2794)
			(end 0.12065 0.2794)
			(stroke
				(width 0.1)
				(type default)
			)
			(layer "B.Fab")
		)
		(fp_line
			(start -0.120396 0.3048)
			(end -0.120396 0.2794)
			(stroke
				(width 0.1)
				(type default)
			)
			(layer "B.Fab")
		)
		(fp_line
			(start 0.12065 -0.305054)
			(end 0.12065 -0.2794)
			(stroke
				(width 0.1)
				(type default)
			)
			(layer "B.Fab")
		)
		(fp_line
			(start 0.12065 -0.2794)
			(end -0.12065 -0.2794)
			(stroke
				(width 0.1)
				(type default)
			)
			(layer "B.Fab")
		)
		(fp_line
			(start 0.12065 0.2794)
			(end 0.12065 0.3048)
			(stroke
				(width 0.1)
				(type default)
			)
			(layer "B.Fab")
		)
		(fp_line
			(start 0.12065 0.3048)
			(end 0.67945 0.3048)
			(stroke
				(width 0.1)
				(type default)
			)
			(layer "B.Fab")
		)
		(fp_line
			(start 0.67945 -0.305054)
			(end 0.12065 -0.305054)
			(stroke
				(width 0.1)
				(type default)
			)
			(layer "B.Fab")
		)
		(fp_line
			(start 0.67945 0.3048)
			(end 0.67945 -0.305054)
			(stroke
				(width 0.1)
				(type default)
			)
			(layer "B.Fab")
		)
		(pad "1" smd circle
			(at 0.40005 0 180)
			(size 0 0)
			(layers "B.Cu" "B.Mask" "B.Paste")
			(net "P3V3_NIC3")
		)
		(pad "2" smd circle
			(at -0.40005 0 180)
			(size 0 0)
			(layers "B.Cu" "B.Mask" "B.Paste")
			(net "GND")
		)
	)
	(footprint ""
		(layer "B.Cu")
		(at 49.1998 -290.674806 180)
		(property "Reference" "C1104"
			(at 0 0 0)
			(layer "B.SilkS")
			(hide yes)
			(effects
				(font
					(size 1.27 1.27)
				)
				(justify mirror)
			)
		)
		(property "Value" ""
			(at 0 0 0)
			(layer "B.Fab")
			(effects
				(font
					(size 1.27 1.27)
				)
				(justify mirror)
			)
		)
		(duplicate_pad_numbers_are_jumpers no)
		(fp_line
			(start 0.299974 0.150114)
			(end 0.299974 -0.150114)
			(stroke
				(width 0.1)
				(type default)
			)
			(layer "B.Fab")
		)
		(fp_line
			(start 0.299974 -0.150114)
			(end -0.299974 -0.150114)
			(stroke
				(width 0.1)
				(type default)
			)
			(layer "B.Fab")
		)
		(fp_line
			(start -0.299974 0.150114)
			(end 0.299974 0.150114)
			(stroke
				(width 0.1)
				(type default)
			)
			(layer "B.Fab")
		)
		(fp_line
			(start -0.299974 -0.150114)
			(end -0.299974 0.150114)
			(stroke
				(width 0.1)
				(type default)
			)
			(layer "B.Fab")
		)
		(pad "1" smd rect
			(at 0.2667 0)
			(size 0.3048 0.381)
			(layers "B.Cu" "B.Mask" "B.Paste")
			(net "P0V8_PEX0")
		)
		(pad "2" smd rect
			(at -0.2667 0)
			(size 0.3048 0.381)
			(layers "B.Cu" "B.Mask" "B.Paste")
			(net "GND")
		)
	)
	(footprint ""
		(layer "B.Cu")
		(at 174.800006 -292.099746 90)
		(property "Reference" "C1416"
			(at 0 0 90)
			(layer "B.SilkS")
			(hide yes)
			(effects
				(font
					(size 1.27 1.27)
				)
				(justify mirror)
			)
		)
		(property "Value" ""
			(at 0 0 90)
			(layer "B.Fab")
			(effects
				(font
					(size 1.27 1.27)
				)
				(justify mirror)
			)
		)
		(duplicate_pad_numbers_are_jumpers no)
		(fp_line
			(start 0.299974 -0.150114)
			(end -0.299974 -0.150114)
			(stroke
				(width 0.1)
				(type default)
			)
			(layer "B.Fab")
		)
		(fp_line
			(start -0.299974 -0.150114)
			(end -0.299974 0.150114)
			(stroke
				(width 0.1)
				(type default)
			)
			(layer "B.Fab")
		)
		(fp_line
			(start 0.299974 0.150114)
			(end 0.299974 -0.150114)
			(stroke
				(width 0.1)
				(type default)
			)
			(layer "B.Fab")
		)
		(fp_line
			(start -0.299974 0.150114)
			(end 0.299974 0.150114)
			(stroke
				(width 0.1)
				(type default)
			)
			(layer "B.Fab")
		)
		(pad "1" smd rect
			(at 0.2667 0 270)
			(size 0.3048 0.381)
			(layers "B.Cu" "B.Mask" "B.Paste")
			(net "P0V8_SERDES_VDDA_PEX1")
		)
		(pad "2" smd rect
			(at -0.2667 0 270)
			(size 0.3048 0.381)
			(layers "B.Cu" "B.Mask" "B.Paste")
			(net "GND")
		)
	)
	(footprint ""
		(layer "B.Cu")
		(at 172.900086 -301.599854 -90)
		(property "Reference" "C1469"
			(at 0 0 90)
			(layer "B.SilkS")
			(hide yes)
			(effects
				(font
					(size 1.27 1.27)
				)
				(justify mirror)
			)
		)
		(property "Value" ""
			(at 0 0 90)
			(layer "B.Fab")
			(effects
				(font
					(size 1.27 1.27)
				)
				(justify mirror)
			)
		)
		(duplicate_pad_numbers_are_jumpers no)
		(fp_line
			(start -0.299974 0.150114)
			(end 0.299974 0.150114)
			(stroke
				(width 0.1)
				(type default)
			)
			(layer "B.Fab")
		)
		(fp_line
			(start 0.299974 0.150114)
			(end 0.299974 -0.150114)
			(stroke
				(width 0.1)
				(type default)
			)
			(layer "B.Fab")
		)
		(fp_line
			(start -0.299974 -0.150114)
			(end -0.299974 0.150114)
			(stroke
				(width 0.1)
				(type default)
			)
			(layer "B.Fab")
		)
		(fp_line
			(start 0.299974 -0.150114)
			(end -0.299974 -0.150114)
			(stroke
				(width 0.1)
				(type default)
			)
			(layer "B.Fab")
		)
		(pad "1" smd rect
			(at 0.2667 0 90)
			(size 0.3048 0.381)
			(layers "B.Cu" "B.Mask" "B.Paste")
			(net "P0V8_SERDES_VDDA_PEX1")
		)
		(pad "2" smd rect
			(at -0.2667 0 90)
			(size 0.3048 0.381)
			(layers "B.Cu" "B.Mask" "B.Paste")
			(net "GND")
		)
	)
	(footprint ""
		(layer "B.Cu")
		(at 403.674834 -286.399732 90)
		(property "Reference" "C3475"
			(at 0 0 90)
			(layer "B.SilkS")
			(hide yes)
			(effects
				(font
					(size 1.27 1.27)
				)
				(justify mirror)
			)
		)
		(property "Value" ""
			(at 0 0 90)
			(layer "B.Fab")
			(effects
				(font
					(size 1.27 1.27)
				)
				(justify mirror)
			)
		)
		(duplicate_pad_numbers_are_jumpers no)
		(fp_line
			(start 0.299974 -0.150114)
			(end -0.299974 -0.150114)
			(stroke
				(width 0.1)
				(type default)
			)
			(layer "B.Fab")
		)
		(fp_line
			(start -0.299974 -0.150114)
			(end -0.299974 0.150114)
			(stroke
				(width 0.1)
				(type default)
			)
			(layer "B.Fab")
		)
		(fp_line
			(start 0.299974 0.150114)
			(end 0.299974 -0.150114)
			(stroke
				(width 0.1)
				(type default)
			)
			(layer "B.Fab")
		)
		(fp_line
			(start -0.299974 0.150114)
			(end 0.299974 0.150114)
			(stroke
				(width 0.1)
				(type default)
			)
			(layer "B.Fab")
		)
		(pad "1" smd rect
			(at 0.2667 0 270)
			(size 0.3048 0.381)
			(layers "B.Cu" "B.Mask" "B.Paste")
			(net "P1V25_SERDES_VDDPLL_PEX3")
		)
		(pad "2" smd rect
			(at -0.2667 0 270)
			(size 0.3048 0.381)
			(layers "B.Cu" "B.Mask" "B.Paste")
			(net "GND")
		)
	)
	(footprint ""
		(layer "B.Cu")
		(at 220.676978 -266.873228)
		(property "Reference" "L101"
			(at 0 0 0)
			(layer "B.SilkS")
			(hide yes)
			(effects
				(font
					(size 1.27 1.27)
				)
				(justify mirror)
			)
		)
		(property "Value" ""
			(at 0 0 0)
			(layer "B.Fab")
			(effects
				(font
					(size 1.27 1.27)
				)
				(justify mirror)
			)
		)
		(duplicate_pad_numbers_are_jumpers no)
		(fp_line
			(start -2.248154 -4.9911)
			(end 2.248154 -4.9911)
			(stroke
				(width 0.1524)
				(type default)
			)
			(layer "B.SilkS")
		)
		(fp_line
			(start -2.248154 -1.689862)
			(end -2.248154 -4.9911)
			(stroke
				(width 0.1524)
				(type default)
			)
			(layer "B.SilkS")
		)
		(fp_line
			(start -2.248154 4.9911)
			(end -2.248154 2.114296)
			(stroke
				(width 0.1524)
				(type default)
			)
			(layer "B.SilkS")
		)
		(fp_line
			(start 2.248154 -4.9911)
			(end 2.248154 -1.689862)
			(stroke
				(width 0.1524)
				(type default)
			)
			(layer "B.SilkS")
		)
		(fp_line
			(start 2.248154 2.114296)
			(end 2.248154 4.9911)
			(stroke
				(width 0.1524)
				(type default)
			)
			(layer "B.SilkS")
		)
		(fp_line
			(start 2.248154 4.9911)
			(end -2.248154 4.9911)
			(stroke
				(width 0.1524)
				(type default)
			)
			(layer "B.SilkS")
		)
		(fp_line
			(start -1.700022 -0.899922)
			(end 1.700022 -0.899922)
			(stroke
				(width 0.1)
				(type default)
			)
			(layer "B.Fab")
		)
		(fp_line
			(start -1.700022 0.899922)
			(end -1.700022 -0.899922)
			(stroke
				(width 0.1)
				(type default)
			)
			(layer "B.Fab")
		)
		(fp_line
			(start 1.700022 -0.899922)
			(end 1.700022 0.899922)
			(stroke
				(width 0.1)
				(type default)
			)
			(layer "B.Fab")
		)
		(fp_line
			(start 1.700022 0.899922)
			(end -1.700022 0.899922)
			(stroke
				(width 0.1)
				(type default)
			)
			(layer "B.Fab")
		)
		(pad "1" smd rect
			(at 1.575054 0 180)
			(size 1.1684 9.8044)
			(layers "B.Cu" "B.Mask" "B.Paste")
			(net "P1V25_PEX1")
		)
		(pad "2" smd rect
			(at -1.575054 0 180)
			(size 1.1684 9.8044)
			(layers "B.Cu" "B.Mask" "B.Paste")
			(net "P1V25_SERDES_VDDPLL_PEX1")
		)
	)
	(footprint ""
		(layer "B.Cu")
		(at 355.520752 -282.259532 180)
		(property "Reference" "PR7173"
			(at 0 0 0)
			(layer "B.SilkS")
			(hide yes)
			(effects
				(font
					(size 1.27 1.27)
				)
				(justify mirror)
			)
		)
		(property "Value" ""
			(at 0 0 0)
			(layer "B.Fab")
			(effects
				(font
					(size 1.27 1.27)
				)
				(justify mirror)
			)
		)
		(duplicate_pad_numbers_are_jumpers no)
		(fp_line
			(start 0.7874 0.4064)
			(end 0.7874 -0.4064)
			(stroke
				(width 0.1524)
				(type default)
			)
			(layer "B.SilkS")
		)
		(fp_line
			(start 0.7874 -0.4064)
			(end -0.7874 -0.4064)
			(stroke
				(width 0.1524)
				(type default)
			)
			(layer "B.SilkS")
		)
		(fp_line
			(start -0.7874 0.4064)
			(end 0.7874 0.4064)
			(stroke
				(width 0.1524)
				(type default)
			)
			(layer "B.SilkS")
		)
		(fp_line
			(start -0.7874 -0.4064)
			(end -0.7874 0.4064)
			(stroke
				(width 0.1524)
				(type default)
			)
			(layer "B.SilkS")
		)
		(fp_line
			(start 0.67945 0.3048)
			(end 0.67945 -0.305054)
			(stroke
				(width 0.1)
				(type default)
			)
			(layer "B.Fab")
		)
		(fp_line
			(start 0.67945 -0.305054)
			(end 0.12065 -0.305054)
			(stroke
				(width 0.1)
				(type default)
			)
			(layer "B.Fab")
		)
		(fp_line
			(start 0.12065 0.3048)
			(end 0.67945 0.3048)
			(stroke
				(width 0.1)
				(type default)
			)
			(layer "B.Fab")
		)
		(fp_line
			(start 0.12065 0.2794)
			(end 0.12065 0.3048)
			(stroke
				(width 0.1)
				(type default)
			)
			(layer "B.Fab")
		)
		(fp_line
			(start 0.12065 -0.2794)
			(end -0.12065 -0.2794)
			(stroke
				(width 0.1)
				(type default)
			)
			(layer "B.Fab")
		)
		(fp_line
			(start 0.12065 -0.305054)
			(end 0.12065 -0.2794)
			(stroke
				(width 0.1)
				(type default)
			)
			(layer "B.Fab")
		)
		(fp_line
			(start -0.120396 0.3048)
			(end -0.120396 0.2794)
			(stroke
				(width 0.1)
				(type default)
			)
			(layer "B.Fab")
		)
		(fp_line
			(start -0.120396 0.2794)
			(end 0.12065 0.2794)
			(stroke
				(width 0.1)
				(type default)
			)
			(layer "B.Fab")
		)
		(fp_line
			(start -0.12065 -0.2794)
			(end -0.12065 -0.3048)
			(stroke
				(width 0.1)
				(type default)
			)
			(layer "B.Fab")
		)
		(fp_line
			(start -0.12065 -0.3048)
			(end -0.67945 -0.3048)
			(stroke
				(width 0.1)
				(type default)
			)
			(layer "B.Fab")
		)
		(fp_line
			(start -0.67945 0.3048)
			(end -0.120396 0.3048)
			(stroke
				(width 0.1)
				(type default)
			)
			(layer "B.Fab")
		)
		(fp_line
			(start -0.67945 -0.3048)
			(end -0.67945 0.3048)
			(stroke
				(width 0.1)
				(type default)
			)
			(layer "B.Fab")
		)
		(pad "1" smd circle
			(at 0.40005 0)
			(size 0 0)
			(layers "B.Cu" "B.Mask" "B.Paste")
			(net "P0V8_PEX2_EN3")
		)
		(pad "2" smd circle
			(at -0.40005 0)
			(size 0 0)
			(layers "B.Cu" "B.Mask" "B.Paste")
			(net "P0V8_PEX3_VCC1")
		)
	)
	(footprint ""
		(layer "B.Cu")
		(at 217.2335 -222.368872)
		(property "Reference" "R6799"
			(at 0 0 0)
			(layer "B.SilkS")
			(hide yes)
			(effects
				(font
					(size 1.27 1.27)
				)
				(justify mirror)
			)
		)
		(property "Value" ""
			(at 0 0 0)
			(layer "B.Fab")
			(effects
				(font
					(size 1.27 1.27)
				)
				(justify mirror)
			)
		)
		(duplicate_pad_numbers_are_jumpers no)
		(fp_line
			(start -0.7874 -0.4064)
			(end -0.7874 0.4064)
			(stroke
				(width 0.1524)
				(type default)
			)
			(layer "B.SilkS")
		)
		(fp_line
			(start -0.7874 0.4064)
			(end 0.7874 0.4064)
			(stroke
				(width 0.1524)
				(type default)
			)
			(layer "B.SilkS")
		)
		(fp_line
			(start 0.7874 -0.4064)
			(end -0.7874 -0.4064)
			(stroke
				(width 0.1524)
				(type default)
			)
			(layer "B.SilkS")
		)
		(fp_line
			(start 0.7874 0.4064)
			(end 0.7874 -0.4064)
			(stroke
				(width 0.1524)
				(type default)
			)
			(layer "B.SilkS")
		)
		(fp_line
			(start -0.67945 -0.3048)
			(end -0.67945 0.3048)
			(stroke
				(width 0.1)
				(type default)
			)
			(layer "B.Fab")
		)
		(fp_line
			(start -0.67945 0.3048)
			(end -0.120396 0.3048)
			(stroke
				(width 0.1)
				(type default)
			)
			(layer "B.Fab")
		)
		(fp_line
			(start -0.12065 -0.3048)
			(end -0.67945 -0.3048)
			(stroke
				(width 0.1)
				(type default)
			)
			(layer "B.Fab")
		)
		(fp_line
			(start -0.12065 -0.2794)
			(end -0.12065 -0.3048)
			(stroke
				(width 0.1)
				(type default)
			)
			(layer "B.Fab")
		)
		(fp_line
			(start -0.120396 0.2794)
			(end 0.12065 0.2794)
			(stroke
				(width 0.1)
				(type default)
			)
			(layer "B.Fab")
		)
		(fp_line
			(start -0.120396 0.3048)
			(end -0.120396 0.2794)
			(stroke
				(width 0.1)
				(type default)
			)
			(layer "B.Fab")
		)
		(fp_line
			(start 0.12065 -0.305054)
			(end 0.12065 -0.2794)
			(stroke
				(width 0.1)
				(type default)
			)
			(layer "B.Fab")
		)
		(fp_line
			(start 0.12065 -0.2794)
			(end -0.12065 -0.2794)
			(stroke
				(width 0.1)
				(type default)
			)
			(layer "B.Fab")
		)
		(fp_line
			(start 0.12065 0.2794)
			(end 0.12065 0.3048)
			(stroke
				(width 0.1)
				(type default)
			)
			(layer "B.Fab")
		)
		(fp_line
			(start 0.12065 0.3048)
			(end 0.67945 0.3048)
			(stroke
				(width 0.1)
				(type default)
			)
			(layer "B.Fab")
		)
		(fp_line
			(start 0.67945 -0.305054)
			(end 0.12065 -0.305054)
			(stroke
				(width 0.1)
				(type default)
			)
			(layer "B.Fab")
		)
		(fp_line
			(start 0.67945 0.3048)
			(end 0.67945 -0.305054)
			(stroke
				(width 0.1)
				(type default)
			)
			(layer "B.Fab")
		)
		(pad "1" smd circle
			(at 0.40005 0 180)
			(size 0 0)
			(layers "B.Cu" "B.Mask" "B.Paste")
			(net "SMB_BIC_FPGA_SCL")
		)
		(pad "2" smd circle
			(at -0.40005 0 180)
			(size 0 0)
			(layers "B.Cu" "B.Mask" "B.Paste")
			(net "SMB_BIC_FPGA_R1_SCL")
		)
	)
	(footprint ""
		(layer "B.Cu")
		(at 304.408078 -300.174914 180)
		(property "Reference" "C3361"
			(at 0 0 0)
			(layer "B.SilkS")
			(hide yes)
			(effects
				(font
					(size 1.27 1.27)
				)
				(justify mirror)
			)
		)
		(property "Value" ""
			(at 0 0 0)
			(layer "B.Fab")
			(effects
				(font
					(size 1.27 1.27)
				)
				(justify mirror)
			)
		)
		(duplicate_pad_numbers_are_jumpers no)
		(fp_line
			(start 0.299974 0.150114)
			(end 0.299974 -0.150114)
			(stroke
				(width 0.1)
				(type default)
			)
			(layer "B.Fab")
		)
		(fp_line
			(start 0.299974 -0.150114)
			(end -0.299974 -0.150114)
			(stroke
				(width 0.1)
				(type default)
			)
			(layer "B.Fab")
		)
		(fp_line
			(start -0.299974 0.150114)
			(end 0.299974 0.150114)
			(stroke
				(width 0.1)
				(type default)
			)
			(layer "B.Fab")
		)
		(fp_line
			(start -0.299974 -0.150114)
			(end -0.299974 0.150114)
			(stroke
				(width 0.1)
				(type default)
			)
			(layer "B.Fab")
		)
		(pad "1" smd rect
			(at 0.2667 0)
			(size 0.3048 0.381)
			(layers "B.Cu" "B.Mask" "B.Paste")
			(net "P1V8_VDDA_PEX2")
		)
		(pad "2" smd rect
			(at -0.2667 0)
			(size 0.3048 0.381)
			(layers "B.Cu" "B.Mask" "B.Paste")
			(net "GND")
		)
	)
	(footprint ""
		(layer "B.Cu")
		(at 338.398612 -89.608152 180)
		(property "Reference" "C2680"
			(at 0 0 0)
			(layer "B.SilkS")
			(hide yes)
			(effects
				(font
					(size 1.27 1.27)
				)
				(justify mirror)
			)
		)
		(property "Value" ""
			(at 0 0 0)
			(layer "B.Fab")
			(effects
				(font
					(size 1.27 1.27)
				)
				(justify mirror)
			)
		)
		(duplicate_pad_numbers_are_jumpers no)
		(fp_line
			(start 0.7874 0.4064)
			(end 0.7874 -0.4064)
			(stroke
				(width 0.1524)
				(type default)
			)
			(layer "B.SilkS")
		)
		(fp_line
			(start 0.7874 -0.4064)
			(end -0.7874 -0.4064)
			(stroke
				(width 0.1524)
				(type default)
			)
			(layer "B.SilkS")
		)
		(fp_line
			(start -0.7874 0.4064)
			(end 0.7874 0.4064)
			(stroke
				(width 0.1524)
				(type default)
			)
			(layer "B.SilkS")
		)
		(fp_line
			(start -0.7874 -0.4064)
			(end -0.7874 0.4064)
			(stroke
				(width 0.1524)
				(type default)
			)
			(layer "B.SilkS")
		)
		(fp_line
			(start 0.67945 0.3048)
			(end 0.67945 -0.305054)
			(stroke
				(width 0.1)
				(type default)
			)
			(layer "B.Fab")
		)
		(fp_line
			(start 0.67945 -0.305054)
			(end 0.12065 -0.305054)
			(stroke
				(width 0.1)
				(type default)
			)
			(layer "B.Fab")
		)
		(fp_line
			(start 0.12065 0.3048)
			(end 0.67945 0.3048)
			(stroke
				(width 0.1)
				(type default)
			)
			(layer "B.Fab")
		)
		(fp_line
			(start 0.12065 0.2794)
			(end 0.12065 0.3048)
			(stroke
				(width 0.1)
				(type default)
			)
			(layer "B.Fab")
		)
		(fp_line
			(start 0.12065 -0.2794)
			(end -0.12065 -0.2794)
			(stroke
				(width 0.1)
				(type default)
			)
			(layer "B.Fab")
		)
		(fp_line
			(start 0.12065 -0.305054)
			(end 0.12065 -0.2794)
			(stroke
				(width 0.1)
				(type default)
			)
			(layer "B.Fab")
		)
		(fp_line
			(start -0.120396 0.3048)
			(end -0.120396 0.2794)
			(stroke
				(width 0.1)
				(type default)
			)
			(layer "B.Fab")
		)
		(fp_line
			(start -0.120396 0.2794)
			(end 0.12065 0.2794)
			(stroke
				(width 0.1)
				(type default)
			)
			(layer "B.Fab")
		)
		(fp_line
			(start -0.12065 -0.2794)
			(end -0.12065 -0.3048)
			(stroke
				(width 0.1)
				(type default)
			)
			(layer "B.Fab")
		)
		(fp_line
			(start -0.12065 -0.3048)
			(end -0.67945 -0.3048)
			(stroke
				(width 0.1)
				(type default)
			)
			(layer "B.Fab")
		)
		(fp_line
			(start -0.67945 0.3048)
			(end -0.120396 0.3048)
			(stroke
				(width 0.1)
				(type default)
			)
			(layer "B.Fab")
		)
		(fp_line
			(start -0.67945 -0.3048)
			(end -0.67945 0.3048)
			(stroke
				(width 0.1)
				(type default)
			)
			(layer "B.Fab")
		)
		(pad "1" smd circle
			(at 0.40005 0)
			(size 0 0)
			(layers "B.Cu" "B.Mask" "B.Paste")
			(net "P3V3_VDD_9ZXL0851_8_15")
		)
		(pad "2" smd circle
			(at -0.40005 0)
			(size 0 0)
			(layers "B.Cu" "B.Mask" "B.Paste")
			(net "GND")
		)
	)
	(footprint ""
		(layer "B.Cu")
		(at 183.82488 -305.399948 -90)
		(property "Reference" "C3160"
			(at 0 0 90)
			(layer "B.SilkS")
			(hide yes)
			(effects
				(font
					(size 1.27 1.27)
				)
				(justify mirror)
			)
		)
		(property "Value" ""
			(at 0 0 90)
			(layer "B.Fab")
			(effects
				(font
					(size 1.27 1.27)
				)
				(justify mirror)
			)
		)
		(duplicate_pad_numbers_are_jumpers no)
		(fp_line
			(start -0.299974 0.150114)
			(end 0.299974 0.150114)
			(stroke
				(width 0.1)
				(type default)
			)
			(layer "B.Fab")
		)
		(fp_line
			(start 0.299974 0.150114)
			(end 0.299974 -0.150114)
			(stroke
				(width 0.1)
				(type default)
			)
			(layer "B.Fab")
		)
		(fp_line
			(start -0.299974 -0.150114)
			(end -0.299974 0.150114)
			(stroke
				(width 0.1)
				(type default)
			)
			(layer "B.Fab")
		)
		(fp_line
			(start 0.299974 -0.150114)
			(end -0.299974 -0.150114)
			(stroke
				(width 0.1)
				(type default)
			)
			(layer "B.Fab")
		)
		(pad "1" smd rect
			(at 0.2667 0 90)
			(size 0.3048 0.381)
			(layers "B.Cu" "B.Mask" "B.Paste")
			(net "P1V25_SERDES_VDDPLL_PEX1")
		)
		(pad "2" smd rect
			(at -0.2667 0 90)
			(size 0.3048 0.381)
			(layers "B.Cu" "B.Mask" "B.Paste")
			(net "GND")
		)
	)
	(footprint ""
		(layer "B.Cu")
		(at 305.490626 -246.199406 90)
		(property "Reference" "R4103"
			(at 0 0 90)
			(layer "B.SilkS")
			(hide yes)
			(effects
				(font
					(size 1.27 1.27)
				)
				(justify mirror)
			)
		)
		(property "Value" ""
			(at 0 0 90)
			(layer "B.Fab")
			(effects
				(font
					(size 1.27 1.27)
				)
				(justify mirror)
			)
		)
		(duplicate_pad_numbers_are_jumpers no)
		(fp_line
			(start 0.7874 -0.4064)
			(end -0.7874 -0.4064)
			(stroke
				(width 0.1524)
				(type default)
			)
			(layer "B.SilkS")
		)
		(fp_line
			(start -0.7874 -0.4064)
			(end -0.7874 0.4064)
			(stroke
				(width 0.1524)
				(type default)
			)
			(layer "B.SilkS")
		)
		(fp_line
			(start 0.7874 0.4064)
			(end 0.7874 -0.4064)
			(stroke
				(width 0.1524)
				(type default)
			)
			(layer "B.SilkS")
		)
		(fp_line
			(start -0.7874 0.4064)
			(end 0.7874 0.4064)
			(stroke
				(width 0.1524)
				(type default)
			)
			(layer "B.SilkS")
		)
		(fp_line
			(start 0.67945 -0.305054)
			(end 0.12065 -0.305054)
			(stroke
				(width 0.1)
				(type default)
			)
			(layer "B.Fab")
		)
		(fp_line
			(start 0.12065 -0.305054)
			(end 0.12065 -0.2794)
			(stroke
				(width 0.1)
				(type default)
			)
			(layer "B.Fab")
		)
		(fp_line
			(start -0.12065 -0.3048)
			(end -0.67945 -0.3048)
			(stroke
				(width 0.1)
				(type default)
			)
			(layer "B.Fab")
		)
		(fp_line
			(start -0.67945 -0.3048)
			(end -0.67945 0.3048)
			(stroke
				(width 0.1)
				(type default)
			)
			(layer "B.Fab")
		)
		(fp_line
			(start 0.12065 -0.2794)
			(end -0.12065 -0.2794)
			(stroke
				(width 0.1)
				(type default)
			)
			(layer "B.Fab")
		)
		(fp_line
			(start -0.12065 -0.2794)
			(end -0.12065 -0.3048)
			(stroke
				(width 0.1)
				(type default)
			)
			(layer "B.Fab")
		)
		(fp_line
			(start 0.12065 0.2794)
			(end 0.12065 0.3048)
			(stroke
				(width 0.1)
				(type default)
			)
			(layer "B.Fab")
		)
		(fp_line
			(start -0.120396 0.2794)
			(end 0.12065 0.2794)
			(stroke
				(width 0.1)
				(type default)
			)
			(layer "B.Fab")
		)
		(fp_line
			(start 0.67945 0.3048)
			(end 0.67945 -0.305054)
			(stroke
				(width 0.1)
				(type default)
			)
			(layer "B.Fab")
		)
		(fp_line
			(start 0.12065 0.3048)
			(end 0.67945 0.3048)
			(stroke
				(width 0.1)
				(type default)
			)
			(layer "B.Fab")
		)
		(fp_line
			(start -0.120396 0.3048)
			(end -0.120396 0.2794)
			(stroke
				(width 0.1)
				(type default)
			)
			(layer "B.Fab")
		)
		(fp_line
			(start -0.67945 0.3048)
			(end -0.120396 0.3048)
			(stroke
				(width 0.1)
				(type default)
			)
			(layer "B.Fab")
		)
		(pad "1" smd circle
			(at 0.40005 0 270)
			(size 0 0)
			(layers "B.Cu" "B.Mask" "B.Paste")
			(net "SMB_MB_BMC_R_SDA")
		)
		(pad "2" smd circle
			(at -0.40005 0 270)
			(size 0 0)
			(layers "B.Cu" "B.Mask" "B.Paste")
			(net "SMB_MB_BMC_ISO_SDA")
		)
	)
	(footprint ""
		(layer "B.Cu")
		(at 105.619042 -395.673834 90)
		(property "Reference" "R5442"
			(at 0 0 90)
			(layer "B.SilkS")
			(hide yes)
			(effects
				(font
					(size 1.27 1.27)
				)
				(justify mirror)
			)
		)
		(property "Value" ""
			(at 0 0 90)
			(layer "B.Fab")
			(effects
				(font
					(size 1.27 1.27)
				)
				(justify mirror)
			)
		)
		(duplicate_pad_numbers_are_jumpers no)
		(fp_line
			(start 0.7874 -0.4064)
			(end -0.7874 -0.4064)
			(stroke
				(width 0.1524)
				(type default)
			)
			(layer "B.SilkS")
		)
		(fp_line
			(start -0.7874 -0.4064)
			(end -0.7874 0.4064)
			(stroke
				(width 0.1524)
				(type default)
			)
			(layer "B.SilkS")
		)
		(fp_line
			(start 0.7874 0.4064)
			(end 0.7874 -0.4064)
			(stroke
				(width 0.1524)
				(type default)
			)
			(layer "B.SilkS")
		)
		(fp_line
			(start -0.7874 0.4064)
			(end 0.7874 0.4064)
			(stroke
				(width 0.1524)
				(type default)
			)
			(layer "B.SilkS")
		)
		(fp_line
			(start 0.67945 -0.305054)
			(end 0.12065 -0.305054)
			(stroke
				(width 0.1)
				(type default)
			)
			(layer "B.Fab")
		)
		(fp_line
			(start 0.12065 -0.305054)
			(end 0.12065 -0.2794)
			(stroke
				(width 0.1)
				(type default)
			)
			(layer "B.Fab")
		)
		(fp_line
			(start -0.12065 -0.3048)
			(end -0.67945 -0.3048)
			(stroke
				(width 0.1)
				(type default)
			)
			(layer "B.Fab")
		)
		(fp_line
			(start -0.67945 -0.3048)
			(end -0.67945 0.3048)
			(stroke
				(width 0.1)
				(type default)
			)
			(layer "B.Fab")
		)
		(fp_line
			(start 0.12065 -0.2794)
			(end -0.12065 -0.2794)
			(stroke
				(width 0.1)
				(type default)
			)
			(layer "B.Fab")
		)
		(fp_line
			(start -0.12065 -0.2794)
			(end -0.12065 -0.3048)
			(stroke
				(width 0.1)
				(type default)
			)
			(layer "B.Fab")
		)
		(fp_line
			(start 0.12065 0.2794)
			(end 0.12065 0.3048)
			(stroke
				(width 0.1)
				(type default)
			)
			(layer "B.Fab")
		)
		(fp_line
			(start -0.120396 0.2794)
			(end 0.12065 0.2794)
			(stroke
				(width 0.1)
				(type default)
			)
			(layer "B.Fab")
		)
		(fp_line
			(start 0.67945 0.3048)
			(end 0.67945 -0.305054)
			(stroke
				(width 0.1)
				(type default)
			)
			(layer "B.Fab")
		)
		(fp_line
			(start 0.12065 0.3048)
			(end 0.67945 0.3048)
			(stroke
				(width 0.1)
				(type default)
			)
			(layer "B.Fab")
		)
		(fp_line
			(start -0.120396 0.3048)
			(end -0.120396 0.2794)
			(stroke
				(width 0.1)
				(type default)
			)
			(layer "B.Fab")
		)
		(fp_line
			(start -0.67945 0.3048)
			(end -0.120396 0.3048)
			(stroke
				(width 0.1)
				(type default)
			)
			(layer "B.Fab")
		)
		(pad "1" smd circle
			(at 0.40005 0 270)
			(size 0 0)
			(layers "B.Cu" "B.Mask" "B.Paste")
			(net "P3V3_AUX")
		)
		(pad "2" smd circle
			(at -0.40005 0 270)
			(size 0 0)
			(layers "B.Cu" "B.Mask" "B.Paste")
			(net "P3V3_BIC_USB_HUB")
		)
	)
	(footprint ""
		(layer "B.Cu")
		(at 378.079 -239.014 -90)
		(property "Reference" "C2564"
			(at 0 0 90)
			(layer "B.SilkS")
			(hide yes)
			(effects
				(font
					(size 1.27 1.27)
				)
				(justify mirror)
			)
		)
		(property "Value" ""
			(at 0 0 90)
			(layer "B.Fab")
			(effects
				(font
					(size 1.27 1.27)
				)
				(justify mirror)
			)
		)
		(duplicate_pad_numbers_are_jumpers no)
		(fp_line
			(start -1.2954 0.5842)
			(end 1.2954 0.5842)
			(stroke
				(width 0.1524)
				(type default)
			)
			(layer "B.SilkS")
		)
		(fp_line
			(start 1.2954 0.5842)
			(end 1.2954 -0.5842)
			(stroke
				(width 0.1524)
				(type default)
			)
			(layer "B.SilkS")
		)
		(fp_line
			(start -1.2954 -0.5842)
			(end -1.2954 0.5842)
			(stroke
				(width 0.1524)
				(type default)
			)
			(layer "B.SilkS")
		)
		(fp_line
			(start 1.2954 -0.5842)
			(end -1.2954 -0.5842)
			(stroke
				(width 0.1524)
				(type default)
			)
			(layer "B.SilkS")
		)
		(fp_line
			(start -0.8636 0.4572)
			(end 0.8636 0.4572)
			(stroke
				(width 0.1)
				(type default)
			)
			(layer "B.Fab")
		)
		(fp_line
			(start 0.8636 0.4572)
			(end 0.8636 0.4064)
			(stroke
				(width 0.1)
				(type default)
			)
			(layer "B.Fab")
		)
		(fp_line
			(start -1.1938 0.4064)
			(end -0.8636 0.4064)
			(stroke
				(width 0.1)
				(type default)
			)
			(layer "B.Fab")
		)
		(fp_line
			(start -0.8636 0.4064)
			(end -0.8636 0.4572)
			(stroke
				(width 0.1)
				(type default)
			)
			(layer "B.Fab")
		)
		(fp_line
			(start 0.8636 0.4064)
			(end 1.1938 0.4064)
			(stroke
				(width 0.1)
				(type default)
			)
			(layer "B.Fab")
		)
		(fp_line
			(start 1.1938 0.4064)
			(end 1.1938 -0.4064)
			(stroke
				(width 0.1)
				(type default)
			)
			(layer "B.Fab")
		)
		(fp_line
			(start -1.1938 -0.4064)
			(end -1.1938 0.4064)
			(stroke
				(width 0.1)
				(type default)
			)
			(layer "B.Fab")
		)
		(fp_line
			(start -0.8636 -0.4064)
			(end -1.1938 -0.4064)
			(stroke
				(width 0.1)
				(type default)
			)
			(layer "B.Fab")
		)
		(fp_line
			(start 0.8636 -0.4064)
			(end 0.8636 -0.4572)
			(stroke
				(width 0.1)
				(type default)
			)
			(layer "B.Fab")
		)
		(fp_line
			(start 1.1938 -0.4064)
			(end 0.8636 -0.4064)
			(stroke
				(width 0.1)
				(type default)
			)
			(layer "B.Fab")
		)
		(fp_line
			(start -0.8636 -0.4572)
			(end -0.8636 -0.4064)
			(stroke
				(width 0.1)
				(type default)
			)
			(layer "B.Fab")
		)
		(fp_line
			(start 0.8636 -0.4572)
			(end -0.8636 -0.4572)
			(stroke
				(width 0.1)
				(type default)
			)
			(layer "B.Fab")
		)
		(pad "1" smd rect
			(at 0.7366 0 180)
			(size 0.7112 0.8128)
			(layers "B.Cu" "B.Mask" "B.Paste")
			(net "P3V3_AUX")
		)
		(pad "2" smd rect
			(at -0.7366 0 180)
			(size 0.7112 0.8128)
			(layers "B.Cu" "B.Mask" "B.Paste")
			(net "GND")
		)
	)
	(footprint ""
		(layer "B.Cu")
		(at 122.809254 -325.186294 -90)
		(property "Reference" "C4271"
			(at 0 0 90)
			(layer "B.SilkS")
			(hide yes)
			(effects
				(font
					(size 1.27 1.27)
				)
				(justify mirror)
			)
		)
		(property "Value" ""
			(at 0 0 90)
			(layer "B.Fab")
			(effects
				(font
					(size 1.27 1.27)
				)
				(justify mirror)
			)
		)
		(duplicate_pad_numbers_are_jumpers no)
		(fp_line
			(start -1.2954 0.5842)
			(end 1.2954 0.5842)
			(stroke
				(width 0.1524)
				(type default)
			)
			(layer "B.SilkS")
		)
		(fp_line
			(start 1.2954 0.5842)
			(end 1.2954 -0.5842)
			(stroke
				(width 0.1524)
				(type default)
			)
			(layer "B.SilkS")
		)
		(fp_line
			(start -1.2954 -0.5842)
			(end -1.2954 0.5842)
			(stroke
				(width 0.1524)
				(type default)
			)
			(layer "B.SilkS")
		)
		(fp_line
			(start 1.2954 -0.5842)
			(end -1.2954 -0.5842)
			(stroke
				(width 0.1524)
				(type default)
			)
			(layer "B.SilkS")
		)
		(fp_line
			(start -0.8636 0.4572)
			(end 0.8636 0.4572)
			(stroke
				(width 0.1)
				(type default)
			)
			(layer "B.Fab")
		)
		(fp_line
			(start 0.8636 0.4572)
			(end 0.8636 0.4064)
			(stroke
				(width 0.1)
				(type default)
			)
			(layer "B.Fab")
		)
		(fp_line
			(start -1.1938 0.4064)
			(end -0.8636 0.4064)
			(stroke
				(width 0.1)
				(type default)
			)
			(layer "B.Fab")
		)
		(fp_line
			(start -0.8636 0.4064)
			(end -0.8636 0.4572)
			(stroke
				(width 0.1)
				(type default)
			)
			(layer "B.Fab")
		)
		(fp_line
			(start 0.8636 0.4064)
			(end 1.1938 0.4064)
			(stroke
				(width 0.1)
				(type default)
			)
			(layer "B.Fab")
		)
		(fp_line
			(start 1.1938 0.4064)
			(end 1.1938 -0.4064)
			(stroke
				(width 0.1)
				(type default)
			)
			(layer "B.Fab")
		)
		(fp_line
			(start -1.1938 -0.4064)
			(end -1.1938 0.4064)
			(stroke
				(width 0.1)
				(type default)
			)
			(layer "B.Fab")
		)
		(fp_line
			(start -0.8636 -0.4064)
			(end -1.1938 -0.4064)
			(stroke
				(width 0.1)
				(type default)
			)
			(layer "B.Fab")
		)
		(fp_line
			(start 0.8636 -0.4064)
			(end 0.8636 -0.4572)
			(stroke
				(width 0.1)
				(type default)
			)
			(layer "B.Fab")
		)
		(fp_line
			(start 1.1938 -0.4064)
			(end 0.8636 -0.4064)
			(stroke
				(width 0.1)
				(type default)
			)
			(layer "B.Fab")
		)
		(fp_line
			(start -0.8636 -0.4572)
			(end -0.8636 -0.4064)
			(stroke
				(width 0.1)
				(type default)
			)
			(layer "B.Fab")
		)
		(fp_line
			(start 0.8636 -0.4572)
			(end -0.8636 -0.4572)
			(stroke
				(width 0.1)
				(type default)
			)
			(layer "B.Fab")
		)
		(pad "1" smd rect
			(at 0.7366 0 180)
			(size 0.7112 0.8128)
			(layers "B.Cu" "B.Mask" "B.Paste")
			(net "P0V8_SERDES_VDDA_PEX1_C9")
		)
		(pad "2" smd rect
			(at -0.7366 0 180)
			(size 0.7112 0.8128)
			(layers "B.Cu" "B.Mask" "B.Paste")
			(net "GND")
		)
	)
	(footprint ""
		(layer "B.Cu")
		(at 217.235786 -219.318586)
		(property "Reference" "R1495"
			(at 0 0 0)
			(layer "B.SilkS")
			(hide yes)
			(effects
				(font
					(size 1.27 1.27)
				)
				(justify mirror)
			)
		)
		(property "Value" ""
			(at 0 0 0)
			(layer "B.Fab")
			(effects
				(font
					(size 1.27 1.27)
				)
				(justify mirror)
			)
		)
		(duplicate_pad_numbers_are_jumpers no)
		(fp_line
			(start -0.7874 -0.4064)
			(end -0.7874 0.4064)
			(stroke
				(width 0.1524)
				(type default)
			)
			(layer "B.SilkS")
		)
		(fp_line
			(start -0.7874 0.4064)
			(end 0.7874 0.4064)
			(stroke
				(width 0.1524)
				(type default)
			)
			(layer "B.SilkS")
		)
		(fp_line
			(start 0.7874 -0.4064)
			(end -0.7874 -0.4064)
			(stroke
				(width 0.1524)
				(type default)
			)
			(layer "B.SilkS")
		)
		(fp_line
			(start 0.7874 0.4064)
			(end 0.7874 -0.4064)
			(stroke
				(width 0.1524)
				(type default)
			)
			(layer "B.SilkS")
		)
		(fp_line
			(start -0.67945 -0.3048)
			(end -0.67945 0.3048)
			(stroke
				(width 0.1)
				(type default)
			)
			(layer "B.Fab")
		)
		(fp_line
			(start -0.67945 0.3048)
			(end -0.120396 0.3048)
			(stroke
				(width 0.1)
				(type default)
			)
			(layer "B.Fab")
		)
		(fp_line
			(start -0.12065 -0.3048)
			(end -0.67945 -0.3048)
			(stroke
				(width 0.1)
				(type default)
			)
			(layer "B.Fab")
		)
		(fp_line
			(start -0.12065 -0.2794)
			(end -0.12065 -0.3048)
			(stroke
				(width 0.1)
				(type default)
			)
			(layer "B.Fab")
		)
		(fp_line
			(start -0.120396 0.2794)
			(end 0.12065 0.2794)
			(stroke
				(width 0.1)
				(type default)
			)
			(layer "B.Fab")
		)
		(fp_line
			(start -0.120396 0.3048)
			(end -0.120396 0.2794)
			(stroke
				(width 0.1)
				(type default)
			)
			(layer "B.Fab")
		)
		(fp_line
			(start 0.12065 -0.305054)
			(end 0.12065 -0.2794)
			(stroke
				(width 0.1)
				(type default)
			)
			(layer "B.Fab")
		)
		(fp_line
			(start 0.12065 -0.2794)
			(end -0.12065 -0.2794)
			(stroke
				(width 0.1)
				(type default)
			)
			(layer "B.Fab")
		)
		(fp_line
			(start 0.12065 0.2794)
			(end 0.12065 0.3048)
			(stroke
				(width 0.1)
				(type default)
			)
			(layer "B.Fab")
		)
		(fp_line
			(start 0.12065 0.3048)
			(end 0.67945 0.3048)
			(stroke
				(width 0.1)
				(type default)
			)
			(layer "B.Fab")
		)
		(fp_line
			(start 0.67945 -0.305054)
			(end 0.12065 -0.305054)
			(stroke
				(width 0.1)
				(type default)
			)
			(layer "B.Fab")
		)
		(fp_line
			(start 0.67945 0.3048)
			(end 0.67945 -0.305054)
			(stroke
				(width 0.1)
				(type default)
			)
			(layer "B.Fab")
		)
		(pad "1" smd circle
			(at 0.40005 0 180)
			(size 0 0)
			(layers "B.Cu" "B.Mask" "B.Paste")
			(net "SMB_PEX_SCL")
		)
		(pad "2" smd circle
			(at -0.40005 0 180)
			(size 0 0)
			(layers "B.Cu" "B.Mask" "B.Paste")
			(net "SMB_PEX_R_SCL")
		)
	)
	(footprint ""
		(layer "B.Cu")
		(at 3.079242 -271.930368)
		(property "Reference" "C4219"
			(at 0 0 0)
			(layer "B.SilkS")
			(hide yes)
			(effects
				(font
					(size 1.27 1.27)
				)
				(justify mirror)
			)
		)
		(property "Value" ""
			(at 0 0 0)
			(layer "B.Fab")
			(effects
				(font
					(size 1.27 1.27)
				)
				(justify mirror)
			)
		)
		(duplicate_pad_numbers_are_jumpers no)
		(fp_line
			(start -1.2954 -0.5842)
			(end -1.2954 0.5842)
			(stroke
				(width 0.1524)
				(type default)
			)
			(layer "B.SilkS")
		)
		(fp_line
			(start -1.2954 0.5842)
			(end 1.2954 0.5842)
			(stroke
				(width 0.1524)
				(type default)
			)
			(layer "B.SilkS")
		)
		(fp_line
			(start 1.2954 -0.5842)
			(end -1.2954 -0.5842)
			(stroke
				(width 0.1524)
				(type default)
			)
			(layer "B.SilkS")
		)
		(fp_line
			(start 1.2954 0.5842)
			(end 1.2954 -0.5842)
			(stroke
				(width 0.1524)
				(type default)
			)
			(layer "B.SilkS")
		)
		(fp_line
			(start -1.1938 -0.4064)
			(end -1.1938 0.4064)
			(stroke
				(width 0.1)
				(type default)
			)
			(layer "B.Fab")
		)
		(fp_line
			(start -1.1938 0.4064)
			(end -0.8636 0.4064)
			(stroke
				(width 0.1)
				(type default)
			)
			(layer "B.Fab")
		)
		(fp_line
			(start -0.8636 -0.4572)
			(end -0.8636 -0.4064)
			(stroke
				(width 0.1)
				(type default)
			)
			(layer "B.Fab")
		)
		(fp_line
			(start -0.8636 -0.4064)
			(end -1.1938 -0.4064)
			(stroke
				(width 0.1)
				(type default)
			)
			(layer "B.Fab")
		)
		(fp_line
			(start -0.8636 0.4064)
			(end -0.8636 0.4572)
			(stroke
				(width 0.1)
				(type default)
			)
			(layer "B.Fab")
		)
		(fp_line
			(start -0.8636 0.4572)
			(end 0.8636 0.4572)
			(stroke
				(width 0.1)
				(type default)
			)
			(layer "B.Fab")
		)
		(fp_line
			(start 0.8636 -0.4572)
			(end -0.8636 -0.4572)
			(stroke
				(width 0.1)
				(type default)
			)
			(layer "B.Fab")
		)
		(fp_line
			(start 0.8636 -0.4064)
			(end 0.8636 -0.4572)
			(stroke
				(width 0.1)
				(type default)
			)
			(layer "B.Fab")
		)
		(fp_line
			(start 0.8636 0.4064)
			(end 1.1938 0.4064)
			(stroke
				(width 0.1)
				(type default)
			)
			(layer "B.Fab")
		)
		(fp_line
			(start 0.8636 0.4572)
			(end 0.8636 0.4064)
			(stroke
				(width 0.1)
				(type default)
			)
			(layer "B.Fab")
		)
		(fp_line
			(start 1.1938 -0.4064)
			(end 0.8636 -0.4064)
			(stroke
				(width 0.1)
				(type default)
			)
			(layer "B.Fab")
		)
		(fp_line
			(start 1.1938 0.4064)
			(end 1.1938 -0.4064)
			(stroke
				(width 0.1)
				(type default)
			)
			(layer "B.Fab")
		)
		(pad "1" smd rect
			(at 0.7366 0 270)
			(size 0.7112 0.8128)
			(layers "B.Cu" "B.Mask" "B.Paste")
			(net "P1V25_PEX0")
		)
		(pad "2" smd rect
			(at -0.7366 0 270)
			(size 0.7112 0.8128)
			(layers "B.Cu" "B.Mask" "B.Paste")
			(net "GND")
		)
	)
	(footprint ""
		(layer "B.Cu")
		(at 388.419086 -294.8051 180)
		(property "Reference" "R3492"
			(at 0 0 0)
			(layer "B.SilkS")
			(hide yes)
			(effects
				(font
					(size 1.27 1.27)
				)
				(justify mirror)
			)
		)
		(property "Value" ""
			(at 0 0 0)
			(layer "B.Fab")
			(effects
				(font
					(size 1.27 1.27)
				)
				(justify mirror)
			)
		)
		(duplicate_pad_numbers_are_jumpers no)
		(fp_line
			(start 0.7874 0.4064)
			(end 0.7874 -0.4064)
			(stroke
				(width 0.1524)
				(type default)
			)
			(layer "B.SilkS")
		)
		(fp_line
			(start 0.7874 -0.4064)
			(end -0.7874 -0.4064)
			(stroke
				(width 0.1524)
				(type default)
			)
			(layer "B.SilkS")
		)
		(fp_line
			(start -0.7874 0.4064)
			(end 0.7874 0.4064)
			(stroke
				(width 0.1524)
				(type default)
			)
			(layer "B.SilkS")
		)
		(fp_line
			(start -0.7874 -0.4064)
			(end -0.7874 0.4064)
			(stroke
				(width 0.1524)
				(type default)
			)
			(layer "B.SilkS")
		)
		(fp_line
			(start 0.67945 0.3048)
			(end 0.67945 -0.305054)
			(stroke
				(width 0.1)
				(type default)
			)
			(layer "B.Fab")
		)
		(fp_line
			(start 0.67945 -0.305054)
			(end 0.12065 -0.305054)
			(stroke
				(width 0.1)
				(type default)
			)
			(layer "B.Fab")
		)
		(fp_line
			(start 0.12065 0.3048)
			(end 0.67945 0.3048)
			(stroke
				(width 0.1)
				(type default)
			)
			(layer "B.Fab")
		)
		(fp_line
			(start 0.12065 0.2794)
			(end 0.12065 0.3048)
			(stroke
				(width 0.1)
				(type default)
			)
			(layer "B.Fab")
		)
		(fp_line
			(start 0.12065 -0.2794)
			(end -0.12065 -0.2794)
			(stroke
				(width 0.1)
				(type default)
			)
			(layer "B.Fab")
		)
		(fp_line
			(start 0.12065 -0.305054)
			(end 0.12065 -0.2794)
			(stroke
				(width 0.1)
				(type default)
			)
			(layer "B.Fab")
		)
		(fp_line
			(start -0.120396 0.3048)
			(end -0.120396 0.2794)
			(stroke
				(width 0.1)
				(type default)
			)
			(layer "B.Fab")
		)
		(fp_line
			(start -0.120396 0.2794)
			(end 0.12065 0.2794)
			(stroke
				(width 0.1)
				(type default)
			)
			(layer "B.Fab")
		)
		(fp_line
			(start -0.12065 -0.2794)
			(end -0.12065 -0.3048)
			(stroke
				(width 0.1)
				(type default)
			)
			(layer "B.Fab")
		)
		(fp_line
			(start -0.12065 -0.3048)
			(end -0.67945 -0.3048)
			(stroke
				(width 0.1)
				(type default)
			)
			(layer "B.Fab")
		)
		(fp_line
			(start -0.67945 0.3048)
			(end -0.120396 0.3048)
			(stroke
				(width 0.1)
				(type default)
			)
			(layer "B.Fab")
		)
		(fp_line
			(start -0.67945 -0.3048)
			(end -0.67945 0.3048)
			(stroke
				(width 0.1)
				(type default)
			)
			(layer "B.Fab")
		)
		(pad "1" smd circle
			(at 0.40005 0)
			(size 0 0)
			(layers "B.Cu" "B.Mask" "B.Paste")
			(net "SPI_PEX3_SDIO2_R")
		)
		(pad "2" smd circle
			(at -0.40005 0)
			(size 0 0)
			(layers "B.Cu" "B.Mask" "B.Paste")
			(net "SPI_PEX3_SDIO2")
		)
	)
	(footprint ""
		(layer "B.Cu")
		(at 63.383414 -108.462318 180)
		(property "Reference" "R81"
			(at 0 0 0)
			(layer "B.SilkS")
			(hide yes)
			(effects
				(font
					(size 1.27 1.27)
				)
				(justify mirror)
			)
		)
		(property "Value" ""
			(at 0 0 0)
			(layer "B.Fab")
			(effects
				(font
					(size 1.27 1.27)
				)
				(justify mirror)
			)
		)
		(duplicate_pad_numbers_are_jumpers no)
		(fp_line
			(start 0.7874 0.4064)
			(end 0.7874 -0.4064)
			(stroke
				(width 0.1524)
				(type default)
			)
			(layer "B.SilkS")
		)
		(fp_line
			(start 0.7874 -0.4064)
			(end -0.7874 -0.4064)
			(stroke
				(width 0.1524)
				(type default)
			)
			(layer "B.SilkS")
		)
		(fp_line
			(start -0.7874 0.4064)
			(end 0.7874 0.4064)
			(stroke
				(width 0.1524)
				(type default)
			)
			(layer "B.SilkS")
		)
		(fp_line
			(start -0.7874 -0.4064)
			(end -0.7874 0.4064)
			(stroke
				(width 0.1524)
				(type default)
			)
			(layer "B.SilkS")
		)
		(fp_line
			(start 0.67945 0.3048)
			(end 0.67945 -0.305054)
			(stroke
				(width 0.1)
				(type default)
			)
			(layer "B.Fab")
		)
		(fp_line
			(start 0.67945 -0.305054)
			(end 0.12065 -0.305054)
			(stroke
				(width 0.1)
				(type default)
			)
			(layer "B.Fab")
		)
		(fp_line
			(start 0.12065 0.3048)
			(end 0.67945 0.3048)
			(stroke
				(width 0.1)
				(type default)
			)
			(layer "B.Fab")
		)
		(fp_line
			(start 0.12065 0.2794)
			(end 0.12065 0.3048)
			(stroke
				(width 0.1)
				(type default)
			)
			(layer "B.Fab")
		)
		(fp_line
			(start 0.12065 -0.2794)
			(end -0.12065 -0.2794)
			(stroke
				(width 0.1)
				(type default)
			)
			(layer "B.Fab")
		)
		(fp_line
			(start 0.12065 -0.305054)
			(end 0.12065 -0.2794)
			(stroke
				(width 0.1)
				(type default)
			)
			(layer "B.Fab")
		)
		(fp_line
			(start -0.120396 0.3048)
			(end -0.120396 0.2794)
			(stroke
				(width 0.1)
				(type default)
			)
			(layer "B.Fab")
		)
		(fp_line
			(start -0.120396 0.2794)
			(end 0.12065 0.2794)
			(stroke
				(width 0.1)
				(type default)
			)
			(layer "B.Fab")
		)
		(fp_line
			(start -0.12065 -0.2794)
			(end -0.12065 -0.3048)
			(stroke
				(width 0.1)
				(type default)
			)
			(layer "B.Fab")
		)
		(fp_line
			(start -0.12065 -0.3048)
			(end -0.67945 -0.3048)
			(stroke
				(width 0.1)
				(type default)
			)
			(layer "B.Fab")
		)
		(fp_line
			(start -0.67945 0.3048)
			(end -0.120396 0.3048)
			(stroke
				(width 0.1)
				(type default)
			)
			(layer "B.Fab")
		)
		(fp_line
			(start -0.67945 -0.3048)
			(end -0.67945 0.3048)
			(stroke
				(width 0.1)
				(type default)
			)
			(layer "B.Fab")
		)
		(pad "1" smd circle
			(at 0.40005 0)
			(size 0 0)
			(layers "B.Cu" "B.Mask" "B.Paste")
			(net "NIC1_BIF0_N")
		)
		(pad "2" smd circle
			(at -0.40005 0)
			(size 0 0)
			(layers "B.Cu" "B.Mask" "B.Paste")
			(net "GND")
		)
	)
	(footprint ""
		(layer "B.Cu")
		(at 405.100028 -290.199826 90)
		(property "Reference" "C1970"
			(at 0 0 90)
			(layer "B.SilkS")
			(hide yes)
			(effects
				(font
					(size 1.27 1.27)
				)
				(justify mirror)
			)
		)
		(property "Value" ""
			(at 0 0 90)
			(layer "B.Fab")
			(effects
				(font
					(size 1.27 1.27)
				)
				(justify mirror)
			)
		)
		(duplicate_pad_numbers_are_jumpers no)
		(fp_line
			(start 0.299974 -0.150114)
			(end -0.299974 -0.150114)
			(stroke
				(width 0.1)
				(type default)
			)
			(layer "B.Fab")
		)
		(fp_line
			(start -0.299974 -0.150114)
			(end -0.299974 0.150114)
			(stroke
				(width 0.1)
				(type default)
			)
			(layer "B.Fab")
		)
		(fp_line
			(start 0.299974 0.150114)
			(end 0.299974 -0.150114)
			(stroke
				(width 0.1)
				(type default)
			)
			(layer "B.Fab")
		)
		(fp_line
			(start -0.299974 0.150114)
			(end 0.299974 0.150114)
			(stroke
				(width 0.1)
				(type default)
			)
			(layer "B.Fab")
		)
		(pad "1" smd rect
			(at 0.2667 0 270)
			(size 0.3048 0.381)
			(layers "B.Cu" "B.Mask" "B.Paste")
			(net "P0V8_SERDES_VDDA_PEX3")
		)
		(pad "2" smd rect
			(at -0.2667 0 270)
			(size 0.3048 0.381)
			(layers "B.Cu" "B.Mask" "B.Paste")
			(net "GND")
		)
	)
	(footprint ""
		(layer "B.Cu")
		(at 338.893912 -222.78721 -90)
		(property "Reference" "C2086"
			(at 0 0 90)
			(layer "B.SilkS")
			(hide yes)
			(effects
				(font
					(size 1.27 1.27)
				)
				(justify mirror)
			)
		)
		(property "Value" ""
			(at 0 0 90)
			(layer "B.Fab")
			(effects
				(font
					(size 1.27 1.27)
				)
				(justify mirror)
			)
		)
		(duplicate_pad_numbers_are_jumpers no)
		(fp_line
			(start -0.69215 0.2921)
			(end 0.69215 0.2921)
			(stroke
				(width 0.1524)
				(type default)
			)
			(layer "B.SilkS")
		)
		(fp_line
			(start 0.69215 0.2921)
			(end 0.69215 -0.2921)
			(stroke
				(width 0.1524)
				(type default)
			)
			(layer "B.SilkS")
		)
		(fp_line
			(start -0.69215 -0.2921)
			(end -0.69215 0.2921)
			(stroke
				(width 0.1524)
				(type default)
			)
			(layer "B.SilkS")
		)
		(fp_line
			(start 0.69215 -0.2921)
			(end -0.69215 -0.2921)
			(stroke
				(width 0.1524)
				(type default)
			)
			(layer "B.SilkS")
		)
		(fp_line
			(start -0.51435 0.2794)
			(end 0.51435 0.2794)
			(stroke
				(width 0.1)
				(type default)
			)
			(layer "B.Fab")
		)
		(fp_line
			(start 0.51435 0.2794)
			(end 0.51435 -0.2794)
			(stroke
				(width 0.1)
				(type default)
			)
			(layer "B.Fab")
		)
		(fp_line
			(start -0.51435 -0.2794)
			(end -0.51435 0.2794)
			(stroke
				(width 0.1)
				(type default)
			)
			(layer "B.Fab")
		)
		(fp_line
			(start 0.51435 -0.2794)
			(end -0.51435 -0.2794)
			(stroke
				(width 0.1)
				(type default)
			)
			(layer "B.Fab")
		)
		(pad "1" smd circle
			(at 0.40005 0 90)
			(size 0 0)
			(layers "B.Cu" "B.Mask" "B.Paste")
			(net "P3V3_FPGA_VCCIO5")
		)
		(pad "2" smd circle
			(at -0.40005 0 90)
			(size 0 0)
			(layers "B.Cu" "B.Mask" "B.Paste")
			(net "GND")
		)
		(zone
			(layer "B.Cu")
			(hatch none 0.5)
			(connect_pads
				(clearance 0)
			)
			(min_thickness 0.25)
			(keepout
				(tracks not_allowed)
				(vias allowed)
				(pads allowed)
				(copperpour not_allowed)
				(footprints allowed)
			)
			(placement
				(enabled no)
				(sheetname "")
			)
			(fill
				(thermal_gap 0.5)
				(thermal_bridge_width 0.5)
				(island_removal_mode 0)
			)
			(polygon
				(pts
					(xy 338.806282 -222.59671) (xy 338.748116 -222.68815) (xy 338.748116 -222.88754) (xy 338.806282 -222.97771)
					(xy 338.981542 -222.97771) (xy 339.039962 -222.88754) (xy 339.039962 -222.68815) (xy 338.981796 -222.59671)
				)
			)
		)
	)
	(footprint ""
		(layer "B.Cu")
		(at 47.77486 -295.3766 90)
		(property "Reference" "C3040"
			(at 0 0 90)
			(layer "B.SilkS")
			(hide yes)
			(effects
				(font
					(size 1.27 1.27)
				)
				(justify mirror)
			)
		)
		(property "Value" ""
			(at 0 0 90)
			(layer "B.Fab")
			(effects
				(font
					(size 1.27 1.27)
				)
				(justify mirror)
			)
		)
		(duplicate_pad_numbers_are_jumpers no)
		(fp_line
			(start 0.299974 -0.150114)
			(end -0.299974 -0.150114)
			(stroke
				(width 0.1)
				(type default)
			)
			(layer "B.Fab")
		)
		(fp_line
			(start -0.299974 -0.150114)
			(end -0.299974 0.150114)
			(stroke
				(width 0.1)
				(type default)
			)
			(layer "B.Fab")
		)
		(fp_line
			(start 0.299974 0.150114)
			(end 0.299974 -0.150114)
			(stroke
				(width 0.1)
				(type default)
			)
			(layer "B.Fab")
		)
		(fp_line
			(start -0.299974 0.150114)
			(end 0.299974 0.150114)
			(stroke
				(width 0.1)
				(type default)
			)
			(layer "B.Fab")
		)
		(pad "1" smd rect
			(at 0.2667 0 270)
			(size 0.3048 0.381)
			(layers "B.Cu" "B.Mask" "B.Paste")
			(net "PCEPLL3_VDDA18_PEX0")
		)
		(pad "2" smd rect
			(at -0.2667 0 270)
			(size 0.3048 0.381)
			(layers "B.Cu" "B.Mask" "B.Paste")
			(net "GND")
		)
	)
	(footprint ""
		(layer "B.Cu")
		(at 11.1379 -264.508234 180)
		(property "Reference" "L85"
			(at 0 0 0)
			(layer "B.SilkS")
			(hide yes)
			(effects
				(font
					(size 1.27 1.27)
				)
				(justify mirror)
			)
		)
		(property "Value" ""
			(at 0 0 0)
			(layer "B.Fab")
			(effects
				(font
					(size 1.27 1.27)
				)
				(justify mirror)
			)
		)
		(duplicate_pad_numbers_are_jumpers no)
		(fp_line
			(start 2.248154 4.9911)
			(end -2.248154 4.9911)
			(stroke
				(width 0.1524)
				(type default)
			)
			(layer "B.SilkS")
		)
		(fp_line
			(start 2.248154 2.156206)
			(end 2.248154 4.9911)
			(stroke
				(width 0.1524)
				(type default)
			)
			(layer "B.SilkS")
		)
		(fp_line
			(start 2.248154 -4.9911)
			(end 2.248154 -2.126488)
			(stroke
				(width 0.1524)
				(type default)
			)
			(layer "B.SilkS")
		)
		(fp_line
			(start -2.248154 4.9911)
			(end -2.248154 2.156206)
			(stroke
				(width 0.1524)
				(type default)
			)
			(layer "B.SilkS")
		)
		(fp_line
			(start -2.248154 -2.126488)
			(end -2.248154 -4.9911)
			(stroke
				(width 0.1524)
				(type default)
			)
			(layer "B.SilkS")
		)
		(fp_line
			(start -2.248154 -4.9911)
			(end 2.248154 -4.9911)
			(stroke
				(width 0.1524)
				(type default)
			)
			(layer "B.SilkS")
		)
		(fp_line
			(start 1.700022 0.899922)
			(end -1.700022 0.899922)
			(stroke
				(width 0.1)
				(type default)
			)
			(layer "B.Fab")
		)
		(fp_line
			(start 1.700022 -0.899922)
			(end 1.700022 0.899922)
			(stroke
				(width 0.1)
				(type default)
			)
			(layer "B.Fab")
		)
		(fp_line
			(start -1.700022 0.899922)
			(end -1.700022 -0.899922)
			(stroke
				(width 0.1)
				(type default)
			)
			(layer "B.Fab")
		)
		(fp_line
			(start -1.700022 -0.899922)
			(end 1.700022 -0.899922)
			(stroke
				(width 0.1)
				(type default)
			)
			(layer "B.Fab")
		)
		(pad "1" smd rect
			(at 1.575054 0)
			(size 1.1684 9.8044)
			(layers "B.Cu" "B.Mask" "B.Paste")
			(net "P1V25_PEX0")
		)
		(pad "2" smd rect
			(at -1.575054 0)
			(size 1.1684 9.8044)
			(layers "B.Cu" "B.Mask" "B.Paste")
			(net "P1V25_SERDES_VDDPLL_PEX0")
		)
	)
	(footprint ""
		(layer "B.Cu")
		(at 230.66756 -221.904052 90)
		(property "Reference" "C3622"
			(at 0 0 90)
			(layer "B.SilkS")
			(hide yes)
			(effects
				(font
					(size 1.27 1.27)
				)
				(justify mirror)
			)
		)
		(property "Value" ""
			(at 0 0 90)
			(layer "B.Fab")
			(effects
				(font
					(size 1.27 1.27)
				)
				(justify mirror)
			)
		)
		(duplicate_pad_numbers_are_jumpers no)
		(fp_line
			(start 0.69215 -0.2921)
			(end -0.69215 -0.2921)
			(stroke
				(width 0.1524)
				(type default)
			)
			(layer "B.SilkS")
		)
		(fp_line
			(start -0.69215 -0.2921)
			(end -0.69215 0.2921)
			(stroke
				(width 0.1524)
				(type default)
			)
			(layer "B.SilkS")
		)
		(fp_line
			(start 0.69215 0.2921)
			(end 0.69215 -0.2921)
			(stroke
				(width 0.1524)
				(type default)
			)
			(layer "B.SilkS")
		)
		(fp_line
			(start -0.69215 0.2921)
			(end 0.69215 0.2921)
			(stroke
				(width 0.1524)
				(type default)
			)
			(layer "B.SilkS")
		)
		(fp_line
			(start 0.51435 -0.2794)
			(end -0.51435 -0.2794)
			(stroke
				(width 0.1)
				(type default)
			)
			(layer "B.Fab")
		)
		(fp_line
			(start -0.51435 -0.2794)
			(end -0.51435 0.2794)
			(stroke
				(width 0.1)
				(type default)
			)
			(layer "B.Fab")
		)
		(fp_line
			(start 0.51435 0.2794)
			(end 0.51435 -0.2794)
			(stroke
				(width 0.1)
				(type default)
			)
			(layer "B.Fab")
		)
		(fp_line
			(start -0.51435 0.2794)
			(end 0.51435 0.2794)
			(stroke
				(width 0.1)
				(type default)
			)
			(layer "B.Fab")
		)
		(pad "1" smd circle
			(at 0.40005 0 270)
			(size 0 0)
			(layers "B.Cu" "B.Mask" "B.Paste")
			(net "P3V3_AUX")
		)
		(pad "2" smd circle
			(at -0.40005 0 270)
			(size 0 0)
			(layers "B.Cu" "B.Mask" "B.Paste")
			(net "GND")
		)
		(zone
			(layer "B.Cu")
			(hatch none 0.5)
			(connect_pads
				(clearance 0)
			)
			(min_thickness 0.25)
			(keepout
				(tracks not_allowed)
				(vias allowed)
				(pads allowed)
				(copperpour not_allowed)
				(footprints allowed)
			)
			(placement
				(enabled no)
				(sheetname "")
			)
			(fill
				(thermal_gap 0.5)
				(thermal_bridge_width 0.5)
				(island_removal_mode 0)
			)
			(polygon
				(pts
					(xy 230.75519 -222.094552) (xy 230.813356 -222.003112) (xy 230.813356 -221.803722) (xy 230.75519 -221.713552)
					(xy 230.57993 -221.713552) (xy 230.52151 -221.803722) (xy 230.52151 -222.003112) (xy 230.579676 -222.094552)
				)
			)
		)
	)
	(footprint ""
		(layer "B.Cu")
		(at 284.249876 -292.099746 90)
		(property "Reference" "C1697"
			(at 0 0 90)
			(layer "B.SilkS")
			(hide yes)
			(effects
				(font
					(size 1.27 1.27)
				)
				(justify mirror)
			)
		)
		(property "Value" ""
			(at 0 0 90)
			(layer "B.Fab")
			(effects
				(font
					(size 1.27 1.27)
				)
				(justify mirror)
			)
		)
		(duplicate_pad_numbers_are_jumpers no)
		(fp_line
			(start 0.299974 -0.150114)
			(end -0.299974 -0.150114)
			(stroke
				(width 0.1)
				(type default)
			)
			(layer "B.Fab")
		)
		(fp_line
			(start -0.299974 -0.150114)
			(end -0.299974 0.150114)
			(stroke
				(width 0.1)
				(type default)
			)
			(layer "B.Fab")
		)
		(fp_line
			(start 0.299974 0.150114)
			(end 0.299974 -0.150114)
			(stroke
				(width 0.1)
				(type default)
			)
			(layer "B.Fab")
		)
		(fp_line
			(start -0.299974 0.150114)
			(end 0.299974 0.150114)
			(stroke
				(width 0.1)
				(type default)
			)
			(layer "B.Fab")
		)
		(pad "1" smd rect
			(at 0.2667 0 270)
			(size 0.3048 0.381)
			(layers "B.Cu" "B.Mask" "B.Paste")
			(net "P0V8_SERDES_VDDA_PEX2")
		)
		(pad "2" smd rect
			(at -0.2667 0 270)
			(size 0.3048 0.381)
			(layers "B.Cu" "B.Mask" "B.Paste")
			(net "GND")
		)
	)
	(footprint ""
		(layer "B.Cu")
		(at 295.174924 -297.79976 -90)
		(property "Reference" "C1648"
			(at 0 0 90)
			(layer "B.SilkS")
			(hide yes)
			(effects
				(font
					(size 1.27 1.27)
				)
				(justify mirror)
			)
		)
		(property "Value" ""
			(at 0 0 90)
			(layer "B.Fab")
			(effects
				(font
					(size 1.27 1.27)
				)
				(justify mirror)
			)
		)
		(duplicate_pad_numbers_are_jumpers no)
		(fp_line
			(start -0.299974 0.150114)
			(end 0.299974 0.150114)
			(stroke
				(width 0.1)
				(type default)
			)
			(layer "B.Fab")
		)
		(fp_line
			(start 0.299974 0.150114)
			(end 0.299974 -0.150114)
			(stroke
				(width 0.1)
				(type default)
			)
			(layer "B.Fab")
		)
		(fp_line
			(start -0.299974 -0.150114)
			(end -0.299974 0.150114)
			(stroke
				(width 0.1)
				(type default)
			)
			(layer "B.Fab")
		)
		(fp_line
			(start 0.299974 -0.150114)
			(end -0.299974 -0.150114)
			(stroke
				(width 0.1)
				(type default)
			)
			(layer "B.Fab")
		)
		(pad "1" smd rect
			(at 0.2667 0 90)
			(size 0.3048 0.381)
			(layers "B.Cu" "B.Mask" "B.Paste")
			(net "P0V8_PEX2")
		)
		(pad "2" smd rect
			(at -0.2667 0 90)
			(size 0.3048 0.381)
			(layers "B.Cu" "B.Mask" "B.Paste")
			(net "GND")
		)
	)
	(footprint ""
		(layer "B.Cu")
		(at 346.093796 -217.187018 90)
		(property "Reference" "C2049"
			(at 0 0 90)
			(layer "B.SilkS")
			(hide yes)
			(effects
				(font
					(size 1.27 1.27)
				)
				(justify mirror)
			)
		)
		(property "Value" ""
			(at 0 0 90)
			(layer "B.Fab")
			(effects
				(font
					(size 1.27 1.27)
				)
				(justify mirror)
			)
		)
		(duplicate_pad_numbers_are_jumpers no)
		(fp_line
			(start 0.69215 -0.2921)
			(end -0.69215 -0.2921)
			(stroke
				(width 0.1524)
				(type default)
			)
			(layer "B.SilkS")
		)
		(fp_line
			(start -0.69215 -0.2921)
			(end -0.69215 0.2921)
			(stroke
				(width 0.1524)
				(type default)
			)
			(layer "B.SilkS")
		)
		(fp_line
			(start 0.69215 0.2921)
			(end 0.69215 -0.2921)
			(stroke
				(width 0.1524)
				(type default)
			)
			(layer "B.SilkS")
		)
		(fp_line
			(start -0.69215 0.2921)
			(end 0.69215 0.2921)
			(stroke
				(width 0.1524)
				(type default)
			)
			(layer "B.SilkS")
		)
		(fp_line
			(start 0.51435 -0.2794)
			(end -0.51435 -0.2794)
			(stroke
				(width 0.1)
				(type default)
			)
			(layer "B.Fab")
		)
		(fp_line
			(start -0.51435 -0.2794)
			(end -0.51435 0.2794)
			(stroke
				(width 0.1)
				(type default)
			)
			(layer "B.Fab")
		)
		(fp_line
			(start 0.51435 0.2794)
			(end 0.51435 -0.2794)
			(stroke
				(width 0.1)
				(type default)
			)
			(layer "B.Fab")
		)
		(fp_line
			(start -0.51435 0.2794)
			(end 0.51435 0.2794)
			(stroke
				(width 0.1)
				(type default)
			)
			(layer "B.Fab")
		)
		(pad "1" smd circle
			(at 0.40005 0 270)
			(size 0 0)
			(layers "B.Cu" "B.Mask" "B.Paste")
			(net "P3V3_FPGA_VCCIO1")
		)
		(pad "2" smd circle
			(at -0.40005 0 270)
			(size 0 0)
			(layers "B.Cu" "B.Mask" "B.Paste")
			(net "GND")
		)
		(zone
			(layer "B.Cu")
			(hatch none 0.5)
			(connect_pads
				(clearance 0)
			)
			(min_thickness 0.25)
			(keepout
				(tracks not_allowed)
				(vias allowed)
				(pads allowed)
				(copperpour not_allowed)
				(footprints allowed)
			)
			(placement
				(enabled no)
				(sheetname "")
			)
			(fill
				(thermal_gap 0.5)
				(thermal_bridge_width 0.5)
				(island_removal_mode 0)
			)
			(polygon
				(pts
					(xy 346.181426 -217.377518) (xy 346.239592 -217.286078) (xy 346.239592 -217.086688) (xy 346.181426 -216.996518)
					(xy 346.006166 -216.996518) (xy 345.947746 -217.086688) (xy 345.947746 -217.286078) (xy 346.005912 -217.377518)
				)
			)
		)
	)
	(footprint ""
		(layer "B.Cu")
		(at 452.08444 -288.320988)
		(property "Reference" "PC272"
			(at 0 0 0)
			(layer "B.SilkS")
			(hide yes)
			(effects
				(font
					(size 1.27 1.27)
				)
				(justify mirror)
			)
		)
		(property "Value" ""
			(at 0 0 0)
			(layer "B.Fab")
			(effects
				(font
					(size 1.27 1.27)
				)
				(justify mirror)
			)
		)
		(duplicate_pad_numbers_are_jumpers no)
		(fp_line
			(start -1.524 -0.762)
			(end -1.524 0.762)
			(stroke
				(width 0.1524)
				(type default)
			)
			(layer "B.SilkS")
		)
		(fp_line
			(start -1.524 0.762)
			(end 1.524 0.762)
			(stroke
				(width 0.1524)
				(type default)
			)
			(layer "B.SilkS")
		)
		(fp_line
			(start 1.524 -0.762)
			(end -1.524 -0.762)
			(stroke
				(width 0.1524)
				(type default)
			)
			(layer "B.SilkS")
		)
		(fp_line
			(start 1.524 0.762)
			(end 1.524 -0.762)
			(stroke
				(width 0.1524)
				(type default)
			)
			(layer "B.SilkS")
		)
		(fp_line
			(start -1.1049 -0.724916)
			(end 1.1049 -0.724916)
			(stroke
				(width 0.1)
				(type default)
			)
			(layer "B.Fab")
		)
		(fp_line
			(start -1.1049 0.724916)
			(end -1.1049 -0.724916)
			(stroke
				(width 0.1)
				(type default)
			)
			(layer "B.Fab")
		)
		(fp_line
			(start 1.1049 -0.724916)
			(end 1.1049 0.724916)
			(stroke
				(width 0.1)
				(type default)
			)
			(layer "B.Fab")
		)
		(fp_line
			(start 1.1049 0.724916)
			(end -1.1049 0.724916)
			(stroke
				(width 0.1)
				(type default)
			)
			(layer "B.Fab")
		)
		(pad "1" smd rect
			(at 0.889 0)
			(size 1.016 1.27)
			(layers "B.Cu" "B.Mask" "B.Paste")
			(net "P1V25_PEX3_R")
		)
		(pad "2" smd rect
			(at -0.889 0)
			(size 1.016 1.27)
			(layers "B.Cu" "B.Mask" "B.Paste")
			(net "GND")
		)
	)
	(footprint ""
		(layer "B.Cu")
		(at 379.233684 -83.1088)
		(property "Reference" "R6303"
			(at 0 0 0)
			(layer "B.SilkS")
			(hide yes)
			(effects
				(font
					(size 1.27 1.27)
				)
				(justify mirror)
			)
		)
		(property "Value" ""
			(at 0 0 0)
			(layer "B.Fab")
			(effects
				(font
					(size 1.27 1.27)
				)
				(justify mirror)
			)
		)
		(duplicate_pad_numbers_are_jumpers no)
		(fp_line
			(start -0.7874 -0.4064)
			(end -0.7874 0.4064)
			(stroke
				(width 0.1524)
				(type default)
			)
			(layer "B.SilkS")
		)
		(fp_line
			(start -0.7874 0.4064)
			(end 0.7874 0.4064)
			(stroke
				(width 0.1524)
				(type default)
			)
			(layer "B.SilkS")
		)
		(fp_line
			(start 0.7874 -0.4064)
			(end -0.7874 -0.4064)
			(stroke
				(width 0.1524)
				(type default)
			)
			(layer "B.SilkS")
		)
		(fp_line
			(start 0.7874 0.4064)
			(end 0.7874 -0.4064)
			(stroke
				(width 0.1524)
				(type default)
			)
			(layer "B.SilkS")
		)
		(fp_line
			(start -0.67945 -0.3048)
			(end -0.67945 0.3048)
			(stroke
				(width 0.1)
				(type default)
			)
			(layer "B.Fab")
		)
		(fp_line
			(start -0.67945 0.3048)
			(end -0.120396 0.3048)
			(stroke
				(width 0.1)
				(type default)
			)
			(layer "B.Fab")
		)
		(fp_line
			(start -0.12065 -0.3048)
			(end -0.67945 -0.3048)
			(stroke
				(width 0.1)
				(type default)
			)
			(layer "B.Fab")
		)
		(fp_line
			(start -0.12065 -0.2794)
			(end -0.12065 -0.3048)
			(stroke
				(width 0.1)
				(type default)
			)
			(layer "B.Fab")
		)
		(fp_line
			(start -0.120396 0.2794)
			(end 0.12065 0.2794)
			(stroke
				(width 0.1)
				(type default)
			)
			(layer "B.Fab")
		)
		(fp_line
			(start -0.120396 0.3048)
			(end -0.120396 0.2794)
			(stroke
				(width 0.1)
				(type default)
			)
			(layer "B.Fab")
		)
		(fp_line
			(start 0.12065 -0.305054)
			(end 0.12065 -0.2794)
			(stroke
				(width 0.1)
				(type default)
			)
			(layer "B.Fab")
		)
		(fp_line
			(start 0.12065 -0.2794)
			(end -0.12065 -0.2794)
			(stroke
				(width 0.1)
				(type default)
			)
			(layer "B.Fab")
		)
		(fp_line
			(start 0.12065 0.2794)
			(end 0.12065 0.3048)
			(stroke
				(width 0.1)
				(type default)
			)
			(layer "B.Fab")
		)
		(fp_line
			(start 0.12065 0.3048)
			(end 0.67945 0.3048)
			(stroke
				(width 0.1)
				(type default)
			)
			(layer "B.Fab")
		)
		(fp_line
			(start 0.67945 -0.305054)
			(end 0.12065 -0.305054)
			(stroke
				(width 0.1)
				(type default)
			)
			(layer "B.Fab")
		)
		(fp_line
			(start 0.67945 0.3048)
			(end 0.67945 -0.305054)
			(stroke
				(width 0.1)
				(type default)
			)
			(layer "B.Fab")
		)
		(pad "1" smd circle
			(at 0.40005 0 180)
			(size 0 0)
			(layers "B.Cu" "B.Mask" "B.Paste")
			(net "SMB_BIC_I2C6_MUX_THERMAL_R1_SCL")
		)
		(pad "2" smd circle
			(at -0.40005 0 180)
			(size 0 0)
			(layers "B.Cu" "B.Mask" "B.Paste")
			(net "SMB_BIC_I2C6_MUX_THERMAL_R_SCL")
		)
	)
	(footprint ""
		(layer "B.Cu")
		(at 102.928674 -284.796738 -90)
		(property "Reference" "PC62"
			(at 0 0 90)
			(layer "B.SilkS")
			(hide yes)
			(effects
				(font
					(size 1.27 1.27)
				)
				(justify mirror)
			)
		)
		(property "Value" ""
			(at 0 0 90)
			(layer "B.Fab")
			(effects
				(font
					(size 1.27 1.27)
				)
				(justify mirror)
			)
		)
		(duplicate_pad_numbers_are_jumpers no)
		(fp_line
			(start -1.524 0.762)
			(end 1.524 0.762)
			(stroke
				(width 0.1524)
				(type default)
			)
			(layer "B.SilkS")
		)
		(fp_line
			(start 1.524 0.762)
			(end 1.524 -0.762)
			(stroke
				(width 0.1524)
				(type default)
			)
			(layer "B.SilkS")
		)
		(fp_line
			(start -1.524 -0.762)
			(end -1.524 0.762)
			(stroke
				(width 0.1524)
				(type default)
			)
			(layer "B.SilkS")
		)
		(fp_line
			(start 1.524 -0.762)
			(end -1.524 -0.762)
			(stroke
				(width 0.1524)
				(type default)
			)
			(layer "B.SilkS")
		)
		(fp_line
			(start -1.1049 0.724916)
			(end -1.1049 -0.724916)
			(stroke
				(width 0.1)
				(type default)
			)
			(layer "B.Fab")
		)
		(fp_line
			(start 1.1049 0.724916)
			(end -1.1049 0.724916)
			(stroke
				(width 0.1)
				(type default)
			)
			(layer "B.Fab")
		)
		(fp_line
			(start -1.1049 -0.724916)
			(end 1.1049 -0.724916)
			(stroke
				(width 0.1)
				(type default)
			)
			(layer "B.Fab")
		)
		(fp_line
			(start 1.1049 -0.724916)
			(end 1.1049 0.724916)
			(stroke
				(width 0.1)
				(type default)
			)
			(layer "B.Fab")
		)
		(pad "1" smd rect
			(at 0.889 0 270)
			(size 1.016 1.27)
			(layers "B.Cu" "B.Mask" "B.Paste")
			(net "SW_P12V_P0V8_PEX0_FLT")
		)
		(pad "2" smd rect
			(at -0.889 0 270)
			(size 1.016 1.27)
			(layers "B.Cu" "B.Mask" "B.Paste")
			(net "GND")
		)
	)
	(footprint ""
		(layer "B.Cu")
		(at 213.106 -201.549 90)
		(property "Reference" "R6309"
			(at 0 0 90)
			(layer "B.SilkS")
			(hide yes)
			(effects
				(font
					(size 1.27 1.27)
				)
				(justify mirror)
			)
		)
		(property "Value" ""
			(at 0 0 90)
			(layer "B.Fab")
			(effects
				(font
					(size 1.27 1.27)
				)
				(justify mirror)
			)
		)
		(duplicate_pad_numbers_are_jumpers no)
		(fp_line
			(start 0.7874 -0.4064)
			(end -0.7874 -0.4064)
			(stroke
				(width 0.1524)
				(type default)
			)
			(layer "B.SilkS")
		)
		(fp_line
			(start -0.7874 -0.4064)
			(end -0.7874 0.4064)
			(stroke
				(width 0.1524)
				(type default)
			)
			(layer "B.SilkS")
		)
		(fp_line
			(start 0.7874 0.4064)
			(end 0.7874 -0.4064)
			(stroke
				(width 0.1524)
				(type default)
			)
			(layer "B.SilkS")
		)
		(fp_line
			(start -0.7874 0.4064)
			(end 0.7874 0.4064)
			(stroke
				(width 0.1524)
				(type default)
			)
			(layer "B.SilkS")
		)
		(fp_line
			(start 0.67945 -0.305054)
			(end 0.12065 -0.305054)
			(stroke
				(width 0.1)
				(type default)
			)
			(layer "B.Fab")
		)
		(fp_line
			(start 0.12065 -0.305054)
			(end 0.12065 -0.2794)
			(stroke
				(width 0.1)
				(type default)
			)
			(layer "B.Fab")
		)
		(fp_line
			(start -0.12065 -0.3048)
			(end -0.67945 -0.3048)
			(stroke
				(width 0.1)
				(type default)
			)
			(layer "B.Fab")
		)
		(fp_line
			(start -0.67945 -0.3048)
			(end -0.67945 0.3048)
			(stroke
				(width 0.1)
				(type default)
			)
			(layer "B.Fab")
		)
		(fp_line
			(start 0.12065 -0.2794)
			(end -0.12065 -0.2794)
			(stroke
				(width 0.1)
				(type default)
			)
			(layer "B.Fab")
		)
		(fp_line
			(start -0.12065 -0.2794)
			(end -0.12065 -0.3048)
			(stroke
				(width 0.1)
				(type default)
			)
			(layer "B.Fab")
		)
		(fp_line
			(start 0.12065 0.2794)
			(end 0.12065 0.3048)
			(stroke
				(width 0.1)
				(type default)
			)
			(layer "B.Fab")
		)
		(fp_line
			(start -0.120396 0.2794)
			(end 0.12065 0.2794)
			(stroke
				(width 0.1)
				(type default)
			)
			(layer "B.Fab")
		)
		(fp_line
			(start 0.67945 0.3048)
			(end 0.67945 -0.305054)
			(stroke
				(width 0.1)
				(type default)
			)
			(layer "B.Fab")
		)
		(fp_line
			(start 0.12065 0.3048)
			(end 0.67945 0.3048)
			(stroke
				(width 0.1)
				(type default)
			)
			(layer "B.Fab")
		)
		(fp_line
			(start -0.120396 0.3048)
			(end -0.120396 0.2794)
			(stroke
				(width 0.1)
				(type default)
			)
			(layer "B.Fab")
		)
		(fp_line
			(start -0.67945 0.3048)
			(end -0.120396 0.3048)
			(stroke
				(width 0.1)
				(type default)
			)
			(layer "B.Fab")
		)
		(pad "1" smd circle
			(at 0.40005 0 270)
			(size 0 0)
			(layers "B.Cu" "B.Mask" "B.Paste")
			(net "SMB_NIC5_LS_SCL")
		)
		(pad "2" smd circle
			(at -0.40005 0 270)
			(size 0 0)
			(layers "B.Cu" "B.Mask" "B.Paste")
			(net "SMB_NIC5_LS_R_SCL")
		)
	)
	(footprint ""
		(layer "B.Cu")
		(at 289.94989 -301.599854 -90)
		(property "Reference" "C1737"
			(at 0 0 90)
			(layer "B.SilkS")
			(hide yes)
			(effects
				(font
					(size 1.27 1.27)
				)
				(justify mirror)
			)
		)
		(property "Value" ""
			(at 0 0 90)
			(layer "B.Fab")
			(effects
				(font
					(size 1.27 1.27)
				)
				(justify mirror)
			)
		)
		(duplicate_pad_numbers_are_jumpers no)
		(fp_line
			(start -0.299974 0.150114)
			(end 0.299974 0.150114)
			(stroke
				(width 0.1)
				(type default)
			)
			(layer "B.Fab")
		)
		(fp_line
			(start 0.299974 0.150114)
			(end 0.299974 -0.150114)
			(stroke
				(width 0.1)
				(type default)
			)
			(layer "B.Fab")
		)
		(fp_line
			(start -0.299974 -0.150114)
			(end -0.299974 0.150114)
			(stroke
				(width 0.1)
				(type default)
			)
			(layer "B.Fab")
		)
		(fp_line
			(start 0.299974 -0.150114)
			(end -0.299974 -0.150114)
			(stroke
				(width 0.1)
				(type default)
			)
			(layer "B.Fab")
		)
		(pad "1" smd rect
			(at 0.2667 0 90)
			(size 0.3048 0.381)
			(layers "B.Cu" "B.Mask" "B.Paste")
			(net "P0V8_SERDES_VDDA_PEX2")
		)
		(pad "2" smd rect
			(at -0.2667 0 90)
			(size 0.3048 0.381)
			(layers "B.Cu" "B.Mask" "B.Paste")
			(net "GND")
		)
	)
	(footprint ""
		(layer "B.Cu")
		(at 350.139 -233.553 90)
		(property "Reference" "R3597"
			(at 0 0 90)
			(layer "B.SilkS")
			(hide yes)
			(effects
				(font
					(size 1.27 1.27)
				)
				(justify mirror)
			)
		)
		(property "Value" ""
			(at 0 0 90)
			(layer "B.Fab")
			(effects
				(font
					(size 1.27 1.27)
				)
				(justify mirror)
			)
		)
		(duplicate_pad_numbers_are_jumpers no)
		(fp_line
			(start 0.7874 -0.4064)
			(end -0.7874 -0.4064)
			(stroke
				(width 0.1524)
				(type default)
			)
			(layer "B.SilkS")
		)
		(fp_line
			(start -0.7874 -0.4064)
			(end -0.7874 0.4064)
			(stroke
				(width 0.1524)
				(type default)
			)
			(layer "B.SilkS")
		)
		(fp_line
			(start 0.7874 0.4064)
			(end 0.7874 -0.4064)
			(stroke
				(width 0.1524)
				(type default)
			)
			(layer "B.SilkS")
		)
		(fp_line
			(start -0.7874 0.4064)
			(end 0.7874 0.4064)
			(stroke
				(width 0.1524)
				(type default)
			)
			(layer "B.SilkS")
		)
		(fp_line
			(start 0.67945 -0.305054)
			(end 0.12065 -0.305054)
			(stroke
				(width 0.1)
				(type default)
			)
			(layer "B.Fab")
		)
		(fp_line
			(start 0.12065 -0.305054)
			(end 0.12065 -0.2794)
			(stroke
				(width 0.1)
				(type default)
			)
			(layer "B.Fab")
		)
		(fp_line
			(start -0.12065 -0.3048)
			(end -0.67945 -0.3048)
			(stroke
				(width 0.1)
				(type default)
			)
			(layer "B.Fab")
		)
		(fp_line
			(start -0.67945 -0.3048)
			(end -0.67945 0.3048)
			(stroke
				(width 0.1)
				(type default)
			)
			(layer "B.Fab")
		)
		(fp_line
			(start 0.12065 -0.2794)
			(end -0.12065 -0.2794)
			(stroke
				(width 0.1)
				(type default)
			)
			(layer "B.Fab")
		)
		(fp_line
			(start -0.12065 -0.2794)
			(end -0.12065 -0.3048)
			(stroke
				(width 0.1)
				(type default)
			)
			(layer "B.Fab")
		)
		(fp_line
			(start 0.12065 0.2794)
			(end 0.12065 0.3048)
			(stroke
				(width 0.1)
				(type default)
			)
			(layer "B.Fab")
		)
		(fp_line
			(start -0.120396 0.2794)
			(end 0.12065 0.2794)
			(stroke
				(width 0.1)
				(type default)
			)
			(layer "B.Fab")
		)
		(fp_line
			(start 0.67945 0.3048)
			(end 0.67945 -0.305054)
			(stroke
				(width 0.1)
				(type default)
			)
			(layer "B.Fab")
		)
		(fp_line
			(start 0.12065 0.3048)
			(end 0.67945 0.3048)
			(stroke
				(width 0.1)
				(type default)
			)
			(layer "B.Fab")
		)
		(fp_line
			(start -0.120396 0.3048)
			(end -0.120396 0.2794)
			(stroke
				(width 0.1)
				(type default)
			)
			(layer "B.Fab")
		)
		(fp_line
			(start -0.67945 0.3048)
			(end -0.120396 0.3048)
			(stroke
				(width 0.1)
				(type default)
			)
			(layer "B.Fab")
		)
		(pad "1" smd circle
			(at 0.40005 0 270)
			(size 0 0)
			(layers "B.Cu" "B.Mask" "B.Paste")
			(net "SSD7_CLK_EN_R_N")
		)
		(pad "2" smd circle
			(at -0.40005 0 270)
			(size 0 0)
			(layers "B.Cu" "B.Mask" "B.Paste")
			(net "SSD7_CLK_EN_N")
		)
	)
	(footprint ""
		(layer "B.Cu")
		(at 207.110076 -222.65767 180)
		(property "Reference" "R6814"
			(at 0 0 0)
			(layer "B.SilkS")
			(hide yes)
			(effects
				(font
					(size 1.27 1.27)
				)
				(justify mirror)
			)
		)
		(property "Value" ""
			(at 0 0 0)
			(layer "B.Fab")
			(effects
				(font
					(size 1.27 1.27)
				)
				(justify mirror)
			)
		)
		(duplicate_pad_numbers_are_jumpers no)
		(fp_line
			(start 0.7874 0.4064)
			(end 0.7874 -0.4064)
			(stroke
				(width 0.1524)
				(type default)
			)
			(layer "B.SilkS")
		)
		(fp_line
			(start 0.7874 -0.4064)
			(end -0.7874 -0.4064)
			(stroke
				(width 0.1524)
				(type default)
			)
			(layer "B.SilkS")
		)
		(fp_line
			(start -0.7874 0.4064)
			(end 0.7874 0.4064)
			(stroke
				(width 0.1524)
				(type default)
			)
			(layer "B.SilkS")
		)
		(fp_line
			(start -0.7874 -0.4064)
			(end -0.7874 0.4064)
			(stroke
				(width 0.1524)
				(type default)
			)
			(layer "B.SilkS")
		)
		(fp_line
			(start 0.67945 0.3048)
			(end 0.67945 -0.305054)
			(stroke
				(width 0.1)
				(type default)
			)
			(layer "B.Fab")
		)
		(fp_line
			(start 0.67945 -0.305054)
			(end 0.12065 -0.305054)
			(stroke
				(width 0.1)
				(type default)
			)
			(layer "B.Fab")
		)
		(fp_line
			(start 0.12065 0.3048)
			(end 0.67945 0.3048)
			(stroke
				(width 0.1)
				(type default)
			)
			(layer "B.Fab")
		)
		(fp_line
			(start 0.12065 0.2794)
			(end 0.12065 0.3048)
			(stroke
				(width 0.1)
				(type default)
			)
			(layer "B.Fab")
		)
		(fp_line
			(start 0.12065 -0.2794)
			(end -0.12065 -0.2794)
			(stroke
				(width 0.1)
				(type default)
			)
			(layer "B.Fab")
		)
		(fp_line
			(start 0.12065 -0.305054)
			(end 0.12065 -0.2794)
			(stroke
				(width 0.1)
				(type default)
			)
			(layer "B.Fab")
		)
		(fp_line
			(start -0.120396 0.3048)
			(end -0.120396 0.2794)
			(stroke
				(width 0.1)
				(type default)
			)
			(layer "B.Fab")
		)
		(fp_line
			(start -0.120396 0.2794)
			(end 0.12065 0.2794)
			(stroke
				(width 0.1)
				(type default)
			)
			(layer "B.Fab")
		)
		(fp_line
			(start -0.12065 -0.2794)
			(end -0.12065 -0.3048)
			(stroke
				(width 0.1)
				(type default)
			)
			(layer "B.Fab")
		)
		(fp_line
			(start -0.12065 -0.3048)
			(end -0.67945 -0.3048)
			(stroke
				(width 0.1)
				(type default)
			)
			(layer "B.Fab")
		)
		(fp_line
			(start -0.67945 0.3048)
			(end -0.120396 0.3048)
			(stroke
				(width 0.1)
				(type default)
			)
			(layer "B.Fab")
		)
		(fp_line
			(start -0.67945 -0.3048)
			(end -0.67945 0.3048)
			(stroke
				(width 0.1)
				(type default)
			)
			(layer "B.Fab")
		)
		(pad "1" smd circle
			(at 0.40005 0)
			(size 0 0)
			(layers "B.Cu" "B.Mask" "B.Paste")
			(net "BOARD_TYPE_1_ADC_R")
		)
		(pad "2" smd circle
			(at -0.40005 0)
			(size 0 0)
			(layers "B.Cu" "B.Mask" "B.Paste")
			(net "P3V3_AUX")
		)
	)
	(footprint ""
		(layer "B.Cu")
		(at 355.81463 -303.649634 -90)
		(property "Reference" "PC199"
			(at 0 0 90)
			(layer "B.SilkS")
			(hide yes)
			(effects
				(font
					(size 1.27 1.27)
				)
				(justify mirror)
			)
		)
		(property "Value" ""
			(at 0 0 90)
			(layer "B.Fab")
			(effects
				(font
					(size 1.27 1.27)
				)
				(justify mirror)
			)
		)
		(duplicate_pad_numbers_are_jumpers no)
		(fp_line
			(start -1.524 0.762)
			(end 1.524 0.762)
			(stroke
				(width 0.1524)
				(type default)
			)
			(layer "B.SilkS")
		)
		(fp_line
			(start 1.524 0.762)
			(end 1.524 -0.762)
			(stroke
				(width 0.1524)
				(type default)
			)
			(layer "B.SilkS")
		)
		(fp_line
			(start -1.524 -0.762)
			(end -1.524 0.762)
			(stroke
				(width 0.1524)
				(type default)
			)
			(layer "B.SilkS")
		)
		(fp_line
			(start 1.524 -0.762)
			(end -1.524 -0.762)
			(stroke
				(width 0.1524)
				(type default)
			)
			(layer "B.SilkS")
		)
		(fp_line
			(start -1.1049 0.724916)
			(end -1.1049 -0.724916)
			(stroke
				(width 0.1)
				(type default)
			)
			(layer "B.Fab")
		)
		(fp_line
			(start 1.1049 0.724916)
			(end -1.1049 0.724916)
			(stroke
				(width 0.1)
				(type default)
			)
			(layer "B.Fab")
		)
		(fp_line
			(start -1.1049 -0.724916)
			(end 1.1049 -0.724916)
			(stroke
				(width 0.1)
				(type default)
			)
			(layer "B.Fab")
		)
		(fp_line
			(start 1.1049 -0.724916)
			(end 1.1049 0.724916)
			(stroke
				(width 0.1)
				(type default)
			)
			(layer "B.Fab")
		)
		(pad "1" smd rect
			(at 0.889 0 270)
			(size 1.016 1.27)
			(layers "B.Cu" "B.Mask" "B.Paste")
			(net "P0V8_PEX3")
		)
		(pad "2" smd rect
			(at -0.889 0 270)
			(size 1.016 1.27)
			(layers "B.Cu" "B.Mask" "B.Paste")
			(net "GND")
		)
	)
	(footprint ""
		(layer "B.Cu")
		(at 281.399742 -292.574726 180)
		(property "Reference" "C1615"
			(at 0 0 0)
			(layer "B.SilkS")
			(hide yes)
			(effects
				(font
					(size 1.27 1.27)
				)
				(justify mirror)
			)
		)
		(property "Value" ""
			(at 0 0 0)
			(layer "B.Fab")
			(effects
				(font
					(size 1.27 1.27)
				)
				(justify mirror)
			)
		)
		(duplicate_pad_numbers_are_jumpers no)
		(fp_line
			(start 0.299974 0.150114)
			(end 0.299974 -0.150114)
			(stroke
				(width 0.1)
				(type default)
			)
			(layer "B.Fab")
		)
		(fp_line
			(start 0.299974 -0.150114)
			(end -0.299974 -0.150114)
			(stroke
				(width 0.1)
				(type default)
			)
			(layer "B.Fab")
		)
		(fp_line
			(start -0.299974 0.150114)
			(end 0.299974 0.150114)
			(stroke
				(width 0.1)
				(type default)
			)
			(layer "B.Fab")
		)
		(fp_line
			(start -0.299974 -0.150114)
			(end -0.299974 0.150114)
			(stroke
				(width 0.1)
				(type default)
			)
			(layer "B.Fab")
		)
		(pad "1" smd rect
			(at 0.2667 0)
			(size 0.3048 0.381)
			(layers "B.Cu" "B.Mask" "B.Paste")
			(net "P0V8_PEX2")
		)
		(pad "2" smd rect
			(at -0.2667 0)
			(size 0.3048 0.381)
			(layers "B.Cu" "B.Mask" "B.Paste")
			(net "GND")
		)
	)
	(footprint ""
		(layer "B.Cu")
		(at 348.119954 -260.400546 -90)
		(property "Reference" "PR144"
			(at 0 0 90)
			(layer "B.SilkS")
			(hide yes)
			(effects
				(font
					(size 1.27 1.27)
				)
				(justify mirror)
			)
		)
		(property "Value" ""
			(at 0 0 90)
			(layer "B.Fab")
			(effects
				(font
					(size 1.27 1.27)
				)
				(justify mirror)
			)
		)
		(duplicate_pad_numbers_are_jumpers no)
		(fp_line
			(start -0.7874 0.4064)
			(end 0.7874 0.4064)
			(stroke
				(width 0.1524)
				(type default)
			)
			(layer "B.SilkS")
		)
		(fp_line
			(start 0.7874 0.4064)
			(end 0.7874 -0.4064)
			(stroke
				(width 0.1524)
				(type default)
			)
			(layer "B.SilkS")
		)
		(fp_line
			(start -0.7874 -0.4064)
			(end -0.7874 0.4064)
			(stroke
				(width 0.1524)
				(type default)
			)
			(layer "B.SilkS")
		)
		(fp_line
			(start 0.7874 -0.4064)
			(end -0.7874 -0.4064)
			(stroke
				(width 0.1524)
				(type default)
			)
			(layer "B.SilkS")
		)
		(fp_line
			(start -0.67945 0.3048)
			(end -0.120396 0.3048)
			(stroke
				(width 0.1)
				(type default)
			)
			(layer "B.Fab")
		)
		(fp_line
			(start -0.120396 0.3048)
			(end -0.120396 0.2794)
			(stroke
				(width 0.1)
				(type default)
			)
			(layer "B.Fab")
		)
		(fp_line
			(start 0.12065 0.3048)
			(end 0.67945 0.3048)
			(stroke
				(width 0.1)
				(type default)
			)
			(layer "B.Fab")
		)
		(fp_line
			(start 0.67945 0.3048)
			(end 0.67945 -0.305054)
			(stroke
				(width 0.1)
				(type default)
			)
			(layer "B.Fab")
		)
		(fp_line
			(start -0.120396 0.2794)
			(end 0.12065 0.2794)
			(stroke
				(width 0.1)
				(type default)
			)
			(layer "B.Fab")
		)
		(fp_line
			(start 0.12065 0.2794)
			(end 0.12065 0.3048)
			(stroke
				(width 0.1)
				(type default)
			)
			(layer "B.Fab")
		)
		(fp_line
			(start -0.12065 -0.2794)
			(end -0.12065 -0.3048)
			(stroke
				(width 0.1)
				(type default)
			)
			(layer "B.Fab")
		)
		(fp_line
			(start 0.12065 -0.2794)
			(end -0.12065 -0.2794)
			(stroke
				(width 0.1)
				(type default)
			)
			(layer "B.Fab")
		)
		(fp_line
			(start -0.67945 -0.3048)
			(end -0.67945 0.3048)
			(stroke
				(width 0.1)
				(type default)
			)
			(layer "B.Fab")
		)
		(fp_line
			(start -0.12065 -0.3048)
			(end -0.67945 -0.3048)
			(stroke
				(width 0.1)
				(type default)
			)
			(layer "B.Fab")
		)
		(fp_line
			(start 0.12065 -0.305054)
			(end 0.12065 -0.2794)
			(stroke
				(width 0.1)
				(type default)
			)
			(layer "B.Fab")
		)
		(fp_line
			(start 0.67945 -0.305054)
			(end 0.12065 -0.305054)
			(stroke
				(width 0.1)
				(type default)
			)
			(layer "B.Fab")
		)
		(pad "1" smd circle
			(at 0.40005 0 90)
			(size 0 0)
			(layers "B.Cu" "B.Mask" "B.Paste")
			(net "P0V8_PEX2_TSEN_R")
		)
		(pad "2" smd circle
			(at -0.40005 0 90)
			(size 0 0)
			(layers "B.Cu" "B.Mask" "B.Paste")
			(net "P0V8_PEX2_TSEN")
		)
	)
	(footprint ""
		(layer "B.Cu")
		(at 58.170064 -305.399948 -90)
		(property "Reference" "C2967"
			(at 0 0 90)
			(layer "B.SilkS")
			(hide yes)
			(effects
				(font
					(size 1.27 1.27)
				)
				(justify mirror)
			)
		)
		(property "Value" ""
			(at 0 0 90)
			(layer "B.Fab")
			(effects
				(font
					(size 1.27 1.27)
				)
				(justify mirror)
			)
		)
		(duplicate_pad_numbers_are_jumpers no)
		(fp_line
			(start -0.299974 0.150114)
			(end 0.299974 0.150114)
			(stroke
				(width 0.1)
				(type default)
			)
			(layer "B.Fab")
		)
		(fp_line
			(start 0.299974 0.150114)
			(end 0.299974 -0.150114)
			(stroke
				(width 0.1)
				(type default)
			)
			(layer "B.Fab")
		)
		(fp_line
			(start -0.299974 -0.150114)
			(end -0.299974 0.150114)
			(stroke
				(width 0.1)
				(type default)
			)
			(layer "B.Fab")
		)
		(fp_line
			(start 0.299974 -0.150114)
			(end -0.299974 -0.150114)
			(stroke
				(width 0.1)
				(type default)
			)
			(layer "B.Fab")
		)
		(pad "1" smd rect
			(at 0.2667 0 90)
			(size 0.3048 0.381)
			(layers "B.Cu" "B.Mask" "B.Paste")
			(net "P1V25_SERDES_VDDPLL_PEX0")
		)
		(pad "2" smd rect
			(at -0.2667 0 90)
			(size 0.3048 0.381)
			(layers "B.Cu" "B.Mask" "B.Paste")
			(net "GND")
		)
	)
	(footprint ""
		(layer "B.Cu")
		(at 11.1379 -264.586466 180)
		(property "Reference" "R6128"
			(at 0 0 0)
			(layer "B.SilkS")
			(hide yes)
			(effects
				(font
					(size 1.27 1.27)
				)
				(justify mirror)
			)
		)
		(property "Value" ""
			(at 0 0 0)
			(layer "B.Fab")
			(effects
				(font
					(size 1.27 1.27)
				)
				(justify mirror)
			)
		)
		(duplicate_pad_numbers_are_jumpers no)
		(fp_line
			(start 2.576322 1.1303)
			(end 2.576322 -1.1303)
			(stroke
				(width 0.1524)
				(type default)
			)
			(layer "B.SilkS")
		)
		(fp_line
			(start 2.576322 -1.1303)
			(end -2.576322 -1.1303)
			(stroke
				(width 0.1524)
				(type default)
			)
			(layer "B.SilkS")
		)
		(fp_line
			(start -2.576322 1.1303)
			(end 2.576322 1.1303)
			(stroke
				(width 0.1524)
				(type default)
			)
			(layer "B.SilkS")
		)
		(fp_line
			(start -2.576322 -1.1303)
			(end -2.576322 1.1303)
			(stroke
				(width 0.1524)
				(type default)
			)
			(layer "B.SilkS")
		)
		(fp_line
			(start 1.649984 0.899922)
			(end -1.649984 0.899922)
			(stroke
				(width 0.1)
				(type default)
			)
			(layer "B.Fab")
		)
		(fp_line
			(start 1.649984 -0.899922)
			(end 1.649984 0.899922)
			(stroke
				(width 0.1)
				(type default)
			)
			(layer "B.Fab")
		)
		(fp_line
			(start -1.649984 0.899922)
			(end -1.649984 -0.899922)
			(stroke
				(width 0.1)
				(type default)
			)
			(layer "B.Fab")
		)
		(fp_line
			(start -1.649984 -0.899922)
			(end 1.649984 -0.899922)
			(stroke
				(width 0.1)
				(type default)
			)
			(layer "B.Fab")
		)
		(pad "1A" smd rect
			(at 1.700022 0)
			(size 1.4986 2.0066)
			(layers "B.Cu" "B.Mask" "B.Paste")
			(net "P1V25_PEX0")
		)
		(pad "1B" smd rect
			(at 1.077722 0)
			(size 0.254 0.508)
			(layers "B.Cu" "B.Mask" "B.Paste")
			(net "P1V25_PEX0")
		)
		(pad "2A" smd rect
			(at -1.700022 0)
			(size 1.4986 2.0066)
			(layers "B.Cu" "B.Mask" "B.Paste")
			(net "P1V25_SERDES_VDDPLL_PEX0")
		)
		(pad "2B" smd rect
			(at -1.077722 0)
			(size 0.254 0.508)
			(layers "B.Cu" "B.Mask" "B.Paste")
			(net "P1V25_SERDES_VDDPLL_PEX0")
		)
	)
	(footprint ""
		(layer "B.Cu")
		(at 346.075 -233.553 90)
		(property "Reference" "R3578"
			(at 0 0 90)
			(layer "B.SilkS")
			(hide yes)
			(effects
				(font
					(size 1.27 1.27)
				)
				(justify mirror)
			)
		)
		(property "Value" ""
			(at 0 0 90)
			(layer "B.Fab")
			(effects
				(font
					(size 1.27 1.27)
				)
				(justify mirror)
			)
		)
		(duplicate_pad_numbers_are_jumpers no)
		(fp_line
			(start 0.7874 -0.4064)
			(end -0.7874 -0.4064)
			(stroke
				(width 0.1524)
				(type default)
			)
			(layer "B.SilkS")
		)
		(fp_line
			(start -0.7874 -0.4064)
			(end -0.7874 0.4064)
			(stroke
				(width 0.1524)
				(type default)
			)
			(layer "B.SilkS")
		)
		(fp_line
			(start 0.7874 0.4064)
			(end 0.7874 -0.4064)
			(stroke
				(width 0.1524)
				(type default)
			)
			(layer "B.SilkS")
		)
		(fp_line
			(start -0.7874 0.4064)
			(end 0.7874 0.4064)
			(stroke
				(width 0.1524)
				(type default)
			)
			(layer "B.SilkS")
		)
		(fp_line
			(start 0.67945 -0.305054)
			(end 0.12065 -0.305054)
			(stroke
				(width 0.1)
				(type default)
			)
			(layer "B.Fab")
		)
		(fp_line
			(start 0.12065 -0.305054)
			(end 0.12065 -0.2794)
			(stroke
				(width 0.1)
				(type default)
			)
			(layer "B.Fab")
		)
		(fp_line
			(start -0.12065 -0.3048)
			(end -0.67945 -0.3048)
			(stroke
				(width 0.1)
				(type default)
			)
			(layer "B.Fab")
		)
		(fp_line
			(start -0.67945 -0.3048)
			(end -0.67945 0.3048)
			(stroke
				(width 0.1)
				(type default)
			)
			(layer "B.Fab")
		)
		(fp_line
			(start 0.12065 -0.2794)
			(end -0.12065 -0.2794)
			(stroke
				(width 0.1)
				(type default)
			)
			(layer "B.Fab")
		)
		(fp_line
			(start -0.12065 -0.2794)
			(end -0.12065 -0.3048)
			(stroke
				(width 0.1)
				(type default)
			)
			(layer "B.Fab")
		)
		(fp_line
			(start 0.12065 0.2794)
			(end 0.12065 0.3048)
			(stroke
				(width 0.1)
				(type default)
			)
			(layer "B.Fab")
		)
		(fp_line
			(start -0.120396 0.2794)
			(end 0.12065 0.2794)
			(stroke
				(width 0.1)
				(type default)
			)
			(layer "B.Fab")
		)
		(fp_line
			(start 0.67945 0.3048)
			(end 0.67945 -0.305054)
			(stroke
				(width 0.1)
				(type default)
			)
			(layer "B.Fab")
		)
		(fp_line
			(start 0.12065 0.3048)
			(end 0.67945 0.3048)
			(stroke
				(width 0.1)
				(type default)
			)
			(layer "B.Fab")
		)
		(fp_line
			(start -0.120396 0.3048)
			(end -0.120396 0.2794)
			(stroke
				(width 0.1)
				(type default)
			)
			(layer "B.Fab")
		)
		(fp_line
			(start -0.67945 0.3048)
			(end -0.120396 0.3048)
			(stroke
				(width 0.1)
				(type default)
			)
			(layer "B.Fab")
		)
		(pad "1" smd circle
			(at 0.40005 0 270)
			(size 0 0)
			(layers "B.Cu" "B.Mask" "B.Paste")
			(net "SSD6_PWRDIS_R")
		)
		(pad "2" smd circle
			(at -0.40005 0 270)
			(size 0 0)
			(layers "B.Cu" "B.Mask" "B.Paste")
			(net "SSD6_PWRDIS")
		)
	)
	(footprint ""
		(layer "B.Cu")
		(at 222.322644 -231.225598 -90)
		(property "Reference" "R1477"
			(at 0 0 90)
			(layer "B.SilkS")
			(hide yes)
			(effects
				(font
					(size 1.27 1.27)
				)
				(justify mirror)
			)
		)
		(property "Value" ""
			(at 0 0 90)
			(layer "B.Fab")
			(effects
				(font
					(size 1.27 1.27)
				)
				(justify mirror)
			)
		)
		(duplicate_pad_numbers_are_jumpers no)
		(fp_line
			(start -0.7874 0.4064)
			(end 0.7874 0.4064)
			(stroke
				(width 0.1524)
				(type default)
			)
			(layer "B.SilkS")
		)
		(fp_line
			(start 0.7874 0.4064)
			(end 0.7874 -0.4064)
			(stroke
				(width 0.1524)
				(type default)
			)
			(layer "B.SilkS")
		)
		(fp_line
			(start -0.7874 -0.4064)
			(end -0.7874 0.4064)
			(stroke
				(width 0.1524)
				(type default)
			)
			(layer "B.SilkS")
		)
		(fp_line
			(start 0.7874 -0.4064)
			(end -0.7874 -0.4064)
			(stroke
				(width 0.1524)
				(type default)
			)
			(layer "B.SilkS")
		)
		(fp_line
			(start -0.67945 0.3048)
			(end -0.120396 0.3048)
			(stroke
				(width 0.1)
				(type default)
			)
			(layer "B.Fab")
		)
		(fp_line
			(start -0.120396 0.3048)
			(end -0.120396 0.2794)
			(stroke
				(width 0.1)
				(type default)
			)
			(layer "B.Fab")
		)
		(fp_line
			(start 0.12065 0.3048)
			(end 0.67945 0.3048)
			(stroke
				(width 0.1)
				(type default)
			)
			(layer "B.Fab")
		)
		(fp_line
			(start 0.67945 0.3048)
			(end 0.67945 -0.305054)
			(stroke
				(width 0.1)
				(type default)
			)
			(layer "B.Fab")
		)
		(fp_line
			(start -0.120396 0.2794)
			(end 0.12065 0.2794)
			(stroke
				(width 0.1)
				(type default)
			)
			(layer "B.Fab")
		)
		(fp_line
			(start 0.12065 0.2794)
			(end 0.12065 0.3048)
			(stroke
				(width 0.1)
				(type default)
			)
			(layer "B.Fab")
		)
		(fp_line
			(start -0.12065 -0.2794)
			(end -0.12065 -0.3048)
			(stroke
				(width 0.1)
				(type default)
			)
			(layer "B.Fab")
		)
		(fp_line
			(start 0.12065 -0.2794)
			(end -0.12065 -0.2794)
			(stroke
				(width 0.1)
				(type default)
			)
			(layer "B.Fab")
		)
		(fp_line
			(start -0.67945 -0.3048)
			(end -0.67945 0.3048)
			(stroke
				(width 0.1)
				(type default)
			)
			(layer "B.Fab")
		)
		(fp_line
			(start -0.12065 -0.3048)
			(end -0.67945 -0.3048)
			(stroke
				(width 0.1)
				(type default)
			)
			(layer "B.Fab")
		)
		(fp_line
			(start 0.12065 -0.305054)
			(end 0.12065 -0.2794)
			(stroke
				(width 0.1)
				(type default)
			)
			(layer "B.Fab")
		)
		(fp_line
			(start 0.67945 -0.305054)
			(end 0.12065 -0.305054)
			(stroke
				(width 0.1)
				(type default)
			)
			(layer "B.Fab")
		)
		(pad "1" smd circle
			(at 0.40005 0 90)
			(size 0 0)
			(layers "B.Cu" "B.Mask" "B.Paste")
			(net "SMB_NIC0_SCL")
		)
		(pad "2" smd circle
			(at -0.40005 0 90)
			(size 0 0)
			(layers "B.Cu" "B.Mask" "B.Paste")
			(net "SMB_NIC0_R_SCL")
		)
	)
	(footprint ""
		(layer "B.Cu")
		(at 361.437936 -281.024838 90)
		(property "Reference" "PC192"
			(at 0 0 90)
			(layer "B.SilkS")
			(hide yes)
			(effects
				(font
					(size 1.27 1.27)
				)
				(justify mirror)
			)
		)
		(property "Value" ""
			(at 0 0 90)
			(layer "B.Fab")
			(effects
				(font
					(size 1.27 1.27)
				)
				(justify mirror)
			)
		)
		(duplicate_pad_numbers_are_jumpers no)
		(fp_line
			(start 1.524 -0.762)
			(end -1.524 -0.762)
			(stroke
				(width 0.1524)
				(type default)
			)
			(layer "B.SilkS")
		)
		(fp_line
			(start -1.524 -0.762)
			(end -1.524 0.762)
			(stroke
				(width 0.1524)
				(type default)
			)
			(layer "B.SilkS")
		)
		(fp_line
			(start 1.524 0.762)
			(end 1.524 -0.762)
			(stroke
				(width 0.1524)
				(type default)
			)
			(layer "B.SilkS")
		)
		(fp_line
			(start -1.524 0.762)
			(end 1.524 0.762)
			(stroke
				(width 0.1524)
				(type default)
			)
			(layer "B.SilkS")
		)
		(fp_line
			(start 1.1049 -0.724916)
			(end 1.1049 0.724916)
			(stroke
				(width 0.1)
				(type default)
			)
			(layer "B.Fab")
		)
		(fp_line
			(start -1.1049 -0.724916)
			(end 1.1049 -0.724916)
			(stroke
				(width 0.1)
				(type default)
			)
			(layer "B.Fab")
		)
		(fp_line
			(start 1.1049 0.724916)
			(end -1.1049 0.724916)
			(stroke
				(width 0.1)
				(type default)
			)
			(layer "B.Fab")
		)
		(fp_line
			(start -1.1049 0.724916)
			(end -1.1049 -0.724916)
			(stroke
				(width 0.1)
				(type default)
			)
			(layer "B.Fab")
		)
		(pad "1" smd rect
			(at 0.889 0 90)
			(size 1.016 1.27)
			(layers "B.Cu" "B.Mask" "B.Paste")
			(net "SW_P12V_P0V8_PEX3_FLT")
		)
		(pad "2" smd rect
			(at -0.889 0 90)
			(size 1.016 1.27)
			(layers "B.Cu" "B.Mask" "B.Paste")
			(net "GND")
		)
	)
	(footprint ""
		(layer "B.Cu")
		(at 417.450016 -294.4749 180)
		(property "Reference" "C1927"
			(at 0 0 0)
			(layer "B.SilkS")
			(hide yes)
			(effects
				(font
					(size 1.27 1.27)
				)
				(justify mirror)
			)
		)
		(property "Value" ""
			(at 0 0 0)
			(layer "B.Fab")
			(effects
				(font
					(size 1.27 1.27)
				)
				(justify mirror)
			)
		)
		(duplicate_pad_numbers_are_jumpers no)
		(fp_line
			(start 0.299974 0.150114)
			(end 0.299974 -0.150114)
			(stroke
				(width 0.1)
				(type default)
			)
			(layer "B.Fab")
		)
		(fp_line
			(start 0.299974 -0.150114)
			(end -0.299974 -0.150114)
			(stroke
				(width 0.1)
				(type default)
			)
			(layer "B.Fab")
		)
		(fp_line
			(start -0.299974 0.150114)
			(end 0.299974 0.150114)
			(stroke
				(width 0.1)
				(type default)
			)
			(layer "B.Fab")
		)
		(fp_line
			(start -0.299974 -0.150114)
			(end -0.299974 0.150114)
			(stroke
				(width 0.1)
				(type default)
			)
			(layer "B.Fab")
		)
		(pad "1" smd rect
			(at 0.2667 0)
			(size 0.3048 0.381)
			(layers "B.Cu" "B.Mask" "B.Paste")
			(net "P0V8_SERDES_VDDA_PEX3")
		)
		(pad "2" smd rect
			(at -0.2667 0)
			(size 0.3048 0.381)
			(layers "B.Cu" "B.Mask" "B.Paste")
			(net "GND")
		)
	)
	(footprint ""
		(layer "B.Cu")
		(at 340.374224 -308.747668 90)
		(property "Reference" "C4320"
			(at 0 0 90)
			(layer "B.SilkS")
			(hide yes)
			(effects
				(font
					(size 1.27 1.27)
				)
				(justify mirror)
			)
		)
		(property "Value" ""
			(at 0 0 90)
			(layer "B.Fab")
			(effects
				(font
					(size 1.27 1.27)
				)
				(justify mirror)
			)
		)
		(duplicate_pad_numbers_are_jumpers no)
		(fp_line
			(start 0.299974 -0.150114)
			(end -0.299974 -0.150114)
			(stroke
				(width 0.1)
				(type default)
			)
			(layer "B.Fab")
		)
		(fp_line
			(start -0.299974 -0.150114)
			(end -0.299974 0.150114)
			(stroke
				(width 0.1)
				(type default)
			)
			(layer "B.Fab")
		)
		(fp_line
			(start 0.299974 0.150114)
			(end 0.299974 -0.150114)
			(stroke
				(width 0.1)
				(type default)
			)
			(layer "B.Fab")
		)
		(fp_line
			(start -0.299974 0.150114)
			(end 0.299974 0.150114)
			(stroke
				(width 0.1)
				(type default)
			)
			(layer "B.Fab")
		)
		(pad "1" smd rect
			(at 0.2667 0 270)
			(size 0.3048 0.381)
			(layers "B.Cu" "B.Mask" "B.Paste")
			(net "P0V8_PEX2")
		)
		(pad "2" smd rect
			(at -0.2667 0 270)
			(size 0.3048 0.381)
			(layers "B.Cu" "B.Mask" "B.Paste")
			(net "GND")
		)
	)
	(footprint ""
		(layer "B.Cu")
		(at 99.506278 -350.3803 90)
		(property "Reference" "C4181"
			(at 0 0 90)
			(layer "B.SilkS")
			(hide yes)
			(effects
				(font
					(size 1.27 1.27)
				)
				(justify mirror)
			)
		)
		(property "Value" ""
			(at 0 0 90)
			(layer "B.Fab")
			(effects
				(font
					(size 1.27 1.27)
				)
				(justify mirror)
			)
		)
		(duplicate_pad_numbers_are_jumpers no)
		(fp_line
			(start 0.7874 -0.4064)
			(end -0.7874 -0.4064)
			(stroke
				(width 0.1524)
				(type default)
			)
			(layer "B.SilkS")
		)
		(fp_line
			(start -0.7874 -0.4064)
			(end -0.7874 0.4064)
			(stroke
				(width 0.1524)
				(type default)
			)
			(layer "B.SilkS")
		)
		(fp_line
			(start 0.7874 0.4064)
			(end 0.7874 -0.4064)
			(stroke
				(width 0.1524)
				(type default)
			)
			(layer "B.SilkS")
		)
		(fp_line
			(start -0.7874 0.4064)
			(end 0.7874 0.4064)
			(stroke
				(width 0.1524)
				(type default)
			)
			(layer "B.SilkS")
		)
		(fp_line
			(start 0.67945 -0.305054)
			(end 0.12065 -0.305054)
			(stroke
				(width 0.1)
				(type default)
			)
			(layer "B.Fab")
		)
		(fp_line
			(start 0.12065 -0.305054)
			(end 0.12065 -0.2794)
			(stroke
				(width 0.1)
				(type default)
			)
			(layer "B.Fab")
		)
		(fp_line
			(start -0.12065 -0.3048)
			(end -0.67945 -0.3048)
			(stroke
				(width 0.1)
				(type default)
			)
			(layer "B.Fab")
		)
		(fp_line
			(start -0.67945 -0.3048)
			(end -0.67945 0.3048)
			(stroke
				(width 0.1)
				(type default)
			)
			(layer "B.Fab")
		)
		(fp_line
			(start 0.12065 -0.2794)
			(end -0.12065 -0.2794)
			(stroke
				(width 0.1)
				(type default)
			)
			(layer "B.Fab")
		)
		(fp_line
			(start -0.12065 -0.2794)
			(end -0.12065 -0.3048)
			(stroke
				(width 0.1)
				(type default)
			)
			(layer "B.Fab")
		)
		(fp_line
			(start 0.12065 0.2794)
			(end 0.12065 0.3048)
			(stroke
				(width 0.1)
				(type default)
			)
			(layer "B.Fab")
		)
		(fp_line
			(start -0.120396 0.2794)
			(end 0.12065 0.2794)
			(stroke
				(width 0.1)
				(type default)
			)
			(layer "B.Fab")
		)
		(fp_line
			(start 0.67945 0.3048)
			(end 0.67945 -0.305054)
			(stroke
				(width 0.1)
				(type default)
			)
			(layer "B.Fab")
		)
		(fp_line
			(start 0.12065 0.3048)
			(end 0.67945 0.3048)
			(stroke
				(width 0.1)
				(type default)
			)
			(layer "B.Fab")
		)
		(fp_line
			(start -0.120396 0.3048)
			(end -0.120396 0.2794)
			(stroke
				(width 0.1)
				(type default)
			)
			(layer "B.Fab")
		)
		(fp_line
			(start -0.67945 0.3048)
			(end -0.120396 0.3048)
			(stroke
				(width 0.1)
				(type default)
			)
			(layer "B.Fab")
		)
		(pad "1" smd circle
			(at 0.40005 0 270)
			(size 0 0)
			(layers "B.Cu" "B.Mask" "B.Paste")
			(net "P3V3_CLK_BUFFER_9ZXL0451E_S3_VZX3P3")
		)
		(pad "2" smd circle
			(at -0.40005 0 270)
			(size 0 0)
			(layers "B.Cu" "B.Mask" "B.Paste")
			(net "GND")
		)
	)
	(footprint ""
		(layer "B.Cu")
		(at 105.380536 -391.470134)
		(property "Reference" "C3628"
			(at 0 0 0)
			(layer "B.SilkS")
			(hide yes)
			(effects
				(font
					(size 1.27 1.27)
				)
				(justify mirror)
			)
		)
		(property "Value" ""
			(at 0 0 0)
			(layer "B.Fab")
			(effects
				(font
					(size 1.27 1.27)
				)
				(justify mirror)
			)
		)
		(duplicate_pad_numbers_are_jumpers no)
		(fp_line
			(start -0.7874 -0.4064)
			(end -0.7874 0.4064)
			(stroke
				(width 0.1524)
				(type default)
			)
			(layer "B.SilkS")
		)
		(fp_line
			(start -0.7874 0.4064)
			(end 0.7874 0.4064)
			(stroke
				(width 0.1524)
				(type default)
			)
			(layer "B.SilkS")
		)
		(fp_line
			(start 0.7874 -0.4064)
			(end -0.7874 -0.4064)
			(stroke
				(width 0.1524)
				(type default)
			)
			(layer "B.SilkS")
		)
		(fp_line
			(start 0.7874 0.4064)
			(end 0.7874 -0.4064)
			(stroke
				(width 0.1524)
				(type default)
			)
			(layer "B.SilkS")
		)
		(fp_line
			(start -0.67945 -0.3048)
			(end -0.67945 0.3048)
			(stroke
				(width 0.1)
				(type default)
			)
			(layer "B.Fab")
		)
		(fp_line
			(start -0.67945 0.3048)
			(end -0.120396 0.3048)
			(stroke
				(width 0.1)
				(type default)
			)
			(layer "B.Fab")
		)
		(fp_line
			(start -0.12065 -0.3048)
			(end -0.67945 -0.3048)
			(stroke
				(width 0.1)
				(type default)
			)
			(layer "B.Fab")
		)
		(fp_line
			(start -0.12065 -0.2794)
			(end -0.12065 -0.3048)
			(stroke
				(width 0.1)
				(type default)
			)
			(layer "B.Fab")
		)
		(fp_line
			(start -0.120396 0.2794)
			(end 0.12065 0.2794)
			(stroke
				(width 0.1)
				(type default)
			)
			(layer "B.Fab")
		)
		(fp_line
			(start -0.120396 0.3048)
			(end -0.120396 0.2794)
			(stroke
				(width 0.1)
				(type default)
			)
			(layer "B.Fab")
		)
		(fp_line
			(start 0.12065 -0.305054)
			(end 0.12065 -0.2794)
			(stroke
				(width 0.1)
				(type default)
			)
			(layer "B.Fab")
		)
		(fp_line
			(start 0.12065 -0.2794)
			(end -0.12065 -0.2794)
			(stroke
				(width 0.1)
				(type default)
			)
			(layer "B.Fab")
		)
		(fp_line
			(start 0.12065 0.2794)
			(end 0.12065 0.3048)
			(stroke
				(width 0.1)
				(type default)
			)
			(layer "B.Fab")
		)
		(fp_line
			(start 0.12065 0.3048)
			(end 0.67945 0.3048)
			(stroke
				(width 0.1)
				(type default)
			)
			(layer "B.Fab")
		)
		(fp_line
			(start 0.67945 -0.305054)
			(end 0.12065 -0.305054)
			(stroke
				(width 0.1)
				(type default)
			)
			(layer "B.Fab")
		)
		(fp_line
			(start 0.67945 0.3048)
			(end 0.67945 -0.305054)
			(stroke
				(width 0.1)
				(type default)
			)
			(layer "B.Fab")
		)
		(pad "1" smd circle
			(at 0.40005 0 180)
			(size 0 0)
			(layers "B.Cu" "B.Mask" "B.Paste")
			(net "P3V3_BIC_USB_HUB")
		)
		(pad "2" smd circle
			(at -0.40005 0 180)
			(size 0 0)
			(layers "B.Cu" "B.Mask" "B.Paste")
			(net "GND")
		)
	)
	(footprint ""
		(layer "B.Cu")
		(at 100.712016 -332.038452)
		(property "Reference" "C2700"
			(at 0 0 0)
			(layer "B.SilkS")
			(hide yes)
			(effects
				(font
					(size 1.27 1.27)
				)
				(justify mirror)
			)
		)
		(property "Value" ""
			(at 0 0 0)
			(layer "B.Fab")
			(effects
				(font
					(size 1.27 1.27)
				)
				(justify mirror)
			)
		)
		(duplicate_pad_numbers_are_jumpers no)
		(fp_line
			(start -0.7874 -0.4064)
			(end -0.7874 0.4064)
			(stroke
				(width 0.1524)
				(type default)
			)
			(layer "B.SilkS")
		)
		(fp_line
			(start -0.7874 0.4064)
			(end 0.7874 0.4064)
			(stroke
				(width 0.1524)
				(type default)
			)
			(layer "B.SilkS")
		)
		(fp_line
			(start 0.7874 -0.4064)
			(end -0.7874 -0.4064)
			(stroke
				(width 0.1524)
				(type default)
			)
			(layer "B.SilkS")
		)
		(fp_line
			(start 0.7874 0.4064)
			(end 0.7874 -0.4064)
			(stroke
				(width 0.1524)
				(type default)
			)
			(layer "B.SilkS")
		)
		(fp_line
			(start -0.67945 -0.3048)
			(end -0.67945 0.3048)
			(stroke
				(width 0.1)
				(type default)
			)
			(layer "B.Fab")
		)
		(fp_line
			(start -0.67945 0.3048)
			(end -0.120396 0.3048)
			(stroke
				(width 0.1)
				(type default)
			)
			(layer "B.Fab")
		)
		(fp_line
			(start -0.12065 -0.3048)
			(end -0.67945 -0.3048)
			(stroke
				(width 0.1)
				(type default)
			)
			(layer "B.Fab")
		)
		(fp_line
			(start -0.12065 -0.2794)
			(end -0.12065 -0.3048)
			(stroke
				(width 0.1)
				(type default)
			)
			(layer "B.Fab")
		)
		(fp_line
			(start -0.120396 0.2794)
			(end 0.12065 0.2794)
			(stroke
				(width 0.1)
				(type default)
			)
			(layer "B.Fab")
		)
		(fp_line
			(start -0.120396 0.3048)
			(end -0.120396 0.2794)
			(stroke
				(width 0.1)
				(type default)
			)
			(layer "B.Fab")
		)
		(fp_line
			(start 0.12065 -0.305054)
			(end 0.12065 -0.2794)
			(stroke
				(width 0.1)
				(type default)
			)
			(layer "B.Fab")
		)
		(fp_line
			(start 0.12065 -0.2794)
			(end -0.12065 -0.2794)
			(stroke
				(width 0.1)
				(type default)
			)
			(layer "B.Fab")
		)
		(fp_line
			(start 0.12065 0.2794)
			(end 0.12065 0.3048)
			(stroke
				(width 0.1)
				(type default)
			)
			(layer "B.Fab")
		)
		(fp_line
			(start 0.12065 0.3048)
			(end 0.67945 0.3048)
			(stroke
				(width 0.1)
				(type default)
			)
			(layer "B.Fab")
		)
		(fp_line
			(start 0.67945 -0.305054)
			(end 0.12065 -0.305054)
			(stroke
				(width 0.1)
				(type default)
			)
			(layer "B.Fab")
		)
		(fp_line
			(start 0.67945 0.3048)
			(end 0.67945 -0.305054)
			(stroke
				(width 0.1)
				(type default)
			)
			(layer "B.Fab")
		)
		(pad "1" smd circle
			(at 0.40005 0 180)
			(size 0 0)
			(layers "B.Cu" "B.Mask" "B.Paste")
			(net "P3V3_CLK_BUFFER_9ZXL0451E_VZX3P3")
		)
		(pad "2" smd circle
			(at -0.40005 0 180)
			(size 0 0)
			(layers "B.Cu" "B.Mask" "B.Paste")
			(net "GND")
		)
	)
	(footprint ""
		(layer "B.Cu")
		(at 8.875268 -277.036276 180)
		(property "Reference" "C4237"
			(at 0 0 0)
			(layer "B.SilkS")
			(hide yes)
			(effects
				(font
					(size 1.27 1.27)
				)
				(justify mirror)
			)
		)
		(property "Value" ""
			(at 0 0 0)
			(layer "B.Fab")
			(effects
				(font
					(size 1.27 1.27)
				)
				(justify mirror)
			)
		)
		(duplicate_pad_numbers_are_jumpers no)
		(fp_line
			(start 0.299974 0.150114)
			(end 0.299974 -0.150114)
			(stroke
				(width 0.1)
				(type default)
			)
			(layer "B.Fab")
		)
		(fp_line
			(start 0.299974 -0.150114)
			(end -0.299974 -0.150114)
			(stroke
				(width 0.1)
				(type default)
			)
			(layer "B.Fab")
		)
		(fp_line
			(start -0.299974 0.150114)
			(end 0.299974 0.150114)
			(stroke
				(width 0.1)
				(type default)
			)
			(layer "B.Fab")
		)
		(fp_line
			(start -0.299974 -0.150114)
			(end -0.299974 0.150114)
			(stroke
				(width 0.1)
				(type default)
			)
			(layer "B.Fab")
		)
		(pad "1" smd rect
			(at 0.2667 0)
			(size 0.3048 0.381)
			(layers "B.Cu" "B.Mask" "B.Paste")
			(net "P1V25_PEX0")
		)
		(pad "2" smd rect
			(at -0.2667 0)
			(size 0.3048 0.381)
			(layers "B.Cu" "B.Mask" "B.Paste")
			(net "GND")
		)
	)
	(footprint ""
		(layer "B.Cu")
		(at 180.50002 -292.099746 90)
		(property "Reference" "C1493"
			(at 0 0 90)
			(layer "B.SilkS")
			(hide yes)
			(effects
				(font
					(size 1.27 1.27)
				)
				(justify mirror)
			)
		)
		(property "Value" ""
			(at 0 0 90)
			(layer "B.Fab")
			(effects
				(font
					(size 1.27 1.27)
				)
				(justify mirror)
			)
		)
		(duplicate_pad_numbers_are_jumpers no)
		(fp_line
			(start 0.299974 -0.150114)
			(end -0.299974 -0.150114)
			(stroke
				(width 0.1)
				(type default)
			)
			(layer "B.Fab")
		)
		(fp_line
			(start -0.299974 -0.150114)
			(end -0.299974 0.150114)
			(stroke
				(width 0.1)
				(type default)
			)
			(layer "B.Fab")
		)
		(fp_line
			(start 0.299974 0.150114)
			(end 0.299974 -0.150114)
			(stroke
				(width 0.1)
				(type default)
			)
			(layer "B.Fab")
		)
		(fp_line
			(start -0.299974 0.150114)
			(end 0.299974 0.150114)
			(stroke
				(width 0.1)
				(type default)
			)
			(layer "B.Fab")
		)
		(pad "1" smd rect
			(at 0.2667 0 270)
			(size 0.3048 0.381)
			(layers "B.Cu" "B.Mask" "B.Paste")
			(net "P0V8_SERDES_VDDA_PEX1")
		)
		(pad "2" smd rect
			(at -0.2667 0 270)
			(size 0.3048 0.381)
			(layers "B.Cu" "B.Mask" "B.Paste")
			(net "GND")
		)
	)
	(footprint ""
		(layer "B.Cu")
		(at 110.82655 -321.36334 -90)
		(property "Reference" "R6452"
			(at 0 0 90)
			(layer "B.SilkS")
			(hide yes)
			(effects
				(font
					(size 1.27 1.27)
				)
				(justify mirror)
			)
		)
		(property "Value" ""
			(at 0 0 90)
			(layer "B.Fab")
			(effects
				(font
					(size 1.27 1.27)
				)
				(justify mirror)
			)
		)
		(duplicate_pad_numbers_are_jumpers no)
		(fp_line
			(start -0.7874 0.4064)
			(end 0.7874 0.4064)
			(stroke
				(width 0.1524)
				(type default)
			)
			(layer "B.SilkS")
		)
		(fp_line
			(start 0.7874 0.4064)
			(end 0.7874 -0.4064)
			(stroke
				(width 0.1524)
				(type default)
			)
			(layer "B.SilkS")
		)
		(fp_line
			(start -0.7874 -0.4064)
			(end -0.7874 0.4064)
			(stroke
				(width 0.1524)
				(type default)
			)
			(layer "B.SilkS")
		)
		(fp_line
			(start 0.7874 -0.4064)
			(end -0.7874 -0.4064)
			(stroke
				(width 0.1524)
				(type default)
			)
			(layer "B.SilkS")
		)
		(fp_line
			(start -0.67945 0.3048)
			(end -0.120396 0.3048)
			(stroke
				(width 0.1)
				(type default)
			)
			(layer "B.Fab")
		)
		(fp_line
			(start -0.120396 0.3048)
			(end -0.120396 0.2794)
			(stroke
				(width 0.1)
				(type default)
			)
			(layer "B.Fab")
		)
		(fp_line
			(start 0.12065 0.3048)
			(end 0.67945 0.3048)
			(stroke
				(width 0.1)
				(type default)
			)
			(layer "B.Fab")
		)
		(fp_line
			(start 0.67945 0.3048)
			(end 0.67945 -0.305054)
			(stroke
				(width 0.1)
				(type default)
			)
			(layer "B.Fab")
		)
		(fp_line
			(start -0.120396 0.2794)
			(end 0.12065 0.2794)
			(stroke
				(width 0.1)
				(type default)
			)
			(layer "B.Fab")
		)
		(fp_line
			(start 0.12065 0.2794)
			(end 0.12065 0.3048)
			(stroke
				(width 0.1)
				(type default)
			)
			(layer "B.Fab")
		)
		(fp_line
			(start -0.12065 -0.2794)
			(end -0.12065 -0.3048)
			(stroke
				(width 0.1)
				(type default)
			)
			(layer "B.Fab")
		)
		(fp_line
			(start 0.12065 -0.2794)
			(end -0.12065 -0.2794)
			(stroke
				(width 0.1)
				(type default)
			)
			(layer "B.Fab")
		)
		(fp_line
			(start -0.67945 -0.3048)
			(end -0.67945 0.3048)
			(stroke
				(width 0.1)
				(type default)
			)
			(layer "B.Fab")
		)
		(fp_line
			(start -0.12065 -0.3048)
			(end -0.67945 -0.3048)
			(stroke
				(width 0.1)
				(type default)
			)
			(layer "B.Fab")
		)
		(fp_line
			(start 0.12065 -0.305054)
			(end 0.12065 -0.2794)
			(stroke
				(width 0.1)
				(type default)
			)
			(layer "B.Fab")
		)
		(fp_line
			(start 0.67945 -0.305054)
			(end 0.12065 -0.305054)
			(stroke
				(width 0.1)
				(type default)
			)
			(layer "B.Fab")
		)
		(pad "1" smd circle
			(at 0.40005 0 90)
			(size 0 0)
			(layers "B.Cu" "B.Mask" "B.Paste")
			(net "P0V8_SERDES_VDDA_PEX0")
		)
		(pad "2" smd circle
			(at -0.40005 0 90)
			(size 0 0)
			(layers "B.Cu" "B.Mask" "B.Paste")
			(net "P0V8_SERDES_VDDA_PEX0_C3")
		)
	)
	(footprint ""
		(layer "B.Cu")
		(at 303.077626 -239.976406 90)
		(property "Reference" "R4102"
			(at 0 0 90)
			(layer "B.SilkS")
			(hide yes)
			(effects
				(font
					(size 1.27 1.27)
				)
				(justify mirror)
			)
		)
		(property "Value" ""
			(at 0 0 90)
			(layer "B.Fab")
			(effects
				(font
					(size 1.27 1.27)
				)
				(justify mirror)
			)
		)
		(duplicate_pad_numbers_are_jumpers no)
		(fp_line
			(start 0.7874 -0.4064)
			(end -0.7874 -0.4064)
			(stroke
				(width 0.1524)
				(type default)
			)
			(layer "B.SilkS")
		)
		(fp_line
			(start -0.7874 -0.4064)
			(end -0.7874 0.4064)
			(stroke
				(width 0.1524)
				(type default)
			)
			(layer "B.SilkS")
		)
		(fp_line
			(start 0.7874 0.4064)
			(end 0.7874 -0.4064)
			(stroke
				(width 0.1524)
				(type default)
			)
			(layer "B.SilkS")
		)
		(fp_line
			(start -0.7874 0.4064)
			(end 0.7874 0.4064)
			(stroke
				(width 0.1524)
				(type default)
			)
			(layer "B.SilkS")
		)
		(fp_line
			(start 0.67945 -0.305054)
			(end 0.12065 -0.305054)
			(stroke
				(width 0.1)
				(type default)
			)
			(layer "B.Fab")
		)
		(fp_line
			(start 0.12065 -0.305054)
			(end 0.12065 -0.2794)
			(stroke
				(width 0.1)
				(type default)
			)
			(layer "B.Fab")
		)
		(fp_line
			(start -0.12065 -0.3048)
			(end -0.67945 -0.3048)
			(stroke
				(width 0.1)
				(type default)
			)
			(layer "B.Fab")
		)
		(fp_line
			(start -0.67945 -0.3048)
			(end -0.67945 0.3048)
			(stroke
				(width 0.1)
				(type default)
			)
			(layer "B.Fab")
		)
		(fp_line
			(start 0.12065 -0.2794)
			(end -0.12065 -0.2794)
			(stroke
				(width 0.1)
				(type default)
			)
			(layer "B.Fab")
		)
		(fp_line
			(start -0.12065 -0.2794)
			(end -0.12065 -0.3048)
			(stroke
				(width 0.1)
				(type default)
			)
			(layer "B.Fab")
		)
		(fp_line
			(start 0.12065 0.2794)
			(end 0.12065 0.3048)
			(stroke
				(width 0.1)
				(type default)
			)
			(layer "B.Fab")
		)
		(fp_line
			(start -0.120396 0.2794)
			(end 0.12065 0.2794)
			(stroke
				(width 0.1)
				(type default)
			)
			(layer "B.Fab")
		)
		(fp_line
			(start 0.67945 0.3048)
			(end 0.67945 -0.305054)
			(stroke
				(width 0.1)
				(type default)
			)
			(layer "B.Fab")
		)
		(fp_line
			(start 0.12065 0.3048)
			(end 0.67945 0.3048)
			(stroke
				(width 0.1)
				(type default)
			)
			(layer "B.Fab")
		)
		(fp_line
			(start -0.120396 0.3048)
			(end -0.120396 0.2794)
			(stroke
				(width 0.1)
				(type default)
			)
			(layer "B.Fab")
		)
		(fp_line
			(start -0.67945 0.3048)
			(end -0.120396 0.3048)
			(stroke
				(width 0.1)
				(type default)
			)
			(layer "B.Fab")
		)
		(pad "1" smd circle
			(at 0.40005 0 270)
			(size 0 0)
			(layers "B.Cu" "B.Mask" "B.Paste")
			(net "SMB_MB_BMC_ISO_SDA")
		)
		(pad "2" smd circle
			(at -0.40005 0 270)
			(size 0 0)
			(layers "B.Cu" "B.Mask" "B.Paste")
			(net "P3V3_AUX")
		)
	)
	(footprint ""
		(layer "B.Cu")
		(at 141.793214 -210.857846 -90)
		(property "Reference" "U106"
			(at -0.041656 1.854454 270)
			(unlocked yes)
			(layer "B.SilkS")
			(effects
				(font
					(size 0.7874 0.5842)
					(thickness 0.1524)
				)
				(justify mirror)
			)
		)
		(property "Value" ""
			(at 0 0 90)
			(layer "B.Fab")
			(effects
				(font
					(size 1.27 1.27)
				)
				(justify mirror)
			)
		)
		(duplicate_pad_numbers_are_jumpers no)
		(fp_line
			(start -1.7272 1.1176)
			(end 1.7272 1.1176)
			(stroke
				(width 0.1524)
				(type default)
			)
			(layer "B.SilkS")
		)
		(fp_line
			(start 1.7272 1.1176)
			(end 1.7272 -1.1176)
			(stroke
				(width 0.1524)
				(type default)
			)
			(layer "B.SilkS")
		)
		(fp_line
			(start 0 -0.7366)
			(end 0.254 -1.1176)
			(stroke
				(width 0.1524)
				(type default)
			)
			(layer "B.SilkS")
		)
		(fp_line
			(start -1.7272 -1.1176)
			(end -1.7272 1.1176)
			(stroke
				(width 0.1524)
				(type default)
			)
			(layer "B.SilkS")
		)
		(fp_line
			(start -1.7272 -1.1176)
			(end -0.254 -1.1176)
			(stroke
				(width 0.1524)
				(type default)
			)
			(layer "B.SilkS")
		)
		(fp_line
			(start -0.254 -1.1176)
			(end 0 -0.7366)
			(stroke
				(width 0.1524)
				(type default)
			)
			(layer "B.SilkS")
		)
		(fp_line
			(start 0.254 -1.1176)
			(end 1.7272 -1.1176)
			(stroke
				(width 0.1524)
				(type default)
			)
			(layer "B.SilkS")
		)
		(fp_poly
			(pts
				(xy 1.9558 -0.649986) (xy 2.7178 -0.268986) (xy 2.7178 -1.030986)
			)
			(stroke
				(width 0)
				(type default)
			)
			(fill yes)
			(layer "B.SilkS")
		)
		(fp_line
			(start -1.5748 1.1176)
			(end -1.5748 -1.1176)
			(stroke
				(width 0.1)
				(type default)
			)
			(layer "B.Fab")
		)
		(fp_line
			(start 1.5748 1.1176)
			(end -1.5748 1.1176)
			(stroke
				(width 0.1)
				(type default)
			)
			(layer "B.Fab")
		)
		(fp_line
			(start -1.5748 -1.1176)
			(end 1.5748 -1.1176)
			(stroke
				(width 0.1)
				(type default)
			)
			(layer "B.Fab")
		)
		(fp_line
			(start 1.5748 -1.1176)
			(end 1.5748 1.1176)
			(stroke
				(width 0.1)
				(type default)
			)
			(layer "B.Fab")
		)
		(fp_poly
			(pts
				(xy 1.9558 -0.649986) (xy 2.7178 -0.268986) (xy 2.7178 -1.030986)
			)
			(stroke
				(width 0)
				(type default)
			)
			(fill yes)
			(layer "B.Fab")
		)
		(pad "1" smd rect
			(at 0.999998 -0.649986 180)
			(size 0.3556 1.1176)
			(layers "B.Cu" "B.Mask" "B.Paste")
			(net "UART_PEX2_CLI_R_RX")
		)
		(pad "2" smd rect
			(at 0.999998 0 180)
			(size 0.3556 1.1176)
			(layers "B.Cu" "B.Mask" "B.Paste")
			(net "GND")
		)
		(pad "3" smd rect
			(at 0.999998 0.649986 180)
			(size 0.3556 1.1176)
			(layers "B.Cu" "B.Mask" "B.Paste")
			(net "UART_PEX3_CLI_R_RX")
		)
		(pad "4" smd rect
			(at -0.999998 0.649986 180)
			(size 0.3556 1.1176)
			(layers "B.Cu" "B.Mask" "B.Paste")
			(net "UART_PEX3_CLI_BUF_R_RX")
		)
		(pad "5" smd rect
			(at -0.999998 0 180)
			(size 0.3556 1.1176)
			(layers "B.Cu" "B.Mask" "B.Paste")
			(net "P3V3_AUX")
		)
		(pad "6" smd rect
			(at -0.999998 -0.649986 180)
			(size 0.3556 1.1176)
			(layers "B.Cu" "B.Mask" "B.Paste")
			(net "UART_PEX2_CLI_BUF_R_RX")
		)
	)
	(footprint ""
		(layer "B.Cu")
		(at 226.386644 -231.225598 -90)
		(property "Reference" "R1478"
			(at 0 0 90)
			(layer "B.SilkS")
			(hide yes)
			(effects
				(font
					(size 1.27 1.27)
				)
				(justify mirror)
			)
		)
		(property "Value" ""
			(at 0 0 90)
			(layer "B.Fab")
			(effects
				(font
					(size 1.27 1.27)
				)
				(justify mirror)
			)
		)
		(duplicate_pad_numbers_are_jumpers no)
		(fp_line
			(start -0.7874 0.4064)
			(end 0.7874 0.4064)
			(stroke
				(width 0.1524)
				(type default)
			)
			(layer "B.SilkS")
		)
		(fp_line
			(start 0.7874 0.4064)
			(end 0.7874 -0.4064)
			(stroke
				(width 0.1524)
				(type default)
			)
			(layer "B.SilkS")
		)
		(fp_line
			(start -0.7874 -0.4064)
			(end -0.7874 0.4064)
			(stroke
				(width 0.1524)
				(type default)
			)
			(layer "B.SilkS")
		)
		(fp_line
			(start 0.7874 -0.4064)
			(end -0.7874 -0.4064)
			(stroke
				(width 0.1524)
				(type default)
			)
			(layer "B.SilkS")
		)
		(fp_line
			(start -0.67945 0.3048)
			(end -0.120396 0.3048)
			(stroke
				(width 0.1)
				(type default)
			)
			(layer "B.Fab")
		)
		(fp_line
			(start -0.120396 0.3048)
			(end -0.120396 0.2794)
			(stroke
				(width 0.1)
				(type default)
			)
			(layer "B.Fab")
		)
		(fp_line
			(start 0.12065 0.3048)
			(end 0.67945 0.3048)
			(stroke
				(width 0.1)
				(type default)
			)
			(layer "B.Fab")
		)
		(fp_line
			(start 0.67945 0.3048)
			(end 0.67945 -0.305054)
			(stroke
				(width 0.1)
				(type default)
			)
			(layer "B.Fab")
		)
		(fp_line
			(start -0.120396 0.2794)
			(end 0.12065 0.2794)
			(stroke
				(width 0.1)
				(type default)
			)
			(layer "B.Fab")
		)
		(fp_line
			(start 0.12065 0.2794)
			(end 0.12065 0.3048)
			(stroke
				(width 0.1)
				(type default)
			)
			(layer "B.Fab")
		)
		(fp_line
			(start -0.12065 -0.2794)
			(end -0.12065 -0.3048)
			(stroke
				(width 0.1)
				(type default)
			)
			(layer "B.Fab")
		)
		(fp_line
			(start 0.12065 -0.2794)
			(end -0.12065 -0.2794)
			(stroke
				(width 0.1)
				(type default)
			)
			(layer "B.Fab")
		)
		(fp_line
			(start -0.67945 -0.3048)
			(end -0.67945 0.3048)
			(stroke
				(width 0.1)
				(type default)
			)
			(layer "B.Fab")
		)
		(fp_line
			(start -0.12065 -0.3048)
			(end -0.67945 -0.3048)
			(stroke
				(width 0.1)
				(type default)
			)
			(layer "B.Fab")
		)
		(fp_line
			(start 0.12065 -0.305054)
			(end 0.12065 -0.2794)
			(stroke
				(width 0.1)
				(type default)
			)
			(layer "B.Fab")
		)
		(fp_line
			(start 0.67945 -0.305054)
			(end 0.12065 -0.305054)
			(stroke
				(width 0.1)
				(type default)
			)
			(layer "B.Fab")
		)
		(pad "1" smd circle
			(at 0.40005 0 90)
			(size 0 0)
			(layers "B.Cu" "B.Mask" "B.Paste")
			(net "SMB_NIC0_SDA")
		)
		(pad "2" smd circle
			(at -0.40005 0 90)
			(size 0 0)
			(layers "B.Cu" "B.Mask" "B.Paste")
			(net "SMB_NIC0_R_SDA")
		)
	)
	(footprint ""
		(layer "B.Cu")
		(at 412.699962 -299.699934 -90)
		(property "Reference" "C2005"
			(at 0 0 90)
			(layer "B.SilkS")
			(hide yes)
			(effects
				(font
					(size 1.27 1.27)
				)
				(justify mirror)
			)
		)
		(property "Value" ""
			(at 0 0 90)
			(layer "B.Fab")
			(effects
				(font
					(size 1.27 1.27)
				)
				(justify mirror)
			)
		)
		(duplicate_pad_numbers_are_jumpers no)
		(fp_line
			(start -0.299974 0.150114)
			(end 0.299974 0.150114)
			(stroke
				(width 0.1)
				(type default)
			)
			(layer "B.Fab")
		)
		(fp_line
			(start 0.299974 0.150114)
			(end 0.299974 -0.150114)
			(stroke
				(width 0.1)
				(type default)
			)
			(layer "B.Fab")
		)
		(fp_line
			(start -0.299974 -0.150114)
			(end -0.299974 0.150114)
			(stroke
				(width 0.1)
				(type default)
			)
			(layer "B.Fab")
		)
		(fp_line
			(start 0.299974 -0.150114)
			(end -0.299974 -0.150114)
			(stroke
				(width 0.1)
				(type default)
			)
			(layer "B.Fab")
		)
		(pad "1" smd rect
			(at 0.2667 0 90)
			(size 0.3048 0.381)
			(layers "B.Cu" "B.Mask" "B.Paste")
			(net "P0V8_SERDES_VDDA_PEX3")
		)
		(pad "2" smd rect
			(at -0.2667 0 90)
			(size 0.3048 0.381)
			(layers "B.Cu" "B.Mask" "B.Paste")
			(net "GND")
		)
	)
	(footprint ""
		(layer "B.Cu")
		(at 131.402328 -325.30923 -90)
		(property "Reference" "C4272"
			(at 0 0 90)
			(layer "B.SilkS")
			(hide yes)
			(effects
				(font
					(size 1.27 1.27)
				)
				(justify mirror)
			)
		)
		(property "Value" ""
			(at 0 0 90)
			(layer "B.Fab")
			(effects
				(font
					(size 1.27 1.27)
				)
				(justify mirror)
			)
		)
		(duplicate_pad_numbers_are_jumpers no)
		(fp_line
			(start -1.2954 0.5842)
			(end 1.2954 0.5842)
			(stroke
				(width 0.1524)
				(type default)
			)
			(layer "B.SilkS")
		)
		(fp_line
			(start 1.2954 0.5842)
			(end 1.2954 -0.5842)
			(stroke
				(width 0.1524)
				(type default)
			)
			(layer "B.SilkS")
		)
		(fp_line
			(start -1.2954 -0.5842)
			(end -1.2954 0.5842)
			(stroke
				(width 0.1524)
				(type default)
			)
			(layer "B.SilkS")
		)
		(fp_line
			(start 1.2954 -0.5842)
			(end -1.2954 -0.5842)
			(stroke
				(width 0.1524)
				(type default)
			)
			(layer "B.SilkS")
		)
		(fp_line
			(start -0.8636 0.4572)
			(end 0.8636 0.4572)
			(stroke
				(width 0.1)
				(type default)
			)
			(layer "B.Fab")
		)
		(fp_line
			(start 0.8636 0.4572)
			(end 0.8636 0.4064)
			(stroke
				(width 0.1)
				(type default)
			)
			(layer "B.Fab")
		)
		(fp_line
			(start -1.1938 0.4064)
			(end -0.8636 0.4064)
			(stroke
				(width 0.1)
				(type default)
			)
			(layer "B.Fab")
		)
		(fp_line
			(start -0.8636 0.4064)
			(end -0.8636 0.4572)
			(stroke
				(width 0.1)
				(type default)
			)
			(layer "B.Fab")
		)
		(fp_line
			(start 0.8636 0.4064)
			(end 1.1938 0.4064)
			(stroke
				(width 0.1)
				(type default)
			)
			(layer "B.Fab")
		)
		(fp_line
			(start 1.1938 0.4064)
			(end 1.1938 -0.4064)
			(stroke
				(width 0.1)
				(type default)
			)
			(layer "B.Fab")
		)
		(fp_line
			(start -1.1938 -0.4064)
			(end -1.1938 0.4064)
			(stroke
				(width 0.1)
				(type default)
			)
			(layer "B.Fab")
		)
		(fp_line
			(start -0.8636 -0.4064)
			(end -1.1938 -0.4064)
			(stroke
				(width 0.1)
				(type default)
			)
			(layer "B.Fab")
		)
		(fp_line
			(start 0.8636 -0.4064)
			(end 0.8636 -0.4572)
			(stroke
				(width 0.1)
				(type default)
			)
			(layer "B.Fab")
		)
		(fp_line
			(start 1.1938 -0.4064)
			(end 0.8636 -0.4064)
			(stroke
				(width 0.1)
				(type default)
			)
			(layer "B.Fab")
		)
		(fp_line
			(start -0.8636 -0.4572)
			(end -0.8636 -0.4064)
			(stroke
				(width 0.1)
				(type default)
			)
			(layer "B.Fab")
		)
		(fp_line
			(start 0.8636 -0.4572)
			(end -0.8636 -0.4572)
			(stroke
				(width 0.1)
				(type default)
			)
			(layer "B.Fab")
		)
		(pad "1" smd rect
			(at 0.7366 0 180)
			(size 0.7112 0.8128)
			(layers "B.Cu" "B.Mask" "B.Paste")
			(net "P0V8_SERDES_VDDA_PEX1_C10")
		)
		(pad "2" smd rect
			(at -0.7366 0 180)
			(size 0.7112 0.8128)
			(layers "B.Cu" "B.Mask" "B.Paste")
			(net "GND")
		)
	)
	(footprint ""
		(layer "B.Cu")
		(at 411.301438 -305.399948 -90)
		(property "Reference" "C3485"
			(at 0 0 90)
			(layer "B.SilkS")
			(hide yes)
			(effects
				(font
					(size 1.27 1.27)
				)
				(justify mirror)
			)
		)
		(property "Value" ""
			(at 0 0 90)
			(layer "B.Fab")
			(effects
				(font
					(size 1.27 1.27)
				)
				(justify mirror)
			)
		)
		(duplicate_pad_numbers_are_jumpers no)
		(fp_line
			(start -0.299974 0.150114)
			(end 0.299974 0.150114)
			(stroke
				(width 0.1)
				(type default)
			)
			(layer "B.Fab")
		)
		(fp_line
			(start 0.299974 0.150114)
			(end 0.299974 -0.150114)
			(stroke
				(width 0.1)
				(type default)
			)
			(layer "B.Fab")
		)
		(fp_line
			(start -0.299974 -0.150114)
			(end -0.299974 0.150114)
			(stroke
				(width 0.1)
				(type default)
			)
			(layer "B.Fab")
		)
		(fp_line
			(start 0.299974 -0.150114)
			(end -0.299974 -0.150114)
			(stroke
				(width 0.1)
				(type default)
			)
			(layer "B.Fab")
		)
		(pad "1" smd rect
			(at 0.2667 0 90)
			(size 0.3048 0.381)
			(layers "B.Cu" "B.Mask" "B.Paste")
			(net "P1V25_SERDES_VDDPLL_PEX3")
		)
		(pad "2" smd rect
			(at -0.2667 0 90)
			(size 0.3048 0.381)
			(layers "B.Cu" "B.Mask" "B.Paste")
			(net "GND")
		)
	)
	(footprint ""
		(layer "B.Cu")
		(at 402.724874 -297.79976 -90)
		(property "Reference" "C1907"
			(at 0 0 90)
			(layer "B.SilkS")
			(hide yes)
			(effects
				(font
					(size 1.27 1.27)
				)
				(justify mirror)
			)
		)
		(property "Value" ""
			(at 0 0 90)
			(layer "B.Fab")
			(effects
				(font
					(size 1.27 1.27)
				)
				(justify mirror)
			)
		)
		(duplicate_pad_numbers_are_jumpers no)
		(fp_line
			(start -0.299974 0.150114)
			(end 0.299974 0.150114)
			(stroke
				(width 0.1)
				(type default)
			)
			(layer "B.Fab")
		)
		(fp_line
			(start 0.299974 0.150114)
			(end 0.299974 -0.150114)
			(stroke
				(width 0.1)
				(type default)
			)
			(layer "B.Fab")
		)
		(fp_line
			(start -0.299974 -0.150114)
			(end -0.299974 0.150114)
			(stroke
				(width 0.1)
				(type default)
			)
			(layer "B.Fab")
		)
		(fp_line
			(start 0.299974 -0.150114)
			(end -0.299974 -0.150114)
			(stroke
				(width 0.1)
				(type default)
			)
			(layer "B.Fab")
		)
		(pad "1" smd rect
			(at 0.2667 0 90)
			(size 0.3048 0.381)
			(layers "B.Cu" "B.Mask" "B.Paste")
			(net "P0V8_PEX3")
		)
		(pad "2" smd rect
			(at -0.2667 0 90)
			(size 0.3048 0.381)
			(layers "B.Cu" "B.Mask" "B.Paste")
			(net "GND")
		)
	)
	(footprint ""
		(layer "B.Cu")
		(at 212.585808 -239.851692 90)
		(property "Reference" "R1544"
			(at 0 0 90)
			(layer "B.SilkS")
			(hide yes)
			(effects
				(font
					(size 1.27 1.27)
				)
				(justify mirror)
			)
		)
		(property "Value" ""
			(at 0 0 90)
			(layer "B.Fab")
			(effects
				(font
					(size 1.27 1.27)
				)
				(justify mirror)
			)
		)
		(duplicate_pad_numbers_are_jumpers no)
		(fp_line
			(start 0.7874 -0.4064)
			(end -0.7874 -0.4064)
			(stroke
				(width 0.1524)
				(type default)
			)
			(layer "B.SilkS")
		)
		(fp_line
			(start -0.7874 -0.4064)
			(end -0.7874 0.4064)
			(stroke
				(width 0.1524)
				(type default)
			)
			(layer "B.SilkS")
		)
		(fp_line
			(start 0.7874 0.4064)
			(end 0.7874 -0.4064)
			(stroke
				(width 0.1524)
				(type default)
			)
			(layer "B.SilkS")
		)
		(fp_line
			(start -0.7874 0.4064)
			(end 0.7874 0.4064)
			(stroke
				(width 0.1524)
				(type default)
			)
			(layer "B.SilkS")
		)
		(fp_line
			(start 0.67945 -0.305054)
			(end 0.12065 -0.305054)
			(stroke
				(width 0.1)
				(type default)
			)
			(layer "B.Fab")
		)
		(fp_line
			(start 0.12065 -0.305054)
			(end 0.12065 -0.2794)
			(stroke
				(width 0.1)
				(type default)
			)
			(layer "B.Fab")
		)
		(fp_line
			(start -0.12065 -0.3048)
			(end -0.67945 -0.3048)
			(stroke
				(width 0.1)
				(type default)
			)
			(layer "B.Fab")
		)
		(fp_line
			(start -0.67945 -0.3048)
			(end -0.67945 0.3048)
			(stroke
				(width 0.1)
				(type default)
			)
			(layer "B.Fab")
		)
		(fp_line
			(start 0.12065 -0.2794)
			(end -0.12065 -0.2794)
			(stroke
				(width 0.1)
				(type default)
			)
			(layer "B.Fab")
		)
		(fp_line
			(start -0.12065 -0.2794)
			(end -0.12065 -0.3048)
			(stroke
				(width 0.1)
				(type default)
			)
			(layer "B.Fab")
		)
		(fp_line
			(start 0.12065 0.2794)
			(end 0.12065 0.3048)
			(stroke
				(width 0.1)
				(type default)
			)
			(layer "B.Fab")
		)
		(fp_line
			(start -0.120396 0.2794)
			(end 0.12065 0.2794)
			(stroke
				(width 0.1)
				(type default)
			)
			(layer "B.Fab")
		)
		(fp_line
			(start 0.67945 0.3048)
			(end 0.67945 -0.305054)
			(stroke
				(width 0.1)
				(type default)
			)
			(layer "B.Fab")
		)
		(fp_line
			(start 0.12065 0.3048)
			(end 0.67945 0.3048)
			(stroke
				(width 0.1)
				(type default)
			)
			(layer "B.Fab")
		)
		(fp_line
			(start -0.120396 0.3048)
			(end -0.120396 0.2794)
			(stroke
				(width 0.1)
				(type default)
			)
			(layer "B.Fab")
		)
		(fp_line
			(start -0.67945 0.3048)
			(end -0.120396 0.3048)
			(stroke
				(width 0.1)
				(type default)
			)
			(layer "B.Fab")
		)
		(pad "1" smd circle
			(at 0.40005 0 270)
			(size 0 0)
			(layers "B.Cu" "B.Mask" "B.Paste")
			(net "SMB_PEX_R_SDA")
		)
		(pad "2" smd circle
			(at -0.40005 0 270)
			(size 0 0)
			(layers "B.Cu" "B.Mask" "B.Paste")
			(net "SMB_PEX_LS_SDA")
		)
	)
	(footprint ""
		(layer "B.Cu")
		(at 351.916238 -324.950582 -90)
		(property "Reference" "C4366"
			(at 0 0 90)
			(layer "B.SilkS")
			(hide yes)
			(effects
				(font
					(size 1.27 1.27)
				)
				(justify mirror)
			)
		)
		(property "Value" ""
			(at 0 0 90)
			(layer "B.Fab")
			(effects
				(font
					(size 1.27 1.27)
				)
				(justify mirror)
			)
		)
		(duplicate_pad_numbers_are_jumpers no)
		(fp_line
			(start -1.2954 0.5842)
			(end 1.2954 0.5842)
			(stroke
				(width 0.1524)
				(type default)
			)
			(layer "B.SilkS")
		)
		(fp_line
			(start 1.2954 0.5842)
			(end 1.2954 -0.5842)
			(stroke
				(width 0.1524)
				(type default)
			)
			(layer "B.SilkS")
		)
		(fp_line
			(start -1.2954 -0.5842)
			(end -1.2954 0.5842)
			(stroke
				(width 0.1524)
				(type default)
			)
			(layer "B.SilkS")
		)
		(fp_line
			(start 1.2954 -0.5842)
			(end -1.2954 -0.5842)
			(stroke
				(width 0.1524)
				(type default)
			)
			(layer "B.SilkS")
		)
		(fp_line
			(start -0.8636 0.4572)
			(end 0.8636 0.4572)
			(stroke
				(width 0.1)
				(type default)
			)
			(layer "B.Fab")
		)
		(fp_line
			(start 0.8636 0.4572)
			(end 0.8636 0.4064)
			(stroke
				(width 0.1)
				(type default)
			)
			(layer "B.Fab")
		)
		(fp_line
			(start -1.1938 0.4064)
			(end -0.8636 0.4064)
			(stroke
				(width 0.1)
				(type default)
			)
			(layer "B.Fab")
		)
		(fp_line
			(start -0.8636 0.4064)
			(end -0.8636 0.4572)
			(stroke
				(width 0.1)
				(type default)
			)
			(layer "B.Fab")
		)
		(fp_line
			(start 0.8636 0.4064)
			(end 1.1938 0.4064)
			(stroke
				(width 0.1)
				(type default)
			)
			(layer "B.Fab")
		)
		(fp_line
			(start 1.1938 0.4064)
			(end 1.1938 -0.4064)
			(stroke
				(width 0.1)
				(type default)
			)
			(layer "B.Fab")
		)
		(fp_line
			(start -1.1938 -0.4064)
			(end -1.1938 0.4064)
			(stroke
				(width 0.1)
				(type default)
			)
			(layer "B.Fab")
		)
		(fp_line
			(start -0.8636 -0.4064)
			(end -1.1938 -0.4064)
			(stroke
				(width 0.1)
				(type default)
			)
			(layer "B.Fab")
		)
		(fp_line
			(start 0.8636 -0.4064)
			(end 0.8636 -0.4572)
			(stroke
				(width 0.1)
				(type default)
			)
			(layer "B.Fab")
		)
		(fp_line
			(start 1.1938 -0.4064)
			(end 0.8636 -0.4064)
			(stroke
				(width 0.1)
				(type default)
			)
			(layer "B.Fab")
		)
		(fp_line
			(start -0.8636 -0.4572)
			(end -0.8636 -0.4064)
			(stroke
				(width 0.1)
				(type default)
			)
			(layer "B.Fab")
		)
		(fp_line
			(start 0.8636 -0.4572)
			(end -0.8636 -0.4572)
			(stroke
				(width 0.1)
				(type default)
			)
			(layer "B.Fab")
		)
		(pad "1" smd rect
			(at 0.7366 0 180)
			(size 0.7112 0.8128)
			(layers "B.Cu" "B.Mask" "B.Paste")
			(net "P0V8_SERDES_VDDA_PEX3_C0")
		)
		(pad "2" smd rect
			(at -0.7366 0 180)
			(size 0.7112 0.8128)
			(layers "B.Cu" "B.Mask" "B.Paste")
			(net "GND")
		)
	)
	(footprint ""
		(layer "B.Cu")
		(at 127.076708 -321.813174 -90)
		(property "Reference" "R6477"
			(at 0 0 90)
			(layer "B.SilkS")
			(hide yes)
			(effects
				(font
					(size 1.27 1.27)
				)
				(justify mirror)
			)
		)
		(property "Value" ""
			(at 0 0 90)
			(layer "B.Fab")
			(effects
				(font
					(size 1.27 1.27)
				)
				(justify mirror)
			)
		)
		(duplicate_pad_numbers_are_jumpers no)
		(fp_line
			(start -0.7874 0.4064)
			(end 0.7874 0.4064)
			(stroke
				(width 0.1524)
				(type default)
			)
			(layer "B.SilkS")
		)
		(fp_line
			(start 0.7874 0.4064)
			(end 0.7874 -0.4064)
			(stroke
				(width 0.1524)
				(type default)
			)
			(layer "B.SilkS")
		)
		(fp_line
			(start -0.7874 -0.4064)
			(end -0.7874 0.4064)
			(stroke
				(width 0.1524)
				(type default)
			)
			(layer "B.SilkS")
		)
		(fp_line
			(start 0.7874 -0.4064)
			(end -0.7874 -0.4064)
			(stroke
				(width 0.1524)
				(type default)
			)
			(layer "B.SilkS")
		)
		(fp_line
			(start -0.67945 0.3048)
			(end -0.120396 0.3048)
			(stroke
				(width 0.1)
				(type default)
			)
			(layer "B.Fab")
		)
		(fp_line
			(start -0.120396 0.3048)
			(end -0.120396 0.2794)
			(stroke
				(width 0.1)
				(type default)
			)
			(layer "B.Fab")
		)
		(fp_line
			(start 0.12065 0.3048)
			(end 0.67945 0.3048)
			(stroke
				(width 0.1)
				(type default)
			)
			(layer "B.Fab")
		)
		(fp_line
			(start 0.67945 0.3048)
			(end 0.67945 -0.305054)
			(stroke
				(width 0.1)
				(type default)
			)
			(layer "B.Fab")
		)
		(fp_line
			(start -0.120396 0.2794)
			(end 0.12065 0.2794)
			(stroke
				(width 0.1)
				(type default)
			)
			(layer "B.Fab")
		)
		(fp_line
			(start 0.12065 0.2794)
			(end 0.12065 0.3048)
			(stroke
				(width 0.1)
				(type default)
			)
			(layer "B.Fab")
		)
		(fp_line
			(start -0.12065 -0.2794)
			(end -0.12065 -0.3048)
			(stroke
				(width 0.1)
				(type default)
			)
			(layer "B.Fab")
		)
		(fp_line
			(start 0.12065 -0.2794)
			(end -0.12065 -0.2794)
			(stroke
				(width 0.1)
				(type default)
			)
			(layer "B.Fab")
		)
		(fp_line
			(start -0.67945 -0.3048)
			(end -0.67945 0.3048)
			(stroke
				(width 0.1)
				(type default)
			)
			(layer "B.Fab")
		)
		(fp_line
			(start -0.12065 -0.3048)
			(end -0.67945 -0.3048)
			(stroke
				(width 0.1)
				(type default)
			)
			(layer "B.Fab")
		)
		(fp_line
			(start 0.12065 -0.305054)
			(end 0.12065 -0.2794)
			(stroke
				(width 0.1)
				(type default)
			)
			(layer "B.Fab")
		)
		(fp_line
			(start 0.67945 -0.305054)
			(end 0.12065 -0.305054)
			(stroke
				(width 0.1)
				(type default)
			)
			(layer "B.Fab")
		)
		(pad "1" smd circle
			(at 0.40005 0 90)
			(size 0 0)
			(layers "B.Cu" "B.Mask" "B.Paste")
			(net "P0V8_SERDES_VDDA_PEX1")
		)
		(pad "2" smd circle
			(at -0.40005 0 90)
			(size 0 0)
			(layers "B.Cu" "B.Mask" "B.Paste")
			(net "P0V8_SERDES_VDDA_PEX1_C2")
		)
	)
	(footprint ""
		(layer "B.Cu")
		(at 353.22637 -308.613556 90)
		(property "Reference" "C1922"
			(at 0 0 90)
			(layer "B.SilkS")
			(hide yes)
			(effects
				(font
					(size 1.27 1.27)
				)
				(justify mirror)
			)
		)
		(property "Value" ""
			(at 0 0 90)
			(layer "B.Fab")
			(effects
				(font
					(size 1.27 1.27)
				)
				(justify mirror)
			)
		)
		(duplicate_pad_numbers_are_jumpers no)
		(fp_line
			(start 1.2954 -0.5842)
			(end -1.2954 -0.5842)
			(stroke
				(width 0.1524)
				(type default)
			)
			(layer "B.SilkS")
		)
		(fp_line
			(start -1.2954 -0.5842)
			(end -1.2954 0.5842)
			(stroke
				(width 0.1524)
				(type default)
			)
			(layer "B.SilkS")
		)
		(fp_line
			(start 1.2954 0.5842)
			(end 1.2954 -0.5842)
			(stroke
				(width 0.1524)
				(type default)
			)
			(layer "B.SilkS")
		)
		(fp_line
			(start -1.2954 0.5842)
			(end 1.2954 0.5842)
			(stroke
				(width 0.1524)
				(type default)
			)
			(layer "B.SilkS")
		)
		(fp_line
			(start 0.8636 -0.4572)
			(end -0.8636 -0.4572)
			(stroke
				(width 0.1)
				(type default)
			)
			(layer "B.Fab")
		)
		(fp_line
			(start -0.8636 -0.4572)
			(end -0.8636 -0.4064)
			(stroke
				(width 0.1)
				(type default)
			)
			(layer "B.Fab")
		)
		(fp_line
			(start 1.1938 -0.4064)
			(end 0.8636 -0.4064)
			(stroke
				(width 0.1)
				(type default)
			)
			(layer "B.Fab")
		)
		(fp_line
			(start 0.8636 -0.4064)
			(end 0.8636 -0.4572)
			(stroke
				(width 0.1)
				(type default)
			)
			(layer "B.Fab")
		)
		(fp_line
			(start -0.8636 -0.4064)
			(end -1.1938 -0.4064)
			(stroke
				(width 0.1)
				(type default)
			)
			(layer "B.Fab")
		)
		(fp_line
			(start -1.1938 -0.4064)
			(end -1.1938 0.4064)
			(stroke
				(width 0.1)
				(type default)
			)
			(layer "B.Fab")
		)
		(fp_line
			(start 1.1938 0.4064)
			(end 1.1938 -0.4064)
			(stroke
				(width 0.1)
				(type default)
			)
			(layer "B.Fab")
		)
		(fp_line
			(start 0.8636 0.4064)
			(end 1.1938 0.4064)
			(stroke
				(width 0.1)
				(type default)
			)
			(layer "B.Fab")
		)
		(fp_line
			(start -0.8636 0.4064)
			(end -0.8636 0.4572)
			(stroke
				(width 0.1)
				(type default)
			)
			(layer "B.Fab")
		)
		(fp_line
			(start -1.1938 0.4064)
			(end -0.8636 0.4064)
			(stroke
				(width 0.1)
				(type default)
			)
			(layer "B.Fab")
		)
		(fp_line
			(start 0.8636 0.4572)
			(end 0.8636 0.4064)
			(stroke
				(width 0.1)
				(type default)
			)
			(layer "B.Fab")
		)
		(fp_line
			(start -0.8636 0.4572)
			(end 0.8636 0.4572)
			(stroke
				(width 0.1)
				(type default)
			)
			(layer "B.Fab")
		)
		(pad "1" smd rect
			(at 0.7366 0)
			(size 0.7112 0.8128)
			(layers "B.Cu" "B.Mask" "B.Paste")
			(net "P0V8_SERDES_VDDA_PEX3")
		)
		(pad "2" smd rect
			(at -0.7366 0)
			(size 0.7112 0.8128)
			(layers "B.Cu" "B.Mask" "B.Paste")
			(net "GND")
		)
	)
	(footprint ""
		(layer "B.Cu")
		(at 176.251362 -305.399948 -90)
		(property "Reference" "C3152"
			(at 0 0 90)
			(layer "B.SilkS")
			(hide yes)
			(effects
				(font
					(size 1.27 1.27)
				)
				(justify mirror)
			)
		)
		(property "Value" ""
			(at 0 0 90)
			(layer "B.Fab")
			(effects
				(font
					(size 1.27 1.27)
				)
				(justify mirror)
			)
		)
		(duplicate_pad_numbers_are_jumpers no)
		(fp_line
			(start -0.299974 0.150114)
			(end 0.299974 0.150114)
			(stroke
				(width 0.1)
				(type default)
			)
			(layer "B.Fab")
		)
		(fp_line
			(start 0.299974 0.150114)
			(end 0.299974 -0.150114)
			(stroke
				(width 0.1)
				(type default)
			)
			(layer "B.Fab")
		)
		(fp_line
			(start -0.299974 -0.150114)
			(end -0.299974 0.150114)
			(stroke
				(width 0.1)
				(type default)
			)
			(layer "B.Fab")
		)
		(fp_line
			(start 0.299974 -0.150114)
			(end -0.299974 -0.150114)
			(stroke
				(width 0.1)
				(type default)
			)
			(layer "B.Fab")
		)
		(pad "1" smd rect
			(at 0.2667 0 90)
			(size 0.3048 0.381)
			(layers "B.Cu" "B.Mask" "B.Paste")
			(net "P1V25_SERDES_VDDPLL_PEX1")
		)
		(pad "2" smd rect
			(at -0.2667 0 90)
			(size 0.3048 0.381)
			(layers "B.Cu" "B.Mask" "B.Paste")
			(net "GND")
		)
	)
	(footprint ""
		(layer "B.Cu")
		(at 182.39994 -301.599854 -90)
		(property "Reference" "C1446"
			(at 0 0 90)
			(layer "B.SilkS")
			(hide yes)
			(effects
				(font
					(size 1.27 1.27)
				)
				(justify mirror)
			)
		)
		(property "Value" ""
			(at 0 0 90)
			(layer "B.Fab")
			(effects
				(font
					(size 1.27 1.27)
				)
				(justify mirror)
			)
		)
		(duplicate_pad_numbers_are_jumpers no)
		(fp_line
			(start -0.299974 0.150114)
			(end 0.299974 0.150114)
			(stroke
				(width 0.1)
				(type default)
			)
			(layer "B.Fab")
		)
		(fp_line
			(start 0.299974 0.150114)
			(end 0.299974 -0.150114)
			(stroke
				(width 0.1)
				(type default)
			)
			(layer "B.Fab")
		)
		(fp_line
			(start -0.299974 -0.150114)
			(end -0.299974 0.150114)
			(stroke
				(width 0.1)
				(type default)
			)
			(layer "B.Fab")
		)
		(fp_line
			(start 0.299974 -0.150114)
			(end -0.299974 -0.150114)
			(stroke
				(width 0.1)
				(type default)
			)
			(layer "B.Fab")
		)
		(pad "1" smd rect
			(at 0.2667 0 90)
			(size 0.3048 0.381)
			(layers "B.Cu" "B.Mask" "B.Paste")
			(net "P0V8_SERDES_VDDA_PEX1")
		)
		(pad "2" smd rect
			(at -0.2667 0 90)
			(size 0.3048 0.381)
			(layers "B.Cu" "B.Mask" "B.Paste")
			(net "GND")
		)
	)
	(footprint ""
		(layer "B.Cu")
		(at 300.872144 -113.437924 180)
		(property "Reference" "R265"
			(at 0 0 0)
			(layer "B.SilkS")
			(hide yes)
			(effects
				(font
					(size 1.27 1.27)
				)
				(justify mirror)
			)
		)
		(property "Value" ""
			(at 0 0 0)
			(layer "B.Fab")
			(effects
				(font
					(size 1.27 1.27)
				)
				(justify mirror)
			)
		)
		(duplicate_pad_numbers_are_jumpers no)
		(fp_line
			(start 0.7874 0.4064)
			(end 0.7874 -0.4064)
			(stroke
				(width 0.1524)
				(type default)
			)
			(layer "B.SilkS")
		)
		(fp_line
			(start 0.7874 -0.4064)
			(end -0.7874 -0.4064)
			(stroke
				(width 0.1524)
				(type default)
			)
			(layer "B.SilkS")
		)
		(fp_line
			(start -0.7874 0.4064)
			(end 0.7874 0.4064)
			(stroke
				(width 0.1524)
				(type default)
			)
			(layer "B.SilkS")
		)
		(fp_line
			(start -0.7874 -0.4064)
			(end -0.7874 0.4064)
			(stroke
				(width 0.1524)
				(type default)
			)
			(layer "B.SilkS")
		)
		(fp_line
			(start 0.67945 0.3048)
			(end 0.67945 -0.305054)
			(stroke
				(width 0.1)
				(type default)
			)
			(layer "B.Fab")
		)
		(fp_line
			(start 0.67945 -0.305054)
			(end 0.12065 -0.305054)
			(stroke
				(width 0.1)
				(type default)
			)
			(layer "B.Fab")
		)
		(fp_line
			(start 0.12065 0.3048)
			(end 0.67945 0.3048)
			(stroke
				(width 0.1)
				(type default)
			)
			(layer "B.Fab")
		)
		(fp_line
			(start 0.12065 0.2794)
			(end 0.12065 0.3048)
			(stroke
				(width 0.1)
				(type default)
			)
			(layer "B.Fab")
		)
		(fp_line
			(start 0.12065 -0.2794)
			(end -0.12065 -0.2794)
			(stroke
				(width 0.1)
				(type default)
			)
			(layer "B.Fab")
		)
		(fp_line
			(start 0.12065 -0.305054)
			(end 0.12065 -0.2794)
			(stroke
				(width 0.1)
				(type default)
			)
			(layer "B.Fab")
		)
		(fp_line
			(start -0.120396 0.3048)
			(end -0.120396 0.2794)
			(stroke
				(width 0.1)
				(type default)
			)
			(layer "B.Fab")
		)
		(fp_line
			(start -0.120396 0.2794)
			(end 0.12065 0.2794)
			(stroke
				(width 0.1)
				(type default)
			)
			(layer "B.Fab")
		)
		(fp_line
			(start -0.12065 -0.2794)
			(end -0.12065 -0.3048)
			(stroke
				(width 0.1)
				(type default)
			)
			(layer "B.Fab")
		)
		(fp_line
			(start -0.12065 -0.3048)
			(end -0.67945 -0.3048)
			(stroke
				(width 0.1)
				(type default)
			)
			(layer "B.Fab")
		)
		(fp_line
			(start -0.67945 0.3048)
			(end -0.120396 0.3048)
			(stroke
				(width 0.1)
				(type default)
			)
			(layer "B.Fab")
		)
		(fp_line
			(start -0.67945 -0.3048)
			(end -0.67945 0.3048)
			(stroke
				(width 0.1)
				(type default)
			)
			(layer "B.Fab")
		)
		(pad "1" smd circle
			(at 0.40005 0)
			(size 0 0)
			(layers "B.Cu" "B.Mask" "B.Paste")
			(net "SMB_NIC5_LS_SDA")
		)
		(pad "2" smd circle
			(at -0.40005 0)
			(size 0 0)
			(layers "B.Cu" "B.Mask" "B.Paste")
			(net "P3V3_NIC5")
		)
	)
	(footprint ""
		(layer "B.Cu")
		(at 165.299898 -290.674806 180)
		(property "Reference" "C1359"
			(at 0 0 0)
			(layer "B.SilkS")
			(hide yes)
			(effects
				(font
					(size 1.27 1.27)
				)
				(justify mirror)
			)
		)
		(property "Value" ""
			(at 0 0 0)
			(layer "B.Fab")
			(effects
				(font
					(size 1.27 1.27)
				)
				(justify mirror)
			)
		)
		(duplicate_pad_numbers_are_jumpers no)
		(fp_line
			(start 0.299974 0.150114)
			(end 0.299974 -0.150114)
			(stroke
				(width 0.1)
				(type default)
			)
			(layer "B.Fab")
		)
		(fp_line
			(start 0.299974 -0.150114)
			(end -0.299974 -0.150114)
			(stroke
				(width 0.1)
				(type default)
			)
			(layer "B.Fab")
		)
		(fp_line
			(start -0.299974 0.150114)
			(end 0.299974 0.150114)
			(stroke
				(width 0.1)
				(type default)
			)
			(layer "B.Fab")
		)
		(fp_line
			(start -0.299974 -0.150114)
			(end -0.299974 0.150114)
			(stroke
				(width 0.1)
				(type default)
			)
			(layer "B.Fab")
		)
		(pad "1" smd rect
			(at 0.2667 0)
			(size 0.3048 0.381)
			(layers "B.Cu" "B.Mask" "B.Paste")
			(net "P0V8_PEX1")
		)
		(pad "2" smd rect
			(at -0.2667 0)
			(size 0.3048 0.381)
			(layers "B.Cu" "B.Mask" "B.Paste")
			(net "GND")
		)
	)
	(footprint ""
		(layer "B.Cu")
		(at 257.531108 -226.52482 -90)
		(property "Reference" "R3487"
			(at 0 0 90)
			(layer "B.SilkS")
			(hide yes)
			(effects
				(font
					(size 1.27 1.27)
				)
				(justify mirror)
			)
		)
		(property "Value" ""
			(at 0 0 90)
			(layer "B.Fab")
			(effects
				(font
					(size 1.27 1.27)
				)
				(justify mirror)
			)
		)
		(duplicate_pad_numbers_are_jumpers no)
		(fp_line
			(start -0.7874 0.4064)
			(end 0.7874 0.4064)
			(stroke
				(width 0.1524)
				(type default)
			)
			(layer "B.SilkS")
		)
		(fp_line
			(start 0.7874 0.4064)
			(end 0.7874 -0.4064)
			(stroke
				(width 0.1524)
				(type default)
			)
			(layer "B.SilkS")
		)
		(fp_line
			(start -0.7874 -0.4064)
			(end -0.7874 0.4064)
			(stroke
				(width 0.1524)
				(type default)
			)
			(layer "B.SilkS")
		)
		(fp_line
			(start 0.7874 -0.4064)
			(end -0.7874 -0.4064)
			(stroke
				(width 0.1524)
				(type default)
			)
			(layer "B.SilkS")
		)
		(fp_line
			(start -0.67945 0.3048)
			(end -0.120396 0.3048)
			(stroke
				(width 0.1)
				(type default)
			)
			(layer "B.Fab")
		)
		(fp_line
			(start -0.120396 0.3048)
			(end -0.120396 0.2794)
			(stroke
				(width 0.1)
				(type default)
			)
			(layer "B.Fab")
		)
		(fp_line
			(start 0.12065 0.3048)
			(end 0.67945 0.3048)
			(stroke
				(width 0.1)
				(type default)
			)
			(layer "B.Fab")
		)
		(fp_line
			(start 0.67945 0.3048)
			(end 0.67945 -0.305054)
			(stroke
				(width 0.1)
				(type default)
			)
			(layer "B.Fab")
		)
		(fp_line
			(start -0.120396 0.2794)
			(end 0.12065 0.2794)
			(stroke
				(width 0.1)
				(type default)
			)
			(layer "B.Fab")
		)
		(fp_line
			(start 0.12065 0.2794)
			(end 0.12065 0.3048)
			(stroke
				(width 0.1)
				(type default)
			)
			(layer "B.Fab")
		)
		(fp_line
			(start -0.12065 -0.2794)
			(end -0.12065 -0.3048)
			(stroke
				(width 0.1)
				(type default)
			)
			(layer "B.Fab")
		)
		(fp_line
			(start 0.12065 -0.2794)
			(end -0.12065 -0.2794)
			(stroke
				(width 0.1)
				(type default)
			)
			(layer "B.Fab")
		)
		(fp_line
			(start -0.67945 -0.3048)
			(end -0.67945 0.3048)
			(stroke
				(width 0.1)
				(type default)
			)
			(layer "B.Fab")
		)
		(fp_line
			(start -0.12065 -0.3048)
			(end -0.67945 -0.3048)
			(stroke
				(width 0.1)
				(type default)
			)
			(layer "B.Fab")
		)
		(fp_line
			(start 0.12065 -0.305054)
			(end 0.12065 -0.2794)
			(stroke
				(width 0.1)
				(type default)
			)
			(layer "B.Fab")
		)
		(fp_line
			(start 0.67945 -0.305054)
			(end 0.12065 -0.305054)
			(stroke
				(width 0.1)
				(type default)
			)
			(layer "B.Fab")
		)
		(pad "1" smd circle
			(at 0.40005 0 90)
			(size 0 0)
			(layers "B.Cu" "B.Mask" "B.Paste")
			(net "P1V8_PEX")
		)
		(pad "2" smd circle
			(at -0.40005 0 90)
			(size 0 0)
			(layers "B.Cu" "B.Mask" "B.Paste")
			(net "SPI_PEX2_CS_MUX_R_N")
		)
	)
	(footprint ""
		(layer "B.Cu")
		(at 133.78815 -321.844924 -90)
		(property "Reference" "R6480"
			(at 0 0 90)
			(layer "B.SilkS")
			(hide yes)
			(effects
				(font
					(size 1.27 1.27)
				)
				(justify mirror)
			)
		)
		(property "Value" ""
			(at 0 0 90)
			(layer "B.Fab")
			(effects
				(font
					(size 1.27 1.27)
				)
				(justify mirror)
			)
		)
		(duplicate_pad_numbers_are_jumpers no)
		(fp_line
			(start -0.7874 0.4064)
			(end 0.7874 0.4064)
			(stroke
				(width 0.1524)
				(type default)
			)
			(layer "B.SilkS")
		)
		(fp_line
			(start 0.7874 0.4064)
			(end 0.7874 -0.4064)
			(stroke
				(width 0.1524)
				(type default)
			)
			(layer "B.SilkS")
		)
		(fp_line
			(start -0.7874 -0.4064)
			(end -0.7874 0.4064)
			(stroke
				(width 0.1524)
				(type default)
			)
			(layer "B.SilkS")
		)
		(fp_line
			(start 0.7874 -0.4064)
			(end -0.7874 -0.4064)
			(stroke
				(width 0.1524)
				(type default)
			)
			(layer "B.SilkS")
		)
		(fp_line
			(start -0.67945 0.3048)
			(end -0.120396 0.3048)
			(stroke
				(width 0.1)
				(type default)
			)
			(layer "B.Fab")
		)
		(fp_line
			(start -0.120396 0.3048)
			(end -0.120396 0.2794)
			(stroke
				(width 0.1)
				(type default)
			)
			(layer "B.Fab")
		)
		(fp_line
			(start 0.12065 0.3048)
			(end 0.67945 0.3048)
			(stroke
				(width 0.1)
				(type default)
			)
			(layer "B.Fab")
		)
		(fp_line
			(start 0.67945 0.3048)
			(end 0.67945 -0.305054)
			(stroke
				(width 0.1)
				(type default)
			)
			(layer "B.Fab")
		)
		(fp_line
			(start -0.120396 0.2794)
			(end 0.12065 0.2794)
			(stroke
				(width 0.1)
				(type default)
			)
			(layer "B.Fab")
		)
		(fp_line
			(start 0.12065 0.2794)
			(end 0.12065 0.3048)
			(stroke
				(width 0.1)
				(type default)
			)
			(layer "B.Fab")
		)
		(fp_line
			(start -0.12065 -0.2794)
			(end -0.12065 -0.3048)
			(stroke
				(width 0.1)
				(type default)
			)
			(layer "B.Fab")
		)
		(fp_line
			(start 0.12065 -0.2794)
			(end -0.12065 -0.2794)
			(stroke
				(width 0.1)
				(type default)
			)
			(layer "B.Fab")
		)
		(fp_line
			(start -0.67945 -0.3048)
			(end -0.67945 0.3048)
			(stroke
				(width 0.1)
				(type default)
			)
			(layer "B.Fab")
		)
		(fp_line
			(start -0.12065 -0.3048)
			(end -0.67945 -0.3048)
			(stroke
				(width 0.1)
				(type default)
			)
			(layer "B.Fab")
		)
		(fp_line
			(start 0.12065 -0.305054)
			(end 0.12065 -0.2794)
			(stroke
				(width 0.1)
				(type default)
			)
			(layer "B.Fab")
		)
		(fp_line
			(start 0.67945 -0.305054)
			(end 0.12065 -0.305054)
			(stroke
				(width 0.1)
				(type default)
			)
			(layer "B.Fab")
		)
		(pad "1" smd circle
			(at 0.40005 0 90)
			(size 0 0)
			(layers "B.Cu" "B.Mask" "B.Paste")
			(net "P0V8_SERDES_VDDA_PEX1")
		)
		(pad "2" smd circle
			(at -0.40005 0 90)
			(size 0 0)
			(layers "B.Cu" "B.Mask" "B.Paste")
			(net "P0V8_SERDES_VDDA_PEX1_C5")
		)
	)
	(footprint ""
		(layer "B.Cu")
		(at 66.299842 -299.699934 -90)
		(property "Reference" "C1175"
			(at 0 0 90)
			(layer "B.SilkS")
			(hide yes)
			(effects
				(font
					(size 1.27 1.27)
				)
				(justify mirror)
			)
		)
		(property "Value" ""
			(at 0 0 90)
			(layer "B.Fab")
			(effects
				(font
					(size 1.27 1.27)
				)
				(justify mirror)
			)
		)
		(duplicate_pad_numbers_are_jumpers no)
		(fp_line
			(start -0.299974 0.150114)
			(end 0.299974 0.150114)
			(stroke
				(width 0.1)
				(type default)
			)
			(layer "B.Fab")
		)
		(fp_line
			(start 0.299974 0.150114)
			(end 0.299974 -0.150114)
			(stroke
				(width 0.1)
				(type default)
			)
			(layer "B.Fab")
		)
		(fp_line
			(start -0.299974 -0.150114)
			(end -0.299974 0.150114)
			(stroke
				(width 0.1)
				(type default)
			)
			(layer "B.Fab")
		)
		(fp_line
			(start 0.299974 -0.150114)
			(end -0.299974 -0.150114)
			(stroke
				(width 0.1)
				(type default)
			)
			(layer "B.Fab")
		)
		(pad "1" smd rect
			(at 0.2667 0 90)
			(size 0.3048 0.381)
			(layers "B.Cu" "B.Mask" "B.Paste")
			(net "P0V8_SERDES_VDDA_PEX0")
		)
		(pad "2" smd rect
			(at -0.2667 0 90)
			(size 0.3048 0.381)
			(layers "B.Cu" "B.Mask" "B.Paste")
			(net "GND")
		)
	)
	(footprint ""
		(layer "B.Cu")
		(at 291.84981 -299.699934 -90)
		(property "Reference" "C1718"
			(at 0 0 90)
			(layer "B.SilkS")
			(hide yes)
			(effects
				(font
					(size 1.27 1.27)
				)
				(justify mirror)
			)
		)
		(property "Value" ""
			(at 0 0 90)
			(layer "B.Fab")
			(effects
				(font
					(size 1.27 1.27)
				)
				(justify mirror)
			)
		)
		(duplicate_pad_numbers_are_jumpers no)
		(fp_line
			(start -0.299974 0.150114)
			(end 0.299974 0.150114)
			(stroke
				(width 0.1)
				(type default)
			)
			(layer "B.Fab")
		)
		(fp_line
			(start 0.299974 0.150114)
			(end 0.299974 -0.150114)
			(stroke
				(width 0.1)
				(type default)
			)
			(layer "B.Fab")
		)
		(fp_line
			(start -0.299974 -0.150114)
			(end -0.299974 0.150114)
			(stroke
				(width 0.1)
				(type default)
			)
			(layer "B.Fab")
		)
		(fp_line
			(start 0.299974 -0.150114)
			(end -0.299974 -0.150114)
			(stroke
				(width 0.1)
				(type default)
			)
			(layer "B.Fab")
		)
		(pad "1" smd rect
			(at 0.2667 0 90)
			(size 0.3048 0.381)
			(layers "B.Cu" "B.Mask" "B.Paste")
			(net "P0V8_SERDES_VDDA_PEX2")
		)
		(pad "2" smd rect
			(at -0.2667 0 90)
			(size 0.3048 0.381)
			(layers "B.Cu" "B.Mask" "B.Paste")
			(net "GND")
		)
	)
	(footprint ""
		(layer "B.Cu")
		(at 183.3499 -292.099746 90)
		(property "Reference" "C1439"
			(at 0 0 90)
			(layer "B.SilkS")
			(hide yes)
			(effects
				(font
					(size 1.27 1.27)
				)
				(justify mirror)
			)
		)
		(property "Value" ""
			(at 0 0 90)
			(layer "B.Fab")
			(effects
				(font
					(size 1.27 1.27)
				)
				(justify mirror)
			)
		)
		(duplicate_pad_numbers_are_jumpers no)
		(fp_line
			(start 0.299974 -0.150114)
			(end -0.299974 -0.150114)
			(stroke
				(width 0.1)
				(type default)
			)
			(layer "B.Fab")
		)
		(fp_line
			(start -0.299974 -0.150114)
			(end -0.299974 0.150114)
			(stroke
				(width 0.1)
				(type default)
			)
			(layer "B.Fab")
		)
		(fp_line
			(start 0.299974 0.150114)
			(end 0.299974 -0.150114)
			(stroke
				(width 0.1)
				(type default)
			)
			(layer "B.Fab")
		)
		(fp_line
			(start -0.299974 0.150114)
			(end 0.299974 0.150114)
			(stroke
				(width 0.1)
				(type default)
			)
			(layer "B.Fab")
		)
		(pad "1" smd rect
			(at 0.2667 0 270)
			(size 0.3048 0.381)
			(layers "B.Cu" "B.Mask" "B.Paste")
			(net "P0V8_SERDES_VDDA_PEX1")
		)
		(pad "2" smd rect
			(at -0.2667 0 270)
			(size 0.3048 0.381)
			(layers "B.Cu" "B.Mask" "B.Paste")
			(net "GND")
		)
	)
	(footprint ""
		(layer "B.Cu")
		(at 375.58853 -238.588296 180)
		(property "Reference" "R911"
			(at 0 0 0)
			(layer "B.SilkS")
			(hide yes)
			(effects
				(font
					(size 1.27 1.27)
				)
				(justify mirror)
			)
		)
		(property "Value" ""
			(at 0 0 0)
			(layer "B.Fab")
			(effects
				(font
					(size 1.27 1.27)
				)
				(justify mirror)
			)
		)
		(duplicate_pad_numbers_are_jumpers no)
		(fp_line
			(start 0.7874 0.4064)
			(end 0.7874 -0.4064)
			(stroke
				(width 0.1524)
				(type default)
			)
			(layer "B.SilkS")
		)
		(fp_line
			(start 0.7874 -0.4064)
			(end -0.7874 -0.4064)
			(stroke
				(width 0.1524)
				(type default)
			)
			(layer "B.SilkS")
		)
		(fp_line
			(start -0.7874 0.4064)
			(end 0.7874 0.4064)
			(stroke
				(width 0.1524)
				(type default)
			)
			(layer "B.SilkS")
		)
		(fp_line
			(start -0.7874 -0.4064)
			(end -0.7874 0.4064)
			(stroke
				(width 0.1524)
				(type default)
			)
			(layer "B.SilkS")
		)
		(fp_line
			(start 0.67945 0.3048)
			(end 0.67945 -0.305054)
			(stroke
				(width 0.1)
				(type default)
			)
			(layer "B.Fab")
		)
		(fp_line
			(start 0.67945 -0.305054)
			(end 0.12065 -0.305054)
			(stroke
				(width 0.1)
				(type default)
			)
			(layer "B.Fab")
		)
		(fp_line
			(start 0.12065 0.3048)
			(end 0.67945 0.3048)
			(stroke
				(width 0.1)
				(type default)
			)
			(layer "B.Fab")
		)
		(fp_line
			(start 0.12065 0.2794)
			(end 0.12065 0.3048)
			(stroke
				(width 0.1)
				(type default)
			)
			(layer "B.Fab")
		)
		(fp_line
			(start 0.12065 -0.2794)
			(end -0.12065 -0.2794)
			(stroke
				(width 0.1)
				(type default)
			)
			(layer "B.Fab")
		)
		(fp_line
			(start 0.12065 -0.305054)
			(end 0.12065 -0.2794)
			(stroke
				(width 0.1)
				(type default)
			)
			(layer "B.Fab")
		)
		(fp_line
			(start -0.120396 0.3048)
			(end -0.120396 0.2794)
			(stroke
				(width 0.1)
				(type default)
			)
			(layer "B.Fab")
		)
		(fp_line
			(start -0.120396 0.2794)
			(end 0.12065 0.2794)
			(stroke
				(width 0.1)
				(type default)
			)
			(layer "B.Fab")
		)
		(fp_line
			(start -0.12065 -0.2794)
			(end -0.12065 -0.3048)
			(stroke
				(width 0.1)
				(type default)
			)
			(layer "B.Fab")
		)
		(fp_line
			(start -0.12065 -0.3048)
			(end -0.67945 -0.3048)
			(stroke
				(width 0.1)
				(type default)
			)
			(layer "B.Fab")
		)
		(fp_line
			(start -0.67945 0.3048)
			(end -0.120396 0.3048)
			(stroke
				(width 0.1)
				(type default)
			)
			(layer "B.Fab")
		)
		(fp_line
			(start -0.67945 -0.3048)
			(end -0.67945 0.3048)
			(stroke
				(width 0.1)
				(type default)
			)
			(layer "B.Fab")
		)
		(pad "1" smd circle
			(at 0.40005 0)
			(size 0 0)
			(layers "B.Cu" "B.Mask" "B.Paste")
			(net "FT4232_SDB_EEPROM_R_SCL")
		)
		(pad "2" smd circle
			(at -0.40005 0)
			(size 0 0)
			(layers "B.Cu" "B.Mask" "B.Paste")
			(net "P3V3_AUX")
		)
	)
	(footprint ""
		(layer "B.Cu")
		(at 113.346484 -321.371468 -90)
		(property "Reference" "R6456"
			(at 0 0 90)
			(layer "B.SilkS")
			(hide yes)
			(effects
				(font
					(size 1.27 1.27)
				)
				(justify mirror)
			)
		)
		(property "Value" ""
			(at 0 0 90)
			(layer "B.Fab")
			(effects
				(font
					(size 1.27 1.27)
				)
				(justify mirror)
			)
		)
		(duplicate_pad_numbers_are_jumpers no)
		(fp_line
			(start -0.7874 0.4064)
			(end 0.7874 0.4064)
			(stroke
				(width 0.1524)
				(type default)
			)
			(layer "B.SilkS")
		)
		(fp_line
			(start 0.7874 0.4064)
			(end 0.7874 -0.4064)
			(stroke
				(width 0.1524)
				(type default)
			)
			(layer "B.SilkS")
		)
		(fp_line
			(start -0.7874 -0.4064)
			(end -0.7874 0.4064)
			(stroke
				(width 0.1524)
				(type default)
			)
			(layer "B.SilkS")
		)
		(fp_line
			(start 0.7874 -0.4064)
			(end -0.7874 -0.4064)
			(stroke
				(width 0.1524)
				(type default)
			)
			(layer "B.SilkS")
		)
		(fp_line
			(start -0.67945 0.3048)
			(end -0.120396 0.3048)
			(stroke
				(width 0.1)
				(type default)
			)
			(layer "B.Fab")
		)
		(fp_line
			(start -0.120396 0.3048)
			(end -0.120396 0.2794)
			(stroke
				(width 0.1)
				(type default)
			)
			(layer "B.Fab")
		)
		(fp_line
			(start 0.12065 0.3048)
			(end 0.67945 0.3048)
			(stroke
				(width 0.1)
				(type default)
			)
			(layer "B.Fab")
		)
		(fp_line
			(start 0.67945 0.3048)
			(end 0.67945 -0.305054)
			(stroke
				(width 0.1)
				(type default)
			)
			(layer "B.Fab")
		)
		(fp_line
			(start -0.120396 0.2794)
			(end 0.12065 0.2794)
			(stroke
				(width 0.1)
				(type default)
			)
			(layer "B.Fab")
		)
		(fp_line
			(start 0.12065 0.2794)
			(end 0.12065 0.3048)
			(stroke
				(width 0.1)
				(type default)
			)
			(layer "B.Fab")
		)
		(fp_line
			(start -0.12065 -0.2794)
			(end -0.12065 -0.3048)
			(stroke
				(width 0.1)
				(type default)
			)
			(layer "B.Fab")
		)
		(fp_line
			(start 0.12065 -0.2794)
			(end -0.12065 -0.2794)
			(stroke
				(width 0.1)
				(type default)
			)
			(layer "B.Fab")
		)
		(fp_line
			(start -0.67945 -0.3048)
			(end -0.67945 0.3048)
			(stroke
				(width 0.1)
				(type default)
			)
			(layer "B.Fab")
		)
		(fp_line
			(start -0.12065 -0.3048)
			(end -0.67945 -0.3048)
			(stroke
				(width 0.1)
				(type default)
			)
			(layer "B.Fab")
		)
		(fp_line
			(start 0.12065 -0.305054)
			(end 0.12065 -0.2794)
			(stroke
				(width 0.1)
				(type default)
			)
			(layer "B.Fab")
		)
		(fp_line
			(start 0.67945 -0.305054)
			(end 0.12065 -0.305054)
			(stroke
				(width 0.1)
				(type default)
			)
			(layer "B.Fab")
		)
		(pad "1" smd circle
			(at 0.40005 0 90)
			(size 0 0)
			(layers "B.Cu" "B.Mask" "B.Paste")
			(net "P0V8_SERDES_VDDA_PEX0")
		)
		(pad "2" smd circle
			(at -0.40005 0 90)
			(size 0 0)
			(layers "B.Cu" "B.Mask" "B.Paste")
			(net "P0V8_SERDES_VDDA_PEX0_C7")
		)
	)
	(footprint ""
		(layer "B.Cu")
		(at 404.625048 -297.79976 -90)
		(property "Reference" "C1884"
			(at 0 0 90)
			(layer "B.SilkS")
			(hide yes)
			(effects
				(font
					(size 1.27 1.27)
				)
				(justify mirror)
			)
		)
		(property "Value" ""
			(at 0 0 90)
			(layer "B.Fab")
			(effects
				(font
					(size 1.27 1.27)
				)
				(justify mirror)
			)
		)
		(duplicate_pad_numbers_are_jumpers no)
		(fp_line
			(start -0.299974 0.150114)
			(end 0.299974 0.150114)
			(stroke
				(width 0.1)
				(type default)
			)
			(layer "B.Fab")
		)
		(fp_line
			(start 0.299974 0.150114)
			(end 0.299974 -0.150114)
			(stroke
				(width 0.1)
				(type default)
			)
			(layer "B.Fab")
		)
		(fp_line
			(start -0.299974 -0.150114)
			(end -0.299974 0.150114)
			(stroke
				(width 0.1)
				(type default)
			)
			(layer "B.Fab")
		)
		(fp_line
			(start 0.299974 -0.150114)
			(end -0.299974 -0.150114)
			(stroke
				(width 0.1)
				(type default)
			)
			(layer "B.Fab")
		)
		(pad "1" smd rect
			(at 0.2667 0 90)
			(size 0.3048 0.381)
			(layers "B.Cu" "B.Mask" "B.Paste")
			(net "P0V8_PEX3")
		)
		(pad "2" smd rect
			(at -0.2667 0 90)
			(size 0.3048 0.381)
			(layers "B.Cu" "B.Mask" "B.Paste")
			(net "GND")
		)
	)
	(footprint ""
		(layer "B.Cu")
		(at 302.303942 -98.552)
		(property "Reference" "R278"
			(at 0 0 0)
			(layer "B.SilkS")
			(hide yes)
			(effects
				(font
					(size 1.27 1.27)
				)
				(justify mirror)
			)
		)
		(property "Value" ""
			(at 0 0 0)
			(layer "B.Fab")
			(effects
				(font
					(size 1.27 1.27)
				)
				(justify mirror)
			)
		)
		(duplicate_pad_numbers_are_jumpers no)
		(fp_line
			(start -0.7874 -0.4064)
			(end -0.7874 0.4064)
			(stroke
				(width 0.1524)
				(type default)
			)
			(layer "B.SilkS")
		)
		(fp_line
			(start -0.7874 0.4064)
			(end 0.7874 0.4064)
			(stroke
				(width 0.1524)
				(type default)
			)
			(layer "B.SilkS")
		)
		(fp_line
			(start 0.7874 -0.4064)
			(end -0.7874 -0.4064)
			(stroke
				(width 0.1524)
				(type default)
			)
			(layer "B.SilkS")
		)
		(fp_line
			(start 0.7874 0.4064)
			(end 0.7874 -0.4064)
			(stroke
				(width 0.1524)
				(type default)
			)
			(layer "B.SilkS")
		)
		(fp_line
			(start -0.67945 -0.3048)
			(end -0.67945 0.3048)
			(stroke
				(width 0.1)
				(type default)
			)
			(layer "B.Fab")
		)
		(fp_line
			(start -0.67945 0.3048)
			(end -0.120396 0.3048)
			(stroke
				(width 0.1)
				(type default)
			)
			(layer "B.Fab")
		)
		(fp_line
			(start -0.12065 -0.3048)
			(end -0.67945 -0.3048)
			(stroke
				(width 0.1)
				(type default)
			)
			(layer "B.Fab")
		)
		(fp_line
			(start -0.12065 -0.2794)
			(end -0.12065 -0.3048)
			(stroke
				(width 0.1)
				(type default)
			)
			(layer "B.Fab")
		)
		(fp_line
			(start -0.120396 0.2794)
			(end 0.12065 0.2794)
			(stroke
				(width 0.1)
				(type default)
			)
			(layer "B.Fab")
		)
		(fp_line
			(start -0.120396 0.3048)
			(end -0.120396 0.2794)
			(stroke
				(width 0.1)
				(type default)
			)
			(layer "B.Fab")
		)
		(fp_line
			(start 0.12065 -0.305054)
			(end 0.12065 -0.2794)
			(stroke
				(width 0.1)
				(type default)
			)
			(layer "B.Fab")
		)
		(fp_line
			(start 0.12065 -0.2794)
			(end -0.12065 -0.2794)
			(stroke
				(width 0.1)
				(type default)
			)
			(layer "B.Fab")
		)
		(fp_line
			(start 0.12065 0.2794)
			(end 0.12065 0.3048)
			(stroke
				(width 0.1)
				(type default)
			)
			(layer "B.Fab")
		)
		(fp_line
			(start 0.12065 0.3048)
			(end 0.67945 0.3048)
			(stroke
				(width 0.1)
				(type default)
			)
			(layer "B.Fab")
		)
		(fp_line
			(start 0.67945 -0.305054)
			(end 0.12065 -0.305054)
			(stroke
				(width 0.1)
				(type default)
			)
			(layer "B.Fab")
		)
		(fp_line
			(start 0.67945 0.3048)
			(end 0.67945 -0.305054)
			(stroke
				(width 0.1)
				(type default)
			)
			(layer "B.Fab")
		)
		(pad "1" smd circle
			(at 0.40005 0 180)
			(size 0 0)
			(layers "B.Cu" "B.Mask" "B.Paste")
			(net "NIC5_MAIN_PWR_EN")
		)
		(pad "2" smd circle
			(at -0.40005 0 180)
			(size 0 0)
			(layers "B.Cu" "B.Mask" "B.Paste")
			(net "GND")
		)
	)
	(footprint ""
		(layer "B.Cu")
		(at 349.264986 -255.86055 180)
		(property "Reference" "PC124"
			(at 0 0 0)
			(layer "B.SilkS")
			(hide yes)
			(effects
				(font
					(size 1.27 1.27)
				)
				(justify mirror)
			)
		)
		(property "Value" ""
			(at 0 0 0)
			(layer "B.Fab")
			(effects
				(font
					(size 1.27 1.27)
				)
				(justify mirror)
			)
		)
		(duplicate_pad_numbers_are_jumpers no)
		(fp_line
			(start 0.7874 0.4064)
			(end 0.7874 -0.4064)
			(stroke
				(width 0.1524)
				(type default)
			)
			(layer "B.SilkS")
		)
		(fp_line
			(start 0.7874 -0.4064)
			(end -0.7874 -0.4064)
			(stroke
				(width 0.1524)
				(type default)
			)
			(layer "B.SilkS")
		)
		(fp_line
			(start -0.7874 0.4064)
			(end 0.7874 0.4064)
			(stroke
				(width 0.1524)
				(type default)
			)
			(layer "B.SilkS")
		)
		(fp_line
			(start -0.7874 -0.4064)
			(end -0.7874 0.4064)
			(stroke
				(width 0.1524)
				(type default)
			)
			(layer "B.SilkS")
		)
		(fp_line
			(start 0.67945 0.3048)
			(end 0.67945 -0.305054)
			(stroke
				(width 0.1)
				(type default)
			)
			(layer "B.Fab")
		)
		(fp_line
			(start 0.67945 -0.305054)
			(end 0.12065 -0.305054)
			(stroke
				(width 0.1)
				(type default)
			)
			(layer "B.Fab")
		)
		(fp_line
			(start 0.12065 0.3048)
			(end 0.67945 0.3048)
			(stroke
				(width 0.1)
				(type default)
			)
			(layer "B.Fab")
		)
		(fp_line
			(start 0.12065 0.2794)
			(end 0.12065 0.3048)
			(stroke
				(width 0.1)
				(type default)
			)
			(layer "B.Fab")
		)
		(fp_line
			(start 0.12065 -0.2794)
			(end -0.12065 -0.2794)
			(stroke
				(width 0.1)
				(type default)
			)
			(layer "B.Fab")
		)
		(fp_line
			(start 0.12065 -0.305054)
			(end 0.12065 -0.2794)
			(stroke
				(width 0.1)
				(type default)
			)
			(layer "B.Fab")
		)
		(fp_line
			(start -0.120396 0.3048)
			(end -0.120396 0.2794)
			(stroke
				(width 0.1)
				(type default)
			)
			(layer "B.Fab")
		)
		(fp_line
			(start -0.120396 0.2794)
			(end 0.12065 0.2794)
			(stroke
				(width 0.1)
				(type default)
			)
			(layer "B.Fab")
		)
		(fp_line
			(start -0.12065 -0.2794)
			(end -0.12065 -0.3048)
			(stroke
				(width 0.1)
				(type default)
			)
			(layer "B.Fab")
		)
		(fp_line
			(start -0.12065 -0.3048)
			(end -0.67945 -0.3048)
			(stroke
				(width 0.1)
				(type default)
			)
			(layer "B.Fab")
		)
		(fp_line
			(start -0.67945 0.3048)
			(end -0.120396 0.3048)
			(stroke
				(width 0.1)
				(type default)
			)
			(layer "B.Fab")
		)
		(fp_line
			(start -0.67945 -0.3048)
			(end -0.67945 0.3048)
			(stroke
				(width 0.1)
				(type default)
			)
			(layer "B.Fab")
		)
		(pad "1" smd circle
			(at 0.40005 0)
			(size 0 0)
			(layers "B.Cu" "B.Mask" "B.Paste")
			(net "P0V8_PEX2_VDD")
		)
		(pad "2" smd circle
			(at -0.40005 0)
			(size 0 0)
			(layers "B.Cu" "B.Mask" "B.Paste")
			(net "GND")
		)
	)
	(footprint ""
		(layer "B.Cu")
		(at 280.924762 -297.79976 -90)
		(property "Reference" "C1633"
			(at 0 0 90)
			(layer "B.SilkS")
			(hide yes)
			(effects
				(font
					(size 1.27 1.27)
				)
				(justify mirror)
			)
		)
		(property "Value" ""
			(at 0 0 90)
			(layer "B.Fab")
			(effects
				(font
					(size 1.27 1.27)
				)
				(justify mirror)
			)
		)
		(duplicate_pad_numbers_are_jumpers no)
		(fp_line
			(start -0.299974 0.150114)
			(end 0.299974 0.150114)
			(stroke
				(width 0.1)
				(type default)
			)
			(layer "B.Fab")
		)
		(fp_line
			(start 0.299974 0.150114)
			(end 0.299974 -0.150114)
			(stroke
				(width 0.1)
				(type default)
			)
			(layer "B.Fab")
		)
		(fp_line
			(start -0.299974 -0.150114)
			(end -0.299974 0.150114)
			(stroke
				(width 0.1)
				(type default)
			)
			(layer "B.Fab")
		)
		(fp_line
			(start 0.299974 -0.150114)
			(end -0.299974 -0.150114)
			(stroke
				(width 0.1)
				(type default)
			)
			(layer "B.Fab")
		)
		(pad "1" smd rect
			(at 0.2667 0 90)
			(size 0.3048 0.381)
			(layers "B.Cu" "B.Mask" "B.Paste")
			(net "P0V8_PEX2")
		)
		(pad "2" smd rect
			(at -0.2667 0 90)
			(size 0.3048 0.381)
			(layers "B.Cu" "B.Mask" "B.Paste")
			(net "GND")
		)
	)
	(footprint ""
		(layer "B.Cu")
		(at 424.016932 -295.42486)
		(property "Reference" "C3423"
			(at 0 0 0)
			(layer "B.SilkS")
			(hide yes)
			(effects
				(font
					(size 1.27 1.27)
				)
				(justify mirror)
			)
		)
		(property "Value" ""
			(at 0 0 0)
			(layer "B.Fab")
			(effects
				(font
					(size 1.27 1.27)
				)
				(justify mirror)
			)
		)
		(duplicate_pad_numbers_are_jumpers no)
		(fp_line
			(start -1.2954 -0.5842)
			(end -1.2954 0.5842)
			(stroke
				(width 0.1524)
				(type default)
			)
			(layer "B.SilkS")
		)
		(fp_line
			(start -1.2954 0.5842)
			(end 1.2954 0.5842)
			(stroke
				(width 0.1524)
				(type default)
			)
			(layer "B.SilkS")
		)
		(fp_line
			(start 1.2954 -0.5842)
			(end -1.2954 -0.5842)
			(stroke
				(width 0.1524)
				(type default)
			)
			(layer "B.SilkS")
		)
		(fp_line
			(start 1.2954 0.5842)
			(end 1.2954 -0.5842)
			(stroke
				(width 0.1524)
				(type default)
			)
			(layer "B.SilkS")
		)
		(fp_line
			(start -1.1938 -0.4064)
			(end -1.1938 0.4064)
			(stroke
				(width 0.1)
				(type default)
			)
			(layer "B.Fab")
		)
		(fp_line
			(start -1.1938 0.4064)
			(end -0.8636 0.4064)
			(stroke
				(width 0.1)
				(type default)
			)
			(layer "B.Fab")
		)
		(fp_line
			(start -0.8636 -0.4572)
			(end -0.8636 -0.4064)
			(stroke
				(width 0.1)
				(type default)
			)
			(layer "B.Fab")
		)
		(fp_line
			(start -0.8636 -0.4064)
			(end -1.1938 -0.4064)
			(stroke
				(width 0.1)
				(type default)
			)
			(layer "B.Fab")
		)
		(fp_line
			(start -0.8636 0.4064)
			(end -0.8636 0.4572)
			(stroke
				(width 0.1)
				(type default)
			)
			(layer "B.Fab")
		)
		(fp_line
			(start -0.8636 0.4572)
			(end 0.8636 0.4572)
			(stroke
				(width 0.1)
				(type default)
			)
			(layer "B.Fab")
		)
		(fp_line
			(start 0.8636 -0.4572)
			(end -0.8636 -0.4572)
			(stroke
				(width 0.1)
				(type default)
			)
			(layer "B.Fab")
		)
		(fp_line
			(start 0.8636 -0.4064)
			(end 0.8636 -0.4572)
			(stroke
				(width 0.1)
				(type default)
			)
			(layer "B.Fab")
		)
		(fp_line
			(start 0.8636 0.4064)
			(end 1.1938 0.4064)
			(stroke
				(width 0.1)
				(type default)
			)
			(layer "B.Fab")
		)
		(fp_line
			(start 0.8636 0.4572)
			(end 0.8636 0.4064)
			(stroke
				(width 0.1)
				(type default)
			)
			(layer "B.Fab")
		)
		(fp_line
			(start 1.1938 -0.4064)
			(end 0.8636 -0.4064)
			(stroke
				(width 0.1)
				(type default)
			)
			(layer "B.Fab")
		)
		(fp_line
			(start 1.1938 0.4064)
			(end 1.1938 -0.4064)
			(stroke
				(width 0.1)
				(type default)
			)
			(layer "B.Fab")
		)
		(pad "1" smd rect
			(at 0.7366 0 270)
			(size 0.7112 0.8128)
			(layers "B.Cu" "B.Mask" "B.Paste")
			(net "P1V25_PEX3")
		)
		(pad "2" smd rect
			(at -0.7366 0 270)
			(size 0.7112 0.8128)
			(layers "B.Cu" "B.Mask" "B.Paste")
			(net "GND")
		)
	)
	(footprint ""
		(layer "B.Cu")
		(at 409.849828 -299.699934 -90)
		(property "Reference" "C1977"
			(at 0 0 90)
			(layer "B.SilkS")
			(hide yes)
			(effects
				(font
					(size 1.27 1.27)
				)
				(justify mirror)
			)
		)
		(property "Value" ""
			(at 0 0 90)
			(layer "B.Fab")
			(effects
				(font
					(size 1.27 1.27)
				)
				(justify mirror)
			)
		)
		(duplicate_pad_numbers_are_jumpers no)
		(fp_line
			(start -0.299974 0.150114)
			(end 0.299974 0.150114)
			(stroke
				(width 0.1)
				(type default)
			)
			(layer "B.Fab")
		)
		(fp_line
			(start 0.299974 0.150114)
			(end 0.299974 -0.150114)
			(stroke
				(width 0.1)
				(type default)
			)
			(layer "B.Fab")
		)
		(fp_line
			(start -0.299974 -0.150114)
			(end -0.299974 0.150114)
			(stroke
				(width 0.1)
				(type default)
			)
			(layer "B.Fab")
		)
		(fp_line
			(start 0.299974 -0.150114)
			(end -0.299974 -0.150114)
			(stroke
				(width 0.1)
				(type default)
			)
			(layer "B.Fab")
		)
		(pad "1" smd rect
			(at 0.2667 0 90)
			(size 0.3048 0.381)
			(layers "B.Cu" "B.Mask" "B.Paste")
			(net "P0V8_SERDES_VDDA_PEX3")
		)
		(pad "2" smd rect
			(at -0.2667 0 90)
			(size 0.3048 0.381)
			(layers "B.Cu" "B.Mask" "B.Paste")
			(net "GND")
		)
	)
	(footprint ""
		(layer "B.Cu")
		(at 118.456964 -317.706756)
		(property "Reference" "C4267"
			(at 0 0 0)
			(layer "B.SilkS")
			(hide yes)
			(effects
				(font
					(size 1.27 1.27)
				)
				(justify mirror)
			)
		)
		(property "Value" ""
			(at 0 0 0)
			(layer "B.Fab")
			(effects
				(font
					(size 1.27 1.27)
				)
				(justify mirror)
			)
		)
		(duplicate_pad_numbers_are_jumpers no)
		(fp_line
			(start -0.299974 -0.150114)
			(end -0.299974 0.150114)
			(stroke
				(width 0.1)
				(type default)
			)
			(layer "B.Fab")
		)
		(fp_line
			(start -0.299974 0.150114)
			(end 0.299974 0.150114)
			(stroke
				(width 0.1)
				(type default)
			)
			(layer "B.Fab")
		)
		(fp_line
			(start 0.299974 -0.150114)
			(end -0.299974 -0.150114)
			(stroke
				(width 0.1)
				(type default)
			)
			(layer "B.Fab")
		)
		(fp_line
			(start 0.299974 0.150114)
			(end 0.299974 -0.150114)
			(stroke
				(width 0.1)
				(type default)
			)
			(layer "B.Fab")
		)
		(pad "1" smd rect
			(at 0.2667 0 180)
			(size 0.3048 0.381)
			(layers "B.Cu" "B.Mask" "B.Paste")
			(net "P0V8_SERDES_VDDA_PEX1")
		)
		(pad "2" smd rect
			(at -0.2667 0 180)
			(size 0.3048 0.381)
			(layers "B.Cu" "B.Mask" "B.Paste")
			(net "GND")
		)
	)
	(footprint ""
		(layer "B.Cu")
		(at 295.670224 -296.37482)
		(property "Reference" "C1617"
			(at 0 0 0)
			(layer "B.SilkS")
			(hide yes)
			(effects
				(font
					(size 1.27 1.27)
				)
				(justify mirror)
			)
		)
		(property "Value" ""
			(at 0 0 0)
			(layer "B.Fab")
			(effects
				(font
					(size 1.27 1.27)
				)
				(justify mirror)
			)
		)
		(duplicate_pad_numbers_are_jumpers no)
		(fp_line
			(start -0.299974 -0.150114)
			(end -0.299974 0.150114)
			(stroke
				(width 0.1)
				(type default)
			)
			(layer "B.Fab")
		)
		(fp_line
			(start -0.299974 0.150114)
			(end 0.299974 0.150114)
			(stroke
				(width 0.1)
				(type default)
			)
			(layer "B.Fab")
		)
		(fp_line
			(start 0.299974 -0.150114)
			(end -0.299974 -0.150114)
			(stroke
				(width 0.1)
				(type default)
			)
			(layer "B.Fab")
		)
		(fp_line
			(start 0.299974 0.150114)
			(end 0.299974 -0.150114)
			(stroke
				(width 0.1)
				(type default)
			)
			(layer "B.Fab")
		)
		(pad "1" smd rect
			(at 0.2667 0 180)
			(size 0.3048 0.381)
			(layers "B.Cu" "B.Mask" "B.Paste")
			(net "P0V8_PEX2")
		)
		(pad "2" smd rect
			(at -0.2667 0 180)
			(size 0.3048 0.381)
			(layers "B.Cu" "B.Mask" "B.Paste")
			(net "GND")
		)
	)
	(footprint ""
		(layer "B.Cu")
		(at 410.799788 -292.099746 90)
		(property "Reference" "C1978"
			(at 0 0 90)
			(layer "B.SilkS")
			(hide yes)
			(effects
				(font
					(size 1.27 1.27)
				)
				(justify mirror)
			)
		)
		(property "Value" ""
			(at 0 0 90)
			(layer "B.Fab")
			(effects
				(font
					(size 1.27 1.27)
				)
				(justify mirror)
			)
		)
		(duplicate_pad_numbers_are_jumpers no)
		(fp_line
			(start 0.299974 -0.150114)
			(end -0.299974 -0.150114)
			(stroke
				(width 0.1)
				(type default)
			)
			(layer "B.Fab")
		)
		(fp_line
			(start -0.299974 -0.150114)
			(end -0.299974 0.150114)
			(stroke
				(width 0.1)
				(type default)
			)
			(layer "B.Fab")
		)
		(fp_line
			(start 0.299974 0.150114)
			(end 0.299974 -0.150114)
			(stroke
				(width 0.1)
				(type default)
			)
			(layer "B.Fab")
		)
		(fp_line
			(start -0.299974 0.150114)
			(end 0.299974 0.150114)
			(stroke
				(width 0.1)
				(type default)
			)
			(layer "B.Fab")
		)
		(pad "1" smd rect
			(at 0.2667 0 270)
			(size 0.3048 0.381)
			(layers "B.Cu" "B.Mask" "B.Paste")
			(net "P0V8_SERDES_VDDA_PEX3")
		)
		(pad "2" smd rect
			(at -0.2667 0 270)
			(size 0.3048 0.381)
			(layers "B.Cu" "B.Mask" "B.Paste")
			(net "GND")
		)
	)
	(footprint ""
		(layer "B.Cu")
		(at 288.049716 -288.299906 90)
		(property "Reference" "C3290"
			(at 0 0 90)
			(layer "B.SilkS")
			(hide yes)
			(effects
				(font
					(size 1.27 1.27)
				)
				(justify mirror)
			)
		)
		(property "Value" ""
			(at 0 0 90)
			(layer "B.Fab")
			(effects
				(font
					(size 1.27 1.27)
				)
				(justify mirror)
			)
		)
		(duplicate_pad_numbers_are_jumpers no)
		(fp_line
			(start 0.299974 -0.150114)
			(end -0.299974 -0.150114)
			(stroke
				(width 0.1)
				(type default)
			)
			(layer "B.Fab")
		)
		(fp_line
			(start -0.299974 -0.150114)
			(end -0.299974 0.150114)
			(stroke
				(width 0.1)
				(type default)
			)
			(layer "B.Fab")
		)
		(fp_line
			(start 0.299974 0.150114)
			(end 0.299974 -0.150114)
			(stroke
				(width 0.1)
				(type default)
			)
			(layer "B.Fab")
		)
		(fp_line
			(start -0.299974 0.150114)
			(end 0.299974 0.150114)
			(stroke
				(width 0.1)
				(type default)
			)
			(layer "B.Fab")
		)
		(pad "1" smd rect
			(at 0.2667 0 270)
			(size 0.3048 0.381)
			(layers "B.Cu" "B.Mask" "B.Paste")
			(net "P1V25_PEX2")
		)
		(pad "2" smd rect
			(at -0.2667 0 270)
			(size 0.3048 0.381)
			(layers "B.Cu" "B.Mask" "B.Paste")
			(net "GND")
		)
	)
	(footprint ""
		(layer "B.Cu")
		(at 134.300214 -206.793846 -90)
		(property "Reference" "C2585"
			(at 0 0 90)
			(layer "B.SilkS")
			(hide yes)
			(effects
				(font
					(size 1.27 1.27)
				)
				(justify mirror)
			)
		)
		(property "Value" ""
			(at 0 0 90)
			(layer "B.Fab")
			(effects
				(font
					(size 1.27 1.27)
				)
				(justify mirror)
			)
		)
		(duplicate_pad_numbers_are_jumpers no)
		(fp_line
			(start -0.7874 0.4064)
			(end 0.7874 0.4064)
			(stroke
				(width 0.1524)
				(type default)
			)
			(layer "B.SilkS")
		)
		(fp_line
			(start 0.7874 0.4064)
			(end 0.7874 -0.4064)
			(stroke
				(width 0.1524)
				(type default)
			)
			(layer "B.SilkS")
		)
		(fp_line
			(start -0.7874 -0.4064)
			(end -0.7874 0.4064)
			(stroke
				(width 0.1524)
				(type default)
			)
			(layer "B.SilkS")
		)
		(fp_line
			(start 0.7874 -0.4064)
			(end -0.7874 -0.4064)
			(stroke
				(width 0.1524)
				(type default)
			)
			(layer "B.SilkS")
		)
		(fp_line
			(start -0.67945 0.3048)
			(end -0.120396 0.3048)
			(stroke
				(width 0.1)
				(type default)
			)
			(layer "B.Fab")
		)
		(fp_line
			(start -0.120396 0.3048)
			(end -0.120396 0.2794)
			(stroke
				(width 0.1)
				(type default)
			)
			(layer "B.Fab")
		)
		(fp_line
			(start 0.12065 0.3048)
			(end 0.67945 0.3048)
			(stroke
				(width 0.1)
				(type default)
			)
			(layer "B.Fab")
		)
		(fp_line
			(start 0.67945 0.3048)
			(end 0.67945 -0.305054)
			(stroke
				(width 0.1)
				(type default)
			)
			(layer "B.Fab")
		)
		(fp_line
			(start -0.120396 0.2794)
			(end 0.12065 0.2794)
			(stroke
				(width 0.1)
				(type default)
			)
			(layer "B.Fab")
		)
		(fp_line
			(start 0.12065 0.2794)
			(end 0.12065 0.3048)
			(stroke
				(width 0.1)
				(type default)
			)
			(layer "B.Fab")
		)
		(fp_line
			(start -0.12065 -0.2794)
			(end -0.12065 -0.3048)
			(stroke
				(width 0.1)
				(type default)
			)
			(layer "B.Fab")
		)
		(fp_line
			(start 0.12065 -0.2794)
			(end -0.12065 -0.2794)
			(stroke
				(width 0.1)
				(type default)
			)
			(layer "B.Fab")
		)
		(fp_line
			(start -0.67945 -0.3048)
			(end -0.67945 0.3048)
			(stroke
				(width 0.1)
				(type default)
			)
			(layer "B.Fab")
		)
		(fp_line
			(start -0.12065 -0.3048)
			(end -0.67945 -0.3048)
			(stroke
				(width 0.1)
				(type default)
			)
			(layer "B.Fab")
		)
		(fp_line
			(start 0.12065 -0.305054)
			(end 0.12065 -0.2794)
			(stroke
				(width 0.1)
				(type default)
			)
			(layer "B.Fab")
		)
		(fp_line
			(start 0.67945 -0.305054)
			(end 0.12065 -0.305054)
			(stroke
				(width 0.1)
				(type default)
			)
			(layer "B.Fab")
		)
		(pad "1" smd circle
			(at 0.40005 0 90)
			(size 0 0)
			(layers "B.Cu" "B.Mask" "B.Paste")
			(net "P3V3_AUX")
		)
		(pad "2" smd circle
			(at -0.40005 0 90)
			(size 0 0)
			(layers "B.Cu" "B.Mask" "B.Paste")
			(net "GND")
		)
	)
	(footprint ""
		(layer "B.Cu")
		(at 163.874958 -294.2082 -90)
		(property "Reference" "C3221"
			(at 0 0 90)
			(layer "B.SilkS")
			(hide yes)
			(effects
				(font
					(size 1.27 1.27)
				)
				(justify mirror)
			)
		)
		(property "Value" ""
			(at 0 0 90)
			(layer "B.Fab")
			(effects
				(font
					(size 1.27 1.27)
				)
				(justify mirror)
			)
		)
		(duplicate_pad_numbers_are_jumpers no)
		(fp_line
			(start -0.299974 0.150114)
			(end 0.299974 0.150114)
			(stroke
				(width 0.1)
				(type default)
			)
			(layer "B.Fab")
		)
		(fp_line
			(start 0.299974 0.150114)
			(end 0.299974 -0.150114)
			(stroke
				(width 0.1)
				(type default)
			)
			(layer "B.Fab")
		)
		(fp_line
			(start -0.299974 -0.150114)
			(end -0.299974 0.150114)
			(stroke
				(width 0.1)
				(type default)
			)
			(layer "B.Fab")
		)
		(fp_line
			(start 0.299974 -0.150114)
			(end -0.299974 -0.150114)
			(stroke
				(width 0.1)
				(type default)
			)
			(layer "B.Fab")
		)
		(pad "1" smd rect
			(at 0.2667 0 90)
			(size 0.3048 0.381)
			(layers "B.Cu" "B.Mask" "B.Paste")
			(net "PCEPLL5_VDDA18_PEX1")
		)
		(pad "2" smd rect
			(at -0.2667 0 90)
			(size 0.3048 0.381)
			(layers "B.Cu" "B.Mask" "B.Paste")
			(net "GND")
		)
	)
	(footprint ""
		(layer "B.Cu")
		(at 120.038368 -321.387978 -90)
		(property "Reference" "R6484"
			(at 0 0 90)
			(layer "B.SilkS")
			(hide yes)
			(effects
				(font
					(size 1.27 1.27)
				)
				(justify mirror)
			)
		)
		(property "Value" ""
			(at 0 0 90)
			(layer "B.Fab")
			(effects
				(font
					(size 1.27 1.27)
				)
				(justify mirror)
			)
		)
		(duplicate_pad_numbers_are_jumpers no)
		(fp_line
			(start -0.7874 0.4064)
			(end 0.7874 0.4064)
			(stroke
				(width 0.1524)
				(type default)
			)
			(layer "B.SilkS")
		)
		(fp_line
			(start 0.7874 0.4064)
			(end 0.7874 -0.4064)
			(stroke
				(width 0.1524)
				(type default)
			)
			(layer "B.SilkS")
		)
		(fp_line
			(start -0.7874 -0.4064)
			(end -0.7874 0.4064)
			(stroke
				(width 0.1524)
				(type default)
			)
			(layer "B.SilkS")
		)
		(fp_line
			(start 0.7874 -0.4064)
			(end -0.7874 -0.4064)
			(stroke
				(width 0.1524)
				(type default)
			)
			(layer "B.SilkS")
		)
		(fp_line
			(start -0.67945 0.3048)
			(end -0.120396 0.3048)
			(stroke
				(width 0.1)
				(type default)
			)
			(layer "B.Fab")
		)
		(fp_line
			(start -0.120396 0.3048)
			(end -0.120396 0.2794)
			(stroke
				(width 0.1)
				(type default)
			)
			(layer "B.Fab")
		)
		(fp_line
			(start 0.12065 0.3048)
			(end 0.67945 0.3048)
			(stroke
				(width 0.1)
				(type default)
			)
			(layer "B.Fab")
		)
		(fp_line
			(start 0.67945 0.3048)
			(end 0.67945 -0.305054)
			(stroke
				(width 0.1)
				(type default)
			)
			(layer "B.Fab")
		)
		(fp_line
			(start -0.120396 0.2794)
			(end 0.12065 0.2794)
			(stroke
				(width 0.1)
				(type default)
			)
			(layer "B.Fab")
		)
		(fp_line
			(start 0.12065 0.2794)
			(end 0.12065 0.3048)
			(stroke
				(width 0.1)
				(type default)
			)
			(layer "B.Fab")
		)
		(fp_line
			(start -0.12065 -0.2794)
			(end -0.12065 -0.3048)
			(stroke
				(width 0.1)
				(type default)
			)
			(layer "B.Fab")
		)
		(fp_line
			(start 0.12065 -0.2794)
			(end -0.12065 -0.2794)
			(stroke
				(width 0.1)
				(type default)
			)
			(layer "B.Fab")
		)
		(fp_line
			(start -0.67945 -0.3048)
			(end -0.67945 0.3048)
			(stroke
				(width 0.1)
				(type default)
			)
			(layer "B.Fab")
		)
		(fp_line
			(start -0.12065 -0.3048)
			(end -0.67945 -0.3048)
			(stroke
				(width 0.1)
				(type default)
			)
			(layer "B.Fab")
		)
		(fp_line
			(start 0.12065 -0.305054)
			(end 0.12065 -0.2794)
			(stroke
				(width 0.1)
				(type default)
			)
			(layer "B.Fab")
		)
		(fp_line
			(start 0.67945 -0.305054)
			(end 0.12065 -0.305054)
			(stroke
				(width 0.1)
				(type default)
			)
			(layer "B.Fab")
		)
		(pad "1" smd circle
			(at 0.40005 0 90)
			(size 0 0)
			(layers "B.Cu" "B.Mask" "B.Paste")
			(net "P0V8_SERDES_VDDA_PEX1")
		)
		(pad "2" smd circle
			(at -0.40005 0 90)
			(size 0 0)
			(layers "B.Cu" "B.Mask" "B.Paste")
			(net "P0V8_SERDES_VDDA_PEX1_C7")
		)
	)
	(footprint ""
		(layer "B.Cu")
		(at 288.99993 -303.499774 -90)
		(property "Reference" "C3262"
			(at 0 0 90)
			(layer "B.SilkS")
			(hide yes)
			(effects
				(font
					(size 1.27 1.27)
				)
				(justify mirror)
			)
		)
		(property "Value" ""
			(at 0 0 90)
			(layer "B.Fab")
			(effects
				(font
					(size 1.27 1.27)
				)
				(justify mirror)
			)
		)
		(duplicate_pad_numbers_are_jumpers no)
		(fp_line
			(start -0.299974 0.150114)
			(end 0.299974 0.150114)
			(stroke
				(width 0.1)
				(type default)
			)
			(layer "B.Fab")
		)
		(fp_line
			(start 0.299974 0.150114)
			(end 0.299974 -0.150114)
			(stroke
				(width 0.1)
				(type default)
			)
			(layer "B.Fab")
		)
		(fp_line
			(start -0.299974 -0.150114)
			(end -0.299974 0.150114)
			(stroke
				(width 0.1)
				(type default)
			)
			(layer "B.Fab")
		)
		(fp_line
			(start 0.299974 -0.150114)
			(end -0.299974 -0.150114)
			(stroke
				(width 0.1)
				(type default)
			)
			(layer "B.Fab")
		)
		(pad "1" smd rect
			(at 0.2667 0 90)
			(size 0.3048 0.381)
			(layers "B.Cu" "B.Mask" "B.Paste")
			(net "P1V25_PEX2")
		)
		(pad "2" smd rect
			(at -0.2667 0 90)
			(size 0.3048 0.381)
			(layers "B.Cu" "B.Mask" "B.Paste")
			(net "GND")
		)
	)
	(footprint ""
		(layer "B.Cu")
		(at 377.587002 -223.733106)
		(property "Reference" "R925"
			(at 0 0 0)
			(layer "B.SilkS")
			(hide yes)
			(effects
				(font
					(size 1.27 1.27)
				)
				(justify mirror)
			)
		)
		(property "Value" ""
			(at 0 0 0)
			(layer "B.Fab")
			(effects
				(font
					(size 1.27 1.27)
				)
				(justify mirror)
			)
		)
		(duplicate_pad_numbers_are_jumpers no)
		(fp_line
			(start -0.7874 -0.4064)
			(end -0.7874 0.4064)
			(stroke
				(width 0.1524)
				(type default)
			)
			(layer "B.SilkS")
		)
		(fp_line
			(start -0.7874 0.4064)
			(end 0.7874 0.4064)
			(stroke
				(width 0.1524)
				(type default)
			)
			(layer "B.SilkS")
		)
		(fp_line
			(start 0.7874 -0.4064)
			(end -0.7874 -0.4064)
			(stroke
				(width 0.1524)
				(type default)
			)
			(layer "B.SilkS")
		)
		(fp_line
			(start 0.7874 0.4064)
			(end 0.7874 -0.4064)
			(stroke
				(width 0.1524)
				(type default)
			)
			(layer "B.SilkS")
		)
		(fp_line
			(start -0.67945 -0.3048)
			(end -0.67945 0.3048)
			(stroke
				(width 0.1)
				(type default)
			)
			(layer "B.Fab")
		)
		(fp_line
			(start -0.67945 0.3048)
			(end -0.120396 0.3048)
			(stroke
				(width 0.1)
				(type default)
			)
			(layer "B.Fab")
		)
		(fp_line
			(start -0.12065 -0.3048)
			(end -0.67945 -0.3048)
			(stroke
				(width 0.1)
				(type default)
			)
			(layer "B.Fab")
		)
		(fp_line
			(start -0.12065 -0.2794)
			(end -0.12065 -0.3048)
			(stroke
				(width 0.1)
				(type default)
			)
			(layer "B.Fab")
		)
		(fp_line
			(start -0.120396 0.2794)
			(end 0.12065 0.2794)
			(stroke
				(width 0.1)
				(type default)
			)
			(layer "B.Fab")
		)
		(fp_line
			(start -0.120396 0.3048)
			(end -0.120396 0.2794)
			(stroke
				(width 0.1)
				(type default)
			)
			(layer "B.Fab")
		)
		(fp_line
			(start 0.12065 -0.305054)
			(end 0.12065 -0.2794)
			(stroke
				(width 0.1)
				(type default)
			)
			(layer "B.Fab")
		)
		(fp_line
			(start 0.12065 -0.2794)
			(end -0.12065 -0.2794)
			(stroke
				(width 0.1)
				(type default)
			)
			(layer "B.Fab")
		)
		(fp_line
			(start 0.12065 0.2794)
			(end 0.12065 0.3048)
			(stroke
				(width 0.1)
				(type default)
			)
			(layer "B.Fab")
		)
		(fp_line
			(start 0.12065 0.3048)
			(end 0.67945 0.3048)
			(stroke
				(width 0.1)
				(type default)
			)
			(layer "B.Fab")
		)
		(fp_line
			(start 0.67945 -0.305054)
			(end 0.12065 -0.305054)
			(stroke
				(width 0.1)
				(type default)
			)
			(layer "B.Fab")
		)
		(fp_line
			(start 0.67945 0.3048)
			(end 0.67945 -0.305054)
			(stroke
				(width 0.1)
				(type default)
			)
			(layer "B.Fab")
		)
		(pad "1" smd circle
			(at 0.40005 0 180)
			(size 0 0)
			(layers "B.Cu" "B.Mask" "B.Paste")
			(net "UART_PEX0_SDB_BUF_RX")
		)
		(pad "2" smd circle
			(at -0.40005 0 180)
			(size 0 0)
			(layers "B.Cu" "B.Mask" "B.Paste")
			(net "P1V8_PEX")
		)
	)
	(footprint ""
		(layer "B.Cu")
		(at 189.049914 -293.99992 180)
		(property "Reference" "C3124"
			(at 0 0 0)
			(layer "B.SilkS")
			(hide yes)
			(effects
				(font
					(size 1.27 1.27)
				)
				(justify mirror)
			)
		)
		(property "Value" ""
			(at 0 0 0)
			(layer "B.Fab")
			(effects
				(font
					(size 1.27 1.27)
				)
				(justify mirror)
			)
		)
		(duplicate_pad_numbers_are_jumpers no)
		(fp_line
			(start 0.299974 0.150114)
			(end 0.299974 -0.150114)
			(stroke
				(width 0.1)
				(type default)
			)
			(layer "B.Fab")
		)
		(fp_line
			(start 0.299974 -0.150114)
			(end -0.299974 -0.150114)
			(stroke
				(width 0.1)
				(type default)
			)
			(layer "B.Fab")
		)
		(fp_line
			(start -0.299974 0.150114)
			(end 0.299974 0.150114)
			(stroke
				(width 0.1)
				(type default)
			)
			(layer "B.Fab")
		)
		(fp_line
			(start -0.299974 -0.150114)
			(end -0.299974 0.150114)
			(stroke
				(width 0.1)
				(type default)
			)
			(layer "B.Fab")
		)
		(pad "1" smd rect
			(at 0.2667 0)
			(size 0.3048 0.381)
			(layers "B.Cu" "B.Mask" "B.Paste")
			(net "P1V25_SERDES_VDDPLL_PEX1")
		)
		(pad "2" smd rect
			(at -0.2667 0)
			(size 0.3048 0.381)
			(layers "B.Cu" "B.Mask" "B.Paste")
			(net "GND")
		)
	)
	(footprint ""
		(layer "B.Cu")
		(at 46.355 -294.4749)
		(property "Reference" "C3044"
			(at 0 0 0)
			(layer "B.SilkS")
			(hide yes)
			(effects
				(font
					(size 1.27 1.27)
				)
				(justify mirror)
			)
		)
		(property "Value" ""
			(at 0 0 0)
			(layer "B.Fab")
			(effects
				(font
					(size 1.27 1.27)
				)
				(justify mirror)
			)
		)
		(duplicate_pad_numbers_are_jumpers no)
		(fp_line
			(start -0.299974 -0.150114)
			(end -0.299974 0.150114)
			(stroke
				(width 0.1)
				(type default)
			)
			(layer "B.Fab")
		)
		(fp_line
			(start -0.299974 0.150114)
			(end 0.299974 0.150114)
			(stroke
				(width 0.1)
				(type default)
			)
			(layer "B.Fab")
		)
		(fp_line
			(start 0.299974 -0.150114)
			(end -0.299974 -0.150114)
			(stroke
				(width 0.1)
				(type default)
			)
			(layer "B.Fab")
		)
		(fp_line
			(start 0.299974 0.150114)
			(end 0.299974 -0.150114)
			(stroke
				(width 0.1)
				(type default)
			)
			(layer "B.Fab")
		)
		(pad "1" smd rect
			(at 0.2667 0 180)
			(size 0.3048 0.381)
			(layers "B.Cu" "B.Mask" "B.Paste")
			(net "PCEPLL4_VDDA18_PEX0")
		)
		(pad "2" smd rect
			(at -0.2667 0 180)
			(size 0.3048 0.381)
			(layers "B.Cu" "B.Mask" "B.Paste")
			(net "GND")
		)
	)
	(footprint ""
		(layer "B.Cu")
		(at 236.927136 -266.873228)
		(property "Reference" "L117"
			(at 0 0 0)
			(layer "B.SilkS")
			(hide yes)
			(effects
				(font
					(size 1.27 1.27)
				)
				(justify mirror)
			)
		)
		(property "Value" ""
			(at 0 0 0)
			(layer "B.Fab")
			(effects
				(font
					(size 1.27 1.27)
				)
				(justify mirror)
			)
		)
		(duplicate_pad_numbers_are_jumpers no)
		(fp_line
			(start -2.248154 -4.9911)
			(end 2.248154 -4.9911)
			(stroke
				(width 0.1524)
				(type default)
			)
			(layer "B.SilkS")
		)
		(fp_line
			(start -2.248154 -1.895094)
			(end -2.248154 -4.9911)
			(stroke
				(width 0.1524)
				(type default)
			)
			(layer "B.SilkS")
		)
		(fp_line
			(start -2.248154 4.9911)
			(end -2.248154 2.06883)
			(stroke
				(width 0.1524)
				(type default)
			)
			(layer "B.SilkS")
		)
		(fp_line
			(start 2.248154 -4.9911)
			(end 2.248154 -1.895094)
			(stroke
				(width 0.1524)
				(type default)
			)
			(layer "B.SilkS")
		)
		(fp_line
			(start 2.248154 2.06883)
			(end 2.248154 4.9911)
			(stroke
				(width 0.1524)
				(type default)
			)
			(layer "B.SilkS")
		)
		(fp_line
			(start 2.248154 4.9911)
			(end -2.248154 4.9911)
			(stroke
				(width 0.1524)
				(type default)
			)
			(layer "B.SilkS")
		)
		(fp_line
			(start -1.700022 -0.899922)
			(end 1.700022 -0.899922)
			(stroke
				(width 0.1)
				(type default)
			)
			(layer "B.Fab")
		)
		(fp_line
			(start -1.700022 0.899922)
			(end -1.700022 -0.899922)
			(stroke
				(width 0.1)
				(type default)
			)
			(layer "B.Fab")
		)
		(fp_line
			(start 1.700022 -0.899922)
			(end 1.700022 0.899922)
			(stroke
				(width 0.1)
				(type default)
			)
			(layer "B.Fab")
		)
		(fp_line
			(start 1.700022 0.899922)
			(end -1.700022 0.899922)
			(stroke
				(width 0.1)
				(type default)
			)
			(layer "B.Fab")
		)
		(pad "1" smd rect
			(at 1.575054 0 180)
			(size 1.1684 9.8044)
			(layers "B.Cu" "B.Mask" "B.Paste")
			(net "P1V25_PEX2")
		)
		(pad "2" smd rect
			(at -1.575054 0 180)
			(size 1.1684 9.8044)
			(layers "B.Cu" "B.Mask" "B.Paste")
			(net "P1V25_SERDES_VDDPLL_PEX2")
		)
	)
	(footprint ""
		(layer "B.Cu")
		(at 266.67968 -80.506316 180)
		(property "Reference" "C2630"
			(at 0 0 0)
			(layer "B.SilkS")
			(hide yes)
			(effects
				(font
					(size 1.27 1.27)
				)
				(justify mirror)
			)
		)
		(property "Value" ""
			(at 0 0 0)
			(layer "B.Fab")
			(effects
				(font
					(size 1.27 1.27)
				)
				(justify mirror)
			)
		)
		(duplicate_pad_numbers_are_jumpers no)
		(fp_line
			(start 1.2954 0.5842)
			(end 1.2954 -0.5842)
			(stroke
				(width 0.1524)
				(type default)
			)
			(layer "B.SilkS")
		)
		(fp_line
			(start 1.2954 -0.5842)
			(end -1.2954 -0.5842)
			(stroke
				(width 0.1524)
				(type default)
			)
			(layer "B.SilkS")
		)
		(fp_line
			(start -1.2954 0.5842)
			(end 1.2954 0.5842)
			(stroke
				(width 0.1524)
				(type default)
			)
			(layer "B.SilkS")
		)
		(fp_line
			(start -1.2954 -0.5842)
			(end -1.2954 0.5842)
			(stroke
				(width 0.1524)
				(type default)
			)
			(layer "B.SilkS")
		)
		(fp_line
			(start 1.1938 0.4064)
			(end 1.1938 -0.4064)
			(stroke
				(width 0.1)
				(type default)
			)
			(layer "B.Fab")
		)
		(fp_line
			(start 1.1938 -0.4064)
			(end 0.8636 -0.4064)
			(stroke
				(width 0.1)
				(type default)
			)
			(layer "B.Fab")
		)
		(fp_line
			(start 0.8636 0.4572)
			(end 0.8636 0.4064)
			(stroke
				(width 0.1)
				(type default)
			)
			(layer "B.Fab")
		)
		(fp_line
			(start 0.8636 0.4064)
			(end 1.1938 0.4064)
			(stroke
				(width 0.1)
				(type default)
			)
			(layer "B.Fab")
		)
		(fp_line
			(start 0.8636 -0.4064)
			(end 0.8636 -0.4572)
			(stroke
				(width 0.1)
				(type default)
			)
			(layer "B.Fab")
		)
		(fp_line
			(start 0.8636 -0.4572)
			(end -0.8636 -0.4572)
			(stroke
				(width 0.1)
				(type default)
			)
			(layer "B.Fab")
		)
		(fp_line
			(start -0.8636 0.4572)
			(end 0.8636 0.4572)
			(stroke
				(width 0.1)
				(type default)
			)
			(layer "B.Fab")
		)
		(fp_line
			(start -0.8636 0.4064)
			(end -0.8636 0.4572)
			(stroke
				(width 0.1)
				(type default)
			)
			(layer "B.Fab")
		)
		(fp_line
			(start -0.8636 -0.4064)
			(end -1.1938 -0.4064)
			(stroke
				(width 0.1)
				(type default)
			)
			(layer "B.Fab")
		)
		(fp_line
			(start -0.8636 -0.4572)
			(end -0.8636 -0.4064)
			(stroke
				(width 0.1)
				(type default)
			)
			(layer "B.Fab")
		)
		(fp_line
			(start -1.1938 0.4064)
			(end -0.8636 0.4064)
			(stroke
				(width 0.1)
				(type default)
			)
			(layer "B.Fab")
		)
		(fp_line
			(start -1.1938 -0.4064)
			(end -1.1938 0.4064)
			(stroke
				(width 0.1)
				(type default)
			)
			(layer "B.Fab")
		)
		(pad "1" smd rect
			(at 0.7366 0 90)
			(size 0.7112 0.8128)
			(layers "B.Cu" "B.Mask" "B.Paste")
			(net "P3V3_CLK_GEN_VDD_CK440")
		)
		(pad "2" smd rect
			(at -0.7366 0 90)
			(size 0.7112 0.8128)
			(layers "B.Cu" "B.Mask" "B.Paste")
			(net "GND")
		)
	)
	(footprint ""
		(layer "B.Cu")
		(at 72.949816 -294.94988 180)
		(property "Reference" "C2949"
			(at 0 0 0)
			(layer "B.SilkS")
			(hide yes)
			(effects
				(font
					(size 1.27 1.27)
				)
				(justify mirror)
			)
		)
		(property "Value" ""
			(at 0 0 0)
			(layer "B.Fab")
			(effects
				(font
					(size 1.27 1.27)
				)
				(justify mirror)
			)
		)
		(duplicate_pad_numbers_are_jumpers no)
		(fp_line
			(start 0.299974 0.150114)
			(end 0.299974 -0.150114)
			(stroke
				(width 0.1)
				(type default)
			)
			(layer "B.Fab")
		)
		(fp_line
			(start 0.299974 -0.150114)
			(end -0.299974 -0.150114)
			(stroke
				(width 0.1)
				(type default)
			)
			(layer "B.Fab")
		)
		(fp_line
			(start -0.299974 0.150114)
			(end 0.299974 0.150114)
			(stroke
				(width 0.1)
				(type default)
			)
			(layer "B.Fab")
		)
		(fp_line
			(start -0.299974 -0.150114)
			(end -0.299974 0.150114)
			(stroke
				(width 0.1)
				(type default)
			)
			(layer "B.Fab")
		)
		(pad "1" smd rect
			(at 0.2667 0)
			(size 0.3048 0.381)
			(layers "B.Cu" "B.Mask" "B.Paste")
			(net "P1V25_SERDES_VDDPLL_PEX0")
		)
		(pad "2" smd rect
			(at -0.2667 0)
			(size 0.3048 0.381)
			(layers "B.Cu" "B.Mask" "B.Paste")
			(net "GND")
		)
	)
	(footprint ""
		(layer "B.Cu")
		(at 230.763318 -143.815054 -90)
		(property "Reference" "C2794"
			(at 0 0 90)
			(layer "B.SilkS")
			(hide yes)
			(effects
				(font
					(size 1.27 1.27)
				)
				(justify mirror)
			)
		)
		(property "Value" ""
			(at 0 0 90)
			(layer "B.Fab")
			(effects
				(font
					(size 1.27 1.27)
				)
				(justify mirror)
			)
		)
		(duplicate_pad_numbers_are_jumpers no)
		(fp_line
			(start -0.7874 0.4064)
			(end 0.7874 0.4064)
			(stroke
				(width 0.1524)
				(type default)
			)
			(layer "B.SilkS")
		)
		(fp_line
			(start 0.7874 0.4064)
			(end 0.7874 -0.4064)
			(stroke
				(width 0.1524)
				(type default)
			)
			(layer "B.SilkS")
		)
		(fp_line
			(start -0.7874 -0.4064)
			(end -0.7874 0.4064)
			(stroke
				(width 0.1524)
				(type default)
			)
			(layer "B.SilkS")
		)
		(fp_line
			(start 0.7874 -0.4064)
			(end -0.7874 -0.4064)
			(stroke
				(width 0.1524)
				(type default)
			)
			(layer "B.SilkS")
		)
		(fp_line
			(start -0.67945 0.3048)
			(end -0.120396 0.3048)
			(stroke
				(width 0.1)
				(type default)
			)
			(layer "B.Fab")
		)
		(fp_line
			(start -0.120396 0.3048)
			(end -0.120396 0.2794)
			(stroke
				(width 0.1)
				(type default)
			)
			(layer "B.Fab")
		)
		(fp_line
			(start 0.12065 0.3048)
			(end 0.67945 0.3048)
			(stroke
				(width 0.1)
				(type default)
			)
			(layer "B.Fab")
		)
		(fp_line
			(start 0.67945 0.3048)
			(end 0.67945 -0.305054)
			(stroke
				(width 0.1)
				(type default)
			)
			(layer "B.Fab")
		)
		(fp_line
			(start -0.120396 0.2794)
			(end 0.12065 0.2794)
			(stroke
				(width 0.1)
				(type default)
			)
			(layer "B.Fab")
		)
		(fp_line
			(start 0.12065 0.2794)
			(end 0.12065 0.3048)
			(stroke
				(width 0.1)
				(type default)
			)
			(layer "B.Fab")
		)
		(fp_line
			(start -0.12065 -0.2794)
			(end -0.12065 -0.3048)
			(stroke
				(width 0.1)
				(type default)
			)
			(layer "B.Fab")
		)
		(fp_line
			(start 0.12065 -0.2794)
			(end -0.12065 -0.2794)
			(stroke
				(width 0.1)
				(type default)
			)
			(layer "B.Fab")
		)
		(fp_line
			(start -0.67945 -0.3048)
			(end -0.67945 0.3048)
			(stroke
				(width 0.1)
				(type default)
			)
			(layer "B.Fab")
		)
		(fp_line
			(start -0.12065 -0.3048)
			(end -0.67945 -0.3048)
			(stroke
				(width 0.1)
				(type default)
			)
			(layer "B.Fab")
		)
		(fp_line
			(start 0.12065 -0.305054)
			(end 0.12065 -0.2794)
			(stroke
				(width 0.1)
				(type default)
			)
			(layer "B.Fab")
		)
		(fp_line
			(start 0.67945 -0.305054)
			(end 0.12065 -0.305054)
			(stroke
				(width 0.1)
				(type default)
			)
			(layer "B.Fab")
		)
		(pad "1" smd circle
			(at 0.40005 0 90)
			(size 0 0)
			(layers "B.Cu" "B.Mask" "B.Paste")
			(net "P3V3_CLK_GEN_VDDXTAL_CK440_PEX")
		)
		(pad "2" smd circle
			(at -0.40005 0 90)
			(size 0 0)
			(layers "B.Cu" "B.Mask" "B.Paste")
			(net "GND")
		)
	)
	(footprint ""
		(layer "B.Cu")
		(at 236.887512 -234.728004 90)
		(property "Reference" "R6197"
			(at 0 0 90)
			(layer "B.SilkS")
			(hide yes)
			(effects
				(font
					(size 1.27 1.27)
				)
				(justify mirror)
			)
		)
		(property "Value" ""
			(at 0 0 90)
			(layer "B.Fab")
			(effects
				(font
					(size 1.27 1.27)
				)
				(justify mirror)
			)
		)
		(duplicate_pad_numbers_are_jumpers no)
		(fp_line
			(start 0.7874 -0.4064)
			(end -0.7874 -0.4064)
			(stroke
				(width 0.1524)
				(type default)
			)
			(layer "B.SilkS")
		)
		(fp_line
			(start -0.7874 -0.4064)
			(end -0.7874 0.4064)
			(stroke
				(width 0.1524)
				(type default)
			)
			(layer "B.SilkS")
		)
		(fp_line
			(start 0.7874 0.4064)
			(end 0.7874 -0.4064)
			(stroke
				(width 0.1524)
				(type default)
			)
			(layer "B.SilkS")
		)
		(fp_line
			(start -0.7874 0.4064)
			(end 0.7874 0.4064)
			(stroke
				(width 0.1524)
				(type default)
			)
			(layer "B.SilkS")
		)
		(fp_line
			(start 0.67945 -0.305054)
			(end 0.12065 -0.305054)
			(stroke
				(width 0.1)
				(type default)
			)
			(layer "B.Fab")
		)
		(fp_line
			(start 0.12065 -0.305054)
			(end 0.12065 -0.2794)
			(stroke
				(width 0.1)
				(type default)
			)
			(layer "B.Fab")
		)
		(fp_line
			(start -0.12065 -0.3048)
			(end -0.67945 -0.3048)
			(stroke
				(width 0.1)
				(type default)
			)
			(layer "B.Fab")
		)
		(fp_line
			(start -0.67945 -0.3048)
			(end -0.67945 0.3048)
			(stroke
				(width 0.1)
				(type default)
			)
			(layer "B.Fab")
		)
		(fp_line
			(start 0.12065 -0.2794)
			(end -0.12065 -0.2794)
			(stroke
				(width 0.1)
				(type default)
			)
			(layer "B.Fab")
		)
		(fp_line
			(start -0.12065 -0.2794)
			(end -0.12065 -0.3048)
			(stroke
				(width 0.1)
				(type default)
			)
			(layer "B.Fab")
		)
		(fp_line
			(start 0.12065 0.2794)
			(end 0.12065 0.3048)
			(stroke
				(width 0.1)
				(type default)
			)
			(layer "B.Fab")
		)
		(fp_line
			(start -0.120396 0.2794)
			(end 0.12065 0.2794)
			(stroke
				(width 0.1)
				(type default)
			)
			(layer "B.Fab")
		)
		(fp_line
			(start 0.67945 0.3048)
			(end 0.67945 -0.305054)
			(stroke
				(width 0.1)
				(type default)
			)
			(layer "B.Fab")
		)
		(fp_line
			(start 0.12065 0.3048)
			(end 0.67945 0.3048)
			(stroke
				(width 0.1)
				(type default)
			)
			(layer "B.Fab")
		)
		(fp_line
			(start -0.120396 0.3048)
			(end -0.120396 0.2794)
			(stroke
				(width 0.1)
				(type default)
			)
			(layer "B.Fab")
		)
		(fp_line
			(start -0.67945 0.3048)
			(end -0.120396 0.3048)
			(stroke
				(width 0.1)
				(type default)
			)
			(layer "B.Fab")
		)
		(pad "1" smd circle
			(at 0.40005 0 270)
			(size 0 0)
			(layers "B.Cu" "B.Mask" "B.Paste")
			(net "GND")
		)
		(pad "2" smd circle
			(at -0.40005 0 270)
			(size 0 0)
			(layers "B.Cu" "B.Mask" "B.Paste")
			(net "SSD15_PWRDIS_BIC_R")
		)
	)
	(footprint ""
		(layer "B.Cu")
		(at 343.693242 -221.98711 90)
		(property "Reference" "C2033"
			(at 0 0 90)
			(layer "B.SilkS")
			(hide yes)
			(effects
				(font
					(size 1.27 1.27)
				)
				(justify mirror)
			)
		)
		(property "Value" ""
			(at 0 0 90)
			(layer "B.Fab")
			(effects
				(font
					(size 1.27 1.27)
				)
				(justify mirror)
			)
		)
		(duplicate_pad_numbers_are_jumpers no)
		(fp_line
			(start 0.69215 -0.2921)
			(end -0.69215 -0.2921)
			(stroke
				(width 0.1524)
				(type default)
			)
			(layer "B.SilkS")
		)
		(fp_line
			(start -0.69215 -0.2921)
			(end -0.69215 0.2921)
			(stroke
				(width 0.1524)
				(type default)
			)
			(layer "B.SilkS")
		)
		(fp_line
			(start 0.69215 0.2921)
			(end 0.69215 -0.2921)
			(stroke
				(width 0.1524)
				(type default)
			)
			(layer "B.SilkS")
		)
		(fp_line
			(start -0.69215 0.2921)
			(end 0.69215 0.2921)
			(stroke
				(width 0.1524)
				(type default)
			)
			(layer "B.SilkS")
		)
		(fp_line
			(start 0.51435 -0.2794)
			(end -0.51435 -0.2794)
			(stroke
				(width 0.1)
				(type default)
			)
			(layer "B.Fab")
		)
		(fp_line
			(start -0.51435 -0.2794)
			(end -0.51435 0.2794)
			(stroke
				(width 0.1)
				(type default)
			)
			(layer "B.Fab")
		)
		(fp_line
			(start 0.51435 0.2794)
			(end 0.51435 -0.2794)
			(stroke
				(width 0.1)
				(type default)
			)
			(layer "B.Fab")
		)
		(fp_line
			(start -0.51435 0.2794)
			(end 0.51435 0.2794)
			(stroke
				(width 0.1)
				(type default)
			)
			(layer "B.Fab")
		)
		(pad "1" smd circle
			(at 0.40005 0 270)
			(size 0 0)
			(layers "B.Cu" "B.Mask" "B.Paste")
			(net "P3V3_FPGA_VCCIO0")
		)
		(pad "2" smd circle
			(at -0.40005 0 270)
			(size 0 0)
			(layers "B.Cu" "B.Mask" "B.Paste")
			(net "GND")
		)
		(zone
			(layer "B.Cu")
			(hatch none 0.5)
			(connect_pads
				(clearance 0)
			)
			(min_thickness 0.25)
			(keepout
				(tracks not_allowed)
				(vias allowed)
				(pads allowed)
				(copperpour not_allowed)
				(footprints allowed)
			)
			(placement
				(enabled no)
				(sheetname "")
			)
			(fill
				(thermal_gap 0.5)
				(thermal_bridge_width 0.5)
				(island_removal_mode 0)
			)
			(polygon
				(pts
					(xy 343.780872 -222.17761) (xy 343.839038 -222.08617) (xy 343.839038 -221.88678) (xy 343.780872 -221.79661)
					(xy 343.605612 -221.79661) (xy 343.547192 -221.88678) (xy 343.547192 -222.08617) (xy 343.605358 -222.17761)
				)
			)
		)
	)
	(footprint ""
		(layer "B.Cu")
		(at 134.239 -282.040584 90)
		(property "Reference" "PR113"
			(at 0 0 90)
			(layer "B.SilkS")
			(hide yes)
			(effects
				(font
					(size 1.27 1.27)
				)
				(justify mirror)
			)
		)
		(property "Value" ""
			(at 0 0 90)
			(layer "B.Fab")
			(effects
				(font
					(size 1.27 1.27)
				)
				(justify mirror)
			)
		)
		(duplicate_pad_numbers_are_jumpers no)
		(fp_line
			(start 0.7874 -0.4064)
			(end -0.7874 -0.4064)
			(stroke
				(width 0.1524)
				(type default)
			)
			(layer "B.SilkS")
		)
		(fp_line
			(start -0.7874 -0.4064)
			(end -0.7874 0.4064)
			(stroke
				(width 0.1524)
				(type default)
			)
			(layer "B.SilkS")
		)
		(fp_line
			(start 0.7874 0.4064)
			(end 0.7874 -0.4064)
			(stroke
				(width 0.1524)
				(type default)
			)
			(layer "B.SilkS")
		)
		(fp_line
			(start -0.7874 0.4064)
			(end 0.7874 0.4064)
			(stroke
				(width 0.1524)
				(type default)
			)
			(layer "B.SilkS")
		)
		(fp_line
			(start 0.67945 -0.305054)
			(end 0.12065 -0.305054)
			(stroke
				(width 0.1)
				(type default)
			)
			(layer "B.Fab")
		)
		(fp_line
			(start 0.12065 -0.305054)
			(end 0.12065 -0.2794)
			(stroke
				(width 0.1)
				(type default)
			)
			(layer "B.Fab")
		)
		(fp_line
			(start -0.12065 -0.3048)
			(end -0.67945 -0.3048)
			(stroke
				(width 0.1)
				(type default)
			)
			(layer "B.Fab")
		)
		(fp_line
			(start -0.67945 -0.3048)
			(end -0.67945 0.3048)
			(stroke
				(width 0.1)
				(type default)
			)
			(layer "B.Fab")
		)
		(fp_line
			(start 0.12065 -0.2794)
			(end -0.12065 -0.2794)
			(stroke
				(width 0.1)
				(type default)
			)
			(layer "B.Fab")
		)
		(fp_line
			(start -0.12065 -0.2794)
			(end -0.12065 -0.3048)
			(stroke
				(width 0.1)
				(type default)
			)
			(layer "B.Fab")
		)
		(fp_line
			(start 0.12065 0.2794)
			(end 0.12065 0.3048)
			(stroke
				(width 0.1)
				(type default)
			)
			(layer "B.Fab")
		)
		(fp_line
			(start -0.120396 0.2794)
			(end 0.12065 0.2794)
			(stroke
				(width 0.1)
				(type default)
			)
			(layer "B.Fab")
		)
		(fp_line
			(start 0.67945 0.3048)
			(end 0.67945 -0.305054)
			(stroke
				(width 0.1)
				(type default)
			)
			(layer "B.Fab")
		)
		(fp_line
			(start 0.12065 0.3048)
			(end 0.67945 0.3048)
			(stroke
				(width 0.1)
				(type default)
			)
			(layer "B.Fab")
		)
		(fp_line
			(start -0.120396 0.3048)
			(end -0.120396 0.2794)
			(stroke
				(width 0.1)
				(type default)
			)
			(layer "B.Fab")
		)
		(fp_line
			(start -0.67945 0.3048)
			(end -0.120396 0.3048)
			(stroke
				(width 0.1)
				(type default)
			)
			(layer "B.Fab")
		)
		(pad "1" smd circle
			(at 0.40005 0 270)
			(size 0 0)
			(layers "B.Cu" "B.Mask" "B.Paste")
			(net "SW_P0V8_PEX1_VOS2")
		)
		(pad "2" smd circle
			(at -0.40005 0 270)
			(size 0 0)
			(layers "B.Cu" "B.Mask" "B.Paste")
			(net "P0V8_PEX1")
		)
	)
	(footprint ""
		(layer "B.Cu")
		(at 243.3193 -207.982566 180)
		(property "Reference" "C2020"
			(at 0 0 0)
			(layer "B.SilkS")
			(hide yes)
			(effects
				(font
					(size 1.27 1.27)
				)
				(justify mirror)
			)
		)
		(property "Value" ""
			(at 0 0 0)
			(layer "B.Fab")
			(effects
				(font
					(size 1.27 1.27)
				)
				(justify mirror)
			)
		)
		(duplicate_pad_numbers_are_jumpers no)
		(fp_line
			(start 1.2954 0.5842)
			(end 1.2954 -0.5842)
			(stroke
				(width 0.1524)
				(type default)
			)
			(layer "B.SilkS")
		)
		(fp_line
			(start 1.2954 -0.5842)
			(end -1.2954 -0.5842)
			(stroke
				(width 0.1524)
				(type default)
			)
			(layer "B.SilkS")
		)
		(fp_line
			(start -1.2954 0.5842)
			(end 1.2954 0.5842)
			(stroke
				(width 0.1524)
				(type default)
			)
			(layer "B.SilkS")
		)
		(fp_line
			(start -1.2954 -0.5842)
			(end -1.2954 0.5842)
			(stroke
				(width 0.1524)
				(type default)
			)
			(layer "B.SilkS")
		)
		(fp_line
			(start 1.1938 0.4064)
			(end 1.1938 -0.4064)
			(stroke
				(width 0.1)
				(type default)
			)
			(layer "B.Fab")
		)
		(fp_line
			(start 1.1938 -0.4064)
			(end 0.8636 -0.4064)
			(stroke
				(width 0.1)
				(type default)
			)
			(layer "B.Fab")
		)
		(fp_line
			(start 0.8636 0.4572)
			(end 0.8636 0.4064)
			(stroke
				(width 0.1)
				(type default)
			)
			(layer "B.Fab")
		)
		(fp_line
			(start 0.8636 0.4064)
			(end 1.1938 0.4064)
			(stroke
				(width 0.1)
				(type default)
			)
			(layer "B.Fab")
		)
		(fp_line
			(start 0.8636 -0.4064)
			(end 0.8636 -0.4572)
			(stroke
				(width 0.1)
				(type default)
			)
			(layer "B.Fab")
		)
		(fp_line
			(start 0.8636 -0.4572)
			(end -0.8636 -0.4572)
			(stroke
				(width 0.1)
				(type default)
			)
			(layer "B.Fab")
		)
		(fp_line
			(start -0.8636 0.4572)
			(end 0.8636 0.4572)
			(stroke
				(width 0.1)
				(type default)
			)
			(layer "B.Fab")
		)
		(fp_line
			(start -0.8636 0.4064)
			(end -0.8636 0.4572)
			(stroke
				(width 0.1)
				(type default)
			)
			(layer "B.Fab")
		)
		(fp_line
			(start -0.8636 -0.4064)
			(end -1.1938 -0.4064)
			(stroke
				(width 0.1)
				(type default)
			)
			(layer "B.Fab")
		)
		(fp_line
			(start -0.8636 -0.4572)
			(end -0.8636 -0.4064)
			(stroke
				(width 0.1)
				(type default)
			)
			(layer "B.Fab")
		)
		(fp_line
			(start -1.1938 0.4064)
			(end -0.8636 0.4064)
			(stroke
				(width 0.1)
				(type default)
			)
			(layer "B.Fab")
		)
		(fp_line
			(start -1.1938 -0.4064)
			(end -1.1938 0.4064)
			(stroke
				(width 0.1)
				(type default)
			)
			(layer "B.Fab")
		)
		(pad "1" smd rect
			(at 0.7366 0 90)
			(size 0.7112 0.8128)
			(layers "B.Cu" "B.Mask" "B.Paste")
			(net "P1V2_AUX")
		)
		(pad "2" smd rect
			(at -0.7366 0 90)
			(size 0.7112 0.8128)
			(layers "B.Cu" "B.Mask" "B.Paste")
			(net "GND")
		)
	)
	(footprint ""
		(layer "B.Cu")
		(at 236.015784 -91.472766)
		(property "Reference" "C2617"
			(at 0 0 0)
			(layer "B.SilkS")
			(hide yes)
			(effects
				(font
					(size 1.27 1.27)
				)
				(justify mirror)
			)
		)
		(property "Value" ""
			(at 0 0 0)
			(layer "B.Fab")
			(effects
				(font
					(size 1.27 1.27)
				)
				(justify mirror)
			)
		)
		(duplicate_pad_numbers_are_jumpers no)
		(fp_line
			(start -0.7874 -0.4064)
			(end -0.7874 0.4064)
			(stroke
				(width 0.1524)
				(type default)
			)
			(layer "B.SilkS")
		)
		(fp_line
			(start -0.7874 0.4064)
			(end 0.7874 0.4064)
			(stroke
				(width 0.1524)
				(type default)
			)
			(layer "B.SilkS")
		)
		(fp_line
			(start 0.7874 -0.4064)
			(end -0.7874 -0.4064)
			(stroke
				(width 0.1524)
				(type default)
			)
			(layer "B.SilkS")
		)
		(fp_line
			(start 0.7874 0.4064)
			(end 0.7874 -0.4064)
			(stroke
				(width 0.1524)
				(type default)
			)
			(layer "B.SilkS")
		)
		(fp_line
			(start -0.67945 -0.3048)
			(end -0.67945 0.3048)
			(stroke
				(width 0.1)
				(type default)
			)
			(layer "B.Fab")
		)
		(fp_line
			(start -0.67945 0.3048)
			(end -0.120396 0.3048)
			(stroke
				(width 0.1)
				(type default)
			)
			(layer "B.Fab")
		)
		(fp_line
			(start -0.12065 -0.3048)
			(end -0.67945 -0.3048)
			(stroke
				(width 0.1)
				(type default)
			)
			(layer "B.Fab")
		)
		(fp_line
			(start -0.12065 -0.2794)
			(end -0.12065 -0.3048)
			(stroke
				(width 0.1)
				(type default)
			)
			(layer "B.Fab")
		)
		(fp_line
			(start -0.120396 0.2794)
			(end 0.12065 0.2794)
			(stroke
				(width 0.1)
				(type default)
			)
			(layer "B.Fab")
		)
		(fp_line
			(start -0.120396 0.3048)
			(end -0.120396 0.2794)
			(stroke
				(width 0.1)
				(type default)
			)
			(layer "B.Fab")
		)
		(fp_line
			(start 0.12065 -0.305054)
			(end 0.12065 -0.2794)
			(stroke
				(width 0.1)
				(type default)
			)
			(layer "B.Fab")
		)
		(fp_line
			(start 0.12065 -0.2794)
			(end -0.12065 -0.2794)
			(stroke
				(width 0.1)
				(type default)
			)
			(layer "B.Fab")
		)
		(fp_line
			(start 0.12065 0.2794)
			(end 0.12065 0.3048)
			(stroke
				(width 0.1)
				(type default)
			)
			(layer "B.Fab")
		)
		(fp_line
			(start 0.12065 0.3048)
			(end 0.67945 0.3048)
			(stroke
				(width 0.1)
				(type default)
			)
			(layer "B.Fab")
		)
		(fp_line
			(start 0.67945 -0.305054)
			(end 0.12065 -0.305054)
			(stroke
				(width 0.1)
				(type default)
			)
			(layer "B.Fab")
		)
		(fp_line
			(start 0.67945 0.3048)
			(end 0.67945 -0.305054)
			(stroke
				(width 0.1)
				(type default)
			)
			(layer "B.Fab")
		)
		(pad "1" smd circle
			(at 0.40005 0 180)
			(size 0 0)
			(layers "B.Cu" "B.Mask" "B.Paste")
			(net "P3V3_PEX_USB_HUB")
		)
		(pad "2" smd circle
			(at -0.40005 0 180)
			(size 0 0)
			(layers "B.Cu" "B.Mask" "B.Paste")
			(net "GND")
		)
	)
	(footprint ""
		(layer "B.Cu")
		(at 57.220104 -305.399948 -90)
		(property "Reference" "C2974"
			(at 0 0 90)
			(layer "B.SilkS")
			(hide yes)
			(effects
				(font
					(size 1.27 1.27)
				)
				(justify mirror)
			)
		)
		(property "Value" ""
			(at 0 0 90)
			(layer "B.Fab")
			(effects
				(font
					(size 1.27 1.27)
				)
				(justify mirror)
			)
		)
		(duplicate_pad_numbers_are_jumpers no)
		(fp_line
			(start -0.299974 0.150114)
			(end 0.299974 0.150114)
			(stroke
				(width 0.1)
				(type default)
			)
			(layer "B.Fab")
		)
		(fp_line
			(start 0.299974 0.150114)
			(end 0.299974 -0.150114)
			(stroke
				(width 0.1)
				(type default)
			)
			(layer "B.Fab")
		)
		(fp_line
			(start -0.299974 -0.150114)
			(end -0.299974 0.150114)
			(stroke
				(width 0.1)
				(type default)
			)
			(layer "B.Fab")
		)
		(fp_line
			(start 0.299974 -0.150114)
			(end -0.299974 -0.150114)
			(stroke
				(width 0.1)
				(type default)
			)
			(layer "B.Fab")
		)
		(pad "1" smd rect
			(at 0.2667 0 90)
			(size 0.3048 0.381)
			(layers "B.Cu" "B.Mask" "B.Paste")
			(net "P1V25_SERDES_VDDPLL_PEX0")
		)
		(pad "2" smd rect
			(at -0.2667 0 90)
			(size 0.3048 0.381)
			(layers "B.Cu" "B.Mask" "B.Paste")
			(net "GND")
		)
	)
	(footprint ""
		(layer "B.Cu")
		(at 396.0749 -294.132 -90)
		(property "Reference" "C3569"
			(at 0 0 90)
			(layer "B.SilkS")
			(hide yes)
			(effects
				(font
					(size 1.27 1.27)
				)
				(justify mirror)
			)
		)
		(property "Value" ""
			(at 0 0 90)
			(layer "B.Fab")
			(effects
				(font
					(size 1.27 1.27)
				)
				(justify mirror)
			)
		)
		(duplicate_pad_numbers_are_jumpers no)
		(fp_line
			(start -0.299974 0.150114)
			(end 0.299974 0.150114)
			(stroke
				(width 0.1)
				(type default)
			)
			(layer "B.Fab")
		)
		(fp_line
			(start 0.299974 0.150114)
			(end 0.299974 -0.150114)
			(stroke
				(width 0.1)
				(type default)
			)
			(layer "B.Fab")
		)
		(fp_line
			(start -0.299974 -0.150114)
			(end -0.299974 0.150114)
			(stroke
				(width 0.1)
				(type default)
			)
			(layer "B.Fab")
		)
		(fp_line
			(start 0.299974 -0.150114)
			(end -0.299974 -0.150114)
			(stroke
				(width 0.1)
				(type default)
			)
			(layer "B.Fab")
		)
		(pad "1" smd rect
			(at 0.2667 0 90)
			(size 0.3048 0.381)
			(layers "B.Cu" "B.Mask" "B.Paste")
			(net "PCEPLL5_VDDA18_PEX3")
		)
		(pad "2" smd rect
			(at -0.2667 0 90)
			(size 0.3048 0.381)
			(layers "B.Cu" "B.Mask" "B.Paste")
			(net "GND")
		)
	)
	(footprint ""
		(layer "B.Cu")
		(at 224.848674 -371.055138 180)
		(property "Reference" "PR31"
			(at 0 0 0)
			(layer "B.SilkS")
			(hide yes)
			(effects
				(font
					(size 1.27 1.27)
				)
				(justify mirror)
			)
		)
		(property "Value" ""
			(at 0 0 0)
			(layer "B.Fab")
			(effects
				(font
					(size 1.27 1.27)
				)
				(justify mirror)
			)
		)
		(duplicate_pad_numbers_are_jumpers no)
		(fp_line
			(start 0.7874 0.4064)
			(end 0.7874 -0.4064)
			(stroke
				(width 0.1524)
				(type default)
			)
			(layer "B.SilkS")
		)
		(fp_line
			(start 0.7874 -0.4064)
			(end -0.7874 -0.4064)
			(stroke
				(width 0.1524)
				(type default)
			)
			(layer "B.SilkS")
		)
		(fp_line
			(start -0.7874 0.4064)
			(end 0.7874 0.4064)
			(stroke
				(width 0.1524)
				(type default)
			)
			(layer "B.SilkS")
		)
		(fp_line
			(start -0.7874 -0.4064)
			(end -0.7874 0.4064)
			(stroke
				(width 0.1524)
				(type default)
			)
			(layer "B.SilkS")
		)
		(fp_line
			(start 0.67945 0.3048)
			(end 0.67945 -0.305054)
			(stroke
				(width 0.1)
				(type default)
			)
			(layer "B.Fab")
		)
		(fp_line
			(start 0.67945 -0.305054)
			(end 0.12065 -0.305054)
			(stroke
				(width 0.1)
				(type default)
			)
			(layer "B.Fab")
		)
		(fp_line
			(start 0.12065 0.3048)
			(end 0.67945 0.3048)
			(stroke
				(width 0.1)
				(type default)
			)
			(layer "B.Fab")
		)
		(fp_line
			(start 0.12065 0.2794)
			(end 0.12065 0.3048)
			(stroke
				(width 0.1)
				(type default)
			)
			(layer "B.Fab")
		)
		(fp_line
			(start 0.12065 -0.2794)
			(end -0.12065 -0.2794)
			(stroke
				(width 0.1)
				(type default)
			)
			(layer "B.Fab")
		)
		(fp_line
			(start 0.12065 -0.305054)
			(end 0.12065 -0.2794)
			(stroke
				(width 0.1)
				(type default)
			)
			(layer "B.Fab")
		)
		(fp_line
			(start -0.120396 0.3048)
			(end -0.120396 0.2794)
			(stroke
				(width 0.1)
				(type default)
			)
			(layer "B.Fab")
		)
		(fp_line
			(start -0.120396 0.2794)
			(end 0.12065 0.2794)
			(stroke
				(width 0.1)
				(type default)
			)
			(layer "B.Fab")
		)
		(fp_line
			(start -0.12065 -0.2794)
			(end -0.12065 -0.3048)
			(stroke
				(width 0.1)
				(type default)
			)
			(layer "B.Fab")
		)
		(fp_line
			(start -0.12065 -0.3048)
			(end -0.67945 -0.3048)
			(stroke
				(width 0.1)
				(type default)
			)
			(layer "B.Fab")
		)
		(fp_line
			(start -0.67945 0.3048)
			(end -0.120396 0.3048)
			(stroke
				(width 0.1)
				(type default)
			)
			(layer "B.Fab")
		)
		(fp_line
			(start -0.67945 -0.3048)
			(end -0.67945 0.3048)
			(stroke
				(width 0.1)
				(type default)
			)
			(layer "B.Fab")
		)
		(pad "1" smd circle
			(at 0.40005 0)
			(size 0 0)
			(layers "B.Cu" "B.Mask" "B.Paste")
			(net "HSC_FAULT_N_1")
		)
		(pad "2" smd circle
			(at -0.40005 0)
			(size 0 0)
			(layers "B.Cu" "B.Mask" "B.Paste")
			(net "HSC_FAULT_N")
		)
	)
	(footprint ""
		(layer "B.Cu")
		(at 244.782086 -284.252162 180)
		(property "Reference" "PC253"
			(at 0 0 0)
			(layer "B.SilkS")
			(hide yes)
			(effects
				(font
					(size 1.27 1.27)
				)
				(justify mirror)
			)
		)
		(property "Value" ""
			(at 0 0 0)
			(layer "B.Fab")
			(effects
				(font
					(size 1.27 1.27)
				)
				(justify mirror)
			)
		)
		(duplicate_pad_numbers_are_jumpers no)
		(fp_line
			(start 1.524 0.762)
			(end 1.524 -0.762)
			(stroke
				(width 0.1524)
				(type default)
			)
			(layer "B.SilkS")
		)
		(fp_line
			(start 1.524 -0.762)
			(end -1.524 -0.762)
			(stroke
				(width 0.1524)
				(type default)
			)
			(layer "B.SilkS")
		)
		(fp_line
			(start -1.524 0.762)
			(end 1.524 0.762)
			(stroke
				(width 0.1524)
				(type default)
			)
			(layer "B.SilkS")
		)
		(fp_line
			(start -1.524 -0.762)
			(end -1.524 0.762)
			(stroke
				(width 0.1524)
				(type default)
			)
			(layer "B.SilkS")
		)
		(fp_line
			(start 1.1049 0.724916)
			(end -1.1049 0.724916)
			(stroke
				(width 0.1)
				(type default)
			)
			(layer "B.Fab")
		)
		(fp_line
			(start 1.1049 -0.724916)
			(end 1.1049 0.724916)
			(stroke
				(width 0.1)
				(type default)
			)
			(layer "B.Fab")
		)
		(fp_line
			(start -1.1049 0.724916)
			(end -1.1049 -0.724916)
			(stroke
				(width 0.1)
				(type default)
			)
			(layer "B.Fab")
		)
		(fp_line
			(start -1.1049 -0.724916)
			(end 1.1049 -0.724916)
			(stroke
				(width 0.1)
				(type default)
			)
			(layer "B.Fab")
		)
		(pad "1" smd rect
			(at 0.889 0 180)
			(size 1.016 1.27)
			(layers "B.Cu" "B.Mask" "B.Paste")
			(net "P1V25_PEX2_R")
		)
		(pad "2" smd rect
			(at -0.889 0 180)
			(size 1.016 1.27)
			(layers "B.Cu" "B.Mask" "B.Paste")
			(net "GND")
		)
	)
	(footprint ""
		(layer "B.Cu")
		(at 193.641726 -100.056696 180)
		(property "Reference" "R179"
			(at 0 0 0)
			(layer "B.SilkS")
			(hide yes)
			(effects
				(font
					(size 1.27 1.27)
				)
				(justify mirror)
			)
		)
		(property "Value" ""
			(at 0 0 0)
			(layer "B.Fab")
			(effects
				(font
					(size 1.27 1.27)
				)
				(justify mirror)
			)
		)
		(duplicate_pad_numbers_are_jumpers no)
		(fp_line
			(start 0.7874 0.4064)
			(end 0.7874 -0.4064)
			(stroke
				(width 0.1524)
				(type default)
			)
			(layer "B.SilkS")
		)
		(fp_line
			(start 0.7874 -0.4064)
			(end -0.7874 -0.4064)
			(stroke
				(width 0.1524)
				(type default)
			)
			(layer "B.SilkS")
		)
		(fp_line
			(start -0.7874 0.4064)
			(end 0.7874 0.4064)
			(stroke
				(width 0.1524)
				(type default)
			)
			(layer "B.SilkS")
		)
		(fp_line
			(start -0.7874 -0.4064)
			(end -0.7874 0.4064)
			(stroke
				(width 0.1524)
				(type default)
			)
			(layer "B.SilkS")
		)
		(fp_line
			(start 0.67945 0.3048)
			(end 0.67945 -0.305054)
			(stroke
				(width 0.1)
				(type default)
			)
			(layer "B.Fab")
		)
		(fp_line
			(start 0.67945 -0.305054)
			(end 0.12065 -0.305054)
			(stroke
				(width 0.1)
				(type default)
			)
			(layer "B.Fab")
		)
		(fp_line
			(start 0.12065 0.3048)
			(end 0.67945 0.3048)
			(stroke
				(width 0.1)
				(type default)
			)
			(layer "B.Fab")
		)
		(fp_line
			(start 0.12065 0.2794)
			(end 0.12065 0.3048)
			(stroke
				(width 0.1)
				(type default)
			)
			(layer "B.Fab")
		)
		(fp_line
			(start 0.12065 -0.2794)
			(end -0.12065 -0.2794)
			(stroke
				(width 0.1)
				(type default)
			)
			(layer "B.Fab")
		)
		(fp_line
			(start 0.12065 -0.305054)
			(end 0.12065 -0.2794)
			(stroke
				(width 0.1)
				(type default)
			)
			(layer "B.Fab")
		)
		(fp_line
			(start -0.120396 0.3048)
			(end -0.120396 0.2794)
			(stroke
				(width 0.1)
				(type default)
			)
			(layer "B.Fab")
		)
		(fp_line
			(start -0.120396 0.2794)
			(end 0.12065 0.2794)
			(stroke
				(width 0.1)
				(type default)
			)
			(layer "B.Fab")
		)
		(fp_line
			(start -0.12065 -0.2794)
			(end -0.12065 -0.3048)
			(stroke
				(width 0.1)
				(type default)
			)
			(layer "B.Fab")
		)
		(fp_line
			(start -0.12065 -0.3048)
			(end -0.67945 -0.3048)
			(stroke
				(width 0.1)
				(type default)
			)
			(layer "B.Fab")
		)
		(fp_line
			(start -0.67945 0.3048)
			(end -0.120396 0.3048)
			(stroke
				(width 0.1)
				(type default)
			)
			(layer "B.Fab")
		)
		(fp_line
			(start -0.67945 -0.3048)
			(end -0.67945 0.3048)
			(stroke
				(width 0.1)
				(type default)
			)
			(layer "B.Fab")
		)
		(pad "1" smd circle
			(at 0.40005 0)
			(size 0 0)
			(layers "B.Cu" "B.Mask" "B.Paste")
			(net "NIC3_SLOT_ID0")
		)
		(pad "2" smd circle
			(at -0.40005 0)
			(size 0 0)
			(layers "B.Cu" "B.Mask" "B.Paste")
			(net "GND")
		)
	)
	(footprint ""
		(layer "B.Cu")
		(at 146.685254 -209.562192 -90)
		(property "Reference" "R972"
			(at 0 0 90)
			(layer "B.SilkS")
			(hide yes)
			(effects
				(font
					(size 1.27 1.27)
				)
				(justify mirror)
			)
		)
		(property "Value" ""
			(at 0 0 90)
			(layer "B.Fab")
			(effects
				(font
					(size 1.27 1.27)
				)
				(justify mirror)
			)
		)
		(duplicate_pad_numbers_are_jumpers no)
		(fp_line
			(start -0.7874 0.4064)
			(end 0.7874 0.4064)
			(stroke
				(width 0.1524)
				(type default)
			)
			(layer "B.SilkS")
		)
		(fp_line
			(start 0.7874 0.4064)
			(end 0.7874 -0.4064)
			(stroke
				(width 0.1524)
				(type default)
			)
			(layer "B.SilkS")
		)
		(fp_line
			(start -0.7874 -0.4064)
			(end -0.7874 0.4064)
			(stroke
				(width 0.1524)
				(type default)
			)
			(layer "B.SilkS")
		)
		(fp_line
			(start 0.7874 -0.4064)
			(end -0.7874 -0.4064)
			(stroke
				(width 0.1524)
				(type default)
			)
			(layer "B.SilkS")
		)
		(fp_line
			(start -0.67945 0.3048)
			(end -0.120396 0.3048)
			(stroke
				(width 0.1)
				(type default)
			)
			(layer "B.Fab")
		)
		(fp_line
			(start -0.120396 0.3048)
			(end -0.120396 0.2794)
			(stroke
				(width 0.1)
				(type default)
			)
			(layer "B.Fab")
		)
		(fp_line
			(start 0.12065 0.3048)
			(end 0.67945 0.3048)
			(stroke
				(width 0.1)
				(type default)
			)
			(layer "B.Fab")
		)
		(fp_line
			(start 0.67945 0.3048)
			(end 0.67945 -0.305054)
			(stroke
				(width 0.1)
				(type default)
			)
			(layer "B.Fab")
		)
		(fp_line
			(start -0.120396 0.2794)
			(end 0.12065 0.2794)
			(stroke
				(width 0.1)
				(type default)
			)
			(layer "B.Fab")
		)
		(fp_line
			(start 0.12065 0.2794)
			(end 0.12065 0.3048)
			(stroke
				(width 0.1)
				(type default)
			)
			(layer "B.Fab")
		)
		(fp_line
			(start -0.12065 -0.2794)
			(end -0.12065 -0.3048)
			(stroke
				(width 0.1)
				(type default)
			)
			(layer "B.Fab")
		)
		(fp_line
			(start 0.12065 -0.2794)
			(end -0.12065 -0.2794)
			(stroke
				(width 0.1)
				(type default)
			)
			(layer "B.Fab")
		)
		(fp_line
			(start -0.67945 -0.3048)
			(end -0.67945 0.3048)
			(stroke
				(width 0.1)
				(type default)
			)
			(layer "B.Fab")
		)
		(fp_line
			(start -0.12065 -0.3048)
			(end -0.67945 -0.3048)
			(stroke
				(width 0.1)
				(type default)
			)
			(layer "B.Fab")
		)
		(fp_line
			(start 0.12065 -0.305054)
			(end 0.12065 -0.2794)
			(stroke
				(width 0.1)
				(type default)
			)
			(layer "B.Fab")
		)
		(fp_line
			(start 0.67945 -0.305054)
			(end 0.12065 -0.305054)
			(stroke
				(width 0.1)
				(type default)
			)
			(layer "B.Fab")
		)
		(pad "1" smd circle
			(at 0.40005 0 90)
			(size 0 0)
			(layers "B.Cu" "B.Mask" "B.Paste")
			(net "UART_PEX1_CLI_BUF_RX")
		)
		(pad "2" smd circle
			(at -0.40005 0 90)
			(size 0 0)
			(layers "B.Cu" "B.Mask" "B.Paste")
			(net "P1V8_PEX")
		)
	)
	(footprint ""
		(layer "B.Cu")
		(at 191.823848 -291.624766 90)
		(property "Reference" "R986"
			(at 0 0 90)
			(layer "B.SilkS")
			(hide yes)
			(effects
				(font
					(size 1.27 1.27)
				)
				(justify mirror)
			)
		)
		(property "Value" ""
			(at 0 0 90)
			(layer "B.Fab")
			(effects
				(font
					(size 1.27 1.27)
				)
				(justify mirror)
			)
		)
		(duplicate_pad_numbers_are_jumpers no)
		(fp_line
			(start 0.7874 -0.4064)
			(end -0.7874 -0.4064)
			(stroke
				(width 0.1524)
				(type default)
			)
			(layer "B.SilkS")
		)
		(fp_line
			(start -0.7874 -0.4064)
			(end -0.7874 0.4064)
			(stroke
				(width 0.1524)
				(type default)
			)
			(layer "B.SilkS")
		)
		(fp_line
			(start 0.7874 0.4064)
			(end 0.7874 -0.4064)
			(stroke
				(width 0.1524)
				(type default)
			)
			(layer "B.SilkS")
		)
		(fp_line
			(start -0.7874 0.4064)
			(end 0.7874 0.4064)
			(stroke
				(width 0.1524)
				(type default)
			)
			(layer "B.SilkS")
		)
		(fp_line
			(start 0.67945 -0.305054)
			(end 0.12065 -0.305054)
			(stroke
				(width 0.1)
				(type default)
			)
			(layer "B.Fab")
		)
		(fp_line
			(start 0.12065 -0.305054)
			(end 0.12065 -0.2794)
			(stroke
				(width 0.1)
				(type default)
			)
			(layer "B.Fab")
		)
		(fp_line
			(start -0.12065 -0.3048)
			(end -0.67945 -0.3048)
			(stroke
				(width 0.1)
				(type default)
			)
			(layer "B.Fab")
		)
		(fp_line
			(start -0.67945 -0.3048)
			(end -0.67945 0.3048)
			(stroke
				(width 0.1)
				(type default)
			)
			(layer "B.Fab")
		)
		(fp_line
			(start 0.12065 -0.2794)
			(end -0.12065 -0.2794)
			(stroke
				(width 0.1)
				(type default)
			)
			(layer "B.Fab")
		)
		(fp_line
			(start -0.12065 -0.2794)
			(end -0.12065 -0.3048)
			(stroke
				(width 0.1)
				(type default)
			)
			(layer "B.Fab")
		)
		(fp_line
			(start 0.12065 0.2794)
			(end 0.12065 0.3048)
			(stroke
				(width 0.1)
				(type default)
			)
			(layer "B.Fab")
		)
		(fp_line
			(start -0.120396 0.2794)
			(end 0.12065 0.2794)
			(stroke
				(width 0.1)
				(type default)
			)
			(layer "B.Fab")
		)
		(fp_line
			(start 0.67945 0.3048)
			(end 0.67945 -0.305054)
			(stroke
				(width 0.1)
				(type default)
			)
			(layer "B.Fab")
		)
		(fp_line
			(start 0.12065 0.3048)
			(end 0.67945 0.3048)
			(stroke
				(width 0.1)
				(type default)
			)
			(layer "B.Fab")
		)
		(fp_line
			(start -0.120396 0.3048)
			(end -0.120396 0.2794)
			(stroke
				(width 0.1)
				(type default)
			)
			(layer "B.Fab")
		)
		(fp_line
			(start -0.67945 0.3048)
			(end -0.120396 0.3048)
			(stroke
				(width 0.1)
				(type default)
			)
			(layer "B.Fab")
		)
		(pad "1" smd circle
			(at 0.40005 0 270)
			(size 0 0)
			(layers "B.Cu" "B.Mask" "B.Paste")
			(net "UART_PEX1_CLI_TX")
		)
		(pad "2" smd circle
			(at -0.40005 0 270)
			(size 0 0)
			(layers "B.Cu" "B.Mask" "B.Paste")
			(net "UART_PEX1_CLI_R_TX")
		)
	)
	(footprint ""
		(layer "B.Cu")
		(at 133.932422 -222.658432)
		(property "Reference" "C2307"
			(at 0 0 0)
			(layer "B.SilkS")
			(hide yes)
			(effects
				(font
					(size 1.27 1.27)
				)
				(justify mirror)
			)
		)
		(property "Value" ""
			(at 0 0 0)
			(layer "B.Fab")
			(effects
				(font
					(size 1.27 1.27)
				)
				(justify mirror)
			)
		)
		(duplicate_pad_numbers_are_jumpers no)
		(fp_line
			(start -0.7874 -0.4064)
			(end -0.7874 0.4064)
			(stroke
				(width 0.1524)
				(type default)
			)
			(layer "B.SilkS")
		)
		(fp_line
			(start -0.7874 0.4064)
			(end 0.7874 0.4064)
			(stroke
				(width 0.1524)
				(type default)
			)
			(layer "B.SilkS")
		)
		(fp_line
			(start 0.7874 -0.4064)
			(end -0.7874 -0.4064)
			(stroke
				(width 0.1524)
				(type default)
			)
			(layer "B.SilkS")
		)
		(fp_line
			(start 0.7874 0.4064)
			(end 0.7874 -0.4064)
			(stroke
				(width 0.1524)
				(type default)
			)
			(layer "B.SilkS")
		)
		(fp_line
			(start -0.67945 -0.3048)
			(end -0.67945 0.3048)
			(stroke
				(width 0.1)
				(type default)
			)
			(layer "B.Fab")
		)
		(fp_line
			(start -0.67945 0.3048)
			(end -0.120396 0.3048)
			(stroke
				(width 0.1)
				(type default)
			)
			(layer "B.Fab")
		)
		(fp_line
			(start -0.12065 -0.3048)
			(end -0.67945 -0.3048)
			(stroke
				(width 0.1)
				(type default)
			)
			(layer "B.Fab")
		)
		(fp_line
			(start -0.12065 -0.2794)
			(end -0.12065 -0.3048)
			(stroke
				(width 0.1)
				(type default)
			)
			(layer "B.Fab")
		)
		(fp_line
			(start -0.120396 0.2794)
			(end 0.12065 0.2794)
			(stroke
				(width 0.1)
				(type default)
			)
			(layer "B.Fab")
		)
		(fp_line
			(start -0.120396 0.3048)
			(end -0.120396 0.2794)
			(stroke
				(width 0.1)
				(type default)
			)
			(layer "B.Fab")
		)
		(fp_line
			(start 0.12065 -0.305054)
			(end 0.12065 -0.2794)
			(stroke
				(width 0.1)
				(type default)
			)
			(layer "B.Fab")
		)
		(fp_line
			(start 0.12065 -0.2794)
			(end -0.12065 -0.2794)
			(stroke
				(width 0.1)
				(type default)
			)
			(layer "B.Fab")
		)
		(fp_line
			(start 0.12065 0.2794)
			(end 0.12065 0.3048)
			(stroke
				(width 0.1)
				(type default)
			)
			(layer "B.Fab")
		)
		(fp_line
			(start 0.12065 0.3048)
			(end 0.67945 0.3048)
			(stroke
				(width 0.1)
				(type default)
			)
			(layer "B.Fab")
		)
		(fp_line
			(start 0.67945 -0.305054)
			(end 0.12065 -0.305054)
			(stroke
				(width 0.1)
				(type default)
			)
			(layer "B.Fab")
		)
		(fp_line
			(start 0.67945 0.3048)
			(end 0.67945 -0.305054)
			(stroke
				(width 0.1)
				(type default)
			)
			(layer "B.Fab")
		)
		(pad "1" smd circle
			(at 0.40005 0 180)
			(size 0 0)
			(layers "B.Cu" "B.Mask" "B.Paste")
			(net "GND")
		)
		(pad "2" smd circle
			(at -0.40005 0 180)
			(size 0 0)
			(layers "B.Cu" "B.Mask" "B.Paste")
			(net "P3V3_AUX")
		)
	)
	(footprint ""
		(layer "B.Cu")
		(at 52.049934 -301.599854 -90)
		(property "Reference" "C1180"
			(at 0 0 90)
			(layer "B.SilkS")
			(hide yes)
			(effects
				(font
					(size 1.27 1.27)
				)
				(justify mirror)
			)
		)
		(property "Value" ""
			(at 0 0 90)
			(layer "B.Fab")
			(effects
				(font
					(size 1.27 1.27)
				)
				(justify mirror)
			)
		)
		(duplicate_pad_numbers_are_jumpers no)
		(fp_line
			(start -0.299974 0.150114)
			(end 0.299974 0.150114)
			(stroke
				(width 0.1)
				(type default)
			)
			(layer "B.Fab")
		)
		(fp_line
			(start 0.299974 0.150114)
			(end 0.299974 -0.150114)
			(stroke
				(width 0.1)
				(type default)
			)
			(layer "B.Fab")
		)
		(fp_line
			(start -0.299974 -0.150114)
			(end -0.299974 0.150114)
			(stroke
				(width 0.1)
				(type default)
			)
			(layer "B.Fab")
		)
		(fp_line
			(start 0.299974 -0.150114)
			(end -0.299974 -0.150114)
			(stroke
				(width 0.1)
				(type default)
			)
			(layer "B.Fab")
		)
		(pad "1" smd rect
			(at 0.2667 0 90)
			(size 0.3048 0.381)
			(layers "B.Cu" "B.Mask" "B.Paste")
			(net "P0V8_SERDES_VDDA_PEX0")
		)
		(pad "2" smd rect
			(at -0.2667 0 90)
			(size 0.3048 0.381)
			(layers "B.Cu" "B.Mask" "B.Paste")
			(net "GND")
		)
	)
	(footprint ""
		(layer "B.Cu")
		(at 333.63916 -82.569558 90)
		(property "Reference" "C2673"
			(at 0 0 90)
			(layer "B.SilkS")
			(hide yes)
			(effects
				(font
					(size 1.27 1.27)
				)
				(justify mirror)
			)
		)
		(property "Value" ""
			(at 0 0 90)
			(layer "B.Fab")
			(effects
				(font
					(size 1.27 1.27)
				)
				(justify mirror)
			)
		)
		(duplicate_pad_numbers_are_jumpers no)
		(fp_line
			(start 1.524 -0.762)
			(end -1.524 -0.762)
			(stroke
				(width 0.1524)
				(type default)
			)
			(layer "B.SilkS")
		)
		(fp_line
			(start -1.524 -0.762)
			(end -1.524 0.762)
			(stroke
				(width 0.1524)
				(type default)
			)
			(layer "B.SilkS")
		)
		(fp_line
			(start 1.524 0.762)
			(end 1.524 -0.762)
			(stroke
				(width 0.1524)
				(type default)
			)
			(layer "B.SilkS")
		)
		(fp_line
			(start -1.524 0.762)
			(end 1.524 0.762)
			(stroke
				(width 0.1524)
				(type default)
			)
			(layer "B.SilkS")
		)
		(fp_line
			(start 1.1049 -0.724916)
			(end 1.1049 0.724916)
			(stroke
				(width 0.1)
				(type default)
			)
			(layer "B.Fab")
		)
		(fp_line
			(start -1.1049 -0.724916)
			(end 1.1049 -0.724916)
			(stroke
				(width 0.1)
				(type default)
			)
			(layer "B.Fab")
		)
		(fp_line
			(start 1.1049 0.724916)
			(end -1.1049 0.724916)
			(stroke
				(width 0.1)
				(type default)
			)
			(layer "B.Fab")
		)
		(fp_line
			(start -1.1049 0.724916)
			(end -1.1049 -0.724916)
			(stroke
				(width 0.1)
				(type default)
			)
			(layer "B.Fab")
		)
		(pad "1" smd rect
			(at 0.889 0 90)
			(size 1.016 1.27)
			(layers "B.Cu" "B.Mask" "B.Paste")
			(net "P3V3_VDD_9ZXL0851_8_15")
		)
		(pad "2" smd rect
			(at -0.889 0 90)
			(size 1.016 1.27)
			(layers "B.Cu" "B.Mask" "B.Paste")
			(net "GND")
		)
	)
	(footprint ""
		(layer "B.Cu")
		(at 50.624994 -297.79976 -90)
		(property "Reference" "C1138"
			(at 0 0 90)
			(layer "B.SilkS")
			(hide yes)
			(effects
				(font
					(size 1.27 1.27)
				)
				(justify mirror)
			)
		)
		(property "Value" ""
			(at 0 0 90)
			(layer "B.Fab")
			(effects
				(font
					(size 1.27 1.27)
				)
				(justify mirror)
			)
		)
		(duplicate_pad_numbers_are_jumpers no)
		(fp_line
			(start -0.299974 0.150114)
			(end 0.299974 0.150114)
			(stroke
				(width 0.1)
				(type default)
			)
			(layer "B.Fab")
		)
		(fp_line
			(start 0.299974 0.150114)
			(end 0.299974 -0.150114)
			(stroke
				(width 0.1)
				(type default)
			)
			(layer "B.Fab")
		)
		(fp_line
			(start -0.299974 -0.150114)
			(end -0.299974 0.150114)
			(stroke
				(width 0.1)
				(type default)
			)
			(layer "B.Fab")
		)
		(fp_line
			(start 0.299974 -0.150114)
			(end -0.299974 -0.150114)
			(stroke
				(width 0.1)
				(type default)
			)
			(layer "B.Fab")
		)
		(pad "1" smd rect
			(at 0.2667 0 90)
			(size 0.3048 0.381)
			(layers "B.Cu" "B.Mask" "B.Paste")
			(net "P0V8_PEX0")
		)
		(pad "2" smd rect
			(at -0.2667 0 90)
			(size 0.3048 0.381)
			(layers "B.Cu" "B.Mask" "B.Paste")
			(net "GND")
		)
	)
	(footprint ""
		(layer "B.Cu")
		(at 51.52009 -305.399948 -90)
		(property "Reference" "C2983"
			(at 0 0 90)
			(layer "B.SilkS")
			(hide yes)
			(effects
				(font
					(size 1.27 1.27)
				)
				(justify mirror)
			)
		)
		(property "Value" ""
			(at 0 0 90)
			(layer "B.Fab")
			(effects
				(font
					(size 1.27 1.27)
				)
				(justify mirror)
			)
		)
		(duplicate_pad_numbers_are_jumpers no)
		(fp_line
			(start -0.299974 0.150114)
			(end 0.299974 0.150114)
			(stroke
				(width 0.1)
				(type default)
			)
			(layer "B.Fab")
		)
		(fp_line
			(start 0.299974 0.150114)
			(end 0.299974 -0.150114)
			(stroke
				(width 0.1)
				(type default)
			)
			(layer "B.Fab")
		)
		(fp_line
			(start -0.299974 -0.150114)
			(end -0.299974 0.150114)
			(stroke
				(width 0.1)
				(type default)
			)
			(layer "B.Fab")
		)
		(fp_line
			(start 0.299974 -0.150114)
			(end -0.299974 -0.150114)
			(stroke
				(width 0.1)
				(type default)
			)
			(layer "B.Fab")
		)
		(pad "1" smd rect
			(at 0.2667 0 90)
			(size 0.3048 0.381)
			(layers "B.Cu" "B.Mask" "B.Paste")
			(net "P1V25_SERDES_VDDPLL_PEX0")
		)
		(pad "2" smd rect
			(at -0.2667 0 90)
			(size 0.3048 0.381)
			(layers "B.Cu" "B.Mask" "B.Paste")
			(net "GND")
		)
	)
	(footprint ""
		(layer "B.Cu")
		(at 299.067474 -223.599502 90)
		(property "Reference" "R1861"
			(at 0 0 90)
			(layer "B.SilkS")
			(hide yes)
			(effects
				(font
					(size 1.27 1.27)
				)
				(justify mirror)
			)
		)
		(property "Value" ""
			(at 0 0 90)
			(layer "B.Fab")
			(effects
				(font
					(size 1.27 1.27)
				)
				(justify mirror)
			)
		)
		(duplicate_pad_numbers_are_jumpers no)
		(fp_line
			(start 0.7874 -0.4064)
			(end -0.7874 -0.4064)
			(stroke
				(width 0.1524)
				(type default)
			)
			(layer "B.SilkS")
		)
		(fp_line
			(start -0.7874 -0.4064)
			(end -0.7874 0.4064)
			(stroke
				(width 0.1524)
				(type default)
			)
			(layer "B.SilkS")
		)
		(fp_line
			(start 0.7874 0.4064)
			(end 0.7874 -0.4064)
			(stroke
				(width 0.1524)
				(type default)
			)
			(layer "B.SilkS")
		)
		(fp_line
			(start -0.7874 0.4064)
			(end 0.7874 0.4064)
			(stroke
				(width 0.1524)
				(type default)
			)
			(layer "B.SilkS")
		)
		(fp_line
			(start 0.67945 -0.305054)
			(end 0.12065 -0.305054)
			(stroke
				(width 0.1)
				(type default)
			)
			(layer "B.Fab")
		)
		(fp_line
			(start 0.12065 -0.305054)
			(end 0.12065 -0.2794)
			(stroke
				(width 0.1)
				(type default)
			)
			(layer "B.Fab")
		)
		(fp_line
			(start -0.12065 -0.3048)
			(end -0.67945 -0.3048)
			(stroke
				(width 0.1)
				(type default)
			)
			(layer "B.Fab")
		)
		(fp_line
			(start -0.67945 -0.3048)
			(end -0.67945 0.3048)
			(stroke
				(width 0.1)
				(type default)
			)
			(layer "B.Fab")
		)
		(fp_line
			(start 0.12065 -0.2794)
			(end -0.12065 -0.2794)
			(stroke
				(width 0.1)
				(type default)
			)
			(layer "B.Fab")
		)
		(fp_line
			(start -0.12065 -0.2794)
			(end -0.12065 -0.3048)
			(stroke
				(width 0.1)
				(type default)
			)
			(layer "B.Fab")
		)
		(fp_line
			(start 0.12065 0.2794)
			(end 0.12065 0.3048)
			(stroke
				(width 0.1)
				(type default)
			)
			(layer "B.Fab")
		)
		(fp_line
			(start -0.120396 0.2794)
			(end 0.12065 0.2794)
			(stroke
				(width 0.1)
				(type default)
			)
			(layer "B.Fab")
		)
		(fp_line
			(start 0.67945 0.3048)
			(end 0.67945 -0.305054)
			(stroke
				(width 0.1)
				(type default)
			)
			(layer "B.Fab")
		)
		(fp_line
			(start 0.12065 0.3048)
			(end 0.67945 0.3048)
			(stroke
				(width 0.1)
				(type default)
			)
			(layer "B.Fab")
		)
		(fp_line
			(start -0.120396 0.3048)
			(end -0.120396 0.2794)
			(stroke
				(width 0.1)
				(type default)
			)
			(layer "B.Fab")
		)
		(fp_line
			(start -0.67945 0.3048)
			(end -0.120396 0.3048)
			(stroke
				(width 0.1)
				(type default)
			)
			(layer "B.Fab")
		)
		(pad "1" smd circle
			(at 0.40005 0 270)
			(size 0 0)
			(layers "B.Cu" "B.Mask" "B.Paste")
			(net "P3V3_AUX")
		)
		(pad "2" smd circle
			(at -0.40005 0 270)
			(size 0 0)
			(layers "B.Cu" "B.Mask" "B.Paste")
			(net "RST_GPU_PERST_0_BUF_N")
		)
	)
	(footprint ""
		(layer "B.Cu")
		(at 189.500002 -110.115096)
		(property "Reference" "C894"
			(at 0 0 0)
			(layer "B.SilkS")
			(hide yes)
			(effects
				(font
					(size 1.27 1.27)
				)
				(justify mirror)
			)
		)
		(property "Value" ""
			(at 0 0 0)
			(layer "B.Fab")
			(effects
				(font
					(size 1.27 1.27)
				)
				(justify mirror)
			)
		)
		(duplicate_pad_numbers_are_jumpers no)
		(fp_line
			(start -0.299974 -0.150114)
			(end -0.299974 0.150114)
			(stroke
				(width 0.1)
				(type default)
			)
			(layer "B.Fab")
		)
		(fp_line
			(start -0.299974 0.150114)
			(end 0.299974 0.150114)
			(stroke
				(width 0.1)
				(type default)
			)
			(layer "B.Fab")
		)
		(fp_line
			(start 0.299974 -0.150114)
			(end -0.299974 -0.150114)
			(stroke
				(width 0.1)
				(type default)
			)
			(layer "B.Fab")
		)
		(fp_line
			(start 0.299974 0.150114)
			(end 0.299974 -0.150114)
			(stroke
				(width 0.1)
				(type default)
			)
			(layer "B.Fab")
		)
		(pad "1" smd rect
			(at 0.2667 0 180)
			(size 0.3048 0.381)
			(layers "B.Cu" "B.Mask" "B.Paste")
			(net "P12V_NIC3")
		)
		(pad "2" smd rect
			(at -0.2667 0 180)
			(size 0.3048 0.381)
			(layers "B.Cu" "B.Mask" "B.Paste")
			(net "GND")
		)
	)
	(footprint ""
		(layer "B.Cu")
		(at 234.227878 -276.86381)
		(property "Reference" "C4349"
			(at 0 0 0)
			(layer "B.SilkS")
			(hide yes)
			(effects
				(font
					(size 1.27 1.27)
				)
				(justify mirror)
			)
		)
		(property "Value" ""
			(at 0 0 0)
			(layer "B.Fab")
			(effects
				(font
					(size 1.27 1.27)
				)
				(justify mirror)
			)
		)
		(duplicate_pad_numbers_are_jumpers no)
		(fp_line
			(start -0.299974 -0.150114)
			(end -0.299974 0.150114)
			(stroke
				(width 0.1)
				(type default)
			)
			(layer "B.Fab")
		)
		(fp_line
			(start -0.299974 0.150114)
			(end 0.299974 0.150114)
			(stroke
				(width 0.1)
				(type default)
			)
			(layer "B.Fab")
		)
		(fp_line
			(start 0.299974 -0.150114)
			(end -0.299974 -0.150114)
			(stroke
				(width 0.1)
				(type default)
			)
			(layer "B.Fab")
		)
		(fp_line
			(start 0.299974 0.150114)
			(end 0.299974 -0.150114)
			(stroke
				(width 0.1)
				(type default)
			)
			(layer "B.Fab")
		)
		(pad "1" smd rect
			(at 0.2667 0 180)
			(size 0.3048 0.381)
			(layers "B.Cu" "B.Mask" "B.Paste")
			(net "P1V25_PEX2")
		)
		(pad "2" smd rect
			(at -0.2667 0 180)
			(size 0.3048 0.381)
			(layers "B.Cu" "B.Mask" "B.Paste")
			(net "GND")
		)
	)
	(footprint ""
		(layer "B.Cu")
		(at 335.12887 -284.796738 -90)
		(property "Reference" "PC140"
			(at 0 0 90)
			(layer "B.SilkS")
			(hide yes)
			(effects
				(font
					(size 1.27 1.27)
				)
				(justify mirror)
			)
		)
		(property "Value" ""
			(at 0 0 90)
			(layer "B.Fab")
			(effects
				(font
					(size 1.27 1.27)
				)
				(justify mirror)
			)
		)
		(duplicate_pad_numbers_are_jumpers no)
		(fp_line
			(start -1.524 0.762)
			(end 1.524 0.762)
			(stroke
				(width 0.1524)
				(type default)
			)
			(layer "B.SilkS")
		)
		(fp_line
			(start 1.524 0.762)
			(end 1.524 -0.762)
			(stroke
				(width 0.1524)
				(type default)
			)
			(layer "B.SilkS")
		)
		(fp_line
			(start -1.524 -0.762)
			(end -1.524 0.762)
			(stroke
				(width 0.1524)
				(type default)
			)
			(layer "B.SilkS")
		)
		(fp_line
			(start 1.524 -0.762)
			(end -1.524 -0.762)
			(stroke
				(width 0.1524)
				(type default)
			)
			(layer "B.SilkS")
		)
		(fp_line
			(start -1.1049 0.724916)
			(end -1.1049 -0.724916)
			(stroke
				(width 0.1)
				(type default)
			)
			(layer "B.Fab")
		)
		(fp_line
			(start 1.1049 0.724916)
			(end -1.1049 0.724916)
			(stroke
				(width 0.1)
				(type default)
			)
			(layer "B.Fab")
		)
		(fp_line
			(start -1.1049 -0.724916)
			(end 1.1049 -0.724916)
			(stroke
				(width 0.1)
				(type default)
			)
			(layer "B.Fab")
		)
		(fp_line
			(start 1.1049 -0.724916)
			(end 1.1049 0.724916)
			(stroke
				(width 0.1)
				(type default)
			)
			(layer "B.Fab")
		)
		(pad "1" smd rect
			(at 0.889 0 270)
			(size 1.016 1.27)
			(layers "B.Cu" "B.Mask" "B.Paste")
			(net "SW_P12V_P0V8_PEX2_FLT")
		)
		(pad "2" smd rect
			(at -0.889 0 270)
			(size 1.016 1.27)
			(layers "B.Cu" "B.Mask" "B.Paste")
			(net "GND")
		)
	)
	(footprint ""
		(layer "B.Cu")
		(at 105.99547 -346.801186 -90)
		(property "Reference" "R6365"
			(at 0 0 90)
			(layer "B.SilkS")
			(hide yes)
			(effects
				(font
					(size 1.27 1.27)
				)
				(justify mirror)
			)
		)
		(property "Value" ""
			(at 0 0 90)
			(layer "B.Fab")
			(effects
				(font
					(size 1.27 1.27)
				)
				(justify mirror)
			)
		)
		(duplicate_pad_numbers_are_jumpers no)
		(fp_line
			(start -1.2954 0.5842)
			(end 1.2954 0.5842)
			(stroke
				(width 0.1524)
				(type default)
			)
			(layer "B.SilkS")
		)
		(fp_line
			(start 1.2954 0.5842)
			(end 1.2954 -0.5842)
			(stroke
				(width 0.1524)
				(type default)
			)
			(layer "B.SilkS")
		)
		(fp_line
			(start -1.2954 -0.5842)
			(end -1.2954 0.5842)
			(stroke
				(width 0.1524)
				(type default)
			)
			(layer "B.SilkS")
		)
		(fp_line
			(start 1.2954 -0.5842)
			(end -1.2954 -0.5842)
			(stroke
				(width 0.1524)
				(type default)
			)
			(layer "B.SilkS")
		)
		(fp_line
			(start -0.8636 0.4572)
			(end 0.8636 0.4572)
			(stroke
				(width 0.1)
				(type default)
			)
			(layer "B.Fab")
		)
		(fp_line
			(start 0.8636 0.4572)
			(end 0.8636 0.4318)
			(stroke
				(width 0.1)
				(type default)
			)
			(layer "B.Fab")
		)
		(fp_line
			(start 0.8636 0.4318)
			(end 0.8636 0.4064)
			(stroke
				(width 0.1)
				(type default)
			)
			(layer "B.Fab")
		)
		(fp_line
			(start -1.1938 0.4064)
			(end -0.8636 0.4064)
			(stroke
				(width 0.1)
				(type default)
			)
			(layer "B.Fab")
		)
		(fp_line
			(start -0.8636 0.4064)
			(end -0.8636 0.4572)
			(stroke
				(width 0.1)
				(type default)
			)
			(layer "B.Fab")
		)
		(fp_line
			(start 0.8636 0.4064)
			(end 1.1938 0.4064)
			(stroke
				(width 0.1)
				(type default)
			)
			(layer "B.Fab")
		)
		(fp_line
			(start 1.1938 0.4064)
			(end 1.1938 -0.406654)
			(stroke
				(width 0.1)
				(type default)
			)
			(layer "B.Fab")
		)
		(fp_line
			(start -1.1938 -0.406654)
			(end -1.1938 0.4064)
			(stroke
				(width 0.1)
				(type default)
			)
			(layer "B.Fab")
		)
		(fp_line
			(start -0.8636 -0.406654)
			(end -1.1938 -0.406654)
			(stroke
				(width 0.1)
				(type default)
			)
			(layer "B.Fab")
		)
		(fp_line
			(start 0.8636 -0.406654)
			(end 0.8636 -0.4572)
			(stroke
				(width 0.1)
				(type default)
			)
			(layer "B.Fab")
		)
		(fp_line
			(start 1.1938 -0.406654)
			(end 0.8636 -0.406654)
			(stroke
				(width 0.1)
				(type default)
			)
			(layer "B.Fab")
		)
		(fp_line
			(start -0.8636 -0.4572)
			(end -0.8636 -0.406654)
			(stroke
				(width 0.1)
				(type default)
			)
			(layer "B.Fab")
		)
		(fp_line
			(start 0.8636 -0.4572)
			(end -0.8636 -0.4572)
			(stroke
				(width 0.1)
				(type default)
			)
			(layer "B.Fab")
		)
		(pad "1" smd rect
			(at 0.7366 0 180)
			(size 0.7112 0.8128)
			(layers "B.Cu" "B.Mask" "B.Paste")
			(net "P3V3_CLK_BUFFER_9ZXL0451E_S3_VZX3P3")
		)
		(pad "2" smd rect
			(at -0.7366 0 180)
			(size 0.7112 0.8128)
			(layers "B.Cu" "B.Mask" "B.Paste")
			(net "P3V3_CLK_BUFFER_9ZXL0451E_S3_VZX3P3A")
		)
	)
	(footprint ""
		(layer "B.Cu")
		(at 303.486312 -117.66169)
		(property "Reference" "R258"
			(at 0 0 0)
			(layer "B.SilkS")
			(hide yes)
			(effects
				(font
					(size 1.27 1.27)
				)
				(justify mirror)
			)
		)
		(property "Value" ""
			(at 0 0 0)
			(layer "B.Fab")
			(effects
				(font
					(size 1.27 1.27)
				)
				(justify mirror)
			)
		)
		(duplicate_pad_numbers_are_jumpers no)
		(fp_line
			(start -0.7874 -0.4064)
			(end -0.7874 0.4064)
			(stroke
				(width 0.1524)
				(type default)
			)
			(layer "B.SilkS")
		)
		(fp_line
			(start -0.7874 0.4064)
			(end 0.7874 0.4064)
			(stroke
				(width 0.1524)
				(type default)
			)
			(layer "B.SilkS")
		)
		(fp_line
			(start 0.7874 -0.4064)
			(end -0.7874 -0.4064)
			(stroke
				(width 0.1524)
				(type default)
			)
			(layer "B.SilkS")
		)
		(fp_line
			(start 0.7874 0.4064)
			(end 0.7874 -0.4064)
			(stroke
				(width 0.1524)
				(type default)
			)
			(layer "B.SilkS")
		)
		(fp_line
			(start -0.67945 -0.3048)
			(end -0.67945 0.3048)
			(stroke
				(width 0.1)
				(type default)
			)
			(layer "B.Fab")
		)
		(fp_line
			(start -0.67945 0.3048)
			(end -0.120396 0.3048)
			(stroke
				(width 0.1)
				(type default)
			)
			(layer "B.Fab")
		)
		(fp_line
			(start -0.12065 -0.3048)
			(end -0.67945 -0.3048)
			(stroke
				(width 0.1)
				(type default)
			)
			(layer "B.Fab")
		)
		(fp_line
			(start -0.12065 -0.2794)
			(end -0.12065 -0.3048)
			(stroke
				(width 0.1)
				(type default)
			)
			(layer "B.Fab")
		)
		(fp_line
			(start -0.120396 0.2794)
			(end 0.12065 0.2794)
			(stroke
				(width 0.1)
				(type default)
			)
			(layer "B.Fab")
		)
		(fp_line
			(start -0.120396 0.3048)
			(end -0.120396 0.2794)
			(stroke
				(width 0.1)
				(type default)
			)
			(layer "B.Fab")
		)
		(fp_line
			(start 0.12065 -0.305054)
			(end 0.12065 -0.2794)
			(stroke
				(width 0.1)
				(type default)
			)
			(layer "B.Fab")
		)
		(fp_line
			(start 0.12065 -0.2794)
			(end -0.12065 -0.2794)
			(stroke
				(width 0.1)
				(type default)
			)
			(layer "B.Fab")
		)
		(fp_line
			(start 0.12065 0.2794)
			(end 0.12065 0.3048)
			(stroke
				(width 0.1)
				(type default)
			)
			(layer "B.Fab")
		)
		(fp_line
			(start 0.12065 0.3048)
			(end 0.67945 0.3048)
			(stroke
				(width 0.1)
				(type default)
			)
			(layer "B.Fab")
		)
		(fp_line
			(start 0.67945 -0.305054)
			(end 0.12065 -0.305054)
			(stroke
				(width 0.1)
				(type default)
			)
			(layer "B.Fab")
		)
		(fp_line
			(start 0.67945 0.3048)
			(end 0.67945 -0.305054)
			(stroke
				(width 0.1)
				(type default)
			)
			(layer "B.Fab")
		)
		(pad "1" smd circle
			(at 0.40005 0 180)
			(size 0 0)
			(layers "B.Cu" "B.Mask" "B.Paste")
			(net "NIC5_AUX_PWR_EN_R")
		)
		(pad "2" smd circle
			(at -0.40005 0 180)
			(size 0 0)
			(layers "B.Cu" "B.Mask" "B.Paste")
			(net "NIC5_AUX_PWR_EN")
		)
	)
	(footprint ""
		(layer "B.Cu")
		(at 173.850046 -301.599854 -90)
		(property "Reference" "C1459"
			(at 0 0 90)
			(layer "B.SilkS")
			(hide yes)
			(effects
				(font
					(size 1.27 1.27)
				)
				(justify mirror)
			)
		)
		(property "Value" ""
			(at 0 0 90)
			(layer "B.Fab")
			(effects
				(font
					(size 1.27 1.27)
				)
				(justify mirror)
			)
		)
		(duplicate_pad_numbers_are_jumpers no)
		(fp_line
			(start -0.299974 0.150114)
			(end 0.299974 0.150114)
			(stroke
				(width 0.1)
				(type default)
			)
			(layer "B.Fab")
		)
		(fp_line
			(start 0.299974 0.150114)
			(end 0.299974 -0.150114)
			(stroke
				(width 0.1)
				(type default)
			)
			(layer "B.Fab")
		)
		(fp_line
			(start -0.299974 -0.150114)
			(end -0.299974 0.150114)
			(stroke
				(width 0.1)
				(type default)
			)
			(layer "B.Fab")
		)
		(fp_line
			(start 0.299974 -0.150114)
			(end -0.299974 -0.150114)
			(stroke
				(width 0.1)
				(type default)
			)
			(layer "B.Fab")
		)
		(pad "1" smd rect
			(at 0.2667 0 90)
			(size 0.3048 0.381)
			(layers "B.Cu" "B.Mask" "B.Paste")
			(net "P0V8_SERDES_VDDA_PEX1")
		)
		(pad "2" smd rect
			(at -0.2667 0 90)
			(size 0.3048 0.381)
			(layers "B.Cu" "B.Mask" "B.Paste")
			(net "GND")
		)
	)
	(footprint ""
		(layer "B.Cu")
		(at 340.493858 -221.98711 90)
		(property "Reference" "C2037"
			(at 0 0 90)
			(layer "B.SilkS")
			(hide yes)
			(effects
				(font
					(size 1.27 1.27)
				)
				(justify mirror)
			)
		)
		(property "Value" ""
			(at 0 0 90)
			(layer "B.Fab")
			(effects
				(font
					(size 1.27 1.27)
				)
				(justify mirror)
			)
		)
		(duplicate_pad_numbers_are_jumpers no)
		(fp_line
			(start 0.69215 -0.2921)
			(end -0.69215 -0.2921)
			(stroke
				(width 0.1524)
				(type default)
			)
			(layer "B.SilkS")
		)
		(fp_line
			(start -0.69215 -0.2921)
			(end -0.69215 0.2921)
			(stroke
				(width 0.1524)
				(type default)
			)
			(layer "B.SilkS")
		)
		(fp_line
			(start 0.69215 0.2921)
			(end 0.69215 -0.2921)
			(stroke
				(width 0.1524)
				(type default)
			)
			(layer "B.SilkS")
		)
		(fp_line
			(start -0.69215 0.2921)
			(end 0.69215 0.2921)
			(stroke
				(width 0.1524)
				(type default)
			)
			(layer "B.SilkS")
		)
		(fp_line
			(start 0.51435 -0.2794)
			(end -0.51435 -0.2794)
			(stroke
				(width 0.1)
				(type default)
			)
			(layer "B.Fab")
		)
		(fp_line
			(start -0.51435 -0.2794)
			(end -0.51435 0.2794)
			(stroke
				(width 0.1)
				(type default)
			)
			(layer "B.Fab")
		)
		(fp_line
			(start 0.51435 0.2794)
			(end 0.51435 -0.2794)
			(stroke
				(width 0.1)
				(type default)
			)
			(layer "B.Fab")
		)
		(fp_line
			(start -0.51435 0.2794)
			(end 0.51435 0.2794)
			(stroke
				(width 0.1)
				(type default)
			)
			(layer "B.Fab")
		)
		(pad "1" smd circle
			(at 0.40005 0 270)
			(size 0 0)
			(layers "B.Cu" "B.Mask" "B.Paste")
			(net "P3V3_FPGA_VCCIO0")
		)
		(pad "2" smd circle
			(at -0.40005 0 270)
			(size 0 0)
			(layers "B.Cu" "B.Mask" "B.Paste")
			(net "GND")
		)
		(zone
			(layer "B.Cu")
			(hatch none 0.5)
			(connect_pads
				(clearance 0)
			)
			(min_thickness 0.25)
			(keepout
				(tracks not_allowed)
				(vias allowed)
				(pads allowed)
				(copperpour not_allowed)
				(footprints allowed)
			)
			(placement
				(enabled no)
				(sheetname "")
			)
			(fill
				(thermal_gap 0.5)
				(thermal_bridge_width 0.5)
				(island_removal_mode 0)
			)
			(polygon
				(pts
					(xy 340.581488 -222.17761) (xy 340.639654 -222.08617) (xy 340.639654 -221.88678) (xy 340.581488 -221.79661)
					(xy 340.406228 -221.79661) (xy 340.347808 -221.88678) (xy 340.347808 -222.08617) (xy 340.405974 -222.17761)
				)
			)
		)
	)
	(footprint ""
		(layer "B.Cu")
		(at 186.200034 -290.674806 180)
		(property "Reference" "C3167"
			(at 0 0 0)
			(layer "B.SilkS")
			(hide yes)
			(effects
				(font
					(size 1.27 1.27)
				)
				(justify mirror)
			)
		)
		(property "Value" ""
			(at 0 0 0)
			(layer "B.Fab")
			(effects
				(font
					(size 1.27 1.27)
				)
				(justify mirror)
			)
		)
		(duplicate_pad_numbers_are_jumpers no)
		(fp_line
			(start 0.299974 0.150114)
			(end 0.299974 -0.150114)
			(stroke
				(width 0.1)
				(type default)
			)
			(layer "B.Fab")
		)
		(fp_line
			(start 0.299974 -0.150114)
			(end -0.299974 -0.150114)
			(stroke
				(width 0.1)
				(type default)
			)
			(layer "B.Fab")
		)
		(fp_line
			(start -0.299974 0.150114)
			(end 0.299974 0.150114)
			(stroke
				(width 0.1)
				(type default)
			)
			(layer "B.Fab")
		)
		(fp_line
			(start -0.299974 -0.150114)
			(end -0.299974 0.150114)
			(stroke
				(width 0.1)
				(type default)
			)
			(layer "B.Fab")
		)
		(pad "1" smd rect
			(at 0.2667 0)
			(size 0.3048 0.381)
			(layers "B.Cu" "B.Mask" "B.Paste")
			(net "P1V8_PEX")
		)
		(pad "2" smd rect
			(at -0.2667 0)
			(size 0.3048 0.381)
			(layers "B.Cu" "B.Mask" "B.Paste")
			(net "GND")
		)
	)
	(footprint ""
		(layer "B.Cu")
		(at 63.924942 -293.99992 -90)
		(property "Reference" "C1141"
			(at 0 0 90)
			(layer "B.SilkS")
			(hide yes)
			(effects
				(font
					(size 1.27 1.27)
				)
				(justify mirror)
			)
		)
		(property "Value" ""
			(at 0 0 90)
			(layer "B.Fab")
			(effects
				(font
					(size 1.27 1.27)
				)
				(justify mirror)
			)
		)
		(duplicate_pad_numbers_are_jumpers no)
		(fp_line
			(start -0.299974 0.150114)
			(end 0.299974 0.150114)
			(stroke
				(width 0.1)
				(type default)
			)
			(layer "B.Fab")
		)
		(fp_line
			(start 0.299974 0.150114)
			(end 0.299974 -0.150114)
			(stroke
				(width 0.1)
				(type default)
			)
			(layer "B.Fab")
		)
		(fp_line
			(start -0.299974 -0.150114)
			(end -0.299974 0.150114)
			(stroke
				(width 0.1)
				(type default)
			)
			(layer "B.Fab")
		)
		(fp_line
			(start 0.299974 -0.150114)
			(end -0.299974 -0.150114)
			(stroke
				(width 0.1)
				(type default)
			)
			(layer "B.Fab")
		)
		(pad "1" smd rect
			(at 0.2667 0 90)
			(size 0.3048 0.381)
			(layers "B.Cu" "B.Mask" "B.Paste")
			(net "P0V8_PEX0")
		)
		(pad "2" smd rect
			(at -0.2667 0 90)
			(size 0.3048 0.381)
			(layers "B.Cu" "B.Mask" "B.Paste")
			(net "GND")
		)
	)
	(footprint ""
		(layer "B.Cu")
		(at 288.049716 -292.099746 90)
		(property "Reference" "C1732"
			(at 0 0 90)
			(layer "B.SilkS")
			(hide yes)
			(effects
				(font
					(size 1.27 1.27)
				)
				(justify mirror)
			)
		)
		(property "Value" ""
			(at 0 0 90)
			(layer "B.Fab")
			(effects
				(font
					(size 1.27 1.27)
				)
				(justify mirror)
			)
		)
		(duplicate_pad_numbers_are_jumpers no)
		(fp_line
			(start 0.299974 -0.150114)
			(end -0.299974 -0.150114)
			(stroke
				(width 0.1)
				(type default)
			)
			(layer "B.Fab")
		)
		(fp_line
			(start -0.299974 -0.150114)
			(end -0.299974 0.150114)
			(stroke
				(width 0.1)
				(type default)
			)
			(layer "B.Fab")
		)
		(fp_line
			(start 0.299974 0.150114)
			(end 0.299974 -0.150114)
			(stroke
				(width 0.1)
				(type default)
			)
			(layer "B.Fab")
		)
		(fp_line
			(start -0.299974 0.150114)
			(end 0.299974 0.150114)
			(stroke
				(width 0.1)
				(type default)
			)
			(layer "B.Fab")
		)
		(pad "1" smd rect
			(at 0.2667 0 270)
			(size 0.3048 0.381)
			(layers "B.Cu" "B.Mask" "B.Paste")
			(net "P0V8_SERDES_VDDA_PEX2")
		)
		(pad "2" smd rect
			(at -0.2667 0 270)
			(size 0.3048 0.381)
			(layers "B.Cu" "B.Mask" "B.Paste")
			(net "GND")
		)
	)
	(footprint ""
		(layer "B.Cu")
		(at 314.165234 -443.028832 -90)
		(property "Reference" "J47"
			(at 2.4257 -5.635752 90)
			(unlocked yes)
			(layer "B.SilkS")
			(effects
				(font
					(size 0.7874 0.5842)
					(thickness 0.1524)
				)
				(justify mirror)
			)
		)
		(property "Value" ""
			(at 0 0 90)
			(layer "B.Fab")
			(effects
				(font
					(size 1.27 1.27)
				)
				(justify mirror)
			)
		)
		(duplicate_pad_numbers_are_jumpers no)
		(fp_line
			(start 0 4.011168)
			(end 3.330702 -4.771136)
			(stroke
				(width 0.1524)
				(type default)
			)
			(layer "B.SilkS")
		)
		(fp_line
			(start -3.330702 -4.771136)
			(end 0 4.011168)
			(stroke
				(width 0.1524)
				(type default)
			)
			(layer "B.SilkS")
		)
		(fp_line
			(start 3.330702 -4.771136)
			(end -3.330702 -4.771136)
			(stroke
				(width 0.1524)
				(type default)
			)
			(layer "B.SilkS")
		)
		(fp_line
			(start 0 4.011168)
			(end 3.330702 -4.771136)
			(stroke
				(width 0.1)
				(type default)
			)
			(layer "B.Fab")
		)
		(fp_line
			(start -3.330702 -4.771136)
			(end 0 4.011168)
			(stroke
				(width 0.1)
				(type default)
			)
			(layer "B.Fab")
		)
		(fp_line
			(start 3.330702 -4.771136)
			(end -3.330702 -4.771136)
			(stroke
				(width 0.1)
				(type default)
			)
			(layer "B.Fab")
		)
		(pad "1" thru_hole circle
			(at 0 0 90)
			(size 2.159 2.159)
			(drill 1.7018)
			(layers "*.Cu" "*.Mask")
			(remove_unused_layers no)
			(net "COUPON_GND1")
			(clearance 0.0254)
			(thermal_gap 0.0254)
		)
		(pad "2" thru_hole circle
			(at 1.27 -3.348736 90)
			(size 2.159 2.159)
			(drill 1.7018)
			(layers "*.Cu" "*.Mask")
			(remove_unused_layers no)
			(net "TDR_SE_50_OHM_IN1")
			(clearance 0.0254)
			(thermal_gap 0.0254)
		)
		(pad "3" thru_hole circle
			(at -1.27 -3.348736 90)
			(size 2.159 2.159)
			(drill 1.7018)
			(layers "*.Cu" "*.Mask")
			(remove_unused_layers no)
			(net "TDR_SE_50_OHM_IN1")
			(clearance 0.0254)
			(thermal_gap 0.0254)
		)
	)
	(footprint ""
		(layer "B.Cu")
		(at 351.155 -233.553 90)
		(property "Reference" "R3605"
			(at 0 0 90)
			(layer "B.SilkS")
			(hide yes)
			(effects
				(font
					(size 1.27 1.27)
				)
				(justify mirror)
			)
		)
		(property "Value" ""
			(at 0 0 90)
			(layer "B.Fab")
			(effects
				(font
					(size 1.27 1.27)
				)
				(justify mirror)
			)
		)
		(duplicate_pad_numbers_are_jumpers no)
		(fp_line
			(start 0.7874 -0.4064)
			(end -0.7874 -0.4064)
			(stroke
				(width 0.1524)
				(type default)
			)
			(layer "B.SilkS")
		)
		(fp_line
			(start -0.7874 -0.4064)
			(end -0.7874 0.4064)
			(stroke
				(width 0.1524)
				(type default)
			)
			(layer "B.SilkS")
		)
		(fp_line
			(start 0.7874 0.4064)
			(end 0.7874 -0.4064)
			(stroke
				(width 0.1524)
				(type default)
			)
			(layer "B.SilkS")
		)
		(fp_line
			(start -0.7874 0.4064)
			(end 0.7874 0.4064)
			(stroke
				(width 0.1524)
				(type default)
			)
			(layer "B.SilkS")
		)
		(fp_line
			(start 0.67945 -0.305054)
			(end 0.12065 -0.305054)
			(stroke
				(width 0.1)
				(type default)
			)
			(layer "B.Fab")
		)
		(fp_line
			(start 0.12065 -0.305054)
			(end 0.12065 -0.2794)
			(stroke
				(width 0.1)
				(type default)
			)
			(layer "B.Fab")
		)
		(fp_line
			(start -0.12065 -0.3048)
			(end -0.67945 -0.3048)
			(stroke
				(width 0.1)
				(type default)
			)
			(layer "B.Fab")
		)
		(fp_line
			(start -0.67945 -0.3048)
			(end -0.67945 0.3048)
			(stroke
				(width 0.1)
				(type default)
			)
			(layer "B.Fab")
		)
		(fp_line
			(start 0.12065 -0.2794)
			(end -0.12065 -0.2794)
			(stroke
				(width 0.1)
				(type default)
			)
			(layer "B.Fab")
		)
		(fp_line
			(start -0.12065 -0.2794)
			(end -0.12065 -0.3048)
			(stroke
				(width 0.1)
				(type default)
			)
			(layer "B.Fab")
		)
		(fp_line
			(start 0.12065 0.2794)
			(end 0.12065 0.3048)
			(stroke
				(width 0.1)
				(type default)
			)
			(layer "B.Fab")
		)
		(fp_line
			(start -0.120396 0.2794)
			(end 0.12065 0.2794)
			(stroke
				(width 0.1)
				(type default)
			)
			(layer "B.Fab")
		)
		(fp_line
			(start 0.67945 0.3048)
			(end 0.67945 -0.305054)
			(stroke
				(width 0.1)
				(type default)
			)
			(layer "B.Fab")
		)
		(fp_line
			(start 0.12065 0.3048)
			(end 0.67945 0.3048)
			(stroke
				(width 0.1)
				(type default)
			)
			(layer "B.Fab")
		)
		(fp_line
			(start -0.120396 0.3048)
			(end -0.120396 0.2794)
			(stroke
				(width 0.1)
				(type default)
			)
			(layer "B.Fab")
		)
		(fp_line
			(start -0.67945 0.3048)
			(end -0.120396 0.3048)
			(stroke
				(width 0.1)
				(type default)
			)
			(layer "B.Fab")
		)
		(pad "1" smd circle
			(at 0.40005 0 270)
			(size 0 0)
			(layers "B.Cu" "B.Mask" "B.Paste")
			(net "NIC0_CLK_EN_R_N")
		)
		(pad "2" smd circle
			(at -0.40005 0 270)
			(size 0 0)
			(layers "B.Cu" "B.Mask" "B.Paste")
			(net "NIC0_CLK_EN_N")
		)
	)
	(footprint ""
		(layer "B.Cu")
		(at 178.124866 -286.399732 90)
		(property "Reference" "C3132"
			(at 0 0 90)
			(layer "B.SilkS")
			(hide yes)
			(effects
				(font
					(size 1.27 1.27)
				)
				(justify mirror)
			)
		)
		(property "Value" ""
			(at 0 0 90)
			(layer "B.Fab")
			(effects
				(font
					(size 1.27 1.27)
				)
				(justify mirror)
			)
		)
		(duplicate_pad_numbers_are_jumpers no)
		(fp_line
			(start 0.299974 -0.150114)
			(end -0.299974 -0.150114)
			(stroke
				(width 0.1)
				(type default)
			)
			(layer "B.Fab")
		)
		(fp_line
			(start -0.299974 -0.150114)
			(end -0.299974 0.150114)
			(stroke
				(width 0.1)
				(type default)
			)
			(layer "B.Fab")
		)
		(fp_line
			(start 0.299974 0.150114)
			(end 0.299974 -0.150114)
			(stroke
				(width 0.1)
				(type default)
			)
			(layer "B.Fab")
		)
		(fp_line
			(start -0.299974 0.150114)
			(end 0.299974 0.150114)
			(stroke
				(width 0.1)
				(type default)
			)
			(layer "B.Fab")
		)
		(pad "1" smd rect
			(at 0.2667 0 270)
			(size 0.3048 0.381)
			(layers "B.Cu" "B.Mask" "B.Paste")
			(net "P1V25_SERDES_VDDPLL_PEX1")
		)
		(pad "2" smd rect
			(at -0.2667 0 270)
			(size 0.3048 0.381)
			(layers "B.Cu" "B.Mask" "B.Paste")
			(net "GND")
		)
	)
	(footprint ""
		(layer "B.Cu")
		(at 215.480392 -210.164426)
		(property "Reference" "R5890"
			(at 0 0 0)
			(layer "B.SilkS")
			(hide yes)
			(effects
				(font
					(size 1.27 1.27)
				)
				(justify mirror)
			)
		)
		(property "Value" ""
			(at 0 0 0)
			(layer "B.Fab")
			(effects
				(font
					(size 1.27 1.27)
				)
				(justify mirror)
			)
		)
		(duplicate_pad_numbers_are_jumpers no)
		(fp_line
			(start -0.7874 -0.4064)
			(end -0.7874 0.4064)
			(stroke
				(width 0.1524)
				(type default)
			)
			(layer "B.SilkS")
		)
		(fp_line
			(start -0.7874 0.4064)
			(end 0.7874 0.4064)
			(stroke
				(width 0.1524)
				(type default)
			)
			(layer "B.SilkS")
		)
		(fp_line
			(start 0.7874 -0.4064)
			(end -0.7874 -0.4064)
			(stroke
				(width 0.1524)
				(type default)
			)
			(layer "B.SilkS")
		)
		(fp_line
			(start 0.7874 0.4064)
			(end 0.7874 -0.4064)
			(stroke
				(width 0.1524)
				(type default)
			)
			(layer "B.SilkS")
		)
		(fp_line
			(start -0.67945 -0.3048)
			(end -0.67945 0.3048)
			(stroke
				(width 0.1)
				(type default)
			)
			(layer "B.Fab")
		)
		(fp_line
			(start -0.67945 0.3048)
			(end -0.120396 0.3048)
			(stroke
				(width 0.1)
				(type default)
			)
			(layer "B.Fab")
		)
		(fp_line
			(start -0.12065 -0.3048)
			(end -0.67945 -0.3048)
			(stroke
				(width 0.1)
				(type default)
			)
			(layer "B.Fab")
		)
		(fp_line
			(start -0.12065 -0.2794)
			(end -0.12065 -0.3048)
			(stroke
				(width 0.1)
				(type default)
			)
			(layer "B.Fab")
		)
		(fp_line
			(start -0.120396 0.2794)
			(end 0.12065 0.2794)
			(stroke
				(width 0.1)
				(type default)
			)
			(layer "B.Fab")
		)
		(fp_line
			(start -0.120396 0.3048)
			(end -0.120396 0.2794)
			(stroke
				(width 0.1)
				(type default)
			)
			(layer "B.Fab")
		)
		(fp_line
			(start 0.12065 -0.305054)
			(end 0.12065 -0.2794)
			(stroke
				(width 0.1)
				(type default)
			)
			(layer "B.Fab")
		)
		(fp_line
			(start 0.12065 -0.2794)
			(end -0.12065 -0.2794)
			(stroke
				(width 0.1)
				(type default)
			)
			(layer "B.Fab")
		)
		(fp_line
			(start 0.12065 0.2794)
			(end 0.12065 0.3048)
			(stroke
				(width 0.1)
				(type default)
			)
			(layer "B.Fab")
		)
		(fp_line
			(start 0.12065 0.3048)
			(end 0.67945 0.3048)
			(stroke
				(width 0.1)
				(type default)
			)
			(layer "B.Fab")
		)
		(fp_line
			(start 0.67945 -0.305054)
			(end 0.12065 -0.305054)
			(stroke
				(width 0.1)
				(type default)
			)
			(layer "B.Fab")
		)
		(fp_line
			(start 0.67945 0.3048)
			(end 0.67945 -0.305054)
			(stroke
				(width 0.1)
				(type default)
			)
			(layer "B.Fab")
		)
		(pad "1" smd circle
			(at 0.40005 0 180)
			(size 0 0)
			(layers "B.Cu" "B.Mask" "B.Paste")
			(net "FM_SYS_THROTTLE_R1")
		)
		(pad "2" smd circle
			(at -0.40005 0 180)
			(size 0 0)
			(layers "B.Cu" "B.Mask" "B.Paste")
			(net "FM_SYS_THROTTLE_R")
		)
	)
	(footprint ""
		(layer "B.Cu")
		(at 60.599828 -290.199826 90)
		(property "Reference" "C1221"
			(at 0 0 90)
			(layer "B.SilkS")
			(hide yes)
			(effects
				(font
					(size 1.27 1.27)
				)
				(justify mirror)
			)
		)
		(property "Value" ""
			(at 0 0 90)
			(layer "B.Fab")
			(effects
				(font
					(size 1.27 1.27)
				)
				(justify mirror)
			)
		)
		(duplicate_pad_numbers_are_jumpers no)
		(fp_line
			(start 0.299974 -0.150114)
			(end -0.299974 -0.150114)
			(stroke
				(width 0.1)
				(type default)
			)
			(layer "B.Fab")
		)
		(fp_line
			(start -0.299974 -0.150114)
			(end -0.299974 0.150114)
			(stroke
				(width 0.1)
				(type default)
			)
			(layer "B.Fab")
		)
		(fp_line
			(start 0.299974 0.150114)
			(end 0.299974 -0.150114)
			(stroke
				(width 0.1)
				(type default)
			)
			(layer "B.Fab")
		)
		(fp_line
			(start -0.299974 0.150114)
			(end 0.299974 0.150114)
			(stroke
				(width 0.1)
				(type default)
			)
			(layer "B.Fab")
		)
		(pad "1" smd rect
			(at 0.2667 0 270)
			(size 0.3048 0.381)
			(layers "B.Cu" "B.Mask" "B.Paste")
			(net "P0V8_SERDES_VDDA_PEX0")
		)
		(pad "2" smd rect
			(at -0.2667 0 270)
			(size 0.3048 0.381)
			(layers "B.Cu" "B.Mask" "B.Paste")
			(net "GND")
		)
	)
	(footprint ""
		(layer "B.Cu")
		(at 392.749786 -293.99992)
		(property "Reference" "C3509"
			(at 0 0 0)
			(layer "B.SilkS")
			(hide yes)
			(effects
				(font
					(size 1.27 1.27)
				)
				(justify mirror)
			)
		)
		(property "Value" ""
			(at 0 0 0)
			(layer "B.Fab")
			(effects
				(font
					(size 1.27 1.27)
				)
				(justify mirror)
			)
		)
		(duplicate_pad_numbers_are_jumpers no)
		(fp_line
			(start -0.299974 -0.150114)
			(end -0.299974 0.150114)
			(stroke
				(width 0.1)
				(type default)
			)
			(layer "B.Fab")
		)
		(fp_line
			(start -0.299974 0.150114)
			(end 0.299974 0.150114)
			(stroke
				(width 0.1)
				(type default)
			)
			(layer "B.Fab")
		)
		(fp_line
			(start 0.299974 -0.150114)
			(end -0.299974 -0.150114)
			(stroke
				(width 0.1)
				(type default)
			)
			(layer "B.Fab")
		)
		(fp_line
			(start 0.299974 0.150114)
			(end 0.299974 -0.150114)
			(stroke
				(width 0.1)
				(type default)
			)
			(layer "B.Fab")
		)
		(pad "1" smd rect
			(at 0.2667 0 180)
			(size 0.3048 0.381)
			(layers "B.Cu" "B.Mask" "B.Paste")
			(net "P1V8_PEX")
		)
		(pad "2" smd rect
			(at -0.2667 0 180)
			(size 0.3048 0.381)
			(layers "B.Cu" "B.Mask" "B.Paste")
			(net "GND")
		)
	)
	(footprint ""
		(layer "B.Cu")
		(at 4.581398 -384.554476 -90)
		(property "Reference" "C4461"
			(at 0 0 90)
			(layer "B.SilkS")
			(hide yes)
			(effects
				(font
					(size 1.27 1.27)
				)
				(justify mirror)
			)
		)
		(property "Value" ""
			(at 0 0 90)
			(layer "B.Fab")
			(effects
				(font
					(size 1.27 1.27)
				)
				(justify mirror)
			)
		)
		(duplicate_pad_numbers_are_jumpers no)
		(fp_line
			(start -0.7874 0.4064)
			(end 0.7874 0.4064)
			(stroke
				(width 0.1524)
				(type default)
			)
			(layer "B.SilkS")
		)
		(fp_line
			(start 0.7874 0.4064)
			(end 0.7874 -0.4064)
			(stroke
				(width 0.1524)
				(type default)
			)
			(layer "B.SilkS")
		)
		(fp_line
			(start -0.7874 -0.4064)
			(end -0.7874 0.4064)
			(stroke
				(width 0.1524)
				(type default)
			)
			(layer "B.SilkS")
		)
		(fp_line
			(start 0.7874 -0.4064)
			(end -0.7874 -0.4064)
			(stroke
				(width 0.1524)
				(type default)
			)
			(layer "B.SilkS")
		)
		(fp_line
			(start -0.67945 0.3048)
			(end -0.120396 0.3048)
			(stroke
				(width 0.1)
				(type default)
			)
			(layer "B.Fab")
		)
		(fp_line
			(start -0.120396 0.3048)
			(end -0.120396 0.2794)
			(stroke
				(width 0.1)
				(type default)
			)
			(layer "B.Fab")
		)
		(fp_line
			(start 0.12065 0.3048)
			(end 0.67945 0.3048)
			(stroke
				(width 0.1)
				(type default)
			)
			(layer "B.Fab")
		)
		(fp_line
			(start 0.67945 0.3048)
			(end 0.67945 -0.305054)
			(stroke
				(width 0.1)
				(type default)
			)
			(layer "B.Fab")
		)
		(fp_line
			(start -0.120396 0.2794)
			(end 0.12065 0.2794)
			(stroke
				(width 0.1)
				(type default)
			)
			(layer "B.Fab")
		)
		(fp_line
			(start 0.12065 0.2794)
			(end 0.12065 0.3048)
			(stroke
				(width 0.1)
				(type default)
			)
			(layer "B.Fab")
		)
		(fp_line
			(start -0.12065 -0.2794)
			(end -0.12065 -0.3048)
			(stroke
				(width 0.1)
				(type default)
			)
			(layer "B.Fab")
		)
		(fp_line
			(start 0.12065 -0.2794)
			(end -0.12065 -0.2794)
			(stroke
				(width 0.1)
				(type default)
			)
			(layer "B.Fab")
		)
		(fp_line
			(start -0.67945 -0.3048)
			(end -0.67945 0.3048)
			(stroke
				(width 0.1)
				(type default)
			)
			(layer "B.Fab")
		)
		(fp_line
			(start -0.12065 -0.3048)
			(end -0.67945 -0.3048)
			(stroke
				(width 0.1)
				(type default)
			)
			(layer "B.Fab")
		)
		(fp_line
			(start 0.12065 -0.305054)
			(end 0.12065 -0.2794)
			(stroke
				(width 0.1)
				(type default)
			)
			(layer "B.Fab")
		)
		(fp_line
			(start 0.67945 -0.305054)
			(end 0.12065 -0.305054)
			(stroke
				(width 0.1)
				(type default)
			)
			(layer "B.Fab")
		)
		(pad "1" smd circle
			(at 0.40005 0 90)
			(size 0 0)
			(layers "B.Cu" "B.Mask" "B.Paste")
			(net "P3V3_USB_8042")
		)
		(pad "2" smd circle
			(at -0.40005 0 90)
			(size 0 0)
			(layers "B.Cu" "B.Mask" "B.Paste")
			(net "GND")
		)
	)
	(footprint ""
		(layer "B.Cu")
		(at 350.65716 -317.706756)
		(property "Reference" "C4378"
			(at 0 0 0)
			(layer "B.SilkS")
			(hide yes)
			(effects
				(font
					(size 1.27 1.27)
				)
				(justify mirror)
			)
		)
		(property "Value" ""
			(at 0 0 0)
			(layer "B.Fab")
			(effects
				(font
					(size 1.27 1.27)
				)
				(justify mirror)
			)
		)
		(duplicate_pad_numbers_are_jumpers no)
		(fp_line
			(start -0.299974 -0.150114)
			(end -0.299974 0.150114)
			(stroke
				(width 0.1)
				(type default)
			)
			(layer "B.Fab")
		)
		(fp_line
			(start -0.299974 0.150114)
			(end 0.299974 0.150114)
			(stroke
				(width 0.1)
				(type default)
			)
			(layer "B.Fab")
		)
		(fp_line
			(start 0.299974 -0.150114)
			(end -0.299974 -0.150114)
			(stroke
				(width 0.1)
				(type default)
			)
			(layer "B.Fab")
		)
		(fp_line
			(start 0.299974 0.150114)
			(end 0.299974 -0.150114)
			(stroke
				(width 0.1)
				(type default)
			)
			(layer "B.Fab")
		)
		(pad "1" smd rect
			(at 0.2667 0 180)
			(size 0.3048 0.381)
			(layers "B.Cu" "B.Mask" "B.Paste")
			(net "P0V8_SERDES_VDDA_PEX3")
		)
		(pad "2" smd rect
			(at -0.2667 0 180)
			(size 0.3048 0.381)
			(layers "B.Cu" "B.Mask" "B.Paste")
			(net "GND")
		)
	)
	(footprint ""
		(layer "B.Cu")
		(at 5.401818 -381.906526 180)
		(property "Reference" "C4465"
			(at 0 0 0)
			(layer "B.SilkS")
			(hide yes)
			(effects
				(font
					(size 1.27 1.27)
				)
				(justify mirror)
			)
		)
		(property "Value" ""
			(at 0 0 0)
			(layer "B.Fab")
			(effects
				(font
					(size 1.27 1.27)
				)
				(justify mirror)
			)
		)
		(duplicate_pad_numbers_are_jumpers no)
		(fp_line
			(start 1.524 0.762)
			(end 1.524 -0.762)
			(stroke
				(width 0.1524)
				(type default)
			)
			(layer "B.SilkS")
		)
		(fp_line
			(start 1.524 -0.762)
			(end -1.524 -0.762)
			(stroke
				(width 0.1524)
				(type default)
			)
			(layer "B.SilkS")
		)
		(fp_line
			(start -1.524 0.762)
			(end 1.524 0.762)
			(stroke
				(width 0.1524)
				(type default)
			)
			(layer "B.SilkS")
		)
		(fp_line
			(start -1.524 -0.762)
			(end -1.524 0.762)
			(stroke
				(width 0.1524)
				(type default)
			)
			(layer "B.SilkS")
		)
		(fp_line
			(start 1.1049 0.724916)
			(end -1.1049 0.724916)
			(stroke
				(width 0.1)
				(type default)
			)
			(layer "B.Fab")
		)
		(fp_line
			(start 1.1049 -0.724916)
			(end 1.1049 0.724916)
			(stroke
				(width 0.1)
				(type default)
			)
			(layer "B.Fab")
		)
		(fp_line
			(start -1.1049 0.724916)
			(end -1.1049 -0.724916)
			(stroke
				(width 0.1)
				(type default)
			)
			(layer "B.Fab")
		)
		(fp_line
			(start -1.1049 -0.724916)
			(end 1.1049 -0.724916)
			(stroke
				(width 0.1)
				(type default)
			)
			(layer "B.Fab")
		)
		(pad "1" smd rect
			(at 0.889 0 180)
			(size 1.016 1.27)
			(layers "B.Cu" "B.Mask" "B.Paste")
			(net "P3V3_USB_8042")
		)
		(pad "2" smd rect
			(at -0.889 0 180)
			(size 1.016 1.27)
			(layers "B.Cu" "B.Mask" "B.Paste")
			(net "GND")
		)
	)
	(footprint ""
		(layer "B.Cu")
		(at 397.54556 -296.37482)
		(property "Reference" "C1892"
			(at 0 0 0)
			(layer "B.SilkS")
			(hide yes)
			(effects
				(font
					(size 1.27 1.27)
				)
				(justify mirror)
			)
		)
		(property "Value" ""
			(at 0 0 0)
			(layer "B.Fab")
			(effects
				(font
					(size 1.27 1.27)
				)
				(justify mirror)
			)
		)
		(duplicate_pad_numbers_are_jumpers no)
		(fp_line
			(start -0.299974 -0.150114)
			(end -0.299974 0.150114)
			(stroke
				(width 0.1)
				(type default)
			)
			(layer "B.Fab")
		)
		(fp_line
			(start -0.299974 0.150114)
			(end 0.299974 0.150114)
			(stroke
				(width 0.1)
				(type default)
			)
			(layer "B.Fab")
		)
		(fp_line
			(start 0.299974 -0.150114)
			(end -0.299974 -0.150114)
			(stroke
				(width 0.1)
				(type default)
			)
			(layer "B.Fab")
		)
		(fp_line
			(start 0.299974 0.150114)
			(end 0.299974 -0.150114)
			(stroke
				(width 0.1)
				(type default)
			)
			(layer "B.Fab")
		)
		(pad "1" smd rect
			(at 0.2667 0 180)
			(size 0.3048 0.381)
			(layers "B.Cu" "B.Mask" "B.Paste")
			(net "P0V8_PEX3")
		)
		(pad "2" smd rect
			(at -0.2667 0 180)
			(size 0.3048 0.381)
			(layers "B.Cu" "B.Mask" "B.Paste")
			(net "GND")
		)
	)
	(footprint ""
		(layer "B.Cu")
		(at 172.900086 -303.499774 -90)
		(property "Reference" "C3090"
			(at 0 0 90)
			(layer "B.SilkS")
			(hide yes)
			(effects
				(font
					(size 1.27 1.27)
				)
				(justify mirror)
			)
		)
		(property "Value" ""
			(at 0 0 90)
			(layer "B.Fab")
			(effects
				(font
					(size 1.27 1.27)
				)
				(justify mirror)
			)
		)
		(duplicate_pad_numbers_are_jumpers no)
		(fp_line
			(start -0.299974 0.150114)
			(end 0.299974 0.150114)
			(stroke
				(width 0.1)
				(type default)
			)
			(layer "B.Fab")
		)
		(fp_line
			(start 0.299974 0.150114)
			(end 0.299974 -0.150114)
			(stroke
				(width 0.1)
				(type default)
			)
			(layer "B.Fab")
		)
		(fp_line
			(start -0.299974 -0.150114)
			(end -0.299974 0.150114)
			(stroke
				(width 0.1)
				(type default)
			)
			(layer "B.Fab")
		)
		(fp_line
			(start 0.299974 -0.150114)
			(end -0.299974 -0.150114)
			(stroke
				(width 0.1)
				(type default)
			)
			(layer "B.Fab")
		)
		(pad "1" smd rect
			(at 0.2667 0 90)
			(size 0.3048 0.381)
			(layers "B.Cu" "B.Mask" "B.Paste")
			(net "P1V25_PEX1")
		)
		(pad "2" smd rect
			(at -0.2667 0 90)
			(size 0.3048 0.381)
			(layers "B.Cu" "B.Mask" "B.Paste")
			(net "GND")
		)
	)
	(footprint ""
		(layer "B.Cu")
		(at 243.3193 -206.588868 180)
		(property "Reference" "C2015"
			(at 0 0 0)
			(layer "B.SilkS")
			(hide yes)
			(effects
				(font
					(size 1.27 1.27)
				)
				(justify mirror)
			)
		)
		(property "Value" ""
			(at 0 0 0)
			(layer "B.Fab")
			(effects
				(font
					(size 1.27 1.27)
				)
				(justify mirror)
			)
		)
		(duplicate_pad_numbers_are_jumpers no)
		(fp_line
			(start 1.2954 0.5842)
			(end 1.2954 -0.5842)
			(stroke
				(width 0.1524)
				(type default)
			)
			(layer "B.SilkS")
		)
		(fp_line
			(start 1.2954 -0.5842)
			(end -1.2954 -0.5842)
			(stroke
				(width 0.1524)
				(type default)
			)
			(layer "B.SilkS")
		)
		(fp_line
			(start -1.2954 0.5842)
			(end 1.2954 0.5842)
			(stroke
				(width 0.1524)
				(type default)
			)
			(layer "B.SilkS")
		)
		(fp_line
			(start -1.2954 -0.5842)
			(end -1.2954 0.5842)
			(stroke
				(width 0.1524)
				(type default)
			)
			(layer "B.SilkS")
		)
		(fp_line
			(start 1.1938 0.4064)
			(end 1.1938 -0.4064)
			(stroke
				(width 0.1)
				(type default)
			)
			(layer "B.Fab")
		)
		(fp_line
			(start 1.1938 -0.4064)
			(end 0.8636 -0.4064)
			(stroke
				(width 0.1)
				(type default)
			)
			(layer "B.Fab")
		)
		(fp_line
			(start 0.8636 0.4572)
			(end 0.8636 0.4064)
			(stroke
				(width 0.1)
				(type default)
			)
			(layer "B.Fab")
		)
		(fp_line
			(start 0.8636 0.4064)
			(end 1.1938 0.4064)
			(stroke
				(width 0.1)
				(type default)
			)
			(layer "B.Fab")
		)
		(fp_line
			(start 0.8636 -0.4064)
			(end 0.8636 -0.4572)
			(stroke
				(width 0.1)
				(type default)
			)
			(layer "B.Fab")
		)
		(fp_line
			(start 0.8636 -0.4572)
			(end -0.8636 -0.4572)
			(stroke
				(width 0.1)
				(type default)
			)
			(layer "B.Fab")
		)
		(fp_line
			(start -0.8636 0.4572)
			(end 0.8636 0.4572)
			(stroke
				(width 0.1)
				(type default)
			)
			(layer "B.Fab")
		)
		(fp_line
			(start -0.8636 0.4064)
			(end -0.8636 0.4572)
			(stroke
				(width 0.1)
				(type default)
			)
			(layer "B.Fab")
		)
		(fp_line
			(start -0.8636 -0.4064)
			(end -1.1938 -0.4064)
			(stroke
				(width 0.1)
				(type default)
			)
			(layer "B.Fab")
		)
		(fp_line
			(start -0.8636 -0.4572)
			(end -0.8636 -0.4064)
			(stroke
				(width 0.1)
				(type default)
			)
			(layer "B.Fab")
		)
		(fp_line
			(start -1.1938 0.4064)
			(end -0.8636 0.4064)
			(stroke
				(width 0.1)
				(type default)
			)
			(layer "B.Fab")
		)
		(fp_line
			(start -1.1938 -0.4064)
			(end -1.1938 0.4064)
			(stroke
				(width 0.1)
				(type default)
			)
			(layer "B.Fab")
		)
		(pad "1" smd rect
			(at 0.7366 0 90)
			(size 0.7112 0.8128)
			(layers "B.Cu" "B.Mask" "B.Paste")
			(net "P1V2_AUX")
		)
		(pad "2" smd rect
			(at -0.7366 0 90)
			(size 0.7112 0.8128)
			(layers "B.Cu" "B.Mask" "B.Paste")
			(net "GND")
		)
	)
	(footprint ""
		(layer "B.Cu")
		(at 335.72958 -87.890604 180)
		(property "Reference" "C2682"
			(at 0 0 0)
			(layer "B.SilkS")
			(hide yes)
			(effects
				(font
					(size 1.27 1.27)
				)
				(justify mirror)
			)
		)
		(property "Value" ""
			(at 0 0 0)
			(layer "B.Fab")
			(effects
				(font
					(size 1.27 1.27)
				)
				(justify mirror)
			)
		)
		(duplicate_pad_numbers_are_jumpers no)
		(fp_line
			(start 0.7874 0.4064)
			(end 0.7874 -0.4064)
			(stroke
				(width 0.1524)
				(type default)
			)
			(layer "B.SilkS")
		)
		(fp_line
			(start 0.7874 -0.4064)
			(end -0.7874 -0.4064)
			(stroke
				(width 0.1524)
				(type default)
			)
			(layer "B.SilkS")
		)
		(fp_line
			(start -0.7874 0.4064)
			(end 0.7874 0.4064)
			(stroke
				(width 0.1524)
				(type default)
			)
			(layer "B.SilkS")
		)
		(fp_line
			(start -0.7874 -0.4064)
			(end -0.7874 0.4064)
			(stroke
				(width 0.1524)
				(type default)
			)
			(layer "B.SilkS")
		)
		(fp_line
			(start 0.67945 0.3048)
			(end 0.67945 -0.305054)
			(stroke
				(width 0.1)
				(type default)
			)
			(layer "B.Fab")
		)
		(fp_line
			(start 0.67945 -0.305054)
			(end 0.12065 -0.305054)
			(stroke
				(width 0.1)
				(type default)
			)
			(layer "B.Fab")
		)
		(fp_line
			(start 0.12065 0.3048)
			(end 0.67945 0.3048)
			(stroke
				(width 0.1)
				(type default)
			)
			(layer "B.Fab")
		)
		(fp_line
			(start 0.12065 0.2794)
			(end 0.12065 0.3048)
			(stroke
				(width 0.1)
				(type default)
			)
			(layer "B.Fab")
		)
		(fp_line
			(start 0.12065 -0.2794)
			(end -0.12065 -0.2794)
			(stroke
				(width 0.1)
				(type default)
			)
			(layer "B.Fab")
		)
		(fp_line
			(start 0.12065 -0.305054)
			(end 0.12065 -0.2794)
			(stroke
				(width 0.1)
				(type default)
			)
			(layer "B.Fab")
		)
		(fp_line
			(start -0.120396 0.3048)
			(end -0.120396 0.2794)
			(stroke
				(width 0.1)
				(type default)
			)
			(layer "B.Fab")
		)
		(fp_line
			(start -0.120396 0.2794)
			(end 0.12065 0.2794)
			(stroke
				(width 0.1)
				(type default)
			)
			(layer "B.Fab")
		)
		(fp_line
			(start -0.12065 -0.2794)
			(end -0.12065 -0.3048)
			(stroke
				(width 0.1)
				(type default)
			)
			(layer "B.Fab")
		)
		(fp_line
			(start -0.12065 -0.3048)
			(end -0.67945 -0.3048)
			(stroke
				(width 0.1)
				(type default)
			)
			(layer "B.Fab")
		)
		(fp_line
			(start -0.67945 0.3048)
			(end -0.120396 0.3048)
			(stroke
				(width 0.1)
				(type default)
			)
			(layer "B.Fab")
		)
		(fp_line
			(start -0.67945 -0.3048)
			(end -0.67945 0.3048)
			(stroke
				(width 0.1)
				(type default)
			)
			(layer "B.Fab")
		)
		(pad "1" smd circle
			(at 0.40005 0)
			(size 0 0)
			(layers "B.Cu" "B.Mask" "B.Paste")
			(net "P3V3_VDDAR_9ZXL0851_8_15")
		)
		(pad "2" smd circle
			(at -0.40005 0)
			(size 0 0)
			(layers "B.Cu" "B.Mask" "B.Paste")
			(net "GND")
		)
	)
	(footprint ""
		(layer "B.Cu")
		(at 261.536942 -81.001616 -90)
		(property "Reference" "C2631"
			(at 0 0 90)
			(layer "B.SilkS")
			(hide yes)
			(effects
				(font
					(size 1.27 1.27)
				)
				(justify mirror)
			)
		)
		(property "Value" ""
			(at 0 0 90)
			(layer "B.Fab")
			(effects
				(font
					(size 1.27 1.27)
				)
				(justify mirror)
			)
		)
		(duplicate_pad_numbers_are_jumpers no)
		(fp_line
			(start -0.7874 0.4064)
			(end 0.7874 0.4064)
			(stroke
				(width 0.1524)
				(type default)
			)
			(layer "B.SilkS")
		)
		(fp_line
			(start 0.7874 0.4064)
			(end 0.7874 -0.4064)
			(stroke
				(width 0.1524)
				(type default)
			)
			(layer "B.SilkS")
		)
		(fp_line
			(start -0.7874 -0.4064)
			(end -0.7874 0.4064)
			(stroke
				(width 0.1524)
				(type default)
			)
			(layer "B.SilkS")
		)
		(fp_line
			(start 0.7874 -0.4064)
			(end -0.7874 -0.4064)
			(stroke
				(width 0.1524)
				(type default)
			)
			(layer "B.SilkS")
		)
		(fp_line
			(start -0.67945 0.3048)
			(end -0.120396 0.3048)
			(stroke
				(width 0.1)
				(type default)
			)
			(layer "B.Fab")
		)
		(fp_line
			(start -0.120396 0.3048)
			(end -0.120396 0.2794)
			(stroke
				(width 0.1)
				(type default)
			)
			(layer "B.Fab")
		)
		(fp_line
			(start 0.12065 0.3048)
			(end 0.67945 0.3048)
			(stroke
				(width 0.1)
				(type default)
			)
			(layer "B.Fab")
		)
		(fp_line
			(start 0.67945 0.3048)
			(end 0.67945 -0.305054)
			(stroke
				(width 0.1)
				(type default)
			)
			(layer "B.Fab")
		)
		(fp_line
			(start -0.120396 0.2794)
			(end 0.12065 0.2794)
			(stroke
				(width 0.1)
				(type default)
			)
			(layer "B.Fab")
		)
		(fp_line
			(start 0.12065 0.2794)
			(end 0.12065 0.3048)
			(stroke
				(width 0.1)
				(type default)
			)
			(layer "B.Fab")
		)
		(fp_line
			(start -0.12065 -0.2794)
			(end -0.12065 -0.3048)
			(stroke
				(width 0.1)
				(type default)
			)
			(layer "B.Fab")
		)
		(fp_line
			(start 0.12065 -0.2794)
			(end -0.12065 -0.2794)
			(stroke
				(width 0.1)
				(type default)
			)
			(layer "B.Fab")
		)
		(fp_line
			(start -0.67945 -0.3048)
			(end -0.67945 0.3048)
			(stroke
				(width 0.1)
				(type default)
			)
			(layer "B.Fab")
		)
		(fp_line
			(start -0.12065 -0.3048)
			(end -0.67945 -0.3048)
			(stroke
				(width 0.1)
				(type default)
			)
			(layer "B.Fab")
		)
		(fp_line
			(start 0.12065 -0.305054)
			(end 0.12065 -0.2794)
			(stroke
				(width 0.1)
				(type default)
			)
			(layer "B.Fab")
		)
		(fp_line
			(start 0.67945 -0.305054)
			(end 0.12065 -0.305054)
			(stroke
				(width 0.1)
				(type default)
			)
			(layer "B.Fab")
		)
		(pad "1" smd circle
			(at 0.40005 0 90)
			(size 0 0)
			(layers "B.Cu" "B.Mask" "B.Paste")
			(net "P3V3_CLK_GEN_VDD_CK440")
		)
		(pad "2" smd circle
			(at -0.40005 0 90)
			(size 0 0)
			(layers "B.Cu" "B.Mask" "B.Paste")
			(net "GND")
		)
	)
	(footprint ""
		(layer "B.Cu")
		(at 124.331222 -200.92035)
		(property "Reference" "R923"
			(at 0 0 0)
			(layer "B.SilkS")
			(hide yes)
			(effects
				(font
					(size 1.27 1.27)
				)
				(justify mirror)
			)
		)
		(property "Value" ""
			(at 0 0 0)
			(layer "B.Fab")
			(effects
				(font
					(size 1.27 1.27)
				)
				(justify mirror)
			)
		)
		(duplicate_pad_numbers_are_jumpers no)
		(fp_line
			(start -0.7874 -0.4064)
			(end -0.7874 0.4064)
			(stroke
				(width 0.1524)
				(type default)
			)
			(layer "B.SilkS")
		)
		(fp_line
			(start -0.7874 0.4064)
			(end 0.7874 0.4064)
			(stroke
				(width 0.1524)
				(type default)
			)
			(layer "B.SilkS")
		)
		(fp_line
			(start 0.7874 -0.4064)
			(end -0.7874 -0.4064)
			(stroke
				(width 0.1524)
				(type default)
			)
			(layer "B.SilkS")
		)
		(fp_line
			(start 0.7874 0.4064)
			(end 0.7874 -0.4064)
			(stroke
				(width 0.1524)
				(type default)
			)
			(layer "B.SilkS")
		)
		(fp_line
			(start -0.67945 -0.3048)
			(end -0.67945 0.3048)
			(stroke
				(width 0.1)
				(type default)
			)
			(layer "B.Fab")
		)
		(fp_line
			(start -0.67945 0.3048)
			(end -0.120396 0.3048)
			(stroke
				(width 0.1)
				(type default)
			)
			(layer "B.Fab")
		)
		(fp_line
			(start -0.12065 -0.3048)
			(end -0.67945 -0.3048)
			(stroke
				(width 0.1)
				(type default)
			)
			(layer "B.Fab")
		)
		(fp_line
			(start -0.12065 -0.2794)
			(end -0.12065 -0.3048)
			(stroke
				(width 0.1)
				(type default)
			)
			(layer "B.Fab")
		)
		(fp_line
			(start -0.120396 0.2794)
			(end 0.12065 0.2794)
			(stroke
				(width 0.1)
				(type default)
			)
			(layer "B.Fab")
		)
		(fp_line
			(start -0.120396 0.3048)
			(end -0.120396 0.2794)
			(stroke
				(width 0.1)
				(type default)
			)
			(layer "B.Fab")
		)
		(fp_line
			(start 0.12065 -0.305054)
			(end 0.12065 -0.2794)
			(stroke
				(width 0.1)
				(type default)
			)
			(layer "B.Fab")
		)
		(fp_line
			(start 0.12065 -0.2794)
			(end -0.12065 -0.2794)
			(stroke
				(width 0.1)
				(type default)
			)
			(layer "B.Fab")
		)
		(fp_line
			(start 0.12065 0.2794)
			(end 0.12065 0.3048)
			(stroke
				(width 0.1)
				(type default)
			)
			(layer "B.Fab")
		)
		(fp_line
			(start 0.12065 0.3048)
			(end 0.67945 0.3048)
			(stroke
				(width 0.1)
				(type default)
			)
			(layer "B.Fab")
		)
		(fp_line
			(start 0.67945 -0.305054)
			(end 0.12065 -0.305054)
			(stroke
				(width 0.1)
				(type default)
			)
			(layer "B.Fab")
		)
		(fp_line
			(start 0.67945 0.3048)
			(end 0.67945 -0.305054)
			(stroke
				(width 0.1)
				(type default)
			)
			(layer "B.Fab")
		)
		(pad "1" smd circle
			(at 0.40005 0 180)
			(size 0 0)
			(layers "B.Cu" "B.Mask" "B.Paste")
			(net "FT4232_CLI_EEPROM_R_SDA")
		)
		(pad "2" smd circle
			(at -0.40005 0 180)
			(size 0 0)
			(layers "B.Cu" "B.Mask" "B.Paste")
			(net "FT4232_CLI_EEPROM_DO")
		)
	)
	(footprint ""
		(layer "B.Cu")
		(at 56.799988 -292.099746 90)
		(property "Reference" "C1197"
			(at 0 0 90)
			(layer "B.SilkS")
			(hide yes)
			(effects
				(font
					(size 1.27 1.27)
				)
				(justify mirror)
			)
		)
		(property "Value" ""
			(at 0 0 90)
			(layer "B.Fab")
			(effects
				(font
					(size 1.27 1.27)
				)
				(justify mirror)
			)
		)
		(duplicate_pad_numbers_are_jumpers no)
		(fp_line
			(start 0.299974 -0.150114)
			(end -0.299974 -0.150114)
			(stroke
				(width 0.1)
				(type default)
			)
			(layer "B.Fab")
		)
		(fp_line
			(start -0.299974 -0.150114)
			(end -0.299974 0.150114)
			(stroke
				(width 0.1)
				(type default)
			)
			(layer "B.Fab")
		)
		(fp_line
			(start 0.299974 0.150114)
			(end 0.299974 -0.150114)
			(stroke
				(width 0.1)
				(type default)
			)
			(layer "B.Fab")
		)
		(fp_line
			(start -0.299974 0.150114)
			(end 0.299974 0.150114)
			(stroke
				(width 0.1)
				(type default)
			)
			(layer "B.Fab")
		)
		(pad "1" smd rect
			(at 0.2667 0 270)
			(size 0.3048 0.381)
			(layers "B.Cu" "B.Mask" "B.Paste")
			(net "P0V8_SERDES_VDDA_PEX0")
		)
		(pad "2" smd rect
			(at -0.2667 0 270)
			(size 0.3048 0.381)
			(layers "B.Cu" "B.Mask" "B.Paste")
			(net "GND")
		)
	)
	(footprint ""
		(layer "B.Cu")
		(at 295.583356 -108.462318 180)
		(property "Reference" "R285"
			(at 0 0 0)
			(layer "B.SilkS")
			(hide yes)
			(effects
				(font
					(size 1.27 1.27)
				)
				(justify mirror)
			)
		)
		(property "Value" ""
			(at 0 0 0)
			(layer "B.Fab")
			(effects
				(font
					(size 1.27 1.27)
				)
				(justify mirror)
			)
		)
		(duplicate_pad_numbers_are_jumpers no)
		(fp_line
			(start 0.7874 0.4064)
			(end 0.7874 -0.4064)
			(stroke
				(width 0.1524)
				(type default)
			)
			(layer "B.SilkS")
		)
		(fp_line
			(start 0.7874 -0.4064)
			(end -0.7874 -0.4064)
			(stroke
				(width 0.1524)
				(type default)
			)
			(layer "B.SilkS")
		)
		(fp_line
			(start -0.7874 0.4064)
			(end 0.7874 0.4064)
			(stroke
				(width 0.1524)
				(type default)
			)
			(layer "B.SilkS")
		)
		(fp_line
			(start -0.7874 -0.4064)
			(end -0.7874 0.4064)
			(stroke
				(width 0.1524)
				(type default)
			)
			(layer "B.SilkS")
		)
		(fp_line
			(start 0.67945 0.3048)
			(end 0.67945 -0.305054)
			(stroke
				(width 0.1)
				(type default)
			)
			(layer "B.Fab")
		)
		(fp_line
			(start 0.67945 -0.305054)
			(end 0.12065 -0.305054)
			(stroke
				(width 0.1)
				(type default)
			)
			(layer "B.Fab")
		)
		(fp_line
			(start 0.12065 0.3048)
			(end 0.67945 0.3048)
			(stroke
				(width 0.1)
				(type default)
			)
			(layer "B.Fab")
		)
		(fp_line
			(start 0.12065 0.2794)
			(end 0.12065 0.3048)
			(stroke
				(width 0.1)
				(type default)
			)
			(layer "B.Fab")
		)
		(fp_line
			(start 0.12065 -0.2794)
			(end -0.12065 -0.2794)
			(stroke
				(width 0.1)
				(type default)
			)
			(layer "B.Fab")
		)
		(fp_line
			(start 0.12065 -0.305054)
			(end 0.12065 -0.2794)
			(stroke
				(width 0.1)
				(type default)
			)
			(layer "B.Fab")
		)
		(fp_line
			(start -0.120396 0.3048)
			(end -0.120396 0.2794)
			(stroke
				(width 0.1)
				(type default)
			)
			(layer "B.Fab")
		)
		(fp_line
			(start -0.120396 0.2794)
			(end 0.12065 0.2794)
			(stroke
				(width 0.1)
				(type default)
			)
			(layer "B.Fab")
		)
		(fp_line
			(start -0.12065 -0.2794)
			(end -0.12065 -0.3048)
			(stroke
				(width 0.1)
				(type default)
			)
			(layer "B.Fab")
		)
		(fp_line
			(start -0.12065 -0.3048)
			(end -0.67945 -0.3048)
			(stroke
				(width 0.1)
				(type default)
			)
			(layer "B.Fab")
		)
		(fp_line
			(start -0.67945 0.3048)
			(end -0.120396 0.3048)
			(stroke
				(width 0.1)
				(type default)
			)
			(layer "B.Fab")
		)
		(fp_line
			(start -0.67945 -0.3048)
			(end -0.67945 0.3048)
			(stroke
				(width 0.1)
				(type default)
			)
			(layer "B.Fab")
		)
		(pad "1" smd circle
			(at 0.40005 0)
			(size 0 0)
			(layers "B.Cu" "B.Mask" "B.Paste")
			(net "NIC5_BIF0_N")
		)
		(pad "2" smd circle
			(at -0.40005 0)
			(size 0 0)
			(layers "B.Cu" "B.Mask" "B.Paste")
			(net "GND")
		)
	)
	(footprint ""
		(layer "B.Cu")
		(at 357.620316 -285.613348 -90)
		(property "Reference" "PR7181"
			(at 0 0 90)
			(layer "B.SilkS")
			(hide yes)
			(effects
				(font
					(size 1.27 1.27)
				)
				(justify mirror)
			)
		)
		(property "Value" ""
			(at 0 0 90)
			(layer "B.Fab")
			(effects
				(font
					(size 1.27 1.27)
				)
				(justify mirror)
			)
		)
		(duplicate_pad_numbers_are_jumpers no)
		(fp_line
			(start -0.7874 0.4064)
			(end 0.7874 0.4064)
			(stroke
				(width 0.1524)
				(type default)
			)
			(layer "B.SilkS")
		)
		(fp_line
			(start 0.7874 0.4064)
			(end 0.7874 -0.4064)
			(stroke
				(width 0.1524)
				(type default)
			)
			(layer "B.SilkS")
		)
		(fp_line
			(start -0.7874 -0.4064)
			(end -0.7874 0.4064)
			(stroke
				(width 0.1524)
				(type default)
			)
			(layer "B.SilkS")
		)
		(fp_line
			(start 0.7874 -0.4064)
			(end -0.7874 -0.4064)
			(stroke
				(width 0.1524)
				(type default)
			)
			(layer "B.SilkS")
		)
		(fp_line
			(start -0.67945 0.3048)
			(end -0.120396 0.3048)
			(stroke
				(width 0.1)
				(type default)
			)
			(layer "B.Fab")
		)
		(fp_line
			(start -0.120396 0.3048)
			(end -0.120396 0.2794)
			(stroke
				(width 0.1)
				(type default)
			)
			(layer "B.Fab")
		)
		(fp_line
			(start 0.12065 0.3048)
			(end 0.67945 0.3048)
			(stroke
				(width 0.1)
				(type default)
			)
			(layer "B.Fab")
		)
		(fp_line
			(start 0.67945 0.3048)
			(end 0.67945 -0.305054)
			(stroke
				(width 0.1)
				(type default)
			)
			(layer "B.Fab")
		)
		(fp_line
			(start -0.120396 0.2794)
			(end 0.12065 0.2794)
			(stroke
				(width 0.1)
				(type default)
			)
			(layer "B.Fab")
		)
		(fp_line
			(start 0.12065 0.2794)
			(end 0.12065 0.3048)
			(stroke
				(width 0.1)
				(type default)
			)
			(layer "B.Fab")
		)
		(fp_line
			(start -0.12065 -0.2794)
			(end -0.12065 -0.3048)
			(stroke
				(width 0.1)
				(type default)
			)
			(layer "B.Fab")
		)
		(fp_line
			(start 0.12065 -0.2794)
			(end -0.12065 -0.2794)
			(stroke
				(width 0.1)
				(type default)
			)
			(layer "B.Fab")
		)
		(fp_line
			(start -0.67945 -0.3048)
			(end -0.67945 0.3048)
			(stroke
				(width 0.1)
				(type default)
			)
			(layer "B.Fab")
		)
		(fp_line
			(start -0.12065 -0.3048)
			(end -0.67945 -0.3048)
			(stroke
				(width 0.1)
				(type default)
			)
			(layer "B.Fab")
		)
		(fp_line
			(start 0.12065 -0.305054)
			(end 0.12065 -0.2794)
			(stroke
				(width 0.1)
				(type default)
			)
			(layer "B.Fab")
		)
		(fp_line
			(start 0.67945 -0.305054)
			(end 0.12065 -0.305054)
			(stroke
				(width 0.1)
				(type default)
			)
			(layer "B.Fab")
		)
		(pad "1" smd circle
			(at 0.40005 0 90)
			(size 0 0)
			(layers "B.Cu" "B.Mask" "B.Paste")
			(net "P0V8_PEX3_PVCC")
		)
		(pad "2" smd circle
			(at -0.40005 0 90)
			(size 0 0)
			(layers "B.Cu" "B.Mask" "B.Paste")
			(net "P3V3_AUX")
		)
	)
	(footprint ""
		(layer "B.Cu")
		(at 406.999948 -301.599854 -90)
		(property "Reference" "C1951"
			(at 0 0 90)
			(layer "B.SilkS")
			(hide yes)
			(effects
				(font
					(size 1.27 1.27)
				)
				(justify mirror)
			)
		)
		(property "Value" ""
			(at 0 0 90)
			(layer "B.Fab")
			(effects
				(font
					(size 1.27 1.27)
				)
				(justify mirror)
			)
		)
		(duplicate_pad_numbers_are_jumpers no)
		(fp_line
			(start -0.299974 0.150114)
			(end 0.299974 0.150114)
			(stroke
				(width 0.1)
				(type default)
			)
			(layer "B.Fab")
		)
		(fp_line
			(start 0.299974 0.150114)
			(end 0.299974 -0.150114)
			(stroke
				(width 0.1)
				(type default)
			)
			(layer "B.Fab")
		)
		(fp_line
			(start -0.299974 -0.150114)
			(end -0.299974 0.150114)
			(stroke
				(width 0.1)
				(type default)
			)
			(layer "B.Fab")
		)
		(fp_line
			(start 0.299974 -0.150114)
			(end -0.299974 -0.150114)
			(stroke
				(width 0.1)
				(type default)
			)
			(layer "B.Fab")
		)
		(pad "1" smd rect
			(at 0.2667 0 90)
			(size 0.3048 0.381)
			(layers "B.Cu" "B.Mask" "B.Paste")
			(net "P0V8_SERDES_VDDA_PEX3")
		)
		(pad "2" smd rect
			(at -0.2667 0 90)
			(size 0.3048 0.381)
			(layers "B.Cu" "B.Mask" "B.Paste")
			(net "GND")
		)
	)
	(footprint ""
		(layer "B.Cu")
		(at 163.874958 -295.4528 90)
		(property "Reference" "C3214"
			(at 0 0 90)
			(layer "B.SilkS")
			(hide yes)
			(effects
				(font
					(size 1.27 1.27)
				)
				(justify mirror)
			)
		)
		(property "Value" ""
			(at 0 0 90)
			(layer "B.Fab")
			(effects
				(font
					(size 1.27 1.27)
				)
				(justify mirror)
			)
		)
		(duplicate_pad_numbers_are_jumpers no)
		(fp_line
			(start 0.299974 -0.150114)
			(end -0.299974 -0.150114)
			(stroke
				(width 0.1)
				(type default)
			)
			(layer "B.Fab")
		)
		(fp_line
			(start -0.299974 -0.150114)
			(end -0.299974 0.150114)
			(stroke
				(width 0.1)
				(type default)
			)
			(layer "B.Fab")
		)
		(fp_line
			(start 0.299974 0.150114)
			(end 0.299974 -0.150114)
			(stroke
				(width 0.1)
				(type default)
			)
			(layer "B.Fab")
		)
		(fp_line
			(start -0.299974 0.150114)
			(end 0.299974 0.150114)
			(stroke
				(width 0.1)
				(type default)
			)
			(layer "B.Fab")
		)
		(pad "1" smd rect
			(at 0.2667 0 270)
			(size 0.3048 0.381)
			(layers "B.Cu" "B.Mask" "B.Paste")
			(net "PCEPLL3_VDDA18_PEX1")
		)
		(pad "2" smd rect
			(at -0.2667 0 270)
			(size 0.3048 0.381)
			(layers "B.Cu" "B.Mask" "B.Paste")
			(net "GND")
		)
	)
	(footprint ""
		(layer "B.Cu")
		(at 109.142022 -88.822784 180)
		(property "Reference" "C2665"
			(at 0 0 0)
			(layer "B.SilkS")
			(hide yes)
			(effects
				(font
					(size 1.27 1.27)
				)
				(justify mirror)
			)
		)
		(property "Value" ""
			(at 0 0 0)
			(layer "B.Fab")
			(effects
				(font
					(size 1.27 1.27)
				)
				(justify mirror)
			)
		)
		(duplicate_pad_numbers_are_jumpers no)
		(fp_line
			(start 0.7874 0.4064)
			(end 0.7874 -0.4064)
			(stroke
				(width 0.1524)
				(type default)
			)
			(layer "B.SilkS")
		)
		(fp_line
			(start 0.7874 -0.4064)
			(end -0.7874 -0.4064)
			(stroke
				(width 0.1524)
				(type default)
			)
			(layer "B.SilkS")
		)
		(fp_line
			(start -0.7874 0.4064)
			(end 0.7874 0.4064)
			(stroke
				(width 0.1524)
				(type default)
			)
			(layer "B.SilkS")
		)
		(fp_line
			(start -0.7874 -0.4064)
			(end -0.7874 0.4064)
			(stroke
				(width 0.1524)
				(type default)
			)
			(layer "B.SilkS")
		)
		(fp_line
			(start 0.67945 0.3048)
			(end 0.67945 -0.305054)
			(stroke
				(width 0.1)
				(type default)
			)
			(layer "B.Fab")
		)
		(fp_line
			(start 0.67945 -0.305054)
			(end 0.12065 -0.305054)
			(stroke
				(width 0.1)
				(type default)
			)
			(layer "B.Fab")
		)
		(fp_line
			(start 0.12065 0.3048)
			(end 0.67945 0.3048)
			(stroke
				(width 0.1)
				(type default)
			)
			(layer "B.Fab")
		)
		(fp_line
			(start 0.12065 0.2794)
			(end 0.12065 0.3048)
			(stroke
				(width 0.1)
				(type default)
			)
			(layer "B.Fab")
		)
		(fp_line
			(start 0.12065 -0.2794)
			(end -0.12065 -0.2794)
			(stroke
				(width 0.1)
				(type default)
			)
			(layer "B.Fab")
		)
		(fp_line
			(start 0.12065 -0.305054)
			(end 0.12065 -0.2794)
			(stroke
				(width 0.1)
				(type default)
			)
			(layer "B.Fab")
		)
		(fp_line
			(start -0.120396 0.3048)
			(end -0.120396 0.2794)
			(stroke
				(width 0.1)
				(type default)
			)
			(layer "B.Fab")
		)
		(fp_line
			(start -0.120396 0.2794)
			(end 0.12065 0.2794)
			(stroke
				(width 0.1)
				(type default)
			)
			(layer "B.Fab")
		)
		(fp_line
			(start -0.12065 -0.2794)
			(end -0.12065 -0.3048)
			(stroke
				(width 0.1)
				(type default)
			)
			(layer "B.Fab")
		)
		(fp_line
			(start -0.12065 -0.3048)
			(end -0.67945 -0.3048)
			(stroke
				(width 0.1)
				(type default)
			)
			(layer "B.Fab")
		)
		(fp_line
			(start -0.67945 0.3048)
			(end -0.120396 0.3048)
			(stroke
				(width 0.1)
				(type default)
			)
			(layer "B.Fab")
		)
		(fp_line
			(start -0.67945 -0.3048)
			(end -0.67945 0.3048)
			(stroke
				(width 0.1)
				(type default)
			)
			(layer "B.Fab")
		)
		(pad "1" smd circle
			(at 0.40005 0)
			(size 0 0)
			(layers "B.Cu" "B.Mask" "B.Paste")
			(net "P3V3_VDD_9ZXL0851_0_7")
		)
		(pad "2" smd circle
			(at -0.40005 0)
			(size 0 0)
			(layers "B.Cu" "B.Mask" "B.Paste")
			(net "GND")
		)
	)
	(footprint ""
		(layer "B.Cu")
		(at 256.351532 -83.18754 180)
		(property "Reference" "C2641"
			(at 0 0 0)
			(layer "B.SilkS")
			(hide yes)
			(effects
				(font
					(size 1.27 1.27)
				)
				(justify mirror)
			)
		)
		(property "Value" ""
			(at 0 0 0)
			(layer "B.Fab")
			(effects
				(font
					(size 1.27 1.27)
				)
				(justify mirror)
			)
		)
		(duplicate_pad_numbers_are_jumpers no)
		(fp_line
			(start 0.7874 0.4064)
			(end 0.7874 -0.4064)
			(stroke
				(width 0.1524)
				(type default)
			)
			(layer "B.SilkS")
		)
		(fp_line
			(start 0.7874 -0.4064)
			(end -0.7874 -0.4064)
			(stroke
				(width 0.1524)
				(type default)
			)
			(layer "B.SilkS")
		)
		(fp_line
			(start -0.7874 0.4064)
			(end 0.7874 0.4064)
			(stroke
				(width 0.1524)
				(type default)
			)
			(layer "B.SilkS")
		)
		(fp_line
			(start -0.7874 -0.4064)
			(end -0.7874 0.4064)
			(stroke
				(width 0.1524)
				(type default)
			)
			(layer "B.SilkS")
		)
		(fp_line
			(start 0.67945 0.3048)
			(end 0.67945 -0.305054)
			(stroke
				(width 0.1)
				(type default)
			)
			(layer "B.Fab")
		)
		(fp_line
			(start 0.67945 -0.305054)
			(end 0.12065 -0.305054)
			(stroke
				(width 0.1)
				(type default)
			)
			(layer "B.Fab")
		)
		(fp_line
			(start 0.12065 0.3048)
			(end 0.67945 0.3048)
			(stroke
				(width 0.1)
				(type default)
			)
			(layer "B.Fab")
		)
		(fp_line
			(start 0.12065 0.2794)
			(end 0.12065 0.3048)
			(stroke
				(width 0.1)
				(type default)
			)
			(layer "B.Fab")
		)
		(fp_line
			(start 0.12065 -0.2794)
			(end -0.12065 -0.2794)
			(stroke
				(width 0.1)
				(type default)
			)
			(layer "B.Fab")
		)
		(fp_line
			(start 0.12065 -0.305054)
			(end 0.12065 -0.2794)
			(stroke
				(width 0.1)
				(type default)
			)
			(layer "B.Fab")
		)
		(fp_line
			(start -0.120396 0.3048)
			(end -0.120396 0.2794)
			(stroke
				(width 0.1)
				(type default)
			)
			(layer "B.Fab")
		)
		(fp_line
			(start -0.120396 0.2794)
			(end 0.12065 0.2794)
			(stroke
				(width 0.1)
				(type default)
			)
			(layer "B.Fab")
		)
		(fp_line
			(start -0.12065 -0.2794)
			(end -0.12065 -0.3048)
			(stroke
				(width 0.1)
				(type default)
			)
			(layer "B.Fab")
		)
		(fp_line
			(start -0.12065 -0.3048)
			(end -0.67945 -0.3048)
			(stroke
				(width 0.1)
				(type default)
			)
			(layer "B.Fab")
		)
		(fp_line
			(start -0.67945 0.3048)
			(end -0.120396 0.3048)
			(stroke
				(width 0.1)
				(type default)
			)
			(layer "B.Fab")
		)
		(fp_line
			(start -0.67945 -0.3048)
			(end -0.67945 0.3048)
			(stroke
				(width 0.1)
				(type default)
			)
			(layer "B.Fab")
		)
		(pad "1" smd circle
			(at 0.40005 0)
			(size 0 0)
			(layers "B.Cu" "B.Mask" "B.Paste")
			(net "P3V3_CLK_GEN_VDDXTAL_CK440")
		)
		(pad "2" smd circle
			(at -0.40005 0)
			(size 0 0)
			(layers "B.Cu" "B.Mask" "B.Paste")
			(net "GND")
		)
	)
	(footprint ""
		(layer "B.Cu")
		(at 288.049716 -303.499774 -90)
		(property "Reference" "C3266"
			(at 0 0 90)
			(layer "B.SilkS")
			(hide yes)
			(effects
				(font
					(size 1.27 1.27)
				)
				(justify mirror)
			)
		)
		(property "Value" ""
			(at 0 0 90)
			(layer "B.Fab")
			(effects
				(font
					(size 1.27 1.27)
				)
				(justify mirror)
			)
		)
		(duplicate_pad_numbers_are_jumpers no)
		(fp_line
			(start -0.299974 0.150114)
			(end 0.299974 0.150114)
			(stroke
				(width 0.1)
				(type default)
			)
			(layer "B.Fab")
		)
		(fp_line
			(start 0.299974 0.150114)
			(end 0.299974 -0.150114)
			(stroke
				(width 0.1)
				(type default)
			)
			(layer "B.Fab")
		)
		(fp_line
			(start -0.299974 -0.150114)
			(end -0.299974 0.150114)
			(stroke
				(width 0.1)
				(type default)
			)
			(layer "B.Fab")
		)
		(fp_line
			(start 0.299974 -0.150114)
			(end -0.299974 -0.150114)
			(stroke
				(width 0.1)
				(type default)
			)
			(layer "B.Fab")
		)
		(pad "1" smd rect
			(at 0.2667 0 90)
			(size 0.3048 0.381)
			(layers "B.Cu" "B.Mask" "B.Paste")
			(net "P1V25_PEX2")
		)
		(pad "2" smd rect
			(at -0.2667 0 90)
			(size 0.3048 0.381)
			(layers "B.Cu" "B.Mask" "B.Paste")
			(net "GND")
		)
	)
	(footprint ""
		(layer "B.Cu")
		(at 179.55006 -299.699934 -90)
		(property "Reference" "C1468"
			(at 0 0 90)
			(layer "B.SilkS")
			(hide yes)
			(effects
				(font
					(size 1.27 1.27)
				)
				(justify mirror)
			)
		)
		(property "Value" ""
			(at 0 0 90)
			(layer "B.Fab")
			(effects
				(font
					(size 1.27 1.27)
				)
				(justify mirror)
			)
		)
		(duplicate_pad_numbers_are_jumpers no)
		(fp_line
			(start -0.299974 0.150114)
			(end 0.299974 0.150114)
			(stroke
				(width 0.1)
				(type default)
			)
			(layer "B.Fab")
		)
		(fp_line
			(start 0.299974 0.150114)
			(end 0.299974 -0.150114)
			(stroke
				(width 0.1)
				(type default)
			)
			(layer "B.Fab")
		)
		(fp_line
			(start -0.299974 -0.150114)
			(end -0.299974 0.150114)
			(stroke
				(width 0.1)
				(type default)
			)
			(layer "B.Fab")
		)
		(fp_line
			(start 0.299974 -0.150114)
			(end -0.299974 -0.150114)
			(stroke
				(width 0.1)
				(type default)
			)
			(layer "B.Fab")
		)
		(pad "1" smd rect
			(at 0.2667 0 90)
			(size 0.3048 0.381)
			(layers "B.Cu" "B.Mask" "B.Paste")
			(net "P0V8_SERDES_VDDA_PEX1")
		)
		(pad "2" smd rect
			(at -0.2667 0 90)
			(size 0.3048 0.381)
			(layers "B.Cu" "B.Mask" "B.Paste")
			(net "GND")
		)
	)
	(footprint ""
		(layer "B.Cu")
		(at 237.631986 -355.200458)
		(property "Reference" "PR7151"
			(at 0 0 0)
			(layer "B.SilkS")
			(hide yes)
			(effects
				(font
					(size 1.27 1.27)
				)
				(justify mirror)
			)
		)
		(property "Value" ""
			(at 0 0 0)
			(layer "B.Fab")
			(effects
				(font
					(size 1.27 1.27)
				)
				(justify mirror)
			)
		)
		(duplicate_pad_numbers_are_jumpers no)
		(fp_line
			(start -0.7874 -0.4064)
			(end -0.7874 0.4064)
			(stroke
				(width 0.1524)
				(type default)
			)
			(layer "B.SilkS")
		)
		(fp_line
			(start -0.7874 0.4064)
			(end 0.7874 0.4064)
			(stroke
				(width 0.1524)
				(type default)
			)
			(layer "B.SilkS")
		)
		(fp_line
			(start 0.7874 -0.4064)
			(end -0.7874 -0.4064)
			(stroke
				(width 0.1524)
				(type default)
			)
			(layer "B.SilkS")
		)
		(fp_line
			(start 0.7874 0.4064)
			(end 0.7874 -0.4064)
			(stroke
				(width 0.1524)
				(type default)
			)
			(layer "B.SilkS")
		)
		(fp_line
			(start -0.67945 -0.3048)
			(end -0.67945 0.3048)
			(stroke
				(width 0.1)
				(type default)
			)
			(layer "B.Fab")
		)
		(fp_line
			(start -0.67945 0.3048)
			(end -0.120396 0.3048)
			(stroke
				(width 0.1)
				(type default)
			)
			(layer "B.Fab")
		)
		(fp_line
			(start -0.12065 -0.3048)
			(end -0.67945 -0.3048)
			(stroke
				(width 0.1)
				(type default)
			)
			(layer "B.Fab")
		)
		(fp_line
			(start -0.12065 -0.2794)
			(end -0.12065 -0.3048)
			(stroke
				(width 0.1)
				(type default)
			)
			(layer "B.Fab")
		)
		(fp_line
			(start -0.120396 0.2794)
			(end 0.12065 0.2794)
			(stroke
				(width 0.1)
				(type default)
			)
			(layer "B.Fab")
		)
		(fp_line
			(start -0.120396 0.3048)
			(end -0.120396 0.2794)
			(stroke
				(width 0.1)
				(type default)
			)
			(layer "B.Fab")
		)
		(fp_line
			(start 0.12065 -0.305054)
			(end 0.12065 -0.2794)
			(stroke
				(width 0.1)
				(type default)
			)
			(layer "B.Fab")
		)
		(fp_line
			(start 0.12065 -0.2794)
			(end -0.12065 -0.2794)
			(stroke
				(width 0.1)
				(type default)
			)
			(layer "B.Fab")
		)
		(fp_line
			(start 0.12065 0.2794)
			(end 0.12065 0.3048)
			(stroke
				(width 0.1)
				(type default)
			)
			(layer "B.Fab")
		)
		(fp_line
			(start 0.12065 0.3048)
			(end 0.67945 0.3048)
			(stroke
				(width 0.1)
				(type default)
			)
			(layer "B.Fab")
		)
		(fp_line
			(start 0.67945 -0.305054)
			(end 0.12065 -0.305054)
			(stroke
				(width 0.1)
				(type default)
			)
			(layer "B.Fab")
		)
		(fp_line
			(start 0.67945 0.3048)
			(end 0.67945 -0.305054)
			(stroke
				(width 0.1)
				(type default)
			)
			(layer "B.Fab")
		)
		(pad "1" smd circle
			(at 0.40005 0 180)
			(size 0 0)
			(layers "B.Cu" "B.Mask" "B.Paste")
			(net "P12V_HSC_ADC_N")
		)
		(pad "2" smd circle
			(at -0.40005 0 180)
			(size 0 0)
			(layers "B.Cu" "B.Mask" "B.Paste")
			(net "P12V_HSC_SENSE2_R2_N")
		)
	)
	(footprint ""
		(layer "B.Cu")
		(at 163.874958 -299.491654 90)
		(property "Reference" "C3197"
			(at 0 0 90)
			(layer "B.SilkS")
			(hide yes)
			(effects
				(font
					(size 1.27 1.27)
				)
				(justify mirror)
			)
		)
		(property "Value" ""
			(at 0 0 90)
			(layer "B.Fab")
			(effects
				(font
					(size 1.27 1.27)
				)
				(justify mirror)
			)
		)
		(duplicate_pad_numbers_are_jumpers no)
		(fp_line
			(start 0.299974 -0.150114)
			(end -0.299974 -0.150114)
			(stroke
				(width 0.1)
				(type default)
			)
			(layer "B.Fab")
		)
		(fp_line
			(start -0.299974 -0.150114)
			(end -0.299974 0.150114)
			(stroke
				(width 0.1)
				(type default)
			)
			(layer "B.Fab")
		)
		(fp_line
			(start 0.299974 0.150114)
			(end 0.299974 -0.150114)
			(stroke
				(width 0.1)
				(type default)
			)
			(layer "B.Fab")
		)
		(fp_line
			(start -0.299974 0.150114)
			(end 0.299974 0.150114)
			(stroke
				(width 0.1)
				(type default)
			)
			(layer "B.Fab")
		)
		(pad "1" smd rect
			(at 0.2667 0 270)
			(size 0.3048 0.381)
			(layers "B.Cu" "B.Mask" "B.Paste")
			(net "PCEPLL0_VDDA18_PEX1")
		)
		(pad "2" smd rect
			(at -0.2667 0 270)
			(size 0.3048 0.381)
			(layers "B.Cu" "B.Mask" "B.Paste")
			(net "GND")
		)
	)
	(footprint ""
		(layer "B.Cu")
		(at 229.349046 -140.173202)
		(property "Reference" "C2793"
			(at 0 0 0)
			(layer "B.SilkS")
			(hide yes)
			(effects
				(font
					(size 1.27 1.27)
				)
				(justify mirror)
			)
		)
		(property "Value" ""
			(at 0 0 0)
			(layer "B.Fab")
			(effects
				(font
					(size 1.27 1.27)
				)
				(justify mirror)
			)
		)
		(duplicate_pad_numbers_are_jumpers no)
		(fp_line
			(start -1.2954 -0.5842)
			(end -1.2954 0.5842)
			(stroke
				(width 0.1524)
				(type default)
			)
			(layer "B.SilkS")
		)
		(fp_line
			(start -1.2954 0.5842)
			(end 1.2954 0.5842)
			(stroke
				(width 0.1524)
				(type default)
			)
			(layer "B.SilkS")
		)
		(fp_line
			(start 1.2954 -0.5842)
			(end -1.2954 -0.5842)
			(stroke
				(width 0.1524)
				(type default)
			)
			(layer "B.SilkS")
		)
		(fp_line
			(start 1.2954 0.5842)
			(end 1.2954 -0.5842)
			(stroke
				(width 0.1524)
				(type default)
			)
			(layer "B.SilkS")
		)
		(fp_line
			(start -1.1938 -0.4064)
			(end -1.1938 0.4064)
			(stroke
				(width 0.1)
				(type default)
			)
			(layer "B.Fab")
		)
		(fp_line
			(start -1.1938 0.4064)
			(end -0.8636 0.4064)
			(stroke
				(width 0.1)
				(type default)
			)
			(layer "B.Fab")
		)
		(fp_line
			(start -0.8636 -0.4572)
			(end -0.8636 -0.4064)
			(stroke
				(width 0.1)
				(type default)
			)
			(layer "B.Fab")
		)
		(fp_line
			(start -0.8636 -0.4064)
			(end -1.1938 -0.4064)
			(stroke
				(width 0.1)
				(type default)
			)
			(layer "B.Fab")
		)
		(fp_line
			(start -0.8636 0.4064)
			(end -0.8636 0.4572)
			(stroke
				(width 0.1)
				(type default)
			)
			(layer "B.Fab")
		)
		(fp_line
			(start -0.8636 0.4572)
			(end 0.8636 0.4572)
			(stroke
				(width 0.1)
				(type default)
			)
			(layer "B.Fab")
		)
		(fp_line
			(start 0.8636 -0.4572)
			(end -0.8636 -0.4572)
			(stroke
				(width 0.1)
				(type default)
			)
			(layer "B.Fab")
		)
		(fp_line
			(start 0.8636 -0.4064)
			(end 0.8636 -0.4572)
			(stroke
				(width 0.1)
				(type default)
			)
			(layer "B.Fab")
		)
		(fp_line
			(start 0.8636 0.4064)
			(end 1.1938 0.4064)
			(stroke
				(width 0.1)
				(type default)
			)
			(layer "B.Fab")
		)
		(fp_line
			(start 0.8636 0.4572)
			(end 0.8636 0.4064)
			(stroke
				(width 0.1)
				(type default)
			)
			(layer "B.Fab")
		)
		(fp_line
			(start 1.1938 -0.4064)
			(end 0.8636 -0.4064)
			(stroke
				(width 0.1)
				(type default)
			)
			(layer "B.Fab")
		)
		(fp_line
			(start 1.1938 0.4064)
			(end 1.1938 -0.4064)
			(stroke
				(width 0.1)
				(type default)
			)
			(layer "B.Fab")
		)
		(pad "1" smd rect
			(at 0.7366 0 270)
			(size 0.7112 0.8128)
			(layers "B.Cu" "B.Mask" "B.Paste")
			(net "P3V3_CLK_GEN_VDDXTAL_CK440_PEX")
		)
		(pad "2" smd rect
			(at -0.7366 0 270)
			(size 0.7112 0.8128)
			(layers "B.Cu" "B.Mask" "B.Paste")
			(net "GND")
		)
	)
	(footprint ""
		(layer "B.Cu")
		(at 290.89985 -288.299906 90)
		(property "Reference" "C3283"
			(at 0 0 90)
			(layer "B.SilkS")
			(hide yes)
			(effects
				(font
					(size 1.27 1.27)
				)
				(justify mirror)
			)
		)
		(property "Value" ""
			(at 0 0 90)
			(layer "B.Fab")
			(effects
				(font
					(size 1.27 1.27)
				)
				(justify mirror)
			)
		)
		(duplicate_pad_numbers_are_jumpers no)
		(fp_line
			(start 0.299974 -0.150114)
			(end -0.299974 -0.150114)
			(stroke
				(width 0.1)
				(type default)
			)
			(layer "B.Fab")
		)
		(fp_line
			(start -0.299974 -0.150114)
			(end -0.299974 0.150114)
			(stroke
				(width 0.1)
				(type default)
			)
			(layer "B.Fab")
		)
		(fp_line
			(start 0.299974 0.150114)
			(end 0.299974 -0.150114)
			(stroke
				(width 0.1)
				(type default)
			)
			(layer "B.Fab")
		)
		(fp_line
			(start -0.299974 0.150114)
			(end 0.299974 0.150114)
			(stroke
				(width 0.1)
				(type default)
			)
			(layer "B.Fab")
		)
		(pad "1" smd rect
			(at 0.2667 0 270)
			(size 0.3048 0.381)
			(layers "B.Cu" "B.Mask" "B.Paste")
			(net "P1V25_PEX2")
		)
		(pad "2" smd rect
			(at -0.2667 0 270)
			(size 0.3048 0.381)
			(layers "B.Cu" "B.Mask" "B.Paste")
			(net "GND")
		)
	)
	(footprint ""
		(layer "B.Cu")
		(at 353.910646 -216.946734)
		(property "Reference" "R5637"
			(at 0 0 0)
			(layer "B.SilkS")
			(hide yes)
			(effects
				(font
					(size 1.27 1.27)
				)
				(justify mirror)
			)
		)
		(property "Value" ""
			(at 0 0 0)
			(layer "B.Fab")
			(effects
				(font
					(size 1.27 1.27)
				)
				(justify mirror)
			)
		)
		(duplicate_pad_numbers_are_jumpers no)
		(fp_line
			(start -1.2954 -0.5842)
			(end -1.2954 0.5842)
			(stroke
				(width 0.1524)
				(type default)
			)
			(layer "B.SilkS")
		)
		(fp_line
			(start -1.2954 0.5842)
			(end 1.2954 0.5842)
			(stroke
				(width 0.1524)
				(type default)
			)
			(layer "B.SilkS")
		)
		(fp_line
			(start 1.2954 -0.5842)
			(end -1.2954 -0.5842)
			(stroke
				(width 0.1524)
				(type default)
			)
			(layer "B.SilkS")
		)
		(fp_line
			(start 1.2954 0.5842)
			(end 1.2954 -0.5842)
			(stroke
				(width 0.1524)
				(type default)
			)
			(layer "B.SilkS")
		)
		(fp_line
			(start -1.1938 -0.406654)
			(end -1.1938 0.4064)
			(stroke
				(width 0.1)
				(type default)
			)
			(layer "B.Fab")
		)
		(fp_line
			(start -1.1938 0.4064)
			(end -0.8636 0.4064)
			(stroke
				(width 0.1)
				(type default)
			)
			(layer "B.Fab")
		)
		(fp_line
			(start -0.8636 -0.4572)
			(end -0.8636 -0.406654)
			(stroke
				(width 0.1)
				(type default)
			)
			(layer "B.Fab")
		)
		(fp_line
			(start -0.8636 -0.406654)
			(end -1.1938 -0.406654)
			(stroke
				(width 0.1)
				(type default)
			)
			(layer "B.Fab")
		)
		(fp_line
			(start -0.8636 0.4064)
			(end -0.8636 0.4572)
			(stroke
				(width 0.1)
				(type default)
			)
			(layer "B.Fab")
		)
		(fp_line
			(start -0.8636 0.4572)
			(end 0.8636 0.4572)
			(stroke
				(width 0.1)
				(type default)
			)
			(layer "B.Fab")
		)
		(fp_line
			(start 0.8636 -0.4572)
			(end -0.8636 -0.4572)
			(stroke
				(width 0.1)
				(type default)
			)
			(layer "B.Fab")
		)
		(fp_line
			(start 0.8636 -0.406654)
			(end 0.8636 -0.4572)
			(stroke
				(width 0.1)
				(type default)
			)
			(layer "B.Fab")
		)
		(fp_line
			(start 0.8636 0.4064)
			(end 1.1938 0.4064)
			(stroke
				(width 0.1)
				(type default)
			)
			(layer "B.Fab")
		)
		(fp_line
			(start 0.8636 0.4318)
			(end 0.8636 0.4064)
			(stroke
				(width 0.1)
				(type default)
			)
			(layer "B.Fab")
		)
		(fp_line
			(start 0.8636 0.4572)
			(end 0.8636 0.4318)
			(stroke
				(width 0.1)
				(type default)
			)
			(layer "B.Fab")
		)
		(fp_line
			(start 1.1938 -0.406654)
			(end 0.8636 -0.406654)
			(stroke
				(width 0.1)
				(type default)
			)
			(layer "B.Fab")
		)
		(fp_line
			(start 1.1938 0.4064)
			(end 1.1938 -0.406654)
			(stroke
				(width 0.1)
				(type default)
			)
			(layer "B.Fab")
		)
		(pad "1" smd rect
			(at 0.7366 0 270)
			(size 0.7112 0.8128)
			(layers "B.Cu" "B.Mask" "B.Paste")
			(net "P3V3_AUX")
		)
		(pad "2" smd rect
			(at -0.7366 0 270)
			(size 0.7112 0.8128)
			(layers "B.Cu" "B.Mask" "B.Paste")
			(net "P3V3_FPGA_VCCIO1")
		)
	)
	(footprint ""
		(layer "B.Cu")
		(at 403.10054 -86.813898 180)
		(property "Reference" "R6270"
			(at 0 0 0)
			(layer "B.SilkS")
			(hide yes)
			(effects
				(font
					(size 1.27 1.27)
				)
				(justify mirror)
			)
		)
		(property "Value" ""
			(at 0 0 0)
			(layer "B.Fab")
			(effects
				(font
					(size 1.27 1.27)
				)
				(justify mirror)
			)
		)
		(duplicate_pad_numbers_are_jumpers no)
		(fp_line
			(start 0.7874 0.4064)
			(end 0.7874 -0.4064)
			(stroke
				(width 0.1524)
				(type default)
			)
			(layer "B.SilkS")
		)
		(fp_line
			(start 0.7874 -0.4064)
			(end -0.7874 -0.4064)
			(stroke
				(width 0.1524)
				(type default)
			)
			(layer "B.SilkS")
		)
		(fp_line
			(start -0.7874 0.4064)
			(end 0.7874 0.4064)
			(stroke
				(width 0.1524)
				(type default)
			)
			(layer "B.SilkS")
		)
		(fp_line
			(start -0.7874 -0.4064)
			(end -0.7874 0.4064)
			(stroke
				(width 0.1524)
				(type default)
			)
			(layer "B.SilkS")
		)
		(fp_line
			(start 0.67945 0.3048)
			(end 0.67945 -0.305054)
			(stroke
				(width 0.1)
				(type default)
			)
			(layer "B.Fab")
		)
		(fp_line
			(start 0.67945 -0.305054)
			(end 0.12065 -0.305054)
			(stroke
				(width 0.1)
				(type default)
			)
			(layer "B.Fab")
		)
		(fp_line
			(start 0.12065 0.3048)
			(end 0.67945 0.3048)
			(stroke
				(width 0.1)
				(type default)
			)
			(layer "B.Fab")
		)
		(fp_line
			(start 0.12065 0.2794)
			(end 0.12065 0.3048)
			(stroke
				(width 0.1)
				(type default)
			)
			(layer "B.Fab")
		)
		(fp_line
			(start 0.12065 -0.2794)
			(end -0.12065 -0.2794)
			(stroke
				(width 0.1)
				(type default)
			)
			(layer "B.Fab")
		)
		(fp_line
			(start 0.12065 -0.305054)
			(end 0.12065 -0.2794)
			(stroke
				(width 0.1)
				(type default)
			)
			(layer "B.Fab")
		)
		(fp_line
			(start -0.120396 0.3048)
			(end -0.120396 0.2794)
			(stroke
				(width 0.1)
				(type default)
			)
			(layer "B.Fab")
		)
		(fp_line
			(start -0.120396 0.2794)
			(end 0.12065 0.2794)
			(stroke
				(width 0.1)
				(type default)
			)
			(layer "B.Fab")
		)
		(fp_line
			(start -0.12065 -0.2794)
			(end -0.12065 -0.3048)
			(stroke
				(width 0.1)
				(type default)
			)
			(layer "B.Fab")
		)
		(fp_line
			(start -0.12065 -0.3048)
			(end -0.67945 -0.3048)
			(stroke
				(width 0.1)
				(type default)
			)
			(layer "B.Fab")
		)
		(fp_line
			(start -0.67945 0.3048)
			(end -0.120396 0.3048)
			(stroke
				(width 0.1)
				(type default)
			)
			(layer "B.Fab")
		)
		(fp_line
			(start -0.67945 -0.3048)
			(end -0.67945 0.3048)
			(stroke
				(width 0.1)
				(type default)
			)
			(layer "B.Fab")
		)
		(pad "1" smd circle
			(at 0.40005 0)
			(size 0 0)
			(layers "B.Cu" "B.Mask" "B.Paste")
			(net "SMB_BIC_I2C6_MUX_CLK_R_SDA")
		)
		(pad "2" smd circle
			(at -0.40005 0)
			(size 0 0)
			(layers "B.Cu" "B.Mask" "B.Paste")
			(net "SMB_CLK_ISO_SDA")
		)
	)
	(footprint ""
		(layer "B.Cu")
		(at 168.150032 -290.199826 90)
		(property "Reference" "C1425"
			(at 0 0 90)
			(layer "B.SilkS")
			(hide yes)
			(effects
				(font
					(size 1.27 1.27)
				)
				(justify mirror)
			)
		)
		(property "Value" ""
			(at 0 0 90)
			(layer "B.Fab")
			(effects
				(font
					(size 1.27 1.27)
				)
				(justify mirror)
			)
		)
		(duplicate_pad_numbers_are_jumpers no)
		(fp_line
			(start 0.299974 -0.150114)
			(end -0.299974 -0.150114)
			(stroke
				(width 0.1)
				(type default)
			)
			(layer "B.Fab")
		)
		(fp_line
			(start -0.299974 -0.150114)
			(end -0.299974 0.150114)
			(stroke
				(width 0.1)
				(type default)
			)
			(layer "B.Fab")
		)
		(fp_line
			(start 0.299974 0.150114)
			(end 0.299974 -0.150114)
			(stroke
				(width 0.1)
				(type default)
			)
			(layer "B.Fab")
		)
		(fp_line
			(start -0.299974 0.150114)
			(end 0.299974 0.150114)
			(stroke
				(width 0.1)
				(type default)
			)
			(layer "B.Fab")
		)
		(pad "1" smd rect
			(at 0.2667 0 270)
			(size 0.3048 0.381)
			(layers "B.Cu" "B.Mask" "B.Paste")
			(net "P0V8_SERDES_VDDA_PEX1")
		)
		(pad "2" smd rect
			(at -0.2667 0 270)
			(size 0.3048 0.381)
			(layers "B.Cu" "B.Mask" "B.Paste")
			(net "GND")
		)
	)
	(footprint ""
		(layer "B.Cu")
		(at 284.724856 -286.399732 90)
		(property "Reference" "C3331"
			(at 0 0 90)
			(layer "B.SilkS")
			(hide yes)
			(effects
				(font
					(size 1.27 1.27)
				)
				(justify mirror)
			)
		)
		(property "Value" ""
			(at 0 0 90)
			(layer "B.Fab")
			(effects
				(font
					(size 1.27 1.27)
				)
				(justify mirror)
			)
		)
		(duplicate_pad_numbers_are_jumpers no)
		(fp_line
			(start 0.299974 -0.150114)
			(end -0.299974 -0.150114)
			(stroke
				(width 0.1)
				(type default)
			)
			(layer "B.Fab")
		)
		(fp_line
			(start -0.299974 -0.150114)
			(end -0.299974 0.150114)
			(stroke
				(width 0.1)
				(type default)
			)
			(layer "B.Fab")
		)
		(fp_line
			(start 0.299974 0.150114)
			(end 0.299974 -0.150114)
			(stroke
				(width 0.1)
				(type default)
			)
			(layer "B.Fab")
		)
		(fp_line
			(start -0.299974 0.150114)
			(end 0.299974 0.150114)
			(stroke
				(width 0.1)
				(type default)
			)
			(layer "B.Fab")
		)
		(pad "1" smd rect
			(at 0.2667 0 270)
			(size 0.3048 0.381)
			(layers "B.Cu" "B.Mask" "B.Paste")
			(net "P1V25_SERDES_VDDPLL_PEX2")
		)
		(pad "2" smd rect
			(at -0.2667 0 270)
			(size 0.3048 0.381)
			(layers "B.Cu" "B.Mask" "B.Paste")
			(net "GND")
		)
	)
	(footprint ""
		(layer "B.Cu")
		(at 292.79977 -303.499774 -90)
		(property "Reference" "C3259"
			(at 0 0 90)
			(layer "B.SilkS")
			(hide yes)
			(effects
				(font
					(size 1.27 1.27)
				)
				(justify mirror)
			)
		)
		(property "Value" ""
			(at 0 0 90)
			(layer "B.Fab")
			(effects
				(font
					(size 1.27 1.27)
				)
				(justify mirror)
			)
		)
		(duplicate_pad_numbers_are_jumpers no)
		(fp_line
			(start -0.299974 0.150114)
			(end 0.299974 0.150114)
			(stroke
				(width 0.1)
				(type default)
			)
			(layer "B.Fab")
		)
		(fp_line
			(start 0.299974 0.150114)
			(end 0.299974 -0.150114)
			(stroke
				(width 0.1)
				(type default)
			)
			(layer "B.Fab")
		)
		(fp_line
			(start -0.299974 -0.150114)
			(end -0.299974 0.150114)
			(stroke
				(width 0.1)
				(type default)
			)
			(layer "B.Fab")
		)
		(fp_line
			(start 0.299974 -0.150114)
			(end -0.299974 -0.150114)
			(stroke
				(width 0.1)
				(type default)
			)
			(layer "B.Fab")
		)
		(pad "1" smd rect
			(at 0.2667 0 90)
			(size 0.3048 0.381)
			(layers "B.Cu" "B.Mask" "B.Paste")
			(net "P1V25_PEX2")
		)
		(pad "2" smd rect
			(at -0.2667 0 90)
			(size 0.3048 0.381)
			(layers "B.Cu" "B.Mask" "B.Paste")
			(net "GND")
		)
	)
	(footprint ""
		(layer "B.Cu")
		(at 255.335024 10.623804 180)
		(property "Reference" "DE16T_3"
			(at -2.525776 -3.068066 0)
			(unlocked yes)
			(layer "B.SilkS")
			(effects
				(font
					(size 0.7874 0.5842)
					(thickness 0.1524)
				)
				(justify left mirror)
			)
		)
		(property "Value" ""
			(at 0 0 0)
			(layer "B.Fab")
			(effects
				(font
					(size 1.27 1.27)
				)
				(justify mirror)
			)
		)
		(duplicate_pad_numbers_are_jumpers no)
		(fp_line
			(start 1.2192 2.1082)
			(end 1.2192 -2.1082)
			(stroke
				(width 0.1524)
				(type default)
			)
			(layer "B.SilkS")
		)
		(fp_line
			(start 1.2192 -2.1082)
			(end -1.2192 -2.1082)
			(stroke
				(width 0.1524)
				(type default)
			)
			(layer "B.SilkS")
		)
		(fp_line
			(start -1.2192 2.1082)
			(end 1.2192 2.1082)
			(stroke
				(width 0.1524)
				(type default)
			)
			(layer "B.SilkS")
		)
		(fp_line
			(start -1.2192 -2.1082)
			(end -1.2192 2.1082)
			(stroke
				(width 0.1524)
				(type default)
			)
			(layer "B.SilkS")
		)
		(pad "" np_thru_hole circle
			(at -3.4671 -1.27 90)
			(size 1.0414 1.0414)
			(drill 1.0414)
			(layers "*.Cu" "*.Mask")
			(clearance 0.381)
			(thermal_gap 0.381)
		)
		(pad "" np_thru_hole circle
			(at -3.4671 1.27 90)
			(size 1.0414 1.0414)
			(drill 1.0414)
			(layers "*.Cu" "*.Mask")
			(clearance 0.381)
			(thermal_gap 0.381)
		)
		(pad "" np_thru_hole circle
			(at 2.8829 -1.27 90)
			(size 1.0414 1.0414)
			(drill 1.0414)
			(layers "*.Cu" "*.Mask")
			(clearance 0.381)
			(thermal_gap 0.381)
		)
		(pad "" np_thru_hole circle
			(at 2.8829 1.27 90)
			(size 1.0414 1.0414)
			(drill 1.0414)
			(layers "*.Cu" "*.Mask")
			(clearance 0.381)
			(thermal_gap 0.381)
		)
		(pad "1" smd rect
			(at -0.8255 -0.249936 90)
			(size 0.3048 0.508)
			(layers "B.Cu" "B.Mask" "B.Paste")
			(net "85_10INCH_IN6_DP")
		)
		(pad "2" smd rect
			(at -0.8255 0.249936 90)
			(size 0.3048 0.508)
			(layers "B.Cu" "B.Mask" "B.Paste")
			(net "85_10INCH_IN6_DN")
		)
		(pad "3" smd circle
			(at 0 0)
			(size 0 0)
			(layers "B.Cu" "B.Mask" "B.Paste")
			(net "COUPON_GND2")
		)
		(zone
			(layers "F.Cu" "B.Cu" "In1.Cu" "In2.Cu" "In3.Cu" "In4.Cu" "In5.Cu" "In6.Cu"
				"In7.Cu" "In8.Cu" "In9.Cu" "In10.Cu" "In11.Cu" "In12.Cu" "In13.Cu" "In14.Cu"
				"In15.Cu" "In16.Cu"
			)
			(hatch none 0.5)
			(connect_pads
				(clearance 0)
			)
			(min_thickness 0.25)
			(keepout
				(tracks not_allowed)
				(vias allowed)
				(pads allowed)
				(copperpour not_allowed)
				(footprints allowed)
			)
			(placement
				(enabled no)
				(sheetname "")
			)
			(fill
				(thermal_gap 0.5)
				(thermal_bridge_width 0.5)
				(island_removal_mode 0)
			)
			(polygon
				(pts
					(arc
						(start 253.379224 9.353804)
						(mid 251.525024 9.353804)
						(end 253.379224 9.353804)
					)
				)
			)
		)
		(zone
			(layers "F.Cu" "B.Cu" "In1.Cu" "In2.Cu" "In3.Cu" "In4.Cu" "In5.Cu" "In6.Cu"
				"In7.Cu" "In8.Cu" "In9.Cu" "In10.Cu" "In11.Cu" "In12.Cu" "In13.Cu" "In14.Cu"
				"In15.Cu" "In16.Cu"
			)
			(hatch none 0.5)
			(connect_pads
				(clearance 0)
			)
			(min_thickness 0.25)
			(keepout
				(tracks not_allowed)
				(vias allowed)
				(pads allowed)
				(copperpour not_allowed)
				(footprints allowed)
			)
			(placement
				(enabled no)
				(sheetname "")
			)
			(fill
				(thermal_gap 0.5)
				(thermal_bridge_width 0.5)
				(island_removal_mode 0)
			)
			(polygon
				(pts
					(arc
						(start 253.379224 11.893804)
						(mid 251.525024 11.893804)
						(end 253.379224 11.893804)
					)
				)
			)
		)
		(zone
			(layers "F.Cu" "B.Cu" "In1.Cu" "In2.Cu" "In3.Cu" "In4.Cu" "In5.Cu" "In6.Cu"
				"In7.Cu" "In8.Cu" "In9.Cu" "In10.Cu" "In11.Cu" "In12.Cu" "In13.Cu" "In14.Cu"
				"In15.Cu" "In16.Cu"
			)
			(hatch none 0.5)
			(connect_pads
				(clearance 0)
			)
			(min_thickness 0.25)
			(keepout
				(tracks not_allowed)
				(vias allowed)
				(pads allowed)
				(copperpour not_allowed)
				(footprints allowed)
			)
			(placement
				(enabled no)
				(sheetname "")
			)
			(fill
				(thermal_gap 0.5)
				(thermal_bridge_width 0.5)
				(island_removal_mode 0)
			)
			(polygon
				(pts
					(arc
						(start 259.729224 9.353804)
						(mid 257.875024 9.353804)
						(end 259.729224 9.353804)
					)
				)
			)
		)
		(zone
			(layers "F.Cu" "B.Cu" "In1.Cu" "In2.Cu" "In3.Cu" "In4.Cu" "In5.Cu" "In6.Cu"
				"In7.Cu" "In8.Cu" "In9.Cu" "In10.Cu" "In11.Cu" "In12.Cu" "In13.Cu" "In14.Cu"
				"In15.Cu" "In16.Cu"
			)
			(hatch none 0.5)
			(connect_pads
				(clearance 0)
			)
			(min_thickness 0.25)
			(keepout
				(tracks not_allowed)
				(vias allowed)
				(pads allowed)
				(copperpour not_allowed)
				(footprints allowed)
			)
			(placement
				(enabled no)
				(sheetname "")
			)
			(fill
				(thermal_gap 0.5)
				(thermal_bridge_width 0.5)
				(island_removal_mode 0)
			)
			(polygon
				(pts
					(arc
						(start 259.729224 11.893804)
						(mid 257.875024 11.893804)
						(end 259.729224 11.893804)
					)
				)
			)
		)
		(zone
			(layer "B.Cu")
			(hatch none 0.5)
			(connect_pads
				(clearance 0)
			)
			(min_thickness 0.25)
			(keepout
				(tracks not_allowed)
				(vias allowed)
				(pads allowed)
				(copperpour not_allowed)
				(footprints allowed)
			)
			(placement
				(enabled no)
				(sheetname "")
			)
			(fill
				(thermal_gap 0.5)
				(thermal_bridge_width 0.5)
				(island_removal_mode 0)
			)
			(polygon
				(pts
					(xy 256.452624 11.172444) (xy 256.452624 11.07694) (xy 255.855724 11.07694) (xy 255.855724 10.67054)
					(xy 256.452624 10.67054) (xy 256.452624 10.577068) (xy 255.855724 10.577068) (xy 255.855724 10.170668)
					(xy 256.452624 10.170668) (xy 256.452624 10.075164) (xy 255.754124 10.075164) (xy 255.754124 11.172444)
				)
			)
		)
	)
	(footprint ""
		(layer "B.Cu")
		(at 9.078976 -380.957836 90)
		(property "Reference" "C4471"
			(at 0 0 90)
			(layer "B.SilkS")
			(hide yes)
			(effects
				(font
					(size 1.27 1.27)
				)
				(justify mirror)
			)
		)
		(property "Value" ""
			(at 0 0 90)
			(layer "B.Fab")
			(effects
				(font
					(size 1.27 1.27)
				)
				(justify mirror)
			)
		)
		(duplicate_pad_numbers_are_jumpers no)
		(fp_line
			(start 0.7874 -0.4064)
			(end -0.7874 -0.4064)
			(stroke
				(width 0.1524)
				(type default)
			)
			(layer "B.SilkS")
		)
		(fp_line
			(start -0.7874 -0.4064)
			(end -0.7874 0.4064)
			(stroke
				(width 0.1524)
				(type default)
			)
			(layer "B.SilkS")
		)
		(fp_line
			(start 0.7874 0.4064)
			(end 0.7874 -0.4064)
			(stroke
				(width 0.1524)
				(type default)
			)
			(layer "B.SilkS")
		)
		(fp_line
			(start -0.7874 0.4064)
			(end 0.7874 0.4064)
			(stroke
				(width 0.1524)
				(type default)
			)
			(layer "B.SilkS")
		)
		(fp_line
			(start 0.67945 -0.305054)
			(end 0.12065 -0.305054)
			(stroke
				(width 0.1)
				(type default)
			)
			(layer "B.Fab")
		)
		(fp_line
			(start 0.12065 -0.305054)
			(end 0.12065 -0.2794)
			(stroke
				(width 0.1)
				(type default)
			)
			(layer "B.Fab")
		)
		(fp_line
			(start -0.12065 -0.3048)
			(end -0.67945 -0.3048)
			(stroke
				(width 0.1)
				(type default)
			)
			(layer "B.Fab")
		)
		(fp_line
			(start -0.67945 -0.3048)
			(end -0.67945 0.3048)
			(stroke
				(width 0.1)
				(type default)
			)
			(layer "B.Fab")
		)
		(fp_line
			(start 0.12065 -0.2794)
			(end -0.12065 -0.2794)
			(stroke
				(width 0.1)
				(type default)
			)
			(layer "B.Fab")
		)
		(fp_line
			(start -0.12065 -0.2794)
			(end -0.12065 -0.3048)
			(stroke
				(width 0.1)
				(type default)
			)
			(layer "B.Fab")
		)
		(fp_line
			(start 0.12065 0.2794)
			(end 0.12065 0.3048)
			(stroke
				(width 0.1)
				(type default)
			)
			(layer "B.Fab")
		)
		(fp_line
			(start -0.120396 0.2794)
			(end 0.12065 0.2794)
			(stroke
				(width 0.1)
				(type default)
			)
			(layer "B.Fab")
		)
		(fp_line
			(start 0.67945 0.3048)
			(end 0.67945 -0.305054)
			(stroke
				(width 0.1)
				(type default)
			)
			(layer "B.Fab")
		)
		(fp_line
			(start 0.12065 0.3048)
			(end 0.67945 0.3048)
			(stroke
				(width 0.1)
				(type default)
			)
			(layer "B.Fab")
		)
		(fp_line
			(start -0.120396 0.3048)
			(end -0.120396 0.2794)
			(stroke
				(width 0.1)
				(type default)
			)
			(layer "B.Fab")
		)
		(fp_line
			(start -0.67945 0.3048)
			(end -0.120396 0.3048)
			(stroke
				(width 0.1)
				(type default)
			)
			(layer "B.Fab")
		)
		(pad "1" smd circle
			(at 0.40005 0 270)
			(size 0 0)
			(layers "B.Cu" "B.Mask" "B.Paste")
			(net "P1V2_USB_8042")
		)
		(pad "2" smd circle
			(at -0.40005 0 270)
			(size 0 0)
			(layers "B.Cu" "B.Mask" "B.Paste")
			(net "GND")
		)
	)
	(footprint ""
		(layer "B.Cu")
		(at 50.644044 -138.421618 180)
		(property "Reference" "R24"
			(at 0 0 0)
			(layer "B.SilkS")
			(hide yes)
			(effects
				(font
					(size 1.27 1.27)
				)
				(justify mirror)
			)
		)
		(property "Value" ""
			(at 0 0 0)
			(layer "B.Fab")
			(effects
				(font
					(size 1.27 1.27)
				)
				(justify mirror)
			)
		)
		(duplicate_pad_numbers_are_jumpers no)
		(fp_line
			(start 0.7874 0.4064)
			(end 0.7874 -0.4064)
			(stroke
				(width 0.1524)
				(type default)
			)
			(layer "B.SilkS")
		)
		(fp_line
			(start 0.7874 -0.4064)
			(end -0.7874 -0.4064)
			(stroke
				(width 0.1524)
				(type default)
			)
			(layer "B.SilkS")
		)
		(fp_line
			(start -0.7874 0.4064)
			(end 0.7874 0.4064)
			(stroke
				(width 0.1524)
				(type default)
			)
			(layer "B.SilkS")
		)
		(fp_line
			(start -0.7874 -0.4064)
			(end -0.7874 0.4064)
			(stroke
				(width 0.1524)
				(type default)
			)
			(layer "B.SilkS")
		)
		(fp_line
			(start 0.67945 0.3048)
			(end 0.67945 -0.305054)
			(stroke
				(width 0.1)
				(type default)
			)
			(layer "B.Fab")
		)
		(fp_line
			(start 0.67945 -0.305054)
			(end 0.12065 -0.305054)
			(stroke
				(width 0.1)
				(type default)
			)
			(layer "B.Fab")
		)
		(fp_line
			(start 0.12065 0.3048)
			(end 0.67945 0.3048)
			(stroke
				(width 0.1)
				(type default)
			)
			(layer "B.Fab")
		)
		(fp_line
			(start 0.12065 0.2794)
			(end 0.12065 0.3048)
			(stroke
				(width 0.1)
				(type default)
			)
			(layer "B.Fab")
		)
		(fp_line
			(start 0.12065 -0.2794)
			(end -0.12065 -0.2794)
			(stroke
				(width 0.1)
				(type default)
			)
			(layer "B.Fab")
		)
		(fp_line
			(start 0.12065 -0.305054)
			(end 0.12065 -0.2794)
			(stroke
				(width 0.1)
				(type default)
			)
			(layer "B.Fab")
		)
		(fp_line
			(start -0.120396 0.3048)
			(end -0.120396 0.2794)
			(stroke
				(width 0.1)
				(type default)
			)
			(layer "B.Fab")
		)
		(fp_line
			(start -0.120396 0.2794)
			(end 0.12065 0.2794)
			(stroke
				(width 0.1)
				(type default)
			)
			(layer "B.Fab")
		)
		(fp_line
			(start -0.12065 -0.2794)
			(end -0.12065 -0.3048)
			(stroke
				(width 0.1)
				(type default)
			)
			(layer "B.Fab")
		)
		(fp_line
			(start -0.12065 -0.3048)
			(end -0.67945 -0.3048)
			(stroke
				(width 0.1)
				(type default)
			)
			(layer "B.Fab")
		)
		(fp_line
			(start -0.67945 0.3048)
			(end -0.120396 0.3048)
			(stroke
				(width 0.1)
				(type default)
			)
			(layer "B.Fab")
		)
		(fp_line
			(start -0.67945 -0.3048)
			(end -0.67945 0.3048)
			(stroke
				(width 0.1)
				(type default)
			)
			(layer "B.Fab")
		)
		(pad "1" smd circle
			(at 0.40005 0)
			(size 0 0)
			(layers "B.Cu" "B.Mask" "B.Paste")
			(net "NIC0_AUX_PWR_EN")
		)
		(pad "2" smd circle
			(at -0.40005 0)
			(size 0 0)
			(layers "B.Cu" "B.Mask" "B.Paste")
			(net "GND")
		)
	)
	(footprint ""
		(layer "B.Cu")
		(at 110.817914 -325.153528 -90)
		(property "Reference" "C4205"
			(at 0 0 90)
			(layer "B.SilkS")
			(hide yes)
			(effects
				(font
					(size 1.27 1.27)
				)
				(justify mirror)
			)
		)
		(property "Value" ""
			(at 0 0 90)
			(layer "B.Fab")
			(effects
				(font
					(size 1.27 1.27)
				)
				(justify mirror)
			)
		)
		(duplicate_pad_numbers_are_jumpers no)
		(fp_line
			(start -1.2954 0.5842)
			(end 1.2954 0.5842)
			(stroke
				(width 0.1524)
				(type default)
			)
			(layer "B.SilkS")
		)
		(fp_line
			(start 1.2954 0.5842)
			(end 1.2954 -0.5842)
			(stroke
				(width 0.1524)
				(type default)
			)
			(layer "B.SilkS")
		)
		(fp_line
			(start -1.2954 -0.5842)
			(end -1.2954 0.5842)
			(stroke
				(width 0.1524)
				(type default)
			)
			(layer "B.SilkS")
		)
		(fp_line
			(start 1.2954 -0.5842)
			(end -1.2954 -0.5842)
			(stroke
				(width 0.1524)
				(type default)
			)
			(layer "B.SilkS")
		)
		(fp_line
			(start -0.8636 0.4572)
			(end 0.8636 0.4572)
			(stroke
				(width 0.1)
				(type default)
			)
			(layer "B.Fab")
		)
		(fp_line
			(start 0.8636 0.4572)
			(end 0.8636 0.4064)
			(stroke
				(width 0.1)
				(type default)
			)
			(layer "B.Fab")
		)
		(fp_line
			(start -1.1938 0.4064)
			(end -0.8636 0.4064)
			(stroke
				(width 0.1)
				(type default)
			)
			(layer "B.Fab")
		)
		(fp_line
			(start -0.8636 0.4064)
			(end -0.8636 0.4572)
			(stroke
				(width 0.1)
				(type default)
			)
			(layer "B.Fab")
		)
		(fp_line
			(start 0.8636 0.4064)
			(end 1.1938 0.4064)
			(stroke
				(width 0.1)
				(type default)
			)
			(layer "B.Fab")
		)
		(fp_line
			(start 1.1938 0.4064)
			(end 1.1938 -0.4064)
			(stroke
				(width 0.1)
				(type default)
			)
			(layer "B.Fab")
		)
		(fp_line
			(start -1.1938 -0.4064)
			(end -1.1938 0.4064)
			(stroke
				(width 0.1)
				(type default)
			)
			(layer "B.Fab")
		)
		(fp_line
			(start -0.8636 -0.4064)
			(end -1.1938 -0.4064)
			(stroke
				(width 0.1)
				(type default)
			)
			(layer "B.Fab")
		)
		(fp_line
			(start 0.8636 -0.4064)
			(end 0.8636 -0.4572)
			(stroke
				(width 0.1)
				(type default)
			)
			(layer "B.Fab")
		)
		(fp_line
			(start 1.1938 -0.4064)
			(end 0.8636 -0.4064)
			(stroke
				(width 0.1)
				(type default)
			)
			(layer "B.Fab")
		)
		(fp_line
			(start -0.8636 -0.4572)
			(end -0.8636 -0.4064)
			(stroke
				(width 0.1)
				(type default)
			)
			(layer "B.Fab")
		)
		(fp_line
			(start 0.8636 -0.4572)
			(end -0.8636 -0.4572)
			(stroke
				(width 0.1)
				(type default)
			)
			(layer "B.Fab")
		)
		(pad "1" smd rect
			(at 0.7366 0 180)
			(size 0.7112 0.8128)
			(layers "B.Cu" "B.Mask" "B.Paste")
			(net "P0V8_SERDES_VDDA_PEX0_C3")
		)
		(pad "2" smd rect
			(at -0.7366 0 180)
			(size 0.7112 0.8128)
			(layers "B.Cu" "B.Mask" "B.Paste")
			(net "GND")
		)
	)
	(footprint ""
		(layer "B.Cu")
		(at 239.209072 -220.085412 90)
		(property "Reference" "C3618"
			(at 0 0 90)
			(layer "B.SilkS")
			(hide yes)
			(effects
				(font
					(size 1.27 1.27)
				)
				(justify mirror)
			)
		)
		(property "Value" ""
			(at 0 0 90)
			(layer "B.Fab")
			(effects
				(font
					(size 1.27 1.27)
				)
				(justify mirror)
			)
		)
		(duplicate_pad_numbers_are_jumpers no)
		(fp_line
			(start 0.69215 -0.2921)
			(end -0.69215 -0.2921)
			(stroke
				(width 0.1524)
				(type default)
			)
			(layer "B.SilkS")
		)
		(fp_line
			(start -0.69215 -0.2921)
			(end -0.69215 0.2921)
			(stroke
				(width 0.1524)
				(type default)
			)
			(layer "B.SilkS")
		)
		(fp_line
			(start 0.69215 0.2921)
			(end 0.69215 -0.2921)
			(stroke
				(width 0.1524)
				(type default)
			)
			(layer "B.SilkS")
		)
		(fp_line
			(start -0.69215 0.2921)
			(end 0.69215 0.2921)
			(stroke
				(width 0.1524)
				(type default)
			)
			(layer "B.SilkS")
		)
		(fp_line
			(start 0.51435 -0.2794)
			(end -0.51435 -0.2794)
			(stroke
				(width 0.1)
				(type default)
			)
			(layer "B.Fab")
		)
		(fp_line
			(start -0.51435 -0.2794)
			(end -0.51435 0.2794)
			(stroke
				(width 0.1)
				(type default)
			)
			(layer "B.Fab")
		)
		(fp_line
			(start 0.51435 0.2794)
			(end 0.51435 -0.2794)
			(stroke
				(width 0.1)
				(type default)
			)
			(layer "B.Fab")
		)
		(fp_line
			(start -0.51435 0.2794)
			(end 0.51435 0.2794)
			(stroke
				(width 0.1)
				(type default)
			)
			(layer "B.Fab")
		)
		(pad "1" smd circle
			(at 0.40005 0 270)
			(size 0 0)
			(layers "B.Cu" "B.Mask" "B.Paste")
			(net "BIC_ADCVREFP1")
		)
		(pad "2" smd circle
			(at -0.40005 0 270)
			(size 0 0)
			(layers "B.Cu" "B.Mask" "B.Paste")
			(net "BIC_ADCVREFN1")
		)
		(zone
			(layer "B.Cu")
			(hatch none 0.5)
			(connect_pads
				(clearance 0)
			)
			(min_thickness 0.25)
			(keepout
				(tracks not_allowed)
				(vias allowed)
				(pads allowed)
				(copperpour not_allowed)
				(footprints allowed)
			)
			(placement
				(enabled no)
				(sheetname "")
			)
			(fill
				(thermal_gap 0.5)
				(thermal_bridge_width 0.5)
				(island_removal_mode 0)
			)
			(polygon
				(pts
					(xy 239.296702 -220.275912) (xy 239.354868 -220.184472) (xy 239.354868 -219.985082) (xy 239.296702 -219.894912)
					(xy 239.121442 -219.894912) (xy 239.063022 -219.985082) (xy 239.063022 -220.184472) (xy 239.121188 -220.275912)
				)
			)
		)
	)
	(footprint ""
		(layer "B.Cu")
		(at 400.77009 -305.399948 -90)
		(property "Reference" "C3492"
			(at 0 0 90)
			(layer "B.SilkS")
			(hide yes)
			(effects
				(font
					(size 1.27 1.27)
				)
				(justify mirror)
			)
		)
		(property "Value" ""
			(at 0 0 90)
			(layer "B.Fab")
			(effects
				(font
					(size 1.27 1.27)
				)
				(justify mirror)
			)
		)
		(duplicate_pad_numbers_are_jumpers no)
		(fp_line
			(start -0.299974 0.150114)
			(end 0.299974 0.150114)
			(stroke
				(width 0.1)
				(type default)
			)
			(layer "B.Fab")
		)
		(fp_line
			(start 0.299974 0.150114)
			(end 0.299974 -0.150114)
			(stroke
				(width 0.1)
				(type default)
			)
			(layer "B.Fab")
		)
		(fp_line
			(start -0.299974 -0.150114)
			(end -0.299974 0.150114)
			(stroke
				(width 0.1)
				(type default)
			)
			(layer "B.Fab")
		)
		(fp_line
			(start 0.299974 -0.150114)
			(end -0.299974 -0.150114)
			(stroke
				(width 0.1)
				(type default)
			)
			(layer "B.Fab")
		)
		(pad "1" smd rect
			(at 0.2667 0 90)
			(size 0.3048 0.381)
			(layers "B.Cu" "B.Mask" "B.Paste")
			(net "P1V25_SERDES_VDDPLL_PEX3")
		)
		(pad "2" smd rect
			(at -0.2667 0 90)
			(size 0.3048 0.381)
			(layers "B.Cu" "B.Mask" "B.Paste")
			(net "GND")
		)
	)
	(footprint ""
		(layer "B.Cu")
		(at 297.074844 -286.399732 90)
		(property "Reference" "C3328"
			(at 0 0 90)
			(layer "B.SilkS")
			(hide yes)
			(effects
				(font
					(size 1.27 1.27)
				)
				(justify mirror)
			)
		)
		(property "Value" ""
			(at 0 0 90)
			(layer "B.Fab")
			(effects
				(font
					(size 1.27 1.27)
				)
				(justify mirror)
			)
		)
		(duplicate_pad_numbers_are_jumpers no)
		(fp_line
			(start 0.299974 -0.150114)
			(end -0.299974 -0.150114)
			(stroke
				(width 0.1)
				(type default)
			)
			(layer "B.Fab")
		)
		(fp_line
			(start -0.299974 -0.150114)
			(end -0.299974 0.150114)
			(stroke
				(width 0.1)
				(type default)
			)
			(layer "B.Fab")
		)
		(fp_line
			(start 0.299974 0.150114)
			(end 0.299974 -0.150114)
			(stroke
				(width 0.1)
				(type default)
			)
			(layer "B.Fab")
		)
		(fp_line
			(start -0.299974 0.150114)
			(end 0.299974 0.150114)
			(stroke
				(width 0.1)
				(type default)
			)
			(layer "B.Fab")
		)
		(pad "1" smd rect
			(at 0.2667 0 270)
			(size 0.3048 0.381)
			(layers "B.Cu" "B.Mask" "B.Paste")
			(net "P1V25_SERDES_VDDPLL_PEX2")
		)
		(pad "2" smd rect
			(at -0.2667 0 270)
			(size 0.3048 0.381)
			(layers "B.Cu" "B.Mask" "B.Paste")
			(net "GND")
		)
	)
	(footprint ""
		(layer "B.Cu")
		(at 226.694492 -176.303178 180)
		(property "Reference" "U450"
			(at -1.600708 -1.755648 0)
			(unlocked yes)
			(layer "B.SilkS")
			(effects
				(font
					(size 0.7874 0.5842)
					(thickness 0.1524)
				)
				(justify left mirror)
			)
		)
		(property "Value" ""
			(at 0 0 0)
			(layer "B.Fab")
			(effects
				(font
					(size 1.27 1.27)
				)
				(justify mirror)
			)
		)
		(duplicate_pad_numbers_are_jumpers no)
		(fp_line
			(start 0.779018 0.800862)
			(end -0.779018 0.800862)
			(stroke
				(width 0.1524)
				(type default)
			)
			(layer "B.SilkS")
		)
		(fp_line
			(start 0.779018 -0.800862)
			(end 0.779018 0.800862)
			(stroke
				(width 0.1524)
				(type default)
			)
			(layer "B.SilkS")
		)
		(fp_line
			(start -0.779018 0.800862)
			(end -0.779018 -0.800862)
			(stroke
				(width 0.1524)
				(type default)
			)
			(layer "B.SilkS")
		)
		(fp_line
			(start -0.779018 -0.800862)
			(end 0.779018 -0.800862)
			(stroke
				(width 0.1524)
				(type default)
			)
			(layer "B.SilkS")
		)
		(fp_poly
			(pts
				(xy 0.923544 -0.500126) (xy 1.313434 -0.714502) (xy 1.313434 -0.285496)
			)
			(stroke
				(width 0)
				(type default)
			)
			(fill yes)
			(layer "B.SilkS")
		)
		(fp_line
			(start 0.525018 0.750062)
			(end 0.525018 -0.750062)
			(stroke
				(width 0.1)
				(type default)
			)
			(layer "B.Fab")
		)
		(fp_line
			(start 0.525018 -0.750062)
			(end -0.525018 -0.750062)
			(stroke
				(width 0.1)
				(type default)
			)
			(layer "B.Fab")
		)
		(fp_line
			(start -0.525018 0.750062)
			(end 0.525018 0.750062)
			(stroke
				(width 0.1)
				(type default)
			)
			(layer "B.Fab")
		)
		(fp_line
			(start -0.525018 -0.750062)
			(end -0.525018 0.750062)
			(stroke
				(width 0.1)
				(type default)
			)
			(layer "B.Fab")
		)
		(fp_poly
			(pts
				(xy 0.923544 -0.500126) (xy 1.313434 -0.714502) (xy 1.313434 -0.285496)
			)
			(stroke
				(width 0)
				(type default)
			)
			(fill yes)
			(layer "B.Fab")
		)
		(pad "1" smd rect
			(at 0.377444 -0.500126 90)
			(size 0.3048 0.5334)
			(layers "B.Cu" "B.Mask" "B.Paste")
			(net "ADM1085_CEXT")
		)
		(pad "2" smd rect
			(at 0.372618 0 90)
			(size 0.2794 0.508)
			(layers "B.Cu" "B.Mask" "B.Paste")
			(net "GND")
		)
		(pad "3" smd rect
			(at 0.372618 0.499872 90)
			(size 0.2794 0.508)
			(layers "B.Cu" "B.Mask" "B.Paste")
			(net "ADM1085_IN")
		)
		(pad "4" smd rect
			(at -0.377444 0.499872 90)
			(size 0.2794 0.508)
			(layers "B.Cu" "B.Mask" "B.Paste")
			(net "ADM1085_ENOUT")
		)
		(pad "5" smd rect
			(at -0.377444 0 90)
			(size 0.2794 0.508)
			(layers "B.Cu" "B.Mask" "B.Paste")
			(net "THRESHOLD")
		)
		(pad "6" smd rect
			(at -0.377444 -0.500126 90)
			(size 0.2794 0.508)
			(layers "B.Cu" "B.Mask" "B.Paste")
			(net "P3V3_AUX")
		)
	)
	(footprint ""
		(layer "B.Cu")
		(at 306.633626 -246.199406 90)
		(property "Reference" "R4104"
			(at 0 0 90)
			(layer "B.SilkS")
			(hide yes)
			(effects
				(font
					(size 1.27 1.27)
				)
				(justify mirror)
			)
		)
		(property "Value" ""
			(at 0 0 90)
			(layer "B.Fab")
			(effects
				(font
					(size 1.27 1.27)
				)
				(justify mirror)
			)
		)
		(duplicate_pad_numbers_are_jumpers no)
		(fp_line
			(start 0.7874 -0.4064)
			(end -0.7874 -0.4064)
			(stroke
				(width 0.1524)
				(type default)
			)
			(layer "B.SilkS")
		)
		(fp_line
			(start -0.7874 -0.4064)
			(end -0.7874 0.4064)
			(stroke
				(width 0.1524)
				(type default)
			)
			(layer "B.SilkS")
		)
		(fp_line
			(start 0.7874 0.4064)
			(end 0.7874 -0.4064)
			(stroke
				(width 0.1524)
				(type default)
			)
			(layer "B.SilkS")
		)
		(fp_line
			(start -0.7874 0.4064)
			(end 0.7874 0.4064)
			(stroke
				(width 0.1524)
				(type default)
			)
			(layer "B.SilkS")
		)
		(fp_line
			(start 0.67945 -0.305054)
			(end 0.12065 -0.305054)
			(stroke
				(width 0.1)
				(type default)
			)
			(layer "B.Fab")
		)
		(fp_line
			(start 0.12065 -0.305054)
			(end 0.12065 -0.2794)
			(stroke
				(width 0.1)
				(type default)
			)
			(layer "B.Fab")
		)
		(fp_line
			(start -0.12065 -0.3048)
			(end -0.67945 -0.3048)
			(stroke
				(width 0.1)
				(type default)
			)
			(layer "B.Fab")
		)
		(fp_line
			(start -0.67945 -0.3048)
			(end -0.67945 0.3048)
			(stroke
				(width 0.1)
				(type default)
			)
			(layer "B.Fab")
		)
		(fp_line
			(start 0.12065 -0.2794)
			(end -0.12065 -0.2794)
			(stroke
				(width 0.1)
				(type default)
			)
			(layer "B.Fab")
		)
		(fp_line
			(start -0.12065 -0.2794)
			(end -0.12065 -0.3048)
			(stroke
				(width 0.1)
				(type default)
			)
			(layer "B.Fab")
		)
		(fp_line
			(start 0.12065 0.2794)
			(end 0.12065 0.3048)
			(stroke
				(width 0.1)
				(type default)
			)
			(layer "B.Fab")
		)
		(fp_line
			(start -0.120396 0.2794)
			(end 0.12065 0.2794)
			(stroke
				(width 0.1)
				(type default)
			)
			(layer "B.Fab")
		)
		(fp_line
			(start 0.67945 0.3048)
			(end 0.67945 -0.305054)
			(stroke
				(width 0.1)
				(type default)
			)
			(layer "B.Fab")
		)
		(fp_line
			(start 0.12065 0.3048)
			(end 0.67945 0.3048)
			(stroke
				(width 0.1)
				(type default)
			)
			(layer "B.Fab")
		)
		(fp_line
			(start -0.120396 0.3048)
			(end -0.120396 0.2794)
			(stroke
				(width 0.1)
				(type default)
			)
			(layer "B.Fab")
		)
		(fp_line
			(start -0.67945 0.3048)
			(end -0.120396 0.3048)
			(stroke
				(width 0.1)
				(type default)
			)
			(layer "B.Fab")
		)
		(pad "1" smd circle
			(at 0.40005 0 270)
			(size 0 0)
			(layers "B.Cu" "B.Mask" "B.Paste")
			(net "SMB_MB_BMC_R_SCL")
		)
		(pad "2" smd circle
			(at -0.40005 0 270)
			(size 0 0)
			(layers "B.Cu" "B.Mask" "B.Paste")
			(net "SMB_MB_BMC_ISO_SCL")
		)
	)
	(footprint ""
		(layer "B.Cu")
		(at 185.250074 -303.024794)
		(property "Reference" "C3165"
			(at 0 0 0)
			(layer "B.SilkS")
			(hide yes)
			(effects
				(font
					(size 1.27 1.27)
				)
				(justify mirror)
			)
		)
		(property "Value" ""
			(at 0 0 0)
			(layer "B.Fab")
			(effects
				(font
					(size 1.27 1.27)
				)
				(justify mirror)
			)
		)
		(duplicate_pad_numbers_are_jumpers no)
		(fp_line
			(start -0.299974 -0.150114)
			(end -0.299974 0.150114)
			(stroke
				(width 0.1)
				(type default)
			)
			(layer "B.Fab")
		)
		(fp_line
			(start -0.299974 0.150114)
			(end 0.299974 0.150114)
			(stroke
				(width 0.1)
				(type default)
			)
			(layer "B.Fab")
		)
		(fp_line
			(start 0.299974 -0.150114)
			(end -0.299974 -0.150114)
			(stroke
				(width 0.1)
				(type default)
			)
			(layer "B.Fab")
		)
		(fp_line
			(start 0.299974 0.150114)
			(end 0.299974 -0.150114)
			(stroke
				(width 0.1)
				(type default)
			)
			(layer "B.Fab")
		)
		(pad "1" smd rect
			(at 0.2667 0 180)
			(size 0.3048 0.381)
			(layers "B.Cu" "B.Mask" "B.Paste")
			(net "P1V8_PEX")
		)
		(pad "2" smd rect
			(at -0.2667 0 180)
			(size 0.3048 0.381)
			(layers "B.Cu" "B.Mask" "B.Paste")
			(net "GND")
		)
	)
	(footprint ""
		(layer "B.Cu")
		(at 165.299898 -292.574726 180)
		(property "Reference" "C1361"
			(at 0 0 0)
			(layer "B.SilkS")
			(hide yes)
			(effects
				(font
					(size 1.27 1.27)
				)
				(justify mirror)
			)
		)
		(property "Value" ""
			(at 0 0 0)
			(layer "B.Fab")
			(effects
				(font
					(size 1.27 1.27)
				)
				(justify mirror)
			)
		)
		(duplicate_pad_numbers_are_jumpers no)
		(fp_line
			(start 0.299974 0.150114)
			(end 0.299974 -0.150114)
			(stroke
				(width 0.1)
				(type default)
			)
			(layer "B.Fab")
		)
		(fp_line
			(start 0.299974 -0.150114)
			(end -0.299974 -0.150114)
			(stroke
				(width 0.1)
				(type default)
			)
			(layer "B.Fab")
		)
		(fp_line
			(start -0.299974 0.150114)
			(end 0.299974 0.150114)
			(stroke
				(width 0.1)
				(type default)
			)
			(layer "B.Fab")
		)
		(fp_line
			(start -0.299974 -0.150114)
			(end -0.299974 0.150114)
			(stroke
				(width 0.1)
				(type default)
			)
			(layer "B.Fab")
		)
		(pad "1" smd rect
			(at 0.2667 0)
			(size 0.3048 0.381)
			(layers "B.Cu" "B.Mask" "B.Paste")
			(net "P0V8_PEX1")
		)
		(pad "2" smd rect
			(at -0.2667 0)
			(size 0.3048 0.381)
			(layers "B.Cu" "B.Mask" "B.Paste")
			(net "GND")
		)
	)
	(footprint ""
		(layer "B.Cu")
		(at 132.939536 -215.85682 180)
		(property "Reference" "R999"
			(at 0 0 0)
			(layer "B.SilkS")
			(hide yes)
			(effects
				(font
					(size 1.27 1.27)
				)
				(justify mirror)
			)
		)
		(property "Value" ""
			(at 0 0 0)
			(layer "B.Fab")
			(effects
				(font
					(size 1.27 1.27)
				)
				(justify mirror)
			)
		)
		(duplicate_pad_numbers_are_jumpers no)
		(fp_line
			(start 0.7874 0.4064)
			(end 0.7874 -0.4064)
			(stroke
				(width 0.1524)
				(type default)
			)
			(layer "B.SilkS")
		)
		(fp_line
			(start 0.7874 -0.4064)
			(end -0.7874 -0.4064)
			(stroke
				(width 0.1524)
				(type default)
			)
			(layer "B.SilkS")
		)
		(fp_line
			(start -0.7874 0.4064)
			(end 0.7874 0.4064)
			(stroke
				(width 0.1524)
				(type default)
			)
			(layer "B.SilkS")
		)
		(fp_line
			(start -0.7874 -0.4064)
			(end -0.7874 0.4064)
			(stroke
				(width 0.1524)
				(type default)
			)
			(layer "B.SilkS")
		)
		(fp_line
			(start 0.67945 0.3048)
			(end 0.67945 -0.305054)
			(stroke
				(width 0.1)
				(type default)
			)
			(layer "B.Fab")
		)
		(fp_line
			(start 0.67945 -0.305054)
			(end 0.12065 -0.305054)
			(stroke
				(width 0.1)
				(type default)
			)
			(layer "B.Fab")
		)
		(fp_line
			(start 0.12065 0.3048)
			(end 0.67945 0.3048)
			(stroke
				(width 0.1)
				(type default)
			)
			(layer "B.Fab")
		)
		(fp_line
			(start 0.12065 0.2794)
			(end 0.12065 0.3048)
			(stroke
				(width 0.1)
				(type default)
			)
			(layer "B.Fab")
		)
		(fp_line
			(start 0.12065 -0.2794)
			(end -0.12065 -0.2794)
			(stroke
				(width 0.1)
				(type default)
			)
			(layer "B.Fab")
		)
		(fp_line
			(start 0.12065 -0.305054)
			(end 0.12065 -0.2794)
			(stroke
				(width 0.1)
				(type default)
			)
			(layer "B.Fab")
		)
		(fp_line
			(start -0.120396 0.3048)
			(end -0.120396 0.2794)
			(stroke
				(width 0.1)
				(type default)
			)
			(layer "B.Fab")
		)
		(fp_line
			(start -0.120396 0.2794)
			(end 0.12065 0.2794)
			(stroke
				(width 0.1)
				(type default)
			)
			(layer "B.Fab")
		)
		(fp_line
			(start -0.12065 -0.2794)
			(end -0.12065 -0.3048)
			(stroke
				(width 0.1)
				(type default)
			)
			(layer "B.Fab")
		)
		(fp_line
			(start -0.12065 -0.3048)
			(end -0.67945 -0.3048)
			(stroke
				(width 0.1)
				(type default)
			)
			(layer "B.Fab")
		)
		(fp_line
			(start -0.67945 0.3048)
			(end -0.120396 0.3048)
			(stroke
				(width 0.1)
				(type default)
			)
			(layer "B.Fab")
		)
		(fp_line
			(start -0.67945 -0.3048)
			(end -0.67945 0.3048)
			(stroke
				(width 0.1)
				(type default)
			)
			(layer "B.Fab")
		)
		(pad "1" smd circle
			(at 0.40005 0)
			(size 0 0)
			(layers "B.Cu" "B.Mask" "B.Paste")
			(net "UART_PEX3_CLI_BUF_R_TX")
		)
		(pad "2" smd circle
			(at -0.40005 0)
			(size 0 0)
			(layers "B.Cu" "B.Mask" "B.Paste")
			(net "UART_PEX3_CLI_BUF_TX")
		)
	)
	(footprint ""
		(layer "B.Cu")
		(at 6.93166 -386.784596 180)
		(property "Reference" "C4467"
			(at 0 0 0)
			(layer "B.SilkS")
			(hide yes)
			(effects
				(font
					(size 1.27 1.27)
				)
				(justify mirror)
			)
		)
		(property "Value" ""
			(at 0 0 0)
			(layer "B.Fab")
			(effects
				(font
					(size 1.27 1.27)
				)
				(justify mirror)
			)
		)
		(duplicate_pad_numbers_are_jumpers no)
		(fp_line
			(start 0.7874 0.4064)
			(end 0.7874 -0.4064)
			(stroke
				(width 0.1524)
				(type default)
			)
			(layer "B.SilkS")
		)
		(fp_line
			(start 0.7874 -0.4064)
			(end -0.7874 -0.4064)
			(stroke
				(width 0.1524)
				(type default)
			)
			(layer "B.SilkS")
		)
		(fp_line
			(start -0.7874 0.4064)
			(end 0.7874 0.4064)
			(stroke
				(width 0.1524)
				(type default)
			)
			(layer "B.SilkS")
		)
		(fp_line
			(start -0.7874 -0.4064)
			(end -0.7874 0.4064)
			(stroke
				(width 0.1524)
				(type default)
			)
			(layer "B.SilkS")
		)
		(fp_line
			(start 0.67945 0.3048)
			(end 0.67945 -0.305054)
			(stroke
				(width 0.1)
				(type default)
			)
			(layer "B.Fab")
		)
		(fp_line
			(start 0.67945 -0.305054)
			(end 0.12065 -0.305054)
			(stroke
				(width 0.1)
				(type default)
			)
			(layer "B.Fab")
		)
		(fp_line
			(start 0.12065 0.3048)
			(end 0.67945 0.3048)
			(stroke
				(width 0.1)
				(type default)
			)
			(layer "B.Fab")
		)
		(fp_line
			(start 0.12065 0.2794)
			(end 0.12065 0.3048)
			(stroke
				(width 0.1)
				(type default)
			)
			(layer "B.Fab")
		)
		(fp_line
			(start 0.12065 -0.2794)
			(end -0.12065 -0.2794)
			(stroke
				(width 0.1)
				(type default)
			)
			(layer "B.Fab")
		)
		(fp_line
			(start 0.12065 -0.305054)
			(end 0.12065 -0.2794)
			(stroke
				(width 0.1)
				(type default)
			)
			(layer "B.Fab")
		)
		(fp_line
			(start -0.120396 0.3048)
			(end -0.120396 0.2794)
			(stroke
				(width 0.1)
				(type default)
			)
			(layer "B.Fab")
		)
		(fp_line
			(start -0.120396 0.2794)
			(end 0.12065 0.2794)
			(stroke
				(width 0.1)
				(type default)
			)
			(layer "B.Fab")
		)
		(fp_line
			(start -0.12065 -0.2794)
			(end -0.12065 -0.3048)
			(stroke
				(width 0.1)
				(type default)
			)
			(layer "B.Fab")
		)
		(fp_line
			(start -0.12065 -0.3048)
			(end -0.67945 -0.3048)
			(stroke
				(width 0.1)
				(type default)
			)
			(layer "B.Fab")
		)
		(fp_line
			(start -0.67945 0.3048)
			(end -0.120396 0.3048)
			(stroke
				(width 0.1)
				(type default)
			)
			(layer "B.Fab")
		)
		(fp_line
			(start -0.67945 -0.3048)
			(end -0.67945 0.3048)
			(stroke
				(width 0.1)
				(type default)
			)
			(layer "B.Fab")
		)
		(pad "1" smd circle
			(at 0.40005 0)
			(size 0 0)
			(layers "B.Cu" "B.Mask" "B.Paste")
			(net "P1V2_USB_8042")
		)
		(pad "2" smd circle
			(at -0.40005 0)
			(size 0 0)
			(layers "B.Cu" "B.Mask" "B.Paste")
			(net "GND")
		)
	)
	(footprint ""
		(layer "B.Cu")
		(at 401.299934 -303.499774 -90)
		(property "Reference" "C3437"
			(at 0 0 90)
			(layer "B.SilkS")
			(hide yes)
			(effects
				(font
					(size 1.27 1.27)
				)
				(justify mirror)
			)
		)
		(property "Value" ""
			(at 0 0 90)
			(layer "B.Fab")
			(effects
				(font
					(size 1.27 1.27)
				)
				(justify mirror)
			)
		)
		(duplicate_pad_numbers_are_jumpers no)
		(fp_line
			(start -0.299974 0.150114)
			(end 0.299974 0.150114)
			(stroke
				(width 0.1)
				(type default)
			)
			(layer "B.Fab")
		)
		(fp_line
			(start 0.299974 0.150114)
			(end 0.299974 -0.150114)
			(stroke
				(width 0.1)
				(type default)
			)
			(layer "B.Fab")
		)
		(fp_line
			(start -0.299974 -0.150114)
			(end -0.299974 0.150114)
			(stroke
				(width 0.1)
				(type default)
			)
			(layer "B.Fab")
		)
		(fp_line
			(start 0.299974 -0.150114)
			(end -0.299974 -0.150114)
			(stroke
				(width 0.1)
				(type default)
			)
			(layer "B.Fab")
		)
		(pad "1" smd rect
			(at 0.2667 0 90)
			(size 0.3048 0.381)
			(layers "B.Cu" "B.Mask" "B.Paste")
			(net "P1V25_PEX3")
		)
		(pad "2" smd rect
			(at -0.2667 0 90)
			(size 0.3048 0.381)
			(layers "B.Cu" "B.Mask" "B.Paste")
			(net "GND")
		)
	)
	(footprint ""
		(layer "B.Cu")
		(at 417.450016 -302.074834)
		(property "Reference" "C3516"
			(at 0 0 0)
			(layer "B.SilkS")
			(hide yes)
			(effects
				(font
					(size 1.27 1.27)
				)
				(justify mirror)
			)
		)
		(property "Value" ""
			(at 0 0 0)
			(layer "B.Fab")
			(effects
				(font
					(size 1.27 1.27)
				)
				(justify mirror)
			)
		)
		(duplicate_pad_numbers_are_jumpers no)
		(fp_line
			(start -0.299974 -0.150114)
			(end -0.299974 0.150114)
			(stroke
				(width 0.1)
				(type default)
			)
			(layer "B.Fab")
		)
		(fp_line
			(start -0.299974 0.150114)
			(end 0.299974 0.150114)
			(stroke
				(width 0.1)
				(type default)
			)
			(layer "B.Fab")
		)
		(fp_line
			(start 0.299974 -0.150114)
			(end -0.299974 -0.150114)
			(stroke
				(width 0.1)
				(type default)
			)
			(layer "B.Fab")
		)
		(fp_line
			(start 0.299974 0.150114)
			(end 0.299974 -0.150114)
			(stroke
				(width 0.1)
				(type default)
			)
			(layer "B.Fab")
		)
		(pad "1" smd rect
			(at 0.2667 0 180)
			(size 0.3048 0.381)
			(layers "B.Cu" "B.Mask" "B.Paste")
			(net "P1V8_PEX")
		)
		(pad "2" smd rect
			(at -0.2667 0 180)
			(size 0.3048 0.381)
			(layers "B.Cu" "B.Mask" "B.Paste")
			(net "GND")
		)
	)
	(footprint ""
		(layer "B.Cu")
		(at 179.07508 -297.79976 -90)
		(property "Reference" "C1398"
			(at 0 0 90)
			(layer "B.SilkS")
			(hide yes)
			(effects
				(font
					(size 1.27 1.27)
				)
				(justify mirror)
			)
		)
		(property "Value" ""
			(at 0 0 90)
			(layer "B.Fab")
			(effects
				(font
					(size 1.27 1.27)
				)
				(justify mirror)
			)
		)
		(duplicate_pad_numbers_are_jumpers no)
		(fp_line
			(start -0.299974 0.150114)
			(end 0.299974 0.150114)
			(stroke
				(width 0.1)
				(type default)
			)
			(layer "B.Fab")
		)
		(fp_line
			(start 0.299974 0.150114)
			(end 0.299974 -0.150114)
			(stroke
				(width 0.1)
				(type default)
			)
			(layer "B.Fab")
		)
		(fp_line
			(start -0.299974 -0.150114)
			(end -0.299974 0.150114)
			(stroke
				(width 0.1)
				(type default)
			)
			(layer "B.Fab")
		)
		(fp_line
			(start 0.299974 -0.150114)
			(end -0.299974 -0.150114)
			(stroke
				(width 0.1)
				(type default)
			)
			(layer "B.Fab")
		)
		(pad "1" smd rect
			(at 0.2667 0 90)
			(size 0.3048 0.381)
			(layers "B.Cu" "B.Mask" "B.Paste")
			(net "P0V8_PEX1")
		)
		(pad "2" smd rect
			(at -0.2667 0 90)
			(size 0.3048 0.381)
			(layers "B.Cu" "B.Mask" "B.Paste")
			(net "GND")
		)
	)
	(footprint ""
		(layer "B.Cu")
		(at 185.250074 -297.32478 180)
		(property "Reference" "C1421"
			(at 0 0 0)
			(layer "B.SilkS")
			(hide yes)
			(effects
				(font
					(size 1.27 1.27)
				)
				(justify mirror)
			)
		)
		(property "Value" ""
			(at 0 0 0)
			(layer "B.Fab")
			(effects
				(font
					(size 1.27 1.27)
				)
				(justify mirror)
			)
		)
		(duplicate_pad_numbers_are_jumpers no)
		(fp_line
			(start 0.299974 0.150114)
			(end 0.299974 -0.150114)
			(stroke
				(width 0.1)
				(type default)
			)
			(layer "B.Fab")
		)
		(fp_line
			(start 0.299974 -0.150114)
			(end -0.299974 -0.150114)
			(stroke
				(width 0.1)
				(type default)
			)
			(layer "B.Fab")
		)
		(fp_line
			(start -0.299974 0.150114)
			(end 0.299974 0.150114)
			(stroke
				(width 0.1)
				(type default)
			)
			(layer "B.Fab")
		)
		(fp_line
			(start -0.299974 -0.150114)
			(end -0.299974 0.150114)
			(stroke
				(width 0.1)
				(type default)
			)
			(layer "B.Fab")
		)
		(pad "1" smd rect
			(at 0.2667 0)
			(size 0.3048 0.381)
			(layers "B.Cu" "B.Mask" "B.Paste")
			(net "P0V8_SERDES_VDDA_PEX1")
		)
		(pad "2" smd rect
			(at -0.2667 0)
			(size 0.3048 0.381)
			(layers "B.Cu" "B.Mask" "B.Paste")
			(net "GND")
		)
	)
	(footprint ""
		(layer "B.Cu")
		(at 364.855506 -321.85229 -90)
		(property "Reference" "R6547"
			(at 0 0 90)
			(layer "B.SilkS")
			(hide yes)
			(effects
				(font
					(size 1.27 1.27)
				)
				(justify mirror)
			)
		)
		(property "Value" ""
			(at 0 0 90)
			(layer "B.Fab")
			(effects
				(font
					(size 1.27 1.27)
				)
				(justify mirror)
			)
		)
		(duplicate_pad_numbers_are_jumpers no)
		(fp_line
			(start -0.7874 0.4064)
			(end 0.7874 0.4064)
			(stroke
				(width 0.1524)
				(type default)
			)
			(layer "B.SilkS")
		)
		(fp_line
			(start 0.7874 0.4064)
			(end 0.7874 -0.4064)
			(stroke
				(width 0.1524)
				(type default)
			)
			(layer "B.SilkS")
		)
		(fp_line
			(start -0.7874 -0.4064)
			(end -0.7874 0.4064)
			(stroke
				(width 0.1524)
				(type default)
			)
			(layer "B.SilkS")
		)
		(fp_line
			(start 0.7874 -0.4064)
			(end -0.7874 -0.4064)
			(stroke
				(width 0.1524)
				(type default)
			)
			(layer "B.SilkS")
		)
		(fp_line
			(start -0.67945 0.3048)
			(end -0.120396 0.3048)
			(stroke
				(width 0.1)
				(type default)
			)
			(layer "B.Fab")
		)
		(fp_line
			(start -0.120396 0.3048)
			(end -0.120396 0.2794)
			(stroke
				(width 0.1)
				(type default)
			)
			(layer "B.Fab")
		)
		(fp_line
			(start 0.12065 0.3048)
			(end 0.67945 0.3048)
			(stroke
				(width 0.1)
				(type default)
			)
			(layer "B.Fab")
		)
		(fp_line
			(start 0.67945 0.3048)
			(end 0.67945 -0.305054)
			(stroke
				(width 0.1)
				(type default)
			)
			(layer "B.Fab")
		)
		(fp_line
			(start -0.120396 0.2794)
			(end 0.12065 0.2794)
			(stroke
				(width 0.1)
				(type default)
			)
			(layer "B.Fab")
		)
		(fp_line
			(start 0.12065 0.2794)
			(end 0.12065 0.3048)
			(stroke
				(width 0.1)
				(type default)
			)
			(layer "B.Fab")
		)
		(fp_line
			(start -0.12065 -0.2794)
			(end -0.12065 -0.3048)
			(stroke
				(width 0.1)
				(type default)
			)
			(layer "B.Fab")
		)
		(fp_line
			(start 0.12065 -0.2794)
			(end -0.12065 -0.2794)
			(stroke
				(width 0.1)
				(type default)
			)
			(layer "B.Fab")
		)
		(fp_line
			(start -0.67945 -0.3048)
			(end -0.67945 0.3048)
			(stroke
				(width 0.1)
				(type default)
			)
			(layer "B.Fab")
		)
		(fp_line
			(start -0.12065 -0.3048)
			(end -0.67945 -0.3048)
			(stroke
				(width 0.1)
				(type default)
			)
			(layer "B.Fab")
		)
		(fp_line
			(start 0.12065 -0.305054)
			(end 0.12065 -0.2794)
			(stroke
				(width 0.1)
				(type default)
			)
			(layer "B.Fab")
		)
		(fp_line
			(start 0.67945 -0.305054)
			(end 0.12065 -0.305054)
			(stroke
				(width 0.1)
				(type default)
			)
			(layer "B.Fab")
		)
		(pad "1" smd circle
			(at 0.40005 0 90)
			(size 0 0)
			(layers "B.Cu" "B.Mask" "B.Paste")
			(net "P0V8_SERDES_VDDA_PEX3")
		)
		(pad "2" smd circle
			(at -0.40005 0 90)
			(size 0 0)
			(layers "B.Cu" "B.Mask" "B.Paste")
			(net "P0V8_SERDES_VDDA_PEX3_C10")
		)
	)
	(footprint ""
		(layer "B.Cu")
		(at 177.649886 -301.599854 -90)
		(property "Reference" "C1494"
			(at 0 0 90)
			(layer "B.SilkS")
			(hide yes)
			(effects
				(font
					(size 1.27 1.27)
				)
				(justify mirror)
			)
		)
		(property "Value" ""
			(at 0 0 90)
			(layer "B.Fab")
			(effects
				(font
					(size 1.27 1.27)
				)
				(justify mirror)
			)
		)
		(duplicate_pad_numbers_are_jumpers no)
		(fp_line
			(start -0.299974 0.150114)
			(end 0.299974 0.150114)
			(stroke
				(width 0.1)
				(type default)
			)
			(layer "B.Fab")
		)
		(fp_line
			(start 0.299974 0.150114)
			(end 0.299974 -0.150114)
			(stroke
				(width 0.1)
				(type default)
			)
			(layer "B.Fab")
		)
		(fp_line
			(start -0.299974 -0.150114)
			(end -0.299974 0.150114)
			(stroke
				(width 0.1)
				(type default)
			)
			(layer "B.Fab")
		)
		(fp_line
			(start 0.299974 -0.150114)
			(end -0.299974 -0.150114)
			(stroke
				(width 0.1)
				(type default)
			)
			(layer "B.Fab")
		)
		(pad "1" smd rect
			(at 0.2667 0 90)
			(size 0.3048 0.381)
			(layers "B.Cu" "B.Mask" "B.Paste")
			(net "P0V8_SERDES_VDDA_PEX1")
		)
		(pad "2" smd rect
			(at -0.2667 0 90)
			(size 0.3048 0.381)
			(layers "B.Cu" "B.Mask" "B.Paste")
			(net "GND")
		)
	)
	(footprint ""
		(layer "B.Cu")
		(at 125.704346 -325.61149 -90)
		(property "Reference" "C4254"
			(at 0 0 90)
			(layer "B.SilkS")
			(hide yes)
			(effects
				(font
					(size 1.27 1.27)
				)
				(justify mirror)
			)
		)
		(property "Value" ""
			(at 0 0 90)
			(layer "B.Fab")
			(effects
				(font
					(size 1.27 1.27)
				)
				(justify mirror)
			)
		)
		(duplicate_pad_numbers_are_jumpers no)
		(fp_line
			(start -1.2954 0.5842)
			(end 1.2954 0.5842)
			(stroke
				(width 0.1524)
				(type default)
			)
			(layer "B.SilkS")
		)
		(fp_line
			(start 1.2954 0.5842)
			(end 1.2954 -0.5842)
			(stroke
				(width 0.1524)
				(type default)
			)
			(layer "B.SilkS")
		)
		(fp_line
			(start -1.2954 -0.5842)
			(end -1.2954 0.5842)
			(stroke
				(width 0.1524)
				(type default)
			)
			(layer "B.SilkS")
		)
		(fp_line
			(start 1.2954 -0.5842)
			(end -1.2954 -0.5842)
			(stroke
				(width 0.1524)
				(type default)
			)
			(layer "B.SilkS")
		)
		(fp_line
			(start -0.8636 0.4572)
			(end 0.8636 0.4572)
			(stroke
				(width 0.1)
				(type default)
			)
			(layer "B.Fab")
		)
		(fp_line
			(start 0.8636 0.4572)
			(end 0.8636 0.4064)
			(stroke
				(width 0.1)
				(type default)
			)
			(layer "B.Fab")
		)
		(fp_line
			(start -1.1938 0.4064)
			(end -0.8636 0.4064)
			(stroke
				(width 0.1)
				(type default)
			)
			(layer "B.Fab")
		)
		(fp_line
			(start -0.8636 0.4064)
			(end -0.8636 0.4572)
			(stroke
				(width 0.1)
				(type default)
			)
			(layer "B.Fab")
		)
		(fp_line
			(start 0.8636 0.4064)
			(end 1.1938 0.4064)
			(stroke
				(width 0.1)
				(type default)
			)
			(layer "B.Fab")
		)
		(fp_line
			(start 1.1938 0.4064)
			(end 1.1938 -0.4064)
			(stroke
				(width 0.1)
				(type default)
			)
			(layer "B.Fab")
		)
		(fp_line
			(start -1.1938 -0.4064)
			(end -1.1938 0.4064)
			(stroke
				(width 0.1)
				(type default)
			)
			(layer "B.Fab")
		)
		(fp_line
			(start -0.8636 -0.4064)
			(end -1.1938 -0.4064)
			(stroke
				(width 0.1)
				(type default)
			)
			(layer "B.Fab")
		)
		(fp_line
			(start 0.8636 -0.4064)
			(end 0.8636 -0.4572)
			(stroke
				(width 0.1)
				(type default)
			)
			(layer "B.Fab")
		)
		(fp_line
			(start 1.1938 -0.4064)
			(end 0.8636 -0.4064)
			(stroke
				(width 0.1)
				(type default)
			)
			(layer "B.Fab")
		)
		(fp_line
			(start -0.8636 -0.4572)
			(end -0.8636 -0.4064)
			(stroke
				(width 0.1)
				(type default)
			)
			(layer "B.Fab")
		)
		(fp_line
			(start 0.8636 -0.4572)
			(end -0.8636 -0.4572)
			(stroke
				(width 0.1)
				(type default)
			)
			(layer "B.Fab")
		)
		(pad "1" smd rect
			(at 0.7366 0 180)
			(size 0.7112 0.8128)
			(layers "B.Cu" "B.Mask" "B.Paste")
			(net "P0V8_SERDES_VDDA_PEX1_C0")
		)
		(pad "2" smd rect
			(at -0.7366 0 180)
			(size 0.7112 0.8128)
			(layers "B.Cu" "B.Mask" "B.Paste")
			(net "GND")
		)
	)
	(footprint ""
		(layer "B.Cu")
		(at 186.941714 -300.174914)
		(property "Reference" "C3187"
			(at 0 0 0)
			(layer "B.SilkS")
			(hide yes)
			(effects
				(font
					(size 1.27 1.27)
				)
				(justify mirror)
			)
		)
		(property "Value" ""
			(at 0 0 0)
			(layer "B.Fab")
			(effects
				(font
					(size 1.27 1.27)
				)
				(justify mirror)
			)
		)
		(duplicate_pad_numbers_are_jumpers no)
		(fp_line
			(start -0.299974 -0.150114)
			(end -0.299974 0.150114)
			(stroke
				(width 0.1)
				(type default)
			)
			(layer "B.Fab")
		)
		(fp_line
			(start -0.299974 0.150114)
			(end 0.299974 0.150114)
			(stroke
				(width 0.1)
				(type default)
			)
			(layer "B.Fab")
		)
		(fp_line
			(start 0.299974 -0.150114)
			(end -0.299974 -0.150114)
			(stroke
				(width 0.1)
				(type default)
			)
			(layer "B.Fab")
		)
		(fp_line
			(start 0.299974 0.150114)
			(end 0.299974 -0.150114)
			(stroke
				(width 0.1)
				(type default)
			)
			(layer "B.Fab")
		)
		(pad "1" smd rect
			(at 0.2667 0 180)
			(size 0.3048 0.381)
			(layers "B.Cu" "B.Mask" "B.Paste")
			(net "P1V8_VDDA_PEX1")
		)
		(pad "2" smd rect
			(at -0.2667 0 180)
			(size 0.3048 0.381)
			(layers "B.Cu" "B.Mask" "B.Paste")
			(net "GND")
		)
	)
	(footprint ""
		(layer "B.Cu")
		(at 410.324808 -297.79976 90)
		(property "Reference" "C1914"
			(at 0 0 90)
			(layer "B.SilkS")
			(hide yes)
			(effects
				(font
					(size 1.27 1.27)
				)
				(justify mirror)
			)
		)
		(property "Value" ""
			(at 0 0 90)
			(layer "B.Fab")
			(effects
				(font
					(size 1.27 1.27)
				)
				(justify mirror)
			)
		)
		(duplicate_pad_numbers_are_jumpers no)
		(fp_line
			(start 0.299974 -0.150114)
			(end -0.299974 -0.150114)
			(stroke
				(width 0.1)
				(type default)
			)
			(layer "B.Fab")
		)
		(fp_line
			(start -0.299974 -0.150114)
			(end -0.299974 0.150114)
			(stroke
				(width 0.1)
				(type default)
			)
			(layer "B.Fab")
		)
		(fp_line
			(start 0.299974 0.150114)
			(end 0.299974 -0.150114)
			(stroke
				(width 0.1)
				(type default)
			)
			(layer "B.Fab")
		)
		(fp_line
			(start -0.299974 0.150114)
			(end 0.299974 0.150114)
			(stroke
				(width 0.1)
				(type default)
			)
			(layer "B.Fab")
		)
		(pad "1" smd rect
			(at 0.2667 0 270)
			(size 0.3048 0.381)
			(layers "B.Cu" "B.Mask" "B.Paste")
			(net "P0V8_PEX3")
		)
		(pad "2" smd rect
			(at -0.2667 0 270)
			(size 0.3048 0.381)
			(layers "B.Cu" "B.Mask" "B.Paste")
			(net "GND")
		)
	)
	(footprint ""
		(layer "B.Cu")
		(at 296.124884 -286.399732 90)
		(property "Reference" "C3312"
			(at 0 0 90)
			(layer "B.SilkS")
			(hide yes)
			(effects
				(font
					(size 1.27 1.27)
				)
				(justify mirror)
			)
		)
		(property "Value" ""
			(at 0 0 90)
			(layer "B.Fab")
			(effects
				(font
					(size 1.27 1.27)
				)
				(justify mirror)
			)
		)
		(duplicate_pad_numbers_are_jumpers no)
		(fp_line
			(start 0.299974 -0.150114)
			(end -0.299974 -0.150114)
			(stroke
				(width 0.1)
				(type default)
			)
			(layer "B.Fab")
		)
		(fp_line
			(start -0.299974 -0.150114)
			(end -0.299974 0.150114)
			(stroke
				(width 0.1)
				(type default)
			)
			(layer "B.Fab")
		)
		(fp_line
			(start 0.299974 0.150114)
			(end 0.299974 -0.150114)
			(stroke
				(width 0.1)
				(type default)
			)
			(layer "B.Fab")
		)
		(fp_line
			(start -0.299974 0.150114)
			(end 0.299974 0.150114)
			(stroke
				(width 0.1)
				(type default)
			)
			(layer "B.Fab")
		)
		(pad "1" smd rect
			(at 0.2667 0 270)
			(size 0.3048 0.381)
			(layers "B.Cu" "B.Mask" "B.Paste")
			(net "P1V25_SERDES_VDDPLL_PEX2")
		)
		(pad "2" smd rect
			(at -0.2667 0 270)
			(size 0.3048 0.381)
			(layers "B.Cu" "B.Mask" "B.Paste")
			(net "GND")
		)
	)
	(footprint ""
		(layer "B.Cu")
		(at 236.262418 -278.898604 -90)
		(property "Reference" "C4346"
			(at 0 0 90)
			(layer "B.SilkS")
			(hide yes)
			(effects
				(font
					(size 1.27 1.27)
				)
				(justify mirror)
			)
		)
		(property "Value" ""
			(at 0 0 90)
			(layer "B.Fab")
			(effects
				(font
					(size 1.27 1.27)
				)
				(justify mirror)
			)
		)
		(duplicate_pad_numbers_are_jumpers no)
		(fp_line
			(start -1.2954 0.5842)
			(end 1.2954 0.5842)
			(stroke
				(width 0.1524)
				(type default)
			)
			(layer "B.SilkS")
		)
		(fp_line
			(start 1.2954 0.5842)
			(end 1.2954 -0.5842)
			(stroke
				(width 0.1524)
				(type default)
			)
			(layer "B.SilkS")
		)
		(fp_line
			(start -1.2954 -0.5842)
			(end -1.2954 0.5842)
			(stroke
				(width 0.1524)
				(type default)
			)
			(layer "B.SilkS")
		)
		(fp_line
			(start 1.2954 -0.5842)
			(end -1.2954 -0.5842)
			(stroke
				(width 0.1524)
				(type default)
			)
			(layer "B.SilkS")
		)
		(fp_line
			(start -0.8636 0.4572)
			(end 0.8636 0.4572)
			(stroke
				(width 0.1)
				(type default)
			)
			(layer "B.Fab")
		)
		(fp_line
			(start 0.8636 0.4572)
			(end 0.8636 0.4064)
			(stroke
				(width 0.1)
				(type default)
			)
			(layer "B.Fab")
		)
		(fp_line
			(start -1.1938 0.4064)
			(end -0.8636 0.4064)
			(stroke
				(width 0.1)
				(type default)
			)
			(layer "B.Fab")
		)
		(fp_line
			(start -0.8636 0.4064)
			(end -0.8636 0.4572)
			(stroke
				(width 0.1)
				(type default)
			)
			(layer "B.Fab")
		)
		(fp_line
			(start 0.8636 0.4064)
			(end 1.1938 0.4064)
			(stroke
				(width 0.1)
				(type default)
			)
			(layer "B.Fab")
		)
		(fp_line
			(start 1.1938 0.4064)
			(end 1.1938 -0.4064)
			(stroke
				(width 0.1)
				(type default)
			)
			(layer "B.Fab")
		)
		(fp_line
			(start -1.1938 -0.4064)
			(end -1.1938 0.4064)
			(stroke
				(width 0.1)
				(type default)
			)
			(layer "B.Fab")
		)
		(fp_line
			(start -0.8636 -0.4064)
			(end -1.1938 -0.4064)
			(stroke
				(width 0.1)
				(type default)
			)
			(layer "B.Fab")
		)
		(fp_line
			(start 0.8636 -0.4064)
			(end 0.8636 -0.4572)
			(stroke
				(width 0.1)
				(type default)
			)
			(layer "B.Fab")
		)
		(fp_line
			(start 1.1938 -0.4064)
			(end 0.8636 -0.4064)
			(stroke
				(width 0.1)
				(type default)
			)
			(layer "B.Fab")
		)
		(fp_line
			(start -0.8636 -0.4572)
			(end -0.8636 -0.4064)
			(stroke
				(width 0.1)
				(type default)
			)
			(layer "B.Fab")
		)
		(fp_line
			(start 0.8636 -0.4572)
			(end -0.8636 -0.4572)
			(stroke
				(width 0.1)
				(type default)
			)
			(layer "B.Fab")
		)
		(pad "1" smd rect
			(at 0.7366 0 180)
			(size 0.7112 0.8128)
			(layers "B.Cu" "B.Mask" "B.Paste")
			(net "P1V25_PEX2")
		)
		(pad "2" smd rect
			(at -0.7366 0 180)
			(size 0.7112 0.8128)
			(layers "B.Cu" "B.Mask" "B.Paste")
			(net "GND")
		)
	)
	(footprint ""
		(layer "B.Cu")
		(at 11.196066 -389.350504 90)
		(property "Reference" "C4474"
			(at 0 0 90)
			(layer "B.SilkS")
			(hide yes)
			(effects
				(font
					(size 1.27 1.27)
				)
				(justify mirror)
			)
		)
		(property "Value" ""
			(at 0 0 90)
			(layer "B.Fab")
			(effects
				(font
					(size 1.27 1.27)
				)
				(justify mirror)
			)
		)
		(duplicate_pad_numbers_are_jumpers no)
		(fp_line
			(start 1.524 -0.762)
			(end -1.524 -0.762)
			(stroke
				(width 0.1524)
				(type default)
			)
			(layer "B.SilkS")
		)
		(fp_line
			(start -1.524 -0.762)
			(end -1.524 0.762)
			(stroke
				(width 0.1524)
				(type default)
			)
			(layer "B.SilkS")
		)
		(fp_line
			(start 1.524 0.762)
			(end 1.524 -0.762)
			(stroke
				(width 0.1524)
				(type default)
			)
			(layer "B.SilkS")
		)
		(fp_line
			(start -1.524 0.762)
			(end 1.524 0.762)
			(stroke
				(width 0.1524)
				(type default)
			)
			(layer "B.SilkS")
		)
		(fp_line
			(start 1.1049 -0.724916)
			(end 1.1049 0.724916)
			(stroke
				(width 0.1)
				(type default)
			)
			(layer "B.Fab")
		)
		(fp_line
			(start -1.1049 -0.724916)
			(end 1.1049 -0.724916)
			(stroke
				(width 0.1)
				(type default)
			)
			(layer "B.Fab")
		)
		(fp_line
			(start 1.1049 0.724916)
			(end -1.1049 0.724916)
			(stroke
				(width 0.1)
				(type default)
			)
			(layer "B.Fab")
		)
		(fp_line
			(start -1.1049 0.724916)
			(end -1.1049 -0.724916)
			(stroke
				(width 0.1)
				(type default)
			)
			(layer "B.Fab")
		)
		(pad "1" smd rect
			(at 0.889 0 90)
			(size 1.016 1.27)
			(layers "B.Cu" "B.Mask" "B.Paste")
			(net "P1V2_USB_8042")
		)
		(pad "2" smd rect
			(at -0.889 0 90)
			(size 1.016 1.27)
			(layers "B.Cu" "B.Mask" "B.Paste")
			(net "GND")
		)
	)
	(footprint ""
		(layer "B.Cu")
		(at 103.748586 -344.563954 90)
		(property "Reference" "R6366"
			(at 0 0 90)
			(layer "B.SilkS")
			(hide yes)
			(effects
				(font
					(size 1.27 1.27)
				)
				(justify mirror)
			)
		)
		(property "Value" ""
			(at 0 0 90)
			(layer "B.Fab")
			(effects
				(font
					(size 1.27 1.27)
				)
				(justify mirror)
			)
		)
		(duplicate_pad_numbers_are_jumpers no)
		(fp_line
			(start 0.7874 -0.4064)
			(end -0.7874 -0.4064)
			(stroke
				(width 0.1524)
				(type default)
			)
			(layer "B.SilkS")
		)
		(fp_line
			(start -0.7874 -0.4064)
			(end -0.7874 0.4064)
			(stroke
				(width 0.1524)
				(type default)
			)
			(layer "B.SilkS")
		)
		(fp_line
			(start 0.7874 0.4064)
			(end 0.7874 -0.4064)
			(stroke
				(width 0.1524)
				(type default)
			)
			(layer "B.SilkS")
		)
		(fp_line
			(start -0.7874 0.4064)
			(end 0.7874 0.4064)
			(stroke
				(width 0.1524)
				(type default)
			)
			(layer "B.SilkS")
		)
		(fp_line
			(start 0.67945 -0.305054)
			(end 0.12065 -0.305054)
			(stroke
				(width 0.1)
				(type default)
			)
			(layer "B.Fab")
		)
		(fp_line
			(start 0.12065 -0.305054)
			(end 0.12065 -0.2794)
			(stroke
				(width 0.1)
				(type default)
			)
			(layer "B.Fab")
		)
		(fp_line
			(start -0.12065 -0.3048)
			(end -0.67945 -0.3048)
			(stroke
				(width 0.1)
				(type default)
			)
			(layer "B.Fab")
		)
		(fp_line
			(start -0.67945 -0.3048)
			(end -0.67945 0.3048)
			(stroke
				(width 0.1)
				(type default)
			)
			(layer "B.Fab")
		)
		(fp_line
			(start 0.12065 -0.2794)
			(end -0.12065 -0.2794)
			(stroke
				(width 0.1)
				(type default)
			)
			(layer "B.Fab")
		)
		(fp_line
			(start -0.12065 -0.2794)
			(end -0.12065 -0.3048)
			(stroke
				(width 0.1)
				(type default)
			)
			(layer "B.Fab")
		)
		(fp_line
			(start 0.12065 0.2794)
			(end 0.12065 0.3048)
			(stroke
				(width 0.1)
				(type default)
			)
			(layer "B.Fab")
		)
		(fp_line
			(start -0.120396 0.2794)
			(end 0.12065 0.2794)
			(stroke
				(width 0.1)
				(type default)
			)
			(layer "B.Fab")
		)
		(fp_line
			(start 0.67945 0.3048)
			(end 0.67945 -0.305054)
			(stroke
				(width 0.1)
				(type default)
			)
			(layer "B.Fab")
		)
		(fp_line
			(start 0.12065 0.3048)
			(end 0.67945 0.3048)
			(stroke
				(width 0.1)
				(type default)
			)
			(layer "B.Fab")
		)
		(fp_line
			(start -0.120396 0.3048)
			(end -0.120396 0.2794)
			(stroke
				(width 0.1)
				(type default)
			)
			(layer "B.Fab")
		)
		(fp_line
			(start -0.67945 0.3048)
			(end -0.120396 0.3048)
			(stroke
				(width 0.1)
				(type default)
			)
			(layer "B.Fab")
		)
		(pad "1" smd circle
			(at 0.40005 0 270)
			(size 0 0)
			(layers "B.Cu" "B.Mask" "B.Paste")
			(net "CLK_100M_MB_1_R_DP")
		)
		(pad "2" smd circle
			(at -0.40005 0 270)
			(size 0 0)
			(layers "B.Cu" "B.Mask" "B.Paste")
			(net "CLK_100M_MB_1_DP")
		)
	)
	(footprint ""
		(layer "B.Cu")
		(at 294.69969 -301.599854 -90)
		(property "Reference" "C1749"
			(at 0 0 90)
			(layer "B.SilkS")
			(hide yes)
			(effects
				(font
					(size 1.27 1.27)
				)
				(justify mirror)
			)
		)
		(property "Value" ""
			(at 0 0 90)
			(layer "B.Fab")
			(effects
				(font
					(size 1.27 1.27)
				)
				(justify mirror)
			)
		)
		(duplicate_pad_numbers_are_jumpers no)
		(fp_line
			(start -0.299974 0.150114)
			(end 0.299974 0.150114)
			(stroke
				(width 0.1)
				(type default)
			)
			(layer "B.Fab")
		)
		(fp_line
			(start 0.299974 0.150114)
			(end 0.299974 -0.150114)
			(stroke
				(width 0.1)
				(type default)
			)
			(layer "B.Fab")
		)
		(fp_line
			(start -0.299974 -0.150114)
			(end -0.299974 0.150114)
			(stroke
				(width 0.1)
				(type default)
			)
			(layer "B.Fab")
		)
		(fp_line
			(start 0.299974 -0.150114)
			(end -0.299974 -0.150114)
			(stroke
				(width 0.1)
				(type default)
			)
			(layer "B.Fab")
		)
		(pad "1" smd rect
			(at 0.2667 0 90)
			(size 0.3048 0.381)
			(layers "B.Cu" "B.Mask" "B.Paste")
			(net "P0V8_SERDES_VDDA_PEX2")
		)
		(pad "2" smd rect
			(at -0.2667 0 90)
			(size 0.3048 0.381)
			(layers "B.Cu" "B.Mask" "B.Paste")
			(net "GND")
		)
	)
	(footprint ""
		(layer "B.Cu")
		(at 337.16087 -284.796738 -90)
		(property "Reference" "PC159"
			(at 0 0 90)
			(layer "B.SilkS")
			(hide yes)
			(effects
				(font
					(size 1.27 1.27)
				)
				(justify mirror)
			)
		)
		(property "Value" ""
			(at 0 0 90)
			(layer "B.Fab")
			(effects
				(font
					(size 1.27 1.27)
				)
				(justify mirror)
			)
		)
		(duplicate_pad_numbers_are_jumpers no)
		(fp_line
			(start -1.524 0.762)
			(end 1.524 0.762)
			(stroke
				(width 0.1524)
				(type default)
			)
			(layer "B.SilkS")
		)
		(fp_line
			(start 1.524 0.762)
			(end 1.524 -0.762)
			(stroke
				(width 0.1524)
				(type default)
			)
			(layer "B.SilkS")
		)
		(fp_line
			(start -1.524 -0.762)
			(end -1.524 0.762)
			(stroke
				(width 0.1524)
				(type default)
			)
			(layer "B.SilkS")
		)
		(fp_line
			(start 1.524 -0.762)
			(end -1.524 -0.762)
			(stroke
				(width 0.1524)
				(type default)
			)
			(layer "B.SilkS")
		)
		(fp_line
			(start -1.1049 0.724916)
			(end -1.1049 -0.724916)
			(stroke
				(width 0.1)
				(type default)
			)
			(layer "B.Fab")
		)
		(fp_line
			(start 1.1049 0.724916)
			(end -1.1049 0.724916)
			(stroke
				(width 0.1)
				(type default)
			)
			(layer "B.Fab")
		)
		(fp_line
			(start -1.1049 -0.724916)
			(end 1.1049 -0.724916)
			(stroke
				(width 0.1)
				(type default)
			)
			(layer "B.Fab")
		)
		(fp_line
			(start 1.1049 -0.724916)
			(end 1.1049 0.724916)
			(stroke
				(width 0.1)
				(type default)
			)
			(layer "B.Fab")
		)
		(pad "1" smd rect
			(at 0.889 0 270)
			(size 1.016 1.27)
			(layers "B.Cu" "B.Mask" "B.Paste")
			(net "SW_P12V_P0V8_PEX2_FLT")
		)
		(pad "2" smd rect
			(at -0.889 0 270)
			(size 1.016 1.27)
			(layers "B.Cu" "B.Mask" "B.Paste")
			(net "GND")
		)
	)
	(footprint ""
		(layer "B.Cu")
		(at 307.916834 -295.42486)
		(property "Reference" "C3249"
			(at 0 0 0)
			(layer "B.SilkS")
			(hide yes)
			(effects
				(font
					(size 1.27 1.27)
				)
				(justify mirror)
			)
		)
		(property "Value" ""
			(at 0 0 0)
			(layer "B.Fab")
			(effects
				(font
					(size 1.27 1.27)
				)
				(justify mirror)
			)
		)
		(duplicate_pad_numbers_are_jumpers no)
		(fp_line
			(start -1.2954 -0.5842)
			(end -1.2954 0.5842)
			(stroke
				(width 0.1524)
				(type default)
			)
			(layer "B.SilkS")
		)
		(fp_line
			(start -1.2954 0.5842)
			(end 1.2954 0.5842)
			(stroke
				(width 0.1524)
				(type default)
			)
			(layer "B.SilkS")
		)
		(fp_line
			(start 1.2954 -0.5842)
			(end -1.2954 -0.5842)
			(stroke
				(width 0.1524)
				(type default)
			)
			(layer "B.SilkS")
		)
		(fp_line
			(start 1.2954 0.5842)
			(end 1.2954 -0.5842)
			(stroke
				(width 0.1524)
				(type default)
			)
			(layer "B.SilkS")
		)
		(fp_line
			(start -1.1938 -0.4064)
			(end -1.1938 0.4064)
			(stroke
				(width 0.1)
				(type default)
			)
			(layer "B.Fab")
		)
		(fp_line
			(start -1.1938 0.4064)
			(end -0.8636 0.4064)
			(stroke
				(width 0.1)
				(type default)
			)
			(layer "B.Fab")
		)
		(fp_line
			(start -0.8636 -0.4572)
			(end -0.8636 -0.4064)
			(stroke
				(width 0.1)
				(type default)
			)
			(layer "B.Fab")
		)
		(fp_line
			(start -0.8636 -0.4064)
			(end -1.1938 -0.4064)
			(stroke
				(width 0.1)
				(type default)
			)
			(layer "B.Fab")
		)
		(fp_line
			(start -0.8636 0.4064)
			(end -0.8636 0.4572)
			(stroke
				(width 0.1)
				(type default)
			)
			(layer "B.Fab")
		)
		(fp_line
			(start -0.8636 0.4572)
			(end 0.8636 0.4572)
			(stroke
				(width 0.1)
				(type default)
			)
			(layer "B.Fab")
		)
		(fp_line
			(start 0.8636 -0.4572)
			(end -0.8636 -0.4572)
			(stroke
				(width 0.1)
				(type default)
			)
			(layer "B.Fab")
		)
		(fp_line
			(start 0.8636 -0.4064)
			(end 0.8636 -0.4572)
			(stroke
				(width 0.1)
				(type default)
			)
			(layer "B.Fab")
		)
		(fp_line
			(start 0.8636 0.4064)
			(end 1.1938 0.4064)
			(stroke
				(width 0.1)
				(type default)
			)
			(layer "B.Fab")
		)
		(fp_line
			(start 0.8636 0.4572)
			(end 0.8636 0.4064)
			(stroke
				(width 0.1)
				(type default)
			)
			(layer "B.Fab")
		)
		(fp_line
			(start 1.1938 -0.4064)
			(end 0.8636 -0.4064)
			(stroke
				(width 0.1)
				(type default)
			)
			(layer "B.Fab")
		)
		(fp_line
			(start 1.1938 0.4064)
			(end 1.1938 -0.4064)
			(stroke
				(width 0.1)
				(type default)
			)
			(layer "B.Fab")
		)
		(pad "1" smd rect
			(at 0.7366 0 270)
			(size 0.7112 0.8128)
			(layers "B.Cu" "B.Mask" "B.Paste")
			(net "P1V25_PEX2")
		)
		(pad "2" smd rect
			(at -0.7366 0 270)
			(size 0.7112 0.8128)
			(layers "B.Cu" "B.Mask" "B.Paste")
			(net "GND")
		)
	)
	(footprint ""
		(layer "B.Cu")
		(at 162.226244 -139.8016 180)
		(property "Reference" "C885"
			(at 0 0 0)
			(layer "B.SilkS")
			(hide yes)
			(effects
				(font
					(size 1.27 1.27)
				)
				(justify mirror)
			)
		)
		(property "Value" ""
			(at 0 0 0)
			(layer "B.Fab")
			(effects
				(font
					(size 1.27 1.27)
				)
				(justify mirror)
			)
		)
		(duplicate_pad_numbers_are_jumpers no)
		(fp_line
			(start 0.7874 0.4064)
			(end 0.7874 -0.4064)
			(stroke
				(width 0.1524)
				(type default)
			)
			(layer "B.SilkS")
		)
		(fp_line
			(start 0.7874 -0.4064)
			(end -0.7874 -0.4064)
			(stroke
				(width 0.1524)
				(type default)
			)
			(layer "B.SilkS")
		)
		(fp_line
			(start -0.7874 0.4064)
			(end 0.7874 0.4064)
			(stroke
				(width 0.1524)
				(type default)
			)
			(layer "B.SilkS")
		)
		(fp_line
			(start -0.7874 -0.4064)
			(end -0.7874 0.4064)
			(stroke
				(width 0.1524)
				(type default)
			)
			(layer "B.SilkS")
		)
		(fp_line
			(start 0.67945 0.3048)
			(end 0.67945 -0.305054)
			(stroke
				(width 0.1)
				(type default)
			)
			(layer "B.Fab")
		)
		(fp_line
			(start 0.67945 -0.305054)
			(end 0.12065 -0.305054)
			(stroke
				(width 0.1)
				(type default)
			)
			(layer "B.Fab")
		)
		(fp_line
			(start 0.12065 0.3048)
			(end 0.67945 0.3048)
			(stroke
				(width 0.1)
				(type default)
			)
			(layer "B.Fab")
		)
		(fp_line
			(start 0.12065 0.2794)
			(end 0.12065 0.3048)
			(stroke
				(width 0.1)
				(type default)
			)
			(layer "B.Fab")
		)
		(fp_line
			(start 0.12065 -0.2794)
			(end -0.12065 -0.2794)
			(stroke
				(width 0.1)
				(type default)
			)
			(layer "B.Fab")
		)
		(fp_line
			(start 0.12065 -0.305054)
			(end 0.12065 -0.2794)
			(stroke
				(width 0.1)
				(type default)
			)
			(layer "B.Fab")
		)
		(fp_line
			(start -0.120396 0.3048)
			(end -0.120396 0.2794)
			(stroke
				(width 0.1)
				(type default)
			)
			(layer "B.Fab")
		)
		(fp_line
			(start -0.120396 0.2794)
			(end 0.12065 0.2794)
			(stroke
				(width 0.1)
				(type default)
			)
			(layer "B.Fab")
		)
		(fp_line
			(start -0.12065 -0.2794)
			(end -0.12065 -0.3048)
			(stroke
				(width 0.1)
				(type default)
			)
			(layer "B.Fab")
		)
		(fp_line
			(start -0.12065 -0.3048)
			(end -0.67945 -0.3048)
			(stroke
				(width 0.1)
				(type default)
			)
			(layer "B.Fab")
		)
		(fp_line
			(start -0.67945 0.3048)
			(end -0.120396 0.3048)
			(stroke
				(width 0.1)
				(type default)
			)
			(layer "B.Fab")
		)
		(fp_line
			(start -0.67945 -0.3048)
			(end -0.67945 0.3048)
			(stroke
				(width 0.1)
				(type default)
			)
			(layer "B.Fab")
		)
		(pad "1" smd circle
			(at 0.40005 0)
			(size 0 0)
			(layers "B.Cu" "B.Mask" "B.Paste")
			(net "P3V3_NIC2")
		)
		(pad "2" smd circle
			(at -0.40005 0)
			(size 0 0)
			(layers "B.Cu" "B.Mask" "B.Paste")
			(net "GND")
		)
	)
	(footprint ""
		(layer "B.Cu")
		(at 64.399922 -292.099746 90)
		(property "Reference" "C1209"
			(at 0 0 90)
			(layer "B.SilkS")
			(hide yes)
			(effects
				(font
					(size 1.27 1.27)
				)
				(justify mirror)
			)
		)
		(property "Value" ""
			(at 0 0 90)
			(layer "B.Fab")
			(effects
				(font
					(size 1.27 1.27)
				)
				(justify mirror)
			)
		)
		(duplicate_pad_numbers_are_jumpers no)
		(fp_line
			(start 0.299974 -0.150114)
			(end -0.299974 -0.150114)
			(stroke
				(width 0.1)
				(type default)
			)
			(layer "B.Fab")
		)
		(fp_line
			(start -0.299974 -0.150114)
			(end -0.299974 0.150114)
			(stroke
				(width 0.1)
				(type default)
			)
			(layer "B.Fab")
		)
		(fp_line
			(start 0.299974 0.150114)
			(end 0.299974 -0.150114)
			(stroke
				(width 0.1)
				(type default)
			)
			(layer "B.Fab")
		)
		(fp_line
			(start -0.299974 0.150114)
			(end 0.299974 0.150114)
			(stroke
				(width 0.1)
				(type default)
			)
			(layer "B.Fab")
		)
		(pad "1" smd rect
			(at 0.2667 0 270)
			(size 0.3048 0.381)
			(layers "B.Cu" "B.Mask" "B.Paste")
			(net "P0V8_SERDES_VDDA_PEX0")
		)
		(pad "2" smd rect
			(at -0.2667 0 270)
			(size 0.3048 0.381)
			(layers "B.Cu" "B.Mask" "B.Paste")
			(net "GND")
		)
	)
	(footprint ""
		(layer "B.Cu")
		(at 178.124866 -297.79976 90)
		(property "Reference" "C1410"
			(at 0 0 90)
			(layer "B.SilkS")
			(hide yes)
			(effects
				(font
					(size 1.27 1.27)
				)
				(justify mirror)
			)
		)
		(property "Value" ""
			(at 0 0 90)
			(layer "B.Fab")
			(effects
				(font
					(size 1.27 1.27)
				)
				(justify mirror)
			)
		)
		(duplicate_pad_numbers_are_jumpers no)
		(fp_line
			(start 0.299974 -0.150114)
			(end -0.299974 -0.150114)
			(stroke
				(width 0.1)
				(type default)
			)
			(layer "B.Fab")
		)
		(fp_line
			(start -0.299974 -0.150114)
			(end -0.299974 0.150114)
			(stroke
				(width 0.1)
				(type default)
			)
			(layer "B.Fab")
		)
		(fp_line
			(start 0.299974 0.150114)
			(end 0.299974 -0.150114)
			(stroke
				(width 0.1)
				(type default)
			)
			(layer "B.Fab")
		)
		(fp_line
			(start -0.299974 0.150114)
			(end 0.299974 0.150114)
			(stroke
				(width 0.1)
				(type default)
			)
			(layer "B.Fab")
		)
		(pad "1" smd rect
			(at 0.2667 0 270)
			(size 0.3048 0.381)
			(layers "B.Cu" "B.Mask" "B.Paste")
			(net "P0V8_PEX1")
		)
		(pad "2" smd rect
			(at -0.2667 0 270)
			(size 0.3048 0.381)
			(layers "B.Cu" "B.Mask" "B.Paste")
			(net "GND")
		)
	)
	(footprint ""
		(layer "B.Cu")
		(at 331.305154 -216.203022)
		(property "Reference" "C2077"
			(at 0 0 0)
			(layer "B.SilkS")
			(hide yes)
			(effects
				(font
					(size 1.27 1.27)
				)
				(justify mirror)
			)
		)
		(property "Value" ""
			(at 0 0 0)
			(layer "B.Fab")
			(effects
				(font
					(size 1.27 1.27)
				)
				(justify mirror)
			)
		)
		(duplicate_pad_numbers_are_jumpers no)
		(fp_line
			(start -0.69215 -0.2921)
			(end -0.69215 0.2921)
			(stroke
				(width 0.1524)
				(type default)
			)
			(layer "B.SilkS")
		)
		(fp_line
			(start -0.69215 0.2921)
			(end 0.69215 0.2921)
			(stroke
				(width 0.1524)
				(type default)
			)
			(layer "B.SilkS")
		)
		(fp_line
			(start 0.69215 -0.2921)
			(end -0.69215 -0.2921)
			(stroke
				(width 0.1524)
				(type default)
			)
			(layer "B.SilkS")
		)
		(fp_line
			(start 0.69215 0.2921)
			(end 0.69215 -0.2921)
			(stroke
				(width 0.1524)
				(type default)
			)
			(layer "B.SilkS")
		)
		(fp_line
			(start -0.51435 -0.2794)
			(end -0.51435 0.2794)
			(stroke
				(width 0.1)
				(type default)
			)
			(layer "B.Fab")
		)
		(fp_line
			(start -0.51435 0.2794)
			(end 0.51435 0.2794)
			(stroke
				(width 0.1)
				(type default)
			)
			(layer "B.Fab")
		)
		(fp_line
			(start 0.51435 -0.2794)
			(end -0.51435 -0.2794)
			(stroke
				(width 0.1)
				(type default)
			)
			(layer "B.Fab")
		)
		(fp_line
			(start 0.51435 0.2794)
			(end 0.51435 -0.2794)
			(stroke
				(width 0.1)
				(type default)
			)
			(layer "B.Fab")
		)
		(pad "1" smd circle
			(at 0.40005 0 180)
			(size 0 0)
			(layers "B.Cu" "B.Mask" "B.Paste")
			(net "P3V3_FPGA_VCCIO3")
		)
		(pad "2" smd circle
			(at -0.40005 0 180)
			(size 0 0)
			(layers "B.Cu" "B.Mask" "B.Paste")
			(net "GND")
		)
		(zone
			(layer "B.Cu")
			(hatch none 0.5)
			(connect_pads
				(clearance 0)
			)
			(min_thickness 0.25)
			(keepout
				(tracks not_allowed)
				(vias allowed)
				(pads allowed)
				(copperpour not_allowed)
				(footprints allowed)
			)
			(placement
				(enabled no)
				(sheetname "")
			)
			(fill
				(thermal_gap 0.5)
				(thermal_bridge_width 0.5)
				(island_removal_mode 0)
			)
			(polygon
				(pts
					(xy 331.495654 -216.115392) (xy 331.404214 -216.057226) (xy 331.204824 -216.057226) (xy 331.114654 -216.115392)
					(xy 331.114654 -216.290652) (xy 331.204824 -216.349072) (xy 331.404214 -216.349072) (xy 331.495654 -216.290906)
				)
			)
		)
	)
	(footprint ""
		(layer "B.Cu")
		(at 114.41938 -308.580028 90)
		(property "Reference" "C1158"
			(at 0 0 90)
			(layer "B.SilkS")
			(hide yes)
			(effects
				(font
					(size 1.27 1.27)
				)
				(justify mirror)
			)
		)
		(property "Value" ""
			(at 0 0 90)
			(layer "B.Fab")
			(effects
				(font
					(size 1.27 1.27)
				)
				(justify mirror)
			)
		)
		(duplicate_pad_numbers_are_jumpers no)
		(fp_line
			(start 1.2954 -0.5842)
			(end -1.2954 -0.5842)
			(stroke
				(width 0.1524)
				(type default)
			)
			(layer "B.SilkS")
		)
		(fp_line
			(start -1.2954 -0.5842)
			(end -1.2954 0.5842)
			(stroke
				(width 0.1524)
				(type default)
			)
			(layer "B.SilkS")
		)
		(fp_line
			(start 1.2954 0.5842)
			(end 1.2954 -0.5842)
			(stroke
				(width 0.1524)
				(type default)
			)
			(layer "B.SilkS")
		)
		(fp_line
			(start -1.2954 0.5842)
			(end 1.2954 0.5842)
			(stroke
				(width 0.1524)
				(type default)
			)
			(layer "B.SilkS")
		)
		(fp_line
			(start 0.8636 -0.4572)
			(end -0.8636 -0.4572)
			(stroke
				(width 0.1)
				(type default)
			)
			(layer "B.Fab")
		)
		(fp_line
			(start -0.8636 -0.4572)
			(end -0.8636 -0.4064)
			(stroke
				(width 0.1)
				(type default)
			)
			(layer "B.Fab")
		)
		(fp_line
			(start 1.1938 -0.4064)
			(end 0.8636 -0.4064)
			(stroke
				(width 0.1)
				(type default)
			)
			(layer "B.Fab")
		)
		(fp_line
			(start 0.8636 -0.4064)
			(end 0.8636 -0.4572)
			(stroke
				(width 0.1)
				(type default)
			)
			(layer "B.Fab")
		)
		(fp_line
			(start -0.8636 -0.4064)
			(end -1.1938 -0.4064)
			(stroke
				(width 0.1)
				(type default)
			)
			(layer "B.Fab")
		)
		(fp_line
			(start -1.1938 -0.4064)
			(end -1.1938 0.4064)
			(stroke
				(width 0.1)
				(type default)
			)
			(layer "B.Fab")
		)
		(fp_line
			(start 1.1938 0.4064)
			(end 1.1938 -0.4064)
			(stroke
				(width 0.1)
				(type default)
			)
			(layer "B.Fab")
		)
		(fp_line
			(start 0.8636 0.4064)
			(end 1.1938 0.4064)
			(stroke
				(width 0.1)
				(type default)
			)
			(layer "B.Fab")
		)
		(fp_line
			(start -0.8636 0.4064)
			(end -0.8636 0.4572)
			(stroke
				(width 0.1)
				(type default)
			)
			(layer "B.Fab")
		)
		(fp_line
			(start -1.1938 0.4064)
			(end -0.8636 0.4064)
			(stroke
				(width 0.1)
				(type default)
			)
			(layer "B.Fab")
		)
		(fp_line
			(start 0.8636 0.4572)
			(end 0.8636 0.4064)
			(stroke
				(width 0.1)
				(type default)
			)
			(layer "B.Fab")
		)
		(fp_line
			(start -0.8636 0.4572)
			(end 0.8636 0.4572)
			(stroke
				(width 0.1)
				(type default)
			)
			(layer "B.Fab")
		)
		(pad "1" smd rect
			(at 0.7366 0)
			(size 0.7112 0.8128)
			(layers "B.Cu" "B.Mask" "B.Paste")
			(net "P0V8_SERDES_VDDA_PEX0")
		)
		(pad "2" smd rect
			(at -0.7366 0)
			(size 0.7112 0.8128)
			(layers "B.Cu" "B.Mask" "B.Paste")
			(net "GND")
		)
	)
	(footprint ""
		(layer "B.Cu")
		(at 113.514124 -329.44943 180)
		(property "Reference" "R1221"
			(at 0 0 0)
			(layer "B.SilkS")
			(hide yes)
			(effects
				(font
					(size 1.27 1.27)
				)
				(justify mirror)
			)
		)
		(property "Value" ""
			(at 0 0 0)
			(layer "B.Fab")
			(effects
				(font
					(size 1.27 1.27)
				)
				(justify mirror)
			)
		)
		(duplicate_pad_numbers_are_jumpers no)
		(fp_line
			(start 0.7874 0.4064)
			(end 0.7874 -0.4064)
			(stroke
				(width 0.1524)
				(type default)
			)
			(layer "B.SilkS")
		)
		(fp_line
			(start 0.7874 -0.4064)
			(end -0.7874 -0.4064)
			(stroke
				(width 0.1524)
				(type default)
			)
			(layer "B.SilkS")
		)
		(fp_line
			(start -0.7874 0.4064)
			(end 0.7874 0.4064)
			(stroke
				(width 0.1524)
				(type default)
			)
			(layer "B.SilkS")
		)
		(fp_line
			(start -0.7874 -0.4064)
			(end -0.7874 0.4064)
			(stroke
				(width 0.1524)
				(type default)
			)
			(layer "B.SilkS")
		)
		(fp_line
			(start 0.67945 0.3048)
			(end 0.67945 -0.305054)
			(stroke
				(width 0.1)
				(type default)
			)
			(layer "B.Fab")
		)
		(fp_line
			(start 0.67945 -0.305054)
			(end 0.12065 -0.305054)
			(stroke
				(width 0.1)
				(type default)
			)
			(layer "B.Fab")
		)
		(fp_line
			(start 0.12065 0.3048)
			(end 0.67945 0.3048)
			(stroke
				(width 0.1)
				(type default)
			)
			(layer "B.Fab")
		)
		(fp_line
			(start 0.12065 0.2794)
			(end 0.12065 0.3048)
			(stroke
				(width 0.1)
				(type default)
			)
			(layer "B.Fab")
		)
		(fp_line
			(start 0.12065 -0.2794)
			(end -0.12065 -0.2794)
			(stroke
				(width 0.1)
				(type default)
			)
			(layer "B.Fab")
		)
		(fp_line
			(start 0.12065 -0.305054)
			(end 0.12065 -0.2794)
			(stroke
				(width 0.1)
				(type default)
			)
			(layer "B.Fab")
		)
		(fp_line
			(start -0.120396 0.3048)
			(end -0.120396 0.2794)
			(stroke
				(width 0.1)
				(type default)
			)
			(layer "B.Fab")
		)
		(fp_line
			(start -0.120396 0.2794)
			(end 0.12065 0.2794)
			(stroke
				(width 0.1)
				(type default)
			)
			(layer "B.Fab")
		)
		(fp_line
			(start -0.12065 -0.2794)
			(end -0.12065 -0.3048)
			(stroke
				(width 0.1)
				(type default)
			)
			(layer "B.Fab")
		)
		(fp_line
			(start -0.12065 -0.3048)
			(end -0.67945 -0.3048)
			(stroke
				(width 0.1)
				(type default)
			)
			(layer "B.Fab")
		)
		(fp_line
			(start -0.67945 0.3048)
			(end -0.120396 0.3048)
			(stroke
				(width 0.1)
				(type default)
			)
			(layer "B.Fab")
		)
		(fp_line
			(start -0.67945 -0.3048)
			(end -0.67945 0.3048)
			(stroke
				(width 0.1)
				(type default)
			)
			(layer "B.Fab")
		)
		(pad "1" smd circle
			(at 0.40005 0)
			(size 0 0)
			(layers "B.Cu" "B.Mask" "B.Paste")
			(net "SMB_9ZXL0451E_ADDR0")
		)
		(pad "2" smd circle
			(at -0.40005 0)
			(size 0 0)
			(layers "B.Cu" "B.Mask" "B.Paste")
			(net "P3V3")
		)
	)
	(footprint ""
		(layer "B.Cu")
		(at 222.212154 -192.959736 -90)
		(property "Reference" "R1027"
			(at 0 0 90)
			(layer "B.SilkS")
			(hide yes)
			(effects
				(font
					(size 1.27 1.27)
				)
				(justify mirror)
			)
		)
		(property "Value" ""
			(at 0 0 90)
			(layer "B.Fab")
			(effects
				(font
					(size 1.27 1.27)
				)
				(justify mirror)
			)
		)
		(duplicate_pad_numbers_are_jumpers no)
		(fp_line
			(start -0.7874 0.4064)
			(end 0.7874 0.4064)
			(stroke
				(width 0.1524)
				(type default)
			)
			(layer "B.SilkS")
		)
		(fp_line
			(start 0.7874 0.4064)
			(end 0.7874 -0.4064)
			(stroke
				(width 0.1524)
				(type default)
			)
			(layer "B.SilkS")
		)
		(fp_line
			(start -0.7874 -0.4064)
			(end -0.7874 0.4064)
			(stroke
				(width 0.1524)
				(type default)
			)
			(layer "B.SilkS")
		)
		(fp_line
			(start 0.7874 -0.4064)
			(end -0.7874 -0.4064)
			(stroke
				(width 0.1524)
				(type default)
			)
			(layer "B.SilkS")
		)
		(fp_line
			(start -0.67945 0.3048)
			(end -0.120396 0.3048)
			(stroke
				(width 0.1)
				(type default)
			)
			(layer "B.Fab")
		)
		(fp_line
			(start -0.120396 0.3048)
			(end -0.120396 0.2794)
			(stroke
				(width 0.1)
				(type default)
			)
			(layer "B.Fab")
		)
		(fp_line
			(start 0.12065 0.3048)
			(end 0.67945 0.3048)
			(stroke
				(width 0.1)
				(type default)
			)
			(layer "B.Fab")
		)
		(fp_line
			(start 0.67945 0.3048)
			(end 0.67945 -0.305054)
			(stroke
				(width 0.1)
				(type default)
			)
			(layer "B.Fab")
		)
		(fp_line
			(start -0.120396 0.2794)
			(end 0.12065 0.2794)
			(stroke
				(width 0.1)
				(type default)
			)
			(layer "B.Fab")
		)
		(fp_line
			(start 0.12065 0.2794)
			(end 0.12065 0.3048)
			(stroke
				(width 0.1)
				(type default)
			)
			(layer "B.Fab")
		)
		(fp_line
			(start -0.12065 -0.2794)
			(end -0.12065 -0.3048)
			(stroke
				(width 0.1)
				(type default)
			)
			(layer "B.Fab")
		)
		(fp_line
			(start 0.12065 -0.2794)
			(end -0.12065 -0.2794)
			(stroke
				(width 0.1)
				(type default)
			)
			(layer "B.Fab")
		)
		(fp_line
			(start -0.67945 -0.3048)
			(end -0.67945 0.3048)
			(stroke
				(width 0.1)
				(type default)
			)
			(layer "B.Fab")
		)
		(fp_line
			(start -0.12065 -0.3048)
			(end -0.67945 -0.3048)
			(stroke
				(width 0.1)
				(type default)
			)
			(layer "B.Fab")
		)
		(fp_line
			(start 0.12065 -0.305054)
			(end 0.12065 -0.2794)
			(stroke
				(width 0.1)
				(type default)
			)
			(layer "B.Fab")
		)
		(fp_line
			(start 0.67945 -0.305054)
			(end 0.12065 -0.305054)
			(stroke
				(width 0.1)
				(type default)
			)
			(layer "B.Fab")
		)
		(pad "1" smd circle
			(at 0.40005 0 90)
			(size 0 0)
			(layers "B.Cu" "B.Mask" "B.Paste")
			(net "SPI2_DO_BUF")
		)
		(pad "2" smd circle
			(at -0.40005 0 90)
			(size 0 0)
			(layers "B.Cu" "B.Mask" "B.Paste")
			(net "SPI_BIC1_MOSI_R2")
		)
	)
	(footprint ""
		(layer "B.Cu")
		(at 351.547684 -304.157634 180)
		(property "Reference" "PR130"
			(at 0 0 0)
			(layer "B.SilkS")
			(hide yes)
			(effects
				(font
					(size 1.27 1.27)
				)
				(justify mirror)
			)
		)
		(property "Value" ""
			(at 0 0 0)
			(layer "B.Fab")
			(effects
				(font
					(size 1.27 1.27)
				)
				(justify mirror)
			)
		)
		(duplicate_pad_numbers_are_jumpers no)
		(fp_line
			(start 0.7874 0.4064)
			(end 0.7874 -0.4064)
			(stroke
				(width 0.1524)
				(type default)
			)
			(layer "B.SilkS")
		)
		(fp_line
			(start 0.7874 -0.4064)
			(end -0.7874 -0.4064)
			(stroke
				(width 0.1524)
				(type default)
			)
			(layer "B.SilkS")
		)
		(fp_line
			(start -0.7874 0.4064)
			(end 0.7874 0.4064)
			(stroke
				(width 0.1524)
				(type default)
			)
			(layer "B.SilkS")
		)
		(fp_line
			(start -0.7874 -0.4064)
			(end -0.7874 0.4064)
			(stroke
				(width 0.1524)
				(type default)
			)
			(layer "B.SilkS")
		)
		(fp_line
			(start 0.67945 0.3048)
			(end 0.67945 -0.305054)
			(stroke
				(width 0.1)
				(type default)
			)
			(layer "B.Fab")
		)
		(fp_line
			(start 0.67945 -0.305054)
			(end 0.12065 -0.305054)
			(stroke
				(width 0.1)
				(type default)
			)
			(layer "B.Fab")
		)
		(fp_line
			(start 0.12065 0.3048)
			(end 0.67945 0.3048)
			(stroke
				(width 0.1)
				(type default)
			)
			(layer "B.Fab")
		)
		(fp_line
			(start 0.12065 0.2794)
			(end 0.12065 0.3048)
			(stroke
				(width 0.1)
				(type default)
			)
			(layer "B.Fab")
		)
		(fp_line
			(start 0.12065 -0.2794)
			(end -0.12065 -0.2794)
			(stroke
				(width 0.1)
				(type default)
			)
			(layer "B.Fab")
		)
		(fp_line
			(start 0.12065 -0.305054)
			(end 0.12065 -0.2794)
			(stroke
				(width 0.1)
				(type default)
			)
			(layer "B.Fab")
		)
		(fp_line
			(start -0.120396 0.3048)
			(end -0.120396 0.2794)
			(stroke
				(width 0.1)
				(type default)
			)
			(layer "B.Fab")
		)
		(fp_line
			(start -0.120396 0.2794)
			(end 0.12065 0.2794)
			(stroke
				(width 0.1)
				(type default)
			)
			(layer "B.Fab")
		)
		(fp_line
			(start -0.12065 -0.2794)
			(end -0.12065 -0.3048)
			(stroke
				(width 0.1)
				(type default)
			)
			(layer "B.Fab")
		)
		(fp_line
			(start -0.12065 -0.3048)
			(end -0.67945 -0.3048)
			(stroke
				(width 0.1)
				(type default)
			)
			(layer "B.Fab")
		)
		(fp_line
			(start -0.67945 0.3048)
			(end -0.120396 0.3048)
			(stroke
				(width 0.1)
				(type default)
			)
			(layer "B.Fab")
		)
		(fp_line
			(start -0.67945 -0.3048)
			(end -0.67945 0.3048)
			(stroke
				(width 0.1)
				(type default)
			)
			(layer "B.Fab")
		)
		(pad "1" smd circle
			(at 0.40005 0)
			(size 0 0)
			(layers "B.Cu" "B.Mask" "B.Paste")
			(net "SH_P0V8_PEX3_RGND3")
		)
		(pad "2" smd circle
			(at -0.40005 0)
			(size 0 0)
			(layers "B.Cu" "B.Mask" "B.Paste")
			(net "GND")
		)
	)
	(footprint ""
		(layer "B.Cu")
		(at 180.02504 -286.399732 90)
		(property "Reference" "C3159"
			(at 0 0 90)
			(layer "B.SilkS")
			(hide yes)
			(effects
				(font
					(size 1.27 1.27)
				)
				(justify mirror)
			)
		)
		(property "Value" ""
			(at 0 0 90)
			(layer "B.Fab")
			(effects
				(font
					(size 1.27 1.27)
				)
				(justify mirror)
			)
		)
		(duplicate_pad_numbers_are_jumpers no)
		(fp_line
			(start 0.299974 -0.150114)
			(end -0.299974 -0.150114)
			(stroke
				(width 0.1)
				(type default)
			)
			(layer "B.Fab")
		)
		(fp_line
			(start -0.299974 -0.150114)
			(end -0.299974 0.150114)
			(stroke
				(width 0.1)
				(type default)
			)
			(layer "B.Fab")
		)
		(fp_line
			(start 0.299974 0.150114)
			(end 0.299974 -0.150114)
			(stroke
				(width 0.1)
				(type default)
			)
			(layer "B.Fab")
		)
		(fp_line
			(start -0.299974 0.150114)
			(end 0.299974 0.150114)
			(stroke
				(width 0.1)
				(type default)
			)
			(layer "B.Fab")
		)
		(pad "1" smd rect
			(at 0.2667 0 270)
			(size 0.3048 0.381)
			(layers "B.Cu" "B.Mask" "B.Paste")
			(net "P1V25_SERDES_VDDPLL_PEX1")
		)
		(pad "2" smd rect
			(at -0.2667 0 270)
			(size 0.3048 0.381)
			(layers "B.Cu" "B.Mask" "B.Paste")
			(net "GND")
		)
	)
	(footprint ""
		(layer "B.Cu")
		(at 392.749786 -292.099746)
		(property "Reference" "C3525"
			(at 0 0 0)
			(layer "B.SilkS")
			(hide yes)
			(effects
				(font
					(size 1.27 1.27)
				)
				(justify mirror)
			)
		)
		(property "Value" ""
			(at 0 0 0)
			(layer "B.Fab")
			(effects
				(font
					(size 1.27 1.27)
				)
				(justify mirror)
			)
		)
		(duplicate_pad_numbers_are_jumpers no)
		(fp_line
			(start -0.299974 -0.150114)
			(end -0.299974 0.150114)
			(stroke
				(width 0.1)
				(type default)
			)
			(layer "B.Fab")
		)
		(fp_line
			(start -0.299974 0.150114)
			(end 0.299974 0.150114)
			(stroke
				(width 0.1)
				(type default)
			)
			(layer "B.Fab")
		)
		(fp_line
			(start 0.299974 -0.150114)
			(end -0.299974 -0.150114)
			(stroke
				(width 0.1)
				(type default)
			)
			(layer "B.Fab")
		)
		(fp_line
			(start 0.299974 0.150114)
			(end 0.299974 -0.150114)
			(stroke
				(width 0.1)
				(type default)
			)
			(layer "B.Fab")
		)
		(pad "1" smd rect
			(at 0.2667 0 180)
			(size 0.3048 0.381)
			(layers "B.Cu" "B.Mask" "B.Paste")
			(net "P1V8_PEX")
		)
		(pad "2" smd rect
			(at -0.2667 0 180)
			(size 0.3048 0.381)
			(layers "B.Cu" "B.Mask" "B.Paste")
			(net "GND")
		)
	)
	(footprint ""
		(layer "B.Cu")
		(at 181.44998 -299.699934 -90)
		(property "Reference" "C1440"
			(at 0 0 90)
			(layer "B.SilkS")
			(hide yes)
			(effects
				(font
					(size 1.27 1.27)
				)
				(justify mirror)
			)
		)
		(property "Value" ""
			(at 0 0 90)
			(layer "B.Fab")
			(effects
				(font
					(size 1.27 1.27)
				)
				(justify mirror)
			)
		)
		(duplicate_pad_numbers_are_jumpers no)
		(fp_line
			(start -0.299974 0.150114)
			(end 0.299974 0.150114)
			(stroke
				(width 0.1)
				(type default)
			)
			(layer "B.Fab")
		)
		(fp_line
			(start 0.299974 0.150114)
			(end 0.299974 -0.150114)
			(stroke
				(width 0.1)
				(type default)
			)
			(layer "B.Fab")
		)
		(fp_line
			(start -0.299974 -0.150114)
			(end -0.299974 0.150114)
			(stroke
				(width 0.1)
				(type default)
			)
			(layer "B.Fab")
		)
		(fp_line
			(start 0.299974 -0.150114)
			(end -0.299974 -0.150114)
			(stroke
				(width 0.1)
				(type default)
			)
			(layer "B.Fab")
		)
		(pad "1" smd rect
			(at 0.2667 0 90)
			(size 0.3048 0.381)
			(layers "B.Cu" "B.Mask" "B.Paste")
			(net "P0V8_SERDES_VDDA_PEX1")
		)
		(pad "2" smd rect
			(at -0.2667 0 90)
			(size 0.3048 0.381)
			(layers "B.Cu" "B.Mask" "B.Paste")
			(net "GND")
		)
	)
	(footprint ""
		(layer "B.Cu")
		(at 460.169006 -286.661606 180)
		(property "Reference" "PC273"
			(at 0 0 0)
			(layer "B.SilkS")
			(hide yes)
			(effects
				(font
					(size 1.27 1.27)
				)
				(justify mirror)
			)
		)
		(property "Value" ""
			(at 0 0 0)
			(layer "B.Fab")
			(effects
				(font
					(size 1.27 1.27)
				)
				(justify mirror)
			)
		)
		(duplicate_pad_numbers_are_jumpers no)
		(fp_line
			(start 1.524 0.762)
			(end 1.524 -0.762)
			(stroke
				(width 0.1524)
				(type default)
			)
			(layer "B.SilkS")
		)
		(fp_line
			(start 1.524 -0.762)
			(end -1.524 -0.762)
			(stroke
				(width 0.1524)
				(type default)
			)
			(layer "B.SilkS")
		)
		(fp_line
			(start -1.524 0.762)
			(end 1.524 0.762)
			(stroke
				(width 0.1524)
				(type default)
			)
			(layer "B.SilkS")
		)
		(fp_line
			(start -1.524 -0.762)
			(end -1.524 0.762)
			(stroke
				(width 0.1524)
				(type default)
			)
			(layer "B.SilkS")
		)
		(fp_line
			(start 1.1049 0.724916)
			(end -1.1049 0.724916)
			(stroke
				(width 0.1)
				(type default)
			)
			(layer "B.Fab")
		)
		(fp_line
			(start 1.1049 -0.724916)
			(end 1.1049 0.724916)
			(stroke
				(width 0.1)
				(type default)
			)
			(layer "B.Fab")
		)
		(fp_line
			(start -1.1049 0.724916)
			(end -1.1049 -0.724916)
			(stroke
				(width 0.1)
				(type default)
			)
			(layer "B.Fab")
		)
		(fp_line
			(start -1.1049 -0.724916)
			(end 1.1049 -0.724916)
			(stroke
				(width 0.1)
				(type default)
			)
			(layer "B.Fab")
		)
		(pad "1" smd rect
			(at 0.889 0 180)
			(size 1.016 1.27)
			(layers "B.Cu" "B.Mask" "B.Paste")
			(net "P1V25_PEX3_R")
		)
		(pad "2" smd rect
			(at -0.889 0 180)
			(size 1.016 1.27)
			(layers "B.Cu" "B.Mask" "B.Paste")
			(net "GND")
		)
	)
	(footprint ""
		(layer "B.Cu")
		(at 58.240168 -297.79976 -90)
		(property "Reference" "C1133"
			(at 0 0 90)
			(layer "B.SilkS")
			(hide yes)
			(effects
				(font
					(size 1.27 1.27)
				)
				(justify mirror)
			)
		)
		(property "Value" ""
			(at 0 0 90)
			(layer "B.Fab")
			(effects
				(font
					(size 1.27 1.27)
				)
				(justify mirror)
			)
		)
		(duplicate_pad_numbers_are_jumpers no)
		(fp_line
			(start -0.299974 0.150114)
			(end 0.299974 0.150114)
			(stroke
				(width 0.1)
				(type default)
			)
			(layer "B.Fab")
		)
		(fp_line
			(start 0.299974 0.150114)
			(end 0.299974 -0.150114)
			(stroke
				(width 0.1)
				(type default)
			)
			(layer "B.Fab")
		)
		(fp_line
			(start -0.299974 -0.150114)
			(end -0.299974 0.150114)
			(stroke
				(width 0.1)
				(type default)
			)
			(layer "B.Fab")
		)
		(fp_line
			(start 0.299974 -0.150114)
			(end -0.299974 -0.150114)
			(stroke
				(width 0.1)
				(type default)
			)
			(layer "B.Fab")
		)
		(pad "1" smd rect
			(at 0.2667 0 90)
			(size 0.3048 0.381)
			(layers "B.Cu" "B.Mask" "B.Paste")
			(net "P0V8_PEX0")
		)
		(pad "2" smd rect
			(at -0.2667 0 90)
			(size 0.3048 0.381)
			(layers "B.Cu" "B.Mask" "B.Paste")
			(net "GND")
		)
	)
	(footprint ""
		(layer "B.Cu")
		(at 169.574972 -297.79976 90)
		(property "Reference" "C1379"
			(at 0 0 90)
			(layer "B.SilkS")
			(hide yes)
			(effects
				(font
					(size 1.27 1.27)
				)
				(justify mirror)
			)
		)
		(property "Value" ""
			(at 0 0 90)
			(layer "B.Fab")
			(effects
				(font
					(size 1.27 1.27)
				)
				(justify mirror)
			)
		)
		(duplicate_pad_numbers_are_jumpers no)
		(fp_line
			(start 0.299974 -0.150114)
			(end -0.299974 -0.150114)
			(stroke
				(width 0.1)
				(type default)
			)
			(layer "B.Fab")
		)
		(fp_line
			(start -0.299974 -0.150114)
			(end -0.299974 0.150114)
			(stroke
				(width 0.1)
				(type default)
			)
			(layer "B.Fab")
		)
		(fp_line
			(start 0.299974 0.150114)
			(end 0.299974 -0.150114)
			(stroke
				(width 0.1)
				(type default)
			)
			(layer "B.Fab")
		)
		(fp_line
			(start -0.299974 0.150114)
			(end 0.299974 0.150114)
			(stroke
				(width 0.1)
				(type default)
			)
			(layer "B.Fab")
		)
		(pad "1" smd rect
			(at 0.2667 0 270)
			(size 0.3048 0.381)
			(layers "B.Cu" "B.Mask" "B.Paste")
			(net "P0V8_PEX1")
		)
		(pad "2" smd rect
			(at -0.2667 0 270)
			(size 0.3048 0.381)
			(layers "B.Cu" "B.Mask" "B.Paste")
			(net "GND")
		)
	)
	(footprint ""
		(layer "B.Cu")
		(at 405.100028 -301.599854 -90)
		(property "Reference" "C1987"
			(at 0 0 90)
			(layer "B.SilkS")
			(hide yes)
			(effects
				(font
					(size 1.27 1.27)
				)
				(justify mirror)
			)
		)
		(property "Value" ""
			(at 0 0 90)
			(layer "B.Fab")
			(effects
				(font
					(size 1.27 1.27)
				)
				(justify mirror)
			)
		)
		(duplicate_pad_numbers_are_jumpers no)
		(fp_line
			(start -0.299974 0.150114)
			(end 0.299974 0.150114)
			(stroke
				(width 0.1)
				(type default)
			)
			(layer "B.Fab")
		)
		(fp_line
			(start 0.299974 0.150114)
			(end 0.299974 -0.150114)
			(stroke
				(width 0.1)
				(type default)
			)
			(layer "B.Fab")
		)
		(fp_line
			(start -0.299974 -0.150114)
			(end -0.299974 0.150114)
			(stroke
				(width 0.1)
				(type default)
			)
			(layer "B.Fab")
		)
		(fp_line
			(start 0.299974 -0.150114)
			(end -0.299974 -0.150114)
			(stroke
				(width 0.1)
				(type default)
			)
			(layer "B.Fab")
		)
		(pad "1" smd rect
			(at 0.2667 0 90)
			(size 0.3048 0.381)
			(layers "B.Cu" "B.Mask" "B.Paste")
			(net "P0V8_SERDES_VDDA_PEX3")
		)
		(pad "2" smd rect
			(at -0.2667 0 90)
			(size 0.3048 0.381)
			(layers "B.Cu" "B.Mask" "B.Paste")
			(net "GND")
		)
	)
	(footprint ""
		(layer "B.Cu")
		(at 281.755342 -154.0256)
		(property "Reference" "R225"
			(at 0 0 0)
			(layer "B.SilkS")
			(hide yes)
			(effects
				(font
					(size 1.27 1.27)
				)
				(justify mirror)
			)
		)
		(property "Value" ""
			(at 0 0 0)
			(layer "B.Fab")
			(effects
				(font
					(size 1.27 1.27)
				)
				(justify mirror)
			)
		)
		(duplicate_pad_numbers_are_jumpers no)
		(fp_line
			(start -0.7874 -0.4064)
			(end -0.7874 0.4064)
			(stroke
				(width 0.1524)
				(type default)
			)
			(layer "B.SilkS")
		)
		(fp_line
			(start -0.7874 0.4064)
			(end 0.7874 0.4064)
			(stroke
				(width 0.1524)
				(type default)
			)
			(layer "B.SilkS")
		)
		(fp_line
			(start 0.7874 -0.4064)
			(end -0.7874 -0.4064)
			(stroke
				(width 0.1524)
				(type default)
			)
			(layer "B.SilkS")
		)
		(fp_line
			(start 0.7874 0.4064)
			(end 0.7874 -0.4064)
			(stroke
				(width 0.1524)
				(type default)
			)
			(layer "B.SilkS")
		)
		(fp_line
			(start -0.67945 -0.3048)
			(end -0.67945 0.3048)
			(stroke
				(width 0.1)
				(type default)
			)
			(layer "B.Fab")
		)
		(fp_line
			(start -0.67945 0.3048)
			(end -0.120396 0.3048)
			(stroke
				(width 0.1)
				(type default)
			)
			(layer "B.Fab")
		)
		(fp_line
			(start -0.12065 -0.3048)
			(end -0.67945 -0.3048)
			(stroke
				(width 0.1)
				(type default)
			)
			(layer "B.Fab")
		)
		(fp_line
			(start -0.12065 -0.2794)
			(end -0.12065 -0.3048)
			(stroke
				(width 0.1)
				(type default)
			)
			(layer "B.Fab")
		)
		(fp_line
			(start -0.120396 0.2794)
			(end 0.12065 0.2794)
			(stroke
				(width 0.1)
				(type default)
			)
			(layer "B.Fab")
		)
		(fp_line
			(start -0.120396 0.3048)
			(end -0.120396 0.2794)
			(stroke
				(width 0.1)
				(type default)
			)
			(layer "B.Fab")
		)
		(fp_line
			(start 0.12065 -0.305054)
			(end 0.12065 -0.2794)
			(stroke
				(width 0.1)
				(type default)
			)
			(layer "B.Fab")
		)
		(fp_line
			(start 0.12065 -0.2794)
			(end -0.12065 -0.2794)
			(stroke
				(width 0.1)
				(type default)
			)
			(layer "B.Fab")
		)
		(fp_line
			(start 0.12065 0.2794)
			(end 0.12065 0.3048)
			(stroke
				(width 0.1)
				(type default)
			)
			(layer "B.Fab")
		)
		(fp_line
			(start 0.12065 0.3048)
			(end 0.67945 0.3048)
			(stroke
				(width 0.1)
				(type default)
			)
			(layer "B.Fab")
		)
		(fp_line
			(start 0.67945 -0.305054)
			(end 0.12065 -0.305054)
			(stroke
				(width 0.1)
				(type default)
			)
			(layer "B.Fab")
		)
		(fp_line
			(start 0.67945 0.3048)
			(end 0.67945 -0.305054)
			(stroke
				(width 0.1)
				(type default)
			)
			(layer "B.Fab")
		)
		(pad "1" smd circle
			(at 0.40005 0 180)
			(size 0 0)
			(layers "B.Cu" "B.Mask" "B.Paste")
			(net "NCSI_NIC4_TX_EN")
		)
		(pad "2" smd circle
			(at -0.40005 0 180)
			(size 0 0)
			(layers "B.Cu" "B.Mask" "B.Paste")
			(net "GND")
		)
	)
	(footprint ""
		(layer "B.Cu")
		(at 299.449744 -303.499774 -90)
		(property "Reference" "C3272"
			(at 0 0 90)
			(layer "B.SilkS")
			(hide yes)
			(effects
				(font
					(size 1.27 1.27)
				)
				(justify mirror)
			)
		)
		(property "Value" ""
			(at 0 0 90)
			(layer "B.Fab")
			(effects
				(font
					(size 1.27 1.27)
				)
				(justify mirror)
			)
		)
		(duplicate_pad_numbers_are_jumpers no)
		(fp_line
			(start -0.299974 0.150114)
			(end 0.299974 0.150114)
			(stroke
				(width 0.1)
				(type default)
			)
			(layer "B.Fab")
		)
		(fp_line
			(start 0.299974 0.150114)
			(end 0.299974 -0.150114)
			(stroke
				(width 0.1)
				(type default)
			)
			(layer "B.Fab")
		)
		(fp_line
			(start -0.299974 -0.150114)
			(end -0.299974 0.150114)
			(stroke
				(width 0.1)
				(type default)
			)
			(layer "B.Fab")
		)
		(fp_line
			(start 0.299974 -0.150114)
			(end -0.299974 -0.150114)
			(stroke
				(width 0.1)
				(type default)
			)
			(layer "B.Fab")
		)
		(pad "1" smd rect
			(at 0.2667 0 90)
			(size 0.3048 0.381)
			(layers "B.Cu" "B.Mask" "B.Paste")
			(net "P1V25_PEX2")
		)
		(pad "2" smd rect
			(at -0.2667 0 90)
			(size 0.3048 0.381)
			(layers "B.Cu" "B.Mask" "B.Paste")
			(net "GND")
		)
	)
	(footprint ""
		(layer "B.Cu")
		(at 334.520286 -308.613556 90)
		(property "Reference" "C4318"
			(at 0 0 90)
			(layer "B.SilkS")
			(hide yes)
			(effects
				(font
					(size 1.27 1.27)
				)
				(justify mirror)
			)
		)
		(property "Value" ""
			(at 0 0 90)
			(layer "B.Fab")
			(effects
				(font
					(size 1.27 1.27)
				)
				(justify mirror)
			)
		)
		(duplicate_pad_numbers_are_jumpers no)
		(fp_line
			(start 1.2954 -0.5842)
			(end -1.2954 -0.5842)
			(stroke
				(width 0.1524)
				(type default)
			)
			(layer "B.SilkS")
		)
		(fp_line
			(start -1.2954 -0.5842)
			(end -1.2954 0.5842)
			(stroke
				(width 0.1524)
				(type default)
			)
			(layer "B.SilkS")
		)
		(fp_line
			(start 1.2954 0.5842)
			(end 1.2954 -0.5842)
			(stroke
				(width 0.1524)
				(type default)
			)
			(layer "B.SilkS")
		)
		(fp_line
			(start -1.2954 0.5842)
			(end 1.2954 0.5842)
			(stroke
				(width 0.1524)
				(type default)
			)
			(layer "B.SilkS")
		)
		(fp_line
			(start 0.8636 -0.4572)
			(end -0.8636 -0.4572)
			(stroke
				(width 0.1)
				(type default)
			)
			(layer "B.Fab")
		)
		(fp_line
			(start -0.8636 -0.4572)
			(end -0.8636 -0.4064)
			(stroke
				(width 0.1)
				(type default)
			)
			(layer "B.Fab")
		)
		(fp_line
			(start 1.1938 -0.4064)
			(end 0.8636 -0.4064)
			(stroke
				(width 0.1)
				(type default)
			)
			(layer "B.Fab")
		)
		(fp_line
			(start 0.8636 -0.4064)
			(end 0.8636 -0.4572)
			(stroke
				(width 0.1)
				(type default)
			)
			(layer "B.Fab")
		)
		(fp_line
			(start -0.8636 -0.4064)
			(end -1.1938 -0.4064)
			(stroke
				(width 0.1)
				(type default)
			)
			(layer "B.Fab")
		)
		(fp_line
			(start -1.1938 -0.4064)
			(end -1.1938 0.4064)
			(stroke
				(width 0.1)
				(type default)
			)
			(layer "B.Fab")
		)
		(fp_line
			(start 1.1938 0.4064)
			(end 1.1938 -0.4064)
			(stroke
				(width 0.1)
				(type default)
			)
			(layer "B.Fab")
		)
		(fp_line
			(start 0.8636 0.4064)
			(end 1.1938 0.4064)
			(stroke
				(width 0.1)
				(type default)
			)
			(layer "B.Fab")
		)
		(fp_line
			(start -0.8636 0.4064)
			(end -0.8636 0.4572)
			(stroke
				(width 0.1)
				(type default)
			)
			(layer "B.Fab")
		)
		(fp_line
			(start -1.1938 0.4064)
			(end -0.8636 0.4064)
			(stroke
				(width 0.1)
				(type default)
			)
			(layer "B.Fab")
		)
		(fp_line
			(start 0.8636 0.4572)
			(end 0.8636 0.4064)
			(stroke
				(width 0.1)
				(type default)
			)
			(layer "B.Fab")
		)
		(fp_line
			(start -0.8636 0.4572)
			(end 0.8636 0.4572)
			(stroke
				(width 0.1)
				(type default)
			)
			(layer "B.Fab")
		)
		(pad "1" smd rect
			(at 0.7366 0)
			(size 0.7112 0.8128)
			(layers "B.Cu" "B.Mask" "B.Paste")
			(net "P0V8_PEX2")
		)
		(pad "2" smd rect
			(at -0.7366 0)
			(size 0.7112 0.8128)
			(layers "B.Cu" "B.Mask" "B.Paste")
			(net "GND")
		)
	)
	(footprint ""
		(layer "B.Cu")
		(at 57.274968 -297.79976 90)
		(property "Reference" "C1118"
			(at 0 0 90)
			(layer "B.SilkS")
			(hide yes)
			(effects
				(font
					(size 1.27 1.27)
				)
				(justify mirror)
			)
		)
		(property "Value" ""
			(at 0 0 90)
			(layer "B.Fab")
			(effects
				(font
					(size 1.27 1.27)
				)
				(justify mirror)
			)
		)
		(duplicate_pad_numbers_are_jumpers no)
		(fp_line
			(start 0.299974 -0.150114)
			(end -0.299974 -0.150114)
			(stroke
				(width 0.1)
				(type default)
			)
			(layer "B.Fab")
		)
		(fp_line
			(start -0.299974 -0.150114)
			(end -0.299974 0.150114)
			(stroke
				(width 0.1)
				(type default)
			)
			(layer "B.Fab")
		)
		(fp_line
			(start 0.299974 0.150114)
			(end 0.299974 -0.150114)
			(stroke
				(width 0.1)
				(type default)
			)
			(layer "B.Fab")
		)
		(fp_line
			(start -0.299974 0.150114)
			(end 0.299974 0.150114)
			(stroke
				(width 0.1)
				(type default)
			)
			(layer "B.Fab")
		)
		(pad "1" smd rect
			(at 0.2667 0 270)
			(size 0.3048 0.381)
			(layers "B.Cu" "B.Mask" "B.Paste")
			(net "P0V8_PEX0")
		)
		(pad "2" smd rect
			(at -0.2667 0 270)
			(size 0.3048 0.381)
			(layers "B.Cu" "B.Mask" "B.Paste")
			(net "GND")
		)
	)
	(footprint ""
		(layer "B.Cu")
		(at 189.500002 -110.978696)
		(property "Reference" "C896"
			(at 0 0 0)
			(layer "B.SilkS")
			(hide yes)
			(effects
				(font
					(size 1.27 1.27)
				)
				(justify mirror)
			)
		)
		(property "Value" ""
			(at 0 0 0)
			(layer "B.Fab")
			(effects
				(font
					(size 1.27 1.27)
				)
				(justify mirror)
			)
		)
		(duplicate_pad_numbers_are_jumpers no)
		(fp_line
			(start -0.299974 -0.150114)
			(end -0.299974 0.150114)
			(stroke
				(width 0.1)
				(type default)
			)
			(layer "B.Fab")
		)
		(fp_line
			(start -0.299974 0.150114)
			(end 0.299974 0.150114)
			(stroke
				(width 0.1)
				(type default)
			)
			(layer "B.Fab")
		)
		(fp_line
			(start 0.299974 -0.150114)
			(end -0.299974 -0.150114)
			(stroke
				(width 0.1)
				(type default)
			)
			(layer "B.Fab")
		)
		(fp_line
			(start 0.299974 0.150114)
			(end 0.299974 -0.150114)
			(stroke
				(width 0.1)
				(type default)
			)
			(layer "B.Fab")
		)
		(pad "1" smd rect
			(at 0.2667 0 180)
			(size 0.3048 0.381)
			(layers "B.Cu" "B.Mask" "B.Paste")
			(net "P12V_NIC3")
		)
		(pad "2" smd rect
			(at -0.2667 0 180)
			(size 0.3048 0.381)
			(layers "B.Cu" "B.Mask" "B.Paste")
			(net "GND")
		)
	)
	(footprint ""
		(layer "B.Cu")
		(at 278.326342 -140.8176 180)
		(property "Reference" "C912"
			(at 0 0 0)
			(layer "B.SilkS")
			(hide yes)
			(effects
				(font
					(size 1.27 1.27)
				)
				(justify mirror)
			)
		)
		(property "Value" ""
			(at 0 0 0)
			(layer "B.Fab")
			(effects
				(font
					(size 1.27 1.27)
				)
				(justify mirror)
			)
		)
		(duplicate_pad_numbers_are_jumpers no)
		(fp_line
			(start 0.7874 0.4064)
			(end 0.7874 -0.4064)
			(stroke
				(width 0.1524)
				(type default)
			)
			(layer "B.SilkS")
		)
		(fp_line
			(start 0.7874 -0.4064)
			(end -0.7874 -0.4064)
			(stroke
				(width 0.1524)
				(type default)
			)
			(layer "B.SilkS")
		)
		(fp_line
			(start -0.7874 0.4064)
			(end 0.7874 0.4064)
			(stroke
				(width 0.1524)
				(type default)
			)
			(layer "B.SilkS")
		)
		(fp_line
			(start -0.7874 -0.4064)
			(end -0.7874 0.4064)
			(stroke
				(width 0.1524)
				(type default)
			)
			(layer "B.SilkS")
		)
		(fp_line
			(start 0.67945 0.3048)
			(end 0.67945 -0.305054)
			(stroke
				(width 0.1)
				(type default)
			)
			(layer "B.Fab")
		)
		(fp_line
			(start 0.67945 -0.305054)
			(end 0.12065 -0.305054)
			(stroke
				(width 0.1)
				(type default)
			)
			(layer "B.Fab")
		)
		(fp_line
			(start 0.12065 0.3048)
			(end 0.67945 0.3048)
			(stroke
				(width 0.1)
				(type default)
			)
			(layer "B.Fab")
		)
		(fp_line
			(start 0.12065 0.2794)
			(end 0.12065 0.3048)
			(stroke
				(width 0.1)
				(type default)
			)
			(layer "B.Fab")
		)
		(fp_line
			(start 0.12065 -0.2794)
			(end -0.12065 -0.2794)
			(stroke
				(width 0.1)
				(type default)
			)
			(layer "B.Fab")
		)
		(fp_line
			(start 0.12065 -0.305054)
			(end 0.12065 -0.2794)
			(stroke
				(width 0.1)
				(type default)
			)
			(layer "B.Fab")
		)
		(fp_line
			(start -0.120396 0.3048)
			(end -0.120396 0.2794)
			(stroke
				(width 0.1)
				(type default)
			)
			(layer "B.Fab")
		)
		(fp_line
			(start -0.120396 0.2794)
			(end 0.12065 0.2794)
			(stroke
				(width 0.1)
				(type default)
			)
			(layer "B.Fab")
		)
		(fp_line
			(start -0.12065 -0.2794)
			(end -0.12065 -0.3048)
			(stroke
				(width 0.1)
				(type default)
			)
			(layer "B.Fab")
		)
		(fp_line
			(start -0.12065 -0.3048)
			(end -0.67945 -0.3048)
			(stroke
				(width 0.1)
				(type default)
			)
			(layer "B.Fab")
		)
		(fp_line
			(start -0.67945 0.3048)
			(end -0.120396 0.3048)
			(stroke
				(width 0.1)
				(type default)
			)
			(layer "B.Fab")
		)
		(fp_line
			(start -0.67945 -0.3048)
			(end -0.67945 0.3048)
			(stroke
				(width 0.1)
				(type default)
			)
			(layer "B.Fab")
		)
		(pad "1" smd circle
			(at 0.40005 0)
			(size 0 0)
			(layers "B.Cu" "B.Mask" "B.Paste")
			(net "P3V3_NIC4")
		)
		(pad "2" smd circle
			(at -0.40005 0)
			(size 0 0)
			(layers "B.Cu" "B.Mask" "B.Paste")
			(net "GND")
		)
	)
	(footprint ""
		(layer "B.Cu")
		(at 293.27475 -297.79976 -90)
		(property "Reference" "C1649"
			(at 0 0 90)
			(layer "B.SilkS")
			(hide yes)
			(effects
				(font
					(size 1.27 1.27)
				)
				(justify mirror)
			)
		)
		(property "Value" ""
			(at 0 0 90)
			(layer "B.Fab")
			(effects
				(font
					(size 1.27 1.27)
				)
				(justify mirror)
			)
		)
		(duplicate_pad_numbers_are_jumpers no)
		(fp_line
			(start -0.299974 0.150114)
			(end 0.299974 0.150114)
			(stroke
				(width 0.1)
				(type default)
			)
			(layer "B.Fab")
		)
		(fp_line
			(start 0.299974 0.150114)
			(end 0.299974 -0.150114)
			(stroke
				(width 0.1)
				(type default)
			)
			(layer "B.Fab")
		)
		(fp_line
			(start -0.299974 -0.150114)
			(end -0.299974 0.150114)
			(stroke
				(width 0.1)
				(type default)
			)
			(layer "B.Fab")
		)
		(fp_line
			(start 0.299974 -0.150114)
			(end -0.299974 -0.150114)
			(stroke
				(width 0.1)
				(type default)
			)
			(layer "B.Fab")
		)
		(pad "1" smd rect
			(at 0.2667 0 90)
			(size 0.3048 0.381)
			(layers "B.Cu" "B.Mask" "B.Paste")
			(net "P0V8_PEX2")
		)
		(pad "2" smd rect
			(at -0.2667 0 90)
			(size 0.3048 0.381)
			(layers "B.Cu" "B.Mask" "B.Paste")
			(net "GND")
		)
	)
	(footprint ""
		(layer "B.Cu")
		(at 414.376616 -111.334042 180)
		(property "Reference" "R393"
			(at 0 0 0)
			(layer "B.SilkS")
			(hide yes)
			(effects
				(font
					(size 1.27 1.27)
				)
				(justify mirror)
			)
		)
		(property "Value" ""
			(at 0 0 0)
			(layer "B.Fab")
			(effects
				(font
					(size 1.27 1.27)
				)
				(justify mirror)
			)
		)
		(duplicate_pad_numbers_are_jumpers no)
		(fp_line
			(start 0.7874 0.4064)
			(end 0.7874 -0.4064)
			(stroke
				(width 0.1524)
				(type default)
			)
			(layer "B.SilkS")
		)
		(fp_line
			(start 0.7874 -0.4064)
			(end -0.7874 -0.4064)
			(stroke
				(width 0.1524)
				(type default)
			)
			(layer "B.SilkS")
		)
		(fp_line
			(start -0.7874 0.4064)
			(end 0.7874 0.4064)
			(stroke
				(width 0.1524)
				(type default)
			)
			(layer "B.SilkS")
		)
		(fp_line
			(start -0.7874 -0.4064)
			(end -0.7874 0.4064)
			(stroke
				(width 0.1524)
				(type default)
			)
			(layer "B.SilkS")
		)
		(fp_line
			(start 0.67945 0.3048)
			(end 0.67945 -0.305054)
			(stroke
				(width 0.1)
				(type default)
			)
			(layer "B.Fab")
		)
		(fp_line
			(start 0.67945 -0.305054)
			(end 0.12065 -0.305054)
			(stroke
				(width 0.1)
				(type default)
			)
			(layer "B.Fab")
		)
		(fp_line
			(start 0.12065 0.3048)
			(end 0.67945 0.3048)
			(stroke
				(width 0.1)
				(type default)
			)
			(layer "B.Fab")
		)
		(fp_line
			(start 0.12065 0.2794)
			(end 0.12065 0.3048)
			(stroke
				(width 0.1)
				(type default)
			)
			(layer "B.Fab")
		)
		(fp_line
			(start 0.12065 -0.2794)
			(end -0.12065 -0.2794)
			(stroke
				(width 0.1)
				(type default)
			)
			(layer "B.Fab")
		)
		(fp_line
			(start 0.12065 -0.305054)
			(end 0.12065 -0.2794)
			(stroke
				(width 0.1)
				(type default)
			)
			(layer "B.Fab")
		)
		(fp_line
			(start -0.120396 0.3048)
			(end -0.120396 0.2794)
			(stroke
				(width 0.1)
				(type default)
			)
			(layer "B.Fab")
		)
		(fp_line
			(start -0.120396 0.2794)
			(end 0.12065 0.2794)
			(stroke
				(width 0.1)
				(type default)
			)
			(layer "B.Fab")
		)
		(fp_line
			(start -0.12065 -0.2794)
			(end -0.12065 -0.3048)
			(stroke
				(width 0.1)
				(type default)
			)
			(layer "B.Fab")
		)
		(fp_line
			(start -0.12065 -0.3048)
			(end -0.67945 -0.3048)
			(stroke
				(width 0.1)
				(type default)
			)
			(layer "B.Fab")
		)
		(fp_line
			(start -0.67945 0.3048)
			(end -0.120396 0.3048)
			(stroke
				(width 0.1)
				(type default)
			)
			(layer "B.Fab")
		)
		(fp_line
			(start -0.67945 -0.3048)
			(end -0.67945 0.3048)
			(stroke
				(width 0.1)
				(type default)
			)
			(layer "B.Fab")
		)
		(pad "1" smd circle
			(at 0.40005 0)
			(size 0 0)
			(layers "B.Cu" "B.Mask" "B.Paste")
			(net "RST_SMB_NIC_MUX_R_N")
		)
		(pad "2" smd circle
			(at -0.40005 0)
			(size 0 0)
			(layers "B.Cu" "B.Mask" "B.Paste")
			(net "RST_SMB_NIC7_MUX_N")
		)
	)
	(footprint ""
		(layer "B.Cu")
		(at 49.5554 -157.0736 180)
		(property "Reference" "R1"
			(at 0 0 0)
			(layer "B.SilkS")
			(hide yes)
			(effects
				(font
					(size 1.27 1.27)
				)
				(justify mirror)
			)
		)
		(property "Value" ""
			(at 0 0 0)
			(layer "B.Fab")
			(effects
				(font
					(size 1.27 1.27)
				)
				(justify mirror)
			)
		)
		(duplicate_pad_numbers_are_jumpers no)
		(fp_line
			(start 0.7874 0.4064)
			(end 0.7874 -0.4064)
			(stroke
				(width 0.1524)
				(type default)
			)
			(layer "B.SilkS")
		)
		(fp_line
			(start 0.7874 -0.4064)
			(end -0.7874 -0.4064)
			(stroke
				(width 0.1524)
				(type default)
			)
			(layer "B.SilkS")
		)
		(fp_line
			(start -0.7874 0.4064)
			(end 0.7874 0.4064)
			(stroke
				(width 0.1524)
				(type default)
			)
			(layer "B.SilkS")
		)
		(fp_line
			(start -0.7874 -0.4064)
			(end -0.7874 0.4064)
			(stroke
				(width 0.1524)
				(type default)
			)
			(layer "B.SilkS")
		)
		(fp_line
			(start 0.67945 0.3048)
			(end 0.67945 -0.305054)
			(stroke
				(width 0.1)
				(type default)
			)
			(layer "B.Fab")
		)
		(fp_line
			(start 0.67945 -0.305054)
			(end 0.12065 -0.305054)
			(stroke
				(width 0.1)
				(type default)
			)
			(layer "B.Fab")
		)
		(fp_line
			(start 0.12065 0.3048)
			(end 0.67945 0.3048)
			(stroke
				(width 0.1)
				(type default)
			)
			(layer "B.Fab")
		)
		(fp_line
			(start 0.12065 0.2794)
			(end 0.12065 0.3048)
			(stroke
				(width 0.1)
				(type default)
			)
			(layer "B.Fab")
		)
		(fp_line
			(start 0.12065 -0.2794)
			(end -0.12065 -0.2794)
			(stroke
				(width 0.1)
				(type default)
			)
			(layer "B.Fab")
		)
		(fp_line
			(start 0.12065 -0.305054)
			(end 0.12065 -0.2794)
			(stroke
				(width 0.1)
				(type default)
			)
			(layer "B.Fab")
		)
		(fp_line
			(start -0.120396 0.3048)
			(end -0.120396 0.2794)
			(stroke
				(width 0.1)
				(type default)
			)
			(layer "B.Fab")
		)
		(fp_line
			(start -0.120396 0.2794)
			(end 0.12065 0.2794)
			(stroke
				(width 0.1)
				(type default)
			)
			(layer "B.Fab")
		)
		(fp_line
			(start -0.12065 -0.2794)
			(end -0.12065 -0.3048)
			(stroke
				(width 0.1)
				(type default)
			)
			(layer "B.Fab")
		)
		(fp_line
			(start -0.12065 -0.3048)
			(end -0.67945 -0.3048)
			(stroke
				(width 0.1)
				(type default)
			)
			(layer "B.Fab")
		)
		(fp_line
			(start -0.67945 0.3048)
			(end -0.120396 0.3048)
			(stroke
				(width 0.1)
				(type default)
			)
			(layer "B.Fab")
		)
		(fp_line
			(start -0.67945 -0.3048)
			(end -0.67945 0.3048)
			(stroke
				(width 0.1)
				(type default)
			)
			(layer "B.Fab")
		)
		(pad "1" smd circle
			(at 0.40005 0)
			(size 0 0)
			(layers "B.Cu" "B.Mask" "B.Paste")
			(net "NIC0_RBT_ARB_OUT")
		)
		(pad "2" smd circle
			(at -0.40005 0)
			(size 0 0)
			(layers "B.Cu" "B.Mask" "B.Paste")
			(net "NIC0_RBT_ARB_IN")
		)
	)
	(footprint ""
		(layer "B.Cu")
		(at 302.061626 -239.976406 90)
		(property "Reference" "R4108"
			(at 0 0 90)
			(layer "B.SilkS")
			(hide yes)
			(effects
				(font
					(size 1.27 1.27)
				)
				(justify mirror)
			)
		)
		(property "Value" ""
			(at 0 0 90)
			(layer "B.Fab")
			(effects
				(font
					(size 1.27 1.27)
				)
				(justify mirror)
			)
		)
		(duplicate_pad_numbers_are_jumpers no)
		(fp_line
			(start 0.7874 -0.4064)
			(end -0.7874 -0.4064)
			(stroke
				(width 0.1524)
				(type default)
			)
			(layer "B.SilkS")
		)
		(fp_line
			(start -0.7874 -0.4064)
			(end -0.7874 0.4064)
			(stroke
				(width 0.1524)
				(type default)
			)
			(layer "B.SilkS")
		)
		(fp_line
			(start 0.7874 0.4064)
			(end 0.7874 -0.4064)
			(stroke
				(width 0.1524)
				(type default)
			)
			(layer "B.SilkS")
		)
		(fp_line
			(start -0.7874 0.4064)
			(end 0.7874 0.4064)
			(stroke
				(width 0.1524)
				(type default)
			)
			(layer "B.SilkS")
		)
		(fp_line
			(start 0.67945 -0.305054)
			(end 0.12065 -0.305054)
			(stroke
				(width 0.1)
				(type default)
			)
			(layer "B.Fab")
		)
		(fp_line
			(start 0.12065 -0.305054)
			(end 0.12065 -0.2794)
			(stroke
				(width 0.1)
				(type default)
			)
			(layer "B.Fab")
		)
		(fp_line
			(start -0.12065 -0.3048)
			(end -0.67945 -0.3048)
			(stroke
				(width 0.1)
				(type default)
			)
			(layer "B.Fab")
		)
		(fp_line
			(start -0.67945 -0.3048)
			(end -0.67945 0.3048)
			(stroke
				(width 0.1)
				(type default)
			)
			(layer "B.Fab")
		)
		(fp_line
			(start 0.12065 -0.2794)
			(end -0.12065 -0.2794)
			(stroke
				(width 0.1)
				(type default)
			)
			(layer "B.Fab")
		)
		(fp_line
			(start -0.12065 -0.2794)
			(end -0.12065 -0.3048)
			(stroke
				(width 0.1)
				(type default)
			)
			(layer "B.Fab")
		)
		(fp_line
			(start 0.12065 0.2794)
			(end 0.12065 0.3048)
			(stroke
				(width 0.1)
				(type default)
			)
			(layer "B.Fab")
		)
		(fp_line
			(start -0.120396 0.2794)
			(end 0.12065 0.2794)
			(stroke
				(width 0.1)
				(type default)
			)
			(layer "B.Fab")
		)
		(fp_line
			(start 0.67945 0.3048)
			(end 0.67945 -0.305054)
			(stroke
				(width 0.1)
				(type default)
			)
			(layer "B.Fab")
		)
		(fp_line
			(start 0.12065 0.3048)
			(end 0.67945 0.3048)
			(stroke
				(width 0.1)
				(type default)
			)
			(layer "B.Fab")
		)
		(fp_line
			(start -0.120396 0.3048)
			(end -0.120396 0.2794)
			(stroke
				(width 0.1)
				(type default)
			)
			(layer "B.Fab")
		)
		(fp_line
			(start -0.67945 0.3048)
			(end -0.120396 0.3048)
			(stroke
				(width 0.1)
				(type default)
			)
			(layer "B.Fab")
		)
		(pad "1" smd circle
			(at 0.40005 0 270)
			(size 0 0)
			(layers "B.Cu" "B.Mask" "B.Paste")
			(net "SMB_MB_BMC_ISO_SDA")
		)
		(pad "2" smd circle
			(at -0.40005 0 270)
			(size 0 0)
			(layers "B.Cu" "B.Mask" "B.Paste")
			(net "SMB_MB_R_SDA")
		)
	)
	(footprint ""
		(layer "B.Cu")
		(at 355.300788 -293.660068 90)
		(property "Reference" "PC200"
			(at 0 0 90)
			(layer "B.SilkS")
			(hide yes)
			(effects
				(font
					(size 1.27 1.27)
				)
				(justify mirror)
			)
		)
		(property "Value" ""
			(at 0 0 90)
			(layer "B.Fab")
			(effects
				(font
					(size 1.27 1.27)
				)
				(justify mirror)
			)
		)
		(duplicate_pad_numbers_are_jumpers no)
		(fp_line
			(start 4.84378 -2.150618)
			(end 4.53898 -2.150618)
			(stroke
				(width 0.1524)
				(type default)
			)
			(layer "B.SilkS")
		)
		(fp_line
			(start 4.84378 -2.150618)
			(end 4.842256 2.163064)
			(stroke
				(width 0.1524)
				(type default)
			)
			(layer "B.SilkS")
		)
		(fp_line
			(start 4.69138 -2.150618)
			(end 4.692396 2.161032)
			(stroke
				(width 0.1524)
				(type default)
			)
			(layer "B.SilkS")
		)
		(fp_line
			(start 4.53898 -2.150618)
			(end 4.539742 2.152142)
			(stroke
				(width 0.1524)
				(type default)
			)
			(layer "B.SilkS")
		)
		(fp_line
			(start 4.53898 -2.15011)
			(end -4.53898 -2.15011)
			(stroke
				(width 0.1524)
				(type default)
			)
			(layer "B.SilkS")
		)
		(fp_line
			(start -4.53898 -2.15011)
			(end -4.53898 2.15011)
			(stroke
				(width 0.1524)
				(type default)
			)
			(layer "B.SilkS")
		)
		(fp_line
			(start 4.53898 2.15011)
			(end 4.53898 -2.15011)
			(stroke
				(width 0.1524)
				(type default)
			)
			(layer "B.SilkS")
		)
		(fp_line
			(start -4.53898 2.15011)
			(end 4.53898 2.15011)
			(stroke
				(width 0.1524)
				(type default)
			)
			(layer "B.SilkS")
		)
		(fp_line
			(start 4.83108 2.150364)
			(end 4.447794 2.149348)
			(stroke
				(width 0.1524)
				(type default)
			)
			(layer "B.SilkS")
		)
		(fp_line
			(start 3.64998 -2.15011)
			(end -3.64998 -2.15011)
			(stroke
				(width 0.1)
				(type default)
			)
			(layer "B.Fab")
		)
		(fp_line
			(start -3.64998 -2.15011)
			(end -3.64998 2.15011)
			(stroke
				(width 0.1)
				(type default)
			)
			(layer "B.Fab")
		)
		(fp_line
			(start 3.64998 2.15011)
			(end 3.64998 -2.15011)
			(stroke
				(width 0.1)
				(type default)
			)
			(layer "B.Fab")
		)
		(fp_line
			(start -3.64998 2.15011)
			(end 3.64998 2.15011)
			(stroke
				(width 0.1)
				(type default)
			)
			(layer "B.Fab")
		)
		(fp_text user "+"
			(at 6.214872 -0.337058 90)
			(unlocked yes)
			(layer "B.SilkS")
			(effects
				(font
					(size 1.905 1.4224)
					(thickness 0.1524)
				)
				(justify left mirror)
			)
		)
		(fp_text user "-"
			(at -4.313174 -0.094488 90)
			(unlocked yes)
			(layer "B.SilkS")
			(effects
				(font
					(size 1.905 1.4224)
					(thickness 0.1524)
				)
				(justify left mirror)
			)
		)
		(fp_text user "+"
			(at 6.214872 -0.337058 90)
			(unlocked yes)
			(layer "B.Fab")
			(effects
				(font
					(size 1.905 1.4224)
					(thickness 0.1524)
				)
				(justify left mirror)
			)
		)
		(fp_text user "-"
			(at -4.313174 -0.094488 90)
			(unlocked yes)
			(layer "B.Fab")
			(effects
				(font
					(size 1.905 1.4224)
					(thickness 0.1524)
				)
				(justify left mirror)
			)
		)
		(pad "1" smd rect
			(at 3.199892 0 270)
			(size 2.413 2.8194)
			(layers "B.Cu" "B.Mask" "B.Paste")
			(net "P0V8_PEX3")
		)
		(pad "2" smd rect
			(at -3.199892 0 270)
			(size 2.413 2.8194)
			(layers "B.Cu" "B.Mask" "B.Paste")
			(net "GND")
		)
	)
	(footprint ""
		(layer "B.Cu")
		(at 230.991664 -207.02016 -90)
		(property "Reference" "R5525"
			(at 0 0 90)
			(layer "B.SilkS")
			(hide yes)
			(effects
				(font
					(size 1.27 1.27)
				)
				(justify mirror)
			)
		)
		(property "Value" ""
			(at 0 0 90)
			(layer "B.Fab")
			(effects
				(font
					(size 1.27 1.27)
				)
				(justify mirror)
			)
		)
		(duplicate_pad_numbers_are_jumpers no)
		(fp_line
			(start -0.7874 0.4064)
			(end 0.7874 0.4064)
			(stroke
				(width 0.1524)
				(type default)
			)
			(layer "B.SilkS")
		)
		(fp_line
			(start 0.7874 0.4064)
			(end 0.7874 -0.4064)
			(stroke
				(width 0.1524)
				(type default)
			)
			(layer "B.SilkS")
		)
		(fp_line
			(start -0.7874 -0.4064)
			(end -0.7874 0.4064)
			(stroke
				(width 0.1524)
				(type default)
			)
			(layer "B.SilkS")
		)
		(fp_line
			(start 0.7874 -0.4064)
			(end -0.7874 -0.4064)
			(stroke
				(width 0.1524)
				(type default)
			)
			(layer "B.SilkS")
		)
		(fp_line
			(start -0.67945 0.3048)
			(end -0.120396 0.3048)
			(stroke
				(width 0.1)
				(type default)
			)
			(layer "B.Fab")
		)
		(fp_line
			(start -0.120396 0.3048)
			(end -0.120396 0.2794)
			(stroke
				(width 0.1)
				(type default)
			)
			(layer "B.Fab")
		)
		(fp_line
			(start 0.12065 0.3048)
			(end 0.67945 0.3048)
			(stroke
				(width 0.1)
				(type default)
			)
			(layer "B.Fab")
		)
		(fp_line
			(start 0.67945 0.3048)
			(end 0.67945 -0.305054)
			(stroke
				(width 0.1)
				(type default)
			)
			(layer "B.Fab")
		)
		(fp_line
			(start -0.120396 0.2794)
			(end 0.12065 0.2794)
			(stroke
				(width 0.1)
				(type default)
			)
			(layer "B.Fab")
		)
		(fp_line
			(start 0.12065 0.2794)
			(end 0.12065 0.3048)
			(stroke
				(width 0.1)
				(type default)
			)
			(layer "B.Fab")
		)
		(fp_line
			(start -0.12065 -0.2794)
			(end -0.12065 -0.3048)
			(stroke
				(width 0.1)
				(type default)
			)
			(layer "B.Fab")
		)
		(fp_line
			(start 0.12065 -0.2794)
			(end -0.12065 -0.2794)
			(stroke
				(width 0.1)
				(type default)
			)
			(layer "B.Fab")
		)
		(fp_line
			(start -0.67945 -0.3048)
			(end -0.67945 0.3048)
			(stroke
				(width 0.1)
				(type default)
			)
			(layer "B.Fab")
		)
		(fp_line
			(start -0.12065 -0.3048)
			(end -0.67945 -0.3048)
			(stroke
				(width 0.1)
				(type default)
			)
			(layer "B.Fab")
		)
		(fp_line
			(start 0.12065 -0.305054)
			(end 0.12065 -0.2794)
			(stroke
				(width 0.1)
				(type default)
			)
			(layer "B.Fab")
		)
		(fp_line
			(start 0.67945 -0.305054)
			(end 0.12065 -0.305054)
			(stroke
				(width 0.1)
				(type default)
			)
			(layer "B.Fab")
		)
		(pad "1" smd circle
			(at 0.40005 0 90)
			(size 0 0)
			(layers "B.Cu" "B.Mask" "B.Paste")
			(net "P3V3_AUX")
		)
		(pad "2" smd circle
			(at -0.40005 0 90)
			(size 0 0)
			(layers "B.Cu" "B.Mask" "B.Paste")
			(net "BIC_FWSPIMISO")
		)
	)
	(footprint ""
		(layer "B.Cu")
		(at 106.223562 -358.724708 90)
		(property "Reference" "R6379"
			(at 0 0 90)
			(layer "B.SilkS")
			(hide yes)
			(effects
				(font
					(size 1.27 1.27)
				)
				(justify mirror)
			)
		)
		(property "Value" ""
			(at 0 0 90)
			(layer "B.Fab")
			(effects
				(font
					(size 1.27 1.27)
				)
				(justify mirror)
			)
		)
		(duplicate_pad_numbers_are_jumpers no)
		(fp_line
			(start 0.7874 -0.4064)
			(end -0.7874 -0.4064)
			(stroke
				(width 0.1524)
				(type default)
			)
			(layer "B.SilkS")
		)
		(fp_line
			(start -0.7874 -0.4064)
			(end -0.7874 0.4064)
			(stroke
				(width 0.1524)
				(type default)
			)
			(layer "B.SilkS")
		)
		(fp_line
			(start 0.7874 0.4064)
			(end 0.7874 -0.4064)
			(stroke
				(width 0.1524)
				(type default)
			)
			(layer "B.SilkS")
		)
		(fp_line
			(start -0.7874 0.4064)
			(end 0.7874 0.4064)
			(stroke
				(width 0.1524)
				(type default)
			)
			(layer "B.SilkS")
		)
		(fp_line
			(start 0.67945 -0.305054)
			(end 0.12065 -0.305054)
			(stroke
				(width 0.1)
				(type default)
			)
			(layer "B.Fab")
		)
		(fp_line
			(start 0.12065 -0.305054)
			(end 0.12065 -0.2794)
			(stroke
				(width 0.1)
				(type default)
			)
			(layer "B.Fab")
		)
		(fp_line
			(start -0.12065 -0.3048)
			(end -0.67945 -0.3048)
			(stroke
				(width 0.1)
				(type default)
			)
			(layer "B.Fab")
		)
		(fp_line
			(start -0.67945 -0.3048)
			(end -0.67945 0.3048)
			(stroke
				(width 0.1)
				(type default)
			)
			(layer "B.Fab")
		)
		(fp_line
			(start 0.12065 -0.2794)
			(end -0.12065 -0.2794)
			(stroke
				(width 0.1)
				(type default)
			)
			(layer "B.Fab")
		)
		(fp_line
			(start -0.12065 -0.2794)
			(end -0.12065 -0.3048)
			(stroke
				(width 0.1)
				(type default)
			)
			(layer "B.Fab")
		)
		(fp_line
			(start 0.12065 0.2794)
			(end 0.12065 0.3048)
			(stroke
				(width 0.1)
				(type default)
			)
			(layer "B.Fab")
		)
		(fp_line
			(start -0.120396 0.2794)
			(end 0.12065 0.2794)
			(stroke
				(width 0.1)
				(type default)
			)
			(layer "B.Fab")
		)
		(fp_line
			(start 0.67945 0.3048)
			(end 0.67945 -0.305054)
			(stroke
				(width 0.1)
				(type default)
			)
			(layer "B.Fab")
		)
		(fp_line
			(start 0.12065 0.3048)
			(end 0.67945 0.3048)
			(stroke
				(width 0.1)
				(type default)
			)
			(layer "B.Fab")
		)
		(fp_line
			(start -0.120396 0.3048)
			(end -0.120396 0.2794)
			(stroke
				(width 0.1)
				(type default)
			)
			(layer "B.Fab")
		)
		(fp_line
			(start -0.67945 0.3048)
			(end -0.120396 0.3048)
			(stroke
				(width 0.1)
				(type default)
			)
			(layer "B.Fab")
		)
		(pad "1" smd circle
			(at 0.40005 0 270)
			(size 0 0)
			(layers "B.Cu" "B.Mask" "B.Paste")
			(net "CLK_100M_DB800ZL_PEX2_S3_R_DN")
		)
		(pad "2" smd circle
			(at -0.40005 0 270)
			(size 0 0)
			(layers "B.Cu" "B.Mask" "B.Paste")
			(net "CLK_100M_DB800ZL_PEX2_S3_DN")
		)
	)
	(footprint ""
		(layer "B.Cu")
		(at 348.526608 -323.146928 -90)
		(property "Reference" "R6508"
			(at 0 0 90)
			(layer "B.SilkS")
			(hide yes)
			(effects
				(font
					(size 1.27 1.27)
				)
				(justify mirror)
			)
		)
		(property "Value" ""
			(at 0 0 90)
			(layer "B.Fab")
			(effects
				(font
					(size 1.27 1.27)
				)
				(justify mirror)
			)
		)
		(duplicate_pad_numbers_are_jumpers no)
		(fp_line
			(start -0.7874 0.4064)
			(end 0.7874 0.4064)
			(stroke
				(width 0.1524)
				(type default)
			)
			(layer "B.SilkS")
		)
		(fp_line
			(start 0.7874 0.4064)
			(end 0.7874 -0.4064)
			(stroke
				(width 0.1524)
				(type default)
			)
			(layer "B.SilkS")
		)
		(fp_line
			(start -0.7874 -0.4064)
			(end -0.7874 0.4064)
			(stroke
				(width 0.1524)
				(type default)
			)
			(layer "B.SilkS")
		)
		(fp_line
			(start 0.7874 -0.4064)
			(end -0.7874 -0.4064)
			(stroke
				(width 0.1524)
				(type default)
			)
			(layer "B.SilkS")
		)
		(fp_line
			(start -0.67945 0.3048)
			(end -0.120396 0.3048)
			(stroke
				(width 0.1)
				(type default)
			)
			(layer "B.Fab")
		)
		(fp_line
			(start -0.120396 0.3048)
			(end -0.120396 0.2794)
			(stroke
				(width 0.1)
				(type default)
			)
			(layer "B.Fab")
		)
		(fp_line
			(start 0.12065 0.3048)
			(end 0.67945 0.3048)
			(stroke
				(width 0.1)
				(type default)
			)
			(layer "B.Fab")
		)
		(fp_line
			(start 0.67945 0.3048)
			(end 0.67945 -0.305054)
			(stroke
				(width 0.1)
				(type default)
			)
			(layer "B.Fab")
		)
		(fp_line
			(start -0.120396 0.2794)
			(end 0.12065 0.2794)
			(stroke
				(width 0.1)
				(type default)
			)
			(layer "B.Fab")
		)
		(fp_line
			(start 0.12065 0.2794)
			(end 0.12065 0.3048)
			(stroke
				(width 0.1)
				(type default)
			)
			(layer "B.Fab")
		)
		(fp_line
			(start -0.12065 -0.2794)
			(end -0.12065 -0.3048)
			(stroke
				(width 0.1)
				(type default)
			)
			(layer "B.Fab")
		)
		(fp_line
			(start 0.12065 -0.2794)
			(end -0.12065 -0.2794)
			(stroke
				(width 0.1)
				(type default)
			)
			(layer "B.Fab")
		)
		(fp_line
			(start -0.67945 -0.3048)
			(end -0.67945 0.3048)
			(stroke
				(width 0.1)
				(type default)
			)
			(layer "B.Fab")
		)
		(fp_line
			(start -0.12065 -0.3048)
			(end -0.67945 -0.3048)
			(stroke
				(width 0.1)
				(type default)
			)
			(layer "B.Fab")
		)
		(fp_line
			(start 0.12065 -0.305054)
			(end 0.12065 -0.2794)
			(stroke
				(width 0.1)
				(type default)
			)
			(layer "B.Fab")
		)
		(fp_line
			(start 0.67945 -0.305054)
			(end 0.12065 -0.305054)
			(stroke
				(width 0.1)
				(type default)
			)
			(layer "B.Fab")
		)
		(pad "1" smd circle
			(at 0.40005 0 90)
			(size 0 0)
			(layers "B.Cu" "B.Mask" "B.Paste")
			(net "P0V8_SERDES_VDDA_PEX2")
		)
		(pad "2" smd circle
			(at -0.40005 0 90)
			(size 0 0)
			(layers "B.Cu" "B.Mask" "B.Paste")
			(net "P0V8_SERDES_VDDA_PEX2_C3")
		)
	)
	(footprint ""
		(layer "B.Cu")
		(at 358.504236 -308.613556 90)
		(property "Reference" "C4359"
			(at 0 0 90)
			(layer "B.SilkS")
			(hide yes)
			(effects
				(font
					(size 1.27 1.27)
				)
				(justify mirror)
			)
		)
		(property "Value" ""
			(at 0 0 90)
			(layer "B.Fab")
			(effects
				(font
					(size 1.27 1.27)
				)
				(justify mirror)
			)
		)
		(duplicate_pad_numbers_are_jumpers no)
		(fp_line
			(start 1.2954 -0.5842)
			(end -1.2954 -0.5842)
			(stroke
				(width 0.1524)
				(type default)
			)
			(layer "B.SilkS")
		)
		(fp_line
			(start -1.2954 -0.5842)
			(end -1.2954 0.5842)
			(stroke
				(width 0.1524)
				(type default)
			)
			(layer "B.SilkS")
		)
		(fp_line
			(start 1.2954 0.5842)
			(end 1.2954 -0.5842)
			(stroke
				(width 0.1524)
				(type default)
			)
			(layer "B.SilkS")
		)
		(fp_line
			(start -1.2954 0.5842)
			(end 1.2954 0.5842)
			(stroke
				(width 0.1524)
				(type default)
			)
			(layer "B.SilkS")
		)
		(fp_line
			(start 0.8636 -0.4572)
			(end -0.8636 -0.4572)
			(stroke
				(width 0.1)
				(type default)
			)
			(layer "B.Fab")
		)
		(fp_line
			(start -0.8636 -0.4572)
			(end -0.8636 -0.4064)
			(stroke
				(width 0.1)
				(type default)
			)
			(layer "B.Fab")
		)
		(fp_line
			(start 1.1938 -0.4064)
			(end 0.8636 -0.4064)
			(stroke
				(width 0.1)
				(type default)
			)
			(layer "B.Fab")
		)
		(fp_line
			(start 0.8636 -0.4064)
			(end 0.8636 -0.4572)
			(stroke
				(width 0.1)
				(type default)
			)
			(layer "B.Fab")
		)
		(fp_line
			(start -0.8636 -0.4064)
			(end -1.1938 -0.4064)
			(stroke
				(width 0.1)
				(type default)
			)
			(layer "B.Fab")
		)
		(fp_line
			(start -1.1938 -0.4064)
			(end -1.1938 0.4064)
			(stroke
				(width 0.1)
				(type default)
			)
			(layer "B.Fab")
		)
		(fp_line
			(start 1.1938 0.4064)
			(end 1.1938 -0.4064)
			(stroke
				(width 0.1)
				(type default)
			)
			(layer "B.Fab")
		)
		(fp_line
			(start 0.8636 0.4064)
			(end 1.1938 0.4064)
			(stroke
				(width 0.1)
				(type default)
			)
			(layer "B.Fab")
		)
		(fp_line
			(start -0.8636 0.4064)
			(end -0.8636 0.4572)
			(stroke
				(width 0.1)
				(type default)
			)
			(layer "B.Fab")
		)
		(fp_line
			(start -1.1938 0.4064)
			(end -0.8636 0.4064)
			(stroke
				(width 0.1)
				(type default)
			)
			(layer "B.Fab")
		)
		(fp_line
			(start 0.8636 0.4572)
			(end 0.8636 0.4064)
			(stroke
				(width 0.1)
				(type default)
			)
			(layer "B.Fab")
		)
		(fp_line
			(start -0.8636 0.4572)
			(end 0.8636 0.4572)
			(stroke
				(width 0.1)
				(type default)
			)
			(layer "B.Fab")
		)
		(pad "1" smd rect
			(at 0.7366 0)
			(size 0.7112 0.8128)
			(layers "B.Cu" "B.Mask" "B.Paste")
			(net "P0V8_PEX3")
		)
		(pad "2" smd rect
			(at -0.7366 0)
			(size 0.7112 0.8128)
			(layers "B.Cu" "B.Mask" "B.Paste")
			(net "GND")
		)
	)
	(footprint ""
		(layer "B.Cu")
		(at 217.647012 -279.586436)
		(property "Reference" "C4290"
			(at 0 0 0)
			(layer "B.SilkS")
			(hide yes)
			(effects
				(font
					(size 1.27 1.27)
				)
				(justify mirror)
			)
		)
		(property "Value" ""
			(at 0 0 0)
			(layer "B.Fab")
			(effects
				(font
					(size 1.27 1.27)
				)
				(justify mirror)
			)
		)
		(duplicate_pad_numbers_are_jumpers no)
		(fp_line
			(start -1.2954 -0.5842)
			(end -1.2954 0.5842)
			(stroke
				(width 0.1524)
				(type default)
			)
			(layer "B.SilkS")
		)
		(fp_line
			(start -1.2954 0.5842)
			(end 1.2954 0.5842)
			(stroke
				(width 0.1524)
				(type default)
			)
			(layer "B.SilkS")
		)
		(fp_line
			(start 1.2954 -0.5842)
			(end -1.2954 -0.5842)
			(stroke
				(width 0.1524)
				(type default)
			)
			(layer "B.SilkS")
		)
		(fp_line
			(start 1.2954 0.5842)
			(end 1.2954 -0.5842)
			(stroke
				(width 0.1524)
				(type default)
			)
			(layer "B.SilkS")
		)
		(fp_line
			(start -1.1938 -0.4064)
			(end -1.1938 0.4064)
			(stroke
				(width 0.1)
				(type default)
			)
			(layer "B.Fab")
		)
		(fp_line
			(start -1.1938 0.4064)
			(end -0.8636 0.4064)
			(stroke
				(width 0.1)
				(type default)
			)
			(layer "B.Fab")
		)
		(fp_line
			(start -0.8636 -0.4572)
			(end -0.8636 -0.4064)
			(stroke
				(width 0.1)
				(type default)
			)
			(layer "B.Fab")
		)
		(fp_line
			(start -0.8636 -0.4064)
			(end -1.1938 -0.4064)
			(stroke
				(width 0.1)
				(type default)
			)
			(layer "B.Fab")
		)
		(fp_line
			(start -0.8636 0.4064)
			(end -0.8636 0.4572)
			(stroke
				(width 0.1)
				(type default)
			)
			(layer "B.Fab")
		)
		(fp_line
			(start -0.8636 0.4572)
			(end 0.8636 0.4572)
			(stroke
				(width 0.1)
				(type default)
			)
			(layer "B.Fab")
		)
		(fp_line
			(start 0.8636 -0.4572)
			(end -0.8636 -0.4572)
			(stroke
				(width 0.1)
				(type default)
			)
			(layer "B.Fab")
		)
		(fp_line
			(start 0.8636 -0.4064)
			(end 0.8636 -0.4572)
			(stroke
				(width 0.1)
				(type default)
			)
			(layer "B.Fab")
		)
		(fp_line
			(start 0.8636 0.4064)
			(end 1.1938 0.4064)
			(stroke
				(width 0.1)
				(type default)
			)
			(layer "B.Fab")
		)
		(fp_line
			(start 0.8636 0.4572)
			(end 0.8636 0.4064)
			(stroke
				(width 0.1)
				(type default)
			)
			(layer "B.Fab")
		)
		(fp_line
			(start 1.1938 -0.4064)
			(end 0.8636 -0.4064)
			(stroke
				(width 0.1)
				(type default)
			)
			(layer "B.Fab")
		)
		(fp_line
			(start 1.1938 0.4064)
			(end 1.1938 -0.4064)
			(stroke
				(width 0.1)
				(type default)
			)
			(layer "B.Fab")
		)
		(pad "1" smd rect
			(at 0.7366 0 270)
			(size 0.7112 0.8128)
			(layers "B.Cu" "B.Mask" "B.Paste")
			(net "P1V25_PEX1")
		)
		(pad "2" smd rect
			(at -0.7366 0 270)
			(size 0.7112 0.8128)
			(layers "B.Cu" "B.Mask" "B.Paste")
			(net "GND")
		)
	)
	(footprint ""
		(layer "B.Cu")
		(at 345.293442 -221.986856 90)
		(property "Reference" "C2048"
			(at 0 0 90)
			(layer "B.SilkS")
			(hide yes)
			(effects
				(font
					(size 1.27 1.27)
				)
				(justify mirror)
			)
		)
		(property "Value" ""
			(at 0 0 90)
			(layer "B.Fab")
			(effects
				(font
					(size 1.27 1.27)
				)
				(justify mirror)
			)
		)
		(duplicate_pad_numbers_are_jumpers no)
		(fp_line
			(start 0.69215 -0.2921)
			(end -0.69215 -0.2921)
			(stroke
				(width 0.1524)
				(type default)
			)
			(layer "B.SilkS")
		)
		(fp_line
			(start -0.69215 -0.2921)
			(end -0.69215 0.2921)
			(stroke
				(width 0.1524)
				(type default)
			)
			(layer "B.SilkS")
		)
		(fp_line
			(start 0.69215 0.2921)
			(end 0.69215 -0.2921)
			(stroke
				(width 0.1524)
				(type default)
			)
			(layer "B.SilkS")
		)
		(fp_line
			(start -0.69215 0.2921)
			(end 0.69215 0.2921)
			(stroke
				(width 0.1524)
				(type default)
			)
			(layer "B.SilkS")
		)
		(fp_line
			(start 0.51435 -0.2794)
			(end -0.51435 -0.2794)
			(stroke
				(width 0.1)
				(type default)
			)
			(layer "B.Fab")
		)
		(fp_line
			(start -0.51435 -0.2794)
			(end -0.51435 0.2794)
			(stroke
				(width 0.1)
				(type default)
			)
			(layer "B.Fab")
		)
		(fp_line
			(start 0.51435 0.2794)
			(end 0.51435 -0.2794)
			(stroke
				(width 0.1)
				(type default)
			)
			(layer "B.Fab")
		)
		(fp_line
			(start -0.51435 0.2794)
			(end 0.51435 0.2794)
			(stroke
				(width 0.1)
				(type default)
			)
			(layer "B.Fab")
		)
		(pad "1" smd circle
			(at 0.40005 0 270)
			(size 0 0)
			(layers "B.Cu" "B.Mask" "B.Paste")
			(net "P3V3_FPGA_VCCIO1")
		)
		(pad "2" smd circle
			(at -0.40005 0 270)
			(size 0 0)
			(layers "B.Cu" "B.Mask" "B.Paste")
			(net "GND")
		)
		(zone
			(layer "B.Cu")
			(hatch none 0.5)
			(connect_pads
				(clearance 0)
			)
			(min_thickness 0.25)
			(keepout
				(tracks not_allowed)
				(vias allowed)
				(pads allowed)
				(copperpour not_allowed)
				(footprints allowed)
			)
			(placement
				(enabled no)
				(sheetname "")
			)
			(fill
				(thermal_gap 0.5)
				(thermal_bridge_width 0.5)
				(island_removal_mode 0)
			)
			(polygon
				(pts
					(xy 345.381072 -222.177356) (xy 345.439238 -222.085916) (xy 345.439238 -221.886526) (xy 345.381072 -221.796356)
					(xy 345.205812 -221.796356) (xy 345.147392 -221.886526) (xy 345.147392 -222.085916) (xy 345.205558 -222.177356)
				)
			)
		)
	)
	(footprint ""
		(layer "B.Cu")
		(at 359.812082 -308.613556 90)
		(property "Reference" "C4374"
			(at 0 0 90)
			(layer "B.SilkS")
			(hide yes)
			(effects
				(font
					(size 1.27 1.27)
				)
				(justify mirror)
			)
		)
		(property "Value" ""
			(at 0 0 90)
			(layer "B.Fab")
			(effects
				(font
					(size 1.27 1.27)
				)
				(justify mirror)
			)
		)
		(duplicate_pad_numbers_are_jumpers no)
		(fp_line
			(start 1.2954 -0.5842)
			(end -1.2954 -0.5842)
			(stroke
				(width 0.1524)
				(type default)
			)
			(layer "B.SilkS")
		)
		(fp_line
			(start -1.2954 -0.5842)
			(end -1.2954 0.5842)
			(stroke
				(width 0.1524)
				(type default)
			)
			(layer "B.SilkS")
		)
		(fp_line
			(start 1.2954 0.5842)
			(end 1.2954 -0.5842)
			(stroke
				(width 0.1524)
				(type default)
			)
			(layer "B.SilkS")
		)
		(fp_line
			(start -1.2954 0.5842)
			(end 1.2954 0.5842)
			(stroke
				(width 0.1524)
				(type default)
			)
			(layer "B.SilkS")
		)
		(fp_line
			(start 0.8636 -0.4572)
			(end -0.8636 -0.4572)
			(stroke
				(width 0.1)
				(type default)
			)
			(layer "B.Fab")
		)
		(fp_line
			(start -0.8636 -0.4572)
			(end -0.8636 -0.4064)
			(stroke
				(width 0.1)
				(type default)
			)
			(layer "B.Fab")
		)
		(fp_line
			(start 1.1938 -0.4064)
			(end 0.8636 -0.4064)
			(stroke
				(width 0.1)
				(type default)
			)
			(layer "B.Fab")
		)
		(fp_line
			(start 0.8636 -0.4064)
			(end 0.8636 -0.4572)
			(stroke
				(width 0.1)
				(type default)
			)
			(layer "B.Fab")
		)
		(fp_line
			(start -0.8636 -0.4064)
			(end -1.1938 -0.4064)
			(stroke
				(width 0.1)
				(type default)
			)
			(layer "B.Fab")
		)
		(fp_line
			(start -1.1938 -0.4064)
			(end -1.1938 0.4064)
			(stroke
				(width 0.1)
				(type default)
			)
			(layer "B.Fab")
		)
		(fp_line
			(start 1.1938 0.4064)
			(end 1.1938 -0.4064)
			(stroke
				(width 0.1)
				(type default)
			)
			(layer "B.Fab")
		)
		(fp_line
			(start 0.8636 0.4064)
			(end 1.1938 0.4064)
			(stroke
				(width 0.1)
				(type default)
			)
			(layer "B.Fab")
		)
		(fp_line
			(start -0.8636 0.4064)
			(end -0.8636 0.4572)
			(stroke
				(width 0.1)
				(type default)
			)
			(layer "B.Fab")
		)
		(fp_line
			(start -1.1938 0.4064)
			(end -0.8636 0.4064)
			(stroke
				(width 0.1)
				(type default)
			)
			(layer "B.Fab")
		)
		(fp_line
			(start 0.8636 0.4572)
			(end 0.8636 0.4064)
			(stroke
				(width 0.1)
				(type default)
			)
			(layer "B.Fab")
		)
		(fp_line
			(start -0.8636 0.4572)
			(end 0.8636 0.4572)
			(stroke
				(width 0.1)
				(type default)
			)
			(layer "B.Fab")
		)
		(pad "1" smd rect
			(at 0.7366 0)
			(size 0.7112 0.8128)
			(layers "B.Cu" "B.Mask" "B.Paste")
			(net "P0V8_PEX3")
		)
		(pad "2" smd rect
			(at -0.7366 0)
			(size 0.7112 0.8128)
			(layers "B.Cu" "B.Mask" "B.Paste")
			(net "GND")
		)
	)
	(footprint ""
		(layer "B.Cu")
		(at 116.612416 -137.53846 90)
		(property "Reference" "PC32"
			(at 0 0 90)
			(layer "B.SilkS")
			(hide yes)
			(effects
				(font
					(size 1.27 1.27)
				)
				(justify mirror)
			)
		)
		(property "Value" ""
			(at 0 0 90)
			(layer "B.Fab")
			(effects
				(font
					(size 1.27 1.27)
				)
				(justify mirror)
			)
		)
		(duplicate_pad_numbers_are_jumpers no)
		(fp_line
			(start 1.524 -0.762)
			(end -1.524 -0.762)
			(stroke
				(width 0.1524)
				(type default)
			)
			(layer "B.SilkS")
		)
		(fp_line
			(start -1.524 -0.762)
			(end -1.524 0.762)
			(stroke
				(width 0.1524)
				(type default)
			)
			(layer "B.SilkS")
		)
		(fp_line
			(start 1.524 0.762)
			(end 1.524 -0.762)
			(stroke
				(width 0.1524)
				(type default)
			)
			(layer "B.SilkS")
		)
		(fp_line
			(start -1.524 0.762)
			(end 1.524 0.762)
			(stroke
				(width 0.1524)
				(type default)
			)
			(layer "B.SilkS")
		)
		(fp_line
			(start 1.1049 -0.724916)
			(end 1.1049 0.724916)
			(stroke
				(width 0.1)
				(type default)
			)
			(layer "B.Fab")
		)
		(fp_line
			(start -1.1049 -0.724916)
			(end 1.1049 -0.724916)
			(stroke
				(width 0.1)
				(type default)
			)
			(layer "B.Fab")
		)
		(fp_line
			(start 1.1049 0.724916)
			(end -1.1049 0.724916)
			(stroke
				(width 0.1)
				(type default)
			)
			(layer "B.Fab")
		)
		(fp_line
			(start -1.1049 0.724916)
			(end -1.1049 -0.724916)
			(stroke
				(width 0.1)
				(type default)
			)
			(layer "B.Fab")
		)
		(pad "1" smd rect
			(at 0.889 0 90)
			(size 1.016 1.27)
			(layers "B.Cu" "B.Mask" "B.Paste")
			(net "P3V3_AUX")
		)
		(pad "2" smd rect
			(at -0.889 0 90)
			(size 1.016 1.27)
			(layers "B.Cu" "B.Mask" "B.Paste")
			(net "GND")
		)
	)
	(footprint ""
		(layer "B.Cu")
		(at 403.245574 -296.37482)
		(property "Reference" "C1896"
			(at 0 0 0)
			(layer "B.SilkS")
			(hide yes)
			(effects
				(font
					(size 1.27 1.27)
				)
				(justify mirror)
			)
		)
		(property "Value" ""
			(at 0 0 0)
			(layer "B.Fab")
			(effects
				(font
					(size 1.27 1.27)
				)
				(justify mirror)
			)
		)
		(duplicate_pad_numbers_are_jumpers no)
		(fp_line
			(start -0.299974 -0.150114)
			(end -0.299974 0.150114)
			(stroke
				(width 0.1)
				(type default)
			)
			(layer "B.Fab")
		)
		(fp_line
			(start -0.299974 0.150114)
			(end 0.299974 0.150114)
			(stroke
				(width 0.1)
				(type default)
			)
			(layer "B.Fab")
		)
		(fp_line
			(start 0.299974 -0.150114)
			(end -0.299974 -0.150114)
			(stroke
				(width 0.1)
				(type default)
			)
			(layer "B.Fab")
		)
		(fp_line
			(start 0.299974 0.150114)
			(end 0.299974 -0.150114)
			(stroke
				(width 0.1)
				(type default)
			)
			(layer "B.Fab")
		)
		(pad "1" smd rect
			(at 0.2667 0 180)
			(size 0.3048 0.381)
			(layers "B.Cu" "B.Mask" "B.Paste")
			(net "P0V8_PEX3")
		)
		(pad "2" smd rect
			(at -0.2667 0 180)
			(size 0.3048 0.381)
			(layers "B.Cu" "B.Mask" "B.Paste")
			(net "GND")
		)
	)
	(footprint ""
		(layer "B.Cu")
		(at 343.154 -207.772 90)
		(property "Reference" "R4142"
			(at 0 0 90)
			(layer "B.SilkS")
			(hide yes)
			(effects
				(font
					(size 1.27 1.27)
				)
				(justify mirror)
			)
		)
		(property "Value" ""
			(at 0 0 90)
			(layer "B.Fab")
			(effects
				(font
					(size 1.27 1.27)
				)
				(justify mirror)
			)
		)
		(duplicate_pad_numbers_are_jumpers no)
		(fp_line
			(start 0.7874 -0.4064)
			(end -0.7874 -0.4064)
			(stroke
				(width 0.1524)
				(type default)
			)
			(layer "B.SilkS")
		)
		(fp_line
			(start -0.7874 -0.4064)
			(end -0.7874 0.4064)
			(stroke
				(width 0.1524)
				(type default)
			)
			(layer "B.SilkS")
		)
		(fp_line
			(start 0.7874 0.4064)
			(end 0.7874 -0.4064)
			(stroke
				(width 0.1524)
				(type default)
			)
			(layer "B.SilkS")
		)
		(fp_line
			(start -0.7874 0.4064)
			(end 0.7874 0.4064)
			(stroke
				(width 0.1524)
				(type default)
			)
			(layer "B.SilkS")
		)
		(fp_line
			(start 0.67945 -0.305054)
			(end 0.12065 -0.305054)
			(stroke
				(width 0.1)
				(type default)
			)
			(layer "B.Fab")
		)
		(fp_line
			(start 0.12065 -0.305054)
			(end 0.12065 -0.2794)
			(stroke
				(width 0.1)
				(type default)
			)
			(layer "B.Fab")
		)
		(fp_line
			(start -0.12065 -0.3048)
			(end -0.67945 -0.3048)
			(stroke
				(width 0.1)
				(type default)
			)
			(layer "B.Fab")
		)
		(fp_line
			(start -0.67945 -0.3048)
			(end -0.67945 0.3048)
			(stroke
				(width 0.1)
				(type default)
			)
			(layer "B.Fab")
		)
		(fp_line
			(start 0.12065 -0.2794)
			(end -0.12065 -0.2794)
			(stroke
				(width 0.1)
				(type default)
			)
			(layer "B.Fab")
		)
		(fp_line
			(start -0.12065 -0.2794)
			(end -0.12065 -0.3048)
			(stroke
				(width 0.1)
				(type default)
			)
			(layer "B.Fab")
		)
		(fp_line
			(start 0.12065 0.2794)
			(end 0.12065 0.3048)
			(stroke
				(width 0.1)
				(type default)
			)
			(layer "B.Fab")
		)
		(fp_line
			(start -0.120396 0.2794)
			(end 0.12065 0.2794)
			(stroke
				(width 0.1)
				(type default)
			)
			(layer "B.Fab")
		)
		(fp_line
			(start 0.67945 0.3048)
			(end 0.67945 -0.305054)
			(stroke
				(width 0.1)
				(type default)
			)
			(layer "B.Fab")
		)
		(fp_line
			(start 0.12065 0.3048)
			(end 0.67945 0.3048)
			(stroke
				(width 0.1)
				(type default)
			)
			(layer "B.Fab")
		)
		(fp_line
			(start -0.120396 0.3048)
			(end -0.120396 0.2794)
			(stroke
				(width 0.1)
				(type default)
			)
			(layer "B.Fab")
		)
		(fp_line
			(start -0.67945 0.3048)
			(end -0.120396 0.3048)
			(stroke
				(width 0.1)
				(type default)
			)
			(layer "B.Fab")
		)
		(pad "1" smd circle
			(at 0.40005 0 270)
			(size 0 0)
			(layers "B.Cu" "B.Mask" "B.Paste")
			(net "SSD14_CLK_EN_N")
		)
		(pad "2" smd circle
			(at -0.40005 0 270)
			(size 0 0)
			(layers "B.Cu" "B.Mask" "B.Paste")
			(net "SSD14_CLK_EN_R_N")
		)
	)
	(footprint ""
		(layer "B.Cu")
		(at 285.674816 -286.399732 90)
		(property "Reference" "C3334"
			(at 0 0 90)
			(layer "B.SilkS")
			(hide yes)
			(effects
				(font
					(size 1.27 1.27)
				)
				(justify mirror)
			)
		)
		(property "Value" ""
			(at 0 0 90)
			(layer "B.Fab")
			(effects
				(font
					(size 1.27 1.27)
				)
				(justify mirror)
			)
		)
		(duplicate_pad_numbers_are_jumpers no)
		(fp_line
			(start 0.299974 -0.150114)
			(end -0.299974 -0.150114)
			(stroke
				(width 0.1)
				(type default)
			)
			(layer "B.Fab")
		)
		(fp_line
			(start -0.299974 -0.150114)
			(end -0.299974 0.150114)
			(stroke
				(width 0.1)
				(type default)
			)
			(layer "B.Fab")
		)
		(fp_line
			(start 0.299974 0.150114)
			(end 0.299974 -0.150114)
			(stroke
				(width 0.1)
				(type default)
			)
			(layer "B.Fab")
		)
		(fp_line
			(start -0.299974 0.150114)
			(end 0.299974 0.150114)
			(stroke
				(width 0.1)
				(type default)
			)
			(layer "B.Fab")
		)
		(pad "1" smd rect
			(at 0.2667 0 270)
			(size 0.3048 0.381)
			(layers "B.Cu" "B.Mask" "B.Paste")
			(net "P1V25_SERDES_VDDPLL_PEX2")
		)
		(pad "2" smd rect
			(at -0.2667 0 270)
			(size 0.3048 0.381)
			(layers "B.Cu" "B.Mask" "B.Paste")
			(net "GND")
		)
	)
	(footprint ""
		(layer "B.Cu")
		(at 102.027736 -275.813774)
		(property "Reference" "PC6608"
			(at 0 0 0)
			(layer "B.SilkS")
			(hide yes)
			(effects
				(font
					(size 1.27 1.27)
				)
				(justify mirror)
			)
		)
		(property "Value" ""
			(at 0 0 0)
			(layer "B.Fab")
			(effects
				(font
					(size 1.27 1.27)
				)
				(justify mirror)
			)
		)
		(duplicate_pad_numbers_are_jumpers no)
		(fp_line
			(start -1.524 -0.762)
			(end -1.524 0.762)
			(stroke
				(width 0.1524)
				(type default)
			)
			(layer "B.SilkS")
		)
		(fp_line
			(start -1.524 0.762)
			(end 1.524 0.762)
			(stroke
				(width 0.1524)
				(type default)
			)
			(layer "B.SilkS")
		)
		(fp_line
			(start 1.524 -0.762)
			(end -1.524 -0.762)
			(stroke
				(width 0.1524)
				(type default)
			)
			(layer "B.SilkS")
		)
		(fp_line
			(start 1.524 0.762)
			(end 1.524 -0.762)
			(stroke
				(width 0.1524)
				(type default)
			)
			(layer "B.SilkS")
		)
		(fp_line
			(start -1.1049 -0.724916)
			(end 1.1049 -0.724916)
			(stroke
				(width 0.1)
				(type default)
			)
			(layer "B.Fab")
		)
		(fp_line
			(start -1.1049 0.724916)
			(end -1.1049 -0.724916)
			(stroke
				(width 0.1)
				(type default)
			)
			(layer "B.Fab")
		)
		(fp_line
			(start 1.1049 -0.724916)
			(end 1.1049 0.724916)
			(stroke
				(width 0.1)
				(type default)
			)
			(layer "B.Fab")
		)
		(fp_line
			(start 1.1049 0.724916)
			(end -1.1049 0.724916)
			(stroke
				(width 0.1)
				(type default)
			)
			(layer "B.Fab")
		)
		(pad "1" smd rect
			(at 0.889 0)
			(size 1.016 1.27)
			(layers "B.Cu" "B.Mask" "B.Paste")
			(net "SW_P12V_P0V8_PEX0_FLT")
		)
		(pad "2" smd rect
			(at -0.889 0)
			(size 1.016 1.27)
			(layers "B.Cu" "B.Mask" "B.Paste")
			(net "GND")
		)
	)
	(footprint ""
		(layer "B.Cu")
		(at 399.874994 -297.79976 90)
		(property "Reference" "C1904"
			(at 0 0 90)
			(layer "B.SilkS")
			(hide yes)
			(effects
				(font
					(size 1.27 1.27)
				)
				(justify mirror)
			)
		)
		(property "Value" ""
			(at 0 0 90)
			(layer "B.Fab")
			(effects
				(font
					(size 1.27 1.27)
				)
				(justify mirror)
			)
		)
		(duplicate_pad_numbers_are_jumpers no)
		(fp_line
			(start 0.299974 -0.150114)
			(end -0.299974 -0.150114)
			(stroke
				(width 0.1)
				(type default)
			)
			(layer "B.Fab")
		)
		(fp_line
			(start -0.299974 -0.150114)
			(end -0.299974 0.150114)
			(stroke
				(width 0.1)
				(type default)
			)
			(layer "B.Fab")
		)
		(fp_line
			(start 0.299974 0.150114)
			(end 0.299974 -0.150114)
			(stroke
				(width 0.1)
				(type default)
			)
			(layer "B.Fab")
		)
		(fp_line
			(start -0.299974 0.150114)
			(end 0.299974 0.150114)
			(stroke
				(width 0.1)
				(type default)
			)
			(layer "B.Fab")
		)
		(pad "1" smd rect
			(at 0.2667 0 270)
			(size 0.3048 0.381)
			(layers "B.Cu" "B.Mask" "B.Paste")
			(net "P0V8_PEX3")
		)
		(pad "2" smd rect
			(at -0.2667 0 270)
			(size 0.3048 0.381)
			(layers "B.Cu" "B.Mask" "B.Paste")
			(net "GND")
		)
	)
	(footprint ""
		(layer "B.Cu")
		(at 309.741824 -102.088696 180)
		(property "Reference" "R272"
			(at 0 0 0)
			(layer "B.SilkS")
			(hide yes)
			(effects
				(font
					(size 1.27 1.27)
				)
				(justify mirror)
			)
		)
		(property "Value" ""
			(at 0 0 0)
			(layer "B.Fab")
			(effects
				(font
					(size 1.27 1.27)
				)
				(justify mirror)
			)
		)
		(duplicate_pad_numbers_are_jumpers no)
		(fp_line
			(start 0.7874 0.4064)
			(end 0.7874 -0.4064)
			(stroke
				(width 0.1524)
				(type default)
			)
			(layer "B.SilkS")
		)
		(fp_line
			(start 0.7874 -0.4064)
			(end -0.7874 -0.4064)
			(stroke
				(width 0.1524)
				(type default)
			)
			(layer "B.SilkS")
		)
		(fp_line
			(start -0.7874 0.4064)
			(end 0.7874 0.4064)
			(stroke
				(width 0.1524)
				(type default)
			)
			(layer "B.SilkS")
		)
		(fp_line
			(start -0.7874 -0.4064)
			(end -0.7874 0.4064)
			(stroke
				(width 0.1524)
				(type default)
			)
			(layer "B.SilkS")
		)
		(fp_line
			(start 0.67945 0.3048)
			(end 0.67945 -0.305054)
			(stroke
				(width 0.1)
				(type default)
			)
			(layer "B.Fab")
		)
		(fp_line
			(start 0.67945 -0.305054)
			(end 0.12065 -0.305054)
			(stroke
				(width 0.1)
				(type default)
			)
			(layer "B.Fab")
		)
		(fp_line
			(start 0.12065 0.3048)
			(end 0.67945 0.3048)
			(stroke
				(width 0.1)
				(type default)
			)
			(layer "B.Fab")
		)
		(fp_line
			(start 0.12065 0.2794)
			(end 0.12065 0.3048)
			(stroke
				(width 0.1)
				(type default)
			)
			(layer "B.Fab")
		)
		(fp_line
			(start 0.12065 -0.2794)
			(end -0.12065 -0.2794)
			(stroke
				(width 0.1)
				(type default)
			)
			(layer "B.Fab")
		)
		(fp_line
			(start 0.12065 -0.305054)
			(end 0.12065 -0.2794)
			(stroke
				(width 0.1)
				(type default)
			)
			(layer "B.Fab")
		)
		(fp_line
			(start -0.120396 0.3048)
			(end -0.120396 0.2794)
			(stroke
				(width 0.1)
				(type default)
			)
			(layer "B.Fab")
		)
		(fp_line
			(start -0.120396 0.2794)
			(end 0.12065 0.2794)
			(stroke
				(width 0.1)
				(type default)
			)
			(layer "B.Fab")
		)
		(fp_line
			(start -0.12065 -0.2794)
			(end -0.12065 -0.3048)
			(stroke
				(width 0.1)
				(type default)
			)
			(layer "B.Fab")
		)
		(fp_line
			(start -0.12065 -0.3048)
			(end -0.67945 -0.3048)
			(stroke
				(width 0.1)
				(type default)
			)
			(layer "B.Fab")
		)
		(fp_line
			(start -0.67945 0.3048)
			(end -0.120396 0.3048)
			(stroke
				(width 0.1)
				(type default)
			)
			(layer "B.Fab")
		)
		(fp_line
			(start -0.67945 -0.3048)
			(end -0.67945 0.3048)
			(stroke
				(width 0.1)
				(type default)
			)
			(layer "B.Fab")
		)
		(pad "1" smd circle
			(at 0.40005 0)
			(size 0 0)
			(layers "B.Cu" "B.Mask" "B.Paste")
			(net "NCSI_NIC5_RXD1")
		)
		(pad "2" smd circle
			(at -0.40005 0)
			(size 0 0)
			(layers "B.Cu" "B.Mask" "B.Paste")
			(net "GND")
		)
	)
	(footprint ""
		(layer "B.Cu")
		(at 190.126874 -301.124874 -90)
		(property "Reference" "R1311"
			(at 0 0 90)
			(layer "B.SilkS")
			(hide yes)
			(effects
				(font
					(size 1.27 1.27)
				)
				(justify mirror)
			)
		)
		(property "Value" ""
			(at 0 0 90)
			(layer "B.Fab")
			(effects
				(font
					(size 1.27 1.27)
				)
				(justify mirror)
			)
		)
		(duplicate_pad_numbers_are_jumpers no)
		(fp_line
			(start -0.7874 0.4064)
			(end 0.7874 0.4064)
			(stroke
				(width 0.1524)
				(type default)
			)
			(layer "B.SilkS")
		)
		(fp_line
			(start 0.7874 0.4064)
			(end 0.7874 -0.4064)
			(stroke
				(width 0.1524)
				(type default)
			)
			(layer "B.SilkS")
		)
		(fp_line
			(start -0.7874 -0.4064)
			(end -0.7874 0.4064)
			(stroke
				(width 0.1524)
				(type default)
			)
			(layer "B.SilkS")
		)
		(fp_line
			(start 0.7874 -0.4064)
			(end -0.7874 -0.4064)
			(stroke
				(width 0.1524)
				(type default)
			)
			(layer "B.SilkS")
		)
		(fp_line
			(start -0.67945 0.3048)
			(end -0.120396 0.3048)
			(stroke
				(width 0.1)
				(type default)
			)
			(layer "B.Fab")
		)
		(fp_line
			(start -0.120396 0.3048)
			(end -0.120396 0.2794)
			(stroke
				(width 0.1)
				(type default)
			)
			(layer "B.Fab")
		)
		(fp_line
			(start 0.12065 0.3048)
			(end 0.67945 0.3048)
			(stroke
				(width 0.1)
				(type default)
			)
			(layer "B.Fab")
		)
		(fp_line
			(start 0.67945 0.3048)
			(end 0.67945 -0.305054)
			(stroke
				(width 0.1)
				(type default)
			)
			(layer "B.Fab")
		)
		(fp_line
			(start -0.120396 0.2794)
			(end 0.12065 0.2794)
			(stroke
				(width 0.1)
				(type default)
			)
			(layer "B.Fab")
		)
		(fp_line
			(start 0.12065 0.2794)
			(end 0.12065 0.3048)
			(stroke
				(width 0.1)
				(type default)
			)
			(layer "B.Fab")
		)
		(fp_line
			(start -0.12065 -0.2794)
			(end -0.12065 -0.3048)
			(stroke
				(width 0.1)
				(type default)
			)
			(layer "B.Fab")
		)
		(fp_line
			(start 0.12065 -0.2794)
			(end -0.12065 -0.2794)
			(stroke
				(width 0.1)
				(type default)
			)
			(layer "B.Fab")
		)
		(fp_line
			(start -0.67945 -0.3048)
			(end -0.67945 0.3048)
			(stroke
				(width 0.1)
				(type default)
			)
			(layer "B.Fab")
		)
		(fp_line
			(start -0.12065 -0.3048)
			(end -0.67945 -0.3048)
			(stroke
				(width 0.1)
				(type default)
			)
			(layer "B.Fab")
		)
		(fp_line
			(start 0.12065 -0.305054)
			(end 0.12065 -0.2794)
			(stroke
				(width 0.1)
				(type default)
			)
			(layer "B.Fab")
		)
		(fp_line
			(start 0.67945 -0.305054)
			(end 0.12065 -0.305054)
			(stroke
				(width 0.1)
				(type default)
			)
			(layer "B.Fab")
		)
		(pad "1" smd circle
			(at 0.40005 0 90)
			(size 0 0)
			(layers "B.Cu" "B.Mask" "B.Paste")
			(net "PEX1_ADCTEMP_VINP0")
		)
		(pad "2" smd circle
			(at -0.40005 0 90)
			(size 0 0)
			(layers "B.Cu" "B.Mask" "B.Paste")
			(net "GND")
		)
	)
	(footprint ""
		(layer "B.Cu")
		(at 278.554942 -292.57498)
		(property "Reference" "C3404"
			(at 0 0 0)
			(layer "B.SilkS")
			(hide yes)
			(effects
				(font
					(size 1.27 1.27)
				)
				(justify mirror)
			)
		)
		(property "Value" ""
			(at 0 0 0)
			(layer "B.Fab")
			(effects
				(font
					(size 1.27 1.27)
				)
				(justify mirror)
			)
		)
		(duplicate_pad_numbers_are_jumpers no)
		(fp_line
			(start -0.299974 -0.150114)
			(end -0.299974 0.150114)
			(stroke
				(width 0.1)
				(type default)
			)
			(layer "B.Fab")
		)
		(fp_line
			(start -0.299974 0.150114)
			(end 0.299974 0.150114)
			(stroke
				(width 0.1)
				(type default)
			)
			(layer "B.Fab")
		)
		(fp_line
			(start 0.299974 -0.150114)
			(end -0.299974 -0.150114)
			(stroke
				(width 0.1)
				(type default)
			)
			(layer "B.Fab")
		)
		(fp_line
			(start 0.299974 0.150114)
			(end 0.299974 -0.150114)
			(stroke
				(width 0.1)
				(type default)
			)
			(layer "B.Fab")
		)
		(pad "1" smd rect
			(at 0.2667 0 180)
			(size 0.3048 0.381)
			(layers "B.Cu" "B.Mask" "B.Paste")
			(net "PCEPLL6_VDDA18_PEX2")
		)
		(pad "2" smd rect
			(at -0.2667 0 180)
			(size 0.3048 0.381)
			(layers "B.Cu" "B.Mask" "B.Paste")
			(net "GND")
		)
	)
	(footprint ""
		(layer "B.Cu")
		(at 340.923372 -285.569152 -90)
		(property "Reference" "PR7180"
			(at 0 0 90)
			(layer "B.SilkS")
			(hide yes)
			(effects
				(font
					(size 1.27 1.27)
				)
				(justify mirror)
			)
		)
		(property "Value" ""
			(at 0 0 90)
			(layer "B.Fab")
			(effects
				(font
					(size 1.27 1.27)
				)
				(justify mirror)
			)
		)
		(duplicate_pad_numbers_are_jumpers no)
		(fp_line
			(start -0.7874 0.4064)
			(end 0.7874 0.4064)
			(stroke
				(width 0.1524)
				(type default)
			)
			(layer "B.SilkS")
		)
		(fp_line
			(start 0.7874 0.4064)
			(end 0.7874 -0.4064)
			(stroke
				(width 0.1524)
				(type default)
			)
			(layer "B.SilkS")
		)
		(fp_line
			(start -0.7874 -0.4064)
			(end -0.7874 0.4064)
			(stroke
				(width 0.1524)
				(type default)
			)
			(layer "B.SilkS")
		)
		(fp_line
			(start 0.7874 -0.4064)
			(end -0.7874 -0.4064)
			(stroke
				(width 0.1524)
				(type default)
			)
			(layer "B.SilkS")
		)
		(fp_line
			(start -0.67945 0.3048)
			(end -0.120396 0.3048)
			(stroke
				(width 0.1)
				(type default)
			)
			(layer "B.Fab")
		)
		(fp_line
			(start -0.120396 0.3048)
			(end -0.120396 0.2794)
			(stroke
				(width 0.1)
				(type default)
			)
			(layer "B.Fab")
		)
		(fp_line
			(start 0.12065 0.3048)
			(end 0.67945 0.3048)
			(stroke
				(width 0.1)
				(type default)
			)
			(layer "B.Fab")
		)
		(fp_line
			(start 0.67945 0.3048)
			(end 0.67945 -0.305054)
			(stroke
				(width 0.1)
				(type default)
			)
			(layer "B.Fab")
		)
		(fp_line
			(start -0.120396 0.2794)
			(end 0.12065 0.2794)
			(stroke
				(width 0.1)
				(type default)
			)
			(layer "B.Fab")
		)
		(fp_line
			(start 0.12065 0.2794)
			(end 0.12065 0.3048)
			(stroke
				(width 0.1)
				(type default)
			)
			(layer "B.Fab")
		)
		(fp_line
			(start -0.12065 -0.2794)
			(end -0.12065 -0.3048)
			(stroke
				(width 0.1)
				(type default)
			)
			(layer "B.Fab")
		)
		(fp_line
			(start 0.12065 -0.2794)
			(end -0.12065 -0.2794)
			(stroke
				(width 0.1)
				(type default)
			)
			(layer "B.Fab")
		)
		(fp_line
			(start -0.67945 -0.3048)
			(end -0.67945 0.3048)
			(stroke
				(width 0.1)
				(type default)
			)
			(layer "B.Fab")
		)
		(fp_line
			(start -0.12065 -0.3048)
			(end -0.67945 -0.3048)
			(stroke
				(width 0.1)
				(type default)
			)
			(layer "B.Fab")
		)
		(fp_line
			(start 0.12065 -0.305054)
			(end 0.12065 -0.2794)
			(stroke
				(width 0.1)
				(type default)
			)
			(layer "B.Fab")
		)
		(fp_line
			(start 0.67945 -0.305054)
			(end 0.12065 -0.305054)
			(stroke
				(width 0.1)
				(type default)
			)
			(layer "B.Fab")
		)
		(pad "1" smd circle
			(at 0.40005 0 90)
			(size 0 0)
			(layers "B.Cu" "B.Mask" "B.Paste")
			(net "P0V8_PEX2_PVCC")
		)
		(pad "2" smd circle
			(at -0.40005 0 90)
			(size 0 0)
			(layers "B.Cu" "B.Mask" "B.Paste")
			(net "P5V_AUX")
		)
	)
	(footprint ""
		(layer "B.Cu")
		(at 170.999912 -290.199826 90)
		(property "Reference" "C1453"
			(at 0 0 90)
			(layer "B.SilkS")
			(hide yes)
			(effects
				(font
					(size 1.27 1.27)
				)
				(justify mirror)
			)
		)
		(property "Value" ""
			(at 0 0 90)
			(layer "B.Fab")
			(effects
				(font
					(size 1.27 1.27)
				)
				(justify mirror)
			)
		)
		(duplicate_pad_numbers_are_jumpers no)
		(fp_line
			(start 0.299974 -0.150114)
			(end -0.299974 -0.150114)
			(stroke
				(width 0.1)
				(type default)
			)
			(layer "B.Fab")
		)
		(fp_line
			(start -0.299974 -0.150114)
			(end -0.299974 0.150114)
			(stroke
				(width 0.1)
				(type default)
			)
			(layer "B.Fab")
		)
		(fp_line
			(start 0.299974 0.150114)
			(end 0.299974 -0.150114)
			(stroke
				(width 0.1)
				(type default)
			)
			(layer "B.Fab")
		)
		(fp_line
			(start -0.299974 0.150114)
			(end 0.299974 0.150114)
			(stroke
				(width 0.1)
				(type default)
			)
			(layer "B.Fab")
		)
		(pad "1" smd rect
			(at 0.2667 0 270)
			(size 0.3048 0.381)
			(layers "B.Cu" "B.Mask" "B.Paste")
			(net "P0V8_SERDES_VDDA_PEX1")
		)
		(pad "2" smd rect
			(at -0.2667 0 270)
			(size 0.3048 0.381)
			(layers "B.Cu" "B.Mask" "B.Paste")
			(net "GND")
		)
	)
	(footprint ""
		(layer "B.Cu")
		(at 357.887524 -260.160516)
		(property "Reference" "PR7142"
			(at 0 0 0)
			(layer "B.SilkS")
			(hide yes)
			(effects
				(font
					(size 1.27 1.27)
				)
				(justify mirror)
			)
		)
		(property "Value" ""
			(at 0 0 0)
			(layer "B.Fab")
			(effects
				(font
					(size 1.27 1.27)
				)
				(justify mirror)
			)
		)
		(duplicate_pad_numbers_are_jumpers no)
		(fp_line
			(start -0.7874 -0.4064)
			(end -0.7874 0.4064)
			(stroke
				(width 0.1524)
				(type default)
			)
			(layer "B.SilkS")
		)
		(fp_line
			(start -0.7874 0.4064)
			(end 0.7874 0.4064)
			(stroke
				(width 0.1524)
				(type default)
			)
			(layer "B.SilkS")
		)
		(fp_line
			(start 0.7874 -0.4064)
			(end -0.7874 -0.4064)
			(stroke
				(width 0.1524)
				(type default)
			)
			(layer "B.SilkS")
		)
		(fp_line
			(start 0.7874 0.4064)
			(end 0.7874 -0.4064)
			(stroke
				(width 0.1524)
				(type default)
			)
			(layer "B.SilkS")
		)
		(fp_line
			(start -0.67945 -0.3048)
			(end -0.67945 0.3048)
			(stroke
				(width 0.1)
				(type default)
			)
			(layer "B.Fab")
		)
		(fp_line
			(start -0.67945 0.3048)
			(end -0.120396 0.3048)
			(stroke
				(width 0.1)
				(type default)
			)
			(layer "B.Fab")
		)
		(fp_line
			(start -0.12065 -0.3048)
			(end -0.67945 -0.3048)
			(stroke
				(width 0.1)
				(type default)
			)
			(layer "B.Fab")
		)
		(fp_line
			(start -0.12065 -0.2794)
			(end -0.12065 -0.3048)
			(stroke
				(width 0.1)
				(type default)
			)
			(layer "B.Fab")
		)
		(fp_line
			(start -0.120396 0.2794)
			(end 0.12065 0.2794)
			(stroke
				(width 0.1)
				(type default)
			)
			(layer "B.Fab")
		)
		(fp_line
			(start -0.120396 0.3048)
			(end -0.120396 0.2794)
			(stroke
				(width 0.1)
				(type default)
			)
			(layer "B.Fab")
		)
		(fp_line
			(start 0.12065 -0.305054)
			(end 0.12065 -0.2794)
			(stroke
				(width 0.1)
				(type default)
			)
			(layer "B.Fab")
		)
		(fp_line
			(start 0.12065 -0.2794)
			(end -0.12065 -0.2794)
			(stroke
				(width 0.1)
				(type default)
			)
			(layer "B.Fab")
		)
		(fp_line
			(start 0.12065 0.2794)
			(end 0.12065 0.3048)
			(stroke
				(width 0.1)
				(type default)
			)
			(layer "B.Fab")
		)
		(fp_line
			(start 0.12065 0.3048)
			(end 0.67945 0.3048)
			(stroke
				(width 0.1)
				(type default)
			)
			(layer "B.Fab")
		)
		(fp_line
			(start 0.67945 -0.305054)
			(end 0.12065 -0.305054)
			(stroke
				(width 0.1)
				(type default)
			)
			(layer "B.Fab")
		)
		(fp_line
			(start 0.67945 0.3048)
			(end 0.67945 -0.305054)
			(stroke
				(width 0.1)
				(type default)
			)
			(layer "B.Fab")
		)
		(pad "1" smd circle
			(at 0.40005 0 180)
			(size 0 0)
			(layers "B.Cu" "B.Mask" "B.Paste")
			(net "P0V8_PEX2_VREF")
		)
		(pad "2" smd circle
			(at -0.40005 0 180)
			(size 0 0)
			(layers "B.Cu" "B.Mask" "B.Paste")
			(net "P0V8_PEX2_SVID")
		)
	)
	(footprint ""
		(layer "B.Cu")
		(at 233.467656 -216.704164 180)
		(property "Reference" "C3607"
			(at 0 0 0)
			(layer "B.SilkS")
			(hide yes)
			(effects
				(font
					(size 1.27 1.27)
				)
				(justify mirror)
			)
		)
		(property "Value" ""
			(at 0 0 0)
			(layer "B.Fab")
			(effects
				(font
					(size 1.27 1.27)
				)
				(justify mirror)
			)
		)
		(duplicate_pad_numbers_are_jumpers no)
		(fp_line
			(start 0.69215 0.2921)
			(end 0.69215 -0.2921)
			(stroke
				(width 0.1524)
				(type default)
			)
			(layer "B.SilkS")
		)
		(fp_line
			(start 0.69215 -0.2921)
			(end -0.69215 -0.2921)
			(stroke
				(width 0.1524)
				(type default)
			)
			(layer "B.SilkS")
		)
		(fp_line
			(start -0.69215 0.2921)
			(end 0.69215 0.2921)
			(stroke
				(width 0.1524)
				(type default)
			)
			(layer "B.SilkS")
		)
		(fp_line
			(start -0.69215 -0.2921)
			(end -0.69215 0.2921)
			(stroke
				(width 0.1524)
				(type default)
			)
			(layer "B.SilkS")
		)
		(fp_line
			(start 0.51435 0.2794)
			(end 0.51435 -0.2794)
			(stroke
				(width 0.1)
				(type default)
			)
			(layer "B.Fab")
		)
		(fp_line
			(start 0.51435 -0.2794)
			(end -0.51435 -0.2794)
			(stroke
				(width 0.1)
				(type default)
			)
			(layer "B.Fab")
		)
		(fp_line
			(start -0.51435 0.2794)
			(end 0.51435 0.2794)
			(stroke
				(width 0.1)
				(type default)
			)
			(layer "B.Fab")
		)
		(fp_line
			(start -0.51435 -0.2794)
			(end -0.51435 0.2794)
			(stroke
				(width 0.1)
				(type default)
			)
			(layer "B.Fab")
		)
		(pad "1" smd circle
			(at 0.40005 0)
			(size 0 0)
			(layers "B.Cu" "B.Mask" "B.Paste")
			(net "P3V3_BIC_USB2AV33")
		)
		(pad "2" smd circle
			(at -0.40005 0)
			(size 0 0)
			(layers "B.Cu" "B.Mask" "B.Paste")
			(net "GND")
		)
		(zone
			(layer "B.Cu")
			(hatch none 0.5)
			(connect_pads
				(clearance 0)
			)
			(min_thickness 0.25)
			(keepout
				(tracks not_allowed)
				(vias allowed)
				(pads allowed)
				(copperpour not_allowed)
				(footprints allowed)
			)
			(placement
				(enabled no)
				(sheetname "")
			)
			(fill
				(thermal_gap 0.5)
				(thermal_bridge_width 0.5)
				(island_removal_mode 0)
			)
			(polygon
				(pts
					(xy 233.277156 -216.791794) (xy 233.368596 -216.84996) (xy 233.567986 -216.84996) (xy 233.658156 -216.791794)
					(xy 233.658156 -216.616534) (xy 233.567986 -216.558114) (xy 233.368596 -216.558114) (xy 233.277156 -216.61628)
				)
			)
		)
	)
	(footprint ""
		(layer "B.Cu")
		(at 176.699926 -288.299906 90)
		(property "Reference" "C3107"
			(at 0 0 90)
			(layer "B.SilkS")
			(hide yes)
			(effects
				(font
					(size 1.27 1.27)
				)
				(justify mirror)
			)
		)
		(property "Value" ""
			(at 0 0 90)
			(layer "B.Fab")
			(effects
				(font
					(size 1.27 1.27)
				)
				(justify mirror)
			)
		)
		(duplicate_pad_numbers_are_jumpers no)
		(fp_line
			(start 0.299974 -0.150114)
			(end -0.299974 -0.150114)
			(stroke
				(width 0.1)
				(type default)
			)
			(layer "B.Fab")
		)
		(fp_line
			(start -0.299974 -0.150114)
			(end -0.299974 0.150114)
			(stroke
				(width 0.1)
				(type default)
			)
			(layer "B.Fab")
		)
		(fp_line
			(start 0.299974 0.150114)
			(end 0.299974 -0.150114)
			(stroke
				(width 0.1)
				(type default)
			)
			(layer "B.Fab")
		)
		(fp_line
			(start -0.299974 0.150114)
			(end 0.299974 0.150114)
			(stroke
				(width 0.1)
				(type default)
			)
			(layer "B.Fab")
		)
		(pad "1" smd rect
			(at 0.2667 0 270)
			(size 0.3048 0.381)
			(layers "B.Cu" "B.Mask" "B.Paste")
			(net "P1V25_PEX1")
		)
		(pad "2" smd rect
			(at -0.2667 0 270)
			(size 0.3048 0.381)
			(layers "B.Cu" "B.Mask" "B.Paste")
			(net "GND")
		)
	)
	(footprint ""
		(layer "B.Cu")
		(at 233.867706 -218.70416 -90)
		(property "Reference" "C2006"
			(at 0 0 90)
			(layer "B.SilkS")
			(hide yes)
			(effects
				(font
					(size 1.27 1.27)
				)
				(justify mirror)
			)
		)
		(property "Value" ""
			(at 0 0 90)
			(layer "B.Fab")
			(effects
				(font
					(size 1.27 1.27)
				)
				(justify mirror)
			)
		)
		(duplicate_pad_numbers_are_jumpers no)
		(fp_line
			(start -0.69215 0.2921)
			(end 0.69215 0.2921)
			(stroke
				(width 0.1524)
				(type default)
			)
			(layer "B.SilkS")
		)
		(fp_line
			(start 0.69215 0.2921)
			(end 0.69215 -0.2921)
			(stroke
				(width 0.1524)
				(type default)
			)
			(layer "B.SilkS")
		)
		(fp_line
			(start -0.69215 -0.2921)
			(end -0.69215 0.2921)
			(stroke
				(width 0.1524)
				(type default)
			)
			(layer "B.SilkS")
		)
		(fp_line
			(start 0.69215 -0.2921)
			(end -0.69215 -0.2921)
			(stroke
				(width 0.1524)
				(type default)
			)
			(layer "B.SilkS")
		)
		(fp_line
			(start -0.51435 0.2794)
			(end 0.51435 0.2794)
			(stroke
				(width 0.1)
				(type default)
			)
			(layer "B.Fab")
		)
		(fp_line
			(start 0.51435 0.2794)
			(end 0.51435 -0.2794)
			(stroke
				(width 0.1)
				(type default)
			)
			(layer "B.Fab")
		)
		(fp_line
			(start -0.51435 -0.2794)
			(end -0.51435 0.2794)
			(stroke
				(width 0.1)
				(type default)
			)
			(layer "B.Fab")
		)
		(fp_line
			(start 0.51435 -0.2794)
			(end -0.51435 -0.2794)
			(stroke
				(width 0.1)
				(type default)
			)
			(layer "B.Fab")
		)
		(pad "1" smd circle
			(at 0.40005 0 90)
			(size 0 0)
			(layers "B.Cu" "B.Mask" "B.Paste")
			(net "P3V3_AUX")
		)
		(pad "2" smd circle
			(at -0.40005 0 90)
			(size 0 0)
			(layers "B.Cu" "B.Mask" "B.Paste")
			(net "GND")
		)
		(zone
			(layer "B.Cu")
			(hatch none 0.5)
			(connect_pads
				(clearance 0)
			)
			(min_thickness 0.25)
			(keepout
				(tracks not_allowed)
				(vias allowed)
				(pads allowed)
				(copperpour not_allowed)
				(footprints allowed)
			)
			(placement
				(enabled no)
				(sheetname "")
			)
			(fill
				(thermal_gap 0.5)
				(thermal_bridge_width 0.5)
				(island_removal_mode 0)
			)
			(polygon
				(pts
					(xy 233.780076 -218.51366) (xy 233.72191 -218.6051) (xy 233.72191 -218.80449) (xy 233.780076 -218.89466)
					(xy 233.955336 -218.89466) (xy 234.013756 -218.80449) (xy 234.013756 -218.6051) (xy 233.95559 -218.51366)
				)
			)
		)
	)
	(footprint ""
		(layer "B.Cu")
		(at 407.949908 -290.199826 90)
		(property "Reference" "C2000"
			(at 0 0 90)
			(layer "B.SilkS")
			(hide yes)
			(effects
				(font
					(size 1.27 1.27)
				)
				(justify mirror)
			)
		)
		(property "Value" ""
			(at 0 0 90)
			(layer "B.Fab")
			(effects
				(font
					(size 1.27 1.27)
				)
				(justify mirror)
			)
		)
		(duplicate_pad_numbers_are_jumpers no)
		(fp_line
			(start 0.299974 -0.150114)
			(end -0.299974 -0.150114)
			(stroke
				(width 0.1)
				(type default)
			)
			(layer "B.Fab")
		)
		(fp_line
			(start -0.299974 -0.150114)
			(end -0.299974 0.150114)
			(stroke
				(width 0.1)
				(type default)
			)
			(layer "B.Fab")
		)
		(fp_line
			(start 0.299974 0.150114)
			(end 0.299974 -0.150114)
			(stroke
				(width 0.1)
				(type default)
			)
			(layer "B.Fab")
		)
		(fp_line
			(start -0.299974 0.150114)
			(end 0.299974 0.150114)
			(stroke
				(width 0.1)
				(type default)
			)
			(layer "B.Fab")
		)
		(pad "1" smd rect
			(at 0.2667 0 270)
			(size 0.3048 0.381)
			(layers "B.Cu" "B.Mask" "B.Paste")
			(net "P0V8_SERDES_VDDA_PEX3")
		)
		(pad "2" smd rect
			(at -0.2667 0 270)
			(size 0.3048 0.381)
			(layers "B.Cu" "B.Mask" "B.Paste")
			(net "GND")
		)
	)
	(footprint ""
		(layer "B.Cu")
		(at 341.294212 -217.187018 -90)
		(property "Reference" "C2059"
			(at 0 0 90)
			(layer "B.SilkS")
			(hide yes)
			(effects
				(font
					(size 1.27 1.27)
				)
				(justify mirror)
			)
		)
		(property "Value" ""
			(at 0 0 90)
			(layer "B.Fab")
			(effects
				(font
					(size 1.27 1.27)
				)
				(justify mirror)
			)
		)
		(duplicate_pad_numbers_are_jumpers no)
		(fp_line
			(start -0.69215 0.2921)
			(end 0.69215 0.2921)
			(stroke
				(width 0.1524)
				(type default)
			)
			(layer "B.SilkS")
		)
		(fp_line
			(start 0.69215 0.2921)
			(end 0.69215 -0.2921)
			(stroke
				(width 0.1524)
				(type default)
			)
			(layer "B.SilkS")
		)
		(fp_line
			(start -0.69215 -0.2921)
			(end -0.69215 0.2921)
			(stroke
				(width 0.1524)
				(type default)
			)
			(layer "B.SilkS")
		)
		(fp_line
			(start 0.69215 -0.2921)
			(end -0.69215 -0.2921)
			(stroke
				(width 0.1524)
				(type default)
			)
			(layer "B.SilkS")
		)
		(fp_line
			(start -0.51435 0.2794)
			(end 0.51435 0.2794)
			(stroke
				(width 0.1)
				(type default)
			)
			(layer "B.Fab")
		)
		(fp_line
			(start 0.51435 0.2794)
			(end 0.51435 -0.2794)
			(stroke
				(width 0.1)
				(type default)
			)
			(layer "B.Fab")
		)
		(fp_line
			(start -0.51435 -0.2794)
			(end -0.51435 0.2794)
			(stroke
				(width 0.1)
				(type default)
			)
			(layer "B.Fab")
		)
		(fp_line
			(start 0.51435 -0.2794)
			(end -0.51435 -0.2794)
			(stroke
				(width 0.1)
				(type default)
			)
			(layer "B.Fab")
		)
		(pad "1" smd circle
			(at 0.40005 0 90)
			(size 0 0)
			(layers "B.Cu" "B.Mask" "B.Paste")
			(net "P3V3_FPGA_VCCIO2")
		)
		(pad "2" smd circle
			(at -0.40005 0 90)
			(size 0 0)
			(layers "B.Cu" "B.Mask" "B.Paste")
			(net "GND")
		)
		(zone
			(layer "B.Cu")
			(hatch none 0.5)
			(connect_pads
				(clearance 0)
			)
			(min_thickness 0.25)
			(keepout
				(tracks not_allowed)
				(vias allowed)
				(pads allowed)
				(copperpour not_allowed)
				(footprints allowed)
			)
			(placement
				(enabled no)
				(sheetname "")
			)
			(fill
				(thermal_gap 0.5)
				(thermal_bridge_width 0.5)
				(island_removal_mode 0)
			)
			(polygon
				(pts
					(xy 341.206582 -216.996518) (xy 341.148416 -217.087958) (xy 341.148416 -217.287348) (xy 341.206582 -217.377518)
					(xy 341.381842 -217.377518) (xy 341.440262 -217.287348) (xy 341.440262 -217.087958) (xy 341.382096 -216.996518)
				)
			)
		)
	)
	(footprint ""
		(layer "B.Cu")
		(at 15.742666 -387.531356 180)
		(property "Reference" "C4468"
			(at 0 0 0)
			(layer "B.SilkS")
			(hide yes)
			(effects
				(font
					(size 1.27 1.27)
				)
				(justify mirror)
			)
		)
		(property "Value" ""
			(at 0 0 0)
			(layer "B.Fab")
			(effects
				(font
					(size 1.27 1.27)
				)
				(justify mirror)
			)
		)
		(duplicate_pad_numbers_are_jumpers no)
		(fp_line
			(start 0.7874 0.4064)
			(end 0.7874 -0.4064)
			(stroke
				(width 0.1524)
				(type default)
			)
			(layer "B.SilkS")
		)
		(fp_line
			(start 0.7874 -0.4064)
			(end -0.7874 -0.4064)
			(stroke
				(width 0.1524)
				(type default)
			)
			(layer "B.SilkS")
		)
		(fp_line
			(start -0.7874 0.4064)
			(end 0.7874 0.4064)
			(stroke
				(width 0.1524)
				(type default)
			)
			(layer "B.SilkS")
		)
		(fp_line
			(start -0.7874 -0.4064)
			(end -0.7874 0.4064)
			(stroke
				(width 0.1524)
				(type default)
			)
			(layer "B.SilkS")
		)
		(fp_line
			(start 0.67945 0.3048)
			(end 0.67945 -0.305054)
			(stroke
				(width 0.1)
				(type default)
			)
			(layer "B.Fab")
		)
		(fp_line
			(start 0.67945 -0.305054)
			(end 0.12065 -0.305054)
			(stroke
				(width 0.1)
				(type default)
			)
			(layer "B.Fab")
		)
		(fp_line
			(start 0.12065 0.3048)
			(end 0.67945 0.3048)
			(stroke
				(width 0.1)
				(type default)
			)
			(layer "B.Fab")
		)
		(fp_line
			(start 0.12065 0.2794)
			(end 0.12065 0.3048)
			(stroke
				(width 0.1)
				(type default)
			)
			(layer "B.Fab")
		)
		(fp_line
			(start 0.12065 -0.2794)
			(end -0.12065 -0.2794)
			(stroke
				(width 0.1)
				(type default)
			)
			(layer "B.Fab")
		)
		(fp_line
			(start 0.12065 -0.305054)
			(end 0.12065 -0.2794)
			(stroke
				(width 0.1)
				(type default)
			)
			(layer "B.Fab")
		)
		(fp_line
			(start -0.120396 0.3048)
			(end -0.120396 0.2794)
			(stroke
				(width 0.1)
				(type default)
			)
			(layer "B.Fab")
		)
		(fp_line
			(start -0.120396 0.2794)
			(end 0.12065 0.2794)
			(stroke
				(width 0.1)
				(type default)
			)
			(layer "B.Fab")
		)
		(fp_line
			(start -0.12065 -0.2794)
			(end -0.12065 -0.3048)
			(stroke
				(width 0.1)
				(type default)
			)
			(layer "B.Fab")
		)
		(fp_line
			(start -0.12065 -0.3048)
			(end -0.67945 -0.3048)
			(stroke
				(width 0.1)
				(type default)
			)
			(layer "B.Fab")
		)
		(fp_line
			(start -0.67945 0.3048)
			(end -0.120396 0.3048)
			(stroke
				(width 0.1)
				(type default)
			)
			(layer "B.Fab")
		)
		(fp_line
			(start -0.67945 -0.3048)
			(end -0.67945 0.3048)
			(stroke
				(width 0.1)
				(type default)
			)
			(layer "B.Fab")
		)
		(pad "1" smd circle
			(at 0.40005 0)
			(size 0 0)
			(layers "B.Cu" "B.Mask" "B.Paste")
			(net "P1V2_USB_8042")
		)
		(pad "2" smd circle
			(at -0.40005 0)
			(size 0 0)
			(layers "B.Cu" "B.Mask" "B.Paste")
			(net "GND")
		)
	)
	(footprint ""
		(layer "B.Cu")
		(at 278.549862 -290.215066)
		(property "Reference" "C3353"
			(at 0 0 0)
			(layer "B.SilkS")
			(hide yes)
			(effects
				(font
					(size 1.27 1.27)
				)
				(justify mirror)
			)
		)
		(property "Value" ""
			(at 0 0 0)
			(layer "B.Fab")
			(effects
				(font
					(size 1.27 1.27)
				)
				(justify mirror)
			)
		)
		(duplicate_pad_numbers_are_jumpers no)
		(fp_line
			(start -0.299974 -0.150114)
			(end -0.299974 0.150114)
			(stroke
				(width 0.1)
				(type default)
			)
			(layer "B.Fab")
		)
		(fp_line
			(start -0.299974 0.150114)
			(end 0.299974 0.150114)
			(stroke
				(width 0.1)
				(type default)
			)
			(layer "B.Fab")
		)
		(fp_line
			(start 0.299974 -0.150114)
			(end -0.299974 -0.150114)
			(stroke
				(width 0.1)
				(type default)
			)
			(layer "B.Fab")
		)
		(fp_line
			(start 0.299974 0.150114)
			(end 0.299974 -0.150114)
			(stroke
				(width 0.1)
				(type default)
			)
			(layer "B.Fab")
		)
		(pad "1" smd rect
			(at 0.2667 0 180)
			(size 0.3048 0.381)
			(layers "B.Cu" "B.Mask" "B.Paste")
			(net "P1V8_PEX")
		)
		(pad "2" smd rect
			(at -0.2667 0 180)
			(size 0.3048 0.381)
			(layers "B.Cu" "B.Mask" "B.Paste")
			(net "GND")
		)
	)
	(footprint ""
		(layer "B.Cu")
		(at 252.0188 -348.8436 180)
		(property "Reference" "PR7162"
			(at 0 0 0)
			(layer "B.SilkS")
			(hide yes)
			(effects
				(font
					(size 1.27 1.27)
				)
				(justify mirror)
			)
		)
		(property "Value" ""
			(at 0 0 0)
			(layer "B.Fab")
			(effects
				(font
					(size 1.27 1.27)
				)
				(justify mirror)
			)
		)
		(duplicate_pad_numbers_are_jumpers no)
		(fp_line
			(start 0.7874 0.4064)
			(end 0.7874 -0.4064)
			(stroke
				(width 0.1524)
				(type default)
			)
			(layer "B.SilkS")
		)
		(fp_line
			(start 0.7874 -0.4064)
			(end -0.7874 -0.4064)
			(stroke
				(width 0.1524)
				(type default)
			)
			(layer "B.SilkS")
		)
		(fp_line
			(start -0.7874 0.4064)
			(end 0.7874 0.4064)
			(stroke
				(width 0.1524)
				(type default)
			)
			(layer "B.SilkS")
		)
		(fp_line
			(start -0.7874 -0.4064)
			(end -0.7874 0.4064)
			(stroke
				(width 0.1524)
				(type default)
			)
			(layer "B.SilkS")
		)
		(fp_line
			(start 0.67945 0.3048)
			(end 0.67945 -0.305054)
			(stroke
				(width 0.1)
				(type default)
			)
			(layer "B.Fab")
		)
		(fp_line
			(start 0.67945 -0.305054)
			(end 0.12065 -0.305054)
			(stroke
				(width 0.1)
				(type default)
			)
			(layer "B.Fab")
		)
		(fp_line
			(start 0.12065 0.3048)
			(end 0.67945 0.3048)
			(stroke
				(width 0.1)
				(type default)
			)
			(layer "B.Fab")
		)
		(fp_line
			(start 0.12065 0.2794)
			(end 0.12065 0.3048)
			(stroke
				(width 0.1)
				(type default)
			)
			(layer "B.Fab")
		)
		(fp_line
			(start 0.12065 -0.2794)
			(end -0.12065 -0.2794)
			(stroke
				(width 0.1)
				(type default)
			)
			(layer "B.Fab")
		)
		(fp_line
			(start 0.12065 -0.305054)
			(end 0.12065 -0.2794)
			(stroke
				(width 0.1)
				(type default)
			)
			(layer "B.Fab")
		)
		(fp_line
			(start -0.120396 0.3048)
			(end -0.120396 0.2794)
			(stroke
				(width 0.1)
				(type default)
			)
			(layer "B.Fab")
		)
		(fp_line
			(start -0.120396 0.2794)
			(end 0.12065 0.2794)
			(stroke
				(width 0.1)
				(type default)
			)
			(layer "B.Fab")
		)
		(fp_line
			(start -0.12065 -0.2794)
			(end -0.12065 -0.3048)
			(stroke
				(width 0.1)
				(type default)
			)
			(layer "B.Fab")
		)
		(fp_line
			(start -0.12065 -0.3048)
			(end -0.67945 -0.3048)
			(stroke
				(width 0.1)
				(type default)
			)
			(layer "B.Fab")
		)
		(fp_line
			(start -0.67945 0.3048)
			(end -0.120396 0.3048)
			(stroke
				(width 0.1)
				(type default)
			)
			(layer "B.Fab")
		)
		(fp_line
			(start -0.67945 -0.3048)
			(end -0.67945 0.3048)
			(stroke
				(width 0.1)
				(type default)
			)
			(layer "B.Fab")
		)
		(pad "1" smd circle
			(at 0.40005 0)
			(size 0 0)
			(layers "B.Cu" "B.Mask" "B.Paste")
			(net "P12V_HSC_EN")
		)
		(pad "2" smd circle
			(at -0.40005 0)
			(size 0 0)
			(layers "B.Cu" "B.Mask" "B.Paste")
			(net "HSC_P12V_EN")
		)
	)
	(footprint ""
		(layer "B.Cu")
		(at 167.675052 -293.99992 -90)
		(property "Reference" "C1387"
			(at 0 0 90)
			(layer "B.SilkS")
			(hide yes)
			(effects
				(font
					(size 1.27 1.27)
				)
				(justify mirror)
			)
		)
		(property "Value" ""
			(at 0 0 90)
			(layer "B.Fab")
			(effects
				(font
					(size 1.27 1.27)
				)
				(justify mirror)
			)
		)
		(duplicate_pad_numbers_are_jumpers no)
		(fp_line
			(start -0.299974 0.150114)
			(end 0.299974 0.150114)
			(stroke
				(width 0.1)
				(type default)
			)
			(layer "B.Fab")
		)
		(fp_line
			(start 0.299974 0.150114)
			(end 0.299974 -0.150114)
			(stroke
				(width 0.1)
				(type default)
			)
			(layer "B.Fab")
		)
		(fp_line
			(start -0.299974 -0.150114)
			(end -0.299974 0.150114)
			(stroke
				(width 0.1)
				(type default)
			)
			(layer "B.Fab")
		)
		(fp_line
			(start 0.299974 -0.150114)
			(end -0.299974 -0.150114)
			(stroke
				(width 0.1)
				(type default)
			)
			(layer "B.Fab")
		)
		(pad "1" smd rect
			(at 0.2667 0 90)
			(size 0.3048 0.381)
			(layers "B.Cu" "B.Mask" "B.Paste")
			(net "P0V8_PEX1")
		)
		(pad "2" smd rect
			(at -0.2667 0 90)
			(size 0.3048 0.381)
			(layers "B.Cu" "B.Mask" "B.Paste")
			(net "GND")
		)
	)
	(footprint ""
		(layer "B.Cu")
		(at 225.556064 -208.78546 -90)
		(property "Reference" "R5288"
			(at 0 0 90)
			(layer "B.SilkS")
			(hide yes)
			(effects
				(font
					(size 1.27 1.27)
				)
				(justify mirror)
			)
		)
		(property "Value" ""
			(at 0 0 90)
			(layer "B.Fab")
			(effects
				(font
					(size 1.27 1.27)
				)
				(justify mirror)
			)
		)
		(duplicate_pad_numbers_are_jumpers no)
		(fp_line
			(start -0.7874 0.4064)
			(end 0.7874 0.4064)
			(stroke
				(width 0.1524)
				(type default)
			)
			(layer "B.SilkS")
		)
		(fp_line
			(start 0.7874 0.4064)
			(end 0.7874 -0.4064)
			(stroke
				(width 0.1524)
				(type default)
			)
			(layer "B.SilkS")
		)
		(fp_line
			(start -0.7874 -0.4064)
			(end -0.7874 0.4064)
			(stroke
				(width 0.1524)
				(type default)
			)
			(layer "B.SilkS")
		)
		(fp_line
			(start 0.7874 -0.4064)
			(end -0.7874 -0.4064)
			(stroke
				(width 0.1524)
				(type default)
			)
			(layer "B.SilkS")
		)
		(fp_line
			(start -0.67945 0.3048)
			(end -0.120396 0.3048)
			(stroke
				(width 0.1)
				(type default)
			)
			(layer "B.Fab")
		)
		(fp_line
			(start -0.120396 0.3048)
			(end -0.120396 0.2794)
			(stroke
				(width 0.1)
				(type default)
			)
			(layer "B.Fab")
		)
		(fp_line
			(start 0.12065 0.3048)
			(end 0.67945 0.3048)
			(stroke
				(width 0.1)
				(type default)
			)
			(layer "B.Fab")
		)
		(fp_line
			(start 0.67945 0.3048)
			(end 0.67945 -0.305054)
			(stroke
				(width 0.1)
				(type default)
			)
			(layer "B.Fab")
		)
		(fp_line
			(start -0.120396 0.2794)
			(end 0.12065 0.2794)
			(stroke
				(width 0.1)
				(type default)
			)
			(layer "B.Fab")
		)
		(fp_line
			(start 0.12065 0.2794)
			(end 0.12065 0.3048)
			(stroke
				(width 0.1)
				(type default)
			)
			(layer "B.Fab")
		)
		(fp_line
			(start -0.12065 -0.2794)
			(end -0.12065 -0.3048)
			(stroke
				(width 0.1)
				(type default)
			)
			(layer "B.Fab")
		)
		(fp_line
			(start 0.12065 -0.2794)
			(end -0.12065 -0.2794)
			(stroke
				(width 0.1)
				(type default)
			)
			(layer "B.Fab")
		)
		(fp_line
			(start -0.67945 -0.3048)
			(end -0.67945 0.3048)
			(stroke
				(width 0.1)
				(type default)
			)
			(layer "B.Fab")
		)
		(fp_line
			(start -0.12065 -0.3048)
			(end -0.67945 -0.3048)
			(stroke
				(width 0.1)
				(type default)
			)
			(layer "B.Fab")
		)
		(fp_line
			(start 0.12065 -0.305054)
			(end 0.12065 -0.2794)
			(stroke
				(width 0.1)
				(type default)
			)
			(layer "B.Fab")
		)
		(fp_line
			(start 0.67945 -0.305054)
			(end 0.12065 -0.305054)
			(stroke
				(width 0.1)
				(type default)
			)
			(layer "B.Fab")
		)
		(pad "1" smd circle
			(at 0.40005 0 90)
			(size 0 0)
			(layers "B.Cu" "B.Mask" "B.Paste")
			(net "RST_SMB_FIO_R_N")
		)
		(pad "2" smd circle
			(at -0.40005 0 90)
			(size 0 0)
			(layers "B.Cu" "B.Mask" "B.Paste")
			(net "RST_SMB_FIO_N")
		)
	)
	(footprint ""
		(layer "B.Cu")
		(at 299.067474 -221.694502 90)
		(property "Reference" "R1865"
			(at 0 0 90)
			(layer "B.SilkS")
			(hide yes)
			(effects
				(font
					(size 1.27 1.27)
				)
				(justify mirror)
			)
		)
		(property "Value" ""
			(at 0 0 90)
			(layer "B.Fab")
			(effects
				(font
					(size 1.27 1.27)
				)
				(justify mirror)
			)
		)
		(duplicate_pad_numbers_are_jumpers no)
		(fp_line
			(start 0.7874 -0.4064)
			(end -0.7874 -0.4064)
			(stroke
				(width 0.1524)
				(type default)
			)
			(layer "B.SilkS")
		)
		(fp_line
			(start -0.7874 -0.4064)
			(end -0.7874 0.4064)
			(stroke
				(width 0.1524)
				(type default)
			)
			(layer "B.SilkS")
		)
		(fp_line
			(start 0.7874 0.4064)
			(end 0.7874 -0.4064)
			(stroke
				(width 0.1524)
				(type default)
			)
			(layer "B.SilkS")
		)
		(fp_line
			(start -0.7874 0.4064)
			(end 0.7874 0.4064)
			(stroke
				(width 0.1524)
				(type default)
			)
			(layer "B.SilkS")
		)
		(fp_line
			(start 0.67945 -0.305054)
			(end 0.12065 -0.305054)
			(stroke
				(width 0.1)
				(type default)
			)
			(layer "B.Fab")
		)
		(fp_line
			(start 0.12065 -0.305054)
			(end 0.12065 -0.2794)
			(stroke
				(width 0.1)
				(type default)
			)
			(layer "B.Fab")
		)
		(fp_line
			(start -0.12065 -0.3048)
			(end -0.67945 -0.3048)
			(stroke
				(width 0.1)
				(type default)
			)
			(layer "B.Fab")
		)
		(fp_line
			(start -0.67945 -0.3048)
			(end -0.67945 0.3048)
			(stroke
				(width 0.1)
				(type default)
			)
			(layer "B.Fab")
		)
		(fp_line
			(start 0.12065 -0.2794)
			(end -0.12065 -0.2794)
			(stroke
				(width 0.1)
				(type default)
			)
			(layer "B.Fab")
		)
		(fp_line
			(start -0.12065 -0.2794)
			(end -0.12065 -0.3048)
			(stroke
				(width 0.1)
				(type default)
			)
			(layer "B.Fab")
		)
		(fp_line
			(start 0.12065 0.2794)
			(end 0.12065 0.3048)
			(stroke
				(width 0.1)
				(type default)
			)
			(layer "B.Fab")
		)
		(fp_line
			(start -0.120396 0.2794)
			(end 0.12065 0.2794)
			(stroke
				(width 0.1)
				(type default)
			)
			(layer "B.Fab")
		)
		(fp_line
			(start 0.67945 0.3048)
			(end 0.67945 -0.305054)
			(stroke
				(width 0.1)
				(type default)
			)
			(layer "B.Fab")
		)
		(fp_line
			(start 0.12065 0.3048)
			(end 0.67945 0.3048)
			(stroke
				(width 0.1)
				(type default)
			)
			(layer "B.Fab")
		)
		(fp_line
			(start -0.120396 0.3048)
			(end -0.120396 0.2794)
			(stroke
				(width 0.1)
				(type default)
			)
			(layer "B.Fab")
		)
		(fp_line
			(start -0.67945 0.3048)
			(end -0.120396 0.3048)
			(stroke
				(width 0.1)
				(type default)
			)
			(layer "B.Fab")
		)
		(pad "1" smd circle
			(at 0.40005 0 270)
			(size 0 0)
			(layers "B.Cu" "B.Mask" "B.Paste")
			(net "RST_GPU_PERST_0_BUF_N")
		)
		(pad "2" smd circle
			(at -0.40005 0 270)
			(size 0 0)
			(layers "B.Cu" "B.Mask" "B.Paste")
			(net "RST_GPU_PERST_0_BUF_R_N")
		)
	)
	(footprint ""
		(layer "B.Cu")
		(at 300.399704 -298.27474 180)
		(property "Reference" "C1630"
			(at 0 0 0)
			(layer "B.SilkS")
			(hide yes)
			(effects
				(font
					(size 1.27 1.27)
				)
				(justify mirror)
			)
		)
		(property "Value" ""
			(at 0 0 0)
			(layer "B.Fab")
			(effects
				(font
					(size 1.27 1.27)
				)
				(justify mirror)
			)
		)
		(duplicate_pad_numbers_are_jumpers no)
		(fp_line
			(start 0.299974 0.150114)
			(end 0.299974 -0.150114)
			(stroke
				(width 0.1)
				(type default)
			)
			(layer "B.Fab")
		)
		(fp_line
			(start 0.299974 -0.150114)
			(end -0.299974 -0.150114)
			(stroke
				(width 0.1)
				(type default)
			)
			(layer "B.Fab")
		)
		(fp_line
			(start -0.299974 0.150114)
			(end 0.299974 0.150114)
			(stroke
				(width 0.1)
				(type default)
			)
			(layer "B.Fab")
		)
		(fp_line
			(start -0.299974 -0.150114)
			(end -0.299974 0.150114)
			(stroke
				(width 0.1)
				(type default)
			)
			(layer "B.Fab")
		)
		(pad "1" smd rect
			(at 0.2667 0)
			(size 0.3048 0.381)
			(layers "B.Cu" "B.Mask" "B.Paste")
			(net "P0V8_PEX2")
		)
		(pad "2" smd rect
			(at -0.2667 0)
			(size 0.3048 0.381)
			(layers "B.Cu" "B.Mask" "B.Paste")
			(net "GND")
		)
	)
	(footprint ""
		(layer "B.Cu")
		(at 449.857876 -274.541996)
		(property "Reference" "C4386"
			(at 0 0 0)
			(layer "B.SilkS")
			(hide yes)
			(effects
				(font
					(size 1.27 1.27)
				)
				(justify mirror)
			)
		)
		(property "Value" ""
			(at 0 0 0)
			(layer "B.Fab")
			(effects
				(font
					(size 1.27 1.27)
				)
				(justify mirror)
			)
		)
		(duplicate_pad_numbers_are_jumpers no)
		(fp_line
			(start -1.2954 -0.5842)
			(end -1.2954 0.5842)
			(stroke
				(width 0.1524)
				(type default)
			)
			(layer "B.SilkS")
		)
		(fp_line
			(start -1.2954 0.5842)
			(end 1.2954 0.5842)
			(stroke
				(width 0.1524)
				(type default)
			)
			(layer "B.SilkS")
		)
		(fp_line
			(start 1.2954 -0.5842)
			(end -1.2954 -0.5842)
			(stroke
				(width 0.1524)
				(type default)
			)
			(layer "B.SilkS")
		)
		(fp_line
			(start 1.2954 0.5842)
			(end 1.2954 -0.5842)
			(stroke
				(width 0.1524)
				(type default)
			)
			(layer "B.SilkS")
		)
		(fp_line
			(start -1.1938 -0.4064)
			(end -1.1938 0.4064)
			(stroke
				(width 0.1)
				(type default)
			)
			(layer "B.Fab")
		)
		(fp_line
			(start -1.1938 0.4064)
			(end -0.8636 0.4064)
			(stroke
				(width 0.1)
				(type default)
			)
			(layer "B.Fab")
		)
		(fp_line
			(start -0.8636 -0.4572)
			(end -0.8636 -0.4064)
			(stroke
				(width 0.1)
				(type default)
			)
			(layer "B.Fab")
		)
		(fp_line
			(start -0.8636 -0.4064)
			(end -1.1938 -0.4064)
			(stroke
				(width 0.1)
				(type default)
			)
			(layer "B.Fab")
		)
		(fp_line
			(start -0.8636 0.4064)
			(end -0.8636 0.4572)
			(stroke
				(width 0.1)
				(type default)
			)
			(layer "B.Fab")
		)
		(fp_line
			(start -0.8636 0.4572)
			(end 0.8636 0.4572)
			(stroke
				(width 0.1)
				(type default)
			)
			(layer "B.Fab")
		)
		(fp_line
			(start 0.8636 -0.4572)
			(end -0.8636 -0.4572)
			(stroke
				(width 0.1)
				(type default)
			)
			(layer "B.Fab")
		)
		(fp_line
			(start 0.8636 -0.4064)
			(end 0.8636 -0.4572)
			(stroke
				(width 0.1)
				(type default)
			)
			(layer "B.Fab")
		)
		(fp_line
			(start 0.8636 0.4064)
			(end 1.1938 0.4064)
			(stroke
				(width 0.1)
				(type default)
			)
			(layer "B.Fab")
		)
		(fp_line
			(start 0.8636 0.4572)
			(end 0.8636 0.4064)
			(stroke
				(width 0.1)
				(type default)
			)
			(layer "B.Fab")
		)
		(fp_line
			(start 1.1938 -0.4064)
			(end 0.8636 -0.4064)
			(stroke
				(width 0.1)
				(type default)
			)
			(layer "B.Fab")
		)
		(fp_line
			(start 1.1938 0.4064)
			(end 1.1938 -0.4064)
			(stroke
				(width 0.1)
				(type default)
			)
			(layer "B.Fab")
		)
		(pad "1" smd rect
			(at 0.7366 0 270)
			(size 0.7112 0.8128)
			(layers "B.Cu" "B.Mask" "B.Paste")
			(net "P1V25_PEX3")
		)
		(pad "2" smd rect
			(at -0.7366 0 270)
			(size 0.7112 0.8128)
			(layers "B.Cu" "B.Mask" "B.Paste")
			(net "GND")
		)
	)
	(footprint ""
		(layer "B.Cu")
		(at 454.797668 -277.176484 180)
		(property "Reference" "C4390"
			(at 0 0 0)
			(layer "B.SilkS")
			(hide yes)
			(effects
				(font
					(size 1.27 1.27)
				)
				(justify mirror)
			)
		)
		(property "Value" ""
			(at 0 0 0)
			(layer "B.Fab")
			(effects
				(font
					(size 1.27 1.27)
				)
				(justify mirror)
			)
		)
		(duplicate_pad_numbers_are_jumpers no)
		(fp_line
			(start 0.299974 0.150114)
			(end 0.299974 -0.150114)
			(stroke
				(width 0.1)
				(type default)
			)
			(layer "B.Fab")
		)
		(fp_line
			(start 0.299974 -0.150114)
			(end -0.299974 -0.150114)
			(stroke
				(width 0.1)
				(type default)
			)
			(layer "B.Fab")
		)
		(fp_line
			(start -0.299974 0.150114)
			(end 0.299974 0.150114)
			(stroke
				(width 0.1)
				(type default)
			)
			(layer "B.Fab")
		)
		(fp_line
			(start -0.299974 -0.150114)
			(end -0.299974 0.150114)
			(stroke
				(width 0.1)
				(type default)
			)
			(layer "B.Fab")
		)
		(pad "1" smd rect
			(at 0.2667 0)
			(size 0.3048 0.381)
			(layers "B.Cu" "B.Mask" "B.Paste")
			(net "P1V25_PEX3")
		)
		(pad "2" smd rect
			(at -0.2667 0)
			(size 0.3048 0.381)
			(layers "B.Cu" "B.Mask" "B.Paste")
			(net "GND")
		)
	)
	(footprint ""
		(layer "B.Cu")
		(at 49.67478 -293.99992 -90)
		(property "Reference" "C1137"
			(at 0 0 90)
			(layer "B.SilkS")
			(hide yes)
			(effects
				(font
					(size 1.27 1.27)
				)
				(justify mirror)
			)
		)
		(property "Value" ""
			(at 0 0 90)
			(layer "B.Fab")
			(effects
				(font
					(size 1.27 1.27)
				)
				(justify mirror)
			)
		)
		(duplicate_pad_numbers_are_jumpers no)
		(fp_line
			(start -0.299974 0.150114)
			(end 0.299974 0.150114)
			(stroke
				(width 0.1)
				(type default)
			)
			(layer "B.Fab")
		)
		(fp_line
			(start 0.299974 0.150114)
			(end 0.299974 -0.150114)
			(stroke
				(width 0.1)
				(type default)
			)
			(layer "B.Fab")
		)
		(fp_line
			(start -0.299974 -0.150114)
			(end -0.299974 0.150114)
			(stroke
				(width 0.1)
				(type default)
			)
			(layer "B.Fab")
		)
		(fp_line
			(start 0.299974 -0.150114)
			(end -0.299974 -0.150114)
			(stroke
				(width 0.1)
				(type default)
			)
			(layer "B.Fab")
		)
		(pad "1" smd rect
			(at 0.2667 0 90)
			(size 0.3048 0.381)
			(layers "B.Cu" "B.Mask" "B.Paste")
			(net "P0V8_PEX0")
		)
		(pad "2" smd rect
			(at -0.2667 0 90)
			(size 0.3048 0.381)
			(layers "B.Cu" "B.Mask" "B.Paste")
			(net "GND")
		)
	)
	(footprint ""
		(layer "B.Cu")
		(at 179.55006 -290.199826 90)
		(property "Reference" "C1458"
			(at 0 0 90)
			(layer "B.SilkS")
			(hide yes)
			(effects
				(font
					(size 1.27 1.27)
				)
				(justify mirror)
			)
		)
		(property "Value" ""
			(at 0 0 90)
			(layer "B.Fab")
			(effects
				(font
					(size 1.27 1.27)
				)
				(justify mirror)
			)
		)
		(duplicate_pad_numbers_are_jumpers no)
		(fp_line
			(start 0.299974 -0.150114)
			(end -0.299974 -0.150114)
			(stroke
				(width 0.1)
				(type default)
			)
			(layer "B.Fab")
		)
		(fp_line
			(start -0.299974 -0.150114)
			(end -0.299974 0.150114)
			(stroke
				(width 0.1)
				(type default)
			)
			(layer "B.Fab")
		)
		(fp_line
			(start 0.299974 0.150114)
			(end 0.299974 -0.150114)
			(stroke
				(width 0.1)
				(type default)
			)
			(layer "B.Fab")
		)
		(fp_line
			(start -0.299974 0.150114)
			(end 0.299974 0.150114)
			(stroke
				(width 0.1)
				(type default)
			)
			(layer "B.Fab")
		)
		(pad "1" smd rect
			(at 0.2667 0 270)
			(size 0.3048 0.381)
			(layers "B.Cu" "B.Mask" "B.Paste")
			(net "P0V8_SERDES_VDDA_PEX1")
		)
		(pad "2" smd rect
			(at -0.2667 0 270)
			(size 0.3048 0.381)
			(layers "B.Cu" "B.Mask" "B.Paste")
			(net "GND")
		)
	)
	(footprint ""
		(layer "B.Cu")
		(at 60.124848 -293.99992 -90)
		(property "Reference" "C1136"
			(at 0 0 90)
			(layer "B.SilkS")
			(hide yes)
			(effects
				(font
					(size 1.27 1.27)
				)
				(justify mirror)
			)
		)
		(property "Value" ""
			(at 0 0 90)
			(layer "B.Fab")
			(effects
				(font
					(size 1.27 1.27)
				)
				(justify mirror)
			)
		)
		(duplicate_pad_numbers_are_jumpers no)
		(fp_line
			(start -0.299974 0.150114)
			(end 0.299974 0.150114)
			(stroke
				(width 0.1)
				(type default)
			)
			(layer "B.Fab")
		)
		(fp_line
			(start 0.299974 0.150114)
			(end 0.299974 -0.150114)
			(stroke
				(width 0.1)
				(type default)
			)
			(layer "B.Fab")
		)
		(fp_line
			(start -0.299974 -0.150114)
			(end -0.299974 0.150114)
			(stroke
				(width 0.1)
				(type default)
			)
			(layer "B.Fab")
		)
		(fp_line
			(start 0.299974 -0.150114)
			(end -0.299974 -0.150114)
			(stroke
				(width 0.1)
				(type default)
			)
			(layer "B.Fab")
		)
		(pad "1" smd rect
			(at 0.2667 0 90)
			(size 0.3048 0.381)
			(layers "B.Cu" "B.Mask" "B.Paste")
			(net "P0V8_PEX0")
		)
		(pad "2" smd rect
			(at -0.2667 0 90)
			(size 0.3048 0.381)
			(layers "B.Cu" "B.Mask" "B.Paste")
			(net "GND")
		)
	)
	(footprint ""
		(layer "B.Cu")
		(at 386.890768 10.682732)
		(property "Reference" "DE16T_2"
			(at 2.542032 3.136138 0)
			(unlocked yes)
			(layer "B.SilkS")
			(effects
				(font
					(size 0.7874 0.5842)
					(thickness 0.1524)
				)
				(justify left mirror)
			)
		)
		(property "Value" ""
			(at 0 0 0)
			(layer "B.Fab")
			(effects
				(font
					(size 1.27 1.27)
				)
				(justify mirror)
			)
		)
		(duplicate_pad_numbers_are_jumpers no)
		(fp_line
			(start -1.2192 -2.1082)
			(end -1.2192 2.1082)
			(stroke
				(width 0.1524)
				(type default)
			)
			(layer "B.SilkS")
		)
		(fp_line
			(start -1.2192 2.1082)
			(end 1.2192 2.1082)
			(stroke
				(width 0.1524)
				(type default)
			)
			(layer "B.SilkS")
		)
		(fp_line
			(start 1.2192 -2.1082)
			(end -1.2192 -2.1082)
			(stroke
				(width 0.1524)
				(type default)
			)
			(layer "B.SilkS")
		)
		(fp_line
			(start 1.2192 2.1082)
			(end 1.2192 -2.1082)
			(stroke
				(width 0.1524)
				(type default)
			)
			(layer "B.SilkS")
		)
		(pad "" np_thru_hole circle
			(at -3.4671 -1.27 270)
			(size 1.0414 1.0414)
			(drill 1.0414)
			(layers "*.Cu" "*.Mask")
			(clearance 0.381)
			(thermal_gap 0.381)
		)
		(pad "" np_thru_hole circle
			(at -3.4671 1.27 270)
			(size 1.0414 1.0414)
			(drill 1.0414)
			(layers "*.Cu" "*.Mask")
			(clearance 0.381)
			(thermal_gap 0.381)
		)
		(pad "" np_thru_hole circle
			(at 2.8829 -1.27 270)
			(size 1.0414 1.0414)
			(drill 1.0414)
			(layers "*.Cu" "*.Mask")
			(clearance 0.381)
			(thermal_gap 0.381)
		)
		(pad "" np_thru_hole circle
			(at 2.8829 1.27 270)
			(size 1.0414 1.0414)
			(drill 1.0414)
			(layers "*.Cu" "*.Mask")
			(clearance 0.381)
			(thermal_gap 0.381)
		)
		(pad "1" smd rect
			(at -0.8255 -0.249936 270)
			(size 0.3048 0.508)
			(layers "B.Cu" "B.Mask" "B.Paste")
			(net "85_10INCH_IN4_DN")
		)
		(pad "2" smd rect
			(at -0.8255 0.249936 270)
			(size 0.3048 0.508)
			(layers "B.Cu" "B.Mask" "B.Paste")
			(net "85_10INCH_IN4_DP")
		)
		(pad "3" smd circle
			(at 0 0 180)
			(size 0 0)
			(layers "B.Cu" "B.Mask" "B.Paste")
			(net "COUPON_GND2")
		)
		(zone
			(layers "F.Cu" "B.Cu" "In1.Cu" "In2.Cu" "In3.Cu" "In4.Cu" "In5.Cu" "In6.Cu"
				"In7.Cu" "In8.Cu" "In9.Cu" "In10.Cu" "In11.Cu" "In12.Cu" "In13.Cu" "In14.Cu"
				"In15.Cu" "In16.Cu"
			)
			(hatch none 0.5)
			(connect_pads
				(clearance 0)
			)
			(min_thickness 0.25)
			(keepout
				(tracks not_allowed)
				(vias allowed)
				(pads allowed)
				(copperpour not_allowed)
				(footprints allowed)
			)
			(placement
				(enabled no)
				(sheetname "")
			)
			(fill
				(thermal_gap 0.5)
				(thermal_bridge_width 0.5)
				(island_removal_mode 0)
			)
			(polygon
				(pts
					(arc
						(start 384.350768 9.412732)
						(mid 382.496568 9.412732)
						(end 384.350768 9.412732)
					)
				)
			)
		)
		(zone
			(layers "F.Cu" "B.Cu" "In1.Cu" "In2.Cu" "In3.Cu" "In4.Cu" "In5.Cu" "In6.Cu"
				"In7.Cu" "In8.Cu" "In9.Cu" "In10.Cu" "In11.Cu" "In12.Cu" "In13.Cu" "In14.Cu"
				"In15.Cu" "In16.Cu"
			)
			(hatch none 0.5)
			(connect_pads
				(clearance 0)
			)
			(min_thickness 0.25)
			(keepout
				(tracks not_allowed)
				(vias allowed)
				(pads allowed)
				(copperpour not_allowed)
				(footprints allowed)
			)
			(placement
				(enabled no)
				(sheetname "")
			)
			(fill
				(thermal_gap 0.5)
				(thermal_bridge_width 0.5)
				(island_removal_mode 0)
			)
			(polygon
				(pts
					(arc
						(start 384.350768 11.952732)
						(mid 382.496568 11.952732)
						(end 384.350768 11.952732)
					)
				)
			)
		)
		(zone
			(layers "F.Cu" "B.Cu" "In1.Cu" "In2.Cu" "In3.Cu" "In4.Cu" "In5.Cu" "In6.Cu"
				"In7.Cu" "In8.Cu" "In9.Cu" "In10.Cu" "In11.Cu" "In12.Cu" "In13.Cu" "In14.Cu"
				"In15.Cu" "In16.Cu"
			)
			(hatch none 0.5)
			(connect_pads
				(clearance 0)
			)
			(min_thickness 0.25)
			(keepout
				(tracks not_allowed)
				(vias allowed)
				(pads allowed)
				(copperpour not_allowed)
				(footprints allowed)
			)
			(placement
				(enabled no)
				(sheetname "")
			)
			(fill
				(thermal_gap 0.5)
				(thermal_bridge_width 0.5)
				(island_removal_mode 0)
			)
			(polygon
				(pts
					(arc
						(start 390.700768 9.412732)
						(mid 388.846568 9.412732)
						(end 390.700768 9.412732)
					)
				)
			)
		)
		(zone
			(layers "F.Cu" "B.Cu" "In1.Cu" "In2.Cu" "In3.Cu" "In4.Cu" "In5.Cu" "In6.Cu"
				"In7.Cu" "In8.Cu" "In9.Cu" "In10.Cu" "In11.Cu" "In12.Cu" "In13.Cu" "In14.Cu"
				"In15.Cu" "In16.Cu"
			)
			(hatch none 0.5)
			(connect_pads
				(clearance 0)
			)
			(min_thickness 0.25)
			(keepout
				(tracks not_allowed)
				(vias allowed)
				(pads allowed)
				(copperpour not_allowed)
				(footprints allowed)
			)
			(placement
				(enabled no)
				(sheetname "")
			)
			(fill
				(thermal_gap 0.5)
				(thermal_bridge_width 0.5)
				(island_removal_mode 0)
			)
			(polygon
				(pts
					(arc
						(start 390.700768 11.952732)
						(mid 388.846568 11.952732)
						(end 390.700768 11.952732)
					)
				)
			)
		)
		(zone
			(layer "B.Cu")
			(hatch none 0.5)
			(connect_pads
				(clearance 0)
			)
			(min_thickness 0.25)
			(keepout
				(tracks not_allowed)
				(vias allowed)
				(pads allowed)
				(copperpour not_allowed)
				(footprints allowed)
			)
			(placement
				(enabled no)
				(sheetname "")
			)
			(fill
				(thermal_gap 0.5)
				(thermal_bridge_width 0.5)
				(island_removal_mode 0)
			)
			(polygon
				(pts
					(xy 385.773168 10.134092) (xy 385.773168 10.229596) (xy 386.370068 10.229596) (xy 386.370068 10.635996)
					(xy 385.773168 10.635996) (xy 385.773168 10.729468) (xy 386.370068 10.729468) (xy 386.370068 11.135868)
					(xy 385.773168 11.135868) (xy 385.773168 11.231372) (xy 386.471668 11.231372) (xy 386.471668 10.134092)
				)
			)
		)
	)
	(footprint ""
		(layer "B.Cu")
		(at 135.697214 -209.333846 90)
		(property "Reference" "C2593"
			(at 0 0 90)
			(layer "B.SilkS")
			(hide yes)
			(effects
				(font
					(size 1.27 1.27)
				)
				(justify mirror)
			)
		)
		(property "Value" ""
			(at 0 0 90)
			(layer "B.Fab")
			(effects
				(font
					(size 1.27 1.27)
				)
				(justify mirror)
			)
		)
		(duplicate_pad_numbers_are_jumpers no)
		(fp_line
			(start 0.7874 -0.4064)
			(end -0.7874 -0.4064)
			(stroke
				(width 0.1524)
				(type default)
			)
			(layer "B.SilkS")
		)
		(fp_line
			(start -0.7874 -0.4064)
			(end -0.7874 0.4064)
			(stroke
				(width 0.1524)
				(type default)
			)
			(layer "B.SilkS")
		)
		(fp_line
			(start 0.7874 0.4064)
			(end 0.7874 -0.4064)
			(stroke
				(width 0.1524)
				(type default)
			)
			(layer "B.SilkS")
		)
		(fp_line
			(start -0.7874 0.4064)
			(end 0.7874 0.4064)
			(stroke
				(width 0.1524)
				(type default)
			)
			(layer "B.SilkS")
		)
		(fp_line
			(start 0.67945 -0.305054)
			(end 0.12065 -0.305054)
			(stroke
				(width 0.1)
				(type default)
			)
			(layer "B.Fab")
		)
		(fp_line
			(start 0.12065 -0.305054)
			(end 0.12065 -0.2794)
			(stroke
				(width 0.1)
				(type default)
			)
			(layer "B.Fab")
		)
		(fp_line
			(start -0.12065 -0.3048)
			(end -0.67945 -0.3048)
			(stroke
				(width 0.1)
				(type default)
			)
			(layer "B.Fab")
		)
		(fp_line
			(start -0.67945 -0.3048)
			(end -0.67945 0.3048)
			(stroke
				(width 0.1)
				(type default)
			)
			(layer "B.Fab")
		)
		(fp_line
			(start 0.12065 -0.2794)
			(end -0.12065 -0.2794)
			(stroke
				(width 0.1)
				(type default)
			)
			(layer "B.Fab")
		)
		(fp_line
			(start -0.12065 -0.2794)
			(end -0.12065 -0.3048)
			(stroke
				(width 0.1)
				(type default)
			)
			(layer "B.Fab")
		)
		(fp_line
			(start 0.12065 0.2794)
			(end 0.12065 0.3048)
			(stroke
				(width 0.1)
				(type default)
			)
			(layer "B.Fab")
		)
		(fp_line
			(start -0.120396 0.2794)
			(end 0.12065 0.2794)
			(stroke
				(width 0.1)
				(type default)
			)
			(layer "B.Fab")
		)
		(fp_line
			(start 0.67945 0.3048)
			(end 0.67945 -0.305054)
			(stroke
				(width 0.1)
				(type default)
			)
			(layer "B.Fab")
		)
		(fp_line
			(start 0.12065 0.3048)
			(end 0.67945 0.3048)
			(stroke
				(width 0.1)
				(type default)
			)
			(layer "B.Fab")
		)
		(fp_line
			(start -0.120396 0.3048)
			(end -0.120396 0.2794)
			(stroke
				(width 0.1)
				(type default)
			)
			(layer "B.Fab")
		)
		(fp_line
			(start -0.67945 0.3048)
			(end -0.120396 0.3048)
			(stroke
				(width 0.1)
				(type default)
			)
			(layer "B.Fab")
		)
		(pad "1" smd circle
			(at 0.40005 0 270)
			(size 0 0)
			(layers "B.Cu" "B.Mask" "B.Paste")
			(net "P1V8_CLI_VCORE")
		)
		(pad "2" smd circle
			(at -0.40005 0 270)
			(size 0 0)
			(layers "B.Cu" "B.Mask" "B.Paste")
			(net "GND")
		)
	)
	(footprint ""
		(layer "B.Cu")
		(at 114.649758 -321.385438 -90)
		(property "Reference" "R6455"
			(at 0 0 90)
			(layer "B.SilkS")
			(hide yes)
			(effects
				(font
					(size 1.27 1.27)
				)
				(justify mirror)
			)
		)
		(property "Value" ""
			(at 0 0 90)
			(layer "B.Fab")
			(effects
				(font
					(size 1.27 1.27)
				)
				(justify mirror)
			)
		)
		(duplicate_pad_numbers_are_jumpers no)
		(fp_line
			(start -0.7874 0.4064)
			(end 0.7874 0.4064)
			(stroke
				(width 0.1524)
				(type default)
			)
			(layer "B.SilkS")
		)
		(fp_line
			(start 0.7874 0.4064)
			(end 0.7874 -0.4064)
			(stroke
				(width 0.1524)
				(type default)
			)
			(layer "B.SilkS")
		)
		(fp_line
			(start -0.7874 -0.4064)
			(end -0.7874 0.4064)
			(stroke
				(width 0.1524)
				(type default)
			)
			(layer "B.SilkS")
		)
		(fp_line
			(start 0.7874 -0.4064)
			(end -0.7874 -0.4064)
			(stroke
				(width 0.1524)
				(type default)
			)
			(layer "B.SilkS")
		)
		(fp_line
			(start -0.67945 0.3048)
			(end -0.120396 0.3048)
			(stroke
				(width 0.1)
				(type default)
			)
			(layer "B.Fab")
		)
		(fp_line
			(start -0.120396 0.3048)
			(end -0.120396 0.2794)
			(stroke
				(width 0.1)
				(type default)
			)
			(layer "B.Fab")
		)
		(fp_line
			(start 0.12065 0.3048)
			(end 0.67945 0.3048)
			(stroke
				(width 0.1)
				(type default)
			)
			(layer "B.Fab")
		)
		(fp_line
			(start 0.67945 0.3048)
			(end 0.67945 -0.305054)
			(stroke
				(width 0.1)
				(type default)
			)
			(layer "B.Fab")
		)
		(fp_line
			(start -0.120396 0.2794)
			(end 0.12065 0.2794)
			(stroke
				(width 0.1)
				(type default)
			)
			(layer "B.Fab")
		)
		(fp_line
			(start 0.12065 0.2794)
			(end 0.12065 0.3048)
			(stroke
				(width 0.1)
				(type default)
			)
			(layer "B.Fab")
		)
		(fp_line
			(start -0.12065 -0.2794)
			(end -0.12065 -0.3048)
			(stroke
				(width 0.1)
				(type default)
			)
			(layer "B.Fab")
		)
		(fp_line
			(start 0.12065 -0.2794)
			(end -0.12065 -0.2794)
			(stroke
				(width 0.1)
				(type default)
			)
			(layer "B.Fab")
		)
		(fp_line
			(start -0.67945 -0.3048)
			(end -0.67945 0.3048)
			(stroke
				(width 0.1)
				(type default)
			)
			(layer "B.Fab")
		)
		(fp_line
			(start -0.12065 -0.3048)
			(end -0.67945 -0.3048)
			(stroke
				(width 0.1)
				(type default)
			)
			(layer "B.Fab")
		)
		(fp_line
			(start 0.12065 -0.305054)
			(end 0.12065 -0.2794)
			(stroke
				(width 0.1)
				(type default)
			)
			(layer "B.Fab")
		)
		(fp_line
			(start 0.67945 -0.305054)
			(end 0.12065 -0.305054)
			(stroke
				(width 0.1)
				(type default)
			)
			(layer "B.Fab")
		)
		(pad "1" smd circle
			(at 0.40005 0 90)
			(size 0 0)
			(layers "B.Cu" "B.Mask" "B.Paste")
			(net "P0V8_SERDES_VDDA_PEX0")
		)
		(pad "2" smd circle
			(at -0.40005 0 90)
			(size 0 0)
			(layers "B.Cu" "B.Mask" "B.Paste")
			(net "P0V8_SERDES_VDDA_PEX0_C6")
		)
	)
	(footprint ""
		(layer "B.Cu")
		(at 353.422204 -221.238572 180)
		(property "Reference" "C2061"
			(at 0 0 0)
			(layer "B.SilkS")
			(hide yes)
			(effects
				(font
					(size 1.27 1.27)
				)
				(justify mirror)
			)
		)
		(property "Value" ""
			(at 0 0 0)
			(layer "B.Fab")
			(effects
				(font
					(size 1.27 1.27)
				)
				(justify mirror)
			)
		)
		(duplicate_pad_numbers_are_jumpers no)
		(fp_line
			(start 0.69215 0.2921)
			(end 0.69215 -0.2921)
			(stroke
				(width 0.1524)
				(type default)
			)
			(layer "B.SilkS")
		)
		(fp_line
			(start 0.69215 -0.2921)
			(end -0.69215 -0.2921)
			(stroke
				(width 0.1524)
				(type default)
			)
			(layer "B.SilkS")
		)
		(fp_line
			(start -0.69215 0.2921)
			(end 0.69215 0.2921)
			(stroke
				(width 0.1524)
				(type default)
			)
			(layer "B.SilkS")
		)
		(fp_line
			(start -0.69215 -0.2921)
			(end -0.69215 0.2921)
			(stroke
				(width 0.1524)
				(type default)
			)
			(layer "B.SilkS")
		)
		(fp_line
			(start 0.51435 0.2794)
			(end 0.51435 -0.2794)
			(stroke
				(width 0.1)
				(type default)
			)
			(layer "B.Fab")
		)
		(fp_line
			(start 0.51435 -0.2794)
			(end -0.51435 -0.2794)
			(stroke
				(width 0.1)
				(type default)
			)
			(layer "B.Fab")
		)
		(fp_line
			(start -0.51435 0.2794)
			(end 0.51435 0.2794)
			(stroke
				(width 0.1)
				(type default)
			)
			(layer "B.Fab")
		)
		(fp_line
			(start -0.51435 -0.2794)
			(end -0.51435 0.2794)
			(stroke
				(width 0.1)
				(type default)
			)
			(layer "B.Fab")
		)
		(pad "1" smd circle
			(at 0.40005 0)
			(size 0 0)
			(layers "B.Cu" "B.Mask" "B.Paste")
			(net "P3V3_VCC_FPGA_CORE")
		)
		(pad "2" smd circle
			(at -0.40005 0)
			(size 0 0)
			(layers "B.Cu" "B.Mask" "B.Paste")
			(net "GND")
		)
		(zone
			(layer "B.Cu")
			(hatch none 0.5)
			(connect_pads
				(clearance 0)
			)
			(min_thickness 0.25)
			(keepout
				(tracks not_allowed)
				(vias allowed)
				(pads allowed)
				(copperpour not_allowed)
				(footprints allowed)
			)
			(placement
				(enabled no)
				(sheetname "")
			)
			(fill
				(thermal_gap 0.5)
				(thermal_bridge_width 0.5)
				(island_removal_mode 0)
			)
			(polygon
				(pts
					(xy 353.231704 -221.326202) (xy 353.323144 -221.384368) (xy 353.522534 -221.384368) (xy 353.612704 -221.326202)
					(xy 353.612704 -221.150942) (xy 353.522534 -221.092522) (xy 353.323144 -221.092522) (xy 353.231704 -221.150688)
				)
			)
		)
	)
	(footprint ""
		(layer "B.Cu")
		(at 105.021126 -303.649634 -90)
		(property "Reference" "PC70"
			(at 0 0 90)
			(layer "B.SilkS")
			(hide yes)
			(effects
				(font
					(size 1.27 1.27)
				)
				(justify mirror)
			)
		)
		(property "Value" ""
			(at 0 0 90)
			(layer "B.Fab")
			(effects
				(font
					(size 1.27 1.27)
				)
				(justify mirror)
			)
		)
		(duplicate_pad_numbers_are_jumpers no)
		(fp_line
			(start -1.524 0.762)
			(end 1.524 0.762)
			(stroke
				(width 0.1524)
				(type default)
			)
			(layer "B.SilkS")
		)
		(fp_line
			(start 1.524 0.762)
			(end 1.524 -0.762)
			(stroke
				(width 0.1524)
				(type default)
			)
			(layer "B.SilkS")
		)
		(fp_line
			(start -1.524 -0.762)
			(end -1.524 0.762)
			(stroke
				(width 0.1524)
				(type default)
			)
			(layer "B.SilkS")
		)
		(fp_line
			(start 1.524 -0.762)
			(end -1.524 -0.762)
			(stroke
				(width 0.1524)
				(type default)
			)
			(layer "B.SilkS")
		)
		(fp_line
			(start -1.1049 0.724916)
			(end -1.1049 -0.724916)
			(stroke
				(width 0.1)
				(type default)
			)
			(layer "B.Fab")
		)
		(fp_line
			(start 1.1049 0.724916)
			(end -1.1049 0.724916)
			(stroke
				(width 0.1)
				(type default)
			)
			(layer "B.Fab")
		)
		(fp_line
			(start -1.1049 -0.724916)
			(end 1.1049 -0.724916)
			(stroke
				(width 0.1)
				(type default)
			)
			(layer "B.Fab")
		)
		(fp_line
			(start 1.1049 -0.724916)
			(end 1.1049 0.724916)
			(stroke
				(width 0.1)
				(type default)
			)
			(layer "B.Fab")
		)
		(pad "1" smd rect
			(at 0.889 0 270)
			(size 1.016 1.27)
			(layers "B.Cu" "B.Mask" "B.Paste")
			(net "P0V8_PEX0")
		)
		(pad "2" smd rect
			(at -0.889 0 270)
			(size 1.016 1.27)
			(layers "B.Cu" "B.Mask" "B.Paste")
			(net "GND")
		)
	)
	(footprint ""
		(layer "B.Cu")
		(at 336.671412 -323.15531 -90)
		(property "Reference" "R6515"
			(at 0 0 90)
			(layer "B.SilkS")
			(hide yes)
			(effects
				(font
					(size 1.27 1.27)
				)
				(justify mirror)
			)
		)
		(property "Value" ""
			(at 0 0 90)
			(layer "B.Fab")
			(effects
				(font
					(size 1.27 1.27)
				)
				(justify mirror)
			)
		)
		(duplicate_pad_numbers_are_jumpers no)
		(fp_line
			(start -0.7874 0.4064)
			(end 0.7874 0.4064)
			(stroke
				(width 0.1524)
				(type default)
			)
			(layer "B.SilkS")
		)
		(fp_line
			(start 0.7874 0.4064)
			(end 0.7874 -0.4064)
			(stroke
				(width 0.1524)
				(type default)
			)
			(layer "B.SilkS")
		)
		(fp_line
			(start -0.7874 -0.4064)
			(end -0.7874 0.4064)
			(stroke
				(width 0.1524)
				(type default)
			)
			(layer "B.SilkS")
		)
		(fp_line
			(start 0.7874 -0.4064)
			(end -0.7874 -0.4064)
			(stroke
				(width 0.1524)
				(type default)
			)
			(layer "B.SilkS")
		)
		(fp_line
			(start -0.67945 0.3048)
			(end -0.120396 0.3048)
			(stroke
				(width 0.1)
				(type default)
			)
			(layer "B.Fab")
		)
		(fp_line
			(start -0.120396 0.3048)
			(end -0.120396 0.2794)
			(stroke
				(width 0.1)
				(type default)
			)
			(layer "B.Fab")
		)
		(fp_line
			(start 0.12065 0.3048)
			(end 0.67945 0.3048)
			(stroke
				(width 0.1)
				(type default)
			)
			(layer "B.Fab")
		)
		(fp_line
			(start 0.67945 0.3048)
			(end 0.67945 -0.305054)
			(stroke
				(width 0.1)
				(type default)
			)
			(layer "B.Fab")
		)
		(fp_line
			(start -0.120396 0.2794)
			(end 0.12065 0.2794)
			(stroke
				(width 0.1)
				(type default)
			)
			(layer "B.Fab")
		)
		(fp_line
			(start 0.12065 0.2794)
			(end 0.12065 0.3048)
			(stroke
				(width 0.1)
				(type default)
			)
			(layer "B.Fab")
		)
		(fp_line
			(start -0.12065 -0.2794)
			(end -0.12065 -0.3048)
			(stroke
				(width 0.1)
				(type default)
			)
			(layer "B.Fab")
		)
		(fp_line
			(start 0.12065 -0.2794)
			(end -0.12065 -0.2794)
			(stroke
				(width 0.1)
				(type default)
			)
			(layer "B.Fab")
		)
		(fp_line
			(start -0.67945 -0.3048)
			(end -0.67945 0.3048)
			(stroke
				(width 0.1)
				(type default)
			)
			(layer "B.Fab")
		)
		(fp_line
			(start -0.12065 -0.3048)
			(end -0.67945 -0.3048)
			(stroke
				(width 0.1)
				(type default)
			)
			(layer "B.Fab")
		)
		(fp_line
			(start 0.12065 -0.305054)
			(end 0.12065 -0.2794)
			(stroke
				(width 0.1)
				(type default)
			)
			(layer "B.Fab")
		)
		(fp_line
			(start 0.67945 -0.305054)
			(end 0.12065 -0.305054)
			(stroke
				(width 0.1)
				(type default)
			)
			(layer "B.Fab")
		)
		(pad "1" smd circle
			(at 0.40005 0 90)
			(size 0 0)
			(layers "B.Cu" "B.Mask" "B.Paste")
			(net "P0V8_SERDES_VDDA_PEX2")
		)
		(pad "2" smd circle
			(at -0.40005 0 90)
			(size 0 0)
			(layers "B.Cu" "B.Mask" "B.Paste")
			(net "P0V8_SERDES_VDDA_PEX2_C8")
		)
	)
	(footprint ""
		(layer "B.Cu")
		(at 237.631986 -357.130858)
		(property "Reference" "PR7148"
			(at 0 0 0)
			(layer "B.SilkS")
			(hide yes)
			(effects
				(font
					(size 1.27 1.27)
				)
				(justify mirror)
			)
		)
		(property "Value" ""
			(at 0 0 0)
			(layer "B.Fab")
			(effects
				(font
					(size 1.27 1.27)
				)
				(justify mirror)
			)
		)
		(duplicate_pad_numbers_are_jumpers no)
		(fp_line
			(start -0.7874 -0.4064)
			(end -0.7874 0.4064)
			(stroke
				(width 0.1524)
				(type default)
			)
			(layer "B.SilkS")
		)
		(fp_line
			(start -0.7874 0.4064)
			(end 0.7874 0.4064)
			(stroke
				(width 0.1524)
				(type default)
			)
			(layer "B.SilkS")
		)
		(fp_line
			(start 0.7874 -0.4064)
			(end -0.7874 -0.4064)
			(stroke
				(width 0.1524)
				(type default)
			)
			(layer "B.SilkS")
		)
		(fp_line
			(start 0.7874 0.4064)
			(end 0.7874 -0.4064)
			(stroke
				(width 0.1524)
				(type default)
			)
			(layer "B.SilkS")
		)
		(fp_line
			(start -0.67945 -0.3048)
			(end -0.67945 0.3048)
			(stroke
				(width 0.1)
				(type default)
			)
			(layer "B.Fab")
		)
		(fp_line
			(start -0.67945 0.3048)
			(end -0.120396 0.3048)
			(stroke
				(width 0.1)
				(type default)
			)
			(layer "B.Fab")
		)
		(fp_line
			(start -0.12065 -0.3048)
			(end -0.67945 -0.3048)
			(stroke
				(width 0.1)
				(type default)
			)
			(layer "B.Fab")
		)
		(fp_line
			(start -0.12065 -0.2794)
			(end -0.12065 -0.3048)
			(stroke
				(width 0.1)
				(type default)
			)
			(layer "B.Fab")
		)
		(fp_line
			(start -0.120396 0.2794)
			(end 0.12065 0.2794)
			(stroke
				(width 0.1)
				(type default)
			)
			(layer "B.Fab")
		)
		(fp_line
			(start -0.120396 0.3048)
			(end -0.120396 0.2794)
			(stroke
				(width 0.1)
				(type default)
			)
			(layer "B.Fab")
		)
		(fp_line
			(start 0.12065 -0.305054)
			(end 0.12065 -0.2794)
			(stroke
				(width 0.1)
				(type default)
			)
			(layer "B.Fab")
		)
		(fp_line
			(start 0.12065 -0.2794)
			(end -0.12065 -0.2794)
			(stroke
				(width 0.1)
				(type default)
			)
			(layer "B.Fab")
		)
		(fp_line
			(start 0.12065 0.2794)
			(end 0.12065 0.3048)
			(stroke
				(width 0.1)
				(type default)
			)
			(layer "B.Fab")
		)
		(fp_line
			(start 0.12065 0.3048)
			(end 0.67945 0.3048)
			(stroke
				(width 0.1)
				(type default)
			)
			(layer "B.Fab")
		)
		(fp_line
			(start 0.67945 -0.305054)
			(end 0.12065 -0.305054)
			(stroke
				(width 0.1)
				(type default)
			)
			(layer "B.Fab")
		)
		(fp_line
			(start 0.67945 0.3048)
			(end 0.67945 -0.305054)
			(stroke
				(width 0.1)
				(type default)
			)
			(layer "B.Fab")
		)
		(pad "1" smd circle
			(at 0.40005 0 180)
			(size 0 0)
			(layers "B.Cu" "B.Mask" "B.Paste")
			(net "P12V_HSC_ADC_P")
		)
		(pad "2" smd circle
			(at -0.40005 0 180)
			(size 0 0)
			(layers "B.Cu" "B.Mask" "B.Paste")
			(net "P12V_HSC_SENSE2_R2_P")
		)
	)
	(footprint ""
		(layer "B.Cu")
		(at 228.651054 -291.888926 180)
		(property "Reference" "PC993"
			(at 0 0 0)
			(layer "B.SilkS")
			(hide yes)
			(effects
				(font
					(size 1.27 1.27)
				)
				(justify mirror)
			)
		)
		(property "Value" ""
			(at 0 0 0)
			(layer "B.Fab")
			(effects
				(font
					(size 1.27 1.27)
				)
				(justify mirror)
			)
		)
		(duplicate_pad_numbers_are_jumpers no)
		(fp_line
			(start 1.524 0.762)
			(end 1.524 -0.762)
			(stroke
				(width 0.1524)
				(type default)
			)
			(layer "B.SilkS")
		)
		(fp_line
			(start 1.524 -0.762)
			(end -1.524 -0.762)
			(stroke
				(width 0.1524)
				(type default)
			)
			(layer "B.SilkS")
		)
		(fp_line
			(start -1.524 0.762)
			(end 1.524 0.762)
			(stroke
				(width 0.1524)
				(type default)
			)
			(layer "B.SilkS")
		)
		(fp_line
			(start -1.524 -0.762)
			(end -1.524 0.762)
			(stroke
				(width 0.1524)
				(type default)
			)
			(layer "B.SilkS")
		)
		(fp_line
			(start 1.1049 0.724916)
			(end -1.1049 0.724916)
			(stroke
				(width 0.1)
				(type default)
			)
			(layer "B.Fab")
		)
		(fp_line
			(start 1.1049 -0.724916)
			(end 1.1049 0.724916)
			(stroke
				(width 0.1)
				(type default)
			)
			(layer "B.Fab")
		)
		(fp_line
			(start -1.1049 0.724916)
			(end -1.1049 -0.724916)
			(stroke
				(width 0.1)
				(type default)
			)
			(layer "B.Fab")
		)
		(fp_line
			(start -1.1049 -0.724916)
			(end 1.1049 -0.724916)
			(stroke
				(width 0.1)
				(type default)
			)
			(layer "B.Fab")
		)
		(pad "1" smd rect
			(at 0.889 0 180)
			(size 1.016 1.27)
			(layers "B.Cu" "B.Mask" "B.Paste")
			(net "P1V25_PEX1_R")
		)
		(pad "2" smd rect
			(at -0.889 0 180)
			(size 1.016 1.27)
			(layers "B.Cu" "B.Mask" "B.Paste")
			(net "GND")
		)
	)
	(footprint ""
		(layer "B.Cu")
		(at 52.999894 -292.099746 90)
		(property "Reference" "C1188"
			(at 0 0 90)
			(layer "B.SilkS")
			(hide yes)
			(effects
				(font
					(size 1.27 1.27)
				)
				(justify mirror)
			)
		)
		(property "Value" ""
			(at 0 0 90)
			(layer "B.Fab")
			(effects
				(font
					(size 1.27 1.27)
				)
				(justify mirror)
			)
		)
		(duplicate_pad_numbers_are_jumpers no)
		(fp_line
			(start 0.299974 -0.150114)
			(end -0.299974 -0.150114)
			(stroke
				(width 0.1)
				(type default)
			)
			(layer "B.Fab")
		)
		(fp_line
			(start -0.299974 -0.150114)
			(end -0.299974 0.150114)
			(stroke
				(width 0.1)
				(type default)
			)
			(layer "B.Fab")
		)
		(fp_line
			(start 0.299974 0.150114)
			(end 0.299974 -0.150114)
			(stroke
				(width 0.1)
				(type default)
			)
			(layer "B.Fab")
		)
		(fp_line
			(start -0.299974 0.150114)
			(end 0.299974 0.150114)
			(stroke
				(width 0.1)
				(type default)
			)
			(layer "B.Fab")
		)
		(pad "1" smd rect
			(at 0.2667 0 270)
			(size 0.3048 0.381)
			(layers "B.Cu" "B.Mask" "B.Paste")
			(net "P0V8_SERDES_VDDA_PEX0")
		)
		(pad "2" smd rect
			(at -0.2667 0 270)
			(size 0.3048 0.381)
			(layers "B.Cu" "B.Mask" "B.Paste")
			(net "GND")
		)
	)
	(footprint ""
		(layer "B.Cu")
		(at 229.146354 -224.667064)
		(property "Reference" "R6813"
			(at 0 0 0)
			(layer "B.SilkS")
			(hide yes)
			(effects
				(font
					(size 1.27 1.27)
				)
				(justify mirror)
			)
		)
		(property "Value" ""
			(at 0 0 0)
			(layer "B.Fab")
			(effects
				(font
					(size 1.27 1.27)
				)
				(justify mirror)
			)
		)
		(duplicate_pad_numbers_are_jumpers no)
		(fp_line
			(start -0.7874 -0.4064)
			(end -0.7874 0.4064)
			(stroke
				(width 0.1524)
				(type default)
			)
			(layer "B.SilkS")
		)
		(fp_line
			(start -0.7874 0.4064)
			(end 0.7874 0.4064)
			(stroke
				(width 0.1524)
				(type default)
			)
			(layer "B.SilkS")
		)
		(fp_line
			(start 0.7874 -0.4064)
			(end -0.7874 -0.4064)
			(stroke
				(width 0.1524)
				(type default)
			)
			(layer "B.SilkS")
		)
		(fp_line
			(start 0.7874 0.4064)
			(end 0.7874 -0.4064)
			(stroke
				(width 0.1524)
				(type default)
			)
			(layer "B.SilkS")
		)
		(fp_line
			(start -0.67945 -0.3048)
			(end -0.67945 0.3048)
			(stroke
				(width 0.1)
				(type default)
			)
			(layer "B.Fab")
		)
		(fp_line
			(start -0.67945 0.3048)
			(end -0.120396 0.3048)
			(stroke
				(width 0.1)
				(type default)
			)
			(layer "B.Fab")
		)
		(fp_line
			(start -0.12065 -0.3048)
			(end -0.67945 -0.3048)
			(stroke
				(width 0.1)
				(type default)
			)
			(layer "B.Fab")
		)
		(fp_line
			(start -0.12065 -0.2794)
			(end -0.12065 -0.3048)
			(stroke
				(width 0.1)
				(type default)
			)
			(layer "B.Fab")
		)
		(fp_line
			(start -0.120396 0.2794)
			(end 0.12065 0.2794)
			(stroke
				(width 0.1)
				(type default)
			)
			(layer "B.Fab")
		)
		(fp_line
			(start -0.120396 0.3048)
			(end -0.120396 0.2794)
			(stroke
				(width 0.1)
				(type default)
			)
			(layer "B.Fab")
		)
		(fp_line
			(start 0.12065 -0.305054)
			(end 0.12065 -0.2794)
			(stroke
				(width 0.1)
				(type default)
			)
			(layer "B.Fab")
		)
		(fp_line
			(start 0.12065 -0.2794)
			(end -0.12065 -0.2794)
			(stroke
				(width 0.1)
				(type default)
			)
			(layer "B.Fab")
		)
		(fp_line
			(start 0.12065 0.2794)
			(end 0.12065 0.3048)
			(stroke
				(width 0.1)
				(type default)
			)
			(layer "B.Fab")
		)
		(fp_line
			(start 0.12065 0.3048)
			(end 0.67945 0.3048)
			(stroke
				(width 0.1)
				(type default)
			)
			(layer "B.Fab")
		)
		(fp_line
			(start 0.67945 -0.305054)
			(end 0.12065 -0.305054)
			(stroke
				(width 0.1)
				(type default)
			)
			(layer "B.Fab")
		)
		(fp_line
			(start 0.67945 0.3048)
			(end 0.67945 -0.305054)
			(stroke
				(width 0.1)
				(type default)
			)
			(layer "B.Fab")
		)
		(pad "1" smd circle
			(at 0.40005 0 180)
			(size 0 0)
			(layers "B.Cu" "B.Mask" "B.Paste")
			(net "BOARD_TYPE_0_ADC_R")
		)
		(pad "2" smd circle
			(at -0.40005 0 180)
			(size 0 0)
			(layers "B.Cu" "B.Mask" "B.Paste")
			(net "P3V3_AUX")
		)
	)
	(footprint ""
		(layer "B.Cu")
		(at 107.6325 -137.56132 90)
		(property "Reference" "PC33"
			(at 0 0 90)
			(layer "B.SilkS")
			(hide yes)
			(effects
				(font
					(size 1.27 1.27)
				)
				(justify mirror)
			)
		)
		(property "Value" ""
			(at 0 0 90)
			(layer "B.Fab")
			(effects
				(font
					(size 1.27 1.27)
				)
				(justify mirror)
			)
		)
		(duplicate_pad_numbers_are_jumpers no)
		(fp_line
			(start 1.524 -0.762)
			(end -1.524 -0.762)
			(stroke
				(width 0.1524)
				(type default)
			)
			(layer "B.SilkS")
		)
		(fp_line
			(start -1.524 -0.762)
			(end -1.524 0.762)
			(stroke
				(width 0.1524)
				(type default)
			)
			(layer "B.SilkS")
		)
		(fp_line
			(start 1.524 0.762)
			(end 1.524 -0.762)
			(stroke
				(width 0.1524)
				(type default)
			)
			(layer "B.SilkS")
		)
		(fp_line
			(start -1.524 0.762)
			(end 1.524 0.762)
			(stroke
				(width 0.1524)
				(type default)
			)
			(layer "B.SilkS")
		)
		(fp_line
			(start 1.1049 -0.724916)
			(end 1.1049 0.724916)
			(stroke
				(width 0.1)
				(type default)
			)
			(layer "B.Fab")
		)
		(fp_line
			(start -1.1049 -0.724916)
			(end 1.1049 -0.724916)
			(stroke
				(width 0.1)
				(type default)
			)
			(layer "B.Fab")
		)
		(fp_line
			(start 1.1049 0.724916)
			(end -1.1049 0.724916)
			(stroke
				(width 0.1)
				(type default)
			)
			(layer "B.Fab")
		)
		(fp_line
			(start -1.1049 0.724916)
			(end -1.1049 -0.724916)
			(stroke
				(width 0.1)
				(type default)
			)
			(layer "B.Fab")
		)
		(pad "1" smd rect
			(at 0.889 0 90)
			(size 1.016 1.27)
			(layers "B.Cu" "B.Mask" "B.Paste")
			(net "P3V3_AUX")
		)
		(pad "2" smd rect
			(at -0.889 0 90)
			(size 1.016 1.27)
			(layers "B.Cu" "B.Mask" "B.Paste")
			(net "GND")
		)
	)
	(footprint ""
		(layer "B.Cu")
		(at 25.15997 -220.924374 90)
		(property "Reference" "R3438"
			(at 0 0 90)
			(layer "B.SilkS")
			(hide yes)
			(effects
				(font
					(size 1.27 1.27)
				)
				(justify mirror)
			)
		)
		(property "Value" ""
			(at 0 0 90)
			(layer "B.Fab")
			(effects
				(font
					(size 1.27 1.27)
				)
				(justify mirror)
			)
		)
		(duplicate_pad_numbers_are_jumpers no)
		(fp_line
			(start 0.7874 -0.4064)
			(end -0.7874 -0.4064)
			(stroke
				(width 0.1524)
				(type default)
			)
			(layer "B.SilkS")
		)
		(fp_line
			(start -0.7874 -0.4064)
			(end -0.7874 0.4064)
			(stroke
				(width 0.1524)
				(type default)
			)
			(layer "B.SilkS")
		)
		(fp_line
			(start 0.7874 0.4064)
			(end 0.7874 -0.4064)
			(stroke
				(width 0.1524)
				(type default)
			)
			(layer "B.SilkS")
		)
		(fp_line
			(start -0.7874 0.4064)
			(end 0.7874 0.4064)
			(stroke
				(width 0.1524)
				(type default)
			)
			(layer "B.SilkS")
		)
		(fp_line
			(start 0.67945 -0.305054)
			(end 0.12065 -0.305054)
			(stroke
				(width 0.1)
				(type default)
			)
			(layer "B.Fab")
		)
		(fp_line
			(start 0.12065 -0.305054)
			(end 0.12065 -0.2794)
			(stroke
				(width 0.1)
				(type default)
			)
			(layer "B.Fab")
		)
		(fp_line
			(start -0.12065 -0.3048)
			(end -0.67945 -0.3048)
			(stroke
				(width 0.1)
				(type default)
			)
			(layer "B.Fab")
		)
		(fp_line
			(start -0.67945 -0.3048)
			(end -0.67945 0.3048)
			(stroke
				(width 0.1)
				(type default)
			)
			(layer "B.Fab")
		)
		(fp_line
			(start 0.12065 -0.2794)
			(end -0.12065 -0.2794)
			(stroke
				(width 0.1)
				(type default)
			)
			(layer "B.Fab")
		)
		(fp_line
			(start -0.12065 -0.2794)
			(end -0.12065 -0.3048)
			(stroke
				(width 0.1)
				(type default)
			)
			(layer "B.Fab")
		)
		(fp_line
			(start 0.12065 0.2794)
			(end 0.12065 0.3048)
			(stroke
				(width 0.1)
				(type default)
			)
			(layer "B.Fab")
		)
		(fp_line
			(start -0.120396 0.2794)
			(end 0.12065 0.2794)
			(stroke
				(width 0.1)
				(type default)
			)
			(layer "B.Fab")
		)
		(fp_line
			(start 0.67945 0.3048)
			(end 0.67945 -0.305054)
			(stroke
				(width 0.1)
				(type default)
			)
			(layer "B.Fab")
		)
		(fp_line
			(start 0.12065 0.3048)
			(end 0.67945 0.3048)
			(stroke
				(width 0.1)
				(type default)
			)
			(layer "B.Fab")
		)
		(fp_line
			(start -0.120396 0.3048)
			(end -0.120396 0.2794)
			(stroke
				(width 0.1)
				(type default)
			)
			(layer "B.Fab")
		)
		(fp_line
			(start -0.67945 0.3048)
			(end -0.120396 0.3048)
			(stroke
				(width 0.1)
				(type default)
			)
			(layer "B.Fab")
		)
		(pad "1" smd circle
			(at 0.40005 0 270)
			(size 0 0)
			(layers "B.Cu" "B.Mask" "B.Paste")
			(net "P1V8_PEX")
		)
		(pad "2" smd circle
			(at -0.40005 0 270)
			(size 0 0)
			(layers "B.Cu" "B.Mask" "B.Paste")
			(net "SPI_PEX0_SDIO3_R1")
		)
	)
	(footprint ""
		(layer "B.Cu")
		(at 381.127 -233.68)
		(property "Reference" "C2582"
			(at 0 0 0)
			(layer "B.SilkS")
			(hide yes)
			(effects
				(font
					(size 1.27 1.27)
				)
				(justify mirror)
			)
		)
		(property "Value" ""
			(at 0 0 0)
			(layer "B.Fab")
			(effects
				(font
					(size 1.27 1.27)
				)
				(justify mirror)
			)
		)
		(duplicate_pad_numbers_are_jumpers no)
		(fp_line
			(start -0.7874 -0.4064)
			(end -0.7874 0.4064)
			(stroke
				(width 0.1524)
				(type default)
			)
			(layer "B.SilkS")
		)
		(fp_line
			(start -0.7874 0.4064)
			(end 0.7874 0.4064)
			(stroke
				(width 0.1524)
				(type default)
			)
			(layer "B.SilkS")
		)
		(fp_line
			(start 0.7874 -0.4064)
			(end -0.7874 -0.4064)
			(stroke
				(width 0.1524)
				(type default)
			)
			(layer "B.SilkS")
		)
		(fp_line
			(start 0.7874 0.4064)
			(end 0.7874 -0.4064)
			(stroke
				(width 0.1524)
				(type default)
			)
			(layer "B.SilkS")
		)
		(fp_line
			(start -0.67945 -0.3048)
			(end -0.67945 0.3048)
			(stroke
				(width 0.1)
				(type default)
			)
			(layer "B.Fab")
		)
		(fp_line
			(start -0.67945 0.3048)
			(end -0.120396 0.3048)
			(stroke
				(width 0.1)
				(type default)
			)
			(layer "B.Fab")
		)
		(fp_line
			(start -0.12065 -0.3048)
			(end -0.67945 -0.3048)
			(stroke
				(width 0.1)
				(type default)
			)
			(layer "B.Fab")
		)
		(fp_line
			(start -0.12065 -0.2794)
			(end -0.12065 -0.3048)
			(stroke
				(width 0.1)
				(type default)
			)
			(layer "B.Fab")
		)
		(fp_line
			(start -0.120396 0.2794)
			(end 0.12065 0.2794)
			(stroke
				(width 0.1)
				(type default)
			)
			(layer "B.Fab")
		)
		(fp_line
			(start -0.120396 0.3048)
			(end -0.120396 0.2794)
			(stroke
				(width 0.1)
				(type default)
			)
			(layer "B.Fab")
		)
		(fp_line
			(start 0.12065 -0.305054)
			(end 0.12065 -0.2794)
			(stroke
				(width 0.1)
				(type default)
			)
			(layer "B.Fab")
		)
		(fp_line
			(start 0.12065 -0.2794)
			(end -0.12065 -0.2794)
			(stroke
				(width 0.1)
				(type default)
			)
			(layer "B.Fab")
		)
		(fp_line
			(start 0.12065 0.2794)
			(end 0.12065 0.3048)
			(stroke
				(width 0.1)
				(type default)
			)
			(layer "B.Fab")
		)
		(fp_line
			(start 0.12065 0.3048)
			(end 0.67945 0.3048)
			(stroke
				(width 0.1)
				(type default)
			)
			(layer "B.Fab")
		)
		(fp_line
			(start 0.67945 -0.305054)
			(end 0.12065 -0.305054)
			(stroke
				(width 0.1)
				(type default)
			)
			(layer "B.Fab")
		)
		(fp_line
			(start 0.67945 0.3048)
			(end 0.67945 -0.305054)
			(stroke
				(width 0.1)
				(type default)
			)
			(layer "B.Fab")
		)
		(pad "1" smd circle
			(at 0.40005 0 180)
			(size 0 0)
			(layers "B.Cu" "B.Mask" "B.Paste")
			(net "P3V3_SDB_VPHY")
		)
		(pad "2" smd circle
			(at -0.40005 0 180)
			(size 0 0)
			(layers "B.Cu" "B.Mask" "B.Paste")
			(net "GND")
		)
	)
	(footprint ""
		(layer "B.Cu")
		(at 172.424852 -305.399948 -90)
		(property "Reference" "C3145"
			(at 0 0 90)
			(layer "B.SilkS")
			(hide yes)
			(effects
				(font
					(size 1.27 1.27)
				)
				(justify mirror)
			)
		)
		(property "Value" ""
			(at 0 0 90)
			(layer "B.Fab")
			(effects
				(font
					(size 1.27 1.27)
				)
				(justify mirror)
			)
		)
		(duplicate_pad_numbers_are_jumpers no)
		(fp_line
			(start -0.299974 0.150114)
			(end 0.299974 0.150114)
			(stroke
				(width 0.1)
				(type default)
			)
			(layer "B.Fab")
		)
		(fp_line
			(start 0.299974 0.150114)
			(end 0.299974 -0.150114)
			(stroke
				(width 0.1)
				(type default)
			)
			(layer "B.Fab")
		)
		(fp_line
			(start -0.299974 -0.150114)
			(end -0.299974 0.150114)
			(stroke
				(width 0.1)
				(type default)
			)
			(layer "B.Fab")
		)
		(fp_line
			(start 0.299974 -0.150114)
			(end -0.299974 -0.150114)
			(stroke
				(width 0.1)
				(type default)
			)
			(layer "B.Fab")
		)
		(pad "1" smd rect
			(at 0.2667 0 90)
			(size 0.3048 0.381)
			(layers "B.Cu" "B.Mask" "B.Paste")
			(net "P1V25_SERDES_VDDPLL_PEX1")
		)
		(pad "2" smd rect
			(at -0.2667 0 90)
			(size 0.3048 0.381)
			(layers "B.Cu" "B.Mask" "B.Paste")
			(net "GND")
		)
	)
	(footprint ""
		(layer "B.Cu")
		(at 167.675052 -297.79976 90)
		(property "Reference" "C1401"
			(at 0 0 90)
			(layer "B.SilkS")
			(hide yes)
			(effects
				(font
					(size 1.27 1.27)
				)
				(justify mirror)
			)
		)
		(property "Value" ""
			(at 0 0 90)
			(layer "B.Fab")
			(effects
				(font
					(size 1.27 1.27)
				)
				(justify mirror)
			)
		)
		(duplicate_pad_numbers_are_jumpers no)
		(fp_line
			(start 0.299974 -0.150114)
			(end -0.299974 -0.150114)
			(stroke
				(width 0.1)
				(type default)
			)
			(layer "B.Fab")
		)
		(fp_line
			(start -0.299974 -0.150114)
			(end -0.299974 0.150114)
			(stroke
				(width 0.1)
				(type default)
			)
			(layer "B.Fab")
		)
		(fp_line
			(start 0.299974 0.150114)
			(end 0.299974 -0.150114)
			(stroke
				(width 0.1)
				(type default)
			)
			(layer "B.Fab")
		)
		(fp_line
			(start -0.299974 0.150114)
			(end 0.299974 0.150114)
			(stroke
				(width 0.1)
				(type default)
			)
			(layer "B.Fab")
		)
		(pad "1" smd rect
			(at 0.2667 0 270)
			(size 0.3048 0.381)
			(layers "B.Cu" "B.Mask" "B.Paste")
			(net "P0V8_PEX1")
		)
		(pad "2" smd rect
			(at -0.2667 0 270)
			(size 0.3048 0.381)
			(layers "B.Cu" "B.Mask" "B.Paste")
			(net "GND")
		)
	)
	(footprint ""
		(layer "B.Cu")
		(at 406.999948 -290.199826 90)
		(property "Reference" "C1938"
			(at 0 0 90)
			(layer "B.SilkS")
			(hide yes)
			(effects
				(font
					(size 1.27 1.27)
				)
				(justify mirror)
			)
		)
		(property "Value" ""
			(at 0 0 90)
			(layer "B.Fab")
			(effects
				(font
					(size 1.27 1.27)
				)
				(justify mirror)
			)
		)
		(duplicate_pad_numbers_are_jumpers no)
		(fp_line
			(start 0.299974 -0.150114)
			(end -0.299974 -0.150114)
			(stroke
				(width 0.1)
				(type default)
			)
			(layer "B.Fab")
		)
		(fp_line
			(start -0.299974 -0.150114)
			(end -0.299974 0.150114)
			(stroke
				(width 0.1)
				(type default)
			)
			(layer "B.Fab")
		)
		(fp_line
			(start 0.299974 0.150114)
			(end 0.299974 -0.150114)
			(stroke
				(width 0.1)
				(type default)
			)
			(layer "B.Fab")
		)
		(fp_line
			(start -0.299974 0.150114)
			(end 0.299974 0.150114)
			(stroke
				(width 0.1)
				(type default)
			)
			(layer "B.Fab")
		)
		(pad "1" smd rect
			(at 0.2667 0 270)
			(size 0.3048 0.381)
			(layers "B.Cu" "B.Mask" "B.Paste")
			(net "P0V8_SERDES_VDDA_PEX3")
		)
		(pad "2" smd rect
			(at -0.2667 0 270)
			(size 0.3048 0.381)
			(layers "B.Cu" "B.Mask" "B.Paste")
			(net "GND")
		)
	)
	(footprint ""
		(layer "B.Cu")
		(at 106.441494 -293.660068 90)
		(property "Reference" "PC87"
			(at 0 0 90)
			(layer "B.SilkS")
			(hide yes)
			(effects
				(font
					(size 1.27 1.27)
				)
				(justify mirror)
			)
		)
		(property "Value" ""
			(at 0 0 90)
			(layer "B.Fab")
			(effects
				(font
					(size 1.27 1.27)
				)
				(justify mirror)
			)
		)
		(duplicate_pad_numbers_are_jumpers no)
		(fp_line
			(start 4.84378 -2.150618)
			(end 4.53898 -2.150618)
			(stroke
				(width 0.1524)
				(type default)
			)
			(layer "B.SilkS")
		)
		(fp_line
			(start 4.84378 -2.150618)
			(end 4.842256 2.163064)
			(stroke
				(width 0.1524)
				(type default)
			)
			(layer "B.SilkS")
		)
		(fp_line
			(start 4.69138 -2.150618)
			(end 4.692396 2.161032)
			(stroke
				(width 0.1524)
				(type default)
			)
			(layer "B.SilkS")
		)
		(fp_line
			(start 4.53898 -2.150618)
			(end 4.539742 2.152142)
			(stroke
				(width 0.1524)
				(type default)
			)
			(layer "B.SilkS")
		)
		(fp_line
			(start 4.53898 -2.15011)
			(end -4.53898 -2.15011)
			(stroke
				(width 0.1524)
				(type default)
			)
			(layer "B.SilkS")
		)
		(fp_line
			(start -4.53898 -2.15011)
			(end -4.53898 2.15011)
			(stroke
				(width 0.1524)
				(type default)
			)
			(layer "B.SilkS")
		)
		(fp_line
			(start 4.53898 2.15011)
			(end 4.53898 -2.15011)
			(stroke
				(width 0.1524)
				(type default)
			)
			(layer "B.SilkS")
		)
		(fp_line
			(start -4.53898 2.15011)
			(end 4.53898 2.15011)
			(stroke
				(width 0.1524)
				(type default)
			)
			(layer "B.SilkS")
		)
		(fp_line
			(start 4.83108 2.150364)
			(end 4.447794 2.149348)
			(stroke
				(width 0.1524)
				(type default)
			)
			(layer "B.SilkS")
		)
		(fp_line
			(start 3.64998 -2.15011)
			(end -3.64998 -2.15011)
			(stroke
				(width 0.1)
				(type default)
			)
			(layer "B.Fab")
		)
		(fp_line
			(start -3.64998 -2.15011)
			(end -3.64998 2.15011)
			(stroke
				(width 0.1)
				(type default)
			)
			(layer "B.Fab")
		)
		(fp_line
			(start 3.64998 2.15011)
			(end 3.64998 -2.15011)
			(stroke
				(width 0.1)
				(type default)
			)
			(layer "B.Fab")
		)
		(fp_line
			(start -3.64998 2.15011)
			(end 3.64998 2.15011)
			(stroke
				(width 0.1)
				(type default)
			)
			(layer "B.Fab")
		)
		(fp_text user "+"
			(at 6.214872 -0.337058 90)
			(unlocked yes)
			(layer "B.SilkS")
			(effects
				(font
					(size 1.905 1.4224)
					(thickness 0.1524)
				)
				(justify left mirror)
			)
		)
		(fp_text user "-"
			(at -4.313174 -0.094488 90)
			(unlocked yes)
			(layer "B.SilkS")
			(effects
				(font
					(size 1.905 1.4224)
					(thickness 0.1524)
				)
				(justify left mirror)
			)
		)
		(fp_text user "+"
			(at 6.214872 -0.337058 90)
			(unlocked yes)
			(layer "B.Fab")
			(effects
				(font
					(size 1.905 1.4224)
					(thickness 0.1524)
				)
				(justify left mirror)
			)
		)
		(fp_text user "-"
			(at -4.313174 -0.094488 90)
			(unlocked yes)
			(layer "B.Fab")
			(effects
				(font
					(size 1.905 1.4224)
					(thickness 0.1524)
				)
				(justify left mirror)
			)
		)
		(pad "1" smd rect
			(at 3.199892 0 270)
			(size 2.413 2.8194)
			(layers "B.Cu" "B.Mask" "B.Paste")
			(net "P0V8_PEX0")
		)
		(pad "2" smd rect
			(at -3.199892 0 270)
			(size 2.413 2.8194)
			(layers "B.Cu" "B.Mask" "B.Paste")
			(net "GND")
		)
	)
	(footprint ""
		(layer "B.Cu")
		(at 115.935252 -325.180706 -90)
		(property "Reference" "C4203"
			(at 0 0 90)
			(layer "B.SilkS")
			(hide yes)
			(effects
				(font
					(size 1.27 1.27)
				)
				(justify mirror)
			)
		)
		(property "Value" ""
			(at 0 0 90)
			(layer "B.Fab")
			(effects
				(font
					(size 1.27 1.27)
				)
				(justify mirror)
			)
		)
		(duplicate_pad_numbers_are_jumpers no)
		(fp_line
			(start -1.2954 0.5842)
			(end 1.2954 0.5842)
			(stroke
				(width 0.1524)
				(type default)
			)
			(layer "B.SilkS")
		)
		(fp_line
			(start 1.2954 0.5842)
			(end 1.2954 -0.5842)
			(stroke
				(width 0.1524)
				(type default)
			)
			(layer "B.SilkS")
		)
		(fp_line
			(start -1.2954 -0.5842)
			(end -1.2954 0.5842)
			(stroke
				(width 0.1524)
				(type default)
			)
			(layer "B.SilkS")
		)
		(fp_line
			(start 1.2954 -0.5842)
			(end -1.2954 -0.5842)
			(stroke
				(width 0.1524)
				(type default)
			)
			(layer "B.SilkS")
		)
		(fp_line
			(start -0.8636 0.4572)
			(end 0.8636 0.4572)
			(stroke
				(width 0.1)
				(type default)
			)
			(layer "B.Fab")
		)
		(fp_line
			(start 0.8636 0.4572)
			(end 0.8636 0.4064)
			(stroke
				(width 0.1)
				(type default)
			)
			(layer "B.Fab")
		)
		(fp_line
			(start -1.1938 0.4064)
			(end -0.8636 0.4064)
			(stroke
				(width 0.1)
				(type default)
			)
			(layer "B.Fab")
		)
		(fp_line
			(start -0.8636 0.4064)
			(end -0.8636 0.4572)
			(stroke
				(width 0.1)
				(type default)
			)
			(layer "B.Fab")
		)
		(fp_line
			(start 0.8636 0.4064)
			(end 1.1938 0.4064)
			(stroke
				(width 0.1)
				(type default)
			)
			(layer "B.Fab")
		)
		(fp_line
			(start 1.1938 0.4064)
			(end 1.1938 -0.4064)
			(stroke
				(width 0.1)
				(type default)
			)
			(layer "B.Fab")
		)
		(fp_line
			(start -1.1938 -0.4064)
			(end -1.1938 0.4064)
			(stroke
				(width 0.1)
				(type default)
			)
			(layer "B.Fab")
		)
		(fp_line
			(start -0.8636 -0.4064)
			(end -1.1938 -0.4064)
			(stroke
				(width 0.1)
				(type default)
			)
			(layer "B.Fab")
		)
		(fp_line
			(start 0.8636 -0.4064)
			(end 0.8636 -0.4572)
			(stroke
				(width 0.1)
				(type default)
			)
			(layer "B.Fab")
		)
		(fp_line
			(start 1.1938 -0.4064)
			(end 0.8636 -0.4064)
			(stroke
				(width 0.1)
				(type default)
			)
			(layer "B.Fab")
		)
		(fp_line
			(start -0.8636 -0.4572)
			(end -0.8636 -0.4064)
			(stroke
				(width 0.1)
				(type default)
			)
			(layer "B.Fab")
		)
		(fp_line
			(start 0.8636 -0.4572)
			(end -0.8636 -0.4572)
			(stroke
				(width 0.1)
				(type default)
			)
			(layer "B.Fab")
		)
		(pad "1" smd rect
			(at 0.7366 0 180)
			(size 0.7112 0.8128)
			(layers "B.Cu" "B.Mask" "B.Paste")
			(net "P0V8_SERDES_VDDA_PEX0_C1")
		)
		(pad "2" smd rect
			(at -0.7366 0 180)
			(size 0.7112 0.8128)
			(layers "B.Cu" "B.Mask" "B.Paste")
			(net "GND")
		)
	)
	(footprint ""
		(layer "B.Cu")
		(at 339.575902 -308.746398 90)
		(property "Reference" "C4321"
			(at 0 0 90)
			(layer "B.SilkS")
			(hide yes)
			(effects
				(font
					(size 1.27 1.27)
				)
				(justify mirror)
			)
		)
		(property "Value" ""
			(at 0 0 90)
			(layer "B.Fab")
			(effects
				(font
					(size 1.27 1.27)
				)
				(justify mirror)
			)
		)
		(duplicate_pad_numbers_are_jumpers no)
		(fp_line
			(start 0.299974 -0.150114)
			(end -0.299974 -0.150114)
			(stroke
				(width 0.1)
				(type default)
			)
			(layer "B.Fab")
		)
		(fp_line
			(start -0.299974 -0.150114)
			(end -0.299974 0.150114)
			(stroke
				(width 0.1)
				(type default)
			)
			(layer "B.Fab")
		)
		(fp_line
			(start 0.299974 0.150114)
			(end 0.299974 -0.150114)
			(stroke
				(width 0.1)
				(type default)
			)
			(layer "B.Fab")
		)
		(fp_line
			(start -0.299974 0.150114)
			(end 0.299974 0.150114)
			(stroke
				(width 0.1)
				(type default)
			)
			(layer "B.Fab")
		)
		(pad "1" smd rect
			(at 0.2667 0 270)
			(size 0.3048 0.381)
			(layers "B.Cu" "B.Mask" "B.Paste")
			(net "P0V8_PEX2")
		)
		(pad "2" smd rect
			(at -0.2667 0 270)
			(size 0.3048 0.381)
			(layers "B.Cu" "B.Mask" "B.Paste")
			(net "GND")
		)
	)
	(footprint ""
		(layer "B.Cu")
		(at 399.400014 -301.599854 -90)
		(property "Reference" "C1957"
			(at 0 0 90)
			(layer "B.SilkS")
			(hide yes)
			(effects
				(font
					(size 1.27 1.27)
				)
				(justify mirror)
			)
		)
		(property "Value" ""
			(at 0 0 90)
			(layer "B.Fab")
			(effects
				(font
					(size 1.27 1.27)
				)
				(justify mirror)
			)
		)
		(duplicate_pad_numbers_are_jumpers no)
		(fp_line
			(start -0.299974 0.150114)
			(end 0.299974 0.150114)
			(stroke
				(width 0.1)
				(type default)
			)
			(layer "B.Fab")
		)
		(fp_line
			(start 0.299974 0.150114)
			(end 0.299974 -0.150114)
			(stroke
				(width 0.1)
				(type default)
			)
			(layer "B.Fab")
		)
		(fp_line
			(start -0.299974 -0.150114)
			(end -0.299974 0.150114)
			(stroke
				(width 0.1)
				(type default)
			)
			(layer "B.Fab")
		)
		(fp_line
			(start 0.299974 -0.150114)
			(end -0.299974 -0.150114)
			(stroke
				(width 0.1)
				(type default)
			)
			(layer "B.Fab")
		)
		(pad "1" smd rect
			(at 0.2667 0 90)
			(size 0.3048 0.381)
			(layers "B.Cu" "B.Mask" "B.Paste")
			(net "P0V8_SERDES_VDDA_PEX3")
		)
		(pad "2" smd rect
			(at -0.2667 0 90)
			(size 0.3048 0.381)
			(layers "B.Cu" "B.Mask" "B.Paste")
			(net "GND")
		)
	)
	(footprint ""
		(layer "B.Cu")
		(at 201.088244 -259.311648 -90)
		(property "Reference" "R6340"
			(at 0 0 90)
			(layer "B.SilkS")
			(hide yes)
			(effects
				(font
					(size 1.27 1.27)
				)
				(justify mirror)
			)
		)
		(property "Value" ""
			(at 0 0 90)
			(layer "B.Fab")
			(effects
				(font
					(size 1.27 1.27)
				)
				(justify mirror)
			)
		)
		(duplicate_pad_numbers_are_jumpers no)
		(fp_line
			(start -0.7874 0.4064)
			(end 0.7874 0.4064)
			(stroke
				(width 0.1524)
				(type default)
			)
			(layer "B.SilkS")
		)
		(fp_line
			(start 0.7874 0.4064)
			(end 0.7874 -0.4064)
			(stroke
				(width 0.1524)
				(type default)
			)
			(layer "B.SilkS")
		)
		(fp_line
			(start -0.7874 -0.4064)
			(end -0.7874 0.4064)
			(stroke
				(width 0.1524)
				(type default)
			)
			(layer "B.SilkS")
		)
		(fp_line
			(start 0.7874 -0.4064)
			(end -0.7874 -0.4064)
			(stroke
				(width 0.1524)
				(type default)
			)
			(layer "B.SilkS")
		)
		(fp_line
			(start -0.67945 0.3048)
			(end -0.120396 0.3048)
			(stroke
				(width 0.1)
				(type default)
			)
			(layer "B.Fab")
		)
		(fp_line
			(start -0.120396 0.3048)
			(end -0.120396 0.2794)
			(stroke
				(width 0.1)
				(type default)
			)
			(layer "B.Fab")
		)
		(fp_line
			(start 0.12065 0.3048)
			(end 0.67945 0.3048)
			(stroke
				(width 0.1)
				(type default)
			)
			(layer "B.Fab")
		)
		(fp_line
			(start 0.67945 0.3048)
			(end 0.67945 -0.305054)
			(stroke
				(width 0.1)
				(type default)
			)
			(layer "B.Fab")
		)
		(fp_line
			(start -0.120396 0.2794)
			(end 0.12065 0.2794)
			(stroke
				(width 0.1)
				(type default)
			)
			(layer "B.Fab")
		)
		(fp_line
			(start 0.12065 0.2794)
			(end 0.12065 0.3048)
			(stroke
				(width 0.1)
				(type default)
			)
			(layer "B.Fab")
		)
		(fp_line
			(start -0.12065 -0.2794)
			(end -0.12065 -0.3048)
			(stroke
				(width 0.1)
				(type default)
			)
			(layer "B.Fab")
		)
		(fp_line
			(start 0.12065 -0.2794)
			(end -0.12065 -0.2794)
			(stroke
				(width 0.1)
				(type default)
			)
			(layer "B.Fab")
		)
		(fp_line
			(start -0.67945 -0.3048)
			(end -0.67945 0.3048)
			(stroke
				(width 0.1)
				(type default)
			)
			(layer "B.Fab")
		)
		(fp_line
			(start -0.12065 -0.3048)
			(end -0.67945 -0.3048)
			(stroke
				(width 0.1)
				(type default)
			)
			(layer "B.Fab")
		)
		(fp_line
			(start 0.12065 -0.305054)
			(end 0.12065 -0.2794)
			(stroke
				(width 0.1)
				(type default)
			)
			(layer "B.Fab")
		)
		(fp_line
			(start 0.67945 -0.305054)
			(end 0.12065 -0.305054)
			(stroke
				(width 0.1)
				(type default)
			)
			(layer "B.Fab")
		)
		(pad "1" smd circle
			(at 0.40005 0 90)
			(size 0 0)
			(layers "B.Cu" "B.Mask" "B.Paste")
			(net "PEX_MUX_A1")
		)
		(pad "2" smd circle
			(at -0.40005 0 90)
			(size 0 0)
			(layers "B.Cu" "B.Mask" "B.Paste")
			(net "GND")
		)
	)
	(footprint ""
		(layer "B.Cu")
		(at 252.70968 -83.554316 -90)
		(property "Reference" "C2638"
			(at 0 0 90)
			(layer "B.SilkS")
			(hide yes)
			(effects
				(font
					(size 1.27 1.27)
				)
				(justify mirror)
			)
		)
		(property "Value" ""
			(at 0 0 90)
			(layer "B.Fab")
			(effects
				(font
					(size 1.27 1.27)
				)
				(justify mirror)
			)
		)
		(duplicate_pad_numbers_are_jumpers no)
		(fp_line
			(start -1.2954 0.5842)
			(end 1.2954 0.5842)
			(stroke
				(width 0.1524)
				(type default)
			)
			(layer "B.SilkS")
		)
		(fp_line
			(start 1.2954 0.5842)
			(end 1.2954 -0.5842)
			(stroke
				(width 0.1524)
				(type default)
			)
			(layer "B.SilkS")
		)
		(fp_line
			(start -1.2954 -0.5842)
			(end -1.2954 0.5842)
			(stroke
				(width 0.1524)
				(type default)
			)
			(layer "B.SilkS")
		)
		(fp_line
			(start 1.2954 -0.5842)
			(end -1.2954 -0.5842)
			(stroke
				(width 0.1524)
				(type default)
			)
			(layer "B.SilkS")
		)
		(fp_line
			(start -0.8636 0.4572)
			(end 0.8636 0.4572)
			(stroke
				(width 0.1)
				(type default)
			)
			(layer "B.Fab")
		)
		(fp_line
			(start 0.8636 0.4572)
			(end 0.8636 0.4064)
			(stroke
				(width 0.1)
				(type default)
			)
			(layer "B.Fab")
		)
		(fp_line
			(start -1.1938 0.4064)
			(end -0.8636 0.4064)
			(stroke
				(width 0.1)
				(type default)
			)
			(layer "B.Fab")
		)
		(fp_line
			(start -0.8636 0.4064)
			(end -0.8636 0.4572)
			(stroke
				(width 0.1)
				(type default)
			)
			(layer "B.Fab")
		)
		(fp_line
			(start 0.8636 0.4064)
			(end 1.1938 0.4064)
			(stroke
				(width 0.1)
				(type default)
			)
			(layer "B.Fab")
		)
		(fp_line
			(start 1.1938 0.4064)
			(end 1.1938 -0.4064)
			(stroke
				(width 0.1)
				(type default)
			)
			(layer "B.Fab")
		)
		(fp_line
			(start -1.1938 -0.4064)
			(end -1.1938 0.4064)
			(stroke
				(width 0.1)
				(type default)
			)
			(layer "B.Fab")
		)
		(fp_line
			(start -0.8636 -0.4064)
			(end -1.1938 -0.4064)
			(stroke
				(width 0.1)
				(type default)
			)
			(layer "B.Fab")
		)
		(fp_line
			(start 0.8636 -0.4064)
			(end 0.8636 -0.4572)
			(stroke
				(width 0.1)
				(type default)
			)
			(layer "B.Fab")
		)
		(fp_line
			(start 1.1938 -0.4064)
			(end 0.8636 -0.4064)
			(stroke
				(width 0.1)
				(type default)
			)
			(layer "B.Fab")
		)
		(fp_line
			(start -0.8636 -0.4572)
			(end -0.8636 -0.4064)
			(stroke
				(width 0.1)
				(type default)
			)
			(layer "B.Fab")
		)
		(fp_line
			(start 0.8636 -0.4572)
			(end -0.8636 -0.4572)
			(stroke
				(width 0.1)
				(type default)
			)
			(layer "B.Fab")
		)
		(pad "1" smd rect
			(at 0.7366 0 180)
			(size 0.7112 0.8128)
			(layers "B.Cu" "B.Mask" "B.Paste")
			(net "P3V3_CLK_GEN_VDDXTAL_CK440")
		)
		(pad "2" smd rect
			(at -0.7366 0 180)
			(size 0.7112 0.8128)
			(layers "B.Cu" "B.Mask" "B.Paste")
			(net "GND")
		)
	)
	(footprint ""
		(layer "B.Cu")
		(at 172.900086 -290.199826 90)
		(property "Reference" "C1485"
			(at 0 0 90)
			(layer "B.SilkS")
			(hide yes)
			(effects
				(font
					(size 1.27 1.27)
				)
				(justify mirror)
			)
		)
		(property "Value" ""
			(at 0 0 90)
			(layer "B.Fab")
			(effects
				(font
					(size 1.27 1.27)
				)
				(justify mirror)
			)
		)
		(duplicate_pad_numbers_are_jumpers no)
		(fp_line
			(start 0.299974 -0.150114)
			(end -0.299974 -0.150114)
			(stroke
				(width 0.1)
				(type default)
			)
			(layer "B.Fab")
		)
		(fp_line
			(start -0.299974 -0.150114)
			(end -0.299974 0.150114)
			(stroke
				(width 0.1)
				(type default)
			)
			(layer "B.Fab")
		)
		(fp_line
			(start 0.299974 0.150114)
			(end 0.299974 -0.150114)
			(stroke
				(width 0.1)
				(type default)
			)
			(layer "B.Fab")
		)
		(fp_line
			(start -0.299974 0.150114)
			(end 0.299974 0.150114)
			(stroke
				(width 0.1)
				(type default)
			)
			(layer "B.Fab")
		)
		(pad "1" smd rect
			(at 0.2667 0 270)
			(size 0.3048 0.381)
			(layers "B.Cu" "B.Mask" "B.Paste")
			(net "P0V8_SERDES_VDDA_PEX1")
		)
		(pad "2" smd rect
			(at -0.2667 0 270)
			(size 0.3048 0.381)
			(layers "B.Cu" "B.Mask" "B.Paste")
			(net "GND")
		)
	)
	(footprint ""
		(layer "B.Cu")
		(at 98.292412 -352.735388 180)
		(property "Reference" "R6375"
			(at 0 0 0)
			(layer "B.SilkS")
			(hide yes)
			(effects
				(font
					(size 1.27 1.27)
				)
				(justify mirror)
			)
		)
		(property "Value" ""
			(at 0 0 0)
			(layer "B.Fab")
			(effects
				(font
					(size 1.27 1.27)
				)
				(justify mirror)
			)
		)
		(duplicate_pad_numbers_are_jumpers no)
		(fp_line
			(start 0.7874 0.4064)
			(end 0.7874 -0.4064)
			(stroke
				(width 0.1524)
				(type default)
			)
			(layer "B.SilkS")
		)
		(fp_line
			(start 0.7874 -0.4064)
			(end -0.7874 -0.4064)
			(stroke
				(width 0.1524)
				(type default)
			)
			(layer "B.SilkS")
		)
		(fp_line
			(start -0.7874 0.4064)
			(end 0.7874 0.4064)
			(stroke
				(width 0.1524)
				(type default)
			)
			(layer "B.SilkS")
		)
		(fp_line
			(start -0.7874 -0.4064)
			(end -0.7874 0.4064)
			(stroke
				(width 0.1524)
				(type default)
			)
			(layer "B.SilkS")
		)
		(fp_line
			(start 0.67945 0.3048)
			(end 0.67945 -0.305054)
			(stroke
				(width 0.1)
				(type default)
			)
			(layer "B.Fab")
		)
		(fp_line
			(start 0.67945 -0.305054)
			(end 0.12065 -0.305054)
			(stroke
				(width 0.1)
				(type default)
			)
			(layer "B.Fab")
		)
		(fp_line
			(start 0.12065 0.3048)
			(end 0.67945 0.3048)
			(stroke
				(width 0.1)
				(type default)
			)
			(layer "B.Fab")
		)
		(fp_line
			(start 0.12065 0.2794)
			(end 0.12065 0.3048)
			(stroke
				(width 0.1)
				(type default)
			)
			(layer "B.Fab")
		)
		(fp_line
			(start 0.12065 -0.2794)
			(end -0.12065 -0.2794)
			(stroke
				(width 0.1)
				(type default)
			)
			(layer "B.Fab")
		)
		(fp_line
			(start 0.12065 -0.305054)
			(end 0.12065 -0.2794)
			(stroke
				(width 0.1)
				(type default)
			)
			(layer "B.Fab")
		)
		(fp_line
			(start -0.120396 0.3048)
			(end -0.120396 0.2794)
			(stroke
				(width 0.1)
				(type default)
			)
			(layer "B.Fab")
		)
		(fp_line
			(start -0.120396 0.2794)
			(end 0.12065 0.2794)
			(stroke
				(width 0.1)
				(type default)
			)
			(layer "B.Fab")
		)
		(fp_line
			(start -0.12065 -0.2794)
			(end -0.12065 -0.3048)
			(stroke
				(width 0.1)
				(type default)
			)
			(layer "B.Fab")
		)
		(fp_line
			(start -0.12065 -0.3048)
			(end -0.67945 -0.3048)
			(stroke
				(width 0.1)
				(type default)
			)
			(layer "B.Fab")
		)
		(fp_line
			(start -0.67945 0.3048)
			(end -0.120396 0.3048)
			(stroke
				(width 0.1)
				(type default)
			)
			(layer "B.Fab")
		)
		(fp_line
			(start -0.67945 -0.3048)
			(end -0.67945 0.3048)
			(stroke
				(width 0.1)
				(type default)
			)
			(layer "B.Fab")
		)
		(pad "1" smd circle
			(at 0.40005 0)
			(size 0 0)
			(layers "B.Cu" "B.Mask" "B.Paste")
			(net "CLK_100M_DB800ZL_PEX0_S3_R_DN")
		)
		(pad "2" smd circle
			(at -0.40005 0)
			(size 0 0)
			(layers "B.Cu" "B.Mask" "B.Paste")
			(net "CLK_100M_DB800ZL_PEX0_S3_DN")
		)
	)
	(footprint ""
		(layer "B.Cu")
		(at 69.149976 -294.4749 180)
		(property "Reference" "C1163"
			(at 0 0 0)
			(layer "B.SilkS")
			(hide yes)
			(effects
				(font
					(size 1.27 1.27)
				)
				(justify mirror)
			)
		)
		(property "Value" ""
			(at 0 0 0)
			(layer "B.Fab")
			(effects
				(font
					(size 1.27 1.27)
				)
				(justify mirror)
			)
		)
		(duplicate_pad_numbers_are_jumpers no)
		(fp_line
			(start 0.299974 0.150114)
			(end 0.299974 -0.150114)
			(stroke
				(width 0.1)
				(type default)
			)
			(layer "B.Fab")
		)
		(fp_line
			(start 0.299974 -0.150114)
			(end -0.299974 -0.150114)
			(stroke
				(width 0.1)
				(type default)
			)
			(layer "B.Fab")
		)
		(fp_line
			(start -0.299974 0.150114)
			(end 0.299974 0.150114)
			(stroke
				(width 0.1)
				(type default)
			)
			(layer "B.Fab")
		)
		(fp_line
			(start -0.299974 -0.150114)
			(end -0.299974 0.150114)
			(stroke
				(width 0.1)
				(type default)
			)
			(layer "B.Fab")
		)
		(pad "1" smd rect
			(at 0.2667 0)
			(size 0.3048 0.381)
			(layers "B.Cu" "B.Mask" "B.Paste")
			(net "P0V8_SERDES_VDDA_PEX0")
		)
		(pad "2" smd rect
			(at -0.2667 0)
			(size 0.3048 0.381)
			(layers "B.Cu" "B.Mask" "B.Paste")
			(net "GND")
		)
	)
	(footprint ""
		(layer "B.Cu")
		(at 111.166656 -87.089996)
		(property "Reference" "C2664"
			(at 0 0 0)
			(layer "B.SilkS")
			(hide yes)
			(effects
				(font
					(size 1.27 1.27)
				)
				(justify mirror)
			)
		)
		(property "Value" ""
			(at 0 0 0)
			(layer "B.Fab")
			(effects
				(font
					(size 1.27 1.27)
				)
				(justify mirror)
			)
		)
		(duplicate_pad_numbers_are_jumpers no)
		(fp_line
			(start -0.7874 -0.4064)
			(end -0.7874 0.4064)
			(stroke
				(width 0.1524)
				(type default)
			)
			(layer "B.SilkS")
		)
		(fp_line
			(start -0.7874 0.4064)
			(end 0.7874 0.4064)
			(stroke
				(width 0.1524)
				(type default)
			)
			(layer "B.SilkS")
		)
		(fp_line
			(start 0.7874 -0.4064)
			(end -0.7874 -0.4064)
			(stroke
				(width 0.1524)
				(type default)
			)
			(layer "B.SilkS")
		)
		(fp_line
			(start 0.7874 0.4064)
			(end 0.7874 -0.4064)
			(stroke
				(width 0.1524)
				(type default)
			)
			(layer "B.SilkS")
		)
		(fp_line
			(start -0.67945 -0.3048)
			(end -0.67945 0.3048)
			(stroke
				(width 0.1)
				(type default)
			)
			(layer "B.Fab")
		)
		(fp_line
			(start -0.67945 0.3048)
			(end -0.120396 0.3048)
			(stroke
				(width 0.1)
				(type default)
			)
			(layer "B.Fab")
		)
		(fp_line
			(start -0.12065 -0.3048)
			(end -0.67945 -0.3048)
			(stroke
				(width 0.1)
				(type default)
			)
			(layer "B.Fab")
		)
		(fp_line
			(start -0.12065 -0.2794)
			(end -0.12065 -0.3048)
			(stroke
				(width 0.1)
				(type default)
			)
			(layer "B.Fab")
		)
		(fp_line
			(start -0.120396 0.2794)
			(end 0.12065 0.2794)
			(stroke
				(width 0.1)
				(type default)
			)
			(layer "B.Fab")
		)
		(fp_line
			(start -0.120396 0.3048)
			(end -0.120396 0.2794)
			(stroke
				(width 0.1)
				(type default)
			)
			(layer "B.Fab")
		)
		(fp_line
			(start 0.12065 -0.305054)
			(end 0.12065 -0.2794)
			(stroke
				(width 0.1)
				(type default)
			)
			(layer "B.Fab")
		)
		(fp_line
			(start 0.12065 -0.2794)
			(end -0.12065 -0.2794)
			(stroke
				(width 0.1)
				(type default)
			)
			(layer "B.Fab")
		)
		(fp_line
			(start 0.12065 0.2794)
			(end 0.12065 0.3048)
			(stroke
				(width 0.1)
				(type default)
			)
			(layer "B.Fab")
		)
		(fp_line
			(start 0.12065 0.3048)
			(end 0.67945 0.3048)
			(stroke
				(width 0.1)
				(type default)
			)
			(layer "B.Fab")
		)
		(fp_line
			(start 0.67945 -0.305054)
			(end 0.12065 -0.305054)
			(stroke
				(width 0.1)
				(type default)
			)
			(layer "B.Fab")
		)
		(fp_line
			(start 0.67945 0.3048)
			(end 0.67945 -0.305054)
			(stroke
				(width 0.1)
				(type default)
			)
			(layer "B.Fab")
		)
		(pad "1" smd circle
			(at 0.40005 0 180)
			(size 0 0)
			(layers "B.Cu" "B.Mask" "B.Paste")
			(net "P3V3_VDD_9ZXL0851_0_7")
		)
		(pad "2" smd circle
			(at -0.40005 0 180)
			(size 0 0)
			(layers "B.Cu" "B.Mask" "B.Paste")
			(net "GND")
		)
	)
	(footprint ""
		(layer "B.Cu")
		(at 415.074862 -286.399732 90)
		(property "Reference" "C3506"
			(at 0 0 90)
			(layer "B.SilkS")
			(hide yes)
			(effects
				(font
					(size 1.27 1.27)
				)
				(justify mirror)
			)
		)
		(property "Value" ""
			(at 0 0 90)
			(layer "B.Fab")
			(effects
				(font
					(size 1.27 1.27)
				)
				(justify mirror)
			)
		)
		(duplicate_pad_numbers_are_jumpers no)
		(fp_line
			(start 0.299974 -0.150114)
			(end -0.299974 -0.150114)
			(stroke
				(width 0.1)
				(type default)
			)
			(layer "B.Fab")
		)
		(fp_line
			(start -0.299974 -0.150114)
			(end -0.299974 0.150114)
			(stroke
				(width 0.1)
				(type default)
			)
			(layer "B.Fab")
		)
		(fp_line
			(start 0.299974 0.150114)
			(end 0.299974 -0.150114)
			(stroke
				(width 0.1)
				(type default)
			)
			(layer "B.Fab")
		)
		(fp_line
			(start -0.299974 0.150114)
			(end 0.299974 0.150114)
			(stroke
				(width 0.1)
				(type default)
			)
			(layer "B.Fab")
		)
		(pad "1" smd rect
			(at 0.2667 0 270)
			(size 0.3048 0.381)
			(layers "B.Cu" "B.Mask" "B.Paste")
			(net "P1V25_SERDES_VDDPLL_PEX3")
		)
		(pad "2" smd rect
			(at -0.2667 0 270)
			(size 0.3048 0.381)
			(layers "B.Cu" "B.Mask" "B.Paste")
			(net "GND")
		)
	)
	(footprint ""
		(layer "B.Cu")
		(at 351.645982 -144.526 180)
		(property "Reference" "R4798"
			(at 0 0 0)
			(layer "B.SilkS")
			(hide yes)
			(effects
				(font
					(size 1.27 1.27)
				)
				(justify mirror)
			)
		)
		(property "Value" ""
			(at 0 0 0)
			(layer "B.Fab")
			(effects
				(font
					(size 1.27 1.27)
				)
				(justify mirror)
			)
		)
		(duplicate_pad_numbers_are_jumpers no)
		(fp_line
			(start 0.7874 0.4064)
			(end 0.7874 -0.4064)
			(stroke
				(width 0.1524)
				(type default)
			)
			(layer "B.SilkS")
		)
		(fp_line
			(start 0.7874 -0.4064)
			(end -0.7874 -0.4064)
			(stroke
				(width 0.1524)
				(type default)
			)
			(layer "B.SilkS")
		)
		(fp_line
			(start -0.7874 0.4064)
			(end 0.7874 0.4064)
			(stroke
				(width 0.1524)
				(type default)
			)
			(layer "B.SilkS")
		)
		(fp_line
			(start -0.7874 -0.4064)
			(end -0.7874 0.4064)
			(stroke
				(width 0.1524)
				(type default)
			)
			(layer "B.SilkS")
		)
		(fp_line
			(start 0.67945 0.3048)
			(end 0.67945 -0.305054)
			(stroke
				(width 0.1)
				(type default)
			)
			(layer "B.Fab")
		)
		(fp_line
			(start 0.67945 -0.305054)
			(end 0.12065 -0.305054)
			(stroke
				(width 0.1)
				(type default)
			)
			(layer "B.Fab")
		)
		(fp_line
			(start 0.12065 0.3048)
			(end 0.67945 0.3048)
			(stroke
				(width 0.1)
				(type default)
			)
			(layer "B.Fab")
		)
		(fp_line
			(start 0.12065 0.2794)
			(end 0.12065 0.3048)
			(stroke
				(width 0.1)
				(type default)
			)
			(layer "B.Fab")
		)
		(fp_line
			(start 0.12065 -0.2794)
			(end -0.12065 -0.2794)
			(stroke
				(width 0.1)
				(type default)
			)
			(layer "B.Fab")
		)
		(fp_line
			(start 0.12065 -0.305054)
			(end 0.12065 -0.2794)
			(stroke
				(width 0.1)
				(type default)
			)
			(layer "B.Fab")
		)
		(fp_line
			(start -0.120396 0.3048)
			(end -0.120396 0.2794)
			(stroke
				(width 0.1)
				(type default)
			)
			(layer "B.Fab")
		)
		(fp_line
			(start -0.120396 0.2794)
			(end 0.12065 0.2794)
			(stroke
				(width 0.1)
				(type default)
			)
			(layer "B.Fab")
		)
		(fp_line
			(start -0.12065 -0.2794)
			(end -0.12065 -0.3048)
			(stroke
				(width 0.1)
				(type default)
			)
			(layer "B.Fab")
		)
		(fp_line
			(start -0.12065 -0.3048)
			(end -0.67945 -0.3048)
			(stroke
				(width 0.1)
				(type default)
			)
			(layer "B.Fab")
		)
		(fp_line
			(start -0.67945 0.3048)
			(end -0.120396 0.3048)
			(stroke
				(width 0.1)
				(type default)
			)
			(layer "B.Fab")
		)
		(fp_line
			(start -0.67945 -0.3048)
			(end -0.67945 0.3048)
			(stroke
				(width 0.1)
				(type default)
			)
			(layer "B.Fab")
		)
		(pad "1" smd circle
			(at 0.40005 0)
			(size 0 0)
			(layers "B.Cu" "B.Mask" "B.Paste")
			(net "P3V3_AUX")
		)
		(pad "2" smd circle
			(at -0.40005 0)
			(size 0 0)
			(layers "B.Cu" "B.Mask" "B.Paste")
			(net "RST_PEX_NIC7_PERST_R_N")
		)
	)
	(footprint ""
		(layer "B.Cu")
		(at 344.645234 -326.945498 -90)
		(property "Reference" "C4312"
			(at 0 0 90)
			(layer "B.SilkS")
			(hide yes)
			(effects
				(font
					(size 1.27 1.27)
				)
				(justify mirror)
			)
		)
		(property "Value" ""
			(at 0 0 90)
			(layer "B.Fab")
			(effects
				(font
					(size 1.27 1.27)
				)
				(justify mirror)
			)
		)
		(duplicate_pad_numbers_are_jumpers no)
		(fp_line
			(start -1.2954 0.5842)
			(end 1.2954 0.5842)
			(stroke
				(width 0.1524)
				(type default)
			)
			(layer "B.SilkS")
		)
		(fp_line
			(start 1.2954 0.5842)
			(end 1.2954 -0.5842)
			(stroke
				(width 0.1524)
				(type default)
			)
			(layer "B.SilkS")
		)
		(fp_line
			(start -1.2954 -0.5842)
			(end -1.2954 0.5842)
			(stroke
				(width 0.1524)
				(type default)
			)
			(layer "B.SilkS")
		)
		(fp_line
			(start 1.2954 -0.5842)
			(end -1.2954 -0.5842)
			(stroke
				(width 0.1524)
				(type default)
			)
			(layer "B.SilkS")
		)
		(fp_line
			(start -0.8636 0.4572)
			(end 0.8636 0.4572)
			(stroke
				(width 0.1)
				(type default)
			)
			(layer "B.Fab")
		)
		(fp_line
			(start 0.8636 0.4572)
			(end 0.8636 0.4064)
			(stroke
				(width 0.1)
				(type default)
			)
			(layer "B.Fab")
		)
		(fp_line
			(start -1.1938 0.4064)
			(end -0.8636 0.4064)
			(stroke
				(width 0.1)
				(type default)
			)
			(layer "B.Fab")
		)
		(fp_line
			(start -0.8636 0.4064)
			(end -0.8636 0.4572)
			(stroke
				(width 0.1)
				(type default)
			)
			(layer "B.Fab")
		)
		(fp_line
			(start 0.8636 0.4064)
			(end 1.1938 0.4064)
			(stroke
				(width 0.1)
				(type default)
			)
			(layer "B.Fab")
		)
		(fp_line
			(start 1.1938 0.4064)
			(end 1.1938 -0.4064)
			(stroke
				(width 0.1)
				(type default)
			)
			(layer "B.Fab")
		)
		(fp_line
			(start -1.1938 -0.4064)
			(end -1.1938 0.4064)
			(stroke
				(width 0.1)
				(type default)
			)
			(layer "B.Fab")
		)
		(fp_line
			(start -0.8636 -0.4064)
			(end -1.1938 -0.4064)
			(stroke
				(width 0.1)
				(type default)
			)
			(layer "B.Fab")
		)
		(fp_line
			(start 0.8636 -0.4064)
			(end 0.8636 -0.4572)
			(stroke
				(width 0.1)
				(type default)
			)
			(layer "B.Fab")
		)
		(fp_line
			(start 1.1938 -0.4064)
			(end 0.8636 -0.4064)
			(stroke
				(width 0.1)
				(type default)
			)
			(layer "B.Fab")
		)
		(fp_line
			(start -0.8636 -0.4572)
			(end -0.8636 -0.4064)
			(stroke
				(width 0.1)
				(type default)
			)
			(layer "B.Fab")
		)
		(fp_line
			(start 0.8636 -0.4572)
			(end -0.8636 -0.4572)
			(stroke
				(width 0.1)
				(type default)
			)
			(layer "B.Fab")
		)
		(pad "1" smd rect
			(at 0.7366 0 180)
			(size 0.7112 0.8128)
			(layers "B.Cu" "B.Mask" "B.Paste")
			(net "P0V8_SERDES_VDDA_PEX2_C2")
		)
		(pad "2" smd rect
			(at -0.7366 0 180)
			(size 0.7112 0.8128)
			(layers "B.Cu" "B.Mask" "B.Paste")
			(net "GND")
		)
	)
	(footprint ""
		(layer "B.Cu")
		(at 231.466644 -231.225598 90)
		(property "Reference" "R4541"
			(at 0 0 90)
			(layer "B.SilkS")
			(hide yes)
			(effects
				(font
					(size 1.27 1.27)
				)
				(justify mirror)
			)
		)
		(property "Value" ""
			(at 0 0 90)
			(layer "B.Fab")
			(effects
				(font
					(size 1.27 1.27)
				)
				(justify mirror)
			)
		)
		(duplicate_pad_numbers_are_jumpers no)
		(fp_line
			(start 0.7874 -0.4064)
			(end -0.7874 -0.4064)
			(stroke
				(width 0.1524)
				(type default)
			)
			(layer "B.SilkS")
		)
		(fp_line
			(start -0.7874 -0.4064)
			(end -0.7874 0.4064)
			(stroke
				(width 0.1524)
				(type default)
			)
			(layer "B.SilkS")
		)
		(fp_line
			(start 0.7874 0.4064)
			(end 0.7874 -0.4064)
			(stroke
				(width 0.1524)
				(type default)
			)
			(layer "B.SilkS")
		)
		(fp_line
			(start -0.7874 0.4064)
			(end 0.7874 0.4064)
			(stroke
				(width 0.1524)
				(type default)
			)
			(layer "B.SilkS")
		)
		(fp_line
			(start 0.67945 -0.305054)
			(end 0.12065 -0.305054)
			(stroke
				(width 0.1)
				(type default)
			)
			(layer "B.Fab")
		)
		(fp_line
			(start 0.12065 -0.305054)
			(end 0.12065 -0.2794)
			(stroke
				(width 0.1)
				(type default)
			)
			(layer "B.Fab")
		)
		(fp_line
			(start -0.12065 -0.3048)
			(end -0.67945 -0.3048)
			(stroke
				(width 0.1)
				(type default)
			)
			(layer "B.Fab")
		)
		(fp_line
			(start -0.67945 -0.3048)
			(end -0.67945 0.3048)
			(stroke
				(width 0.1)
				(type default)
			)
			(layer "B.Fab")
		)
		(fp_line
			(start 0.12065 -0.2794)
			(end -0.12065 -0.2794)
			(stroke
				(width 0.1)
				(type default)
			)
			(layer "B.Fab")
		)
		(fp_line
			(start -0.12065 -0.2794)
			(end -0.12065 -0.3048)
			(stroke
				(width 0.1)
				(type default)
			)
			(layer "B.Fab")
		)
		(fp_line
			(start 0.12065 0.2794)
			(end 0.12065 0.3048)
			(stroke
				(width 0.1)
				(type default)
			)
			(layer "B.Fab")
		)
		(fp_line
			(start -0.120396 0.2794)
			(end 0.12065 0.2794)
			(stroke
				(width 0.1)
				(type default)
			)
			(layer "B.Fab")
		)
		(fp_line
			(start 0.67945 0.3048)
			(end 0.67945 -0.305054)
			(stroke
				(width 0.1)
				(type default)
			)
			(layer "B.Fab")
		)
		(fp_line
			(start 0.12065 0.3048)
			(end 0.67945 0.3048)
			(stroke
				(width 0.1)
				(type default)
			)
			(layer "B.Fab")
		)
		(fp_line
			(start -0.120396 0.3048)
			(end -0.120396 0.2794)
			(stroke
				(width 0.1)
				(type default)
			)
			(layer "B.Fab")
		)
		(fp_line
			(start -0.67945 0.3048)
			(end -0.120396 0.3048)
			(stroke
				(width 0.1)
				(type default)
			)
			(layer "B.Fab")
		)
		(pad "1" smd circle
			(at 0.40005 0 270)
			(size 0 0)
			(layers "B.Cu" "B.Mask" "B.Paste")
			(net "NIC5_MAIN_PWR_BIC_EN_R")
		)
		(pad "2" smd circle
			(at -0.40005 0 270)
			(size 0 0)
			(layers "B.Cu" "B.Mask" "B.Paste")
			(net "NIC5_MAIN_PWR_BIC_EN")
		)
	)
	(footprint ""
		(layer "B.Cu")
		(at 63.449962 -290.199826 90)
		(property "Reference" "C1237"
			(at 0 0 90)
			(layer "B.SilkS")
			(hide yes)
			(effects
				(font
					(size 1.27 1.27)
				)
				(justify mirror)
			)
		)
		(property "Value" ""
			(at 0 0 90)
			(layer "B.Fab")
			(effects
				(font
					(size 1.27 1.27)
				)
				(justify mirror)
			)
		)
		(duplicate_pad_numbers_are_jumpers no)
		(fp_line
			(start 0.299974 -0.150114)
			(end -0.299974 -0.150114)
			(stroke
				(width 0.1)
				(type default)
			)
			(layer "B.Fab")
		)
		(fp_line
			(start -0.299974 -0.150114)
			(end -0.299974 0.150114)
			(stroke
				(width 0.1)
				(type default)
			)
			(layer "B.Fab")
		)
		(fp_line
			(start 0.299974 0.150114)
			(end 0.299974 -0.150114)
			(stroke
				(width 0.1)
				(type default)
			)
			(layer "B.Fab")
		)
		(fp_line
			(start -0.299974 0.150114)
			(end 0.299974 0.150114)
			(stroke
				(width 0.1)
				(type default)
			)
			(layer "B.Fab")
		)
		(pad "1" smd rect
			(at 0.2667 0 270)
			(size 0.3048 0.381)
			(layers "B.Cu" "B.Mask" "B.Paste")
			(net "P0V8_SERDES_VDDA_PEX0")
		)
		(pad "2" smd rect
			(at -0.2667 0 270)
			(size 0.3048 0.381)
			(layers "B.Cu" "B.Mask" "B.Paste")
			(net "GND")
		)
	)
	(footprint ""
		(layer "B.Cu")
		(at 345.057476 -313.620404 180)
		(property "Reference" "R5792"
			(at 0 0 0)
			(layer "B.SilkS")
			(hide yes)
			(effects
				(font
					(size 1.27 1.27)
				)
				(justify mirror)
			)
		)
		(property "Value" ""
			(at 0 0 0)
			(layer "B.Fab")
			(effects
				(font
					(size 1.27 1.27)
				)
				(justify mirror)
			)
		)
		(duplicate_pad_numbers_are_jumpers no)
		(fp_line
			(start 2.576322 1.1303)
			(end 2.576322 -1.1303)
			(stroke
				(width 0.1524)
				(type default)
			)
			(layer "B.SilkS")
		)
		(fp_line
			(start 2.576322 -1.1303)
			(end -2.576322 -1.1303)
			(stroke
				(width 0.1524)
				(type default)
			)
			(layer "B.SilkS")
		)
		(fp_line
			(start -2.576322 1.1303)
			(end 2.576322 1.1303)
			(stroke
				(width 0.1524)
				(type default)
			)
			(layer "B.SilkS")
		)
		(fp_line
			(start -2.576322 -1.1303)
			(end -2.576322 1.1303)
			(stroke
				(width 0.1524)
				(type default)
			)
			(layer "B.SilkS")
		)
		(fp_line
			(start 1.649984 0.899922)
			(end -1.649984 0.899922)
			(stroke
				(width 0.1)
				(type default)
			)
			(layer "B.Fab")
		)
		(fp_line
			(start 1.649984 -0.899922)
			(end 1.649984 0.899922)
			(stroke
				(width 0.1)
				(type default)
			)
			(layer "B.Fab")
		)
		(fp_line
			(start -1.649984 0.899922)
			(end -1.649984 -0.899922)
			(stroke
				(width 0.1)
				(type default)
			)
			(layer "B.Fab")
		)
		(fp_line
			(start -1.649984 -0.899922)
			(end 1.649984 -0.899922)
			(stroke
				(width 0.1)
				(type default)
			)
			(layer "B.Fab")
		)
		(pad "1A" smd rect
			(at 1.700022 0)
			(size 1.4986 2.0066)
			(layers "B.Cu" "B.Mask" "B.Paste")
			(net "P0V8_PEX2")
		)
		(pad "1B" smd rect
			(at 1.077722 0)
			(size 0.254 0.508)
			(layers "B.Cu" "B.Mask" "B.Paste")
			(net "P0V8_PEX2")
		)
		(pad "2A" smd rect
			(at -1.700022 0)
			(size 1.4986 2.0066)
			(layers "B.Cu" "B.Mask" "B.Paste")
			(net "P0V8_SERDES_VDDA_PEX2")
		)
		(pad "2B" smd rect
			(at -1.077722 0)
			(size 0.254 0.508)
			(layers "B.Cu" "B.Mask" "B.Paste")
			(net "P0V8_SERDES_VDDA_PEX2")
		)
	)
	(footprint ""
		(layer "B.Cu")
		(at 160.549844 -292.099746)
		(property "Reference" "C3174"
			(at 0 0 0)
			(layer "B.SilkS")
			(hide yes)
			(effects
				(font
					(size 1.27 1.27)
				)
				(justify mirror)
			)
		)
		(property "Value" ""
			(at 0 0 0)
			(layer "B.Fab")
			(effects
				(font
					(size 1.27 1.27)
				)
				(justify mirror)
			)
		)
		(duplicate_pad_numbers_are_jumpers no)
		(fp_line
			(start -0.299974 -0.150114)
			(end -0.299974 0.150114)
			(stroke
				(width 0.1)
				(type default)
			)
			(layer "B.Fab")
		)
		(fp_line
			(start -0.299974 0.150114)
			(end 0.299974 0.150114)
			(stroke
				(width 0.1)
				(type default)
			)
			(layer "B.Fab")
		)
		(fp_line
			(start 0.299974 -0.150114)
			(end -0.299974 -0.150114)
			(stroke
				(width 0.1)
				(type default)
			)
			(layer "B.Fab")
		)
		(fp_line
			(start 0.299974 0.150114)
			(end 0.299974 -0.150114)
			(stroke
				(width 0.1)
				(type default)
			)
			(layer "B.Fab")
		)
		(pad "1" smd rect
			(at 0.2667 0 180)
			(size 0.3048 0.381)
			(layers "B.Cu" "B.Mask" "B.Paste")
			(net "P1V8_PEX")
		)
		(pad "2" smd rect
			(at -0.2667 0 180)
			(size 0.3048 0.381)
			(layers "B.Cu" "B.Mask" "B.Paste")
			(net "GND")
		)
	)
	(footprint ""
		(layer "B.Cu")
		(at 281.445462 -296.37482)
		(property "Reference" "C1626"
			(at 0 0 0)
			(layer "B.SilkS")
			(hide yes)
			(effects
				(font
					(size 1.27 1.27)
				)
				(justify mirror)
			)
		)
		(property "Value" ""
			(at 0 0 0)
			(layer "B.Fab")
			(effects
				(font
					(size 1.27 1.27)
				)
				(justify mirror)
			)
		)
		(duplicate_pad_numbers_are_jumpers no)
		(fp_line
			(start -0.299974 -0.150114)
			(end -0.299974 0.150114)
			(stroke
				(width 0.1)
				(type default)
			)
			(layer "B.Fab")
		)
		(fp_line
			(start -0.299974 0.150114)
			(end 0.299974 0.150114)
			(stroke
				(width 0.1)
				(type default)
			)
			(layer "B.Fab")
		)
		(fp_line
			(start 0.299974 -0.150114)
			(end -0.299974 -0.150114)
			(stroke
				(width 0.1)
				(type default)
			)
			(layer "B.Fab")
		)
		(fp_line
			(start 0.299974 0.150114)
			(end 0.299974 -0.150114)
			(stroke
				(width 0.1)
				(type default)
			)
			(layer "B.Fab")
		)
		(pad "1" smd rect
			(at 0.2667 0 180)
			(size 0.3048 0.381)
			(layers "B.Cu" "B.Mask" "B.Paste")
			(net "P0V8_PEX2")
		)
		(pad "2" smd rect
			(at -0.2667 0 180)
			(size 0.3048 0.381)
			(layers "B.Cu" "B.Mask" "B.Paste")
			(net "GND")
		)
	)
	(footprint ""
		(layer "B.Cu")
		(at 105.34269 -326.152256 -90)
		(property "Reference" "R1226"
			(at 0 0 90)
			(layer "B.SilkS")
			(hide yes)
			(effects
				(font
					(size 1.27 1.27)
				)
				(justify mirror)
			)
		)
		(property "Value" ""
			(at 0 0 90)
			(layer "B.Fab")
			(effects
				(font
					(size 1.27 1.27)
				)
				(justify mirror)
			)
		)
		(duplicate_pad_numbers_are_jumpers no)
		(fp_line
			(start -0.7874 0.4064)
			(end 0.7874 0.4064)
			(stroke
				(width 0.1524)
				(type default)
			)
			(layer "B.SilkS")
		)
		(fp_line
			(start 0.7874 0.4064)
			(end 0.7874 -0.4064)
			(stroke
				(width 0.1524)
				(type default)
			)
			(layer "B.SilkS")
		)
		(fp_line
			(start -0.7874 -0.4064)
			(end -0.7874 0.4064)
			(stroke
				(width 0.1524)
				(type default)
			)
			(layer "B.SilkS")
		)
		(fp_line
			(start 0.7874 -0.4064)
			(end -0.7874 -0.4064)
			(stroke
				(width 0.1524)
				(type default)
			)
			(layer "B.SilkS")
		)
		(fp_line
			(start -0.67945 0.3048)
			(end -0.120396 0.3048)
			(stroke
				(width 0.1)
				(type default)
			)
			(layer "B.Fab")
		)
		(fp_line
			(start -0.120396 0.3048)
			(end -0.120396 0.2794)
			(stroke
				(width 0.1)
				(type default)
			)
			(layer "B.Fab")
		)
		(fp_line
			(start 0.12065 0.3048)
			(end 0.67945 0.3048)
			(stroke
				(width 0.1)
				(type default)
			)
			(layer "B.Fab")
		)
		(fp_line
			(start 0.67945 0.3048)
			(end 0.67945 -0.305054)
			(stroke
				(width 0.1)
				(type default)
			)
			(layer "B.Fab")
		)
		(fp_line
			(start -0.120396 0.2794)
			(end 0.12065 0.2794)
			(stroke
				(width 0.1)
				(type default)
			)
			(layer "B.Fab")
		)
		(fp_line
			(start 0.12065 0.2794)
			(end 0.12065 0.3048)
			(stroke
				(width 0.1)
				(type default)
			)
			(layer "B.Fab")
		)
		(fp_line
			(start -0.12065 -0.2794)
			(end -0.12065 -0.3048)
			(stroke
				(width 0.1)
				(type default)
			)
			(layer "B.Fab")
		)
		(fp_line
			(start 0.12065 -0.2794)
			(end -0.12065 -0.2794)
			(stroke
				(width 0.1)
				(type default)
			)
			(layer "B.Fab")
		)
		(fp_line
			(start -0.67945 -0.3048)
			(end -0.67945 0.3048)
			(stroke
				(width 0.1)
				(type default)
			)
			(layer "B.Fab")
		)
		(fp_line
			(start -0.12065 -0.3048)
			(end -0.67945 -0.3048)
			(stroke
				(width 0.1)
				(type default)
			)
			(layer "B.Fab")
		)
		(fp_line
			(start 0.12065 -0.305054)
			(end 0.12065 -0.2794)
			(stroke
				(width 0.1)
				(type default)
			)
			(layer "B.Fab")
		)
		(fp_line
			(start 0.67945 -0.305054)
			(end 0.12065 -0.305054)
			(stroke
				(width 0.1)
				(type default)
			)
			(layer "B.Fab")
		)
		(pad "1" smd circle
			(at 0.40005 0 90)
			(size 0 0)
			(layers "B.Cu" "B.Mask" "B.Paste")
			(net "CLK_100M_DB800ZL_PEX0_S0_R_DN")
		)
		(pad "2" smd circle
			(at -0.40005 0 90)
			(size 0 0)
			(layers "B.Cu" "B.Mask" "B.Paste")
			(net "CLK_100M_DB800ZL_PEX0_S0_DN")
		)
	)
	(footprint ""
		(layer "B.Cu")
		(at 156.219144 -294.8051 180)
		(property "Reference" "R3454"
			(at 0 0 0)
			(layer "B.SilkS")
			(hide yes)
			(effects
				(font
					(size 1.27 1.27)
				)
				(justify mirror)
			)
		)
		(property "Value" ""
			(at 0 0 0)
			(layer "B.Fab")
			(effects
				(font
					(size 1.27 1.27)
				)
				(justify mirror)
			)
		)
		(duplicate_pad_numbers_are_jumpers no)
		(fp_line
			(start 0.7874 0.4064)
			(end 0.7874 -0.4064)
			(stroke
				(width 0.1524)
				(type default)
			)
			(layer "B.SilkS")
		)
		(fp_line
			(start 0.7874 -0.4064)
			(end -0.7874 -0.4064)
			(stroke
				(width 0.1524)
				(type default)
			)
			(layer "B.SilkS")
		)
		(fp_line
			(start -0.7874 0.4064)
			(end 0.7874 0.4064)
			(stroke
				(width 0.1524)
				(type default)
			)
			(layer "B.SilkS")
		)
		(fp_line
			(start -0.7874 -0.4064)
			(end -0.7874 0.4064)
			(stroke
				(width 0.1524)
				(type default)
			)
			(layer "B.SilkS")
		)
		(fp_line
			(start 0.67945 0.3048)
			(end 0.67945 -0.305054)
			(stroke
				(width 0.1)
				(type default)
			)
			(layer "B.Fab")
		)
		(fp_line
			(start 0.67945 -0.305054)
			(end 0.12065 -0.305054)
			(stroke
				(width 0.1)
				(type default)
			)
			(layer "B.Fab")
		)
		(fp_line
			(start 0.12065 0.3048)
			(end 0.67945 0.3048)
			(stroke
				(width 0.1)
				(type default)
			)
			(layer "B.Fab")
		)
		(fp_line
			(start 0.12065 0.2794)
			(end 0.12065 0.3048)
			(stroke
				(width 0.1)
				(type default)
			)
			(layer "B.Fab")
		)
		(fp_line
			(start 0.12065 -0.2794)
			(end -0.12065 -0.2794)
			(stroke
				(width 0.1)
				(type default)
			)
			(layer "B.Fab")
		)
		(fp_line
			(start 0.12065 -0.305054)
			(end 0.12065 -0.2794)
			(stroke
				(width 0.1)
				(type default)
			)
			(layer "B.Fab")
		)
		(fp_line
			(start -0.120396 0.3048)
			(end -0.120396 0.2794)
			(stroke
				(width 0.1)
				(type default)
			)
			(layer "B.Fab")
		)
		(fp_line
			(start -0.120396 0.2794)
			(end 0.12065 0.2794)
			(stroke
				(width 0.1)
				(type default)
			)
			(layer "B.Fab")
		)
		(fp_line
			(start -0.12065 -0.2794)
			(end -0.12065 -0.3048)
			(stroke
				(width 0.1)
				(type default)
			)
			(layer "B.Fab")
		)
		(fp_line
			(start -0.12065 -0.3048)
			(end -0.67945 -0.3048)
			(stroke
				(width 0.1)
				(type default)
			)
			(layer "B.Fab")
		)
		(fp_line
			(start -0.67945 0.3048)
			(end -0.120396 0.3048)
			(stroke
				(width 0.1)
				(type default)
			)
			(layer "B.Fab")
		)
		(fp_line
			(start -0.67945 -0.3048)
			(end -0.67945 0.3048)
			(stroke
				(width 0.1)
				(type default)
			)
			(layer "B.Fab")
		)
		(pad "1" smd circle
			(at 0.40005 0)
			(size 0 0)
			(layers "B.Cu" "B.Mask" "B.Paste")
			(net "SPI_PEX1_SDIO2_R")
		)
		(pad "2" smd circle
			(at -0.40005 0)
			(size 0 0)
			(layers "B.Cu" "B.Mask" "B.Paste")
			(net "SPI_PEX1_SDIO2")
		)
	)
	(footprint ""
		(layer "B.Cu")
		(at 346.583 -207.772 -90)
		(property "Reference" "R4150"
			(at 0 0 90)
			(layer "B.SilkS")
			(hide yes)
			(effects
				(font
					(size 1.27 1.27)
				)
				(justify mirror)
			)
		)
		(property "Value" ""
			(at 0 0 90)
			(layer "B.Fab")
			(effects
				(font
					(size 1.27 1.27)
				)
				(justify mirror)
			)
		)
		(duplicate_pad_numbers_are_jumpers no)
		(fp_line
			(start -0.7874 0.4064)
			(end 0.7874 0.4064)
			(stroke
				(width 0.1524)
				(type default)
			)
			(layer "B.SilkS")
		)
		(fp_line
			(start 0.7874 0.4064)
			(end 0.7874 -0.4064)
			(stroke
				(width 0.1524)
				(type default)
			)
			(layer "B.SilkS")
		)
		(fp_line
			(start -0.7874 -0.4064)
			(end -0.7874 0.4064)
			(stroke
				(width 0.1524)
				(type default)
			)
			(layer "B.SilkS")
		)
		(fp_line
			(start 0.7874 -0.4064)
			(end -0.7874 -0.4064)
			(stroke
				(width 0.1524)
				(type default)
			)
			(layer "B.SilkS")
		)
		(fp_line
			(start -0.67945 0.3048)
			(end -0.120396 0.3048)
			(stroke
				(width 0.1)
				(type default)
			)
			(layer "B.Fab")
		)
		(fp_line
			(start -0.120396 0.3048)
			(end -0.120396 0.2794)
			(stroke
				(width 0.1)
				(type default)
			)
			(layer "B.Fab")
		)
		(fp_line
			(start 0.12065 0.3048)
			(end 0.67945 0.3048)
			(stroke
				(width 0.1)
				(type default)
			)
			(layer "B.Fab")
		)
		(fp_line
			(start 0.67945 0.3048)
			(end 0.67945 -0.305054)
			(stroke
				(width 0.1)
				(type default)
			)
			(layer "B.Fab")
		)
		(fp_line
			(start -0.120396 0.2794)
			(end 0.12065 0.2794)
			(stroke
				(width 0.1)
				(type default)
			)
			(layer "B.Fab")
		)
		(fp_line
			(start 0.12065 0.2794)
			(end 0.12065 0.3048)
			(stroke
				(width 0.1)
				(type default)
			)
			(layer "B.Fab")
		)
		(fp_line
			(start -0.12065 -0.2794)
			(end -0.12065 -0.3048)
			(stroke
				(width 0.1)
				(type default)
			)
			(layer "B.Fab")
		)
		(fp_line
			(start 0.12065 -0.2794)
			(end -0.12065 -0.2794)
			(stroke
				(width 0.1)
				(type default)
			)
			(layer "B.Fab")
		)
		(fp_line
			(start -0.67945 -0.3048)
			(end -0.67945 0.3048)
			(stroke
				(width 0.1)
				(type default)
			)
			(layer "B.Fab")
		)
		(fp_line
			(start -0.12065 -0.3048)
			(end -0.67945 -0.3048)
			(stroke
				(width 0.1)
				(type default)
			)
			(layer "B.Fab")
		)
		(fp_line
			(start 0.12065 -0.305054)
			(end 0.12065 -0.2794)
			(stroke
				(width 0.1)
				(type default)
			)
			(layer "B.Fab")
		)
		(fp_line
			(start 0.67945 -0.305054)
			(end 0.12065 -0.305054)
			(stroke
				(width 0.1)
				(type default)
			)
			(layer "B.Fab")
		)
		(pad "1" smd circle
			(at 0.40005 0 90)
			(size 0 0)
			(layers "B.Cu" "B.Mask" "B.Paste")
			(net "PRSNT_SSD3_FPGA_R_N")
		)
		(pad "2" smd circle
			(at -0.40005 0 90)
			(size 0 0)
			(layers "B.Cu" "B.Mask" "B.Paste")
			(net "PRSNT_SSD3_FPGA_N")
		)
	)
	(footprint ""
		(layer "B.Cu")
		(at 109.97565 -293.506906 90)
		(property "Reference" "PC86"
			(at 0 0 90)
			(layer "B.SilkS")
			(hide yes)
			(effects
				(font
					(size 1.27 1.27)
				)
				(justify mirror)
			)
		)
		(property "Value" ""
			(at 0 0 90)
			(layer "B.Fab")
			(effects
				(font
					(size 1.27 1.27)
				)
				(justify mirror)
			)
		)
		(duplicate_pad_numbers_are_jumpers no)
		(fp_line
			(start 1.524 -0.762)
			(end -1.524 -0.762)
			(stroke
				(width 0.1524)
				(type default)
			)
			(layer "B.SilkS")
		)
		(fp_line
			(start -1.524 -0.762)
			(end -1.524 0.762)
			(stroke
				(width 0.1524)
				(type default)
			)
			(layer "B.SilkS")
		)
		(fp_line
			(start 1.524 0.762)
			(end 1.524 -0.762)
			(stroke
				(width 0.1524)
				(type default)
			)
			(layer "B.SilkS")
		)
		(fp_line
			(start -1.524 0.762)
			(end 1.524 0.762)
			(stroke
				(width 0.1524)
				(type default)
			)
			(layer "B.SilkS")
		)
		(fp_line
			(start 1.1049 -0.724916)
			(end 1.1049 0.724916)
			(stroke
				(width 0.1)
				(type default)
			)
			(layer "B.Fab")
		)
		(fp_line
			(start -1.1049 -0.724916)
			(end 1.1049 -0.724916)
			(stroke
				(width 0.1)
				(type default)
			)
			(layer "B.Fab")
		)
		(fp_line
			(start 1.1049 0.724916)
			(end -1.1049 0.724916)
			(stroke
				(width 0.1)
				(type default)
			)
			(layer "B.Fab")
		)
		(fp_line
			(start -1.1049 0.724916)
			(end -1.1049 -0.724916)
			(stroke
				(width 0.1)
				(type default)
			)
			(layer "B.Fab")
		)
		(pad "1" smd rect
			(at 0.889 0 90)
			(size 1.016 1.27)
			(layers "B.Cu" "B.Mask" "B.Paste")
			(net "P0V8_PEX0")
		)
		(pad "2" smd rect
			(at -0.889 0 90)
			(size 1.016 1.27)
			(layers "B.Cu" "B.Mask" "B.Paste")
			(net "GND")
		)
	)
	(footprint ""
		(layer "B.Cu")
		(at 180.50002 -288.299906 90)
		(property "Reference" "C3095"
			(at 0 0 90)
			(layer "B.SilkS")
			(hide yes)
			(effects
				(font
					(size 1.27 1.27)
				)
				(justify mirror)
			)
		)
		(property "Value" ""
			(at 0 0 90)
			(layer "B.Fab")
			(effects
				(font
					(size 1.27 1.27)
				)
				(justify mirror)
			)
		)
		(duplicate_pad_numbers_are_jumpers no)
		(fp_line
			(start 0.299974 -0.150114)
			(end -0.299974 -0.150114)
			(stroke
				(width 0.1)
				(type default)
			)
			(layer "B.Fab")
		)
		(fp_line
			(start -0.299974 -0.150114)
			(end -0.299974 0.150114)
			(stroke
				(width 0.1)
				(type default)
			)
			(layer "B.Fab")
		)
		(fp_line
			(start 0.299974 0.150114)
			(end 0.299974 -0.150114)
			(stroke
				(width 0.1)
				(type default)
			)
			(layer "B.Fab")
		)
		(fp_line
			(start -0.299974 0.150114)
			(end 0.299974 0.150114)
			(stroke
				(width 0.1)
				(type default)
			)
			(layer "B.Fab")
		)
		(pad "1" smd rect
			(at 0.2667 0 270)
			(size 0.3048 0.381)
			(layers "B.Cu" "B.Mask" "B.Paste")
			(net "P1V25_PEX1")
		)
		(pad "2" smd rect
			(at -0.2667 0 270)
			(size 0.3048 0.381)
			(layers "B.Cu" "B.Mask" "B.Paste")
			(net "GND")
		)
	)
	(footprint ""
		(layer "B.Cu")
		(at 283.299916 -299.699934 -90)
		(property "Reference" "C1677"
			(at 0 0 90)
			(layer "B.SilkS")
			(hide yes)
			(effects
				(font
					(size 1.27 1.27)
				)
				(justify mirror)
			)
		)
		(property "Value" ""
			(at 0 0 90)
			(layer "B.Fab")
			(effects
				(font
					(size 1.27 1.27)
				)
				(justify mirror)
			)
		)
		(duplicate_pad_numbers_are_jumpers no)
		(fp_line
			(start -0.299974 0.150114)
			(end 0.299974 0.150114)
			(stroke
				(width 0.1)
				(type default)
			)
			(layer "B.Fab")
		)
		(fp_line
			(start 0.299974 0.150114)
			(end 0.299974 -0.150114)
			(stroke
				(width 0.1)
				(type default)
			)
			(layer "B.Fab")
		)
		(fp_line
			(start -0.299974 -0.150114)
			(end -0.299974 0.150114)
			(stroke
				(width 0.1)
				(type default)
			)
			(layer "B.Fab")
		)
		(fp_line
			(start 0.299974 -0.150114)
			(end -0.299974 -0.150114)
			(stroke
				(width 0.1)
				(type default)
			)
			(layer "B.Fab")
		)
		(pad "1" smd rect
			(at 0.2667 0 90)
			(size 0.3048 0.381)
			(layers "B.Cu" "B.Mask" "B.Paste")
			(net "P0V8_SERDES_VDDA_PEX2")
		)
		(pad "2" smd rect
			(at -0.2667 0 90)
			(size 0.3048 0.381)
			(layers "B.Cu" "B.Mask" "B.Paste")
			(net "GND")
		)
	)
	(footprint ""
		(layer "B.Cu")
		(at 73.271634 -114.592608)
		(property "Reference" "C870"
			(at 0 0 0)
			(layer "B.SilkS")
			(hide yes)
			(effects
				(font
					(size 1.27 1.27)
				)
				(justify mirror)
			)
		)
		(property "Value" ""
			(at 0 0 0)
			(layer "B.Fab")
			(effects
				(font
					(size 1.27 1.27)
				)
				(justify mirror)
			)
		)
		(duplicate_pad_numbers_are_jumpers no)
		(fp_line
			(start -0.7874 -0.4064)
			(end -0.7874 0.4064)
			(stroke
				(width 0.1524)
				(type default)
			)
			(layer "B.SilkS")
		)
		(fp_line
			(start -0.7874 0.4064)
			(end 0.7874 0.4064)
			(stroke
				(width 0.1524)
				(type default)
			)
			(layer "B.SilkS")
		)
		(fp_line
			(start 0.7874 -0.4064)
			(end -0.7874 -0.4064)
			(stroke
				(width 0.1524)
				(type default)
			)
			(layer "B.SilkS")
		)
		(fp_line
			(start 0.7874 0.4064)
			(end 0.7874 -0.4064)
			(stroke
				(width 0.1524)
				(type default)
			)
			(layer "B.SilkS")
		)
		(fp_line
			(start -0.67945 -0.3048)
			(end -0.67945 0.3048)
			(stroke
				(width 0.1)
				(type default)
			)
			(layer "B.Fab")
		)
		(fp_line
			(start -0.67945 0.3048)
			(end -0.120396 0.3048)
			(stroke
				(width 0.1)
				(type default)
			)
			(layer "B.Fab")
		)
		(fp_line
			(start -0.12065 -0.3048)
			(end -0.67945 -0.3048)
			(stroke
				(width 0.1)
				(type default)
			)
			(layer "B.Fab")
		)
		(fp_line
			(start -0.12065 -0.2794)
			(end -0.12065 -0.3048)
			(stroke
				(width 0.1)
				(type default)
			)
			(layer "B.Fab")
		)
		(fp_line
			(start -0.120396 0.2794)
			(end 0.12065 0.2794)
			(stroke
				(width 0.1)
				(type default)
			)
			(layer "B.Fab")
		)
		(fp_line
			(start -0.120396 0.3048)
			(end -0.120396 0.2794)
			(stroke
				(width 0.1)
				(type default)
			)
			(layer "B.Fab")
		)
		(fp_line
			(start 0.12065 -0.305054)
			(end 0.12065 -0.2794)
			(stroke
				(width 0.1)
				(type default)
			)
			(layer "B.Fab")
		)
		(fp_line
			(start 0.12065 -0.2794)
			(end -0.12065 -0.2794)
			(stroke
				(width 0.1)
				(type default)
			)
			(layer "B.Fab")
		)
		(fp_line
			(start 0.12065 0.2794)
			(end 0.12065 0.3048)
			(stroke
				(width 0.1)
				(type default)
			)
			(layer "B.Fab")
		)
		(fp_line
			(start 0.12065 0.3048)
			(end 0.67945 0.3048)
			(stroke
				(width 0.1)
				(type default)
			)
			(layer "B.Fab")
		)
		(fp_line
			(start 0.67945 -0.305054)
			(end 0.12065 -0.305054)
			(stroke
				(width 0.1)
				(type default)
			)
			(layer "B.Fab")
		)
		(fp_line
			(start 0.67945 0.3048)
			(end 0.67945 -0.305054)
			(stroke
				(width 0.1)
				(type default)
			)
			(layer "B.Fab")
		)
		(pad "1" smd circle
			(at 0.40005 0 180)
			(size 0 0)
			(layers "B.Cu" "B.Mask" "B.Paste")
			(net "P3V3_NIC1")
		)
		(pad "2" smd circle
			(at -0.40005 0 180)
			(size 0 0)
			(layers "B.Cu" "B.Mask" "B.Paste")
			(net "GND")
		)
	)
	(footprint ""
		(layer "B.Cu")
		(at 388.949946 -288.774886 -90)
		(property "Reference" "R3491"
			(at 0 0 90)
			(layer "B.SilkS")
			(hide yes)
			(effects
				(font
					(size 1.27 1.27)
				)
				(justify mirror)
			)
		)
		(property "Value" ""
			(at 0 0 90)
			(layer "B.Fab")
			(effects
				(font
					(size 1.27 1.27)
				)
				(justify mirror)
			)
		)
		(duplicate_pad_numbers_are_jumpers no)
		(fp_line
			(start -0.7874 0.4064)
			(end 0.7874 0.4064)
			(stroke
				(width 0.1524)
				(type default)
			)
			(layer "B.SilkS")
		)
		(fp_line
			(start 0.7874 0.4064)
			(end 0.7874 -0.4064)
			(stroke
				(width 0.1524)
				(type default)
			)
			(layer "B.SilkS")
		)
		(fp_line
			(start -0.7874 -0.4064)
			(end -0.7874 0.4064)
			(stroke
				(width 0.1524)
				(type default)
			)
			(layer "B.SilkS")
		)
		(fp_line
			(start 0.7874 -0.4064)
			(end -0.7874 -0.4064)
			(stroke
				(width 0.1524)
				(type default)
			)
			(layer "B.SilkS")
		)
		(fp_line
			(start -0.67945 0.3048)
			(end -0.120396 0.3048)
			(stroke
				(width 0.1)
				(type default)
			)
			(layer "B.Fab")
		)
		(fp_line
			(start -0.120396 0.3048)
			(end -0.120396 0.2794)
			(stroke
				(width 0.1)
				(type default)
			)
			(layer "B.Fab")
		)
		(fp_line
			(start 0.12065 0.3048)
			(end 0.67945 0.3048)
			(stroke
				(width 0.1)
				(type default)
			)
			(layer "B.Fab")
		)
		(fp_line
			(start 0.67945 0.3048)
			(end 0.67945 -0.305054)
			(stroke
				(width 0.1)
				(type default)
			)
			(layer "B.Fab")
		)
		(fp_line
			(start -0.120396 0.2794)
			(end 0.12065 0.2794)
			(stroke
				(width 0.1)
				(type default)
			)
			(layer "B.Fab")
		)
		(fp_line
			(start 0.12065 0.2794)
			(end 0.12065 0.3048)
			(stroke
				(width 0.1)
				(type default)
			)
			(layer "B.Fab")
		)
		(fp_line
			(start -0.12065 -0.2794)
			(end -0.12065 -0.3048)
			(stroke
				(width 0.1)
				(type default)
			)
			(layer "B.Fab")
		)
		(fp_line
			(start 0.12065 -0.2794)
			(end -0.12065 -0.2794)
			(stroke
				(width 0.1)
				(type default)
			)
			(layer "B.Fab")
		)
		(fp_line
			(start -0.67945 -0.3048)
			(end -0.67945 0.3048)
			(stroke
				(width 0.1)
				(type default)
			)
			(layer "B.Fab")
		)
		(fp_line
			(start -0.12065 -0.3048)
			(end -0.67945 -0.3048)
			(stroke
				(width 0.1)
				(type default)
			)
			(layer "B.Fab")
		)
		(fp_line
			(start 0.12065 -0.305054)
			(end 0.12065 -0.2794)
			(stroke
				(width 0.1)
				(type default)
			)
			(layer "B.Fab")
		)
		(fp_line
			(start 0.67945 -0.305054)
			(end 0.12065 -0.305054)
			(stroke
				(width 0.1)
				(type default)
			)
			(layer "B.Fab")
		)
		(pad "1" smd circle
			(at 0.40005 0 90)
			(size 0 0)
			(layers "B.Cu" "B.Mask" "B.Paste")
			(net "SPI_PEX3_CS_R_N")
		)
		(pad "2" smd circle
			(at -0.40005 0 90)
			(size 0 0)
			(layers "B.Cu" "B.Mask" "B.Paste")
			(net "SPI_PEX3_CS_N")
		)
	)
	(footprint ""
		(layer "B.Cu")
		(at 225.539046 -153.127202 -90)
		(property "Reference" "C2799"
			(at 0 0 90)
			(layer "B.SilkS")
			(hide yes)
			(effects
				(font
					(size 1.27 1.27)
				)
				(justify mirror)
			)
		)
		(property "Value" ""
			(at 0 0 90)
			(layer "B.Fab")
			(effects
				(font
					(size 1.27 1.27)
				)
				(justify mirror)
			)
		)
		(duplicate_pad_numbers_are_jumpers no)
		(fp_line
			(start -1.2954 0.5842)
			(end 1.2954 0.5842)
			(stroke
				(width 0.1524)
				(type default)
			)
			(layer "B.SilkS")
		)
		(fp_line
			(start 1.2954 0.5842)
			(end 1.2954 -0.5842)
			(stroke
				(width 0.1524)
				(type default)
			)
			(layer "B.SilkS")
		)
		(fp_line
			(start -1.2954 -0.5842)
			(end -1.2954 0.5842)
			(stroke
				(width 0.1524)
				(type default)
			)
			(layer "B.SilkS")
		)
		(fp_line
			(start 1.2954 -0.5842)
			(end -1.2954 -0.5842)
			(stroke
				(width 0.1524)
				(type default)
			)
			(layer "B.SilkS")
		)
		(fp_line
			(start -0.8636 0.4572)
			(end 0.8636 0.4572)
			(stroke
				(width 0.1)
				(type default)
			)
			(layer "B.Fab")
		)
		(fp_line
			(start 0.8636 0.4572)
			(end 0.8636 0.4064)
			(stroke
				(width 0.1)
				(type default)
			)
			(layer "B.Fab")
		)
		(fp_line
			(start -1.1938 0.4064)
			(end -0.8636 0.4064)
			(stroke
				(width 0.1)
				(type default)
			)
			(layer "B.Fab")
		)
		(fp_line
			(start -0.8636 0.4064)
			(end -0.8636 0.4572)
			(stroke
				(width 0.1)
				(type default)
			)
			(layer "B.Fab")
		)
		(fp_line
			(start 0.8636 0.4064)
			(end 1.1938 0.4064)
			(stroke
				(width 0.1)
				(type default)
			)
			(layer "B.Fab")
		)
		(fp_line
			(start 1.1938 0.4064)
			(end 1.1938 -0.4064)
			(stroke
				(width 0.1)
				(type default)
			)
			(layer "B.Fab")
		)
		(fp_line
			(start -1.1938 -0.4064)
			(end -1.1938 0.4064)
			(stroke
				(width 0.1)
				(type default)
			)
			(layer "B.Fab")
		)
		(fp_line
			(start -0.8636 -0.4064)
			(end -1.1938 -0.4064)
			(stroke
				(width 0.1)
				(type default)
			)
			(layer "B.Fab")
		)
		(fp_line
			(start 0.8636 -0.4064)
			(end 0.8636 -0.4572)
			(stroke
				(width 0.1)
				(type default)
			)
			(layer "B.Fab")
		)
		(fp_line
			(start 1.1938 -0.4064)
			(end 0.8636 -0.4064)
			(stroke
				(width 0.1)
				(type default)
			)
			(layer "B.Fab")
		)
		(fp_line
			(start -0.8636 -0.4572)
			(end -0.8636 -0.4064)
			(stroke
				(width 0.1)
				(type default)
			)
			(layer "B.Fab")
		)
		(fp_line
			(start 0.8636 -0.4572)
			(end -0.8636 -0.4572)
			(stroke
				(width 0.1)
				(type default)
			)
			(layer "B.Fab")
		)
		(pad "1" smd rect
			(at 0.7366 0 180)
			(size 0.7112 0.8128)
			(layers "B.Cu" "B.Mask" "B.Paste")
			(net "P3V3_CLK_GEN_VDDMXCK_CK440_PEX")
		)
		(pad "2" smd rect
			(at -0.7366 0 180)
			(size 0.7112 0.8128)
			(layers "B.Cu" "B.Mask" "B.Paste")
			(net "GND")
		)
	)
	(footprint ""
		(layer "B.Cu")
		(at 279.974802 -295.3766 90)
		(property "Reference" "C3388"
			(at 0 0 90)
			(layer "B.SilkS")
			(hide yes)
			(effects
				(font
					(size 1.27 1.27)
				)
				(justify mirror)
			)
		)
		(property "Value" ""
			(at 0 0 90)
			(layer "B.Fab")
			(effects
				(font
					(size 1.27 1.27)
				)
				(justify mirror)
			)
		)
		(duplicate_pad_numbers_are_jumpers no)
		(fp_line
			(start 0.299974 -0.150114)
			(end -0.299974 -0.150114)
			(stroke
				(width 0.1)
				(type default)
			)
			(layer "B.Fab")
		)
		(fp_line
			(start -0.299974 -0.150114)
			(end -0.299974 0.150114)
			(stroke
				(width 0.1)
				(type default)
			)
			(layer "B.Fab")
		)
		(fp_line
			(start 0.299974 0.150114)
			(end 0.299974 -0.150114)
			(stroke
				(width 0.1)
				(type default)
			)
			(layer "B.Fab")
		)
		(fp_line
			(start -0.299974 0.150114)
			(end 0.299974 0.150114)
			(stroke
				(width 0.1)
				(type default)
			)
			(layer "B.Fab")
		)
		(pad "1" smd rect
			(at 0.2667 0 270)
			(size 0.3048 0.381)
			(layers "B.Cu" "B.Mask" "B.Paste")
			(net "PCEPLL3_VDDA18_PEX2")
		)
		(pad "2" smd rect
			(at -0.2667 0 270)
			(size 0.3048 0.381)
			(layers "B.Cu" "B.Mask" "B.Paste")
			(net "GND")
		)
	)
	(footprint ""
		(layer "B.Cu")
		(at 388.35711 -291.72662 180)
		(property "Reference" "R3489"
			(at 0 0 0)
			(layer "B.SilkS")
			(hide yes)
			(effects
				(font
					(size 1.27 1.27)
				)
				(justify mirror)
			)
		)
		(property "Value" ""
			(at 0 0 0)
			(layer "B.Fab")
			(effects
				(font
					(size 1.27 1.27)
				)
				(justify mirror)
			)
		)
		(duplicate_pad_numbers_are_jumpers no)
		(fp_line
			(start 0.7874 0.4064)
			(end 0.7874 -0.4064)
			(stroke
				(width 0.1524)
				(type default)
			)
			(layer "B.SilkS")
		)
		(fp_line
			(start 0.7874 -0.4064)
			(end -0.7874 -0.4064)
			(stroke
				(width 0.1524)
				(type default)
			)
			(layer "B.SilkS")
		)
		(fp_line
			(start -0.7874 0.4064)
			(end 0.7874 0.4064)
			(stroke
				(width 0.1524)
				(type default)
			)
			(layer "B.SilkS")
		)
		(fp_line
			(start -0.7874 -0.4064)
			(end -0.7874 0.4064)
			(stroke
				(width 0.1524)
				(type default)
			)
			(layer "B.SilkS")
		)
		(fp_line
			(start 0.67945 0.3048)
			(end 0.67945 -0.305054)
			(stroke
				(width 0.1)
				(type default)
			)
			(layer "B.Fab")
		)
		(fp_line
			(start 0.67945 -0.305054)
			(end 0.12065 -0.305054)
			(stroke
				(width 0.1)
				(type default)
			)
			(layer "B.Fab")
		)
		(fp_line
			(start 0.12065 0.3048)
			(end 0.67945 0.3048)
			(stroke
				(width 0.1)
				(type default)
			)
			(layer "B.Fab")
		)
		(fp_line
			(start 0.12065 0.2794)
			(end 0.12065 0.3048)
			(stroke
				(width 0.1)
				(type default)
			)
			(layer "B.Fab")
		)
		(fp_line
			(start 0.12065 -0.2794)
			(end -0.12065 -0.2794)
			(stroke
				(width 0.1)
				(type default)
			)
			(layer "B.Fab")
		)
		(fp_line
			(start 0.12065 -0.305054)
			(end 0.12065 -0.2794)
			(stroke
				(width 0.1)
				(type default)
			)
			(layer "B.Fab")
		)
		(fp_line
			(start -0.120396 0.3048)
			(end -0.120396 0.2794)
			(stroke
				(width 0.1)
				(type default)
			)
			(layer "B.Fab")
		)
		(fp_line
			(start -0.120396 0.2794)
			(end 0.12065 0.2794)
			(stroke
				(width 0.1)
				(type default)
			)
			(layer "B.Fab")
		)
		(fp_line
			(start -0.12065 -0.2794)
			(end -0.12065 -0.3048)
			(stroke
				(width 0.1)
				(type default)
			)
			(layer "B.Fab")
		)
		(fp_line
			(start -0.12065 -0.3048)
			(end -0.67945 -0.3048)
			(stroke
				(width 0.1)
				(type default)
			)
			(layer "B.Fab")
		)
		(fp_line
			(start -0.67945 0.3048)
			(end -0.120396 0.3048)
			(stroke
				(width 0.1)
				(type default)
			)
			(layer "B.Fab")
		)
		(fp_line
			(start -0.67945 -0.3048)
			(end -0.67945 0.3048)
			(stroke
				(width 0.1)
				(type default)
			)
			(layer "B.Fab")
		)
		(pad "1" smd circle
			(at 0.40005 0)
			(size 0 0)
			(layers "B.Cu" "B.Mask" "B.Paste")
			(net "SPI_PEX3_CLK_R")
		)
		(pad "2" smd circle
			(at -0.40005 0)
			(size 0 0)
			(layers "B.Cu" "B.Mask" "B.Paste")
			(net "SPI_PEX3_CLK")
		)
	)
	(footprint ""
		(layer "B.Cu")
		(at 333.073756 -327.942194 180)
		(property "Reference" "PJ22"
			(at 0 0 0)
			(layer "B.SilkS")
			(hide yes)
			(effects
				(font
					(size 1.27 1.27)
				)
				(justify mirror)
			)
		)
		(property "Value" ""
			(at 0 0 0)
			(layer "B.Fab")
			(effects
				(font
					(size 1.27 1.27)
				)
				(justify mirror)
			)
		)
		(duplicate_pad_numbers_are_jumpers no)
		(pad "1" smd circle
			(at 0.40005 0 270)
			(size 0 0)
			(layers "B.Cu" "B.Mask" "B.Paste")
			(net "VSENSE_P0V8_PEX2_SKT_VSEN")
		)
		(pad "2" smd rect
			(at -0.40005 0 180)
			(size 0.4572 0.508)
			(layers "B.Cu" "B.Mask" "B.Paste")
			(net "SH_P0V8_PEX2_VSEN2_L")
		)
		(zone
			(layer "B.Cu")
			(hatch none 0.5)
			(connect_pads
				(clearance 0)
			)
			(min_thickness 0.25)
			(keepout
				(tracks allowed)
				(vias not_allowed)
				(pads allowed)
				(copperpour not_allowed)
				(footprints allowed)
			)
			(placement
				(enabled no)
				(sheetname "")
			)
			(fill
				(thermal_gap 0.5)
				(thermal_bridge_width 0.5)
				(island_removal_mode 0)
			)
			(polygon
				(pts
					(xy 333.759556 -328.246994) (xy 333.759556 -327.637394) (xy 332.387956 -327.637394) (xy 332.387956 -328.246994)
				)
			)
		)
	)
	(footprint ""
		(layer "B.Cu")
		(at 299.449744 -292.099746 90)
		(property "Reference" "C1706"
			(at 0 0 90)
			(layer "B.SilkS")
			(hide yes)
			(effects
				(font
					(size 1.27 1.27)
				)
				(justify mirror)
			)
		)
		(property "Value" ""
			(at 0 0 90)
			(layer "B.Fab")
			(effects
				(font
					(size 1.27 1.27)
				)
				(justify mirror)
			)
		)
		(duplicate_pad_numbers_are_jumpers no)
		(fp_line
			(start 0.299974 -0.150114)
			(end -0.299974 -0.150114)
			(stroke
				(width 0.1)
				(type default)
			)
			(layer "B.Fab")
		)
		(fp_line
			(start -0.299974 -0.150114)
			(end -0.299974 0.150114)
			(stroke
				(width 0.1)
				(type default)
			)
			(layer "B.Fab")
		)
		(fp_line
			(start 0.299974 0.150114)
			(end 0.299974 -0.150114)
			(stroke
				(width 0.1)
				(type default)
			)
			(layer "B.Fab")
		)
		(fp_line
			(start -0.299974 0.150114)
			(end 0.299974 0.150114)
			(stroke
				(width 0.1)
				(type default)
			)
			(layer "B.Fab")
		)
		(pad "1" smd rect
			(at 0.2667 0 270)
			(size 0.3048 0.381)
			(layers "B.Cu" "B.Mask" "B.Paste")
			(net "P0V8_SERDES_VDDA_PEX2")
		)
		(pad "2" smd rect
			(at -0.2667 0 270)
			(size 0.3048 0.381)
			(layers "B.Cu" "B.Mask" "B.Paste")
			(net "GND")
		)
	)
	(footprint ""
		(layer "B.Cu")
		(at 72.949816 -297.79976 180)
		(property "Reference" "C2947"
			(at 0 0 0)
			(layer "B.SilkS")
			(hide yes)
			(effects
				(font
					(size 1.27 1.27)
				)
				(justify mirror)
			)
		)
		(property "Value" ""
			(at 0 0 0)
			(layer "B.Fab")
			(effects
				(font
					(size 1.27 1.27)
				)
				(justify mirror)
			)
		)
		(duplicate_pad_numbers_are_jumpers no)
		(fp_line
			(start 0.299974 0.150114)
			(end 0.299974 -0.150114)
			(stroke
				(width 0.1)
				(type default)
			)
			(layer "B.Fab")
		)
		(fp_line
			(start 0.299974 -0.150114)
			(end -0.299974 -0.150114)
			(stroke
				(width 0.1)
				(type default)
			)
			(layer "B.Fab")
		)
		(fp_line
			(start -0.299974 0.150114)
			(end 0.299974 0.150114)
			(stroke
				(width 0.1)
				(type default)
			)
			(layer "B.Fab")
		)
		(fp_line
			(start -0.299974 -0.150114)
			(end -0.299974 0.150114)
			(stroke
				(width 0.1)
				(type default)
			)
			(layer "B.Fab")
		)
		(pad "1" smd rect
			(at 0.2667 0)
			(size 0.3048 0.381)
			(layers "B.Cu" "B.Mask" "B.Paste")
			(net "P1V25_SERDES_VDDPLL_PEX0")
		)
		(pad "2" smd rect
			(at -0.2667 0)
			(size 0.3048 0.381)
			(layers "B.Cu" "B.Mask" "B.Paste")
			(net "GND")
		)
	)
	(footprint ""
		(layer "B.Cu")
		(at 69.149976 -296.37482 180)
		(property "Reference" "C1162"
			(at 0 0 0)
			(layer "B.SilkS")
			(hide yes)
			(effects
				(font
					(size 1.27 1.27)
				)
				(justify mirror)
			)
		)
		(property "Value" ""
			(at 0 0 0)
			(layer "B.Fab")
			(effects
				(font
					(size 1.27 1.27)
				)
				(justify mirror)
			)
		)
		(duplicate_pad_numbers_are_jumpers no)
		(fp_line
			(start 0.299974 0.150114)
			(end 0.299974 -0.150114)
			(stroke
				(width 0.1)
				(type default)
			)
			(layer "B.Fab")
		)
		(fp_line
			(start 0.299974 -0.150114)
			(end -0.299974 -0.150114)
			(stroke
				(width 0.1)
				(type default)
			)
			(layer "B.Fab")
		)
		(fp_line
			(start -0.299974 0.150114)
			(end 0.299974 0.150114)
			(stroke
				(width 0.1)
				(type default)
			)
			(layer "B.Fab")
		)
		(fp_line
			(start -0.299974 -0.150114)
			(end -0.299974 0.150114)
			(stroke
				(width 0.1)
				(type default)
			)
			(layer "B.Fab")
		)
		(pad "1" smd rect
			(at 0.2667 0)
			(size 0.3048 0.381)
			(layers "B.Cu" "B.Mask" "B.Paste")
			(net "P0V8_SERDES_VDDA_PEX0")
		)
		(pad "2" smd rect
			(at -0.2667 0)
			(size 0.3048 0.381)
			(layers "B.Cu" "B.Mask" "B.Paste")
			(net "GND")
		)
	)
	(footprint ""
		(layer "B.Cu")
		(at 40.119046 -294.8051 180)
		(property "Reference" "R3435"
			(at 0 0 0)
			(layer "B.SilkS")
			(hide yes)
			(effects
				(font
					(size 1.27 1.27)
				)
				(justify mirror)
			)
		)
		(property "Value" ""
			(at 0 0 0)
			(layer "B.Fab")
			(effects
				(font
					(size 1.27 1.27)
				)
				(justify mirror)
			)
		)
		(duplicate_pad_numbers_are_jumpers no)
		(fp_line
			(start 0.7874 0.4064)
			(end 0.7874 -0.4064)
			(stroke
				(width 0.1524)
				(type default)
			)
			(layer "B.SilkS")
		)
		(fp_line
			(start 0.7874 -0.4064)
			(end -0.7874 -0.4064)
			(stroke
				(width 0.1524)
				(type default)
			)
			(layer "B.SilkS")
		)
		(fp_line
			(start -0.7874 0.4064)
			(end 0.7874 0.4064)
			(stroke
				(width 0.1524)
				(type default)
			)
			(layer "B.SilkS")
		)
		(fp_line
			(start -0.7874 -0.4064)
			(end -0.7874 0.4064)
			(stroke
				(width 0.1524)
				(type default)
			)
			(layer "B.SilkS")
		)
		(fp_line
			(start 0.67945 0.3048)
			(end 0.67945 -0.305054)
			(stroke
				(width 0.1)
				(type default)
			)
			(layer "B.Fab")
		)
		(fp_line
			(start 0.67945 -0.305054)
			(end 0.12065 -0.305054)
			(stroke
				(width 0.1)
				(type default)
			)
			(layer "B.Fab")
		)
		(fp_line
			(start 0.12065 0.3048)
			(end 0.67945 0.3048)
			(stroke
				(width 0.1)
				(type default)
			)
			(layer "B.Fab")
		)
		(fp_line
			(start 0.12065 0.2794)
			(end 0.12065 0.3048)
			(stroke
				(width 0.1)
				(type default)
			)
			(layer "B.Fab")
		)
		(fp_line
			(start 0.12065 -0.2794)
			(end -0.12065 -0.2794)
			(stroke
				(width 0.1)
				(type default)
			)
			(layer "B.Fab")
		)
		(fp_line
			(start 0.12065 -0.305054)
			(end 0.12065 -0.2794)
			(stroke
				(width 0.1)
				(type default)
			)
			(layer "B.Fab")
		)
		(fp_line
			(start -0.120396 0.3048)
			(end -0.120396 0.2794)
			(stroke
				(width 0.1)
				(type default)
			)
			(layer "B.Fab")
		)
		(fp_line
			(start -0.120396 0.2794)
			(end 0.12065 0.2794)
			(stroke
				(width 0.1)
				(type default)
			)
			(layer "B.Fab")
		)
		(fp_line
			(start -0.12065 -0.2794)
			(end -0.12065 -0.3048)
			(stroke
				(width 0.1)
				(type default)
			)
			(layer "B.Fab")
		)
		(fp_line
			(start -0.12065 -0.3048)
			(end -0.67945 -0.3048)
			(stroke
				(width 0.1)
				(type default)
			)
			(layer "B.Fab")
		)
		(fp_line
			(start -0.67945 0.3048)
			(end -0.120396 0.3048)
			(stroke
				(width 0.1)
				(type default)
			)
			(layer "B.Fab")
		)
		(fp_line
			(start -0.67945 -0.3048)
			(end -0.67945 0.3048)
			(stroke
				(width 0.1)
				(type default)
			)
			(layer "B.Fab")
		)
		(pad "1" smd circle
			(at 0.40005 0)
			(size 0 0)
			(layers "B.Cu" "B.Mask" "B.Paste")
			(net "SPI_PEX0_SDIO2_R")
		)
		(pad "2" smd circle
			(at -0.40005 0)
			(size 0 0)
			(layers "B.Cu" "B.Mask" "B.Paste")
			(net "SPI_PEX0_SDIO2")
		)
	)
	(footprint ""
		(layer "B.Cu")
		(at 54.945534 -296.37482)
		(property "Reference" "C1113"
			(at 0 0 0)
			(layer "B.SilkS")
			(hide yes)
			(effects
				(font
					(size 1.27 1.27)
				)
				(justify mirror)
			)
		)
		(property "Value" ""
			(at 0 0 0)
			(layer "B.Fab")
			(effects
				(font
					(size 1.27 1.27)
				)
				(justify mirror)
			)
		)
		(duplicate_pad_numbers_are_jumpers no)
		(fp_line
			(start -0.299974 -0.150114)
			(end -0.299974 0.150114)
			(stroke
				(width 0.1)
				(type default)
			)
			(layer "B.Fab")
		)
		(fp_line
			(start -0.299974 0.150114)
			(end 0.299974 0.150114)
			(stroke
				(width 0.1)
				(type default)
			)
			(layer "B.Fab")
		)
		(fp_line
			(start 0.299974 -0.150114)
			(end -0.299974 -0.150114)
			(stroke
				(width 0.1)
				(type default)
			)
			(layer "B.Fab")
		)
		(fp_line
			(start 0.299974 0.150114)
			(end 0.299974 -0.150114)
			(stroke
				(width 0.1)
				(type default)
			)
			(layer "B.Fab")
		)
		(pad "1" smd rect
			(at 0.2667 0 180)
			(size 0.3048 0.381)
			(layers "B.Cu" "B.Mask" "B.Paste")
			(net "P0V8_PEX0")
		)
		(pad "2" smd rect
			(at -0.2667 0 180)
			(size 0.3048 0.381)
			(layers "B.Cu" "B.Mask" "B.Paste")
			(net "GND")
		)
	)
	(footprint ""
		(layer "B.Cu")
		(at 281.755342 -150.9776)
		(property "Reference" "R224"
			(at 0 0 0)
			(layer "B.SilkS")
			(hide yes)
			(effects
				(font
					(size 1.27 1.27)
				)
				(justify mirror)
			)
		)
		(property "Value" ""
			(at 0 0 0)
			(layer "B.Fab")
			(effects
				(font
					(size 1.27 1.27)
				)
				(justify mirror)
			)
		)
		(duplicate_pad_numbers_are_jumpers no)
		(fp_line
			(start -0.7874 -0.4064)
			(end -0.7874 0.4064)
			(stroke
				(width 0.1524)
				(type default)
			)
			(layer "B.SilkS")
		)
		(fp_line
			(start -0.7874 0.4064)
			(end 0.7874 0.4064)
			(stroke
				(width 0.1524)
				(type default)
			)
			(layer "B.SilkS")
		)
		(fp_line
			(start 0.7874 -0.4064)
			(end -0.7874 -0.4064)
			(stroke
				(width 0.1524)
				(type default)
			)
			(layer "B.SilkS")
		)
		(fp_line
			(start 0.7874 0.4064)
			(end 0.7874 -0.4064)
			(stroke
				(width 0.1524)
				(type default)
			)
			(layer "B.SilkS")
		)
		(fp_line
			(start -0.67945 -0.3048)
			(end -0.67945 0.3048)
			(stroke
				(width 0.1)
				(type default)
			)
			(layer "B.Fab")
		)
		(fp_line
			(start -0.67945 0.3048)
			(end -0.120396 0.3048)
			(stroke
				(width 0.1)
				(type default)
			)
			(layer "B.Fab")
		)
		(fp_line
			(start -0.12065 -0.3048)
			(end -0.67945 -0.3048)
			(stroke
				(width 0.1)
				(type default)
			)
			(layer "B.Fab")
		)
		(fp_line
			(start -0.12065 -0.2794)
			(end -0.12065 -0.3048)
			(stroke
				(width 0.1)
				(type default)
			)
			(layer "B.Fab")
		)
		(fp_line
			(start -0.120396 0.2794)
			(end 0.12065 0.2794)
			(stroke
				(width 0.1)
				(type default)
			)
			(layer "B.Fab")
		)
		(fp_line
			(start -0.120396 0.3048)
			(end -0.120396 0.2794)
			(stroke
				(width 0.1)
				(type default)
			)
			(layer "B.Fab")
		)
		(fp_line
			(start 0.12065 -0.305054)
			(end 0.12065 -0.2794)
			(stroke
				(width 0.1)
				(type default)
			)
			(layer "B.Fab")
		)
		(fp_line
			(start 0.12065 -0.2794)
			(end -0.12065 -0.2794)
			(stroke
				(width 0.1)
				(type default)
			)
			(layer "B.Fab")
		)
		(fp_line
			(start 0.12065 0.2794)
			(end 0.12065 0.3048)
			(stroke
				(width 0.1)
				(type default)
			)
			(layer "B.Fab")
		)
		(fp_line
			(start 0.12065 0.3048)
			(end 0.67945 0.3048)
			(stroke
				(width 0.1)
				(type default)
			)
			(layer "B.Fab")
		)
		(fp_line
			(start 0.67945 -0.305054)
			(end 0.12065 -0.305054)
			(stroke
				(width 0.1)
				(type default)
			)
			(layer "B.Fab")
		)
		(fp_line
			(start 0.67945 0.3048)
			(end 0.67945 -0.305054)
			(stroke
				(width 0.1)
				(type default)
			)
			(layer "B.Fab")
		)
		(pad "1" smd circle
			(at 0.40005 0 180)
			(size 0 0)
			(layers "B.Cu" "B.Mask" "B.Paste")
			(net "CLK_50M_NIC4_RBT_REF")
		)
		(pad "2" smd circle
			(at -0.40005 0 180)
			(size 0 0)
			(layers "B.Cu" "B.Mask" "B.Paste")
			(net "GND")
		)
	)
	(footprint ""
		(layer "B.Cu")
		(at 193.641726 -97.005648 180)
		(property "Reference" "R165"
			(at 0 0 0)
			(layer "B.SilkS")
			(hide yes)
			(effects
				(font
					(size 1.27 1.27)
				)
				(justify mirror)
			)
		)
		(property "Value" ""
			(at 0 0 0)
			(layer "B.Fab")
			(effects
				(font
					(size 1.27 1.27)
				)
				(justify mirror)
			)
		)
		(duplicate_pad_numbers_are_jumpers no)
		(fp_line
			(start 0.7874 0.4064)
			(end 0.7874 -0.4064)
			(stroke
				(width 0.1524)
				(type default)
			)
			(layer "B.SilkS")
		)
		(fp_line
			(start 0.7874 -0.4064)
			(end -0.7874 -0.4064)
			(stroke
				(width 0.1524)
				(type default)
			)
			(layer "B.SilkS")
		)
		(fp_line
			(start -0.7874 0.4064)
			(end 0.7874 0.4064)
			(stroke
				(width 0.1524)
				(type default)
			)
			(layer "B.SilkS")
		)
		(fp_line
			(start -0.7874 -0.4064)
			(end -0.7874 0.4064)
			(stroke
				(width 0.1524)
				(type default)
			)
			(layer "B.SilkS")
		)
		(fp_line
			(start 0.67945 0.3048)
			(end 0.67945 -0.305054)
			(stroke
				(width 0.1)
				(type default)
			)
			(layer "B.Fab")
		)
		(fp_line
			(start 0.67945 -0.305054)
			(end 0.12065 -0.305054)
			(stroke
				(width 0.1)
				(type default)
			)
			(layer "B.Fab")
		)
		(fp_line
			(start 0.12065 0.3048)
			(end 0.67945 0.3048)
			(stroke
				(width 0.1)
				(type default)
			)
			(layer "B.Fab")
		)
		(fp_line
			(start 0.12065 0.2794)
			(end 0.12065 0.3048)
			(stroke
				(width 0.1)
				(type default)
			)
			(layer "B.Fab")
		)
		(fp_line
			(start 0.12065 -0.2794)
			(end -0.12065 -0.2794)
			(stroke
				(width 0.1)
				(type default)
			)
			(layer "B.Fab")
		)
		(fp_line
			(start 0.12065 -0.305054)
			(end 0.12065 -0.2794)
			(stroke
				(width 0.1)
				(type default)
			)
			(layer "B.Fab")
		)
		(fp_line
			(start -0.120396 0.3048)
			(end -0.120396 0.2794)
			(stroke
				(width 0.1)
				(type default)
			)
			(layer "B.Fab")
		)
		(fp_line
			(start -0.120396 0.2794)
			(end 0.12065 0.2794)
			(stroke
				(width 0.1)
				(type default)
			)
			(layer "B.Fab")
		)
		(fp_line
			(start -0.12065 -0.2794)
			(end -0.12065 -0.3048)
			(stroke
				(width 0.1)
				(type default)
			)
			(layer "B.Fab")
		)
		(fp_line
			(start -0.12065 -0.3048)
			(end -0.67945 -0.3048)
			(stroke
				(width 0.1)
				(type default)
			)
			(layer "B.Fab")
		)
		(fp_line
			(start -0.67945 0.3048)
			(end -0.120396 0.3048)
			(stroke
				(width 0.1)
				(type default)
			)
			(layer "B.Fab")
		)
		(fp_line
			(start -0.67945 -0.3048)
			(end -0.67945 0.3048)
			(stroke
				(width 0.1)
				(type default)
			)
			(layer "B.Fab")
		)
		(pad "1" smd circle
			(at 0.40005 0)
			(size 0 0)
			(layers "B.Cu" "B.Mask" "B.Paste")
			(net "NIC3_DATA_IN")
		)
		(pad "2" smd circle
			(at -0.40005 0)
			(size 0 0)
			(layers "B.Cu" "B.Mask" "B.Paste")
			(net "P3V3_NIC3")
		)
	)
	(footprint ""
		(layer "B.Cu")
		(at 303.249838 -296.37482 180)
		(property "Reference" "C3285"
			(at 0 0 0)
			(layer "B.SilkS")
			(hide yes)
			(effects
				(font
					(size 1.27 1.27)
				)
				(justify mirror)
			)
		)
		(property "Value" ""
			(at 0 0 0)
			(layer "B.Fab")
			(effects
				(font
					(size 1.27 1.27)
				)
				(justify mirror)
			)
		)
		(duplicate_pad_numbers_are_jumpers no)
		(fp_line
			(start 0.299974 0.150114)
			(end 0.299974 -0.150114)
			(stroke
				(width 0.1)
				(type default)
			)
			(layer "B.Fab")
		)
		(fp_line
			(start 0.299974 -0.150114)
			(end -0.299974 -0.150114)
			(stroke
				(width 0.1)
				(type default)
			)
			(layer "B.Fab")
		)
		(fp_line
			(start -0.299974 0.150114)
			(end 0.299974 0.150114)
			(stroke
				(width 0.1)
				(type default)
			)
			(layer "B.Fab")
		)
		(fp_line
			(start -0.299974 -0.150114)
			(end -0.299974 0.150114)
			(stroke
				(width 0.1)
				(type default)
			)
			(layer "B.Fab")
		)
		(pad "1" smd rect
			(at 0.2667 0)
			(size 0.3048 0.381)
			(layers "B.Cu" "B.Mask" "B.Paste")
			(net "P1V25_PEX2")
		)
		(pad "2" smd rect
			(at -0.2667 0)
			(size 0.3048 0.381)
			(layers "B.Cu" "B.Mask" "B.Paste")
			(net "GND")
		)
	)
	(footprint ""
		(layer "B.Cu")
		(at 70.099936 -288.774886 180)
		(property "Reference" "C3002"
			(at 0 0 0)
			(layer "B.SilkS")
			(hide yes)
			(effects
				(font
					(size 1.27 1.27)
				)
				(justify mirror)
			)
		)
		(property "Value" ""
			(at 0 0 0)
			(layer "B.Fab")
			(effects
				(font
					(size 1.27 1.27)
				)
				(justify mirror)
			)
		)
		(duplicate_pad_numbers_are_jumpers no)
		(fp_line
			(start 0.299974 0.150114)
			(end 0.299974 -0.150114)
			(stroke
				(width 0.1)
				(type default)
			)
			(layer "B.Fab")
		)
		(fp_line
			(start 0.299974 -0.150114)
			(end -0.299974 -0.150114)
			(stroke
				(width 0.1)
				(type default)
			)
			(layer "B.Fab")
		)
		(fp_line
			(start -0.299974 0.150114)
			(end 0.299974 0.150114)
			(stroke
				(width 0.1)
				(type default)
			)
			(layer "B.Fab")
		)
		(fp_line
			(start -0.299974 -0.150114)
			(end -0.299974 0.150114)
			(stroke
				(width 0.1)
				(type default)
			)
			(layer "B.Fab")
		)
		(pad "1" smd rect
			(at 0.2667 0)
			(size 0.3048 0.381)
			(layers "B.Cu" "B.Mask" "B.Paste")
			(net "P1V8_PEX")
		)
		(pad "2" smd rect
			(at -0.2667 0)
			(size 0.3048 0.381)
			(layers "B.Cu" "B.Mask" "B.Paste")
			(net "GND")
		)
	)
	(footprint ""
		(layer "B.Cu")
		(at 286.149796 -292.099746 90)
		(property "Reference" "C1744"
			(at 0 0 90)
			(layer "B.SilkS")
			(hide yes)
			(effects
				(font
					(size 1.27 1.27)
				)
				(justify mirror)
			)
		)
		(property "Value" ""
			(at 0 0 90)
			(layer "B.Fab")
			(effects
				(font
					(size 1.27 1.27)
				)
				(justify mirror)
			)
		)
		(duplicate_pad_numbers_are_jumpers no)
		(fp_line
			(start 0.299974 -0.150114)
			(end -0.299974 -0.150114)
			(stroke
				(width 0.1)
				(type default)
			)
			(layer "B.Fab")
		)
		(fp_line
			(start -0.299974 -0.150114)
			(end -0.299974 0.150114)
			(stroke
				(width 0.1)
				(type default)
			)
			(layer "B.Fab")
		)
		(fp_line
			(start 0.299974 0.150114)
			(end 0.299974 -0.150114)
			(stroke
				(width 0.1)
				(type default)
			)
			(layer "B.Fab")
		)
		(fp_line
			(start -0.299974 0.150114)
			(end 0.299974 0.150114)
			(stroke
				(width 0.1)
				(type default)
			)
			(layer "B.Fab")
		)
		(pad "1" smd rect
			(at 0.2667 0 270)
			(size 0.3048 0.381)
			(layers "B.Cu" "B.Mask" "B.Paste")
			(net "P0V8_SERDES_VDDA_PEX2")
		)
		(pad "2" smd rect
			(at -0.2667 0 270)
			(size 0.3048 0.381)
			(layers "B.Cu" "B.Mask" "B.Paste")
			(net "GND")
		)
	)
	(footprint ""
		(layer "B.Cu")
		(at 302.552354 -236.736636 90)
		(property "Reference" "R1859"
			(at 0 0 90)
			(layer "B.SilkS")
			(hide yes)
			(effects
				(font
					(size 1.27 1.27)
				)
				(justify mirror)
			)
		)
		(property "Value" ""
			(at 0 0 90)
			(layer "B.Fab")
			(effects
				(font
					(size 1.27 1.27)
				)
				(justify mirror)
			)
		)
		(duplicate_pad_numbers_are_jumpers no)
		(fp_line
			(start 0.7874 -0.4064)
			(end -0.7874 -0.4064)
			(stroke
				(width 0.1524)
				(type default)
			)
			(layer "B.SilkS")
		)
		(fp_line
			(start -0.7874 -0.4064)
			(end -0.7874 0.4064)
			(stroke
				(width 0.1524)
				(type default)
			)
			(layer "B.SilkS")
		)
		(fp_line
			(start 0.7874 0.4064)
			(end 0.7874 -0.4064)
			(stroke
				(width 0.1524)
				(type default)
			)
			(layer "B.SilkS")
		)
		(fp_line
			(start -0.7874 0.4064)
			(end 0.7874 0.4064)
			(stroke
				(width 0.1524)
				(type default)
			)
			(layer "B.SilkS")
		)
		(fp_line
			(start 0.67945 -0.305054)
			(end 0.12065 -0.305054)
			(stroke
				(width 0.1)
				(type default)
			)
			(layer "B.Fab")
		)
		(fp_line
			(start 0.12065 -0.305054)
			(end 0.12065 -0.2794)
			(stroke
				(width 0.1)
				(type default)
			)
			(layer "B.Fab")
		)
		(fp_line
			(start -0.12065 -0.3048)
			(end -0.67945 -0.3048)
			(stroke
				(width 0.1)
				(type default)
			)
			(layer "B.Fab")
		)
		(fp_line
			(start -0.67945 -0.3048)
			(end -0.67945 0.3048)
			(stroke
				(width 0.1)
				(type default)
			)
			(layer "B.Fab")
		)
		(fp_line
			(start 0.12065 -0.2794)
			(end -0.12065 -0.2794)
			(stroke
				(width 0.1)
				(type default)
			)
			(layer "B.Fab")
		)
		(fp_line
			(start -0.12065 -0.2794)
			(end -0.12065 -0.3048)
			(stroke
				(width 0.1)
				(type default)
			)
			(layer "B.Fab")
		)
		(fp_line
			(start 0.12065 0.2794)
			(end 0.12065 0.3048)
			(stroke
				(width 0.1)
				(type default)
			)
			(layer "B.Fab")
		)
		(fp_line
			(start -0.120396 0.2794)
			(end 0.12065 0.2794)
			(stroke
				(width 0.1)
				(type default)
			)
			(layer "B.Fab")
		)
		(fp_line
			(start 0.67945 0.3048)
			(end 0.67945 -0.305054)
			(stroke
				(width 0.1)
				(type default)
			)
			(layer "B.Fab")
		)
		(fp_line
			(start 0.12065 0.3048)
			(end 0.67945 0.3048)
			(stroke
				(width 0.1)
				(type default)
			)
			(layer "B.Fab")
		)
		(fp_line
			(start -0.120396 0.3048)
			(end -0.120396 0.2794)
			(stroke
				(width 0.1)
				(type default)
			)
			(layer "B.Fab")
		)
		(fp_line
			(start -0.67945 0.3048)
			(end -0.120396 0.3048)
			(stroke
				(width 0.1)
				(type default)
			)
			(layer "B.Fab")
		)
		(pad "1" smd circle
			(at 0.40005 0 270)
			(size 0 0)
			(layers "B.Cu" "B.Mask" "B.Paste")
			(net "P3V3_AUX")
		)
		(pad "2" smd circle
			(at -0.40005 0 270)
			(size 0 0)
			(layers "B.Cu" "B.Mask" "B.Paste")
			(net "RST_GPU_PERST_1_N")
		)
	)
	(footprint ""
		(layer "B.Cu")
		(at 221.257114 -211.591398)
		(property "Reference" "C2010"
			(at 0 0 0)
			(layer "B.SilkS")
			(hide yes)
			(effects
				(font
					(size 1.27 1.27)
				)
				(justify mirror)
			)
		)
		(property "Value" ""
			(at 0 0 0)
			(layer "B.Fab")
			(effects
				(font
					(size 1.27 1.27)
				)
				(justify mirror)
			)
		)
		(duplicate_pad_numbers_are_jumpers no)
		(fp_line
			(start -1.2954 -0.5842)
			(end -1.2954 0.5842)
			(stroke
				(width 0.1524)
				(type default)
			)
			(layer "B.SilkS")
		)
		(fp_line
			(start -1.2954 0.5842)
			(end 1.2954 0.5842)
			(stroke
				(width 0.1524)
				(type default)
			)
			(layer "B.SilkS")
		)
		(fp_line
			(start 1.2954 -0.5842)
			(end -1.2954 -0.5842)
			(stroke
				(width 0.1524)
				(type default)
			)
			(layer "B.SilkS")
		)
		(fp_line
			(start 1.2954 0.5842)
			(end 1.2954 -0.5842)
			(stroke
				(width 0.1524)
				(type default)
			)
			(layer "B.SilkS")
		)
		(fp_line
			(start -1.1938 -0.4064)
			(end -1.1938 0.4064)
			(stroke
				(width 0.1)
				(type default)
			)
			(layer "B.Fab")
		)
		(fp_line
			(start -1.1938 0.4064)
			(end -0.8636 0.4064)
			(stroke
				(width 0.1)
				(type default)
			)
			(layer "B.Fab")
		)
		(fp_line
			(start -0.8636 -0.4572)
			(end -0.8636 -0.4064)
			(stroke
				(width 0.1)
				(type default)
			)
			(layer "B.Fab")
		)
		(fp_line
			(start -0.8636 -0.4064)
			(end -1.1938 -0.4064)
			(stroke
				(width 0.1)
				(type default)
			)
			(layer "B.Fab")
		)
		(fp_line
			(start -0.8636 0.4064)
			(end -0.8636 0.4572)
			(stroke
				(width 0.1)
				(type default)
			)
			(layer "B.Fab")
		)
		(fp_line
			(start -0.8636 0.4572)
			(end 0.8636 0.4572)
			(stroke
				(width 0.1)
				(type default)
			)
			(layer "B.Fab")
		)
		(fp_line
			(start 0.8636 -0.4572)
			(end -0.8636 -0.4572)
			(stroke
				(width 0.1)
				(type default)
			)
			(layer "B.Fab")
		)
		(fp_line
			(start 0.8636 -0.4064)
			(end 0.8636 -0.4572)
			(stroke
				(width 0.1)
				(type default)
			)
			(layer "B.Fab")
		)
		(fp_line
			(start 0.8636 0.4064)
			(end 1.1938 0.4064)
			(stroke
				(width 0.1)
				(type default)
			)
			(layer "B.Fab")
		)
		(fp_line
			(start 0.8636 0.4572)
			(end 0.8636 0.4064)
			(stroke
				(width 0.1)
				(type default)
			)
			(layer "B.Fab")
		)
		(fp_line
			(start 1.1938 -0.4064)
			(end 0.8636 -0.4064)
			(stroke
				(width 0.1)
				(type default)
			)
			(layer "B.Fab")
		)
		(fp_line
			(start 1.1938 0.4064)
			(end 1.1938 -0.4064)
			(stroke
				(width 0.1)
				(type default)
			)
			(layer "B.Fab")
		)
		(pad "1" smd rect
			(at 0.7366 0 270)
			(size 0.7112 0.8128)
			(layers "B.Cu" "B.Mask" "B.Paste")
			(net "P3V3_AUX")
		)
		(pad "2" smd rect
			(at -0.7366 0 270)
			(size 0.7112 0.8128)
			(layers "B.Cu" "B.Mask" "B.Paste")
			(net "GND")
		)
	)
	(footprint ""
		(layer "B.Cu")
		(at 402.249894 -301.599854 -90)
		(property "Reference" "C1969"
			(at 0 0 90)
			(layer "B.SilkS")
			(hide yes)
			(effects
				(font
					(size 1.27 1.27)
				)
				(justify mirror)
			)
		)
		(property "Value" ""
			(at 0 0 90)
			(layer "B.Fab")
			(effects
				(font
					(size 1.27 1.27)
				)
				(justify mirror)
			)
		)
		(duplicate_pad_numbers_are_jumpers no)
		(fp_line
			(start -0.299974 0.150114)
			(end 0.299974 0.150114)
			(stroke
				(width 0.1)
				(type default)
			)
			(layer "B.Fab")
		)
		(fp_line
			(start 0.299974 0.150114)
			(end 0.299974 -0.150114)
			(stroke
				(width 0.1)
				(type default)
			)
			(layer "B.Fab")
		)
		(fp_line
			(start -0.299974 -0.150114)
			(end -0.299974 0.150114)
			(stroke
				(width 0.1)
				(type default)
			)
			(layer "B.Fab")
		)
		(fp_line
			(start 0.299974 -0.150114)
			(end -0.299974 -0.150114)
			(stroke
				(width 0.1)
				(type default)
			)
			(layer "B.Fab")
		)
		(pad "1" smd rect
			(at 0.2667 0 90)
			(size 0.3048 0.381)
			(layers "B.Cu" "B.Mask" "B.Paste")
			(net "P0V8_SERDES_VDDA_PEX3")
		)
		(pad "2" smd rect
			(at -0.2667 0 90)
			(size 0.3048 0.381)
			(layers "B.Cu" "B.Mask" "B.Paste")
			(net "GND")
		)
	)
	(footprint ""
		(layer "B.Cu")
		(at 411.675326 -110.497366 180)
		(property "Reference" "R391"
			(at 0 0 0)
			(layer "B.SilkS")
			(hide yes)
			(effects
				(font
					(size 1.27 1.27)
				)
				(justify mirror)
			)
		)
		(property "Value" ""
			(at 0 0 0)
			(layer "B.Fab")
			(effects
				(font
					(size 1.27 1.27)
				)
				(justify mirror)
			)
		)
		(duplicate_pad_numbers_are_jumpers no)
		(fp_line
			(start 0.7874 0.4064)
			(end 0.7874 -0.4064)
			(stroke
				(width 0.1524)
				(type default)
			)
			(layer "B.SilkS")
		)
		(fp_line
			(start 0.7874 -0.4064)
			(end -0.7874 -0.4064)
			(stroke
				(width 0.1524)
				(type default)
			)
			(layer "B.SilkS")
		)
		(fp_line
			(start -0.7874 0.4064)
			(end 0.7874 0.4064)
			(stroke
				(width 0.1524)
				(type default)
			)
			(layer "B.SilkS")
		)
		(fp_line
			(start -0.7874 -0.4064)
			(end -0.7874 0.4064)
			(stroke
				(width 0.1524)
				(type default)
			)
			(layer "B.SilkS")
		)
		(fp_line
			(start 0.67945 0.3048)
			(end 0.67945 -0.305054)
			(stroke
				(width 0.1)
				(type default)
			)
			(layer "B.Fab")
		)
		(fp_line
			(start 0.67945 -0.305054)
			(end 0.12065 -0.305054)
			(stroke
				(width 0.1)
				(type default)
			)
			(layer "B.Fab")
		)
		(fp_line
			(start 0.12065 0.3048)
			(end 0.67945 0.3048)
			(stroke
				(width 0.1)
				(type default)
			)
			(layer "B.Fab")
		)
		(fp_line
			(start 0.12065 0.2794)
			(end 0.12065 0.3048)
			(stroke
				(width 0.1)
				(type default)
			)
			(layer "B.Fab")
		)
		(fp_line
			(start 0.12065 -0.2794)
			(end -0.12065 -0.2794)
			(stroke
				(width 0.1)
				(type default)
			)
			(layer "B.Fab")
		)
		(fp_line
			(start 0.12065 -0.305054)
			(end 0.12065 -0.2794)
			(stroke
				(width 0.1)
				(type default)
			)
			(layer "B.Fab")
		)
		(fp_line
			(start -0.120396 0.3048)
			(end -0.120396 0.2794)
			(stroke
				(width 0.1)
				(type default)
			)
			(layer "B.Fab")
		)
		(fp_line
			(start -0.120396 0.2794)
			(end 0.12065 0.2794)
			(stroke
				(width 0.1)
				(type default)
			)
			(layer "B.Fab")
		)
		(fp_line
			(start -0.12065 -0.2794)
			(end -0.12065 -0.3048)
			(stroke
				(width 0.1)
				(type default)
			)
			(layer "B.Fab")
		)
		(fp_line
			(start -0.12065 -0.3048)
			(end -0.67945 -0.3048)
			(stroke
				(width 0.1)
				(type default)
			)
			(layer "B.Fab")
		)
		(fp_line
			(start -0.67945 0.3048)
			(end -0.120396 0.3048)
			(stroke
				(width 0.1)
				(type default)
			)
			(layer "B.Fab")
		)
		(fp_line
			(start -0.67945 -0.3048)
			(end -0.67945 0.3048)
			(stroke
				(width 0.1)
				(type default)
			)
			(layer "B.Fab")
		)
		(pad "1" smd circle
			(at 0.40005 0)
			(size 0 0)
			(layers "B.Cu" "B.Mask" "B.Paste")
			(net "NIC7_BIF2_N")
		)
		(pad "2" smd circle
			(at -0.40005 0)
			(size 0 0)
			(layers "B.Cu" "B.Mask" "B.Paste")
			(net "GND")
		)
	)
	(footprint ""
		(layer "B.Cu")
		(at 71.049896 -293.52494 180)
		(property "Reference" "C2929"
			(at 0 0 0)
			(layer "B.SilkS")
			(hide yes)
			(effects
				(font
					(size 1.27 1.27)
				)
				(justify mirror)
			)
		)
		(property "Value" ""
			(at 0 0 0)
			(layer "B.Fab")
			(effects
				(font
					(size 1.27 1.27)
				)
				(justify mirror)
			)
		)
		(duplicate_pad_numbers_are_jumpers no)
		(fp_line
			(start 0.299974 0.150114)
			(end 0.299974 -0.150114)
			(stroke
				(width 0.1)
				(type default)
			)
			(layer "B.Fab")
		)
		(fp_line
			(start 0.299974 -0.150114)
			(end -0.299974 -0.150114)
			(stroke
				(width 0.1)
				(type default)
			)
			(layer "B.Fab")
		)
		(fp_line
			(start -0.299974 0.150114)
			(end 0.299974 0.150114)
			(stroke
				(width 0.1)
				(type default)
			)
			(layer "B.Fab")
		)
		(fp_line
			(start -0.299974 -0.150114)
			(end -0.299974 0.150114)
			(stroke
				(width 0.1)
				(type default)
			)
			(layer "B.Fab")
		)
		(pad "1" smd rect
			(at 0.2667 0)
			(size 0.3048 0.381)
			(layers "B.Cu" "B.Mask" "B.Paste")
			(net "P1V25_PEX0")
		)
		(pad "2" smd rect
			(at -0.2667 0)
			(size 0.3048 0.381)
			(layers "B.Cu" "B.Mask" "B.Paste")
			(net "GND")
		)
	)
	(footprint ""
		(layer "B.Cu")
		(at 124.217938 -308.580028 90)
		(property "Reference" "C4246"
			(at 0 0 90)
			(layer "B.SilkS")
			(hide yes)
			(effects
				(font
					(size 1.27 1.27)
				)
				(justify mirror)
			)
		)
		(property "Value" ""
			(at 0 0 90)
			(layer "B.Fab")
			(effects
				(font
					(size 1.27 1.27)
				)
				(justify mirror)
			)
		)
		(duplicate_pad_numbers_are_jumpers no)
		(fp_line
			(start 1.2954 -0.5842)
			(end -1.2954 -0.5842)
			(stroke
				(width 0.1524)
				(type default)
			)
			(layer "B.SilkS")
		)
		(fp_line
			(start -1.2954 -0.5842)
			(end -1.2954 0.5842)
			(stroke
				(width 0.1524)
				(type default)
			)
			(layer "B.SilkS")
		)
		(fp_line
			(start 1.2954 0.5842)
			(end 1.2954 -0.5842)
			(stroke
				(width 0.1524)
				(type default)
			)
			(layer "B.SilkS")
		)
		(fp_line
			(start -1.2954 0.5842)
			(end 1.2954 0.5842)
			(stroke
				(width 0.1524)
				(type default)
			)
			(layer "B.SilkS")
		)
		(fp_line
			(start 0.8636 -0.4572)
			(end -0.8636 -0.4572)
			(stroke
				(width 0.1)
				(type default)
			)
			(layer "B.Fab")
		)
		(fp_line
			(start -0.8636 -0.4572)
			(end -0.8636 -0.4064)
			(stroke
				(width 0.1)
				(type default)
			)
			(layer "B.Fab")
		)
		(fp_line
			(start 1.1938 -0.4064)
			(end 0.8636 -0.4064)
			(stroke
				(width 0.1)
				(type default)
			)
			(layer "B.Fab")
		)
		(fp_line
			(start 0.8636 -0.4064)
			(end 0.8636 -0.4572)
			(stroke
				(width 0.1)
				(type default)
			)
			(layer "B.Fab")
		)
		(fp_line
			(start -0.8636 -0.4064)
			(end -1.1938 -0.4064)
			(stroke
				(width 0.1)
				(type default)
			)
			(layer "B.Fab")
		)
		(fp_line
			(start -1.1938 -0.4064)
			(end -1.1938 0.4064)
			(stroke
				(width 0.1)
				(type default)
			)
			(layer "B.Fab")
		)
		(fp_line
			(start 1.1938 0.4064)
			(end 1.1938 -0.4064)
			(stroke
				(width 0.1)
				(type default)
			)
			(layer "B.Fab")
		)
		(fp_line
			(start 0.8636 0.4064)
			(end 1.1938 0.4064)
			(stroke
				(width 0.1)
				(type default)
			)
			(layer "B.Fab")
		)
		(fp_line
			(start -0.8636 0.4064)
			(end -0.8636 0.4572)
			(stroke
				(width 0.1)
				(type default)
			)
			(layer "B.Fab")
		)
		(fp_line
			(start -1.1938 0.4064)
			(end -0.8636 0.4064)
			(stroke
				(width 0.1)
				(type default)
			)
			(layer "B.Fab")
		)
		(fp_line
			(start 0.8636 0.4572)
			(end 0.8636 0.4064)
			(stroke
				(width 0.1)
				(type default)
			)
			(layer "B.Fab")
		)
		(fp_line
			(start -0.8636 0.4572)
			(end 0.8636 0.4572)
			(stroke
				(width 0.1)
				(type default)
			)
			(layer "B.Fab")
		)
		(pad "1" smd rect
			(at 0.7366 0)
			(size 0.7112 0.8128)
			(layers "B.Cu" "B.Mask" "B.Paste")
			(net "P0V8_PEX1")
		)
		(pad "2" smd rect
			(at -0.7366 0)
			(size 0.7112 0.8128)
			(layers "B.Cu" "B.Mask" "B.Paste")
			(net "GND")
		)
	)
	(footprint ""
		(layer "B.Cu")
		(at 101.223318 -391.3378 180)
		(property "Reference" "C3627"
			(at 0 0 0)
			(layer "B.SilkS")
			(hide yes)
			(effects
				(font
					(size 1.27 1.27)
				)
				(justify mirror)
			)
		)
		(property "Value" ""
			(at 0 0 0)
			(layer "B.Fab")
			(effects
				(font
					(size 1.27 1.27)
				)
				(justify mirror)
			)
		)
		(duplicate_pad_numbers_are_jumpers no)
		(fp_line
			(start 0.7874 0.4064)
			(end 0.7874 -0.4064)
			(stroke
				(width 0.1524)
				(type default)
			)
			(layer "B.SilkS")
		)
		(fp_line
			(start 0.7874 -0.4064)
			(end -0.7874 -0.4064)
			(stroke
				(width 0.1524)
				(type default)
			)
			(layer "B.SilkS")
		)
		(fp_line
			(start -0.7874 0.4064)
			(end 0.7874 0.4064)
			(stroke
				(width 0.1524)
				(type default)
			)
			(layer "B.SilkS")
		)
		(fp_line
			(start -0.7874 -0.4064)
			(end -0.7874 0.4064)
			(stroke
				(width 0.1524)
				(type default)
			)
			(layer "B.SilkS")
		)
		(fp_line
			(start 0.67945 0.3048)
			(end 0.67945 -0.305054)
			(stroke
				(width 0.1)
				(type default)
			)
			(layer "B.Fab")
		)
		(fp_line
			(start 0.67945 -0.305054)
			(end 0.12065 -0.305054)
			(stroke
				(width 0.1)
				(type default)
			)
			(layer "B.Fab")
		)
		(fp_line
			(start 0.12065 0.3048)
			(end 0.67945 0.3048)
			(stroke
				(width 0.1)
				(type default)
			)
			(layer "B.Fab")
		)
		(fp_line
			(start 0.12065 0.2794)
			(end 0.12065 0.3048)
			(stroke
				(width 0.1)
				(type default)
			)
			(layer "B.Fab")
		)
		(fp_line
			(start 0.12065 -0.2794)
			(end -0.12065 -0.2794)
			(stroke
				(width 0.1)
				(type default)
			)
			(layer "B.Fab")
		)
		(fp_line
			(start 0.12065 -0.305054)
			(end 0.12065 -0.2794)
			(stroke
				(width 0.1)
				(type default)
			)
			(layer "B.Fab")
		)
		(fp_line
			(start -0.120396 0.3048)
			(end -0.120396 0.2794)
			(stroke
				(width 0.1)
				(type default)
			)
			(layer "B.Fab")
		)
		(fp_line
			(start -0.120396 0.2794)
			(end 0.12065 0.2794)
			(stroke
				(width 0.1)
				(type default)
			)
			(layer "B.Fab")
		)
		(fp_line
			(start -0.12065 -0.2794)
			(end -0.12065 -0.3048)
			(stroke
				(width 0.1)
				(type default)
			)
			(layer "B.Fab")
		)
		(fp_line
			(start -0.12065 -0.3048)
			(end -0.67945 -0.3048)
			(stroke
				(width 0.1)
				(type default)
			)
			(layer "B.Fab")
		)
		(fp_line
			(start -0.67945 0.3048)
			(end -0.120396 0.3048)
			(stroke
				(width 0.1)
				(type default)
			)
			(layer "B.Fab")
		)
		(fp_line
			(start -0.67945 -0.3048)
			(end -0.67945 0.3048)
			(stroke
				(width 0.1)
				(type default)
			)
			(layer "B.Fab")
		)
		(pad "1" smd circle
			(at 0.40005 0)
			(size 0 0)
			(layers "B.Cu" "B.Mask" "B.Paste")
			(net "P3V3_BIC_USB_HUB")
		)
		(pad "2" smd circle
			(at -0.40005 0)
			(size 0 0)
			(layers "B.Cu" "B.Mask" "B.Paste")
			(net "GND")
		)
	)
	(footprint ""
		(layer "B.Cu")
		(at 176.224946 -297.79976 90)
		(property "Reference" "C1405"
			(at 0 0 90)
			(layer "B.SilkS")
			(hide yes)
			(effects
				(font
					(size 1.27 1.27)
				)
				(justify mirror)
			)
		)
		(property "Value" ""
			(at 0 0 90)
			(layer "B.Fab")
			(effects
				(font
					(size 1.27 1.27)
				)
				(justify mirror)
			)
		)
		(duplicate_pad_numbers_are_jumpers no)
		(fp_line
			(start 0.299974 -0.150114)
			(end -0.299974 -0.150114)
			(stroke
				(width 0.1)
				(type default)
			)
			(layer "B.Fab")
		)
		(fp_line
			(start -0.299974 -0.150114)
			(end -0.299974 0.150114)
			(stroke
				(width 0.1)
				(type default)
			)
			(layer "B.Fab")
		)
		(fp_line
			(start 0.299974 0.150114)
			(end 0.299974 -0.150114)
			(stroke
				(width 0.1)
				(type default)
			)
			(layer "B.Fab")
		)
		(fp_line
			(start -0.299974 0.150114)
			(end 0.299974 0.150114)
			(stroke
				(width 0.1)
				(type default)
			)
			(layer "B.Fab")
		)
		(pad "1" smd rect
			(at 0.2667 0 270)
			(size 0.3048 0.381)
			(layers "B.Cu" "B.Mask" "B.Paste")
			(net "P0V8_PEX1")
		)
		(pad "2" smd rect
			(at -0.2667 0 270)
			(size 0.3048 0.381)
			(layers "B.Cu" "B.Mask" "B.Paste")
			(net "GND")
		)
	)
	(footprint ""
		(layer "B.Cu")
		(at 104.845866 -347.125036 90)
		(property "Reference" "C4183"
			(at 0 0 90)
			(layer "B.SilkS")
			(hide yes)
			(effects
				(font
					(size 1.27 1.27)
				)
				(justify mirror)
			)
		)
		(property "Value" ""
			(at 0 0 90)
			(layer "B.Fab")
			(effects
				(font
					(size 1.27 1.27)
				)
				(justify mirror)
			)
		)
		(duplicate_pad_numbers_are_jumpers no)
		(fp_line
			(start 0.7874 -0.4064)
			(end -0.7874 -0.4064)
			(stroke
				(width 0.1524)
				(type default)
			)
			(layer "B.SilkS")
		)
		(fp_line
			(start -0.7874 -0.4064)
			(end -0.7874 0.4064)
			(stroke
				(width 0.1524)
				(type default)
			)
			(layer "B.SilkS")
		)
		(fp_line
			(start 0.7874 0.4064)
			(end 0.7874 -0.4064)
			(stroke
				(width 0.1524)
				(type default)
			)
			(layer "B.SilkS")
		)
		(fp_line
			(start -0.7874 0.4064)
			(end 0.7874 0.4064)
			(stroke
				(width 0.1524)
				(type default)
			)
			(layer "B.SilkS")
		)
		(fp_line
			(start 0.67945 -0.305054)
			(end 0.12065 -0.305054)
			(stroke
				(width 0.1)
				(type default)
			)
			(layer "B.Fab")
		)
		(fp_line
			(start 0.12065 -0.305054)
			(end 0.12065 -0.2794)
			(stroke
				(width 0.1)
				(type default)
			)
			(layer "B.Fab")
		)
		(fp_line
			(start -0.12065 -0.3048)
			(end -0.67945 -0.3048)
			(stroke
				(width 0.1)
				(type default)
			)
			(layer "B.Fab")
		)
		(fp_line
			(start -0.67945 -0.3048)
			(end -0.67945 0.3048)
			(stroke
				(width 0.1)
				(type default)
			)
			(layer "B.Fab")
		)
		(fp_line
			(start 0.12065 -0.2794)
			(end -0.12065 -0.2794)
			(stroke
				(width 0.1)
				(type default)
			)
			(layer "B.Fab")
		)
		(fp_line
			(start -0.12065 -0.2794)
			(end -0.12065 -0.3048)
			(stroke
				(width 0.1)
				(type default)
			)
			(layer "B.Fab")
		)
		(fp_line
			(start 0.12065 0.2794)
			(end 0.12065 0.3048)
			(stroke
				(width 0.1)
				(type default)
			)
			(layer "B.Fab")
		)
		(fp_line
			(start -0.120396 0.2794)
			(end 0.12065 0.2794)
			(stroke
				(width 0.1)
				(type default)
			)
			(layer "B.Fab")
		)
		(fp_line
			(start 0.67945 0.3048)
			(end 0.67945 -0.305054)
			(stroke
				(width 0.1)
				(type default)
			)
			(layer "B.Fab")
		)
		(fp_line
			(start 0.12065 0.3048)
			(end 0.67945 0.3048)
			(stroke
				(width 0.1)
				(type default)
			)
			(layer "B.Fab")
		)
		(fp_line
			(start -0.120396 0.3048)
			(end -0.120396 0.2794)
			(stroke
				(width 0.1)
				(type default)
			)
			(layer "B.Fab")
		)
		(fp_line
			(start -0.67945 0.3048)
			(end -0.120396 0.3048)
			(stroke
				(width 0.1)
				(type default)
			)
			(layer "B.Fab")
		)
		(pad "1" smd circle
			(at 0.40005 0 270)
			(size 0 0)
			(layers "B.Cu" "B.Mask" "B.Paste")
			(net "P3V3_CLK_BUFFER_9ZXL0451E_S3_VZX3P3A")
		)
		(pad "2" smd circle
			(at -0.40005 0 270)
			(size 0 0)
			(layers "B.Cu" "B.Mask" "B.Paste")
			(net "GND")
		)
	)
	(footprint ""
		(layer "B.Cu")
		(at 131.51485 -171.43857 90)
		(property "Reference" "R1468"
			(at 0 0 90)
			(layer "B.SilkS")
			(hide yes)
			(effects
				(font
					(size 1.27 1.27)
				)
				(justify mirror)
			)
		)
		(property "Value" ""
			(at 0 0 90)
			(layer "B.Fab")
			(effects
				(font
					(size 1.27 1.27)
				)
				(justify mirror)
			)
		)
		(duplicate_pad_numbers_are_jumpers no)
		(fp_line
			(start 0.7874 -0.4064)
			(end -0.7874 -0.4064)
			(stroke
				(width 0.1524)
				(type default)
			)
			(layer "B.SilkS")
		)
		(fp_line
			(start -0.7874 -0.4064)
			(end -0.7874 0.4064)
			(stroke
				(width 0.1524)
				(type default)
			)
			(layer "B.SilkS")
		)
		(fp_line
			(start 0.7874 0.4064)
			(end 0.7874 -0.4064)
			(stroke
				(width 0.1524)
				(type default)
			)
			(layer "B.SilkS")
		)
		(fp_line
			(start -0.7874 0.4064)
			(end 0.7874 0.4064)
			(stroke
				(width 0.1524)
				(type default)
			)
			(layer "B.SilkS")
		)
		(fp_line
			(start 0.67945 -0.305054)
			(end 0.12065 -0.305054)
			(stroke
				(width 0.1)
				(type default)
			)
			(layer "B.Fab")
		)
		(fp_line
			(start 0.12065 -0.305054)
			(end 0.12065 -0.2794)
			(stroke
				(width 0.1)
				(type default)
			)
			(layer "B.Fab")
		)
		(fp_line
			(start -0.12065 -0.3048)
			(end -0.67945 -0.3048)
			(stroke
				(width 0.1)
				(type default)
			)
			(layer "B.Fab")
		)
		(fp_line
			(start -0.67945 -0.3048)
			(end -0.67945 0.3048)
			(stroke
				(width 0.1)
				(type default)
			)
			(layer "B.Fab")
		)
		(fp_line
			(start 0.12065 -0.2794)
			(end -0.12065 -0.2794)
			(stroke
				(width 0.1)
				(type default)
			)
			(layer "B.Fab")
		)
		(fp_line
			(start -0.12065 -0.2794)
			(end -0.12065 -0.3048)
			(stroke
				(width 0.1)
				(type default)
			)
			(layer "B.Fab")
		)
		(fp_line
			(start 0.12065 0.2794)
			(end 0.12065 0.3048)
			(stroke
				(width 0.1)
				(type default)
			)
			(layer "B.Fab")
		)
		(fp_line
			(start -0.120396 0.2794)
			(end 0.12065 0.2794)
			(stroke
				(width 0.1)
				(type default)
			)
			(layer "B.Fab")
		)
		(fp_line
			(start 0.67945 0.3048)
			(end 0.67945 -0.305054)
			(stroke
				(width 0.1)
				(type default)
			)
			(layer "B.Fab")
		)
		(fp_line
			(start 0.12065 0.3048)
			(end 0.67945 0.3048)
			(stroke
				(width 0.1)
				(type default)
			)
			(layer "B.Fab")
		)
		(fp_line
			(start -0.120396 0.3048)
			(end -0.120396 0.2794)
			(stroke
				(width 0.1)
				(type default)
			)
			(layer "B.Fab")
		)
		(fp_line
			(start -0.67945 0.3048)
			(end -0.120396 0.3048)
			(stroke
				(width 0.1)
				(type default)
			)
			(layer "B.Fab")
		)
		(pad "1" smd circle
			(at 0.40005 0 270)
			(size 0 0)
			(layers "B.Cu" "B.Mask" "B.Paste")
			(net "SMB_BMC_9QXL2001_SCL")
		)
		(pad "2" smd circle
			(at -0.40005 0 270)
			(size 0 0)
			(layers "B.Cu" "B.Mask" "B.Paste")
			(net "SMB_CLK_ISO_R_SCL")
		)
	)
	(footprint ""
		(layer "B.Cu")
		(at 227.317046 -141.443202 90)
		(property "Reference" "C2805"
			(at 0 0 90)
			(layer "B.SilkS")
			(hide yes)
			(effects
				(font
					(size 1.27 1.27)
				)
				(justify mirror)
			)
		)
		(property "Value" ""
			(at 0 0 90)
			(layer "B.Fab")
			(effects
				(font
					(size 1.27 1.27)
				)
				(justify mirror)
			)
		)
		(duplicate_pad_numbers_are_jumpers no)
		(fp_line
			(start 1.2954 -0.5842)
			(end -1.2954 -0.5842)
			(stroke
				(width 0.1524)
				(type default)
			)
			(layer "B.SilkS")
		)
		(fp_line
			(start -1.2954 -0.5842)
			(end -1.2954 0.5842)
			(stroke
				(width 0.1524)
				(type default)
			)
			(layer "B.SilkS")
		)
		(fp_line
			(start 1.2954 0.5842)
			(end 1.2954 -0.5842)
			(stroke
				(width 0.1524)
				(type default)
			)
			(layer "B.SilkS")
		)
		(fp_line
			(start -1.2954 0.5842)
			(end 1.2954 0.5842)
			(stroke
				(width 0.1524)
				(type default)
			)
			(layer "B.SilkS")
		)
		(fp_line
			(start 0.8636 -0.4572)
			(end -0.8636 -0.4572)
			(stroke
				(width 0.1)
				(type default)
			)
			(layer "B.Fab")
		)
		(fp_line
			(start -0.8636 -0.4572)
			(end -0.8636 -0.4064)
			(stroke
				(width 0.1)
				(type default)
			)
			(layer "B.Fab")
		)
		(fp_line
			(start 1.1938 -0.4064)
			(end 0.8636 -0.4064)
			(stroke
				(width 0.1)
				(type default)
			)
			(layer "B.Fab")
		)
		(fp_line
			(start 0.8636 -0.4064)
			(end 0.8636 -0.4572)
			(stroke
				(width 0.1)
				(type default)
			)
			(layer "B.Fab")
		)
		(fp_line
			(start -0.8636 -0.4064)
			(end -1.1938 -0.4064)
			(stroke
				(width 0.1)
				(type default)
			)
			(layer "B.Fab")
		)
		(fp_line
			(start -1.1938 -0.4064)
			(end -1.1938 0.4064)
			(stroke
				(width 0.1)
				(type default)
			)
			(layer "B.Fab")
		)
		(fp_line
			(start 1.1938 0.4064)
			(end 1.1938 -0.4064)
			(stroke
				(width 0.1)
				(type default)
			)
			(layer "B.Fab")
		)
		(fp_line
			(start 0.8636 0.4064)
			(end 1.1938 0.4064)
			(stroke
				(width 0.1)
				(type default)
			)
			(layer "B.Fab")
		)
		(fp_line
			(start -0.8636 0.4064)
			(end -0.8636 0.4572)
			(stroke
				(width 0.1)
				(type default)
			)
			(layer "B.Fab")
		)
		(fp_line
			(start -1.1938 0.4064)
			(end -0.8636 0.4064)
			(stroke
				(width 0.1)
				(type default)
			)
			(layer "B.Fab")
		)
		(fp_line
			(start 0.8636 0.4572)
			(end 0.8636 0.4064)
			(stroke
				(width 0.1)
				(type default)
			)
			(layer "B.Fab")
		)
		(fp_line
			(start -0.8636 0.4572)
			(end 0.8636 0.4572)
			(stroke
				(width 0.1)
				(type default)
			)
			(layer "B.Fab")
		)
		(pad "1" smd rect
			(at 0.7366 0)
			(size 0.7112 0.8128)
			(layers "B.Cu" "B.Mask" "B.Paste")
			(net "P3V3_CLK_GEN_VDDPT_CK440_PEX")
		)
		(pad "2" smd rect
			(at -0.7366 0)
			(size 0.7112 0.8128)
			(layers "B.Cu" "B.Mask" "B.Paste")
			(net "GND")
		)
	)
	(footprint ""
		(layer "B.Cu")
		(at 304.728626 -249.628406)
		(property "Reference" "C2780"
			(at 0 0 0)
			(layer "B.SilkS")
			(hide yes)
			(effects
				(font
					(size 1.27 1.27)
				)
				(justify mirror)
			)
		)
		(property "Value" ""
			(at 0 0 0)
			(layer "B.Fab")
			(effects
				(font
					(size 1.27 1.27)
				)
				(justify mirror)
			)
		)
		(duplicate_pad_numbers_are_jumpers no)
		(fp_line
			(start -0.7874 -0.4064)
			(end -0.7874 0.4064)
			(stroke
				(width 0.1524)
				(type default)
			)
			(layer "B.SilkS")
		)
		(fp_line
			(start -0.7874 0.4064)
			(end 0.7874 0.4064)
			(stroke
				(width 0.1524)
				(type default)
			)
			(layer "B.SilkS")
		)
		(fp_line
			(start 0.7874 -0.4064)
			(end -0.7874 -0.4064)
			(stroke
				(width 0.1524)
				(type default)
			)
			(layer "B.SilkS")
		)
		(fp_line
			(start 0.7874 0.4064)
			(end 0.7874 -0.4064)
			(stroke
				(width 0.1524)
				(type default)
			)
			(layer "B.SilkS")
		)
		(fp_line
			(start -0.67945 -0.3048)
			(end -0.67945 0.3048)
			(stroke
				(width 0.1)
				(type default)
			)
			(layer "B.Fab")
		)
		(fp_line
			(start -0.67945 0.3048)
			(end -0.120396 0.3048)
			(stroke
				(width 0.1)
				(type default)
			)
			(layer "B.Fab")
		)
		(fp_line
			(start -0.12065 -0.3048)
			(end -0.67945 -0.3048)
			(stroke
				(width 0.1)
				(type default)
			)
			(layer "B.Fab")
		)
		(fp_line
			(start -0.12065 -0.2794)
			(end -0.12065 -0.3048)
			(stroke
				(width 0.1)
				(type default)
			)
			(layer "B.Fab")
		)
		(fp_line
			(start -0.120396 0.2794)
			(end 0.12065 0.2794)
			(stroke
				(width 0.1)
				(type default)
			)
			(layer "B.Fab")
		)
		(fp_line
			(start -0.120396 0.3048)
			(end -0.120396 0.2794)
			(stroke
				(width 0.1)
				(type default)
			)
			(layer "B.Fab")
		)
		(fp_line
			(start 0.12065 -0.305054)
			(end 0.12065 -0.2794)
			(stroke
				(width 0.1)
				(type default)
			)
			(layer "B.Fab")
		)
		(fp_line
			(start 0.12065 -0.2794)
			(end -0.12065 -0.2794)
			(stroke
				(width 0.1)
				(type default)
			)
			(layer "B.Fab")
		)
		(fp_line
			(start 0.12065 0.2794)
			(end 0.12065 0.3048)
			(stroke
				(width 0.1)
				(type default)
			)
			(layer "B.Fab")
		)
		(fp_line
			(start 0.12065 0.3048)
			(end 0.67945 0.3048)
			(stroke
				(width 0.1)
				(type default)
			)
			(layer "B.Fab")
		)
		(fp_line
			(start 0.67945 -0.305054)
			(end 0.12065 -0.305054)
			(stroke
				(width 0.1)
				(type default)
			)
			(layer "B.Fab")
		)
		(fp_line
			(start 0.67945 0.3048)
			(end 0.67945 -0.305054)
			(stroke
				(width 0.1)
				(type default)
			)
			(layer "B.Fab")
		)
		(pad "1" smd circle
			(at 0.40005 0 180)
			(size 0 0)
			(layers "B.Cu" "B.Mask" "B.Paste")
			(net "GND")
		)
		(pad "2" smd circle
			(at -0.40005 0 180)
			(size 0 0)
			(layers "B.Cu" "B.Mask" "B.Paste")
			(net "P3V3_AUX")
		)
	)
	(footprint ""
		(layer "B.Cu")
		(at 291.84981 -303.499774 -90)
		(property "Reference" "C3251"
			(at 0 0 90)
			(layer "B.SilkS")
			(hide yes)
			(effects
				(font
					(size 1.27 1.27)
				)
				(justify mirror)
			)
		)
		(property "Value" ""
			(at 0 0 90)
			(layer "B.Fab")
			(effects
				(font
					(size 1.27 1.27)
				)
				(justify mirror)
			)
		)
		(duplicate_pad_numbers_are_jumpers no)
		(fp_line
			(start -0.299974 0.150114)
			(end 0.299974 0.150114)
			(stroke
				(width 0.1)
				(type default)
			)
			(layer "B.Fab")
		)
		(fp_line
			(start 0.299974 0.150114)
			(end 0.299974 -0.150114)
			(stroke
				(width 0.1)
				(type default)
			)
			(layer "B.Fab")
		)
		(fp_line
			(start -0.299974 -0.150114)
			(end -0.299974 0.150114)
			(stroke
				(width 0.1)
				(type default)
			)
			(layer "B.Fab")
		)
		(fp_line
			(start 0.299974 -0.150114)
			(end -0.299974 -0.150114)
			(stroke
				(width 0.1)
				(type default)
			)
			(layer "B.Fab")
		)
		(pad "1" smd rect
			(at 0.2667 0 90)
			(size 0.3048 0.381)
			(layers "B.Cu" "B.Mask" "B.Paste")
			(net "P1V25_PEX2")
		)
		(pad "2" smd rect
			(at -0.2667 0 90)
			(size 0.3048 0.381)
			(layers "B.Cu" "B.Mask" "B.Paste")
			(net "GND")
		)
	)
	(footprint ""
		(layer "B.Cu")
		(at 284.249876 -299.699934 -90)
		(property "Reference" "C1691"
			(at 0 0 90)
			(layer "B.SilkS")
			(hide yes)
			(effects
				(font
					(size 1.27 1.27)
				)
				(justify mirror)
			)
		)
		(property "Value" ""
			(at 0 0 90)
			(layer "B.Fab")
			(effects
				(font
					(size 1.27 1.27)
				)
				(justify mirror)
			)
		)
		(duplicate_pad_numbers_are_jumpers no)
		(fp_line
			(start -0.299974 0.150114)
			(end 0.299974 0.150114)
			(stroke
				(width 0.1)
				(type default)
			)
			(layer "B.Fab")
		)
		(fp_line
			(start 0.299974 0.150114)
			(end 0.299974 -0.150114)
			(stroke
				(width 0.1)
				(type default)
			)
			(layer "B.Fab")
		)
		(fp_line
			(start -0.299974 -0.150114)
			(end -0.299974 0.150114)
			(stroke
				(width 0.1)
				(type default)
			)
			(layer "B.Fab")
		)
		(fp_line
			(start 0.299974 -0.150114)
			(end -0.299974 -0.150114)
			(stroke
				(width 0.1)
				(type default)
			)
			(layer "B.Fab")
		)
		(pad "1" smd rect
			(at 0.2667 0 90)
			(size 0.3048 0.381)
			(layers "B.Cu" "B.Mask" "B.Paste")
			(net "P0V8_SERDES_VDDA_PEX2")
		)
		(pad "2" smd rect
			(at -0.2667 0 90)
			(size 0.3048 0.381)
			(layers "B.Cu" "B.Mask" "B.Paste")
			(net "GND")
		)
	)
	(footprint ""
		(layer "B.Cu")
		(at 126.634748 -293.506906 90)
		(property "Reference" "PC103"
			(at 0 0 90)
			(layer "B.SilkS")
			(hide yes)
			(effects
				(font
					(size 1.27 1.27)
				)
				(justify mirror)
			)
		)
		(property "Value" ""
			(at 0 0 90)
			(layer "B.Fab")
			(effects
				(font
					(size 1.27 1.27)
				)
				(justify mirror)
			)
		)
		(duplicate_pad_numbers_are_jumpers no)
		(fp_line
			(start 1.524 -0.762)
			(end -1.524 -0.762)
			(stroke
				(width 0.1524)
				(type default)
			)
			(layer "B.SilkS")
		)
		(fp_line
			(start -1.524 -0.762)
			(end -1.524 0.762)
			(stroke
				(width 0.1524)
				(type default)
			)
			(layer "B.SilkS")
		)
		(fp_line
			(start 1.524 0.762)
			(end 1.524 -0.762)
			(stroke
				(width 0.1524)
				(type default)
			)
			(layer "B.SilkS")
		)
		(fp_line
			(start -1.524 0.762)
			(end 1.524 0.762)
			(stroke
				(width 0.1524)
				(type default)
			)
			(layer "B.SilkS")
		)
		(fp_line
			(start 1.1049 -0.724916)
			(end 1.1049 0.724916)
			(stroke
				(width 0.1)
				(type default)
			)
			(layer "B.Fab")
		)
		(fp_line
			(start -1.1049 -0.724916)
			(end 1.1049 -0.724916)
			(stroke
				(width 0.1)
				(type default)
			)
			(layer "B.Fab")
		)
		(fp_line
			(start 1.1049 0.724916)
			(end -1.1049 0.724916)
			(stroke
				(width 0.1)
				(type default)
			)
			(layer "B.Fab")
		)
		(fp_line
			(start -1.1049 0.724916)
			(end -1.1049 -0.724916)
			(stroke
				(width 0.1)
				(type default)
			)
			(layer "B.Fab")
		)
		(pad "1" smd rect
			(at 0.889 0 90)
			(size 1.016 1.27)
			(layers "B.Cu" "B.Mask" "B.Paste")
			(net "P0V8_PEX1")
		)
		(pad "2" smd rect
			(at -0.889 0 90)
			(size 1.016 1.27)
			(layers "B.Cu" "B.Mask" "B.Paste")
			(net "GND")
		)
	)
	(footprint ""
		(layer "B.Cu")
		(at 395.03604 -291.624766)
		(property "Reference" "C3581"
			(at 0 0 0)
			(layer "B.SilkS")
			(hide yes)
			(effects
				(font
					(size 1.27 1.27)
				)
				(justify mirror)
			)
		)
		(property "Value" ""
			(at 0 0 0)
			(layer "B.Fab")
			(effects
				(font
					(size 1.27 1.27)
				)
				(justify mirror)
			)
		)
		(duplicate_pad_numbers_are_jumpers no)
		(fp_line
			(start -0.299974 -0.150114)
			(end -0.299974 0.150114)
			(stroke
				(width 0.1)
				(type default)
			)
			(layer "B.Fab")
		)
		(fp_line
			(start -0.299974 0.150114)
			(end 0.299974 0.150114)
			(stroke
				(width 0.1)
				(type default)
			)
			(layer "B.Fab")
		)
		(fp_line
			(start 0.299974 -0.150114)
			(end -0.299974 -0.150114)
			(stroke
				(width 0.1)
				(type default)
			)
			(layer "B.Fab")
		)
		(fp_line
			(start 0.299974 0.150114)
			(end 0.299974 -0.150114)
			(stroke
				(width 0.1)
				(type default)
			)
			(layer "B.Fab")
		)
		(pad "1" smd rect
			(at 0.2667 0 180)
			(size 0.3048 0.381)
			(layers "B.Cu" "B.Mask" "B.Paste")
			(net "PCEPLL7_VDDA18_PEX3")
		)
		(pad "2" smd rect
			(at -0.2667 0 180)
			(size 0.3048 0.381)
			(layers "B.Cu" "B.Mask" "B.Paste")
			(net "GND")
		)
	)
	(footprint ""
		(layer "B.Cu")
		(at 415.549842 -303.499774 -90)
		(property "Reference" "C3455"
			(at 0 0 90)
			(layer "B.SilkS")
			(hide yes)
			(effects
				(font
					(size 1.27 1.27)
				)
				(justify mirror)
			)
		)
		(property "Value" ""
			(at 0 0 90)
			(layer "B.Fab")
			(effects
				(font
					(size 1.27 1.27)
				)
				(justify mirror)
			)
		)
		(duplicate_pad_numbers_are_jumpers no)
		(fp_line
			(start -0.299974 0.150114)
			(end 0.299974 0.150114)
			(stroke
				(width 0.1)
				(type default)
			)
			(layer "B.Fab")
		)
		(fp_line
			(start 0.299974 0.150114)
			(end 0.299974 -0.150114)
			(stroke
				(width 0.1)
				(type default)
			)
			(layer "B.Fab")
		)
		(fp_line
			(start -0.299974 -0.150114)
			(end -0.299974 0.150114)
			(stroke
				(width 0.1)
				(type default)
			)
			(layer "B.Fab")
		)
		(fp_line
			(start 0.299974 -0.150114)
			(end -0.299974 -0.150114)
			(stroke
				(width 0.1)
				(type default)
			)
			(layer "B.Fab")
		)
		(pad "1" smd rect
			(at 0.2667 0 90)
			(size 0.3048 0.381)
			(layers "B.Cu" "B.Mask" "B.Paste")
			(net "P1V25_PEX3")
		)
		(pad "2" smd rect
			(at -0.2667 0 90)
			(size 0.3048 0.381)
			(layers "B.Cu" "B.Mask" "B.Paste")
			(net "GND")
		)
	)
	(footprint ""
		(layer "B.Cu")
		(at 212.09 -203.327 90)
		(property "Reference" "R1521"
			(at 0 0 90)
			(layer "B.SilkS")
			(hide yes)
			(effects
				(font
					(size 1.27 1.27)
				)
				(justify mirror)
			)
		)
		(property "Value" ""
			(at 0 0 90)
			(layer "B.Fab")
			(effects
				(font
					(size 1.27 1.27)
				)
				(justify mirror)
			)
		)
		(duplicate_pad_numbers_are_jumpers no)
		(fp_line
			(start 0.7874 -0.4064)
			(end -0.7874 -0.4064)
			(stroke
				(width 0.1524)
				(type default)
			)
			(layer "B.SilkS")
		)
		(fp_line
			(start -0.7874 -0.4064)
			(end -0.7874 0.4064)
			(stroke
				(width 0.1524)
				(type default)
			)
			(layer "B.SilkS")
		)
		(fp_line
			(start 0.7874 0.4064)
			(end 0.7874 -0.4064)
			(stroke
				(width 0.1524)
				(type default)
			)
			(layer "B.SilkS")
		)
		(fp_line
			(start -0.7874 0.4064)
			(end 0.7874 0.4064)
			(stroke
				(width 0.1524)
				(type default)
			)
			(layer "B.SilkS")
		)
		(fp_line
			(start 0.67945 -0.305054)
			(end 0.12065 -0.305054)
			(stroke
				(width 0.1)
				(type default)
			)
			(layer "B.Fab")
		)
		(fp_line
			(start 0.12065 -0.305054)
			(end 0.12065 -0.2794)
			(stroke
				(width 0.1)
				(type default)
			)
			(layer "B.Fab")
		)
		(fp_line
			(start -0.12065 -0.3048)
			(end -0.67945 -0.3048)
			(stroke
				(width 0.1)
				(type default)
			)
			(layer "B.Fab")
		)
		(fp_line
			(start -0.67945 -0.3048)
			(end -0.67945 0.3048)
			(stroke
				(width 0.1)
				(type default)
			)
			(layer "B.Fab")
		)
		(fp_line
			(start 0.12065 -0.2794)
			(end -0.12065 -0.2794)
			(stroke
				(width 0.1)
				(type default)
			)
			(layer "B.Fab")
		)
		(fp_line
			(start -0.12065 -0.2794)
			(end -0.12065 -0.3048)
			(stroke
				(width 0.1)
				(type default)
			)
			(layer "B.Fab")
		)
		(fp_line
			(start 0.12065 0.2794)
			(end 0.12065 0.3048)
			(stroke
				(width 0.1)
				(type default)
			)
			(layer "B.Fab")
		)
		(fp_line
			(start -0.120396 0.2794)
			(end 0.12065 0.2794)
			(stroke
				(width 0.1)
				(type default)
			)
			(layer "B.Fab")
		)
		(fp_line
			(start 0.67945 0.3048)
			(end 0.67945 -0.305054)
			(stroke
				(width 0.1)
				(type default)
			)
			(layer "B.Fab")
		)
		(fp_line
			(start 0.12065 0.3048)
			(end 0.67945 0.3048)
			(stroke
				(width 0.1)
				(type default)
			)
			(layer "B.Fab")
		)
		(fp_line
			(start -0.120396 0.3048)
			(end -0.120396 0.2794)
			(stroke
				(width 0.1)
				(type default)
			)
			(layer "B.Fab")
		)
		(fp_line
			(start -0.67945 0.3048)
			(end -0.120396 0.3048)
			(stroke
				(width 0.1)
				(type default)
			)
			(layer "B.Fab")
		)
		(pad "1" smd circle
			(at 0.40005 0 270)
			(size 0 0)
			(layers "B.Cu" "B.Mask" "B.Paste")
			(net "SMB_NIC5_LS_R_SDA")
		)
		(pad "2" smd circle
			(at -0.40005 0 270)
			(size 0 0)
			(layers "B.Cu" "B.Mask" "B.Paste")
			(net "SMB_NIC5_R_SDA")
		)
	)
	(footprint ""
		(layer "B.Cu")
		(at 49.5554 -153.0096)
		(property "Reference" "R19"
			(at 0 0 0)
			(layer "B.SilkS")
			(hide yes)
			(effects
				(font
					(size 1.27 1.27)
				)
				(justify mirror)
			)
		)
		(property "Value" ""
			(at 0 0 0)
			(layer "B.Fab")
			(effects
				(font
					(size 1.27 1.27)
				)
				(justify mirror)
			)
		)
		(duplicate_pad_numbers_are_jumpers no)
		(fp_line
			(start -0.7874 -0.4064)
			(end -0.7874 0.4064)
			(stroke
				(width 0.1524)
				(type default)
			)
			(layer "B.SilkS")
		)
		(fp_line
			(start -0.7874 0.4064)
			(end 0.7874 0.4064)
			(stroke
				(width 0.1524)
				(type default)
			)
			(layer "B.SilkS")
		)
		(fp_line
			(start 0.7874 -0.4064)
			(end -0.7874 -0.4064)
			(stroke
				(width 0.1524)
				(type default)
			)
			(layer "B.SilkS")
		)
		(fp_line
			(start 0.7874 0.4064)
			(end 0.7874 -0.4064)
			(stroke
				(width 0.1524)
				(type default)
			)
			(layer "B.SilkS")
		)
		(fp_line
			(start -0.67945 -0.3048)
			(end -0.67945 0.3048)
			(stroke
				(width 0.1)
				(type default)
			)
			(layer "B.Fab")
		)
		(fp_line
			(start -0.67945 0.3048)
			(end -0.120396 0.3048)
			(stroke
				(width 0.1)
				(type default)
			)
			(layer "B.Fab")
		)
		(fp_line
			(start -0.12065 -0.3048)
			(end -0.67945 -0.3048)
			(stroke
				(width 0.1)
				(type default)
			)
			(layer "B.Fab")
		)
		(fp_line
			(start -0.12065 -0.2794)
			(end -0.12065 -0.3048)
			(stroke
				(width 0.1)
				(type default)
			)
			(layer "B.Fab")
		)
		(fp_line
			(start -0.120396 0.2794)
			(end 0.12065 0.2794)
			(stroke
				(width 0.1)
				(type default)
			)
			(layer "B.Fab")
		)
		(fp_line
			(start -0.120396 0.3048)
			(end -0.120396 0.2794)
			(stroke
				(width 0.1)
				(type default)
			)
			(layer "B.Fab")
		)
		(fp_line
			(start 0.12065 -0.305054)
			(end 0.12065 -0.2794)
			(stroke
				(width 0.1)
				(type default)
			)
			(layer "B.Fab")
		)
		(fp_line
			(start 0.12065 -0.2794)
			(end -0.12065 -0.2794)
			(stroke
				(width 0.1)
				(type default)
			)
			(layer "B.Fab")
		)
		(fp_line
			(start 0.12065 0.2794)
			(end 0.12065 0.3048)
			(stroke
				(width 0.1)
				(type default)
			)
			(layer "B.Fab")
		)
		(fp_line
			(start 0.12065 0.3048)
			(end 0.67945 0.3048)
			(stroke
				(width 0.1)
				(type default)
			)
			(layer "B.Fab")
		)
		(fp_line
			(start 0.67945 -0.305054)
			(end 0.12065 -0.305054)
			(stroke
				(width 0.1)
				(type default)
			)
			(layer "B.Fab")
		)
		(fp_line
			(start 0.67945 0.3048)
			(end 0.67945 -0.305054)
			(stroke
				(width 0.1)
				(type default)
			)
			(layer "B.Fab")
		)
		(pad "1" smd circle
			(at 0.40005 0 180)
			(size 0 0)
			(layers "B.Cu" "B.Mask" "B.Paste")
			(net "NCSI_NIC0_TXD1")
		)
		(pad "2" smd circle
			(at -0.40005 0 180)
			(size 0 0)
			(layers "B.Cu" "B.Mask" "B.Paste")
			(net "GND")
		)
	)
	(footprint ""
		(layer "B.Cu")
		(at 414.124902 -297.79976 90)
		(property "Reference" "C1889"
			(at 0 0 90)
			(layer "B.SilkS")
			(hide yes)
			(effects
				(font
					(size 1.27 1.27)
				)
				(justify mirror)
			)
		)
		(property "Value" ""
			(at 0 0 90)
			(layer "B.Fab")
			(effects
				(font
					(size 1.27 1.27)
				)
				(justify mirror)
			)
		)
		(duplicate_pad_numbers_are_jumpers no)
		(fp_line
			(start 0.299974 -0.150114)
			(end -0.299974 -0.150114)
			(stroke
				(width 0.1)
				(type default)
			)
			(layer "B.Fab")
		)
		(fp_line
			(start -0.299974 -0.150114)
			(end -0.299974 0.150114)
			(stroke
				(width 0.1)
				(type default)
			)
			(layer "B.Fab")
		)
		(fp_line
			(start 0.299974 0.150114)
			(end 0.299974 -0.150114)
			(stroke
				(width 0.1)
				(type default)
			)
			(layer "B.Fab")
		)
		(fp_line
			(start -0.299974 0.150114)
			(end 0.299974 0.150114)
			(stroke
				(width 0.1)
				(type default)
			)
			(layer "B.Fab")
		)
		(pad "1" smd rect
			(at 0.2667 0 270)
			(size 0.3048 0.381)
			(layers "B.Cu" "B.Mask" "B.Paste")
			(net "P0V8_PEX3")
		)
		(pad "2" smd rect
			(at -0.2667 0 270)
			(size 0.3048 0.381)
			(layers "B.Cu" "B.Mask" "B.Paste")
			(net "GND")
		)
	)
	(footprint ""
		(layer "B.Cu")
		(at 380.762002 -222.590106 180)
		(property "Reference" "C2604"
			(at 0 0 0)
			(layer "B.SilkS")
			(hide yes)
			(effects
				(font
					(size 1.27 1.27)
				)
				(justify mirror)
			)
		)
		(property "Value" ""
			(at 0 0 0)
			(layer "B.Fab")
			(effects
				(font
					(size 1.27 1.27)
				)
				(justify mirror)
			)
		)
		(duplicate_pad_numbers_are_jumpers no)
		(fp_line
			(start 0.7874 0.4064)
			(end 0.7874 -0.4064)
			(stroke
				(width 0.1524)
				(type default)
			)
			(layer "B.SilkS")
		)
		(fp_line
			(start 0.7874 -0.4064)
			(end -0.7874 -0.4064)
			(stroke
				(width 0.1524)
				(type default)
			)
			(layer "B.SilkS")
		)
		(fp_line
			(start -0.7874 0.4064)
			(end 0.7874 0.4064)
			(stroke
				(width 0.1524)
				(type default)
			)
			(layer "B.SilkS")
		)
		(fp_line
			(start -0.7874 -0.4064)
			(end -0.7874 0.4064)
			(stroke
				(width 0.1524)
				(type default)
			)
			(layer "B.SilkS")
		)
		(fp_line
			(start 0.67945 0.3048)
			(end 0.67945 -0.305054)
			(stroke
				(width 0.1)
				(type default)
			)
			(layer "B.Fab")
		)
		(fp_line
			(start 0.67945 -0.305054)
			(end 0.12065 -0.305054)
			(stroke
				(width 0.1)
				(type default)
			)
			(layer "B.Fab")
		)
		(fp_line
			(start 0.12065 0.3048)
			(end 0.67945 0.3048)
			(stroke
				(width 0.1)
				(type default)
			)
			(layer "B.Fab")
		)
		(fp_line
			(start 0.12065 0.2794)
			(end 0.12065 0.3048)
			(stroke
				(width 0.1)
				(type default)
			)
			(layer "B.Fab")
		)
		(fp_line
			(start 0.12065 -0.2794)
			(end -0.12065 -0.2794)
			(stroke
				(width 0.1)
				(type default)
			)
			(layer "B.Fab")
		)
		(fp_line
			(start 0.12065 -0.305054)
			(end 0.12065 -0.2794)
			(stroke
				(width 0.1)
				(type default)
			)
			(layer "B.Fab")
		)
		(fp_line
			(start -0.120396 0.3048)
			(end -0.120396 0.2794)
			(stroke
				(width 0.1)
				(type default)
			)
			(layer "B.Fab")
		)
		(fp_line
			(start -0.120396 0.2794)
			(end 0.12065 0.2794)
			(stroke
				(width 0.1)
				(type default)
			)
			(layer "B.Fab")
		)
		(fp_line
			(start -0.12065 -0.2794)
			(end -0.12065 -0.3048)
			(stroke
				(width 0.1)
				(type default)
			)
			(layer "B.Fab")
		)
		(fp_line
			(start -0.12065 -0.3048)
			(end -0.67945 -0.3048)
			(stroke
				(width 0.1)
				(type default)
			)
			(layer "B.Fab")
		)
		(fp_line
			(start -0.67945 0.3048)
			(end -0.120396 0.3048)
			(stroke
				(width 0.1)
				(type default)
			)
			(layer "B.Fab")
		)
		(fp_line
			(start -0.67945 -0.3048)
			(end -0.67945 0.3048)
			(stroke
				(width 0.1)
				(type default)
			)
			(layer "B.Fab")
		)
		(pad "1" smd circle
			(at 0.40005 0)
			(size 0 0)
			(layers "B.Cu" "B.Mask" "B.Paste")
			(net "GND")
		)
		(pad "2" smd circle
			(at -0.40005 0)
			(size 0 0)
			(layers "B.Cu" "B.Mask" "B.Paste")
			(net "P3V3_AUX")
		)
	)
	(footprint ""
		(layer "B.Cu")
		(at 363.093 -227.965 180)
		(property "Reference" "R3507"
			(at 0 0 0)
			(layer "B.SilkS")
			(hide yes)
			(effects
				(font
					(size 1.27 1.27)
				)
				(justify mirror)
			)
		)
		(property "Value" ""
			(at 0 0 0)
			(layer "B.Fab")
			(effects
				(font
					(size 1.27 1.27)
				)
				(justify mirror)
			)
		)
		(duplicate_pad_numbers_are_jumpers no)
		(fp_line
			(start 0.7874 0.4064)
			(end 0.7874 -0.4064)
			(stroke
				(width 0.1524)
				(type default)
			)
			(layer "B.SilkS")
		)
		(fp_line
			(start 0.7874 -0.4064)
			(end -0.7874 -0.4064)
			(stroke
				(width 0.1524)
				(type default)
			)
			(layer "B.SilkS")
		)
		(fp_line
			(start -0.7874 0.4064)
			(end 0.7874 0.4064)
			(stroke
				(width 0.1524)
				(type default)
			)
			(layer "B.SilkS")
		)
		(fp_line
			(start -0.7874 -0.4064)
			(end -0.7874 0.4064)
			(stroke
				(width 0.1524)
				(type default)
			)
			(layer "B.SilkS")
		)
		(fp_line
			(start 0.67945 0.3048)
			(end 0.67945 -0.305054)
			(stroke
				(width 0.1)
				(type default)
			)
			(layer "B.Fab")
		)
		(fp_line
			(start 0.67945 -0.305054)
			(end 0.12065 -0.305054)
			(stroke
				(width 0.1)
				(type default)
			)
			(layer "B.Fab")
		)
		(fp_line
			(start 0.12065 0.3048)
			(end 0.67945 0.3048)
			(stroke
				(width 0.1)
				(type default)
			)
			(layer "B.Fab")
		)
		(fp_line
			(start 0.12065 0.2794)
			(end 0.12065 0.3048)
			(stroke
				(width 0.1)
				(type default)
			)
			(layer "B.Fab")
		)
		(fp_line
			(start 0.12065 -0.2794)
			(end -0.12065 -0.2794)
			(stroke
				(width 0.1)
				(type default)
			)
			(layer "B.Fab")
		)
		(fp_line
			(start 0.12065 -0.305054)
			(end 0.12065 -0.2794)
			(stroke
				(width 0.1)
				(type default)
			)
			(layer "B.Fab")
		)
		(fp_line
			(start -0.120396 0.3048)
			(end -0.120396 0.2794)
			(stroke
				(width 0.1)
				(type default)
			)
			(layer "B.Fab")
		)
		(fp_line
			(start -0.120396 0.2794)
			(end 0.12065 0.2794)
			(stroke
				(width 0.1)
				(type default)
			)
			(layer "B.Fab")
		)
		(fp_line
			(start -0.12065 -0.2794)
			(end -0.12065 -0.3048)
			(stroke
				(width 0.1)
				(type default)
			)
			(layer "B.Fab")
		)
		(fp_line
			(start -0.12065 -0.3048)
			(end -0.67945 -0.3048)
			(stroke
				(width 0.1)
				(type default)
			)
			(layer "B.Fab")
		)
		(fp_line
			(start -0.67945 0.3048)
			(end -0.120396 0.3048)
			(stroke
				(width 0.1)
				(type default)
			)
			(layer "B.Fab")
		)
		(fp_line
			(start -0.67945 -0.3048)
			(end -0.67945 0.3048)
			(stroke
				(width 0.1)
				(type default)
			)
			(layer "B.Fab")
		)
		(pad "1" smd circle
			(at 0.40005 0)
			(size 0 0)
			(layers "B.Cu" "B.Mask" "B.Paste")
			(net "SPI_PEX3_SDIO2_R1")
		)
		(pad "2" smd circle
			(at -0.40005 0)
			(size 0 0)
			(layers "B.Cu" "B.Mask" "B.Paste")
			(net "GND")
		)
	)
	(footprint ""
		(layer "B.Cu")
		(at 421.249856 -294.94988 180)
		(property "Reference" "C3470"
			(at 0 0 0)
			(layer "B.SilkS")
			(hide yes)
			(effects
				(font
					(size 1.27 1.27)
				)
				(justify mirror)
			)
		)
		(property "Value" ""
			(at 0 0 0)
			(layer "B.Fab")
			(effects
				(font
					(size 1.27 1.27)
				)
				(justify mirror)
			)
		)
		(duplicate_pad_numbers_are_jumpers no)
		(fp_line
			(start 0.299974 0.150114)
			(end 0.299974 -0.150114)
			(stroke
				(width 0.1)
				(type default)
			)
			(layer "B.Fab")
		)
		(fp_line
			(start 0.299974 -0.150114)
			(end -0.299974 -0.150114)
			(stroke
				(width 0.1)
				(type default)
			)
			(layer "B.Fab")
		)
		(fp_line
			(start -0.299974 0.150114)
			(end 0.299974 0.150114)
			(stroke
				(width 0.1)
				(type default)
			)
			(layer "B.Fab")
		)
		(fp_line
			(start -0.299974 -0.150114)
			(end -0.299974 0.150114)
			(stroke
				(width 0.1)
				(type default)
			)
			(layer "B.Fab")
		)
		(pad "1" smd rect
			(at 0.2667 0)
			(size 0.3048 0.381)
			(layers "B.Cu" "B.Mask" "B.Paste")
			(net "P1V25_SERDES_VDDPLL_PEX3")
		)
		(pad "2" smd rect
			(at -0.2667 0)
			(size 0.3048 0.381)
			(layers "B.Cu" "B.Mask" "B.Paste")
			(net "GND")
		)
	)
	(footprint ""
		(layer "B.Cu")
		(at 394.65504 -293.52494)
		(property "Reference" "C3579"
			(at 0 0 0)
			(layer "B.SilkS")
			(hide yes)
			(effects
				(font
					(size 1.27 1.27)
				)
				(justify mirror)
			)
		)
		(property "Value" ""
			(at 0 0 0)
			(layer "B.Fab")
			(effects
				(font
					(size 1.27 1.27)
				)
				(justify mirror)
			)
		)
		(duplicate_pad_numbers_are_jumpers no)
		(fp_line
			(start -0.299974 -0.150114)
			(end -0.299974 0.150114)
			(stroke
				(width 0.1)
				(type default)
			)
			(layer "B.Fab")
		)
		(fp_line
			(start -0.299974 0.150114)
			(end 0.299974 0.150114)
			(stroke
				(width 0.1)
				(type default)
			)
			(layer "B.Fab")
		)
		(fp_line
			(start 0.299974 -0.150114)
			(end -0.299974 -0.150114)
			(stroke
				(width 0.1)
				(type default)
			)
			(layer "B.Fab")
		)
		(fp_line
			(start 0.299974 0.150114)
			(end 0.299974 -0.150114)
			(stroke
				(width 0.1)
				(type default)
			)
			(layer "B.Fab")
		)
		(pad "1" smd rect
			(at 0.2667 0 180)
			(size 0.3048 0.381)
			(layers "B.Cu" "B.Mask" "B.Paste")
			(net "PCEPLL6_VDDA18_PEX3")
		)
		(pad "2" smd rect
			(at -0.2667 0 180)
			(size 0.3048 0.381)
			(layers "B.Cu" "B.Mask" "B.Paste")
			(net "GND")
		)
	)
	(footprint ""
		(layer "B.Cu")
		(at 406.540208 -297.79976 -90)
		(property "Reference" "C1898"
			(at 0 0 90)
			(layer "B.SilkS")
			(hide yes)
			(effects
				(font
					(size 1.27 1.27)
				)
				(justify mirror)
			)
		)
		(property "Value" ""
			(at 0 0 90)
			(layer "B.Fab")
			(effects
				(font
					(size 1.27 1.27)
				)
				(justify mirror)
			)
		)
		(duplicate_pad_numbers_are_jumpers no)
		(fp_line
			(start -0.299974 0.150114)
			(end 0.299974 0.150114)
			(stroke
				(width 0.1)
				(type default)
			)
			(layer "B.Fab")
		)
		(fp_line
			(start 0.299974 0.150114)
			(end 0.299974 -0.150114)
			(stroke
				(width 0.1)
				(type default)
			)
			(layer "B.Fab")
		)
		(fp_line
			(start -0.299974 -0.150114)
			(end -0.299974 0.150114)
			(stroke
				(width 0.1)
				(type default)
			)
			(layer "B.Fab")
		)
		(fp_line
			(start 0.299974 -0.150114)
			(end -0.299974 -0.150114)
			(stroke
				(width 0.1)
				(type default)
			)
			(layer "B.Fab")
		)
		(pad "1" smd rect
			(at 0.2667 0 90)
			(size 0.3048 0.381)
			(layers "B.Cu" "B.Mask" "B.Paste")
			(net "P0V8_PEX3")
		)
		(pad "2" smd rect
			(at -0.2667 0 90)
			(size 0.3048 0.381)
			(layers "B.Cu" "B.Mask" "B.Paste")
			(net "GND")
		)
	)
	(footprint ""
		(layer "B.Cu")
		(at 233.380026 -94.074234 90)
		(property "Reference" "C2614"
			(at 0 0 90)
			(layer "B.SilkS")
			(hide yes)
			(effects
				(font
					(size 1.27 1.27)
				)
				(justify mirror)
			)
		)
		(property "Value" ""
			(at 0 0 90)
			(layer "B.Fab")
			(effects
				(font
					(size 1.27 1.27)
				)
				(justify mirror)
			)
		)
		(duplicate_pad_numbers_are_jumpers no)
		(fp_line
			(start 0.7874 -0.4064)
			(end -0.7874 -0.4064)
			(stroke
				(width 0.1524)
				(type default)
			)
			(layer "B.SilkS")
		)
		(fp_line
			(start -0.7874 -0.4064)
			(end -0.7874 0.4064)
			(stroke
				(width 0.1524)
				(type default)
			)
			(layer "B.SilkS")
		)
		(fp_line
			(start 0.7874 0.4064)
			(end 0.7874 -0.4064)
			(stroke
				(width 0.1524)
				(type default)
			)
			(layer "B.SilkS")
		)
		(fp_line
			(start -0.7874 0.4064)
			(end 0.7874 0.4064)
			(stroke
				(width 0.1524)
				(type default)
			)
			(layer "B.SilkS")
		)
		(fp_line
			(start 0.67945 -0.305054)
			(end 0.12065 -0.305054)
			(stroke
				(width 0.1)
				(type default)
			)
			(layer "B.Fab")
		)
		(fp_line
			(start 0.12065 -0.305054)
			(end 0.12065 -0.2794)
			(stroke
				(width 0.1)
				(type default)
			)
			(layer "B.Fab")
		)
		(fp_line
			(start -0.12065 -0.3048)
			(end -0.67945 -0.3048)
			(stroke
				(width 0.1)
				(type default)
			)
			(layer "B.Fab")
		)
		(fp_line
			(start -0.67945 -0.3048)
			(end -0.67945 0.3048)
			(stroke
				(width 0.1)
				(type default)
			)
			(layer "B.Fab")
		)
		(fp_line
			(start 0.12065 -0.2794)
			(end -0.12065 -0.2794)
			(stroke
				(width 0.1)
				(type default)
			)
			(layer "B.Fab")
		)
		(fp_line
			(start -0.12065 -0.2794)
			(end -0.12065 -0.3048)
			(stroke
				(width 0.1)
				(type default)
			)
			(layer "B.Fab")
		)
		(fp_line
			(start 0.12065 0.2794)
			(end 0.12065 0.3048)
			(stroke
				(width 0.1)
				(type default)
			)
			(layer "B.Fab")
		)
		(fp_line
			(start -0.120396 0.2794)
			(end 0.12065 0.2794)
			(stroke
				(width 0.1)
				(type default)
			)
			(layer "B.Fab")
		)
		(fp_line
			(start 0.67945 0.3048)
			(end 0.67945 -0.305054)
			(stroke
				(width 0.1)
				(type default)
			)
			(layer "B.Fab")
		)
		(fp_line
			(start 0.12065 0.3048)
			(end 0.67945 0.3048)
			(stroke
				(width 0.1)
				(type default)
			)
			(layer "B.Fab")
		)
		(fp_line
			(start -0.120396 0.3048)
			(end -0.120396 0.2794)
			(stroke
				(width 0.1)
				(type default)
			)
			(layer "B.Fab")
		)
		(fp_line
			(start -0.67945 0.3048)
			(end -0.120396 0.3048)
			(stroke
				(width 0.1)
				(type default)
			)
			(layer "B.Fab")
		)
		(pad "1" smd circle
			(at 0.40005 0 270)
			(size 0 0)
			(layers "B.Cu" "B.Mask" "B.Paste")
			(net "P3V3_PEX_USB_HUB")
		)
		(pad "2" smd circle
			(at -0.40005 0 270)
			(size 0 0)
			(layers "B.Cu" "B.Mask" "B.Paste")
			(net "GND")
		)
	)
	(footprint ""
		(layer "B.Cu")
		(at 366.268 -235.458 180)
		(property "Reference" "R909"
			(at 0 0 0)
			(layer "B.SilkS")
			(hide yes)
			(effects
				(font
					(size 1.27 1.27)
				)
				(justify mirror)
			)
		)
		(property "Value" ""
			(at 0 0 0)
			(layer "B.Fab")
			(effects
				(font
					(size 1.27 1.27)
				)
				(justify mirror)
			)
		)
		(duplicate_pad_numbers_are_jumpers no)
		(fp_line
			(start 0.7874 0.4064)
			(end 0.7874 -0.4064)
			(stroke
				(width 0.1524)
				(type default)
			)
			(layer "B.SilkS")
		)
		(fp_line
			(start 0.7874 -0.4064)
			(end -0.7874 -0.4064)
			(stroke
				(width 0.1524)
				(type default)
			)
			(layer "B.SilkS")
		)
		(fp_line
			(start -0.7874 0.4064)
			(end 0.7874 0.4064)
			(stroke
				(width 0.1524)
				(type default)
			)
			(layer "B.SilkS")
		)
		(fp_line
			(start -0.7874 -0.4064)
			(end -0.7874 0.4064)
			(stroke
				(width 0.1524)
				(type default)
			)
			(layer "B.SilkS")
		)
		(fp_line
			(start 0.67945 0.3048)
			(end 0.67945 -0.305054)
			(stroke
				(width 0.1)
				(type default)
			)
			(layer "B.Fab")
		)
		(fp_line
			(start 0.67945 -0.305054)
			(end 0.12065 -0.305054)
			(stroke
				(width 0.1)
				(type default)
			)
			(layer "B.Fab")
		)
		(fp_line
			(start 0.12065 0.3048)
			(end 0.67945 0.3048)
			(stroke
				(width 0.1)
				(type default)
			)
			(layer "B.Fab")
		)
		(fp_line
			(start 0.12065 0.2794)
			(end 0.12065 0.3048)
			(stroke
				(width 0.1)
				(type default)
			)
			(layer "B.Fab")
		)
		(fp_line
			(start 0.12065 -0.2794)
			(end -0.12065 -0.2794)
			(stroke
				(width 0.1)
				(type default)
			)
			(layer "B.Fab")
		)
		(fp_line
			(start 0.12065 -0.305054)
			(end 0.12065 -0.2794)
			(stroke
				(width 0.1)
				(type default)
			)
			(layer "B.Fab")
		)
		(fp_line
			(start -0.120396 0.3048)
			(end -0.120396 0.2794)
			(stroke
				(width 0.1)
				(type default)
			)
			(layer "B.Fab")
		)
		(fp_line
			(start -0.120396 0.2794)
			(end 0.12065 0.2794)
			(stroke
				(width 0.1)
				(type default)
			)
			(layer "B.Fab")
		)
		(fp_line
			(start -0.12065 -0.2794)
			(end -0.12065 -0.3048)
			(stroke
				(width 0.1)
				(type default)
			)
			(layer "B.Fab")
		)
		(fp_line
			(start -0.12065 -0.3048)
			(end -0.67945 -0.3048)
			(stroke
				(width 0.1)
				(type default)
			)
			(layer "B.Fab")
		)
		(fp_line
			(start -0.67945 0.3048)
			(end -0.120396 0.3048)
			(stroke
				(width 0.1)
				(type default)
			)
			(layer "B.Fab")
		)
		(fp_line
			(start -0.67945 -0.3048)
			(end -0.67945 0.3048)
			(stroke
				(width 0.1)
				(type default)
			)
			(layer "B.Fab")
		)
		(pad "1" smd circle
			(at 0.40005 0)
			(size 0 0)
			(layers "B.Cu" "B.Mask" "B.Paste")
			(net "FT4232_SDB_EEPROM_DO")
		)
		(pad "2" smd circle
			(at -0.40005 0)
			(size 0 0)
			(layers "B.Cu" "B.Mask" "B.Paste")
			(net "P3V3_AUX")
		)
	)
	(footprint ""
		(layer "B.Cu")
		(at 293.120318 -200.261474 180)
		(property "Reference" "C2110"
			(at 0 0 0)
			(layer "B.SilkS")
			(hide yes)
			(effects
				(font
					(size 1.27 1.27)
				)
				(justify mirror)
			)
		)
		(property "Value" ""
			(at 0 0 0)
			(layer "B.Fab")
			(effects
				(font
					(size 1.27 1.27)
				)
				(justify mirror)
			)
		)
		(duplicate_pad_numbers_are_jumpers no)
		(fp_line
			(start 0.7874 0.4064)
			(end 0.7874 -0.4064)
			(stroke
				(width 0.1524)
				(type default)
			)
			(layer "B.SilkS")
		)
		(fp_line
			(start 0.7874 -0.4064)
			(end -0.7874 -0.4064)
			(stroke
				(width 0.1524)
				(type default)
			)
			(layer "B.SilkS")
		)
		(fp_line
			(start -0.7874 0.4064)
			(end 0.7874 0.4064)
			(stroke
				(width 0.1524)
				(type default)
			)
			(layer "B.SilkS")
		)
		(fp_line
			(start -0.7874 -0.4064)
			(end -0.7874 0.4064)
			(stroke
				(width 0.1524)
				(type default)
			)
			(layer "B.SilkS")
		)
		(fp_line
			(start 0.67945 0.3048)
			(end 0.67945 -0.305054)
			(stroke
				(width 0.1)
				(type default)
			)
			(layer "B.Fab")
		)
		(fp_line
			(start 0.67945 -0.305054)
			(end 0.12065 -0.305054)
			(stroke
				(width 0.1)
				(type default)
			)
			(layer "B.Fab")
		)
		(fp_line
			(start 0.12065 0.3048)
			(end 0.67945 0.3048)
			(stroke
				(width 0.1)
				(type default)
			)
			(layer "B.Fab")
		)
		(fp_line
			(start 0.12065 0.2794)
			(end 0.12065 0.3048)
			(stroke
				(width 0.1)
				(type default)
			)
			(layer "B.Fab")
		)
		(fp_line
			(start 0.12065 -0.2794)
			(end -0.12065 -0.2794)
			(stroke
				(width 0.1)
				(type default)
			)
			(layer "B.Fab")
		)
		(fp_line
			(start 0.12065 -0.305054)
			(end 0.12065 -0.2794)
			(stroke
				(width 0.1)
				(type default)
			)
			(layer "B.Fab")
		)
		(fp_line
			(start -0.120396 0.3048)
			(end -0.120396 0.2794)
			(stroke
				(width 0.1)
				(type default)
			)
			(layer "B.Fab")
		)
		(fp_line
			(start -0.120396 0.2794)
			(end 0.12065 0.2794)
			(stroke
				(width 0.1)
				(type default)
			)
			(layer "B.Fab")
		)
		(fp_line
			(start -0.12065 -0.2794)
			(end -0.12065 -0.3048)
			(stroke
				(width 0.1)
				(type default)
			)
			(layer "B.Fab")
		)
		(fp_line
			(start -0.12065 -0.3048)
			(end -0.67945 -0.3048)
			(stroke
				(width 0.1)
				(type default)
			)
			(layer "B.Fab")
		)
		(fp_line
			(start -0.67945 0.3048)
			(end -0.120396 0.3048)
			(stroke
				(width 0.1)
				(type default)
			)
			(layer "B.Fab")
		)
		(fp_line
			(start -0.67945 -0.3048)
			(end -0.67945 0.3048)
			(stroke
				(width 0.1)
				(type default)
			)
			(layer "B.Fab")
		)
		(pad "1" smd circle
			(at 0.40005 0)
			(size 0 0)
			(layers "B.Cu" "B.Mask" "B.Paste")
			(net "GND")
		)
		(pad "2" smd circle
			(at -0.40005 0)
			(size 0 0)
			(layers "B.Cu" "B.Mask" "B.Paste")
			(net "P3V3_AUX")
		)
	)
	(footprint ""
		(layer "B.Cu")
		(at 280.924762 -293.99992 90)
		(property "Reference" "C1638"
			(at 0 0 90)
			(layer "B.SilkS")
			(hide yes)
			(effects
				(font
					(size 1.27 1.27)
				)
				(justify mirror)
			)
		)
		(property "Value" ""
			(at 0 0 90)
			(layer "B.Fab")
			(effects
				(font
					(size 1.27 1.27)
				)
				(justify mirror)
			)
		)
		(duplicate_pad_numbers_are_jumpers no)
		(fp_line
			(start 0.299974 -0.150114)
			(end -0.299974 -0.150114)
			(stroke
				(width 0.1)
				(type default)
			)
			(layer "B.Fab")
		)
		(fp_line
			(start -0.299974 -0.150114)
			(end -0.299974 0.150114)
			(stroke
				(width 0.1)
				(type default)
			)
			(layer "B.Fab")
		)
		(fp_line
			(start 0.299974 0.150114)
			(end 0.299974 -0.150114)
			(stroke
				(width 0.1)
				(type default)
			)
			(layer "B.Fab")
		)
		(fp_line
			(start -0.299974 0.150114)
			(end 0.299974 0.150114)
			(stroke
				(width 0.1)
				(type default)
			)
			(layer "B.Fab")
		)
		(pad "1" smd rect
			(at 0.2667 0 270)
			(size 0.3048 0.381)
			(layers "B.Cu" "B.Mask" "B.Paste")
			(net "P0V8_PEX2")
		)
		(pad "2" smd rect
			(at -0.2667 0 270)
			(size 0.3048 0.381)
			(layers "B.Cu" "B.Mask" "B.Paste")
			(net "GND")
		)
	)
	(footprint ""
		(layer "B.Cu")
		(at 287.099756 -292.099746 90)
		(property "Reference" "C1743"
			(at 0 0 90)
			(layer "B.SilkS")
			(hide yes)
			(effects
				(font
					(size 1.27 1.27)
				)
				(justify mirror)
			)
		)
		(property "Value" ""
			(at 0 0 90)
			(layer "B.Fab")
			(effects
				(font
					(size 1.27 1.27)
				)
				(justify mirror)
			)
		)
		(duplicate_pad_numbers_are_jumpers no)
		(fp_line
			(start 0.299974 -0.150114)
			(end -0.299974 -0.150114)
			(stroke
				(width 0.1)
				(type default)
			)
			(layer "B.Fab")
		)
		(fp_line
			(start -0.299974 -0.150114)
			(end -0.299974 0.150114)
			(stroke
				(width 0.1)
				(type default)
			)
			(layer "B.Fab")
		)
		(fp_line
			(start 0.299974 0.150114)
			(end 0.299974 -0.150114)
			(stroke
				(width 0.1)
				(type default)
			)
			(layer "B.Fab")
		)
		(fp_line
			(start -0.299974 0.150114)
			(end 0.299974 0.150114)
			(stroke
				(width 0.1)
				(type default)
			)
			(layer "B.Fab")
		)
		(pad "1" smd rect
			(at 0.2667 0 270)
			(size 0.3048 0.381)
			(layers "B.Cu" "B.Mask" "B.Paste")
			(net "P0V8_SERDES_VDDA_PEX2")
		)
		(pad "2" smd rect
			(at -0.2667 0 270)
			(size 0.3048 0.381)
			(layers "B.Cu" "B.Mask" "B.Paste")
			(net "GND")
		)
	)
	(footprint ""
		(layer "B.Cu")
		(at 49.5554 -150.9776)
		(property "Reference" "R20"
			(at 0 0 0)
			(layer "B.SilkS")
			(hide yes)
			(effects
				(font
					(size 1.27 1.27)
				)
				(justify mirror)
			)
		)
		(property "Value" ""
			(at 0 0 0)
			(layer "B.Fab")
			(effects
				(font
					(size 1.27 1.27)
				)
				(justify mirror)
			)
		)
		(duplicate_pad_numbers_are_jumpers no)
		(fp_line
			(start -0.7874 -0.4064)
			(end -0.7874 0.4064)
			(stroke
				(width 0.1524)
				(type default)
			)
			(layer "B.SilkS")
		)
		(fp_line
			(start -0.7874 0.4064)
			(end 0.7874 0.4064)
			(stroke
				(width 0.1524)
				(type default)
			)
			(layer "B.SilkS")
		)
		(fp_line
			(start 0.7874 -0.4064)
			(end -0.7874 -0.4064)
			(stroke
				(width 0.1524)
				(type default)
			)
			(layer "B.SilkS")
		)
		(fp_line
			(start 0.7874 0.4064)
			(end 0.7874 -0.4064)
			(stroke
				(width 0.1524)
				(type default)
			)
			(layer "B.SilkS")
		)
		(fp_line
			(start -0.67945 -0.3048)
			(end -0.67945 0.3048)
			(stroke
				(width 0.1)
				(type default)
			)
			(layer "B.Fab")
		)
		(fp_line
			(start -0.67945 0.3048)
			(end -0.120396 0.3048)
			(stroke
				(width 0.1)
				(type default)
			)
			(layer "B.Fab")
		)
		(fp_line
			(start -0.12065 -0.3048)
			(end -0.67945 -0.3048)
			(stroke
				(width 0.1)
				(type default)
			)
			(layer "B.Fab")
		)
		(fp_line
			(start -0.12065 -0.2794)
			(end -0.12065 -0.3048)
			(stroke
				(width 0.1)
				(type default)
			)
			(layer "B.Fab")
		)
		(fp_line
			(start -0.120396 0.2794)
			(end 0.12065 0.2794)
			(stroke
				(width 0.1)
				(type default)
			)
			(layer "B.Fab")
		)
		(fp_line
			(start -0.120396 0.3048)
			(end -0.120396 0.2794)
			(stroke
				(width 0.1)
				(type default)
			)
			(layer "B.Fab")
		)
		(fp_line
			(start 0.12065 -0.305054)
			(end 0.12065 -0.2794)
			(stroke
				(width 0.1)
				(type default)
			)
			(layer "B.Fab")
		)
		(fp_line
			(start 0.12065 -0.2794)
			(end -0.12065 -0.2794)
			(stroke
				(width 0.1)
				(type default)
			)
			(layer "B.Fab")
		)
		(fp_line
			(start 0.12065 0.2794)
			(end 0.12065 0.3048)
			(stroke
				(width 0.1)
				(type default)
			)
			(layer "B.Fab")
		)
		(fp_line
			(start 0.12065 0.3048)
			(end 0.67945 0.3048)
			(stroke
				(width 0.1)
				(type default)
			)
			(layer "B.Fab")
		)
		(fp_line
			(start 0.67945 -0.305054)
			(end 0.12065 -0.305054)
			(stroke
				(width 0.1)
				(type default)
			)
			(layer "B.Fab")
		)
		(fp_line
			(start 0.67945 0.3048)
			(end 0.67945 -0.305054)
			(stroke
				(width 0.1)
				(type default)
			)
			(layer "B.Fab")
		)
		(pad "1" smd circle
			(at 0.40005 0 180)
			(size 0 0)
			(layers "B.Cu" "B.Mask" "B.Paste")
			(net "CLK_50M_NIC0_RBT_REF")
		)
		(pad "2" smd circle
			(at -0.40005 0 180)
			(size 0 0)
			(layers "B.Cu" "B.Mask" "B.Paste")
			(net "GND")
		)
	)
	(footprint ""
		(layer "B.Cu")
		(at 300.607984 -299.224954 180)
		(property "Reference" "C1704"
			(at 0 0 0)
			(layer "B.SilkS")
			(hide yes)
			(effects
				(font
					(size 1.27 1.27)
				)
				(justify mirror)
			)
		)
		(property "Value" ""
			(at 0 0 0)
			(layer "B.Fab")
			(effects
				(font
					(size 1.27 1.27)
				)
				(justify mirror)
			)
		)
		(duplicate_pad_numbers_are_jumpers no)
		(fp_line
			(start 0.299974 0.150114)
			(end 0.299974 -0.150114)
			(stroke
				(width 0.1)
				(type default)
			)
			(layer "B.Fab")
		)
		(fp_line
			(start 0.299974 -0.150114)
			(end -0.299974 -0.150114)
			(stroke
				(width 0.1)
				(type default)
			)
			(layer "B.Fab")
		)
		(fp_line
			(start -0.299974 0.150114)
			(end 0.299974 0.150114)
			(stroke
				(width 0.1)
				(type default)
			)
			(layer "B.Fab")
		)
		(fp_line
			(start -0.299974 -0.150114)
			(end -0.299974 0.150114)
			(stroke
				(width 0.1)
				(type default)
			)
			(layer "B.Fab")
		)
		(pad "1" smd rect
			(at 0.2667 0)
			(size 0.3048 0.381)
			(layers "B.Cu" "B.Mask" "B.Paste")
			(net "P0V8_SERDES_VDDA_PEX2")
		)
		(pad "2" smd rect
			(at -0.2667 0)
			(size 0.3048 0.381)
			(layers "B.Cu" "B.Mask" "B.Paste")
			(net "GND")
		)
	)
	(footprint ""
		(layer "B.Cu")
		(at 52.524914 -293.99992 90)
		(property "Reference" "C1134"
			(at 0 0 90)
			(layer "B.SilkS")
			(hide yes)
			(effects
				(font
					(size 1.27 1.27)
				)
				(justify mirror)
			)
		)
		(property "Value" ""
			(at 0 0 90)
			(layer "B.Fab")
			(effects
				(font
					(size 1.27 1.27)
				)
				(justify mirror)
			)
		)
		(duplicate_pad_numbers_are_jumpers no)
		(fp_line
			(start 0.299974 -0.150114)
			(end -0.299974 -0.150114)
			(stroke
				(width 0.1)
				(type default)
			)
			(layer "B.Fab")
		)
		(fp_line
			(start -0.299974 -0.150114)
			(end -0.299974 0.150114)
			(stroke
				(width 0.1)
				(type default)
			)
			(layer "B.Fab")
		)
		(fp_line
			(start 0.299974 0.150114)
			(end 0.299974 -0.150114)
			(stroke
				(width 0.1)
				(type default)
			)
			(layer "B.Fab")
		)
		(fp_line
			(start -0.299974 0.150114)
			(end 0.299974 0.150114)
			(stroke
				(width 0.1)
				(type default)
			)
			(layer "B.Fab")
		)
		(pad "1" smd rect
			(at 0.2667 0 270)
			(size 0.3048 0.381)
			(layers "B.Cu" "B.Mask" "B.Paste")
			(net "P0V8_PEX0")
		)
		(pad "2" smd rect
			(at -0.2667 0 270)
			(size 0.3048 0.381)
			(layers "B.Cu" "B.Mask" "B.Paste")
			(net "GND")
		)
	)
	(footprint ""
		(layer "B.Cu")
		(at 50.57013 -305.399948 -90)
		(property "Reference" "C2984"
			(at 0 0 90)
			(layer "B.SilkS")
			(hide yes)
			(effects
				(font
					(size 1.27 1.27)
				)
				(justify mirror)
			)
		)
		(property "Value" ""
			(at 0 0 90)
			(layer "B.Fab")
			(effects
				(font
					(size 1.27 1.27)
				)
				(justify mirror)
			)
		)
		(duplicate_pad_numbers_are_jumpers no)
		(fp_line
			(start -0.299974 0.150114)
			(end 0.299974 0.150114)
			(stroke
				(width 0.1)
				(type default)
			)
			(layer "B.Fab")
		)
		(fp_line
			(start 0.299974 0.150114)
			(end 0.299974 -0.150114)
			(stroke
				(width 0.1)
				(type default)
			)
			(layer "B.Fab")
		)
		(fp_line
			(start -0.299974 -0.150114)
			(end -0.299974 0.150114)
			(stroke
				(width 0.1)
				(type default)
			)
			(layer "B.Fab")
		)
		(fp_line
			(start 0.299974 -0.150114)
			(end -0.299974 -0.150114)
			(stroke
				(width 0.1)
				(type default)
			)
			(layer "B.Fab")
		)
		(pad "1" smd rect
			(at 0.2667 0 90)
			(size 0.3048 0.381)
			(layers "B.Cu" "B.Mask" "B.Paste")
			(net "P1V25_SERDES_VDDPLL_PEX0")
		)
		(pad "2" smd rect
			(at -0.2667 0 90)
			(size 0.3048 0.381)
			(layers "B.Cu" "B.Mask" "B.Paste")
			(net "GND")
		)
	)
	(footprint ""
		(layer "B.Cu")
		(at 73.400158 -110.115096)
		(property "Reference" "C865"
			(at 0 0 0)
			(layer "B.SilkS")
			(hide yes)
			(effects
				(font
					(size 1.27 1.27)
				)
				(justify mirror)
			)
		)
		(property "Value" ""
			(at 0 0 0)
			(layer "B.Fab")
			(effects
				(font
					(size 1.27 1.27)
				)
				(justify mirror)
			)
		)
		(duplicate_pad_numbers_are_jumpers no)
		(fp_line
			(start -0.299974 -0.150114)
			(end -0.299974 0.150114)
			(stroke
				(width 0.1)
				(type default)
			)
			(layer "B.Fab")
		)
		(fp_line
			(start -0.299974 0.150114)
			(end 0.299974 0.150114)
			(stroke
				(width 0.1)
				(type default)
			)
			(layer "B.Fab")
		)
		(fp_line
			(start 0.299974 -0.150114)
			(end -0.299974 -0.150114)
			(stroke
				(width 0.1)
				(type default)
			)
			(layer "B.Fab")
		)
		(fp_line
			(start 0.299974 0.150114)
			(end 0.299974 -0.150114)
			(stroke
				(width 0.1)
				(type default)
			)
			(layer "B.Fab")
		)
		(pad "1" smd rect
			(at 0.2667 0 180)
			(size 0.3048 0.381)
			(layers "B.Cu" "B.Mask" "B.Paste")
			(net "P12V_NIC1")
		)
		(pad "2" smd rect
			(at -0.2667 0 180)
			(size 0.3048 0.381)
			(layers "B.Cu" "B.Mask" "B.Paste")
			(net "GND")
		)
	)
	(footprint ""
		(layer "B.Cu")
		(at 295.649904 -301.599854 -90)
		(property "Reference" "C1740"
			(at 0 0 90)
			(layer "B.SilkS")
			(hide yes)
			(effects
				(font
					(size 1.27 1.27)
				)
				(justify mirror)
			)
		)
		(property "Value" ""
			(at 0 0 90)
			(layer "B.Fab")
			(effects
				(font
					(size 1.27 1.27)
				)
				(justify mirror)
			)
		)
		(duplicate_pad_numbers_are_jumpers no)
		(fp_line
			(start -0.299974 0.150114)
			(end 0.299974 0.150114)
			(stroke
				(width 0.1)
				(type default)
			)
			(layer "B.Fab")
		)
		(fp_line
			(start 0.299974 0.150114)
			(end 0.299974 -0.150114)
			(stroke
				(width 0.1)
				(type default)
			)
			(layer "B.Fab")
		)
		(fp_line
			(start -0.299974 -0.150114)
			(end -0.299974 0.150114)
			(stroke
				(width 0.1)
				(type default)
			)
			(layer "B.Fab")
		)
		(fp_line
			(start 0.299974 -0.150114)
			(end -0.299974 -0.150114)
			(stroke
				(width 0.1)
				(type default)
			)
			(layer "B.Fab")
		)
		(pad "1" smd rect
			(at 0.2667 0 90)
			(size 0.3048 0.381)
			(layers "B.Cu" "B.Mask" "B.Paste")
			(net "P0V8_SERDES_VDDA_PEX2")
		)
		(pad "2" smd rect
			(at -0.2667 0 90)
			(size 0.3048 0.381)
			(layers "B.Cu" "B.Mask" "B.Paste")
			(net "GND")
		)
	)
	(footprint ""
		(layer "B.Cu")
		(at 344.49385 -217.187018 -90)
		(property "Reference" "C2055"
			(at 0 0 90)
			(layer "B.SilkS")
			(hide yes)
			(effects
				(font
					(size 1.27 1.27)
				)
				(justify mirror)
			)
		)
		(property "Value" ""
			(at 0 0 90)
			(layer "B.Fab")
			(effects
				(font
					(size 1.27 1.27)
				)
				(justify mirror)
			)
		)
		(duplicate_pad_numbers_are_jumpers no)
		(fp_line
			(start -0.69215 0.2921)
			(end 0.69215 0.2921)
			(stroke
				(width 0.1524)
				(type default)
			)
			(layer "B.SilkS")
		)
		(fp_line
			(start 0.69215 0.2921)
			(end 0.69215 -0.2921)
			(stroke
				(width 0.1524)
				(type default)
			)
			(layer "B.SilkS")
		)
		(fp_line
			(start -0.69215 -0.2921)
			(end -0.69215 0.2921)
			(stroke
				(width 0.1524)
				(type default)
			)
			(layer "B.SilkS")
		)
		(fp_line
			(start 0.69215 -0.2921)
			(end -0.69215 -0.2921)
			(stroke
				(width 0.1524)
				(type default)
			)
			(layer "B.SilkS")
		)
		(fp_line
			(start -0.51435 0.2794)
			(end 0.51435 0.2794)
			(stroke
				(width 0.1)
				(type default)
			)
			(layer "B.Fab")
		)
		(fp_line
			(start 0.51435 0.2794)
			(end 0.51435 -0.2794)
			(stroke
				(width 0.1)
				(type default)
			)
			(layer "B.Fab")
		)
		(fp_line
			(start -0.51435 -0.2794)
			(end -0.51435 0.2794)
			(stroke
				(width 0.1)
				(type default)
			)
			(layer "B.Fab")
		)
		(fp_line
			(start 0.51435 -0.2794)
			(end -0.51435 -0.2794)
			(stroke
				(width 0.1)
				(type default)
			)
			(layer "B.Fab")
		)
		(pad "1" smd circle
			(at 0.40005 0 90)
			(size 0 0)
			(layers "B.Cu" "B.Mask" "B.Paste")
			(net "P3V3_FPGA_VCCIO2")
		)
		(pad "2" smd circle
			(at -0.40005 0 90)
			(size 0 0)
			(layers "B.Cu" "B.Mask" "B.Paste")
			(net "GND")
		)
		(zone
			(layer "B.Cu")
			(hatch none 0.5)
			(connect_pads
				(clearance 0)
			)
			(min_thickness 0.25)
			(keepout
				(tracks not_allowed)
				(vias allowed)
				(pads allowed)
				(copperpour not_allowed)
				(footprints allowed)
			)
			(placement
				(enabled no)
				(sheetname "")
			)
			(fill
				(thermal_gap 0.5)
				(thermal_bridge_width 0.5)
				(island_removal_mode 0)
			)
			(polygon
				(pts
					(xy 344.40622 -216.996518) (xy 344.348054 -217.087958) (xy 344.348054 -217.287348) (xy 344.40622 -217.377518)
					(xy 344.58148 -217.377518) (xy 344.6399 -217.287348) (xy 344.6399 -217.087958) (xy 344.581734 -216.996518)
				)
			)
		)
	)
	(footprint ""
		(layer "B.Cu")
		(at 64.901318 -305.399948 -90)
		(property "Reference" "C2954"
			(at 0 0 90)
			(layer "B.SilkS")
			(hide yes)
			(effects
				(font
					(size 1.27 1.27)
				)
				(justify mirror)
			)
		)
		(property "Value" ""
			(at 0 0 90)
			(layer "B.Fab")
			(effects
				(font
					(size 1.27 1.27)
				)
				(justify mirror)
			)
		)
		(duplicate_pad_numbers_are_jumpers no)
		(fp_line
			(start -0.299974 0.150114)
			(end 0.299974 0.150114)
			(stroke
				(width 0.1)
				(type default)
			)
			(layer "B.Fab")
		)
		(fp_line
			(start 0.299974 0.150114)
			(end 0.299974 -0.150114)
			(stroke
				(width 0.1)
				(type default)
			)
			(layer "B.Fab")
		)
		(fp_line
			(start -0.299974 -0.150114)
			(end -0.299974 0.150114)
			(stroke
				(width 0.1)
				(type default)
			)
			(layer "B.Fab")
		)
		(fp_line
			(start 0.299974 -0.150114)
			(end -0.299974 -0.150114)
			(stroke
				(width 0.1)
				(type default)
			)
			(layer "B.Fab")
		)
		(pad "1" smd rect
			(at 0.2667 0 90)
			(size 0.3048 0.381)
			(layers "B.Cu" "B.Mask" "B.Paste")
			(net "P1V25_SERDES_VDDPLL_PEX0")
		)
		(pad "2" smd rect
			(at -0.2667 0 90)
			(size 0.3048 0.381)
			(layers "B.Cu" "B.Mask" "B.Paste")
			(net "GND")
		)
	)
	(footprint ""
		(layer "B.Cu")
		(at 52.47005 -305.399948 -90)
		(property "Reference" "C2982"
			(at 0 0 90)
			(layer "B.SilkS")
			(hide yes)
			(effects
				(font
					(size 1.27 1.27)
				)
				(justify mirror)
			)
		)
		(property "Value" ""
			(at 0 0 90)
			(layer "B.Fab")
			(effects
				(font
					(size 1.27 1.27)
				)
				(justify mirror)
			)
		)
		(duplicate_pad_numbers_are_jumpers no)
		(fp_line
			(start -0.299974 0.150114)
			(end 0.299974 0.150114)
			(stroke
				(width 0.1)
				(type default)
			)
			(layer "B.Fab")
		)
		(fp_line
			(start 0.299974 0.150114)
			(end 0.299974 -0.150114)
			(stroke
				(width 0.1)
				(type default)
			)
			(layer "B.Fab")
		)
		(fp_line
			(start -0.299974 -0.150114)
			(end -0.299974 0.150114)
			(stroke
				(width 0.1)
				(type default)
			)
			(layer "B.Fab")
		)
		(fp_line
			(start 0.299974 -0.150114)
			(end -0.299974 -0.150114)
			(stroke
				(width 0.1)
				(type default)
			)
			(layer "B.Fab")
		)
		(pad "1" smd rect
			(at 0.2667 0 90)
			(size 0.3048 0.381)
			(layers "B.Cu" "B.Mask" "B.Paste")
			(net "P1V25_SERDES_VDDPLL_PEX0")
		)
		(pad "2" smd rect
			(at -0.2667 0 90)
			(size 0.3048 0.381)
			(layers "B.Cu" "B.Mask" "B.Paste")
			(net "GND")
		)
	)
	(footprint ""
		(layer "B.Cu")
		(at 333.492348 -308.524402 90)
		(property "Reference" "C4306"
			(at 0 0 90)
			(layer "B.SilkS")
			(hide yes)
			(effects
				(font
					(size 1.27 1.27)
				)
				(justify mirror)
			)
		)
		(property "Value" ""
			(at 0 0 90)
			(layer "B.Fab")
			(effects
				(font
					(size 1.27 1.27)
				)
				(justify mirror)
			)
		)
		(duplicate_pad_numbers_are_jumpers no)
		(fp_line
			(start 0.299974 -0.150114)
			(end -0.299974 -0.150114)
			(stroke
				(width 0.1)
				(type default)
			)
			(layer "B.Fab")
		)
		(fp_line
			(start -0.299974 -0.150114)
			(end -0.299974 0.150114)
			(stroke
				(width 0.1)
				(type default)
			)
			(layer "B.Fab")
		)
		(fp_line
			(start 0.299974 0.150114)
			(end 0.299974 -0.150114)
			(stroke
				(width 0.1)
				(type default)
			)
			(layer "B.Fab")
		)
		(fp_line
			(start -0.299974 0.150114)
			(end 0.299974 0.150114)
			(stroke
				(width 0.1)
				(type default)
			)
			(layer "B.Fab")
		)
		(pad "1" smd rect
			(at 0.2667 0 270)
			(size 0.3048 0.381)
			(layers "B.Cu" "B.Mask" "B.Paste")
			(net "P0V8_PEX2")
		)
		(pad "2" smd rect
			(at -0.2667 0 270)
			(size 0.3048 0.381)
			(layers "B.Cu" "B.Mask" "B.Paste")
			(net "GND")
		)
	)
	(footprint ""
		(layer "B.Cu")
		(at 170.049952 -301.599854 -90)
		(property "Reference" "C1477"
			(at 0 0 90)
			(layer "B.SilkS")
			(hide yes)
			(effects
				(font
					(size 1.27 1.27)
				)
				(justify mirror)
			)
		)
		(property "Value" ""
			(at 0 0 90)
			(layer "B.Fab")
			(effects
				(font
					(size 1.27 1.27)
				)
				(justify mirror)
			)
		)
		(duplicate_pad_numbers_are_jumpers no)
		(fp_line
			(start -0.299974 0.150114)
			(end 0.299974 0.150114)
			(stroke
				(width 0.1)
				(type default)
			)
			(layer "B.Fab")
		)
		(fp_line
			(start 0.299974 0.150114)
			(end 0.299974 -0.150114)
			(stroke
				(width 0.1)
				(type default)
			)
			(layer "B.Fab")
		)
		(fp_line
			(start -0.299974 -0.150114)
			(end -0.299974 0.150114)
			(stroke
				(width 0.1)
				(type default)
			)
			(layer "B.Fab")
		)
		(fp_line
			(start 0.299974 -0.150114)
			(end -0.299974 -0.150114)
			(stroke
				(width 0.1)
				(type default)
			)
			(layer "B.Fab")
		)
		(pad "1" smd rect
			(at 0.2667 0 90)
			(size 0.3048 0.381)
			(layers "B.Cu" "B.Mask" "B.Paste")
			(net "P0V8_SERDES_VDDA_PEX1")
		)
		(pad "2" smd rect
			(at -0.2667 0 90)
			(size 0.3048 0.381)
			(layers "B.Cu" "B.Mask" "B.Paste")
			(net "GND")
		)
	)
	(footprint ""
		(layer "B.Cu")
		(at 112.85728 -313.620404 180)
		(property "Reference" "L48"
			(at 0 0 0)
			(layer "B.SilkS")
			(hide yes)
			(effects
				(font
					(size 1.27 1.27)
				)
				(justify mirror)
			)
		)
		(property "Value" ""
			(at 0 0 0)
			(layer "B.Fab")
			(effects
				(font
					(size 1.27 1.27)
				)
				(justify mirror)
			)
		)
		(duplicate_pad_numbers_are_jumpers no)
		(fp_line
			(start 2.248154 4.9911)
			(end -2.248154 4.9911)
			(stroke
				(width 0.1524)
				(type default)
			)
			(layer "B.SilkS")
		)
		(fp_line
			(start 2.248154 1.88595)
			(end 2.248154 4.9911)
			(stroke
				(width 0.1524)
				(type default)
			)
			(layer "B.SilkS")
		)
		(fp_line
			(start 2.248154 -4.9911)
			(end 2.248154 -1.918462)
			(stroke
				(width 0.1524)
				(type default)
			)
			(layer "B.SilkS")
		)
		(fp_line
			(start -2.248154 4.9911)
			(end -2.248154 1.88595)
			(stroke
				(width 0.1524)
				(type default)
			)
			(layer "B.SilkS")
		)
		(fp_line
			(start -2.248154 -1.918462)
			(end -2.248154 -4.9911)
			(stroke
				(width 0.1524)
				(type default)
			)
			(layer "B.SilkS")
		)
		(fp_line
			(start -2.248154 -4.9911)
			(end 2.248154 -4.9911)
			(stroke
				(width 0.1524)
				(type default)
			)
			(layer "B.SilkS")
		)
		(fp_line
			(start 1.700022 0.899922)
			(end -1.700022 0.899922)
			(stroke
				(width 0.1)
				(type default)
			)
			(layer "B.Fab")
		)
		(fp_line
			(start 1.700022 -0.899922)
			(end 1.700022 0.899922)
			(stroke
				(width 0.1)
				(type default)
			)
			(layer "B.Fab")
		)
		(fp_line
			(start -1.700022 0.899922)
			(end -1.700022 -0.899922)
			(stroke
				(width 0.1)
				(type default)
			)
			(layer "B.Fab")
		)
		(fp_line
			(start -1.700022 -0.899922)
			(end 1.700022 -0.899922)
			(stroke
				(width 0.1)
				(type default)
			)
			(layer "B.Fab")
		)
		(pad "1" smd rect
			(at 1.575054 0)
			(size 1.1684 9.8044)
			(layers "B.Cu" "B.Mask" "B.Paste")
			(net "P0V8_PEX0")
		)
		(pad "2" smd rect
			(at -1.575054 0)
			(size 1.1684 9.8044)
			(layers "B.Cu" "B.Mask" "B.Paste")
			(net "P0V8_SERDES_VDDA_PEX0")
		)
	)
	(footprint ""
		(layer "B.Cu")
		(at 336.618326 -281.024838 90)
		(property "Reference" "PC141"
			(at 0 0 90)
			(layer "B.SilkS")
			(hide yes)
			(effects
				(font
					(size 1.27 1.27)
				)
				(justify mirror)
			)
		)
		(property "Value" ""
			(at 0 0 90)
			(layer "B.Fab")
			(effects
				(font
					(size 1.27 1.27)
				)
				(justify mirror)
			)
		)
		(duplicate_pad_numbers_are_jumpers no)
		(fp_line
			(start 1.524 -0.762)
			(end -1.524 -0.762)
			(stroke
				(width 0.1524)
				(type default)
			)
			(layer "B.SilkS")
		)
		(fp_line
			(start -1.524 -0.762)
			(end -1.524 0.762)
			(stroke
				(width 0.1524)
				(type default)
			)
			(layer "B.SilkS")
		)
		(fp_line
			(start 1.524 0.762)
			(end 1.524 -0.762)
			(stroke
				(width 0.1524)
				(type default)
			)
			(layer "B.SilkS")
		)
		(fp_line
			(start -1.524 0.762)
			(end 1.524 0.762)
			(stroke
				(width 0.1524)
				(type default)
			)
			(layer "B.SilkS")
		)
		(fp_line
			(start 1.1049 -0.724916)
			(end 1.1049 0.724916)
			(stroke
				(width 0.1)
				(type default)
			)
			(layer "B.Fab")
		)
		(fp_line
			(start -1.1049 -0.724916)
			(end 1.1049 -0.724916)
			(stroke
				(width 0.1)
				(type default)
			)
			(layer "B.Fab")
		)
		(fp_line
			(start 1.1049 0.724916)
			(end -1.1049 0.724916)
			(stroke
				(width 0.1)
				(type default)
			)
			(layer "B.Fab")
		)
		(fp_line
			(start -1.1049 0.724916)
			(end -1.1049 -0.724916)
			(stroke
				(width 0.1)
				(type default)
			)
			(layer "B.Fab")
		)
		(pad "1" smd rect
			(at 0.889 0 90)
			(size 1.016 1.27)
			(layers "B.Cu" "B.Mask" "B.Paste")
			(net "SW_P12V_P0V8_PEX2_FLT")
		)
		(pad "2" smd rect
			(at -0.889 0 90)
			(size 1.016 1.27)
			(layers "B.Cu" "B.Mask" "B.Paste")
			(net "GND")
		)
	)
	(footprint ""
		(layer "B.Cu")
		(at 124.236226 -325.186294 -90)
		(property "Reference" "C4257"
			(at 0 0 90)
			(layer "B.SilkS")
			(hide yes)
			(effects
				(font
					(size 1.27 1.27)
				)
				(justify mirror)
			)
		)
		(property "Value" ""
			(at 0 0 90)
			(layer "B.Fab")
			(effects
				(font
					(size 1.27 1.27)
				)
				(justify mirror)
			)
		)
		(duplicate_pad_numbers_are_jumpers no)
		(fp_line
			(start -1.2954 0.5842)
			(end 1.2954 0.5842)
			(stroke
				(width 0.1524)
				(type default)
			)
			(layer "B.SilkS")
		)
		(fp_line
			(start 1.2954 0.5842)
			(end 1.2954 -0.5842)
			(stroke
				(width 0.1524)
				(type default)
			)
			(layer "B.SilkS")
		)
		(fp_line
			(start -1.2954 -0.5842)
			(end -1.2954 0.5842)
			(stroke
				(width 0.1524)
				(type default)
			)
			(layer "B.SilkS")
		)
		(fp_line
			(start 1.2954 -0.5842)
			(end -1.2954 -0.5842)
			(stroke
				(width 0.1524)
				(type default)
			)
			(layer "B.SilkS")
		)
		(fp_line
			(start -0.8636 0.4572)
			(end 0.8636 0.4572)
			(stroke
				(width 0.1)
				(type default)
			)
			(layer "B.Fab")
		)
		(fp_line
			(start 0.8636 0.4572)
			(end 0.8636 0.4064)
			(stroke
				(width 0.1)
				(type default)
			)
			(layer "B.Fab")
		)
		(fp_line
			(start -1.1938 0.4064)
			(end -0.8636 0.4064)
			(stroke
				(width 0.1)
				(type default)
			)
			(layer "B.Fab")
		)
		(fp_line
			(start -0.8636 0.4064)
			(end -0.8636 0.4572)
			(stroke
				(width 0.1)
				(type default)
			)
			(layer "B.Fab")
		)
		(fp_line
			(start 0.8636 0.4064)
			(end 1.1938 0.4064)
			(stroke
				(width 0.1)
				(type default)
			)
			(layer "B.Fab")
		)
		(fp_line
			(start 1.1938 0.4064)
			(end 1.1938 -0.4064)
			(stroke
				(width 0.1)
				(type default)
			)
			(layer "B.Fab")
		)
		(fp_line
			(start -1.1938 -0.4064)
			(end -1.1938 0.4064)
			(stroke
				(width 0.1)
				(type default)
			)
			(layer "B.Fab")
		)
		(fp_line
			(start -0.8636 -0.4064)
			(end -1.1938 -0.4064)
			(stroke
				(width 0.1)
				(type default)
			)
			(layer "B.Fab")
		)
		(fp_line
			(start 0.8636 -0.4064)
			(end 0.8636 -0.4572)
			(stroke
				(width 0.1)
				(type default)
			)
			(layer "B.Fab")
		)
		(fp_line
			(start 1.1938 -0.4064)
			(end 0.8636 -0.4064)
			(stroke
				(width 0.1)
				(type default)
			)
			(layer "B.Fab")
		)
		(fp_line
			(start -0.8636 -0.4572)
			(end -0.8636 -0.4064)
			(stroke
				(width 0.1)
				(type default)
			)
			(layer "B.Fab")
		)
		(fp_line
			(start 0.8636 -0.4572)
			(end -0.8636 -0.4572)
			(stroke
				(width 0.1)
				(type default)
			)
			(layer "B.Fab")
		)
		(pad "1" smd rect
			(at 0.7366 0 180)
			(size 0.7112 0.8128)
			(layers "B.Cu" "B.Mask" "B.Paste")
			(net "P0V8_SERDES_VDDA_PEX1_C3")
		)
		(pad "2" smd rect
			(at -0.7366 0 180)
			(size 0.7112 0.8128)
			(layers "B.Cu" "B.Mask" "B.Paste")
			(net "GND")
		)
	)
	(footprint ""
		(layer "B.Cu")
		(at 385.689602 -234.62996 180)
		(property "Reference" "C2580"
			(at 0 0 0)
			(layer "B.SilkS")
			(hide yes)
			(effects
				(font
					(size 1.27 1.27)
				)
				(justify mirror)
			)
		)
		(property "Value" ""
			(at 0 0 0)
			(layer "B.Fab")
			(effects
				(font
					(size 1.27 1.27)
				)
				(justify mirror)
			)
		)
		(duplicate_pad_numbers_are_jumpers no)
		(fp_line
			(start 0.7874 0.4064)
			(end 0.7874 -0.4064)
			(stroke
				(width 0.1524)
				(type default)
			)
			(layer "B.SilkS")
		)
		(fp_line
			(start 0.7874 -0.4064)
			(end -0.7874 -0.4064)
			(stroke
				(width 0.1524)
				(type default)
			)
			(layer "B.SilkS")
		)
		(fp_line
			(start -0.7874 0.4064)
			(end 0.7874 0.4064)
			(stroke
				(width 0.1524)
				(type default)
			)
			(layer "B.SilkS")
		)
		(fp_line
			(start -0.7874 -0.4064)
			(end -0.7874 0.4064)
			(stroke
				(width 0.1524)
				(type default)
			)
			(layer "B.SilkS")
		)
		(fp_line
			(start 0.67945 0.3048)
			(end 0.67945 -0.305054)
			(stroke
				(width 0.1)
				(type default)
			)
			(layer "B.Fab")
		)
		(fp_line
			(start 0.67945 -0.305054)
			(end 0.12065 -0.305054)
			(stroke
				(width 0.1)
				(type default)
			)
			(layer "B.Fab")
		)
		(fp_line
			(start 0.12065 0.3048)
			(end 0.67945 0.3048)
			(stroke
				(width 0.1)
				(type default)
			)
			(layer "B.Fab")
		)
		(fp_line
			(start 0.12065 0.2794)
			(end 0.12065 0.3048)
			(stroke
				(width 0.1)
				(type default)
			)
			(layer "B.Fab")
		)
		(fp_line
			(start 0.12065 -0.2794)
			(end -0.12065 -0.2794)
			(stroke
				(width 0.1)
				(type default)
			)
			(layer "B.Fab")
		)
		(fp_line
			(start 0.12065 -0.305054)
			(end 0.12065 -0.2794)
			(stroke
				(width 0.1)
				(type default)
			)
			(layer "B.Fab")
		)
		(fp_line
			(start -0.120396 0.3048)
			(end -0.120396 0.2794)
			(stroke
				(width 0.1)
				(type default)
			)
			(layer "B.Fab")
		)
		(fp_line
			(start -0.120396 0.2794)
			(end 0.12065 0.2794)
			(stroke
				(width 0.1)
				(type default)
			)
			(layer "B.Fab")
		)
		(fp_line
			(start -0.12065 -0.2794)
			(end -0.12065 -0.3048)
			(stroke
				(width 0.1)
				(type default)
			)
			(layer "B.Fab")
		)
		(fp_line
			(start -0.12065 -0.3048)
			(end -0.67945 -0.3048)
			(stroke
				(width 0.1)
				(type default)
			)
			(layer "B.Fab")
		)
		(fp_line
			(start -0.67945 0.3048)
			(end -0.120396 0.3048)
			(stroke
				(width 0.1)
				(type default)
			)
			(layer "B.Fab")
		)
		(fp_line
			(start -0.67945 -0.3048)
			(end -0.67945 0.3048)
			(stroke
				(width 0.1)
				(type default)
			)
			(layer "B.Fab")
		)
		(pad "1" smd circle
			(at 0.40005 0)
			(size 0 0)
			(layers "B.Cu" "B.Mask" "B.Paste")
			(net "P3V3_SDB_VPLL")
		)
		(pad "2" smd circle
			(at -0.40005 0)
			(size 0 0)
			(layers "B.Cu" "B.Mask" "B.Paste")
			(net "GND")
		)
	)
	(footprint ""
		(layer "B.Cu")
		(at 113.514124 -331.60843 180)
		(property "Reference" "R1218"
			(at 0 0 0)
			(layer "B.SilkS")
			(hide yes)
			(effects
				(font
					(size 1.27 1.27)
				)
				(justify mirror)
			)
		)
		(property "Value" ""
			(at 0 0 0)
			(layer "B.Fab")
			(effects
				(font
					(size 1.27 1.27)
				)
				(justify mirror)
			)
		)
		(duplicate_pad_numbers_are_jumpers no)
		(fp_line
			(start 0.7874 0.4064)
			(end 0.7874 -0.4064)
			(stroke
				(width 0.1524)
				(type default)
			)
			(layer "B.SilkS")
		)
		(fp_line
			(start 0.7874 -0.4064)
			(end -0.7874 -0.4064)
			(stroke
				(width 0.1524)
				(type default)
			)
			(layer "B.SilkS")
		)
		(fp_line
			(start -0.7874 0.4064)
			(end 0.7874 0.4064)
			(stroke
				(width 0.1524)
				(type default)
			)
			(layer "B.SilkS")
		)
		(fp_line
			(start -0.7874 -0.4064)
			(end -0.7874 0.4064)
			(stroke
				(width 0.1524)
				(type default)
			)
			(layer "B.SilkS")
		)
		(fp_line
			(start 0.67945 0.3048)
			(end 0.67945 -0.305054)
			(stroke
				(width 0.1)
				(type default)
			)
			(layer "B.Fab")
		)
		(fp_line
			(start 0.67945 -0.305054)
			(end 0.12065 -0.305054)
			(stroke
				(width 0.1)
				(type default)
			)
			(layer "B.Fab")
		)
		(fp_line
			(start 0.12065 0.3048)
			(end 0.67945 0.3048)
			(stroke
				(width 0.1)
				(type default)
			)
			(layer "B.Fab")
		)
		(fp_line
			(start 0.12065 0.2794)
			(end 0.12065 0.3048)
			(stroke
				(width 0.1)
				(type default)
			)
			(layer "B.Fab")
		)
		(fp_line
			(start 0.12065 -0.2794)
			(end -0.12065 -0.2794)
			(stroke
				(width 0.1)
				(type default)
			)
			(layer "B.Fab")
		)
		(fp_line
			(start 0.12065 -0.305054)
			(end 0.12065 -0.2794)
			(stroke
				(width 0.1)
				(type default)
			)
			(layer "B.Fab")
		)
		(fp_line
			(start -0.120396 0.3048)
			(end -0.120396 0.2794)
			(stroke
				(width 0.1)
				(type default)
			)
			(layer "B.Fab")
		)
		(fp_line
			(start -0.120396 0.2794)
			(end 0.12065 0.2794)
			(stroke
				(width 0.1)
				(type default)
			)
			(layer "B.Fab")
		)
		(fp_line
			(start -0.12065 -0.2794)
			(end -0.12065 -0.3048)
			(stroke
				(width 0.1)
				(type default)
			)
			(layer "B.Fab")
		)
		(fp_line
			(start -0.12065 -0.3048)
			(end -0.67945 -0.3048)
			(stroke
				(width 0.1)
				(type default)
			)
			(layer "B.Fab")
		)
		(fp_line
			(start -0.67945 0.3048)
			(end -0.120396 0.3048)
			(stroke
				(width 0.1)
				(type default)
			)
			(layer "B.Fab")
		)
		(fp_line
			(start -0.67945 -0.3048)
			(end -0.67945 0.3048)
			(stroke
				(width 0.1)
				(type default)
			)
			(layer "B.Fab")
		)
		(pad "1" smd circle
			(at 0.40005 0)
			(size 0 0)
			(layers "B.Cu" "B.Mask" "B.Paste")
			(net "CLK_100M_MB_0_R_DP")
		)
		(pad "2" smd circle
			(at -0.40005 0)
			(size 0 0)
			(layers "B.Cu" "B.Mask" "B.Paste")
			(net "CLK_100M_MB_0_DP")
		)
	)
	(footprint ""
		(layer "B.Cu")
		(at 54.424834 -297.79976 -90)
		(property "Reference" "C1148"
			(at 0 0 90)
			(layer "B.SilkS")
			(hide yes)
			(effects
				(font
					(size 1.27 1.27)
				)
				(justify mirror)
			)
		)
		(property "Value" ""
			(at 0 0 90)
			(layer "B.Fab")
			(effects
				(font
					(size 1.27 1.27)
				)
				(justify mirror)
			)
		)
		(duplicate_pad_numbers_are_jumpers no)
		(fp_line
			(start -0.299974 0.150114)
			(end 0.299974 0.150114)
			(stroke
				(width 0.1)
				(type default)
			)
			(layer "B.Fab")
		)
		(fp_line
			(start 0.299974 0.150114)
			(end 0.299974 -0.150114)
			(stroke
				(width 0.1)
				(type default)
			)
			(layer "B.Fab")
		)
		(fp_line
			(start -0.299974 -0.150114)
			(end -0.299974 0.150114)
			(stroke
				(width 0.1)
				(type default)
			)
			(layer "B.Fab")
		)
		(fp_line
			(start 0.299974 -0.150114)
			(end -0.299974 -0.150114)
			(stroke
				(width 0.1)
				(type default)
			)
			(layer "B.Fab")
		)
		(pad "1" smd rect
			(at 0.2667 0 90)
			(size 0.3048 0.381)
			(layers "B.Cu" "B.Mask" "B.Paste")
			(net "P0V8_PEX0")
		)
		(pad "2" smd rect
			(at -0.2667 0 90)
			(size 0.3048 0.381)
			(layers "B.Cu" "B.Mask" "B.Paste")
			(net "GND")
		)
	)
	(footprint ""
		(layer "B.Cu")
		(at 344.87231 -258.004564 90)
		(property "Reference" "PR142"
			(at 0 0 90)
			(layer "B.SilkS")
			(hide yes)
			(effects
				(font
					(size 1.27 1.27)
				)
				(justify mirror)
			)
		)
		(property "Value" ""
			(at 0 0 90)
			(layer "B.Fab")
			(effects
				(font
					(size 1.27 1.27)
				)
				(justify mirror)
			)
		)
		(duplicate_pad_numbers_are_jumpers no)
		(fp_line
			(start 0.7874 -0.4064)
			(end -0.7874 -0.4064)
			(stroke
				(width 0.1524)
				(type default)
			)
			(layer "B.SilkS")
		)
		(fp_line
			(start -0.7874 -0.4064)
			(end -0.7874 0.4064)
			(stroke
				(width 0.1524)
				(type default)
			)
			(layer "B.SilkS")
		)
		(fp_line
			(start 0.7874 0.4064)
			(end 0.7874 -0.4064)
			(stroke
				(width 0.1524)
				(type default)
			)
			(layer "B.SilkS")
		)
		(fp_line
			(start -0.7874 0.4064)
			(end 0.7874 0.4064)
			(stroke
				(width 0.1524)
				(type default)
			)
			(layer "B.SilkS")
		)
		(fp_line
			(start 0.67945 -0.305054)
			(end 0.12065 -0.305054)
			(stroke
				(width 0.1)
				(type default)
			)
			(layer "B.Fab")
		)
		(fp_line
			(start 0.12065 -0.305054)
			(end 0.12065 -0.2794)
			(stroke
				(width 0.1)
				(type default)
			)
			(layer "B.Fab")
		)
		(fp_line
			(start -0.12065 -0.3048)
			(end -0.67945 -0.3048)
			(stroke
				(width 0.1)
				(type default)
			)
			(layer "B.Fab")
		)
		(fp_line
			(start -0.67945 -0.3048)
			(end -0.67945 0.3048)
			(stroke
				(width 0.1)
				(type default)
			)
			(layer "B.Fab")
		)
		(fp_line
			(start 0.12065 -0.2794)
			(end -0.12065 -0.2794)
			(stroke
				(width 0.1)
				(type default)
			)
			(layer "B.Fab")
		)
		(fp_line
			(start -0.12065 -0.2794)
			(end -0.12065 -0.3048)
			(stroke
				(width 0.1)
				(type default)
			)
			(layer "B.Fab")
		)
		(fp_line
			(start 0.12065 0.2794)
			(end 0.12065 0.3048)
			(stroke
				(width 0.1)
				(type default)
			)
			(layer "B.Fab")
		)
		(fp_line
			(start -0.120396 0.2794)
			(end 0.12065 0.2794)
			(stroke
				(width 0.1)
				(type default)
			)
			(layer "B.Fab")
		)
		(fp_line
			(start 0.67945 0.3048)
			(end 0.67945 -0.305054)
			(stroke
				(width 0.1)
				(type default)
			)
			(layer "B.Fab")
		)
		(fp_line
			(start 0.12065 0.3048)
			(end 0.67945 0.3048)
			(stroke
				(width 0.1)
				(type default)
			)
			(layer "B.Fab")
		)
		(fp_line
			(start -0.120396 0.3048)
			(end -0.120396 0.2794)
			(stroke
				(width 0.1)
				(type default)
			)
			(layer "B.Fab")
		)
		(fp_line
			(start -0.67945 0.3048)
			(end -0.120396 0.3048)
			(stroke
				(width 0.1)
				(type default)
			)
			(layer "B.Fab")
		)
		(pad "1" smd circle
			(at 0.40005 0 270)
			(size 0 0)
			(layers "B.Cu" "B.Mask" "B.Paste")
			(net "P12V_AUX")
		)
		(pad "2" smd circle
			(at -0.40005 0 270)
			(size 0 0)
			(layers "B.Cu" "B.Mask" "B.Paste")
			(net "P0V8_PEX2_IINSEN")
		)
	)
	(footprint ""
		(layer "B.Cu")
		(at 261.32282 -87.031576 90)
		(property "Reference" "C2645"
			(at 0 0 90)
			(layer "B.SilkS")
			(hide yes)
			(effects
				(font
					(size 1.27 1.27)
				)
				(justify mirror)
			)
		)
		(property "Value" ""
			(at 0 0 90)
			(layer "B.Fab")
			(effects
				(font
					(size 1.27 1.27)
				)
				(justify mirror)
			)
		)
		(duplicate_pad_numbers_are_jumpers no)
		(fp_line
			(start 0.7874 -0.4064)
			(end -0.7874 -0.4064)
			(stroke
				(width 0.1524)
				(type default)
			)
			(layer "B.SilkS")
		)
		(fp_line
			(start -0.7874 -0.4064)
			(end -0.7874 0.4064)
			(stroke
				(width 0.1524)
				(type default)
			)
			(layer "B.SilkS")
		)
		(fp_line
			(start 0.7874 0.4064)
			(end 0.7874 -0.4064)
			(stroke
				(width 0.1524)
				(type default)
			)
			(layer "B.SilkS")
		)
		(fp_line
			(start -0.7874 0.4064)
			(end 0.7874 0.4064)
			(stroke
				(width 0.1524)
				(type default)
			)
			(layer "B.SilkS")
		)
		(fp_line
			(start 0.67945 -0.305054)
			(end 0.12065 -0.305054)
			(stroke
				(width 0.1)
				(type default)
			)
			(layer "B.Fab")
		)
		(fp_line
			(start 0.12065 -0.305054)
			(end 0.12065 -0.2794)
			(stroke
				(width 0.1)
				(type default)
			)
			(layer "B.Fab")
		)
		(fp_line
			(start -0.12065 -0.3048)
			(end -0.67945 -0.3048)
			(stroke
				(width 0.1)
				(type default)
			)
			(layer "B.Fab")
		)
		(fp_line
			(start -0.67945 -0.3048)
			(end -0.67945 0.3048)
			(stroke
				(width 0.1)
				(type default)
			)
			(layer "B.Fab")
		)
		(fp_line
			(start 0.12065 -0.2794)
			(end -0.12065 -0.2794)
			(stroke
				(width 0.1)
				(type default)
			)
			(layer "B.Fab")
		)
		(fp_line
			(start -0.12065 -0.2794)
			(end -0.12065 -0.3048)
			(stroke
				(width 0.1)
				(type default)
			)
			(layer "B.Fab")
		)
		(fp_line
			(start 0.12065 0.2794)
			(end 0.12065 0.3048)
			(stroke
				(width 0.1)
				(type default)
			)
			(layer "B.Fab")
		)
		(fp_line
			(start -0.120396 0.2794)
			(end 0.12065 0.2794)
			(stroke
				(width 0.1)
				(type default)
			)
			(layer "B.Fab")
		)
		(fp_line
			(start 0.67945 0.3048)
			(end 0.67945 -0.305054)
			(stroke
				(width 0.1)
				(type default)
			)
			(layer "B.Fab")
		)
		(fp_line
			(start 0.12065 0.3048)
			(end 0.67945 0.3048)
			(stroke
				(width 0.1)
				(type default)
			)
			(layer "B.Fab")
		)
		(fp_line
			(start -0.120396 0.3048)
			(end -0.120396 0.2794)
			(stroke
				(width 0.1)
				(type default)
			)
			(layer "B.Fab")
		)
		(fp_line
			(start -0.67945 0.3048)
			(end -0.120396 0.3048)
			(stroke
				(width 0.1)
				(type default)
			)
			(layer "B.Fab")
		)
		(pad "1" smd circle
			(at 0.40005 0 270)
			(size 0 0)
			(layers "B.Cu" "B.Mask" "B.Paste")
			(net "P3V3_CLK_GEN_VDDMXCK_CK440")
		)
		(pad "2" smd circle
			(at -0.40005 0 270)
			(size 0 0)
			(layers "B.Cu" "B.Mask" "B.Paste")
			(net "GND")
		)
	)
	(footprint ""
		(layer "B.Cu")
		(at 177.423826 -193.794634 180)
		(property "Reference" "R1031"
			(at 0 0 0)
			(layer "B.SilkS")
			(hide yes)
			(effects
				(font
					(size 1.27 1.27)
				)
				(justify mirror)
			)
		)
		(property "Value" ""
			(at 0 0 0)
			(layer "B.Fab")
			(effects
				(font
					(size 1.27 1.27)
				)
				(justify mirror)
			)
		)
		(duplicate_pad_numbers_are_jumpers no)
		(fp_line
			(start 0.7874 0.4064)
			(end 0.7874 -0.4064)
			(stroke
				(width 0.1524)
				(type default)
			)
			(layer "B.SilkS")
		)
		(fp_line
			(start 0.7874 -0.4064)
			(end -0.7874 -0.4064)
			(stroke
				(width 0.1524)
				(type default)
			)
			(layer "B.SilkS")
		)
		(fp_line
			(start -0.7874 0.4064)
			(end 0.7874 0.4064)
			(stroke
				(width 0.1524)
				(type default)
			)
			(layer "B.SilkS")
		)
		(fp_line
			(start -0.7874 -0.4064)
			(end -0.7874 0.4064)
			(stroke
				(width 0.1524)
				(type default)
			)
			(layer "B.SilkS")
		)
		(fp_line
			(start 0.67945 0.3048)
			(end 0.67945 -0.305054)
			(stroke
				(width 0.1)
				(type default)
			)
			(layer "B.Fab")
		)
		(fp_line
			(start 0.67945 -0.305054)
			(end 0.12065 -0.305054)
			(stroke
				(width 0.1)
				(type default)
			)
			(layer "B.Fab")
		)
		(fp_line
			(start 0.12065 0.3048)
			(end 0.67945 0.3048)
			(stroke
				(width 0.1)
				(type default)
			)
			(layer "B.Fab")
		)
		(fp_line
			(start 0.12065 0.2794)
			(end 0.12065 0.3048)
			(stroke
				(width 0.1)
				(type default)
			)
			(layer "B.Fab")
		)
		(fp_line
			(start 0.12065 -0.2794)
			(end -0.12065 -0.2794)
			(stroke
				(width 0.1)
				(type default)
			)
			(layer "B.Fab")
		)
		(fp_line
			(start 0.12065 -0.305054)
			(end 0.12065 -0.2794)
			(stroke
				(width 0.1)
				(type default)
			)
			(layer "B.Fab")
		)
		(fp_line
			(start -0.120396 0.3048)
			(end -0.120396 0.2794)
			(stroke
				(width 0.1)
				(type default)
			)
			(layer "B.Fab")
		)
		(fp_line
			(start -0.120396 0.2794)
			(end 0.12065 0.2794)
			(stroke
				(width 0.1)
				(type default)
			)
			(layer "B.Fab")
		)
		(fp_line
			(start -0.12065 -0.2794)
			(end -0.12065 -0.3048)
			(stroke
				(width 0.1)
				(type default)
			)
			(layer "B.Fab")
		)
		(fp_line
			(start -0.12065 -0.3048)
			(end -0.67945 -0.3048)
			(stroke
				(width 0.1)
				(type default)
			)
			(layer "B.Fab")
		)
		(fp_line
			(start -0.67945 0.3048)
			(end -0.120396 0.3048)
			(stroke
				(width 0.1)
				(type default)
			)
			(layer "B.Fab")
		)
		(fp_line
			(start -0.67945 -0.3048)
			(end -0.67945 0.3048)
			(stroke
				(width 0.1)
				(type default)
			)
			(layer "B.Fab")
		)
		(pad "1" smd circle
			(at 0.40005 0)
			(size 0 0)
			(layers "B.Cu" "B.Mask" "B.Paste")
			(net "SPI_BIC1_MOSI_LS01_DIR3")
		)
		(pad "2" smd circle
			(at -0.40005 0)
			(size 0 0)
			(layers "B.Cu" "B.Mask" "B.Paste")
			(net "P1V8_PEX")
		)
	)
	(footprint ""
		(layer "B.Cu")
		(at 177.649886 -290.199826 90)
		(property "Reference" "C1480"
			(at 0 0 90)
			(layer "B.SilkS")
			(hide yes)
			(effects
				(font
					(size 1.27 1.27)
				)
				(justify mirror)
			)
		)
		(property "Value" ""
			(at 0 0 90)
			(layer "B.Fab")
			(effects
				(font
					(size 1.27 1.27)
				)
				(justify mirror)
			)
		)
		(duplicate_pad_numbers_are_jumpers no)
		(fp_line
			(start 0.299974 -0.150114)
			(end -0.299974 -0.150114)
			(stroke
				(width 0.1)
				(type default)
			)
			(layer "B.Fab")
		)
		(fp_line
			(start -0.299974 -0.150114)
			(end -0.299974 0.150114)
			(stroke
				(width 0.1)
				(type default)
			)
			(layer "B.Fab")
		)
		(fp_line
			(start 0.299974 0.150114)
			(end 0.299974 -0.150114)
			(stroke
				(width 0.1)
				(type default)
			)
			(layer "B.Fab")
		)
		(fp_line
			(start -0.299974 0.150114)
			(end 0.299974 0.150114)
			(stroke
				(width 0.1)
				(type default)
			)
			(layer "B.Fab")
		)
		(pad "1" smd rect
			(at 0.2667 0 270)
			(size 0.3048 0.381)
			(layers "B.Cu" "B.Mask" "B.Paste")
			(net "P0V8_SERDES_VDDA_PEX1")
		)
		(pad "2" smd rect
			(at -0.2667 0 270)
			(size 0.3048 0.381)
			(layers "B.Cu" "B.Mask" "B.Paste")
			(net "GND")
		)
	)
	(footprint ""
		(layer "B.Cu")
		(at 99.130358 -353.718114)
		(property "Reference" "C4180"
			(at 0 0 0)
			(layer "B.SilkS")
			(hide yes)
			(effects
				(font
					(size 1.27 1.27)
				)
				(justify mirror)
			)
		)
		(property "Value" ""
			(at 0 0 0)
			(layer "B.Fab")
			(effects
				(font
					(size 1.27 1.27)
				)
				(justify mirror)
			)
		)
		(duplicate_pad_numbers_are_jumpers no)
		(fp_line
			(start -0.7874 -0.4064)
			(end -0.7874 0.4064)
			(stroke
				(width 0.1524)
				(type default)
			)
			(layer "B.SilkS")
		)
		(fp_line
			(start -0.7874 0.4064)
			(end 0.7874 0.4064)
			(stroke
				(width 0.1524)
				(type default)
			)
			(layer "B.SilkS")
		)
		(fp_line
			(start 0.7874 -0.4064)
			(end -0.7874 -0.4064)
			(stroke
				(width 0.1524)
				(type default)
			)
			(layer "B.SilkS")
		)
		(fp_line
			(start 0.7874 0.4064)
			(end 0.7874 -0.4064)
			(stroke
				(width 0.1524)
				(type default)
			)
			(layer "B.SilkS")
		)
		(fp_line
			(start -0.67945 -0.3048)
			(end -0.67945 0.3048)
			(stroke
				(width 0.1)
				(type default)
			)
			(layer "B.Fab")
		)
		(fp_line
			(start -0.67945 0.3048)
			(end -0.120396 0.3048)
			(stroke
				(width 0.1)
				(type default)
			)
			(layer "B.Fab")
		)
		(fp_line
			(start -0.12065 -0.3048)
			(end -0.67945 -0.3048)
			(stroke
				(width 0.1)
				(type default)
			)
			(layer "B.Fab")
		)
		(fp_line
			(start -0.12065 -0.2794)
			(end -0.12065 -0.3048)
			(stroke
				(width 0.1)
				(type default)
			)
			(layer "B.Fab")
		)
		(fp_line
			(start -0.120396 0.2794)
			(end 0.12065 0.2794)
			(stroke
				(width 0.1)
				(type default)
			)
			(layer "B.Fab")
		)
		(fp_line
			(start -0.120396 0.3048)
			(end -0.120396 0.2794)
			(stroke
				(width 0.1)
				(type default)
			)
			(layer "B.Fab")
		)
		(fp_line
			(start 0.12065 -0.305054)
			(end 0.12065 -0.2794)
			(stroke
				(width 0.1)
				(type default)
			)
			(layer "B.Fab")
		)
		(fp_line
			(start 0.12065 -0.2794)
			(end -0.12065 -0.2794)
			(stroke
				(width 0.1)
				(type default)
			)
			(layer "B.Fab")
		)
		(fp_line
			(start 0.12065 0.2794)
			(end 0.12065 0.3048)
			(stroke
				(width 0.1)
				(type default)
			)
			(layer "B.Fab")
		)
		(fp_line
			(start 0.12065 0.3048)
			(end 0.67945 0.3048)
			(stroke
				(width 0.1)
				(type default)
			)
			(layer "B.Fab")
		)
		(fp_line
			(start 0.67945 -0.305054)
			(end 0.12065 -0.305054)
			(stroke
				(width 0.1)
				(type default)
			)
			(layer "B.Fab")
		)
		(fp_line
			(start 0.67945 0.3048)
			(end 0.67945 -0.305054)
			(stroke
				(width 0.1)
				(type default)
			)
			(layer "B.Fab")
		)
		(pad "1" smd circle
			(at 0.40005 0 180)
			(size 0 0)
			(layers "B.Cu" "B.Mask" "B.Paste")
			(net "P3V3_CLK_BUFFER_9ZXL0451E_S3_VZX3P3")
		)
		(pad "2" smd circle
			(at -0.40005 0 180)
			(size 0 0)
			(layers "B.Cu" "B.Mask" "B.Paste")
			(net "GND")
		)
	)
	(footprint ""
		(layer "B.Cu")
		(at 211.244942 -259.311648 90)
		(property "Reference" "R6349"
			(at 0 0 90)
			(layer "B.SilkS")
			(hide yes)
			(effects
				(font
					(size 1.27 1.27)
				)
				(justify mirror)
			)
		)
		(property "Value" ""
			(at 0 0 90)
			(layer "B.Fab")
			(effects
				(font
					(size 1.27 1.27)
				)
				(justify mirror)
			)
		)
		(duplicate_pad_numbers_are_jumpers no)
		(fp_line
			(start 0.7874 -0.4064)
			(end -0.7874 -0.4064)
			(stroke
				(width 0.1524)
				(type default)
			)
			(layer "B.SilkS")
		)
		(fp_line
			(start -0.7874 -0.4064)
			(end -0.7874 0.4064)
			(stroke
				(width 0.1524)
				(type default)
			)
			(layer "B.SilkS")
		)
		(fp_line
			(start 0.7874 0.4064)
			(end 0.7874 -0.4064)
			(stroke
				(width 0.1524)
				(type default)
			)
			(layer "B.SilkS")
		)
		(fp_line
			(start -0.7874 0.4064)
			(end 0.7874 0.4064)
			(stroke
				(width 0.1524)
				(type default)
			)
			(layer "B.SilkS")
		)
		(fp_line
			(start 0.67945 -0.305054)
			(end 0.12065 -0.305054)
			(stroke
				(width 0.1)
				(type default)
			)
			(layer "B.Fab")
		)
		(fp_line
			(start 0.12065 -0.305054)
			(end 0.12065 -0.2794)
			(stroke
				(width 0.1)
				(type default)
			)
			(layer "B.Fab")
		)
		(fp_line
			(start -0.12065 -0.3048)
			(end -0.67945 -0.3048)
			(stroke
				(width 0.1)
				(type default)
			)
			(layer "B.Fab")
		)
		(fp_line
			(start -0.67945 -0.3048)
			(end -0.67945 0.3048)
			(stroke
				(width 0.1)
				(type default)
			)
			(layer "B.Fab")
		)
		(fp_line
			(start 0.12065 -0.2794)
			(end -0.12065 -0.2794)
			(stroke
				(width 0.1)
				(type default)
			)
			(layer "B.Fab")
		)
		(fp_line
			(start -0.12065 -0.2794)
			(end -0.12065 -0.3048)
			(stroke
				(width 0.1)
				(type default)
			)
			(layer "B.Fab")
		)
		(fp_line
			(start 0.12065 0.2794)
			(end 0.12065 0.3048)
			(stroke
				(width 0.1)
				(type default)
			)
			(layer "B.Fab")
		)
		(fp_line
			(start -0.120396 0.2794)
			(end 0.12065 0.2794)
			(stroke
				(width 0.1)
				(type default)
			)
			(layer "B.Fab")
		)
		(fp_line
			(start 0.67945 0.3048)
			(end 0.67945 -0.305054)
			(stroke
				(width 0.1)
				(type default)
			)
			(layer "B.Fab")
		)
		(fp_line
			(start 0.12065 0.3048)
			(end 0.67945 0.3048)
			(stroke
				(width 0.1)
				(type default)
			)
			(layer "B.Fab")
		)
		(fp_line
			(start -0.120396 0.3048)
			(end -0.120396 0.2794)
			(stroke
				(width 0.1)
				(type default)
			)
			(layer "B.Fab")
		)
		(fp_line
			(start -0.67945 0.3048)
			(end -0.120396 0.3048)
			(stroke
				(width 0.1)
				(type default)
			)
			(layer "B.Fab")
		)
		(pad "1" smd circle
			(at 0.40005 0 270)
			(size 0 0)
			(layers "B.Cu" "B.Mask" "B.Paste")
			(net "P1V8_PEX")
		)
		(pad "2" smd circle
			(at -0.40005 0 270)
			(size 0 0)
			(layers "B.Cu" "B.Mask" "B.Paste")
			(net "SMB_PEX3_MUX_SCL")
		)
	)
	(footprint ""
		(layer "B.Cu")
		(at 185.250074 -296.37482 180)
		(property "Reference" "C1419"
			(at 0 0 0)
			(layer "B.SilkS")
			(hide yes)
			(effects
				(font
					(size 1.27 1.27)
				)
				(justify mirror)
			)
		)
		(property "Value" ""
			(at 0 0 0)
			(layer "B.Fab")
			(effects
				(font
					(size 1.27 1.27)
				)
				(justify mirror)
			)
		)
		(duplicate_pad_numbers_are_jumpers no)
		(fp_line
			(start 0.299974 0.150114)
			(end 0.299974 -0.150114)
			(stroke
				(width 0.1)
				(type default)
			)
			(layer "B.Fab")
		)
		(fp_line
			(start 0.299974 -0.150114)
			(end -0.299974 -0.150114)
			(stroke
				(width 0.1)
				(type default)
			)
			(layer "B.Fab")
		)
		(fp_line
			(start -0.299974 0.150114)
			(end 0.299974 0.150114)
			(stroke
				(width 0.1)
				(type default)
			)
			(layer "B.Fab")
		)
		(fp_line
			(start -0.299974 -0.150114)
			(end -0.299974 0.150114)
			(stroke
				(width 0.1)
				(type default)
			)
			(layer "B.Fab")
		)
		(pad "1" smd rect
			(at 0.2667 0)
			(size 0.3048 0.381)
			(layers "B.Cu" "B.Mask" "B.Paste")
			(net "P0V8_SERDES_VDDA_PEX1")
		)
		(pad "2" smd rect
			(at -0.2667 0)
			(size 0.3048 0.381)
			(layers "B.Cu" "B.Mask" "B.Paste")
			(net "GND")
		)
	)
	(footprint ""
		(layer "B.Cu")
		(at 14.830298 -228.981)
		(property "Reference" "R3437"
			(at 0 0 0)
			(layer "B.SilkS")
			(hide yes)
			(effects
				(font
					(size 1.27 1.27)
				)
				(justify mirror)
			)
		)
		(property "Value" ""
			(at 0 0 0)
			(layer "B.Fab")
			(effects
				(font
					(size 1.27 1.27)
				)
				(justify mirror)
			)
		)
		(duplicate_pad_numbers_are_jumpers no)
		(fp_line
			(start -0.7874 -0.4064)
			(end -0.7874 0.4064)
			(stroke
				(width 0.1524)
				(type default)
			)
			(layer "B.SilkS")
		)
		(fp_line
			(start -0.7874 0.4064)
			(end 0.7874 0.4064)
			(stroke
				(width 0.1524)
				(type default)
			)
			(layer "B.SilkS")
		)
		(fp_line
			(start 0.7874 -0.4064)
			(end -0.7874 -0.4064)
			(stroke
				(width 0.1524)
				(type default)
			)
			(layer "B.SilkS")
		)
		(fp_line
			(start 0.7874 0.4064)
			(end 0.7874 -0.4064)
			(stroke
				(width 0.1524)
				(type default)
			)
			(layer "B.SilkS")
		)
		(fp_line
			(start -0.67945 -0.3048)
			(end -0.67945 0.3048)
			(stroke
				(width 0.1)
				(type default)
			)
			(layer "B.Fab")
		)
		(fp_line
			(start -0.67945 0.3048)
			(end -0.120396 0.3048)
			(stroke
				(width 0.1)
				(type default)
			)
			(layer "B.Fab")
		)
		(fp_line
			(start -0.12065 -0.3048)
			(end -0.67945 -0.3048)
			(stroke
				(width 0.1)
				(type default)
			)
			(layer "B.Fab")
		)
		(fp_line
			(start -0.12065 -0.2794)
			(end -0.12065 -0.3048)
			(stroke
				(width 0.1)
				(type default)
			)
			(layer "B.Fab")
		)
		(fp_line
			(start -0.120396 0.2794)
			(end 0.12065 0.2794)
			(stroke
				(width 0.1)
				(type default)
			)
			(layer "B.Fab")
		)
		(fp_line
			(start -0.120396 0.3048)
			(end -0.120396 0.2794)
			(stroke
				(width 0.1)
				(type default)
			)
			(layer "B.Fab")
		)
		(fp_line
			(start 0.12065 -0.305054)
			(end 0.12065 -0.2794)
			(stroke
				(width 0.1)
				(type default)
			)
			(layer "B.Fab")
		)
		(fp_line
			(start 0.12065 -0.2794)
			(end -0.12065 -0.2794)
			(stroke
				(width 0.1)
				(type default)
			)
			(layer "B.Fab")
		)
		(fp_line
			(start 0.12065 0.2794)
			(end 0.12065 0.3048)
			(stroke
				(width 0.1)
				(type default)
			)
			(layer "B.Fab")
		)
		(fp_line
			(start 0.12065 0.3048)
			(end 0.67945 0.3048)
			(stroke
				(width 0.1)
				(type default)
			)
			(layer "B.Fab")
		)
		(fp_line
			(start 0.67945 -0.305054)
			(end 0.12065 -0.305054)
			(stroke
				(width 0.1)
				(type default)
			)
			(layer "B.Fab")
		)
		(fp_line
			(start 0.67945 0.3048)
			(end 0.67945 -0.305054)
			(stroke
				(width 0.1)
				(type default)
			)
			(layer "B.Fab")
		)
		(pad "1" smd circle
			(at 0.40005 0 180)
			(size 0 0)
			(layers "B.Cu" "B.Mask" "B.Paste")
			(net "P1V8_PEX")
		)
		(pad "2" smd circle
			(at -0.40005 0 180)
			(size 0 0)
			(layers "B.Cu" "B.Mask" "B.Paste")
			(net "SPI_PEX0_SDIO2_R1")
		)
	)
	(footprint ""
		(layer "B.Cu")
		(at 284.724856 -297.79976 -90)
		(property "Reference" "C1647"
			(at 0 0 90)
			(layer "B.SilkS")
			(hide yes)
			(effects
				(font
					(size 1.27 1.27)
				)
				(justify mirror)
			)
		)
		(property "Value" ""
			(at 0 0 90)
			(layer "B.Fab")
			(effects
				(font
					(size 1.27 1.27)
				)
				(justify mirror)
			)
		)
		(duplicate_pad_numbers_are_jumpers no)
		(fp_line
			(start -0.299974 0.150114)
			(end 0.299974 0.150114)
			(stroke
				(width 0.1)
				(type default)
			)
			(layer "B.Fab")
		)
		(fp_line
			(start 0.299974 0.150114)
			(end 0.299974 -0.150114)
			(stroke
				(width 0.1)
				(type default)
			)
			(layer "B.Fab")
		)
		(fp_line
			(start -0.299974 -0.150114)
			(end -0.299974 0.150114)
			(stroke
				(width 0.1)
				(type default)
			)
			(layer "B.Fab")
		)
		(fp_line
			(start 0.299974 -0.150114)
			(end -0.299974 -0.150114)
			(stroke
				(width 0.1)
				(type default)
			)
			(layer "B.Fab")
		)
		(pad "1" smd rect
			(at 0.2667 0 90)
			(size 0.3048 0.381)
			(layers "B.Cu" "B.Mask" "B.Paste")
			(net "P0V8_PEX2")
		)
		(pad "2" smd rect
			(at -0.2667 0 90)
			(size 0.3048 0.381)
			(layers "B.Cu" "B.Mask" "B.Paste")
			(net "GND")
		)
	)
	(footprint ""
		(layer "B.Cu")
		(at 411.275022 -297.79976 -90)
		(property "Reference" "C1901"
			(at 0 0 90)
			(layer "B.SilkS")
			(hide yes)
			(effects
				(font
					(size 1.27 1.27)
				)
				(justify mirror)
			)
		)
		(property "Value" ""
			(at 0 0 90)
			(layer "B.Fab")
			(effects
				(font
					(size 1.27 1.27)
				)
				(justify mirror)
			)
		)
		(duplicate_pad_numbers_are_jumpers no)
		(fp_line
			(start -0.299974 0.150114)
			(end 0.299974 0.150114)
			(stroke
				(width 0.1)
				(type default)
			)
			(layer "B.Fab")
		)
		(fp_line
			(start 0.299974 0.150114)
			(end 0.299974 -0.150114)
			(stroke
				(width 0.1)
				(type default)
			)
			(layer "B.Fab")
		)
		(fp_line
			(start -0.299974 -0.150114)
			(end -0.299974 0.150114)
			(stroke
				(width 0.1)
				(type default)
			)
			(layer "B.Fab")
		)
		(fp_line
			(start 0.299974 -0.150114)
			(end -0.299974 -0.150114)
			(stroke
				(width 0.1)
				(type default)
			)
			(layer "B.Fab")
		)
		(pad "1" smd rect
			(at 0.2667 0 90)
			(size 0.3048 0.381)
			(layers "B.Cu" "B.Mask" "B.Paste")
			(net "P0V8_PEX3")
		)
		(pad "2" smd rect
			(at -0.2667 0 90)
			(size 0.3048 0.381)
			(layers "B.Cu" "B.Mask" "B.Paste")
			(net "GND")
		)
	)
	(footprint ""
		(layer "B.Cu")
		(at 60.599828 -288.299906 90)
		(property "Reference" "C2921"
			(at 0 0 90)
			(layer "B.SilkS")
			(hide yes)
			(effects
				(font
					(size 1.27 1.27)
				)
				(justify mirror)
			)
		)
		(property "Value" ""
			(at 0 0 90)
			(layer "B.Fab")
			(effects
				(font
					(size 1.27 1.27)
				)
				(justify mirror)
			)
		)
		(duplicate_pad_numbers_are_jumpers no)
		(fp_line
			(start 0.299974 -0.150114)
			(end -0.299974 -0.150114)
			(stroke
				(width 0.1)
				(type default)
			)
			(layer "B.Fab")
		)
		(fp_line
			(start -0.299974 -0.150114)
			(end -0.299974 0.150114)
			(stroke
				(width 0.1)
				(type default)
			)
			(layer "B.Fab")
		)
		(fp_line
			(start 0.299974 0.150114)
			(end 0.299974 -0.150114)
			(stroke
				(width 0.1)
				(type default)
			)
			(layer "B.Fab")
		)
		(fp_line
			(start -0.299974 0.150114)
			(end 0.299974 0.150114)
			(stroke
				(width 0.1)
				(type default)
			)
			(layer "B.Fab")
		)
		(pad "1" smd rect
			(at 0.2667 0 270)
			(size 0.3048 0.381)
			(layers "B.Cu" "B.Mask" "B.Paste")
			(net "P1V25_PEX0")
		)
		(pad "2" smd rect
			(at -0.2667 0 270)
			(size 0.3048 0.381)
			(layers "B.Cu" "B.Mask" "B.Paste")
			(net "GND")
		)
	)
	(footprint ""
		(layer "B.Cu")
		(at 297.549824 -303.499774 -90)
		(property "Reference" "C3250"
			(at 0 0 90)
			(layer "B.SilkS")
			(hide yes)
			(effects
				(font
					(size 1.27 1.27)
				)
				(justify mirror)
			)
		)
		(property "Value" ""
			(at 0 0 90)
			(layer "B.Fab")
			(effects
				(font
					(size 1.27 1.27)
				)
				(justify mirror)
			)
		)
		(duplicate_pad_numbers_are_jumpers no)
		(fp_line
			(start -0.299974 0.150114)
			(end 0.299974 0.150114)
			(stroke
				(width 0.1)
				(type default)
			)
			(layer "B.Fab")
		)
		(fp_line
			(start 0.299974 0.150114)
			(end 0.299974 -0.150114)
			(stroke
				(width 0.1)
				(type default)
			)
			(layer "B.Fab")
		)
		(fp_line
			(start -0.299974 -0.150114)
			(end -0.299974 0.150114)
			(stroke
				(width 0.1)
				(type default)
			)
			(layer "B.Fab")
		)
		(fp_line
			(start 0.299974 -0.150114)
			(end -0.299974 -0.150114)
			(stroke
				(width 0.1)
				(type default)
			)
			(layer "B.Fab")
		)
		(pad "1" smd rect
			(at 0.2667 0 90)
			(size 0.3048 0.381)
			(layers "B.Cu" "B.Mask" "B.Paste")
			(net "P1V25_PEX2")
		)
		(pad "2" smd rect
			(at -0.2667 0 90)
			(size 0.3048 0.381)
			(layers "B.Cu" "B.Mask" "B.Paste")
			(net "GND")
		)
	)
	(footprint ""
		(layer "B.Cu")
		(at 417.450016 -301.124874)
		(property "Reference" "C3515"
			(at 0 0 0)
			(layer "B.SilkS")
			(hide yes)
			(effects
				(font
					(size 1.27 1.27)
				)
				(justify mirror)
			)
		)
		(property "Value" ""
			(at 0 0 0)
			(layer "B.Fab")
			(effects
				(font
					(size 1.27 1.27)
				)
				(justify mirror)
			)
		)
		(duplicate_pad_numbers_are_jumpers no)
		(fp_line
			(start -0.299974 -0.150114)
			(end -0.299974 0.150114)
			(stroke
				(width 0.1)
				(type default)
			)
			(layer "B.Fab")
		)
		(fp_line
			(start -0.299974 0.150114)
			(end 0.299974 0.150114)
			(stroke
				(width 0.1)
				(type default)
			)
			(layer "B.Fab")
		)
		(fp_line
			(start 0.299974 -0.150114)
			(end -0.299974 -0.150114)
			(stroke
				(width 0.1)
				(type default)
			)
			(layer "B.Fab")
		)
		(fp_line
			(start 0.299974 0.150114)
			(end 0.299974 -0.150114)
			(stroke
				(width 0.1)
				(type default)
			)
			(layer "B.Fab")
		)
		(pad "1" smd rect
			(at 0.2667 0 180)
			(size 0.3048 0.381)
			(layers "B.Cu" "B.Mask" "B.Paste")
			(net "P1V8_PEX")
		)
		(pad "2" smd rect
			(at -0.2667 0 180)
			(size 0.3048 0.381)
			(layers "B.Cu" "B.Mask" "B.Paste")
			(net "GND")
		)
	)
	(footprint ""
		(layer "B.Cu")
		(at 252.011434 -355.160834 180)
		(property "Reference" "PR7164"
			(at 0 0 0)
			(layer "B.SilkS")
			(hide yes)
			(effects
				(font
					(size 1.27 1.27)
				)
				(justify mirror)
			)
		)
		(property "Value" ""
			(at 0 0 0)
			(layer "B.Fab")
			(effects
				(font
					(size 1.27 1.27)
				)
				(justify mirror)
			)
		)
		(duplicate_pad_numbers_are_jumpers no)
		(fp_line
			(start 0.7874 0.4064)
			(end 0.7874 -0.4064)
			(stroke
				(width 0.1524)
				(type default)
			)
			(layer "B.SilkS")
		)
		(fp_line
			(start 0.7874 -0.4064)
			(end -0.7874 -0.4064)
			(stroke
				(width 0.1524)
				(type default)
			)
			(layer "B.SilkS")
		)
		(fp_line
			(start -0.7874 0.4064)
			(end 0.7874 0.4064)
			(stroke
				(width 0.1524)
				(type default)
			)
			(layer "B.SilkS")
		)
		(fp_line
			(start -0.7874 -0.4064)
			(end -0.7874 0.4064)
			(stroke
				(width 0.1524)
				(type default)
			)
			(layer "B.SilkS")
		)
		(fp_line
			(start 0.67945 0.3048)
			(end 0.67945 -0.305054)
			(stroke
				(width 0.1)
				(type default)
			)
			(layer "B.Fab")
		)
		(fp_line
			(start 0.67945 -0.305054)
			(end 0.12065 -0.305054)
			(stroke
				(width 0.1)
				(type default)
			)
			(layer "B.Fab")
		)
		(fp_line
			(start 0.12065 0.3048)
			(end 0.67945 0.3048)
			(stroke
				(width 0.1)
				(type default)
			)
			(layer "B.Fab")
		)
		(fp_line
			(start 0.12065 0.2794)
			(end 0.12065 0.3048)
			(stroke
				(width 0.1)
				(type default)
			)
			(layer "B.Fab")
		)
		(fp_line
			(start 0.12065 -0.2794)
			(end -0.12065 -0.2794)
			(stroke
				(width 0.1)
				(type default)
			)
			(layer "B.Fab")
		)
		(fp_line
			(start 0.12065 -0.305054)
			(end 0.12065 -0.2794)
			(stroke
				(width 0.1)
				(type default)
			)
			(layer "B.Fab")
		)
		(fp_line
			(start -0.120396 0.3048)
			(end -0.120396 0.2794)
			(stroke
				(width 0.1)
				(type default)
			)
			(layer "B.Fab")
		)
		(fp_line
			(start -0.120396 0.2794)
			(end 0.12065 0.2794)
			(stroke
				(width 0.1)
				(type default)
			)
			(layer "B.Fab")
		)
		(fp_line
			(start -0.12065 -0.2794)
			(end -0.12065 -0.3048)
			(stroke
				(width 0.1)
				(type default)
			)
			(layer "B.Fab")
		)
		(fp_line
			(start -0.12065 -0.3048)
			(end -0.67945 -0.3048)
			(stroke
				(width 0.1)
				(type default)
			)
			(layer "B.Fab")
		)
		(fp_line
			(start -0.67945 0.3048)
			(end -0.120396 0.3048)
			(stroke
				(width 0.1)
				(type default)
			)
			(layer "B.Fab")
		)
		(fp_line
			(start -0.67945 -0.3048)
			(end -0.67945 0.3048)
			(stroke
				(width 0.1)
				(type default)
			)
			(layer "B.Fab")
		)
		(pad "1" smd circle
			(at 0.40005 0)
			(size 0 0)
			(layers "B.Cu" "B.Mask" "B.Paste")
			(net "IRQ_SML1_PMBUS_ALERT_N")
		)
		(pad "2" smd circle
			(at -0.40005 0)
			(size 0 0)
			(layers "B.Cu" "B.Mask" "B.Paste")
			(net "HSC_ALERT1_R_N")
		)
	)
	(footprint ""
		(layer "B.Cu")
		(at 131.52374 -282.263088 180)
		(property "Reference" "PR7169"
			(at 0 0 0)
			(layer "B.SilkS")
			(hide yes)
			(effects
				(font
					(size 1.27 1.27)
				)
				(justify mirror)
			)
		)
		(property "Value" ""
			(at 0 0 0)
			(layer "B.Fab")
			(effects
				(font
					(size 1.27 1.27)
				)
				(justify mirror)
			)
		)
		(duplicate_pad_numbers_are_jumpers no)
		(fp_line
			(start 0.7874 0.4064)
			(end 0.7874 -0.4064)
			(stroke
				(width 0.1524)
				(type default)
			)
			(layer "B.SilkS")
		)
		(fp_line
			(start 0.7874 -0.4064)
			(end -0.7874 -0.4064)
			(stroke
				(width 0.1524)
				(type default)
			)
			(layer "B.SilkS")
		)
		(fp_line
			(start -0.7874 0.4064)
			(end 0.7874 0.4064)
			(stroke
				(width 0.1524)
				(type default)
			)
			(layer "B.SilkS")
		)
		(fp_line
			(start -0.7874 -0.4064)
			(end -0.7874 0.4064)
			(stroke
				(width 0.1524)
				(type default)
			)
			(layer "B.SilkS")
		)
		(fp_line
			(start 0.67945 0.3048)
			(end 0.67945 -0.305054)
			(stroke
				(width 0.1)
				(type default)
			)
			(layer "B.Fab")
		)
		(fp_line
			(start 0.67945 -0.305054)
			(end 0.12065 -0.305054)
			(stroke
				(width 0.1)
				(type default)
			)
			(layer "B.Fab")
		)
		(fp_line
			(start 0.12065 0.3048)
			(end 0.67945 0.3048)
			(stroke
				(width 0.1)
				(type default)
			)
			(layer "B.Fab")
		)
		(fp_line
			(start 0.12065 0.2794)
			(end 0.12065 0.3048)
			(stroke
				(width 0.1)
				(type default)
			)
			(layer "B.Fab")
		)
		(fp_line
			(start 0.12065 -0.2794)
			(end -0.12065 -0.2794)
			(stroke
				(width 0.1)
				(type default)
			)
			(layer "B.Fab")
		)
		(fp_line
			(start 0.12065 -0.305054)
			(end 0.12065 -0.2794)
			(stroke
				(width 0.1)
				(type default)
			)
			(layer "B.Fab")
		)
		(fp_line
			(start -0.120396 0.3048)
			(end -0.120396 0.2794)
			(stroke
				(width 0.1)
				(type default)
			)
			(layer "B.Fab")
		)
		(fp_line
			(start -0.120396 0.2794)
			(end 0.12065 0.2794)
			(stroke
				(width 0.1)
				(type default)
			)
			(layer "B.Fab")
		)
		(fp_line
			(start -0.12065 -0.2794)
			(end -0.12065 -0.3048)
			(stroke
				(width 0.1)
				(type default)
			)
			(layer "B.Fab")
		)
		(fp_line
			(start -0.12065 -0.3048)
			(end -0.67945 -0.3048)
			(stroke
				(width 0.1)
				(type default)
			)
			(layer "B.Fab")
		)
		(fp_line
			(start -0.67945 0.3048)
			(end -0.120396 0.3048)
			(stroke
				(width 0.1)
				(type default)
			)
			(layer "B.Fab")
		)
		(fp_line
			(start -0.67945 -0.3048)
			(end -0.67945 0.3048)
			(stroke
				(width 0.1)
				(type default)
			)
			(layer "B.Fab")
		)
		(pad "1" smd circle
			(at 0.40005 0)
			(size 0 0)
			(layers "B.Cu" "B.Mask" "B.Paste")
			(net "P0V8_PEX0_EN4")
		)
		(pad "2" smd circle
			(at -0.40005 0)
			(size 0 0)
			(layers "B.Cu" "B.Mask" "B.Paste")
			(net "P0V8_PEX1_VCC2")
		)
	)
	(footprint ""
		(layer "B.Cu")
		(at 355.165406 -260.469126 90)
		(property "Reference" "PR7138"
			(at 0 0 90)
			(layer "B.SilkS")
			(hide yes)
			(effects
				(font
					(size 1.27 1.27)
				)
				(justify mirror)
			)
		)
		(property "Value" ""
			(at 0 0 90)
			(layer "B.Fab")
			(effects
				(font
					(size 1.27 1.27)
				)
				(justify mirror)
			)
		)
		(duplicate_pad_numbers_are_jumpers no)
		(fp_line
			(start 0.7874 -0.4064)
			(end -0.7874 -0.4064)
			(stroke
				(width 0.1524)
				(type default)
			)
			(layer "B.SilkS")
		)
		(fp_line
			(start -0.7874 -0.4064)
			(end -0.7874 0.4064)
			(stroke
				(width 0.1524)
				(type default)
			)
			(layer "B.SilkS")
		)
		(fp_line
			(start 0.7874 0.4064)
			(end 0.7874 -0.4064)
			(stroke
				(width 0.1524)
				(type default)
			)
			(layer "B.SilkS")
		)
		(fp_line
			(start -0.7874 0.4064)
			(end 0.7874 0.4064)
			(stroke
				(width 0.1524)
				(type default)
			)
			(layer "B.SilkS")
		)
		(fp_line
			(start 0.67945 -0.305054)
			(end 0.12065 -0.305054)
			(stroke
				(width 0.1)
				(type default)
			)
			(layer "B.Fab")
		)
		(fp_line
			(start 0.12065 -0.305054)
			(end 0.12065 -0.2794)
			(stroke
				(width 0.1)
				(type default)
			)
			(layer "B.Fab")
		)
		(fp_line
			(start -0.12065 -0.3048)
			(end -0.67945 -0.3048)
			(stroke
				(width 0.1)
				(type default)
			)
			(layer "B.Fab")
		)
		(fp_line
			(start -0.67945 -0.3048)
			(end -0.67945 0.3048)
			(stroke
				(width 0.1)
				(type default)
			)
			(layer "B.Fab")
		)
		(fp_line
			(start 0.12065 -0.2794)
			(end -0.12065 -0.2794)
			(stroke
				(width 0.1)
				(type default)
			)
			(layer "B.Fab")
		)
		(fp_line
			(start -0.12065 -0.2794)
			(end -0.12065 -0.3048)
			(stroke
				(width 0.1)
				(type default)
			)
			(layer "B.Fab")
		)
		(fp_line
			(start 0.12065 0.2794)
			(end 0.12065 0.3048)
			(stroke
				(width 0.1)
				(type default)
			)
			(layer "B.Fab")
		)
		(fp_line
			(start -0.120396 0.2794)
			(end 0.12065 0.2794)
			(stroke
				(width 0.1)
				(type default)
			)
			(layer "B.Fab")
		)
		(fp_line
			(start 0.67945 0.3048)
			(end 0.67945 -0.305054)
			(stroke
				(width 0.1)
				(type default)
			)
			(layer "B.Fab")
		)
		(fp_line
			(start 0.12065 0.3048)
			(end 0.67945 0.3048)
			(stroke
				(width 0.1)
				(type default)
			)
			(layer "B.Fab")
		)
		(fp_line
			(start -0.120396 0.3048)
			(end -0.120396 0.2794)
			(stroke
				(width 0.1)
				(type default)
			)
			(layer "B.Fab")
		)
		(fp_line
			(start -0.67945 0.3048)
			(end -0.120396 0.3048)
			(stroke
				(width 0.1)
				(type default)
			)
			(layer "B.Fab")
		)
		(pad "1" smd circle
			(at 0.40005 0 270)
			(size 0 0)
			(layers "B.Cu" "B.Mask" "B.Paste")
			(net "NC_P0V8_PEX2_ISEN4")
		)
		(pad "2" smd circle
			(at -0.40005 0 270)
			(size 0 0)
			(layers "B.Cu" "B.Mask" "B.Paste")
			(net "GND")
		)
	)
	(footprint ""
		(layer "B.Cu")
		(at 308.02072 -114.35207 90)
		(property "Reference" "C927"
			(at 0 0 90)
			(layer "B.SilkS")
			(hide yes)
			(effects
				(font
					(size 1.27 1.27)
				)
				(justify mirror)
			)
		)
		(property "Value" ""
			(at 0 0 90)
			(layer "B.Fab")
			(effects
				(font
					(size 1.27 1.27)
				)
				(justify mirror)
			)
		)
		(duplicate_pad_numbers_are_jumpers no)
		(fp_line
			(start 0.7874 -0.4064)
			(end -0.7874 -0.4064)
			(stroke
				(width 0.1524)
				(type default)
			)
			(layer "B.SilkS")
		)
		(fp_line
			(start -0.7874 -0.4064)
			(end -0.7874 0.4064)
			(stroke
				(width 0.1524)
				(type default)
			)
			(layer "B.SilkS")
		)
		(fp_line
			(start 0.7874 0.4064)
			(end 0.7874 -0.4064)
			(stroke
				(width 0.1524)
				(type default)
			)
			(layer "B.SilkS")
		)
		(fp_line
			(start -0.7874 0.4064)
			(end 0.7874 0.4064)
			(stroke
				(width 0.1524)
				(type default)
			)
			(layer "B.SilkS")
		)
		(fp_line
			(start 0.67945 -0.305054)
			(end 0.12065 -0.305054)
			(stroke
				(width 0.1)
				(type default)
			)
			(layer "B.Fab")
		)
		(fp_line
			(start 0.12065 -0.305054)
			(end 0.12065 -0.2794)
			(stroke
				(width 0.1)
				(type default)
			)
			(layer "B.Fab")
		)
		(fp_line
			(start -0.12065 -0.3048)
			(end -0.67945 -0.3048)
			(stroke
				(width 0.1)
				(type default)
			)
			(layer "B.Fab")
		)
		(fp_line
			(start -0.67945 -0.3048)
			(end -0.67945 0.3048)
			(stroke
				(width 0.1)
				(type default)
			)
			(layer "B.Fab")
		)
		(fp_line
			(start 0.12065 -0.2794)
			(end -0.12065 -0.2794)
			(stroke
				(width 0.1)
				(type default)
			)
			(layer "B.Fab")
		)
		(fp_line
			(start -0.12065 -0.2794)
			(end -0.12065 -0.3048)
			(stroke
				(width 0.1)
				(type default)
			)
			(layer "B.Fab")
		)
		(fp_line
			(start 0.12065 0.2794)
			(end 0.12065 0.3048)
			(stroke
				(width 0.1)
				(type default)
			)
			(layer "B.Fab")
		)
		(fp_line
			(start -0.120396 0.2794)
			(end 0.12065 0.2794)
			(stroke
				(width 0.1)
				(type default)
			)
			(layer "B.Fab")
		)
		(fp_line
			(start 0.67945 0.3048)
			(end 0.67945 -0.305054)
			(stroke
				(width 0.1)
				(type default)
			)
			(layer "B.Fab")
		)
		(fp_line
			(start 0.12065 0.3048)
			(end 0.67945 0.3048)
			(stroke
				(width 0.1)
				(type default)
			)
			(layer "B.Fab")
		)
		(fp_line
			(start -0.120396 0.3048)
			(end -0.120396 0.2794)
			(stroke
				(width 0.1)
				(type default)
			)
			(layer "B.Fab")
		)
		(fp_line
			(start -0.67945 0.3048)
			(end -0.120396 0.3048)
			(stroke
				(width 0.1)
				(type default)
			)
			(layer "B.Fab")
		)
		(pad "1" smd circle
			(at 0.40005 0 270)
			(size 0 0)
			(layers "B.Cu" "B.Mask" "B.Paste")
			(net "P3V3_NIC5")
		)
		(pad "2" smd circle
			(at -0.40005 0 270)
			(size 0 0)
			(layers "B.Cu" "B.Mask" "B.Paste")
			(net "GND")
		)
	)
	(footprint ""
		(layer "B.Cu")
		(at 58.224928 -293.99992 90)
		(property "Reference" "C1155"
			(at 0 0 90)
			(layer "B.SilkS")
			(hide yes)
			(effects
				(font
					(size 1.27 1.27)
				)
				(justify mirror)
			)
		)
		(property "Value" ""
			(at 0 0 90)
			(layer "B.Fab")
			(effects
				(font
					(size 1.27 1.27)
				)
				(justify mirror)
			)
		)
		(duplicate_pad_numbers_are_jumpers no)
		(fp_line
			(start 0.299974 -0.150114)
			(end -0.299974 -0.150114)
			(stroke
				(width 0.1)
				(type default)
			)
			(layer "B.Fab")
		)
		(fp_line
			(start -0.299974 -0.150114)
			(end -0.299974 0.150114)
			(stroke
				(width 0.1)
				(type default)
			)
			(layer "B.Fab")
		)
		(fp_line
			(start 0.299974 0.150114)
			(end 0.299974 -0.150114)
			(stroke
				(width 0.1)
				(type default)
			)
			(layer "B.Fab")
		)
		(fp_line
			(start -0.299974 0.150114)
			(end 0.299974 0.150114)
			(stroke
				(width 0.1)
				(type default)
			)
			(layer "B.Fab")
		)
		(pad "1" smd rect
			(at 0.2667 0 270)
			(size 0.3048 0.381)
			(layers "B.Cu" "B.Mask" "B.Paste")
			(net "P0V8_PEX0")
		)
		(pad "2" smd rect
			(at -0.2667 0 270)
			(size 0.3048 0.381)
			(layers "B.Cu" "B.Mask" "B.Paste")
			(net "GND")
		)
	)
	(footprint ""
		(layer "B.Cu")
		(at 236.540294 -224.060258 90)
		(property "Reference" "R6821"
			(at 0 0 90)
			(layer "B.SilkS")
			(hide yes)
			(effects
				(font
					(size 1.27 1.27)
				)
				(justify mirror)
			)
		)
		(property "Value" ""
			(at 0 0 90)
			(layer "B.Fab")
			(effects
				(font
					(size 1.27 1.27)
				)
				(justify mirror)
			)
		)
		(duplicate_pad_numbers_are_jumpers no)
		(fp_line
			(start 0.7874 -0.4064)
			(end -0.7874 -0.4064)
			(stroke
				(width 0.1524)
				(type default)
			)
			(layer "B.SilkS")
		)
		(fp_line
			(start -0.7874 -0.4064)
			(end -0.7874 0.4064)
			(stroke
				(width 0.1524)
				(type default)
			)
			(layer "B.SilkS")
		)
		(fp_line
			(start 0.7874 0.4064)
			(end 0.7874 -0.4064)
			(stroke
				(width 0.1524)
				(type default)
			)
			(layer "B.SilkS")
		)
		(fp_line
			(start -0.7874 0.4064)
			(end 0.7874 0.4064)
			(stroke
				(width 0.1524)
				(type default)
			)
			(layer "B.SilkS")
		)
		(fp_line
			(start 0.67945 -0.305054)
			(end 0.12065 -0.305054)
			(stroke
				(width 0.1)
				(type default)
			)
			(layer "B.Fab")
		)
		(fp_line
			(start 0.12065 -0.305054)
			(end 0.12065 -0.2794)
			(stroke
				(width 0.1)
				(type default)
			)
			(layer "B.Fab")
		)
		(fp_line
			(start -0.12065 -0.3048)
			(end -0.67945 -0.3048)
			(stroke
				(width 0.1)
				(type default)
			)
			(layer "B.Fab")
		)
		(fp_line
			(start -0.67945 -0.3048)
			(end -0.67945 0.3048)
			(stroke
				(width 0.1)
				(type default)
			)
			(layer "B.Fab")
		)
		(fp_line
			(start 0.12065 -0.2794)
			(end -0.12065 -0.2794)
			(stroke
				(width 0.1)
				(type default)
			)
			(layer "B.Fab")
		)
		(fp_line
			(start -0.12065 -0.2794)
			(end -0.12065 -0.3048)
			(stroke
				(width 0.1)
				(type default)
			)
			(layer "B.Fab")
		)
		(fp_line
			(start 0.12065 0.2794)
			(end 0.12065 0.3048)
			(stroke
				(width 0.1)
				(type default)
			)
			(layer "B.Fab")
		)
		(fp_line
			(start -0.120396 0.2794)
			(end 0.12065 0.2794)
			(stroke
				(width 0.1)
				(type default)
			)
			(layer "B.Fab")
		)
		(fp_line
			(start 0.67945 0.3048)
			(end 0.67945 -0.305054)
			(stroke
				(width 0.1)
				(type default)
			)
			(layer "B.Fab")
		)
		(fp_line
			(start 0.12065 0.3048)
			(end 0.67945 0.3048)
			(stroke
				(width 0.1)
				(type default)
			)
			(layer "B.Fab")
		)
		(fp_line
			(start -0.120396 0.3048)
			(end -0.120396 0.2794)
			(stroke
				(width 0.1)
				(type default)
			)
			(layer "B.Fab")
		)
		(fp_line
			(start -0.67945 0.3048)
			(end -0.120396 0.3048)
			(stroke
				(width 0.1)
				(type default)
			)
			(layer "B.Fab")
		)
		(pad "1" smd circle
			(at 0.40005 0 270)
			(size 0 0)
			(layers "B.Cu" "B.Mask" "B.Paste")
			(net "VR_TYPE_ADC_R")
		)
		(pad "2" smd circle
			(at -0.40005 0 270)
			(size 0 0)
			(layers "B.Cu" "B.Mask" "B.Paste")
			(net "P3V3_AUX")
		)
	)
	(footprint ""
		(layer "B.Cu")
		(at 288.52495 -293.99992 90)
		(property "Reference" "C1621"
			(at 0 0 90)
			(layer "B.SilkS")
			(hide yes)
			(effects
				(font
					(size 1.27 1.27)
				)
				(justify mirror)
			)
		)
		(property "Value" ""
			(at 0 0 90)
			(layer "B.Fab")
			(effects
				(font
					(size 1.27 1.27)
				)
				(justify mirror)
			)
		)
		(duplicate_pad_numbers_are_jumpers no)
		(fp_line
			(start 0.299974 -0.150114)
			(end -0.299974 -0.150114)
			(stroke
				(width 0.1)
				(type default)
			)
			(layer "B.Fab")
		)
		(fp_line
			(start -0.299974 -0.150114)
			(end -0.299974 0.150114)
			(stroke
				(width 0.1)
				(type default)
			)
			(layer "B.Fab")
		)
		(fp_line
			(start 0.299974 0.150114)
			(end 0.299974 -0.150114)
			(stroke
				(width 0.1)
				(type default)
			)
			(layer "B.Fab")
		)
		(fp_line
			(start -0.299974 0.150114)
			(end 0.299974 0.150114)
			(stroke
				(width 0.1)
				(type default)
			)
			(layer "B.Fab")
		)
		(pad "1" smd rect
			(at 0.2667 0 270)
			(size 0.3048 0.381)
			(layers "B.Cu" "B.Mask" "B.Paste")
			(net "P0V8_PEX2")
		)
		(pad "2" smd rect
			(at -0.2667 0 270)
			(size 0.3048 0.381)
			(layers "B.Cu" "B.Mask" "B.Paste")
			(net "GND")
		)
	)
	(footprint ""
		(layer "B.Cu")
		(at 261.904226 -225.76663 180)
		(property "Reference" "R6169"
			(at 0 0 0)
			(layer "B.SilkS")
			(hide yes)
			(effects
				(font
					(size 1.27 1.27)
				)
				(justify mirror)
			)
		)
		(property "Value" ""
			(at 0 0 0)
			(layer "B.Fab")
			(effects
				(font
					(size 1.27 1.27)
				)
				(justify mirror)
			)
		)
		(duplicate_pad_numbers_are_jumpers no)
		(fp_line
			(start 0.7874 0.4064)
			(end 0.7874 -0.4064)
			(stroke
				(width 0.1524)
				(type default)
			)
			(layer "B.SilkS")
		)
		(fp_line
			(start 0.7874 -0.4064)
			(end -0.7874 -0.4064)
			(stroke
				(width 0.1524)
				(type default)
			)
			(layer "B.SilkS")
		)
		(fp_line
			(start -0.7874 0.4064)
			(end 0.7874 0.4064)
			(stroke
				(width 0.1524)
				(type default)
			)
			(layer "B.SilkS")
		)
		(fp_line
			(start -0.7874 -0.4064)
			(end -0.7874 0.4064)
			(stroke
				(width 0.1524)
				(type default)
			)
			(layer "B.SilkS")
		)
		(fp_line
			(start 0.67945 0.3048)
			(end 0.67945 -0.305054)
			(stroke
				(width 0.1)
				(type default)
			)
			(layer "B.Fab")
		)
		(fp_line
			(start 0.67945 -0.305054)
			(end 0.12065 -0.305054)
			(stroke
				(width 0.1)
				(type default)
			)
			(layer "B.Fab")
		)
		(fp_line
			(start 0.12065 0.3048)
			(end 0.67945 0.3048)
			(stroke
				(width 0.1)
				(type default)
			)
			(layer "B.Fab")
		)
		(fp_line
			(start 0.12065 0.2794)
			(end 0.12065 0.3048)
			(stroke
				(width 0.1)
				(type default)
			)
			(layer "B.Fab")
		)
		(fp_line
			(start 0.12065 -0.2794)
			(end -0.12065 -0.2794)
			(stroke
				(width 0.1)
				(type default)
			)
			(layer "B.Fab")
		)
		(fp_line
			(start 0.12065 -0.305054)
			(end 0.12065 -0.2794)
			(stroke
				(width 0.1)
				(type default)
			)
			(layer "B.Fab")
		)
		(fp_line
			(start -0.120396 0.3048)
			(end -0.120396 0.2794)
			(stroke
				(width 0.1)
				(type default)
			)
			(layer "B.Fab")
		)
		(fp_line
			(start -0.120396 0.2794)
			(end 0.12065 0.2794)
			(stroke
				(width 0.1)
				(type default)
			)
			(layer "B.Fab")
		)
		(fp_line
			(start -0.12065 -0.2794)
			(end -0.12065 -0.3048)
			(stroke
				(width 0.1)
				(type default)
			)
			(layer "B.Fab")
		)
		(fp_line
			(start -0.12065 -0.3048)
			(end -0.67945 -0.3048)
			(stroke
				(width 0.1)
				(type default)
			)
			(layer "B.Fab")
		)
		(fp_line
			(start -0.67945 0.3048)
			(end -0.120396 0.3048)
			(stroke
				(width 0.1)
				(type default)
			)
			(layer "B.Fab")
		)
		(fp_line
			(start -0.67945 -0.3048)
			(end -0.67945 0.3048)
			(stroke
				(width 0.1)
				(type default)
			)
			(layer "B.Fab")
		)
		(pad "1" smd circle
			(at 0.40005 0)
			(size 0 0)
			(layers "B.Cu" "B.Mask" "B.Paste")
			(net "SPI_PEX2_RST_R_N")
		)
		(pad "2" smd circle
			(at -0.40005 0)
			(size 0 0)
			(layers "B.Cu" "B.Mask" "B.Paste")
			(net "P1V8_PEX")
		)
	)
	(footprint ""
		(layer "B.Cu")
		(at 425.841922 -99.037648 180)
		(property "Reference" "R371"
			(at 0 0 0)
			(layer "B.SilkS")
			(hide yes)
			(effects
				(font
					(size 1.27 1.27)
				)
				(justify mirror)
			)
		)
		(property "Value" ""
			(at 0 0 0)
			(layer "B.Fab")
			(effects
				(font
					(size 1.27 1.27)
				)
				(justify mirror)
			)
		)
		(duplicate_pad_numbers_are_jumpers no)
		(fp_line
			(start 0.7874 0.4064)
			(end 0.7874 -0.4064)
			(stroke
				(width 0.1524)
				(type default)
			)
			(layer "B.SilkS")
		)
		(fp_line
			(start 0.7874 -0.4064)
			(end -0.7874 -0.4064)
			(stroke
				(width 0.1524)
				(type default)
			)
			(layer "B.SilkS")
		)
		(fp_line
			(start -0.7874 0.4064)
			(end 0.7874 0.4064)
			(stroke
				(width 0.1524)
				(type default)
			)
			(layer "B.SilkS")
		)
		(fp_line
			(start -0.7874 -0.4064)
			(end -0.7874 0.4064)
			(stroke
				(width 0.1524)
				(type default)
			)
			(layer "B.SilkS")
		)
		(fp_line
			(start 0.67945 0.3048)
			(end 0.67945 -0.305054)
			(stroke
				(width 0.1)
				(type default)
			)
			(layer "B.Fab")
		)
		(fp_line
			(start 0.67945 -0.305054)
			(end 0.12065 -0.305054)
			(stroke
				(width 0.1)
				(type default)
			)
			(layer "B.Fab")
		)
		(fp_line
			(start 0.12065 0.3048)
			(end 0.67945 0.3048)
			(stroke
				(width 0.1)
				(type default)
			)
			(layer "B.Fab")
		)
		(fp_line
			(start 0.12065 0.2794)
			(end 0.12065 0.3048)
			(stroke
				(width 0.1)
				(type default)
			)
			(layer "B.Fab")
		)
		(fp_line
			(start 0.12065 -0.2794)
			(end -0.12065 -0.2794)
			(stroke
				(width 0.1)
				(type default)
			)
			(layer "B.Fab")
		)
		(fp_line
			(start 0.12065 -0.305054)
			(end 0.12065 -0.2794)
			(stroke
				(width 0.1)
				(type default)
			)
			(layer "B.Fab")
		)
		(fp_line
			(start -0.120396 0.3048)
			(end -0.120396 0.2794)
			(stroke
				(width 0.1)
				(type default)
			)
			(layer "B.Fab")
		)
		(fp_line
			(start -0.120396 0.2794)
			(end 0.12065 0.2794)
			(stroke
				(width 0.1)
				(type default)
			)
			(layer "B.Fab")
		)
		(fp_line
			(start -0.12065 -0.2794)
			(end -0.12065 -0.3048)
			(stroke
				(width 0.1)
				(type default)
			)
			(layer "B.Fab")
		)
		(fp_line
			(start -0.12065 -0.3048)
			(end -0.67945 -0.3048)
			(stroke
				(width 0.1)
				(type default)
			)
			(layer "B.Fab")
		)
		(fp_line
			(start -0.67945 0.3048)
			(end -0.120396 0.3048)
			(stroke
				(width 0.1)
				(type default)
			)
			(layer "B.Fab")
		)
		(fp_line
			(start -0.67945 -0.3048)
			(end -0.67945 0.3048)
			(stroke
				(width 0.1)
				(type default)
			)
			(layer "B.Fab")
		)
		(pad "1" smd circle
			(at 0.40005 0)
			(size 0 0)
			(layers "B.Cu" "B.Mask" "B.Paste")
			(net "NIC7_CLK")
		)
		(pad "2" smd circle
			(at -0.40005 0)
			(size 0 0)
			(layers "B.Cu" "B.Mask" "B.Paste")
			(net "GND")
		)
	)
	(footprint ""
		(layer "B.Cu")
		(at 293.74973 -290.199826 90)
		(property "Reference" "C1731"
			(at 0 0 90)
			(layer "B.SilkS")
			(hide yes)
			(effects
				(font
					(size 1.27 1.27)
				)
				(justify mirror)
			)
		)
		(property "Value" ""
			(at 0 0 90)
			(layer "B.Fab")
			(effects
				(font
					(size 1.27 1.27)
				)
				(justify mirror)
			)
		)
		(duplicate_pad_numbers_are_jumpers no)
		(fp_line
			(start 0.299974 -0.150114)
			(end -0.299974 -0.150114)
			(stroke
				(width 0.1)
				(type default)
			)
			(layer "B.Fab")
		)
		(fp_line
			(start -0.299974 -0.150114)
			(end -0.299974 0.150114)
			(stroke
				(width 0.1)
				(type default)
			)
			(layer "B.Fab")
		)
		(fp_line
			(start 0.299974 0.150114)
			(end 0.299974 -0.150114)
			(stroke
				(width 0.1)
				(type default)
			)
			(layer "B.Fab")
		)
		(fp_line
			(start -0.299974 0.150114)
			(end 0.299974 0.150114)
			(stroke
				(width 0.1)
				(type default)
			)
			(layer "B.Fab")
		)
		(pad "1" smd rect
			(at 0.2667 0 270)
			(size 0.3048 0.381)
			(layers "B.Cu" "B.Mask" "B.Paste")
			(net "P0V8_SERDES_VDDA_PEX2")
		)
		(pad "2" smd rect
			(at -0.2667 0 270)
			(size 0.3048 0.381)
			(layers "B.Cu" "B.Mask" "B.Paste")
			(net "GND")
		)
	)
	(footprint ""
		(layer "B.Cu")
		(at 399.82013 -305.399948 -90)
		(property "Reference" "C3490"
			(at 0 0 90)
			(layer "B.SilkS")
			(hide yes)
			(effects
				(font
					(size 1.27 1.27)
				)
				(justify mirror)
			)
		)
		(property "Value" ""
			(at 0 0 90)
			(layer "B.Fab")
			(effects
				(font
					(size 1.27 1.27)
				)
				(justify mirror)
			)
		)
		(duplicate_pad_numbers_are_jumpers no)
		(fp_line
			(start -0.299974 0.150114)
			(end 0.299974 0.150114)
			(stroke
				(width 0.1)
				(type default)
			)
			(layer "B.Fab")
		)
		(fp_line
			(start 0.299974 0.150114)
			(end 0.299974 -0.150114)
			(stroke
				(width 0.1)
				(type default)
			)
			(layer "B.Fab")
		)
		(fp_line
			(start -0.299974 -0.150114)
			(end -0.299974 0.150114)
			(stroke
				(width 0.1)
				(type default)
			)
			(layer "B.Fab")
		)
		(fp_line
			(start 0.299974 -0.150114)
			(end -0.299974 -0.150114)
			(stroke
				(width 0.1)
				(type default)
			)
			(layer "B.Fab")
		)
		(pad "1" smd rect
			(at 0.2667 0 90)
			(size 0.3048 0.381)
			(layers "B.Cu" "B.Mask" "B.Paste")
			(net "P1V25_SERDES_VDDPLL_PEX3")
		)
		(pad "2" smd rect
			(at -0.2667 0 90)
			(size 0.3048 0.381)
			(layers "B.Cu" "B.Mask" "B.Paste")
			(net "GND")
		)
	)
	(footprint ""
		(layer "B.Cu")
		(at 351.197418 -207.739234 -90)
		(property "Reference" "R5774"
			(at 0 0 90)
			(layer "B.SilkS")
			(hide yes)
			(effects
				(font
					(size 1.27 1.27)
				)
				(justify mirror)
			)
		)
		(property "Value" ""
			(at 0 0 90)
			(layer "B.Fab")
			(effects
				(font
					(size 1.27 1.27)
				)
				(justify mirror)
			)
		)
		(duplicate_pad_numbers_are_jumpers no)
		(fp_line
			(start -0.7874 0.4064)
			(end 0.7874 0.4064)
			(stroke
				(width 0.1524)
				(type default)
			)
			(layer "B.SilkS")
		)
		(fp_line
			(start 0.7874 0.4064)
			(end 0.7874 -0.4064)
			(stroke
				(width 0.1524)
				(type default)
			)
			(layer "B.SilkS")
		)
		(fp_line
			(start -0.7874 -0.4064)
			(end -0.7874 0.4064)
			(stroke
				(width 0.1524)
				(type default)
			)
			(layer "B.SilkS")
		)
		(fp_line
			(start 0.7874 -0.4064)
			(end -0.7874 -0.4064)
			(stroke
				(width 0.1524)
				(type default)
			)
			(layer "B.SilkS")
		)
		(fp_line
			(start -0.67945 0.3048)
			(end -0.120396 0.3048)
			(stroke
				(width 0.1)
				(type default)
			)
			(layer "B.Fab")
		)
		(fp_line
			(start -0.120396 0.3048)
			(end -0.120396 0.2794)
			(stroke
				(width 0.1)
				(type default)
			)
			(layer "B.Fab")
		)
		(fp_line
			(start 0.12065 0.3048)
			(end 0.67945 0.3048)
			(stroke
				(width 0.1)
				(type default)
			)
			(layer "B.Fab")
		)
		(fp_line
			(start 0.67945 0.3048)
			(end 0.67945 -0.305054)
			(stroke
				(width 0.1)
				(type default)
			)
			(layer "B.Fab")
		)
		(fp_line
			(start -0.120396 0.2794)
			(end 0.12065 0.2794)
			(stroke
				(width 0.1)
				(type default)
			)
			(layer "B.Fab")
		)
		(fp_line
			(start 0.12065 0.2794)
			(end 0.12065 0.3048)
			(stroke
				(width 0.1)
				(type default)
			)
			(layer "B.Fab")
		)
		(fp_line
			(start -0.12065 -0.2794)
			(end -0.12065 -0.3048)
			(stroke
				(width 0.1)
				(type default)
			)
			(layer "B.Fab")
		)
		(fp_line
			(start 0.12065 -0.2794)
			(end -0.12065 -0.2794)
			(stroke
				(width 0.1)
				(type default)
			)
			(layer "B.Fab")
		)
		(fp_line
			(start -0.67945 -0.3048)
			(end -0.67945 0.3048)
			(stroke
				(width 0.1)
				(type default)
			)
			(layer "B.Fab")
		)
		(fp_line
			(start -0.12065 -0.3048)
			(end -0.67945 -0.3048)
			(stroke
				(width 0.1)
				(type default)
			)
			(layer "B.Fab")
		)
		(fp_line
			(start 0.12065 -0.305054)
			(end 0.12065 -0.2794)
			(stroke
				(width 0.1)
				(type default)
			)
			(layer "B.Fab")
		)
		(fp_line
			(start 0.67945 -0.305054)
			(end 0.12065 -0.305054)
			(stroke
				(width 0.1)
				(type default)
			)
			(layer "B.Fab")
		)
		(pad "1" smd circle
			(at 0.40005 0 90)
			(size 0 0)
			(layers "B.Cu" "B.Mask" "B.Paste")
			(net "RST_FT4232_R_N")
		)
		(pad "2" smd circle
			(at -0.40005 0 90)
			(size 0 0)
			(layers "B.Cu" "B.Mask" "B.Paste")
			(net "RST_FT4232_N")
		)
	)
	(footprint ""
		(layer "B.Cu")
		(at 98.292412 -351.719388 180)
		(property "Reference" "R6374"
			(at 0 0 0)
			(layer "B.SilkS")
			(hide yes)
			(effects
				(font
					(size 1.27 1.27)
				)
				(justify mirror)
			)
		)
		(property "Value" ""
			(at 0 0 0)
			(layer "B.Fab")
			(effects
				(font
					(size 1.27 1.27)
				)
				(justify mirror)
			)
		)
		(duplicate_pad_numbers_are_jumpers no)
		(fp_line
			(start 0.7874 0.4064)
			(end 0.7874 -0.4064)
			(stroke
				(width 0.1524)
				(type default)
			)
			(layer "B.SilkS")
		)
		(fp_line
			(start 0.7874 -0.4064)
			(end -0.7874 -0.4064)
			(stroke
				(width 0.1524)
				(type default)
			)
			(layer "B.SilkS")
		)
		(fp_line
			(start -0.7874 0.4064)
			(end 0.7874 0.4064)
			(stroke
				(width 0.1524)
				(type default)
			)
			(layer "B.SilkS")
		)
		(fp_line
			(start -0.7874 -0.4064)
			(end -0.7874 0.4064)
			(stroke
				(width 0.1524)
				(type default)
			)
			(layer "B.SilkS")
		)
		(fp_line
			(start 0.67945 0.3048)
			(end 0.67945 -0.305054)
			(stroke
				(width 0.1)
				(type default)
			)
			(layer "B.Fab")
		)
		(fp_line
			(start 0.67945 -0.305054)
			(end 0.12065 -0.305054)
			(stroke
				(width 0.1)
				(type default)
			)
			(layer "B.Fab")
		)
		(fp_line
			(start 0.12065 0.3048)
			(end 0.67945 0.3048)
			(stroke
				(width 0.1)
				(type default)
			)
			(layer "B.Fab")
		)
		(fp_line
			(start 0.12065 0.2794)
			(end 0.12065 0.3048)
			(stroke
				(width 0.1)
				(type default)
			)
			(layer "B.Fab")
		)
		(fp_line
			(start 0.12065 -0.2794)
			(end -0.12065 -0.2794)
			(stroke
				(width 0.1)
				(type default)
			)
			(layer "B.Fab")
		)
		(fp_line
			(start 0.12065 -0.305054)
			(end 0.12065 -0.2794)
			(stroke
				(width 0.1)
				(type default)
			)
			(layer "B.Fab")
		)
		(fp_line
			(start -0.120396 0.3048)
			(end -0.120396 0.2794)
			(stroke
				(width 0.1)
				(type default)
			)
			(layer "B.Fab")
		)
		(fp_line
			(start -0.120396 0.2794)
			(end 0.12065 0.2794)
			(stroke
				(width 0.1)
				(type default)
			)
			(layer "B.Fab")
		)
		(fp_line
			(start -0.12065 -0.2794)
			(end -0.12065 -0.3048)
			(stroke
				(width 0.1)
				(type default)
			)
			(layer "B.Fab")
		)
		(fp_line
			(start -0.12065 -0.3048)
			(end -0.67945 -0.3048)
			(stroke
				(width 0.1)
				(type default)
			)
			(layer "B.Fab")
		)
		(fp_line
			(start -0.67945 0.3048)
			(end -0.120396 0.3048)
			(stroke
				(width 0.1)
				(type default)
			)
			(layer "B.Fab")
		)
		(fp_line
			(start -0.67945 -0.3048)
			(end -0.67945 0.3048)
			(stroke
				(width 0.1)
				(type default)
			)
			(layer "B.Fab")
		)
		(pad "1" smd circle
			(at 0.40005 0)
			(size 0 0)
			(layers "B.Cu" "B.Mask" "B.Paste")
			(net "CLK_100M_DB800ZL_PEX0_S3_R_DP")
		)
		(pad "2" smd circle
			(at -0.40005 0)
			(size 0 0)
			(layers "B.Cu" "B.Mask" "B.Paste")
			(net "CLK_100M_DB800ZL_PEX0_S3_DP")
		)
	)
	(footprint ""
		(layer "B.Cu")
		(at 228.553264 -208.78546 90)
		(property "Reference" "R5295"
			(at 0 0 90)
			(layer "B.SilkS")
			(hide yes)
			(effects
				(font
					(size 1.27 1.27)
				)
				(justify mirror)
			)
		)
		(property "Value" ""
			(at 0 0 90)
			(layer "B.Fab")
			(effects
				(font
					(size 1.27 1.27)
				)
				(justify mirror)
			)
		)
		(duplicate_pad_numbers_are_jumpers no)
		(fp_line
			(start 0.7874 -0.4064)
			(end -0.7874 -0.4064)
			(stroke
				(width 0.1524)
				(type default)
			)
			(layer "B.SilkS")
		)
		(fp_line
			(start -0.7874 -0.4064)
			(end -0.7874 0.4064)
			(stroke
				(width 0.1524)
				(type default)
			)
			(layer "B.SilkS")
		)
		(fp_line
			(start 0.7874 0.4064)
			(end 0.7874 -0.4064)
			(stroke
				(width 0.1524)
				(type default)
			)
			(layer "B.SilkS")
		)
		(fp_line
			(start -0.7874 0.4064)
			(end 0.7874 0.4064)
			(stroke
				(width 0.1524)
				(type default)
			)
			(layer "B.SilkS")
		)
		(fp_line
			(start 0.67945 -0.305054)
			(end 0.12065 -0.305054)
			(stroke
				(width 0.1)
				(type default)
			)
			(layer "B.Fab")
		)
		(fp_line
			(start 0.12065 -0.305054)
			(end 0.12065 -0.2794)
			(stroke
				(width 0.1)
				(type default)
			)
			(layer "B.Fab")
		)
		(fp_line
			(start -0.12065 -0.3048)
			(end -0.67945 -0.3048)
			(stroke
				(width 0.1)
				(type default)
			)
			(layer "B.Fab")
		)
		(fp_line
			(start -0.67945 -0.3048)
			(end -0.67945 0.3048)
			(stroke
				(width 0.1)
				(type default)
			)
			(layer "B.Fab")
		)
		(fp_line
			(start 0.12065 -0.2794)
			(end -0.12065 -0.2794)
			(stroke
				(width 0.1)
				(type default)
			)
			(layer "B.Fab")
		)
		(fp_line
			(start -0.12065 -0.2794)
			(end -0.12065 -0.3048)
			(stroke
				(width 0.1)
				(type default)
			)
			(layer "B.Fab")
		)
		(fp_line
			(start 0.12065 0.2794)
			(end 0.12065 0.3048)
			(stroke
				(width 0.1)
				(type default)
			)
			(layer "B.Fab")
		)
		(fp_line
			(start -0.120396 0.2794)
			(end 0.12065 0.2794)
			(stroke
				(width 0.1)
				(type default)
			)
			(layer "B.Fab")
		)
		(fp_line
			(start 0.67945 0.3048)
			(end 0.67945 -0.305054)
			(stroke
				(width 0.1)
				(type default)
			)
			(layer "B.Fab")
		)
		(fp_line
			(start 0.12065 0.3048)
			(end 0.67945 0.3048)
			(stroke
				(width 0.1)
				(type default)
			)
			(layer "B.Fab")
		)
		(fp_line
			(start -0.120396 0.3048)
			(end -0.120396 0.2794)
			(stroke
				(width 0.1)
				(type default)
			)
			(layer "B.Fab")
		)
		(fp_line
			(start -0.67945 0.3048)
			(end -0.120396 0.3048)
			(stroke
				(width 0.1)
				(type default)
			)
			(layer "B.Fab")
		)
		(pad "1" smd circle
			(at 0.40005 0 270)
			(size 0 0)
			(layers "B.Cu" "B.Mask" "B.Paste")
			(net "BIC_SEL_FLASH_SW2")
		)
		(pad "2" smd circle
			(at -0.40005 0 270)
			(size 0 0)
			(layers "B.Cu" "B.Mask" "B.Paste")
			(net "BIC_SEL_FLASH_SW2_R")
		)
	)
	(footprint ""
		(layer "B.Cu")
		(at 287.06445 -195.290186)
		(property "Reference" "R6658"
			(at 0 0 0)
			(layer "B.SilkS")
			(hide yes)
			(effects
				(font
					(size 1.27 1.27)
				)
				(justify mirror)
			)
		)
		(property "Value" ""
			(at 0 0 0)
			(layer "B.Fab")
			(effects
				(font
					(size 1.27 1.27)
				)
				(justify mirror)
			)
		)
		(duplicate_pad_numbers_are_jumpers no)
		(fp_line
			(start -0.7874 -0.4064)
			(end -0.7874 0.4064)
			(stroke
				(width 0.1524)
				(type default)
			)
			(layer "B.SilkS")
		)
		(fp_line
			(start -0.7874 0.4064)
			(end 0.7874 0.4064)
			(stroke
				(width 0.1524)
				(type default)
			)
			(layer "B.SilkS")
		)
		(fp_line
			(start 0.7874 -0.4064)
			(end -0.7874 -0.4064)
			(stroke
				(width 0.1524)
				(type default)
			)
			(layer "B.SilkS")
		)
		(fp_line
			(start 0.7874 0.4064)
			(end 0.7874 -0.4064)
			(stroke
				(width 0.1524)
				(type default)
			)
			(layer "B.SilkS")
		)
		(fp_line
			(start -0.67945 -0.3048)
			(end -0.67945 0.3048)
			(stroke
				(width 0.1)
				(type default)
			)
			(layer "B.Fab")
		)
		(fp_line
			(start -0.67945 0.3048)
			(end -0.120396 0.3048)
			(stroke
				(width 0.1)
				(type default)
			)
			(layer "B.Fab")
		)
		(fp_line
			(start -0.12065 -0.3048)
			(end -0.67945 -0.3048)
			(stroke
				(width 0.1)
				(type default)
			)
			(layer "B.Fab")
		)
		(fp_line
			(start -0.12065 -0.2794)
			(end -0.12065 -0.3048)
			(stroke
				(width 0.1)
				(type default)
			)
			(layer "B.Fab")
		)
		(fp_line
			(start -0.120396 0.2794)
			(end 0.12065 0.2794)
			(stroke
				(width 0.1)
				(type default)
			)
			(layer "B.Fab")
		)
		(fp_line
			(start -0.120396 0.3048)
			(end -0.120396 0.2794)
			(stroke
				(width 0.1)
				(type default)
			)
			(layer "B.Fab")
		)
		(fp_line
			(start 0.12065 -0.305054)
			(end 0.12065 -0.2794)
			(stroke
				(width 0.1)
				(type default)
			)
			(layer "B.Fab")
		)
		(fp_line
			(start 0.12065 -0.2794)
			(end -0.12065 -0.2794)
			(stroke
				(width 0.1)
				(type default)
			)
			(layer "B.Fab")
		)
		(fp_line
			(start 0.12065 0.2794)
			(end 0.12065 0.3048)
			(stroke
				(width 0.1)
				(type default)
			)
			(layer "B.Fab")
		)
		(fp_line
			(start 0.12065 0.3048)
			(end 0.67945 0.3048)
			(stroke
				(width 0.1)
				(type default)
			)
			(layer "B.Fab")
		)
		(fp_line
			(start 0.67945 -0.305054)
			(end 0.12065 -0.305054)
			(stroke
				(width 0.1)
				(type default)
			)
			(layer "B.Fab")
		)
		(fp_line
			(start 0.67945 0.3048)
			(end 0.67945 -0.305054)
			(stroke
				(width 0.1)
				(type default)
			)
			(layer "B.Fab")
		)
		(pad "1" smd circle
			(at 0.40005 0 180)
			(size 0 0)
			(layers "B.Cu" "B.Mask" "B.Paste")
			(net "SPI_BIC1_LS23_EN_N")
		)
		(pad "2" smd circle
			(at -0.40005 0 180)
			(size 0 0)
			(layers "B.Cu" "B.Mask" "B.Paste")
			(net "P1V8_PEX")
		)
	)
	(footprint ""
		(layer "B.Cu")
		(at 419.349936 -298.27474 180)
		(property "Reference" "C3465"
			(at 0 0 0)
			(layer "B.SilkS")
			(hide yes)
			(effects
				(font
					(size 1.27 1.27)
				)
				(justify mirror)
			)
		)
		(property "Value" ""
			(at 0 0 0)
			(layer "B.Fab")
			(effects
				(font
					(size 1.27 1.27)
				)
				(justify mirror)
			)
		)
		(duplicate_pad_numbers_are_jumpers no)
		(fp_line
			(start 0.299974 0.150114)
			(end 0.299974 -0.150114)
			(stroke
				(width 0.1)
				(type default)
			)
			(layer "B.Fab")
		)
		(fp_line
			(start 0.299974 -0.150114)
			(end -0.299974 -0.150114)
			(stroke
				(width 0.1)
				(type default)
			)
			(layer "B.Fab")
		)
		(fp_line
			(start -0.299974 0.150114)
			(end 0.299974 0.150114)
			(stroke
				(width 0.1)
				(type default)
			)
			(layer "B.Fab")
		)
		(fp_line
			(start -0.299974 -0.150114)
			(end -0.299974 0.150114)
			(stroke
				(width 0.1)
				(type default)
			)
			(layer "B.Fab")
		)
		(pad "1" smd rect
			(at 0.2667 0)
			(size 0.3048 0.381)
			(layers "B.Cu" "B.Mask" "B.Paste")
			(net "P1V25_PEX3")
		)
		(pad "2" smd rect
			(at -0.2667 0)
			(size 0.3048 0.381)
			(layers "B.Cu" "B.Mask" "B.Paste")
			(net "GND")
		)
	)
	(footprint ""
		(layer "B.Cu")
		(at 449.863718 -278.333962)
		(property "Reference" "C4402"
			(at 0 0 0)
			(layer "B.SilkS")
			(hide yes)
			(effects
				(font
					(size 1.27 1.27)
				)
				(justify mirror)
			)
		)
		(property "Value" ""
			(at 0 0 0)
			(layer "B.Fab")
			(effects
				(font
					(size 1.27 1.27)
				)
				(justify mirror)
			)
		)
		(duplicate_pad_numbers_are_jumpers no)
		(fp_line
			(start -1.2954 -0.5842)
			(end -1.2954 0.5842)
			(stroke
				(width 0.1524)
				(type default)
			)
			(layer "B.SilkS")
		)
		(fp_line
			(start -1.2954 0.5842)
			(end 1.2954 0.5842)
			(stroke
				(width 0.1524)
				(type default)
			)
			(layer "B.SilkS")
		)
		(fp_line
			(start 1.2954 -0.5842)
			(end -1.2954 -0.5842)
			(stroke
				(width 0.1524)
				(type default)
			)
			(layer "B.SilkS")
		)
		(fp_line
			(start 1.2954 0.5842)
			(end 1.2954 -0.5842)
			(stroke
				(width 0.1524)
				(type default)
			)
			(layer "B.SilkS")
		)
		(fp_line
			(start -1.1938 -0.4064)
			(end -1.1938 0.4064)
			(stroke
				(width 0.1)
				(type default)
			)
			(layer "B.Fab")
		)
		(fp_line
			(start -1.1938 0.4064)
			(end -0.8636 0.4064)
			(stroke
				(width 0.1)
				(type default)
			)
			(layer "B.Fab")
		)
		(fp_line
			(start -0.8636 -0.4572)
			(end -0.8636 -0.4064)
			(stroke
				(width 0.1)
				(type default)
			)
			(layer "B.Fab")
		)
		(fp_line
			(start -0.8636 -0.4064)
			(end -1.1938 -0.4064)
			(stroke
				(width 0.1)
				(type default)
			)
			(layer "B.Fab")
		)
		(fp_line
			(start -0.8636 0.4064)
			(end -0.8636 0.4572)
			(stroke
				(width 0.1)
				(type default)
			)
			(layer "B.Fab")
		)
		(fp_line
			(start -0.8636 0.4572)
			(end 0.8636 0.4572)
			(stroke
				(width 0.1)
				(type default)
			)
			(layer "B.Fab")
		)
		(fp_line
			(start 0.8636 -0.4572)
			(end -0.8636 -0.4572)
			(stroke
				(width 0.1)
				(type default)
			)
			(layer "B.Fab")
		)
		(fp_line
			(start 0.8636 -0.4064)
			(end 0.8636 -0.4572)
			(stroke
				(width 0.1)
				(type default)
			)
			(layer "B.Fab")
		)
		(fp_line
			(start 0.8636 0.4064)
			(end 1.1938 0.4064)
			(stroke
				(width 0.1)
				(type default)
			)
			(layer "B.Fab")
		)
		(fp_line
			(start 0.8636 0.4572)
			(end 0.8636 0.4064)
			(stroke
				(width 0.1)
				(type default)
			)
			(layer "B.Fab")
		)
		(fp_line
			(start 1.1938 -0.4064)
			(end 0.8636 -0.4064)
			(stroke
				(width 0.1)
				(type default)
			)
			(layer "B.Fab")
		)
		(fp_line
			(start 1.1938 0.4064)
			(end 1.1938 -0.4064)
			(stroke
				(width 0.1)
				(type default)
			)
			(layer "B.Fab")
		)
		(pad "1" smd rect
			(at 0.7366 0 270)
			(size 0.7112 0.8128)
			(layers "B.Cu" "B.Mask" "B.Paste")
			(net "P1V25_PEX3")
		)
		(pad "2" smd rect
			(at -0.7366 0 270)
			(size 0.7112 0.8128)
			(layers "B.Cu" "B.Mask" "B.Paste")
			(net "GND")
		)
	)
	(footprint ""
		(layer "B.Cu")
		(at 4.893818 -288.21507)
		(property "Reference" "PC986"
			(at 0 0 0)
			(layer "B.SilkS")
			(hide yes)
			(effects
				(font
					(size 1.27 1.27)
				)
				(justify mirror)
			)
		)
		(property "Value" ""
			(at 0 0 0)
			(layer "B.Fab")
			(effects
				(font
					(size 1.27 1.27)
				)
				(justify mirror)
			)
		)
		(duplicate_pad_numbers_are_jumpers no)
		(fp_line
			(start -1.524 -0.762)
			(end -1.524 0.762)
			(stroke
				(width 0.1524)
				(type default)
			)
			(layer "B.SilkS")
		)
		(fp_line
			(start -1.524 0.762)
			(end 1.524 0.762)
			(stroke
				(width 0.1524)
				(type default)
			)
			(layer "B.SilkS")
		)
		(fp_line
			(start 1.524 -0.762)
			(end -1.524 -0.762)
			(stroke
				(width 0.1524)
				(type default)
			)
			(layer "B.SilkS")
		)
		(fp_line
			(start 1.524 0.762)
			(end 1.524 -0.762)
			(stroke
				(width 0.1524)
				(type default)
			)
			(layer "B.SilkS")
		)
		(fp_line
			(start -1.1049 -0.724916)
			(end 1.1049 -0.724916)
			(stroke
				(width 0.1)
				(type default)
			)
			(layer "B.Fab")
		)
		(fp_line
			(start -1.1049 0.724916)
			(end -1.1049 -0.724916)
			(stroke
				(width 0.1)
				(type default)
			)
			(layer "B.Fab")
		)
		(fp_line
			(start 1.1049 -0.724916)
			(end 1.1049 0.724916)
			(stroke
				(width 0.1)
				(type default)
			)
			(layer "B.Fab")
		)
		(fp_line
			(start 1.1049 0.724916)
			(end -1.1049 0.724916)
			(stroke
				(width 0.1)
				(type default)
			)
			(layer "B.Fab")
		)
		(pad "1" smd rect
			(at 0.889 0)
			(size 1.016 1.27)
			(layers "B.Cu" "B.Mask" "B.Paste")
			(net "P1V25_PEX0_R")
		)
		(pad "2" smd rect
			(at -0.889 0)
			(size 1.016 1.27)
			(layers "B.Cu" "B.Mask" "B.Paste")
			(net "GND")
		)
	)
	(footprint ""
		(layer "B.Cu")
		(at 71.049896 -296.37482 180)
		(property "Reference" "C2926"
			(at 0 0 0)
			(layer "B.SilkS")
			(hide yes)
			(effects
				(font
					(size 1.27 1.27)
				)
				(justify mirror)
			)
		)
		(property "Value" ""
			(at 0 0 0)
			(layer "B.Fab")
			(effects
				(font
					(size 1.27 1.27)
				)
				(justify mirror)
			)
		)
		(duplicate_pad_numbers_are_jumpers no)
		(fp_line
			(start 0.299974 0.150114)
			(end 0.299974 -0.150114)
			(stroke
				(width 0.1)
				(type default)
			)
			(layer "B.Fab")
		)
		(fp_line
			(start 0.299974 -0.150114)
			(end -0.299974 -0.150114)
			(stroke
				(width 0.1)
				(type default)
			)
			(layer "B.Fab")
		)
		(fp_line
			(start -0.299974 0.150114)
			(end 0.299974 0.150114)
			(stroke
				(width 0.1)
				(type default)
			)
			(layer "B.Fab")
		)
		(fp_line
			(start -0.299974 -0.150114)
			(end -0.299974 0.150114)
			(stroke
				(width 0.1)
				(type default)
			)
			(layer "B.Fab")
		)
		(pad "1" smd rect
			(at 0.2667 0)
			(size 0.3048 0.381)
			(layers "B.Cu" "B.Mask" "B.Paste")
			(net "P1V25_PEX0")
		)
		(pad "2" smd rect
			(at -0.2667 0)
			(size 0.3048 0.381)
			(layers "B.Cu" "B.Mask" "B.Paste")
			(net "GND")
		)
	)
	(footprint ""
		(layer "B.Cu")
		(at 335.279746 -323.15531 -90)
		(property "Reference" "R6505"
			(at 0 0 90)
			(layer "B.SilkS")
			(hide yes)
			(effects
				(font
					(size 1.27 1.27)
				)
				(justify mirror)
			)
		)
		(property "Value" ""
			(at 0 0 90)
			(layer "B.Fab")
			(effects
				(font
					(size 1.27 1.27)
				)
				(justify mirror)
			)
		)
		(duplicate_pad_numbers_are_jumpers no)
		(fp_line
			(start -0.7874 0.4064)
			(end 0.7874 0.4064)
			(stroke
				(width 0.1524)
				(type default)
			)
			(layer "B.SilkS")
		)
		(fp_line
			(start 0.7874 0.4064)
			(end 0.7874 -0.4064)
			(stroke
				(width 0.1524)
				(type default)
			)
			(layer "B.SilkS")
		)
		(fp_line
			(start -0.7874 -0.4064)
			(end -0.7874 0.4064)
			(stroke
				(width 0.1524)
				(type default)
			)
			(layer "B.SilkS")
		)
		(fp_line
			(start 0.7874 -0.4064)
			(end -0.7874 -0.4064)
			(stroke
				(width 0.1524)
				(type default)
			)
			(layer "B.SilkS")
		)
		(fp_line
			(start -0.67945 0.3048)
			(end -0.120396 0.3048)
			(stroke
				(width 0.1)
				(type default)
			)
			(layer "B.Fab")
		)
		(fp_line
			(start -0.120396 0.3048)
			(end -0.120396 0.2794)
			(stroke
				(width 0.1)
				(type default)
			)
			(layer "B.Fab")
		)
		(fp_line
			(start 0.12065 0.3048)
			(end 0.67945 0.3048)
			(stroke
				(width 0.1)
				(type default)
			)
			(layer "B.Fab")
		)
		(fp_line
			(start 0.67945 0.3048)
			(end 0.67945 -0.305054)
			(stroke
				(width 0.1)
				(type default)
			)
			(layer "B.Fab")
		)
		(fp_line
			(start -0.120396 0.2794)
			(end 0.12065 0.2794)
			(stroke
				(width 0.1)
				(type default)
			)
			(layer "B.Fab")
		)
		(fp_line
			(start 0.12065 0.2794)
			(end 0.12065 0.3048)
			(stroke
				(width 0.1)
				(type default)
			)
			(layer "B.Fab")
		)
		(fp_line
			(start -0.12065 -0.2794)
			(end -0.12065 -0.3048)
			(stroke
				(width 0.1)
				(type default)
			)
			(layer "B.Fab")
		)
		(fp_line
			(start 0.12065 -0.2794)
			(end -0.12065 -0.2794)
			(stroke
				(width 0.1)
				(type default)
			)
			(layer "B.Fab")
		)
		(fp_line
			(start -0.67945 -0.3048)
			(end -0.67945 0.3048)
			(stroke
				(width 0.1)
				(type default)
			)
			(layer "B.Fab")
		)
		(fp_line
			(start -0.12065 -0.3048)
			(end -0.67945 -0.3048)
			(stroke
				(width 0.1)
				(type default)
			)
			(layer "B.Fab")
		)
		(fp_line
			(start 0.12065 -0.305054)
			(end 0.12065 -0.2794)
			(stroke
				(width 0.1)
				(type default)
			)
			(layer "B.Fab")
		)
		(fp_line
			(start 0.67945 -0.305054)
			(end 0.12065 -0.305054)
			(stroke
				(width 0.1)
				(type default)
			)
			(layer "B.Fab")
		)
		(pad "1" smd circle
			(at 0.40005 0 90)
			(size 0 0)
			(layers "B.Cu" "B.Mask" "B.Paste")
			(net "P0V8_SERDES_VDDA_PEX2")
		)
		(pad "2" smd circle
			(at -0.40005 0 90)
			(size 0 0)
			(layers "B.Cu" "B.Mask" "B.Paste")
			(net "P0V8_SERDES_VDDA_PEX2_C0")
		)
	)
	(footprint ""
		(layer "B.Cu")
		(at 68.941442 -286.874966)
		(property "Reference" "C2996"
			(at 0 0 0)
			(layer "B.SilkS")
			(hide yes)
			(effects
				(font
					(size 1.27 1.27)
				)
				(justify mirror)
			)
		)
		(property "Value" ""
			(at 0 0 0)
			(layer "B.Fab")
			(effects
				(font
					(size 1.27 1.27)
				)
				(justify mirror)
			)
		)
		(duplicate_pad_numbers_are_jumpers no)
		(fp_line
			(start -0.299974 -0.150114)
			(end -0.299974 0.150114)
			(stroke
				(width 0.1)
				(type default)
			)
			(layer "B.Fab")
		)
		(fp_line
			(start -0.299974 0.150114)
			(end 0.299974 0.150114)
			(stroke
				(width 0.1)
				(type default)
			)
			(layer "B.Fab")
		)
		(fp_line
			(start 0.299974 -0.150114)
			(end -0.299974 -0.150114)
			(stroke
				(width 0.1)
				(type default)
			)
			(layer "B.Fab")
		)
		(fp_line
			(start 0.299974 0.150114)
			(end 0.299974 -0.150114)
			(stroke
				(width 0.1)
				(type default)
			)
			(layer "B.Fab")
		)
		(pad "1" smd rect
			(at 0.2667 0 180)
			(size 0.3048 0.381)
			(layers "B.Cu" "B.Mask" "B.Paste")
			(net "P1V8_VDDA_PEX0")
		)
		(pad "2" smd rect
			(at -0.2667 0 180)
			(size 0.3048 0.381)
			(layers "B.Cu" "B.Mask" "B.Paste")
			(net "GND")
		)
	)
	(footprint ""
		(layer "B.Cu")
		(at 300.591474 -221.694502 -90)
		(property "Reference" "R6176"
			(at 0 0 90)
			(layer "B.SilkS")
			(hide yes)
			(effects
				(font
					(size 1.27 1.27)
				)
				(justify mirror)
			)
		)
		(property "Value" ""
			(at 0 0 90)
			(layer "B.Fab")
			(effects
				(font
					(size 1.27 1.27)
				)
				(justify mirror)
			)
		)
		(duplicate_pad_numbers_are_jumpers no)
		(fp_line
			(start -0.7874 0.4064)
			(end 0.7874 0.4064)
			(stroke
				(width 0.1524)
				(type default)
			)
			(layer "B.SilkS")
		)
		(fp_line
			(start 0.7874 0.4064)
			(end 0.7874 -0.4064)
			(stroke
				(width 0.1524)
				(type default)
			)
			(layer "B.SilkS")
		)
		(fp_line
			(start -0.7874 -0.4064)
			(end -0.7874 0.4064)
			(stroke
				(width 0.1524)
				(type default)
			)
			(layer "B.SilkS")
		)
		(fp_line
			(start 0.7874 -0.4064)
			(end -0.7874 -0.4064)
			(stroke
				(width 0.1524)
				(type default)
			)
			(layer "B.SilkS")
		)
		(fp_line
			(start -0.67945 0.3048)
			(end -0.120396 0.3048)
			(stroke
				(width 0.1)
				(type default)
			)
			(layer "B.Fab")
		)
		(fp_line
			(start -0.120396 0.3048)
			(end -0.120396 0.2794)
			(stroke
				(width 0.1)
				(type default)
			)
			(layer "B.Fab")
		)
		(fp_line
			(start 0.12065 0.3048)
			(end 0.67945 0.3048)
			(stroke
				(width 0.1)
				(type default)
			)
			(layer "B.Fab")
		)
		(fp_line
			(start 0.67945 0.3048)
			(end 0.67945 -0.305054)
			(stroke
				(width 0.1)
				(type default)
			)
			(layer "B.Fab")
		)
		(fp_line
			(start -0.120396 0.2794)
			(end 0.12065 0.2794)
			(stroke
				(width 0.1)
				(type default)
			)
			(layer "B.Fab")
		)
		(fp_line
			(start 0.12065 0.2794)
			(end 0.12065 0.3048)
			(stroke
				(width 0.1)
				(type default)
			)
			(layer "B.Fab")
		)
		(fp_line
			(start -0.12065 -0.2794)
			(end -0.12065 -0.3048)
			(stroke
				(width 0.1)
				(type default)
			)
			(layer "B.Fab")
		)
		(fp_line
			(start 0.12065 -0.2794)
			(end -0.12065 -0.2794)
			(stroke
				(width 0.1)
				(type default)
			)
			(layer "B.Fab")
		)
		(fp_line
			(start -0.67945 -0.3048)
			(end -0.67945 0.3048)
			(stroke
				(width 0.1)
				(type default)
			)
			(layer "B.Fab")
		)
		(fp_line
			(start -0.12065 -0.3048)
			(end -0.67945 -0.3048)
			(stroke
				(width 0.1)
				(type default)
			)
			(layer "B.Fab")
		)
		(fp_line
			(start 0.12065 -0.305054)
			(end 0.12065 -0.2794)
			(stroke
				(width 0.1)
				(type default)
			)
			(layer "B.Fab")
		)
		(fp_line
			(start 0.67945 -0.305054)
			(end 0.12065 -0.305054)
			(stroke
				(width 0.1)
				(type default)
			)
			(layer "B.Fab")
		)
		(pad "1" smd circle
			(at 0.40005 0 90)
			(size 0 0)
			(layers "B.Cu" "B.Mask" "B.Paste")
			(net "GND")
		)
		(pad "2" smd circle
			(at -0.40005 0 90)
			(size 0 0)
			(layers "B.Cu" "B.Mask" "B.Paste")
			(net "RST_GPU_PERST_2_N")
		)
	)
	(footprint ""
		(layer "B.Cu")
		(at 166.265098 -301.599854 -90)
		(property "Reference" "C1444"
			(at 0 0 90)
			(layer "B.SilkS")
			(hide yes)
			(effects
				(font
					(size 1.27 1.27)
				)
				(justify mirror)
			)
		)
		(property "Value" ""
			(at 0 0 90)
			(layer "B.Fab")
			(effects
				(font
					(size 1.27 1.27)
				)
				(justify mirror)
			)
		)
		(duplicate_pad_numbers_are_jumpers no)
		(fp_line
			(start -0.299974 0.150114)
			(end 0.299974 0.150114)
			(stroke
				(width 0.1)
				(type default)
			)
			(layer "B.Fab")
		)
		(fp_line
			(start 0.299974 0.150114)
			(end 0.299974 -0.150114)
			(stroke
				(width 0.1)
				(type default)
			)
			(layer "B.Fab")
		)
		(fp_line
			(start -0.299974 -0.150114)
			(end -0.299974 0.150114)
			(stroke
				(width 0.1)
				(type default)
			)
			(layer "B.Fab")
		)
		(fp_line
			(start 0.299974 -0.150114)
			(end -0.299974 -0.150114)
			(stroke
				(width 0.1)
				(type default)
			)
			(layer "B.Fab")
		)
		(pad "1" smd rect
			(at 0.2667 0 90)
			(size 0.3048 0.381)
			(layers "B.Cu" "B.Mask" "B.Paste")
			(net "P0V8_SERDES_VDDA_PEX1")
		)
		(pad "2" smd rect
			(at -0.2667 0 90)
			(size 0.3048 0.381)
			(layers "B.Cu" "B.Mask" "B.Paste")
			(net "GND")
		)
	)
	(footprint ""
		(layer "B.Cu")
		(at 416.024822 -286.399732 90)
		(property "Reference" "C3482"
			(at 0 0 90)
			(layer "B.SilkS")
			(hide yes)
			(effects
				(font
					(size 1.27 1.27)
				)
				(justify mirror)
			)
		)
		(property "Value" ""
			(at 0 0 90)
			(layer "B.Fab")
			(effects
				(font
					(size 1.27 1.27)
				)
				(justify mirror)
			)
		)
		(duplicate_pad_numbers_are_jumpers no)
		(fp_line
			(start 0.299974 -0.150114)
			(end -0.299974 -0.150114)
			(stroke
				(width 0.1)
				(type default)
			)
			(layer "B.Fab")
		)
		(fp_line
			(start -0.299974 -0.150114)
			(end -0.299974 0.150114)
			(stroke
				(width 0.1)
				(type default)
			)
			(layer "B.Fab")
		)
		(fp_line
			(start 0.299974 0.150114)
			(end 0.299974 -0.150114)
			(stroke
				(width 0.1)
				(type default)
			)
			(layer "B.Fab")
		)
		(fp_line
			(start -0.299974 0.150114)
			(end 0.299974 0.150114)
			(stroke
				(width 0.1)
				(type default)
			)
			(layer "B.Fab")
		)
		(pad "1" smd rect
			(at 0.2667 0 270)
			(size 0.3048 0.381)
			(layers "B.Cu" "B.Mask" "B.Paste")
			(net "P1V25_SERDES_VDDPLL_PEX3")
		)
		(pad "2" smd rect
			(at -0.2667 0 270)
			(size 0.3048 0.381)
			(layers "B.Cu" "B.Mask" "B.Paste")
			(net "GND")
		)
	)
	(footprint ""
		(layer "B.Cu")
		(at 347.726 -207.772 -90)
		(property "Reference" "R4151"
			(at 0 0 90)
			(layer "B.SilkS")
			(hide yes)
			(effects
				(font
					(size 1.27 1.27)
				)
				(justify mirror)
			)
		)
		(property "Value" ""
			(at 0 0 90)
			(layer "B.Fab")
			(effects
				(font
					(size 1.27 1.27)
				)
				(justify mirror)
			)
		)
		(duplicate_pad_numbers_are_jumpers no)
		(fp_line
			(start -0.7874 0.4064)
			(end 0.7874 0.4064)
			(stroke
				(width 0.1524)
				(type default)
			)
			(layer "B.SilkS")
		)
		(fp_line
			(start 0.7874 0.4064)
			(end 0.7874 -0.4064)
			(stroke
				(width 0.1524)
				(type default)
			)
			(layer "B.SilkS")
		)
		(fp_line
			(start -0.7874 -0.4064)
			(end -0.7874 0.4064)
			(stroke
				(width 0.1524)
				(type default)
			)
			(layer "B.SilkS")
		)
		(fp_line
			(start 0.7874 -0.4064)
			(end -0.7874 -0.4064)
			(stroke
				(width 0.1524)
				(type default)
			)
			(layer "B.SilkS")
		)
		(fp_line
			(start -0.67945 0.3048)
			(end -0.120396 0.3048)
			(stroke
				(width 0.1)
				(type default)
			)
			(layer "B.Fab")
		)
		(fp_line
			(start -0.120396 0.3048)
			(end -0.120396 0.2794)
			(stroke
				(width 0.1)
				(type default)
			)
			(layer "B.Fab")
		)
		(fp_line
			(start 0.12065 0.3048)
			(end 0.67945 0.3048)
			(stroke
				(width 0.1)
				(type default)
			)
			(layer "B.Fab")
		)
		(fp_line
			(start 0.67945 0.3048)
			(end 0.67945 -0.305054)
			(stroke
				(width 0.1)
				(type default)
			)
			(layer "B.Fab")
		)
		(fp_line
			(start -0.120396 0.2794)
			(end 0.12065 0.2794)
			(stroke
				(width 0.1)
				(type default)
			)
			(layer "B.Fab")
		)
		(fp_line
			(start 0.12065 0.2794)
			(end 0.12065 0.3048)
			(stroke
				(width 0.1)
				(type default)
			)
			(layer "B.Fab")
		)
		(fp_line
			(start -0.12065 -0.2794)
			(end -0.12065 -0.3048)
			(stroke
				(width 0.1)
				(type default)
			)
			(layer "B.Fab")
		)
		(fp_line
			(start 0.12065 -0.2794)
			(end -0.12065 -0.2794)
			(stroke
				(width 0.1)
				(type default)
			)
			(layer "B.Fab")
		)
		(fp_line
			(start -0.67945 -0.3048)
			(end -0.67945 0.3048)
			(stroke
				(width 0.1)
				(type default)
			)
			(layer "B.Fab")
		)
		(fp_line
			(start -0.12065 -0.3048)
			(end -0.67945 -0.3048)
			(stroke
				(width 0.1)
				(type default)
			)
			(layer "B.Fab")
		)
		(fp_line
			(start 0.12065 -0.305054)
			(end 0.12065 -0.2794)
			(stroke
				(width 0.1)
				(type default)
			)
			(layer "B.Fab")
		)
		(fp_line
			(start 0.67945 -0.305054)
			(end 0.12065 -0.305054)
			(stroke
				(width 0.1)
				(type default)
			)
			(layer "B.Fab")
		)
		(pad "1" smd circle
			(at 0.40005 0 90)
			(size 0 0)
			(layers "B.Cu" "B.Mask" "B.Paste")
			(net "PRSNT_SSD4_FPGA_R_N")
		)
		(pad "2" smd circle
			(at -0.40005 0 90)
			(size 0 0)
			(layers "B.Cu" "B.Mask" "B.Paste")
			(net "PRSNT_SSD4_FPGA_N")
		)
	)
	(footprint ""
		(layer "B.Cu")
		(at 357.436928 -325.336408 -90)
		(property "Reference" "C4383"
			(at 0 0 90)
			(layer "B.SilkS")
			(hide yes)
			(effects
				(font
					(size 1.27 1.27)
				)
				(justify mirror)
			)
		)
		(property "Value" ""
			(at 0 0 90)
			(layer "B.Fab")
			(effects
				(font
					(size 1.27 1.27)
				)
				(justify mirror)
			)
		)
		(duplicate_pad_numbers_are_jumpers no)
		(fp_line
			(start -1.2954 0.5842)
			(end 1.2954 0.5842)
			(stroke
				(width 0.1524)
				(type default)
			)
			(layer "B.SilkS")
		)
		(fp_line
			(start 1.2954 0.5842)
			(end 1.2954 -0.5842)
			(stroke
				(width 0.1524)
				(type default)
			)
			(layer "B.SilkS")
		)
		(fp_line
			(start -1.2954 -0.5842)
			(end -1.2954 0.5842)
			(stroke
				(width 0.1524)
				(type default)
			)
			(layer "B.SilkS")
		)
		(fp_line
			(start 1.2954 -0.5842)
			(end -1.2954 -0.5842)
			(stroke
				(width 0.1524)
				(type default)
			)
			(layer "B.SilkS")
		)
		(fp_line
			(start -0.8636 0.4572)
			(end 0.8636 0.4572)
			(stroke
				(width 0.1)
				(type default)
			)
			(layer "B.Fab")
		)
		(fp_line
			(start 0.8636 0.4572)
			(end 0.8636 0.4064)
			(stroke
				(width 0.1)
				(type default)
			)
			(layer "B.Fab")
		)
		(fp_line
			(start -1.1938 0.4064)
			(end -0.8636 0.4064)
			(stroke
				(width 0.1)
				(type default)
			)
			(layer "B.Fab")
		)
		(fp_line
			(start -0.8636 0.4064)
			(end -0.8636 0.4572)
			(stroke
				(width 0.1)
				(type default)
			)
			(layer "B.Fab")
		)
		(fp_line
			(start 0.8636 0.4064)
			(end 1.1938 0.4064)
			(stroke
				(width 0.1)
				(type default)
			)
			(layer "B.Fab")
		)
		(fp_line
			(start 1.1938 0.4064)
			(end 1.1938 -0.4064)
			(stroke
				(width 0.1)
				(type default)
			)
			(layer "B.Fab")
		)
		(fp_line
			(start -1.1938 -0.4064)
			(end -1.1938 0.4064)
			(stroke
				(width 0.1)
				(type default)
			)
			(layer "B.Fab")
		)
		(fp_line
			(start -0.8636 -0.4064)
			(end -1.1938 -0.4064)
			(stroke
				(width 0.1)
				(type default)
			)
			(layer "B.Fab")
		)
		(fp_line
			(start 0.8636 -0.4064)
			(end 0.8636 -0.4572)
			(stroke
				(width 0.1)
				(type default)
			)
			(layer "B.Fab")
		)
		(fp_line
			(start 1.1938 -0.4064)
			(end 0.8636 -0.4064)
			(stroke
				(width 0.1)
				(type default)
			)
			(layer "B.Fab")
		)
		(fp_line
			(start -0.8636 -0.4572)
			(end -0.8636 -0.4064)
			(stroke
				(width 0.1)
				(type default)
			)
			(layer "B.Fab")
		)
		(fp_line
			(start 0.8636 -0.4572)
			(end -0.8636 -0.4572)
			(stroke
				(width 0.1)
				(type default)
			)
			(layer "B.Fab")
		)
		(pad "1" smd rect
			(at 0.7366 0 180)
			(size 0.7112 0.8128)
			(layers "B.Cu" "B.Mask" "B.Paste")
			(net "P0V8_SERDES_VDDA_PEX3_C9")
		)
		(pad "2" smd rect
			(at -0.7366 0 180)
			(size 0.7112 0.8128)
			(layers "B.Cu" "B.Mask" "B.Paste")
			(net "GND")
		)
	)
	(footprint ""
		(layer "B.Cu")
		(at 184.772046 -113.437924 180)
		(property "Reference" "R163"
			(at 0 0 0)
			(layer "B.SilkS")
			(hide yes)
			(effects
				(font
					(size 1.27 1.27)
				)
				(justify mirror)
			)
		)
		(property "Value" ""
			(at 0 0 0)
			(layer "B.Fab")
			(effects
				(font
					(size 1.27 1.27)
				)
				(justify mirror)
			)
		)
		(duplicate_pad_numbers_are_jumpers no)
		(fp_line
			(start 0.7874 0.4064)
			(end 0.7874 -0.4064)
			(stroke
				(width 0.1524)
				(type default)
			)
			(layer "B.SilkS")
		)
		(fp_line
			(start 0.7874 -0.4064)
			(end -0.7874 -0.4064)
			(stroke
				(width 0.1524)
				(type default)
			)
			(layer "B.SilkS")
		)
		(fp_line
			(start -0.7874 0.4064)
			(end 0.7874 0.4064)
			(stroke
				(width 0.1524)
				(type default)
			)
			(layer "B.SilkS")
		)
		(fp_line
			(start -0.7874 -0.4064)
			(end -0.7874 0.4064)
			(stroke
				(width 0.1524)
				(type default)
			)
			(layer "B.SilkS")
		)
		(fp_line
			(start 0.67945 0.3048)
			(end 0.67945 -0.305054)
			(stroke
				(width 0.1)
				(type default)
			)
			(layer "B.Fab")
		)
		(fp_line
			(start 0.67945 -0.305054)
			(end 0.12065 -0.305054)
			(stroke
				(width 0.1)
				(type default)
			)
			(layer "B.Fab")
		)
		(fp_line
			(start 0.12065 0.3048)
			(end 0.67945 0.3048)
			(stroke
				(width 0.1)
				(type default)
			)
			(layer "B.Fab")
		)
		(fp_line
			(start 0.12065 0.2794)
			(end 0.12065 0.3048)
			(stroke
				(width 0.1)
				(type default)
			)
			(layer "B.Fab")
		)
		(fp_line
			(start 0.12065 -0.2794)
			(end -0.12065 -0.2794)
			(stroke
				(width 0.1)
				(type default)
			)
			(layer "B.Fab")
		)
		(fp_line
			(start 0.12065 -0.305054)
			(end 0.12065 -0.2794)
			(stroke
				(width 0.1)
				(type default)
			)
			(layer "B.Fab")
		)
		(fp_line
			(start -0.120396 0.3048)
			(end -0.120396 0.2794)
			(stroke
				(width 0.1)
				(type default)
			)
			(layer "B.Fab")
		)
		(fp_line
			(start -0.120396 0.2794)
			(end 0.12065 0.2794)
			(stroke
				(width 0.1)
				(type default)
			)
			(layer "B.Fab")
		)
		(fp_line
			(start -0.12065 -0.2794)
			(end -0.12065 -0.3048)
			(stroke
				(width 0.1)
				(type default)
			)
			(layer "B.Fab")
		)
		(fp_line
			(start -0.12065 -0.3048)
			(end -0.67945 -0.3048)
			(stroke
				(width 0.1)
				(type default)
			)
			(layer "B.Fab")
		)
		(fp_line
			(start -0.67945 0.3048)
			(end -0.120396 0.3048)
			(stroke
				(width 0.1)
				(type default)
			)
			(layer "B.Fab")
		)
		(fp_line
			(start -0.67945 -0.3048)
			(end -0.67945 0.3048)
			(stroke
				(width 0.1)
				(type default)
			)
			(layer "B.Fab")
		)
		(pad "1" smd circle
			(at 0.40005 0)
			(size 0 0)
			(layers "B.Cu" "B.Mask" "B.Paste")
			(net "SMB_NIC3_R_SDA")
		)
		(pad "2" smd circle
			(at -0.40005 0)
			(size 0 0)
			(layers "B.Cu" "B.Mask" "B.Paste")
			(net "P3V3_NIC3")
		)
	)
	(footprint ""
		(layer "B.Cu")
		(at 45.864272 -145.284952 180)
		(property "Reference" "C850"
			(at 0 0 0)
			(layer "B.SilkS")
			(hide yes)
			(effects
				(font
					(size 1.27 1.27)
				)
				(justify mirror)
			)
		)
		(property "Value" ""
			(at 0 0 0)
			(layer "B.Fab")
			(effects
				(font
					(size 1.27 1.27)
				)
				(justify mirror)
			)
		)
		(duplicate_pad_numbers_are_jumpers no)
		(fp_line
			(start 0.299974 0.150114)
			(end 0.299974 -0.150114)
			(stroke
				(width 0.1)
				(type default)
			)
			(layer "B.Fab")
		)
		(fp_line
			(start 0.299974 -0.150114)
			(end -0.299974 -0.150114)
			(stroke
				(width 0.1)
				(type default)
			)
			(layer "B.Fab")
		)
		(fp_line
			(start -0.299974 0.150114)
			(end 0.299974 0.150114)
			(stroke
				(width 0.1)
				(type default)
			)
			(layer "B.Fab")
		)
		(fp_line
			(start -0.299974 -0.150114)
			(end -0.299974 0.150114)
			(stroke
				(width 0.1)
				(type default)
			)
			(layer "B.Fab")
		)
		(pad "1" smd rect
			(at 0.2667 0)
			(size 0.3048 0.381)
			(layers "B.Cu" "B.Mask" "B.Paste")
			(net "P12V_NIC0")
		)
		(pad "2" smd rect
			(at -0.2667 0)
			(size 0.3048 0.381)
			(layers "B.Cu" "B.Mask" "B.Paste")
			(net "GND")
		)
	)
	(footprint ""
		(layer "B.Cu")
		(at 100.573586 -344.563954 -90)
		(property "Reference" "R6373"
			(at 0 0 90)
			(layer "B.SilkS")
			(hide yes)
			(effects
				(font
					(size 1.27 1.27)
				)
				(justify mirror)
			)
		)
		(property "Value" ""
			(at 0 0 90)
			(layer "B.Fab")
			(effects
				(font
					(size 1.27 1.27)
				)
				(justify mirror)
			)
		)
		(duplicate_pad_numbers_are_jumpers no)
		(fp_line
			(start -0.7874 0.4064)
			(end 0.7874 0.4064)
			(stroke
				(width 0.1524)
				(type default)
			)
			(layer "B.SilkS")
		)
		(fp_line
			(start 0.7874 0.4064)
			(end 0.7874 -0.4064)
			(stroke
				(width 0.1524)
				(type default)
			)
			(layer "B.SilkS")
		)
		(fp_line
			(start -0.7874 -0.4064)
			(end -0.7874 0.4064)
			(stroke
				(width 0.1524)
				(type default)
			)
			(layer "B.SilkS")
		)
		(fp_line
			(start 0.7874 -0.4064)
			(end -0.7874 -0.4064)
			(stroke
				(width 0.1524)
				(type default)
			)
			(layer "B.SilkS")
		)
		(fp_line
			(start -0.67945 0.3048)
			(end -0.120396 0.3048)
			(stroke
				(width 0.1)
				(type default)
			)
			(layer "B.Fab")
		)
		(fp_line
			(start -0.120396 0.3048)
			(end -0.120396 0.2794)
			(stroke
				(width 0.1)
				(type default)
			)
			(layer "B.Fab")
		)
		(fp_line
			(start 0.12065 0.3048)
			(end 0.67945 0.3048)
			(stroke
				(width 0.1)
				(type default)
			)
			(layer "B.Fab")
		)
		(fp_line
			(start 0.67945 0.3048)
			(end 0.67945 -0.305054)
			(stroke
				(width 0.1)
				(type default)
			)
			(layer "B.Fab")
		)
		(fp_line
			(start -0.120396 0.2794)
			(end 0.12065 0.2794)
			(stroke
				(width 0.1)
				(type default)
			)
			(layer "B.Fab")
		)
		(fp_line
			(start 0.12065 0.2794)
			(end 0.12065 0.3048)
			(stroke
				(width 0.1)
				(type default)
			)
			(layer "B.Fab")
		)
		(fp_line
			(start -0.12065 -0.2794)
			(end -0.12065 -0.3048)
			(stroke
				(width 0.1)
				(type default)
			)
			(layer "B.Fab")
		)
		(fp_line
			(start 0.12065 -0.2794)
			(end -0.12065 -0.2794)
			(stroke
				(width 0.1)
				(type default)
			)
			(layer "B.Fab")
		)
		(fp_line
			(start -0.67945 -0.3048)
			(end -0.67945 0.3048)
			(stroke
				(width 0.1)
				(type default)
			)
			(layer "B.Fab")
		)
		(fp_line
			(start -0.12065 -0.3048)
			(end -0.67945 -0.3048)
			(stroke
				(width 0.1)
				(type default)
			)
			(layer "B.Fab")
		)
		(fp_line
			(start 0.12065 -0.305054)
			(end 0.12065 -0.2794)
			(stroke
				(width 0.1)
				(type default)
			)
			(layer "B.Fab")
		)
		(fp_line
			(start 0.67945 -0.305054)
			(end 0.12065 -0.305054)
			(stroke
				(width 0.1)
				(type default)
			)
			(layer "B.Fab")
		)
		(pad "1" smd circle
			(at 0.40005 0 90)
			(size 0 0)
			(layers "B.Cu" "B.Mask" "B.Paste")
			(net "GND")
		)
		(pad "2" smd circle
			(at -0.40005 0 90)
			(size 0 0)
			(layers "B.Cu" "B.Mask" "B.Paste")
			(net "SMB_9ZXL0451E_S3_ADDR0")
		)
	)
	(footprint ""
		(layer "B.Cu")
		(at 126.078488 -282.040584 90)
		(property "Reference" "PR109"
			(at 0 0 90)
			(layer "B.SilkS")
			(hide yes)
			(effects
				(font
					(size 1.27 1.27)
				)
				(justify mirror)
			)
		)
		(property "Value" ""
			(at 0 0 90)
			(layer "B.Fab")
			(effects
				(font
					(size 1.27 1.27)
				)
				(justify mirror)
			)
		)
		(duplicate_pad_numbers_are_jumpers no)
		(fp_line
			(start 0.7874 -0.4064)
			(end -0.7874 -0.4064)
			(stroke
				(width 0.1524)
				(type default)
			)
			(layer "B.SilkS")
		)
		(fp_line
			(start -0.7874 -0.4064)
			(end -0.7874 0.4064)
			(stroke
				(width 0.1524)
				(type default)
			)
			(layer "B.SilkS")
		)
		(fp_line
			(start 0.7874 0.4064)
			(end 0.7874 -0.4064)
			(stroke
				(width 0.1524)
				(type default)
			)
			(layer "B.SilkS")
		)
		(fp_line
			(start -0.7874 0.4064)
			(end 0.7874 0.4064)
			(stroke
				(width 0.1524)
				(type default)
			)
			(layer "B.SilkS")
		)
		(fp_line
			(start 0.67945 -0.305054)
			(end 0.12065 -0.305054)
			(stroke
				(width 0.1)
				(type default)
			)
			(layer "B.Fab")
		)
		(fp_line
			(start 0.12065 -0.305054)
			(end 0.12065 -0.2794)
			(stroke
				(width 0.1)
				(type default)
			)
			(layer "B.Fab")
		)
		(fp_line
			(start -0.12065 -0.3048)
			(end -0.67945 -0.3048)
			(stroke
				(width 0.1)
				(type default)
			)
			(layer "B.Fab")
		)
		(fp_line
			(start -0.67945 -0.3048)
			(end -0.67945 0.3048)
			(stroke
				(width 0.1)
				(type default)
			)
			(layer "B.Fab")
		)
		(fp_line
			(start 0.12065 -0.2794)
			(end -0.12065 -0.2794)
			(stroke
				(width 0.1)
				(type default)
			)
			(layer "B.Fab")
		)
		(fp_line
			(start -0.12065 -0.2794)
			(end -0.12065 -0.3048)
			(stroke
				(width 0.1)
				(type default)
			)
			(layer "B.Fab")
		)
		(fp_line
			(start 0.12065 0.2794)
			(end 0.12065 0.3048)
			(stroke
				(width 0.1)
				(type default)
			)
			(layer "B.Fab")
		)
		(fp_line
			(start -0.120396 0.2794)
			(end 0.12065 0.2794)
			(stroke
				(width 0.1)
				(type default)
			)
			(layer "B.Fab")
		)
		(fp_line
			(start 0.67945 0.3048)
			(end 0.67945 -0.305054)
			(stroke
				(width 0.1)
				(type default)
			)
			(layer "B.Fab")
		)
		(fp_line
			(start 0.12065 0.3048)
			(end 0.67945 0.3048)
			(stroke
				(width 0.1)
				(type default)
			)
			(layer "B.Fab")
		)
		(fp_line
			(start -0.120396 0.3048)
			(end -0.120396 0.2794)
			(stroke
				(width 0.1)
				(type default)
			)
			(layer "B.Fab")
		)
		(fp_line
			(start -0.67945 0.3048)
			(end -0.120396 0.3048)
			(stroke
				(width 0.1)
				(type default)
			)
			(layer "B.Fab")
		)
		(pad "1" smd circle
			(at 0.40005 0 270)
			(size 0 0)
			(layers "B.Cu" "B.Mask" "B.Paste")
			(net "SW_P0V8_PEX1_VOS1")
		)
		(pad "2" smd circle
			(at -0.40005 0 270)
			(size 0 0)
			(layers "B.Cu" "B.Mask" "B.Paste")
			(net "P0V8_PEX1")
		)
	)
	(footprint ""
		(layer "B.Cu")
		(at 403.199854 -301.599854 -90)
		(property "Reference" "C1974"
			(at 0 0 90)
			(layer "B.SilkS")
			(hide yes)
			(effects
				(font
					(size 1.27 1.27)
				)
				(justify mirror)
			)
		)
		(property "Value" ""
			(at 0 0 90)
			(layer "B.Fab")
			(effects
				(font
					(size 1.27 1.27)
				)
				(justify mirror)
			)
		)
		(duplicate_pad_numbers_are_jumpers no)
		(fp_line
			(start -0.299974 0.150114)
			(end 0.299974 0.150114)
			(stroke
				(width 0.1)
				(type default)
			)
			(layer "B.Fab")
		)
		(fp_line
			(start 0.299974 0.150114)
			(end 0.299974 -0.150114)
			(stroke
				(width 0.1)
				(type default)
			)
			(layer "B.Fab")
		)
		(fp_line
			(start -0.299974 -0.150114)
			(end -0.299974 0.150114)
			(stroke
				(width 0.1)
				(type default)
			)
			(layer "B.Fab")
		)
		(fp_line
			(start 0.299974 -0.150114)
			(end -0.299974 -0.150114)
			(stroke
				(width 0.1)
				(type default)
			)
			(layer "B.Fab")
		)
		(pad "1" smd rect
			(at 0.2667 0 90)
			(size 0.3048 0.381)
			(layers "B.Cu" "B.Mask" "B.Paste")
			(net "P0V8_SERDES_VDDA_PEX3")
		)
		(pad "2" smd rect
			(at -0.2667 0 90)
			(size 0.3048 0.381)
			(layers "B.Cu" "B.Mask" "B.Paste")
			(net "GND")
		)
	)
	(footprint ""
		(layer "B.Cu")
		(at 177.649886 -292.099746 90)
		(property "Reference" "C1464"
			(at 0 0 90)
			(layer "B.SilkS")
			(hide yes)
			(effects
				(font
					(size 1.27 1.27)
				)
				(justify mirror)
			)
		)
		(property "Value" ""
			(at 0 0 90)
			(layer "B.Fab")
			(effects
				(font
					(size 1.27 1.27)
				)
				(justify mirror)
			)
		)
		(duplicate_pad_numbers_are_jumpers no)
		(fp_line
			(start 0.299974 -0.150114)
			(end -0.299974 -0.150114)
			(stroke
				(width 0.1)
				(type default)
			)
			(layer "B.Fab")
		)
		(fp_line
			(start -0.299974 -0.150114)
			(end -0.299974 0.150114)
			(stroke
				(width 0.1)
				(type default)
			)
			(layer "B.Fab")
		)
		(fp_line
			(start 0.299974 0.150114)
			(end 0.299974 -0.150114)
			(stroke
				(width 0.1)
				(type default)
			)
			(layer "B.Fab")
		)
		(fp_line
			(start -0.299974 0.150114)
			(end 0.299974 0.150114)
			(stroke
				(width 0.1)
				(type default)
			)
			(layer "B.Fab")
		)
		(pad "1" smd rect
			(at 0.2667 0 270)
			(size 0.3048 0.381)
			(layers "B.Cu" "B.Mask" "B.Paste")
			(net "P0V8_SERDES_VDDA_PEX1")
		)
		(pad "2" smd rect
			(at -0.2667 0 270)
			(size 0.3048 0.381)
			(layers "B.Cu" "B.Mask" "B.Paste")
			(net "GND")
		)
	)
	(footprint ""
		(layer "B.Cu")
		(at 360.24312 -324.163944 -90)
		(property "Reference" "C4382"
			(at 0 0 90)
			(layer "B.SilkS")
			(hide yes)
			(effects
				(font
					(size 1.27 1.27)
				)
				(justify mirror)
			)
		)
		(property "Value" ""
			(at 0 0 90)
			(layer "B.Fab")
			(effects
				(font
					(size 1.27 1.27)
				)
				(justify mirror)
			)
		)
		(duplicate_pad_numbers_are_jumpers no)
		(fp_line
			(start -1.2954 0.5842)
			(end 1.2954 0.5842)
			(stroke
				(width 0.1524)
				(type default)
			)
			(layer "B.SilkS")
		)
		(fp_line
			(start 1.2954 0.5842)
			(end 1.2954 -0.5842)
			(stroke
				(width 0.1524)
				(type default)
			)
			(layer "B.SilkS")
		)
		(fp_line
			(start -1.2954 -0.5842)
			(end -1.2954 0.5842)
			(stroke
				(width 0.1524)
				(type default)
			)
			(layer "B.SilkS")
		)
		(fp_line
			(start 1.2954 -0.5842)
			(end -1.2954 -0.5842)
			(stroke
				(width 0.1524)
				(type default)
			)
			(layer "B.SilkS")
		)
		(fp_line
			(start -0.8636 0.4572)
			(end 0.8636 0.4572)
			(stroke
				(width 0.1)
				(type default)
			)
			(layer "B.Fab")
		)
		(fp_line
			(start 0.8636 0.4572)
			(end 0.8636 0.4064)
			(stroke
				(width 0.1)
				(type default)
			)
			(layer "B.Fab")
		)
		(fp_line
			(start -1.1938 0.4064)
			(end -0.8636 0.4064)
			(stroke
				(width 0.1)
				(type default)
			)
			(layer "B.Fab")
		)
		(fp_line
			(start -0.8636 0.4064)
			(end -0.8636 0.4572)
			(stroke
				(width 0.1)
				(type default)
			)
			(layer "B.Fab")
		)
		(fp_line
			(start 0.8636 0.4064)
			(end 1.1938 0.4064)
			(stroke
				(width 0.1)
				(type default)
			)
			(layer "B.Fab")
		)
		(fp_line
			(start 1.1938 0.4064)
			(end 1.1938 -0.4064)
			(stroke
				(width 0.1)
				(type default)
			)
			(layer "B.Fab")
		)
		(fp_line
			(start -1.1938 -0.4064)
			(end -1.1938 0.4064)
			(stroke
				(width 0.1)
				(type default)
			)
			(layer "B.Fab")
		)
		(fp_line
			(start -0.8636 -0.4064)
			(end -1.1938 -0.4064)
			(stroke
				(width 0.1)
				(type default)
			)
			(layer "B.Fab")
		)
		(fp_line
			(start 0.8636 -0.4064)
			(end 0.8636 -0.4572)
			(stroke
				(width 0.1)
				(type default)
			)
			(layer "B.Fab")
		)
		(fp_line
			(start 1.1938 -0.4064)
			(end 0.8636 -0.4064)
			(stroke
				(width 0.1)
				(type default)
			)
			(layer "B.Fab")
		)
		(fp_line
			(start -0.8636 -0.4572)
			(end -0.8636 -0.4064)
			(stroke
				(width 0.1)
				(type default)
			)
			(layer "B.Fab")
		)
		(fp_line
			(start 0.8636 -0.4572)
			(end -0.8636 -0.4572)
			(stroke
				(width 0.1)
				(type default)
			)
			(layer "B.Fab")
		)
		(pad "1" smd rect
			(at 0.7366 0 180)
			(size 0.7112 0.8128)
			(layers "B.Cu" "B.Mask" "B.Paste")
			(net "P0V8_SERDES_VDDA_PEX3_C8")
		)
		(pad "2" smd rect
			(at -0.7366 0 180)
			(size 0.7112 0.8128)
			(layers "B.Cu" "B.Mask" "B.Paste")
			(net "GND")
		)
	)
	(footprint ""
		(layer "B.Cu")
		(at 181.44998 -288.299906 90)
		(property "Reference" "C3108"
			(at 0 0 90)
			(layer "B.SilkS")
			(hide yes)
			(effects
				(font
					(size 1.27 1.27)
				)
				(justify mirror)
			)
		)
		(property "Value" ""
			(at 0 0 90)
			(layer "B.Fab")
			(effects
				(font
					(size 1.27 1.27)
				)
				(justify mirror)
			)
		)
		(duplicate_pad_numbers_are_jumpers no)
		(fp_line
			(start 0.299974 -0.150114)
			(end -0.299974 -0.150114)
			(stroke
				(width 0.1)
				(type default)
			)
			(layer "B.Fab")
		)
		(fp_line
			(start -0.299974 -0.150114)
			(end -0.299974 0.150114)
			(stroke
				(width 0.1)
				(type default)
			)
			(layer "B.Fab")
		)
		(fp_line
			(start 0.299974 0.150114)
			(end 0.299974 -0.150114)
			(stroke
				(width 0.1)
				(type default)
			)
			(layer "B.Fab")
		)
		(fp_line
			(start -0.299974 0.150114)
			(end 0.299974 0.150114)
			(stroke
				(width 0.1)
				(type default)
			)
			(layer "B.Fab")
		)
		(pad "1" smd rect
			(at 0.2667 0 270)
			(size 0.3048 0.381)
			(layers "B.Cu" "B.Mask" "B.Paste")
			(net "P1V25_PEX1")
		)
		(pad "2" smd rect
			(at -0.2667 0 270)
			(size 0.3048 0.381)
			(layers "B.Cu" "B.Mask" "B.Paste")
			(net "GND")
		)
	)
	(footprint ""
		(layer "B.Cu")
		(at 389.443976 -247.161304 90)
		(property "Reference" "R937"
			(at 0 0 90)
			(layer "B.SilkS")
			(hide yes)
			(effects
				(font
					(size 1.27 1.27)
				)
				(justify mirror)
			)
		)
		(property "Value" ""
			(at 0 0 90)
			(layer "B.Fab")
			(effects
				(font
					(size 1.27 1.27)
				)
				(justify mirror)
			)
		)
		(duplicate_pad_numbers_are_jumpers no)
		(fp_line
			(start 0.7874 -0.4064)
			(end -0.7874 -0.4064)
			(stroke
				(width 0.1524)
				(type default)
			)
			(layer "B.SilkS")
		)
		(fp_line
			(start -0.7874 -0.4064)
			(end -0.7874 0.4064)
			(stroke
				(width 0.1524)
				(type default)
			)
			(layer "B.SilkS")
		)
		(fp_line
			(start 0.7874 0.4064)
			(end 0.7874 -0.4064)
			(stroke
				(width 0.1524)
				(type default)
			)
			(layer "B.SilkS")
		)
		(fp_line
			(start -0.7874 0.4064)
			(end 0.7874 0.4064)
			(stroke
				(width 0.1524)
				(type default)
			)
			(layer "B.SilkS")
		)
		(fp_line
			(start 0.67945 -0.305054)
			(end 0.12065 -0.305054)
			(stroke
				(width 0.1)
				(type default)
			)
			(layer "B.Fab")
		)
		(fp_line
			(start 0.12065 -0.305054)
			(end 0.12065 -0.2794)
			(stroke
				(width 0.1)
				(type default)
			)
			(layer "B.Fab")
		)
		(fp_line
			(start -0.12065 -0.3048)
			(end -0.67945 -0.3048)
			(stroke
				(width 0.1)
				(type default)
			)
			(layer "B.Fab")
		)
		(fp_line
			(start -0.67945 -0.3048)
			(end -0.67945 0.3048)
			(stroke
				(width 0.1)
				(type default)
			)
			(layer "B.Fab")
		)
		(fp_line
			(start 0.12065 -0.2794)
			(end -0.12065 -0.2794)
			(stroke
				(width 0.1)
				(type default)
			)
			(layer "B.Fab")
		)
		(fp_line
			(start -0.12065 -0.2794)
			(end -0.12065 -0.3048)
			(stroke
				(width 0.1)
				(type default)
			)
			(layer "B.Fab")
		)
		(fp_line
			(start 0.12065 0.2794)
			(end 0.12065 0.3048)
			(stroke
				(width 0.1)
				(type default)
			)
			(layer "B.Fab")
		)
		(fp_line
			(start -0.120396 0.2794)
			(end 0.12065 0.2794)
			(stroke
				(width 0.1)
				(type default)
			)
			(layer "B.Fab")
		)
		(fp_line
			(start 0.67945 0.3048)
			(end 0.67945 -0.305054)
			(stroke
				(width 0.1)
				(type default)
			)
			(layer "B.Fab")
		)
		(fp_line
			(start 0.12065 0.3048)
			(end 0.67945 0.3048)
			(stroke
				(width 0.1)
				(type default)
			)
			(layer "B.Fab")
		)
		(fp_line
			(start -0.120396 0.3048)
			(end -0.120396 0.2794)
			(stroke
				(width 0.1)
				(type default)
			)
			(layer "B.Fab")
		)
		(fp_line
			(start -0.67945 0.3048)
			(end -0.120396 0.3048)
			(stroke
				(width 0.1)
				(type default)
			)
			(layer "B.Fab")
		)
		(pad "1" smd circle
			(at 0.40005 0 270)
			(size 0 0)
			(layers "B.Cu" "B.Mask" "B.Paste")
			(net "UART_PEX2_SDB_BUF_RX")
		)
		(pad "2" smd circle
			(at -0.40005 0 270)
			(size 0 0)
			(layers "B.Cu" "B.Mask" "B.Paste")
			(net "P1V8_PEX")
		)
	)
	(footprint ""
		(layer "B.Cu")
		(at 49.5554 -154.0256)
		(property "Reference" "R21"
			(at 0 0 0)
			(layer "B.SilkS")
			(hide yes)
			(effects
				(font
					(size 1.27 1.27)
				)
				(justify mirror)
			)
		)
		(property "Value" ""
			(at 0 0 0)
			(layer "B.Fab")
			(effects
				(font
					(size 1.27 1.27)
				)
				(justify mirror)
			)
		)
		(duplicate_pad_numbers_are_jumpers no)
		(fp_line
			(start -0.7874 -0.4064)
			(end -0.7874 0.4064)
			(stroke
				(width 0.1524)
				(type default)
			)
			(layer "B.SilkS")
		)
		(fp_line
			(start -0.7874 0.4064)
			(end 0.7874 0.4064)
			(stroke
				(width 0.1524)
				(type default)
			)
			(layer "B.SilkS")
		)
		(fp_line
			(start 0.7874 -0.4064)
			(end -0.7874 -0.4064)
			(stroke
				(width 0.1524)
				(type default)
			)
			(layer "B.SilkS")
		)
		(fp_line
			(start 0.7874 0.4064)
			(end 0.7874 -0.4064)
			(stroke
				(width 0.1524)
				(type default)
			)
			(layer "B.SilkS")
		)
		(fp_line
			(start -0.67945 -0.3048)
			(end -0.67945 0.3048)
			(stroke
				(width 0.1)
				(type default)
			)
			(layer "B.Fab")
		)
		(fp_line
			(start -0.67945 0.3048)
			(end -0.120396 0.3048)
			(stroke
				(width 0.1)
				(type default)
			)
			(layer "B.Fab")
		)
		(fp_line
			(start -0.12065 -0.3048)
			(end -0.67945 -0.3048)
			(stroke
				(width 0.1)
				(type default)
			)
			(layer "B.Fab")
		)
		(fp_line
			(start -0.12065 -0.2794)
			(end -0.12065 -0.3048)
			(stroke
				(width 0.1)
				(type default)
			)
			(layer "B.Fab")
		)
		(fp_line
			(start -0.120396 0.2794)
			(end 0.12065 0.2794)
			(stroke
				(width 0.1)
				(type default)
			)
			(layer "B.Fab")
		)
		(fp_line
			(start -0.120396 0.3048)
			(end -0.120396 0.2794)
			(stroke
				(width 0.1)
				(type default)
			)
			(layer "B.Fab")
		)
		(fp_line
			(start 0.12065 -0.305054)
			(end 0.12065 -0.2794)
			(stroke
				(width 0.1)
				(type default)
			)
			(layer "B.Fab")
		)
		(fp_line
			(start 0.12065 -0.2794)
			(end -0.12065 -0.2794)
			(stroke
				(width 0.1)
				(type default)
			)
			(layer "B.Fab")
		)
		(fp_line
			(start 0.12065 0.2794)
			(end 0.12065 0.3048)
			(stroke
				(width 0.1)
				(type default)
			)
			(layer "B.Fab")
		)
		(fp_line
			(start 0.12065 0.3048)
			(end 0.67945 0.3048)
			(stroke
				(width 0.1)
				(type default)
			)
			(layer "B.Fab")
		)
		(fp_line
			(start 0.67945 -0.305054)
			(end 0.12065 -0.305054)
			(stroke
				(width 0.1)
				(type default)
			)
			(layer "B.Fab")
		)
		(fp_line
			(start 0.67945 0.3048)
			(end 0.67945 -0.305054)
			(stroke
				(width 0.1)
				(type default)
			)
			(layer "B.Fab")
		)
		(pad "1" smd circle
			(at 0.40005 0 180)
			(size 0 0)
			(layers "B.Cu" "B.Mask" "B.Paste")
			(net "NCSI_NIC0_TX_EN")
		)
		(pad "2" smd circle
			(at -0.40005 0 180)
			(size 0 0)
			(layers "B.Cu" "B.Mask" "B.Paste")
			(net "GND")
		)
	)
	(footprint ""
		(layer "B.Cu")
		(at 273.799808 -288.774886 90)
		(property "Reference" "R6159"
			(at 0 0 90)
			(layer "B.SilkS")
			(hide yes)
			(effects
				(font
					(size 1.27 1.27)
				)
				(justify mirror)
			)
		)
		(property "Value" ""
			(at 0 0 90)
			(layer "B.Fab")
			(effects
				(font
					(size 1.27 1.27)
				)
				(justify mirror)
			)
		)
		(duplicate_pad_numbers_are_jumpers no)
		(fp_line
			(start 0.7874 -0.4064)
			(end -0.7874 -0.4064)
			(stroke
				(width 0.1524)
				(type default)
			)
			(layer "B.SilkS")
		)
		(fp_line
			(start -0.7874 -0.4064)
			(end -0.7874 0.4064)
			(stroke
				(width 0.1524)
				(type default)
			)
			(layer "B.SilkS")
		)
		(fp_line
			(start 0.7874 0.4064)
			(end 0.7874 -0.4064)
			(stroke
				(width 0.1524)
				(type default)
			)
			(layer "B.SilkS")
		)
		(fp_line
			(start -0.7874 0.4064)
			(end 0.7874 0.4064)
			(stroke
				(width 0.1524)
				(type default)
			)
			(layer "B.SilkS")
		)
		(fp_line
			(start 0.67945 -0.305054)
			(end 0.12065 -0.305054)
			(stroke
				(width 0.1)
				(type default)
			)
			(layer "B.Fab")
		)
		(fp_line
			(start 0.12065 -0.305054)
			(end 0.12065 -0.2794)
			(stroke
				(width 0.1)
				(type default)
			)
			(layer "B.Fab")
		)
		(fp_line
			(start -0.12065 -0.3048)
			(end -0.67945 -0.3048)
			(stroke
				(width 0.1)
				(type default)
			)
			(layer "B.Fab")
		)
		(fp_line
			(start -0.67945 -0.3048)
			(end -0.67945 0.3048)
			(stroke
				(width 0.1)
				(type default)
			)
			(layer "B.Fab")
		)
		(fp_line
			(start 0.12065 -0.2794)
			(end -0.12065 -0.2794)
			(stroke
				(width 0.1)
				(type default)
			)
			(layer "B.Fab")
		)
		(fp_line
			(start -0.12065 -0.2794)
			(end -0.12065 -0.3048)
			(stroke
				(width 0.1)
				(type default)
			)
			(layer "B.Fab")
		)
		(fp_line
			(start 0.12065 0.2794)
			(end 0.12065 0.3048)
			(stroke
				(width 0.1)
				(type default)
			)
			(layer "B.Fab")
		)
		(fp_line
			(start -0.120396 0.2794)
			(end 0.12065 0.2794)
			(stroke
				(width 0.1)
				(type default)
			)
			(layer "B.Fab")
		)
		(fp_line
			(start 0.67945 0.3048)
			(end 0.67945 -0.305054)
			(stroke
				(width 0.1)
				(type default)
			)
			(layer "B.Fab")
		)
		(fp_line
			(start 0.12065 0.3048)
			(end 0.67945 0.3048)
			(stroke
				(width 0.1)
				(type default)
			)
			(layer "B.Fab")
		)
		(fp_line
			(start -0.120396 0.3048)
			(end -0.120396 0.2794)
			(stroke
				(width 0.1)
				(type default)
			)
			(layer "B.Fab")
		)
		(fp_line
			(start -0.67945 0.3048)
			(end -0.120396 0.3048)
			(stroke
				(width 0.1)
				(type default)
			)
			(layer "B.Fab")
		)
		(pad "1" smd circle
			(at 0.40005 0 270)
			(size 0 0)
			(layers "B.Cu" "B.Mask" "B.Paste")
			(net "SPI_PEX2_CS_N")
		)
		(pad "2" smd circle
			(at -0.40005 0 270)
			(size 0 0)
			(layers "B.Cu" "B.Mask" "B.Paste")
			(net "P1V8_PEX")
		)
	)
	(footprint ""
		(layer "B.Cu")
		(at 128.095248 -174.746412)
		(property "Reference" "R1083"
			(at 0 0 0)
			(layer "B.SilkS")
			(hide yes)
			(effects
				(font
					(size 1.27 1.27)
				)
				(justify mirror)
			)
		)
		(property "Value" ""
			(at 0 0 0)
			(layer "B.Fab")
			(effects
				(font
					(size 1.27 1.27)
				)
				(justify mirror)
			)
		)
		(duplicate_pad_numbers_are_jumpers no)
		(fp_line
			(start -1.2954 -0.5842)
			(end -1.2954 0.5842)
			(stroke
				(width 0.1524)
				(type default)
			)
			(layer "B.SilkS")
		)
		(fp_line
			(start -1.2954 0.5842)
			(end 1.2954 0.5842)
			(stroke
				(width 0.1524)
				(type default)
			)
			(layer "B.SilkS")
		)
		(fp_line
			(start 1.2954 -0.5842)
			(end -1.2954 -0.5842)
			(stroke
				(width 0.1524)
				(type default)
			)
			(layer "B.SilkS")
		)
		(fp_line
			(start 1.2954 0.5842)
			(end 1.2954 -0.5842)
			(stroke
				(width 0.1524)
				(type default)
			)
			(layer "B.SilkS")
		)
		(fp_line
			(start -1.1938 -0.406654)
			(end -1.1938 0.4064)
			(stroke
				(width 0.1)
				(type default)
			)
			(layer "B.Fab")
		)
		(fp_line
			(start -1.1938 0.4064)
			(end -0.8636 0.4064)
			(stroke
				(width 0.1)
				(type default)
			)
			(layer "B.Fab")
		)
		(fp_line
			(start -0.8636 -0.4572)
			(end -0.8636 -0.406654)
			(stroke
				(width 0.1)
				(type default)
			)
			(layer "B.Fab")
		)
		(fp_line
			(start -0.8636 -0.406654)
			(end -1.1938 -0.406654)
			(stroke
				(width 0.1)
				(type default)
			)
			(layer "B.Fab")
		)
		(fp_line
			(start -0.8636 0.4064)
			(end -0.8636 0.4572)
			(stroke
				(width 0.1)
				(type default)
			)
			(layer "B.Fab")
		)
		(fp_line
			(start -0.8636 0.4572)
			(end 0.8636 0.4572)
			(stroke
				(width 0.1)
				(type default)
			)
			(layer "B.Fab")
		)
		(fp_line
			(start 0.8636 -0.4572)
			(end -0.8636 -0.4572)
			(stroke
				(width 0.1)
				(type default)
			)
			(layer "B.Fab")
		)
		(fp_line
			(start 0.8636 -0.406654)
			(end 0.8636 -0.4572)
			(stroke
				(width 0.1)
				(type default)
			)
			(layer "B.Fab")
		)
		(fp_line
			(start 0.8636 0.4064)
			(end 1.1938 0.4064)
			(stroke
				(width 0.1)
				(type default)
			)
			(layer "B.Fab")
		)
		(fp_line
			(start 0.8636 0.4318)
			(end 0.8636 0.4064)
			(stroke
				(width 0.1)
				(type default)
			)
			(layer "B.Fab")
		)
		(fp_line
			(start 0.8636 0.4572)
			(end 0.8636 0.4318)
			(stroke
				(width 0.1)
				(type default)
			)
			(layer "B.Fab")
		)
		(fp_line
			(start 1.1938 -0.406654)
			(end 0.8636 -0.406654)
			(stroke
				(width 0.1)
				(type default)
			)
			(layer "B.Fab")
		)
		(fp_line
			(start 1.1938 0.4064)
			(end 1.1938 -0.406654)
			(stroke
				(width 0.1)
				(type default)
			)
			(layer "B.Fab")
		)
		(pad "1" smd rect
			(at 0.7366 0 270)
			(size 0.7112 0.8128)
			(layers "B.Cu" "B.Mask" "B.Paste")
			(net "P3V3_DB2000QL_VDDR")
		)
		(pad "2" smd rect
			(at -0.7366 0 270)
			(size 0.7112 0.8128)
			(layers "B.Cu" "B.Mask" "B.Paste")
			(net "P3V3_DB2000QL_FB_VDD")
		)
	)
	(footprint ""
		(layer "B.Cu")
		(at 59.561476 -161.463736 180)
		(property "Reference" "Q1"
			(at 0.072136 1.843786 0)
			(unlocked yes)
			(layer "B.SilkS")
			(effects
				(font
					(size 0.7874 0.5842)
					(thickness 0.1524)
				)
				(justify mirror)
			)
		)
		(property "Value" ""
			(at 0 0 0)
			(layer "B.Fab")
			(effects
				(font
					(size 1.27 1.27)
				)
				(justify mirror)
			)
		)
		(duplicate_pad_numbers_are_jumpers no)
		(fp_line
			(start 1.38176 1.100074)
			(end -1.38176 1.100074)
			(stroke
				(width 0.1524)
				(type default)
			)
			(layer "B.SilkS")
		)
		(fp_line
			(start 1.38176 -1.100074)
			(end 1.38176 1.100074)
			(stroke
				(width 0.1524)
				(type default)
			)
			(layer "B.SilkS")
		)
		(fp_line
			(start 0.592074 -1.100074)
			(end 1.38176 -1.100074)
			(stroke
				(width 0.1524)
				(type default)
			)
			(layer "B.SilkS")
		)
		(fp_line
			(start 0 -0.508)
			(end 0.592074 -1.100074)
			(stroke
				(width 0.1524)
				(type default)
			)
			(layer "B.SilkS")
		)
		(fp_line
			(start -0.592074 -1.100074)
			(end 0 -0.508)
			(stroke
				(width 0.1524)
				(type default)
			)
			(layer "B.SilkS")
		)
		(fp_line
			(start -1.38176 1.100074)
			(end -1.38176 -1.100074)
			(stroke
				(width 0.1524)
				(type default)
			)
			(layer "B.SilkS")
		)
		(fp_line
			(start -1.38176 -1.100074)
			(end -0.592074 -1.100074)
			(stroke
				(width 0.1524)
				(type default)
			)
			(layer "B.SilkS")
		)
		(fp_poly
			(pts
				(xy 1.9431 -0.870204) (xy 1.50241 -0.649986) (xy 1.9431 -0.429768)
			)
			(stroke
				(width 0)
				(type default)
			)
			(fill yes)
			(layer "B.SilkS")
		)
		(fp_line
			(start 0.674878 1.100074)
			(end -0.674878 1.100074)
			(stroke
				(width 0.1)
				(type default)
			)
			(layer "B.Fab")
		)
		(fp_line
			(start 0.674878 -1.100074)
			(end 0.674878 1.100074)
			(stroke
				(width 0.1)
				(type default)
			)
			(layer "B.Fab")
		)
		(fp_line
			(start -0.674878 1.100074)
			(end -0.674878 -1.100074)
			(stroke
				(width 0.1)
				(type default)
			)
			(layer "B.Fab")
		)
		(fp_line
			(start -0.674878 -1.100074)
			(end 0.674878 -1.100074)
			(stroke
				(width 0.1)
				(type default)
			)
			(layer "B.Fab")
		)
		(fp_poly
			(pts
				(xy 1.9431 -0.870204) (xy 1.50241 -0.649986) (xy 1.9431 -0.429768)
			)
			(stroke
				(width 0)
				(type default)
			)
			(fill yes)
			(layer "B.Fab")
		)
		(pad "1" smd rect
			(at 0.94996 -0.649986 90)
			(size 0.4318 0.6096)
			(layers "B.Cu" "B.Mask" "B.Paste")
			(net "GND")
		)
		(pad "2" smd rect
			(at 0.94996 0 90)
			(size 0.4318 0.6096)
			(layers "B.Cu" "B.Mask" "B.Paste")
			(net "HP_NIC0_HSC_PWRGD_N")
		)
		(pad "3" smd rect
			(at 0.94996 0.649986 90)
			(size 0.4318 0.6096)
			(layers "B.Cu" "B.Mask" "B.Paste")
			(net "HP_NIC0_HSC_PWRGD_N")
		)
		(pad "4" smd rect
			(at -0.94996 0.649986 90)
			(size 0.4318 0.6096)
			(layers "B.Cu" "B.Mask" "B.Paste")
			(net "GND")
		)
		(pad "5" smd rect
			(at -0.94996 0 90)
			(size 0.4318 0.6096)
			(layers "B.Cu" "B.Mask" "B.Paste")
			(net "PWRGD_P12V_NIC0_R")
		)
		(pad "6" smd rect
			(at -0.94996 -0.649986 90)
			(size 0.4318 0.6096)
			(layers "B.Cu" "B.Mask" "B.Paste")
			(net "HP_NIC0_PWRGD_R")
		)
	)
	(footprint ""
		(layer "B.Cu")
		(at 256.87401 -222.299276 180)
		(property "Reference" "C2759"
			(at 0 0 0)
			(layer "B.SilkS")
			(hide yes)
			(effects
				(font
					(size 1.27 1.27)
				)
				(justify mirror)
			)
		)
		(property "Value" ""
			(at 0 0 0)
			(layer "B.Fab")
			(effects
				(font
					(size 1.27 1.27)
				)
				(justify mirror)
			)
		)
		(duplicate_pad_numbers_are_jumpers no)
		(fp_line
			(start 0.7874 0.4064)
			(end 0.7874 -0.4064)
			(stroke
				(width 0.1524)
				(type default)
			)
			(layer "B.SilkS")
		)
		(fp_line
			(start 0.7874 -0.4064)
			(end -0.7874 -0.4064)
			(stroke
				(width 0.1524)
				(type default)
			)
			(layer "B.SilkS")
		)
		(fp_line
			(start -0.7874 0.4064)
			(end 0.7874 0.4064)
			(stroke
				(width 0.1524)
				(type default)
			)
			(layer "B.SilkS")
		)
		(fp_line
			(start -0.7874 -0.4064)
			(end -0.7874 0.4064)
			(stroke
				(width 0.1524)
				(type default)
			)
			(layer "B.SilkS")
		)
		(fp_line
			(start 0.67945 0.3048)
			(end 0.67945 -0.305054)
			(stroke
				(width 0.1)
				(type default)
			)
			(layer "B.Fab")
		)
		(fp_line
			(start 0.67945 -0.305054)
			(end 0.12065 -0.305054)
			(stroke
				(width 0.1)
				(type default)
			)
			(layer "B.Fab")
		)
		(fp_line
			(start 0.12065 0.3048)
			(end 0.67945 0.3048)
			(stroke
				(width 0.1)
				(type default)
			)
			(layer "B.Fab")
		)
		(fp_line
			(start 0.12065 0.2794)
			(end 0.12065 0.3048)
			(stroke
				(width 0.1)
				(type default)
			)
			(layer "B.Fab")
		)
		(fp_line
			(start 0.12065 -0.2794)
			(end -0.12065 -0.2794)
			(stroke
				(width 0.1)
				(type default)
			)
			(layer "B.Fab")
		)
		(fp_line
			(start 0.12065 -0.305054)
			(end 0.12065 -0.2794)
			(stroke
				(width 0.1)
				(type default)
			)
			(layer "B.Fab")
		)
		(fp_line
			(start -0.120396 0.3048)
			(end -0.120396 0.2794)
			(stroke
				(width 0.1)
				(type default)
			)
			(layer "B.Fab")
		)
		(fp_line
			(start -0.120396 0.2794)
			(end 0.12065 0.2794)
			(stroke
				(width 0.1)
				(type default)
			)
			(layer "B.Fab")
		)
		(fp_line
			(start -0.12065 -0.2794)
			(end -0.12065 -0.3048)
			(stroke
				(width 0.1)
				(type default)
			)
			(layer "B.Fab")
		)
		(fp_line
			(start -0.12065 -0.3048)
			(end -0.67945 -0.3048)
			(stroke
				(width 0.1)
				(type default)
			)
			(layer "B.Fab")
		)
		(fp_line
			(start -0.67945 0.3048)
			(end -0.120396 0.3048)
			(stroke
				(width 0.1)
				(type default)
			)
			(layer "B.Fab")
		)
		(fp_line
			(start -0.67945 -0.3048)
			(end -0.67945 0.3048)
			(stroke
				(width 0.1)
				(type default)
			)
			(layer "B.Fab")
		)
		(pad "1" smd circle
			(at 0.40005 0)
			(size 0 0)
			(layers "B.Cu" "B.Mask" "B.Paste")
			(net "GND")
		)
		(pad "2" smd circle
			(at -0.40005 0)
			(size 0 0)
			(layers "B.Cu" "B.Mask" "B.Paste")
			(net "P1V8_PEX")
		)
	)
	(footprint ""
		(layer "B.Cu")
		(at 224.81794 -196.987922 90)
		(property "Reference" "R462"
			(at 0 0 90)
			(layer "B.SilkS")
			(hide yes)
			(effects
				(font
					(size 1.27 1.27)
				)
				(justify mirror)
			)
		)
		(property "Value" ""
			(at 0 0 90)
			(layer "B.Fab")
			(effects
				(font
					(size 1.27 1.27)
				)
				(justify mirror)
			)
		)
		(duplicate_pad_numbers_are_jumpers no)
		(fp_line
			(start 0.7874 -0.4064)
			(end -0.7874 -0.4064)
			(stroke
				(width 0.1524)
				(type default)
			)
			(layer "B.SilkS")
		)
		(fp_line
			(start -0.7874 -0.4064)
			(end -0.7874 0.4064)
			(stroke
				(width 0.1524)
				(type default)
			)
			(layer "B.SilkS")
		)
		(fp_line
			(start 0.7874 0.4064)
			(end 0.7874 -0.4064)
			(stroke
				(width 0.1524)
				(type default)
			)
			(layer "B.SilkS")
		)
		(fp_line
			(start -0.7874 0.4064)
			(end 0.7874 0.4064)
			(stroke
				(width 0.1524)
				(type default)
			)
			(layer "B.SilkS")
		)
		(fp_line
			(start 0.67945 -0.305054)
			(end 0.12065 -0.305054)
			(stroke
				(width 0.1)
				(type default)
			)
			(layer "B.Fab")
		)
		(fp_line
			(start 0.12065 -0.305054)
			(end 0.12065 -0.2794)
			(stroke
				(width 0.1)
				(type default)
			)
			(layer "B.Fab")
		)
		(fp_line
			(start -0.12065 -0.3048)
			(end -0.67945 -0.3048)
			(stroke
				(width 0.1)
				(type default)
			)
			(layer "B.Fab")
		)
		(fp_line
			(start -0.67945 -0.3048)
			(end -0.67945 0.3048)
			(stroke
				(width 0.1)
				(type default)
			)
			(layer "B.Fab")
		)
		(fp_line
			(start 0.12065 -0.2794)
			(end -0.12065 -0.2794)
			(stroke
				(width 0.1)
				(type default)
			)
			(layer "B.Fab")
		)
		(fp_line
			(start -0.12065 -0.2794)
			(end -0.12065 -0.3048)
			(stroke
				(width 0.1)
				(type default)
			)
			(layer "B.Fab")
		)
		(fp_line
			(start 0.12065 0.2794)
			(end 0.12065 0.3048)
			(stroke
				(width 0.1)
				(type default)
			)
			(layer "B.Fab")
		)
		(fp_line
			(start -0.120396 0.2794)
			(end 0.12065 0.2794)
			(stroke
				(width 0.1)
				(type default)
			)
			(layer "B.Fab")
		)
		(fp_line
			(start 0.67945 0.3048)
			(end 0.67945 -0.305054)
			(stroke
				(width 0.1)
				(type default)
			)
			(layer "B.Fab")
		)
		(fp_line
			(start 0.12065 0.3048)
			(end 0.67945 0.3048)
			(stroke
				(width 0.1)
				(type default)
			)
			(layer "B.Fab")
		)
		(fp_line
			(start -0.120396 0.3048)
			(end -0.120396 0.2794)
			(stroke
				(width 0.1)
				(type default)
			)
			(layer "B.Fab")
		)
		(fp_line
			(start -0.67945 0.3048)
			(end -0.120396 0.3048)
			(stroke
				(width 0.1)
				(type default)
			)
			(layer "B.Fab")
		)
		(pad "1" smd circle
			(at 0.40005 0 270)
			(size 0 0)
			(layers "B.Cu" "B.Mask" "B.Paste")
			(net "SPI_BIC1_CLK_R")
		)
		(pad "2" smd circle
			(at -0.40005 0 270)
			(size 0 0)
			(layers "B.Cu" "B.Mask" "B.Paste")
			(net "SPI_BIC1_CLK_R1")
		)
	)
	(footprint ""
		(layer "B.Cu")
		(at 109.615732 -354.313236 180)
		(property "Reference" "C4179"
			(at 0 0 0)
			(layer "B.SilkS")
			(hide yes)
			(effects
				(font
					(size 1.27 1.27)
				)
				(justify mirror)
			)
		)
		(property "Value" ""
			(at 0 0 0)
			(layer "B.Fab")
			(effects
				(font
					(size 1.27 1.27)
				)
				(justify mirror)
			)
		)
		(duplicate_pad_numbers_are_jumpers no)
		(fp_line
			(start 0.7874 0.4064)
			(end 0.7874 -0.4064)
			(stroke
				(width 0.1524)
				(type default)
			)
			(layer "B.SilkS")
		)
		(fp_line
			(start 0.7874 -0.4064)
			(end -0.7874 -0.4064)
			(stroke
				(width 0.1524)
				(type default)
			)
			(layer "B.SilkS")
		)
		(fp_line
			(start -0.7874 0.4064)
			(end 0.7874 0.4064)
			(stroke
				(width 0.1524)
				(type default)
			)
			(layer "B.SilkS")
		)
		(fp_line
			(start -0.7874 -0.4064)
			(end -0.7874 0.4064)
			(stroke
				(width 0.1524)
				(type default)
			)
			(layer "B.SilkS")
		)
		(fp_line
			(start 0.67945 0.3048)
			(end 0.67945 -0.305054)
			(stroke
				(width 0.1)
				(type default)
			)
			(layer "B.Fab")
		)
		(fp_line
			(start 0.67945 -0.305054)
			(end 0.12065 -0.305054)
			(stroke
				(width 0.1)
				(type default)
			)
			(layer "B.Fab")
		)
		(fp_line
			(start 0.12065 0.3048)
			(end 0.67945 0.3048)
			(stroke
				(width 0.1)
				(type default)
			)
			(layer "B.Fab")
		)
		(fp_line
			(start 0.12065 0.2794)
			(end 0.12065 0.3048)
			(stroke
				(width 0.1)
				(type default)
			)
			(layer "B.Fab")
		)
		(fp_line
			(start 0.12065 -0.2794)
			(end -0.12065 -0.2794)
			(stroke
				(width 0.1)
				(type default)
			)
			(layer "B.Fab")
		)
		(fp_line
			(start 0.12065 -0.305054)
			(end 0.12065 -0.2794)
			(stroke
				(width 0.1)
				(type default)
			)
			(layer "B.Fab")
		)
		(fp_line
			(start -0.120396 0.3048)
			(end -0.120396 0.2794)
			(stroke
				(width 0.1)
				(type default)
			)
			(layer "B.Fab")
		)
		(fp_line
			(start -0.120396 0.2794)
			(end 0.12065 0.2794)
			(stroke
				(width 0.1)
				(type default)
			)
			(layer "B.Fab")
		)
		(fp_line
			(start -0.12065 -0.2794)
			(end -0.12065 -0.3048)
			(stroke
				(width 0.1)
				(type default)
			)
			(layer "B.Fab")
		)
		(fp_line
			(start -0.12065 -0.3048)
			(end -0.67945 -0.3048)
			(stroke
				(width 0.1)
				(type default)
			)
			(layer "B.Fab")
		)
		(fp_line
			(start -0.67945 0.3048)
			(end -0.120396 0.3048)
			(stroke
				(width 0.1)
				(type default)
			)
			(layer "B.Fab")
		)
		(fp_line
			(start -0.67945 -0.3048)
			(end -0.67945 0.3048)
			(stroke
				(width 0.1)
				(type default)
			)
			(layer "B.Fab")
		)
		(pad "1" smd circle
			(at 0.40005 0)
			(size 0 0)
			(layers "B.Cu" "B.Mask" "B.Paste")
			(net "P3V3_CLK_BUFFER_9ZXL0451E_S3_VZX3P3")
		)
		(pad "2" smd circle
			(at -0.40005 0)
			(size 0 0)
			(layers "B.Cu" "B.Mask" "B.Paste")
			(net "GND")
		)
	)
	(footprint ""
		(layer "B.Cu")
		(at 253.918212 -83.669378 -90)
		(property "Reference" "C2640"
			(at 0 0 90)
			(layer "B.SilkS")
			(hide yes)
			(effects
				(font
					(size 1.27 1.27)
				)
				(justify mirror)
			)
		)
		(property "Value" ""
			(at 0 0 90)
			(layer "B.Fab")
			(effects
				(font
					(size 1.27 1.27)
				)
				(justify mirror)
			)
		)
		(duplicate_pad_numbers_are_jumpers no)
		(fp_line
			(start -0.7874 0.4064)
			(end 0.7874 0.4064)
			(stroke
				(width 0.1524)
				(type default)
			)
			(layer "B.SilkS")
		)
		(fp_line
			(start 0.7874 0.4064)
			(end 0.7874 -0.4064)
			(stroke
				(width 0.1524)
				(type default)
			)
			(layer "B.SilkS")
		)
		(fp_line
			(start -0.7874 -0.4064)
			(end -0.7874 0.4064)
			(stroke
				(width 0.1524)
				(type default)
			)
			(layer "B.SilkS")
		)
		(fp_line
			(start 0.7874 -0.4064)
			(end -0.7874 -0.4064)
			(stroke
				(width 0.1524)
				(type default)
			)
			(layer "B.SilkS")
		)
		(fp_line
			(start -0.67945 0.3048)
			(end -0.120396 0.3048)
			(stroke
				(width 0.1)
				(type default)
			)
			(layer "B.Fab")
		)
		(fp_line
			(start -0.120396 0.3048)
			(end -0.120396 0.2794)
			(stroke
				(width 0.1)
				(type default)
			)
			(layer "B.Fab")
		)
		(fp_line
			(start 0.12065 0.3048)
			(end 0.67945 0.3048)
			(stroke
				(width 0.1)
				(type default)
			)
			(layer "B.Fab")
		)
		(fp_line
			(start 0.67945 0.3048)
			(end 0.67945 -0.305054)
			(stroke
				(width 0.1)
				(type default)
			)
			(layer "B.Fab")
		)
		(fp_line
			(start -0.120396 0.2794)
			(end 0.12065 0.2794)
			(stroke
				(width 0.1)
				(type default)
			)
			(layer "B.Fab")
		)
		(fp_line
			(start 0.12065 0.2794)
			(end 0.12065 0.3048)
			(stroke
				(width 0.1)
				(type default)
			)
			(layer "B.Fab")
		)
		(fp_line
			(start -0.12065 -0.2794)
			(end -0.12065 -0.3048)
			(stroke
				(width 0.1)
				(type default)
			)
			(layer "B.Fab")
		)
		(fp_line
			(start 0.12065 -0.2794)
			(end -0.12065 -0.2794)
			(stroke
				(width 0.1)
				(type default)
			)
			(layer "B.Fab")
		)
		(fp_line
			(start -0.67945 -0.3048)
			(end -0.67945 0.3048)
			(stroke
				(width 0.1)
				(type default)
			)
			(layer "B.Fab")
		)
		(fp_line
			(start -0.12065 -0.3048)
			(end -0.67945 -0.3048)
			(stroke
				(width 0.1)
				(type default)
			)
			(layer "B.Fab")
		)
		(fp_line
			(start 0.12065 -0.305054)
			(end 0.12065 -0.2794)
			(stroke
				(width 0.1)
				(type default)
			)
			(layer "B.Fab")
		)
		(fp_line
			(start 0.67945 -0.305054)
			(end 0.12065 -0.305054)
			(stroke
				(width 0.1)
				(type default)
			)
			(layer "B.Fab")
		)
		(pad "1" smd circle
			(at 0.40005 0 90)
			(size 0 0)
			(layers "B.Cu" "B.Mask" "B.Paste")
			(net "P3V3_CLK_GEN_VDDXTAL_CK440")
		)
		(pad "2" smd circle
			(at -0.40005 0 90)
			(size 0 0)
			(layers "B.Cu" "B.Mask" "B.Paste")
			(net "GND")
		)
	)
	(footprint ""
		(layer "B.Cu")
		(at 397.70812 -303.024794 180)
		(property "Reference" "C3536"
			(at 0 0 0)
			(layer "B.SilkS")
			(hide yes)
			(effects
				(font
					(size 1.27 1.27)
				)
				(justify mirror)
			)
		)
		(property "Value" ""
			(at 0 0 0)
			(layer "B.Fab")
			(effects
				(font
					(size 1.27 1.27)
				)
				(justify mirror)
			)
		)
		(duplicate_pad_numbers_are_jumpers no)
		(fp_line
			(start 0.299974 0.150114)
			(end 0.299974 -0.150114)
			(stroke
				(width 0.1)
				(type default)
			)
			(layer "B.Fab")
		)
		(fp_line
			(start 0.299974 -0.150114)
			(end -0.299974 -0.150114)
			(stroke
				(width 0.1)
				(type default)
			)
			(layer "B.Fab")
		)
		(fp_line
			(start -0.299974 0.150114)
			(end 0.299974 0.150114)
			(stroke
				(width 0.1)
				(type default)
			)
			(layer "B.Fab")
		)
		(fp_line
			(start -0.299974 -0.150114)
			(end -0.299974 0.150114)
			(stroke
				(width 0.1)
				(type default)
			)
			(layer "B.Fab")
		)
		(pad "1" smd rect
			(at 0.2667 0)
			(size 0.3048 0.381)
			(layers "B.Cu" "B.Mask" "B.Paste")
			(net "P1V8_VDDA_PEX3")
		)
		(pad "2" smd rect
			(at -0.2667 0)
			(size 0.3048 0.381)
			(layers "B.Cu" "B.Mask" "B.Paste")
			(net "GND")
		)
	)
	(footprint ""
		(layer "B.Cu")
		(at 233.292142 -79.305912 180)
		(property "Reference" "C2612"
			(at 0 0 0)
			(layer "B.SilkS")
			(hide yes)
			(effects
				(font
					(size 1.27 1.27)
				)
				(justify mirror)
			)
		)
		(property "Value" ""
			(at 0 0 0)
			(layer "B.Fab")
			(effects
				(font
					(size 1.27 1.27)
				)
				(justify mirror)
			)
		)
		(duplicate_pad_numbers_are_jumpers no)
		(fp_line
			(start 0.7874 0.4064)
			(end 0.7874 -0.4064)
			(stroke
				(width 0.1524)
				(type default)
			)
			(layer "B.SilkS")
		)
		(fp_line
			(start 0.7874 -0.4064)
			(end -0.7874 -0.4064)
			(stroke
				(width 0.1524)
				(type default)
			)
			(layer "B.SilkS")
		)
		(fp_line
			(start -0.7874 0.4064)
			(end 0.7874 0.4064)
			(stroke
				(width 0.1524)
				(type default)
			)
			(layer "B.SilkS")
		)
		(fp_line
			(start -0.7874 -0.4064)
			(end -0.7874 0.4064)
			(stroke
				(width 0.1524)
				(type default)
			)
			(layer "B.SilkS")
		)
		(fp_line
			(start 0.67945 0.3048)
			(end 0.67945 -0.305054)
			(stroke
				(width 0.1)
				(type default)
			)
			(layer "B.Fab")
		)
		(fp_line
			(start 0.67945 -0.305054)
			(end 0.12065 -0.305054)
			(stroke
				(width 0.1)
				(type default)
			)
			(layer "B.Fab")
		)
		(fp_line
			(start 0.12065 0.3048)
			(end 0.67945 0.3048)
			(stroke
				(width 0.1)
				(type default)
			)
			(layer "B.Fab")
		)
		(fp_line
			(start 0.12065 0.2794)
			(end 0.12065 0.3048)
			(stroke
				(width 0.1)
				(type default)
			)
			(layer "B.Fab")
		)
		(fp_line
			(start 0.12065 -0.2794)
			(end -0.12065 -0.2794)
			(stroke
				(width 0.1)
				(type default)
			)
			(layer "B.Fab")
		)
		(fp_line
			(start 0.12065 -0.305054)
			(end 0.12065 -0.2794)
			(stroke
				(width 0.1)
				(type default)
			)
			(layer "B.Fab")
		)
		(fp_line
			(start -0.120396 0.3048)
			(end -0.120396 0.2794)
			(stroke
				(width 0.1)
				(type default)
			)
			(layer "B.Fab")
		)
		(fp_line
			(start -0.120396 0.2794)
			(end 0.12065 0.2794)
			(stroke
				(width 0.1)
				(type default)
			)
			(layer "B.Fab")
		)
		(fp_line
			(start -0.12065 -0.2794)
			(end -0.12065 -0.3048)
			(stroke
				(width 0.1)
				(type default)
			)
			(layer "B.Fab")
		)
		(fp_line
			(start -0.12065 -0.3048)
			(end -0.67945 -0.3048)
			(stroke
				(width 0.1)
				(type default)
			)
			(layer "B.Fab")
		)
		(fp_line
			(start -0.67945 0.3048)
			(end -0.120396 0.3048)
			(stroke
				(width 0.1)
				(type default)
			)
			(layer "B.Fab")
		)
		(fp_line
			(start -0.67945 -0.3048)
			(end -0.67945 0.3048)
			(stroke
				(width 0.1)
				(type default)
			)
			(layer "B.Fab")
		)
		(pad "1" smd circle
			(at 0.40005 0)
			(size 0 0)
			(layers "B.Cu" "B.Mask" "B.Paste")
			(net "P3V3_AUX")
		)
		(pad "2" smd circle
			(at -0.40005 0)
			(size 0 0)
			(layers "B.Cu" "B.Mask" "B.Paste")
			(net "GND")
		)
	)
	(footprint ""
		(layer "B.Cu")
		(at 392.749786 -300.174914)
		(property "Reference" "C3534"
			(at 0 0 0)
			(layer "B.SilkS")
			(hide yes)
			(effects
				(font
					(size 1.27 1.27)
				)
				(justify mirror)
			)
		)
		(property "Value" ""
			(at 0 0 0)
			(layer "B.Fab")
			(effects
				(font
					(size 1.27 1.27)
				)
				(justify mirror)
			)
		)
		(duplicate_pad_numbers_are_jumpers no)
		(fp_line
			(start -0.299974 -0.150114)
			(end -0.299974 0.150114)
			(stroke
				(width 0.1)
				(type default)
			)
			(layer "B.Fab")
		)
		(fp_line
			(start -0.299974 0.150114)
			(end 0.299974 0.150114)
			(stroke
				(width 0.1)
				(type default)
			)
			(layer "B.Fab")
		)
		(fp_line
			(start 0.299974 -0.150114)
			(end -0.299974 -0.150114)
			(stroke
				(width 0.1)
				(type default)
			)
			(layer "B.Fab")
		)
		(fp_line
			(start 0.299974 0.150114)
			(end 0.299974 -0.150114)
			(stroke
				(width 0.1)
				(type default)
			)
			(layer "B.Fab")
		)
		(pad "1" smd rect
			(at 0.2667 0 180)
			(size 0.3048 0.381)
			(layers "B.Cu" "B.Mask" "B.Paste")
			(net "P1V8_VDDA_PEX3")
		)
		(pad "2" smd rect
			(at -0.2667 0 180)
			(size 0.3048 0.381)
			(layers "B.Cu" "B.Mask" "B.Paste")
			(net "GND")
		)
	)
	(footprint ""
		(layer "B.Cu")
		(at 296.599864 -292.099746 90)
		(property "Reference" "C1734"
			(at 0 0 90)
			(layer "B.SilkS")
			(hide yes)
			(effects
				(font
					(size 1.27 1.27)
				)
				(justify mirror)
			)
		)
		(property "Value" ""
			(at 0 0 90)
			(layer "B.Fab")
			(effects
				(font
					(size 1.27 1.27)
				)
				(justify mirror)
			)
		)
		(duplicate_pad_numbers_are_jumpers no)
		(fp_line
			(start 0.299974 -0.150114)
			(end -0.299974 -0.150114)
			(stroke
				(width 0.1)
				(type default)
			)
			(layer "B.Fab")
		)
		(fp_line
			(start -0.299974 -0.150114)
			(end -0.299974 0.150114)
			(stroke
				(width 0.1)
				(type default)
			)
			(layer "B.Fab")
		)
		(fp_line
			(start 0.299974 0.150114)
			(end 0.299974 -0.150114)
			(stroke
				(width 0.1)
				(type default)
			)
			(layer "B.Fab")
		)
		(fp_line
			(start -0.299974 0.150114)
			(end 0.299974 0.150114)
			(stroke
				(width 0.1)
				(type default)
			)
			(layer "B.Fab")
		)
		(pad "1" smd rect
			(at 0.2667 0 270)
			(size 0.3048 0.381)
			(layers "B.Cu" "B.Mask" "B.Paste")
			(net "P0V8_SERDES_VDDA_PEX2")
		)
		(pad "2" smd rect
			(at -0.2667 0 270)
			(size 0.3048 0.381)
			(layers "B.Cu" "B.Mask" "B.Paste")
			(net "GND")
		)
	)
	(footprint ""
		(layer "B.Cu")
		(at 213.106 -206.121 90)
		(property "Reference" "R6307"
			(at 0 0 90)
			(layer "B.SilkS")
			(hide yes)
			(effects
				(font
					(size 1.27 1.27)
				)
				(justify mirror)
			)
		)
		(property "Value" ""
			(at 0 0 90)
			(layer "B.Fab")
			(effects
				(font
					(size 1.27 1.27)
				)
				(justify mirror)
			)
		)
		(duplicate_pad_numbers_are_jumpers no)
		(fp_line
			(start 0.7874 -0.4064)
			(end -0.7874 -0.4064)
			(stroke
				(width 0.1524)
				(type default)
			)
			(layer "B.SilkS")
		)
		(fp_line
			(start -0.7874 -0.4064)
			(end -0.7874 0.4064)
			(stroke
				(width 0.1524)
				(type default)
			)
			(layer "B.SilkS")
		)
		(fp_line
			(start 0.7874 0.4064)
			(end 0.7874 -0.4064)
			(stroke
				(width 0.1524)
				(type default)
			)
			(layer "B.SilkS")
		)
		(fp_line
			(start -0.7874 0.4064)
			(end 0.7874 0.4064)
			(stroke
				(width 0.1524)
				(type default)
			)
			(layer "B.SilkS")
		)
		(fp_line
			(start 0.67945 -0.305054)
			(end 0.12065 -0.305054)
			(stroke
				(width 0.1)
				(type default)
			)
			(layer "B.Fab")
		)
		(fp_line
			(start 0.12065 -0.305054)
			(end 0.12065 -0.2794)
			(stroke
				(width 0.1)
				(type default)
			)
			(layer "B.Fab")
		)
		(fp_line
			(start -0.12065 -0.3048)
			(end -0.67945 -0.3048)
			(stroke
				(width 0.1)
				(type default)
			)
			(layer "B.Fab")
		)
		(fp_line
			(start -0.67945 -0.3048)
			(end -0.67945 0.3048)
			(stroke
				(width 0.1)
				(type default)
			)
			(layer "B.Fab")
		)
		(fp_line
			(start 0.12065 -0.2794)
			(end -0.12065 -0.2794)
			(stroke
				(width 0.1)
				(type default)
			)
			(layer "B.Fab")
		)
		(fp_line
			(start -0.12065 -0.2794)
			(end -0.12065 -0.3048)
			(stroke
				(width 0.1)
				(type default)
			)
			(layer "B.Fab")
		)
		(fp_line
			(start 0.12065 0.2794)
			(end 0.12065 0.3048)
			(stroke
				(width 0.1)
				(type default)
			)
			(layer "B.Fab")
		)
		(fp_line
			(start -0.120396 0.2794)
			(end 0.12065 0.2794)
			(stroke
				(width 0.1)
				(type default)
			)
			(layer "B.Fab")
		)
		(fp_line
			(start 0.67945 0.3048)
			(end 0.67945 -0.305054)
			(stroke
				(width 0.1)
				(type default)
			)
			(layer "B.Fab")
		)
		(fp_line
			(start 0.12065 0.3048)
			(end 0.67945 0.3048)
			(stroke
				(width 0.1)
				(type default)
			)
			(layer "B.Fab")
		)
		(fp_line
			(start -0.120396 0.3048)
			(end -0.120396 0.2794)
			(stroke
				(width 0.1)
				(type default)
			)
			(layer "B.Fab")
		)
		(fp_line
			(start -0.67945 0.3048)
			(end -0.120396 0.3048)
			(stroke
				(width 0.1)
				(type default)
			)
			(layer "B.Fab")
		)
		(pad "1" smd circle
			(at 0.40005 0 270)
			(size 0 0)
			(layers "B.Cu" "B.Mask" "B.Paste")
			(net "SMB_NIC4_LS_SCL")
		)
		(pad "2" smd circle
			(at -0.40005 0 270)
			(size 0 0)
			(layers "B.Cu" "B.Mask" "B.Paste")
			(net "SMB_NIC4_LS_R_SCL")
		)
	)
	(footprint ""
		(layer "B.Cu")
		(at 14.830298 -229.997)
		(property "Reference" "R3448"
			(at 0 0 0)
			(layer "B.SilkS")
			(hide yes)
			(effects
				(font
					(size 1.27 1.27)
				)
				(justify mirror)
			)
		)
		(property "Value" ""
			(at 0 0 0)
			(layer "B.Fab")
			(effects
				(font
					(size 1.27 1.27)
				)
				(justify mirror)
			)
		)
		(duplicate_pad_numbers_are_jumpers no)
		(fp_line
			(start -0.7874 -0.4064)
			(end -0.7874 0.4064)
			(stroke
				(width 0.1524)
				(type default)
			)
			(layer "B.SilkS")
		)
		(fp_line
			(start -0.7874 0.4064)
			(end 0.7874 0.4064)
			(stroke
				(width 0.1524)
				(type default)
			)
			(layer "B.SilkS")
		)
		(fp_line
			(start 0.7874 -0.4064)
			(end -0.7874 -0.4064)
			(stroke
				(width 0.1524)
				(type default)
			)
			(layer "B.SilkS")
		)
		(fp_line
			(start 0.7874 0.4064)
			(end 0.7874 -0.4064)
			(stroke
				(width 0.1524)
				(type default)
			)
			(layer "B.SilkS")
		)
		(fp_line
			(start -0.67945 -0.3048)
			(end -0.67945 0.3048)
			(stroke
				(width 0.1)
				(type default)
			)
			(layer "B.Fab")
		)
		(fp_line
			(start -0.67945 0.3048)
			(end -0.120396 0.3048)
			(stroke
				(width 0.1)
				(type default)
			)
			(layer "B.Fab")
		)
		(fp_line
			(start -0.12065 -0.3048)
			(end -0.67945 -0.3048)
			(stroke
				(width 0.1)
				(type default)
			)
			(layer "B.Fab")
		)
		(fp_line
			(start -0.12065 -0.2794)
			(end -0.12065 -0.3048)
			(stroke
				(width 0.1)
				(type default)
			)
			(layer "B.Fab")
		)
		(fp_line
			(start -0.120396 0.2794)
			(end 0.12065 0.2794)
			(stroke
				(width 0.1)
				(type default)
			)
			(layer "B.Fab")
		)
		(fp_line
			(start -0.120396 0.3048)
			(end -0.120396 0.2794)
			(stroke
				(width 0.1)
				(type default)
			)
			(layer "B.Fab")
		)
		(fp_line
			(start 0.12065 -0.305054)
			(end 0.12065 -0.2794)
			(stroke
				(width 0.1)
				(type default)
			)
			(layer "B.Fab")
		)
		(fp_line
			(start 0.12065 -0.2794)
			(end -0.12065 -0.2794)
			(stroke
				(width 0.1)
				(type default)
			)
			(layer "B.Fab")
		)
		(fp_line
			(start 0.12065 0.2794)
			(end 0.12065 0.3048)
			(stroke
				(width 0.1)
				(type default)
			)
			(layer "B.Fab")
		)
		(fp_line
			(start 0.12065 0.3048)
			(end 0.67945 0.3048)
			(stroke
				(width 0.1)
				(type default)
			)
			(layer "B.Fab")
		)
		(fp_line
			(start 0.67945 -0.305054)
			(end 0.12065 -0.305054)
			(stroke
				(width 0.1)
				(type default)
			)
			(layer "B.Fab")
		)
		(fp_line
			(start 0.67945 0.3048)
			(end 0.67945 -0.305054)
			(stroke
				(width 0.1)
				(type default)
			)
			(layer "B.Fab")
		)
		(pad "1" smd circle
			(at 0.40005 0 180)
			(size 0 0)
			(layers "B.Cu" "B.Mask" "B.Paste")
			(net "SPI_PEX0_SDIO2_R")
		)
		(pad "2" smd circle
			(at -0.40005 0 180)
			(size 0 0)
			(layers "B.Cu" "B.Mask" "B.Paste")
			(net "SPI_PEX0_SDIO2_R1")
		)
	)
	(footprint ""
		(layer "B.Cu")
		(at 214.454486 -212.206586 180)
		(property "Reference" "R5533"
			(at 0 0 0)
			(layer "B.SilkS")
			(hide yes)
			(effects
				(font
					(size 1.27 1.27)
				)
				(justify mirror)
			)
		)
		(property "Value" ""
			(at 0 0 0)
			(layer "B.Fab")
			(effects
				(font
					(size 1.27 1.27)
				)
				(justify mirror)
			)
		)
		(duplicate_pad_numbers_are_jumpers no)
		(fp_line
			(start 0.7874 0.4064)
			(end 0.7874 -0.4064)
			(stroke
				(width 0.1524)
				(type default)
			)
			(layer "B.SilkS")
		)
		(fp_line
			(start 0.7874 -0.4064)
			(end -0.7874 -0.4064)
			(stroke
				(width 0.1524)
				(type default)
			)
			(layer "B.SilkS")
		)
		(fp_line
			(start -0.7874 0.4064)
			(end 0.7874 0.4064)
			(stroke
				(width 0.1524)
				(type default)
			)
			(layer "B.SilkS")
		)
		(fp_line
			(start -0.7874 -0.4064)
			(end -0.7874 0.4064)
			(stroke
				(width 0.1524)
				(type default)
			)
			(layer "B.SilkS")
		)
		(fp_line
			(start 0.67945 0.3048)
			(end 0.67945 -0.305054)
			(stroke
				(width 0.1)
				(type default)
			)
			(layer "B.Fab")
		)
		(fp_line
			(start 0.67945 -0.305054)
			(end 0.12065 -0.305054)
			(stroke
				(width 0.1)
				(type default)
			)
			(layer "B.Fab")
		)
		(fp_line
			(start 0.12065 0.3048)
			(end 0.67945 0.3048)
			(stroke
				(width 0.1)
				(type default)
			)
			(layer "B.Fab")
		)
		(fp_line
			(start 0.12065 0.2794)
			(end 0.12065 0.3048)
			(stroke
				(width 0.1)
				(type default)
			)
			(layer "B.Fab")
		)
		(fp_line
			(start 0.12065 -0.2794)
			(end -0.12065 -0.2794)
			(stroke
				(width 0.1)
				(type default)
			)
			(layer "B.Fab")
		)
		(fp_line
			(start 0.12065 -0.305054)
			(end 0.12065 -0.2794)
			(stroke
				(width 0.1)
				(type default)
			)
			(layer "B.Fab")
		)
		(fp_line
			(start -0.120396 0.3048)
			(end -0.120396 0.2794)
			(stroke
				(width 0.1)
				(type default)
			)
			(layer "B.Fab")
		)
		(fp_line
			(start -0.120396 0.2794)
			(end 0.12065 0.2794)
			(stroke
				(width 0.1)
				(type default)
			)
			(layer "B.Fab")
		)
		(fp_line
			(start -0.12065 -0.2794)
			(end -0.12065 -0.3048)
			(stroke
				(width 0.1)
				(type default)
			)
			(layer "B.Fab")
		)
		(fp_line
			(start -0.12065 -0.3048)
			(end -0.67945 -0.3048)
			(stroke
				(width 0.1)
				(type default)
			)
			(layer "B.Fab")
		)
		(fp_line
			(start -0.67945 0.3048)
			(end -0.120396 0.3048)
			(stroke
				(width 0.1)
				(type default)
			)
			(layer "B.Fab")
		)
		(fp_line
			(start -0.67945 -0.3048)
			(end -0.67945 0.3048)
			(stroke
				(width 0.1)
				(type default)
			)
			(layer "B.Fab")
		)
		(pad "1" smd circle
			(at 0.40005 0)
			(size 0 0)
			(layers "B.Cu" "B.Mask" "B.Paste")
			(net "GND")
		)
		(pad "2" smd circle
			(at -0.40005 0)
			(size 0 0)
			(layers "B.Cu" "B.Mask" "B.Paste")
			(net "UART_BIC_DEBUG_TX")
		)
	)
	(footprint ""
		(layer "B.Cu")
		(at 302.552354 -234.958636 90)
		(property "Reference" "R1866"
			(at 0 0 90)
			(layer "B.SilkS")
			(hide yes)
			(effects
				(font
					(size 1.27 1.27)
				)
				(justify mirror)
			)
		)
		(property "Value" ""
			(at 0 0 90)
			(layer "B.Fab")
			(effects
				(font
					(size 1.27 1.27)
				)
				(justify mirror)
			)
		)
		(duplicate_pad_numbers_are_jumpers no)
		(fp_line
			(start 0.7874 -0.4064)
			(end -0.7874 -0.4064)
			(stroke
				(width 0.1524)
				(type default)
			)
			(layer "B.SilkS")
		)
		(fp_line
			(start -0.7874 -0.4064)
			(end -0.7874 0.4064)
			(stroke
				(width 0.1524)
				(type default)
			)
			(layer "B.SilkS")
		)
		(fp_line
			(start 0.7874 0.4064)
			(end 0.7874 -0.4064)
			(stroke
				(width 0.1524)
				(type default)
			)
			(layer "B.SilkS")
		)
		(fp_line
			(start -0.7874 0.4064)
			(end 0.7874 0.4064)
			(stroke
				(width 0.1524)
				(type default)
			)
			(layer "B.SilkS")
		)
		(fp_line
			(start 0.67945 -0.305054)
			(end 0.12065 -0.305054)
			(stroke
				(width 0.1)
				(type default)
			)
			(layer "B.Fab")
		)
		(fp_line
			(start 0.12065 -0.305054)
			(end 0.12065 -0.2794)
			(stroke
				(width 0.1)
				(type default)
			)
			(layer "B.Fab")
		)
		(fp_line
			(start -0.12065 -0.3048)
			(end -0.67945 -0.3048)
			(stroke
				(width 0.1)
				(type default)
			)
			(layer "B.Fab")
		)
		(fp_line
			(start -0.67945 -0.3048)
			(end -0.67945 0.3048)
			(stroke
				(width 0.1)
				(type default)
			)
			(layer "B.Fab")
		)
		(fp_line
			(start 0.12065 -0.2794)
			(end -0.12065 -0.2794)
			(stroke
				(width 0.1)
				(type default)
			)
			(layer "B.Fab")
		)
		(fp_line
			(start -0.12065 -0.2794)
			(end -0.12065 -0.3048)
			(stroke
				(width 0.1)
				(type default)
			)
			(layer "B.Fab")
		)
		(fp_line
			(start 0.12065 0.2794)
			(end 0.12065 0.3048)
			(stroke
				(width 0.1)
				(type default)
			)
			(layer "B.Fab")
		)
		(fp_line
			(start -0.120396 0.2794)
			(end 0.12065 0.2794)
			(stroke
				(width 0.1)
				(type default)
			)
			(layer "B.Fab")
		)
		(fp_line
			(start 0.67945 0.3048)
			(end 0.67945 -0.305054)
			(stroke
				(width 0.1)
				(type default)
			)
			(layer "B.Fab")
		)
		(fp_line
			(start 0.12065 0.3048)
			(end 0.67945 0.3048)
			(stroke
				(width 0.1)
				(type default)
			)
			(layer "B.Fab")
		)
		(fp_line
			(start -0.120396 0.3048)
			(end -0.120396 0.2794)
			(stroke
				(width 0.1)
				(type default)
			)
			(layer "B.Fab")
		)
		(fp_line
			(start -0.67945 0.3048)
			(end -0.120396 0.3048)
			(stroke
				(width 0.1)
				(type default)
			)
			(layer "B.Fab")
		)
		(pad "1" smd circle
			(at 0.40005 0 270)
			(size 0 0)
			(layers "B.Cu" "B.Mask" "B.Paste")
			(net "RST_GPU_PERST_1_N")
		)
		(pad "2" smd circle
			(at -0.40005 0 270)
			(size 0 0)
			(layers "B.Cu" "B.Mask" "B.Paste")
			(net "RST_GPU_PERST_1_R_N")
		)
	)
	(footprint ""
		(layer "B.Cu")
		(at 100.439474 -335.69783 180)
		(property "Reference" "L16"
			(at 0 0 0)
			(layer "B.SilkS")
			(hide yes)
			(effects
				(font
					(size 1.27 1.27)
				)
				(justify mirror)
			)
		)
		(property "Value" ""
			(at 0 0 0)
			(layer "B.Fab")
			(effects
				(font
					(size 1.27 1.27)
				)
				(justify mirror)
			)
		)
		(duplicate_pad_numbers_are_jumpers no)
		(fp_line
			(start 1.63576 -0.8128)
			(end 1.63576 0.8128)
			(stroke
				(width 0.1524)
				(type default)
			)
			(layer "B.SilkS")
		)
		(fp_line
			(start 1.63576 -0.8128)
			(end -1.63576 -0.8128)
			(stroke
				(width 0.1524)
				(type default)
			)
			(layer "B.SilkS")
		)
		(fp_line
			(start -1.63576 0.8128)
			(end 1.63576 0.8128)
			(stroke
				(width 0.1524)
				(type default)
			)
			(layer "B.SilkS")
		)
		(fp_line
			(start -1.63576 -0.8128)
			(end -1.63576 0.8128)
			(stroke
				(width 0.1524)
				(type default)
			)
			(layer "B.SilkS")
		)
		(fp_line
			(start 1.56083 0.7366)
			(end 1.524 0.7366)
			(stroke
				(width 0.1)
				(type default)
			)
			(layer "B.Fab")
		)
		(fp_line
			(start 1.56083 -0.738632)
			(end 1.56083 0.7366)
			(stroke
				(width 0.1)
				(type default)
			)
			(layer "B.Fab")
		)
		(fp_line
			(start 1.524 0.7366)
			(end -1.524 0.7366)
			(stroke
				(width 0.1)
				(type default)
			)
			(layer "B.Fab")
		)
		(fp_line
			(start -1.524 0.7366)
			(end -1.560576 0.7366)
			(stroke
				(width 0.1)
				(type default)
			)
			(layer "B.Fab")
		)
		(fp_line
			(start -1.560576 0.7366)
			(end -1.560576 -0.738632)
			(stroke
				(width 0.1)
				(type default)
			)
			(layer "B.Fab")
		)
		(fp_line
			(start -1.560576 -0.738632)
			(end 1.56083 -0.738632)
			(stroke
				(width 0.1)
				(type default)
			)
			(layer "B.Fab")
		)
		(pad "1" smd rect
			(at 0.94996 0 180)
			(size 1.1176 1.3716)
			(layers "B.Cu" "B.Mask" "B.Paste")
			(net "P3V3")
		)
		(pad "2" smd rect
			(at -0.94996 0 180)
			(size 1.1176 1.3716)
			(layers "B.Cu" "B.Mask" "B.Paste")
			(net "P3V3_CLK_BUFFER_9ZXL0451E_VZX3P3")
		)
	)
	(footprint ""
		(layer "B.Cu")
		(at 402.724874 -293.99992 90)
		(property "Reference" "C1917"
			(at 0 0 90)
			(layer "B.SilkS")
			(hide yes)
			(effects
				(font
					(size 1.27 1.27)
				)
				(justify mirror)
			)
		)
		(property "Value" ""
			(at 0 0 90)
			(layer "B.Fab")
			(effects
				(font
					(size 1.27 1.27)
				)
				(justify mirror)
			)
		)
		(duplicate_pad_numbers_are_jumpers no)
		(fp_line
			(start 0.299974 -0.150114)
			(end -0.299974 -0.150114)
			(stroke
				(width 0.1)
				(type default)
			)
			(layer "B.Fab")
		)
		(fp_line
			(start -0.299974 -0.150114)
			(end -0.299974 0.150114)
			(stroke
				(width 0.1)
				(type default)
			)
			(layer "B.Fab")
		)
		(fp_line
			(start 0.299974 0.150114)
			(end 0.299974 -0.150114)
			(stroke
				(width 0.1)
				(type default)
			)
			(layer "B.Fab")
		)
		(fp_line
			(start -0.299974 0.150114)
			(end 0.299974 0.150114)
			(stroke
				(width 0.1)
				(type default)
			)
			(layer "B.Fab")
		)
		(pad "1" smd rect
			(at 0.2667 0 270)
			(size 0.3048 0.381)
			(layers "B.Cu" "B.Mask" "B.Paste")
			(net "P0V8_PEX3")
		)
		(pad "2" smd rect
			(at -0.2667 0 270)
			(size 0.3048 0.381)
			(layers "B.Cu" "B.Mask" "B.Paste")
			(net "GND")
		)
	)
	(footprint ""
		(layer "B.Cu")
		(at 349.422212 -319.633346 180)
		(property "Reference" "C1668"
			(at 0 0 0)
			(layer "B.SilkS")
			(hide yes)
			(effects
				(font
					(size 1.27 1.27)
				)
				(justify mirror)
			)
		)
		(property "Value" ""
			(at 0 0 0)
			(layer "B.Fab")
			(effects
				(font
					(size 1.27 1.27)
				)
				(justify mirror)
			)
		)
		(duplicate_pad_numbers_are_jumpers no)
		(fp_line
			(start 1.2954 0.5842)
			(end 1.2954 -0.5842)
			(stroke
				(width 0.1524)
				(type default)
			)
			(layer "B.SilkS")
		)
		(fp_line
			(start 1.2954 -0.5842)
			(end -1.2954 -0.5842)
			(stroke
				(width 0.1524)
				(type default)
			)
			(layer "B.SilkS")
		)
		(fp_line
			(start -1.2954 0.5842)
			(end 1.2954 0.5842)
			(stroke
				(width 0.1524)
				(type default)
			)
			(layer "B.SilkS")
		)
		(fp_line
			(start -1.2954 -0.5842)
			(end -1.2954 0.5842)
			(stroke
				(width 0.1524)
				(type default)
			)
			(layer "B.SilkS")
		)
		(fp_line
			(start 1.1938 0.4064)
			(end 1.1938 -0.4064)
			(stroke
				(width 0.1)
				(type default)
			)
			(layer "B.Fab")
		)
		(fp_line
			(start 1.1938 -0.4064)
			(end 0.8636 -0.4064)
			(stroke
				(width 0.1)
				(type default)
			)
			(layer "B.Fab")
		)
		(fp_line
			(start 0.8636 0.4572)
			(end 0.8636 0.4064)
			(stroke
				(width 0.1)
				(type default)
			)
			(layer "B.Fab")
		)
		(fp_line
			(start 0.8636 0.4064)
			(end 1.1938 0.4064)
			(stroke
				(width 0.1)
				(type default)
			)
			(layer "B.Fab")
		)
		(fp_line
			(start 0.8636 -0.4064)
			(end 0.8636 -0.4572)
			(stroke
				(width 0.1)
				(type default)
			)
			(layer "B.Fab")
		)
		(fp_line
			(start 0.8636 -0.4572)
			(end -0.8636 -0.4572)
			(stroke
				(width 0.1)
				(type default)
			)
			(layer "B.Fab")
		)
		(fp_line
			(start -0.8636 0.4572)
			(end 0.8636 0.4572)
			(stroke
				(width 0.1)
				(type default)
			)
			(layer "B.Fab")
		)
		(fp_line
			(start -0.8636 0.4064)
			(end -0.8636 0.4572)
			(stroke
				(width 0.1)
				(type default)
			)
			(layer "B.Fab")
		)
		(fp_line
			(start -0.8636 -0.4064)
			(end -1.1938 -0.4064)
			(stroke
				(width 0.1)
				(type default)
			)
			(layer "B.Fab")
		)
		(fp_line
			(start -0.8636 -0.4572)
			(end -0.8636 -0.4064)
			(stroke
				(width 0.1)
				(type default)
			)
			(layer "B.Fab")
		)
		(fp_line
			(start -1.1938 0.4064)
			(end -0.8636 0.4064)
			(stroke
				(width 0.1)
				(type default)
			)
			(layer "B.Fab")
		)
		(fp_line
			(start -1.1938 -0.4064)
			(end -1.1938 0.4064)
			(stroke
				(width 0.1)
				(type default)
			)
			(layer "B.Fab")
		)
		(pad "1" smd rect
			(at 0.7366 0 90)
			(size 0.7112 0.8128)
			(layers "B.Cu" "B.Mask" "B.Paste")
			(net "P0V8_SERDES_VDDA_PEX2")
		)
		(pad "2" smd rect
			(at -0.7366 0 90)
			(size 0.7112 0.8128)
			(layers "B.Cu" "B.Mask" "B.Paste")
			(net "GND")
		)
	)
	(footprint ""
		(layer "B.Cu")
		(at 47.77486 -290.941506 90)
		(property "Reference" "C3059"
			(at 0 0 90)
			(layer "B.SilkS")
			(hide yes)
			(effects
				(font
					(size 1.27 1.27)
				)
				(justify mirror)
			)
		)
		(property "Value" ""
			(at 0 0 90)
			(layer "B.Fab")
			(effects
				(font
					(size 1.27 1.27)
				)
				(justify mirror)
			)
		)
		(duplicate_pad_numbers_are_jumpers no)
		(fp_line
			(start 0.299974 -0.150114)
			(end -0.299974 -0.150114)
			(stroke
				(width 0.1)
				(type default)
			)
			(layer "B.Fab")
		)
		(fp_line
			(start -0.299974 -0.150114)
			(end -0.299974 0.150114)
			(stroke
				(width 0.1)
				(type default)
			)
			(layer "B.Fab")
		)
		(fp_line
			(start 0.299974 0.150114)
			(end 0.299974 -0.150114)
			(stroke
				(width 0.1)
				(type default)
			)
			(layer "B.Fab")
		)
		(fp_line
			(start -0.299974 0.150114)
			(end 0.299974 0.150114)
			(stroke
				(width 0.1)
				(type default)
			)
			(layer "B.Fab")
		)
		(pad "1" smd rect
			(at 0.2667 0 270)
			(size 0.3048 0.381)
			(layers "B.Cu" "B.Mask" "B.Paste")
			(net "PCEPLL7_VDDA18_PEX0")
		)
		(pad "2" smd rect
			(at -0.2667 0 270)
			(size 0.3048 0.381)
			(layers "B.Cu" "B.Mask" "B.Paste")
			(net "GND")
		)
	)
	(footprint ""
		(layer "B.Cu")
		(at 348.328488 -303.141634 180)
		(property "Reference" "PR125"
			(at 0 0 0)
			(layer "B.SilkS")
			(hide yes)
			(effects
				(font
					(size 1.27 1.27)
				)
				(justify mirror)
			)
		)
		(property "Value" ""
			(at 0 0 0)
			(layer "B.Fab")
			(effects
				(font
					(size 1.27 1.27)
				)
				(justify mirror)
			)
		)
		(duplicate_pad_numbers_are_jumpers no)
		(fp_line
			(start 0.7874 0.4064)
			(end 0.7874 -0.4064)
			(stroke
				(width 0.1524)
				(type default)
			)
			(layer "B.SilkS")
		)
		(fp_line
			(start 0.7874 -0.4064)
			(end -0.7874 -0.4064)
			(stroke
				(width 0.1524)
				(type default)
			)
			(layer "B.SilkS")
		)
		(fp_line
			(start -0.7874 0.4064)
			(end 0.7874 0.4064)
			(stroke
				(width 0.1524)
				(type default)
			)
			(layer "B.SilkS")
		)
		(fp_line
			(start -0.7874 -0.4064)
			(end -0.7874 0.4064)
			(stroke
				(width 0.1524)
				(type default)
			)
			(layer "B.SilkS")
		)
		(fp_line
			(start 0.67945 0.3048)
			(end 0.67945 -0.305054)
			(stroke
				(width 0.1)
				(type default)
			)
			(layer "B.Fab")
		)
		(fp_line
			(start 0.67945 -0.305054)
			(end 0.12065 -0.305054)
			(stroke
				(width 0.1)
				(type default)
			)
			(layer "B.Fab")
		)
		(fp_line
			(start 0.12065 0.3048)
			(end 0.67945 0.3048)
			(stroke
				(width 0.1)
				(type default)
			)
			(layer "B.Fab")
		)
		(fp_line
			(start 0.12065 0.2794)
			(end 0.12065 0.3048)
			(stroke
				(width 0.1)
				(type default)
			)
			(layer "B.Fab")
		)
		(fp_line
			(start 0.12065 -0.2794)
			(end -0.12065 -0.2794)
			(stroke
				(width 0.1)
				(type default)
			)
			(layer "B.Fab")
		)
		(fp_line
			(start 0.12065 -0.305054)
			(end 0.12065 -0.2794)
			(stroke
				(width 0.1)
				(type default)
			)
			(layer "B.Fab")
		)
		(fp_line
			(start -0.120396 0.3048)
			(end -0.120396 0.2794)
			(stroke
				(width 0.1)
				(type default)
			)
			(layer "B.Fab")
		)
		(fp_line
			(start -0.120396 0.2794)
			(end 0.12065 0.2794)
			(stroke
				(width 0.1)
				(type default)
			)
			(layer "B.Fab")
		)
		(fp_line
			(start -0.12065 -0.2794)
			(end -0.12065 -0.3048)
			(stroke
				(width 0.1)
				(type default)
			)
			(layer "B.Fab")
		)
		(fp_line
			(start -0.12065 -0.3048)
			(end -0.67945 -0.3048)
			(stroke
				(width 0.1)
				(type default)
			)
			(layer "B.Fab")
		)
		(fp_line
			(start -0.67945 0.3048)
			(end -0.120396 0.3048)
			(stroke
				(width 0.1)
				(type default)
			)
			(layer "B.Fab")
		)
		(fp_line
			(start -0.67945 -0.3048)
			(end -0.67945 0.3048)
			(stroke
				(width 0.1)
				(type default)
			)
			(layer "B.Fab")
		)
		(pad "1" smd circle
			(at 0.40005 0)
			(size 0 0)
			(layers "B.Cu" "B.Mask" "B.Paste")
			(net "P0V8_PEX2")
		)
		(pad "2" smd circle
			(at -0.40005 0)
			(size 0 0)
			(layers "B.Cu" "B.Mask" "B.Paste")
			(net "SH_P0V8_PEX2_VSEN2_L")
		)
	)
	(footprint ""
		(layer "B.Cu")
		(at 164.965888 -138.421618 180)
		(property "Reference" "R105"
			(at 0 0 0)
			(layer "B.SilkS")
			(hide yes)
			(effects
				(font
					(size 1.27 1.27)
				)
				(justify mirror)
			)
		)
		(property "Value" ""
			(at 0 0 0)
			(layer "B.Fab")
			(effects
				(font
					(size 1.27 1.27)
				)
				(justify mirror)
			)
		)
		(duplicate_pad_numbers_are_jumpers no)
		(fp_line
			(start 0.7874 0.4064)
			(end 0.7874 -0.4064)
			(stroke
				(width 0.1524)
				(type default)
			)
			(layer "B.SilkS")
		)
		(fp_line
			(start 0.7874 -0.4064)
			(end -0.7874 -0.4064)
			(stroke
				(width 0.1524)
				(type default)
			)
			(layer "B.SilkS")
		)
		(fp_line
			(start -0.7874 0.4064)
			(end 0.7874 0.4064)
			(stroke
				(width 0.1524)
				(type default)
			)
			(layer "B.SilkS")
		)
		(fp_line
			(start -0.7874 -0.4064)
			(end -0.7874 0.4064)
			(stroke
				(width 0.1524)
				(type default)
			)
			(layer "B.SilkS")
		)
		(fp_line
			(start 0.67945 0.3048)
			(end 0.67945 -0.305054)
			(stroke
				(width 0.1)
				(type default)
			)
			(layer "B.Fab")
		)
		(fp_line
			(start 0.67945 -0.305054)
			(end 0.12065 -0.305054)
			(stroke
				(width 0.1)
				(type default)
			)
			(layer "B.Fab")
		)
		(fp_line
			(start 0.12065 0.3048)
			(end 0.67945 0.3048)
			(stroke
				(width 0.1)
				(type default)
			)
			(layer "B.Fab")
		)
		(fp_line
			(start 0.12065 0.2794)
			(end 0.12065 0.3048)
			(stroke
				(width 0.1)
				(type default)
			)
			(layer "B.Fab")
		)
		(fp_line
			(start 0.12065 -0.2794)
			(end -0.12065 -0.2794)
			(stroke
				(width 0.1)
				(type default)
			)
			(layer "B.Fab")
		)
		(fp_line
			(start 0.12065 -0.305054)
			(end 0.12065 -0.2794)
			(stroke
				(width 0.1)
				(type default)
			)
			(layer "B.Fab")
		)
		(fp_line
			(start -0.120396 0.3048)
			(end -0.120396 0.2794)
			(stroke
				(width 0.1)
				(type default)
			)
			(layer "B.Fab")
		)
		(fp_line
			(start -0.120396 0.2794)
			(end 0.12065 0.2794)
			(stroke
				(width 0.1)
				(type default)
			)
			(layer "B.Fab")
		)
		(fp_line
			(start -0.12065 -0.2794)
			(end -0.12065 -0.3048)
			(stroke
				(width 0.1)
				(type default)
			)
			(layer "B.Fab")
		)
		(fp_line
			(start -0.12065 -0.3048)
			(end -0.67945 -0.3048)
			(stroke
				(width 0.1)
				(type default)
			)
			(layer "B.Fab")
		)
		(fp_line
			(start -0.67945 0.3048)
			(end -0.120396 0.3048)
			(stroke
				(width 0.1)
				(type default)
			)
			(layer "B.Fab")
		)
		(fp_line
			(start -0.67945 -0.3048)
			(end -0.67945 0.3048)
			(stroke
				(width 0.1)
				(type default)
			)
			(layer "B.Fab")
		)
		(pad "1" smd circle
			(at 0.40005 0)
			(size 0 0)
			(layers "B.Cu" "B.Mask" "B.Paste")
			(net "NIC2_AUX_PWR_EN_R")
		)
		(pad "2" smd circle
			(at -0.40005 0)
			(size 0 0)
			(layers "B.Cu" "B.Mask" "B.Paste")
			(net "NIC2_AUX_PWR_EN")
		)
	)
	(footprint ""
		(layer "B.Cu")
		(at 56.007 -138.557 90)
		(property "Reference" "C856"
			(at 0 0 90)
			(layer "B.SilkS")
			(hide yes)
			(effects
				(font
					(size 1.27 1.27)
				)
				(justify mirror)
			)
		)
		(property "Value" ""
			(at 0 0 90)
			(layer "B.Fab")
			(effects
				(font
					(size 1.27 1.27)
				)
				(justify mirror)
			)
		)
		(duplicate_pad_numbers_are_jumpers no)
		(fp_line
			(start 0.7874 -0.4064)
			(end -0.7874 -0.4064)
			(stroke
				(width 0.1524)
				(type default)
			)
			(layer "B.SilkS")
		)
		(fp_line
			(start -0.7874 -0.4064)
			(end -0.7874 0.4064)
			(stroke
				(width 0.1524)
				(type default)
			)
			(layer "B.SilkS")
		)
		(fp_line
			(start 0.7874 0.4064)
			(end 0.7874 -0.4064)
			(stroke
				(width 0.1524)
				(type default)
			)
			(layer "B.SilkS")
		)
		(fp_line
			(start -0.7874 0.4064)
			(end 0.7874 0.4064)
			(stroke
				(width 0.1524)
				(type default)
			)
			(layer "B.SilkS")
		)
		(fp_line
			(start 0.67945 -0.305054)
			(end 0.12065 -0.305054)
			(stroke
				(width 0.1)
				(type default)
			)
			(layer "B.Fab")
		)
		(fp_line
			(start 0.12065 -0.305054)
			(end 0.12065 -0.2794)
			(stroke
				(width 0.1)
				(type default)
			)
			(layer "B.Fab")
		)
		(fp_line
			(start -0.12065 -0.3048)
			(end -0.67945 -0.3048)
			(stroke
				(width 0.1)
				(type default)
			)
			(layer "B.Fab")
		)
		(fp_line
			(start -0.67945 -0.3048)
			(end -0.67945 0.3048)
			(stroke
				(width 0.1)
				(type default)
			)
			(layer "B.Fab")
		)
		(fp_line
			(start 0.12065 -0.2794)
			(end -0.12065 -0.2794)
			(stroke
				(width 0.1)
				(type default)
			)
			(layer "B.Fab")
		)
		(fp_line
			(start -0.12065 -0.2794)
			(end -0.12065 -0.3048)
			(stroke
				(width 0.1)
				(type default)
			)
			(layer "B.Fab")
		)
		(fp_line
			(start 0.12065 0.2794)
			(end 0.12065 0.3048)
			(stroke
				(width 0.1)
				(type default)
			)
			(layer "B.Fab")
		)
		(fp_line
			(start -0.120396 0.2794)
			(end 0.12065 0.2794)
			(stroke
				(width 0.1)
				(type default)
			)
			(layer "B.Fab")
		)
		(fp_line
			(start 0.67945 0.3048)
			(end 0.67945 -0.305054)
			(stroke
				(width 0.1)
				(type default)
			)
			(layer "B.Fab")
		)
		(fp_line
			(start 0.12065 0.3048)
			(end 0.67945 0.3048)
			(stroke
				(width 0.1)
				(type default)
			)
			(layer "B.Fab")
		)
		(fp_line
			(start -0.120396 0.3048)
			(end -0.120396 0.2794)
			(stroke
				(width 0.1)
				(type default)
			)
			(layer "B.Fab")
		)
		(fp_line
			(start -0.67945 0.3048)
			(end -0.120396 0.3048)
			(stroke
				(width 0.1)
				(type default)
			)
			(layer "B.Fab")
		)
		(pad "1" smd circle
			(at 0.40005 0 270)
			(size 0 0)
			(layers "B.Cu" "B.Mask" "B.Paste")
			(net "P3V3_AUX")
		)
		(pad "2" smd circle
			(at -0.40005 0 270)
			(size 0 0)
			(layers "B.Cu" "B.Mask" "B.Paste")
			(net "GND")
		)
	)
	(footprint ""
		(layer "B.Cu")
		(at 171.474892 -293.99992 -90)
		(property "Reference" "C1377"
			(at 0 0 90)
			(layer "B.SilkS")
			(hide yes)
			(effects
				(font
					(size 1.27 1.27)
				)
				(justify mirror)
			)
		)
		(property "Value" ""
			(at 0 0 90)
			(layer "B.Fab")
			(effects
				(font
					(size 1.27 1.27)
				)
				(justify mirror)
			)
		)
		(duplicate_pad_numbers_are_jumpers no)
		(fp_line
			(start -0.299974 0.150114)
			(end 0.299974 0.150114)
			(stroke
				(width 0.1)
				(type default)
			)
			(layer "B.Fab")
		)
		(fp_line
			(start 0.299974 0.150114)
			(end 0.299974 -0.150114)
			(stroke
				(width 0.1)
				(type default)
			)
			(layer "B.Fab")
		)
		(fp_line
			(start -0.299974 -0.150114)
			(end -0.299974 0.150114)
			(stroke
				(width 0.1)
				(type default)
			)
			(layer "B.Fab")
		)
		(fp_line
			(start 0.299974 -0.150114)
			(end -0.299974 -0.150114)
			(stroke
				(width 0.1)
				(type default)
			)
			(layer "B.Fab")
		)
		(pad "1" smd rect
			(at 0.2667 0 90)
			(size 0.3048 0.381)
			(layers "B.Cu" "B.Mask" "B.Paste")
			(net "P0V8_PEX1")
		)
		(pad "2" smd rect
			(at -0.2667 0 90)
			(size 0.3048 0.381)
			(layers "B.Cu" "B.Mask" "B.Paste")
			(net "GND")
		)
	)
	(footprint ""
		(layer "B.Cu")
		(at 49.1998 -299.2755 180)
		(property "Reference" "C1132"
			(at 0 0 0)
			(layer "B.SilkS")
			(hide yes)
			(effects
				(font
					(size 1.27 1.27)
				)
				(justify mirror)
			)
		)
		(property "Value" ""
			(at 0 0 0)
			(layer "B.Fab")
			(effects
				(font
					(size 1.27 1.27)
				)
				(justify mirror)
			)
		)
		(duplicate_pad_numbers_are_jumpers no)
		(fp_line
			(start 0.299974 0.150114)
			(end 0.299974 -0.150114)
			(stroke
				(width 0.1)
				(type default)
			)
			(layer "B.Fab")
		)
		(fp_line
			(start 0.299974 -0.150114)
			(end -0.299974 -0.150114)
			(stroke
				(width 0.1)
				(type default)
			)
			(layer "B.Fab")
		)
		(fp_line
			(start -0.299974 0.150114)
			(end 0.299974 0.150114)
			(stroke
				(width 0.1)
				(type default)
			)
			(layer "B.Fab")
		)
		(fp_line
			(start -0.299974 -0.150114)
			(end -0.299974 0.150114)
			(stroke
				(width 0.1)
				(type default)
			)
			(layer "B.Fab")
		)
		(pad "1" smd rect
			(at 0.2667 0)
			(size 0.3048 0.381)
			(layers "B.Cu" "B.Mask" "B.Paste")
			(net "P0V8_PEX0")
		)
		(pad "2" smd rect
			(at -0.2667 0)
			(size 0.3048 0.381)
			(layers "B.Cu" "B.Mask" "B.Paste")
			(net "GND")
		)
	)
	(footprint ""
		(layer "B.Cu")
		(at 69.149976 -303.024794)
		(property "Reference" "C2993"
			(at 0 0 0)
			(layer "B.SilkS")
			(hide yes)
			(effects
				(font
					(size 1.27 1.27)
				)
				(justify mirror)
			)
		)
		(property "Value" ""
			(at 0 0 0)
			(layer "B.Fab")
			(effects
				(font
					(size 1.27 1.27)
				)
				(justify mirror)
			)
		)
		(duplicate_pad_numbers_are_jumpers no)
		(fp_line
			(start -0.299974 -0.150114)
			(end -0.299974 0.150114)
			(stroke
				(width 0.1)
				(type default)
			)
			(layer "B.Fab")
		)
		(fp_line
			(start -0.299974 0.150114)
			(end 0.299974 0.150114)
			(stroke
				(width 0.1)
				(type default)
			)
			(layer "B.Fab")
		)
		(fp_line
			(start 0.299974 -0.150114)
			(end -0.299974 -0.150114)
			(stroke
				(width 0.1)
				(type default)
			)
			(layer "B.Fab")
		)
		(fp_line
			(start 0.299974 0.150114)
			(end 0.299974 -0.150114)
			(stroke
				(width 0.1)
				(type default)
			)
			(layer "B.Fab")
		)
		(pad "1" smd rect
			(at 0.2667 0 180)
			(size 0.3048 0.381)
			(layers "B.Cu" "B.Mask" "B.Paste")
			(net "P1V8_PEX")
		)
		(pad "2" smd rect
			(at -0.2667 0 180)
			(size 0.3048 0.381)
			(layers "B.Cu" "B.Mask" "B.Paste")
			(net "GND")
		)
	)
	(footprint ""
		(layer "B.Cu")
		(at 161.964116 -146.148552 180)
		(property "Reference" "C879"
			(at 0 0 0)
			(layer "B.SilkS")
			(hide yes)
			(effects
				(font
					(size 1.27 1.27)
				)
				(justify mirror)
			)
		)
		(property "Value" ""
			(at 0 0 0)
			(layer "B.Fab")
			(effects
				(font
					(size 1.27 1.27)
				)
				(justify mirror)
			)
		)
		(duplicate_pad_numbers_are_jumpers no)
		(fp_line
			(start 0.299974 0.150114)
			(end 0.299974 -0.150114)
			(stroke
				(width 0.1)
				(type default)
			)
			(layer "B.Fab")
		)
		(fp_line
			(start 0.299974 -0.150114)
			(end -0.299974 -0.150114)
			(stroke
				(width 0.1)
				(type default)
			)
			(layer "B.Fab")
		)
		(fp_line
			(start -0.299974 0.150114)
			(end 0.299974 0.150114)
			(stroke
				(width 0.1)
				(type default)
			)
			(layer "B.Fab")
		)
		(fp_line
			(start -0.299974 -0.150114)
			(end -0.299974 0.150114)
			(stroke
				(width 0.1)
				(type default)
			)
			(layer "B.Fab")
		)
		(pad "1" smd rect
			(at 0.2667 0)
			(size 0.3048 0.381)
			(layers "B.Cu" "B.Mask" "B.Paste")
			(net "P12V_NIC2")
		)
		(pad "2" smd rect
			(at -0.2667 0)
			(size 0.3048 0.381)
			(layers "B.Cu" "B.Mask" "B.Paste")
			(net "GND")
		)
	)
	(footprint ""
		(layer "B.Cu")
		(at 340.27999 -282.167076 90)
		(property "Reference" "R6766"
			(at 0 0 90)
			(layer "B.SilkS")
			(hide yes)
			(effects
				(font
					(size 1.27 1.27)
				)
				(justify mirror)
			)
		)
		(property "Value" ""
			(at 0 0 90)
			(layer "B.Fab")
			(effects
				(font
					(size 1.27 1.27)
				)
				(justify mirror)
			)
		)
		(duplicate_pad_numbers_are_jumpers no)
		(fp_line
			(start 0.7874 -0.4064)
			(end -0.7874 -0.4064)
			(stroke
				(width 0.1524)
				(type default)
			)
			(layer "B.SilkS")
		)
		(fp_line
			(start -0.7874 -0.4064)
			(end -0.7874 0.4064)
			(stroke
				(width 0.1524)
				(type default)
			)
			(layer "B.SilkS")
		)
		(fp_line
			(start 0.7874 0.4064)
			(end 0.7874 -0.4064)
			(stroke
				(width 0.1524)
				(type default)
			)
			(layer "B.SilkS")
		)
		(fp_line
			(start -0.7874 0.4064)
			(end 0.7874 0.4064)
			(stroke
				(width 0.1524)
				(type default)
			)
			(layer "B.SilkS")
		)
		(fp_line
			(start 0.67945 -0.305054)
			(end 0.12065 -0.305054)
			(stroke
				(width 0.1)
				(type default)
			)
			(layer "B.Fab")
		)
		(fp_line
			(start 0.12065 -0.305054)
			(end 0.12065 -0.2794)
			(stroke
				(width 0.1)
				(type default)
			)
			(layer "B.Fab")
		)
		(fp_line
			(start -0.12065 -0.3048)
			(end -0.67945 -0.3048)
			(stroke
				(width 0.1)
				(type default)
			)
			(layer "B.Fab")
		)
		(fp_line
			(start -0.67945 -0.3048)
			(end -0.67945 0.3048)
			(stroke
				(width 0.1)
				(type default)
			)
			(layer "B.Fab")
		)
		(fp_line
			(start 0.12065 -0.2794)
			(end -0.12065 -0.2794)
			(stroke
				(width 0.1)
				(type default)
			)
			(layer "B.Fab")
		)
		(fp_line
			(start -0.12065 -0.2794)
			(end -0.12065 -0.3048)
			(stroke
				(width 0.1)
				(type default)
			)
			(layer "B.Fab")
		)
		(fp_line
			(start 0.12065 0.2794)
			(end 0.12065 0.3048)
			(stroke
				(width 0.1)
				(type default)
			)
			(layer "B.Fab")
		)
		(fp_line
			(start -0.120396 0.2794)
			(end 0.12065 0.2794)
			(stroke
				(width 0.1)
				(type default)
			)
			(layer "B.Fab")
		)
		(fp_line
			(start 0.67945 0.3048)
			(end 0.67945 -0.305054)
			(stroke
				(width 0.1)
				(type default)
			)
			(layer "B.Fab")
		)
		(fp_line
			(start 0.12065 0.3048)
			(end 0.67945 0.3048)
			(stroke
				(width 0.1)
				(type default)
			)
			(layer "B.Fab")
		)
		(fp_line
			(start -0.120396 0.3048)
			(end -0.120396 0.2794)
			(stroke
				(width 0.1)
				(type default)
			)
			(layer "B.Fab")
		)
		(fp_line
			(start -0.67945 0.3048)
			(end -0.120396 0.3048)
			(stroke
				(width 0.1)
				(type default)
			)
			(layer "B.Fab")
		)
		(pad "1" smd circle
			(at 0.40005 0 270)
			(size 0 0)
			(layers "B.Cu" "B.Mask" "B.Paste")
			(net "P0V8_PEX2_VCC1")
		)
		(pad "2" smd circle
			(at -0.40005 0 270)
			(size 0 0)
			(layers "B.Cu" "B.Mask" "B.Paste")
			(net "P0V8_PEX2_EN1")
		)
	)
	(footprint ""
		(layer "B.Cu")
		(at 169.099992 -303.499774 -90)
		(property "Reference" "C3087"
			(at 0 0 90)
			(layer "B.SilkS")
			(hide yes)
			(effects
				(font
					(size 1.27 1.27)
				)
				(justify mirror)
			)
		)
		(property "Value" ""
			(at 0 0 90)
			(layer "B.Fab")
			(effects
				(font
					(size 1.27 1.27)
				)
				(justify mirror)
			)
		)
		(duplicate_pad_numbers_are_jumpers no)
		(fp_line
			(start -0.299974 0.150114)
			(end 0.299974 0.150114)
			(stroke
				(width 0.1)
				(type default)
			)
			(layer "B.Fab")
		)
		(fp_line
			(start 0.299974 0.150114)
			(end 0.299974 -0.150114)
			(stroke
				(width 0.1)
				(type default)
			)
			(layer "B.Fab")
		)
		(fp_line
			(start -0.299974 -0.150114)
			(end -0.299974 0.150114)
			(stroke
				(width 0.1)
				(type default)
			)
			(layer "B.Fab")
		)
		(fp_line
			(start 0.299974 -0.150114)
			(end -0.299974 -0.150114)
			(stroke
				(width 0.1)
				(type default)
			)
			(layer "B.Fab")
		)
		(pad "1" smd rect
			(at 0.2667 0 90)
			(size 0.3048 0.381)
			(layers "B.Cu" "B.Mask" "B.Paste")
			(net "P1V25_PEX1")
		)
		(pad "2" smd rect
			(at -0.2667 0 90)
			(size 0.3048 0.381)
			(layers "B.Cu" "B.Mask" "B.Paste")
			(net "GND")
		)
	)
	(footprint ""
		(layer "B.Cu")
		(at 347.2688 -361.4166)
		(property "Reference" "C4128"
			(at 0 0 0)
			(layer "B.SilkS")
			(hide yes)
			(effects
				(font
					(size 1.27 1.27)
				)
				(justify mirror)
			)
		)
		(property "Value" ""
			(at 0 0 0)
			(layer "B.Fab")
			(effects
				(font
					(size 1.27 1.27)
				)
				(justify mirror)
			)
		)
		(duplicate_pad_numbers_are_jumpers no)
		(fp_line
			(start -0.7874 -0.4064)
			(end -0.7874 0.4064)
			(stroke
				(width 0.1524)
				(type default)
			)
			(layer "B.SilkS")
		)
		(fp_line
			(start -0.7874 0.4064)
			(end 0.7874 0.4064)
			(stroke
				(width 0.1524)
				(type default)
			)
			(layer "B.SilkS")
		)
		(fp_line
			(start 0.7874 -0.4064)
			(end -0.7874 -0.4064)
			(stroke
				(width 0.1524)
				(type default)
			)
			(layer "B.SilkS")
		)
		(fp_line
			(start 0.7874 0.4064)
			(end 0.7874 -0.4064)
			(stroke
				(width 0.1524)
				(type default)
			)
			(layer "B.SilkS")
		)
		(fp_line
			(start -0.67945 -0.3048)
			(end -0.67945 0.3048)
			(stroke
				(width 0.1)
				(type default)
			)
			(layer "B.Fab")
		)
		(fp_line
			(start -0.67945 0.3048)
			(end -0.120396 0.3048)
			(stroke
				(width 0.1)
				(type default)
			)
			(layer "B.Fab")
		)
		(fp_line
			(start -0.12065 -0.3048)
			(end -0.67945 -0.3048)
			(stroke
				(width 0.1)
				(type default)
			)
			(layer "B.Fab")
		)
		(fp_line
			(start -0.12065 -0.2794)
			(end -0.12065 -0.3048)
			(stroke
				(width 0.1)
				(type default)
			)
			(layer "B.Fab")
		)
		(fp_line
			(start -0.120396 0.2794)
			(end 0.12065 0.2794)
			(stroke
				(width 0.1)
				(type default)
			)
			(layer "B.Fab")
		)
		(fp_line
			(start -0.120396 0.3048)
			(end -0.120396 0.2794)
			(stroke
				(width 0.1)
				(type default)
			)
			(layer "B.Fab")
		)
		(fp_line
			(start 0.12065 -0.305054)
			(end 0.12065 -0.2794)
			(stroke
				(width 0.1)
				(type default)
			)
			(layer "B.Fab")
		)
		(fp_line
			(start 0.12065 -0.2794)
			(end -0.12065 -0.2794)
			(stroke
				(width 0.1)
				(type default)
			)
			(layer "B.Fab")
		)
		(fp_line
			(start 0.12065 0.2794)
			(end 0.12065 0.3048)
			(stroke
				(width 0.1)
				(type default)
			)
			(layer "B.Fab")
		)
		(fp_line
			(start 0.12065 0.3048)
			(end 0.67945 0.3048)
			(stroke
				(width 0.1)
				(type default)
			)
			(layer "B.Fab")
		)
		(fp_line
			(start 0.67945 -0.305054)
			(end 0.12065 -0.305054)
			(stroke
				(width 0.1)
				(type default)
			)
			(layer "B.Fab")
		)
		(fp_line
			(start 0.67945 0.3048)
			(end 0.67945 -0.305054)
			(stroke
				(width 0.1)
				(type default)
			)
			(layer "B.Fab")
		)
		(pad "1" smd circle
			(at 0.40005 0 180)
			(size 0 0)
			(layers "B.Cu" "B.Mask" "B.Paste")
			(net "GND")
		)
		(pad "2" smd circle
			(at -0.40005 0 180)
			(size 0 0)
			(layers "B.Cu" "B.Mask" "B.Paste")
			(net "MB_HSC_EN")
		)
	)
	(footprint ""
		(layer "B.Cu")
		(at 296.980864 -457.31049 180)
		(property "Reference" "X74"
			(at 0.1778 -1.92913 180)
			(unlocked yes)
			(layer "B.SilkS")
			(effects
				(font
					(size 0.7874 0.5842)
					(thickness 0.1524)
				)
				(justify left mirror)
			)
		)
		(property "Value" ""
			(at 0 0 0)
			(layer "B.Fab")
			(effects
				(font
					(size 1.27 1.27)
				)
				(justify mirror)
			)
		)
		(property "Device Type" "TP_TDR_4P_FTS_MPKT4_H025P0200_IO_TP15_TP_TDR_4P_DIP"
			(at -1.30175 1.27 90)
			(unlocked yes)
			(layer "B.Fab")
			(hide yes)
			(effects
				(font
					(size 0.635 0.4064)
					(thickness 0.1524)
				)
				(justify mirror)
			)
		)
		(property "User Part Number" "TP15"
			(at -1.30175 1.27 90)
			(unlocked yes)
			(layer "Cmts.User")
			(hide yes)
			(effects
				(font
					(size 0.635 0.4064)
					(thickness 0.1524)
				)
				(justify mirror)
			)
		)
		(duplicate_pad_numbers_are_jumpers no)
		(fp_line
			(start 0 3.81)
			(end -2.54 3.81)
			(stroke
				(width 0.1524)
				(type default)
			)
			(layer "B.SilkS")
		)
		(fp_line
			(start 0 3.175)
			(end 0 3.81)
			(stroke
				(width 0.1524)
				(type default)
			)
			(layer "B.SilkS")
		)
		(fp_line
			(start 0 0.635)
			(end 0 1.905)
			(stroke
				(width 0.1524)
				(type default)
			)
			(layer "B.SilkS")
		)
		(fp_line
			(start 0 -1.27)
			(end 0 -0.635)
			(stroke
				(width 0.1524)
				(type default)
			)
			(layer "B.SilkS")
		)
		(fp_line
			(start -2.54 3.81)
			(end -2.54 3.6703)
			(stroke
				(width 0.1524)
				(type default)
			)
			(layer "B.SilkS")
		)
		(fp_line
			(start -2.54 1.4097)
			(end -2.54 1.1303)
			(stroke
				(width 0.1524)
				(type default)
			)
			(layer "B.SilkS")
		)
		(fp_line
			(start -2.54 -1.1303)
			(end -2.54 -1.27)
			(stroke
				(width 0.1524)
				(type default)
			)
			(layer "B.SilkS")
		)
		(fp_line
			(start -2.54 -1.27)
			(end 0 -1.27)
			(stroke
				(width 0.1524)
				(type default)
			)
			(layer "B.SilkS")
		)
		(fp_poly
			(pts
				(xy 0.761746 0) (xy 2.285746 -0.762) (xy 2.285746 0.762)
			)
			(stroke
				(width 0)
				(type default)
			)
			(fill yes)
			(layer "B.SilkS")
		)
		(fp_line
			(start 0 3.81)
			(end -2.54 3.81)
			(stroke
				(width 0.1)
				(type default)
			)
			(layer "B.Fab")
		)
		(fp_line
			(start 0 -1.27)
			(end 0 3.81)
			(stroke
				(width 0.1)
				(type default)
			)
			(layer "B.Fab")
		)
		(fp_line
			(start -2.54 3.81)
			(end -2.54 -1.27)
			(stroke
				(width 0.1)
				(type default)
			)
			(layer "B.Fab")
		)
		(fp_line
			(start -2.54 -1.27)
			(end 0 -1.27)
			(stroke
				(width 0.1)
				(type default)
			)
			(layer "B.Fab")
		)
		(fp_poly
			(pts
				(xy 0.761746 0) (xy 2.285746 -0.762) (xy 2.285746 0.762)
			)
			(stroke
				(width 0)
				(type default)
			)
			(fill yes)
			(layer "B.Fab")
		)
		(pad "1" thru_hole circle
			(at 0 0)
			(size 1.0033 1.0033)
			(drill 0.249936)
			(layers "*.Cu" "*.Mask")
			(remove_unused_layers no)
			(net "TDR_DIFF_100_IN4_DIP")
			(clearance 0.10795)
			(padstack
				(mode front_inner_back)
				(layer "Inner"
					(shape circle)
					(size 0.8001 0.8001)
					(clearance 0.1524)
				)
				(layer "B.Cu"
					(shape circle)
					(size 1.0033 1.0033)
					(thermal_gap 0.10795)
					(clearance 0.10795)
				)
			)
		)
		(pad "2" thru_hole circle
			(at -2.54 0)
			(size 1.9939 1.9939)
			(drill 0.249936)
			(layers "*.Cu" "*.Mask")
			(remove_unused_layers no)
			(net "COUPON_GND1")
			(clearance 0.10795)
			(padstack
				(mode front_inner_back)
				(layer "Inner"
					(shape circle)
					(size 0.8001 0.8001)
					(clearance 0.1524)
				)
				(layer "B.Cu"
					(shape circle)
					(size 1.9939 1.9939)
					(thermal_gap 0.10795)
					(clearance 0.10795)
				)
			)
		)
		(pad "3" thru_hole circle
			(at -2.54 2.54)
			(size 1.9939 1.9939)
			(drill 0.249936)
			(layers "*.Cu" "*.Mask")
			(remove_unused_layers no)
			(net "COUPON_GND1")
			(clearance 0.10795)
			(padstack
				(mode front_inner_back)
				(layer "Inner"
					(shape circle)
					(size 0.8001 0.8001)
					(clearance 0.1524)
				)
				(layer "B.Cu"
					(shape circle)
					(size 1.9939 1.9939)
					(thermal_gap 0.10795)
					(clearance 0.10795)
				)
			)
		)
		(pad "4" thru_hole circle
			(at 0 2.54)
			(size 1.0033 1.0033)
			(drill 0.249936)
			(layers "*.Cu" "*.Mask")
			(remove_unused_layers no)
			(net "TDR_DIFF_100_IN4_DIN")
			(clearance 0.10795)
			(padstack
				(mode front_inner_back)
				(layer "Inner"
					(shape circle)
					(size 0.8001 0.8001)
					(clearance 0.1524)
				)
				(layer "B.Cu"
					(shape circle)
					(size 1.0033 1.0033)
					(thermal_gap 0.10795)
					(clearance 0.10795)
				)
			)
		)
	)
	(footprint ""
		(layer "B.Cu")
		(at 180.975 -297.79976 -90)
		(property "Reference" "C1399"
			(at 0 0 90)
			(layer "B.SilkS")
			(hide yes)
			(effects
				(font
					(size 1.27 1.27)
				)
				(justify mirror)
			)
		)
		(property "Value" ""
			(at 0 0 90)
			(layer "B.Fab")
			(effects
				(font
					(size 1.27 1.27)
				)
				(justify mirror)
			)
		)
		(duplicate_pad_numbers_are_jumpers no)
		(fp_line
			(start -0.299974 0.150114)
			(end 0.299974 0.150114)
			(stroke
				(width 0.1)
				(type default)
			)
			(layer "B.Fab")
		)
		(fp_line
			(start 0.299974 0.150114)
			(end 0.299974 -0.150114)
			(stroke
				(width 0.1)
				(type default)
			)
			(layer "B.Fab")
		)
		(fp_line
			(start -0.299974 -0.150114)
			(end -0.299974 0.150114)
			(stroke
				(width 0.1)
				(type default)
			)
			(layer "B.Fab")
		)
		(fp_line
			(start 0.299974 -0.150114)
			(end -0.299974 -0.150114)
			(stroke
				(width 0.1)
				(type default)
			)
			(layer "B.Fab")
		)
		(pad "1" smd rect
			(at 0.2667 0 90)
			(size 0.3048 0.381)
			(layers "B.Cu" "B.Mask" "B.Paste")
			(net "P0V8_PEX1")
		)
		(pad "2" smd rect
			(at -0.2667 0 90)
			(size 0.3048 0.381)
			(layers "B.Cu" "B.Mask" "B.Paste")
			(net "GND")
		)
	)
	(footprint ""
		(layer "B.Cu")
		(at 187.149994 -297.32478 180)
		(property "Reference" "C3080"
			(at 0 0 0)
			(layer "B.SilkS")
			(hide yes)
			(effects
				(font
					(size 1.27 1.27)
				)
				(justify mirror)
			)
		)
		(property "Value" ""
			(at 0 0 0)
			(layer "B.Fab")
			(effects
				(font
					(size 1.27 1.27)
				)
				(justify mirror)
			)
		)
		(duplicate_pad_numbers_are_jumpers no)
		(fp_line
			(start 0.299974 0.150114)
			(end 0.299974 -0.150114)
			(stroke
				(width 0.1)
				(type default)
			)
			(layer "B.Fab")
		)
		(fp_line
			(start 0.299974 -0.150114)
			(end -0.299974 -0.150114)
			(stroke
				(width 0.1)
				(type default)
			)
			(layer "B.Fab")
		)
		(fp_line
			(start -0.299974 0.150114)
			(end 0.299974 0.150114)
			(stroke
				(width 0.1)
				(type default)
			)
			(layer "B.Fab")
		)
		(fp_line
			(start -0.299974 -0.150114)
			(end -0.299974 0.150114)
			(stroke
				(width 0.1)
				(type default)
			)
			(layer "B.Fab")
		)
		(pad "1" smd rect
			(at 0.2667 0)
			(size 0.3048 0.381)
			(layers "B.Cu" "B.Mask" "B.Paste")
			(net "P1V25_PEX1")
		)
		(pad "2" smd rect
			(at -0.2667 0)
			(size 0.3048 0.381)
			(layers "B.Cu" "B.Mask" "B.Paste")
			(net "GND")
		)
	)
	(footprint ""
		(layer "B.Cu")
		(at 377.910344 20.568412)
		(property "Reference" "DE06F_2"
			(at 2.480056 3.054858 0)
			(unlocked yes)
			(layer "B.SilkS")
			(effects
				(font
					(size 0.7874 0.5842)
					(thickness 0.1524)
				)
				(justify left mirror)
			)
		)
		(property "Value" ""
			(at 0 0 0)
			(layer "B.Fab")
			(effects
				(font
					(size 1.27 1.27)
				)
				(justify mirror)
			)
		)
		(duplicate_pad_numbers_are_jumpers no)
		(fp_line
			(start -1.2192 -2.1082)
			(end -1.2192 2.1082)
			(stroke
				(width 0.1524)
				(type default)
			)
			(layer "B.SilkS")
		)
		(fp_line
			(start -1.2192 2.1082)
			(end 1.2192 2.1082)
			(stroke
				(width 0.1524)
				(type default)
			)
			(layer "B.SilkS")
		)
		(fp_line
			(start 1.2192 -2.1082)
			(end -1.2192 -2.1082)
			(stroke
				(width 0.1524)
				(type default)
			)
			(layer "B.SilkS")
		)
		(fp_line
			(start 1.2192 2.1082)
			(end 1.2192 -2.1082)
			(stroke
				(width 0.1524)
				(type default)
			)
			(layer "B.SilkS")
		)
		(pad "" np_thru_hole circle
			(at -3.4671 -1.27 270)
			(size 1.0414 1.0414)
			(drill 1.0414)
			(layers "*.Cu" "*.Mask")
			(clearance 0.381)
			(thermal_gap 0.381)
		)
		(pad "" np_thru_hole circle
			(at -3.4671 1.27 270)
			(size 1.0414 1.0414)
			(drill 1.0414)
			(layers "*.Cu" "*.Mask")
			(clearance 0.381)
			(thermal_gap 0.381)
		)
		(pad "" np_thru_hole circle
			(at 2.8829 -1.27 270)
			(size 1.0414 1.0414)
			(drill 1.0414)
			(layers "*.Cu" "*.Mask")
			(clearance 0.381)
			(thermal_gap 0.381)
		)
		(pad "" np_thru_hole circle
			(at 2.8829 1.27 270)
			(size 1.0414 1.0414)
			(drill 1.0414)
			(layers "*.Cu" "*.Mask")
			(clearance 0.381)
			(thermal_gap 0.381)
		)
		(pad "1" smd rect
			(at -0.8255 -0.249936 270)
			(size 0.3048 0.508)
			(layers "B.Cu" "B.Mask" "B.Paste")
			(net "85_5INCH_IN4_DN")
		)
		(pad "2" smd rect
			(at -0.8255 0.249936 270)
			(size 0.3048 0.508)
			(layers "B.Cu" "B.Mask" "B.Paste")
			(net "85_5INCH_IN4_DP")
		)
		(pad "3" smd circle
			(at 0 0 180)
			(size 0 0)
			(layers "B.Cu" "B.Mask" "B.Paste")
			(net "COUPON_GND2")
		)
		(zone
			(layers "F.Cu" "B.Cu" "In1.Cu" "In2.Cu" "In3.Cu" "In4.Cu" "In5.Cu" "In6.Cu"
				"In7.Cu" "In8.Cu" "In9.Cu" "In10.Cu" "In11.Cu" "In12.Cu" "In13.Cu" "In14.Cu"
				"In15.Cu" "In16.Cu"
			)
			(hatch none 0.5)
			(connect_pads
				(clearance 0)
			)
			(min_thickness 0.25)
			(keepout
				(tracks not_allowed)
				(vias allowed)
				(pads allowed)
				(copperpour not_allowed)
				(footprints allowed)
			)
			(placement
				(enabled no)
				(sheetname "")
			)
			(fill
				(thermal_gap 0.5)
				(thermal_bridge_width 0.5)
				(island_removal_mode 0)
			)
			(polygon
				(pts
					(arc
						(start 375.370344 19.298412)
						(mid 373.516144 19.298412)
						(end 375.370344 19.298412)
					)
				)
			)
		)
		(zone
			(layers "F.Cu" "B.Cu" "In1.Cu" "In2.Cu" "In3.Cu" "In4.Cu" "In5.Cu" "In6.Cu"
				"In7.Cu" "In8.Cu" "In9.Cu" "In10.Cu" "In11.Cu" "In12.Cu" "In13.Cu" "In14.Cu"
				"In15.Cu" "In16.Cu"
			)
			(hatch none 0.5)
			(connect_pads
				(clearance 0)
			)
			(min_thickness 0.25)
			(keepout
				(tracks not_allowed)
				(vias allowed)
				(pads allowed)
				(copperpour not_allowed)
				(footprints allowed)
			)
			(placement
				(enabled no)
				(sheetname "")
			)
			(fill
				(thermal_gap 0.5)
				(thermal_bridge_width 0.5)
				(island_removal_mode 0)
			)
			(polygon
				(pts
					(arc
						(start 375.370344 21.838412)
						(mid 373.516144 21.838412)
						(end 375.370344 21.838412)
					)
				)
			)
		)
		(zone
			(layers "F.Cu" "B.Cu" "In1.Cu" "In2.Cu" "In3.Cu" "In4.Cu" "In5.Cu" "In6.Cu"
				"In7.Cu" "In8.Cu" "In9.Cu" "In10.Cu" "In11.Cu" "In12.Cu" "In13.Cu" "In14.Cu"
				"In15.Cu" "In16.Cu"
			)
			(hatch none 0.5)
			(connect_pads
				(clearance 0)
			)
			(min_thickness 0.25)
			(keepout
				(tracks not_allowed)
				(vias allowed)
				(pads allowed)
				(copperpour not_allowed)
				(footprints allowed)
			)
			(placement
				(enabled no)
				(sheetname "")
			)
			(fill
				(thermal_gap 0.5)
				(thermal_bridge_width 0.5)
				(island_removal_mode 0)
			)
			(polygon
				(pts
					(arc
						(start 381.720344 19.298412)
						(mid 379.866144 19.298412)
						(end 381.720344 19.298412)
					)
				)
			)
		)
		(zone
			(layers "F.Cu" "B.Cu" "In1.Cu" "In2.Cu" "In3.Cu" "In4.Cu" "In5.Cu" "In6.Cu"
				"In7.Cu" "In8.Cu" "In9.Cu" "In10.Cu" "In11.Cu" "In12.Cu" "In13.Cu" "In14.Cu"
				"In15.Cu" "In16.Cu"
			)
			(hatch none 0.5)
			(connect_pads
				(clearance 0)
			)
			(min_thickness 0.25)
			(keepout
				(tracks not_allowed)
				(vias allowed)
				(pads allowed)
				(copperpour not_allowed)
				(footprints allowed)
			)
			(placement
				(enabled no)
				(sheetname "")
			)
			(fill
				(thermal_gap 0.5)
				(thermal_bridge_width 0.5)
				(island_removal_mode 0)
			)
			(polygon
				(pts
					(arc
						(start 381.720344 21.838412)
						(mid 379.866144 21.838412)
						(end 381.720344 21.838412)
					)
				)
			)
		)
		(zone
			(layer "B.Cu")
			(hatch none 0.5)
			(connect_pads
				(clearance 0)
			)
			(min_thickness 0.25)
			(keepout
				(tracks not_allowed)
				(vias allowed)
				(pads allowed)
				(copperpour not_allowed)
				(footprints allowed)
			)
			(placement
				(enabled no)
				(sheetname "")
			)
			(fill
				(thermal_gap 0.5)
				(thermal_bridge_width 0.5)
				(island_removal_mode 0)
			)
			(polygon
				(pts
					(xy 376.792744 20.019772) (xy 376.792744 20.115276) (xy 377.389644 20.115276) (xy 377.389644 20.521676)
					(xy 376.792744 20.521676) (xy 376.792744 20.615148) (xy 377.389644 20.615148) (xy 377.389644 21.021548)
					(xy 376.792744 21.021548) (xy 376.792744 21.117052) (xy 377.491244 21.117052) (xy 377.491244 20.019772)
				)
			)
		)
	)
	(footprint ""
		(layer "B.Cu")
		(at 400.369024 10.689844 180)
		(property "Reference" "DE15T_3"
			(at -2.627376 -3.383026 0)
			(unlocked yes)
			(layer "B.SilkS")
			(effects
				(font
					(size 0.7874 0.5842)
					(thickness 0.1524)
				)
				(justify left mirror)
			)
		)
		(property "Value" ""
			(at 0 0 0)
			(layer "B.Fab")
			(effects
				(font
					(size 1.27 1.27)
				)
				(justify mirror)
			)
		)
		(duplicate_pad_numbers_are_jumpers no)
		(fp_line
			(start 1.2192 2.1082)
			(end 1.2192 -2.1082)
			(stroke
				(width 0.1524)
				(type default)
			)
			(layer "B.SilkS")
		)
		(fp_line
			(start 1.2192 -2.1082)
			(end -1.2192 -2.1082)
			(stroke
				(width 0.1524)
				(type default)
			)
			(layer "B.SilkS")
		)
		(fp_line
			(start -1.2192 2.1082)
			(end 1.2192 2.1082)
			(stroke
				(width 0.1524)
				(type default)
			)
			(layer "B.SilkS")
		)
		(fp_line
			(start -1.2192 -2.1082)
			(end -1.2192 2.1082)
			(stroke
				(width 0.1524)
				(type default)
			)
			(layer "B.SilkS")
		)
		(pad "" np_thru_hole circle
			(at -3.4671 -1.27 90)
			(size 1.0414 1.0414)
			(drill 1.0414)
			(layers "*.Cu" "*.Mask")
			(clearance 0.381)
			(thermal_gap 0.381)
		)
		(pad "" np_thru_hole circle
			(at -3.4671 1.27 90)
			(size 1.0414 1.0414)
			(drill 1.0414)
			(layers "*.Cu" "*.Mask")
			(clearance 0.381)
			(thermal_gap 0.381)
		)
		(pad "" np_thru_hole circle
			(at 2.8829 -1.27 90)
			(size 1.0414 1.0414)
			(drill 1.0414)
			(layers "*.Cu" "*.Mask")
			(clearance 0.381)
			(thermal_gap 0.381)
		)
		(pad "" np_thru_hole circle
			(at 2.8829 1.27 90)
			(size 1.0414 1.0414)
			(drill 1.0414)
			(layers "*.Cu" "*.Mask")
			(clearance 0.381)
			(thermal_gap 0.381)
		)
		(pad "1" smd rect
			(at -0.8255 -0.249936 90)
			(size 0.3048 0.508)
			(layers "B.Cu" "B.Mask" "B.Paste")
			(net "85_10INCH_IN5_DP")
		)
		(pad "2" smd rect
			(at -0.8255 0.249936 90)
			(size 0.3048 0.508)
			(layers "B.Cu" "B.Mask" "B.Paste")
			(net "85_10INCH_IN5_DN")
		)
		(pad "3" smd circle
			(at 0 0)
			(size 0 0)
			(layers "B.Cu" "B.Mask" "B.Paste")
			(net "COUPON_GND2")
		)
		(zone
			(layers "F.Cu" "B.Cu" "In1.Cu" "In2.Cu" "In3.Cu" "In4.Cu" "In5.Cu" "In6.Cu"
				"In7.Cu" "In8.Cu" "In9.Cu" "In10.Cu" "In11.Cu" "In12.Cu" "In13.Cu" "In14.Cu"
				"In15.Cu" "In16.Cu"
			)
			(hatch none 0.5)
			(connect_pads
				(clearance 0)
			)
			(min_thickness 0.25)
			(keepout
				(tracks not_allowed)
				(vias allowed)
				(pads allowed)
				(copperpour not_allowed)
				(footprints allowed)
			)
			(placement
				(enabled no)
				(sheetname "")
			)
			(fill
				(thermal_gap 0.5)
				(thermal_bridge_width 0.5)
				(island_removal_mode 0)
			)
			(polygon
				(pts
					(arc
						(start 398.413224 9.419844)
						(mid 396.559024 9.419844)
						(end 398.413224 9.419844)
					)
				)
			)
		)
		(zone
			(layers "F.Cu" "B.Cu" "In1.Cu" "In2.Cu" "In3.Cu" "In4.Cu" "In5.Cu" "In6.Cu"
				"In7.Cu" "In8.Cu" "In9.Cu" "In10.Cu" "In11.Cu" "In12.Cu" "In13.Cu" "In14.Cu"
				"In15.Cu" "In16.Cu"
			)
			(hatch none 0.5)
			(connect_pads
				(clearance 0)
			)
			(min_thickness 0.25)
			(keepout
				(tracks not_allowed)
				(vias allowed)
				(pads allowed)
				(copperpour not_allowed)
				(footprints allowed)
			)
			(placement
				(enabled no)
				(sheetname "")
			)
			(fill
				(thermal_gap 0.5)
				(thermal_bridge_width 0.5)
				(island_removal_mode 0)
			)
			(polygon
				(pts
					(arc
						(start 398.413224 11.959844)
						(mid 396.559024 11.959844)
						(end 398.413224 11.959844)
					)
				)
			)
		)
		(zone
			(layers "F.Cu" "B.Cu" "In1.Cu" "In2.Cu" "In3.Cu" "In4.Cu" "In5.Cu" "In6.Cu"
				"In7.Cu" "In8.Cu" "In9.Cu" "In10.Cu" "In11.Cu" "In12.Cu" "In13.Cu" "In14.Cu"
				"In15.Cu" "In16.Cu"
			)
			(hatch none 0.5)
			(connect_pads
				(clearance 0)
			)
			(min_thickness 0.25)
			(keepout
				(tracks not_allowed)
				(vias allowed)
				(pads allowed)
				(copperpour not_allowed)
				(footprints allowed)
			)
			(placement
				(enabled no)
				(sheetname "")
			)
			(fill
				(thermal_gap 0.5)
				(thermal_bridge_width 0.5)
				(island_removal_mode 0)
			)
			(polygon
				(pts
					(arc
						(start 404.763224 9.419844)
						(mid 402.909024 9.419844)
						(end 404.763224 9.419844)
					)
				)
			)
		)
		(zone
			(layers "F.Cu" "B.Cu" "In1.Cu" "In2.Cu" "In3.Cu" "In4.Cu" "In5.Cu" "In6.Cu"
				"In7.Cu" "In8.Cu" "In9.Cu" "In10.Cu" "In11.Cu" "In12.Cu" "In13.Cu" "In14.Cu"
				"In15.Cu" "In16.Cu"
			)
			(hatch none 0.5)
			(connect_pads
				(clearance 0)
			)
			(min_thickness 0.25)
			(keepout
				(tracks not_allowed)
				(vias allowed)
				(pads allowed)
				(copperpour not_allowed)
				(footprints allowed)
			)
			(placement
				(enabled no)
				(sheetname "")
			)
			(fill
				(thermal_gap 0.5)
				(thermal_bridge_width 0.5)
				(island_removal_mode 0)
			)
			(polygon
				(pts
					(arc
						(start 404.763224 11.959844)
						(mid 402.909024 11.959844)
						(end 404.763224 11.959844)
					)
				)
			)
		)
		(zone
			(layer "B.Cu")
			(hatch none 0.5)
			(connect_pads
				(clearance 0)
			)
			(min_thickness 0.25)
			(keepout
				(tracks not_allowed)
				(vias allowed)
				(pads allowed)
				(copperpour not_allowed)
				(footprints allowed)
			)
			(placement
				(enabled no)
				(sheetname "")
			)
			(fill
				(thermal_gap 0.5)
				(thermal_bridge_width 0.5)
				(island_removal_mode 0)
			)
			(polygon
				(pts
					(xy 401.486624 11.238484) (xy 401.486624 11.14298) (xy 400.889724 11.14298) (xy 400.889724 10.73658)
					(xy 401.486624 10.73658) (xy 401.486624 10.643108) (xy 400.889724 10.643108) (xy 400.889724 10.236708)
					(xy 401.486624 10.236708) (xy 401.486624 10.141204) (xy 400.788124 10.141204) (xy 400.788124 11.238484)
				)
			)
		)
	)
	(footprint ""
		(layer "B.Cu")
		(at 408.899868 -301.599854 -90)
		(property "Reference" "C1990"
			(at 0 0 90)
			(layer "B.SilkS")
			(hide yes)
			(effects
				(font
					(size 1.27 1.27)
				)
				(justify mirror)
			)
		)
		(property "Value" ""
			(at 0 0 90)
			(layer "B.Fab")
			(effects
				(font
					(size 1.27 1.27)
				)
				(justify mirror)
			)
		)
		(duplicate_pad_numbers_are_jumpers no)
		(fp_line
			(start -0.299974 0.150114)
			(end 0.299974 0.150114)
			(stroke
				(width 0.1)
				(type default)
			)
			(layer "B.Fab")
		)
		(fp_line
			(start 0.299974 0.150114)
			(end 0.299974 -0.150114)
			(stroke
				(width 0.1)
				(type default)
			)
			(layer "B.Fab")
		)
		(fp_line
			(start -0.299974 -0.150114)
			(end -0.299974 0.150114)
			(stroke
				(width 0.1)
				(type default)
			)
			(layer "B.Fab")
		)
		(fp_line
			(start 0.299974 -0.150114)
			(end -0.299974 -0.150114)
			(stroke
				(width 0.1)
				(type default)
			)
			(layer "B.Fab")
		)
		(pad "1" smd rect
			(at 0.2667 0 90)
			(size 0.3048 0.381)
			(layers "B.Cu" "B.Mask" "B.Paste")
			(net "P0V8_SERDES_VDDA_PEX3")
		)
		(pad "2" smd rect
			(at -0.2667 0 90)
			(size 0.3048 0.381)
			(layers "B.Cu" "B.Mask" "B.Paste")
			(net "GND")
		)
	)
	(footprint ""
		(layer "B.Cu")
		(at 302.877474 -223.599502 90)
		(property "Reference" "R1862"
			(at 0 0 90)
			(layer "B.SilkS")
			(hide yes)
			(effects
				(font
					(size 1.27 1.27)
				)
				(justify mirror)
			)
		)
		(property "Value" ""
			(at 0 0 90)
			(layer "B.Fab")
			(effects
				(font
					(size 1.27 1.27)
				)
				(justify mirror)
			)
		)
		(duplicate_pad_numbers_are_jumpers no)
		(fp_line
			(start 0.7874 -0.4064)
			(end -0.7874 -0.4064)
			(stroke
				(width 0.1524)
				(type default)
			)
			(layer "B.SilkS")
		)
		(fp_line
			(start -0.7874 -0.4064)
			(end -0.7874 0.4064)
			(stroke
				(width 0.1524)
				(type default)
			)
			(layer "B.SilkS")
		)
		(fp_line
			(start 0.7874 0.4064)
			(end 0.7874 -0.4064)
			(stroke
				(width 0.1524)
				(type default)
			)
			(layer "B.SilkS")
		)
		(fp_line
			(start -0.7874 0.4064)
			(end 0.7874 0.4064)
			(stroke
				(width 0.1524)
				(type default)
			)
			(layer "B.SilkS")
		)
		(fp_line
			(start 0.67945 -0.305054)
			(end 0.12065 -0.305054)
			(stroke
				(width 0.1)
				(type default)
			)
			(layer "B.Fab")
		)
		(fp_line
			(start 0.12065 -0.305054)
			(end 0.12065 -0.2794)
			(stroke
				(width 0.1)
				(type default)
			)
			(layer "B.Fab")
		)
		(fp_line
			(start -0.12065 -0.3048)
			(end -0.67945 -0.3048)
			(stroke
				(width 0.1)
				(type default)
			)
			(layer "B.Fab")
		)
		(fp_line
			(start -0.67945 -0.3048)
			(end -0.67945 0.3048)
			(stroke
				(width 0.1)
				(type default)
			)
			(layer "B.Fab")
		)
		(fp_line
			(start 0.12065 -0.2794)
			(end -0.12065 -0.2794)
			(stroke
				(width 0.1)
				(type default)
			)
			(layer "B.Fab")
		)
		(fp_line
			(start -0.12065 -0.2794)
			(end -0.12065 -0.3048)
			(stroke
				(width 0.1)
				(type default)
			)
			(layer "B.Fab")
		)
		(fp_line
			(start 0.12065 0.2794)
			(end 0.12065 0.3048)
			(stroke
				(width 0.1)
				(type default)
			)
			(layer "B.Fab")
		)
		(fp_line
			(start -0.120396 0.2794)
			(end 0.12065 0.2794)
			(stroke
				(width 0.1)
				(type default)
			)
			(layer "B.Fab")
		)
		(fp_line
			(start 0.67945 0.3048)
			(end 0.67945 -0.305054)
			(stroke
				(width 0.1)
				(type default)
			)
			(layer "B.Fab")
		)
		(fp_line
			(start 0.12065 0.3048)
			(end 0.67945 0.3048)
			(stroke
				(width 0.1)
				(type default)
			)
			(layer "B.Fab")
		)
		(fp_line
			(start -0.120396 0.3048)
			(end -0.120396 0.2794)
			(stroke
				(width 0.1)
				(type default)
			)
			(layer "B.Fab")
		)
		(fp_line
			(start -0.67945 0.3048)
			(end -0.120396 0.3048)
			(stroke
				(width 0.1)
				(type default)
			)
			(layer "B.Fab")
		)
		(pad "1" smd circle
			(at 0.40005 0 270)
			(size 0 0)
			(layers "B.Cu" "B.Mask" "B.Paste")
			(net "P3V3_AUX")
		)
		(pad "2" smd circle
			(at -0.40005 0 270)
			(size 0 0)
			(layers "B.Cu" "B.Mask" "B.Paste")
			(net "RST_GPU_PERST_1_BUF_N")
		)
	)
	(footprint ""
		(layer "B.Cu")
		(at 387.35 -227.203 90)
		(property "Reference" "R927"
			(at 0 0 90)
			(layer "B.SilkS")
			(hide yes)
			(effects
				(font
					(size 1.27 1.27)
				)
				(justify mirror)
			)
		)
		(property "Value" ""
			(at 0 0 90)
			(layer "B.Fab")
			(effects
				(font
					(size 1.27 1.27)
				)
				(justify mirror)
			)
		)
		(duplicate_pad_numbers_are_jumpers no)
		(fp_line
			(start 0.7874 -0.4064)
			(end -0.7874 -0.4064)
			(stroke
				(width 0.1524)
				(type default)
			)
			(layer "B.SilkS")
		)
		(fp_line
			(start -0.7874 -0.4064)
			(end -0.7874 0.4064)
			(stroke
				(width 0.1524)
				(type default)
			)
			(layer "B.SilkS")
		)
		(fp_line
			(start 0.7874 0.4064)
			(end 0.7874 -0.4064)
			(stroke
				(width 0.1524)
				(type default)
			)
			(layer "B.SilkS")
		)
		(fp_line
			(start -0.7874 0.4064)
			(end 0.7874 0.4064)
			(stroke
				(width 0.1524)
				(type default)
			)
			(layer "B.SilkS")
		)
		(fp_line
			(start 0.67945 -0.305054)
			(end 0.12065 -0.305054)
			(stroke
				(width 0.1)
				(type default)
			)
			(layer "B.Fab")
		)
		(fp_line
			(start 0.12065 -0.305054)
			(end 0.12065 -0.2794)
			(stroke
				(width 0.1)
				(type default)
			)
			(layer "B.Fab")
		)
		(fp_line
			(start -0.12065 -0.3048)
			(end -0.67945 -0.3048)
			(stroke
				(width 0.1)
				(type default)
			)
			(layer "B.Fab")
		)
		(fp_line
			(start -0.67945 -0.3048)
			(end -0.67945 0.3048)
			(stroke
				(width 0.1)
				(type default)
			)
			(layer "B.Fab")
		)
		(fp_line
			(start 0.12065 -0.2794)
			(end -0.12065 -0.2794)
			(stroke
				(width 0.1)
				(type default)
			)
			(layer "B.Fab")
		)
		(fp_line
			(start -0.12065 -0.2794)
			(end -0.12065 -0.3048)
			(stroke
				(width 0.1)
				(type default)
			)
			(layer "B.Fab")
		)
		(fp_line
			(start 0.12065 0.2794)
			(end 0.12065 0.3048)
			(stroke
				(width 0.1)
				(type default)
			)
			(layer "B.Fab")
		)
		(fp_line
			(start -0.120396 0.2794)
			(end 0.12065 0.2794)
			(stroke
				(width 0.1)
				(type default)
			)
			(layer "B.Fab")
		)
		(fp_line
			(start 0.67945 0.3048)
			(end 0.67945 -0.305054)
			(stroke
				(width 0.1)
				(type default)
			)
			(layer "B.Fab")
		)
		(fp_line
			(start 0.12065 0.3048)
			(end 0.67945 0.3048)
			(stroke
				(width 0.1)
				(type default)
			)
			(layer "B.Fab")
		)
		(fp_line
			(start -0.120396 0.3048)
			(end -0.120396 0.2794)
			(stroke
				(width 0.1)
				(type default)
			)
			(layer "B.Fab")
		)
		(fp_line
			(start -0.67945 0.3048)
			(end -0.120396 0.3048)
			(stroke
				(width 0.1)
				(type default)
			)
			(layer "B.Fab")
		)
		(pad "1" smd circle
			(at 0.40005 0 270)
			(size 0 0)
			(layers "B.Cu" "B.Mask" "B.Paste")
			(net "UART_PEX0_SDB_RX")
		)
		(pad "2" smd circle
			(at -0.40005 0 270)
			(size 0 0)
			(layers "B.Cu" "B.Mask" "B.Paste")
			(net "UART_PEX0_SDB_R_RX")
		)
	)
	(footprint ""
		(layer "B.Cu")
		(at 346.093288 -221.986856 -90)
		(property "Reference" "C2043"
			(at 0 0 90)
			(layer "B.SilkS")
			(hide yes)
			(effects
				(font
					(size 1.27 1.27)
				)
				(justify mirror)
			)
		)
		(property "Value" ""
			(at 0 0 90)
			(layer "B.Fab")
			(effects
				(font
					(size 1.27 1.27)
				)
				(justify mirror)
			)
		)
		(duplicate_pad_numbers_are_jumpers no)
		(fp_line
			(start -0.69215 0.2921)
			(end 0.69215 0.2921)
			(stroke
				(width 0.1524)
				(type default)
			)
			(layer "B.SilkS")
		)
		(fp_line
			(start 0.69215 0.2921)
			(end 0.69215 -0.2921)
			(stroke
				(width 0.1524)
				(type default)
			)
			(layer "B.SilkS")
		)
		(fp_line
			(start -0.69215 -0.2921)
			(end -0.69215 0.2921)
			(stroke
				(width 0.1524)
				(type default)
			)
			(layer "B.SilkS")
		)
		(fp_line
			(start 0.69215 -0.2921)
			(end -0.69215 -0.2921)
			(stroke
				(width 0.1524)
				(type default)
			)
			(layer "B.SilkS")
		)
		(fp_line
			(start -0.51435 0.2794)
			(end 0.51435 0.2794)
			(stroke
				(width 0.1)
				(type default)
			)
			(layer "B.Fab")
		)
		(fp_line
			(start 0.51435 0.2794)
			(end 0.51435 -0.2794)
			(stroke
				(width 0.1)
				(type default)
			)
			(layer "B.Fab")
		)
		(fp_line
			(start -0.51435 -0.2794)
			(end -0.51435 0.2794)
			(stroke
				(width 0.1)
				(type default)
			)
			(layer "B.Fab")
		)
		(fp_line
			(start 0.51435 -0.2794)
			(end -0.51435 -0.2794)
			(stroke
				(width 0.1)
				(type default)
			)
			(layer "B.Fab")
		)
		(pad "1" smd circle
			(at 0.40005 0 90)
			(size 0 0)
			(layers "B.Cu" "B.Mask" "B.Paste")
			(net "P3V3_FPGA_VCCIO1")
		)
		(pad "2" smd circle
			(at -0.40005 0 90)
			(size 0 0)
			(layers "B.Cu" "B.Mask" "B.Paste")
			(net "GND")
		)
		(zone
			(layer "B.Cu")
			(hatch none 0.5)
			(connect_pads
				(clearance 0)
			)
			(min_thickness 0.25)
			(keepout
				(tracks not_allowed)
				(vias allowed)
				(pads allowed)
				(copperpour not_allowed)
				(footprints allowed)
			)
			(placement
				(enabled no)
				(sheetname "")
			)
			(fill
				(thermal_gap 0.5)
				(thermal_bridge_width 0.5)
				(island_removal_mode 0)
			)
			(polygon
				(pts
					(xy 346.005658 -221.796356) (xy 345.947492 -221.887796) (xy 345.947492 -222.087186) (xy 346.005658 -222.177356)
					(xy 346.180918 -222.177356) (xy 346.239338 -222.087186) (xy 346.239338 -221.887796) (xy 346.181172 -221.796356)
				)
			)
		)
	)
	(footprint ""
		(layer "B.Cu")
		(at 237.62843 -349.473012 180)
		(property "Reference" "PR7149"
			(at 0 0 0)
			(layer "B.SilkS")
			(hide yes)
			(effects
				(font
					(size 1.27 1.27)
				)
				(justify mirror)
			)
		)
		(property "Value" ""
			(at 0 0 0)
			(layer "B.Fab")
			(effects
				(font
					(size 1.27 1.27)
				)
				(justify mirror)
			)
		)
		(duplicate_pad_numbers_are_jumpers no)
		(fp_line
			(start 0.7874 0.4064)
			(end 0.7874 -0.4064)
			(stroke
				(width 0.1524)
				(type default)
			)
			(layer "B.SilkS")
		)
		(fp_line
			(start 0.7874 -0.4064)
			(end -0.7874 -0.4064)
			(stroke
				(width 0.1524)
				(type default)
			)
			(layer "B.SilkS")
		)
		(fp_line
			(start -0.7874 0.4064)
			(end 0.7874 0.4064)
			(stroke
				(width 0.1524)
				(type default)
			)
			(layer "B.SilkS")
		)
		(fp_line
			(start -0.7874 -0.4064)
			(end -0.7874 0.4064)
			(stroke
				(width 0.1524)
				(type default)
			)
			(layer "B.SilkS")
		)
		(fp_line
			(start 0.67945 0.3048)
			(end 0.67945 -0.305054)
			(stroke
				(width 0.1)
				(type default)
			)
			(layer "B.Fab")
		)
		(fp_line
			(start 0.67945 -0.305054)
			(end 0.12065 -0.305054)
			(stroke
				(width 0.1)
				(type default)
			)
			(layer "B.Fab")
		)
		(fp_line
			(start 0.12065 0.3048)
			(end 0.67945 0.3048)
			(stroke
				(width 0.1)
				(type default)
			)
			(layer "B.Fab")
		)
		(fp_line
			(start 0.12065 0.2794)
			(end 0.12065 0.3048)
			(stroke
				(width 0.1)
				(type default)
			)
			(layer "B.Fab")
		)
		(fp_line
			(start 0.12065 -0.2794)
			(end -0.12065 -0.2794)
			(stroke
				(width 0.1)
				(type default)
			)
			(layer "B.Fab")
		)
		(fp_line
			(start 0.12065 -0.305054)
			(end 0.12065 -0.2794)
			(stroke
				(width 0.1)
				(type default)
			)
			(layer "B.Fab")
		)
		(fp_line
			(start -0.120396 0.3048)
			(end -0.120396 0.2794)
			(stroke
				(width 0.1)
				(type default)
			)
			(layer "B.Fab")
		)
		(fp_line
			(start -0.120396 0.2794)
			(end 0.12065 0.2794)
			(stroke
				(width 0.1)
				(type default)
			)
			(layer "B.Fab")
		)
		(fp_line
			(start -0.12065 -0.2794)
			(end -0.12065 -0.3048)
			(stroke
				(width 0.1)
				(type default)
			)
			(layer "B.Fab")
		)
		(fp_line
			(start -0.12065 -0.3048)
			(end -0.67945 -0.3048)
			(stroke
				(width 0.1)
				(type default)
			)
			(layer "B.Fab")
		)
		(fp_line
			(start -0.67945 0.3048)
			(end -0.120396 0.3048)
			(stroke
				(width 0.1)
				(type default)
			)
			(layer "B.Fab")
		)
		(fp_line
			(start -0.67945 -0.3048)
			(end -0.67945 0.3048)
			(stroke
				(width 0.1)
				(type default)
			)
			(layer "B.Fab")
		)
		(pad "1" smd circle
			(at 0.40005 0)
			(size 0 0)
			(layers "B.Cu" "B.Mask" "B.Paste")
			(net "P12V_HSC_ADC_N")
		)
		(pad "2" smd circle
			(at -0.40005 0)
			(size 0 0)
			(layers "B.Cu" "B.Mask" "B.Paste")
			(net "P12V_HSC_SENSE1_N")
		)
	)
	(footprint ""
		(layer "B.Cu")
		(at 314.119768 10.649712)
		(property "Reference" "DE16T_4"
			(at 2.796032 3.067558 0)
			(unlocked yes)
			(layer "B.SilkS")
			(effects
				(font
					(size 0.7874 0.5842)
					(thickness 0.1524)
				)
				(justify left mirror)
			)
		)
		(property "Value" ""
			(at 0 0 0)
			(layer "B.Fab")
			(effects
				(font
					(size 1.27 1.27)
				)
				(justify mirror)
			)
		)
		(duplicate_pad_numbers_are_jumpers no)
		(fp_line
			(start -1.2192 -2.1082)
			(end -1.2192 2.1082)
			(stroke
				(width 0.1524)
				(type default)
			)
			(layer "B.SilkS")
		)
		(fp_line
			(start -1.2192 2.1082)
			(end 1.2192 2.1082)
			(stroke
				(width 0.1524)
				(type default)
			)
			(layer "B.SilkS")
		)
		(fp_line
			(start 1.2192 -2.1082)
			(end -1.2192 -2.1082)
			(stroke
				(width 0.1524)
				(type default)
			)
			(layer "B.SilkS")
		)
		(fp_line
			(start 1.2192 2.1082)
			(end 1.2192 -2.1082)
			(stroke
				(width 0.1524)
				(type default)
			)
			(layer "B.SilkS")
		)
		(pad "" np_thru_hole circle
			(at -3.4671 -1.27 270)
			(size 1.0414 1.0414)
			(drill 1.0414)
			(layers "*.Cu" "*.Mask")
			(clearance 0.381)
			(thermal_gap 0.381)
		)
		(pad "" np_thru_hole circle
			(at -3.4671 1.27 270)
			(size 1.0414 1.0414)
			(drill 1.0414)
			(layers "*.Cu" "*.Mask")
			(clearance 0.381)
			(thermal_gap 0.381)
		)
		(pad "" np_thru_hole circle
			(at 2.8829 -1.27 270)
			(size 1.0414 1.0414)
			(drill 1.0414)
			(layers "*.Cu" "*.Mask")
			(clearance 0.381)
			(thermal_gap 0.381)
		)
		(pad "" np_thru_hole circle
			(at 2.8829 1.27 270)
			(size 1.0414 1.0414)
			(drill 1.0414)
			(layers "*.Cu" "*.Mask")
			(clearance 0.381)
			(thermal_gap 0.381)
		)
		(pad "1" smd rect
			(at -0.8255 -0.249936 270)
			(size 0.3048 0.508)
			(layers "B.Cu" "B.Mask" "B.Paste")
			(net "85_10INCH_IN6_DN")
		)
		(pad "2" smd rect
			(at -0.8255 0.249936 270)
			(size 0.3048 0.508)
			(layers "B.Cu" "B.Mask" "B.Paste")
			(net "85_10INCH_IN6_DP")
		)
		(pad "3" smd circle
			(at 0 0 180)
			(size 0 0)
			(layers "B.Cu" "B.Mask" "B.Paste")
			(net "COUPON_GND2")
		)
		(zone
			(layers "F.Cu" "B.Cu" "In1.Cu" "In2.Cu" "In3.Cu" "In4.Cu" "In5.Cu" "In6.Cu"
				"In7.Cu" "In8.Cu" "In9.Cu" "In10.Cu" "In11.Cu" "In12.Cu" "In13.Cu" "In14.Cu"
				"In15.Cu" "In16.Cu"
			)
			(hatch none 0.5)
			(connect_pads
				(clearance 0)
			)
			(min_thickness 0.25)
			(keepout
				(tracks not_allowed)
				(vias allowed)
				(pads allowed)
				(copperpour not_allowed)
				(footprints allowed)
			)
			(placement
				(enabled no)
				(sheetname "")
			)
			(fill
				(thermal_gap 0.5)
				(thermal_bridge_width 0.5)
				(island_removal_mode 0)
			)
			(polygon
				(pts
					(arc
						(start 311.579768 9.379712)
						(mid 309.725568 9.379712)
						(end 311.579768 9.379712)
					)
				)
			)
		)
		(zone
			(layers "F.Cu" "B.Cu" "In1.Cu" "In2.Cu" "In3.Cu" "In4.Cu" "In5.Cu" "In6.Cu"
				"In7.Cu" "In8.Cu" "In9.Cu" "In10.Cu" "In11.Cu" "In12.Cu" "In13.Cu" "In14.Cu"
				"In15.Cu" "In16.Cu"
			)
			(hatch none 0.5)
			(connect_pads
				(clearance 0)
			)
			(min_thickness 0.25)
			(keepout
				(tracks not_allowed)
				(vias allowed)
				(pads allowed)
				(copperpour not_allowed)
				(footprints allowed)
			)
			(placement
				(enabled no)
				(sheetname "")
			)
			(fill
				(thermal_gap 0.5)
				(thermal_bridge_width 0.5)
				(island_removal_mode 0)
			)
			(polygon
				(pts
					(arc
						(start 311.579768 11.919712)
						(mid 309.725568 11.919712)
						(end 311.579768 11.919712)
					)
				)
			)
		)
		(zone
			(layers "F.Cu" "B.Cu" "In1.Cu" "In2.Cu" "In3.Cu" "In4.Cu" "In5.Cu" "In6.Cu"
				"In7.Cu" "In8.Cu" "In9.Cu" "In10.Cu" "In11.Cu" "In12.Cu" "In13.Cu" "In14.Cu"
				"In15.Cu" "In16.Cu"
			)
			(hatch none 0.5)
			(connect_pads
				(clearance 0)
			)
			(min_thickness 0.25)
			(keepout
				(tracks not_allowed)
				(vias allowed)
				(pads allowed)
				(copperpour not_allowed)
				(footprints allowed)
			)
			(placement
				(enabled no)
				(sheetname "")
			)
			(fill
				(thermal_gap 0.5)
				(thermal_bridge_width 0.5)
				(island_removal_mode 0)
			)
			(polygon
				(pts
					(arc
						(start 317.929768 9.379712)
						(mid 316.075568 9.379712)
						(end 317.929768 9.379712)
					)
				)
			)
		)
		(zone
			(layers "F.Cu" "B.Cu" "In1.Cu" "In2.Cu" "In3.Cu" "In4.Cu" "In5.Cu" "In6.Cu"
				"In7.Cu" "In8.Cu" "In9.Cu" "In10.Cu" "In11.Cu" "In12.Cu" "In13.Cu" "In14.Cu"
				"In15.Cu" "In16.Cu"
			)
			(hatch none 0.5)
			(connect_pads
				(clearance 0)
			)
			(min_thickness 0.25)
			(keepout
				(tracks not_allowed)
				(vias allowed)
				(pads allowed)
				(copperpour not_allowed)
				(footprints allowed)
			)
			(placement
				(enabled no)
				(sheetname "")
			)
			(fill
				(thermal_gap 0.5)
				(thermal_bridge_width 0.5)
				(island_removal_mode 0)
			)
			(polygon
				(pts
					(arc
						(start 317.929768 11.919712)
						(mid 316.075568 11.919712)
						(end 317.929768 11.919712)
					)
				)
			)
		)
		(zone
			(layer "B.Cu")
			(hatch none 0.5)
			(connect_pads
				(clearance 0)
			)
			(min_thickness 0.25)
			(keepout
				(tracks not_allowed)
				(vias allowed)
				(pads allowed)
				(copperpour not_allowed)
				(footprints allowed)
			)
			(placement
				(enabled no)
				(sheetname "")
			)
			(fill
				(thermal_gap 0.5)
				(thermal_bridge_width 0.5)
				(island_removal_mode 0)
			)
			(polygon
				(pts
					(xy 313.002168 10.101072) (xy 313.002168 10.196576) (xy 313.599068 10.196576) (xy 313.599068 10.602976)
					(xy 313.002168 10.602976) (xy 313.002168 10.696448) (xy 313.599068 10.696448) (xy 313.599068 11.102848)
					(xy 313.002168 11.102848) (xy 313.002168 11.198352) (xy 313.700668 11.198352) (xy 313.700668 10.101072)
				)
			)
		)
	)
	(footprint ""
		(layer "B.Cu")
		(at 175.260762 -305.557936 -90)
		(property "Reference" "C3119"
			(at 0 0 90)
			(layer "B.SilkS")
			(hide yes)
			(effects
				(font
					(size 1.27 1.27)
				)
				(justify mirror)
			)
		)
		(property "Value" ""
			(at 0 0 90)
			(layer "B.Fab")
			(effects
				(font
					(size 1.27 1.27)
				)
				(justify mirror)
			)
		)
		(duplicate_pad_numbers_are_jumpers no)
		(fp_line
			(start -1.2954 0.5842)
			(end 1.2954 0.5842)
			(stroke
				(width 0.1524)
				(type default)
			)
			(layer "B.SilkS")
		)
		(fp_line
			(start 1.2954 0.5842)
			(end 1.2954 -0.5842)
			(stroke
				(width 0.1524)
				(type default)
			)
			(layer "B.SilkS")
		)
		(fp_line
			(start -1.2954 -0.5842)
			(end -1.2954 0.5842)
			(stroke
				(width 0.1524)
				(type default)
			)
			(layer "B.SilkS")
		)
		(fp_line
			(start 1.2954 -0.5842)
			(end -1.2954 -0.5842)
			(stroke
				(width 0.1524)
				(type default)
			)
			(layer "B.SilkS")
		)
		(fp_line
			(start -0.8636 0.4572)
			(end 0.8636 0.4572)
			(stroke
				(width 0.1)
				(type default)
			)
			(layer "B.Fab")
		)
		(fp_line
			(start 0.8636 0.4572)
			(end 0.8636 0.4064)
			(stroke
				(width 0.1)
				(type default)
			)
			(layer "B.Fab")
		)
		(fp_line
			(start -1.1938 0.4064)
			(end -0.8636 0.4064)
			(stroke
				(width 0.1)
				(type default)
			)
			(layer "B.Fab")
		)
		(fp_line
			(start -0.8636 0.4064)
			(end -0.8636 0.4572)
			(stroke
				(width 0.1)
				(type default)
			)
			(layer "B.Fab")
		)
		(fp_line
			(start 0.8636 0.4064)
			(end 1.1938 0.4064)
			(stroke
				(width 0.1)
				(type default)
			)
			(layer "B.Fab")
		)
		(fp_line
			(start 1.1938 0.4064)
			(end 1.1938 -0.4064)
			(stroke
				(width 0.1)
				(type default)
			)
			(layer "B.Fab")
		)
		(fp_line
			(start -1.1938 -0.4064)
			(end -1.1938 0.4064)
			(stroke
				(width 0.1)
				(type default)
			)
			(layer "B.Fab")
		)
		(fp_line
			(start -0.8636 -0.4064)
			(end -1.1938 -0.4064)
			(stroke
				(width 0.1)
				(type default)
			)
			(layer "B.Fab")
		)
		(fp_line
			(start 0.8636 -0.4064)
			(end 0.8636 -0.4572)
			(stroke
				(width 0.1)
				(type default)
			)
			(layer "B.Fab")
		)
		(fp_line
			(start 1.1938 -0.4064)
			(end 0.8636 -0.4064)
			(stroke
				(width 0.1)
				(type default)
			)
			(layer "B.Fab")
		)
		(fp_line
			(start -0.8636 -0.4572)
			(end -0.8636 -0.4064)
			(stroke
				(width 0.1)
				(type default)
			)
			(layer "B.Fab")
		)
		(fp_line
			(start 0.8636 -0.4572)
			(end -0.8636 -0.4572)
			(stroke
				(width 0.1)
				(type default)
			)
			(layer "B.Fab")
		)
		(pad "1" smd rect
			(at 0.7366 0 180)
			(size 0.7112 0.8128)
			(layers "B.Cu" "B.Mask" "B.Paste")
			(net "P1V25_SERDES_VDDPLL_PEX1")
		)
		(pad "2" smd rect
			(at -0.7366 0 180)
			(size 0.7112 0.8128)
			(layers "B.Cu" "B.Mask" "B.Paste")
			(net "GND")
		)
	)
	(footprint ""
		(layer "B.Cu")
		(at 387.999986 -288.774886 -90)
		(property "Reference" "R3490"
			(at 0 0 90)
			(layer "B.SilkS")
			(hide yes)
			(effects
				(font
					(size 1.27 1.27)
				)
				(justify mirror)
			)
		)
		(property "Value" ""
			(at 0 0 90)
			(layer "B.Fab")
			(effects
				(font
					(size 1.27 1.27)
				)
				(justify mirror)
			)
		)
		(duplicate_pad_numbers_are_jumpers no)
		(fp_line
			(start -0.7874 0.4064)
			(end 0.7874 0.4064)
			(stroke
				(width 0.1524)
				(type default)
			)
			(layer "B.SilkS")
		)
		(fp_line
			(start 0.7874 0.4064)
			(end 0.7874 -0.4064)
			(stroke
				(width 0.1524)
				(type default)
			)
			(layer "B.SilkS")
		)
		(fp_line
			(start -0.7874 -0.4064)
			(end -0.7874 0.4064)
			(stroke
				(width 0.1524)
				(type default)
			)
			(layer "B.SilkS")
		)
		(fp_line
			(start 0.7874 -0.4064)
			(end -0.7874 -0.4064)
			(stroke
				(width 0.1524)
				(type default)
			)
			(layer "B.SilkS")
		)
		(fp_line
			(start -0.67945 0.3048)
			(end -0.120396 0.3048)
			(stroke
				(width 0.1)
				(type default)
			)
			(layer "B.Fab")
		)
		(fp_line
			(start -0.120396 0.3048)
			(end -0.120396 0.2794)
			(stroke
				(width 0.1)
				(type default)
			)
			(layer "B.Fab")
		)
		(fp_line
			(start 0.12065 0.3048)
			(end 0.67945 0.3048)
			(stroke
				(width 0.1)
				(type default)
			)
			(layer "B.Fab")
		)
		(fp_line
			(start 0.67945 0.3048)
			(end 0.67945 -0.305054)
			(stroke
				(width 0.1)
				(type default)
			)
			(layer "B.Fab")
		)
		(fp_line
			(start -0.120396 0.2794)
			(end 0.12065 0.2794)
			(stroke
				(width 0.1)
				(type default)
			)
			(layer "B.Fab")
		)
		(fp_line
			(start 0.12065 0.2794)
			(end 0.12065 0.3048)
			(stroke
				(width 0.1)
				(type default)
			)
			(layer "B.Fab")
		)
		(fp_line
			(start -0.12065 -0.2794)
			(end -0.12065 -0.3048)
			(stroke
				(width 0.1)
				(type default)
			)
			(layer "B.Fab")
		)
		(fp_line
			(start 0.12065 -0.2794)
			(end -0.12065 -0.2794)
			(stroke
				(width 0.1)
				(type default)
			)
			(layer "B.Fab")
		)
		(fp_line
			(start -0.67945 -0.3048)
			(end -0.67945 0.3048)
			(stroke
				(width 0.1)
				(type default)
			)
			(layer "B.Fab")
		)
		(fp_line
			(start -0.12065 -0.3048)
			(end -0.67945 -0.3048)
			(stroke
				(width 0.1)
				(type default)
			)
			(layer "B.Fab")
		)
		(fp_line
			(start 0.12065 -0.305054)
			(end 0.12065 -0.2794)
			(stroke
				(width 0.1)
				(type default)
			)
			(layer "B.Fab")
		)
		(fp_line
			(start 0.67945 -0.305054)
			(end 0.12065 -0.305054)
			(stroke
				(width 0.1)
				(type default)
			)
			(layer "B.Fab")
		)
		(pad "1" smd circle
			(at 0.40005 0 90)
			(size 0 0)
			(layers "B.Cu" "B.Mask" "B.Paste")
			(net "SPI_PEX3_SDIO3_R")
		)
		(pad "2" smd circle
			(at -0.40005 0 90)
			(size 0 0)
			(layers "B.Cu" "B.Mask" "B.Paste")
			(net "SPI_PEX3_SDIO3")
		)
	)
	(footprint ""
		(layer "B.Cu")
		(at 56.324754 -286.399732 90)
		(property "Reference" "C2957"
			(at 0 0 90)
			(layer "B.SilkS")
			(hide yes)
			(effects
				(font
					(size 1.27 1.27)
				)
				(justify mirror)
			)
		)
		(property "Value" ""
			(at 0 0 90)
			(layer "B.Fab")
			(effects
				(font
					(size 1.27 1.27)
				)
				(justify mirror)
			)
		)
		(duplicate_pad_numbers_are_jumpers no)
		(fp_line
			(start 0.299974 -0.150114)
			(end -0.299974 -0.150114)
			(stroke
				(width 0.1)
				(type default)
			)
			(layer "B.Fab")
		)
		(fp_line
			(start -0.299974 -0.150114)
			(end -0.299974 0.150114)
			(stroke
				(width 0.1)
				(type default)
			)
			(layer "B.Fab")
		)
		(fp_line
			(start 0.299974 0.150114)
			(end 0.299974 -0.150114)
			(stroke
				(width 0.1)
				(type default)
			)
			(layer "B.Fab")
		)
		(fp_line
			(start -0.299974 0.150114)
			(end 0.299974 0.150114)
			(stroke
				(width 0.1)
				(type default)
			)
			(layer "B.Fab")
		)
		(pad "1" smd rect
			(at 0.2667 0 270)
			(size 0.3048 0.381)
			(layers "B.Cu" "B.Mask" "B.Paste")
			(net "P1V25_SERDES_VDDPLL_PEX0")
		)
		(pad "2" smd rect
			(at -0.2667 0 270)
			(size 0.3048 0.381)
			(layers "B.Cu" "B.Mask" "B.Paste")
			(net "GND")
		)
	)
	(footprint ""
		(layer "B.Cu")
		(at 69.149976 -300.174914 180)
		(property "Reference" "C3013"
			(at 0 0 0)
			(layer "B.SilkS")
			(hide yes)
			(effects
				(font
					(size 1.27 1.27)
				)
				(justify mirror)
			)
		)
		(property "Value" ""
			(at 0 0 0)
			(layer "B.Fab")
			(effects
				(font
					(size 1.27 1.27)
				)
				(justify mirror)
			)
		)
		(duplicate_pad_numbers_are_jumpers no)
		(fp_line
			(start 0.299974 0.150114)
			(end 0.299974 -0.150114)
			(stroke
				(width 0.1)
				(type default)
			)
			(layer "B.Fab")
		)
		(fp_line
			(start 0.299974 -0.150114)
			(end -0.299974 -0.150114)
			(stroke
				(width 0.1)
				(type default)
			)
			(layer "B.Fab")
		)
		(fp_line
			(start -0.299974 0.150114)
			(end 0.299974 0.150114)
			(stroke
				(width 0.1)
				(type default)
			)
			(layer "B.Fab")
		)
		(fp_line
			(start -0.299974 -0.150114)
			(end -0.299974 0.150114)
			(stroke
				(width 0.1)
				(type default)
			)
			(layer "B.Fab")
		)
		(pad "1" smd rect
			(at 0.2667 0)
			(size 0.3048 0.381)
			(layers "B.Cu" "B.Mask" "B.Paste")
			(net "P1V8_VDDA_PEX0")
		)
		(pad "2" smd rect
			(at -0.2667 0)
			(size 0.3048 0.381)
			(layers "B.Cu" "B.Mask" "B.Paste")
			(net "GND")
		)
	)
	(footprint ""
		(layer "B.Cu")
		(at 341.905082 -285.559754 -90)
		(property "Reference" "PR7179"
			(at 0 0 90)
			(layer "B.SilkS")
			(hide yes)
			(effects
				(font
					(size 1.27 1.27)
				)
				(justify mirror)
			)
		)
		(property "Value" ""
			(at 0 0 90)
			(layer "B.Fab")
			(effects
				(font
					(size 1.27 1.27)
				)
				(justify mirror)
			)
		)
		(duplicate_pad_numbers_are_jumpers no)
		(fp_line
			(start -0.7874 0.4064)
			(end 0.7874 0.4064)
			(stroke
				(width 0.1524)
				(type default)
			)
			(layer "B.SilkS")
		)
		(fp_line
			(start 0.7874 0.4064)
			(end 0.7874 -0.4064)
			(stroke
				(width 0.1524)
				(type default)
			)
			(layer "B.SilkS")
		)
		(fp_line
			(start -0.7874 -0.4064)
			(end -0.7874 0.4064)
			(stroke
				(width 0.1524)
				(type default)
			)
			(layer "B.SilkS")
		)
		(fp_line
			(start 0.7874 -0.4064)
			(end -0.7874 -0.4064)
			(stroke
				(width 0.1524)
				(type default)
			)
			(layer "B.SilkS")
		)
		(fp_line
			(start -0.67945 0.3048)
			(end -0.120396 0.3048)
			(stroke
				(width 0.1)
				(type default)
			)
			(layer "B.Fab")
		)
		(fp_line
			(start -0.120396 0.3048)
			(end -0.120396 0.2794)
			(stroke
				(width 0.1)
				(type default)
			)
			(layer "B.Fab")
		)
		(fp_line
			(start 0.12065 0.3048)
			(end 0.67945 0.3048)
			(stroke
				(width 0.1)
				(type default)
			)
			(layer "B.Fab")
		)
		(fp_line
			(start 0.67945 0.3048)
			(end 0.67945 -0.305054)
			(stroke
				(width 0.1)
				(type default)
			)
			(layer "B.Fab")
		)
		(fp_line
			(start -0.120396 0.2794)
			(end 0.12065 0.2794)
			(stroke
				(width 0.1)
				(type default)
			)
			(layer "B.Fab")
		)
		(fp_line
			(start 0.12065 0.2794)
			(end 0.12065 0.3048)
			(stroke
				(width 0.1)
				(type default)
			)
			(layer "B.Fab")
		)
		(fp_line
			(start -0.12065 -0.2794)
			(end -0.12065 -0.3048)
			(stroke
				(width 0.1)
				(type default)
			)
			(layer "B.Fab")
		)
		(fp_line
			(start 0.12065 -0.2794)
			(end -0.12065 -0.2794)
			(stroke
				(width 0.1)
				(type default)
			)
			(layer "B.Fab")
		)
		(fp_line
			(start -0.67945 -0.3048)
			(end -0.67945 0.3048)
			(stroke
				(width 0.1)
				(type default)
			)
			(layer "B.Fab")
		)
		(fp_line
			(start -0.12065 -0.3048)
			(end -0.67945 -0.3048)
			(stroke
				(width 0.1)
				(type default)
			)
			(layer "B.Fab")
		)
		(fp_line
			(start 0.12065 -0.305054)
			(end 0.12065 -0.2794)
			(stroke
				(width 0.1)
				(type default)
			)
			(layer "B.Fab")
		)
		(fp_line
			(start 0.67945 -0.305054)
			(end 0.12065 -0.305054)
			(stroke
				(width 0.1)
				(type default)
			)
			(layer "B.Fab")
		)
		(pad "1" smd circle
			(at 0.40005 0 90)
			(size 0 0)
			(layers "B.Cu" "B.Mask" "B.Paste")
			(net "P0V8_PEX2_PVCC")
		)
		(pad "2" smd circle
			(at -0.40005 0 90)
			(size 0 0)
			(layers "B.Cu" "B.Mask" "B.Paste")
			(net "P3V3_AUX")
		)
	)
	(footprint ""
		(layer "B.Cu")
		(at 126.179072 -308.580028 90)
		(property "Reference" "C4261"
			(at 0 0 90)
			(layer "B.SilkS")
			(hide yes)
			(effects
				(font
					(size 1.27 1.27)
				)
				(justify mirror)
			)
		)
		(property "Value" ""
			(at 0 0 90)
			(layer "B.Fab")
			(effects
				(font
					(size 1.27 1.27)
				)
				(justify mirror)
			)
		)
		(duplicate_pad_numbers_are_jumpers no)
		(fp_line
			(start 1.2954 -0.5842)
			(end -1.2954 -0.5842)
			(stroke
				(width 0.1524)
				(type default)
			)
			(layer "B.SilkS")
		)
		(fp_line
			(start -1.2954 -0.5842)
			(end -1.2954 0.5842)
			(stroke
				(width 0.1524)
				(type default)
			)
			(layer "B.SilkS")
		)
		(fp_line
			(start 1.2954 0.5842)
			(end 1.2954 -0.5842)
			(stroke
				(width 0.1524)
				(type default)
			)
			(layer "B.SilkS")
		)
		(fp_line
			(start -1.2954 0.5842)
			(end 1.2954 0.5842)
			(stroke
				(width 0.1524)
				(type default)
			)
			(layer "B.SilkS")
		)
		(fp_line
			(start 0.8636 -0.4572)
			(end -0.8636 -0.4572)
			(stroke
				(width 0.1)
				(type default)
			)
			(layer "B.Fab")
		)
		(fp_line
			(start -0.8636 -0.4572)
			(end -0.8636 -0.4064)
			(stroke
				(width 0.1)
				(type default)
			)
			(layer "B.Fab")
		)
		(fp_line
			(start 1.1938 -0.4064)
			(end 0.8636 -0.4064)
			(stroke
				(width 0.1)
				(type default)
			)
			(layer "B.Fab")
		)
		(fp_line
			(start 0.8636 -0.4064)
			(end 0.8636 -0.4572)
			(stroke
				(width 0.1)
				(type default)
			)
			(layer "B.Fab")
		)
		(fp_line
			(start -0.8636 -0.4064)
			(end -1.1938 -0.4064)
			(stroke
				(width 0.1)
				(type default)
			)
			(layer "B.Fab")
		)
		(fp_line
			(start -1.1938 -0.4064)
			(end -1.1938 0.4064)
			(stroke
				(width 0.1)
				(type default)
			)
			(layer "B.Fab")
		)
		(fp_line
			(start 1.1938 0.4064)
			(end 1.1938 -0.4064)
			(stroke
				(width 0.1)
				(type default)
			)
			(layer "B.Fab")
		)
		(fp_line
			(start 0.8636 0.4064)
			(end 1.1938 0.4064)
			(stroke
				(width 0.1)
				(type default)
			)
			(layer "B.Fab")
		)
		(fp_line
			(start -0.8636 0.4064)
			(end -0.8636 0.4572)
			(stroke
				(width 0.1)
				(type default)
			)
			(layer "B.Fab")
		)
		(fp_line
			(start -1.1938 0.4064)
			(end -0.8636 0.4064)
			(stroke
				(width 0.1)
				(type default)
			)
			(layer "B.Fab")
		)
		(fp_line
			(start 0.8636 0.4572)
			(end 0.8636 0.4064)
			(stroke
				(width 0.1)
				(type default)
			)
			(layer "B.Fab")
		)
		(fp_line
			(start -0.8636 0.4572)
			(end 0.8636 0.4572)
			(stroke
				(width 0.1)
				(type default)
			)
			(layer "B.Fab")
		)
		(pad "1" smd rect
			(at 0.7366 0)
			(size 0.7112 0.8128)
			(layers "B.Cu" "B.Mask" "B.Paste")
			(net "P0V8_PEX1")
		)
		(pad "2" smd rect
			(at -0.7366 0)
			(size 0.7112 0.8128)
			(layers "B.Cu" "B.Mask" "B.Paste")
			(net "GND")
		)
	)
	(footprint ""
		(layer "B.Cu")
		(at 44.449746 -295.89984)
		(property "Reference" "C3000"
			(at 0 0 0)
			(layer "B.SilkS")
			(hide yes)
			(effects
				(font
					(size 1.27 1.27)
				)
				(justify mirror)
			)
		)
		(property "Value" ""
			(at 0 0 0)
			(layer "B.Fab")
			(effects
				(font
					(size 1.27 1.27)
				)
				(justify mirror)
			)
		)
		(duplicate_pad_numbers_are_jumpers no)
		(fp_line
			(start -0.299974 -0.150114)
			(end -0.299974 0.150114)
			(stroke
				(width 0.1)
				(type default)
			)
			(layer "B.Fab")
		)
		(fp_line
			(start -0.299974 0.150114)
			(end 0.299974 0.150114)
			(stroke
				(width 0.1)
				(type default)
			)
			(layer "B.Fab")
		)
		(fp_line
			(start 0.299974 -0.150114)
			(end -0.299974 -0.150114)
			(stroke
				(width 0.1)
				(type default)
			)
			(layer "B.Fab")
		)
		(fp_line
			(start 0.299974 0.150114)
			(end 0.299974 -0.150114)
			(stroke
				(width 0.1)
				(type default)
			)
			(layer "B.Fab")
		)
		(pad "1" smd rect
			(at 0.2667 0 180)
			(size 0.3048 0.381)
			(layers "B.Cu" "B.Mask" "B.Paste")
			(net "P1V8_PEX")
		)
		(pad "2" smd rect
			(at -0.2667 0 180)
			(size 0.3048 0.381)
			(layers "B.Cu" "B.Mask" "B.Paste")
			(net "GND")
		)
	)
	(footprint ""
		(layer "B.Cu")
		(at 389.89 -242.189 -90)
		(property "Reference" "C2572"
			(at 0 0 90)
			(layer "B.SilkS")
			(hide yes)
			(effects
				(font
					(size 1.27 1.27)
				)
				(justify mirror)
			)
		)
		(property "Value" ""
			(at 0 0 90)
			(layer "B.Fab")
			(effects
				(font
					(size 1.27 1.27)
				)
				(justify mirror)
			)
		)
		(duplicate_pad_numbers_are_jumpers no)
		(fp_line
			(start -0.7874 0.4064)
			(end 0.7874 0.4064)
			(stroke
				(width 0.1524)
				(type default)
			)
			(layer "B.SilkS")
		)
		(fp_line
			(start 0.7874 0.4064)
			(end 0.7874 -0.4064)
			(stroke
				(width 0.1524)
				(type default)
			)
			(layer "B.SilkS")
		)
		(fp_line
			(start -0.7874 -0.4064)
			(end -0.7874 0.4064)
			(stroke
				(width 0.1524)
				(type default)
			)
			(layer "B.SilkS")
		)
		(fp_line
			(start 0.7874 -0.4064)
			(end -0.7874 -0.4064)
			(stroke
				(width 0.1524)
				(type default)
			)
			(layer "B.SilkS")
		)
		(fp_line
			(start -0.67945 0.3048)
			(end -0.120396 0.3048)
			(stroke
				(width 0.1)
				(type default)
			)
			(layer "B.Fab")
		)
		(fp_line
			(start -0.120396 0.3048)
			(end -0.120396 0.2794)
			(stroke
				(width 0.1)
				(type default)
			)
			(layer "B.Fab")
		)
		(fp_line
			(start 0.12065 0.3048)
			(end 0.67945 0.3048)
			(stroke
				(width 0.1)
				(type default)
			)
			(layer "B.Fab")
		)
		(fp_line
			(start 0.67945 0.3048)
			(end 0.67945 -0.305054)
			(stroke
				(width 0.1)
				(type default)
			)
			(layer "B.Fab")
		)
		(fp_line
			(start -0.120396 0.2794)
			(end 0.12065 0.2794)
			(stroke
				(width 0.1)
				(type default)
			)
			(layer "B.Fab")
		)
		(fp_line
			(start 0.12065 0.2794)
			(end 0.12065 0.3048)
			(stroke
				(width 0.1)
				(type default)
			)
			(layer "B.Fab")
		)
		(fp_line
			(start -0.12065 -0.2794)
			(end -0.12065 -0.3048)
			(stroke
				(width 0.1)
				(type default)
			)
			(layer "B.Fab")
		)
		(fp_line
			(start 0.12065 -0.2794)
			(end -0.12065 -0.2794)
			(stroke
				(width 0.1)
				(type default)
			)
			(layer "B.Fab")
		)
		(fp_line
			(start -0.67945 -0.3048)
			(end -0.67945 0.3048)
			(stroke
				(width 0.1)
				(type default)
			)
			(layer "B.Fab")
		)
		(fp_line
			(start -0.12065 -0.3048)
			(end -0.67945 -0.3048)
			(stroke
				(width 0.1)
				(type default)
			)
			(layer "B.Fab")
		)
		(fp_line
			(start 0.12065 -0.305054)
			(end 0.12065 -0.2794)
			(stroke
				(width 0.1)
				(type default)
			)
			(layer "B.Fab")
		)
		(fp_line
			(start 0.67945 -0.305054)
			(end 0.12065 -0.305054)
			(stroke
				(width 0.1)
				(type default)
			)
			(layer "B.Fab")
		)
		(pad "1" smd circle
			(at 0.40005 0 90)
			(size 0 0)
			(layers "B.Cu" "B.Mask" "B.Paste")
			(net "P3V3_AUX")
		)
		(pad "2" smd circle
			(at -0.40005 0 90)
			(size 0 0)
			(layers "B.Cu" "B.Mask" "B.Paste")
			(net "GND")
		)
	)
	(footprint ""
		(layer "B.Cu")
		(at 234.514644 -231.225598 -90)
		(property "Reference" "R4517"
			(at 0 0 90)
			(layer "B.SilkS")
			(hide yes)
			(effects
				(font
					(size 1.27 1.27)
				)
				(justify mirror)
			)
		)
		(property "Value" ""
			(at 0 0 90)
			(layer "B.Fab")
			(effects
				(font
					(size 1.27 1.27)
				)
				(justify mirror)
			)
		)
		(duplicate_pad_numbers_are_jumpers no)
		(fp_line
			(start -0.7874 0.4064)
			(end 0.7874 0.4064)
			(stroke
				(width 0.1524)
				(type default)
			)
			(layer "B.SilkS")
		)
		(fp_line
			(start 0.7874 0.4064)
			(end 0.7874 -0.4064)
			(stroke
				(width 0.1524)
				(type default)
			)
			(layer "B.SilkS")
		)
		(fp_line
			(start -0.7874 -0.4064)
			(end -0.7874 0.4064)
			(stroke
				(width 0.1524)
				(type default)
			)
			(layer "B.SilkS")
		)
		(fp_line
			(start 0.7874 -0.4064)
			(end -0.7874 -0.4064)
			(stroke
				(width 0.1524)
				(type default)
			)
			(layer "B.SilkS")
		)
		(fp_line
			(start -0.67945 0.3048)
			(end -0.120396 0.3048)
			(stroke
				(width 0.1)
				(type default)
			)
			(layer "B.Fab")
		)
		(fp_line
			(start -0.120396 0.3048)
			(end -0.120396 0.2794)
			(stroke
				(width 0.1)
				(type default)
			)
			(layer "B.Fab")
		)
		(fp_line
			(start 0.12065 0.3048)
			(end 0.67945 0.3048)
			(stroke
				(width 0.1)
				(type default)
			)
			(layer "B.Fab")
		)
		(fp_line
			(start 0.67945 0.3048)
			(end 0.67945 -0.305054)
			(stroke
				(width 0.1)
				(type default)
			)
			(layer "B.Fab")
		)
		(fp_line
			(start -0.120396 0.2794)
			(end 0.12065 0.2794)
			(stroke
				(width 0.1)
				(type default)
			)
			(layer "B.Fab")
		)
		(fp_line
			(start 0.12065 0.2794)
			(end 0.12065 0.3048)
			(stroke
				(width 0.1)
				(type default)
			)
			(layer "B.Fab")
		)
		(fp_line
			(start -0.12065 -0.2794)
			(end -0.12065 -0.3048)
			(stroke
				(width 0.1)
				(type default)
			)
			(layer "B.Fab")
		)
		(fp_line
			(start 0.12065 -0.2794)
			(end -0.12065 -0.2794)
			(stroke
				(width 0.1)
				(type default)
			)
			(layer "B.Fab")
		)
		(fp_line
			(start -0.67945 -0.3048)
			(end -0.67945 0.3048)
			(stroke
				(width 0.1)
				(type default)
			)
			(layer "B.Fab")
		)
		(fp_line
			(start -0.12065 -0.3048)
			(end -0.67945 -0.3048)
			(stroke
				(width 0.1)
				(type default)
			)
			(layer "B.Fab")
		)
		(fp_line
			(start 0.12065 -0.305054)
			(end 0.12065 -0.2794)
			(stroke
				(width 0.1)
				(type default)
			)
			(layer "B.Fab")
		)
		(fp_line
			(start 0.67945 -0.305054)
			(end 0.12065 -0.305054)
			(stroke
				(width 0.1)
				(type default)
			)
			(layer "B.Fab")
		)
		(pad "1" smd circle
			(at 0.40005 0 90)
			(size 0 0)
			(layers "B.Cu" "B.Mask" "B.Paste")
			(net "SSD3_PWRDIS_BIC")
		)
		(pad "2" smd circle
			(at -0.40005 0 90)
			(size 0 0)
			(layers "B.Cu" "B.Mask" "B.Paste")
			(net "SSD3_PWRDIS_BIC_R")
		)
	)
	(footprint ""
		(layer "B.Cu")
		(at 455.090276 -278.289766 180)
		(property "Reference" "C4400"
			(at 0 0 0)
			(layer "B.SilkS")
			(hide yes)
			(effects
				(font
					(size 1.27 1.27)
				)
				(justify mirror)
			)
		)
		(property "Value" ""
			(at 0 0 0)
			(layer "B.Fab")
			(effects
				(font
					(size 1.27 1.27)
				)
				(justify mirror)
			)
		)
		(duplicate_pad_numbers_are_jumpers no)
		(fp_line
			(start 1.2954 0.5842)
			(end 1.2954 -0.5842)
			(stroke
				(width 0.1524)
				(type default)
			)
			(layer "B.SilkS")
		)
		(fp_line
			(start 1.2954 -0.5842)
			(end -1.2954 -0.5842)
			(stroke
				(width 0.1524)
				(type default)
			)
			(layer "B.SilkS")
		)
		(fp_line
			(start -1.2954 0.5842)
			(end 1.2954 0.5842)
			(stroke
				(width 0.1524)
				(type default)
			)
			(layer "B.SilkS")
		)
		(fp_line
			(start -1.2954 -0.5842)
			(end -1.2954 0.5842)
			(stroke
				(width 0.1524)
				(type default)
			)
			(layer "B.SilkS")
		)
		(fp_line
			(start 1.1938 0.4064)
			(end 1.1938 -0.4064)
			(stroke
				(width 0.1)
				(type default)
			)
			(layer "B.Fab")
		)
		(fp_line
			(start 1.1938 -0.4064)
			(end 0.8636 -0.4064)
			(stroke
				(width 0.1)
				(type default)
			)
			(layer "B.Fab")
		)
		(fp_line
			(start 0.8636 0.4572)
			(end 0.8636 0.4064)
			(stroke
				(width 0.1)
				(type default)
			)
			(layer "B.Fab")
		)
		(fp_line
			(start 0.8636 0.4064)
			(end 1.1938 0.4064)
			(stroke
				(width 0.1)
				(type default)
			)
			(layer "B.Fab")
		)
		(fp_line
			(start 0.8636 -0.4064)
			(end 0.8636 -0.4572)
			(stroke
				(width 0.1)
				(type default)
			)
			(layer "B.Fab")
		)
		(fp_line
			(start 0.8636 -0.4572)
			(end -0.8636 -0.4572)
			(stroke
				(width 0.1)
				(type default)
			)
			(layer "B.Fab")
		)
		(fp_line
			(start -0.8636 0.4572)
			(end 0.8636 0.4572)
			(stroke
				(width 0.1)
				(type default)
			)
			(layer "B.Fab")
		)
		(fp_line
			(start -0.8636 0.4064)
			(end -0.8636 0.4572)
			(stroke
				(width 0.1)
				(type default)
			)
			(layer "B.Fab")
		)
		(fp_line
			(start -0.8636 -0.4064)
			(end -1.1938 -0.4064)
			(stroke
				(width 0.1)
				(type default)
			)
			(layer "B.Fab")
		)
		(fp_line
			(start -0.8636 -0.4572)
			(end -0.8636 -0.4064)
			(stroke
				(width 0.1)
				(type default)
			)
			(layer "B.Fab")
		)
		(fp_line
			(start -1.1938 0.4064)
			(end -0.8636 0.4064)
			(stroke
				(width 0.1)
				(type default)
			)
			(layer "B.Fab")
		)
		(fp_line
			(start -1.1938 -0.4064)
			(end -1.1938 0.4064)
			(stroke
				(width 0.1)
				(type default)
			)
			(layer "B.Fab")
		)
		(pad "1" smd rect
			(at 0.7366 0 90)
			(size 0.7112 0.8128)
			(layers "B.Cu" "B.Mask" "B.Paste")
			(net "P1V25_PEX3")
		)
		(pad "2" smd rect
			(at -0.7366 0 90)
			(size 0.7112 0.8128)
			(layers "B.Cu" "B.Mask" "B.Paste")
			(net "GND")
		)
	)
	(footprint ""
		(layer "B.Cu")
		(at 174.800006 -303.499774 -90)
		(property "Reference" "C3117"
			(at 0 0 90)
			(layer "B.SilkS")
			(hide yes)
			(effects
				(font
					(size 1.27 1.27)
				)
				(justify mirror)
			)
		)
		(property "Value" ""
			(at 0 0 90)
			(layer "B.Fab")
			(effects
				(font
					(size 1.27 1.27)
				)
				(justify mirror)
			)
		)
		(duplicate_pad_numbers_are_jumpers no)
		(fp_line
			(start -0.299974 0.150114)
			(end 0.299974 0.150114)
			(stroke
				(width 0.1)
				(type default)
			)
			(layer "B.Fab")
		)
		(fp_line
			(start 0.299974 0.150114)
			(end 0.299974 -0.150114)
			(stroke
				(width 0.1)
				(type default)
			)
			(layer "B.Fab")
		)
		(fp_line
			(start -0.299974 -0.150114)
			(end -0.299974 0.150114)
			(stroke
				(width 0.1)
				(type default)
			)
			(layer "B.Fab")
		)
		(fp_line
			(start 0.299974 -0.150114)
			(end -0.299974 -0.150114)
			(stroke
				(width 0.1)
				(type default)
			)
			(layer "B.Fab")
		)
		(pad "1" smd rect
			(at 0.2667 0 90)
			(size 0.3048 0.381)
			(layers "B.Cu" "B.Mask" "B.Paste")
			(net "P1V25_PEX1")
		)
		(pad "2" smd rect
			(at -0.2667 0 90)
			(size 0.3048 0.381)
			(layers "B.Cu" "B.Mask" "B.Paste")
			(net "GND")
		)
	)
	(footprint ""
		(layer "B.Cu")
		(at 348.869 -207.772 90)
		(property "Reference" "R2966"
			(at 0 0 90)
			(layer "B.SilkS")
			(hide yes)
			(effects
				(font
					(size 1.27 1.27)
				)
				(justify mirror)
			)
		)
		(property "Value" ""
			(at 0 0 90)
			(layer "B.Fab")
			(effects
				(font
					(size 1.27 1.27)
				)
				(justify mirror)
			)
		)
		(duplicate_pad_numbers_are_jumpers no)
		(fp_line
			(start 0.7874 -0.4064)
			(end -0.7874 -0.4064)
			(stroke
				(width 0.1524)
				(type default)
			)
			(layer "B.SilkS")
		)
		(fp_line
			(start -0.7874 -0.4064)
			(end -0.7874 0.4064)
			(stroke
				(width 0.1524)
				(type default)
			)
			(layer "B.SilkS")
		)
		(fp_line
			(start 0.7874 0.4064)
			(end 0.7874 -0.4064)
			(stroke
				(width 0.1524)
				(type default)
			)
			(layer "B.SilkS")
		)
		(fp_line
			(start -0.7874 0.4064)
			(end 0.7874 0.4064)
			(stroke
				(width 0.1524)
				(type default)
			)
			(layer "B.SilkS")
		)
		(fp_line
			(start 0.67945 -0.305054)
			(end 0.12065 -0.305054)
			(stroke
				(width 0.1)
				(type default)
			)
			(layer "B.Fab")
		)
		(fp_line
			(start 0.12065 -0.305054)
			(end 0.12065 -0.2794)
			(stroke
				(width 0.1)
				(type default)
			)
			(layer "B.Fab")
		)
		(fp_line
			(start -0.12065 -0.3048)
			(end -0.67945 -0.3048)
			(stroke
				(width 0.1)
				(type default)
			)
			(layer "B.Fab")
		)
		(fp_line
			(start -0.67945 -0.3048)
			(end -0.67945 0.3048)
			(stroke
				(width 0.1)
				(type default)
			)
			(layer "B.Fab")
		)
		(fp_line
			(start 0.12065 -0.2794)
			(end -0.12065 -0.2794)
			(stroke
				(width 0.1)
				(type default)
			)
			(layer "B.Fab")
		)
		(fp_line
			(start -0.12065 -0.2794)
			(end -0.12065 -0.3048)
			(stroke
				(width 0.1)
				(type default)
			)
			(layer "B.Fab")
		)
		(fp_line
			(start 0.12065 0.2794)
			(end 0.12065 0.3048)
			(stroke
				(width 0.1)
				(type default)
			)
			(layer "B.Fab")
		)
		(fp_line
			(start -0.120396 0.2794)
			(end 0.12065 0.2794)
			(stroke
				(width 0.1)
				(type default)
			)
			(layer "B.Fab")
		)
		(fp_line
			(start 0.67945 0.3048)
			(end 0.67945 -0.305054)
			(stroke
				(width 0.1)
				(type default)
			)
			(layer "B.Fab")
		)
		(fp_line
			(start 0.12065 0.3048)
			(end 0.67945 0.3048)
			(stroke
				(width 0.1)
				(type default)
			)
			(layer "B.Fab")
		)
		(fp_line
			(start -0.120396 0.3048)
			(end -0.120396 0.2794)
			(stroke
				(width 0.1)
				(type default)
			)
			(layer "B.Fab")
		)
		(fp_line
			(start -0.67945 0.3048)
			(end -0.120396 0.3048)
			(stroke
				(width 0.1)
				(type default)
			)
			(layer "B.Fab")
		)
		(pad "1" smd circle
			(at 0.40005 0 270)
			(size 0 0)
			(layers "B.Cu" "B.Mask" "B.Paste")
			(net "RST_FPGA_BIC_N")
		)
		(pad "2" smd circle
			(at -0.40005 0 270)
			(size 0 0)
			(layers "B.Cu" "B.Mask" "B.Paste")
			(net "RST_FPGA_BIC_R_N")
		)
	)
	(footprint ""
		(layer "B.Cu")
		(at 53.42001 -305.399948 -90)
		(property "Reference" "C2986"
			(at 0 0 90)
			(layer "B.SilkS")
			(hide yes)
			(effects
				(font
					(size 1.27 1.27)
				)
				(justify mirror)
			)
		)
		(property "Value" ""
			(at 0 0 90)
			(layer "B.Fab")
			(effects
				(font
					(size 1.27 1.27)
				)
				(justify mirror)
			)
		)
		(duplicate_pad_numbers_are_jumpers no)
		(fp_line
			(start -0.299974 0.150114)
			(end 0.299974 0.150114)
			(stroke
				(width 0.1)
				(type default)
			)
			(layer "B.Fab")
		)
		(fp_line
			(start 0.299974 0.150114)
			(end 0.299974 -0.150114)
			(stroke
				(width 0.1)
				(type default)
			)
			(layer "B.Fab")
		)
		(fp_line
			(start -0.299974 -0.150114)
			(end -0.299974 0.150114)
			(stroke
				(width 0.1)
				(type default)
			)
			(layer "B.Fab")
		)
		(fp_line
			(start 0.299974 -0.150114)
			(end -0.299974 -0.150114)
			(stroke
				(width 0.1)
				(type default)
			)
			(layer "B.Fab")
		)
		(pad "1" smd rect
			(at 0.2667 0 90)
			(size 0.3048 0.381)
			(layers "B.Cu" "B.Mask" "B.Paste")
			(net "P1V25_SERDES_VDDPLL_PEX0")
		)
		(pad "2" smd rect
			(at -0.2667 0 90)
			(size 0.3048 0.381)
			(layers "B.Cu" "B.Mask" "B.Paste")
			(net "GND")
		)
	)
	(footprint ""
		(layer "B.Cu")
		(at 111.25327 -308.580028 90)
		(property "Reference" "C4194"
			(at 0 0 90)
			(layer "B.SilkS")
			(hide yes)
			(effects
				(font
					(size 1.27 1.27)
				)
				(justify mirror)
			)
		)
		(property "Value" ""
			(at 0 0 90)
			(layer "B.Fab")
			(effects
				(font
					(size 1.27 1.27)
				)
				(justify mirror)
			)
		)
		(duplicate_pad_numbers_are_jumpers no)
		(fp_line
			(start 1.2954 -0.5842)
			(end -1.2954 -0.5842)
			(stroke
				(width 0.1524)
				(type default)
			)
			(layer "B.SilkS")
		)
		(fp_line
			(start -1.2954 -0.5842)
			(end -1.2954 0.5842)
			(stroke
				(width 0.1524)
				(type default)
			)
			(layer "B.SilkS")
		)
		(fp_line
			(start 1.2954 0.5842)
			(end 1.2954 -0.5842)
			(stroke
				(width 0.1524)
				(type default)
			)
			(layer "B.SilkS")
		)
		(fp_line
			(start -1.2954 0.5842)
			(end 1.2954 0.5842)
			(stroke
				(width 0.1524)
				(type default)
			)
			(layer "B.SilkS")
		)
		(fp_line
			(start 0.8636 -0.4572)
			(end -0.8636 -0.4572)
			(stroke
				(width 0.1)
				(type default)
			)
			(layer "B.Fab")
		)
		(fp_line
			(start -0.8636 -0.4572)
			(end -0.8636 -0.4064)
			(stroke
				(width 0.1)
				(type default)
			)
			(layer "B.Fab")
		)
		(fp_line
			(start 1.1938 -0.4064)
			(end 0.8636 -0.4064)
			(stroke
				(width 0.1)
				(type default)
			)
			(layer "B.Fab")
		)
		(fp_line
			(start 0.8636 -0.4064)
			(end 0.8636 -0.4572)
			(stroke
				(width 0.1)
				(type default)
			)
			(layer "B.Fab")
		)
		(fp_line
			(start -0.8636 -0.4064)
			(end -1.1938 -0.4064)
			(stroke
				(width 0.1)
				(type default)
			)
			(layer "B.Fab")
		)
		(fp_line
			(start -1.1938 -0.4064)
			(end -1.1938 0.4064)
			(stroke
				(width 0.1)
				(type default)
			)
			(layer "B.Fab")
		)
		(fp_line
			(start 1.1938 0.4064)
			(end 1.1938 -0.4064)
			(stroke
				(width 0.1)
				(type default)
			)
			(layer "B.Fab")
		)
		(fp_line
			(start 0.8636 0.4064)
			(end 1.1938 0.4064)
			(stroke
				(width 0.1)
				(type default)
			)
			(layer "B.Fab")
		)
		(fp_line
			(start -0.8636 0.4064)
			(end -0.8636 0.4572)
			(stroke
				(width 0.1)
				(type default)
			)
			(layer "B.Fab")
		)
		(fp_line
			(start -1.1938 0.4064)
			(end -0.8636 0.4064)
			(stroke
				(width 0.1)
				(type default)
			)
			(layer "B.Fab")
		)
		(fp_line
			(start 0.8636 0.4572)
			(end 0.8636 0.4064)
			(stroke
				(width 0.1)
				(type default)
			)
			(layer "B.Fab")
		)
		(fp_line
			(start -0.8636 0.4572)
			(end 0.8636 0.4572)
			(stroke
				(width 0.1)
				(type default)
			)
			(layer "B.Fab")
		)
		(pad "1" smd rect
			(at 0.7366 0)
			(size 0.7112 0.8128)
			(layers "B.Cu" "B.Mask" "B.Paste")
			(net "P0V8_PEX0")
		)
		(pad "2" smd rect
			(at -0.7366 0)
			(size 0.7112 0.8128)
			(layers "B.Cu" "B.Mask" "B.Paste")
			(net "GND")
		)
	)
	(footprint ""
		(layer "B.Cu")
		(at 166.725092 -305.399948 -90)
		(property "Reference" "C3141"
			(at 0 0 90)
			(layer "B.SilkS")
			(hide yes)
			(effects
				(font
					(size 1.27 1.27)
				)
				(justify mirror)
			)
		)
		(property "Value" ""
			(at 0 0 90)
			(layer "B.Fab")
			(effects
				(font
					(size 1.27 1.27)
				)
				(justify mirror)
			)
		)
		(duplicate_pad_numbers_are_jumpers no)
		(fp_line
			(start -0.299974 0.150114)
			(end 0.299974 0.150114)
			(stroke
				(width 0.1)
				(type default)
			)
			(layer "B.Fab")
		)
		(fp_line
			(start 0.299974 0.150114)
			(end 0.299974 -0.150114)
			(stroke
				(width 0.1)
				(type default)
			)
			(layer "B.Fab")
		)
		(fp_line
			(start -0.299974 -0.150114)
			(end -0.299974 0.150114)
			(stroke
				(width 0.1)
				(type default)
			)
			(layer "B.Fab")
		)
		(fp_line
			(start 0.299974 -0.150114)
			(end -0.299974 -0.150114)
			(stroke
				(width 0.1)
				(type default)
			)
			(layer "B.Fab")
		)
		(pad "1" smd rect
			(at 0.2667 0 90)
			(size 0.3048 0.381)
			(layers "B.Cu" "B.Mask" "B.Paste")
			(net "P1V25_SERDES_VDDPLL_PEX1")
		)
		(pad "2" smd rect
			(at -0.2667 0 90)
			(size 0.3048 0.381)
			(layers "B.Cu" "B.Mask" "B.Paste")
			(net "GND")
		)
	)
	(footprint ""
		(layer "B.Cu")
		(at 251.18568 -83.935316 90)
		(property "Reference" "L9"
			(at 0 0 90)
			(layer "B.SilkS")
			(hide yes)
			(effects
				(font
					(size 1.27 1.27)
				)
				(justify mirror)
			)
		)
		(property "Value" ""
			(at 0 0 90)
			(layer "B.Fab")
			(effects
				(font
					(size 1.27 1.27)
				)
				(justify mirror)
			)
		)
		(duplicate_pad_numbers_are_jumpers no)
		(fp_line
			(start 1.63576 -0.8128)
			(end -1.63576 -0.8128)
			(stroke
				(width 0.1524)
				(type default)
			)
			(layer "B.SilkS")
		)
		(fp_line
			(start 1.63576 -0.8128)
			(end 1.63576 0.8128)
			(stroke
				(width 0.1524)
				(type default)
			)
			(layer "B.SilkS")
		)
		(fp_line
			(start -1.63576 -0.8128)
			(end -1.63576 0.8128)
			(stroke
				(width 0.1524)
				(type default)
			)
			(layer "B.SilkS")
		)
		(fp_line
			(start -1.63576 0.8128)
			(end 1.63576 0.8128)
			(stroke
				(width 0.1524)
				(type default)
			)
			(layer "B.SilkS")
		)
		(fp_line
			(start 1.56083 -0.738632)
			(end 1.56083 0.7366)
			(stroke
				(width 0.1)
				(type default)
			)
			(layer "B.Fab")
		)
		(fp_line
			(start -1.560576 -0.738632)
			(end 1.56083 -0.738632)
			(stroke
				(width 0.1)
				(type default)
			)
			(layer "B.Fab")
		)
		(fp_line
			(start 1.56083 0.7366)
			(end 1.524 0.7366)
			(stroke
				(width 0.1)
				(type default)
			)
			(layer "B.Fab")
		)
		(fp_line
			(start 1.524 0.7366)
			(end -1.524 0.7366)
			(stroke
				(width 0.1)
				(type default)
			)
			(layer "B.Fab")
		)
		(fp_line
			(start -1.524 0.7366)
			(end -1.560576 0.7366)
			(stroke
				(width 0.1)
				(type default)
			)
			(layer "B.Fab")
		)
		(fp_line
			(start -1.560576 0.7366)
			(end -1.560576 -0.738632)
			(stroke
				(width 0.1)
				(type default)
			)
			(layer "B.Fab")
		)
		(pad "1" smd rect
			(at 0.94996 0 90)
			(size 1.1176 1.3716)
			(layers "B.Cu" "B.Mask" "B.Paste")
			(net "P3V3")
		)
		(pad "2" smd rect
			(at -0.94996 0 90)
			(size 1.1176 1.3716)
			(layers "B.Cu" "B.Mask" "B.Paste")
			(net "P3V3_CLK_GEN_VDDXTAL_CK440")
		)
	)
	(footprint ""
		(layer "B.Cu")
		(at 288.524696 -286.399732 90)
		(property "Reference" "C3309"
			(at 0 0 90)
			(layer "B.SilkS")
			(hide yes)
			(effects
				(font
					(size 1.27 1.27)
				)
				(justify mirror)
			)
		)
		(property "Value" ""
			(at 0 0 90)
			(layer "B.Fab")
			(effects
				(font
					(size 1.27 1.27)
				)
				(justify mirror)
			)
		)
		(duplicate_pad_numbers_are_jumpers no)
		(fp_line
			(start 0.299974 -0.150114)
			(end -0.299974 -0.150114)
			(stroke
				(width 0.1)
				(type default)
			)
			(layer "B.Fab")
		)
		(fp_line
			(start -0.299974 -0.150114)
			(end -0.299974 0.150114)
			(stroke
				(width 0.1)
				(type default)
			)
			(layer "B.Fab")
		)
		(fp_line
			(start 0.299974 0.150114)
			(end 0.299974 -0.150114)
			(stroke
				(width 0.1)
				(type default)
			)
			(layer "B.Fab")
		)
		(fp_line
			(start -0.299974 0.150114)
			(end 0.299974 0.150114)
			(stroke
				(width 0.1)
				(type default)
			)
			(layer "B.Fab")
		)
		(pad "1" smd rect
			(at 0.2667 0 270)
			(size 0.3048 0.381)
			(layers "B.Cu" "B.Mask" "B.Paste")
			(net "P1V25_SERDES_VDDPLL_PEX2")
		)
		(pad "2" smd rect
			(at -0.2667 0 270)
			(size 0.3048 0.381)
			(layers "B.Cu" "B.Mask" "B.Paste")
			(net "GND")
		)
	)
	(footprint ""
		(layer "B.Cu")
		(at 230.450644 -231.225598 90)
		(property "Reference" "R4543"
			(at 0 0 90)
			(layer "B.SilkS")
			(hide yes)
			(effects
				(font
					(size 1.27 1.27)
				)
				(justify mirror)
			)
		)
		(property "Value" ""
			(at 0 0 90)
			(layer "B.Fab")
			(effects
				(font
					(size 1.27 1.27)
				)
				(justify mirror)
			)
		)
		(duplicate_pad_numbers_are_jumpers no)
		(fp_line
			(start 0.7874 -0.4064)
			(end -0.7874 -0.4064)
			(stroke
				(width 0.1524)
				(type default)
			)
			(layer "B.SilkS")
		)
		(fp_line
			(start -0.7874 -0.4064)
			(end -0.7874 0.4064)
			(stroke
				(width 0.1524)
				(type default)
			)
			(layer "B.SilkS")
		)
		(fp_line
			(start 0.7874 0.4064)
			(end 0.7874 -0.4064)
			(stroke
				(width 0.1524)
				(type default)
			)
			(layer "B.SilkS")
		)
		(fp_line
			(start -0.7874 0.4064)
			(end 0.7874 0.4064)
			(stroke
				(width 0.1524)
				(type default)
			)
			(layer "B.SilkS")
		)
		(fp_line
			(start 0.67945 -0.305054)
			(end 0.12065 -0.305054)
			(stroke
				(width 0.1)
				(type default)
			)
			(layer "B.Fab")
		)
		(fp_line
			(start 0.12065 -0.305054)
			(end 0.12065 -0.2794)
			(stroke
				(width 0.1)
				(type default)
			)
			(layer "B.Fab")
		)
		(fp_line
			(start -0.12065 -0.3048)
			(end -0.67945 -0.3048)
			(stroke
				(width 0.1)
				(type default)
			)
			(layer "B.Fab")
		)
		(fp_line
			(start -0.67945 -0.3048)
			(end -0.67945 0.3048)
			(stroke
				(width 0.1)
				(type default)
			)
			(layer "B.Fab")
		)
		(fp_line
			(start 0.12065 -0.2794)
			(end -0.12065 -0.2794)
			(stroke
				(width 0.1)
				(type default)
			)
			(layer "B.Fab")
		)
		(fp_line
			(start -0.12065 -0.2794)
			(end -0.12065 -0.3048)
			(stroke
				(width 0.1)
				(type default)
			)
			(layer "B.Fab")
		)
		(fp_line
			(start 0.12065 0.2794)
			(end 0.12065 0.3048)
			(stroke
				(width 0.1)
				(type default)
			)
			(layer "B.Fab")
		)
		(fp_line
			(start -0.120396 0.2794)
			(end 0.12065 0.2794)
			(stroke
				(width 0.1)
				(type default)
			)
			(layer "B.Fab")
		)
		(fp_line
			(start 0.67945 0.3048)
			(end 0.67945 -0.305054)
			(stroke
				(width 0.1)
				(type default)
			)
			(layer "B.Fab")
		)
		(fp_line
			(start 0.12065 0.3048)
			(end 0.67945 0.3048)
			(stroke
				(width 0.1)
				(type default)
			)
			(layer "B.Fab")
		)
		(fp_line
			(start -0.120396 0.3048)
			(end -0.120396 0.2794)
			(stroke
				(width 0.1)
				(type default)
			)
			(layer "B.Fab")
		)
		(fp_line
			(start -0.67945 0.3048)
			(end -0.120396 0.3048)
			(stroke
				(width 0.1)
				(type default)
			)
			(layer "B.Fab")
		)
		(pad "1" smd circle
			(at 0.40005 0 270)
			(size 0 0)
			(layers "B.Cu" "B.Mask" "B.Paste")
			(net "NIC7_MAIN_PWR_BIC_EN_R")
		)
		(pad "2" smd circle
			(at -0.40005 0 270)
			(size 0 0)
			(layers "B.Cu" "B.Mask" "B.Paste")
			(net "NIC7_MAIN_PWR_BIC_EN")
		)
	)
	(footprint ""
		(layer "B.Cu")
		(at 229.067614 -217.104214 -90)
		(property "Reference" "C3623"
			(at 0 0 90)
			(layer "B.SilkS")
			(hide yes)
			(effects
				(font
					(size 1.27 1.27)
				)
				(justify mirror)
			)
		)
		(property "Value" ""
			(at 0 0 90)
			(layer "B.Fab")
			(effects
				(font
					(size 1.27 1.27)
				)
				(justify mirror)
			)
		)
		(duplicate_pad_numbers_are_jumpers no)
		(fp_line
			(start -0.69215 0.2921)
			(end 0.69215 0.2921)
			(stroke
				(width 0.1524)
				(type default)
			)
			(layer "B.SilkS")
		)
		(fp_line
			(start 0.69215 0.2921)
			(end 0.69215 -0.2921)
			(stroke
				(width 0.1524)
				(type default)
			)
			(layer "B.SilkS")
		)
		(fp_line
			(start -0.69215 -0.2921)
			(end -0.69215 0.2921)
			(stroke
				(width 0.1524)
				(type default)
			)
			(layer "B.SilkS")
		)
		(fp_line
			(start 0.69215 -0.2921)
			(end -0.69215 -0.2921)
			(stroke
				(width 0.1524)
				(type default)
			)
			(layer "B.SilkS")
		)
		(fp_line
			(start -0.51435 0.2794)
			(end 0.51435 0.2794)
			(stroke
				(width 0.1)
				(type default)
			)
			(layer "B.Fab")
		)
		(fp_line
			(start 0.51435 0.2794)
			(end 0.51435 -0.2794)
			(stroke
				(width 0.1)
				(type default)
			)
			(layer "B.Fab")
		)
		(fp_line
			(start -0.51435 -0.2794)
			(end -0.51435 0.2794)
			(stroke
				(width 0.1)
				(type default)
			)
			(layer "B.Fab")
		)
		(fp_line
			(start 0.51435 -0.2794)
			(end -0.51435 -0.2794)
			(stroke
				(width 0.1)
				(type default)
			)
			(layer "B.Fab")
		)
		(pad "1" smd circle
			(at 0.40005 0 90)
			(size 0 0)
			(layers "B.Cu" "B.Mask" "B.Paste")
			(net "P1V2_AUX")
		)
		(pad "2" smd circle
			(at -0.40005 0 90)
			(size 0 0)
			(layers "B.Cu" "B.Mask" "B.Paste")
			(net "GND")
		)
		(zone
			(layer "B.Cu")
			(hatch none 0.5)
			(connect_pads
				(clearance 0)
			)
			(min_thickness 0.25)
			(keepout
				(tracks not_allowed)
				(vias allowed)
				(pads allowed)
				(copperpour not_allowed)
				(footprints allowed)
			)
			(placement
				(enabled no)
				(sheetname "")
			)
			(fill
				(thermal_gap 0.5)
				(thermal_bridge_width 0.5)
				(island_removal_mode 0)
			)
			(polygon
				(pts
					(xy 228.979984 -216.913714) (xy 228.921818 -217.005154) (xy 228.921818 -217.204544) (xy 228.979984 -217.294714)
					(xy 229.155244 -217.294714) (xy 229.213664 -217.204544) (xy 229.213664 -217.005154) (xy 229.155498 -216.913714)
				)
			)
		)
	)
	(footprint ""
		(layer "B.Cu")
		(at 162.4457 -294.4749)
		(property "Reference" "C3218"
			(at 0 0 0)
			(layer "B.SilkS")
			(hide yes)
			(effects
				(font
					(size 1.27 1.27)
				)
				(justify mirror)
			)
		)
		(property "Value" ""
			(at 0 0 0)
			(layer "B.Fab")
			(effects
				(font
					(size 1.27 1.27)
				)
				(justify mirror)
			)
		)
		(duplicate_pad_numbers_are_jumpers no)
		(fp_line
			(start -0.299974 -0.150114)
			(end -0.299974 0.150114)
			(stroke
				(width 0.1)
				(type default)
			)
			(layer "B.Fab")
		)
		(fp_line
			(start -0.299974 0.150114)
			(end 0.299974 0.150114)
			(stroke
				(width 0.1)
				(type default)
			)
			(layer "B.Fab")
		)
		(fp_line
			(start 0.299974 -0.150114)
			(end -0.299974 -0.150114)
			(stroke
				(width 0.1)
				(type default)
			)
			(layer "B.Fab")
		)
		(fp_line
			(start 0.299974 0.150114)
			(end 0.299974 -0.150114)
			(stroke
				(width 0.1)
				(type default)
			)
			(layer "B.Fab")
		)
		(pad "1" smd rect
			(at 0.2667 0 180)
			(size 0.3048 0.381)
			(layers "B.Cu" "B.Mask" "B.Paste")
			(net "PCEPLL4_VDDA18_PEX1")
		)
		(pad "2" smd rect
			(at -0.2667 0 180)
			(size 0.3048 0.381)
			(layers "B.Cu" "B.Mask" "B.Paste")
			(net "GND")
		)
	)
	(footprint ""
		(layer "B.Cu")
		(at 165.774878 -297.79976 90)
		(property "Reference" "C1400"
			(at 0 0 90)
			(layer "B.SilkS")
			(hide yes)
			(effects
				(font
					(size 1.27 1.27)
				)
				(justify mirror)
			)
		)
		(property "Value" ""
			(at 0 0 90)
			(layer "B.Fab")
			(effects
				(font
					(size 1.27 1.27)
				)
				(justify mirror)
			)
		)
		(duplicate_pad_numbers_are_jumpers no)
		(fp_line
			(start 0.299974 -0.150114)
			(end -0.299974 -0.150114)
			(stroke
				(width 0.1)
				(type default)
			)
			(layer "B.Fab")
		)
		(fp_line
			(start -0.299974 -0.150114)
			(end -0.299974 0.150114)
			(stroke
				(width 0.1)
				(type default)
			)
			(layer "B.Fab")
		)
		(fp_line
			(start 0.299974 0.150114)
			(end 0.299974 -0.150114)
			(stroke
				(width 0.1)
				(type default)
			)
			(layer "B.Fab")
		)
		(fp_line
			(start -0.299974 0.150114)
			(end 0.299974 0.150114)
			(stroke
				(width 0.1)
				(type default)
			)
			(layer "B.Fab")
		)
		(pad "1" smd rect
			(at 0.2667 0 270)
			(size 0.3048 0.381)
			(layers "B.Cu" "B.Mask" "B.Paste")
			(net "P0V8_PEX1")
		)
		(pad "2" smd rect
			(at -0.2667 0 270)
			(size 0.3048 0.381)
			(layers "B.Cu" "B.Mask" "B.Paste")
			(net "GND")
		)
	)
	(footprint ""
		(layer "B.Cu")
		(at 67.249802 -288.299906 90)
		(property "Reference" "C2927"
			(at 0 0 90)
			(layer "B.SilkS")
			(hide yes)
			(effects
				(font
					(size 1.27 1.27)
				)
				(justify mirror)
			)
		)
		(property "Value" ""
			(at 0 0 90)
			(layer "B.Fab")
			(effects
				(font
					(size 1.27 1.27)
				)
				(justify mirror)
			)
		)
		(duplicate_pad_numbers_are_jumpers no)
		(fp_line
			(start 0.299974 -0.150114)
			(end -0.299974 -0.150114)
			(stroke
				(width 0.1)
				(type default)
			)
			(layer "B.Fab")
		)
		(fp_line
			(start -0.299974 -0.150114)
			(end -0.299974 0.150114)
			(stroke
				(width 0.1)
				(type default)
			)
			(layer "B.Fab")
		)
		(fp_line
			(start 0.299974 0.150114)
			(end 0.299974 -0.150114)
			(stroke
				(width 0.1)
				(type default)
			)
			(layer "B.Fab")
		)
		(fp_line
			(start -0.299974 0.150114)
			(end 0.299974 0.150114)
			(stroke
				(width 0.1)
				(type default)
			)
			(layer "B.Fab")
		)
		(pad "1" smd rect
			(at 0.2667 0 270)
			(size 0.3048 0.381)
			(layers "B.Cu" "B.Mask" "B.Paste")
			(net "P1V25_PEX0")
		)
		(pad "2" smd rect
			(at -0.2667 0 270)
			(size 0.3048 0.381)
			(layers "B.Cu" "B.Mask" "B.Paste")
			(net "GND")
		)
	)
	(footprint ""
		(layer "B.Cu")
		(at 64.874902 -297.79976 -90)
		(property "Reference" "C1143"
			(at 0 0 90)
			(layer "B.SilkS")
			(hide yes)
			(effects
				(font
					(size 1.27 1.27)
				)
				(justify mirror)
			)
		)
		(property "Value" ""
			(at 0 0 90)
			(layer "B.Fab")
			(effects
				(font
					(size 1.27 1.27)
				)
				(justify mirror)
			)
		)
		(duplicate_pad_numbers_are_jumpers no)
		(fp_line
			(start -0.299974 0.150114)
			(end 0.299974 0.150114)
			(stroke
				(width 0.1)
				(type default)
			)
			(layer "B.Fab")
		)
		(fp_line
			(start 0.299974 0.150114)
			(end 0.299974 -0.150114)
			(stroke
				(width 0.1)
				(type default)
			)
			(layer "B.Fab")
		)
		(fp_line
			(start -0.299974 -0.150114)
			(end -0.299974 0.150114)
			(stroke
				(width 0.1)
				(type default)
			)
			(layer "B.Fab")
		)
		(fp_line
			(start 0.299974 -0.150114)
			(end -0.299974 -0.150114)
			(stroke
				(width 0.1)
				(type default)
			)
			(layer "B.Fab")
		)
		(pad "1" smd rect
			(at 0.2667 0 90)
			(size 0.3048 0.381)
			(layers "B.Cu" "B.Mask" "B.Paste")
			(net "P0V8_PEX0")
		)
		(pad "2" smd rect
			(at -0.2667 0 90)
			(size 0.3048 0.381)
			(layers "B.Cu" "B.Mask" "B.Paste")
			(net "GND")
		)
	)
	(footprint ""
		(layer "B.Cu")
		(at 53.949854 -299.699934 -90)
		(property "Reference" "C1218"
			(at 0 0 90)
			(layer "B.SilkS")
			(hide yes)
			(effects
				(font
					(size 1.27 1.27)
				)
				(justify mirror)
			)
		)
		(property "Value" ""
			(at 0 0 90)
			(layer "B.Fab")
			(effects
				(font
					(size 1.27 1.27)
				)
				(justify mirror)
			)
		)
		(duplicate_pad_numbers_are_jumpers no)
		(fp_line
			(start -0.299974 0.150114)
			(end 0.299974 0.150114)
			(stroke
				(width 0.1)
				(type default)
			)
			(layer "B.Fab")
		)
		(fp_line
			(start 0.299974 0.150114)
			(end 0.299974 -0.150114)
			(stroke
				(width 0.1)
				(type default)
			)
			(layer "B.Fab")
		)
		(fp_line
			(start -0.299974 -0.150114)
			(end -0.299974 0.150114)
			(stroke
				(width 0.1)
				(type default)
			)
			(layer "B.Fab")
		)
		(fp_line
			(start 0.299974 -0.150114)
			(end -0.299974 -0.150114)
			(stroke
				(width 0.1)
				(type default)
			)
			(layer "B.Fab")
		)
		(pad "1" smd rect
			(at 0.2667 0 90)
			(size 0.3048 0.381)
			(layers "B.Cu" "B.Mask" "B.Paste")
			(net "P0V8_SERDES_VDDA_PEX0")
		)
		(pad "2" smd rect
			(at -0.2667 0 90)
			(size 0.3048 0.381)
			(layers "B.Cu" "B.Mask" "B.Paste")
			(net "GND")
		)
	)
	(footprint ""
		(layer "B.Cu")
		(at 344.49385 -218.787218 -90)
		(property "Reference" "C2063"
			(at 0 0 90)
			(layer "B.SilkS")
			(hide yes)
			(effects
				(font
					(size 1.27 1.27)
				)
				(justify mirror)
			)
		)
		(property "Value" ""
			(at 0 0 90)
			(layer "B.Fab")
			(effects
				(font
					(size 1.27 1.27)
				)
				(justify mirror)
			)
		)
		(duplicate_pad_numbers_are_jumpers no)
		(fp_line
			(start -0.69215 0.2921)
			(end 0.69215 0.2921)
			(stroke
				(width 0.1524)
				(type default)
			)
			(layer "B.SilkS")
		)
		(fp_line
			(start 0.69215 0.2921)
			(end 0.69215 -0.2921)
			(stroke
				(width 0.1524)
				(type default)
			)
			(layer "B.SilkS")
		)
		(fp_line
			(start -0.69215 -0.2921)
			(end -0.69215 0.2921)
			(stroke
				(width 0.1524)
				(type default)
			)
			(layer "B.SilkS")
		)
		(fp_line
			(start 0.69215 -0.2921)
			(end -0.69215 -0.2921)
			(stroke
				(width 0.1524)
				(type default)
			)
			(layer "B.SilkS")
		)
		(fp_line
			(start -0.51435 0.2794)
			(end 0.51435 0.2794)
			(stroke
				(width 0.1)
				(type default)
			)
			(layer "B.Fab")
		)
		(fp_line
			(start 0.51435 0.2794)
			(end 0.51435 -0.2794)
			(stroke
				(width 0.1)
				(type default)
			)
			(layer "B.Fab")
		)
		(fp_line
			(start -0.51435 -0.2794)
			(end -0.51435 0.2794)
			(stroke
				(width 0.1)
				(type default)
			)
			(layer "B.Fab")
		)
		(fp_line
			(start 0.51435 -0.2794)
			(end -0.51435 -0.2794)
			(stroke
				(width 0.1)
				(type default)
			)
			(layer "B.Fab")
		)
		(pad "1" smd circle
			(at 0.40005 0 90)
			(size 0 0)
			(layers "B.Cu" "B.Mask" "B.Paste")
			(net "P3V3_VCC_FPGA_CORE")
		)
		(pad "2" smd circle
			(at -0.40005 0 90)
			(size 0 0)
			(layers "B.Cu" "B.Mask" "B.Paste")
			(net "GND")
		)
		(zone
			(layer "B.Cu")
			(hatch none 0.5)
			(connect_pads
				(clearance 0)
			)
			(min_thickness 0.25)
			(keepout
				(tracks not_allowed)
				(vias allowed)
				(pads allowed)
				(copperpour not_allowed)
				(footprints allowed)
			)
			(placement
				(enabled no)
				(sheetname "")
			)
			(fill
				(thermal_gap 0.5)
				(thermal_bridge_width 0.5)
				(island_removal_mode 0)
			)
			(polygon
				(pts
					(xy 344.40622 -218.596718) (xy 344.348054 -218.688158) (xy 344.348054 -218.887548) (xy 344.40622 -218.977718)
					(xy 344.58148 -218.977718) (xy 344.6399 -218.887548) (xy 344.6399 -218.688158) (xy 344.581734 -218.596718)
				)
			)
		)
	)
	(footprint ""
		(layer "B.Cu")
		(at 191.823848 -289.724846 90)
		(property "Reference" "R934"
			(at 0 0 90)
			(layer "B.SilkS")
			(hide yes)
			(effects
				(font
					(size 1.27 1.27)
				)
				(justify mirror)
			)
		)
		(property "Value" ""
			(at 0 0 90)
			(layer "B.Fab")
			(effects
				(font
					(size 1.27 1.27)
				)
				(justify mirror)
			)
		)
		(duplicate_pad_numbers_are_jumpers no)
		(fp_line
			(start 0.7874 -0.4064)
			(end -0.7874 -0.4064)
			(stroke
				(width 0.1524)
				(type default)
			)
			(layer "B.SilkS")
		)
		(fp_line
			(start -0.7874 -0.4064)
			(end -0.7874 0.4064)
			(stroke
				(width 0.1524)
				(type default)
			)
			(layer "B.SilkS")
		)
		(fp_line
			(start 0.7874 0.4064)
			(end 0.7874 -0.4064)
			(stroke
				(width 0.1524)
				(type default)
			)
			(layer "B.SilkS")
		)
		(fp_line
			(start -0.7874 0.4064)
			(end 0.7874 0.4064)
			(stroke
				(width 0.1524)
				(type default)
			)
			(layer "B.SilkS")
		)
		(fp_line
			(start 0.67945 -0.305054)
			(end 0.12065 -0.305054)
			(stroke
				(width 0.1)
				(type default)
			)
			(layer "B.Fab")
		)
		(fp_line
			(start 0.12065 -0.305054)
			(end 0.12065 -0.2794)
			(stroke
				(width 0.1)
				(type default)
			)
			(layer "B.Fab")
		)
		(fp_line
			(start -0.12065 -0.3048)
			(end -0.67945 -0.3048)
			(stroke
				(width 0.1)
				(type default)
			)
			(layer "B.Fab")
		)
		(fp_line
			(start -0.67945 -0.3048)
			(end -0.67945 0.3048)
			(stroke
				(width 0.1)
				(type default)
			)
			(layer "B.Fab")
		)
		(fp_line
			(start 0.12065 -0.2794)
			(end -0.12065 -0.2794)
			(stroke
				(width 0.1)
				(type default)
			)
			(layer "B.Fab")
		)
		(fp_line
			(start -0.12065 -0.2794)
			(end -0.12065 -0.3048)
			(stroke
				(width 0.1)
				(type default)
			)
			(layer "B.Fab")
		)
		(fp_line
			(start 0.12065 0.2794)
			(end 0.12065 0.3048)
			(stroke
				(width 0.1)
				(type default)
			)
			(layer "B.Fab")
		)
		(fp_line
			(start -0.120396 0.2794)
			(end 0.12065 0.2794)
			(stroke
				(width 0.1)
				(type default)
			)
			(layer "B.Fab")
		)
		(fp_line
			(start 0.67945 0.3048)
			(end 0.67945 -0.305054)
			(stroke
				(width 0.1)
				(type default)
			)
			(layer "B.Fab")
		)
		(fp_line
			(start 0.12065 0.3048)
			(end 0.67945 0.3048)
			(stroke
				(width 0.1)
				(type default)
			)
			(layer "B.Fab")
		)
		(fp_line
			(start -0.120396 0.3048)
			(end -0.120396 0.2794)
			(stroke
				(width 0.1)
				(type default)
			)
			(layer "B.Fab")
		)
		(fp_line
			(start -0.67945 0.3048)
			(end -0.120396 0.3048)
			(stroke
				(width 0.1)
				(type default)
			)
			(layer "B.Fab")
		)
		(pad "1" smd circle
			(at 0.40005 0 270)
			(size 0 0)
			(layers "B.Cu" "B.Mask" "B.Paste")
			(net "UART_PEX1_SDB_TX")
		)
		(pad "2" smd circle
			(at -0.40005 0 270)
			(size 0 0)
			(layers "B.Cu" "B.Mask" "B.Paste")
			(net "UART_PEX1_SDB_R_TX")
		)
	)
	(footprint ""
		(layer "B.Cu")
		(at 52.999894 -303.499774 -90)
		(property "Reference" "C2915"
			(at 0 0 90)
			(layer "B.SilkS")
			(hide yes)
			(effects
				(font
					(size 1.27 1.27)
				)
				(justify mirror)
			)
		)
		(property "Value" ""
			(at 0 0 90)
			(layer "B.Fab")
			(effects
				(font
					(size 1.27 1.27)
				)
				(justify mirror)
			)
		)
		(duplicate_pad_numbers_are_jumpers no)
		(fp_line
			(start -0.299974 0.150114)
			(end 0.299974 0.150114)
			(stroke
				(width 0.1)
				(type default)
			)
			(layer "B.Fab")
		)
		(fp_line
			(start 0.299974 0.150114)
			(end 0.299974 -0.150114)
			(stroke
				(width 0.1)
				(type default)
			)
			(layer "B.Fab")
		)
		(fp_line
			(start -0.299974 -0.150114)
			(end -0.299974 0.150114)
			(stroke
				(width 0.1)
				(type default)
			)
			(layer "B.Fab")
		)
		(fp_line
			(start 0.299974 -0.150114)
			(end -0.299974 -0.150114)
			(stroke
				(width 0.1)
				(type default)
			)
			(layer "B.Fab")
		)
		(pad "1" smd rect
			(at 0.2667 0 90)
			(size 0.3048 0.381)
			(layers "B.Cu" "B.Mask" "B.Paste")
			(net "P1V25_PEX0")
		)
		(pad "2" smd rect
			(at -0.2667 0 90)
			(size 0.3048 0.381)
			(layers "B.Cu" "B.Mask" "B.Paste")
			(net "GND")
		)
	)
	(footprint ""
		(layer "B.Cu")
		(at 442.553344 20.568412)
		(property "Reference" "DE05F_3"
			(at 2.403856 3.054858 0)
			(unlocked yes)
			(layer "B.SilkS")
			(effects
				(font
					(size 0.7874 0.5842)
					(thickness 0.1524)
				)
				(justify left mirror)
			)
		)
		(property "Value" ""
			(at 0 0 0)
			(layer "B.Fab")
			(effects
				(font
					(size 1.27 1.27)
				)
				(justify mirror)
			)
		)
		(duplicate_pad_numbers_are_jumpers no)
		(fp_line
			(start -1.2192 -2.1082)
			(end -1.2192 2.1082)
			(stroke
				(width 0.1524)
				(type default)
			)
			(layer "B.SilkS")
		)
		(fp_line
			(start -1.2192 2.1082)
			(end 1.2192 2.1082)
			(stroke
				(width 0.1524)
				(type default)
			)
			(layer "B.SilkS")
		)
		(fp_line
			(start 1.2192 -2.1082)
			(end -1.2192 -2.1082)
			(stroke
				(width 0.1524)
				(type default)
			)
			(layer "B.SilkS")
		)
		(fp_line
			(start 1.2192 2.1082)
			(end 1.2192 -2.1082)
			(stroke
				(width 0.1524)
				(type default)
			)
			(layer "B.SilkS")
		)
		(pad "" np_thru_hole circle
			(at -3.4671 -1.27 270)
			(size 1.0414 1.0414)
			(drill 1.0414)
			(layers "*.Cu" "*.Mask")
			(clearance 0.381)
			(thermal_gap 0.381)
		)
		(pad "" np_thru_hole circle
			(at -3.4671 1.27 270)
			(size 1.0414 1.0414)
			(drill 1.0414)
			(layers "*.Cu" "*.Mask")
			(clearance 0.381)
			(thermal_gap 0.381)
		)
		(pad "" np_thru_hole circle
			(at 2.8829 -1.27 270)
			(size 1.0414 1.0414)
			(drill 1.0414)
			(layers "*.Cu" "*.Mask")
			(clearance 0.381)
			(thermal_gap 0.381)
		)
		(pad "" np_thru_hole circle
			(at 2.8829 1.27 270)
			(size 1.0414 1.0414)
			(drill 1.0414)
			(layers "*.Cu" "*.Mask")
			(clearance 0.381)
			(thermal_gap 0.381)
		)
		(pad "1" smd rect
			(at -0.8255 -0.249936 270)
			(size 0.3048 0.508)
			(layers "B.Cu" "B.Mask" "B.Paste")
			(net "85_5INCH_IN5_DP")
		)
		(pad "2" smd rect
			(at -0.8255 0.249936 270)
			(size 0.3048 0.508)
			(layers "B.Cu" "B.Mask" "B.Paste")
			(net "85_5INCH_IN5_DN")
		)
		(pad "3" smd circle
			(at 0 0 180)
			(size 0 0)
			(layers "B.Cu" "B.Mask" "B.Paste")
			(net "COUPON_GND2")
		)
		(zone
			(layers "F.Cu" "B.Cu" "In1.Cu" "In2.Cu" "In3.Cu" "In4.Cu" "In5.Cu" "In6.Cu"
				"In7.Cu" "In8.Cu" "In9.Cu" "In10.Cu" "In11.Cu" "In12.Cu" "In13.Cu" "In14.Cu"
				"In15.Cu" "In16.Cu"
			)
			(hatch none 0.5)
			(connect_pads
				(clearance 0)
			)
			(min_thickness 0.25)
			(keepout
				(tracks not_allowed)
				(vias allowed)
				(pads allowed)
				(copperpour not_allowed)
				(footprints allowed)
			)
			(placement
				(enabled no)
				(sheetname "")
			)
			(fill
				(thermal_gap 0.5)
				(thermal_bridge_width 0.5)
				(island_removal_mode 0)
			)
			(polygon
				(pts
					(arc
						(start 440.013344 19.298412)
						(mid 438.159144 19.298412)
						(end 440.013344 19.298412)
					)
				)
			)
		)
		(zone
			(layers "F.Cu" "B.Cu" "In1.Cu" "In2.Cu" "In3.Cu" "In4.Cu" "In5.Cu" "In6.Cu"
				"In7.Cu" "In8.Cu" "In9.Cu" "In10.Cu" "In11.Cu" "In12.Cu" "In13.Cu" "In14.Cu"
				"In15.Cu" "In16.Cu"
			)
			(hatch none 0.5)
			(connect_pads
				(clearance 0)
			)
			(min_thickness 0.25)
			(keepout
				(tracks not_allowed)
				(vias allowed)
				(pads allowed)
				(copperpour not_allowed)
				(footprints allowed)
			)
			(placement
				(enabled no)
				(sheetname "")
			)
			(fill
				(thermal_gap 0.5)
				(thermal_bridge_width 0.5)
				(island_removal_mode 0)
			)
			(polygon
				(pts
					(arc
						(start 440.013344 21.838412)
						(mid 438.159144 21.838412)
						(end 440.013344 21.838412)
					)
				)
			)
		)
		(zone
			(layers "F.Cu" "B.Cu" "In1.Cu" "In2.Cu" "In3.Cu" "In4.Cu" "In5.Cu" "In6.Cu"
				"In7.Cu" "In8.Cu" "In9.Cu" "In10.Cu" "In11.Cu" "In12.Cu" "In13.Cu" "In14.Cu"
				"In15.Cu" "In16.Cu"
			)
			(hatch none 0.5)
			(connect_pads
				(clearance 0)
			)
			(min_thickness 0.25)
			(keepout
				(tracks not_allowed)
				(vias allowed)
				(pads allowed)
				(copperpour not_allowed)
				(footprints allowed)
			)
			(placement
				(enabled no)
				(sheetname "")
			)
			(fill
				(thermal_gap 0.5)
				(thermal_bridge_width 0.5)
				(island_removal_mode 0)
			)
			(polygon
				(pts
					(arc
						(start 446.363344 19.298412)
						(mid 444.509144 19.298412)
						(end 446.363344 19.298412)
					)
				)
			)
		)
		(zone
			(layers "F.Cu" "B.Cu" "In1.Cu" "In2.Cu" "In3.Cu" "In4.Cu" "In5.Cu" "In6.Cu"
				"In7.Cu" "In8.Cu" "In9.Cu" "In10.Cu" "In11.Cu" "In12.Cu" "In13.Cu" "In14.Cu"
				"In15.Cu" "In16.Cu"
			)
			(hatch none 0.5)
			(connect_pads
				(clearance 0)
			)
			(min_thickness 0.25)
			(keepout
				(tracks not_allowed)
				(vias allowed)
				(pads allowed)
				(copperpour not_allowed)
				(footprints allowed)
			)
			(placement
				(enabled no)
				(sheetname "")
			)
			(fill
				(thermal_gap 0.5)
				(thermal_bridge_width 0.5)
				(island_removal_mode 0)
			)
			(polygon
				(pts
					(arc
						(start 446.363344 21.838412)
						(mid 444.509144 21.838412)
						(end 446.363344 21.838412)
					)
				)
			)
		)
		(zone
			(layer "B.Cu")
			(hatch none 0.5)
			(connect_pads
				(clearance 0)
			)
			(min_thickness 0.25)
			(keepout
				(tracks not_allowed)
				(vias allowed)
				(pads allowed)
				(copperpour not_allowed)
				(footprints allowed)
			)
			(placement
				(enabled no)
				(sheetname "")
			)
			(fill
				(thermal_gap 0.5)
				(thermal_bridge_width 0.5)
				(island_removal_mode 0)
			)
			(polygon
				(pts
					(xy 441.435744 20.019772) (xy 441.435744 20.115276) (xy 442.032644 20.115276) (xy 442.032644 20.521676)
					(xy 441.435744 20.521676) (xy 441.435744 20.615148) (xy 442.032644 20.615148) (xy 442.032644 21.021548)
					(xy 441.435744 21.021548) (xy 441.435744 21.117052) (xy 442.134244 21.117052) (xy 442.134244 20.019772)
				)
			)
		)
	)
	(footprint ""
		(layer "B.Cu")
		(at 182.87492 -286.399732 90)
		(property "Reference" "C3158"
			(at 0 0 90)
			(layer "B.SilkS")
			(hide yes)
			(effects
				(font
					(size 1.27 1.27)
				)
				(justify mirror)
			)
		)
		(property "Value" ""
			(at 0 0 90)
			(layer "B.Fab")
			(effects
				(font
					(size 1.27 1.27)
				)
				(justify mirror)
			)
		)
		(duplicate_pad_numbers_are_jumpers no)
		(fp_line
			(start 0.299974 -0.150114)
			(end -0.299974 -0.150114)
			(stroke
				(width 0.1)
				(type default)
			)
			(layer "B.Fab")
		)
		(fp_line
			(start -0.299974 -0.150114)
			(end -0.299974 0.150114)
			(stroke
				(width 0.1)
				(type default)
			)
			(layer "B.Fab")
		)
		(fp_line
			(start 0.299974 0.150114)
			(end 0.299974 -0.150114)
			(stroke
				(width 0.1)
				(type default)
			)
			(layer "B.Fab")
		)
		(fp_line
			(start -0.299974 0.150114)
			(end 0.299974 0.150114)
			(stroke
				(width 0.1)
				(type default)
			)
			(layer "B.Fab")
		)
		(pad "1" smd rect
			(at 0.2667 0 270)
			(size 0.3048 0.381)
			(layers "B.Cu" "B.Mask" "B.Paste")
			(net "P1V25_SERDES_VDDPLL_PEX1")
		)
		(pad "2" smd rect
			(at -0.2667 0 270)
			(size 0.3048 0.381)
			(layers "B.Cu" "B.Mask" "B.Paste")
			(net "GND")
		)
	)
	(footprint ""
		(layer "B.Cu")
		(at 177.42027 -198.287386 180)
		(property "Reference" "R1029"
			(at 0 0 0)
			(layer "B.SilkS")
			(hide yes)
			(effects
				(font
					(size 1.27 1.27)
				)
				(justify mirror)
			)
		)
		(property "Value" ""
			(at 0 0 0)
			(layer "B.Fab")
			(effects
				(font
					(size 1.27 1.27)
				)
				(justify mirror)
			)
		)
		(duplicate_pad_numbers_are_jumpers no)
		(fp_line
			(start 0.7874 0.4064)
			(end 0.7874 -0.4064)
			(stroke
				(width 0.1524)
				(type default)
			)
			(layer "B.SilkS")
		)
		(fp_line
			(start 0.7874 -0.4064)
			(end -0.7874 -0.4064)
			(stroke
				(width 0.1524)
				(type default)
			)
			(layer "B.SilkS")
		)
		(fp_line
			(start -0.7874 0.4064)
			(end 0.7874 0.4064)
			(stroke
				(width 0.1524)
				(type default)
			)
			(layer "B.SilkS")
		)
		(fp_line
			(start -0.7874 -0.4064)
			(end -0.7874 0.4064)
			(stroke
				(width 0.1524)
				(type default)
			)
			(layer "B.SilkS")
		)
		(fp_line
			(start 0.67945 0.3048)
			(end 0.67945 -0.305054)
			(stroke
				(width 0.1)
				(type default)
			)
			(layer "B.Fab")
		)
		(fp_line
			(start 0.67945 -0.305054)
			(end 0.12065 -0.305054)
			(stroke
				(width 0.1)
				(type default)
			)
			(layer "B.Fab")
		)
		(fp_line
			(start 0.12065 0.3048)
			(end 0.67945 0.3048)
			(stroke
				(width 0.1)
				(type default)
			)
			(layer "B.Fab")
		)
		(fp_line
			(start 0.12065 0.2794)
			(end 0.12065 0.3048)
			(stroke
				(width 0.1)
				(type default)
			)
			(layer "B.Fab")
		)
		(fp_line
			(start 0.12065 -0.2794)
			(end -0.12065 -0.2794)
			(stroke
				(width 0.1)
				(type default)
			)
			(layer "B.Fab")
		)
		(fp_line
			(start 0.12065 -0.305054)
			(end 0.12065 -0.2794)
			(stroke
				(width 0.1)
				(type default)
			)
			(layer "B.Fab")
		)
		(fp_line
			(start -0.120396 0.3048)
			(end -0.120396 0.2794)
			(stroke
				(width 0.1)
				(type default)
			)
			(layer "B.Fab")
		)
		(fp_line
			(start -0.120396 0.2794)
			(end 0.12065 0.2794)
			(stroke
				(width 0.1)
				(type default)
			)
			(layer "B.Fab")
		)
		(fp_line
			(start -0.12065 -0.2794)
			(end -0.12065 -0.3048)
			(stroke
				(width 0.1)
				(type default)
			)
			(layer "B.Fab")
		)
		(fp_line
			(start -0.12065 -0.3048)
			(end -0.67945 -0.3048)
			(stroke
				(width 0.1)
				(type default)
			)
			(layer "B.Fab")
		)
		(fp_line
			(start -0.67945 0.3048)
			(end -0.120396 0.3048)
			(stroke
				(width 0.1)
				(type default)
			)
			(layer "B.Fab")
		)
		(fp_line
			(start -0.67945 -0.3048)
			(end -0.67945 0.3048)
			(stroke
				(width 0.1)
				(type default)
			)
			(layer "B.Fab")
		)
		(pad "1" smd circle
			(at 0.40005 0)
			(size 0 0)
			(layers "B.Cu" "B.Mask" "B.Paste")
			(net "SPI_BIC1_CS0_LS01_N_DIR1")
		)
		(pad "2" smd circle
			(at -0.40005 0)
			(size 0 0)
			(layers "B.Cu" "B.Mask" "B.Paste")
			(net "P1V8_PEX")
		)
	)
	(footprint ""
		(layer "B.Cu")
		(at 345.29395 -218.787218 -90)
		(property "Reference" "C2047"
			(at 0 0 90)
			(layer "B.SilkS")
			(hide yes)
			(effects
				(font
					(size 1.27 1.27)
				)
				(justify mirror)
			)
		)
		(property "Value" ""
			(at 0 0 90)
			(layer "B.Fab")
			(effects
				(font
					(size 1.27 1.27)
				)
				(justify mirror)
			)
		)
		(duplicate_pad_numbers_are_jumpers no)
		(fp_line
			(start -0.69215 0.2921)
			(end 0.69215 0.2921)
			(stroke
				(width 0.1524)
				(type default)
			)
			(layer "B.SilkS")
		)
		(fp_line
			(start 0.69215 0.2921)
			(end 0.69215 -0.2921)
			(stroke
				(width 0.1524)
				(type default)
			)
			(layer "B.SilkS")
		)
		(fp_line
			(start -0.69215 -0.2921)
			(end -0.69215 0.2921)
			(stroke
				(width 0.1524)
				(type default)
			)
			(layer "B.SilkS")
		)
		(fp_line
			(start 0.69215 -0.2921)
			(end -0.69215 -0.2921)
			(stroke
				(width 0.1524)
				(type default)
			)
			(layer "B.SilkS")
		)
		(fp_line
			(start -0.51435 0.2794)
			(end 0.51435 0.2794)
			(stroke
				(width 0.1)
				(type default)
			)
			(layer "B.Fab")
		)
		(fp_line
			(start 0.51435 0.2794)
			(end 0.51435 -0.2794)
			(stroke
				(width 0.1)
				(type default)
			)
			(layer "B.Fab")
		)
		(fp_line
			(start -0.51435 -0.2794)
			(end -0.51435 0.2794)
			(stroke
				(width 0.1)
				(type default)
			)
			(layer "B.Fab")
		)
		(fp_line
			(start 0.51435 -0.2794)
			(end -0.51435 -0.2794)
			(stroke
				(width 0.1)
				(type default)
			)
			(layer "B.Fab")
		)
		(pad "1" smd circle
			(at 0.40005 0 90)
			(size 0 0)
			(layers "B.Cu" "B.Mask" "B.Paste")
			(net "P3V3_FPGA_VCCIO1")
		)
		(pad "2" smd circle
			(at -0.40005 0 90)
			(size 0 0)
			(layers "B.Cu" "B.Mask" "B.Paste")
			(net "GND")
		)
		(zone
			(layer "B.Cu")
			(hatch none 0.5)
			(connect_pads
				(clearance 0)
			)
			(min_thickness 0.25)
			(keepout
				(tracks not_allowed)
				(vias allowed)
				(pads allowed)
				(copperpour not_allowed)
				(footprints allowed)
			)
			(placement
				(enabled no)
				(sheetname "")
			)
			(fill
				(thermal_gap 0.5)
				(thermal_bridge_width 0.5)
				(island_removal_mode 0)
			)
			(polygon
				(pts
					(xy 345.20632 -218.596718) (xy 345.148154 -218.688158) (xy 345.148154 -218.887548) (xy 345.20632 -218.977718)
					(xy 345.38158 -218.977718) (xy 345.44 -218.887548) (xy 345.44 -218.688158) (xy 345.381834 -218.596718)
				)
			)
		)
	)
	(footprint ""
		(layer "B.Cu")
		(at 227.067618 -219.10421 180)
		(property "Reference" "C2018"
			(at 0 0 0)
			(layer "B.SilkS")
			(hide yes)
			(effects
				(font
					(size 1.27 1.27)
				)
				(justify mirror)
			)
		)
		(property "Value" ""
			(at 0 0 0)
			(layer "B.Fab")
			(effects
				(font
					(size 1.27 1.27)
				)
				(justify mirror)
			)
		)
		(duplicate_pad_numbers_are_jumpers no)
		(fp_line
			(start 0.69215 0.2921)
			(end 0.69215 -0.2921)
			(stroke
				(width 0.1524)
				(type default)
			)
			(layer "B.SilkS")
		)
		(fp_line
			(start 0.69215 -0.2921)
			(end -0.69215 -0.2921)
			(stroke
				(width 0.1524)
				(type default)
			)
			(layer "B.SilkS")
		)
		(fp_line
			(start -0.69215 0.2921)
			(end 0.69215 0.2921)
			(stroke
				(width 0.1524)
				(type default)
			)
			(layer "B.SilkS")
		)
		(fp_line
			(start -0.69215 -0.2921)
			(end -0.69215 0.2921)
			(stroke
				(width 0.1524)
				(type default)
			)
			(layer "B.SilkS")
		)
		(fp_line
			(start 0.51435 0.2794)
			(end 0.51435 -0.2794)
			(stroke
				(width 0.1)
				(type default)
			)
			(layer "B.Fab")
		)
		(fp_line
			(start 0.51435 -0.2794)
			(end -0.51435 -0.2794)
			(stroke
				(width 0.1)
				(type default)
			)
			(layer "B.Fab")
		)
		(fp_line
			(start -0.51435 0.2794)
			(end 0.51435 0.2794)
			(stroke
				(width 0.1)
				(type default)
			)
			(layer "B.Fab")
		)
		(fp_line
			(start -0.51435 -0.2794)
			(end -0.51435 0.2794)
			(stroke
				(width 0.1)
				(type default)
			)
			(layer "B.Fab")
		)
		(pad "1" smd circle
			(at 0.40005 0)
			(size 0 0)
			(layers "B.Cu" "B.Mask" "B.Paste")
			(net "P1V2_AUX")
		)
		(pad "2" smd circle
			(at -0.40005 0)
			(size 0 0)
			(layers "B.Cu" "B.Mask" "B.Paste")
			(net "GND")
		)
		(zone
			(layer "B.Cu")
			(hatch none 0.5)
			(connect_pads
				(clearance 0)
			)
			(min_thickness 0.25)
			(keepout
				(tracks not_allowed)
				(vias allowed)
				(pads allowed)
				(copperpour not_allowed)
				(footprints allowed)
			)
			(placement
				(enabled no)
				(sheetname "")
			)
			(fill
				(thermal_gap 0.5)
				(thermal_bridge_width 0.5)
				(island_removal_mode 0)
			)
			(polygon
				(pts
					(xy 226.877118 -219.19184) (xy 226.968558 -219.250006) (xy 227.167948 -219.250006) (xy 227.258118 -219.19184)
					(xy 227.258118 -219.01658) (xy 227.167948 -218.95816) (xy 226.968558 -218.95816) (xy 226.877118 -219.016326)
				)
			)
		)
	)
	(footprint ""
		(layer "B.Cu")
		(at 130.336544 -303.649634 -90)
		(property "Reference" "PR10"
			(at 0 0 90)
			(layer "B.SilkS")
			(hide yes)
			(effects
				(font
					(size 1.27 1.27)
				)
				(justify mirror)
			)
		)
		(property "Value" ""
			(at 0 0 90)
			(layer "B.Fab")
			(effects
				(font
					(size 1.27 1.27)
				)
				(justify mirror)
			)
		)
		(duplicate_pad_numbers_are_jumpers no)
		(fp_line
			(start -1.2954 0.5842)
			(end 1.2954 0.5842)
			(stroke
				(width 0.1524)
				(type default)
			)
			(layer "B.SilkS")
		)
		(fp_line
			(start 1.2954 0.5842)
			(end 1.2954 -0.5842)
			(stroke
				(width 0.1524)
				(type default)
			)
			(layer "B.SilkS")
		)
		(fp_line
			(start -1.2954 -0.5842)
			(end -1.2954 0.5842)
			(stroke
				(width 0.1524)
				(type default)
			)
			(layer "B.SilkS")
		)
		(fp_line
			(start 1.2954 -0.5842)
			(end -1.2954 -0.5842)
			(stroke
				(width 0.1524)
				(type default)
			)
			(layer "B.SilkS")
		)
		(fp_line
			(start -0.8636 0.4572)
			(end 0.8636 0.4572)
			(stroke
				(width 0.1)
				(type default)
			)
			(layer "B.Fab")
		)
		(fp_line
			(start 0.8636 0.4572)
			(end 0.8636 0.4318)
			(stroke
				(width 0.1)
				(type default)
			)
			(layer "B.Fab")
		)
		(fp_line
			(start 0.8636 0.4318)
			(end 0.8636 0.4064)
			(stroke
				(width 0.1)
				(type default)
			)
			(layer "B.Fab")
		)
		(fp_line
			(start -1.1938 0.4064)
			(end -0.8636 0.4064)
			(stroke
				(width 0.1)
				(type default)
			)
			(layer "B.Fab")
		)
		(fp_line
			(start -0.8636 0.4064)
			(end -0.8636 0.4572)
			(stroke
				(width 0.1)
				(type default)
			)
			(layer "B.Fab")
		)
		(fp_line
			(start 0.8636 0.4064)
			(end 1.1938 0.4064)
			(stroke
				(width 0.1)
				(type default)
			)
			(layer "B.Fab")
		)
		(fp_line
			(start 1.1938 0.4064)
			(end 1.1938 -0.406654)
			(stroke
				(width 0.1)
				(type default)
			)
			(layer "B.Fab")
		)
		(fp_line
			(start -1.1938 -0.406654)
			(end -1.1938 0.4064)
			(stroke
				(width 0.1)
				(type default)
			)
			(layer "B.Fab")
		)
		(fp_line
			(start -0.8636 -0.406654)
			(end -1.1938 -0.406654)
			(stroke
				(width 0.1)
				(type default)
			)
			(layer "B.Fab")
		)
		(fp_line
			(start 0.8636 -0.406654)
			(end 0.8636 -0.4572)
			(stroke
				(width 0.1)
				(type default)
			)
			(layer "B.Fab")
		)
		(fp_line
			(start 1.1938 -0.406654)
			(end 0.8636 -0.406654)
			(stroke
				(width 0.1)
				(type default)
			)
			(layer "B.Fab")
		)
		(fp_line
			(start -0.8636 -0.4572)
			(end -0.8636 -0.406654)
			(stroke
				(width 0.1)
				(type default)
			)
			(layer "B.Fab")
		)
		(fp_line
			(start 0.8636 -0.4572)
			(end -0.8636 -0.4572)
			(stroke
				(width 0.1)
				(type default)
			)
			(layer "B.Fab")
		)
		(pad "1" smd rect
			(at 0.7366 0 180)
			(size 0.7112 0.8128)
			(layers "B.Cu" "B.Mask" "B.Paste")
			(net "P0V8_PEX1")
		)
		(pad "2" smd rect
			(at -0.7366 0 180)
			(size 0.7112 0.8128)
			(layers "B.Cu" "B.Mask" "B.Paste")
			(net "GND")
		)
	)
	(footprint ""
		(layer "B.Cu")
		(at 413.201358 -305.399948 -90)
		(property "Reference" "C3477"
			(at 0 0 90)
			(layer "B.SilkS")
			(hide yes)
			(effects
				(font
					(size 1.27 1.27)
				)
				(justify mirror)
			)
		)
		(property "Value" ""
			(at 0 0 90)
			(layer "B.Fab")
			(effects
				(font
					(size 1.27 1.27)
				)
				(justify mirror)
			)
		)
		(duplicate_pad_numbers_are_jumpers no)
		(fp_line
			(start -0.299974 0.150114)
			(end 0.299974 0.150114)
			(stroke
				(width 0.1)
				(type default)
			)
			(layer "B.Fab")
		)
		(fp_line
			(start 0.299974 0.150114)
			(end 0.299974 -0.150114)
			(stroke
				(width 0.1)
				(type default)
			)
			(layer "B.Fab")
		)
		(fp_line
			(start -0.299974 -0.150114)
			(end -0.299974 0.150114)
			(stroke
				(width 0.1)
				(type default)
			)
			(layer "B.Fab")
		)
		(fp_line
			(start 0.299974 -0.150114)
			(end -0.299974 -0.150114)
			(stroke
				(width 0.1)
				(type default)
			)
			(layer "B.Fab")
		)
		(pad "1" smd rect
			(at 0.2667 0 90)
			(size 0.3048 0.381)
			(layers "B.Cu" "B.Mask" "B.Paste")
			(net "P1V25_SERDES_VDDPLL_PEX3")
		)
		(pad "2" smd rect
			(at -0.2667 0 90)
			(size 0.3048 0.381)
			(layers "B.Cu" "B.Mask" "B.Paste")
			(net "GND")
		)
	)
	(footprint ""
		(layer "B.Cu")
		(at 130.893058 -229.997)
		(property "Reference" "R3463"
			(at 0 0 0)
			(layer "B.SilkS")
			(hide yes)
			(effects
				(font
					(size 1.27 1.27)
				)
				(justify mirror)
			)
		)
		(property "Value" ""
			(at 0 0 0)
			(layer "B.Fab")
			(effects
				(font
					(size 1.27 1.27)
				)
				(justify mirror)
			)
		)
		(duplicate_pad_numbers_are_jumpers no)
		(fp_line
			(start -0.7874 -0.4064)
			(end -0.7874 0.4064)
			(stroke
				(width 0.1524)
				(type default)
			)
			(layer "B.SilkS")
		)
		(fp_line
			(start -0.7874 0.4064)
			(end 0.7874 0.4064)
			(stroke
				(width 0.1524)
				(type default)
			)
			(layer "B.SilkS")
		)
		(fp_line
			(start 0.7874 -0.4064)
			(end -0.7874 -0.4064)
			(stroke
				(width 0.1524)
				(type default)
			)
			(layer "B.SilkS")
		)
		(fp_line
			(start 0.7874 0.4064)
			(end 0.7874 -0.4064)
			(stroke
				(width 0.1524)
				(type default)
			)
			(layer "B.SilkS")
		)
		(fp_line
			(start -0.67945 -0.3048)
			(end -0.67945 0.3048)
			(stroke
				(width 0.1)
				(type default)
			)
			(layer "B.Fab")
		)
		(fp_line
			(start -0.67945 0.3048)
			(end -0.120396 0.3048)
			(stroke
				(width 0.1)
				(type default)
			)
			(layer "B.Fab")
		)
		(fp_line
			(start -0.12065 -0.3048)
			(end -0.67945 -0.3048)
			(stroke
				(width 0.1)
				(type default)
			)
			(layer "B.Fab")
		)
		(fp_line
			(start -0.12065 -0.2794)
			(end -0.12065 -0.3048)
			(stroke
				(width 0.1)
				(type default)
			)
			(layer "B.Fab")
		)
		(fp_line
			(start -0.120396 0.2794)
			(end 0.12065 0.2794)
			(stroke
				(width 0.1)
				(type default)
			)
			(layer "B.Fab")
		)
		(fp_line
			(start -0.120396 0.3048)
			(end -0.120396 0.2794)
			(stroke
				(width 0.1)
				(type default)
			)
			(layer "B.Fab")
		)
		(fp_line
			(start 0.12065 -0.305054)
			(end 0.12065 -0.2794)
			(stroke
				(width 0.1)
				(type default)
			)
			(layer "B.Fab")
		)
		(fp_line
			(start 0.12065 -0.2794)
			(end -0.12065 -0.2794)
			(stroke
				(width 0.1)
				(type default)
			)
			(layer "B.Fab")
		)
		(fp_line
			(start 0.12065 0.2794)
			(end 0.12065 0.3048)
			(stroke
				(width 0.1)
				(type default)
			)
			(layer "B.Fab")
		)
		(fp_line
			(start 0.12065 0.3048)
			(end 0.67945 0.3048)
			(stroke
				(width 0.1)
				(type default)
			)
			(layer "B.Fab")
		)
		(fp_line
			(start 0.67945 -0.305054)
			(end 0.12065 -0.305054)
			(stroke
				(width 0.1)
				(type default)
			)
			(layer "B.Fab")
		)
		(fp_line
			(start 0.67945 0.3048)
			(end 0.67945 -0.305054)
			(stroke
				(width 0.1)
				(type default)
			)
			(layer "B.Fab")
		)
		(pad "1" smd circle
			(at 0.40005 0 180)
			(size 0 0)
			(layers "B.Cu" "B.Mask" "B.Paste")
			(net "SPI_PEX1_SDIO2_R")
		)
		(pad "2" smd circle
			(at -0.40005 0 180)
			(size 0 0)
			(layers "B.Cu" "B.Mask" "B.Paste")
			(net "SPI_PEX1_SDIO2_R1")
		)
	)
	(footprint ""
		(layer "B.Cu")
		(at 214.031576 -369.356386)
		(property "Reference" "PR26"
			(at 0 0 0)
			(layer "B.SilkS")
			(hide yes)
			(effects
				(font
					(size 1.27 1.27)
				)
				(justify mirror)
			)
		)
		(property "Value" ""
			(at 0 0 0)
			(layer "B.Fab")
			(effects
				(font
					(size 1.27 1.27)
				)
				(justify mirror)
			)
		)
		(duplicate_pad_numbers_are_jumpers no)
		(fp_line
			(start -0.7874 -0.4064)
			(end -0.7874 0.4064)
			(stroke
				(width 0.1524)
				(type default)
			)
			(layer "B.SilkS")
		)
		(fp_line
			(start -0.7874 0.4064)
			(end 0.7874 0.4064)
			(stroke
				(width 0.1524)
				(type default)
			)
			(layer "B.SilkS")
		)
		(fp_line
			(start 0.7874 -0.4064)
			(end -0.7874 -0.4064)
			(stroke
				(width 0.1524)
				(type default)
			)
			(layer "B.SilkS")
		)
		(fp_line
			(start 0.7874 0.4064)
			(end 0.7874 -0.4064)
			(stroke
				(width 0.1524)
				(type default)
			)
			(layer "B.SilkS")
		)
		(fp_line
			(start -0.67945 -0.3048)
			(end -0.67945 0.3048)
			(stroke
				(width 0.1)
				(type default)
			)
			(layer "B.Fab")
		)
		(fp_line
			(start -0.67945 0.3048)
			(end -0.120396 0.3048)
			(stroke
				(width 0.1)
				(type default)
			)
			(layer "B.Fab")
		)
		(fp_line
			(start -0.12065 -0.3048)
			(end -0.67945 -0.3048)
			(stroke
				(width 0.1)
				(type default)
			)
			(layer "B.Fab")
		)
		(fp_line
			(start -0.12065 -0.2794)
			(end -0.12065 -0.3048)
			(stroke
				(width 0.1)
				(type default)
			)
			(layer "B.Fab")
		)
		(fp_line
			(start -0.120396 0.2794)
			(end 0.12065 0.2794)
			(stroke
				(width 0.1)
				(type default)
			)
			(layer "B.Fab")
		)
		(fp_line
			(start -0.120396 0.3048)
			(end -0.120396 0.2794)
			(stroke
				(width 0.1)
				(type default)
			)
			(layer "B.Fab")
		)
		(fp_line
			(start 0.12065 -0.305054)
			(end 0.12065 -0.2794)
			(stroke
				(width 0.1)
				(type default)
			)
			(layer "B.Fab")
		)
		(fp_line
			(start 0.12065 -0.2794)
			(end -0.12065 -0.2794)
			(stroke
				(width 0.1)
				(type default)
			)
			(layer "B.Fab")
		)
		(fp_line
			(start 0.12065 0.2794)
			(end 0.12065 0.3048)
			(stroke
				(width 0.1)
				(type default)
			)
			(layer "B.Fab")
		)
		(fp_line
			(start 0.12065 0.3048)
			(end 0.67945 0.3048)
			(stroke
				(width 0.1)
				(type default)
			)
			(layer "B.Fab")
		)
		(fp_line
			(start 0.67945 -0.305054)
			(end 0.12065 -0.305054)
			(stroke
				(width 0.1)
				(type default)
			)
			(layer "B.Fab")
		)
		(fp_line
			(start 0.67945 0.3048)
			(end 0.67945 -0.305054)
			(stroke
				(width 0.1)
				(type default)
			)
			(layer "B.Fab")
		)
		(pad "1" smd circle
			(at 0.40005 0 180)
			(size 0 0)
			(layers "B.Cu" "B.Mask" "B.Paste")
			(net "HSC_VDD_1")
		)
		(pad "2" smd circle
			(at -0.40005 0 180)
			(size 0 0)
			(layers "B.Cu" "B.Mask" "B.Paste")
			(net "HSC_VDD")
		)
	)
	(footprint ""
		(layer "B.Cu")
		(at 56.325008 -293.99992 90)
		(property "Reference" "C1156"
			(at 0 0 90)
			(layer "B.SilkS")
			(hide yes)
			(effects
				(font
					(size 1.27 1.27)
				)
				(justify mirror)
			)
		)
		(property "Value" ""
			(at 0 0 90)
			(layer "B.Fab")
			(effects
				(font
					(size 1.27 1.27)
				)
				(justify mirror)
			)
		)
		(duplicate_pad_numbers_are_jumpers no)
		(fp_line
			(start 0.299974 -0.150114)
			(end -0.299974 -0.150114)
			(stroke
				(width 0.1)
				(type default)
			)
			(layer "B.Fab")
		)
		(fp_line
			(start -0.299974 -0.150114)
			(end -0.299974 0.150114)
			(stroke
				(width 0.1)
				(type default)
			)
			(layer "B.Fab")
		)
		(fp_line
			(start 0.299974 0.150114)
			(end 0.299974 -0.150114)
			(stroke
				(width 0.1)
				(type default)
			)
			(layer "B.Fab")
		)
		(fp_line
			(start -0.299974 0.150114)
			(end 0.299974 0.150114)
			(stroke
				(width 0.1)
				(type default)
			)
			(layer "B.Fab")
		)
		(pad "1" smd rect
			(at 0.2667 0 270)
			(size 0.3048 0.381)
			(layers "B.Cu" "B.Mask" "B.Paste")
			(net "P0V8_PEX0")
		)
		(pad "2" smd rect
			(at -0.2667 0 270)
			(size 0.3048 0.381)
			(layers "B.Cu" "B.Mask" "B.Paste")
			(net "GND")
		)
	)
	(footprint ""
		(layer "B.Cu")
		(at 331.332332 -218.208352)
		(property "Reference" "C2082"
			(at 0 0 0)
			(layer "B.SilkS")
			(hide yes)
			(effects
				(font
					(size 1.27 1.27)
				)
				(justify mirror)
			)
		)
		(property "Value" ""
			(at 0 0 0)
			(layer "B.Fab")
			(effects
				(font
					(size 1.27 1.27)
				)
				(justify mirror)
			)
		)
		(duplicate_pad_numbers_are_jumpers no)
		(fp_line
			(start -0.69215 -0.2921)
			(end -0.69215 0.2921)
			(stroke
				(width 0.1524)
				(type default)
			)
			(layer "B.SilkS")
		)
		(fp_line
			(start -0.69215 0.2921)
			(end 0.69215 0.2921)
			(stroke
				(width 0.1524)
				(type default)
			)
			(layer "B.SilkS")
		)
		(fp_line
			(start 0.69215 -0.2921)
			(end -0.69215 -0.2921)
			(stroke
				(width 0.1524)
				(type default)
			)
			(layer "B.SilkS")
		)
		(fp_line
			(start 0.69215 0.2921)
			(end 0.69215 -0.2921)
			(stroke
				(width 0.1524)
				(type default)
			)
			(layer "B.SilkS")
		)
		(fp_line
			(start -0.51435 -0.2794)
			(end -0.51435 0.2794)
			(stroke
				(width 0.1)
				(type default)
			)
			(layer "B.Fab")
		)
		(fp_line
			(start -0.51435 0.2794)
			(end 0.51435 0.2794)
			(stroke
				(width 0.1)
				(type default)
			)
			(layer "B.Fab")
		)
		(fp_line
			(start 0.51435 -0.2794)
			(end -0.51435 -0.2794)
			(stroke
				(width 0.1)
				(type default)
			)
			(layer "B.Fab")
		)
		(fp_line
			(start 0.51435 0.2794)
			(end 0.51435 -0.2794)
			(stroke
				(width 0.1)
				(type default)
			)
			(layer "B.Fab")
		)
		(pad "1" smd circle
			(at 0.40005 0 180)
			(size 0 0)
			(layers "B.Cu" "B.Mask" "B.Paste")
			(net "P3V3_FPGA_VCCIO4")
		)
		(pad "2" smd circle
			(at -0.40005 0 180)
			(size 0 0)
			(layers "B.Cu" "B.Mask" "B.Paste")
			(net "GND")
		)
		(zone
			(layer "B.Cu")
			(hatch none 0.5)
			(connect_pads
				(clearance 0)
			)
			(min_thickness 0.25)
			(keepout
				(tracks not_allowed)
				(vias allowed)
				(pads allowed)
				(copperpour not_allowed)
				(footprints allowed)
			)
			(placement
				(enabled no)
				(sheetname "")
			)
			(fill
				(thermal_gap 0.5)
				(thermal_bridge_width 0.5)
				(island_removal_mode 0)
			)
			(polygon
				(pts
					(xy 331.522832 -218.120722) (xy 331.431392 -218.062556) (xy 331.232002 -218.062556) (xy 331.141832 -218.120722)
					(xy 331.141832 -218.295982) (xy 331.232002 -218.354402) (xy 331.431392 -218.354402) (xy 331.522832 -218.296236)
				)
			)
		)
	)
	(footprint ""
		(layer "B.Cu")
		(at 417.241482 -287.824926)
		(property "Reference" "C3519"
			(at 0 0 0)
			(layer "B.SilkS")
			(hide yes)
			(effects
				(font
					(size 1.27 1.27)
				)
				(justify mirror)
			)
		)
		(property "Value" ""
			(at 0 0 0)
			(layer "B.Fab")
			(effects
				(font
					(size 1.27 1.27)
				)
				(justify mirror)
			)
		)
		(duplicate_pad_numbers_are_jumpers no)
		(fp_line
			(start -0.299974 -0.150114)
			(end -0.299974 0.150114)
			(stroke
				(width 0.1)
				(type default)
			)
			(layer "B.Fab")
		)
		(fp_line
			(start -0.299974 0.150114)
			(end 0.299974 0.150114)
			(stroke
				(width 0.1)
				(type default)
			)
			(layer "B.Fab")
		)
		(fp_line
			(start 0.299974 -0.150114)
			(end -0.299974 -0.150114)
			(stroke
				(width 0.1)
				(type default)
			)
			(layer "B.Fab")
		)
		(fp_line
			(start 0.299974 0.150114)
			(end 0.299974 -0.150114)
			(stroke
				(width 0.1)
				(type default)
			)
			(layer "B.Fab")
		)
		(pad "1" smd rect
			(at 0.2667 0 180)
			(size 0.3048 0.381)
			(layers "B.Cu" "B.Mask" "B.Paste")
			(net "P1V8_VDDA_PEX3")
		)
		(pad "2" smd rect
			(at -0.2667 0 180)
			(size 0.3048 0.381)
			(layers "B.Cu" "B.Mask" "B.Paste")
			(net "GND")
		)
	)
	(footprint ""
		(layer "B.Cu")
		(at 178.280314 -295.221914)
		(property "Reference" "C1357"
			(at 0 0 0)
			(layer "B.SilkS")
			(hide yes)
			(effects
				(font
					(size 1.27 1.27)
				)
				(justify mirror)
			)
		)
		(property "Value" ""
			(at 0 0 0)
			(layer "B.Fab")
			(effects
				(font
					(size 1.27 1.27)
				)
				(justify mirror)
			)
		)
		(duplicate_pad_numbers_are_jumpers no)
		(fp_line
			(start -1.2954 -0.5842)
			(end -1.2954 0.5842)
			(stroke
				(width 0.1524)
				(type default)
			)
			(layer "B.SilkS")
		)
		(fp_line
			(start -1.2954 0.5842)
			(end 1.2954 0.5842)
			(stroke
				(width 0.1524)
				(type default)
			)
			(layer "B.SilkS")
		)
		(fp_line
			(start 1.2954 -0.5842)
			(end -1.2954 -0.5842)
			(stroke
				(width 0.1524)
				(type default)
			)
			(layer "B.SilkS")
		)
		(fp_line
			(start 1.2954 0.5842)
			(end 1.2954 -0.5842)
			(stroke
				(width 0.1524)
				(type default)
			)
			(layer "B.SilkS")
		)
		(fp_line
			(start -1.1938 -0.4064)
			(end -1.1938 0.4064)
			(stroke
				(width 0.1)
				(type default)
			)
			(layer "B.Fab")
		)
		(fp_line
			(start -1.1938 0.4064)
			(end -0.8636 0.4064)
			(stroke
				(width 0.1)
				(type default)
			)
			(layer "B.Fab")
		)
		(fp_line
			(start -0.8636 -0.4572)
			(end -0.8636 -0.4064)
			(stroke
				(width 0.1)
				(type default)
			)
			(layer "B.Fab")
		)
		(fp_line
			(start -0.8636 -0.4064)
			(end -1.1938 -0.4064)
			(stroke
				(width 0.1)
				(type default)
			)
			(layer "B.Fab")
		)
		(fp_line
			(start -0.8636 0.4064)
			(end -0.8636 0.4572)
			(stroke
				(width 0.1)
				(type default)
			)
			(layer "B.Fab")
		)
		(fp_line
			(start -0.8636 0.4572)
			(end 0.8636 0.4572)
			(stroke
				(width 0.1)
				(type default)
			)
			(layer "B.Fab")
		)
		(fp_line
			(start 0.8636 -0.4572)
			(end -0.8636 -0.4572)
			(stroke
				(width 0.1)
				(type default)
			)
			(layer "B.Fab")
		)
		(fp_line
			(start 0.8636 -0.4064)
			(end 0.8636 -0.4572)
			(stroke
				(width 0.1)
				(type default)
			)
			(layer "B.Fab")
		)
		(fp_line
			(start 0.8636 0.4064)
			(end 1.1938 0.4064)
			(stroke
				(width 0.1)
				(type default)
			)
			(layer "B.Fab")
		)
		(fp_line
			(start 0.8636 0.4572)
			(end 0.8636 0.4064)
			(stroke
				(width 0.1)
				(type default)
			)
			(layer "B.Fab")
		)
		(fp_line
			(start 1.1938 -0.4064)
			(end 0.8636 -0.4064)
			(stroke
				(width 0.1)
				(type default)
			)
			(layer "B.Fab")
		)
		(fp_line
			(start 1.1938 0.4064)
			(end 1.1938 -0.4064)
			(stroke
				(width 0.1)
				(type default)
			)
			(layer "B.Fab")
		)
		(pad "1" smd rect
			(at 0.7366 0 270)
			(size 0.7112 0.8128)
			(layers "B.Cu" "B.Mask" "B.Paste")
			(net "P0V8_PEX1")
		)
		(pad "2" smd rect
			(at -0.7366 0 270)
			(size 0.7112 0.8128)
			(layers "B.Cu" "B.Mask" "B.Paste")
			(net "GND")
		)
	)
	(footprint ""
		(layer "B.Cu")
		(at 346.893896 -226.787202 -90)
		(property "Reference" "C2038"
			(at 0 0 90)
			(layer "B.SilkS")
			(hide yes)
			(effects
				(font
					(size 1.27 1.27)
				)
				(justify mirror)
			)
		)
		(property "Value" ""
			(at 0 0 90)
			(layer "B.Fab")
			(effects
				(font
					(size 1.27 1.27)
				)
				(justify mirror)
			)
		)
		(duplicate_pad_numbers_are_jumpers no)
		(fp_line
			(start -0.69215 0.2921)
			(end 0.69215 0.2921)
			(stroke
				(width 0.1524)
				(type default)
			)
			(layer "B.SilkS")
		)
		(fp_line
			(start 0.69215 0.2921)
			(end 0.69215 -0.2921)
			(stroke
				(width 0.1524)
				(type default)
			)
			(layer "B.SilkS")
		)
		(fp_line
			(start -0.69215 -0.2921)
			(end -0.69215 0.2921)
			(stroke
				(width 0.1524)
				(type default)
			)
			(layer "B.SilkS")
		)
		(fp_line
			(start 0.69215 -0.2921)
			(end -0.69215 -0.2921)
			(stroke
				(width 0.1524)
				(type default)
			)
			(layer "B.SilkS")
		)
		(fp_line
			(start -0.51435 0.2794)
			(end 0.51435 0.2794)
			(stroke
				(width 0.1)
				(type default)
			)
			(layer "B.Fab")
		)
		(fp_line
			(start 0.51435 0.2794)
			(end 0.51435 -0.2794)
			(stroke
				(width 0.1)
				(type default)
			)
			(layer "B.Fab")
		)
		(fp_line
			(start -0.51435 -0.2794)
			(end -0.51435 0.2794)
			(stroke
				(width 0.1)
				(type default)
			)
			(layer "B.Fab")
		)
		(fp_line
			(start 0.51435 -0.2794)
			(end -0.51435 -0.2794)
			(stroke
				(width 0.1)
				(type default)
			)
			(layer "B.Fab")
		)
		(pad "1" smd circle
			(at 0.40005 0 90)
			(size 0 0)
			(layers "B.Cu" "B.Mask" "B.Paste")
			(net "P3V3_FPGA_VCCIO0")
		)
		(pad "2" smd circle
			(at -0.40005 0 90)
			(size 0 0)
			(layers "B.Cu" "B.Mask" "B.Paste")
			(net "GND")
		)
		(zone
			(layer "B.Cu")
			(hatch none 0.5)
			(connect_pads
				(clearance 0)
			)
			(min_thickness 0.25)
			(keepout
				(tracks not_allowed)
				(vias allowed)
				(pads allowed)
				(copperpour not_allowed)
				(footprints allowed)
			)
			(placement
				(enabled no)
				(sheetname "")
			)
			(fill
				(thermal_gap 0.5)
				(thermal_bridge_width 0.5)
				(island_removal_mode 0)
			)
			(polygon
				(pts
					(xy 346.806266 -226.596702) (xy 346.7481 -226.688142) (xy 346.7481 -226.887532) (xy 346.806266 -226.977702)
					(xy 346.981526 -226.977702) (xy 347.039946 -226.887532) (xy 347.039946 -226.688142) (xy 346.98178 -226.596702)
				)
			)
		)
	)
	(footprint ""
		(layer "B.Cu")
		(at 397.49984 -292.574726 180)
		(property "Reference" "C1869"
			(at 0 0 0)
			(layer "B.SilkS")
			(hide yes)
			(effects
				(font
					(size 1.27 1.27)
				)
				(justify mirror)
			)
		)
		(property "Value" ""
			(at 0 0 0)
			(layer "B.Fab")
			(effects
				(font
					(size 1.27 1.27)
				)
				(justify mirror)
			)
		)
		(duplicate_pad_numbers_are_jumpers no)
		(fp_line
			(start 0.299974 0.150114)
			(end 0.299974 -0.150114)
			(stroke
				(width 0.1)
				(type default)
			)
			(layer "B.Fab")
		)
		(fp_line
			(start 0.299974 -0.150114)
			(end -0.299974 -0.150114)
			(stroke
				(width 0.1)
				(type default)
			)
			(layer "B.Fab")
		)
		(fp_line
			(start -0.299974 0.150114)
			(end 0.299974 0.150114)
			(stroke
				(width 0.1)
				(type default)
			)
			(layer "B.Fab")
		)
		(fp_line
			(start -0.299974 -0.150114)
			(end -0.299974 0.150114)
			(stroke
				(width 0.1)
				(type default)
			)
			(layer "B.Fab")
		)
		(pad "1" smd rect
			(at 0.2667 0)
			(size 0.3048 0.381)
			(layers "B.Cu" "B.Mask" "B.Paste")
			(net "P0V8_PEX3")
		)
		(pad "2" smd rect
			(at -0.2667 0)
			(size 0.3048 0.381)
			(layers "B.Cu" "B.Mask" "B.Paste")
			(net "GND")
		)
	)
	(footprint ""
		(layer "B.Cu")
		(at 213.935056 -214.24646 180)
		(property "Reference" "R5530"
			(at 0 0 0)
			(layer "B.SilkS")
			(hide yes)
			(effects
				(font
					(size 1.27 1.27)
				)
				(justify mirror)
			)
		)
		(property "Value" ""
			(at 0 0 0)
			(layer "B.Fab")
			(effects
				(font
					(size 1.27 1.27)
				)
				(justify mirror)
			)
		)
		(duplicate_pad_numbers_are_jumpers no)
		(fp_line
			(start 0.7874 0.4064)
			(end 0.7874 -0.4064)
			(stroke
				(width 0.1524)
				(type default)
			)
			(layer "B.SilkS")
		)
		(fp_line
			(start 0.7874 -0.4064)
			(end -0.7874 -0.4064)
			(stroke
				(width 0.1524)
				(type default)
			)
			(layer "B.SilkS")
		)
		(fp_line
			(start -0.7874 0.4064)
			(end 0.7874 0.4064)
			(stroke
				(width 0.1524)
				(type default)
			)
			(layer "B.SilkS")
		)
		(fp_line
			(start -0.7874 -0.4064)
			(end -0.7874 0.4064)
			(stroke
				(width 0.1524)
				(type default)
			)
			(layer "B.SilkS")
		)
		(fp_line
			(start 0.67945 0.3048)
			(end 0.67945 -0.305054)
			(stroke
				(width 0.1)
				(type default)
			)
			(layer "B.Fab")
		)
		(fp_line
			(start 0.67945 -0.305054)
			(end 0.12065 -0.305054)
			(stroke
				(width 0.1)
				(type default)
			)
			(layer "B.Fab")
		)
		(fp_line
			(start 0.12065 0.3048)
			(end 0.67945 0.3048)
			(stroke
				(width 0.1)
				(type default)
			)
			(layer "B.Fab")
		)
		(fp_line
			(start 0.12065 0.2794)
			(end 0.12065 0.3048)
			(stroke
				(width 0.1)
				(type default)
			)
			(layer "B.Fab")
		)
		(fp_line
			(start 0.12065 -0.2794)
			(end -0.12065 -0.2794)
			(stroke
				(width 0.1)
				(type default)
			)
			(layer "B.Fab")
		)
		(fp_line
			(start 0.12065 -0.305054)
			(end 0.12065 -0.2794)
			(stroke
				(width 0.1)
				(type default)
			)
			(layer "B.Fab")
		)
		(fp_line
			(start -0.120396 0.3048)
			(end -0.120396 0.2794)
			(stroke
				(width 0.1)
				(type default)
			)
			(layer "B.Fab")
		)
		(fp_line
			(start -0.120396 0.2794)
			(end 0.12065 0.2794)
			(stroke
				(width 0.1)
				(type default)
			)
			(layer "B.Fab")
		)
		(fp_line
			(start -0.12065 -0.2794)
			(end -0.12065 -0.3048)
			(stroke
				(width 0.1)
				(type default)
			)
			(layer "B.Fab")
		)
		(fp_line
			(start -0.12065 -0.3048)
			(end -0.67945 -0.3048)
			(stroke
				(width 0.1)
				(type default)
			)
			(layer "B.Fab")
		)
		(fp_line
			(start -0.67945 0.3048)
			(end -0.120396 0.3048)
			(stroke
				(width 0.1)
				(type default)
			)
			(layer "B.Fab")
		)
		(fp_line
			(start -0.67945 -0.3048)
			(end -0.67945 0.3048)
			(stroke
				(width 0.1)
				(type default)
			)
			(layer "B.Fab")
		)
		(pad "1" smd circle
			(at 0.40005 0)
			(size 0 0)
			(layers "B.Cu" "B.Mask" "B.Paste")
			(net "P3V3_AUX")
		)
		(pad "2" smd circle
			(at -0.40005 0)
			(size 0 0)
			(layers "B.Cu" "B.Mask" "B.Paste")
			(net "RST_BIC_USB_HUB_R_N")
		)
	)
	(footprint ""
		(layer "B.Cu")
		(at 234.98683 -351.349056 180)
		(property "Reference" "PR7154"
			(at 0 0 0)
			(layer "B.SilkS")
			(hide yes)
			(effects
				(font
					(size 1.27 1.27)
				)
				(justify mirror)
			)
		)
		(property "Value" ""
			(at 0 0 0)
			(layer "B.Fab")
			(effects
				(font
					(size 1.27 1.27)
				)
				(justify mirror)
			)
		)
		(duplicate_pad_numbers_are_jumpers no)
		(fp_line
			(start 0.7874 0.4064)
			(end 0.7874 -0.4064)
			(stroke
				(width 0.1524)
				(type default)
			)
			(layer "B.SilkS")
		)
		(fp_line
			(start 0.7874 -0.4064)
			(end -0.7874 -0.4064)
			(stroke
				(width 0.1524)
				(type default)
			)
			(layer "B.SilkS")
		)
		(fp_line
			(start -0.7874 0.4064)
			(end 0.7874 0.4064)
			(stroke
				(width 0.1524)
				(type default)
			)
			(layer "B.SilkS")
		)
		(fp_line
			(start -0.7874 -0.4064)
			(end -0.7874 0.4064)
			(stroke
				(width 0.1524)
				(type default)
			)
			(layer "B.SilkS")
		)
		(fp_line
			(start 0.67945 0.3048)
			(end 0.67945 -0.305054)
			(stroke
				(width 0.1)
				(type default)
			)
			(layer "B.Fab")
		)
		(fp_line
			(start 0.67945 -0.305054)
			(end 0.12065 -0.305054)
			(stroke
				(width 0.1)
				(type default)
			)
			(layer "B.Fab")
		)
		(fp_line
			(start 0.12065 0.3048)
			(end 0.67945 0.3048)
			(stroke
				(width 0.1)
				(type default)
			)
			(layer "B.Fab")
		)
		(fp_line
			(start 0.12065 0.2794)
			(end 0.12065 0.3048)
			(stroke
				(width 0.1)
				(type default)
			)
			(layer "B.Fab")
		)
		(fp_line
			(start 0.12065 -0.2794)
			(end -0.12065 -0.2794)
			(stroke
				(width 0.1)
				(type default)
			)
			(layer "B.Fab")
		)
		(fp_line
			(start 0.12065 -0.305054)
			(end 0.12065 -0.2794)
			(stroke
				(width 0.1)
				(type default)
			)
			(layer "B.Fab")
		)
		(fp_line
			(start -0.120396 0.3048)
			(end -0.120396 0.2794)
			(stroke
				(width 0.1)
				(type default)
			)
			(layer "B.Fab")
		)
		(fp_line
			(start -0.120396 0.2794)
			(end 0.12065 0.2794)
			(stroke
				(width 0.1)
				(type default)
			)
			(layer "B.Fab")
		)
		(fp_line
			(start -0.12065 -0.2794)
			(end -0.12065 -0.3048)
			(stroke
				(width 0.1)
				(type default)
			)
			(layer "B.Fab")
		)
		(fp_line
			(start -0.12065 -0.3048)
			(end -0.67945 -0.3048)
			(stroke
				(width 0.1)
				(type default)
			)
			(layer "B.Fab")
		)
		(fp_line
			(start -0.67945 0.3048)
			(end -0.120396 0.3048)
			(stroke
				(width 0.1)
				(type default)
			)
			(layer "B.Fab")
		)
		(fp_line
			(start -0.67945 -0.3048)
			(end -0.67945 0.3048)
			(stroke
				(width 0.1)
				(type default)
			)
			(layer "B.Fab")
		)
		(pad "1" smd circle
			(at 0.40005 0)
			(size 0 0)
			(layers "B.Cu" "B.Mask" "B.Paste")
			(net "P12V_HSC_SENSE2_P")
		)
		(pad "2" smd circle
			(at -0.40005 0)
			(size 0 0)
			(layers "B.Cu" "B.Mask" "B.Paste")
			(net "P12V_HSC_SENSE2_R2_P")
		)
	)
	(footprint ""
		(layer "B.Cu")
		(at 119.587772 -284.796738 -90)
		(property "Reference" "PC93"
			(at 0 0 90)
			(layer "B.SilkS")
			(hide yes)
			(effects
				(font
					(size 1.27 1.27)
				)
				(justify mirror)
			)
		)
		(property "Value" ""
			(at 0 0 90)
			(layer "B.Fab")
			(effects
				(font
					(size 1.27 1.27)
				)
				(justify mirror)
			)
		)
		(duplicate_pad_numbers_are_jumpers no)
		(fp_line
			(start -1.524 0.762)
			(end 1.524 0.762)
			(stroke
				(width 0.1524)
				(type default)
			)
			(layer "B.SilkS")
		)
		(fp_line
			(start 1.524 0.762)
			(end 1.524 -0.762)
			(stroke
				(width 0.1524)
				(type default)
			)
			(layer "B.SilkS")
		)
		(fp_line
			(start -1.524 -0.762)
			(end -1.524 0.762)
			(stroke
				(width 0.1524)
				(type default)
			)
			(layer "B.SilkS")
		)
		(fp_line
			(start 1.524 -0.762)
			(end -1.524 -0.762)
			(stroke
				(width 0.1524)
				(type default)
			)
			(layer "B.SilkS")
		)
		(fp_line
			(start -1.1049 0.724916)
			(end -1.1049 -0.724916)
			(stroke
				(width 0.1)
				(type default)
			)
			(layer "B.Fab")
		)
		(fp_line
			(start 1.1049 0.724916)
			(end -1.1049 0.724916)
			(stroke
				(width 0.1)
				(type default)
			)
			(layer "B.Fab")
		)
		(fp_line
			(start -1.1049 -0.724916)
			(end 1.1049 -0.724916)
			(stroke
				(width 0.1)
				(type default)
			)
			(layer "B.Fab")
		)
		(fp_line
			(start 1.1049 -0.724916)
			(end 1.1049 0.724916)
			(stroke
				(width 0.1)
				(type default)
			)
			(layer "B.Fab")
		)
		(pad "1" smd rect
			(at 0.889 0 270)
			(size 1.016 1.27)
			(layers "B.Cu" "B.Mask" "B.Paste")
			(net "SW_P12V_P0V8_PEX1_FLT")
		)
		(pad "2" smd rect
			(at -0.889 0 270)
			(size 1.016 1.27)
			(layers "B.Cu" "B.Mask" "B.Paste")
			(net "GND")
		)
	)
	(footprint ""
		(layer "B.Cu")
		(at 128.59385 -308.668674 90)
		(property "Reference" "C4264"
			(at 0 0 90)
			(layer "B.SilkS")
			(hide yes)
			(effects
				(font
					(size 1.27 1.27)
				)
				(justify mirror)
			)
		)
		(property "Value" ""
			(at 0 0 90)
			(layer "B.Fab")
			(effects
				(font
					(size 1.27 1.27)
				)
				(justify mirror)
			)
		)
		(duplicate_pad_numbers_are_jumpers no)
		(fp_line
			(start 0.299974 -0.150114)
			(end -0.299974 -0.150114)
			(stroke
				(width 0.1)
				(type default)
			)
			(layer "B.Fab")
		)
		(fp_line
			(start -0.299974 -0.150114)
			(end -0.299974 0.150114)
			(stroke
				(width 0.1)
				(type default)
			)
			(layer "B.Fab")
		)
		(fp_line
			(start 0.299974 0.150114)
			(end 0.299974 -0.150114)
			(stroke
				(width 0.1)
				(type default)
			)
			(layer "B.Fab")
		)
		(fp_line
			(start -0.299974 0.150114)
			(end 0.299974 0.150114)
			(stroke
				(width 0.1)
				(type default)
			)
			(layer "B.Fab")
		)
		(pad "1" smd rect
			(at 0.2667 0 270)
			(size 0.3048 0.381)
			(layers "B.Cu" "B.Mask" "B.Paste")
			(net "P0V8_PEX1")
		)
		(pad "2" smd rect
			(at -0.2667 0 270)
			(size 0.3048 0.381)
			(layers "B.Cu" "B.Mask" "B.Paste")
			(net "GND")
		)
	)
	(footprint ""
		(layer "B.Cu")
		(at 52.049934 -299.699934 -90)
		(property "Reference" "C1182"
			(at 0 0 90)
			(layer "B.SilkS")
			(hide yes)
			(effects
				(font
					(size 1.27 1.27)
				)
				(justify mirror)
			)
		)
		(property "Value" ""
			(at 0 0 90)
			(layer "B.Fab")
			(effects
				(font
					(size 1.27 1.27)
				)
				(justify mirror)
			)
		)
		(duplicate_pad_numbers_are_jumpers no)
		(fp_line
			(start -0.299974 0.150114)
			(end 0.299974 0.150114)
			(stroke
				(width 0.1)
				(type default)
			)
			(layer "B.Fab")
		)
		(fp_line
			(start 0.299974 0.150114)
			(end 0.299974 -0.150114)
			(stroke
				(width 0.1)
				(type default)
			)
			(layer "B.Fab")
		)
		(fp_line
			(start -0.299974 -0.150114)
			(end -0.299974 0.150114)
			(stroke
				(width 0.1)
				(type default)
			)
			(layer "B.Fab")
		)
		(fp_line
			(start 0.299974 -0.150114)
			(end -0.299974 -0.150114)
			(stroke
				(width 0.1)
				(type default)
			)
			(layer "B.Fab")
		)
		(pad "1" smd rect
			(at 0.2667 0 90)
			(size 0.3048 0.381)
			(layers "B.Cu" "B.Mask" "B.Paste")
			(net "P0V8_SERDES_VDDA_PEX0")
		)
		(pad "2" smd rect
			(at -0.2667 0 90)
			(size 0.3048 0.381)
			(layers "B.Cu" "B.Mask" "B.Paste")
			(net "GND")
		)
	)
	(footprint ""
		(layer "B.Cu")
		(at 247.099582 -229.997)
		(property "Reference" "R3482"
			(at 0 0 0)
			(layer "B.SilkS")
			(hide yes)
			(effects
				(font
					(size 1.27 1.27)
				)
				(justify mirror)
			)
		)
		(property "Value" ""
			(at 0 0 0)
			(layer "B.Fab")
			(effects
				(font
					(size 1.27 1.27)
				)
				(justify mirror)
			)
		)
		(duplicate_pad_numbers_are_jumpers no)
		(fp_line
			(start -0.7874 -0.4064)
			(end -0.7874 0.4064)
			(stroke
				(width 0.1524)
				(type default)
			)
			(layer "B.SilkS")
		)
		(fp_line
			(start -0.7874 0.4064)
			(end 0.7874 0.4064)
			(stroke
				(width 0.1524)
				(type default)
			)
			(layer "B.SilkS")
		)
		(fp_line
			(start 0.7874 -0.4064)
			(end -0.7874 -0.4064)
			(stroke
				(width 0.1524)
				(type default)
			)
			(layer "B.SilkS")
		)
		(fp_line
			(start 0.7874 0.4064)
			(end 0.7874 -0.4064)
			(stroke
				(width 0.1524)
				(type default)
			)
			(layer "B.SilkS")
		)
		(fp_line
			(start -0.67945 -0.3048)
			(end -0.67945 0.3048)
			(stroke
				(width 0.1)
				(type default)
			)
			(layer "B.Fab")
		)
		(fp_line
			(start -0.67945 0.3048)
			(end -0.120396 0.3048)
			(stroke
				(width 0.1)
				(type default)
			)
			(layer "B.Fab")
		)
		(fp_line
			(start -0.12065 -0.3048)
			(end -0.67945 -0.3048)
			(stroke
				(width 0.1)
				(type default)
			)
			(layer "B.Fab")
		)
		(fp_line
			(start -0.12065 -0.2794)
			(end -0.12065 -0.3048)
			(stroke
				(width 0.1)
				(type default)
			)
			(layer "B.Fab")
		)
		(fp_line
			(start -0.120396 0.2794)
			(end 0.12065 0.2794)
			(stroke
				(width 0.1)
				(type default)
			)
			(layer "B.Fab")
		)
		(fp_line
			(start -0.120396 0.3048)
			(end -0.120396 0.2794)
			(stroke
				(width 0.1)
				(type default)
			)
			(layer "B.Fab")
		)
		(fp_line
			(start 0.12065 -0.305054)
			(end 0.12065 -0.2794)
			(stroke
				(width 0.1)
				(type default)
			)
			(layer "B.Fab")
		)
		(fp_line
			(start 0.12065 -0.2794)
			(end -0.12065 -0.2794)
			(stroke
				(width 0.1)
				(type default)
			)
			(layer "B.Fab")
		)
		(fp_line
			(start 0.12065 0.2794)
			(end 0.12065 0.3048)
			(stroke
				(width 0.1)
				(type default)
			)
			(layer "B.Fab")
		)
		(fp_line
			(start 0.12065 0.3048)
			(end 0.67945 0.3048)
			(stroke
				(width 0.1)
				(type default)
			)
			(layer "B.Fab")
		)
		(fp_line
			(start 0.67945 -0.305054)
			(end 0.12065 -0.305054)
			(stroke
				(width 0.1)
				(type default)
			)
			(layer "B.Fab")
		)
		(fp_line
			(start 0.67945 0.3048)
			(end 0.67945 -0.305054)
			(stroke
				(width 0.1)
				(type default)
			)
			(layer "B.Fab")
		)
		(pad "1" smd circle
			(at 0.40005 0 180)
			(size 0 0)
			(layers "B.Cu" "B.Mask" "B.Paste")
			(net "SPI_PEX2_SDIO2_R")
		)
		(pad "2" smd circle
			(at -0.40005 0 180)
			(size 0 0)
			(layers "B.Cu" "B.Mask" "B.Paste")
			(net "SPI_PEX2_SDIO2_R1")
		)
	)
	(footprint ""
		(layer "B.Cu")
		(at 237.59922 -278.89708 -90)
		(property "Reference" "C4344"
			(at 0 0 90)
			(layer "B.SilkS")
			(hide yes)
			(effects
				(font
					(size 1.27 1.27)
				)
				(justify mirror)
			)
		)
		(property "Value" ""
			(at 0 0 90)
			(layer "B.Fab")
			(effects
				(font
					(size 1.27 1.27)
				)
				(justify mirror)
			)
		)
		(duplicate_pad_numbers_are_jumpers no)
		(fp_line
			(start -1.2954 0.5842)
			(end 1.2954 0.5842)
			(stroke
				(width 0.1524)
				(type default)
			)
			(layer "B.SilkS")
		)
		(fp_line
			(start 1.2954 0.5842)
			(end 1.2954 -0.5842)
			(stroke
				(width 0.1524)
				(type default)
			)
			(layer "B.SilkS")
		)
		(fp_line
			(start -1.2954 -0.5842)
			(end -1.2954 0.5842)
			(stroke
				(width 0.1524)
				(type default)
			)
			(layer "B.SilkS")
		)
		(fp_line
			(start 1.2954 -0.5842)
			(end -1.2954 -0.5842)
			(stroke
				(width 0.1524)
				(type default)
			)
			(layer "B.SilkS")
		)
		(fp_line
			(start -0.8636 0.4572)
			(end 0.8636 0.4572)
			(stroke
				(width 0.1)
				(type default)
			)
			(layer "B.Fab")
		)
		(fp_line
			(start 0.8636 0.4572)
			(end 0.8636 0.4064)
			(stroke
				(width 0.1)
				(type default)
			)
			(layer "B.Fab")
		)
		(fp_line
			(start -1.1938 0.4064)
			(end -0.8636 0.4064)
			(stroke
				(width 0.1)
				(type default)
			)
			(layer "B.Fab")
		)
		(fp_line
			(start -0.8636 0.4064)
			(end -0.8636 0.4572)
			(stroke
				(width 0.1)
				(type default)
			)
			(layer "B.Fab")
		)
		(fp_line
			(start 0.8636 0.4064)
			(end 1.1938 0.4064)
			(stroke
				(width 0.1)
				(type default)
			)
			(layer "B.Fab")
		)
		(fp_line
			(start 1.1938 0.4064)
			(end 1.1938 -0.4064)
			(stroke
				(width 0.1)
				(type default)
			)
			(layer "B.Fab")
		)
		(fp_line
			(start -1.1938 -0.4064)
			(end -1.1938 0.4064)
			(stroke
				(width 0.1)
				(type default)
			)
			(layer "B.Fab")
		)
		(fp_line
			(start -0.8636 -0.4064)
			(end -1.1938 -0.4064)
			(stroke
				(width 0.1)
				(type default)
			)
			(layer "B.Fab")
		)
		(fp_line
			(start 0.8636 -0.4064)
			(end 0.8636 -0.4572)
			(stroke
				(width 0.1)
				(type default)
			)
			(layer "B.Fab")
		)
		(fp_line
			(start 1.1938 -0.4064)
			(end 0.8636 -0.4064)
			(stroke
				(width 0.1)
				(type default)
			)
			(layer "B.Fab")
		)
		(fp_line
			(start -0.8636 -0.4572)
			(end -0.8636 -0.4064)
			(stroke
				(width 0.1)
				(type default)
			)
			(layer "B.Fab")
		)
		(fp_line
			(start 0.8636 -0.4572)
			(end -0.8636 -0.4572)
			(stroke
				(width 0.1)
				(type default)
			)
			(layer "B.Fab")
		)
		(pad "1" smd rect
			(at 0.7366 0 180)
			(size 0.7112 0.8128)
			(layers "B.Cu" "B.Mask" "B.Paste")
			(net "P1V25_PEX2")
		)
		(pad "2" smd rect
			(at -0.7366 0 180)
			(size 0.7112 0.8128)
			(layers "B.Cu" "B.Mask" "B.Paste")
			(net "GND")
		)
	)
	(footprint ""
		(layer "B.Cu")
		(at 416.051238 -305.399948 -90)
		(property "Reference" "C3494"
			(at 0 0 90)
			(layer "B.SilkS")
			(hide yes)
			(effects
				(font
					(size 1.27 1.27)
				)
				(justify mirror)
			)
		)
		(property "Value" ""
			(at 0 0 90)
			(layer "B.Fab")
			(effects
				(font
					(size 1.27 1.27)
				)
				(justify mirror)
			)
		)
		(duplicate_pad_numbers_are_jumpers no)
		(fp_line
			(start -0.299974 0.150114)
			(end 0.299974 0.150114)
			(stroke
				(width 0.1)
				(type default)
			)
			(layer "B.Fab")
		)
		(fp_line
			(start 0.299974 0.150114)
			(end 0.299974 -0.150114)
			(stroke
				(width 0.1)
				(type default)
			)
			(layer "B.Fab")
		)
		(fp_line
			(start -0.299974 -0.150114)
			(end -0.299974 0.150114)
			(stroke
				(width 0.1)
				(type default)
			)
			(layer "B.Fab")
		)
		(fp_line
			(start 0.299974 -0.150114)
			(end -0.299974 -0.150114)
			(stroke
				(width 0.1)
				(type default)
			)
			(layer "B.Fab")
		)
		(pad "1" smd rect
			(at 0.2667 0 90)
			(size 0.3048 0.381)
			(layers "B.Cu" "B.Mask" "B.Paste")
			(net "P1V25_SERDES_VDDPLL_PEX3")
		)
		(pad "2" smd rect
			(at -0.2667 0 90)
			(size 0.3048 0.381)
			(layers "B.Cu" "B.Mask" "B.Paste")
			(net "GND")
		)
	)
	(footprint ""
		(layer "B.Cu")
		(at 284.249876 -288.299906 90)
		(property "Reference" "C3279"
			(at 0 0 90)
			(layer "B.SilkS")
			(hide yes)
			(effects
				(font
					(size 1.27 1.27)
				)
				(justify mirror)
			)
		)
		(property "Value" ""
			(at 0 0 90)
			(layer "B.Fab")
			(effects
				(font
					(size 1.27 1.27)
				)
				(justify mirror)
			)
		)
		(duplicate_pad_numbers_are_jumpers no)
		(fp_line
			(start 0.299974 -0.150114)
			(end -0.299974 -0.150114)
			(stroke
				(width 0.1)
				(type default)
			)
			(layer "B.Fab")
		)
		(fp_line
			(start -0.299974 -0.150114)
			(end -0.299974 0.150114)
			(stroke
				(width 0.1)
				(type default)
			)
			(layer "B.Fab")
		)
		(fp_line
			(start 0.299974 0.150114)
			(end 0.299974 -0.150114)
			(stroke
				(width 0.1)
				(type default)
			)
			(layer "B.Fab")
		)
		(fp_line
			(start -0.299974 0.150114)
			(end 0.299974 0.150114)
			(stroke
				(width 0.1)
				(type default)
			)
			(layer "B.Fab")
		)
		(pad "1" smd rect
			(at 0.2667 0 270)
			(size 0.3048 0.381)
			(layers "B.Cu" "B.Mask" "B.Paste")
			(net "P1V25_PEX2")
		)
		(pad "2" smd rect
			(at -0.2667 0 270)
			(size 0.3048 0.381)
			(layers "B.Cu" "B.Mask" "B.Paste")
			(net "GND")
		)
	)
	(footprint ""
		(layer "B.Cu")
		(at 177.649886 -288.299906 90)
		(property "Reference" "C3105"
			(at 0 0 90)
			(layer "B.SilkS")
			(hide yes)
			(effects
				(font
					(size 1.27 1.27)
				)
				(justify mirror)
			)
		)
		(property "Value" ""
			(at 0 0 90)
			(layer "B.Fab")
			(effects
				(font
					(size 1.27 1.27)
				)
				(justify mirror)
			)
		)
		(duplicate_pad_numbers_are_jumpers no)
		(fp_line
			(start 0.299974 -0.150114)
			(end -0.299974 -0.150114)
			(stroke
				(width 0.1)
				(type default)
			)
			(layer "B.Fab")
		)
		(fp_line
			(start -0.299974 -0.150114)
			(end -0.299974 0.150114)
			(stroke
				(width 0.1)
				(type default)
			)
			(layer "B.Fab")
		)
		(fp_line
			(start 0.299974 0.150114)
			(end 0.299974 -0.150114)
			(stroke
				(width 0.1)
				(type default)
			)
			(layer "B.Fab")
		)
		(fp_line
			(start -0.299974 0.150114)
			(end 0.299974 0.150114)
			(stroke
				(width 0.1)
				(type default)
			)
			(layer "B.Fab")
		)
		(pad "1" smd rect
			(at 0.2667 0 270)
			(size 0.3048 0.381)
			(layers "B.Cu" "B.Mask" "B.Paste")
			(net "P1V25_PEX1")
		)
		(pad "2" smd rect
			(at -0.2667 0 270)
			(size 0.3048 0.381)
			(layers "B.Cu" "B.Mask" "B.Paste")
			(net "GND")
		)
	)
	(footprint ""
		(layer "B.Cu")
		(at 354.862384 -308.613556 90)
		(property "Reference" "C1925"
			(at 0 0 90)
			(layer "B.SilkS")
			(hide yes)
			(effects
				(font
					(size 1.27 1.27)
				)
				(justify mirror)
			)
		)
		(property "Value" ""
			(at 0 0 90)
			(layer "B.Fab")
			(effects
				(font
					(size 1.27 1.27)
				)
				(justify mirror)
			)
		)
		(duplicate_pad_numbers_are_jumpers no)
		(fp_line
			(start 1.2954 -0.5842)
			(end -1.2954 -0.5842)
			(stroke
				(width 0.1524)
				(type default)
			)
			(layer "B.SilkS")
		)
		(fp_line
			(start -1.2954 -0.5842)
			(end -1.2954 0.5842)
			(stroke
				(width 0.1524)
				(type default)
			)
			(layer "B.SilkS")
		)
		(fp_line
			(start 1.2954 0.5842)
			(end 1.2954 -0.5842)
			(stroke
				(width 0.1524)
				(type default)
			)
			(layer "B.SilkS")
		)
		(fp_line
			(start -1.2954 0.5842)
			(end 1.2954 0.5842)
			(stroke
				(width 0.1524)
				(type default)
			)
			(layer "B.SilkS")
		)
		(fp_line
			(start 0.8636 -0.4572)
			(end -0.8636 -0.4572)
			(stroke
				(width 0.1)
				(type default)
			)
			(layer "B.Fab")
		)
		(fp_line
			(start -0.8636 -0.4572)
			(end -0.8636 -0.4064)
			(stroke
				(width 0.1)
				(type default)
			)
			(layer "B.Fab")
		)
		(fp_line
			(start 1.1938 -0.4064)
			(end 0.8636 -0.4064)
			(stroke
				(width 0.1)
				(type default)
			)
			(layer "B.Fab")
		)
		(fp_line
			(start 0.8636 -0.4064)
			(end 0.8636 -0.4572)
			(stroke
				(width 0.1)
				(type default)
			)
			(layer "B.Fab")
		)
		(fp_line
			(start -0.8636 -0.4064)
			(end -1.1938 -0.4064)
			(stroke
				(width 0.1)
				(type default)
			)
			(layer "B.Fab")
		)
		(fp_line
			(start -1.1938 -0.4064)
			(end -1.1938 0.4064)
			(stroke
				(width 0.1)
				(type default)
			)
			(layer "B.Fab")
		)
		(fp_line
			(start 1.1938 0.4064)
			(end 1.1938 -0.4064)
			(stroke
				(width 0.1)
				(type default)
			)
			(layer "B.Fab")
		)
		(fp_line
			(start 0.8636 0.4064)
			(end 1.1938 0.4064)
			(stroke
				(width 0.1)
				(type default)
			)
			(layer "B.Fab")
		)
		(fp_line
			(start -0.8636 0.4064)
			(end -0.8636 0.4572)
			(stroke
				(width 0.1)
				(type default)
			)
			(layer "B.Fab")
		)
		(fp_line
			(start -1.1938 0.4064)
			(end -0.8636 0.4064)
			(stroke
				(width 0.1)
				(type default)
			)
			(layer "B.Fab")
		)
		(fp_line
			(start 0.8636 0.4572)
			(end 0.8636 0.4064)
			(stroke
				(width 0.1)
				(type default)
			)
			(layer "B.Fab")
		)
		(fp_line
			(start -0.8636 0.4572)
			(end 0.8636 0.4572)
			(stroke
				(width 0.1)
				(type default)
			)
			(layer "B.Fab")
		)
		(pad "1" smd rect
			(at 0.7366 0)
			(size 0.7112 0.8128)
			(layers "B.Cu" "B.Mask" "B.Paste")
			(net "P0V8_SERDES_VDDA_PEX3")
		)
		(pad "2" smd rect
			(at -0.7366 0)
			(size 0.7112 0.8128)
			(layers "B.Cu" "B.Mask" "B.Paste")
			(net "GND")
		)
	)
	(footprint ""
		(layer "B.Cu")
		(at 411.675326 -109.481366 180)
		(property "Reference" "R389"
			(at 0 0 0)
			(layer "B.SilkS")
			(hide yes)
			(effects
				(font
					(size 1.27 1.27)
				)
				(justify mirror)
			)
		)
		(property "Value" ""
			(at 0 0 0)
			(layer "B.Fab")
			(effects
				(font
					(size 1.27 1.27)
				)
				(justify mirror)
			)
		)
		(duplicate_pad_numbers_are_jumpers no)
		(fp_line
			(start 0.7874 0.4064)
			(end 0.7874 -0.4064)
			(stroke
				(width 0.1524)
				(type default)
			)
			(layer "B.SilkS")
		)
		(fp_line
			(start 0.7874 -0.4064)
			(end -0.7874 -0.4064)
			(stroke
				(width 0.1524)
				(type default)
			)
			(layer "B.SilkS")
		)
		(fp_line
			(start -0.7874 0.4064)
			(end 0.7874 0.4064)
			(stroke
				(width 0.1524)
				(type default)
			)
			(layer "B.SilkS")
		)
		(fp_line
			(start -0.7874 -0.4064)
			(end -0.7874 0.4064)
			(stroke
				(width 0.1524)
				(type default)
			)
			(layer "B.SilkS")
		)
		(fp_line
			(start 0.67945 0.3048)
			(end 0.67945 -0.305054)
			(stroke
				(width 0.1)
				(type default)
			)
			(layer "B.Fab")
		)
		(fp_line
			(start 0.67945 -0.305054)
			(end 0.12065 -0.305054)
			(stroke
				(width 0.1)
				(type default)
			)
			(layer "B.Fab")
		)
		(fp_line
			(start 0.12065 0.3048)
			(end 0.67945 0.3048)
			(stroke
				(width 0.1)
				(type default)
			)
			(layer "B.Fab")
		)
		(fp_line
			(start 0.12065 0.2794)
			(end 0.12065 0.3048)
			(stroke
				(width 0.1)
				(type default)
			)
			(layer "B.Fab")
		)
		(fp_line
			(start 0.12065 -0.2794)
			(end -0.12065 -0.2794)
			(stroke
				(width 0.1)
				(type default)
			)
			(layer "B.Fab")
		)
		(fp_line
			(start 0.12065 -0.305054)
			(end 0.12065 -0.2794)
			(stroke
				(width 0.1)
				(type default)
			)
			(layer "B.Fab")
		)
		(fp_line
			(start -0.120396 0.3048)
			(end -0.120396 0.2794)
			(stroke
				(width 0.1)
				(type default)
			)
			(layer "B.Fab")
		)
		(fp_line
			(start -0.120396 0.2794)
			(end 0.12065 0.2794)
			(stroke
				(width 0.1)
				(type default)
			)
			(layer "B.Fab")
		)
		(fp_line
			(start -0.12065 -0.2794)
			(end -0.12065 -0.3048)
			(stroke
				(width 0.1)
				(type default)
			)
			(layer "B.Fab")
		)
		(fp_line
			(start -0.12065 -0.3048)
			(end -0.67945 -0.3048)
			(stroke
				(width 0.1)
				(type default)
			)
			(layer "B.Fab")
		)
		(fp_line
			(start -0.67945 0.3048)
			(end -0.120396 0.3048)
			(stroke
				(width 0.1)
				(type default)
			)
			(layer "B.Fab")
		)
		(fp_line
			(start -0.67945 -0.3048)
			(end -0.67945 0.3048)
			(stroke
				(width 0.1)
				(type default)
			)
			(layer "B.Fab")
		)
		(pad "1" smd circle
			(at 0.40005 0)
			(size 0 0)
			(layers "B.Cu" "B.Mask" "B.Paste")
			(net "NIC7_BIF1_N")
		)
		(pad "2" smd circle
			(at -0.40005 0)
			(size 0 0)
			(layers "B.Cu" "B.Mask" "B.Paste")
			(net "GND")
		)
	)
	(footprint ""
		(layer "B.Cu")
		(at 459.153768 10.715752)
		(property "Reference" "DE15T_4"
			(at 2.796032 3.026918 0)
			(unlocked yes)
			(layer "B.SilkS")
			(effects
				(font
					(size 0.7874 0.5842)
					(thickness 0.1524)
				)
				(justify left mirror)
			)
		)
		(property "Value" ""
			(at 0 0 0)
			(layer "B.Fab")
			(effects
				(font
					(size 1.27 1.27)
				)
				(justify mirror)
			)
		)
		(duplicate_pad_numbers_are_jumpers no)
		(fp_line
			(start -1.2192 -2.1082)
			(end -1.2192 2.1082)
			(stroke
				(width 0.1524)
				(type default)
			)
			(layer "B.SilkS")
		)
		(fp_line
			(start -1.2192 2.1082)
			(end 1.2192 2.1082)
			(stroke
				(width 0.1524)
				(type default)
			)
			(layer "B.SilkS")
		)
		(fp_line
			(start 1.2192 -2.1082)
			(end -1.2192 -2.1082)
			(stroke
				(width 0.1524)
				(type default)
			)
			(layer "B.SilkS")
		)
		(fp_line
			(start 1.2192 2.1082)
			(end 1.2192 -2.1082)
			(stroke
				(width 0.1524)
				(type default)
			)
			(layer "B.SilkS")
		)
		(pad "" np_thru_hole circle
			(at -3.4671 -1.27 270)
			(size 1.0414 1.0414)
			(drill 1.0414)
			(layers "*.Cu" "*.Mask")
			(clearance 0.381)
			(thermal_gap 0.381)
		)
		(pad "" np_thru_hole circle
			(at -3.4671 1.27 270)
			(size 1.0414 1.0414)
			(drill 1.0414)
			(layers "*.Cu" "*.Mask")
			(clearance 0.381)
			(thermal_gap 0.381)
		)
		(pad "" np_thru_hole circle
			(at 2.8829 -1.27 270)
			(size 1.0414 1.0414)
			(drill 1.0414)
			(layers "*.Cu" "*.Mask")
			(clearance 0.381)
			(thermal_gap 0.381)
		)
		(pad "" np_thru_hole circle
			(at 2.8829 1.27 270)
			(size 1.0414 1.0414)
			(drill 1.0414)
			(layers "*.Cu" "*.Mask")
			(clearance 0.381)
			(thermal_gap 0.381)
		)
		(pad "1" smd rect
			(at -0.8255 -0.249936 270)
			(size 0.3048 0.508)
			(layers "B.Cu" "B.Mask" "B.Paste")
			(net "85_10INCH_IN5_DN")
		)
		(pad "2" smd rect
			(at -0.8255 0.249936 270)
			(size 0.3048 0.508)
			(layers "B.Cu" "B.Mask" "B.Paste")
			(net "85_10INCH_IN5_DP")
		)
		(pad "3" smd circle
			(at 0 0 180)
			(size 0 0)
			(layers "B.Cu" "B.Mask" "B.Paste")
			(net "COUPON_GND2")
		)
		(zone
			(layers "F.Cu" "B.Cu" "In1.Cu" "In2.Cu" "In3.Cu" "In4.Cu" "In5.Cu" "In6.Cu"
				"In7.Cu" "In8.Cu" "In9.Cu" "In10.Cu" "In11.Cu" "In12.Cu" "In13.Cu" "In14.Cu"
				"In15.Cu" "In16.Cu"
			)
			(hatch none 0.5)
			(connect_pads
				(clearance 0)
			)
			(min_thickness 0.25)
			(keepout
				(tracks not_allowed)
				(vias allowed)
				(pads allowed)
				(copperpour not_allowed)
				(footprints allowed)
			)
			(placement
				(enabled no)
				(sheetname "")
			)
			(fill
				(thermal_gap 0.5)
				(thermal_bridge_width 0.5)
				(island_removal_mode 0)
			)
			(polygon
				(pts
					(arc
						(start 456.613768 9.445752)
						(mid 454.759568 9.445752)
						(end 456.613768 9.445752)
					)
				)
			)
		)
		(zone
			(layers "F.Cu" "B.Cu" "In1.Cu" "In2.Cu" "In3.Cu" "In4.Cu" "In5.Cu" "In6.Cu"
				"In7.Cu" "In8.Cu" "In9.Cu" "In10.Cu" "In11.Cu" "In12.Cu" "In13.Cu" "In14.Cu"
				"In15.Cu" "In16.Cu"
			)
			(hatch none 0.5)
			(connect_pads
				(clearance 0)
			)
			(min_thickness 0.25)
			(keepout
				(tracks not_allowed)
				(vias allowed)
				(pads allowed)
				(copperpour not_allowed)
				(footprints allowed)
			)
			(placement
				(enabled no)
				(sheetname "")
			)
			(fill
				(thermal_gap 0.5)
				(thermal_bridge_width 0.5)
				(island_removal_mode 0)
			)
			(polygon
				(pts
					(arc
						(start 456.613768 11.985752)
						(mid 454.759568 11.985752)
						(end 456.613768 11.985752)
					)
				)
			)
		)
		(zone
			(layers "F.Cu" "B.Cu" "In1.Cu" "In2.Cu" "In3.Cu" "In4.Cu" "In5.Cu" "In6.Cu"
				"In7.Cu" "In8.Cu" "In9.Cu" "In10.Cu" "In11.Cu" "In12.Cu" "In13.Cu" "In14.Cu"
				"In15.Cu" "In16.Cu"
			)
			(hatch none 0.5)
			(connect_pads
				(clearance 0)
			)
			(min_thickness 0.25)
			(keepout
				(tracks not_allowed)
				(vias allowed)
				(pads allowed)
				(copperpour not_allowed)
				(footprints allowed)
			)
			(placement
				(enabled no)
				(sheetname "")
			)
			(fill
				(thermal_gap 0.5)
				(thermal_bridge_width 0.5)
				(island_removal_mode 0)
			)
			(polygon
				(pts
					(arc
						(start 462.963768 9.445752)
						(mid 461.109568 9.445752)
						(end 462.963768 9.445752)
					)
				)
			)
		)
		(zone
			(layers "F.Cu" "B.Cu" "In1.Cu" "In2.Cu" "In3.Cu" "In4.Cu" "In5.Cu" "In6.Cu"
				"In7.Cu" "In8.Cu" "In9.Cu" "In10.Cu" "In11.Cu" "In12.Cu" "In13.Cu" "In14.Cu"
				"In15.Cu" "In16.Cu"
			)
			(hatch none 0.5)
			(connect_pads
				(clearance 0)
			)
			(min_thickness 0.25)
			(keepout
				(tracks not_allowed)
				(vias allowed)
				(pads allowed)
				(copperpour not_allowed)
				(footprints allowed)
			)
			(placement
				(enabled no)
				(sheetname "")
			)
			(fill
				(thermal_gap 0.5)
				(thermal_bridge_width 0.5)
				(island_removal_mode 0)
			)
			(polygon
				(pts
					(arc
						(start 462.963768 11.985752)
						(mid 461.109568 11.985752)
						(end 462.963768 11.985752)
					)
				)
			)
		)
		(zone
			(layer "B.Cu")
			(hatch none 0.5)
			(connect_pads
				(clearance 0)
			)
			(min_thickness 0.25)
			(keepout
				(tracks not_allowed)
				(vias allowed)
				(pads allowed)
				(copperpour not_allowed)
				(footprints allowed)
			)
			(placement
				(enabled no)
				(sheetname "")
			)
			(fill
				(thermal_gap 0.5)
				(thermal_bridge_width 0.5)
				(island_removal_mode 0)
			)
			(polygon
				(pts
					(xy 458.036168 10.167112) (xy 458.036168 10.262616) (xy 458.633068 10.262616) (xy 458.633068 10.669016)
					(xy 458.036168 10.669016) (xy 458.036168 10.762488) (xy 458.633068 10.762488) (xy 458.633068 11.168888)
					(xy 458.036168 11.168888) (xy 458.036168 11.264392) (xy 458.734668 11.264392) (xy 458.734668 10.167112)
				)
			)
		)
	)
	(footprint ""
		(layer "B.Cu")
		(at 276.649688 -292.099746)
		(property "Reference" "C3349"
			(at 0 0 0)
			(layer "B.SilkS")
			(hide yes)
			(effects
				(font
					(size 1.27 1.27)
				)
				(justify mirror)
			)
		)
		(property "Value" ""
			(at 0 0 0)
			(layer "B.Fab")
			(effects
				(font
					(size 1.27 1.27)
				)
				(justify mirror)
			)
		)
		(duplicate_pad_numbers_are_jumpers no)
		(fp_line
			(start -0.299974 -0.150114)
			(end -0.299974 0.150114)
			(stroke
				(width 0.1)
				(type default)
			)
			(layer "B.Fab")
		)
		(fp_line
			(start -0.299974 0.150114)
			(end 0.299974 0.150114)
			(stroke
				(width 0.1)
				(type default)
			)
			(layer "B.Fab")
		)
		(fp_line
			(start 0.299974 -0.150114)
			(end -0.299974 -0.150114)
			(stroke
				(width 0.1)
				(type default)
			)
			(layer "B.Fab")
		)
		(fp_line
			(start 0.299974 0.150114)
			(end 0.299974 -0.150114)
			(stroke
				(width 0.1)
				(type default)
			)
			(layer "B.Fab")
		)
		(pad "1" smd rect
			(at 0.2667 0 180)
			(size 0.3048 0.381)
			(layers "B.Cu" "B.Mask" "B.Paste")
			(net "P1V8_PEX")
		)
		(pad "2" smd rect
			(at -0.2667 0 180)
			(size 0.3048 0.381)
			(layers "B.Cu" "B.Mask" "B.Paste")
			(net "GND")
		)
	)
	(footprint ""
		(layer "B.Cu")
		(at 338.84362 -282.244292 180)
		(property "Reference" "PR7171"
			(at 0 0 0)
			(layer "B.SilkS")
			(hide yes)
			(effects
				(font
					(size 1.27 1.27)
				)
				(justify mirror)
			)
		)
		(property "Value" ""
			(at 0 0 0)
			(layer "B.Fab")
			(effects
				(font
					(size 1.27 1.27)
				)
				(justify mirror)
			)
		)
		(duplicate_pad_numbers_are_jumpers no)
		(fp_line
			(start 0.7874 0.4064)
			(end 0.7874 -0.4064)
			(stroke
				(width 0.1524)
				(type default)
			)
			(layer "B.SilkS")
		)
		(fp_line
			(start 0.7874 -0.4064)
			(end -0.7874 -0.4064)
			(stroke
				(width 0.1524)
				(type default)
			)
			(layer "B.SilkS")
		)
		(fp_line
			(start -0.7874 0.4064)
			(end 0.7874 0.4064)
			(stroke
				(width 0.1524)
				(type default)
			)
			(layer "B.SilkS")
		)
		(fp_line
			(start -0.7874 -0.4064)
			(end -0.7874 0.4064)
			(stroke
				(width 0.1524)
				(type default)
			)
			(layer "B.SilkS")
		)
		(fp_line
			(start 0.67945 0.3048)
			(end 0.67945 -0.305054)
			(stroke
				(width 0.1)
				(type default)
			)
			(layer "B.Fab")
		)
		(fp_line
			(start 0.67945 -0.305054)
			(end 0.12065 -0.305054)
			(stroke
				(width 0.1)
				(type default)
			)
			(layer "B.Fab")
		)
		(fp_line
			(start 0.12065 0.3048)
			(end 0.67945 0.3048)
			(stroke
				(width 0.1)
				(type default)
			)
			(layer "B.Fab")
		)
		(fp_line
			(start 0.12065 0.2794)
			(end 0.12065 0.3048)
			(stroke
				(width 0.1)
				(type default)
			)
			(layer "B.Fab")
		)
		(fp_line
			(start 0.12065 -0.2794)
			(end -0.12065 -0.2794)
			(stroke
				(width 0.1)
				(type default)
			)
			(layer "B.Fab")
		)
		(fp_line
			(start 0.12065 -0.305054)
			(end 0.12065 -0.2794)
			(stroke
				(width 0.1)
				(type default)
			)
			(layer "B.Fab")
		)
		(fp_line
			(start -0.120396 0.3048)
			(end -0.120396 0.2794)
			(stroke
				(width 0.1)
				(type default)
			)
			(layer "B.Fab")
		)
		(fp_line
			(start -0.120396 0.2794)
			(end 0.12065 0.2794)
			(stroke
				(width 0.1)
				(type default)
			)
			(layer "B.Fab")
		)
		(fp_line
			(start -0.12065 -0.2794)
			(end -0.12065 -0.3048)
			(stroke
				(width 0.1)
				(type default)
			)
			(layer "B.Fab")
		)
		(fp_line
			(start -0.12065 -0.3048)
			(end -0.67945 -0.3048)
			(stroke
				(width 0.1)
				(type default)
			)
			(layer "B.Fab")
		)
		(fp_line
			(start -0.67945 0.3048)
			(end -0.120396 0.3048)
			(stroke
				(width 0.1)
				(type default)
			)
			(layer "B.Fab")
		)
		(fp_line
			(start -0.67945 -0.3048)
			(end -0.67945 0.3048)
			(stroke
				(width 0.1)
				(type default)
			)
			(layer "B.Fab")
		)
		(pad "1" smd circle
			(at 0.40005 0)
			(size 0 0)
			(layers "B.Cu" "B.Mask" "B.Paste")
			(net "P0V8_PEX2_EN1")
		)
		(pad "2" smd circle
			(at -0.40005 0)
			(size 0 0)
			(layers "B.Cu" "B.Mask" "B.Paste")
			(net "P0V8_PEX2_VCC1")
		)
	)
	(footprint ""
		(layer "B.Cu")
		(at 203.707492 -374.031764 -90)
		(property "Reference" "PR5"
			(at 0 0 90)
			(layer "B.SilkS")
			(hide yes)
			(effects
				(font
					(size 1.27 1.27)
				)
				(justify mirror)
			)
		)
		(property "Value" ""
			(at 0 0 90)
			(layer "B.Fab")
			(effects
				(font
					(size 1.27 1.27)
				)
				(justify mirror)
			)
		)
		(duplicate_pad_numbers_are_jumpers no)
		(fp_line
			(start -0.7874 0.4064)
			(end 0.7874 0.4064)
			(stroke
				(width 0.1524)
				(type default)
			)
			(layer "B.SilkS")
		)
		(fp_line
			(start 0.7874 0.4064)
			(end 0.7874 -0.4064)
			(stroke
				(width 0.1524)
				(type default)
			)
			(layer "B.SilkS")
		)
		(fp_line
			(start -0.7874 -0.4064)
			(end -0.7874 0.4064)
			(stroke
				(width 0.1524)
				(type default)
			)
			(layer "B.SilkS")
		)
		(fp_line
			(start 0.7874 -0.4064)
			(end -0.7874 -0.4064)
			(stroke
				(width 0.1524)
				(type default)
			)
			(layer "B.SilkS")
		)
		(fp_line
			(start -0.67945 0.3048)
			(end -0.120396 0.3048)
			(stroke
				(width 0.1)
				(type default)
			)
			(layer "B.Fab")
		)
		(fp_line
			(start -0.120396 0.3048)
			(end -0.120396 0.2794)
			(stroke
				(width 0.1)
				(type default)
			)
			(layer "B.Fab")
		)
		(fp_line
			(start 0.12065 0.3048)
			(end 0.67945 0.3048)
			(stroke
				(width 0.1)
				(type default)
			)
			(layer "B.Fab")
		)
		(fp_line
			(start 0.67945 0.3048)
			(end 0.67945 -0.305054)
			(stroke
				(width 0.1)
				(type default)
			)
			(layer "B.Fab")
		)
		(fp_line
			(start -0.120396 0.2794)
			(end 0.12065 0.2794)
			(stroke
				(width 0.1)
				(type default)
			)
			(layer "B.Fab")
		)
		(fp_line
			(start 0.12065 0.2794)
			(end 0.12065 0.3048)
			(stroke
				(width 0.1)
				(type default)
			)
			(layer "B.Fab")
		)
		(fp_line
			(start -0.12065 -0.2794)
			(end -0.12065 -0.3048)
			(stroke
				(width 0.1)
				(type default)
			)
			(layer "B.Fab")
		)
		(fp_line
			(start 0.12065 -0.2794)
			(end -0.12065 -0.2794)
			(stroke
				(width 0.1)
				(type default)
			)
			(layer "B.Fab")
		)
		(fp_line
			(start -0.67945 -0.3048)
			(end -0.67945 0.3048)
			(stroke
				(width 0.1)
				(type default)
			)
			(layer "B.Fab")
		)
		(fp_line
			(start -0.12065 -0.3048)
			(end -0.67945 -0.3048)
			(stroke
				(width 0.1)
				(type default)
			)
			(layer "B.Fab")
		)
		(fp_line
			(start 0.12065 -0.305054)
			(end 0.12065 -0.2794)
			(stroke
				(width 0.1)
				(type default)
			)
			(layer "B.Fab")
		)
		(fp_line
			(start 0.67945 -0.305054)
			(end 0.12065 -0.305054)
			(stroke
				(width 0.1)
				(type default)
			)
			(layer "B.Fab")
		)
		(pad "1" smd circle
			(at 0.40005 0 90)
			(size 0 0)
			(layers "B.Cu" "B.Mask" "B.Paste")
			(net "HSC_VINSEN")
		)
		(pad "2" smd circle
			(at -0.40005 0 90)
			(size 0 0)
			(layers "B.Cu" "B.Mask" "B.Paste")
			(net "AGND_HSC")
		)
	)
	(footprint ""
		(layer "B.Cu")
		(at 401.299934 -292.099746 90)
		(property "Reference" "C1955"
			(at 0 0 90)
			(layer "B.SilkS")
			(hide yes)
			(effects
				(font
					(size 1.27 1.27)
				)
				(justify mirror)
			)
		)
		(property "Value" ""
			(at 0 0 90)
			(layer "B.Fab")
			(effects
				(font
					(size 1.27 1.27)
				)
				(justify mirror)
			)
		)
		(duplicate_pad_numbers_are_jumpers no)
		(fp_line
			(start 0.299974 -0.150114)
			(end -0.299974 -0.150114)
			(stroke
				(width 0.1)
				(type default)
			)
			(layer "B.Fab")
		)
		(fp_line
			(start -0.299974 -0.150114)
			(end -0.299974 0.150114)
			(stroke
				(width 0.1)
				(type default)
			)
			(layer "B.Fab")
		)
		(fp_line
			(start 0.299974 0.150114)
			(end 0.299974 -0.150114)
			(stroke
				(width 0.1)
				(type default)
			)
			(layer "B.Fab")
		)
		(fp_line
			(start -0.299974 0.150114)
			(end 0.299974 0.150114)
			(stroke
				(width 0.1)
				(type default)
			)
			(layer "B.Fab")
		)
		(pad "1" smd rect
			(at 0.2667 0 270)
			(size 0.3048 0.381)
			(layers "B.Cu" "B.Mask" "B.Paste")
			(net "P0V8_SERDES_VDDA_PEX3")
		)
		(pad "2" smd rect
			(at -0.2667 0 270)
			(size 0.3048 0.381)
			(layers "B.Cu" "B.Mask" "B.Paste")
			(net "GND")
		)
	)
	(footprint ""
		(layer "B.Cu")
		(at 394.164312 -142.795752 180)
		(property "Reference" "C937"
			(at 0 0 0)
			(layer "B.SilkS")
			(hide yes)
			(effects
				(font
					(size 1.27 1.27)
				)
				(justify mirror)
			)
		)
		(property "Value" ""
			(at 0 0 0)
			(layer "B.Fab")
			(effects
				(font
					(size 1.27 1.27)
				)
				(justify mirror)
			)
		)
		(duplicate_pad_numbers_are_jumpers no)
		(fp_line
			(start 0.299974 0.150114)
			(end 0.299974 -0.150114)
			(stroke
				(width 0.1)
				(type default)
			)
			(layer "B.Fab")
		)
		(fp_line
			(start 0.299974 -0.150114)
			(end -0.299974 -0.150114)
			(stroke
				(width 0.1)
				(type default)
			)
			(layer "B.Fab")
		)
		(fp_line
			(start -0.299974 0.150114)
			(end 0.299974 0.150114)
			(stroke
				(width 0.1)
				(type default)
			)
			(layer "B.Fab")
		)
		(fp_line
			(start -0.299974 -0.150114)
			(end -0.299974 0.150114)
			(stroke
				(width 0.1)
				(type default)
			)
			(layer "B.Fab")
		)
		(pad "1" smd rect
			(at 0.2667 0)
			(size 0.3048 0.381)
			(layers "B.Cu" "B.Mask" "B.Paste")
			(net "P12V_NIC6")
		)
		(pad "2" smd rect
			(at -0.2667 0)
			(size 0.3048 0.381)
			(layers "B.Cu" "B.Mask" "B.Paste")
			(net "GND")
		)
	)
	(footprint ""
		(layer "B.Cu")
		(at 302.299878 -290.674806 180)
		(property "Reference" "C3341"
			(at 0 0 0)
			(layer "B.SilkS")
			(hide yes)
			(effects
				(font
					(size 1.27 1.27)
				)
				(justify mirror)
			)
		)
		(property "Value" ""
			(at 0 0 0)
			(layer "B.Fab")
			(effects
				(font
					(size 1.27 1.27)
				)
				(justify mirror)
			)
		)
		(duplicate_pad_numbers_are_jumpers no)
		(fp_line
			(start 0.299974 0.150114)
			(end 0.299974 -0.150114)
			(stroke
				(width 0.1)
				(type default)
			)
			(layer "B.Fab")
		)
		(fp_line
			(start 0.299974 -0.150114)
			(end -0.299974 -0.150114)
			(stroke
				(width 0.1)
				(type default)
			)
			(layer "B.Fab")
		)
		(fp_line
			(start -0.299974 0.150114)
			(end 0.299974 0.150114)
			(stroke
				(width 0.1)
				(type default)
			)
			(layer "B.Fab")
		)
		(fp_line
			(start -0.299974 -0.150114)
			(end -0.299974 0.150114)
			(stroke
				(width 0.1)
				(type default)
			)
			(layer "B.Fab")
		)
		(pad "1" smd rect
			(at 0.2667 0)
			(size 0.3048 0.381)
			(layers "B.Cu" "B.Mask" "B.Paste")
			(net "P1V8_PEX")
		)
		(pad "2" smd rect
			(at -0.2667 0)
			(size 0.3048 0.381)
			(layers "B.Cu" "B.Mask" "B.Paste")
			(net "GND")
		)
	)
	(footprint ""
		(layer "B.Cu")
		(at 183.326024 8.083804 180)
		(property "Reference" "DE12T_1"
			(at 3.6068 -2.962148 180)
			(unlocked yes)
			(layer "B.SilkS")
			(effects
				(font
					(size 0.7874 0.5842)
					(thickness 0.1524)
				)
				(justify left mirror)
			)
		)
		(property "Value" ""
			(at 0 0 0)
			(layer "B.Fab")
			(effects
				(font
					(size 1.27 1.27)
				)
				(justify mirror)
			)
		)
		(duplicate_pad_numbers_are_jumpers no)
		(fp_line
			(start 1.2192 2.1082)
			(end 1.2192 -2.1082)
			(stroke
				(width 0.1524)
				(type default)
			)
			(layer "B.SilkS")
		)
		(fp_line
			(start 1.2192 -2.1082)
			(end -1.2192 -2.1082)
			(stroke
				(width 0.1524)
				(type default)
			)
			(layer "B.SilkS")
		)
		(fp_line
			(start -1.2192 2.1082)
			(end 1.2192 2.1082)
			(stroke
				(width 0.1524)
				(type default)
			)
			(layer "B.SilkS")
		)
		(fp_line
			(start -1.2192 -2.1082)
			(end -1.2192 2.1082)
			(stroke
				(width 0.1524)
				(type default)
			)
			(layer "B.SilkS")
		)
		(pad "" np_thru_hole circle
			(at -3.4671 -1.27 90)
			(size 1.0414 1.0414)
			(drill 1.0414)
			(layers "*.Cu" "*.Mask")
			(clearance 0.381)
			(thermal_gap 0.381)
		)
		(pad "" np_thru_hole circle
			(at -3.4671 1.27 90)
			(size 1.0414 1.0414)
			(drill 1.0414)
			(layers "*.Cu" "*.Mask")
			(clearance 0.381)
			(thermal_gap 0.381)
		)
		(pad "" np_thru_hole circle
			(at 2.8829 -1.27 90)
			(size 1.0414 1.0414)
			(drill 1.0414)
			(layers "*.Cu" "*.Mask")
			(clearance 0.381)
			(thermal_gap 0.381)
		)
		(pad "" np_thru_hole circle
			(at 2.8829 1.27 90)
			(size 1.0414 1.0414)
			(drill 1.0414)
			(layers "*.Cu" "*.Mask")
			(clearance 0.381)
			(thermal_gap 0.381)
		)
		(pad "1" smd rect
			(at -0.8255 -0.249936 90)
			(size 0.3048 0.508)
			(layers "B.Cu" "B.Mask" "B.Paste")
			(net "85_10INCH_BOTTOM_DP")
		)
		(pad "2" smd rect
			(at -0.8255 0.249936 90)
			(size 0.3048 0.508)
			(layers "B.Cu" "B.Mask" "B.Paste")
			(net "85_10INCH_BOTTOM_DN")
		)
		(pad "3" smd circle
			(at 0 0)
			(size 0 0)
			(layers "B.Cu" "B.Mask" "B.Paste")
			(net "COUPON_GND2")
		)
		(zone
			(layers "F.Cu" "B.Cu" "In1.Cu" "In2.Cu" "In3.Cu" "In4.Cu" "In5.Cu" "In6.Cu"
				"In7.Cu" "In8.Cu" "In9.Cu" "In10.Cu" "In11.Cu" "In12.Cu" "In13.Cu" "In14.Cu"
				"In15.Cu" "In16.Cu"
			)
			(hatch none 0.5)
			(connect_pads
				(clearance 0)
			)
			(min_thickness 0.25)
			(keepout
				(tracks not_allowed)
				(vias allowed)
				(pads allowed)
				(copperpour not_allowed)
				(footprints allowed)
			)
			(placement
				(enabled no)
				(sheetname "")
			)
			(fill
				(thermal_gap 0.5)
				(thermal_bridge_width 0.5)
				(island_removal_mode 0)
			)
			(polygon
				(pts
					(arc
						(start 181.370224 6.813804)
						(mid 179.516024 6.813804)
						(end 181.370224 6.813804)
					)
				)
			)
		)
		(zone
			(layers "F.Cu" "B.Cu" "In1.Cu" "In2.Cu" "In3.Cu" "In4.Cu" "In5.Cu" "In6.Cu"
				"In7.Cu" "In8.Cu" "In9.Cu" "In10.Cu" "In11.Cu" "In12.Cu" "In13.Cu" "In14.Cu"
				"In15.Cu" "In16.Cu"
			)
			(hatch none 0.5)
			(connect_pads
				(clearance 0)
			)
			(min_thickness 0.25)
			(keepout
				(tracks not_allowed)
				(vias allowed)
				(pads allowed)
				(copperpour not_allowed)
				(footprints allowed)
			)
			(placement
				(enabled no)
				(sheetname "")
			)
			(fill
				(thermal_gap 0.5)
				(thermal_bridge_width 0.5)
				(island_removal_mode 0)
			)
			(polygon
				(pts
					(arc
						(start 181.370224 9.353804)
						(mid 179.516024 9.353804)
						(end 181.370224 9.353804)
					)
				)
			)
		)
		(zone
			(layers "F.Cu" "B.Cu" "In1.Cu" "In2.Cu" "In3.Cu" "In4.Cu" "In5.Cu" "In6.Cu"
				"In7.Cu" "In8.Cu" "In9.Cu" "In10.Cu" "In11.Cu" "In12.Cu" "In13.Cu" "In14.Cu"
				"In15.Cu" "In16.Cu"
			)
			(hatch none 0.5)
			(connect_pads
				(clearance 0)
			)
			(min_thickness 0.25)
			(keepout
				(tracks not_allowed)
				(vias allowed)
				(pads allowed)
				(copperpour not_allowed)
				(footprints allowed)
			)
			(placement
				(enabled no)
				(sheetname "")
			)
			(fill
				(thermal_gap 0.5)
				(thermal_bridge_width 0.5)
				(island_removal_mode 0)
			)
			(polygon
				(pts
					(arc
						(start 187.720224 6.813804)
						(mid 185.866024 6.813804)
						(end 187.720224 6.813804)
					)
				)
			)
		)
		(zone
			(layers "F.Cu" "B.Cu" "In1.Cu" "In2.Cu" "In3.Cu" "In4.Cu" "In5.Cu" "In6.Cu"
				"In7.Cu" "In8.Cu" "In9.Cu" "In10.Cu" "In11.Cu" "In12.Cu" "In13.Cu" "In14.Cu"
				"In15.Cu" "In16.Cu"
			)
			(hatch none 0.5)
			(connect_pads
				(clearance 0)
			)
			(min_thickness 0.25)
			(keepout
				(tracks not_allowed)
				(vias allowed)
				(pads allowed)
				(copperpour not_allowed)
				(footprints allowed)
			)
			(placement
				(enabled no)
				(sheetname "")
			)
			(fill
				(thermal_gap 0.5)
				(thermal_bridge_width 0.5)
				(island_removal_mode 0)
			)
			(polygon
				(pts
					(arc
						(start 187.720224 9.353804)
						(mid 185.866024 9.353804)
						(end 187.720224 9.353804)
					)
				)
			)
		)
		(zone
			(layer "B.Cu")
			(hatch none 0.5)
			(connect_pads
				(clearance 0)
			)
			(min_thickness 0.25)
			(keepout
				(tracks not_allowed)
				(vias allowed)
				(pads allowed)
				(copperpour not_allowed)
				(footprints allowed)
			)
			(placement
				(enabled no)
				(sheetname "")
			)
			(fill
				(thermal_gap 0.5)
				(thermal_bridge_width 0.5)
				(island_removal_mode 0)
			)
			(polygon
				(pts
					(xy 184.443624 8.632444) (xy 184.443624 8.53694) (xy 183.846724 8.53694) (xy 183.846724 8.13054)
					(xy 184.443624 8.13054) (xy 184.443624 8.037068) (xy 183.846724 8.037068) (xy 183.846724 7.630668)
					(xy 184.443624 7.630668) (xy 184.443624 7.535164) (xy 183.745124 7.535164) (xy 183.745124 8.632444)
				)
			)
		)
	)
	(footprint ""
		(layer "B.Cu")
		(at 403.61997 -305.399948 -90)
		(property "Reference" "C3498"
			(at 0 0 90)
			(layer "B.SilkS")
			(hide yes)
			(effects
				(font
					(size 1.27 1.27)
				)
				(justify mirror)
			)
		)
		(property "Value" ""
			(at 0 0 90)
			(layer "B.Fab")
			(effects
				(font
					(size 1.27 1.27)
				)
				(justify mirror)
			)
		)
		(duplicate_pad_numbers_are_jumpers no)
		(fp_line
			(start -0.299974 0.150114)
			(end 0.299974 0.150114)
			(stroke
				(width 0.1)
				(type default)
			)
			(layer "B.Fab")
		)
		(fp_line
			(start 0.299974 0.150114)
			(end 0.299974 -0.150114)
			(stroke
				(width 0.1)
				(type default)
			)
			(layer "B.Fab")
		)
		(fp_line
			(start -0.299974 -0.150114)
			(end -0.299974 0.150114)
			(stroke
				(width 0.1)
				(type default)
			)
			(layer "B.Fab")
		)
		(fp_line
			(start 0.299974 -0.150114)
			(end -0.299974 -0.150114)
			(stroke
				(width 0.1)
				(type default)
			)
			(layer "B.Fab")
		)
		(pad "1" smd rect
			(at 0.2667 0 90)
			(size 0.3048 0.381)
			(layers "B.Cu" "B.Mask" "B.Paste")
			(net "P1V25_SERDES_VDDPLL_PEX3")
		)
		(pad "2" smd rect
			(at -0.2667 0 90)
			(size 0.3048 0.381)
			(layers "B.Cu" "B.Mask" "B.Paste")
			(net "GND")
		)
	)
	(footprint ""
		(layer "B.Cu")
		(at 143.822674 -214.959184 90)
		(property "Reference" "R988"
			(at 0 0 90)
			(layer "B.SilkS")
			(hide yes)
			(effects
				(font
					(size 1.27 1.27)
				)
				(justify mirror)
			)
		)
		(property "Value" ""
			(at 0 0 90)
			(layer "B.Fab")
			(effects
				(font
					(size 1.27 1.27)
				)
				(justify mirror)
			)
		)
		(duplicate_pad_numbers_are_jumpers no)
		(fp_line
			(start 0.7874 -0.4064)
			(end -0.7874 -0.4064)
			(stroke
				(width 0.1524)
				(type default)
			)
			(layer "B.SilkS")
		)
		(fp_line
			(start -0.7874 -0.4064)
			(end -0.7874 0.4064)
			(stroke
				(width 0.1524)
				(type default)
			)
			(layer "B.SilkS")
		)
		(fp_line
			(start 0.7874 0.4064)
			(end 0.7874 -0.4064)
			(stroke
				(width 0.1524)
				(type default)
			)
			(layer "B.SilkS")
		)
		(fp_line
			(start -0.7874 0.4064)
			(end 0.7874 0.4064)
			(stroke
				(width 0.1524)
				(type default)
			)
			(layer "B.SilkS")
		)
		(fp_line
			(start 0.67945 -0.305054)
			(end 0.12065 -0.305054)
			(stroke
				(width 0.1)
				(type default)
			)
			(layer "B.Fab")
		)
		(fp_line
			(start 0.12065 -0.305054)
			(end 0.12065 -0.2794)
			(stroke
				(width 0.1)
				(type default)
			)
			(layer "B.Fab")
		)
		(fp_line
			(start -0.12065 -0.3048)
			(end -0.67945 -0.3048)
			(stroke
				(width 0.1)
				(type default)
			)
			(layer "B.Fab")
		)
		(fp_line
			(start -0.67945 -0.3048)
			(end -0.67945 0.3048)
			(stroke
				(width 0.1)
				(type default)
			)
			(layer "B.Fab")
		)
		(fp_line
			(start 0.12065 -0.2794)
			(end -0.12065 -0.2794)
			(stroke
				(width 0.1)
				(type default)
			)
			(layer "B.Fab")
		)
		(fp_line
			(start -0.12065 -0.2794)
			(end -0.12065 -0.3048)
			(stroke
				(width 0.1)
				(type default)
			)
			(layer "B.Fab")
		)
		(fp_line
			(start 0.12065 0.2794)
			(end 0.12065 0.3048)
			(stroke
				(width 0.1)
				(type default)
			)
			(layer "B.Fab")
		)
		(fp_line
			(start -0.120396 0.2794)
			(end 0.12065 0.2794)
			(stroke
				(width 0.1)
				(type default)
			)
			(layer "B.Fab")
		)
		(fp_line
			(start 0.67945 0.3048)
			(end 0.67945 -0.305054)
			(stroke
				(width 0.1)
				(type default)
			)
			(layer "B.Fab")
		)
		(fp_line
			(start 0.12065 0.3048)
			(end 0.67945 0.3048)
			(stroke
				(width 0.1)
				(type default)
			)
			(layer "B.Fab")
		)
		(fp_line
			(start -0.120396 0.3048)
			(end -0.120396 0.2794)
			(stroke
				(width 0.1)
				(type default)
			)
			(layer "B.Fab")
		)
		(fp_line
			(start -0.67945 0.3048)
			(end -0.120396 0.3048)
			(stroke
				(width 0.1)
				(type default)
			)
			(layer "B.Fab")
		)
		(pad "1" smd circle
			(at 0.40005 0 270)
			(size 0 0)
			(layers "B.Cu" "B.Mask" "B.Paste")
			(net "UART_PEX2_CLI_BUF_RX")
		)
		(pad "2" smd circle
			(at -0.40005 0 270)
			(size 0 0)
			(layers "B.Cu" "B.Mask" "B.Paste")
			(net "P1V8_PEX")
		)
	)
	(footprint ""
		(layer "B.Cu")
		(at 273.115024 20.575524 180)
		(property "Reference" "DE06F_4"
			(at -2.652776 -2.971546 0)
			(unlocked yes)
			(layer "B.SilkS")
			(effects
				(font
					(size 0.7874 0.5842)
					(thickness 0.1524)
				)
				(justify left mirror)
			)
		)
		(property "Value" ""
			(at 0 0 0)
			(layer "B.Fab")
			(effects
				(font
					(size 1.27 1.27)
				)
				(justify mirror)
			)
		)
		(duplicate_pad_numbers_are_jumpers no)
		(fp_line
			(start 1.2192 2.1082)
			(end 1.2192 -2.1082)
			(stroke
				(width 0.1524)
				(type default)
			)
			(layer "B.SilkS")
		)
		(fp_line
			(start 1.2192 -2.1082)
			(end -1.2192 -2.1082)
			(stroke
				(width 0.1524)
				(type default)
			)
			(layer "B.SilkS")
		)
		(fp_line
			(start -1.2192 2.1082)
			(end 1.2192 2.1082)
			(stroke
				(width 0.1524)
				(type default)
			)
			(layer "B.SilkS")
		)
		(fp_line
			(start -1.2192 -2.1082)
			(end -1.2192 2.1082)
			(stroke
				(width 0.1524)
				(type default)
			)
			(layer "B.SilkS")
		)
		(pad "" np_thru_hole circle
			(at -3.4671 -1.27 90)
			(size 1.0414 1.0414)
			(drill 1.0414)
			(layers "*.Cu" "*.Mask")
			(clearance 0.381)
			(thermal_gap 0.381)
		)
		(pad "" np_thru_hole circle
			(at -3.4671 1.27 90)
			(size 1.0414 1.0414)
			(drill 1.0414)
			(layers "*.Cu" "*.Mask")
			(clearance 0.381)
			(thermal_gap 0.381)
		)
		(pad "" np_thru_hole circle
			(at 2.8829 -1.27 90)
			(size 1.0414 1.0414)
			(drill 1.0414)
			(layers "*.Cu" "*.Mask")
			(clearance 0.381)
			(thermal_gap 0.381)
		)
		(pad "" np_thru_hole circle
			(at 2.8829 1.27 90)
			(size 1.0414 1.0414)
			(drill 1.0414)
			(layers "*.Cu" "*.Mask")
			(clearance 0.381)
			(thermal_gap 0.381)
		)
		(pad "1" smd rect
			(at -0.8255 -0.249936 90)
			(size 0.3048 0.508)
			(layers "B.Cu" "B.Mask" "B.Paste")
			(net "85_5INCH_IN6_DN")
		)
		(pad "2" smd rect
			(at -0.8255 0.249936 90)
			(size 0.3048 0.508)
			(layers "B.Cu" "B.Mask" "B.Paste")
			(net "85_5INCH_IN6_DP")
		)
		(pad "3" smd circle
			(at 0 0)
			(size 0 0)
			(layers "B.Cu" "B.Mask" "B.Paste")
			(net "COUPON_GND2")
		)
		(zone
			(layers "F.Cu" "B.Cu" "In1.Cu" "In2.Cu" "In3.Cu" "In4.Cu" "In5.Cu" "In6.Cu"
				"In7.Cu" "In8.Cu" "In9.Cu" "In10.Cu" "In11.Cu" "In12.Cu" "In13.Cu" "In14.Cu"
				"In15.Cu" "In16.Cu"
			)
			(hatch none 0.5)
			(connect_pads
				(clearance 0)
			)
			(min_thickness 0.25)
			(keepout
				(tracks not_allowed)
				(vias allowed)
				(pads allowed)
				(copperpour not_allowed)
				(footprints allowed)
			)
			(placement
				(enabled no)
				(sheetname "")
			)
			(fill
				(thermal_gap 0.5)
				(thermal_bridge_width 0.5)
				(island_removal_mode 0)
			)
			(polygon
				(pts
					(arc
						(start 271.159224 19.305524)
						(mid 269.305024 19.305524)
						(end 271.159224 19.305524)
					)
				)
			)
		)
		(zone
			(layers "F.Cu" "B.Cu" "In1.Cu" "In2.Cu" "In3.Cu" "In4.Cu" "In5.Cu" "In6.Cu"
				"In7.Cu" "In8.Cu" "In9.Cu" "In10.Cu" "In11.Cu" "In12.Cu" "In13.Cu" "In14.Cu"
				"In15.Cu" "In16.Cu"
			)
			(hatch none 0.5)
			(connect_pads
				(clearance 0)
			)
			(min_thickness 0.25)
			(keepout
				(tracks not_allowed)
				(vias allowed)
				(pads allowed)
				(copperpour not_allowed)
				(footprints allowed)
			)
			(placement
				(enabled no)
				(sheetname "")
			)
			(fill
				(thermal_gap 0.5)
				(thermal_bridge_width 0.5)
				(island_removal_mode 0)
			)
			(polygon
				(pts
					(arc
						(start 271.159224 21.845524)
						(mid 269.305024 21.845524)
						(end 271.159224 21.845524)
					)
				)
			)
		)
		(zone
			(layers "F.Cu" "B.Cu" "In1.Cu" "In2.Cu" "In3.Cu" "In4.Cu" "In5.Cu" "In6.Cu"
				"In7.Cu" "In8.Cu" "In9.Cu" "In10.Cu" "In11.Cu" "In12.Cu" "In13.Cu" "In14.Cu"
				"In15.Cu" "In16.Cu"
			)
			(hatch none 0.5)
			(connect_pads
				(clearance 0)
			)
			(min_thickness 0.25)
			(keepout
				(tracks not_allowed)
				(vias allowed)
				(pads allowed)
				(copperpour not_allowed)
				(footprints allowed)
			)
			(placement
				(enabled no)
				(sheetname "")
			)
			(fill
				(thermal_gap 0.5)
				(thermal_bridge_width 0.5)
				(island_removal_mode 0)
			)
			(polygon
				(pts
					(arc
						(start 277.509224 19.305524)
						(mid 275.655024 19.305524)
						(end 277.509224 19.305524)
					)
				)
			)
		)
		(zone
			(layers "F.Cu" "B.Cu" "In1.Cu" "In2.Cu" "In3.Cu" "In4.Cu" "In5.Cu" "In6.Cu"
				"In7.Cu" "In8.Cu" "In9.Cu" "In10.Cu" "In11.Cu" "In12.Cu" "In13.Cu" "In14.Cu"
				"In15.Cu" "In16.Cu"
			)
			(hatch none 0.5)
			(connect_pads
				(clearance 0)
			)
			(min_thickness 0.25)
			(keepout
				(tracks not_allowed)
				(vias allowed)
				(pads allowed)
				(copperpour not_allowed)
				(footprints allowed)
			)
			(placement
				(enabled no)
				(sheetname "")
			)
			(fill
				(thermal_gap 0.5)
				(thermal_bridge_width 0.5)
				(island_removal_mode 0)
			)
			(polygon
				(pts
					(arc
						(start 277.509224 21.845524)
						(mid 275.655024 21.845524)
						(end 277.509224 21.845524)
					)
				)
			)
		)
		(zone
			(layer "B.Cu")
			(hatch none 0.5)
			(connect_pads
				(clearance 0)
			)
			(min_thickness 0.25)
			(keepout
				(tracks not_allowed)
				(vias allowed)
				(pads allowed)
				(copperpour not_allowed)
				(footprints allowed)
			)
			(placement
				(enabled no)
				(sheetname "")
			)
			(fill
				(thermal_gap 0.5)
				(thermal_bridge_width 0.5)
				(island_removal_mode 0)
			)
			(polygon
				(pts
					(xy 274.232624 21.124164) (xy 274.232624 21.02866) (xy 273.635724 21.02866) (xy 273.635724 20.62226)
					(xy 274.232624 20.62226) (xy 274.232624 20.528788) (xy 273.635724 20.528788) (xy 273.635724 20.122388)
					(xy 274.232624 20.122388) (xy 274.232624 20.026884) (xy 273.534124 20.026884) (xy 273.534124 21.124164)
				)
			)
		)
	)
	(footprint ""
		(layer "B.Cu")
		(at 296.124884 -297.79976 90)
		(property "Reference" "C1656"
			(at 0 0 90)
			(layer "B.SilkS")
			(hide yes)
			(effects
				(font
					(size 1.27 1.27)
				)
				(justify mirror)
			)
		)
		(property "Value" ""
			(at 0 0 90)
			(layer "B.Fab")
			(effects
				(font
					(size 1.27 1.27)
				)
				(justify mirror)
			)
		)
		(duplicate_pad_numbers_are_jumpers no)
		(fp_line
			(start 0.299974 -0.150114)
			(end -0.299974 -0.150114)
			(stroke
				(width 0.1)
				(type default)
			)
			(layer "B.Fab")
		)
		(fp_line
			(start -0.299974 -0.150114)
			(end -0.299974 0.150114)
			(stroke
				(width 0.1)
				(type default)
			)
			(layer "B.Fab")
		)
		(fp_line
			(start 0.299974 0.150114)
			(end 0.299974 -0.150114)
			(stroke
				(width 0.1)
				(type default)
			)
			(layer "B.Fab")
		)
		(fp_line
			(start -0.299974 0.150114)
			(end 0.299974 0.150114)
			(stroke
				(width 0.1)
				(type default)
			)
			(layer "B.Fab")
		)
		(pad "1" smd rect
			(at 0.2667 0 270)
			(size 0.3048 0.381)
			(layers "B.Cu" "B.Mask" "B.Paste")
			(net "P0V8_PEX2")
		)
		(pad "2" smd rect
			(at -0.2667 0 270)
			(size 0.3048 0.381)
			(layers "B.Cu" "B.Mask" "B.Paste")
			(net "GND")
		)
	)
	(footprint ""
		(layer "B.Cu")
		(at 61.549788 -301.599854 -90)
		(property "Reference" "C1238"
			(at 0 0 90)
			(layer "B.SilkS")
			(hide yes)
			(effects
				(font
					(size 1.27 1.27)
				)
				(justify mirror)
			)
		)
		(property "Value" ""
			(at 0 0 90)
			(layer "B.Fab")
			(effects
				(font
					(size 1.27 1.27)
				)
				(justify mirror)
			)
		)
		(duplicate_pad_numbers_are_jumpers no)
		(fp_line
			(start -0.299974 0.150114)
			(end 0.299974 0.150114)
			(stroke
				(width 0.1)
				(type default)
			)
			(layer "B.Fab")
		)
		(fp_line
			(start 0.299974 0.150114)
			(end 0.299974 -0.150114)
			(stroke
				(width 0.1)
				(type default)
			)
			(layer "B.Fab")
		)
		(fp_line
			(start -0.299974 -0.150114)
			(end -0.299974 0.150114)
			(stroke
				(width 0.1)
				(type default)
			)
			(layer "B.Fab")
		)
		(fp_line
			(start 0.299974 -0.150114)
			(end -0.299974 -0.150114)
			(stroke
				(width 0.1)
				(type default)
			)
			(layer "B.Fab")
		)
		(pad "1" smd rect
			(at 0.2667 0 90)
			(size 0.3048 0.381)
			(layers "B.Cu" "B.Mask" "B.Paste")
			(net "P0V8_SERDES_VDDA_PEX0")
		)
		(pad "2" smd rect
			(at -0.2667 0 90)
			(size 0.3048 0.381)
			(layers "B.Cu" "B.Mask" "B.Paste")
			(net "GND")
		)
	)
	(footprint ""
		(layer "B.Cu")
		(at 64.399922 -301.599854 -90)
		(property "Reference" "C1204"
			(at 0 0 90)
			(layer "B.SilkS")
			(hide yes)
			(effects
				(font
					(size 1.27 1.27)
				)
				(justify mirror)
			)
		)
		(property "Value" ""
			(at 0 0 90)
			(layer "B.Fab")
			(effects
				(font
					(size 1.27 1.27)
				)
				(justify mirror)
			)
		)
		(duplicate_pad_numbers_are_jumpers no)
		(fp_line
			(start -0.299974 0.150114)
			(end 0.299974 0.150114)
			(stroke
				(width 0.1)
				(type default)
			)
			(layer "B.Fab")
		)
		(fp_line
			(start 0.299974 0.150114)
			(end 0.299974 -0.150114)
			(stroke
				(width 0.1)
				(type default)
			)
			(layer "B.Fab")
		)
		(fp_line
			(start -0.299974 -0.150114)
			(end -0.299974 0.150114)
			(stroke
				(width 0.1)
				(type default)
			)
			(layer "B.Fab")
		)
		(fp_line
			(start 0.299974 -0.150114)
			(end -0.299974 -0.150114)
			(stroke
				(width 0.1)
				(type default)
			)
			(layer "B.Fab")
		)
		(pad "1" smd rect
			(at 0.2667 0 90)
			(size 0.3048 0.381)
			(layers "B.Cu" "B.Mask" "B.Paste")
			(net "P0V8_SERDES_VDDA_PEX0")
		)
		(pad "2" smd rect
			(at -0.2667 0 90)
			(size 0.3048 0.381)
			(layers "B.Cu" "B.Mask" "B.Paste")
			(net "GND")
		)
	)
	(footprint ""
		(layer "B.Cu")
		(at 227.776024 -272.92554 180)
		(property "Reference" "C4274"
			(at 0 0 0)
			(layer "B.SilkS")
			(hide yes)
			(effects
				(font
					(size 1.27 1.27)
				)
				(justify mirror)
			)
		)
		(property "Value" ""
			(at 0 0 0)
			(layer "B.Fab")
			(effects
				(font
					(size 1.27 1.27)
				)
				(justify mirror)
			)
		)
		(duplicate_pad_numbers_are_jumpers no)
		(fp_line
			(start 1.2954 0.5842)
			(end 1.2954 -0.5842)
			(stroke
				(width 0.1524)
				(type default)
			)
			(layer "B.SilkS")
		)
		(fp_line
			(start 1.2954 -0.5842)
			(end -1.2954 -0.5842)
			(stroke
				(width 0.1524)
				(type default)
			)
			(layer "B.SilkS")
		)
		(fp_line
			(start -1.2954 0.5842)
			(end 1.2954 0.5842)
			(stroke
				(width 0.1524)
				(type default)
			)
			(layer "B.SilkS")
		)
		(fp_line
			(start -1.2954 -0.5842)
			(end -1.2954 0.5842)
			(stroke
				(width 0.1524)
				(type default)
			)
			(layer "B.SilkS")
		)
		(fp_line
			(start 1.1938 0.4064)
			(end 1.1938 -0.4064)
			(stroke
				(width 0.1)
				(type default)
			)
			(layer "B.Fab")
		)
		(fp_line
			(start 1.1938 -0.4064)
			(end 0.8636 -0.4064)
			(stroke
				(width 0.1)
				(type default)
			)
			(layer "B.Fab")
		)
		(fp_line
			(start 0.8636 0.4572)
			(end 0.8636 0.4064)
			(stroke
				(width 0.1)
				(type default)
			)
			(layer "B.Fab")
		)
		(fp_line
			(start 0.8636 0.4064)
			(end 1.1938 0.4064)
			(stroke
				(width 0.1)
				(type default)
			)
			(layer "B.Fab")
		)
		(fp_line
			(start 0.8636 -0.4064)
			(end 0.8636 -0.4572)
			(stroke
				(width 0.1)
				(type default)
			)
			(layer "B.Fab")
		)
		(fp_line
			(start 0.8636 -0.4572)
			(end -0.8636 -0.4572)
			(stroke
				(width 0.1)
				(type default)
			)
			(layer "B.Fab")
		)
		(fp_line
			(start -0.8636 0.4572)
			(end 0.8636 0.4572)
			(stroke
				(width 0.1)
				(type default)
			)
			(layer "B.Fab")
		)
		(fp_line
			(start -0.8636 0.4064)
			(end -0.8636 0.4572)
			(stroke
				(width 0.1)
				(type default)
			)
			(layer "B.Fab")
		)
		(fp_line
			(start -0.8636 -0.4064)
			(end -1.1938 -0.4064)
			(stroke
				(width 0.1)
				(type default)
			)
			(layer "B.Fab")
		)
		(fp_line
			(start -0.8636 -0.4572)
			(end -0.8636 -0.4064)
			(stroke
				(width 0.1)
				(type default)
			)
			(layer "B.Fab")
		)
		(fp_line
			(start -1.1938 0.4064)
			(end -0.8636 0.4064)
			(stroke
				(width 0.1)
				(type default)
			)
			(layer "B.Fab")
		)
		(fp_line
			(start -1.1938 -0.4064)
			(end -1.1938 0.4064)
			(stroke
				(width 0.1)
				(type default)
			)
			(layer "B.Fab")
		)
		(pad "1" smd rect
			(at 0.7366 0 90)
			(size 0.7112 0.8128)
			(layers "B.Cu" "B.Mask" "B.Paste")
			(net "P1V25_PEX1")
		)
		(pad "2" smd rect
			(at -0.7366 0 90)
			(size 0.7112 0.8128)
			(layers "B.Cu" "B.Mask" "B.Paste")
			(net "GND")
		)
	)
	(footprint ""
		(layer "B.Cu")
		(at 339.327744 -323.15531 -90)
		(property "Reference" "R6506"
			(at 0 0 90)
			(layer "B.SilkS")
			(hide yes)
			(effects
				(font
					(size 1.27 1.27)
				)
				(justify mirror)
			)
		)
		(property "Value" ""
			(at 0 0 90)
			(layer "B.Fab")
			(effects
				(font
					(size 1.27 1.27)
				)
				(justify mirror)
			)
		)
		(duplicate_pad_numbers_are_jumpers no)
		(fp_line
			(start -0.7874 0.4064)
			(end 0.7874 0.4064)
			(stroke
				(width 0.1524)
				(type default)
			)
			(layer "B.SilkS")
		)
		(fp_line
			(start 0.7874 0.4064)
			(end 0.7874 -0.4064)
			(stroke
				(width 0.1524)
				(type default)
			)
			(layer "B.SilkS")
		)
		(fp_line
			(start -0.7874 -0.4064)
			(end -0.7874 0.4064)
			(stroke
				(width 0.1524)
				(type default)
			)
			(layer "B.SilkS")
		)
		(fp_line
			(start 0.7874 -0.4064)
			(end -0.7874 -0.4064)
			(stroke
				(width 0.1524)
				(type default)
			)
			(layer "B.SilkS")
		)
		(fp_line
			(start -0.67945 0.3048)
			(end -0.120396 0.3048)
			(stroke
				(width 0.1)
				(type default)
			)
			(layer "B.Fab")
		)
		(fp_line
			(start -0.120396 0.3048)
			(end -0.120396 0.2794)
			(stroke
				(width 0.1)
				(type default)
			)
			(layer "B.Fab")
		)
		(fp_line
			(start 0.12065 0.3048)
			(end 0.67945 0.3048)
			(stroke
				(width 0.1)
				(type default)
			)
			(layer "B.Fab")
		)
		(fp_line
			(start 0.67945 0.3048)
			(end 0.67945 -0.305054)
			(stroke
				(width 0.1)
				(type default)
			)
			(layer "B.Fab")
		)
		(fp_line
			(start -0.120396 0.2794)
			(end 0.12065 0.2794)
			(stroke
				(width 0.1)
				(type default)
			)
			(layer "B.Fab")
		)
		(fp_line
			(start 0.12065 0.2794)
			(end 0.12065 0.3048)
			(stroke
				(width 0.1)
				(type default)
			)
			(layer "B.Fab")
		)
		(fp_line
			(start -0.12065 -0.2794)
			(end -0.12065 -0.3048)
			(stroke
				(width 0.1)
				(type default)
			)
			(layer "B.Fab")
		)
		(fp_line
			(start 0.12065 -0.2794)
			(end -0.12065 -0.2794)
			(stroke
				(width 0.1)
				(type default)
			)
			(layer "B.Fab")
		)
		(fp_line
			(start -0.67945 -0.3048)
			(end -0.67945 0.3048)
			(stroke
				(width 0.1)
				(type default)
			)
			(layer "B.Fab")
		)
		(fp_line
			(start -0.12065 -0.3048)
			(end -0.67945 -0.3048)
			(stroke
				(width 0.1)
				(type default)
			)
			(layer "B.Fab")
		)
		(fp_line
			(start 0.12065 -0.305054)
			(end 0.12065 -0.2794)
			(stroke
				(width 0.1)
				(type default)
			)
			(layer "B.Fab")
		)
		(fp_line
			(start 0.67945 -0.305054)
			(end 0.12065 -0.305054)
			(stroke
				(width 0.1)
				(type default)
			)
			(layer "B.Fab")
		)
		(pad "1" smd circle
			(at 0.40005 0 90)
			(size 0 0)
			(layers "B.Cu" "B.Mask" "B.Paste")
			(net "P0V8_SERDES_VDDA_PEX2")
		)
		(pad "2" smd circle
			(at -0.40005 0 90)
			(size 0 0)
			(layers "B.Cu" "B.Mask" "B.Paste")
			(net "P0V8_SERDES_VDDA_PEX2_C1")
		)
	)
	(footprint ""
		(layer "B.Cu")
		(at 394.42644 -140.8176 180)
		(property "Reference" "C942"
			(at 0 0 0)
			(layer "B.SilkS")
			(hide yes)
			(effects
				(font
					(size 1.27 1.27)
				)
				(justify mirror)
			)
		)
		(property "Value" ""
			(at 0 0 0)
			(layer "B.Fab")
			(effects
				(font
					(size 1.27 1.27)
				)
				(justify mirror)
			)
		)
		(duplicate_pad_numbers_are_jumpers no)
		(fp_line
			(start 0.7874 0.4064)
			(end 0.7874 -0.4064)
			(stroke
				(width 0.1524)
				(type default)
			)
			(layer "B.SilkS")
		)
		(fp_line
			(start 0.7874 -0.4064)
			(end -0.7874 -0.4064)
			(stroke
				(width 0.1524)
				(type default)
			)
			(layer "B.SilkS")
		)
		(fp_line
			(start -0.7874 0.4064)
			(end 0.7874 0.4064)
			(stroke
				(width 0.1524)
				(type default)
			)
			(layer "B.SilkS")
		)
		(fp_line
			(start -0.7874 -0.4064)
			(end -0.7874 0.4064)
			(stroke
				(width 0.1524)
				(type default)
			)
			(layer "B.SilkS")
		)
		(fp_line
			(start 0.67945 0.3048)
			(end 0.67945 -0.305054)
			(stroke
				(width 0.1)
				(type default)
			)
			(layer "B.Fab")
		)
		(fp_line
			(start 0.67945 -0.305054)
			(end 0.12065 -0.305054)
			(stroke
				(width 0.1)
				(type default)
			)
			(layer "B.Fab")
		)
		(fp_line
			(start 0.12065 0.3048)
			(end 0.67945 0.3048)
			(stroke
				(width 0.1)
				(type default)
			)
			(layer "B.Fab")
		)
		(fp_line
			(start 0.12065 0.2794)
			(end 0.12065 0.3048)
			(stroke
				(width 0.1)
				(type default)
			)
			(layer "B.Fab")
		)
		(fp_line
			(start 0.12065 -0.2794)
			(end -0.12065 -0.2794)
			(stroke
				(width 0.1)
				(type default)
			)
			(layer "B.Fab")
		)
		(fp_line
			(start 0.12065 -0.305054)
			(end 0.12065 -0.2794)
			(stroke
				(width 0.1)
				(type default)
			)
			(layer "B.Fab")
		)
		(fp_line
			(start -0.120396 0.3048)
			(end -0.120396 0.2794)
			(stroke
				(width 0.1)
				(type default)
			)
			(layer "B.Fab")
		)
		(fp_line
			(start -0.120396 0.2794)
			(end 0.12065 0.2794)
			(stroke
				(width 0.1)
				(type default)
			)
			(layer "B.Fab")
		)
		(fp_line
			(start -0.12065 -0.2794)
			(end -0.12065 -0.3048)
			(stroke
				(width 0.1)
				(type default)
			)
			(layer "B.Fab")
		)
		(fp_line
			(start -0.12065 -0.3048)
			(end -0.67945 -0.3048)
			(stroke
				(width 0.1)
				(type default)
			)
			(layer "B.Fab")
		)
		(fp_line
			(start -0.67945 0.3048)
			(end -0.120396 0.3048)
			(stroke
				(width 0.1)
				(type default)
			)
			(layer "B.Fab")
		)
		(fp_line
			(start -0.67945 -0.3048)
			(end -0.67945 0.3048)
			(stroke
				(width 0.1)
				(type default)
			)
			(layer "B.Fab")
		)
		(pad "1" smd circle
			(at 0.40005 0)
			(size 0 0)
			(layers "B.Cu" "B.Mask" "B.Paste")
			(net "P3V3_NIC6")
		)
		(pad "2" smd circle
			(at -0.40005 0)
			(size 0 0)
			(layers "B.Cu" "B.Mask" "B.Paste")
			(net "GND")
		)
	)
	(footprint ""
		(layer "B.Cu")
		(at 51.145694 -296.37482)
		(property "Reference" "C1129"
			(at 0 0 0)
			(layer "B.SilkS")
			(hide yes)
			(effects
				(font
					(size 1.27 1.27)
				)
				(justify mirror)
			)
		)
		(property "Value" ""
			(at 0 0 0)
			(layer "B.Fab")
			(effects
				(font
					(size 1.27 1.27)
				)
				(justify mirror)
			)
		)
		(duplicate_pad_numbers_are_jumpers no)
		(fp_line
			(start -0.299974 -0.150114)
			(end -0.299974 0.150114)
			(stroke
				(width 0.1)
				(type default)
			)
			(layer "B.Fab")
		)
		(fp_line
			(start -0.299974 0.150114)
			(end 0.299974 0.150114)
			(stroke
				(width 0.1)
				(type default)
			)
			(layer "B.Fab")
		)
		(fp_line
			(start 0.299974 -0.150114)
			(end -0.299974 -0.150114)
			(stroke
				(width 0.1)
				(type default)
			)
			(layer "B.Fab")
		)
		(fp_line
			(start 0.299974 0.150114)
			(end 0.299974 -0.150114)
			(stroke
				(width 0.1)
				(type default)
			)
			(layer "B.Fab")
		)
		(pad "1" smd rect
			(at 0.2667 0 180)
			(size 0.3048 0.381)
			(layers "B.Cu" "B.Mask" "B.Paste")
			(net "P0V8_PEX0")
		)
		(pad "2" smd rect
			(at -0.2667 0 180)
			(size 0.3048 0.381)
			(layers "B.Cu" "B.Mask" "B.Paste")
			(net "GND")
		)
	)
	(footprint ""
		(layer "B.Cu")
		(at 276.649688 -294.94988)
		(property "Reference" "C3348"
			(at 0 0 0)
			(layer "B.SilkS")
			(hide yes)
			(effects
				(font
					(size 1.27 1.27)
				)
				(justify mirror)
			)
		)
		(property "Value" ""
			(at 0 0 0)
			(layer "B.Fab")
			(effects
				(font
					(size 1.27 1.27)
				)
				(justify mirror)
			)
		)
		(duplicate_pad_numbers_are_jumpers no)
		(fp_line
			(start -0.299974 -0.150114)
			(end -0.299974 0.150114)
			(stroke
				(width 0.1)
				(type default)
			)
			(layer "B.Fab")
		)
		(fp_line
			(start -0.299974 0.150114)
			(end 0.299974 0.150114)
			(stroke
				(width 0.1)
				(type default)
			)
			(layer "B.Fab")
		)
		(fp_line
			(start 0.299974 -0.150114)
			(end -0.299974 -0.150114)
			(stroke
				(width 0.1)
				(type default)
			)
			(layer "B.Fab")
		)
		(fp_line
			(start 0.299974 0.150114)
			(end 0.299974 -0.150114)
			(stroke
				(width 0.1)
				(type default)
			)
			(layer "B.Fab")
		)
		(pad "1" smd rect
			(at 0.2667 0 180)
			(size 0.3048 0.381)
			(layers "B.Cu" "B.Mask" "B.Paste")
			(net "P1V8_PEX")
		)
		(pad "2" smd rect
			(at -0.2667 0 180)
			(size 0.3048 0.381)
			(layers "B.Cu" "B.Mask" "B.Paste")
			(net "GND")
		)
	)
	(footprint ""
		(layer "B.Cu")
		(at 63.449962 -299.699934 -90)
		(property "Reference" "C1232"
			(at 0 0 90)
			(layer "B.SilkS")
			(hide yes)
			(effects
				(font
					(size 1.27 1.27)
				)
				(justify mirror)
			)
		)
		(property "Value" ""
			(at 0 0 90)
			(layer "B.Fab")
			(effects
				(font
					(size 1.27 1.27)
				)
				(justify mirror)
			)
		)
		(duplicate_pad_numbers_are_jumpers no)
		(fp_line
			(start -0.299974 0.150114)
			(end 0.299974 0.150114)
			(stroke
				(width 0.1)
				(type default)
			)
			(layer "B.Fab")
		)
		(fp_line
			(start 0.299974 0.150114)
			(end 0.299974 -0.150114)
			(stroke
				(width 0.1)
				(type default)
			)
			(layer "B.Fab")
		)
		(fp_line
			(start -0.299974 -0.150114)
			(end -0.299974 0.150114)
			(stroke
				(width 0.1)
				(type default)
			)
			(layer "B.Fab")
		)
		(fp_line
			(start 0.299974 -0.150114)
			(end -0.299974 -0.150114)
			(stroke
				(width 0.1)
				(type default)
			)
			(layer "B.Fab")
		)
		(pad "1" smd rect
			(at 0.2667 0 90)
			(size 0.3048 0.381)
			(layers "B.Cu" "B.Mask" "B.Paste")
			(net "P0V8_SERDES_VDDA_PEX0")
		)
		(pad "2" smd rect
			(at -0.2667 0 90)
			(size 0.3048 0.381)
			(layers "B.Cu" "B.Mask" "B.Paste")
			(net "GND")
		)
	)
	(footprint ""
		(layer "B.Cu")
		(at 283.299916 -303.499774 -90)
		(property "Reference" "C3264"
			(at 0 0 90)
			(layer "B.SilkS")
			(hide yes)
			(effects
				(font
					(size 1.27 1.27)
				)
				(justify mirror)
			)
		)
		(property "Value" ""
			(at 0 0 90)
			(layer "B.Fab")
			(effects
				(font
					(size 1.27 1.27)
				)
				(justify mirror)
			)
		)
		(duplicate_pad_numbers_are_jumpers no)
		(fp_line
			(start -0.299974 0.150114)
			(end 0.299974 0.150114)
			(stroke
				(width 0.1)
				(type default)
			)
			(layer "B.Fab")
		)
		(fp_line
			(start 0.299974 0.150114)
			(end 0.299974 -0.150114)
			(stroke
				(width 0.1)
				(type default)
			)
			(layer "B.Fab")
		)
		(fp_line
			(start -0.299974 -0.150114)
			(end -0.299974 0.150114)
			(stroke
				(width 0.1)
				(type default)
			)
			(layer "B.Fab")
		)
		(fp_line
			(start 0.299974 -0.150114)
			(end -0.299974 -0.150114)
			(stroke
				(width 0.1)
				(type default)
			)
			(layer "B.Fab")
		)
		(pad "1" smd rect
			(at 0.2667 0 90)
			(size 0.3048 0.381)
			(layers "B.Cu" "B.Mask" "B.Paste")
			(net "P1V25_PEX2")
		)
		(pad "2" smd rect
			(at -0.2667 0 90)
			(size 0.3048 0.381)
			(layers "B.Cu" "B.Mask" "B.Paste")
			(net "GND")
		)
	)
	(footprint ""
		(layer "B.Cu")
		(at 371.475 -228.346 90)
		(property "Reference" "R3499"
			(at 0 0 90)
			(layer "B.SilkS")
			(hide yes)
			(effects
				(font
					(size 1.27 1.27)
				)
				(justify mirror)
			)
		)
		(property "Value" ""
			(at 0 0 90)
			(layer "B.Fab")
			(effects
				(font
					(size 1.27 1.27)
				)
				(justify mirror)
			)
		)
		(duplicate_pad_numbers_are_jumpers no)
		(fp_line
			(start 0.7874 -0.4064)
			(end -0.7874 -0.4064)
			(stroke
				(width 0.1524)
				(type default)
			)
			(layer "B.SilkS")
		)
		(fp_line
			(start -0.7874 -0.4064)
			(end -0.7874 0.4064)
			(stroke
				(width 0.1524)
				(type default)
			)
			(layer "B.SilkS")
		)
		(fp_line
			(start 0.7874 0.4064)
			(end 0.7874 -0.4064)
			(stroke
				(width 0.1524)
				(type default)
			)
			(layer "B.SilkS")
		)
		(fp_line
			(start -0.7874 0.4064)
			(end 0.7874 0.4064)
			(stroke
				(width 0.1524)
				(type default)
			)
			(layer "B.SilkS")
		)
		(fp_line
			(start 0.67945 -0.305054)
			(end 0.12065 -0.305054)
			(stroke
				(width 0.1)
				(type default)
			)
			(layer "B.Fab")
		)
		(fp_line
			(start 0.12065 -0.305054)
			(end 0.12065 -0.2794)
			(stroke
				(width 0.1)
				(type default)
			)
			(layer "B.Fab")
		)
		(fp_line
			(start -0.12065 -0.3048)
			(end -0.67945 -0.3048)
			(stroke
				(width 0.1)
				(type default)
			)
			(layer "B.Fab")
		)
		(fp_line
			(start -0.67945 -0.3048)
			(end -0.67945 0.3048)
			(stroke
				(width 0.1)
				(type default)
			)
			(layer "B.Fab")
		)
		(fp_line
			(start 0.12065 -0.2794)
			(end -0.12065 -0.2794)
			(stroke
				(width 0.1)
				(type default)
			)
			(layer "B.Fab")
		)
		(fp_line
			(start -0.12065 -0.2794)
			(end -0.12065 -0.3048)
			(stroke
				(width 0.1)
				(type default)
			)
			(layer "B.Fab")
		)
		(fp_line
			(start 0.12065 0.2794)
			(end 0.12065 0.3048)
			(stroke
				(width 0.1)
				(type default)
			)
			(layer "B.Fab")
		)
		(fp_line
			(start -0.120396 0.2794)
			(end 0.12065 0.2794)
			(stroke
				(width 0.1)
				(type default)
			)
			(layer "B.Fab")
		)
		(fp_line
			(start 0.67945 0.3048)
			(end 0.67945 -0.305054)
			(stroke
				(width 0.1)
				(type default)
			)
			(layer "B.Fab")
		)
		(fp_line
			(start 0.12065 0.3048)
			(end 0.67945 0.3048)
			(stroke
				(width 0.1)
				(type default)
			)
			(layer "B.Fab")
		)
		(fp_line
			(start -0.120396 0.3048)
			(end -0.120396 0.2794)
			(stroke
				(width 0.1)
				(type default)
			)
			(layer "B.Fab")
		)
		(fp_line
			(start -0.67945 0.3048)
			(end -0.120396 0.3048)
			(stroke
				(width 0.1)
				(type default)
			)
			(layer "B.Fab")
		)
		(pad "1" smd circle
			(at 0.40005 0 270)
			(size 0 0)
			(layers "B.Cu" "B.Mask" "B.Paste")
			(net "SPI_PEX3_SDIO1_MUX_R")
		)
		(pad "2" smd circle
			(at -0.40005 0 270)
			(size 0 0)
			(layers "B.Cu" "B.Mask" "B.Paste")
			(net "SPI_PEX3_SDIO1_MUX")
		)
	)
	(footprint ""
		(layer "B.Cu")
		(at 61.597286 -108.465366)
		(property "Reference" "R80"
			(at 0 0 0)
			(layer "B.SilkS")
			(hide yes)
			(effects
				(font
					(size 1.27 1.27)
				)
				(justify mirror)
			)
		)
		(property "Value" ""
			(at 0 0 0)
			(layer "B.Fab")
			(effects
				(font
					(size 1.27 1.27)
				)
				(justify mirror)
			)
		)
		(duplicate_pad_numbers_are_jumpers no)
		(fp_line
			(start -0.7874 -0.4064)
			(end -0.7874 0.4064)
			(stroke
				(width 0.1524)
				(type default)
			)
			(layer "B.SilkS")
		)
		(fp_line
			(start -0.7874 0.4064)
			(end 0.7874 0.4064)
			(stroke
				(width 0.1524)
				(type default)
			)
			(layer "B.SilkS")
		)
		(fp_line
			(start 0.7874 -0.4064)
			(end -0.7874 -0.4064)
			(stroke
				(width 0.1524)
				(type default)
			)
			(layer "B.SilkS")
		)
		(fp_line
			(start 0.7874 0.4064)
			(end 0.7874 -0.4064)
			(stroke
				(width 0.1524)
				(type default)
			)
			(layer "B.SilkS")
		)
		(fp_line
			(start -0.67945 -0.3048)
			(end -0.67945 0.3048)
			(stroke
				(width 0.1)
				(type default)
			)
			(layer "B.Fab")
		)
		(fp_line
			(start -0.67945 0.3048)
			(end -0.120396 0.3048)
			(stroke
				(width 0.1)
				(type default)
			)
			(layer "B.Fab")
		)
		(fp_line
			(start -0.12065 -0.3048)
			(end -0.67945 -0.3048)
			(stroke
				(width 0.1)
				(type default)
			)
			(layer "B.Fab")
		)
		(fp_line
			(start -0.12065 -0.2794)
			(end -0.12065 -0.3048)
			(stroke
				(width 0.1)
				(type default)
			)
			(layer "B.Fab")
		)
		(fp_line
			(start -0.120396 0.2794)
			(end 0.12065 0.2794)
			(stroke
				(width 0.1)
				(type default)
			)
			(layer "B.Fab")
		)
		(fp_line
			(start -0.120396 0.3048)
			(end -0.120396 0.2794)
			(stroke
				(width 0.1)
				(type default)
			)
			(layer "B.Fab")
		)
		(fp_line
			(start 0.12065 -0.305054)
			(end 0.12065 -0.2794)
			(stroke
				(width 0.1)
				(type default)
			)
			(layer "B.Fab")
		)
		(fp_line
			(start 0.12065 -0.2794)
			(end -0.12065 -0.2794)
			(stroke
				(width 0.1)
				(type default)
			)
			(layer "B.Fab")
		)
		(fp_line
			(start 0.12065 0.2794)
			(end 0.12065 0.3048)
			(stroke
				(width 0.1)
				(type default)
			)
			(layer "B.Fab")
		)
		(fp_line
			(start 0.12065 0.3048)
			(end 0.67945 0.3048)
			(stroke
				(width 0.1)
				(type default)
			)
			(layer "B.Fab")
		)
		(fp_line
			(start 0.67945 -0.305054)
			(end 0.12065 -0.305054)
			(stroke
				(width 0.1)
				(type default)
			)
			(layer "B.Fab")
		)
		(fp_line
			(start 0.67945 0.3048)
			(end 0.67945 -0.305054)
			(stroke
				(width 0.1)
				(type default)
			)
			(layer "B.Fab")
		)
		(pad "1" smd circle
			(at 0.40005 0 180)
			(size 0 0)
			(layers "B.Cu" "B.Mask" "B.Paste")
			(net "NIC1_BIF0_N")
		)
		(pad "2" smd circle
			(at -0.40005 0 180)
			(size 0 0)
			(layers "B.Cu" "B.Mask" "B.Paste")
			(net "P3V3_AUX")
		)
	)
	(footprint ""
		(layer "B.Cu")
		(at 113.509806 -293.660068 90)
		(property "Reference" "PC71"
			(at 0 0 90)
			(layer "B.SilkS")
			(hide yes)
			(effects
				(font
					(size 1.27 1.27)
				)
				(justify mirror)
			)
		)
		(property "Value" ""
			(at 0 0 90)
			(layer "B.Fab")
			(effects
				(font
					(size 1.27 1.27)
				)
				(justify mirror)
			)
		)
		(duplicate_pad_numbers_are_jumpers no)
		(fp_line
			(start 4.84378 -2.150618)
			(end 4.53898 -2.150618)
			(stroke
				(width 0.1524)
				(type default)
			)
			(layer "B.SilkS")
		)
		(fp_line
			(start 4.84378 -2.150618)
			(end 4.842256 2.163064)
			(stroke
				(width 0.1524)
				(type default)
			)
			(layer "B.SilkS")
		)
		(fp_line
			(start 4.69138 -2.150618)
			(end 4.692396 2.161032)
			(stroke
				(width 0.1524)
				(type default)
			)
			(layer "B.SilkS")
		)
		(fp_line
			(start 4.53898 -2.150618)
			(end 4.539742 2.152142)
			(stroke
				(width 0.1524)
				(type default)
			)
			(layer "B.SilkS")
		)
		(fp_line
			(start 4.53898 -2.15011)
			(end -4.53898 -2.15011)
			(stroke
				(width 0.1524)
				(type default)
			)
			(layer "B.SilkS")
		)
		(fp_line
			(start -4.53898 -2.15011)
			(end -4.53898 2.15011)
			(stroke
				(width 0.1524)
				(type default)
			)
			(layer "B.SilkS")
		)
		(fp_line
			(start 4.53898 2.15011)
			(end 4.53898 -2.15011)
			(stroke
				(width 0.1524)
				(type default)
			)
			(layer "B.SilkS")
		)
		(fp_line
			(start -4.53898 2.15011)
			(end 4.53898 2.15011)
			(stroke
				(width 0.1524)
				(type default)
			)
			(layer "B.SilkS")
		)
		(fp_line
			(start 4.83108 2.150364)
			(end 4.447794 2.149348)
			(stroke
				(width 0.1524)
				(type default)
			)
			(layer "B.SilkS")
		)
		(fp_line
			(start 3.64998 -2.15011)
			(end -3.64998 -2.15011)
			(stroke
				(width 0.1)
				(type default)
			)
			(layer "B.Fab")
		)
		(fp_line
			(start -3.64998 -2.15011)
			(end -3.64998 2.15011)
			(stroke
				(width 0.1)
				(type default)
			)
			(layer "B.Fab")
		)
		(fp_line
			(start 3.64998 2.15011)
			(end 3.64998 -2.15011)
			(stroke
				(width 0.1)
				(type default)
			)
			(layer "B.Fab")
		)
		(fp_line
			(start -3.64998 2.15011)
			(end 3.64998 2.15011)
			(stroke
				(width 0.1)
				(type default)
			)
			(layer "B.Fab")
		)
		(fp_text user "+"
			(at 6.214872 -0.337058 90)
			(unlocked yes)
			(layer "B.SilkS")
			(effects
				(font
					(size 1.905 1.4224)
					(thickness 0.1524)
				)
				(justify left mirror)
			)
		)
		(fp_text user "-"
			(at -4.313174 -0.094488 90)
			(unlocked yes)
			(layer "B.SilkS")
			(effects
				(font
					(size 1.905 1.4224)
					(thickness 0.1524)
				)
				(justify left mirror)
			)
		)
		(fp_text user "+"
			(at 6.214872 -0.337058 90)
			(unlocked yes)
			(layer "B.Fab")
			(effects
				(font
					(size 1.905 1.4224)
					(thickness 0.1524)
				)
				(justify left mirror)
			)
		)
		(fp_text user "-"
			(at -4.313174 -0.094488 90)
			(unlocked yes)
			(layer "B.Fab")
			(effects
				(font
					(size 1.905 1.4224)
					(thickness 0.1524)
				)
				(justify left mirror)
			)
		)
		(pad "1" smd rect
			(at 3.199892 0 270)
			(size 2.413 2.8194)
			(layers "B.Cu" "B.Mask" "B.Paste")
			(net "P0V8_PEX0")
		)
		(pad "2" smd rect
			(at -3.199892 0 270)
			(size 2.413 2.8194)
			(layers "B.Cu" "B.Mask" "B.Paste")
			(net "GND")
		)
	)
	(footprint ""
		(layer "B.Cu")
		(at 405.100028 -292.099746 90)
		(property "Reference" "C1996"
			(at 0 0 90)
			(layer "B.SilkS")
			(hide yes)
			(effects
				(font
					(size 1.27 1.27)
				)
				(justify mirror)
			)
		)
		(property "Value" ""
			(at 0 0 90)
			(layer "B.Fab")
			(effects
				(font
					(size 1.27 1.27)
				)
				(justify mirror)
			)
		)
		(duplicate_pad_numbers_are_jumpers no)
		(fp_line
			(start 0.299974 -0.150114)
			(end -0.299974 -0.150114)
			(stroke
				(width 0.1)
				(type default)
			)
			(layer "B.Fab")
		)
		(fp_line
			(start -0.299974 -0.150114)
			(end -0.299974 0.150114)
			(stroke
				(width 0.1)
				(type default)
			)
			(layer "B.Fab")
		)
		(fp_line
			(start 0.299974 0.150114)
			(end 0.299974 -0.150114)
			(stroke
				(width 0.1)
				(type default)
			)
			(layer "B.Fab")
		)
		(fp_line
			(start -0.299974 0.150114)
			(end 0.299974 0.150114)
			(stroke
				(width 0.1)
				(type default)
			)
			(layer "B.Fab")
		)
		(pad "1" smd rect
			(at 0.2667 0 270)
			(size 0.3048 0.381)
			(layers "B.Cu" "B.Mask" "B.Paste")
			(net "P0V8_SERDES_VDDA_PEX3")
		)
		(pad "2" smd rect
			(at -0.2667 0 270)
			(size 0.3048 0.381)
			(layers "B.Cu" "B.Mask" "B.Paste")
			(net "GND")
		)
	)
	(footprint ""
		(layer "B.Cu")
		(at 13.067284 -381.024892 90)
		(property "Reference" "C4464"
			(at 0 0 90)
			(layer "B.SilkS")
			(hide yes)
			(effects
				(font
					(size 1.27 1.27)
				)
				(justify mirror)
			)
		)
		(property "Value" ""
			(at 0 0 90)
			(layer "B.Fab")
			(effects
				(font
					(size 1.27 1.27)
				)
				(justify mirror)
			)
		)
		(duplicate_pad_numbers_are_jumpers no)
		(fp_line
			(start 0.7874 -0.4064)
			(end -0.7874 -0.4064)
			(stroke
				(width 0.1524)
				(type default)
			)
			(layer "B.SilkS")
		)
		(fp_line
			(start -0.7874 -0.4064)
			(end -0.7874 0.4064)
			(stroke
				(width 0.1524)
				(type default)
			)
			(layer "B.SilkS")
		)
		(fp_line
			(start 0.7874 0.4064)
			(end 0.7874 -0.4064)
			(stroke
				(width 0.1524)
				(type default)
			)
			(layer "B.SilkS")
		)
		(fp_line
			(start -0.7874 0.4064)
			(end 0.7874 0.4064)
			(stroke
				(width 0.1524)
				(type default)
			)
			(layer "B.SilkS")
		)
		(fp_line
			(start 0.67945 -0.305054)
			(end 0.12065 -0.305054)
			(stroke
				(width 0.1)
				(type default)
			)
			(layer "B.Fab")
		)
		(fp_line
			(start 0.12065 -0.305054)
			(end 0.12065 -0.2794)
			(stroke
				(width 0.1)
				(type default)
			)
			(layer "B.Fab")
		)
		(fp_line
			(start -0.12065 -0.3048)
			(end -0.67945 -0.3048)
			(stroke
				(width 0.1)
				(type default)
			)
			(layer "B.Fab")
		)
		(fp_line
			(start -0.67945 -0.3048)
			(end -0.67945 0.3048)
			(stroke
				(width 0.1)
				(type default)
			)
			(layer "B.Fab")
		)
		(fp_line
			(start 0.12065 -0.2794)
			(end -0.12065 -0.2794)
			(stroke
				(width 0.1)
				(type default)
			)
			(layer "B.Fab")
		)
		(fp_line
			(start -0.12065 -0.2794)
			(end -0.12065 -0.3048)
			(stroke
				(width 0.1)
				(type default)
			)
			(layer "B.Fab")
		)
		(fp_line
			(start 0.12065 0.2794)
			(end 0.12065 0.3048)
			(stroke
				(width 0.1)
				(type default)
			)
			(layer "B.Fab")
		)
		(fp_line
			(start -0.120396 0.2794)
			(end 0.12065 0.2794)
			(stroke
				(width 0.1)
				(type default)
			)
			(layer "B.Fab")
		)
		(fp_line
			(start 0.67945 0.3048)
			(end 0.67945 -0.305054)
			(stroke
				(width 0.1)
				(type default)
			)
			(layer "B.Fab")
		)
		(fp_line
			(start 0.12065 0.3048)
			(end 0.67945 0.3048)
			(stroke
				(width 0.1)
				(type default)
			)
			(layer "B.Fab")
		)
		(fp_line
			(start -0.120396 0.3048)
			(end -0.120396 0.2794)
			(stroke
				(width 0.1)
				(type default)
			)
			(layer "B.Fab")
		)
		(fp_line
			(start -0.67945 0.3048)
			(end -0.120396 0.3048)
			(stroke
				(width 0.1)
				(type default)
			)
			(layer "B.Fab")
		)
		(pad "1" smd circle
			(at 0.40005 0 270)
			(size 0 0)
			(layers "B.Cu" "B.Mask" "B.Paste")
			(net "P3V3_USB_8042")
		)
		(pad "2" smd circle
			(at -0.40005 0 270)
			(size 0 0)
			(layers "B.Cu" "B.Mask" "B.Paste")
			(net "GND")
		)
	)
	(footprint ""
		(layer "B.Cu")
		(at 133.020816 -211.080858 180)
		(property "Reference" "R985"
			(at 0 0 0)
			(layer "B.SilkS")
			(hide yes)
			(effects
				(font
					(size 1.27 1.27)
				)
				(justify mirror)
			)
		)
		(property "Value" ""
			(at 0 0 0)
			(layer "B.Fab")
			(effects
				(font
					(size 1.27 1.27)
				)
				(justify mirror)
			)
		)
		(duplicate_pad_numbers_are_jumpers no)
		(fp_line
			(start 0.7874 0.4064)
			(end 0.7874 -0.4064)
			(stroke
				(width 0.1524)
				(type default)
			)
			(layer "B.SilkS")
		)
		(fp_line
			(start 0.7874 -0.4064)
			(end -0.7874 -0.4064)
			(stroke
				(width 0.1524)
				(type default)
			)
			(layer "B.SilkS")
		)
		(fp_line
			(start -0.7874 0.4064)
			(end 0.7874 0.4064)
			(stroke
				(width 0.1524)
				(type default)
			)
			(layer "B.SilkS")
		)
		(fp_line
			(start -0.7874 -0.4064)
			(end -0.7874 0.4064)
			(stroke
				(width 0.1524)
				(type default)
			)
			(layer "B.SilkS")
		)
		(fp_line
			(start 0.67945 0.3048)
			(end 0.67945 -0.305054)
			(stroke
				(width 0.1)
				(type default)
			)
			(layer "B.Fab")
		)
		(fp_line
			(start 0.67945 -0.305054)
			(end 0.12065 -0.305054)
			(stroke
				(width 0.1)
				(type default)
			)
			(layer "B.Fab")
		)
		(fp_line
			(start 0.12065 0.3048)
			(end 0.67945 0.3048)
			(stroke
				(width 0.1)
				(type default)
			)
			(layer "B.Fab")
		)
		(fp_line
			(start 0.12065 0.2794)
			(end 0.12065 0.3048)
			(stroke
				(width 0.1)
				(type default)
			)
			(layer "B.Fab")
		)
		(fp_line
			(start 0.12065 -0.2794)
			(end -0.12065 -0.2794)
			(stroke
				(width 0.1)
				(type default)
			)
			(layer "B.Fab")
		)
		(fp_line
			(start 0.12065 -0.305054)
			(end 0.12065 -0.2794)
			(stroke
				(width 0.1)
				(type default)
			)
			(layer "B.Fab")
		)
		(fp_line
			(start -0.120396 0.3048)
			(end -0.120396 0.2794)
			(stroke
				(width 0.1)
				(type default)
			)
			(layer "B.Fab")
		)
		(fp_line
			(start -0.120396 0.2794)
			(end 0.12065 0.2794)
			(stroke
				(width 0.1)
				(type default)
			)
			(layer "B.Fab")
		)
		(fp_line
			(start -0.12065 -0.2794)
			(end -0.12065 -0.3048)
			(stroke
				(width 0.1)
				(type default)
			)
			(layer "B.Fab")
		)
		(fp_line
			(start -0.12065 -0.3048)
			(end -0.67945 -0.3048)
			(stroke
				(width 0.1)
				(type default)
			)
			(layer "B.Fab")
		)
		(fp_line
			(start -0.67945 0.3048)
			(end -0.120396 0.3048)
			(stroke
				(width 0.1)
				(type default)
			)
			(layer "B.Fab")
		)
		(fp_line
			(start -0.67945 -0.3048)
			(end -0.67945 0.3048)
			(stroke
				(width 0.1)
				(type default)
			)
			(layer "B.Fab")
		)
		(pad "1" smd circle
			(at 0.40005 0)
			(size 0 0)
			(layers "B.Cu" "B.Mask" "B.Paste")
			(net "UART_PEX0_CLI_BUF_R_TX")
		)
		(pad "2" smd circle
			(at -0.40005 0)
			(size 0 0)
			(layers "B.Cu" "B.Mask" "B.Paste")
			(net "UART_PEX0_CLI_BUF_TX")
		)
	)
	(footprint ""
		(layer "B.Cu")
		(at 125.713236 -260.13791)
		(property "Reference" "PR7140"
			(at 0 0 0)
			(layer "B.SilkS")
			(hide yes)
			(effects
				(font
					(size 1.27 1.27)
				)
				(justify mirror)
			)
		)
		(property "Value" ""
			(at 0 0 0)
			(layer "B.Fab")
			(effects
				(font
					(size 1.27 1.27)
				)
				(justify mirror)
			)
		)
		(duplicate_pad_numbers_are_jumpers no)
		(fp_line
			(start -0.7874 -0.4064)
			(end -0.7874 0.4064)
			(stroke
				(width 0.1524)
				(type default)
			)
			(layer "B.SilkS")
		)
		(fp_line
			(start -0.7874 0.4064)
			(end 0.7874 0.4064)
			(stroke
				(width 0.1524)
				(type default)
			)
			(layer "B.SilkS")
		)
		(fp_line
			(start 0.7874 -0.4064)
			(end -0.7874 -0.4064)
			(stroke
				(width 0.1524)
				(type default)
			)
			(layer "B.SilkS")
		)
		(fp_line
			(start 0.7874 0.4064)
			(end 0.7874 -0.4064)
			(stroke
				(width 0.1524)
				(type default)
			)
			(layer "B.SilkS")
		)
		(fp_line
			(start -0.67945 -0.3048)
			(end -0.67945 0.3048)
			(stroke
				(width 0.1)
				(type default)
			)
			(layer "B.Fab")
		)
		(fp_line
			(start -0.67945 0.3048)
			(end -0.120396 0.3048)
			(stroke
				(width 0.1)
				(type default)
			)
			(layer "B.Fab")
		)
		(fp_line
			(start -0.12065 -0.3048)
			(end -0.67945 -0.3048)
			(stroke
				(width 0.1)
				(type default)
			)
			(layer "B.Fab")
		)
		(fp_line
			(start -0.12065 -0.2794)
			(end -0.12065 -0.3048)
			(stroke
				(width 0.1)
				(type default)
			)
			(layer "B.Fab")
		)
		(fp_line
			(start -0.120396 0.2794)
			(end 0.12065 0.2794)
			(stroke
				(width 0.1)
				(type default)
			)
			(layer "B.Fab")
		)
		(fp_line
			(start -0.120396 0.3048)
			(end -0.120396 0.2794)
			(stroke
				(width 0.1)
				(type default)
			)
			(layer "B.Fab")
		)
		(fp_line
			(start 0.12065 -0.305054)
			(end 0.12065 -0.2794)
			(stroke
				(width 0.1)
				(type default)
			)
			(layer "B.Fab")
		)
		(fp_line
			(start 0.12065 -0.2794)
			(end -0.12065 -0.2794)
			(stroke
				(width 0.1)
				(type default)
			)
			(layer "B.Fab")
		)
		(fp_line
			(start 0.12065 0.2794)
			(end 0.12065 0.3048)
			(stroke
				(width 0.1)
				(type default)
			)
			(layer "B.Fab")
		)
		(fp_line
			(start 0.12065 0.3048)
			(end 0.67945 0.3048)
			(stroke
				(width 0.1)
				(type default)
			)
			(layer "B.Fab")
		)
		(fp_line
			(start 0.67945 -0.305054)
			(end 0.12065 -0.305054)
			(stroke
				(width 0.1)
				(type default)
			)
			(layer "B.Fab")
		)
		(fp_line
			(start 0.67945 0.3048)
			(end 0.67945 -0.305054)
			(stroke
				(width 0.1)
				(type default)
			)
			(layer "B.Fab")
		)
		(pad "1" smd circle
			(at 0.40005 0 180)
			(size 0 0)
			(layers "B.Cu" "B.Mask" "B.Paste")
			(net "P0V8_PEX0_VREF")
		)
		(pad "2" smd circle
			(at -0.40005 0 180)
			(size 0 0)
			(layers "B.Cu" "B.Mask" "B.Paste")
			(net "P0V8_PEX0_SVID")
		)
	)
	(footprint ""
		(layer "B.Cu")
		(at 4.880102 -283.624782)
		(property "Reference" "PC215"
			(at 0 0 0)
			(layer "B.SilkS")
			(hide yes)
			(effects
				(font
					(size 1.27 1.27)
				)
				(justify mirror)
			)
		)
		(property "Value" ""
			(at 0 0 0)
			(layer "B.Fab")
			(effects
				(font
					(size 1.27 1.27)
				)
				(justify mirror)
			)
		)
		(duplicate_pad_numbers_are_jumpers no)
		(fp_line
			(start -1.524 -0.762)
			(end -1.524 0.762)
			(stroke
				(width 0.1524)
				(type default)
			)
			(layer "B.SilkS")
		)
		(fp_line
			(start -1.524 0.762)
			(end 1.524 0.762)
			(stroke
				(width 0.1524)
				(type default)
			)
			(layer "B.SilkS")
		)
		(fp_line
			(start 1.524 -0.762)
			(end -1.524 -0.762)
			(stroke
				(width 0.1524)
				(type default)
			)
			(layer "B.SilkS")
		)
		(fp_line
			(start 1.524 0.762)
			(end 1.524 -0.762)
			(stroke
				(width 0.1524)
				(type default)
			)
			(layer "B.SilkS")
		)
		(fp_line
			(start -1.1049 -0.724916)
			(end 1.1049 -0.724916)
			(stroke
				(width 0.1)
				(type default)
			)
			(layer "B.Fab")
		)
		(fp_line
			(start -1.1049 0.724916)
			(end -1.1049 -0.724916)
			(stroke
				(width 0.1)
				(type default)
			)
			(layer "B.Fab")
		)
		(fp_line
			(start 1.1049 -0.724916)
			(end 1.1049 0.724916)
			(stroke
				(width 0.1)
				(type default)
			)
			(layer "B.Fab")
		)
		(fp_line
			(start 1.1049 0.724916)
			(end -1.1049 0.724916)
			(stroke
				(width 0.1)
				(type default)
			)
			(layer "B.Fab")
		)
		(pad "1" smd rect
			(at 0.889 0)
			(size 1.016 1.27)
			(layers "B.Cu" "B.Mask" "B.Paste")
			(net "P1V25_PEX0_R")
		)
		(pad "2" smd rect
			(at -0.889 0)
			(size 1.016 1.27)
			(layers "B.Cu" "B.Mask" "B.Paste")
			(net "GND")
		)
	)
	(footprint ""
		(layer "B.Cu")
		(at 141.793214 -213.905846 90)
		(property "Reference" "C2610"
			(at 0 0 90)
			(layer "B.SilkS")
			(hide yes)
			(effects
				(font
					(size 1.27 1.27)
				)
				(justify mirror)
			)
		)
		(property "Value" ""
			(at 0 0 90)
			(layer "B.Fab")
			(effects
				(font
					(size 1.27 1.27)
				)
				(justify mirror)
			)
		)
		(duplicate_pad_numbers_are_jumpers no)
		(fp_line
			(start 0.7874 -0.4064)
			(end -0.7874 -0.4064)
			(stroke
				(width 0.1524)
				(type default)
			)
			(layer "B.SilkS")
		)
		(fp_line
			(start -0.7874 -0.4064)
			(end -0.7874 0.4064)
			(stroke
				(width 0.1524)
				(type default)
			)
			(layer "B.SilkS")
		)
		(fp_line
			(start 0.7874 0.4064)
			(end 0.7874 -0.4064)
			(stroke
				(width 0.1524)
				(type default)
			)
			(layer "B.SilkS")
		)
		(fp_line
			(start -0.7874 0.4064)
			(end 0.7874 0.4064)
			(stroke
				(width 0.1524)
				(type default)
			)
			(layer "B.SilkS")
		)
		(fp_line
			(start 0.67945 -0.305054)
			(end 0.12065 -0.305054)
			(stroke
				(width 0.1)
				(type default)
			)
			(layer "B.Fab")
		)
		(fp_line
			(start 0.12065 -0.305054)
			(end 0.12065 -0.2794)
			(stroke
				(width 0.1)
				(type default)
			)
			(layer "B.Fab")
		)
		(fp_line
			(start -0.12065 -0.3048)
			(end -0.67945 -0.3048)
			(stroke
				(width 0.1)
				(type default)
			)
			(layer "B.Fab")
		)
		(fp_line
			(start -0.67945 -0.3048)
			(end -0.67945 0.3048)
			(stroke
				(width 0.1)
				(type default)
			)
			(layer "B.Fab")
		)
		(fp_line
			(start 0.12065 -0.2794)
			(end -0.12065 -0.2794)
			(stroke
				(width 0.1)
				(type default)
			)
			(layer "B.Fab")
		)
		(fp_line
			(start -0.12065 -0.2794)
			(end -0.12065 -0.3048)
			(stroke
				(width 0.1)
				(type default)
			)
			(layer "B.Fab")
		)
		(fp_line
			(start 0.12065 0.2794)
			(end 0.12065 0.3048)
			(stroke
				(width 0.1)
				(type default)
			)
			(layer "B.Fab")
		)
		(fp_line
			(start -0.120396 0.2794)
			(end 0.12065 0.2794)
			(stroke
				(width 0.1)
				(type default)
			)
			(layer "B.Fab")
		)
		(fp_line
			(start 0.67945 0.3048)
			(end 0.67945 -0.305054)
			(stroke
				(width 0.1)
				(type default)
			)
			(layer "B.Fab")
		)
		(fp_line
			(start 0.12065 0.3048)
			(end 0.67945 0.3048)
			(stroke
				(width 0.1)
				(type default)
			)
			(layer "B.Fab")
		)
		(fp_line
			(start -0.120396 0.3048)
			(end -0.120396 0.2794)
			(stroke
				(width 0.1)
				(type default)
			)
			(layer "B.Fab")
		)
		(fp_line
			(start -0.67945 0.3048)
			(end -0.120396 0.3048)
			(stroke
				(width 0.1)
				(type default)
			)
			(layer "B.Fab")
		)
		(pad "1" smd circle
			(at 0.40005 0 270)
			(size 0 0)
			(layers "B.Cu" "B.Mask" "B.Paste")
			(net "GND")
		)
		(pad "2" smd circle
			(at -0.40005 0 270)
			(size 0 0)
			(layers "B.Cu" "B.Mask" "B.Paste")
			(net "P3V3_AUX")
		)
	)
	(footprint ""
		(layer "B.Cu")
		(at 63.449962 -288.299906 90)
		(property "Reference" "C2938"
			(at 0 0 90)
			(layer "B.SilkS")
			(hide yes)
			(effects
				(font
					(size 1.27 1.27)
				)
				(justify mirror)
			)
		)
		(property "Value" ""
			(at 0 0 90)
			(layer "B.Fab")
			(effects
				(font
					(size 1.27 1.27)
				)
				(justify mirror)
			)
		)
		(duplicate_pad_numbers_are_jumpers no)
		(fp_line
			(start 0.299974 -0.150114)
			(end -0.299974 -0.150114)
			(stroke
				(width 0.1)
				(type default)
			)
			(layer "B.Fab")
		)
		(fp_line
			(start -0.299974 -0.150114)
			(end -0.299974 0.150114)
			(stroke
				(width 0.1)
				(type default)
			)
			(layer "B.Fab")
		)
		(fp_line
			(start 0.299974 0.150114)
			(end 0.299974 -0.150114)
			(stroke
				(width 0.1)
				(type default)
			)
			(layer "B.Fab")
		)
		(fp_line
			(start -0.299974 0.150114)
			(end 0.299974 0.150114)
			(stroke
				(width 0.1)
				(type default)
			)
			(layer "B.Fab")
		)
		(pad "1" smd rect
			(at 0.2667 0 270)
			(size 0.3048 0.381)
			(layers "B.Cu" "B.Mask" "B.Paste")
			(net "P1V25_PEX0")
		)
		(pad "2" smd rect
			(at -0.2667 0 270)
			(size 0.3048 0.381)
			(layers "B.Cu" "B.Mask" "B.Paste")
			(net "GND")
		)
	)
	(footprint ""
		(layer "B.Cu")
		(at 340.995 -233.553 90)
		(property "Reference" "R3535"
			(at 0 0 90)
			(layer "B.SilkS")
			(hide yes)
			(effects
				(font
					(size 1.27 1.27)
				)
				(justify mirror)
			)
		)
		(property "Value" ""
			(at 0 0 90)
			(layer "B.Fab")
			(effects
				(font
					(size 1.27 1.27)
				)
				(justify mirror)
			)
		)
		(duplicate_pad_numbers_are_jumpers no)
		(fp_line
			(start 0.7874 -0.4064)
			(end -0.7874 -0.4064)
			(stroke
				(width 0.1524)
				(type default)
			)
			(layer "B.SilkS")
		)
		(fp_line
			(start -0.7874 -0.4064)
			(end -0.7874 0.4064)
			(stroke
				(width 0.1524)
				(type default)
			)
			(layer "B.SilkS")
		)
		(fp_line
			(start 0.7874 0.4064)
			(end 0.7874 -0.4064)
			(stroke
				(width 0.1524)
				(type default)
			)
			(layer "B.SilkS")
		)
		(fp_line
			(start -0.7874 0.4064)
			(end 0.7874 0.4064)
			(stroke
				(width 0.1524)
				(type default)
			)
			(layer "B.SilkS")
		)
		(fp_line
			(start 0.67945 -0.305054)
			(end 0.12065 -0.305054)
			(stroke
				(width 0.1)
				(type default)
			)
			(layer "B.Fab")
		)
		(fp_line
			(start 0.12065 -0.305054)
			(end 0.12065 -0.2794)
			(stroke
				(width 0.1)
				(type default)
			)
			(layer "B.Fab")
		)
		(fp_line
			(start -0.12065 -0.3048)
			(end -0.67945 -0.3048)
			(stroke
				(width 0.1)
				(type default)
			)
			(layer "B.Fab")
		)
		(fp_line
			(start -0.67945 -0.3048)
			(end -0.67945 0.3048)
			(stroke
				(width 0.1)
				(type default)
			)
			(layer "B.Fab")
		)
		(fp_line
			(start 0.12065 -0.2794)
			(end -0.12065 -0.2794)
			(stroke
				(width 0.1)
				(type default)
			)
			(layer "B.Fab")
		)
		(fp_line
			(start -0.12065 -0.2794)
			(end -0.12065 -0.3048)
			(stroke
				(width 0.1)
				(type default)
			)
			(layer "B.Fab")
		)
		(fp_line
			(start 0.12065 0.2794)
			(end 0.12065 0.3048)
			(stroke
				(width 0.1)
				(type default)
			)
			(layer "B.Fab")
		)
		(fp_line
			(start -0.120396 0.2794)
			(end 0.12065 0.2794)
			(stroke
				(width 0.1)
				(type default)
			)
			(layer "B.Fab")
		)
		(fp_line
			(start 0.67945 0.3048)
			(end 0.67945 -0.305054)
			(stroke
				(width 0.1)
				(type default)
			)
			(layer "B.Fab")
		)
		(fp_line
			(start 0.12065 0.3048)
			(end 0.67945 0.3048)
			(stroke
				(width 0.1)
				(type default)
			)
			(layer "B.Fab")
		)
		(fp_line
			(start -0.120396 0.3048)
			(end -0.120396 0.2794)
			(stroke
				(width 0.1)
				(type default)
			)
			(layer "B.Fab")
		)
		(fp_line
			(start -0.67945 0.3048)
			(end -0.120396 0.3048)
			(stroke
				(width 0.1)
				(type default)
			)
			(layer "B.Fab")
		)
		(pad "1" smd circle
			(at 0.40005 0 270)
			(size 0 0)
			(layers "B.Cu" "B.Mask" "B.Paste")
			(net "SSD3_PWR_EN_R")
		)
		(pad "2" smd circle
			(at -0.40005 0 270)
			(size 0 0)
			(layers "B.Cu" "B.Mask" "B.Paste")
			(net "SSD3_PWR_EN")
		)
	)
	(footprint ""
		(layer "B.Cu")
		(at 212.09 -196.977 -90)
		(property "Reference" "R1527"
			(at 0 0 90)
			(layer "B.SilkS")
			(hide yes)
			(effects
				(font
					(size 1.27 1.27)
				)
				(justify mirror)
			)
		)
		(property "Value" ""
			(at 0 0 90)
			(layer "B.Fab")
			(effects
				(font
					(size 1.27 1.27)
				)
				(justify mirror)
			)
		)
		(duplicate_pad_numbers_are_jumpers no)
		(fp_line
			(start -0.7874 0.4064)
			(end 0.7874 0.4064)
			(stroke
				(width 0.1524)
				(type default)
			)
			(layer "B.SilkS")
		)
		(fp_line
			(start 0.7874 0.4064)
			(end 0.7874 -0.4064)
			(stroke
				(width 0.1524)
				(type default)
			)
			(layer "B.SilkS")
		)
		(fp_line
			(start -0.7874 -0.4064)
			(end -0.7874 0.4064)
			(stroke
				(width 0.1524)
				(type default)
			)
			(layer "B.SilkS")
		)
		(fp_line
			(start 0.7874 -0.4064)
			(end -0.7874 -0.4064)
			(stroke
				(width 0.1524)
				(type default)
			)
			(layer "B.SilkS")
		)
		(fp_line
			(start -0.67945 0.3048)
			(end -0.120396 0.3048)
			(stroke
				(width 0.1)
				(type default)
			)
			(layer "B.Fab")
		)
		(fp_line
			(start -0.120396 0.3048)
			(end -0.120396 0.2794)
			(stroke
				(width 0.1)
				(type default)
			)
			(layer "B.Fab")
		)
		(fp_line
			(start 0.12065 0.3048)
			(end 0.67945 0.3048)
			(stroke
				(width 0.1)
				(type default)
			)
			(layer "B.Fab")
		)
		(fp_line
			(start 0.67945 0.3048)
			(end 0.67945 -0.305054)
			(stroke
				(width 0.1)
				(type default)
			)
			(layer "B.Fab")
		)
		(fp_line
			(start -0.120396 0.2794)
			(end 0.12065 0.2794)
			(stroke
				(width 0.1)
				(type default)
			)
			(layer "B.Fab")
		)
		(fp_line
			(start 0.12065 0.2794)
			(end 0.12065 0.3048)
			(stroke
				(width 0.1)
				(type default)
			)
			(layer "B.Fab")
		)
		(fp_line
			(start -0.12065 -0.2794)
			(end -0.12065 -0.3048)
			(stroke
				(width 0.1)
				(type default)
			)
			(layer "B.Fab")
		)
		(fp_line
			(start 0.12065 -0.2794)
			(end -0.12065 -0.2794)
			(stroke
				(width 0.1)
				(type default)
			)
			(layer "B.Fab")
		)
		(fp_line
			(start -0.67945 -0.3048)
			(end -0.67945 0.3048)
			(stroke
				(width 0.1)
				(type default)
			)
			(layer "B.Fab")
		)
		(fp_line
			(start -0.12065 -0.3048)
			(end -0.67945 -0.3048)
			(stroke
				(width 0.1)
				(type default)
			)
			(layer "B.Fab")
		)
		(fp_line
			(start 0.12065 -0.305054)
			(end 0.12065 -0.2794)
			(stroke
				(width 0.1)
				(type default)
			)
			(layer "B.Fab")
		)
		(fp_line
			(start 0.67945 -0.305054)
			(end 0.12065 -0.305054)
			(stroke
				(width 0.1)
				(type default)
			)
			(layer "B.Fab")
		)
		(pad "1" smd circle
			(at 0.40005 0 90)
			(size 0 0)
			(layers "B.Cu" "B.Mask" "B.Paste")
			(net "SMB_NIC6_LS_R_SCL")
		)
		(pad "2" smd circle
			(at -0.40005 0 90)
			(size 0 0)
			(layers "B.Cu" "B.Mask" "B.Paste")
			(net "SMB_NIC6_R_SCL")
		)
	)
	(footprint ""
		(layer "B.Cu")
		(at 223.533716 -192.959736 -90)
		(property "Reference" "R1028"
			(at 0 0 90)
			(layer "B.SilkS")
			(hide yes)
			(effects
				(font
					(size 1.27 1.27)
				)
				(justify mirror)
			)
		)
		(property "Value" ""
			(at 0 0 90)
			(layer "B.Fab")
			(effects
				(font
					(size 1.27 1.27)
				)
				(justify mirror)
			)
		)
		(duplicate_pad_numbers_are_jumpers no)
		(fp_line
			(start -0.7874 0.4064)
			(end 0.7874 0.4064)
			(stroke
				(width 0.1524)
				(type default)
			)
			(layer "B.SilkS")
		)
		(fp_line
			(start 0.7874 0.4064)
			(end 0.7874 -0.4064)
			(stroke
				(width 0.1524)
				(type default)
			)
			(layer "B.SilkS")
		)
		(fp_line
			(start -0.7874 -0.4064)
			(end -0.7874 0.4064)
			(stroke
				(width 0.1524)
				(type default)
			)
			(layer "B.SilkS")
		)
		(fp_line
			(start 0.7874 -0.4064)
			(end -0.7874 -0.4064)
			(stroke
				(width 0.1524)
				(type default)
			)
			(layer "B.SilkS")
		)
		(fp_line
			(start -0.67945 0.3048)
			(end -0.120396 0.3048)
			(stroke
				(width 0.1)
				(type default)
			)
			(layer "B.Fab")
		)
		(fp_line
			(start -0.120396 0.3048)
			(end -0.120396 0.2794)
			(stroke
				(width 0.1)
				(type default)
			)
			(layer "B.Fab")
		)
		(fp_line
			(start 0.12065 0.3048)
			(end 0.67945 0.3048)
			(stroke
				(width 0.1)
				(type default)
			)
			(layer "B.Fab")
		)
		(fp_line
			(start 0.67945 0.3048)
			(end 0.67945 -0.305054)
			(stroke
				(width 0.1)
				(type default)
			)
			(layer "B.Fab")
		)
		(fp_line
			(start -0.120396 0.2794)
			(end 0.12065 0.2794)
			(stroke
				(width 0.1)
				(type default)
			)
			(layer "B.Fab")
		)
		(fp_line
			(start 0.12065 0.2794)
			(end 0.12065 0.3048)
			(stroke
				(width 0.1)
				(type default)
			)
			(layer "B.Fab")
		)
		(fp_line
			(start -0.12065 -0.2794)
			(end -0.12065 -0.3048)
			(stroke
				(width 0.1)
				(type default)
			)
			(layer "B.Fab")
		)
		(fp_line
			(start 0.12065 -0.2794)
			(end -0.12065 -0.2794)
			(stroke
				(width 0.1)
				(type default)
			)
			(layer "B.Fab")
		)
		(fp_line
			(start -0.67945 -0.3048)
			(end -0.67945 0.3048)
			(stroke
				(width 0.1)
				(type default)
			)
			(layer "B.Fab")
		)
		(fp_line
			(start -0.12065 -0.3048)
			(end -0.67945 -0.3048)
			(stroke
				(width 0.1)
				(type default)
			)
			(layer "B.Fab")
		)
		(fp_line
			(start 0.12065 -0.305054)
			(end 0.12065 -0.2794)
			(stroke
				(width 0.1)
				(type default)
			)
			(layer "B.Fab")
		)
		(fp_line
			(start 0.67945 -0.305054)
			(end 0.12065 -0.305054)
			(stroke
				(width 0.1)
				(type default)
			)
			(layer "B.Fab")
		)
		(pad "1" smd circle
			(at 0.40005 0 90)
			(size 0 0)
			(layers "B.Cu" "B.Mask" "B.Paste")
			(net "SPI2_DI_BUF")
		)
		(pad "2" smd circle
			(at -0.40005 0 90)
			(size 0 0)
			(layers "B.Cu" "B.Mask" "B.Paste")
			(net "SPI_BIC1_MISO_R2")
		)
	)
	(footprint ""
		(layer "B.Cu")
		(at 65.349882 -303.499774 -90)
		(property "Reference" "C2904"
			(at 0 0 90)
			(layer "B.SilkS")
			(hide yes)
			(effects
				(font
					(size 1.27 1.27)
				)
				(justify mirror)
			)
		)
		(property "Value" ""
			(at 0 0 90)
			(layer "B.Fab")
			(effects
				(font
					(size 1.27 1.27)
				)
				(justify mirror)
			)
		)
		(duplicate_pad_numbers_are_jumpers no)
		(fp_line
			(start -0.299974 0.150114)
			(end 0.299974 0.150114)
			(stroke
				(width 0.1)
				(type default)
			)
			(layer "B.Fab")
		)
		(fp_line
			(start 0.299974 0.150114)
			(end 0.299974 -0.150114)
			(stroke
				(width 0.1)
				(type default)
			)
			(layer "B.Fab")
		)
		(fp_line
			(start -0.299974 -0.150114)
			(end -0.299974 0.150114)
			(stroke
				(width 0.1)
				(type default)
			)
			(layer "B.Fab")
		)
		(fp_line
			(start 0.299974 -0.150114)
			(end -0.299974 -0.150114)
			(stroke
				(width 0.1)
				(type default)
			)
			(layer "B.Fab")
		)
		(pad "1" smd rect
			(at 0.2667 0 90)
			(size 0.3048 0.381)
			(layers "B.Cu" "B.Mask" "B.Paste")
			(net "P1V25_PEX0")
		)
		(pad "2" smd rect
			(at -0.2667 0 90)
			(size 0.3048 0.381)
			(layers "B.Cu" "B.Mask" "B.Paste")
			(net "GND")
		)
	)
	(footprint ""
		(layer "B.Cu")
		(at 353.662488 -220.12148 180)
		(property "Reference" "C2042"
			(at 0 0 0)
			(layer "B.SilkS")
			(hide yes)
			(effects
				(font
					(size 1.27 1.27)
				)
				(justify mirror)
			)
		)
		(property "Value" ""
			(at 0 0 0)
			(layer "B.Fab")
			(effects
				(font
					(size 1.27 1.27)
				)
				(justify mirror)
			)
		)
		(duplicate_pad_numbers_are_jumpers no)
		(fp_line
			(start 0.69215 0.2921)
			(end 0.69215 -0.2921)
			(stroke
				(width 0.1524)
				(type default)
			)
			(layer "B.SilkS")
		)
		(fp_line
			(start 0.69215 -0.2921)
			(end -0.69215 -0.2921)
			(stroke
				(width 0.1524)
				(type default)
			)
			(layer "B.SilkS")
		)
		(fp_line
			(start -0.69215 0.2921)
			(end 0.69215 0.2921)
			(stroke
				(width 0.1524)
				(type default)
			)
			(layer "B.SilkS")
		)
		(fp_line
			(start -0.69215 -0.2921)
			(end -0.69215 0.2921)
			(stroke
				(width 0.1524)
				(type default)
			)
			(layer "B.SilkS")
		)
		(fp_line
			(start 0.51435 0.2794)
			(end 0.51435 -0.2794)
			(stroke
				(width 0.1)
				(type default)
			)
			(layer "B.Fab")
		)
		(fp_line
			(start 0.51435 -0.2794)
			(end -0.51435 -0.2794)
			(stroke
				(width 0.1)
				(type default)
			)
			(layer "B.Fab")
		)
		(fp_line
			(start -0.51435 0.2794)
			(end 0.51435 0.2794)
			(stroke
				(width 0.1)
				(type default)
			)
			(layer "B.Fab")
		)
		(fp_line
			(start -0.51435 -0.2794)
			(end -0.51435 0.2794)
			(stroke
				(width 0.1)
				(type default)
			)
			(layer "B.Fab")
		)
		(pad "1" smd circle
			(at 0.40005 0)
			(size 0 0)
			(layers "B.Cu" "B.Mask" "B.Paste")
			(net "P3V3_FPGA_VCCIO1")
		)
		(pad "2" smd circle
			(at -0.40005 0)
			(size 0 0)
			(layers "B.Cu" "B.Mask" "B.Paste")
			(net "GND")
		)
		(zone
			(layer "B.Cu")
			(hatch none 0.5)
			(connect_pads
				(clearance 0)
			)
			(min_thickness 0.25)
			(keepout
				(tracks not_allowed)
				(vias allowed)
				(pads allowed)
				(copperpour not_allowed)
				(footprints allowed)
			)
			(placement
				(enabled no)
				(sheetname "")
			)
			(fill
				(thermal_gap 0.5)
				(thermal_bridge_width 0.5)
				(island_removal_mode 0)
			)
			(polygon
				(pts
					(xy 353.471988 -220.20911) (xy 353.563428 -220.267276) (xy 353.762818 -220.267276) (xy 353.852988 -220.20911)
					(xy 353.852988 -220.03385) (xy 353.762818 -219.97543) (xy 353.563428 -219.97543) (xy 353.471988 -220.033596)
				)
			)
		)
	)
	(footprint ""
		(layer "B.Cu")
		(at 347.96603 -308.613556 90)
		(property "Reference" "C1669"
			(at 0 0 90)
			(layer "B.SilkS")
			(hide yes)
			(effects
				(font
					(size 1.27 1.27)
				)
				(justify mirror)
			)
		)
		(property "Value" ""
			(at 0 0 90)
			(layer "B.Fab")
			(effects
				(font
					(size 1.27 1.27)
				)
				(justify mirror)
			)
		)
		(duplicate_pad_numbers_are_jumpers no)
		(fp_line
			(start 1.2954 -0.5842)
			(end -1.2954 -0.5842)
			(stroke
				(width 0.1524)
				(type default)
			)
			(layer "B.SilkS")
		)
		(fp_line
			(start -1.2954 -0.5842)
			(end -1.2954 0.5842)
			(stroke
				(width 0.1524)
				(type default)
			)
			(layer "B.SilkS")
		)
		(fp_line
			(start 1.2954 0.5842)
			(end 1.2954 -0.5842)
			(stroke
				(width 0.1524)
				(type default)
			)
			(layer "B.SilkS")
		)
		(fp_line
			(start -1.2954 0.5842)
			(end 1.2954 0.5842)
			(stroke
				(width 0.1524)
				(type default)
			)
			(layer "B.SilkS")
		)
		(fp_line
			(start 0.8636 -0.4572)
			(end -0.8636 -0.4572)
			(stroke
				(width 0.1)
				(type default)
			)
			(layer "B.Fab")
		)
		(fp_line
			(start -0.8636 -0.4572)
			(end -0.8636 -0.4064)
			(stroke
				(width 0.1)
				(type default)
			)
			(layer "B.Fab")
		)
		(fp_line
			(start 1.1938 -0.4064)
			(end 0.8636 -0.4064)
			(stroke
				(width 0.1)
				(type default)
			)
			(layer "B.Fab")
		)
		(fp_line
			(start 0.8636 -0.4064)
			(end 0.8636 -0.4572)
			(stroke
				(width 0.1)
				(type default)
			)
			(layer "B.Fab")
		)
		(fp_line
			(start -0.8636 -0.4064)
			(end -1.1938 -0.4064)
			(stroke
				(width 0.1)
				(type default)
			)
			(layer "B.Fab")
		)
		(fp_line
			(start -1.1938 -0.4064)
			(end -1.1938 0.4064)
			(stroke
				(width 0.1)
				(type default)
			)
			(layer "B.Fab")
		)
		(fp_line
			(start 1.1938 0.4064)
			(end 1.1938 -0.4064)
			(stroke
				(width 0.1)
				(type default)
			)
			(layer "B.Fab")
		)
		(fp_line
			(start 0.8636 0.4064)
			(end 1.1938 0.4064)
			(stroke
				(width 0.1)
				(type default)
			)
			(layer "B.Fab")
		)
		(fp_line
			(start -0.8636 0.4064)
			(end -0.8636 0.4572)
			(stroke
				(width 0.1)
				(type default)
			)
			(layer "B.Fab")
		)
		(fp_line
			(start -1.1938 0.4064)
			(end -0.8636 0.4064)
			(stroke
				(width 0.1)
				(type default)
			)
			(layer "B.Fab")
		)
		(fp_line
			(start 0.8636 0.4572)
			(end 0.8636 0.4064)
			(stroke
				(width 0.1)
				(type default)
			)
			(layer "B.Fab")
		)
		(fp_line
			(start -0.8636 0.4572)
			(end 0.8636 0.4572)
			(stroke
				(width 0.1)
				(type default)
			)
			(layer "B.Fab")
		)
		(pad "1" smd rect
			(at 0.7366 0)
			(size 0.7112 0.8128)
			(layers "B.Cu" "B.Mask" "B.Paste")
			(net "P0V8_SERDES_VDDA_PEX2")
		)
		(pad "2" smd rect
			(at -0.7366 0)
			(size 0.7112 0.8128)
			(layers "B.Cu" "B.Mask" "B.Paste")
			(net "GND")
		)
	)
	(footprint ""
		(layer "B.Cu")
		(at 399.874994 -293.99992 -90)
		(property "Reference" "C1880"
			(at 0 0 90)
			(layer "B.SilkS")
			(hide yes)
			(effects
				(font
					(size 1.27 1.27)
				)
				(justify mirror)
			)
		)
		(property "Value" ""
			(at 0 0 90)
			(layer "B.Fab")
			(effects
				(font
					(size 1.27 1.27)
				)
				(justify mirror)
			)
		)
		(duplicate_pad_numbers_are_jumpers no)
		(fp_line
			(start -0.299974 0.150114)
			(end 0.299974 0.150114)
			(stroke
				(width 0.1)
				(type default)
			)
			(layer "B.Fab")
		)
		(fp_line
			(start 0.299974 0.150114)
			(end 0.299974 -0.150114)
			(stroke
				(width 0.1)
				(type default)
			)
			(layer "B.Fab")
		)
		(fp_line
			(start -0.299974 -0.150114)
			(end -0.299974 0.150114)
			(stroke
				(width 0.1)
				(type default)
			)
			(layer "B.Fab")
		)
		(fp_line
			(start 0.299974 -0.150114)
			(end -0.299974 -0.150114)
			(stroke
				(width 0.1)
				(type default)
			)
			(layer "B.Fab")
		)
		(pad "1" smd rect
			(at 0.2667 0 90)
			(size 0.3048 0.381)
			(layers "B.Cu" "B.Mask" "B.Paste")
			(net "P0V8_PEX3")
		)
		(pad "2" smd rect
			(at -0.2667 0 90)
			(size 0.3048 0.381)
			(layers "B.Cu" "B.Mask" "B.Paste")
			(net "GND")
		)
	)
	(footprint ""
		(layer "B.Cu")
		(at 359.23474 -303.649634 -90)
		(property "Reference" "PC182"
			(at 0 0 90)
			(layer "B.SilkS")
			(hide yes)
			(effects
				(font
					(size 1.27 1.27)
				)
				(justify mirror)
			)
		)
		(property "Value" ""
			(at 0 0 90)
			(layer "B.Fab")
			(effects
				(font
					(size 1.27 1.27)
				)
				(justify mirror)
			)
		)
		(duplicate_pad_numbers_are_jumpers no)
		(fp_line
			(start -1.524 0.762)
			(end 1.524 0.762)
			(stroke
				(width 0.1524)
				(type default)
			)
			(layer "B.SilkS")
		)
		(fp_line
			(start 1.524 0.762)
			(end 1.524 -0.762)
			(stroke
				(width 0.1524)
				(type default)
			)
			(layer "B.SilkS")
		)
		(fp_line
			(start -1.524 -0.762)
			(end -1.524 0.762)
			(stroke
				(width 0.1524)
				(type default)
			)
			(layer "B.SilkS")
		)
		(fp_line
			(start 1.524 -0.762)
			(end -1.524 -0.762)
			(stroke
				(width 0.1524)
				(type default)
			)
			(layer "B.SilkS")
		)
		(fp_line
			(start -1.1049 0.724916)
			(end -1.1049 -0.724916)
			(stroke
				(width 0.1)
				(type default)
			)
			(layer "B.Fab")
		)
		(fp_line
			(start 1.1049 0.724916)
			(end -1.1049 0.724916)
			(stroke
				(width 0.1)
				(type default)
			)
			(layer "B.Fab")
		)
		(fp_line
			(start -1.1049 -0.724916)
			(end 1.1049 -0.724916)
			(stroke
				(width 0.1)
				(type default)
			)
			(layer "B.Fab")
		)
		(fp_line
			(start 1.1049 -0.724916)
			(end 1.1049 0.724916)
			(stroke
				(width 0.1)
				(type default)
			)
			(layer "B.Fab")
		)
		(pad "1" smd rect
			(at 0.889 0 270)
			(size 1.016 1.27)
			(layers "B.Cu" "B.Mask" "B.Paste")
			(net "P0V8_PEX3")
		)
		(pad "2" smd rect
			(at -0.889 0 270)
			(size 1.016 1.27)
			(layers "B.Cu" "B.Mask" "B.Paste")
			(net "GND")
		)
	)
	(footprint ""
		(layer "B.Cu")
		(at 415.549842 -296.37482)
		(property "Reference" "C1936"
			(at 0 0 0)
			(layer "B.SilkS")
			(hide yes)
			(effects
				(font
					(size 1.27 1.27)
				)
				(justify mirror)
			)
		)
		(property "Value" ""
			(at 0 0 0)
			(layer "B.Fab")
			(effects
				(font
					(size 1.27 1.27)
				)
				(justify mirror)
			)
		)
		(duplicate_pad_numbers_are_jumpers no)
		(fp_line
			(start -0.299974 -0.150114)
			(end -0.299974 0.150114)
			(stroke
				(width 0.1)
				(type default)
			)
			(layer "B.Fab")
		)
		(fp_line
			(start -0.299974 0.150114)
			(end 0.299974 0.150114)
			(stroke
				(width 0.1)
				(type default)
			)
			(layer "B.Fab")
		)
		(fp_line
			(start 0.299974 -0.150114)
			(end -0.299974 -0.150114)
			(stroke
				(width 0.1)
				(type default)
			)
			(layer "B.Fab")
		)
		(fp_line
			(start 0.299974 0.150114)
			(end 0.299974 -0.150114)
			(stroke
				(width 0.1)
				(type default)
			)
			(layer "B.Fab")
		)
		(pad "1" smd rect
			(at 0.2667 0 180)
			(size 0.3048 0.381)
			(layers "B.Cu" "B.Mask" "B.Paste")
			(net "P0V8_SERDES_VDDA_PEX3")
		)
		(pad "2" smd rect
			(at -0.2667 0 180)
			(size 0.3048 0.381)
			(layers "B.Cu" "B.Mask" "B.Paste")
			(net "GND")
		)
	)
	(footprint ""
		(layer "B.Cu")
		(at 114.450114 -256.226564 -90)
		(property "Reference" "PR97"
			(at 0 0 90)
			(layer "B.SilkS")
			(hide yes)
			(effects
				(font
					(size 1.27 1.27)
				)
				(justify mirror)
			)
		)
		(property "Value" ""
			(at 0 0 90)
			(layer "B.Fab")
			(effects
				(font
					(size 1.27 1.27)
				)
				(justify mirror)
			)
		)
		(duplicate_pad_numbers_are_jumpers no)
		(fp_line
			(start -0.7874 0.4064)
			(end 0.7874 0.4064)
			(stroke
				(width 0.1524)
				(type default)
			)
			(layer "B.SilkS")
		)
		(fp_line
			(start 0.7874 0.4064)
			(end 0.7874 -0.4064)
			(stroke
				(width 0.1524)
				(type default)
			)
			(layer "B.SilkS")
		)
		(fp_line
			(start -0.7874 -0.4064)
			(end -0.7874 0.4064)
			(stroke
				(width 0.1524)
				(type default)
			)
			(layer "B.SilkS")
		)
		(fp_line
			(start 0.7874 -0.4064)
			(end -0.7874 -0.4064)
			(stroke
				(width 0.1524)
				(type default)
			)
			(layer "B.SilkS")
		)
		(fp_line
			(start -0.67945 0.3048)
			(end -0.120396 0.3048)
			(stroke
				(width 0.1)
				(type default)
			)
			(layer "B.Fab")
		)
		(fp_line
			(start -0.120396 0.3048)
			(end -0.120396 0.2794)
			(stroke
				(width 0.1)
				(type default)
			)
			(layer "B.Fab")
		)
		(fp_line
			(start 0.12065 0.3048)
			(end 0.67945 0.3048)
			(stroke
				(width 0.1)
				(type default)
			)
			(layer "B.Fab")
		)
		(fp_line
			(start 0.67945 0.3048)
			(end 0.67945 -0.305054)
			(stroke
				(width 0.1)
				(type default)
			)
			(layer "B.Fab")
		)
		(fp_line
			(start -0.120396 0.2794)
			(end 0.12065 0.2794)
			(stroke
				(width 0.1)
				(type default)
			)
			(layer "B.Fab")
		)
		(fp_line
			(start 0.12065 0.2794)
			(end 0.12065 0.3048)
			(stroke
				(width 0.1)
				(type default)
			)
			(layer "B.Fab")
		)
		(fp_line
			(start -0.12065 -0.2794)
			(end -0.12065 -0.3048)
			(stroke
				(width 0.1)
				(type default)
			)
			(layer "B.Fab")
		)
		(fp_line
			(start 0.12065 -0.2794)
			(end -0.12065 -0.2794)
			(stroke
				(width 0.1)
				(type default)
			)
			(layer "B.Fab")
		)
		(fp_line
			(start -0.67945 -0.3048)
			(end -0.67945 0.3048)
			(stroke
				(width 0.1)
				(type default)
			)
			(layer "B.Fab")
		)
		(fp_line
			(start -0.12065 -0.3048)
			(end -0.67945 -0.3048)
			(stroke
				(width 0.1)
				(type default)
			)
			(layer "B.Fab")
		)
		(fp_line
			(start 0.12065 -0.305054)
			(end 0.12065 -0.2794)
			(stroke
				(width 0.1)
				(type default)
			)
			(layer "B.Fab")
		)
		(fp_line
			(start 0.67945 -0.305054)
			(end 0.12065 -0.305054)
			(stroke
				(width 0.1)
				(type default)
			)
			(layer "B.Fab")
		)
		(pad "1" smd circle
			(at 0.40005 0 90)
			(size 0 0)
			(layers "B.Cu" "B.Mask" "B.Paste")
			(net "P12V_AUX")
		)
		(pad "2" smd circle
			(at -0.40005 0 90)
			(size 0 0)
			(layers "B.Cu" "B.Mask" "B.Paste")
			(net "P0V8_PEX0_VINSEN")
		)
	)
	(footprint ""
		(layer "B.Cu")
		(at 115.943888 -321.390518 -90)
		(property "Reference" "R6450"
			(at 0 0 90)
			(layer "B.SilkS")
			(hide yes)
			(effects
				(font
					(size 1.27 1.27)
				)
				(justify mirror)
			)
		)
		(property "Value" ""
			(at 0 0 90)
			(layer "B.Fab")
			(effects
				(font
					(size 1.27 1.27)
				)
				(justify mirror)
			)
		)
		(duplicate_pad_numbers_are_jumpers no)
		(fp_line
			(start -0.7874 0.4064)
			(end 0.7874 0.4064)
			(stroke
				(width 0.1524)
				(type default)
			)
			(layer "B.SilkS")
		)
		(fp_line
			(start 0.7874 0.4064)
			(end 0.7874 -0.4064)
			(stroke
				(width 0.1524)
				(type default)
			)
			(layer "B.SilkS")
		)
		(fp_line
			(start -0.7874 -0.4064)
			(end -0.7874 0.4064)
			(stroke
				(width 0.1524)
				(type default)
			)
			(layer "B.SilkS")
		)
		(fp_line
			(start 0.7874 -0.4064)
			(end -0.7874 -0.4064)
			(stroke
				(width 0.1524)
				(type default)
			)
			(layer "B.SilkS")
		)
		(fp_line
			(start -0.67945 0.3048)
			(end -0.120396 0.3048)
			(stroke
				(width 0.1)
				(type default)
			)
			(layer "B.Fab")
		)
		(fp_line
			(start -0.120396 0.3048)
			(end -0.120396 0.2794)
			(stroke
				(width 0.1)
				(type default)
			)
			(layer "B.Fab")
		)
		(fp_line
			(start 0.12065 0.3048)
			(end 0.67945 0.3048)
			(stroke
				(width 0.1)
				(type default)
			)
			(layer "B.Fab")
		)
		(fp_line
			(start 0.67945 0.3048)
			(end 0.67945 -0.305054)
			(stroke
				(width 0.1)
				(type default)
			)
			(layer "B.Fab")
		)
		(fp_line
			(start -0.120396 0.2794)
			(end 0.12065 0.2794)
			(stroke
				(width 0.1)
				(type default)
			)
			(layer "B.Fab")
		)
		(fp_line
			(start 0.12065 0.2794)
			(end 0.12065 0.3048)
			(stroke
				(width 0.1)
				(type default)
			)
			(layer "B.Fab")
		)
		(fp_line
			(start -0.12065 -0.2794)
			(end -0.12065 -0.3048)
			(stroke
				(width 0.1)
				(type default)
			)
			(layer "B.Fab")
		)
		(fp_line
			(start 0.12065 -0.2794)
			(end -0.12065 -0.2794)
			(stroke
				(width 0.1)
				(type default)
			)
			(layer "B.Fab")
		)
		(fp_line
			(start -0.67945 -0.3048)
			(end -0.67945 0.3048)
			(stroke
				(width 0.1)
				(type default)
			)
			(layer "B.Fab")
		)
		(fp_line
			(start -0.12065 -0.3048)
			(end -0.67945 -0.3048)
			(stroke
				(width 0.1)
				(type default)
			)
			(layer "B.Fab")
		)
		(fp_line
			(start 0.12065 -0.305054)
			(end 0.12065 -0.2794)
			(stroke
				(width 0.1)
				(type default)
			)
			(layer "B.Fab")
		)
		(fp_line
			(start 0.67945 -0.305054)
			(end 0.12065 -0.305054)
			(stroke
				(width 0.1)
				(type default)
			)
			(layer "B.Fab")
		)
		(pad "1" smd circle
			(at 0.40005 0 90)
			(size 0 0)
			(layers "B.Cu" "B.Mask" "B.Paste")
			(net "P0V8_SERDES_VDDA_PEX0")
		)
		(pad "2" smd circle
			(at -0.40005 0 90)
			(size 0 0)
			(layers "B.Cu" "B.Mask" "B.Paste")
			(net "P0V8_SERDES_VDDA_PEX0_C1")
		)
	)
	(footprint ""
		(layer "B.Cu")
		(at 279.974802 -294.132 -90)
		(property "Reference" "C3395"
			(at 0 0 90)
			(layer "B.SilkS")
			(hide yes)
			(effects
				(font
					(size 1.27 1.27)
				)
				(justify mirror)
			)
		)
		(property "Value" ""
			(at 0 0 90)
			(layer "B.Fab")
			(effects
				(font
					(size 1.27 1.27)
				)
				(justify mirror)
			)
		)
		(duplicate_pad_numbers_are_jumpers no)
		(fp_line
			(start -0.299974 0.150114)
			(end 0.299974 0.150114)
			(stroke
				(width 0.1)
				(type default)
			)
			(layer "B.Fab")
		)
		(fp_line
			(start 0.299974 0.150114)
			(end 0.299974 -0.150114)
			(stroke
				(width 0.1)
				(type default)
			)
			(layer "B.Fab")
		)
		(fp_line
			(start -0.299974 -0.150114)
			(end -0.299974 0.150114)
			(stroke
				(width 0.1)
				(type default)
			)
			(layer "B.Fab")
		)
		(fp_line
			(start 0.299974 -0.150114)
			(end -0.299974 -0.150114)
			(stroke
				(width 0.1)
				(type default)
			)
			(layer "B.Fab")
		)
		(pad "1" smd rect
			(at 0.2667 0 90)
			(size 0.3048 0.381)
			(layers "B.Cu" "B.Mask" "B.Paste")
			(net "PCEPLL5_VDDA18_PEX2")
		)
		(pad "2" smd rect
			(at -0.2667 0 90)
			(size 0.3048 0.381)
			(layers "B.Cu" "B.Mask" "B.Paste")
			(net "GND")
		)
	)
	(footprint ""
		(layer "B.Cu")
		(at 343.693242 -220.38691 90)
		(property "Reference" "C2071"
			(at 0 0 90)
			(layer "B.SilkS")
			(hide yes)
			(effects
				(font
					(size 1.27 1.27)
				)
				(justify mirror)
			)
		)
		(property "Value" ""
			(at 0 0 90)
			(layer "B.Fab")
			(effects
				(font
					(size 1.27 1.27)
				)
				(justify mirror)
			)
		)
		(duplicate_pad_numbers_are_jumpers no)
		(fp_line
			(start 0.69215 -0.2921)
			(end -0.69215 -0.2921)
			(stroke
				(width 0.1524)
				(type default)
			)
			(layer "B.SilkS")
		)
		(fp_line
			(start -0.69215 -0.2921)
			(end -0.69215 0.2921)
			(stroke
				(width 0.1524)
				(type default)
			)
			(layer "B.SilkS")
		)
		(fp_line
			(start 0.69215 0.2921)
			(end 0.69215 -0.2921)
			(stroke
				(width 0.1524)
				(type default)
			)
			(layer "B.SilkS")
		)
		(fp_line
			(start -0.69215 0.2921)
			(end 0.69215 0.2921)
			(stroke
				(width 0.1524)
				(type default)
			)
			(layer "B.SilkS")
		)
		(fp_line
			(start 0.51435 -0.2794)
			(end -0.51435 -0.2794)
			(stroke
				(width 0.1)
				(type default)
			)
			(layer "B.Fab")
		)
		(fp_line
			(start -0.51435 -0.2794)
			(end -0.51435 0.2794)
			(stroke
				(width 0.1)
				(type default)
			)
			(layer "B.Fab")
		)
		(fp_line
			(start 0.51435 0.2794)
			(end 0.51435 -0.2794)
			(stroke
				(width 0.1)
				(type default)
			)
			(layer "B.Fab")
		)
		(fp_line
			(start -0.51435 0.2794)
			(end 0.51435 0.2794)
			(stroke
				(width 0.1)
				(type default)
			)
			(layer "B.Fab")
		)
		(pad "1" smd circle
			(at 0.40005 0 270)
			(size 0 0)
			(layers "B.Cu" "B.Mask" "B.Paste")
			(net "P3V3_VCC_FPGA_CORE")
		)
		(pad "2" smd circle
			(at -0.40005 0 270)
			(size 0 0)
			(layers "B.Cu" "B.Mask" "B.Paste")
			(net "GND")
		)
		(zone
			(layer "B.Cu")
			(hatch none 0.5)
			(connect_pads
				(clearance 0)
			)
			(min_thickness 0.25)
			(keepout
				(tracks not_allowed)
				(vias allowed)
				(pads allowed)
				(copperpour not_allowed)
				(footprints allowed)
			)
			(placement
				(enabled no)
				(sheetname "")
			)
			(fill
				(thermal_gap 0.5)
				(thermal_bridge_width 0.5)
				(island_removal_mode 0)
			)
			(polygon
				(pts
					(xy 343.780872 -220.57741) (xy 343.839038 -220.48597) (xy 343.839038 -220.28658) (xy 343.780872 -220.19641)
					(xy 343.605612 -220.19641) (xy 343.547192 -220.28658) (xy 343.547192 -220.48597) (xy 343.605358 -220.57741)
				)
			)
		)
	)
	(footprint ""
		(layer "B.Cu")
		(at 104.41813 -281.024838 90)
		(property "Reference" "PC78"
			(at 0 0 90)
			(layer "B.SilkS")
			(hide yes)
			(effects
				(font
					(size 1.27 1.27)
				)
				(justify mirror)
			)
		)
		(property "Value" ""
			(at 0 0 90)
			(layer "B.Fab")
			(effects
				(font
					(size 1.27 1.27)
				)
				(justify mirror)
			)
		)
		(duplicate_pad_numbers_are_jumpers no)
		(fp_line
			(start 1.524 -0.762)
			(end -1.524 -0.762)
			(stroke
				(width 0.1524)
				(type default)
			)
			(layer "B.SilkS")
		)
		(fp_line
			(start -1.524 -0.762)
			(end -1.524 0.762)
			(stroke
				(width 0.1524)
				(type default)
			)
			(layer "B.SilkS")
		)
		(fp_line
			(start 1.524 0.762)
			(end 1.524 -0.762)
			(stroke
				(width 0.1524)
				(type default)
			)
			(layer "B.SilkS")
		)
		(fp_line
			(start -1.524 0.762)
			(end 1.524 0.762)
			(stroke
				(width 0.1524)
				(type default)
			)
			(layer "B.SilkS")
		)
		(fp_line
			(start 1.1049 -0.724916)
			(end 1.1049 0.724916)
			(stroke
				(width 0.1)
				(type default)
			)
			(layer "B.Fab")
		)
		(fp_line
			(start -1.1049 -0.724916)
			(end 1.1049 -0.724916)
			(stroke
				(width 0.1)
				(type default)
			)
			(layer "B.Fab")
		)
		(fp_line
			(start 1.1049 0.724916)
			(end -1.1049 0.724916)
			(stroke
				(width 0.1)
				(type default)
			)
			(layer "B.Fab")
		)
		(fp_line
			(start -1.1049 0.724916)
			(end -1.1049 -0.724916)
			(stroke
				(width 0.1)
				(type default)
			)
			(layer "B.Fab")
		)
		(pad "1" smd rect
			(at 0.889 0 90)
			(size 1.016 1.27)
			(layers "B.Cu" "B.Mask" "B.Paste")
			(net "SW_P12V_P0V8_PEX0_FLT")
		)
		(pad "2" smd rect
			(at -0.889 0 90)
			(size 1.016 1.27)
			(layers "B.Cu" "B.Mask" "B.Paste")
			(net "GND")
		)
	)
	(footprint ""
		(layer "B.Cu")
		(at 366.492536 -328.422)
		(property "Reference" "PJ24"
			(at 0 0 0)
			(layer "B.SilkS")
			(hide yes)
			(effects
				(font
					(size 1.27 1.27)
				)
				(justify mirror)
			)
		)
		(property "Value" ""
			(at 0 0 0)
			(layer "B.Fab")
			(effects
				(font
					(size 1.27 1.27)
				)
				(justify mirror)
			)
		)
		(duplicate_pad_numbers_are_jumpers no)
		(pad "1" smd circle
			(at 0.40005 0 90)
			(size 0 0)
			(layers "B.Cu" "B.Mask" "B.Paste")
			(net "VSENSE_P0V8_PEX3_SKT_VSEN")
		)
		(pad "2" smd rect
			(at -0.40005 0)
			(size 0.4572 0.508)
			(layers "B.Cu" "B.Mask" "B.Paste")
			(net "SH_P0V8_PEX3_VSEN3_L")
		)
		(zone
			(layer "B.Cu")
			(hatch none 0.5)
			(connect_pads
				(clearance 0)
			)
			(min_thickness 0.25)
			(keepout
				(tracks allowed)
				(vias not_allowed)
				(pads allowed)
				(copperpour not_allowed)
				(footprints allowed)
			)
			(placement
				(enabled no)
				(sheetname "")
			)
			(fill
				(thermal_gap 0.5)
				(thermal_bridge_width 0.5)
				(island_removal_mode 0)
			)
			(polygon
				(pts
					(xy 365.806736 -328.1172) (xy 365.806736 -328.7268) (xy 367.178336 -328.7268) (xy 367.178336 -328.1172)
				)
			)
		)
	)
	(footprint ""
		(layer "B.Cu")
		(at 285.245556 -296.37482)
		(property "Reference" "C1618"
			(at 0 0 0)
			(layer "B.SilkS")
			(hide yes)
			(effects
				(font
					(size 1.27 1.27)
				)
				(justify mirror)
			)
		)
		(property "Value" ""
			(at 0 0 0)
			(layer "B.Fab")
			(effects
				(font
					(size 1.27 1.27)
				)
				(justify mirror)
			)
		)
		(duplicate_pad_numbers_are_jumpers no)
		(fp_line
			(start -0.299974 -0.150114)
			(end -0.299974 0.150114)
			(stroke
				(width 0.1)
				(type default)
			)
			(layer "B.Fab")
		)
		(fp_line
			(start -0.299974 0.150114)
			(end 0.299974 0.150114)
			(stroke
				(width 0.1)
				(type default)
			)
			(layer "B.Fab")
		)
		(fp_line
			(start 0.299974 -0.150114)
			(end -0.299974 -0.150114)
			(stroke
				(width 0.1)
				(type default)
			)
			(layer "B.Fab")
		)
		(fp_line
			(start 0.299974 0.150114)
			(end 0.299974 -0.150114)
			(stroke
				(width 0.1)
				(type default)
			)
			(layer "B.Fab")
		)
		(pad "1" smd rect
			(at 0.2667 0 180)
			(size 0.3048 0.381)
			(layers "B.Cu" "B.Mask" "B.Paste")
			(net "P0V8_PEX2")
		)
		(pad "2" smd rect
			(at -0.2667 0 180)
			(size 0.3048 0.381)
			(layers "B.Cu" "B.Mask" "B.Paste")
			(net "GND")
		)
	)
	(footprint ""
		(layer "B.Cu")
		(at 425.841922 -95.989648 180)
		(property "Reference" "R368"
			(at 0 0 0)
			(layer "B.SilkS")
			(hide yes)
			(effects
				(font
					(size 1.27 1.27)
				)
				(justify mirror)
			)
		)
		(property "Value" ""
			(at 0 0 0)
			(layer "B.Fab")
			(effects
				(font
					(size 1.27 1.27)
				)
				(justify mirror)
			)
		)
		(duplicate_pad_numbers_are_jumpers no)
		(fp_line
			(start 0.7874 0.4064)
			(end 0.7874 -0.4064)
			(stroke
				(width 0.1524)
				(type default)
			)
			(layer "B.SilkS")
		)
		(fp_line
			(start 0.7874 -0.4064)
			(end -0.7874 -0.4064)
			(stroke
				(width 0.1524)
				(type default)
			)
			(layer "B.SilkS")
		)
		(fp_line
			(start -0.7874 0.4064)
			(end 0.7874 0.4064)
			(stroke
				(width 0.1524)
				(type default)
			)
			(layer "B.SilkS")
		)
		(fp_line
			(start -0.7874 -0.4064)
			(end -0.7874 0.4064)
			(stroke
				(width 0.1524)
				(type default)
			)
			(layer "B.SilkS")
		)
		(fp_line
			(start 0.67945 0.3048)
			(end 0.67945 -0.305054)
			(stroke
				(width 0.1)
				(type default)
			)
			(layer "B.Fab")
		)
		(fp_line
			(start 0.67945 -0.305054)
			(end 0.12065 -0.305054)
			(stroke
				(width 0.1)
				(type default)
			)
			(layer "B.Fab")
		)
		(fp_line
			(start 0.12065 0.3048)
			(end 0.67945 0.3048)
			(stroke
				(width 0.1)
				(type default)
			)
			(layer "B.Fab")
		)
		(fp_line
			(start 0.12065 0.2794)
			(end 0.12065 0.3048)
			(stroke
				(width 0.1)
				(type default)
			)
			(layer "B.Fab")
		)
		(fp_line
			(start 0.12065 -0.2794)
			(end -0.12065 -0.2794)
			(stroke
				(width 0.1)
				(type default)
			)
			(layer "B.Fab")
		)
		(fp_line
			(start 0.12065 -0.305054)
			(end 0.12065 -0.2794)
			(stroke
				(width 0.1)
				(type default)
			)
			(layer "B.Fab")
		)
		(fp_line
			(start -0.120396 0.3048)
			(end -0.120396 0.2794)
			(stroke
				(width 0.1)
				(type default)
			)
			(layer "B.Fab")
		)
		(fp_line
			(start -0.120396 0.2794)
			(end 0.12065 0.2794)
			(stroke
				(width 0.1)
				(type default)
			)
			(layer "B.Fab")
		)
		(fp_line
			(start -0.12065 -0.2794)
			(end -0.12065 -0.3048)
			(stroke
				(width 0.1)
				(type default)
			)
			(layer "B.Fab")
		)
		(fp_line
			(start -0.12065 -0.3048)
			(end -0.67945 -0.3048)
			(stroke
				(width 0.1)
				(type default)
			)
			(layer "B.Fab")
		)
		(fp_line
			(start -0.67945 0.3048)
			(end -0.120396 0.3048)
			(stroke
				(width 0.1)
				(type default)
			)
			(layer "B.Fab")
		)
		(fp_line
			(start -0.67945 -0.3048)
			(end -0.67945 0.3048)
			(stroke
				(width 0.1)
				(type default)
			)
			(layer "B.Fab")
		)
		(pad "1" smd circle
			(at 0.40005 0)
			(size 0 0)
			(layers "B.Cu" "B.Mask" "B.Paste")
			(net "NIC7_LD_N")
		)
		(pad "2" smd circle
			(at -0.40005 0)
			(size 0 0)
			(layers "B.Cu" "B.Mask" "B.Paste")
			(net "P3V3_NIC7")
		)
	)
	(footprint ""
		(layer "B.Cu")
		(at 421.700198 -110.978696)
		(property "Reference" "C956"
			(at 0 0 0)
			(layer "B.SilkS")
			(hide yes)
			(effects
				(font
					(size 1.27 1.27)
				)
				(justify mirror)
			)
		)
		(property "Value" ""
			(at 0 0 0)
			(layer "B.Fab")
			(effects
				(font
					(size 1.27 1.27)
				)
				(justify mirror)
			)
		)
		(duplicate_pad_numbers_are_jumpers no)
		(fp_line
			(start -0.299974 -0.150114)
			(end -0.299974 0.150114)
			(stroke
				(width 0.1)
				(type default)
			)
			(layer "B.Fab")
		)
		(fp_line
			(start -0.299974 0.150114)
			(end 0.299974 0.150114)
			(stroke
				(width 0.1)
				(type default)
			)
			(layer "B.Fab")
		)
		(fp_line
			(start 0.299974 -0.150114)
			(end -0.299974 -0.150114)
			(stroke
				(width 0.1)
				(type default)
			)
			(layer "B.Fab")
		)
		(fp_line
			(start 0.299974 0.150114)
			(end 0.299974 -0.150114)
			(stroke
				(width 0.1)
				(type default)
			)
			(layer "B.Fab")
		)
		(pad "1" smd rect
			(at 0.2667 0 180)
			(size 0.3048 0.381)
			(layers "B.Cu" "B.Mask" "B.Paste")
			(net "P12V_NIC7")
		)
		(pad "2" smd rect
			(at -0.2667 0 180)
			(size 0.3048 0.381)
			(layers "B.Cu" "B.Mask" "B.Paste")
			(net "GND")
		)
	)
	(footprint ""
		(layer "B.Cu")
		(at 171.949872 -301.599854 -90)
		(property "Reference" "C1484"
			(at 0 0 90)
			(layer "B.SilkS")
			(hide yes)
			(effects
				(font
					(size 1.27 1.27)
				)
				(justify mirror)
			)
		)
		(property "Value" ""
			(at 0 0 90)
			(layer "B.Fab")
			(effects
				(font
					(size 1.27 1.27)
				)
				(justify mirror)
			)
		)
		(duplicate_pad_numbers_are_jumpers no)
		(fp_line
			(start -0.299974 0.150114)
			(end 0.299974 0.150114)
			(stroke
				(width 0.1)
				(type default)
			)
			(layer "B.Fab")
		)
		(fp_line
			(start 0.299974 0.150114)
			(end 0.299974 -0.150114)
			(stroke
				(width 0.1)
				(type default)
			)
			(layer "B.Fab")
		)
		(fp_line
			(start -0.299974 -0.150114)
			(end -0.299974 0.150114)
			(stroke
				(width 0.1)
				(type default)
			)
			(layer "B.Fab")
		)
		(fp_line
			(start 0.299974 -0.150114)
			(end -0.299974 -0.150114)
			(stroke
				(width 0.1)
				(type default)
			)
			(layer "B.Fab")
		)
		(pad "1" smd rect
			(at 0.2667 0 90)
			(size 0.3048 0.381)
			(layers "B.Cu" "B.Mask" "B.Paste")
			(net "P0V8_SERDES_VDDA_PEX1")
		)
		(pad "2" smd rect
			(at -0.2667 0 90)
			(size 0.3048 0.381)
			(layers "B.Cu" "B.Mask" "B.Paste")
			(net "GND")
		)
	)
	(footprint ""
		(layer "B.Cu")
		(at 342.094058 -217.187018 -90)
		(property "Reference" "C2054"
			(at 0 0 90)
			(layer "B.SilkS")
			(hide yes)
			(effects
				(font
					(size 1.27 1.27)
				)
				(justify mirror)
			)
		)
		(property "Value" ""
			(at 0 0 90)
			(layer "B.Fab")
			(effects
				(font
					(size 1.27 1.27)
				)
				(justify mirror)
			)
		)
		(duplicate_pad_numbers_are_jumpers no)
		(fp_line
			(start -0.69215 0.2921)
			(end 0.69215 0.2921)
			(stroke
				(width 0.1524)
				(type default)
			)
			(layer "B.SilkS")
		)
		(fp_line
			(start 0.69215 0.2921)
			(end 0.69215 -0.2921)
			(stroke
				(width 0.1524)
				(type default)
			)
			(layer "B.SilkS")
		)
		(fp_line
			(start -0.69215 -0.2921)
			(end -0.69215 0.2921)
			(stroke
				(width 0.1524)
				(type default)
			)
			(layer "B.SilkS")
		)
		(fp_line
			(start 0.69215 -0.2921)
			(end -0.69215 -0.2921)
			(stroke
				(width 0.1524)
				(type default)
			)
			(layer "B.SilkS")
		)
		(fp_line
			(start -0.51435 0.2794)
			(end 0.51435 0.2794)
			(stroke
				(width 0.1)
				(type default)
			)
			(layer "B.Fab")
		)
		(fp_line
			(start 0.51435 0.2794)
			(end 0.51435 -0.2794)
			(stroke
				(width 0.1)
				(type default)
			)
			(layer "B.Fab")
		)
		(fp_line
			(start -0.51435 -0.2794)
			(end -0.51435 0.2794)
			(stroke
				(width 0.1)
				(type default)
			)
			(layer "B.Fab")
		)
		(fp_line
			(start 0.51435 -0.2794)
			(end -0.51435 -0.2794)
			(stroke
				(width 0.1)
				(type default)
			)
			(layer "B.Fab")
		)
		(pad "1" smd circle
			(at 0.40005 0 90)
			(size 0 0)
			(layers "B.Cu" "B.Mask" "B.Paste")
			(net "P3V3_FPGA_VCCIO2")
		)
		(pad "2" smd circle
			(at -0.40005 0 90)
			(size 0 0)
			(layers "B.Cu" "B.Mask" "B.Paste")
			(net "GND")
		)
		(zone
			(layer "B.Cu")
			(hatch none 0.5)
			(connect_pads
				(clearance 0)
			)
			(min_thickness 0.25)
			(keepout
				(tracks not_allowed)
				(vias allowed)
				(pads allowed)
				(copperpour not_allowed)
				(footprints allowed)
			)
			(placement
				(enabled no)
				(sheetname "")
			)
			(fill
				(thermal_gap 0.5)
				(thermal_bridge_width 0.5)
				(island_removal_mode 0)
			)
			(polygon
				(pts
					(xy 342.006428 -216.996518) (xy 341.948262 -217.087958) (xy 341.948262 -217.287348) (xy 342.006428 -217.377518)
					(xy 342.181688 -217.377518) (xy 342.240108 -217.287348) (xy 342.240108 -217.087958) (xy 342.181942 -216.996518)
				)
			)
		)
	)
	(footprint ""
		(layer "B.Cu")
		(at 49.40808 -303.024794 180)
		(property "Reference" "C3011"
			(at 0 0 0)
			(layer "B.SilkS")
			(hide yes)
			(effects
				(font
					(size 1.27 1.27)
				)
				(justify mirror)
			)
		)
		(property "Value" ""
			(at 0 0 0)
			(layer "B.Fab")
			(effects
				(font
					(size 1.27 1.27)
				)
				(justify mirror)
			)
		)
		(duplicate_pad_numbers_are_jumpers no)
		(fp_line
			(start 0.299974 0.150114)
			(end 0.299974 -0.150114)
			(stroke
				(width 0.1)
				(type default)
			)
			(layer "B.Fab")
		)
		(fp_line
			(start 0.299974 -0.150114)
			(end -0.299974 -0.150114)
			(stroke
				(width 0.1)
				(type default)
			)
			(layer "B.Fab")
		)
		(fp_line
			(start -0.299974 0.150114)
			(end 0.299974 0.150114)
			(stroke
				(width 0.1)
				(type default)
			)
			(layer "B.Fab")
		)
		(fp_line
			(start -0.299974 -0.150114)
			(end -0.299974 0.150114)
			(stroke
				(width 0.1)
				(type default)
			)
			(layer "B.Fab")
		)
		(pad "1" smd rect
			(at 0.2667 0)
			(size 0.3048 0.381)
			(layers "B.Cu" "B.Mask" "B.Paste")
			(net "P1V8_VDDA_PEX0")
		)
		(pad "2" smd rect
			(at -0.2667 0)
			(size 0.3048 0.381)
			(layers "B.Cu" "B.Mask" "B.Paste")
			(net "GND")
		)
	)
	(footprint ""
		(layer "B.Cu")
		(at 293.797228 -108.465366)
		(property "Reference" "R284"
			(at 0 0 0)
			(layer "B.SilkS")
			(hide yes)
			(effects
				(font
					(size 1.27 1.27)
				)
				(justify mirror)
			)
		)
		(property "Value" ""
			(at 0 0 0)
			(layer "B.Fab")
			(effects
				(font
					(size 1.27 1.27)
				)
				(justify mirror)
			)
		)
		(duplicate_pad_numbers_are_jumpers no)
		(fp_line
			(start -0.7874 -0.4064)
			(end -0.7874 0.4064)
			(stroke
				(width 0.1524)
				(type default)
			)
			(layer "B.SilkS")
		)
		(fp_line
			(start -0.7874 0.4064)
			(end 0.7874 0.4064)
			(stroke
				(width 0.1524)
				(type default)
			)
			(layer "B.SilkS")
		)
		(fp_line
			(start 0.7874 -0.4064)
			(end -0.7874 -0.4064)
			(stroke
				(width 0.1524)
				(type default)
			)
			(layer "B.SilkS")
		)
		(fp_line
			(start 0.7874 0.4064)
			(end 0.7874 -0.4064)
			(stroke
				(width 0.1524)
				(type default)
			)
			(layer "B.SilkS")
		)
		(fp_line
			(start -0.67945 -0.3048)
			(end -0.67945 0.3048)
			(stroke
				(width 0.1)
				(type default)
			)
			(layer "B.Fab")
		)
		(fp_line
			(start -0.67945 0.3048)
			(end -0.120396 0.3048)
			(stroke
				(width 0.1)
				(type default)
			)
			(layer "B.Fab")
		)
		(fp_line
			(start -0.12065 -0.3048)
			(end -0.67945 -0.3048)
			(stroke
				(width 0.1)
				(type default)
			)
			(layer "B.Fab")
		)
		(fp_line
			(start -0.12065 -0.2794)
			(end -0.12065 -0.3048)
			(stroke
				(width 0.1)
				(type default)
			)
			(layer "B.Fab")
		)
		(fp_line
			(start -0.120396 0.2794)
			(end 0.12065 0.2794)
			(stroke
				(width 0.1)
				(type default)
			)
			(layer "B.Fab")
		)
		(fp_line
			(start -0.120396 0.3048)
			(end -0.120396 0.2794)
			(stroke
				(width 0.1)
				(type default)
			)
			(layer "B.Fab")
		)
		(fp_line
			(start 0.12065 -0.305054)
			(end 0.12065 -0.2794)
			(stroke
				(width 0.1)
				(type default)
			)
			(layer "B.Fab")
		)
		(fp_line
			(start 0.12065 -0.2794)
			(end -0.12065 -0.2794)
			(stroke
				(width 0.1)
				(type default)
			)
			(layer "B.Fab")
		)
		(fp_line
			(start 0.12065 0.2794)
			(end 0.12065 0.3048)
			(stroke
				(width 0.1)
				(type default)
			)
			(layer "B.Fab")
		)
		(fp_line
			(start 0.12065 0.3048)
			(end 0.67945 0.3048)
			(stroke
				(width 0.1)
				(type default)
			)
			(layer "B.Fab")
		)
		(fp_line
			(start 0.67945 -0.305054)
			(end 0.12065 -0.305054)
			(stroke
				(width 0.1)
				(type default)
			)
			(layer "B.Fab")
		)
		(fp_line
			(start 0.67945 0.3048)
			(end 0.67945 -0.305054)
			(stroke
				(width 0.1)
				(type default)
			)
			(layer "B.Fab")
		)
		(pad "1" smd circle
			(at 0.40005 0 180)
			(size 0 0)
			(layers "B.Cu" "B.Mask" "B.Paste")
			(net "NIC5_BIF0_N")
		)
		(pad "2" smd circle
			(at -0.40005 0 180)
			(size 0 0)
			(layers "B.Cu" "B.Mask" "B.Paste")
			(net "P3V3_AUX")
		)
	)
	(footprint ""
		(layer "B.Cu")
		(at 63.375286 -110.497366 180)
		(property "Reference" "R85"
			(at 0 0 0)
			(layer "B.SilkS")
			(hide yes)
			(effects
				(font
					(size 1.27 1.27)
				)
				(justify mirror)
			)
		)
		(property "Value" ""
			(at 0 0 0)
			(layer "B.Fab")
			(effects
				(font
					(size 1.27 1.27)
				)
				(justify mirror)
			)
		)
		(duplicate_pad_numbers_are_jumpers no)
		(fp_line
			(start 0.7874 0.4064)
			(end 0.7874 -0.4064)
			(stroke
				(width 0.1524)
				(type default)
			)
			(layer "B.SilkS")
		)
		(fp_line
			(start 0.7874 -0.4064)
			(end -0.7874 -0.4064)
			(stroke
				(width 0.1524)
				(type default)
			)
			(layer "B.SilkS")
		)
		(fp_line
			(start -0.7874 0.4064)
			(end 0.7874 0.4064)
			(stroke
				(width 0.1524)
				(type default)
			)
			(layer "B.SilkS")
		)
		(fp_line
			(start -0.7874 -0.4064)
			(end -0.7874 0.4064)
			(stroke
				(width 0.1524)
				(type default)
			)
			(layer "B.SilkS")
		)
		(fp_line
			(start 0.67945 0.3048)
			(end 0.67945 -0.305054)
			(stroke
				(width 0.1)
				(type default)
			)
			(layer "B.Fab")
		)
		(fp_line
			(start 0.67945 -0.305054)
			(end 0.12065 -0.305054)
			(stroke
				(width 0.1)
				(type default)
			)
			(layer "B.Fab")
		)
		(fp_line
			(start 0.12065 0.3048)
			(end 0.67945 0.3048)
			(stroke
				(width 0.1)
				(type default)
			)
			(layer "B.Fab")
		)
		(fp_line
			(start 0.12065 0.2794)
			(end 0.12065 0.3048)
			(stroke
				(width 0.1)
				(type default)
			)
			(layer "B.Fab")
		)
		(fp_line
			(start 0.12065 -0.2794)
			(end -0.12065 -0.2794)
			(stroke
				(width 0.1)
				(type default)
			)
			(layer "B.Fab")
		)
		(fp_line
			(start 0.12065 -0.305054)
			(end 0.12065 -0.2794)
			(stroke
				(width 0.1)
				(type default)
			)
			(layer "B.Fab")
		)
		(fp_line
			(start -0.120396 0.3048)
			(end -0.120396 0.2794)
			(stroke
				(width 0.1)
				(type default)
			)
			(layer "B.Fab")
		)
		(fp_line
			(start -0.120396 0.2794)
			(end 0.12065 0.2794)
			(stroke
				(width 0.1)
				(type default)
			)
			(layer "B.Fab")
		)
		(fp_line
			(start -0.12065 -0.2794)
			(end -0.12065 -0.3048)
			(stroke
				(width 0.1)
				(type default)
			)
			(layer "B.Fab")
		)
		(fp_line
			(start -0.12065 -0.3048)
			(end -0.67945 -0.3048)
			(stroke
				(width 0.1)
				(type default)
			)
			(layer "B.Fab")
		)
		(fp_line
			(start -0.67945 0.3048)
			(end -0.120396 0.3048)
			(stroke
				(width 0.1)
				(type default)
			)
			(layer "B.Fab")
		)
		(fp_line
			(start -0.67945 -0.3048)
			(end -0.67945 0.3048)
			(stroke
				(width 0.1)
				(type default)
			)
			(layer "B.Fab")
		)
		(pad "1" smd circle
			(at 0.40005 0)
			(size 0 0)
			(layers "B.Cu" "B.Mask" "B.Paste")
			(net "NIC1_BIF2_N")
		)
		(pad "2" smd circle
			(at -0.40005 0)
			(size 0 0)
			(layers "B.Cu" "B.Mask" "B.Paste")
			(net "GND")
		)
	)
	(footprint ""
		(layer "B.Cu")
		(at 114.641122 -325.175626 -90)
		(property "Reference" "C4212"
			(at 0 0 90)
			(layer "B.SilkS")
			(hide yes)
			(effects
				(font
					(size 1.27 1.27)
				)
				(justify mirror)
			)
		)
		(property "Value" ""
			(at 0 0 90)
			(layer "B.Fab")
			(effects
				(font
					(size 1.27 1.27)
				)
				(justify mirror)
			)
		)
		(duplicate_pad_numbers_are_jumpers no)
		(fp_line
			(start -1.2954 0.5842)
			(end 1.2954 0.5842)
			(stroke
				(width 0.1524)
				(type default)
			)
			(layer "B.SilkS")
		)
		(fp_line
			(start 1.2954 0.5842)
			(end 1.2954 -0.5842)
			(stroke
				(width 0.1524)
				(type default)
			)
			(layer "B.SilkS")
		)
		(fp_line
			(start -1.2954 -0.5842)
			(end -1.2954 0.5842)
			(stroke
				(width 0.1524)
				(type default)
			)
			(layer "B.SilkS")
		)
		(fp_line
			(start 1.2954 -0.5842)
			(end -1.2954 -0.5842)
			(stroke
				(width 0.1524)
				(type default)
			)
			(layer "B.SilkS")
		)
		(fp_line
			(start -0.8636 0.4572)
			(end 0.8636 0.4572)
			(stroke
				(width 0.1)
				(type default)
			)
			(layer "B.Fab")
		)
		(fp_line
			(start 0.8636 0.4572)
			(end 0.8636 0.4064)
			(stroke
				(width 0.1)
				(type default)
			)
			(layer "B.Fab")
		)
		(fp_line
			(start -1.1938 0.4064)
			(end -0.8636 0.4064)
			(stroke
				(width 0.1)
				(type default)
			)
			(layer "B.Fab")
		)
		(fp_line
			(start -0.8636 0.4064)
			(end -0.8636 0.4572)
			(stroke
				(width 0.1)
				(type default)
			)
			(layer "B.Fab")
		)
		(fp_line
			(start 0.8636 0.4064)
			(end 1.1938 0.4064)
			(stroke
				(width 0.1)
				(type default)
			)
			(layer "B.Fab")
		)
		(fp_line
			(start 1.1938 0.4064)
			(end 1.1938 -0.4064)
			(stroke
				(width 0.1)
				(type default)
			)
			(layer "B.Fab")
		)
		(fp_line
			(start -1.1938 -0.4064)
			(end -1.1938 0.4064)
			(stroke
				(width 0.1)
				(type default)
			)
			(layer "B.Fab")
		)
		(fp_line
			(start -0.8636 -0.4064)
			(end -1.1938 -0.4064)
			(stroke
				(width 0.1)
				(type default)
			)
			(layer "B.Fab")
		)
		(fp_line
			(start 0.8636 -0.4064)
			(end 0.8636 -0.4572)
			(stroke
				(width 0.1)
				(type default)
			)
			(layer "B.Fab")
		)
		(fp_line
			(start 1.1938 -0.4064)
			(end 0.8636 -0.4064)
			(stroke
				(width 0.1)
				(type default)
			)
			(layer "B.Fab")
		)
		(fp_line
			(start -0.8636 -0.4572)
			(end -0.8636 -0.4064)
			(stroke
				(width 0.1)
				(type default)
			)
			(layer "B.Fab")
		)
		(fp_line
			(start 0.8636 -0.4572)
			(end -0.8636 -0.4572)
			(stroke
				(width 0.1)
				(type default)
			)
			(layer "B.Fab")
		)
		(pad "1" smd rect
			(at 0.7366 0 180)
			(size 0.7112 0.8128)
			(layers "B.Cu" "B.Mask" "B.Paste")
			(net "P0V8_SERDES_VDDA_PEX0_C6")
		)
		(pad "2" smd rect
			(at -0.7366 0 180)
			(size 0.7112 0.8128)
			(layers "B.Cu" "B.Mask" "B.Paste")
			(net "GND")
		)
	)
	(footprint ""
		(layer "B.Cu")
		(at 389.89 -236.728 -90)
		(property "Reference" "C2566"
			(at 0 0 90)
			(layer "B.SilkS")
			(hide yes)
			(effects
				(font
					(size 1.27 1.27)
				)
				(justify mirror)
			)
		)
		(property "Value" ""
			(at 0 0 90)
			(layer "B.Fab")
			(effects
				(font
					(size 1.27 1.27)
				)
				(justify mirror)
			)
		)
		(duplicate_pad_numbers_are_jumpers no)
		(fp_line
			(start -0.7874 0.4064)
			(end 0.7874 0.4064)
			(stroke
				(width 0.1524)
				(type default)
			)
			(layer "B.SilkS")
		)
		(fp_line
			(start 0.7874 0.4064)
			(end 0.7874 -0.4064)
			(stroke
				(width 0.1524)
				(type default)
			)
			(layer "B.SilkS")
		)
		(fp_line
			(start -0.7874 -0.4064)
			(end -0.7874 0.4064)
			(stroke
				(width 0.1524)
				(type default)
			)
			(layer "B.SilkS")
		)
		(fp_line
			(start 0.7874 -0.4064)
			(end -0.7874 -0.4064)
			(stroke
				(width 0.1524)
				(type default)
			)
			(layer "B.SilkS")
		)
		(fp_line
			(start -0.67945 0.3048)
			(end -0.120396 0.3048)
			(stroke
				(width 0.1)
				(type default)
			)
			(layer "B.Fab")
		)
		(fp_line
			(start -0.120396 0.3048)
			(end -0.120396 0.2794)
			(stroke
				(width 0.1)
				(type default)
			)
			(layer "B.Fab")
		)
		(fp_line
			(start 0.12065 0.3048)
			(end 0.67945 0.3048)
			(stroke
				(width 0.1)
				(type default)
			)
			(layer "B.Fab")
		)
		(fp_line
			(start 0.67945 0.3048)
			(end 0.67945 -0.305054)
			(stroke
				(width 0.1)
				(type default)
			)
			(layer "B.Fab")
		)
		(fp_line
			(start -0.120396 0.2794)
			(end 0.12065 0.2794)
			(stroke
				(width 0.1)
				(type default)
			)
			(layer "B.Fab")
		)
		(fp_line
			(start 0.12065 0.2794)
			(end 0.12065 0.3048)
			(stroke
				(width 0.1)
				(type default)
			)
			(layer "B.Fab")
		)
		(fp_line
			(start -0.12065 -0.2794)
			(end -0.12065 -0.3048)
			(stroke
				(width 0.1)
				(type default)
			)
			(layer "B.Fab")
		)
		(fp_line
			(start 0.12065 -0.2794)
			(end -0.12065 -0.2794)
			(stroke
				(width 0.1)
				(type default)
			)
			(layer "B.Fab")
		)
		(fp_line
			(start -0.67945 -0.3048)
			(end -0.67945 0.3048)
			(stroke
				(width 0.1)
				(type default)
			)
			(layer "B.Fab")
		)
		(fp_line
			(start -0.12065 -0.3048)
			(end -0.67945 -0.3048)
			(stroke
				(width 0.1)
				(type default)
			)
			(layer "B.Fab")
		)
		(fp_line
			(start 0.12065 -0.305054)
			(end 0.12065 -0.2794)
			(stroke
				(width 0.1)
				(type default)
			)
			(layer "B.Fab")
		)
		(fp_line
			(start 0.67945 -0.305054)
			(end 0.12065 -0.305054)
			(stroke
				(width 0.1)
				(type default)
			)
			(layer "B.Fab")
		)
		(pad "1" smd circle
			(at 0.40005 0 90)
			(size 0 0)
			(layers "B.Cu" "B.Mask" "B.Paste")
			(net "P3V3_AUX")
		)
		(pad "2" smd circle
			(at -0.40005 0 90)
			(size 0 0)
			(layers "B.Cu" "B.Mask" "B.Paste")
			(net "GND")
		)
	)
	(footprint ""
		(layer "B.Cu")
		(at 406.999948 -292.099746 90)
		(property "Reference" "C1926"
			(at 0 0 90)
			(layer "B.SilkS")
			(hide yes)
			(effects
				(font
					(size 1.27 1.27)
				)
				(justify mirror)
			)
		)
		(property "Value" ""
			(at 0 0 90)
			(layer "B.Fab")
			(effects
				(font
					(size 1.27 1.27)
				)
				(justify mirror)
			)
		)
		(duplicate_pad_numbers_are_jumpers no)
		(fp_line
			(start 0.299974 -0.150114)
			(end -0.299974 -0.150114)
			(stroke
				(width 0.1)
				(type default)
			)
			(layer "B.Fab")
		)
		(fp_line
			(start -0.299974 -0.150114)
			(end -0.299974 0.150114)
			(stroke
				(width 0.1)
				(type default)
			)
			(layer "B.Fab")
		)
		(fp_line
			(start 0.299974 0.150114)
			(end 0.299974 -0.150114)
			(stroke
				(width 0.1)
				(type default)
			)
			(layer "B.Fab")
		)
		(fp_line
			(start -0.299974 0.150114)
			(end 0.299974 0.150114)
			(stroke
				(width 0.1)
				(type default)
			)
			(layer "B.Fab")
		)
		(pad "1" smd rect
			(at 0.2667 0 270)
			(size 0.3048 0.381)
			(layers "B.Cu" "B.Mask" "B.Paste")
			(net "P0V8_SERDES_VDDA_PEX3")
		)
		(pad "2" smd rect
			(at -0.2667 0 270)
			(size 0.3048 0.381)
			(layers "B.Cu" "B.Mask" "B.Paste")
			(net "GND")
		)
	)
	(footprint ""
		(layer "B.Cu")
		(at 57.274968 -286.399732 90)
		(property "Reference" "C2951"
			(at 0 0 90)
			(layer "B.SilkS")
			(hide yes)
			(effects
				(font
					(size 1.27 1.27)
				)
				(justify mirror)
			)
		)
		(property "Value" ""
			(at 0 0 90)
			(layer "B.Fab")
			(effects
				(font
					(size 1.27 1.27)
				)
				(justify mirror)
			)
		)
		(duplicate_pad_numbers_are_jumpers no)
		(fp_line
			(start 0.299974 -0.150114)
			(end -0.299974 -0.150114)
			(stroke
				(width 0.1)
				(type default)
			)
			(layer "B.Fab")
		)
		(fp_line
			(start -0.299974 -0.150114)
			(end -0.299974 0.150114)
			(stroke
				(width 0.1)
				(type default)
			)
			(layer "B.Fab")
		)
		(fp_line
			(start 0.299974 0.150114)
			(end 0.299974 -0.150114)
			(stroke
				(width 0.1)
				(type default)
			)
			(layer "B.Fab")
		)
		(fp_line
			(start -0.299974 0.150114)
			(end 0.299974 0.150114)
			(stroke
				(width 0.1)
				(type default)
			)
			(layer "B.Fab")
		)
		(pad "1" smd rect
			(at 0.2667 0 270)
			(size 0.3048 0.381)
			(layers "B.Cu" "B.Mask" "B.Paste")
			(net "P1V25_SERDES_VDDPLL_PEX0")
		)
		(pad "2" smd rect
			(at -0.2667 0 270)
			(size 0.3048 0.381)
			(layers "B.Cu" "B.Mask" "B.Paste")
			(net "GND")
		)
	)
	(footprint ""
		(layer "B.Cu")
		(at 29.741622 -225.76663 180)
		(property "Reference" "R6163"
			(at 0 0 0)
			(layer "B.SilkS")
			(hide yes)
			(effects
				(font
					(size 1.27 1.27)
				)
				(justify mirror)
			)
		)
		(property "Value" ""
			(at 0 0 0)
			(layer "B.Fab")
			(effects
				(font
					(size 1.27 1.27)
				)
				(justify mirror)
			)
		)
		(duplicate_pad_numbers_are_jumpers no)
		(fp_line
			(start 0.7874 0.4064)
			(end 0.7874 -0.4064)
			(stroke
				(width 0.1524)
				(type default)
			)
			(layer "B.SilkS")
		)
		(fp_line
			(start 0.7874 -0.4064)
			(end -0.7874 -0.4064)
			(stroke
				(width 0.1524)
				(type default)
			)
			(layer "B.SilkS")
		)
		(fp_line
			(start -0.7874 0.4064)
			(end 0.7874 0.4064)
			(stroke
				(width 0.1524)
				(type default)
			)
			(layer "B.SilkS")
		)
		(fp_line
			(start -0.7874 -0.4064)
			(end -0.7874 0.4064)
			(stroke
				(width 0.1524)
				(type default)
			)
			(layer "B.SilkS")
		)
		(fp_line
			(start 0.67945 0.3048)
			(end 0.67945 -0.305054)
			(stroke
				(width 0.1)
				(type default)
			)
			(layer "B.Fab")
		)
		(fp_line
			(start 0.67945 -0.305054)
			(end 0.12065 -0.305054)
			(stroke
				(width 0.1)
				(type default)
			)
			(layer "B.Fab")
		)
		(fp_line
			(start 0.12065 0.3048)
			(end 0.67945 0.3048)
			(stroke
				(width 0.1)
				(type default)
			)
			(layer "B.Fab")
		)
		(fp_line
			(start 0.12065 0.2794)
			(end 0.12065 0.3048)
			(stroke
				(width 0.1)
				(type default)
			)
			(layer "B.Fab")
		)
		(fp_line
			(start 0.12065 -0.2794)
			(end -0.12065 -0.2794)
			(stroke
				(width 0.1)
				(type default)
			)
			(layer "B.Fab")
		)
		(fp_line
			(start 0.12065 -0.305054)
			(end 0.12065 -0.2794)
			(stroke
				(width 0.1)
				(type default)
			)
			(layer "B.Fab")
		)
		(fp_line
			(start -0.120396 0.3048)
			(end -0.120396 0.2794)
			(stroke
				(width 0.1)
				(type default)
			)
			(layer "B.Fab")
		)
		(fp_line
			(start -0.120396 0.2794)
			(end 0.12065 0.2794)
			(stroke
				(width 0.1)
				(type default)
			)
			(layer "B.Fab")
		)
		(fp_line
			(start -0.12065 -0.2794)
			(end -0.12065 -0.3048)
			(stroke
				(width 0.1)
				(type default)
			)
			(layer "B.Fab")
		)
		(fp_line
			(start -0.12065 -0.3048)
			(end -0.67945 -0.3048)
			(stroke
				(width 0.1)
				(type default)
			)
			(layer "B.Fab")
		)
		(fp_line
			(start -0.67945 0.3048)
			(end -0.120396 0.3048)
			(stroke
				(width 0.1)
				(type default)
			)
			(layer "B.Fab")
		)
		(fp_line
			(start -0.67945 -0.3048)
			(end -0.67945 0.3048)
			(stroke
				(width 0.1)
				(type default)
			)
			(layer "B.Fab")
		)
		(pad "1" smd circle
			(at 0.40005 0)
			(size 0 0)
			(layers "B.Cu" "B.Mask" "B.Paste")
			(net "SPI_PEX0_RST_R_N")
		)
		(pad "2" smd circle
			(at -0.40005 0)
			(size 0 0)
			(layers "B.Cu" "B.Mask" "B.Paste")
			(net "P1V8_PEX")
		)
	)
	(footprint ""
		(layer "B.Cu")
		(at 282.824936 -297.79976 -90)
		(property "Reference" "C1662"
			(at 0 0 90)
			(layer "B.SilkS")
			(hide yes)
			(effects
				(font
					(size 1.27 1.27)
				)
				(justify mirror)
			)
		)
		(property "Value" ""
			(at 0 0 90)
			(layer "B.Fab")
			(effects
				(font
					(size 1.27 1.27)
				)
				(justify mirror)
			)
		)
		(duplicate_pad_numbers_are_jumpers no)
		(fp_line
			(start -0.299974 0.150114)
			(end 0.299974 0.150114)
			(stroke
				(width 0.1)
				(type default)
			)
			(layer "B.Fab")
		)
		(fp_line
			(start 0.299974 0.150114)
			(end 0.299974 -0.150114)
			(stroke
				(width 0.1)
				(type default)
			)
			(layer "B.Fab")
		)
		(fp_line
			(start -0.299974 -0.150114)
			(end -0.299974 0.150114)
			(stroke
				(width 0.1)
				(type default)
			)
			(layer "B.Fab")
		)
		(fp_line
			(start 0.299974 -0.150114)
			(end -0.299974 -0.150114)
			(stroke
				(width 0.1)
				(type default)
			)
			(layer "B.Fab")
		)
		(pad "1" smd rect
			(at 0.2667 0 90)
			(size 0.3048 0.381)
			(layers "B.Cu" "B.Mask" "B.Paste")
			(net "P0V8_PEX2")
		)
		(pad "2" smd rect
			(at -0.2667 0 90)
			(size 0.3048 0.381)
			(layers "B.Cu" "B.Mask" "B.Paste")
			(net "GND")
		)
	)
	(footprint ""
		(layer "B.Cu")
		(at 301.824898 -304.241454 90)
		(property "Reference" "C3359"
			(at 0 0 90)
			(layer "B.SilkS")
			(hide yes)
			(effects
				(font
					(size 1.27 1.27)
				)
				(justify mirror)
			)
		)
		(property "Value" ""
			(at 0 0 90)
			(layer "B.Fab")
			(effects
				(font
					(size 1.27 1.27)
				)
				(justify mirror)
			)
		)
		(duplicate_pad_numbers_are_jumpers no)
		(fp_line
			(start 0.299974 -0.150114)
			(end -0.299974 -0.150114)
			(stroke
				(width 0.1)
				(type default)
			)
			(layer "B.Fab")
		)
		(fp_line
			(start -0.299974 -0.150114)
			(end -0.299974 0.150114)
			(stroke
				(width 0.1)
				(type default)
			)
			(layer "B.Fab")
		)
		(fp_line
			(start 0.299974 0.150114)
			(end 0.299974 -0.150114)
			(stroke
				(width 0.1)
				(type default)
			)
			(layer "B.Fab")
		)
		(fp_line
			(start -0.299974 0.150114)
			(end 0.299974 0.150114)
			(stroke
				(width 0.1)
				(type default)
			)
			(layer "B.Fab")
		)
		(pad "1" smd rect
			(at 0.2667 0 270)
			(size 0.3048 0.381)
			(layers "B.Cu" "B.Mask" "B.Paste")
			(net "P1V8_VDDA_PEX2")
		)
		(pad "2" smd rect
			(at -0.2667 0 270)
			(size 0.3048 0.381)
			(layers "B.Cu" "B.Mask" "B.Paste")
			(net "GND")
		)
	)
	(footprint ""
		(layer "B.Cu")
		(at 58.177176 -286.399732 90)
		(property "Reference" "C2958"
			(at 0 0 90)
			(layer "B.SilkS")
			(hide yes)
			(effects
				(font
					(size 1.27 1.27)
				)
				(justify mirror)
			)
		)
		(property "Value" ""
			(at 0 0 90)
			(layer "B.Fab")
			(effects
				(font
					(size 1.27 1.27)
				)
				(justify mirror)
			)
		)
		(duplicate_pad_numbers_are_jumpers no)
		(fp_line
			(start 0.299974 -0.150114)
			(end -0.299974 -0.150114)
			(stroke
				(width 0.1)
				(type default)
			)
			(layer "B.Fab")
		)
		(fp_line
			(start -0.299974 -0.150114)
			(end -0.299974 0.150114)
			(stroke
				(width 0.1)
				(type default)
			)
			(layer "B.Fab")
		)
		(fp_line
			(start 0.299974 0.150114)
			(end 0.299974 -0.150114)
			(stroke
				(width 0.1)
				(type default)
			)
			(layer "B.Fab")
		)
		(fp_line
			(start -0.299974 0.150114)
			(end 0.299974 0.150114)
			(stroke
				(width 0.1)
				(type default)
			)
			(layer "B.Fab")
		)
		(pad "1" smd rect
			(at 0.2667 0 270)
			(size 0.3048 0.381)
			(layers "B.Cu" "B.Mask" "B.Paste")
			(net "P1V25_SERDES_VDDPLL_PEX0")
		)
		(pad "2" smd rect
			(at -0.2667 0 270)
			(size 0.3048 0.381)
			(layers "B.Cu" "B.Mask" "B.Paste")
			(net "GND")
		)
	)
	(footprint ""
		(layer "B.Cu")
		(at 340.494112 -217.187018 -90)
		(property "Reference" "C2057"
			(at 0 0 90)
			(layer "B.SilkS")
			(hide yes)
			(effects
				(font
					(size 1.27 1.27)
				)
				(justify mirror)
			)
		)
		(property "Value" ""
			(at 0 0 90)
			(layer "B.Fab")
			(effects
				(font
					(size 1.27 1.27)
				)
				(justify mirror)
			)
		)
		(duplicate_pad_numbers_are_jumpers no)
		(fp_line
			(start -0.69215 0.2921)
			(end 0.69215 0.2921)
			(stroke
				(width 0.1524)
				(type default)
			)
			(layer "B.SilkS")
		)
		(fp_line
			(start 0.69215 0.2921)
			(end 0.69215 -0.2921)
			(stroke
				(width 0.1524)
				(type default)
			)
			(layer "B.SilkS")
		)
		(fp_line
			(start -0.69215 -0.2921)
			(end -0.69215 0.2921)
			(stroke
				(width 0.1524)
				(type default)
			)
			(layer "B.SilkS")
		)
		(fp_line
			(start 0.69215 -0.2921)
			(end -0.69215 -0.2921)
			(stroke
				(width 0.1524)
				(type default)
			)
			(layer "B.SilkS")
		)
		(fp_line
			(start -0.51435 0.2794)
			(end 0.51435 0.2794)
			(stroke
				(width 0.1)
				(type default)
			)
			(layer "B.Fab")
		)
		(fp_line
			(start 0.51435 0.2794)
			(end 0.51435 -0.2794)
			(stroke
				(width 0.1)
				(type default)
			)
			(layer "B.Fab")
		)
		(fp_line
			(start -0.51435 -0.2794)
			(end -0.51435 0.2794)
			(stroke
				(width 0.1)
				(type default)
			)
			(layer "B.Fab")
		)
		(fp_line
			(start 0.51435 -0.2794)
			(end -0.51435 -0.2794)
			(stroke
				(width 0.1)
				(type default)
			)
			(layer "B.Fab")
		)
		(pad "1" smd circle
			(at 0.40005 0 90)
			(size 0 0)
			(layers "B.Cu" "B.Mask" "B.Paste")
			(net "P3V3_FPGA_VCCIO2")
		)
		(pad "2" smd circle
			(at -0.40005 0 90)
			(size 0 0)
			(layers "B.Cu" "B.Mask" "B.Paste")
			(net "GND")
		)
		(zone
			(layer "B.Cu")
			(hatch none 0.5)
			(connect_pads
				(clearance 0)
			)
			(min_thickness 0.25)
			(keepout
				(tracks not_allowed)
				(vias allowed)
				(pads allowed)
				(copperpour not_allowed)
				(footprints allowed)
			)
			(placement
				(enabled no)
				(sheetname "")
			)
			(fill
				(thermal_gap 0.5)
				(thermal_bridge_width 0.5)
				(island_removal_mode 0)
			)
			(polygon
				(pts
					(xy 340.406482 -216.996518) (xy 340.348316 -217.087958) (xy 340.348316 -217.287348) (xy 340.406482 -217.377518)
					(xy 340.581742 -217.377518) (xy 340.640162 -217.287348) (xy 340.640162 -217.087958) (xy 340.581996 -216.996518)
				)
			)
		)
	)
	(footprint ""
		(layer "B.Cu")
		(at 231.410002 -256.168144)
		(property "Reference" "C4350"
			(at 0 0 0)
			(layer "B.SilkS")
			(hide yes)
			(effects
				(font
					(size 1.27 1.27)
				)
				(justify mirror)
			)
		)
		(property "Value" ""
			(at 0 0 0)
			(layer "B.Fab")
			(effects
				(font
					(size 1.27 1.27)
				)
				(justify mirror)
			)
		)
		(duplicate_pad_numbers_are_jumpers no)
		(fp_line
			(start -0.299974 -0.150114)
			(end -0.299974 0.150114)
			(stroke
				(width 0.1)
				(type default)
			)
			(layer "B.Fab")
		)
		(fp_line
			(start -0.299974 0.150114)
			(end 0.299974 0.150114)
			(stroke
				(width 0.1)
				(type default)
			)
			(layer "B.Fab")
		)
		(fp_line
			(start 0.299974 -0.150114)
			(end -0.299974 -0.150114)
			(stroke
				(width 0.1)
				(type default)
			)
			(layer "B.Fab")
		)
		(fp_line
			(start 0.299974 0.150114)
			(end 0.299974 -0.150114)
			(stroke
				(width 0.1)
				(type default)
			)
			(layer "B.Fab")
		)
		(pad "1" smd rect
			(at 0.2667 0 180)
			(size 0.3048 0.381)
			(layers "B.Cu" "B.Mask" "B.Paste")
			(net "P1V25_SERDES_VDDPLL_PEX2")
		)
		(pad "2" smd rect
			(at -0.2667 0 180)
			(size 0.3048 0.381)
			(layers "B.Cu" "B.Mask" "B.Paste")
			(net "GND")
		)
	)
	(footprint ""
		(layer "B.Cu")
		(at 185.250074 -301.124874)
		(property "Reference" "C3168"
			(at 0 0 0)
			(layer "B.SilkS")
			(hide yes)
			(effects
				(font
					(size 1.27 1.27)
				)
				(justify mirror)
			)
		)
		(property "Value" ""
			(at 0 0 0)
			(layer "B.Fab")
			(effects
				(font
					(size 1.27 1.27)
				)
				(justify mirror)
			)
		)
		(duplicate_pad_numbers_are_jumpers no)
		(fp_line
			(start -0.299974 -0.150114)
			(end -0.299974 0.150114)
			(stroke
				(width 0.1)
				(type default)
			)
			(layer "B.Fab")
		)
		(fp_line
			(start -0.299974 0.150114)
			(end 0.299974 0.150114)
			(stroke
				(width 0.1)
				(type default)
			)
			(layer "B.Fab")
		)
		(fp_line
			(start 0.299974 -0.150114)
			(end -0.299974 -0.150114)
			(stroke
				(width 0.1)
				(type default)
			)
			(layer "B.Fab")
		)
		(fp_line
			(start 0.299974 0.150114)
			(end 0.299974 -0.150114)
			(stroke
				(width 0.1)
				(type default)
			)
			(layer "B.Fab")
		)
		(pad "1" smd rect
			(at 0.2667 0 180)
			(size 0.3048 0.381)
			(layers "B.Cu" "B.Mask" "B.Paste")
			(net "P1V8_PEX")
		)
		(pad "2" smd rect
			(at -0.2667 0 180)
			(size 0.3048 0.381)
			(layers "B.Cu" "B.Mask" "B.Paste")
			(net "GND")
		)
	)
	(footprint ""
		(layer "B.Cu")
		(at 71.049896 -294.4749 180)
		(property "Reference" "C2928"
			(at 0 0 0)
			(layer "B.SilkS")
			(hide yes)
			(effects
				(font
					(size 1.27 1.27)
				)
				(justify mirror)
			)
		)
		(property "Value" ""
			(at 0 0 0)
			(layer "B.Fab")
			(effects
				(font
					(size 1.27 1.27)
				)
				(justify mirror)
			)
		)
		(duplicate_pad_numbers_are_jumpers no)
		(fp_line
			(start 0.299974 0.150114)
			(end 0.299974 -0.150114)
			(stroke
				(width 0.1)
				(type default)
			)
			(layer "B.Fab")
		)
		(fp_line
			(start 0.299974 -0.150114)
			(end -0.299974 -0.150114)
			(stroke
				(width 0.1)
				(type default)
			)
			(layer "B.Fab")
		)
		(fp_line
			(start -0.299974 0.150114)
			(end 0.299974 0.150114)
			(stroke
				(width 0.1)
				(type default)
			)
			(layer "B.Fab")
		)
		(fp_line
			(start -0.299974 -0.150114)
			(end -0.299974 0.150114)
			(stroke
				(width 0.1)
				(type default)
			)
			(layer "B.Fab")
		)
		(pad "1" smd rect
			(at 0.2667 0)
			(size 0.3048 0.381)
			(layers "B.Cu" "B.Mask" "B.Paste")
			(net "P1V25_PEX0")
		)
		(pad "2" smd rect
			(at -0.2667 0)
			(size 0.3048 0.381)
			(layers "B.Cu" "B.Mask" "B.Paste")
			(net "GND")
		)
	)
	(footprint ""
		(layer "B.Cu")
		(at 144.841214 -209.841846 -90)
		(property "Reference" "C2590"
			(at 0 0 90)
			(layer "B.SilkS")
			(hide yes)
			(effects
				(font
					(size 1.27 1.27)
				)
				(justify mirror)
			)
		)
		(property "Value" ""
			(at 0 0 90)
			(layer "B.Fab")
			(effects
				(font
					(size 1.27 1.27)
				)
				(justify mirror)
			)
		)
		(duplicate_pad_numbers_are_jumpers no)
		(fp_line
			(start -0.7874 0.4064)
			(end 0.7874 0.4064)
			(stroke
				(width 0.1524)
				(type default)
			)
			(layer "B.SilkS")
		)
		(fp_line
			(start 0.7874 0.4064)
			(end 0.7874 -0.4064)
			(stroke
				(width 0.1524)
				(type default)
			)
			(layer "B.SilkS")
		)
		(fp_line
			(start -0.7874 -0.4064)
			(end -0.7874 0.4064)
			(stroke
				(width 0.1524)
				(type default)
			)
			(layer "B.SilkS")
		)
		(fp_line
			(start 0.7874 -0.4064)
			(end -0.7874 -0.4064)
			(stroke
				(width 0.1524)
				(type default)
			)
			(layer "B.SilkS")
		)
		(fp_line
			(start -0.67945 0.3048)
			(end -0.120396 0.3048)
			(stroke
				(width 0.1)
				(type default)
			)
			(layer "B.Fab")
		)
		(fp_line
			(start -0.120396 0.3048)
			(end -0.120396 0.2794)
			(stroke
				(width 0.1)
				(type default)
			)
			(layer "B.Fab")
		)
		(fp_line
			(start 0.12065 0.3048)
			(end 0.67945 0.3048)
			(stroke
				(width 0.1)
				(type default)
			)
			(layer "B.Fab")
		)
		(fp_line
			(start 0.67945 0.3048)
			(end 0.67945 -0.305054)
			(stroke
				(width 0.1)
				(type default)
			)
			(layer "B.Fab")
		)
		(fp_line
			(start -0.120396 0.2794)
			(end 0.12065 0.2794)
			(stroke
				(width 0.1)
				(type default)
			)
			(layer "B.Fab")
		)
		(fp_line
			(start 0.12065 0.2794)
			(end 0.12065 0.3048)
			(stroke
				(width 0.1)
				(type default)
			)
			(layer "B.Fab")
		)
		(fp_line
			(start -0.12065 -0.2794)
			(end -0.12065 -0.3048)
			(stroke
				(width 0.1)
				(type default)
			)
			(layer "B.Fab")
		)
		(fp_line
			(start 0.12065 -0.2794)
			(end -0.12065 -0.2794)
			(stroke
				(width 0.1)
				(type default)
			)
			(layer "B.Fab")
		)
		(fp_line
			(start -0.67945 -0.3048)
			(end -0.67945 0.3048)
			(stroke
				(width 0.1)
				(type default)
			)
			(layer "B.Fab")
		)
		(fp_line
			(start -0.12065 -0.3048)
			(end -0.67945 -0.3048)
			(stroke
				(width 0.1)
				(type default)
			)
			(layer "B.Fab")
		)
		(fp_line
			(start 0.12065 -0.305054)
			(end 0.12065 -0.2794)
			(stroke
				(width 0.1)
				(type default)
			)
			(layer "B.Fab")
		)
		(fp_line
			(start 0.67945 -0.305054)
			(end 0.12065 -0.305054)
			(stroke
				(width 0.1)
				(type default)
			)
			(layer "B.Fab")
		)
		(pad "1" smd circle
			(at 0.40005 0 90)
			(size 0 0)
			(layers "B.Cu" "B.Mask" "B.Paste")
			(net "P3V3_AUX")
		)
		(pad "2" smd circle
			(at -0.40005 0 90)
			(size 0 0)
			(layers "B.Cu" "B.Mask" "B.Paste")
			(net "GND")
		)
	)
	(footprint ""
		(layer "B.Cu")
		(at 6.93166 -388.602474 180)
		(property "Reference" "C4463"
			(at 0 0 0)
			(layer "B.SilkS")
			(hide yes)
			(effects
				(font
					(size 1.27 1.27)
				)
				(justify mirror)
			)
		)
		(property "Value" ""
			(at 0 0 0)
			(layer "B.Fab")
			(effects
				(font
					(size 1.27 1.27)
				)
				(justify mirror)
			)
		)
		(duplicate_pad_numbers_are_jumpers no)
		(fp_line
			(start 0.7874 0.4064)
			(end 0.7874 -0.4064)
			(stroke
				(width 0.1524)
				(type default)
			)
			(layer "B.SilkS")
		)
		(fp_line
			(start 0.7874 -0.4064)
			(end -0.7874 -0.4064)
			(stroke
				(width 0.1524)
				(type default)
			)
			(layer "B.SilkS")
		)
		(fp_line
			(start -0.7874 0.4064)
			(end 0.7874 0.4064)
			(stroke
				(width 0.1524)
				(type default)
			)
			(layer "B.SilkS")
		)
		(fp_line
			(start -0.7874 -0.4064)
			(end -0.7874 0.4064)
			(stroke
				(width 0.1524)
				(type default)
			)
			(layer "B.SilkS")
		)
		(fp_line
			(start 0.67945 0.3048)
			(end 0.67945 -0.305054)
			(stroke
				(width 0.1)
				(type default)
			)
			(layer "B.Fab")
		)
		(fp_line
			(start 0.67945 -0.305054)
			(end 0.12065 -0.305054)
			(stroke
				(width 0.1)
				(type default)
			)
			(layer "B.Fab")
		)
		(fp_line
			(start 0.12065 0.3048)
			(end 0.67945 0.3048)
			(stroke
				(width 0.1)
				(type default)
			)
			(layer "B.Fab")
		)
		(fp_line
			(start 0.12065 0.2794)
			(end 0.12065 0.3048)
			(stroke
				(width 0.1)
				(type default)
			)
			(layer "B.Fab")
		)
		(fp_line
			(start 0.12065 -0.2794)
			(end -0.12065 -0.2794)
			(stroke
				(width 0.1)
				(type default)
			)
			(layer "B.Fab")
		)
		(fp_line
			(start 0.12065 -0.305054)
			(end 0.12065 -0.2794)
			(stroke
				(width 0.1)
				(type default)
			)
			(layer "B.Fab")
		)
		(fp_line
			(start -0.120396 0.3048)
			(end -0.120396 0.2794)
			(stroke
				(width 0.1)
				(type default)
			)
			(layer "B.Fab")
		)
		(fp_line
			(start -0.120396 0.2794)
			(end 0.12065 0.2794)
			(stroke
				(width 0.1)
				(type default)
			)
			(layer "B.Fab")
		)
		(fp_line
			(start -0.12065 -0.2794)
			(end -0.12065 -0.3048)
			(stroke
				(width 0.1)
				(type default)
			)
			(layer "B.Fab")
		)
		(fp_line
			(start -0.12065 -0.3048)
			(end -0.67945 -0.3048)
			(stroke
				(width 0.1)
				(type default)
			)
			(layer "B.Fab")
		)
		(fp_line
			(start -0.67945 0.3048)
			(end -0.120396 0.3048)
			(stroke
				(width 0.1)
				(type default)
			)
			(layer "B.Fab")
		)
		(fp_line
			(start -0.67945 -0.3048)
			(end -0.67945 0.3048)
			(stroke
				(width 0.1)
				(type default)
			)
			(layer "B.Fab")
		)
		(pad "1" smd circle
			(at 0.40005 0)
			(size 0 0)
			(layers "B.Cu" "B.Mask" "B.Paste")
			(net "P3V3_USB_8042")
		)
		(pad "2" smd circle
			(at -0.40005 0)
			(size 0 0)
			(layers "B.Cu" "B.Mask" "B.Paste")
			(net "GND")
		)
	)
	(footprint ""
		(layer "B.Cu")
		(at 242.051078 -234.056428 -90)
		(property "Reference" "C4489"
			(at 0 0 90)
			(layer "B.SilkS")
			(hide yes)
			(effects
				(font
					(size 1.27 1.27)
				)
				(justify mirror)
			)
		)
		(property "Value" ""
			(at 0 0 90)
			(layer "B.Fab")
			(effects
				(font
					(size 1.27 1.27)
				)
				(justify mirror)
			)
		)
		(duplicate_pad_numbers_are_jumpers no)
		(fp_line
			(start -0.7874 0.4064)
			(end 0.7874 0.4064)
			(stroke
				(width 0.1524)
				(type default)
			)
			(layer "B.SilkS")
		)
		(fp_line
			(start 0.7874 0.4064)
			(end 0.7874 -0.4064)
			(stroke
				(width 0.1524)
				(type default)
			)
			(layer "B.SilkS")
		)
		(fp_line
			(start -0.7874 -0.4064)
			(end -0.7874 0.4064)
			(stroke
				(width 0.1524)
				(type default)
			)
			(layer "B.SilkS")
		)
		(fp_line
			(start 0.7874 -0.4064)
			(end -0.7874 -0.4064)
			(stroke
				(width 0.1524)
				(type default)
			)
			(layer "B.SilkS")
		)
		(fp_line
			(start -0.67945 0.3048)
			(end -0.120396 0.3048)
			(stroke
				(width 0.1)
				(type default)
			)
			(layer "B.Fab")
		)
		(fp_line
			(start -0.120396 0.3048)
			(end -0.120396 0.2794)
			(stroke
				(width 0.1)
				(type default)
			)
			(layer "B.Fab")
		)
		(fp_line
			(start 0.12065 0.3048)
			(end 0.67945 0.3048)
			(stroke
				(width 0.1)
				(type default)
			)
			(layer "B.Fab")
		)
		(fp_line
			(start 0.67945 0.3048)
			(end 0.67945 -0.305054)
			(stroke
				(width 0.1)
				(type default)
			)
			(layer "B.Fab")
		)
		(fp_line
			(start -0.120396 0.2794)
			(end 0.12065 0.2794)
			(stroke
				(width 0.1)
				(type default)
			)
			(layer "B.Fab")
		)
		(fp_line
			(start 0.12065 0.2794)
			(end 0.12065 0.3048)
			(stroke
				(width 0.1)
				(type default)
			)
			(layer "B.Fab")
		)
		(fp_line
			(start -0.12065 -0.2794)
			(end -0.12065 -0.3048)
			(stroke
				(width 0.1)
				(type default)
			)
			(layer "B.Fab")
		)
		(fp_line
			(start 0.12065 -0.2794)
			(end -0.12065 -0.2794)
			(stroke
				(width 0.1)
				(type default)
			)
			(layer "B.Fab")
		)
		(fp_line
			(start -0.67945 -0.3048)
			(end -0.67945 0.3048)
			(stroke
				(width 0.1)
				(type default)
			)
			(layer "B.Fab")
		)
		(fp_line
			(start -0.12065 -0.3048)
			(end -0.67945 -0.3048)
			(stroke
				(width 0.1)
				(type default)
			)
			(layer "B.Fab")
		)
		(fp_line
			(start 0.12065 -0.305054)
			(end 0.12065 -0.2794)
			(stroke
				(width 0.1)
				(type default)
			)
			(layer "B.Fab")
		)
		(fp_line
			(start 0.67945 -0.305054)
			(end 0.12065 -0.305054)
			(stroke
				(width 0.1)
				(type default)
			)
			(layer "B.Fab")
		)
		(pad "1" smd circle
			(at 0.40005 0 90)
			(size 0 0)
			(layers "B.Cu" "B.Mask" "B.Paste")
			(net "BOARD_TYPE_2_ADC_R")
		)
		(pad "2" smd circle
			(at -0.40005 0 90)
			(size 0 0)
			(layers "B.Cu" "B.Mask" "B.Paste")
			(net "GND")
		)
	)
	(footprint ""
		(layer "B.Cu")
		(at 169.574972 -286.399732 90)
		(property "Reference" "C3150"
			(at 0 0 90)
			(layer "B.SilkS")
			(hide yes)
			(effects
				(font
					(size 1.27 1.27)
				)
				(justify mirror)
			)
		)
		(property "Value" ""
			(at 0 0 90)
			(layer "B.Fab")
			(effects
				(font
					(size 1.27 1.27)
				)
				(justify mirror)
			)
		)
		(duplicate_pad_numbers_are_jumpers no)
		(fp_line
			(start 0.299974 -0.150114)
			(end -0.299974 -0.150114)
			(stroke
				(width 0.1)
				(type default)
			)
			(layer "B.Fab")
		)
		(fp_line
			(start -0.299974 -0.150114)
			(end -0.299974 0.150114)
			(stroke
				(width 0.1)
				(type default)
			)
			(layer "B.Fab")
		)
		(fp_line
			(start 0.299974 0.150114)
			(end 0.299974 -0.150114)
			(stroke
				(width 0.1)
				(type default)
			)
			(layer "B.Fab")
		)
		(fp_line
			(start -0.299974 0.150114)
			(end 0.299974 0.150114)
			(stroke
				(width 0.1)
				(type default)
			)
			(layer "B.Fab")
		)
		(pad "1" smd rect
			(at 0.2667 0 270)
			(size 0.3048 0.381)
			(layers "B.Cu" "B.Mask" "B.Paste")
			(net "P1V25_SERDES_VDDPLL_PEX1")
		)
		(pad "2" smd rect
			(at -0.2667 0 270)
			(size 0.3048 0.381)
			(layers "B.Cu" "B.Mask" "B.Paste")
			(net "GND")
		)
	)
	(footprint ""
		(layer "B.Cu")
		(at 288.469832 -305.399948 -90)
		(property "Reference" "C3311"
			(at 0 0 90)
			(layer "B.SilkS")
			(hide yes)
			(effects
				(font
					(size 1.27 1.27)
				)
				(justify mirror)
			)
		)
		(property "Value" ""
			(at 0 0 90)
			(layer "B.Fab")
			(effects
				(font
					(size 1.27 1.27)
				)
				(justify mirror)
			)
		)
		(duplicate_pad_numbers_are_jumpers no)
		(fp_line
			(start -0.299974 0.150114)
			(end 0.299974 0.150114)
			(stroke
				(width 0.1)
				(type default)
			)
			(layer "B.Fab")
		)
		(fp_line
			(start 0.299974 0.150114)
			(end 0.299974 -0.150114)
			(stroke
				(width 0.1)
				(type default)
			)
			(layer "B.Fab")
		)
		(fp_line
			(start -0.299974 -0.150114)
			(end -0.299974 0.150114)
			(stroke
				(width 0.1)
				(type default)
			)
			(layer "B.Fab")
		)
		(fp_line
			(start 0.299974 -0.150114)
			(end -0.299974 -0.150114)
			(stroke
				(width 0.1)
				(type default)
			)
			(layer "B.Fab")
		)
		(pad "1" smd rect
			(at 0.2667 0 90)
			(size 0.3048 0.381)
			(layers "B.Cu" "B.Mask" "B.Paste")
			(net "P1V25_SERDES_VDDPLL_PEX2")
		)
		(pad "2" smd rect
			(at -0.2667 0 90)
			(size 0.3048 0.381)
			(layers "B.Cu" "B.Mask" "B.Paste")
			(net "GND")
		)
	)
	(footprint ""
		(layer "B.Cu")
		(at 394.164312 -146.148552 180)
		(property "Reference" "C939"
			(at 0 0 0)
			(layer "B.SilkS")
			(hide yes)
			(effects
				(font
					(size 1.27 1.27)
				)
				(justify mirror)
			)
		)
		(property "Value" ""
			(at 0 0 0)
			(layer "B.Fab")
			(effects
				(font
					(size 1.27 1.27)
				)
				(justify mirror)
			)
		)
		(duplicate_pad_numbers_are_jumpers no)
		(fp_line
			(start 0.299974 0.150114)
			(end 0.299974 -0.150114)
			(stroke
				(width 0.1)
				(type default)
			)
			(layer "B.Fab")
		)
		(fp_line
			(start 0.299974 -0.150114)
			(end -0.299974 -0.150114)
			(stroke
				(width 0.1)
				(type default)
			)
			(layer "B.Fab")
		)
		(fp_line
			(start -0.299974 0.150114)
			(end 0.299974 0.150114)
			(stroke
				(width 0.1)
				(type default)
			)
			(layer "B.Fab")
		)
		(fp_line
			(start -0.299974 -0.150114)
			(end -0.299974 0.150114)
			(stroke
				(width 0.1)
				(type default)
			)
			(layer "B.Fab")
		)
		(pad "1" smd rect
			(at 0.2667 0)
			(size 0.3048 0.381)
			(layers "B.Cu" "B.Mask" "B.Paste")
			(net "P12V_NIC6")
		)
		(pad "2" smd rect
			(at -0.2667 0)
			(size 0.3048 0.381)
			(layers "B.Cu" "B.Mask" "B.Paste")
			(net "GND")
		)
	)
	(footprint ""
		(layer "B.Cu")
		(at 128.470914 -182.604664 -90)
		(property "Reference" "R1120"
			(at 0 0 90)
			(layer "B.SilkS")
			(hide yes)
			(effects
				(font
					(size 1.27 1.27)
				)
				(justify mirror)
			)
		)
		(property "Value" ""
			(at 0 0 90)
			(layer "B.Fab")
			(effects
				(font
					(size 1.27 1.27)
				)
				(justify mirror)
			)
		)
		(duplicate_pad_numbers_are_jumpers no)
		(fp_line
			(start -0.7874 0.4064)
			(end 0.7874 0.4064)
			(stroke
				(width 0.1524)
				(type default)
			)
			(layer "B.SilkS")
		)
		(fp_line
			(start 0.7874 0.4064)
			(end 0.7874 -0.4064)
			(stroke
				(width 0.1524)
				(type default)
			)
			(layer "B.SilkS")
		)
		(fp_line
			(start -0.7874 -0.4064)
			(end -0.7874 0.4064)
			(stroke
				(width 0.1524)
				(type default)
			)
			(layer "B.SilkS")
		)
		(fp_line
			(start 0.7874 -0.4064)
			(end -0.7874 -0.4064)
			(stroke
				(width 0.1524)
				(type default)
			)
			(layer "B.SilkS")
		)
		(fp_line
			(start -0.67945 0.3048)
			(end -0.120396 0.3048)
			(stroke
				(width 0.1)
				(type default)
			)
			(layer "B.Fab")
		)
		(fp_line
			(start -0.120396 0.3048)
			(end -0.120396 0.2794)
			(stroke
				(width 0.1)
				(type default)
			)
			(layer "B.Fab")
		)
		(fp_line
			(start 0.12065 0.3048)
			(end 0.67945 0.3048)
			(stroke
				(width 0.1)
				(type default)
			)
			(layer "B.Fab")
		)
		(fp_line
			(start 0.67945 0.3048)
			(end 0.67945 -0.305054)
			(stroke
				(width 0.1)
				(type default)
			)
			(layer "B.Fab")
		)
		(fp_line
			(start -0.120396 0.2794)
			(end 0.12065 0.2794)
			(stroke
				(width 0.1)
				(type default)
			)
			(layer "B.Fab")
		)
		(fp_line
			(start 0.12065 0.2794)
			(end 0.12065 0.3048)
			(stroke
				(width 0.1)
				(type default)
			)
			(layer "B.Fab")
		)
		(fp_line
			(start -0.12065 -0.2794)
			(end -0.12065 -0.3048)
			(stroke
				(width 0.1)
				(type default)
			)
			(layer "B.Fab")
		)
		(fp_line
			(start 0.12065 -0.2794)
			(end -0.12065 -0.2794)
			(stroke
				(width 0.1)
				(type default)
			)
			(layer "B.Fab")
		)
		(fp_line
			(start -0.67945 -0.3048)
			(end -0.67945 0.3048)
			(stroke
				(width 0.1)
				(type default)
			)
			(layer "B.Fab")
		)
		(fp_line
			(start -0.12065 -0.3048)
			(end -0.67945 -0.3048)
			(stroke
				(width 0.1)
				(type default)
			)
			(layer "B.Fab")
		)
		(fp_line
			(start 0.12065 -0.305054)
			(end 0.12065 -0.2794)
			(stroke
				(width 0.1)
				(type default)
			)
			(layer "B.Fab")
		)
		(fp_line
			(start 0.67945 -0.305054)
			(end 0.12065 -0.305054)
			(stroke
				(width 0.1)
				(type default)
			)
			(layer "B.Fab")
		)
		(pad "1" smd circle
			(at 0.40005 0 90)
			(size 0 0)
			(layers "B.Cu" "B.Mask" "B.Paste")
			(net "FM_DB2000QL_SMB_SA0")
		)
		(pad "2" smd circle
			(at -0.40005 0 90)
			(size 0 0)
			(layers "B.Cu" "B.Mask" "B.Paste")
			(net "P3V3")
		)
	)
	(footprint ""
		(layer "B.Cu")
		(at 361.98048 -284.796738 -90)
		(property "Reference" "PC193"
			(at 0 0 90)
			(layer "B.SilkS")
			(hide yes)
			(effects
				(font
					(size 1.27 1.27)
				)
				(justify mirror)
			)
		)
		(property "Value" ""
			(at 0 0 90)
			(layer "B.Fab")
			(effects
				(font
					(size 1.27 1.27)
				)
				(justify mirror)
			)
		)
		(duplicate_pad_numbers_are_jumpers no)
		(fp_line
			(start -1.524 0.762)
			(end 1.524 0.762)
			(stroke
				(width 0.1524)
				(type default)
			)
			(layer "B.SilkS")
		)
		(fp_line
			(start 1.524 0.762)
			(end 1.524 -0.762)
			(stroke
				(width 0.1524)
				(type default)
			)
			(layer "B.SilkS")
		)
		(fp_line
			(start -1.524 -0.762)
			(end -1.524 0.762)
			(stroke
				(width 0.1524)
				(type default)
			)
			(layer "B.SilkS")
		)
		(fp_line
			(start 1.524 -0.762)
			(end -1.524 -0.762)
			(stroke
				(width 0.1524)
				(type default)
			)
			(layer "B.SilkS")
		)
		(fp_line
			(start -1.1049 0.724916)
			(end -1.1049 -0.724916)
			(stroke
				(width 0.1)
				(type default)
			)
			(layer "B.Fab")
		)
		(fp_line
			(start 1.1049 0.724916)
			(end -1.1049 0.724916)
			(stroke
				(width 0.1)
				(type default)
			)
			(layer "B.Fab")
		)
		(fp_line
			(start -1.1049 -0.724916)
			(end 1.1049 -0.724916)
			(stroke
				(width 0.1)
				(type default)
			)
			(layer "B.Fab")
		)
		(fp_line
			(start 1.1049 -0.724916)
			(end 1.1049 0.724916)
			(stroke
				(width 0.1)
				(type default)
			)
			(layer "B.Fab")
		)
		(pad "1" smd rect
			(at 0.889 0 270)
			(size 1.016 1.27)
			(layers "B.Cu" "B.Mask" "B.Paste")
			(net "SW_P12V_P0V8_PEX3_FLT")
		)
		(pad "2" smd rect
			(at -0.889 0 270)
			(size 1.016 1.27)
			(layers "B.Cu" "B.Mask" "B.Paste")
			(net "GND")
		)
	)
	(footprint ""
		(layer "B.Cu")
		(at 171.474892 -305.399948 -90)
		(property "Reference" "C3136"
			(at 0 0 90)
			(layer "B.SilkS")
			(hide yes)
			(effects
				(font
					(size 1.27 1.27)
				)
				(justify mirror)
			)
		)
		(property "Value" ""
			(at 0 0 90)
			(layer "B.Fab")
			(effects
				(font
					(size 1.27 1.27)
				)
				(justify mirror)
			)
		)
		(duplicate_pad_numbers_are_jumpers no)
		(fp_line
			(start -0.299974 0.150114)
			(end 0.299974 0.150114)
			(stroke
				(width 0.1)
				(type default)
			)
			(layer "B.Fab")
		)
		(fp_line
			(start 0.299974 0.150114)
			(end 0.299974 -0.150114)
			(stroke
				(width 0.1)
				(type default)
			)
			(layer "B.Fab")
		)
		(fp_line
			(start -0.299974 -0.150114)
			(end -0.299974 0.150114)
			(stroke
				(width 0.1)
				(type default)
			)
			(layer "B.Fab")
		)
		(fp_line
			(start 0.299974 -0.150114)
			(end -0.299974 -0.150114)
			(stroke
				(width 0.1)
				(type default)
			)
			(layer "B.Fab")
		)
		(pad "1" smd rect
			(at 0.2667 0 90)
			(size 0.3048 0.381)
			(layers "B.Cu" "B.Mask" "B.Paste")
			(net "P1V25_SERDES_VDDPLL_PEX1")
		)
		(pad "2" smd rect
			(at -0.2667 0 90)
			(size 0.3048 0.381)
			(layers "B.Cu" "B.Mask" "B.Paste")
			(net "GND")
		)
	)
	(footprint ""
		(layer "B.Cu")
		(at 331.822298 -227.33127 -90)
		(property "Reference" "C2087"
			(at 0 0 90)
			(layer "B.SilkS")
			(hide yes)
			(effects
				(font
					(size 1.27 1.27)
				)
				(justify mirror)
			)
		)
		(property "Value" ""
			(at 0 0 90)
			(layer "B.Fab")
			(effects
				(font
					(size 1.27 1.27)
				)
				(justify mirror)
			)
		)
		(duplicate_pad_numbers_are_jumpers no)
		(fp_line
			(start -0.69215 0.2921)
			(end 0.69215 0.2921)
			(stroke
				(width 0.1524)
				(type default)
			)
			(layer "B.SilkS")
		)
		(fp_line
			(start 0.69215 0.2921)
			(end 0.69215 -0.2921)
			(stroke
				(width 0.1524)
				(type default)
			)
			(layer "B.SilkS")
		)
		(fp_line
			(start -0.69215 -0.2921)
			(end -0.69215 0.2921)
			(stroke
				(width 0.1524)
				(type default)
			)
			(layer "B.SilkS")
		)
		(fp_line
			(start 0.69215 -0.2921)
			(end -0.69215 -0.2921)
			(stroke
				(width 0.1524)
				(type default)
			)
			(layer "B.SilkS")
		)
		(fp_line
			(start -0.51435 0.2794)
			(end 0.51435 0.2794)
			(stroke
				(width 0.1)
				(type default)
			)
			(layer "B.Fab")
		)
		(fp_line
			(start 0.51435 0.2794)
			(end 0.51435 -0.2794)
			(stroke
				(width 0.1)
				(type default)
			)
			(layer "B.Fab")
		)
		(fp_line
			(start -0.51435 -0.2794)
			(end -0.51435 0.2794)
			(stroke
				(width 0.1)
				(type default)
			)
			(layer "B.Fab")
		)
		(fp_line
			(start 0.51435 -0.2794)
			(end -0.51435 -0.2794)
			(stroke
				(width 0.1)
				(type default)
			)
			(layer "B.Fab")
		)
		(pad "1" smd circle
			(at 0.40005 0 90)
			(size 0 0)
			(layers "B.Cu" "B.Mask" "B.Paste")
			(net "P3V3_FPGA_VCCIO5")
		)
		(pad "2" smd circle
			(at -0.40005 0 90)
			(size 0 0)
			(layers "B.Cu" "B.Mask" "B.Paste")
			(net "GND")
		)
		(zone
			(layer "B.Cu")
			(hatch none 0.5)
			(connect_pads
				(clearance 0)
			)
			(min_thickness 0.25)
			(keepout
				(tracks not_allowed)
				(vias allowed)
				(pads allowed)
				(copperpour not_allowed)
				(footprints allowed)
			)
			(placement
				(enabled no)
				(sheetname "")
			)
			(fill
				(thermal_gap 0.5)
				(thermal_bridge_width 0.5)
				(island_removal_mode 0)
			)
			(polygon
				(pts
					(xy 331.734668 -227.14077) (xy 331.676502 -227.23221) (xy 331.676502 -227.4316) (xy 331.734668 -227.52177)
					(xy 331.909928 -227.52177) (xy 331.968348 -227.4316) (xy 331.968348 -227.23221) (xy 331.910182 -227.14077)
				)
			)
		)
	)
	(footprint ""
		(layer "B.Cu")
		(at 349.679514 -214.381334 180)
		(property "Reference" "C2039"
			(at 0 0 0)
			(layer "B.SilkS")
			(hide yes)
			(effects
				(font
					(size 1.27 1.27)
				)
				(justify mirror)
			)
		)
		(property "Value" ""
			(at 0 0 0)
			(layer "B.Fab")
			(effects
				(font
					(size 1.27 1.27)
				)
				(justify mirror)
			)
		)
		(duplicate_pad_numbers_are_jumpers no)
		(fp_line
			(start 0.69215 0.2921)
			(end 0.69215 -0.2921)
			(stroke
				(width 0.1524)
				(type default)
			)
			(layer "B.SilkS")
		)
		(fp_line
			(start 0.69215 -0.2921)
			(end -0.69215 -0.2921)
			(stroke
				(width 0.1524)
				(type default)
			)
			(layer "B.SilkS")
		)
		(fp_line
			(start -0.69215 0.2921)
			(end 0.69215 0.2921)
			(stroke
				(width 0.1524)
				(type default)
			)
			(layer "B.SilkS")
		)
		(fp_line
			(start -0.69215 -0.2921)
			(end -0.69215 0.2921)
			(stroke
				(width 0.1524)
				(type default)
			)
			(layer "B.SilkS")
		)
		(fp_line
			(start 0.51435 0.2794)
			(end 0.51435 -0.2794)
			(stroke
				(width 0.1)
				(type default)
			)
			(layer "B.Fab")
		)
		(fp_line
			(start 0.51435 -0.2794)
			(end -0.51435 -0.2794)
			(stroke
				(width 0.1)
				(type default)
			)
			(layer "B.Fab")
		)
		(fp_line
			(start -0.51435 0.2794)
			(end 0.51435 0.2794)
			(stroke
				(width 0.1)
				(type default)
			)
			(layer "B.Fab")
		)
		(fp_line
			(start -0.51435 -0.2794)
			(end -0.51435 0.2794)
			(stroke
				(width 0.1)
				(type default)
			)
			(layer "B.Fab")
		)
		(pad "1" smd circle
			(at 0.40005 0)
			(size 0 0)
			(layers "B.Cu" "B.Mask" "B.Paste")
			(net "P3V3_FPGA_VCCIO1")
		)
		(pad "2" smd circle
			(at -0.40005 0)
			(size 0 0)
			(layers "B.Cu" "B.Mask" "B.Paste")
			(net "GND")
		)
		(zone
			(layer "B.Cu")
			(hatch none 0.5)
			(connect_pads
				(clearance 0)
			)
			(min_thickness 0.25)
			(keepout
				(tracks not_allowed)
				(vias allowed)
				(pads allowed)
				(copperpour not_allowed)
				(footprints allowed)
			)
			(placement
				(enabled no)
				(sheetname "")
			)
			(fill
				(thermal_gap 0.5)
				(thermal_bridge_width 0.5)
				(island_removal_mode 0)
			)
			(polygon
				(pts
					(xy 349.489014 -214.468964) (xy 349.580454 -214.52713) (xy 349.779844 -214.52713) (xy 349.870014 -214.468964)
					(xy 349.870014 -214.293704) (xy 349.779844 -214.235284) (xy 349.580454 -214.235284) (xy 349.489014 -214.29345)
				)
			)
		)
	)
	(footprint ""
		(layer "B.Cu")
		(at 105.287826 -319.545462 -90)
		(property "Reference" "L47"
			(at 0 0 90)
			(layer "B.SilkS")
			(hide yes)
			(effects
				(font
					(size 1.27 1.27)
				)
				(justify mirror)
			)
		)
		(property "Value" ""
			(at 0 0 90)
			(layer "B.Fab")
			(effects
				(font
					(size 1.27 1.27)
				)
				(justify mirror)
			)
		)
		(duplicate_pad_numbers_are_jumpers no)
		(fp_line
			(start -2.248154 4.9911)
			(end -2.248154 2.048002)
			(stroke
				(width 0.1524)
				(type default)
			)
			(layer "B.SilkS")
		)
		(fp_line
			(start 2.248154 4.9911)
			(end -2.248154 4.9911)
			(stroke
				(width 0.1524)
				(type default)
			)
			(layer "B.SilkS")
		)
		(fp_line
			(start 2.248154 2.048002)
			(end 2.248154 4.9911)
			(stroke
				(width 0.1524)
				(type default)
			)
			(layer "B.SilkS")
		)
		(fp_line
			(start -2.248154 -4.9911)
			(end 2.248154 -4.9911)
			(stroke
				(width 0.1524)
				(type default)
			)
			(layer "B.SilkS")
		)
		(fp_line
			(start 2.248154 -4.9911)
			(end 2.248154 -2.09804)
			(stroke
				(width 0.1524)
				(type default)
			)
			(layer "B.SilkS")
		)
		(fp_line
			(start -1.700022 0.899922)
			(end -1.700022 -0.899922)
			(stroke
				(width 0.1)
				(type default)
			)
			(layer "B.Fab")
		)
		(fp_line
			(start 1.700022 0.899922)
			(end -1.700022 0.899922)
			(stroke
				(width 0.1)
				(type default)
			)
			(layer "B.Fab")
		)
		(fp_line
			(start -1.700022 -0.899922)
			(end 1.700022 -0.899922)
			(stroke
				(width 0.1)
				(type default)
			)
			(layer "B.Fab")
		)
		(fp_line
			(start 1.700022 -0.899922)
			(end 1.700022 0.899922)
			(stroke
				(width 0.1)
				(type default)
			)
			(layer "B.Fab")
		)
		(pad "1" smd rect
			(at 1.575054 0 90)
			(size 1.1684 9.8044)
			(layers "B.Cu" "B.Mask" "B.Paste")
			(net "P0V8_PEX0")
		)
		(pad "2" smd rect
			(at -1.575054 0 90)
			(size 1.1684 9.8044)
			(layers "B.Cu" "B.Mask" "B.Paste")
			(net "P0V8_SERDES_VDDA_PEX0")
		)
	)
	(footprint ""
		(layer "B.Cu")
		(at 404.149814 -292.099746 90)
		(property "Reference" "C1984"
			(at 0 0 90)
			(layer "B.SilkS")
			(hide yes)
			(effects
				(font
					(size 1.27 1.27)
				)
				(justify mirror)
			)
		)
		(property "Value" ""
			(at 0 0 90)
			(layer "B.Fab")
			(effects
				(font
					(size 1.27 1.27)
				)
				(justify mirror)
			)
		)
		(duplicate_pad_numbers_are_jumpers no)
		(fp_line
			(start 0.299974 -0.150114)
			(end -0.299974 -0.150114)
			(stroke
				(width 0.1)
				(type default)
			)
			(layer "B.Fab")
		)
		(fp_line
			(start -0.299974 -0.150114)
			(end -0.299974 0.150114)
			(stroke
				(width 0.1)
				(type default)
			)
			(layer "B.Fab")
		)
		(fp_line
			(start 0.299974 0.150114)
			(end 0.299974 -0.150114)
			(stroke
				(width 0.1)
				(type default)
			)
			(layer "B.Fab")
		)
		(fp_line
			(start -0.299974 0.150114)
			(end 0.299974 0.150114)
			(stroke
				(width 0.1)
				(type default)
			)
			(layer "B.Fab")
		)
		(pad "1" smd rect
			(at 0.2667 0 270)
			(size 0.3048 0.381)
			(layers "B.Cu" "B.Mask" "B.Paste")
			(net "P0V8_SERDES_VDDA_PEX3")
		)
		(pad "2" smd rect
			(at -0.2667 0 270)
			(size 0.3048 0.381)
			(layers "B.Cu" "B.Mask" "B.Paste")
			(net "GND")
		)
	)
	(footprint ""
		(layer "B.Cu")
		(at 220.676978 -266.873228)
		(property "Reference" "R6133"
			(at 0 0 0)
			(layer "B.SilkS")
			(hide yes)
			(effects
				(font
					(size 1.27 1.27)
				)
				(justify mirror)
			)
		)
		(property "Value" ""
			(at 0 0 0)
			(layer "B.Fab")
			(effects
				(font
					(size 1.27 1.27)
				)
				(justify mirror)
			)
		)
		(duplicate_pad_numbers_are_jumpers no)
		(fp_line
			(start -2.576322 -1.1303)
			(end -2.576322 1.1303)
			(stroke
				(width 0.1524)
				(type default)
			)
			(layer "B.SilkS")
		)
		(fp_line
			(start -2.576322 1.1303)
			(end 2.576322 1.1303)
			(stroke
				(width 0.1524)
				(type default)
			)
			(layer "B.SilkS")
		)
		(fp_line
			(start 2.576322 -1.1303)
			(end -2.576322 -1.1303)
			(stroke
				(width 0.1524)
				(type default)
			)
			(layer "B.SilkS")
		)
		(fp_line
			(start 2.576322 1.1303)
			(end 2.576322 -1.1303)
			(stroke
				(width 0.1524)
				(type default)
			)
			(layer "B.SilkS")
		)
		(fp_line
			(start -1.649984 -0.899922)
			(end 1.649984 -0.899922)
			(stroke
				(width 0.1)
				(type default)
			)
			(layer "B.Fab")
		)
		(fp_line
			(start -1.649984 0.899922)
			(end -1.649984 -0.899922)
			(stroke
				(width 0.1)
				(type default)
			)
			(layer "B.Fab")
		)
		(fp_line
			(start 1.649984 -0.899922)
			(end 1.649984 0.899922)
			(stroke
				(width 0.1)
				(type default)
			)
			(layer "B.Fab")
		)
		(fp_line
			(start 1.649984 0.899922)
			(end -1.649984 0.899922)
			(stroke
				(width 0.1)
				(type default)
			)
			(layer "B.Fab")
		)
		(pad "1A" smd rect
			(at 1.700022 0 180)
			(size 1.4986 2.0066)
			(layers "B.Cu" "B.Mask" "B.Paste")
			(net "P1V25_PEX1")
		)
		(pad "1B" smd rect
			(at 1.077722 0 180)
			(size 0.254 0.508)
			(layers "B.Cu" "B.Mask" "B.Paste")
			(net "P1V25_PEX1")
		)
		(pad "2A" smd rect
			(at -1.700022 0 180)
			(size 1.4986 2.0066)
			(layers "B.Cu" "B.Mask" "B.Paste")
			(net "P1V25_SERDES_VDDPLL_PEX1")
		)
		(pad "2B" smd rect
			(at -1.077722 0 180)
			(size 0.254 0.508)
			(layers "B.Cu" "B.Mask" "B.Paste")
			(net "P1V25_SERDES_VDDPLL_PEX1")
		)
	)
	(footprint ""
		(layer "B.Cu")
		(at 176.699926 -292.099746 90)
		(property "Reference" "C1478"
			(at 0 0 90)
			(layer "B.SilkS")
			(hide yes)
			(effects
				(font
					(size 1.27 1.27)
				)
				(justify mirror)
			)
		)
		(property "Value" ""
			(at 0 0 90)
			(layer "B.Fab")
			(effects
				(font
					(size 1.27 1.27)
				)
				(justify mirror)
			)
		)
		(duplicate_pad_numbers_are_jumpers no)
		(fp_line
			(start 0.299974 -0.150114)
			(end -0.299974 -0.150114)
			(stroke
				(width 0.1)
				(type default)
			)
			(layer "B.Fab")
		)
		(fp_line
			(start -0.299974 -0.150114)
			(end -0.299974 0.150114)
			(stroke
				(width 0.1)
				(type default)
			)
			(layer "B.Fab")
		)
		(fp_line
			(start 0.299974 0.150114)
			(end 0.299974 -0.150114)
			(stroke
				(width 0.1)
				(type default)
			)
			(layer "B.Fab")
		)
		(fp_line
			(start -0.299974 0.150114)
			(end 0.299974 0.150114)
			(stroke
				(width 0.1)
				(type default)
			)
			(layer "B.Fab")
		)
		(pad "1" smd rect
			(at 0.2667 0 270)
			(size 0.3048 0.381)
			(layers "B.Cu" "B.Mask" "B.Paste")
			(net "P0V8_SERDES_VDDA_PEX1")
		)
		(pad "2" smd rect
			(at -0.2667 0 270)
			(size 0.3048 0.381)
			(layers "B.Cu" "B.Mask" "B.Paste")
			(net "GND")
		)
	)
	(footprint ""
		(layer "B.Cu")
		(at 238.938054 -278.872442 -90)
		(property "Reference" "C4332"
			(at 0 0 90)
			(layer "B.SilkS")
			(hide yes)
			(effects
				(font
					(size 1.27 1.27)
				)
				(justify mirror)
			)
		)
		(property "Value" ""
			(at 0 0 90)
			(layer "B.Fab")
			(effects
				(font
					(size 1.27 1.27)
				)
				(justify mirror)
			)
		)
		(duplicate_pad_numbers_are_jumpers no)
		(fp_line
			(start -1.2954 0.5842)
			(end 1.2954 0.5842)
			(stroke
				(width 0.1524)
				(type default)
			)
			(layer "B.SilkS")
		)
		(fp_line
			(start 1.2954 0.5842)
			(end 1.2954 -0.5842)
			(stroke
				(width 0.1524)
				(type default)
			)
			(layer "B.SilkS")
		)
		(fp_line
			(start -1.2954 -0.5842)
			(end -1.2954 0.5842)
			(stroke
				(width 0.1524)
				(type default)
			)
			(layer "B.SilkS")
		)
		(fp_line
			(start 1.2954 -0.5842)
			(end -1.2954 -0.5842)
			(stroke
				(width 0.1524)
				(type default)
			)
			(layer "B.SilkS")
		)
		(fp_line
			(start -0.8636 0.4572)
			(end 0.8636 0.4572)
			(stroke
				(width 0.1)
				(type default)
			)
			(layer "B.Fab")
		)
		(fp_line
			(start 0.8636 0.4572)
			(end 0.8636 0.4064)
			(stroke
				(width 0.1)
				(type default)
			)
			(layer "B.Fab")
		)
		(fp_line
			(start -1.1938 0.4064)
			(end -0.8636 0.4064)
			(stroke
				(width 0.1)
				(type default)
			)
			(layer "B.Fab")
		)
		(fp_line
			(start -0.8636 0.4064)
			(end -0.8636 0.4572)
			(stroke
				(width 0.1)
				(type default)
			)
			(layer "B.Fab")
		)
		(fp_line
			(start 0.8636 0.4064)
			(end 1.1938 0.4064)
			(stroke
				(width 0.1)
				(type default)
			)
			(layer "B.Fab")
		)
		(fp_line
			(start 1.1938 0.4064)
			(end 1.1938 -0.4064)
			(stroke
				(width 0.1)
				(type default)
			)
			(layer "B.Fab")
		)
		(fp_line
			(start -1.1938 -0.4064)
			(end -1.1938 0.4064)
			(stroke
				(width 0.1)
				(type default)
			)
			(layer "B.Fab")
		)
		(fp_line
			(start -0.8636 -0.4064)
			(end -1.1938 -0.4064)
			(stroke
				(width 0.1)
				(type default)
			)
			(layer "B.Fab")
		)
		(fp_line
			(start 0.8636 -0.4064)
			(end 0.8636 -0.4572)
			(stroke
				(width 0.1)
				(type default)
			)
			(layer "B.Fab")
		)
		(fp_line
			(start 1.1938 -0.4064)
			(end 0.8636 -0.4064)
			(stroke
				(width 0.1)
				(type default)
			)
			(layer "B.Fab")
		)
		(fp_line
			(start -0.8636 -0.4572)
			(end -0.8636 -0.4064)
			(stroke
				(width 0.1)
				(type default)
			)
			(layer "B.Fab")
		)
		(fp_line
			(start 0.8636 -0.4572)
			(end -0.8636 -0.4572)
			(stroke
				(width 0.1)
				(type default)
			)
			(layer "B.Fab")
		)
		(pad "1" smd rect
			(at 0.7366 0 180)
			(size 0.7112 0.8128)
			(layers "B.Cu" "B.Mask" "B.Paste")
			(net "P1V25_PEX2")
		)
		(pad "2" smd rect
			(at -0.7366 0 180)
			(size 0.7112 0.8128)
			(layers "B.Cu" "B.Mask" "B.Paste")
			(net "GND")
		)
	)
	(footprint ""
		(layer "B.Cu")
		(at 391.263886 -285.853632)
		(property "Reference" "C3512"
			(at 0 0 0)
			(layer "B.SilkS")
			(hide yes)
			(effects
				(font
					(size 1.27 1.27)
				)
				(justify mirror)
			)
		)
		(property "Value" ""
			(at 0 0 0)
			(layer "B.Fab")
			(effects
				(font
					(size 1.27 1.27)
				)
				(justify mirror)
			)
		)
		(duplicate_pad_numbers_are_jumpers no)
		(fp_line
			(start -1.2954 -0.5842)
			(end -1.2954 0.5842)
			(stroke
				(width 0.1524)
				(type default)
			)
			(layer "B.SilkS")
		)
		(fp_line
			(start -1.2954 0.5842)
			(end 1.2954 0.5842)
			(stroke
				(width 0.1524)
				(type default)
			)
			(layer "B.SilkS")
		)
		(fp_line
			(start 1.2954 -0.5842)
			(end -1.2954 -0.5842)
			(stroke
				(width 0.1524)
				(type default)
			)
			(layer "B.SilkS")
		)
		(fp_line
			(start 1.2954 0.5842)
			(end 1.2954 -0.5842)
			(stroke
				(width 0.1524)
				(type default)
			)
			(layer "B.SilkS")
		)
		(fp_line
			(start -1.1938 -0.4064)
			(end -1.1938 0.4064)
			(stroke
				(width 0.1)
				(type default)
			)
			(layer "B.Fab")
		)
		(fp_line
			(start -1.1938 0.4064)
			(end -0.8636 0.4064)
			(stroke
				(width 0.1)
				(type default)
			)
			(layer "B.Fab")
		)
		(fp_line
			(start -0.8636 -0.4572)
			(end -0.8636 -0.4064)
			(stroke
				(width 0.1)
				(type default)
			)
			(layer "B.Fab")
		)
		(fp_line
			(start -0.8636 -0.4064)
			(end -1.1938 -0.4064)
			(stroke
				(width 0.1)
				(type default)
			)
			(layer "B.Fab")
		)
		(fp_line
			(start -0.8636 0.4064)
			(end -0.8636 0.4572)
			(stroke
				(width 0.1)
				(type default)
			)
			(layer "B.Fab")
		)
		(fp_line
			(start -0.8636 0.4572)
			(end 0.8636 0.4572)
			(stroke
				(width 0.1)
				(type default)
			)
			(layer "B.Fab")
		)
		(fp_line
			(start 0.8636 -0.4572)
			(end -0.8636 -0.4572)
			(stroke
				(width 0.1)
				(type default)
			)
			(layer "B.Fab")
		)
		(fp_line
			(start 0.8636 -0.4064)
			(end 0.8636 -0.4572)
			(stroke
				(width 0.1)
				(type default)
			)
			(layer "B.Fab")
		)
		(fp_line
			(start 0.8636 0.4064)
			(end 1.1938 0.4064)
			(stroke
				(width 0.1)
				(type default)
			)
			(layer "B.Fab")
		)
		(fp_line
			(start 0.8636 0.4572)
			(end 0.8636 0.4064)
			(stroke
				(width 0.1)
				(type default)
			)
			(layer "B.Fab")
		)
		(fp_line
			(start 1.1938 -0.4064)
			(end 0.8636 -0.4064)
			(stroke
				(width 0.1)
				(type default)
			)
			(layer "B.Fab")
		)
		(fp_line
			(start 1.1938 0.4064)
			(end 1.1938 -0.4064)
			(stroke
				(width 0.1)
				(type default)
			)
			(layer "B.Fab")
		)
		(pad "1" smd rect
			(at 0.7366 0 270)
			(size 0.7112 0.8128)
			(layers "B.Cu" "B.Mask" "B.Paste")
			(net "P1V8_PEX")
		)
		(pad "2" smd rect
			(at -0.7366 0 270)
			(size 0.7112 0.8128)
			(layers "B.Cu" "B.Mask" "B.Paste")
			(net "GND")
		)
	)
	(footprint ""
		(layer "B.Cu")
		(at 212.409532 -230.65359 90)
		(property "Reference" "R6320"
			(at 0 0 90)
			(layer "B.SilkS")
			(hide yes)
			(effects
				(font
					(size 1.27 1.27)
				)
				(justify mirror)
			)
		)
		(property "Value" ""
			(at 0 0 90)
			(layer "B.Fab")
			(effects
				(font
					(size 1.27 1.27)
				)
				(justify mirror)
			)
		)
		(duplicate_pad_numbers_are_jumpers no)
		(fp_line
			(start 0.7874 -0.4064)
			(end -0.7874 -0.4064)
			(stroke
				(width 0.1524)
				(type default)
			)
			(layer "B.SilkS")
		)
		(fp_line
			(start -0.7874 -0.4064)
			(end -0.7874 0.4064)
			(stroke
				(width 0.1524)
				(type default)
			)
			(layer "B.SilkS")
		)
		(fp_line
			(start 0.7874 0.4064)
			(end 0.7874 -0.4064)
			(stroke
				(width 0.1524)
				(type default)
			)
			(layer "B.SilkS")
		)
		(fp_line
			(start -0.7874 0.4064)
			(end 0.7874 0.4064)
			(stroke
				(width 0.1524)
				(type default)
			)
			(layer "B.SilkS")
		)
		(fp_line
			(start 0.67945 -0.305054)
			(end 0.12065 -0.305054)
			(stroke
				(width 0.1)
				(type default)
			)
			(layer "B.Fab")
		)
		(fp_line
			(start 0.12065 -0.305054)
			(end 0.12065 -0.2794)
			(stroke
				(width 0.1)
				(type default)
			)
			(layer "B.Fab")
		)
		(fp_line
			(start -0.12065 -0.3048)
			(end -0.67945 -0.3048)
			(stroke
				(width 0.1)
				(type default)
			)
			(layer "B.Fab")
		)
		(fp_line
			(start -0.67945 -0.3048)
			(end -0.67945 0.3048)
			(stroke
				(width 0.1)
				(type default)
			)
			(layer "B.Fab")
		)
		(fp_line
			(start 0.12065 -0.2794)
			(end -0.12065 -0.2794)
			(stroke
				(width 0.1)
				(type default)
			)
			(layer "B.Fab")
		)
		(fp_line
			(start -0.12065 -0.2794)
			(end -0.12065 -0.3048)
			(stroke
				(width 0.1)
				(type default)
			)
			(layer "B.Fab")
		)
		(fp_line
			(start 0.12065 0.2794)
			(end 0.12065 0.3048)
			(stroke
				(width 0.1)
				(type default)
			)
			(layer "B.Fab")
		)
		(fp_line
			(start -0.120396 0.2794)
			(end 0.12065 0.2794)
			(stroke
				(width 0.1)
				(type default)
			)
			(layer "B.Fab")
		)
		(fp_line
			(start 0.67945 0.3048)
			(end 0.67945 -0.305054)
			(stroke
				(width 0.1)
				(type default)
			)
			(layer "B.Fab")
		)
		(fp_line
			(start 0.12065 0.3048)
			(end 0.67945 0.3048)
			(stroke
				(width 0.1)
				(type default)
			)
			(layer "B.Fab")
		)
		(fp_line
			(start -0.120396 0.3048)
			(end -0.120396 0.2794)
			(stroke
				(width 0.1)
				(type default)
			)
			(layer "B.Fab")
		)
		(fp_line
			(start -0.67945 0.3048)
			(end -0.120396 0.3048)
			(stroke
				(width 0.1)
				(type default)
			)
			(layer "B.Fab")
		)
		(pad "1" smd circle
			(at 0.40005 0 270)
			(size 0 0)
			(layers "B.Cu" "B.Mask" "B.Paste")
			(net "SMB_PEX0_SDA")
		)
		(pad "2" smd circle
			(at -0.40005 0 270)
			(size 0 0)
			(layers "B.Cu" "B.Mask" "B.Paste")
			(net "SMB_PEX0_MUX_SDA")
		)
	)
	(footprint ""
		(layer "B.Cu")
		(at 421.571674 -114.592608)
		(property "Reference" "C959"
			(at 0 0 0)
			(layer "B.SilkS")
			(hide yes)
			(effects
				(font
					(size 1.27 1.27)
				)
				(justify mirror)
			)
		)
		(property "Value" ""
			(at 0 0 0)
			(layer "B.Fab")
			(effects
				(font
					(size 1.27 1.27)
				)
				(justify mirror)
			)
		)
		(duplicate_pad_numbers_are_jumpers no)
		(fp_line
			(start -0.7874 -0.4064)
			(end -0.7874 0.4064)
			(stroke
				(width 0.1524)
				(type default)
			)
			(layer "B.SilkS")
		)
		(fp_line
			(start -0.7874 0.4064)
			(end 0.7874 0.4064)
			(stroke
				(width 0.1524)
				(type default)
			)
			(layer "B.SilkS")
		)
		(fp_line
			(start 0.7874 -0.4064)
			(end -0.7874 -0.4064)
			(stroke
				(width 0.1524)
				(type default)
			)
			(layer "B.SilkS")
		)
		(fp_line
			(start 0.7874 0.4064)
			(end 0.7874 -0.4064)
			(stroke
				(width 0.1524)
				(type default)
			)
			(layer "B.SilkS")
		)
		(fp_line
			(start -0.67945 -0.3048)
			(end -0.67945 0.3048)
			(stroke
				(width 0.1)
				(type default)
			)
			(layer "B.Fab")
		)
		(fp_line
			(start -0.67945 0.3048)
			(end -0.120396 0.3048)
			(stroke
				(width 0.1)
				(type default)
			)
			(layer "B.Fab")
		)
		(fp_line
			(start -0.12065 -0.3048)
			(end -0.67945 -0.3048)
			(stroke
				(width 0.1)
				(type default)
			)
			(layer "B.Fab")
		)
		(fp_line
			(start -0.12065 -0.2794)
			(end -0.12065 -0.3048)
			(stroke
				(width 0.1)
				(type default)
			)
			(layer "B.Fab")
		)
		(fp_line
			(start -0.120396 0.2794)
			(end 0.12065 0.2794)
			(stroke
				(width 0.1)
				(type default)
			)
			(layer "B.Fab")
		)
		(fp_line
			(start -0.120396 0.3048)
			(end -0.120396 0.2794)
			(stroke
				(width 0.1)
				(type default)
			)
			(layer "B.Fab")
		)
		(fp_line
			(start 0.12065 -0.305054)
			(end 0.12065 -0.2794)
			(stroke
				(width 0.1)
				(type default)
			)
			(layer "B.Fab")
		)
		(fp_line
			(start 0.12065 -0.2794)
			(end -0.12065 -0.2794)
			(stroke
				(width 0.1)
				(type default)
			)
			(layer "B.Fab")
		)
		(fp_line
			(start 0.12065 0.2794)
			(end 0.12065 0.3048)
			(stroke
				(width 0.1)
				(type default)
			)
			(layer "B.Fab")
		)
		(fp_line
			(start 0.12065 0.3048)
			(end 0.67945 0.3048)
			(stroke
				(width 0.1)
				(type default)
			)
			(layer "B.Fab")
		)
		(fp_line
			(start 0.67945 -0.305054)
			(end 0.12065 -0.305054)
			(stroke
				(width 0.1)
				(type default)
			)
			(layer "B.Fab")
		)
		(fp_line
			(start 0.67945 0.3048)
			(end 0.67945 -0.305054)
			(stroke
				(width 0.1)
				(type default)
			)
			(layer "B.Fab")
		)
		(pad "1" smd circle
			(at 0.40005 0 180)
			(size 0 0)
			(layers "B.Cu" "B.Mask" "B.Paste")
			(net "P3V3_NIC7")
		)
		(pad "2" smd circle
			(at -0.40005 0 180)
			(size 0 0)
			(layers "B.Cu" "B.Mask" "B.Paste")
			(net "GND")
		)
	)
	(footprint ""
		(layer "B.Cu")
		(at 49.1998 -292.574726 180)
		(property "Reference" "C1106"
			(at 0 0 0)
			(layer "B.SilkS")
			(hide yes)
			(effects
				(font
					(size 1.27 1.27)
				)
				(justify mirror)
			)
		)
		(property "Value" ""
			(at 0 0 0)
			(layer "B.Fab")
			(effects
				(font
					(size 1.27 1.27)
				)
				(justify mirror)
			)
		)
		(duplicate_pad_numbers_are_jumpers no)
		(fp_line
			(start 0.299974 0.150114)
			(end 0.299974 -0.150114)
			(stroke
				(width 0.1)
				(type default)
			)
			(layer "B.Fab")
		)
		(fp_line
			(start 0.299974 -0.150114)
			(end -0.299974 -0.150114)
			(stroke
				(width 0.1)
				(type default)
			)
			(layer "B.Fab")
		)
		(fp_line
			(start -0.299974 0.150114)
			(end 0.299974 0.150114)
			(stroke
				(width 0.1)
				(type default)
			)
			(layer "B.Fab")
		)
		(fp_line
			(start -0.299974 -0.150114)
			(end -0.299974 0.150114)
			(stroke
				(width 0.1)
				(type default)
			)
			(layer "B.Fab")
		)
		(pad "1" smd rect
			(at 0.2667 0)
			(size 0.3048 0.381)
			(layers "B.Cu" "B.Mask" "B.Paste")
			(net "P0V8_PEX0")
		)
		(pad "2" smd rect
			(at -0.2667 0)
			(size 0.3048 0.381)
			(layers "B.Cu" "B.Mask" "B.Paste")
			(net "GND")
		)
	)
	(footprint ""
		(layer "B.Cu")
		(at 185.250074 -300.174914 180)
		(property "Reference" "C3188"
			(at 0 0 0)
			(layer "B.SilkS")
			(hide yes)
			(effects
				(font
					(size 1.27 1.27)
				)
				(justify mirror)
			)
		)
		(property "Value" ""
			(at 0 0 0)
			(layer "B.Fab")
			(effects
				(font
					(size 1.27 1.27)
				)
				(justify mirror)
			)
		)
		(duplicate_pad_numbers_are_jumpers no)
		(fp_line
			(start 0.299974 0.150114)
			(end 0.299974 -0.150114)
			(stroke
				(width 0.1)
				(type default)
			)
			(layer "B.Fab")
		)
		(fp_line
			(start 0.299974 -0.150114)
			(end -0.299974 -0.150114)
			(stroke
				(width 0.1)
				(type default)
			)
			(layer "B.Fab")
		)
		(fp_line
			(start -0.299974 0.150114)
			(end 0.299974 0.150114)
			(stroke
				(width 0.1)
				(type default)
			)
			(layer "B.Fab")
		)
		(fp_line
			(start -0.299974 -0.150114)
			(end -0.299974 0.150114)
			(stroke
				(width 0.1)
				(type default)
			)
			(layer "B.Fab")
		)
		(pad "1" smd rect
			(at 0.2667 0)
			(size 0.3048 0.381)
			(layers "B.Cu" "B.Mask" "B.Paste")
			(net "P1V8_VDDA_PEX1")
		)
		(pad "2" smd rect
			(at -0.2667 0)
			(size 0.3048 0.381)
			(layers "B.Cu" "B.Mask" "B.Paste")
			(net "GND")
		)
	)
	(footprint ""
		(layer "B.Cu")
		(at 29.741622 -224.75063 180)
		(property "Reference" "R6164"
			(at 0 0 0)
			(layer "B.SilkS")
			(hide yes)
			(effects
				(font
					(size 1.27 1.27)
				)
				(justify mirror)
			)
		)
		(property "Value" ""
			(at 0 0 0)
			(layer "B.Fab")
			(effects
				(font
					(size 1.27 1.27)
				)
				(justify mirror)
			)
		)
		(duplicate_pad_numbers_are_jumpers no)
		(fp_line
			(start 0.7874 0.4064)
			(end 0.7874 -0.4064)
			(stroke
				(width 0.1524)
				(type default)
			)
			(layer "B.SilkS")
		)
		(fp_line
			(start 0.7874 -0.4064)
			(end -0.7874 -0.4064)
			(stroke
				(width 0.1524)
				(type default)
			)
			(layer "B.SilkS")
		)
		(fp_line
			(start -0.7874 0.4064)
			(end 0.7874 0.4064)
			(stroke
				(width 0.1524)
				(type default)
			)
			(layer "B.SilkS")
		)
		(fp_line
			(start -0.7874 -0.4064)
			(end -0.7874 0.4064)
			(stroke
				(width 0.1524)
				(type default)
			)
			(layer "B.SilkS")
		)
		(fp_line
			(start 0.67945 0.3048)
			(end 0.67945 -0.305054)
			(stroke
				(width 0.1)
				(type default)
			)
			(layer "B.Fab")
		)
		(fp_line
			(start 0.67945 -0.305054)
			(end 0.12065 -0.305054)
			(stroke
				(width 0.1)
				(type default)
			)
			(layer "B.Fab")
		)
		(fp_line
			(start 0.12065 0.3048)
			(end 0.67945 0.3048)
			(stroke
				(width 0.1)
				(type default)
			)
			(layer "B.Fab")
		)
		(fp_line
			(start 0.12065 0.2794)
			(end 0.12065 0.3048)
			(stroke
				(width 0.1)
				(type default)
			)
			(layer "B.Fab")
		)
		(fp_line
			(start 0.12065 -0.2794)
			(end -0.12065 -0.2794)
			(stroke
				(width 0.1)
				(type default)
			)
			(layer "B.Fab")
		)
		(fp_line
			(start 0.12065 -0.305054)
			(end 0.12065 -0.2794)
			(stroke
				(width 0.1)
				(type default)
			)
			(layer "B.Fab")
		)
		(fp_line
			(start -0.120396 0.3048)
			(end -0.120396 0.2794)
			(stroke
				(width 0.1)
				(type default)
			)
			(layer "B.Fab")
		)
		(fp_line
			(start -0.120396 0.2794)
			(end 0.12065 0.2794)
			(stroke
				(width 0.1)
				(type default)
			)
			(layer "B.Fab")
		)
		(fp_line
			(start -0.12065 -0.2794)
			(end -0.12065 -0.3048)
			(stroke
				(width 0.1)
				(type default)
			)
			(layer "B.Fab")
		)
		(fp_line
			(start -0.12065 -0.3048)
			(end -0.67945 -0.3048)
			(stroke
				(width 0.1)
				(type default)
			)
			(layer "B.Fab")
		)
		(fp_line
			(start -0.67945 0.3048)
			(end -0.120396 0.3048)
			(stroke
				(width 0.1)
				(type default)
			)
			(layer "B.Fab")
		)
		(fp_line
			(start -0.67945 -0.3048)
			(end -0.67945 0.3048)
			(stroke
				(width 0.1)
				(type default)
			)
			(layer "B.Fab")
		)
		(pad "1" smd circle
			(at 0.40005 0)
			(size 0 0)
			(layers "B.Cu" "B.Mask" "B.Paste")
			(net "SPI_PEX0_RST_R_N")
		)
		(pad "2" smd circle
			(at -0.40005 0)
			(size 0 0)
			(layers "B.Cu" "B.Mask" "B.Paste")
			(net "GND")
		)
	)
	(footprint ""
		(layer "B.Cu")
		(at 305.471576 -115.608608)
		(property "Reference" "C934"
			(at 0 0 0)
			(layer "B.SilkS")
			(hide yes)
			(effects
				(font
					(size 1.27 1.27)
				)
				(justify mirror)
			)
		)
		(property "Value" ""
			(at 0 0 0)
			(layer "B.Fab")
			(effects
				(font
					(size 1.27 1.27)
				)
				(justify mirror)
			)
		)
		(duplicate_pad_numbers_are_jumpers no)
		(fp_line
			(start -0.7874 -0.4064)
			(end -0.7874 0.4064)
			(stroke
				(width 0.1524)
				(type default)
			)
			(layer "B.SilkS")
		)
		(fp_line
			(start -0.7874 0.4064)
			(end 0.7874 0.4064)
			(stroke
				(width 0.1524)
				(type default)
			)
			(layer "B.SilkS")
		)
		(fp_line
			(start 0.7874 -0.4064)
			(end -0.7874 -0.4064)
			(stroke
				(width 0.1524)
				(type default)
			)
			(layer "B.SilkS")
		)
		(fp_line
			(start 0.7874 0.4064)
			(end 0.7874 -0.4064)
			(stroke
				(width 0.1524)
				(type default)
			)
			(layer "B.SilkS")
		)
		(fp_line
			(start -0.67945 -0.3048)
			(end -0.67945 0.3048)
			(stroke
				(width 0.1)
				(type default)
			)
			(layer "B.Fab")
		)
		(fp_line
			(start -0.67945 0.3048)
			(end -0.120396 0.3048)
			(stroke
				(width 0.1)
				(type default)
			)
			(layer "B.Fab")
		)
		(fp_line
			(start -0.12065 -0.3048)
			(end -0.67945 -0.3048)
			(stroke
				(width 0.1)
				(type default)
			)
			(layer "B.Fab")
		)
		(fp_line
			(start -0.12065 -0.2794)
			(end -0.12065 -0.3048)
			(stroke
				(width 0.1)
				(type default)
			)
			(layer "B.Fab")
		)
		(fp_line
			(start -0.120396 0.2794)
			(end 0.12065 0.2794)
			(stroke
				(width 0.1)
				(type default)
			)
			(layer "B.Fab")
		)
		(fp_line
			(start -0.120396 0.3048)
			(end -0.120396 0.2794)
			(stroke
				(width 0.1)
				(type default)
			)
			(layer "B.Fab")
		)
		(fp_line
			(start 0.12065 -0.305054)
			(end 0.12065 -0.2794)
			(stroke
				(width 0.1)
				(type default)
			)
			(layer "B.Fab")
		)
		(fp_line
			(start 0.12065 -0.2794)
			(end -0.12065 -0.2794)
			(stroke
				(width 0.1)
				(type default)
			)
			(layer "B.Fab")
		)
		(fp_line
			(start 0.12065 0.2794)
			(end 0.12065 0.3048)
			(stroke
				(width 0.1)
				(type default)
			)
			(layer "B.Fab")
		)
		(fp_line
			(start 0.12065 0.3048)
			(end 0.67945 0.3048)
			(stroke
				(width 0.1)
				(type default)
			)
			(layer "B.Fab")
		)
		(fp_line
			(start 0.67945 -0.305054)
			(end 0.12065 -0.305054)
			(stroke
				(width 0.1)
				(type default)
			)
			(layer "B.Fab")
		)
		(fp_line
			(start 0.67945 0.3048)
			(end 0.67945 -0.305054)
			(stroke
				(width 0.1)
				(type default)
			)
			(layer "B.Fab")
		)
		(pad "1" smd circle
			(at 0.40005 0 180)
			(size 0 0)
			(layers "B.Cu" "B.Mask" "B.Paste")
			(net "P3V3_NIC5")
		)
		(pad "2" smd circle
			(at -0.40005 0 180)
			(size 0 0)
			(layers "B.Cu" "B.Mask" "B.Paste")
			(net "GND")
		)
	)
	(footprint ""
		(layer "B.Cu")
		(at 234.855512 -234.728004 90)
		(property "Reference" "R6185"
			(at 0 0 90)
			(layer "B.SilkS")
			(hide yes)
			(effects
				(font
					(size 1.27 1.27)
				)
				(justify mirror)
			)
		)
		(property "Value" ""
			(at 0 0 90)
			(layer "B.Fab")
			(effects
				(font
					(size 1.27 1.27)
				)
				(justify mirror)
			)
		)
		(duplicate_pad_numbers_are_jumpers no)
		(fp_line
			(start 0.7874 -0.4064)
			(end -0.7874 -0.4064)
			(stroke
				(width 0.1524)
				(type default)
			)
			(layer "B.SilkS")
		)
		(fp_line
			(start -0.7874 -0.4064)
			(end -0.7874 0.4064)
			(stroke
				(width 0.1524)
				(type default)
			)
			(layer "B.SilkS")
		)
		(fp_line
			(start 0.7874 0.4064)
			(end 0.7874 -0.4064)
			(stroke
				(width 0.1524)
				(type default)
			)
			(layer "B.SilkS")
		)
		(fp_line
			(start -0.7874 0.4064)
			(end 0.7874 0.4064)
			(stroke
				(width 0.1524)
				(type default)
			)
			(layer "B.SilkS")
		)
		(fp_line
			(start 0.67945 -0.305054)
			(end 0.12065 -0.305054)
			(stroke
				(width 0.1)
				(type default)
			)
			(layer "B.Fab")
		)
		(fp_line
			(start 0.12065 -0.305054)
			(end 0.12065 -0.2794)
			(stroke
				(width 0.1)
				(type default)
			)
			(layer "B.Fab")
		)
		(fp_line
			(start -0.12065 -0.3048)
			(end -0.67945 -0.3048)
			(stroke
				(width 0.1)
				(type default)
			)
			(layer "B.Fab")
		)
		(fp_line
			(start -0.67945 -0.3048)
			(end -0.67945 0.3048)
			(stroke
				(width 0.1)
				(type default)
			)
			(layer "B.Fab")
		)
		(fp_line
			(start 0.12065 -0.2794)
			(end -0.12065 -0.2794)
			(stroke
				(width 0.1)
				(type default)
			)
			(layer "B.Fab")
		)
		(fp_line
			(start -0.12065 -0.2794)
			(end -0.12065 -0.3048)
			(stroke
				(width 0.1)
				(type default)
			)
			(layer "B.Fab")
		)
		(fp_line
			(start 0.12065 0.2794)
			(end 0.12065 0.3048)
			(stroke
				(width 0.1)
				(type default)
			)
			(layer "B.Fab")
		)
		(fp_line
			(start -0.120396 0.2794)
			(end 0.12065 0.2794)
			(stroke
				(width 0.1)
				(type default)
			)
			(layer "B.Fab")
		)
		(fp_line
			(start 0.67945 0.3048)
			(end 0.67945 -0.305054)
			(stroke
				(width 0.1)
				(type default)
			)
			(layer "B.Fab")
		)
		(fp_line
			(start 0.12065 0.3048)
			(end 0.67945 0.3048)
			(stroke
				(width 0.1)
				(type default)
			)
			(layer "B.Fab")
		)
		(fp_line
			(start -0.120396 0.3048)
			(end -0.120396 0.2794)
			(stroke
				(width 0.1)
				(type default)
			)
			(layer "B.Fab")
		)
		(fp_line
			(start -0.67945 0.3048)
			(end -0.120396 0.3048)
			(stroke
				(width 0.1)
				(type default)
			)
			(layer "B.Fab")
		)
		(pad "1" smd circle
			(at 0.40005 0 270)
			(size 0 0)
			(layers "B.Cu" "B.Mask" "B.Paste")
			(net "GND")
		)
		(pad "2" smd circle
			(at -0.40005 0 270)
			(size 0 0)
			(layers "B.Cu" "B.Mask" "B.Paste")
			(net "SSD3_PWRDIS_BIC_R")
		)
	)
	(footprint ""
		(layer "B.Cu")
		(at 171.474892 -297.79976 90)
		(property "Reference" "C1403"
			(at 0 0 90)
			(layer "B.SilkS")
			(hide yes)
			(effects
				(font
					(size 1.27 1.27)
				)
				(justify mirror)
			)
		)
		(property "Value" ""
			(at 0 0 90)
			(layer "B.Fab")
			(effects
				(font
					(size 1.27 1.27)
				)
				(justify mirror)
			)
		)
		(duplicate_pad_numbers_are_jumpers no)
		(fp_line
			(start 0.299974 -0.150114)
			(end -0.299974 -0.150114)
			(stroke
				(width 0.1)
				(type default)
			)
			(layer "B.Fab")
		)
		(fp_line
			(start -0.299974 -0.150114)
			(end -0.299974 0.150114)
			(stroke
				(width 0.1)
				(type default)
			)
			(layer "B.Fab")
		)
		(fp_line
			(start 0.299974 0.150114)
			(end 0.299974 -0.150114)
			(stroke
				(width 0.1)
				(type default)
			)
			(layer "B.Fab")
		)
		(fp_line
			(start -0.299974 0.150114)
			(end 0.299974 0.150114)
			(stroke
				(width 0.1)
				(type default)
			)
			(layer "B.Fab")
		)
		(pad "1" smd rect
			(at 0.2667 0 270)
			(size 0.3048 0.381)
			(layers "B.Cu" "B.Mask" "B.Paste")
			(net "P0V8_PEX1")
		)
		(pad "2" smd rect
			(at -0.2667 0 270)
			(size 0.3048 0.381)
			(layers "B.Cu" "B.Mask" "B.Paste")
			(net "GND")
		)
	)
	(footprint ""
		(layer "B.Cu")
		(at 77.541882 -103.104696 180)
		(property "Reference" "R67"
			(at 0 0 0)
			(layer "B.SilkS")
			(hide yes)
			(effects
				(font
					(size 1.27 1.27)
				)
				(justify mirror)
			)
		)
		(property "Value" ""
			(at 0 0 0)
			(layer "B.Fab")
			(effects
				(font
					(size 1.27 1.27)
				)
				(justify mirror)
			)
		)
		(duplicate_pad_numbers_are_jumpers no)
		(fp_line
			(start 0.7874 0.4064)
			(end 0.7874 -0.4064)
			(stroke
				(width 0.1524)
				(type default)
			)
			(layer "B.SilkS")
		)
		(fp_line
			(start 0.7874 -0.4064)
			(end -0.7874 -0.4064)
			(stroke
				(width 0.1524)
				(type default)
			)
			(layer "B.SilkS")
		)
		(fp_line
			(start -0.7874 0.4064)
			(end 0.7874 0.4064)
			(stroke
				(width 0.1524)
				(type default)
			)
			(layer "B.SilkS")
		)
		(fp_line
			(start -0.7874 -0.4064)
			(end -0.7874 0.4064)
			(stroke
				(width 0.1524)
				(type default)
			)
			(layer "B.SilkS")
		)
		(fp_line
			(start 0.67945 0.3048)
			(end 0.67945 -0.305054)
			(stroke
				(width 0.1)
				(type default)
			)
			(layer "B.Fab")
		)
		(fp_line
			(start 0.67945 -0.305054)
			(end 0.12065 -0.305054)
			(stroke
				(width 0.1)
				(type default)
			)
			(layer "B.Fab")
		)
		(fp_line
			(start 0.12065 0.3048)
			(end 0.67945 0.3048)
			(stroke
				(width 0.1)
				(type default)
			)
			(layer "B.Fab")
		)
		(fp_line
			(start 0.12065 0.2794)
			(end 0.12065 0.3048)
			(stroke
				(width 0.1)
				(type default)
			)
			(layer "B.Fab")
		)
		(fp_line
			(start 0.12065 -0.2794)
			(end -0.12065 -0.2794)
			(stroke
				(width 0.1)
				(type default)
			)
			(layer "B.Fab")
		)
		(fp_line
			(start 0.12065 -0.305054)
			(end 0.12065 -0.2794)
			(stroke
				(width 0.1)
				(type default)
			)
			(layer "B.Fab")
		)
		(fp_line
			(start -0.120396 0.3048)
			(end -0.120396 0.2794)
			(stroke
				(width 0.1)
				(type default)
			)
			(layer "B.Fab")
		)
		(fp_line
			(start -0.120396 0.2794)
			(end 0.12065 0.2794)
			(stroke
				(width 0.1)
				(type default)
			)
			(layer "B.Fab")
		)
		(fp_line
			(start -0.12065 -0.2794)
			(end -0.12065 -0.3048)
			(stroke
				(width 0.1)
				(type default)
			)
			(layer "B.Fab")
		)
		(fp_line
			(start -0.12065 -0.3048)
			(end -0.67945 -0.3048)
			(stroke
				(width 0.1)
				(type default)
			)
			(layer "B.Fab")
		)
		(fp_line
			(start -0.67945 0.3048)
			(end -0.120396 0.3048)
			(stroke
				(width 0.1)
				(type default)
			)
			(layer "B.Fab")
		)
		(fp_line
			(start -0.67945 -0.3048)
			(end -0.67945 0.3048)
			(stroke
				(width 0.1)
				(type default)
			)
			(layer "B.Fab")
		)
		(pad "1" smd circle
			(at 0.40005 0)
			(size 0 0)
			(layers "B.Cu" "B.Mask" "B.Paste")
			(net "NCSI_NIC1_RXD0")
		)
		(pad "2" smd circle
			(at -0.40005 0)
			(size 0 0)
			(layers "B.Cu" "B.Mask" "B.Paste")
			(net "GND")
		)
	)
	(footprint ""
		(layer "B.Cu")
		(at 397.85544 -153.0096)
		(property "Reference" "R325"
			(at 0 0 0)
			(layer "B.SilkS")
			(hide yes)
			(effects
				(font
					(size 1.27 1.27)
				)
				(justify mirror)
			)
		)
		(property "Value" ""
			(at 0 0 0)
			(layer "B.Fab")
			(effects
				(font
					(size 1.27 1.27)
				)
				(justify mirror)
			)
		)
		(duplicate_pad_numbers_are_jumpers no)
		(fp_line
			(start -0.7874 -0.4064)
			(end -0.7874 0.4064)
			(stroke
				(width 0.1524)
				(type default)
			)
			(layer "B.SilkS")
		)
		(fp_line
			(start -0.7874 0.4064)
			(end 0.7874 0.4064)
			(stroke
				(width 0.1524)
				(type default)
			)
			(layer "B.SilkS")
		)
		(fp_line
			(start 0.7874 -0.4064)
			(end -0.7874 -0.4064)
			(stroke
				(width 0.1524)
				(type default)
			)
			(layer "B.SilkS")
		)
		(fp_line
			(start 0.7874 0.4064)
			(end 0.7874 -0.4064)
			(stroke
				(width 0.1524)
				(type default)
			)
			(layer "B.SilkS")
		)
		(fp_line
			(start -0.67945 -0.3048)
			(end -0.67945 0.3048)
			(stroke
				(width 0.1)
				(type default)
			)
			(layer "B.Fab")
		)
		(fp_line
			(start -0.67945 0.3048)
			(end -0.120396 0.3048)
			(stroke
				(width 0.1)
				(type default)
			)
			(layer "B.Fab")
		)
		(fp_line
			(start -0.12065 -0.3048)
			(end -0.67945 -0.3048)
			(stroke
				(width 0.1)
				(type default)
			)
			(layer "B.Fab")
		)
		(fp_line
			(start -0.12065 -0.2794)
			(end -0.12065 -0.3048)
			(stroke
				(width 0.1)
				(type default)
			)
			(layer "B.Fab")
		)
		(fp_line
			(start -0.120396 0.2794)
			(end 0.12065 0.2794)
			(stroke
				(width 0.1)
				(type default)
			)
			(layer "B.Fab")
		)
		(fp_line
			(start -0.120396 0.3048)
			(end -0.120396 0.2794)
			(stroke
				(width 0.1)
				(type default)
			)
			(layer "B.Fab")
		)
		(fp_line
			(start 0.12065 -0.305054)
			(end 0.12065 -0.2794)
			(stroke
				(width 0.1)
				(type default)
			)
			(layer "B.Fab")
		)
		(fp_line
			(start 0.12065 -0.2794)
			(end -0.12065 -0.2794)
			(stroke
				(width 0.1)
				(type default)
			)
			(layer "B.Fab")
		)
		(fp_line
			(start 0.12065 0.2794)
			(end 0.12065 0.3048)
			(stroke
				(width 0.1)
				(type default)
			)
			(layer "B.Fab")
		)
		(fp_line
			(start 0.12065 0.3048)
			(end 0.67945 0.3048)
			(stroke
				(width 0.1)
				(type default)
			)
			(layer "B.Fab")
		)
		(fp_line
			(start 0.67945 -0.305054)
			(end 0.12065 -0.305054)
			(stroke
				(width 0.1)
				(type default)
			)
			(layer "B.Fab")
		)
		(fp_line
			(start 0.67945 0.3048)
			(end 0.67945 -0.305054)
			(stroke
				(width 0.1)
				(type default)
			)
			(layer "B.Fab")
		)
		(pad "1" smd circle
			(at 0.40005 0 180)
			(size 0 0)
			(layers "B.Cu" "B.Mask" "B.Paste")
			(net "NCSI_NIC6_TXD1")
		)
		(pad "2" smd circle
			(at -0.40005 0 180)
			(size 0 0)
			(layers "B.Cu" "B.Mask" "B.Paste")
			(net "GND")
		)
	)
	(footprint ""
		(layer "B.Cu")
		(at 231.86771 -219.904056)
		(property "Reference" "C3610"
			(at 0 0 0)
			(layer "B.SilkS")
			(hide yes)
			(effects
				(font
					(size 1.27 1.27)
				)
				(justify mirror)
			)
		)
		(property "Value" ""
			(at 0 0 0)
			(layer "B.Fab")
			(effects
				(font
					(size 1.27 1.27)
				)
				(justify mirror)
			)
		)
		(duplicate_pad_numbers_are_jumpers no)
		(fp_line
			(start -0.69215 -0.2921)
			(end -0.69215 0.2921)
			(stroke
				(width 0.1524)
				(type default)
			)
			(layer "B.SilkS")
		)
		(fp_line
			(start -0.69215 0.2921)
			(end 0.69215 0.2921)
			(stroke
				(width 0.1524)
				(type default)
			)
			(layer "B.SilkS")
		)
		(fp_line
			(start 0.69215 -0.2921)
			(end -0.69215 -0.2921)
			(stroke
				(width 0.1524)
				(type default)
			)
			(layer "B.SilkS")
		)
		(fp_line
			(start 0.69215 0.2921)
			(end 0.69215 -0.2921)
			(stroke
				(width 0.1524)
				(type default)
			)
			(layer "B.SilkS")
		)
		(fp_line
			(start -0.51435 -0.2794)
			(end -0.51435 0.2794)
			(stroke
				(width 0.1)
				(type default)
			)
			(layer "B.Fab")
		)
		(fp_line
			(start -0.51435 0.2794)
			(end 0.51435 0.2794)
			(stroke
				(width 0.1)
				(type default)
			)
			(layer "B.Fab")
		)
		(fp_line
			(start 0.51435 -0.2794)
			(end -0.51435 -0.2794)
			(stroke
				(width 0.1)
				(type default)
			)
			(layer "B.Fab")
		)
		(fp_line
			(start 0.51435 0.2794)
			(end 0.51435 -0.2794)
			(stroke
				(width 0.1)
				(type default)
			)
			(layer "B.Fab")
		)
		(pad "1" smd circle
			(at 0.40005 0 180)
			(size 0 0)
			(layers "B.Cu" "B.Mask" "B.Paste")
			(net "P3V3_BIC_ADCAV33")
		)
		(pad "2" smd circle
			(at -0.40005 0 180)
			(size 0 0)
			(layers "B.Cu" "B.Mask" "B.Paste")
			(net "GND")
		)
		(zone
			(layer "B.Cu")
			(hatch none 0.5)
			(connect_pads
				(clearance 0)
			)
			(min_thickness 0.25)
			(keepout
				(tracks not_allowed)
				(vias allowed)
				(pads allowed)
				(copperpour not_allowed)
				(footprints allowed)
			)
			(placement
				(enabled no)
				(sheetname "")
			)
			(fill
				(thermal_gap 0.5)
				(thermal_bridge_width 0.5)
				(island_removal_mode 0)
			)
			(polygon
				(pts
					(xy 232.05821 -219.816426) (xy 231.96677 -219.75826) (xy 231.76738 -219.75826) (xy 231.67721 -219.816426)
					(xy 231.67721 -219.991686) (xy 231.76738 -220.050106) (xy 231.96677 -220.050106) (xy 232.05821 -219.99194)
				)
			)
		)
	)
	(footprint ""
		(layer "B.Cu")
		(at 379.847602 -243.428012 180)
		(property "Reference" "R931"
			(at 0 0 0)
			(layer "B.SilkS")
			(hide yes)
			(effects
				(font
					(size 1.27 1.27)
				)
				(justify mirror)
			)
		)
		(property "Value" ""
			(at 0 0 0)
			(layer "B.Fab")
			(effects
				(font
					(size 1.27 1.27)
				)
				(justify mirror)
			)
		)
		(duplicate_pad_numbers_are_jumpers no)
		(fp_line
			(start 0.7874 0.4064)
			(end 0.7874 -0.4064)
			(stroke
				(width 0.1524)
				(type default)
			)
			(layer "B.SilkS")
		)
		(fp_line
			(start 0.7874 -0.4064)
			(end -0.7874 -0.4064)
			(stroke
				(width 0.1524)
				(type default)
			)
			(layer "B.SilkS")
		)
		(fp_line
			(start -0.7874 0.4064)
			(end 0.7874 0.4064)
			(stroke
				(width 0.1524)
				(type default)
			)
			(layer "B.SilkS")
		)
		(fp_line
			(start -0.7874 -0.4064)
			(end -0.7874 0.4064)
			(stroke
				(width 0.1524)
				(type default)
			)
			(layer "B.SilkS")
		)
		(fp_line
			(start 0.67945 0.3048)
			(end 0.67945 -0.305054)
			(stroke
				(width 0.1)
				(type default)
			)
			(layer "B.Fab")
		)
		(fp_line
			(start 0.67945 -0.305054)
			(end 0.12065 -0.305054)
			(stroke
				(width 0.1)
				(type default)
			)
			(layer "B.Fab")
		)
		(fp_line
			(start 0.12065 0.3048)
			(end 0.67945 0.3048)
			(stroke
				(width 0.1)
				(type default)
			)
			(layer "B.Fab")
		)
		(fp_line
			(start 0.12065 0.2794)
			(end 0.12065 0.3048)
			(stroke
				(width 0.1)
				(type default)
			)
			(layer "B.Fab")
		)
		(fp_line
			(start 0.12065 -0.2794)
			(end -0.12065 -0.2794)
			(stroke
				(width 0.1)
				(type default)
			)
			(layer "B.Fab")
		)
		(fp_line
			(start 0.12065 -0.305054)
			(end 0.12065 -0.2794)
			(stroke
				(width 0.1)
				(type default)
			)
			(layer "B.Fab")
		)
		(fp_line
			(start -0.120396 0.3048)
			(end -0.120396 0.2794)
			(stroke
				(width 0.1)
				(type default)
			)
			(layer "B.Fab")
		)
		(fp_line
			(start -0.120396 0.2794)
			(end 0.12065 0.2794)
			(stroke
				(width 0.1)
				(type default)
			)
			(layer "B.Fab")
		)
		(fp_line
			(start -0.12065 -0.2794)
			(end -0.12065 -0.3048)
			(stroke
				(width 0.1)
				(type default)
			)
			(layer "B.Fab")
		)
		(fp_line
			(start -0.12065 -0.3048)
			(end -0.67945 -0.3048)
			(stroke
				(width 0.1)
				(type default)
			)
			(layer "B.Fab")
		)
		(fp_line
			(start -0.67945 0.3048)
			(end -0.120396 0.3048)
			(stroke
				(width 0.1)
				(type default)
			)
			(layer "B.Fab")
		)
		(fp_line
			(start -0.67945 -0.3048)
			(end -0.67945 0.3048)
			(stroke
				(width 0.1)
				(type default)
			)
			(layer "B.Fab")
		)
		(pad "1" smd circle
			(at 0.40005 0)
			(size 0 0)
			(layers "B.Cu" "B.Mask" "B.Paste")
			(net "UART_PEX0_SDB_BUF_TX")
		)
		(pad "2" smd circle
			(at -0.40005 0)
			(size 0 0)
			(layers "B.Cu" "B.Mask" "B.Paste")
			(net "P3V3_AUX")
		)
	)
	(footprint ""
		(layer "B.Cu")
		(at 344.83802 -308.613556 90)
		(property "Reference" "C4305"
			(at 0 0 90)
			(layer "B.SilkS")
			(hide yes)
			(effects
				(font
					(size 1.27 1.27)
				)
				(justify mirror)
			)
		)
		(property "Value" ""
			(at 0 0 90)
			(layer "B.Fab")
			(effects
				(font
					(size 1.27 1.27)
				)
				(justify mirror)
			)
		)
		(duplicate_pad_numbers_are_jumpers no)
		(fp_line
			(start 1.2954 -0.5842)
			(end -1.2954 -0.5842)
			(stroke
				(width 0.1524)
				(type default)
			)
			(layer "B.SilkS")
		)
		(fp_line
			(start -1.2954 -0.5842)
			(end -1.2954 0.5842)
			(stroke
				(width 0.1524)
				(type default)
			)
			(layer "B.SilkS")
		)
		(fp_line
			(start 1.2954 0.5842)
			(end 1.2954 -0.5842)
			(stroke
				(width 0.1524)
				(type default)
			)
			(layer "B.SilkS")
		)
		(fp_line
			(start -1.2954 0.5842)
			(end 1.2954 0.5842)
			(stroke
				(width 0.1524)
				(type default)
			)
			(layer "B.SilkS")
		)
		(fp_line
			(start 0.8636 -0.4572)
			(end -0.8636 -0.4572)
			(stroke
				(width 0.1)
				(type default)
			)
			(layer "B.Fab")
		)
		(fp_line
			(start -0.8636 -0.4572)
			(end -0.8636 -0.4064)
			(stroke
				(width 0.1)
				(type default)
			)
			(layer "B.Fab")
		)
		(fp_line
			(start 1.1938 -0.4064)
			(end 0.8636 -0.4064)
			(stroke
				(width 0.1)
				(type default)
			)
			(layer "B.Fab")
		)
		(fp_line
			(start 0.8636 -0.4064)
			(end 0.8636 -0.4572)
			(stroke
				(width 0.1)
				(type default)
			)
			(layer "B.Fab")
		)
		(fp_line
			(start -0.8636 -0.4064)
			(end -1.1938 -0.4064)
			(stroke
				(width 0.1)
				(type default)
			)
			(layer "B.Fab")
		)
		(fp_line
			(start -1.1938 -0.4064)
			(end -1.1938 0.4064)
			(stroke
				(width 0.1)
				(type default)
			)
			(layer "B.Fab")
		)
		(fp_line
			(start 1.1938 0.4064)
			(end 1.1938 -0.4064)
			(stroke
				(width 0.1)
				(type default)
			)
			(layer "B.Fab")
		)
		(fp_line
			(start 0.8636 0.4064)
			(end 1.1938 0.4064)
			(stroke
				(width 0.1)
				(type default)
			)
			(layer "B.Fab")
		)
		(fp_line
			(start -0.8636 0.4064)
			(end -0.8636 0.4572)
			(stroke
				(width 0.1)
				(type default)
			)
			(layer "B.Fab")
		)
		(fp_line
			(start -1.1938 0.4064)
			(end -0.8636 0.4064)
			(stroke
				(width 0.1)
				(type default)
			)
			(layer "B.Fab")
		)
		(fp_line
			(start 0.8636 0.4572)
			(end 0.8636 0.4064)
			(stroke
				(width 0.1)
				(type default)
			)
			(layer "B.Fab")
		)
		(fp_line
			(start -0.8636 0.4572)
			(end 0.8636 0.4572)
			(stroke
				(width 0.1)
				(type default)
			)
			(layer "B.Fab")
		)
		(pad "1" smd rect
			(at 0.7366 0)
			(size 0.7112 0.8128)
			(layers "B.Cu" "B.Mask" "B.Paste")
			(net "P0V8_PEX2")
		)
		(pad "2" smd rect
			(at -0.7366 0)
			(size 0.7112 0.8128)
			(layers "B.Cu" "B.Mask" "B.Paste")
			(net "GND")
		)
	)
	(footprint ""
		(layer "B.Cu")
		(at 167.200072 -290.199826 90)
		(property "Reference" "C1428"
			(at 0 0 90)
			(layer "B.SilkS")
			(hide yes)
			(effects
				(font
					(size 1.27 1.27)
				)
				(justify mirror)
			)
		)
		(property "Value" ""
			(at 0 0 90)
			(layer "B.Fab")
			(effects
				(font
					(size 1.27 1.27)
				)
				(justify mirror)
			)
		)
		(duplicate_pad_numbers_are_jumpers no)
		(fp_line
			(start 0.299974 -0.150114)
			(end -0.299974 -0.150114)
			(stroke
				(width 0.1)
				(type default)
			)
			(layer "B.Fab")
		)
		(fp_line
			(start -0.299974 -0.150114)
			(end -0.299974 0.150114)
			(stroke
				(width 0.1)
				(type default)
			)
			(layer "B.Fab")
		)
		(fp_line
			(start 0.299974 0.150114)
			(end 0.299974 -0.150114)
			(stroke
				(width 0.1)
				(type default)
			)
			(layer "B.Fab")
		)
		(fp_line
			(start -0.299974 0.150114)
			(end 0.299974 0.150114)
			(stroke
				(width 0.1)
				(type default)
			)
			(layer "B.Fab")
		)
		(pad "1" smd rect
			(at 0.2667 0 270)
			(size 0.3048 0.381)
			(layers "B.Cu" "B.Mask" "B.Paste")
			(net "P0V8_SERDES_VDDA_PEX1")
		)
		(pad "2" smd rect
			(at -0.2667 0 270)
			(size 0.3048 0.381)
			(layers "B.Cu" "B.Mask" "B.Paste")
			(net "GND")
		)
	)
	(footprint ""
		(layer "B.Cu")
		(at 59.649868 -299.699934 -90)
		(property "Reference" "C1214"
			(at 0 0 90)
			(layer "B.SilkS")
			(hide yes)
			(effects
				(font
					(size 1.27 1.27)
				)
				(justify mirror)
			)
		)
		(property "Value" ""
			(at 0 0 90)
			(layer "B.Fab")
			(effects
				(font
					(size 1.27 1.27)
				)
				(justify mirror)
			)
		)
		(duplicate_pad_numbers_are_jumpers no)
		(fp_line
			(start -0.299974 0.150114)
			(end 0.299974 0.150114)
			(stroke
				(width 0.1)
				(type default)
			)
			(layer "B.Fab")
		)
		(fp_line
			(start 0.299974 0.150114)
			(end 0.299974 -0.150114)
			(stroke
				(width 0.1)
				(type default)
			)
			(layer "B.Fab")
		)
		(fp_line
			(start -0.299974 -0.150114)
			(end -0.299974 0.150114)
			(stroke
				(width 0.1)
				(type default)
			)
			(layer "B.Fab")
		)
		(fp_line
			(start 0.299974 -0.150114)
			(end -0.299974 -0.150114)
			(stroke
				(width 0.1)
				(type default)
			)
			(layer "B.Fab")
		)
		(pad "1" smd rect
			(at 0.2667 0 90)
			(size 0.3048 0.381)
			(layers "B.Cu" "B.Mask" "B.Paste")
			(net "P0V8_SERDES_VDDA_PEX0")
		)
		(pad "2" smd rect
			(at -0.2667 0 90)
			(size 0.3048 0.381)
			(layers "B.Cu" "B.Mask" "B.Paste")
			(net "GND")
		)
	)
	(footprint ""
		(layer "B.Cu")
		(at 130.927602 -308.580028 90)
		(property "Reference" "C4248"
			(at 0 0 90)
			(layer "B.SilkS")
			(hide yes)
			(effects
				(font
					(size 1.27 1.27)
				)
				(justify mirror)
			)
		)
		(property "Value" ""
			(at 0 0 90)
			(layer "B.Fab")
			(effects
				(font
					(size 1.27 1.27)
				)
				(justify mirror)
			)
		)
		(duplicate_pad_numbers_are_jumpers no)
		(fp_line
			(start 1.2954 -0.5842)
			(end -1.2954 -0.5842)
			(stroke
				(width 0.1524)
				(type default)
			)
			(layer "B.SilkS")
		)
		(fp_line
			(start -1.2954 -0.5842)
			(end -1.2954 0.5842)
			(stroke
				(width 0.1524)
				(type default)
			)
			(layer "B.SilkS")
		)
		(fp_line
			(start 1.2954 0.5842)
			(end 1.2954 -0.5842)
			(stroke
				(width 0.1524)
				(type default)
			)
			(layer "B.SilkS")
		)
		(fp_line
			(start -1.2954 0.5842)
			(end 1.2954 0.5842)
			(stroke
				(width 0.1524)
				(type default)
			)
			(layer "B.SilkS")
		)
		(fp_line
			(start 0.8636 -0.4572)
			(end -0.8636 -0.4572)
			(stroke
				(width 0.1)
				(type default)
			)
			(layer "B.Fab")
		)
		(fp_line
			(start -0.8636 -0.4572)
			(end -0.8636 -0.4064)
			(stroke
				(width 0.1)
				(type default)
			)
			(layer "B.Fab")
		)
		(fp_line
			(start 1.1938 -0.4064)
			(end 0.8636 -0.4064)
			(stroke
				(width 0.1)
				(type default)
			)
			(layer "B.Fab")
		)
		(fp_line
			(start 0.8636 -0.4064)
			(end 0.8636 -0.4572)
			(stroke
				(width 0.1)
				(type default)
			)
			(layer "B.Fab")
		)
		(fp_line
			(start -0.8636 -0.4064)
			(end -1.1938 -0.4064)
			(stroke
				(width 0.1)
				(type default)
			)
			(layer "B.Fab")
		)
		(fp_line
			(start -1.1938 -0.4064)
			(end -1.1938 0.4064)
			(stroke
				(width 0.1)
				(type default)
			)
			(layer "B.Fab")
		)
		(fp_line
			(start 1.1938 0.4064)
			(end 1.1938 -0.4064)
			(stroke
				(width 0.1)
				(type default)
			)
			(layer "B.Fab")
		)
		(fp_line
			(start 0.8636 0.4064)
			(end 1.1938 0.4064)
			(stroke
				(width 0.1)
				(type default)
			)
			(layer "B.Fab")
		)
		(fp_line
			(start -0.8636 0.4064)
			(end -0.8636 0.4572)
			(stroke
				(width 0.1)
				(type default)
			)
			(layer "B.Fab")
		)
		(fp_line
			(start -1.1938 0.4064)
			(end -0.8636 0.4064)
			(stroke
				(width 0.1)
				(type default)
			)
			(layer "B.Fab")
		)
		(fp_line
			(start 0.8636 0.4572)
			(end 0.8636 0.4064)
			(stroke
				(width 0.1)
				(type default)
			)
			(layer "B.Fab")
		)
		(fp_line
			(start -0.8636 0.4572)
			(end 0.8636 0.4572)
			(stroke
				(width 0.1)
				(type default)
			)
			(layer "B.Fab")
		)
		(pad "1" smd rect
			(at 0.7366 0)
			(size 0.7112 0.8128)
			(layers "B.Cu" "B.Mask" "B.Paste")
			(net "P0V8_PEX1")
		)
		(pad "2" smd rect
			(at -0.7366 0)
			(size 0.7112 0.8128)
			(layers "B.Cu" "B.Mask" "B.Paste")
			(net "GND")
		)
	)
	(footprint ""
		(layer "B.Cu")
		(at 256.351532 -86.32952 180)
		(property "Reference" "C2643"
			(at 0 0 0)
			(layer "B.SilkS")
			(hide yes)
			(effects
				(font
					(size 1.27 1.27)
				)
				(justify mirror)
			)
		)
		(property "Value" ""
			(at 0 0 0)
			(layer "B.Fab")
			(effects
				(font
					(size 1.27 1.27)
				)
				(justify mirror)
			)
		)
		(duplicate_pad_numbers_are_jumpers no)
		(fp_line
			(start 0.7874 0.4064)
			(end 0.7874 -0.4064)
			(stroke
				(width 0.1524)
				(type default)
			)
			(layer "B.SilkS")
		)
		(fp_line
			(start 0.7874 -0.4064)
			(end -0.7874 -0.4064)
			(stroke
				(width 0.1524)
				(type default)
			)
			(layer "B.SilkS")
		)
		(fp_line
			(start -0.7874 0.4064)
			(end 0.7874 0.4064)
			(stroke
				(width 0.1524)
				(type default)
			)
			(layer "B.SilkS")
		)
		(fp_line
			(start -0.7874 -0.4064)
			(end -0.7874 0.4064)
			(stroke
				(width 0.1524)
				(type default)
			)
			(layer "B.SilkS")
		)
		(fp_line
			(start 0.67945 0.3048)
			(end 0.67945 -0.305054)
			(stroke
				(width 0.1)
				(type default)
			)
			(layer "B.Fab")
		)
		(fp_line
			(start 0.67945 -0.305054)
			(end 0.12065 -0.305054)
			(stroke
				(width 0.1)
				(type default)
			)
			(layer "B.Fab")
		)
		(fp_line
			(start 0.12065 0.3048)
			(end 0.67945 0.3048)
			(stroke
				(width 0.1)
				(type default)
			)
			(layer "B.Fab")
		)
		(fp_line
			(start 0.12065 0.2794)
			(end 0.12065 0.3048)
			(stroke
				(width 0.1)
				(type default)
			)
			(layer "B.Fab")
		)
		(fp_line
			(start 0.12065 -0.2794)
			(end -0.12065 -0.2794)
			(stroke
				(width 0.1)
				(type default)
			)
			(layer "B.Fab")
		)
		(fp_line
			(start 0.12065 -0.305054)
			(end 0.12065 -0.2794)
			(stroke
				(width 0.1)
				(type default)
			)
			(layer "B.Fab")
		)
		(fp_line
			(start -0.120396 0.3048)
			(end -0.120396 0.2794)
			(stroke
				(width 0.1)
				(type default)
			)
			(layer "B.Fab")
		)
		(fp_line
			(start -0.120396 0.2794)
			(end 0.12065 0.2794)
			(stroke
				(width 0.1)
				(type default)
			)
			(layer "B.Fab")
		)
		(fp_line
			(start -0.12065 -0.2794)
			(end -0.12065 -0.3048)
			(stroke
				(width 0.1)
				(type default)
			)
			(layer "B.Fab")
		)
		(fp_line
			(start -0.12065 -0.3048)
			(end -0.67945 -0.3048)
			(stroke
				(width 0.1)
				(type default)
			)
			(layer "B.Fab")
		)
		(fp_line
			(start -0.67945 0.3048)
			(end -0.120396 0.3048)
			(stroke
				(width 0.1)
				(type default)
			)
			(layer "B.Fab")
		)
		(fp_line
			(start -0.67945 -0.3048)
			(end -0.67945 0.3048)
			(stroke
				(width 0.1)
				(type default)
			)
			(layer "B.Fab")
		)
		(pad "1" smd circle
			(at 0.40005 0)
			(size 0 0)
			(layers "B.Cu" "B.Mask" "B.Paste")
			(net "P3V3_CLK_GEN_VDDA25M_CK440")
		)
		(pad "2" smd circle
			(at -0.40005 0)
			(size 0 0)
			(layers "B.Cu" "B.Mask" "B.Paste")
			(net "GND")
		)
	)
	(footprint ""
		(layer "B.Cu")
		(at 346.614242 -308.613556 90)
		(property "Reference" "C1670"
			(at 0 0 90)
			(layer "B.SilkS")
			(hide yes)
			(effects
				(font
					(size 1.27 1.27)
				)
				(justify mirror)
			)
		)
		(property "Value" ""
			(at 0 0 90)
			(layer "B.Fab")
			(effects
				(font
					(size 1.27 1.27)
				)
				(justify mirror)
			)
		)
		(duplicate_pad_numbers_are_jumpers no)
		(fp_line
			(start 1.2954 -0.5842)
			(end -1.2954 -0.5842)
			(stroke
				(width 0.1524)
				(type default)
			)
			(layer "B.SilkS")
		)
		(fp_line
			(start -1.2954 -0.5842)
			(end -1.2954 0.5842)
			(stroke
				(width 0.1524)
				(type default)
			)
			(layer "B.SilkS")
		)
		(fp_line
			(start 1.2954 0.5842)
			(end 1.2954 -0.5842)
			(stroke
				(width 0.1524)
				(type default)
			)
			(layer "B.SilkS")
		)
		(fp_line
			(start -1.2954 0.5842)
			(end 1.2954 0.5842)
			(stroke
				(width 0.1524)
				(type default)
			)
			(layer "B.SilkS")
		)
		(fp_line
			(start 0.8636 -0.4572)
			(end -0.8636 -0.4572)
			(stroke
				(width 0.1)
				(type default)
			)
			(layer "B.Fab")
		)
		(fp_line
			(start -0.8636 -0.4572)
			(end -0.8636 -0.4064)
			(stroke
				(width 0.1)
				(type default)
			)
			(layer "B.Fab")
		)
		(fp_line
			(start 1.1938 -0.4064)
			(end 0.8636 -0.4064)
			(stroke
				(width 0.1)
				(type default)
			)
			(layer "B.Fab")
		)
		(fp_line
			(start 0.8636 -0.4064)
			(end 0.8636 -0.4572)
			(stroke
				(width 0.1)
				(type default)
			)
			(layer "B.Fab")
		)
		(fp_line
			(start -0.8636 -0.4064)
			(end -1.1938 -0.4064)
			(stroke
				(width 0.1)
				(type default)
			)
			(layer "B.Fab")
		)
		(fp_line
			(start -1.1938 -0.4064)
			(end -1.1938 0.4064)
			(stroke
				(width 0.1)
				(type default)
			)
			(layer "B.Fab")
		)
		(fp_line
			(start 1.1938 0.4064)
			(end 1.1938 -0.4064)
			(stroke
				(width 0.1)
				(type default)
			)
			(layer "B.Fab")
		)
		(fp_line
			(start 0.8636 0.4064)
			(end 1.1938 0.4064)
			(stroke
				(width 0.1)
				(type default)
			)
			(layer "B.Fab")
		)
		(fp_line
			(start -0.8636 0.4064)
			(end -0.8636 0.4572)
			(stroke
				(width 0.1)
				(type default)
			)
			(layer "B.Fab")
		)
		(fp_line
			(start -1.1938 0.4064)
			(end -0.8636 0.4064)
			(stroke
				(width 0.1)
				(type default)
			)
			(layer "B.Fab")
		)
		(fp_line
			(start 0.8636 0.4572)
			(end 0.8636 0.4064)
			(stroke
				(width 0.1)
				(type default)
			)
			(layer "B.Fab")
		)
		(fp_line
			(start -0.8636 0.4572)
			(end 0.8636 0.4572)
			(stroke
				(width 0.1)
				(type default)
			)
			(layer "B.Fab")
		)
		(pad "1" smd rect
			(at 0.7366 0)
			(size 0.7112 0.8128)
			(layers "B.Cu" "B.Mask" "B.Paste")
			(net "P0V8_SERDES_VDDA_PEX2")
		)
		(pad "2" smd rect
			(at -0.7366 0)
			(size 0.7112 0.8128)
			(layers "B.Cu" "B.Mask" "B.Paste")
			(net "GND")
		)
	)
	(footprint ""
		(layer "B.Cu")
		(at 53.474874 -297.79976 90)
		(property "Reference" "C1121"
			(at 0 0 90)
			(layer "B.SilkS")
			(hide yes)
			(effects
				(font
					(size 1.27 1.27)
				)
				(justify mirror)
			)
		)
		(property "Value" ""
			(at 0 0 90)
			(layer "B.Fab")
			(effects
				(font
					(size 1.27 1.27)
				)
				(justify mirror)
			)
		)
		(duplicate_pad_numbers_are_jumpers no)
		(fp_line
			(start 0.299974 -0.150114)
			(end -0.299974 -0.150114)
			(stroke
				(width 0.1)
				(type default)
			)
			(layer "B.Fab")
		)
		(fp_line
			(start -0.299974 -0.150114)
			(end -0.299974 0.150114)
			(stroke
				(width 0.1)
				(type default)
			)
			(layer "B.Fab")
		)
		(fp_line
			(start 0.299974 0.150114)
			(end 0.299974 -0.150114)
			(stroke
				(width 0.1)
				(type default)
			)
			(layer "B.Fab")
		)
		(fp_line
			(start -0.299974 0.150114)
			(end 0.299974 0.150114)
			(stroke
				(width 0.1)
				(type default)
			)
			(layer "B.Fab")
		)
		(pad "1" smd rect
			(at 0.2667 0 270)
			(size 0.3048 0.381)
			(layers "B.Cu" "B.Mask" "B.Paste")
			(net "P0V8_PEX0")
		)
		(pad "2" smd rect
			(at -0.2667 0 270)
			(size 0.3048 0.381)
			(layers "B.Cu" "B.Mask" "B.Paste")
			(net "GND")
		)
	)
	(footprint ""
		(layer "B.Cu")
		(at 303.077626 -251.787406 90)
		(property "Reference" "R4098"
			(at 0 0 90)
			(layer "B.SilkS")
			(hide yes)
			(effects
				(font
					(size 1.27 1.27)
				)
				(justify mirror)
			)
		)
		(property "Value" ""
			(at 0 0 90)
			(layer "B.Fab")
			(effects
				(font
					(size 1.27 1.27)
				)
				(justify mirror)
			)
		)
		(duplicate_pad_numbers_are_jumpers no)
		(fp_line
			(start 0.7874 -0.4064)
			(end -0.7874 -0.4064)
			(stroke
				(width 0.1524)
				(type default)
			)
			(layer "B.SilkS")
		)
		(fp_line
			(start -0.7874 -0.4064)
			(end -0.7874 0.4064)
			(stroke
				(width 0.1524)
				(type default)
			)
			(layer "B.SilkS")
		)
		(fp_line
			(start 0.7874 0.4064)
			(end 0.7874 -0.4064)
			(stroke
				(width 0.1524)
				(type default)
			)
			(layer "B.SilkS")
		)
		(fp_line
			(start -0.7874 0.4064)
			(end 0.7874 0.4064)
			(stroke
				(width 0.1524)
				(type default)
			)
			(layer "B.SilkS")
		)
		(fp_line
			(start 0.67945 -0.305054)
			(end 0.12065 -0.305054)
			(stroke
				(width 0.1)
				(type default)
			)
			(layer "B.Fab")
		)
		(fp_line
			(start 0.12065 -0.305054)
			(end 0.12065 -0.2794)
			(stroke
				(width 0.1)
				(type default)
			)
			(layer "B.Fab")
		)
		(fp_line
			(start -0.12065 -0.3048)
			(end -0.67945 -0.3048)
			(stroke
				(width 0.1)
				(type default)
			)
			(layer "B.Fab")
		)
		(fp_line
			(start -0.67945 -0.3048)
			(end -0.67945 0.3048)
			(stroke
				(width 0.1)
				(type default)
			)
			(layer "B.Fab")
		)
		(fp_line
			(start 0.12065 -0.2794)
			(end -0.12065 -0.2794)
			(stroke
				(width 0.1)
				(type default)
			)
			(layer "B.Fab")
		)
		(fp_line
			(start -0.12065 -0.2794)
			(end -0.12065 -0.3048)
			(stroke
				(width 0.1)
				(type default)
			)
			(layer "B.Fab")
		)
		(fp_line
			(start 0.12065 0.2794)
			(end 0.12065 0.3048)
			(stroke
				(width 0.1)
				(type default)
			)
			(layer "B.Fab")
		)
		(fp_line
			(start -0.120396 0.2794)
			(end 0.12065 0.2794)
			(stroke
				(width 0.1)
				(type default)
			)
			(layer "B.Fab")
		)
		(fp_line
			(start 0.67945 0.3048)
			(end 0.67945 -0.305054)
			(stroke
				(width 0.1)
				(type default)
			)
			(layer "B.Fab")
		)
		(fp_line
			(start 0.12065 0.3048)
			(end 0.67945 0.3048)
			(stroke
				(width 0.1)
				(type default)
			)
			(layer "B.Fab")
		)
		(fp_line
			(start -0.120396 0.3048)
			(end -0.120396 0.2794)
			(stroke
				(width 0.1)
				(type default)
			)
			(layer "B.Fab")
		)
		(fp_line
			(start -0.67945 0.3048)
			(end -0.120396 0.3048)
			(stroke
				(width 0.1)
				(type default)
			)
			(layer "B.Fab")
		)
		(pad "1" smd circle
			(at 0.40005 0 270)
			(size 0 0)
			(layers "B.Cu" "B.Mask" "B.Paste")
			(net "SMB_MB_BMC_R_SCL")
		)
		(pad "2" smd circle
			(at -0.40005 0 270)
			(size 0 0)
			(layers "B.Cu" "B.Mask" "B.Paste")
			(net "P3V3_AUX")
		)
	)
	(footprint ""
		(layer "B.Cu")
		(at 213.106 -203.327 -90)
		(property "Reference" "R6308"
			(at 0 0 90)
			(layer "B.SilkS")
			(hide yes)
			(effects
				(font
					(size 1.27 1.27)
				)
				(justify mirror)
			)
		)
		(property "Value" ""
			(at 0 0 90)
			(layer "B.Fab")
			(effects
				(font
					(size 1.27 1.27)
				)
				(justify mirror)
			)
		)
		(duplicate_pad_numbers_are_jumpers no)
		(fp_line
			(start -0.7874 0.4064)
			(end 0.7874 0.4064)
			(stroke
				(width 0.1524)
				(type default)
			)
			(layer "B.SilkS")
		)
		(fp_line
			(start 0.7874 0.4064)
			(end 0.7874 -0.4064)
			(stroke
				(width 0.1524)
				(type default)
			)
			(layer "B.SilkS")
		)
		(fp_line
			(start -0.7874 -0.4064)
			(end -0.7874 0.4064)
			(stroke
				(width 0.1524)
				(type default)
			)
			(layer "B.SilkS")
		)
		(fp_line
			(start 0.7874 -0.4064)
			(end -0.7874 -0.4064)
			(stroke
				(width 0.1524)
				(type default)
			)
			(layer "B.SilkS")
		)
		(fp_line
			(start -0.67945 0.3048)
			(end -0.120396 0.3048)
			(stroke
				(width 0.1)
				(type default)
			)
			(layer "B.Fab")
		)
		(fp_line
			(start -0.120396 0.3048)
			(end -0.120396 0.2794)
			(stroke
				(width 0.1)
				(type default)
			)
			(layer "B.Fab")
		)
		(fp_line
			(start 0.12065 0.3048)
			(end 0.67945 0.3048)
			(stroke
				(width 0.1)
				(type default)
			)
			(layer "B.Fab")
		)
		(fp_line
			(start 0.67945 0.3048)
			(end 0.67945 -0.305054)
			(stroke
				(width 0.1)
				(type default)
			)
			(layer "B.Fab")
		)
		(fp_line
			(start -0.120396 0.2794)
			(end 0.12065 0.2794)
			(stroke
				(width 0.1)
				(type default)
			)
			(layer "B.Fab")
		)
		(fp_line
			(start 0.12065 0.2794)
			(end 0.12065 0.3048)
			(stroke
				(width 0.1)
				(type default)
			)
			(layer "B.Fab")
		)
		(fp_line
			(start -0.12065 -0.2794)
			(end -0.12065 -0.3048)
			(stroke
				(width 0.1)
				(type default)
			)
			(layer "B.Fab")
		)
		(fp_line
			(start 0.12065 -0.2794)
			(end -0.12065 -0.2794)
			(stroke
				(width 0.1)
				(type default)
			)
			(layer "B.Fab")
		)
		(fp_line
			(start -0.67945 -0.3048)
			(end -0.67945 0.3048)
			(stroke
				(width 0.1)
				(type default)
			)
			(layer "B.Fab")
		)
		(fp_line
			(start -0.12065 -0.3048)
			(end -0.67945 -0.3048)
			(stroke
				(width 0.1)
				(type default)
			)
			(layer "B.Fab")
		)
		(fp_line
			(start 0.12065 -0.305054)
			(end 0.12065 -0.2794)
			(stroke
				(width 0.1)
				(type default)
			)
			(layer "B.Fab")
		)
		(fp_line
			(start 0.67945 -0.305054)
			(end 0.12065 -0.305054)
			(stroke
				(width 0.1)
				(type default)
			)
			(layer "B.Fab")
		)
		(pad "1" smd circle
			(at 0.40005 0 90)
			(size 0 0)
			(layers "B.Cu" "B.Mask" "B.Paste")
			(net "SMB_NIC5_LS_SDA")
		)
		(pad "2" smd circle
			(at -0.40005 0 90)
			(size 0 0)
			(layers "B.Cu" "B.Mask" "B.Paste")
			(net "SMB_NIC5_LS_R_SDA")
		)
	)
	(footprint ""
		(layer "B.Cu")
		(at 338.893912 -216.386918 90)
		(property "Reference" "C2076"
			(at 0 0 90)
			(layer "B.SilkS")
			(hide yes)
			(effects
				(font
					(size 1.27 1.27)
				)
				(justify mirror)
			)
		)
		(property "Value" ""
			(at 0 0 90)
			(layer "B.Fab")
			(effects
				(font
					(size 1.27 1.27)
				)
				(justify mirror)
			)
		)
		(duplicate_pad_numbers_are_jumpers no)
		(fp_line
			(start 0.69215 -0.2921)
			(end -0.69215 -0.2921)
			(stroke
				(width 0.1524)
				(type default)
			)
			(layer "B.SilkS")
		)
		(fp_line
			(start -0.69215 -0.2921)
			(end -0.69215 0.2921)
			(stroke
				(width 0.1524)
				(type default)
			)
			(layer "B.SilkS")
		)
		(fp_line
			(start 0.69215 0.2921)
			(end 0.69215 -0.2921)
			(stroke
				(width 0.1524)
				(type default)
			)
			(layer "B.SilkS")
		)
		(fp_line
			(start -0.69215 0.2921)
			(end 0.69215 0.2921)
			(stroke
				(width 0.1524)
				(type default)
			)
			(layer "B.SilkS")
		)
		(fp_line
			(start 0.51435 -0.2794)
			(end -0.51435 -0.2794)
			(stroke
				(width 0.1)
				(type default)
			)
			(layer "B.Fab")
		)
		(fp_line
			(start -0.51435 -0.2794)
			(end -0.51435 0.2794)
			(stroke
				(width 0.1)
				(type default)
			)
			(layer "B.Fab")
		)
		(fp_line
			(start 0.51435 0.2794)
			(end 0.51435 -0.2794)
			(stroke
				(width 0.1)
				(type default)
			)
			(layer "B.Fab")
		)
		(fp_line
			(start -0.51435 0.2794)
			(end 0.51435 0.2794)
			(stroke
				(width 0.1)
				(type default)
			)
			(layer "B.Fab")
		)
		(pad "1" smd circle
			(at 0.40005 0 270)
			(size 0 0)
			(layers "B.Cu" "B.Mask" "B.Paste")
			(net "P3V3_FPGA_VCCIO3")
		)
		(pad "2" smd circle
			(at -0.40005 0 270)
			(size 0 0)
			(layers "B.Cu" "B.Mask" "B.Paste")
			(net "GND")
		)
		(zone
			(layer "B.Cu")
			(hatch none 0.5)
			(connect_pads
				(clearance 0)
			)
			(min_thickness 0.25)
			(keepout
				(tracks not_allowed)
				(vias allowed)
				(pads allowed)
				(copperpour not_allowed)
				(footprints allowed)
			)
			(placement
				(enabled no)
				(sheetname "")
			)
			(fill
				(thermal_gap 0.5)
				(thermal_bridge_width 0.5)
				(island_removal_mode 0)
			)
			(polygon
				(pts
					(xy 338.981542 -216.577418) (xy 339.039708 -216.485978) (xy 339.039708 -216.286588) (xy 338.981542 -216.196418)
					(xy 338.806282 -216.196418) (xy 338.747862 -216.286588) (xy 338.747862 -216.485978) (xy 338.806028 -216.577418)
				)
			)
		)
	)
	(footprint ""
		(layer "B.Cu")
		(at 214.432642 -222.370904 180)
		(property "Reference" "R1489"
			(at 0 0 0)
			(layer "B.SilkS")
			(hide yes)
			(effects
				(font
					(size 1.27 1.27)
				)
				(justify mirror)
			)
		)
		(property "Value" ""
			(at 0 0 0)
			(layer "B.Fab")
			(effects
				(font
					(size 1.27 1.27)
				)
				(justify mirror)
			)
		)
		(duplicate_pad_numbers_are_jumpers no)
		(fp_line
			(start 0.7874 0.4064)
			(end 0.7874 -0.4064)
			(stroke
				(width 0.1524)
				(type default)
			)
			(layer "B.SilkS")
		)
		(fp_line
			(start 0.7874 -0.4064)
			(end -0.7874 -0.4064)
			(stroke
				(width 0.1524)
				(type default)
			)
			(layer "B.SilkS")
		)
		(fp_line
			(start -0.7874 0.4064)
			(end 0.7874 0.4064)
			(stroke
				(width 0.1524)
				(type default)
			)
			(layer "B.SilkS")
		)
		(fp_line
			(start -0.7874 -0.4064)
			(end -0.7874 0.4064)
			(stroke
				(width 0.1524)
				(type default)
			)
			(layer "B.SilkS")
		)
		(fp_line
			(start 0.67945 0.3048)
			(end 0.67945 -0.305054)
			(stroke
				(width 0.1)
				(type default)
			)
			(layer "B.Fab")
		)
		(fp_line
			(start 0.67945 -0.305054)
			(end 0.12065 -0.305054)
			(stroke
				(width 0.1)
				(type default)
			)
			(layer "B.Fab")
		)
		(fp_line
			(start 0.12065 0.3048)
			(end 0.67945 0.3048)
			(stroke
				(width 0.1)
				(type default)
			)
			(layer "B.Fab")
		)
		(fp_line
			(start 0.12065 0.2794)
			(end 0.12065 0.3048)
			(stroke
				(width 0.1)
				(type default)
			)
			(layer "B.Fab")
		)
		(fp_line
			(start 0.12065 -0.2794)
			(end -0.12065 -0.2794)
			(stroke
				(width 0.1)
				(type default)
			)
			(layer "B.Fab")
		)
		(fp_line
			(start 0.12065 -0.305054)
			(end 0.12065 -0.2794)
			(stroke
				(width 0.1)
				(type default)
			)
			(layer "B.Fab")
		)
		(fp_line
			(start -0.120396 0.3048)
			(end -0.120396 0.2794)
			(stroke
				(width 0.1)
				(type default)
			)
			(layer "B.Fab")
		)
		(fp_line
			(start -0.120396 0.2794)
			(end 0.12065 0.2794)
			(stroke
				(width 0.1)
				(type default)
			)
			(layer "B.Fab")
		)
		(fp_line
			(start -0.12065 -0.2794)
			(end -0.12065 -0.3048)
			(stroke
				(width 0.1)
				(type default)
			)
			(layer "B.Fab")
		)
		(fp_line
			(start -0.12065 -0.3048)
			(end -0.67945 -0.3048)
			(stroke
				(width 0.1)
				(type default)
			)
			(layer "B.Fab")
		)
		(fp_line
			(start -0.67945 0.3048)
			(end -0.120396 0.3048)
			(stroke
				(width 0.1)
				(type default)
			)
			(layer "B.Fab")
		)
		(fp_line
			(start -0.67945 -0.3048)
			(end -0.67945 0.3048)
			(stroke
				(width 0.1)
				(type default)
			)
			(layer "B.Fab")
		)
		(pad "1" smd circle
			(at 0.40005 0)
			(size 0 0)
			(layers "B.Cu" "B.Mask" "B.Paste")
			(net "SMB_BIC_FPGA_SDA")
		)
		(pad "2" smd circle
			(at -0.40005 0)
			(size 0 0)
			(layers "B.Cu" "B.Mask" "B.Paste")
			(net "SMB_BIC_FPGA_R_SDA")
		)
	)
	(footprint ""
		(layer "B.Cu")
		(at 304.728626 -242.262406)
		(property "Reference" "C2779"
			(at 0 0 0)
			(layer "B.SilkS")
			(hide yes)
			(effects
				(font
					(size 1.27 1.27)
				)
				(justify mirror)
			)
		)
		(property "Value" ""
			(at 0 0 0)
			(layer "B.Fab")
			(effects
				(font
					(size 1.27 1.27)
				)
				(justify mirror)
			)
		)
		(duplicate_pad_numbers_are_jumpers no)
		(fp_line
			(start -0.7874 -0.4064)
			(end -0.7874 0.4064)
			(stroke
				(width 0.1524)
				(type default)
			)
			(layer "B.SilkS")
		)
		(fp_line
			(start -0.7874 0.4064)
			(end 0.7874 0.4064)
			(stroke
				(width 0.1524)
				(type default)
			)
			(layer "B.SilkS")
		)
		(fp_line
			(start 0.7874 -0.4064)
			(end -0.7874 -0.4064)
			(stroke
				(width 0.1524)
				(type default)
			)
			(layer "B.SilkS")
		)
		(fp_line
			(start 0.7874 0.4064)
			(end 0.7874 -0.4064)
			(stroke
				(width 0.1524)
				(type default)
			)
			(layer "B.SilkS")
		)
		(fp_line
			(start -0.67945 -0.3048)
			(end -0.67945 0.3048)
			(stroke
				(width 0.1)
				(type default)
			)
			(layer "B.Fab")
		)
		(fp_line
			(start -0.67945 0.3048)
			(end -0.120396 0.3048)
			(stroke
				(width 0.1)
				(type default)
			)
			(layer "B.Fab")
		)
		(fp_line
			(start -0.12065 -0.3048)
			(end -0.67945 -0.3048)
			(stroke
				(width 0.1)
				(type default)
			)
			(layer "B.Fab")
		)
		(fp_line
			(start -0.12065 -0.2794)
			(end -0.12065 -0.3048)
			(stroke
				(width 0.1)
				(type default)
			)
			(layer "B.Fab")
		)
		(fp_line
			(start -0.120396 0.2794)
			(end 0.12065 0.2794)
			(stroke
				(width 0.1)
				(type default)
			)
			(layer "B.Fab")
		)
		(fp_line
			(start -0.120396 0.3048)
			(end -0.120396 0.2794)
			(stroke
				(width 0.1)
				(type default)
			)
			(layer "B.Fab")
		)
		(fp_line
			(start 0.12065 -0.305054)
			(end 0.12065 -0.2794)
			(stroke
				(width 0.1)
				(type default)
			)
			(layer "B.Fab")
		)
		(fp_line
			(start 0.12065 -0.2794)
			(end -0.12065 -0.2794)
			(stroke
				(width 0.1)
				(type default)
			)
			(layer "B.Fab")
		)
		(fp_line
			(start 0.12065 0.2794)
			(end 0.12065 0.3048)
			(stroke
				(width 0.1)
				(type default)
			)
			(layer "B.Fab")
		)
		(fp_line
			(start 0.12065 0.3048)
			(end 0.67945 0.3048)
			(stroke
				(width 0.1)
				(type default)
			)
			(layer "B.Fab")
		)
		(fp_line
			(start 0.67945 -0.305054)
			(end 0.12065 -0.305054)
			(stroke
				(width 0.1)
				(type default)
			)
			(layer "B.Fab")
		)
		(fp_line
			(start 0.67945 0.3048)
			(end 0.67945 -0.305054)
			(stroke
				(width 0.1)
				(type default)
			)
			(layer "B.Fab")
		)
		(pad "1" smd circle
			(at 0.40005 0 180)
			(size 0 0)
			(layers "B.Cu" "B.Mask" "B.Paste")
			(net "GND")
		)
		(pad "2" smd circle
			(at -0.40005 0 180)
			(size 0 0)
			(layers "B.Cu" "B.Mask" "B.Paste")
			(net "P3V3_AUX")
		)
	)
	(footprint ""
		(layer "B.Cu")
		(at 108.059982 -282.168092 90)
		(property "Reference" "R6762"
			(at 0 0 90)
			(layer "B.SilkS")
			(hide yes)
			(effects
				(font
					(size 1.27 1.27)
				)
				(justify mirror)
			)
		)
		(property "Value" ""
			(at 0 0 90)
			(layer "B.Fab")
			(effects
				(font
					(size 1.27 1.27)
				)
				(justify mirror)
			)
		)
		(duplicate_pad_numbers_are_jumpers no)
		(fp_line
			(start 0.7874 -0.4064)
			(end -0.7874 -0.4064)
			(stroke
				(width 0.1524)
				(type default)
			)
			(layer "B.SilkS")
		)
		(fp_line
			(start -0.7874 -0.4064)
			(end -0.7874 0.4064)
			(stroke
				(width 0.1524)
				(type default)
			)
			(layer "B.SilkS")
		)
		(fp_line
			(start 0.7874 0.4064)
			(end 0.7874 -0.4064)
			(stroke
				(width 0.1524)
				(type default)
			)
			(layer "B.SilkS")
		)
		(fp_line
			(start -0.7874 0.4064)
			(end 0.7874 0.4064)
			(stroke
				(width 0.1524)
				(type default)
			)
			(layer "B.SilkS")
		)
		(fp_line
			(start 0.67945 -0.305054)
			(end 0.12065 -0.305054)
			(stroke
				(width 0.1)
				(type default)
			)
			(layer "B.Fab")
		)
		(fp_line
			(start 0.12065 -0.305054)
			(end 0.12065 -0.2794)
			(stroke
				(width 0.1)
				(type default)
			)
			(layer "B.Fab")
		)
		(fp_line
			(start -0.12065 -0.3048)
			(end -0.67945 -0.3048)
			(stroke
				(width 0.1)
				(type default)
			)
			(layer "B.Fab")
		)
		(fp_line
			(start -0.67945 -0.3048)
			(end -0.67945 0.3048)
			(stroke
				(width 0.1)
				(type default)
			)
			(layer "B.Fab")
		)
		(fp_line
			(start 0.12065 -0.2794)
			(end -0.12065 -0.2794)
			(stroke
				(width 0.1)
				(type default)
			)
			(layer "B.Fab")
		)
		(fp_line
			(start -0.12065 -0.2794)
			(end -0.12065 -0.3048)
			(stroke
				(width 0.1)
				(type default)
			)
			(layer "B.Fab")
		)
		(fp_line
			(start 0.12065 0.2794)
			(end 0.12065 0.3048)
			(stroke
				(width 0.1)
				(type default)
			)
			(layer "B.Fab")
		)
		(fp_line
			(start -0.120396 0.2794)
			(end 0.12065 0.2794)
			(stroke
				(width 0.1)
				(type default)
			)
			(layer "B.Fab")
		)
		(fp_line
			(start 0.67945 0.3048)
			(end 0.67945 -0.305054)
			(stroke
				(width 0.1)
				(type default)
			)
			(layer "B.Fab")
		)
		(fp_line
			(start 0.12065 0.3048)
			(end 0.67945 0.3048)
			(stroke
				(width 0.1)
				(type default)
			)
			(layer "B.Fab")
		)
		(fp_line
			(start -0.120396 0.3048)
			(end -0.120396 0.2794)
			(stroke
				(width 0.1)
				(type default)
			)
			(layer "B.Fab")
		)
		(fp_line
			(start -0.67945 0.3048)
			(end -0.120396 0.3048)
			(stroke
				(width 0.1)
				(type default)
			)
			(layer "B.Fab")
		)
		(pad "1" smd circle
			(at 0.40005 0 270)
			(size 0 0)
			(layers "B.Cu" "B.Mask" "B.Paste")
			(net "P0V8_PEX0_VCC1")
		)
		(pad "2" smd circle
			(at -0.40005 0 270)
			(size 0 0)
			(layers "B.Cu" "B.Mask" "B.Paste")
			(net "P0V8_PEX0_EN1")
		)
	)
	(footprint ""
		(layer "B.Cu")
		(at 291.84981 -290.199826 90)
		(property "Reference" "C1739"
			(at 0 0 90)
			(layer "B.SilkS")
			(hide yes)
			(effects
				(font
					(size 1.27 1.27)
				)
				(justify mirror)
			)
		)
		(property "Value" ""
			(at 0 0 90)
			(layer "B.Fab")
			(effects
				(font
					(size 1.27 1.27)
				)
				(justify mirror)
			)
		)
		(duplicate_pad_numbers_are_jumpers no)
		(fp_line
			(start 0.299974 -0.150114)
			(end -0.299974 -0.150114)
			(stroke
				(width 0.1)
				(type default)
			)
			(layer "B.Fab")
		)
		(fp_line
			(start -0.299974 -0.150114)
			(end -0.299974 0.150114)
			(stroke
				(width 0.1)
				(type default)
			)
			(layer "B.Fab")
		)
		(fp_line
			(start 0.299974 0.150114)
			(end 0.299974 -0.150114)
			(stroke
				(width 0.1)
				(type default)
			)
			(layer "B.Fab")
		)
		(fp_line
			(start -0.299974 0.150114)
			(end 0.299974 0.150114)
			(stroke
				(width 0.1)
				(type default)
			)
			(layer "B.Fab")
		)
		(pad "1" smd rect
			(at 0.2667 0 270)
			(size 0.3048 0.381)
			(layers "B.Cu" "B.Mask" "B.Paste")
			(net "P0V8_SERDES_VDDA_PEX2")
		)
		(pad "2" smd rect
			(at -0.2667 0 270)
			(size 0.3048 0.381)
			(layers "B.Cu" "B.Mask" "B.Paste")
			(net "GND")
		)
	)
	(footprint ""
		(layer "B.Cu")
		(at 229.145084 -225.673412 180)
		(property "Reference" "R6820"
			(at 0 0 0)
			(layer "B.SilkS")
			(hide yes)
			(effects
				(font
					(size 1.27 1.27)
				)
				(justify mirror)
			)
		)
		(property "Value" ""
			(at 0 0 0)
			(layer "B.Fab")
			(effects
				(font
					(size 1.27 1.27)
				)
				(justify mirror)
			)
		)
		(duplicate_pad_numbers_are_jumpers no)
		(fp_line
			(start 0.7874 0.4064)
			(end 0.7874 -0.4064)
			(stroke
				(width 0.1524)
				(type default)
			)
			(layer "B.SilkS")
		)
		(fp_line
			(start 0.7874 -0.4064)
			(end -0.7874 -0.4064)
			(stroke
				(width 0.1524)
				(type default)
			)
			(layer "B.SilkS")
		)
		(fp_line
			(start -0.7874 0.4064)
			(end 0.7874 0.4064)
			(stroke
				(width 0.1524)
				(type default)
			)
			(layer "B.SilkS")
		)
		(fp_line
			(start -0.7874 -0.4064)
			(end -0.7874 0.4064)
			(stroke
				(width 0.1524)
				(type default)
			)
			(layer "B.SilkS")
		)
		(fp_line
			(start 0.67945 0.3048)
			(end 0.67945 -0.305054)
			(stroke
				(width 0.1)
				(type default)
			)
			(layer "B.Fab")
		)
		(fp_line
			(start 0.67945 -0.305054)
			(end 0.12065 -0.305054)
			(stroke
				(width 0.1)
				(type default)
			)
			(layer "B.Fab")
		)
		(fp_line
			(start 0.12065 0.3048)
			(end 0.67945 0.3048)
			(stroke
				(width 0.1)
				(type default)
			)
			(layer "B.Fab")
		)
		(fp_line
			(start 0.12065 0.2794)
			(end 0.12065 0.3048)
			(stroke
				(width 0.1)
				(type default)
			)
			(layer "B.Fab")
		)
		(fp_line
			(start 0.12065 -0.2794)
			(end -0.12065 -0.2794)
			(stroke
				(width 0.1)
				(type default)
			)
			(layer "B.Fab")
		)
		(fp_line
			(start 0.12065 -0.305054)
			(end 0.12065 -0.2794)
			(stroke
				(width 0.1)
				(type default)
			)
			(layer "B.Fab")
		)
		(fp_line
			(start -0.120396 0.3048)
			(end -0.120396 0.2794)
			(stroke
				(width 0.1)
				(type default)
			)
			(layer "B.Fab")
		)
		(fp_line
			(start -0.120396 0.2794)
			(end 0.12065 0.2794)
			(stroke
				(width 0.1)
				(type default)
			)
			(layer "B.Fab")
		)
		(fp_line
			(start -0.12065 -0.2794)
			(end -0.12065 -0.3048)
			(stroke
				(width 0.1)
				(type default)
			)
			(layer "B.Fab")
		)
		(fp_line
			(start -0.12065 -0.3048)
			(end -0.67945 -0.3048)
			(stroke
				(width 0.1)
				(type default)
			)
			(layer "B.Fab")
		)
		(fp_line
			(start -0.67945 0.3048)
			(end -0.120396 0.3048)
			(stroke
				(width 0.1)
				(type default)
			)
			(layer "B.Fab")
		)
		(fp_line
			(start -0.67945 -0.3048)
			(end -0.67945 0.3048)
			(stroke
				(width 0.1)
				(type default)
			)
			(layer "B.Fab")
		)
		(pad "1" smd circle
			(at 0.40005 0)
			(size 0 0)
			(layers "B.Cu" "B.Mask" "B.Paste")
			(net "GND")
		)
		(pad "2" smd circle
			(at -0.40005 0)
			(size 0 0)
			(layers "B.Cu" "B.Mask" "B.Paste")
			(net "BOARD_TYPE_0_ADC_R")
		)
	)
	(footprint ""
		(layer "B.Cu")
		(at 112.578642 -281.024838 90)
		(property "Reference" "PC63"
			(at 0 0 90)
			(layer "B.SilkS")
			(hide yes)
			(effects
				(font
					(size 1.27 1.27)
				)
				(justify mirror)
			)
		)
		(property "Value" ""
			(at 0 0 90)
			(layer "B.Fab")
			(effects
				(font
					(size 1.27 1.27)
				)
				(justify mirror)
			)
		)
		(duplicate_pad_numbers_are_jumpers no)
		(fp_line
			(start 1.524 -0.762)
			(end -1.524 -0.762)
			(stroke
				(width 0.1524)
				(type default)
			)
			(layer "B.SilkS")
		)
		(fp_line
			(start -1.524 -0.762)
			(end -1.524 0.762)
			(stroke
				(width 0.1524)
				(type default)
			)
			(layer "B.SilkS")
		)
		(fp_line
			(start 1.524 0.762)
			(end 1.524 -0.762)
			(stroke
				(width 0.1524)
				(type default)
			)
			(layer "B.SilkS")
		)
		(fp_line
			(start -1.524 0.762)
			(end 1.524 0.762)
			(stroke
				(width 0.1524)
				(type default)
			)
			(layer "B.SilkS")
		)
		(fp_line
			(start 1.1049 -0.724916)
			(end 1.1049 0.724916)
			(stroke
				(width 0.1)
				(type default)
			)
			(layer "B.Fab")
		)
		(fp_line
			(start -1.1049 -0.724916)
			(end 1.1049 -0.724916)
			(stroke
				(width 0.1)
				(type default)
			)
			(layer "B.Fab")
		)
		(fp_line
			(start 1.1049 0.724916)
			(end -1.1049 0.724916)
			(stroke
				(width 0.1)
				(type default)
			)
			(layer "B.Fab")
		)
		(fp_line
			(start -1.1049 0.724916)
			(end -1.1049 -0.724916)
			(stroke
				(width 0.1)
				(type default)
			)
			(layer "B.Fab")
		)
		(pad "1" smd rect
			(at 0.889 0 90)
			(size 1.016 1.27)
			(layers "B.Cu" "B.Mask" "B.Paste")
			(net "SW_P12V_P0V8_PEX0_FLT")
		)
		(pad "2" smd rect
			(at -0.889 0 90)
			(size 1.016 1.27)
			(layers "B.Cu" "B.Mask" "B.Paste")
			(net "GND")
		)
	)
	(footprint ""
		(layer "B.Cu")
		(at 160.549844 -295.89984)
		(property "Reference" "C3175"
			(at 0 0 0)
			(layer "B.SilkS")
			(hide yes)
			(effects
				(font
					(size 1.27 1.27)
				)
				(justify mirror)
			)
		)
		(property "Value" ""
			(at 0 0 0)
			(layer "B.Fab")
			(effects
				(font
					(size 1.27 1.27)
				)
				(justify mirror)
			)
		)
		(duplicate_pad_numbers_are_jumpers no)
		(fp_line
			(start -0.299974 -0.150114)
			(end -0.299974 0.150114)
			(stroke
				(width 0.1)
				(type default)
			)
			(layer "B.Fab")
		)
		(fp_line
			(start -0.299974 0.150114)
			(end 0.299974 0.150114)
			(stroke
				(width 0.1)
				(type default)
			)
			(layer "B.Fab")
		)
		(fp_line
			(start 0.299974 -0.150114)
			(end -0.299974 -0.150114)
			(stroke
				(width 0.1)
				(type default)
			)
			(layer "B.Fab")
		)
		(fp_line
			(start 0.299974 0.150114)
			(end 0.299974 -0.150114)
			(stroke
				(width 0.1)
				(type default)
			)
			(layer "B.Fab")
		)
		(pad "1" smd rect
			(at 0.2667 0 180)
			(size 0.3048 0.381)
			(layers "B.Cu" "B.Mask" "B.Paste")
			(net "P1V8_PEX")
		)
		(pad "2" smd rect
			(at -0.2667 0 180)
			(size 0.3048 0.381)
			(layers "B.Cu" "B.Mask" "B.Paste")
			(net "GND")
		)
	)
	(footprint ""
		(layer "B.Cu")
		(at 281.065986 -138.421618 180)
		(property "Reference" "R207"
			(at 0 0 0)
			(layer "B.SilkS")
			(hide yes)
			(effects
				(font
					(size 1.27 1.27)
				)
				(justify mirror)
			)
		)
		(property "Value" ""
			(at 0 0 0)
			(layer "B.Fab")
			(effects
				(font
					(size 1.27 1.27)
				)
				(justify mirror)
			)
		)
		(duplicate_pad_numbers_are_jumpers no)
		(fp_line
			(start 0.7874 0.4064)
			(end 0.7874 -0.4064)
			(stroke
				(width 0.1524)
				(type default)
			)
			(layer "B.SilkS")
		)
		(fp_line
			(start 0.7874 -0.4064)
			(end -0.7874 -0.4064)
			(stroke
				(width 0.1524)
				(type default)
			)
			(layer "B.SilkS")
		)
		(fp_line
			(start -0.7874 0.4064)
			(end 0.7874 0.4064)
			(stroke
				(width 0.1524)
				(type default)
			)
			(layer "B.SilkS")
		)
		(fp_line
			(start -0.7874 -0.4064)
			(end -0.7874 0.4064)
			(stroke
				(width 0.1524)
				(type default)
			)
			(layer "B.SilkS")
		)
		(fp_line
			(start 0.67945 0.3048)
			(end 0.67945 -0.305054)
			(stroke
				(width 0.1)
				(type default)
			)
			(layer "B.Fab")
		)
		(fp_line
			(start 0.67945 -0.305054)
			(end 0.12065 -0.305054)
			(stroke
				(width 0.1)
				(type default)
			)
			(layer "B.Fab")
		)
		(fp_line
			(start 0.12065 0.3048)
			(end 0.67945 0.3048)
			(stroke
				(width 0.1)
				(type default)
			)
			(layer "B.Fab")
		)
		(fp_line
			(start 0.12065 0.2794)
			(end 0.12065 0.3048)
			(stroke
				(width 0.1)
				(type default)
			)
			(layer "B.Fab")
		)
		(fp_line
			(start 0.12065 -0.2794)
			(end -0.12065 -0.2794)
			(stroke
				(width 0.1)
				(type default)
			)
			(layer "B.Fab")
		)
		(fp_line
			(start 0.12065 -0.305054)
			(end 0.12065 -0.2794)
			(stroke
				(width 0.1)
				(type default)
			)
			(layer "B.Fab")
		)
		(fp_line
			(start -0.120396 0.3048)
			(end -0.120396 0.2794)
			(stroke
				(width 0.1)
				(type default)
			)
			(layer "B.Fab")
		)
		(fp_line
			(start -0.120396 0.2794)
			(end 0.12065 0.2794)
			(stroke
				(width 0.1)
				(type default)
			)
			(layer "B.Fab")
		)
		(fp_line
			(start -0.12065 -0.2794)
			(end -0.12065 -0.3048)
			(stroke
				(width 0.1)
				(type default)
			)
			(layer "B.Fab")
		)
		(fp_line
			(start -0.12065 -0.3048)
			(end -0.67945 -0.3048)
			(stroke
				(width 0.1)
				(type default)
			)
			(layer "B.Fab")
		)
		(fp_line
			(start -0.67945 0.3048)
			(end -0.120396 0.3048)
			(stroke
				(width 0.1)
				(type default)
			)
			(layer "B.Fab")
		)
		(fp_line
			(start -0.67945 -0.3048)
			(end -0.67945 0.3048)
			(stroke
				(width 0.1)
				(type default)
			)
			(layer "B.Fab")
		)
		(pad "1" smd circle
			(at 0.40005 0)
			(size 0 0)
			(layers "B.Cu" "B.Mask" "B.Paste")
			(net "NIC4_AUX_PWR_EN_R")
		)
		(pad "2" smd circle
			(at -0.40005 0)
			(size 0 0)
			(layers "B.Cu" "B.Mask" "B.Paste")
			(net "NIC4_AUX_PWR_EN")
		)
	)
	(footprint ""
		(layer "B.Cu")
		(at 269.099792 -364.979204 -90)
		(property "Reference" "PC6001"
			(at 0 0 90)
			(layer "B.SilkS")
			(hide yes)
			(effects
				(font
					(size 1.27 1.27)
				)
				(justify mirror)
			)
		)
		(property "Value" ""
			(at 0 0 90)
			(layer "B.Fab")
			(effects
				(font
					(size 1.27 1.27)
				)
				(justify mirror)
			)
		)
		(duplicate_pad_numbers_are_jumpers no)
		(fp_line
			(start -0.7874 0.4064)
			(end 0.7874 0.4064)
			(stroke
				(width 0.1524)
				(type default)
			)
			(layer "B.SilkS")
		)
		(fp_line
			(start 0.7874 0.4064)
			(end 0.7874 -0.4064)
			(stroke
				(width 0.1524)
				(type default)
			)
			(layer "B.SilkS")
		)
		(fp_line
			(start -0.7874 -0.4064)
			(end -0.7874 0.4064)
			(stroke
				(width 0.1524)
				(type default)
			)
			(layer "B.SilkS")
		)
		(fp_line
			(start 0.7874 -0.4064)
			(end -0.7874 -0.4064)
			(stroke
				(width 0.1524)
				(type default)
			)
			(layer "B.SilkS")
		)
		(fp_line
			(start -0.67945 0.3048)
			(end -0.120396 0.3048)
			(stroke
				(width 0.1)
				(type default)
			)
			(layer "B.Fab")
		)
		(fp_line
			(start -0.120396 0.3048)
			(end -0.120396 0.2794)
			(stroke
				(width 0.1)
				(type default)
			)
			(layer "B.Fab")
		)
		(fp_line
			(start 0.12065 0.3048)
			(end 0.67945 0.3048)
			(stroke
				(width 0.1)
				(type default)
			)
			(layer "B.Fab")
		)
		(fp_line
			(start 0.67945 0.3048)
			(end 0.67945 -0.305054)
			(stroke
				(width 0.1)
				(type default)
			)
			(layer "B.Fab")
		)
		(fp_line
			(start -0.120396 0.2794)
			(end 0.12065 0.2794)
			(stroke
				(width 0.1)
				(type default)
			)
			(layer "B.Fab")
		)
		(fp_line
			(start 0.12065 0.2794)
			(end 0.12065 0.3048)
			(stroke
				(width 0.1)
				(type default)
			)
			(layer "B.Fab")
		)
		(fp_line
			(start -0.12065 -0.2794)
			(end -0.12065 -0.3048)
			(stroke
				(width 0.1)
				(type default)
			)
			(layer "B.Fab")
		)
		(fp_line
			(start 0.12065 -0.2794)
			(end -0.12065 -0.2794)
			(stroke
				(width 0.1)
				(type default)
			)
			(layer "B.Fab")
		)
		(fp_line
			(start -0.67945 -0.3048)
			(end -0.67945 0.3048)
			(stroke
				(width 0.1)
				(type default)
			)
			(layer "B.Fab")
		)
		(fp_line
			(start -0.12065 -0.3048)
			(end -0.67945 -0.3048)
			(stroke
				(width 0.1)
				(type default)
			)
			(layer "B.Fab")
		)
		(fp_line
			(start 0.12065 -0.305054)
			(end 0.12065 -0.2794)
			(stroke
				(width 0.1)
				(type default)
			)
			(layer "B.Fab")
		)
		(fp_line
			(start 0.67945 -0.305054)
			(end 0.12065 -0.305054)
			(stroke
				(width 0.1)
				(type default)
			)
			(layer "B.Fab")
		)
		(pad "1" smd circle
			(at 0.40005 0 90)
			(size 0 0)
			(layers "B.Cu" "B.Mask" "B.Paste")
			(net "P12V_AUX")
		)
		(pad "2" smd circle
			(at -0.40005 0 90)
			(size 0 0)
			(layers "B.Cu" "B.Mask" "B.Paste")
			(net "P12V_HSC_GATE2")
		)
	)
	(footprint ""
		(layer "B.Cu")
		(at 46.34992 -290.674806)
		(property "Reference" "C3006"
			(at 0 0 0)
			(layer "B.SilkS")
			(hide yes)
			(effects
				(font
					(size 1.27 1.27)
				)
				(justify mirror)
			)
		)
		(property "Value" ""
			(at 0 0 0)
			(layer "B.Fab")
			(effects
				(font
					(size 1.27 1.27)
				)
				(justify mirror)
			)
		)
		(duplicate_pad_numbers_are_jumpers no)
		(fp_line
			(start -0.299974 -0.150114)
			(end -0.299974 0.150114)
			(stroke
				(width 0.1)
				(type default)
			)
			(layer "B.Fab")
		)
		(fp_line
			(start -0.299974 0.150114)
			(end 0.299974 0.150114)
			(stroke
				(width 0.1)
				(type default)
			)
			(layer "B.Fab")
		)
		(fp_line
			(start 0.299974 -0.150114)
			(end -0.299974 -0.150114)
			(stroke
				(width 0.1)
				(type default)
			)
			(layer "B.Fab")
		)
		(fp_line
			(start 0.299974 0.150114)
			(end 0.299974 -0.150114)
			(stroke
				(width 0.1)
				(type default)
			)
			(layer "B.Fab")
		)
		(pad "1" smd rect
			(at 0.2667 0 180)
			(size 0.3048 0.381)
			(layers "B.Cu" "B.Mask" "B.Paste")
			(net "P1V8_PEX")
		)
		(pad "2" smd rect
			(at -0.2667 0 180)
			(size 0.3048 0.381)
			(layers "B.Cu" "B.Mask" "B.Paste")
			(net "GND")
		)
	)
	(footprint ""
		(layer "B.Cu")
		(at 361.912408 -324.163944 -90)
		(property "Reference" "C4385"
			(at 0 0 90)
			(layer "B.SilkS")
			(hide yes)
			(effects
				(font
					(size 1.27 1.27)
				)
				(justify mirror)
			)
		)
		(property "Value" ""
			(at 0 0 90)
			(layer "B.Fab")
			(effects
				(font
					(size 1.27 1.27)
				)
				(justify mirror)
			)
		)
		(duplicate_pad_numbers_are_jumpers no)
		(fp_line
			(start -1.2954 0.5842)
			(end 1.2954 0.5842)
			(stroke
				(width 0.1524)
				(type default)
			)
			(layer "B.SilkS")
		)
		(fp_line
			(start 1.2954 0.5842)
			(end 1.2954 -0.5842)
			(stroke
				(width 0.1524)
				(type default)
			)
			(layer "B.SilkS")
		)
		(fp_line
			(start -1.2954 -0.5842)
			(end -1.2954 0.5842)
			(stroke
				(width 0.1524)
				(type default)
			)
			(layer "B.SilkS")
		)
		(fp_line
			(start 1.2954 -0.5842)
			(end -1.2954 -0.5842)
			(stroke
				(width 0.1524)
				(type default)
			)
			(layer "B.SilkS")
		)
		(fp_line
			(start -0.8636 0.4572)
			(end 0.8636 0.4572)
			(stroke
				(width 0.1)
				(type default)
			)
			(layer "B.Fab")
		)
		(fp_line
			(start 0.8636 0.4572)
			(end 0.8636 0.4064)
			(stroke
				(width 0.1)
				(type default)
			)
			(layer "B.Fab")
		)
		(fp_line
			(start -1.1938 0.4064)
			(end -0.8636 0.4064)
			(stroke
				(width 0.1)
				(type default)
			)
			(layer "B.Fab")
		)
		(fp_line
			(start -0.8636 0.4064)
			(end -0.8636 0.4572)
			(stroke
				(width 0.1)
				(type default)
			)
			(layer "B.Fab")
		)
		(fp_line
			(start 0.8636 0.4064)
			(end 1.1938 0.4064)
			(stroke
				(width 0.1)
				(type default)
			)
			(layer "B.Fab")
		)
		(fp_line
			(start 1.1938 0.4064)
			(end 1.1938 -0.4064)
			(stroke
				(width 0.1)
				(type default)
			)
			(layer "B.Fab")
		)
		(fp_line
			(start -1.1938 -0.4064)
			(end -1.1938 0.4064)
			(stroke
				(width 0.1)
				(type default)
			)
			(layer "B.Fab")
		)
		(fp_line
			(start -0.8636 -0.4064)
			(end -1.1938 -0.4064)
			(stroke
				(width 0.1)
				(type default)
			)
			(layer "B.Fab")
		)
		(fp_line
			(start 0.8636 -0.4064)
			(end 0.8636 -0.4572)
			(stroke
				(width 0.1)
				(type default)
			)
			(layer "B.Fab")
		)
		(fp_line
			(start 1.1938 -0.4064)
			(end 0.8636 -0.4064)
			(stroke
				(width 0.1)
				(type default)
			)
			(layer "B.Fab")
		)
		(fp_line
			(start -0.8636 -0.4572)
			(end -0.8636 -0.4064)
			(stroke
				(width 0.1)
				(type default)
			)
			(layer "B.Fab")
		)
		(fp_line
			(start 0.8636 -0.4572)
			(end -0.8636 -0.4572)
			(stroke
				(width 0.1)
				(type default)
			)
			(layer "B.Fab")
		)
		(pad "1" smd rect
			(at 0.7366 0 180)
			(size 0.7112 0.8128)
			(layers "B.Cu" "B.Mask" "B.Paste")
			(net "P0V8_SERDES_VDDA_PEX3_C11")
		)
		(pad "2" smd rect
			(at -0.7366 0 180)
			(size 0.7112 0.8128)
			(layers "B.Cu" "B.Mask" "B.Paste")
			(net "GND")
		)
	)
	(footprint ""
		(layer "B.Cu")
		(at 399.400014 -299.699934 -90)
		(property "Reference" "C1944"
			(at 0 0 90)
			(layer "B.SilkS")
			(hide yes)
			(effects
				(font
					(size 1.27 1.27)
				)
				(justify mirror)
			)
		)
		(property "Value" ""
			(at 0 0 90)
			(layer "B.Fab")
			(effects
				(font
					(size 1.27 1.27)
				)
				(justify mirror)
			)
		)
		(duplicate_pad_numbers_are_jumpers no)
		(fp_line
			(start -0.299974 0.150114)
			(end 0.299974 0.150114)
			(stroke
				(width 0.1)
				(type default)
			)
			(layer "B.Fab")
		)
		(fp_line
			(start 0.299974 0.150114)
			(end 0.299974 -0.150114)
			(stroke
				(width 0.1)
				(type default)
			)
			(layer "B.Fab")
		)
		(fp_line
			(start -0.299974 -0.150114)
			(end -0.299974 0.150114)
			(stroke
				(width 0.1)
				(type default)
			)
			(layer "B.Fab")
		)
		(fp_line
			(start 0.299974 -0.150114)
			(end -0.299974 -0.150114)
			(stroke
				(width 0.1)
				(type default)
			)
			(layer "B.Fab")
		)
		(pad "1" smd rect
			(at 0.2667 0 90)
			(size 0.3048 0.381)
			(layers "B.Cu" "B.Mask" "B.Paste")
			(net "P0V8_SERDES_VDDA_PEX3")
		)
		(pad "2" smd rect
			(at -0.2667 0 90)
			(size 0.3048 0.381)
			(layers "B.Cu" "B.Mask" "B.Paste")
			(net "GND")
		)
	)
	(footprint ""
		(layer "B.Cu")
		(at 281.874722 -297.79976 90)
		(property "Reference" "C1642"
			(at 0 0 90)
			(layer "B.SilkS")
			(hide yes)
			(effects
				(font
					(size 1.27 1.27)
				)
				(justify mirror)
			)
		)
		(property "Value" ""
			(at 0 0 90)
			(layer "B.Fab")
			(effects
				(font
					(size 1.27 1.27)
				)
				(justify mirror)
			)
		)
		(duplicate_pad_numbers_are_jumpers no)
		(fp_line
			(start 0.299974 -0.150114)
			(end -0.299974 -0.150114)
			(stroke
				(width 0.1)
				(type default)
			)
			(layer "B.Fab")
		)
		(fp_line
			(start -0.299974 -0.150114)
			(end -0.299974 0.150114)
			(stroke
				(width 0.1)
				(type default)
			)
			(layer "B.Fab")
		)
		(fp_line
			(start 0.299974 0.150114)
			(end 0.299974 -0.150114)
			(stroke
				(width 0.1)
				(type default)
			)
			(layer "B.Fab")
		)
		(fp_line
			(start -0.299974 0.150114)
			(end 0.299974 0.150114)
			(stroke
				(width 0.1)
				(type default)
			)
			(layer "B.Fab")
		)
		(pad "1" smd rect
			(at 0.2667 0 270)
			(size 0.3048 0.381)
			(layers "B.Cu" "B.Mask" "B.Paste")
			(net "P0V8_PEX2")
		)
		(pad "2" smd rect
			(at -0.2667 0 270)
			(size 0.3048 0.381)
			(layers "B.Cu" "B.Mask" "B.Paste")
			(net "GND")
		)
	)
	(footprint ""
		(layer "B.Cu")
		(at 116.788184 -317.6778 180)
		(property "Reference" "C4208"
			(at 0 0 0)
			(layer "B.SilkS")
			(hide yes)
			(effects
				(font
					(size 1.27 1.27)
				)
				(justify mirror)
			)
		)
		(property "Value" ""
			(at 0 0 0)
			(layer "B.Fab")
			(effects
				(font
					(size 1.27 1.27)
				)
				(justify mirror)
			)
		)
		(duplicate_pad_numbers_are_jumpers no)
		(fp_line
			(start 0.299974 0.150114)
			(end 0.299974 -0.150114)
			(stroke
				(width 0.1)
				(type default)
			)
			(layer "B.Fab")
		)
		(fp_line
			(start 0.299974 -0.150114)
			(end -0.299974 -0.150114)
			(stroke
				(width 0.1)
				(type default)
			)
			(layer "B.Fab")
		)
		(fp_line
			(start -0.299974 0.150114)
			(end 0.299974 0.150114)
			(stroke
				(width 0.1)
				(type default)
			)
			(layer "B.Fab")
		)
		(fp_line
			(start -0.299974 -0.150114)
			(end -0.299974 0.150114)
			(stroke
				(width 0.1)
				(type default)
			)
			(layer "B.Fab")
		)
		(pad "1" smd rect
			(at 0.2667 0)
			(size 0.3048 0.381)
			(layers "B.Cu" "B.Mask" "B.Paste")
			(net "P0V8_SERDES_VDDA_PEX0")
		)
		(pad "2" smd rect
			(at -0.2667 0)
			(size 0.3048 0.381)
			(layers "B.Cu" "B.Mask" "B.Paste")
			(net "GND")
		)
	)
	(footprint ""
		(layer "B.Cu")
		(at 368.018314 -227.084382 90)
		(property "Reference" "U68"
			(at 4.533392 0.149098 0)
			(unlocked yes)
			(layer "B.SilkS")
			(effects
				(font
					(size 0.7874 0.5842)
					(thickness 0.1524)
				)
				(justify mirror)
			)
		)
		(property "Value" ""
			(at 0 0 90)
			(layer "B.Fab")
			(effects
				(font
					(size 1.27 1.27)
				)
				(justify mirror)
			)
		)
		(duplicate_pad_numbers_are_jumpers no)
		(fp_line
			(start 1.8288 -2.4892)
			(end 0.5588 -2.4892)
			(stroke
				(width 0.1524)
				(type default)
			)
			(layer "B.SilkS")
		)
		(fp_line
			(start 0.5588 -2.4892)
			(end 0 -1.9304)
			(stroke
				(width 0.1524)
				(type default)
			)
			(layer "B.SilkS")
		)
		(fp_line
			(start -0.5588 -2.4892)
			(end -1.8288 -2.4892)
			(stroke
				(width 0.1524)
				(type default)
			)
			(layer "B.SilkS")
		)
		(fp_line
			(start -1.8288 -2.4892)
			(end -1.8161 2.4892)
			(stroke
				(width 0.1524)
				(type default)
			)
			(layer "B.SilkS")
		)
		(fp_line
			(start 0 -1.9304)
			(end -0.5588 -2.4892)
			(stroke
				(width 0.1524)
				(type default)
			)
			(layer "B.SilkS")
		)
		(fp_line
			(start 1.8288 2.4892)
			(end 1.8288 -2.4892)
			(stroke
				(width 0.1524)
				(type default)
			)
			(layer "B.SilkS")
		)
		(fp_line
			(start -1.8161 2.4892)
			(end 1.8288 2.4892)
			(stroke
				(width 0.1524)
				(type default)
			)
			(layer "B.SilkS")
		)
		(fp_poly
			(pts
				(xy 4.23672 -1.989328) (xy 4.23672 -2.614168) (xy 3.683 -2.286)
			)
			(stroke
				(width 0)
				(type default)
			)
			(fill yes)
			(layer "B.SilkS")
		)
		(fp_line
			(start 1.9939 -2.4892)
			(end -1.9939 -2.4892)
			(stroke
				(width 0.1)
				(type default)
			)
			(layer "B.Fab")
		)
		(fp_line
			(start -1.9939 -2.4892)
			(end -1.9939 -2.3876)
			(stroke
				(width 0.1)
				(type default)
			)
			(layer "B.Fab")
		)
		(fp_line
			(start 3.0988 -2.3876)
			(end 1.9939 -2.3876)
			(stroke
				(width 0.1)
				(type default)
			)
			(layer "B.Fab")
		)
		(fp_line
			(start 1.9939 -2.3876)
			(end 1.9939 -2.4892)
			(stroke
				(width 0.1)
				(type default)
			)
			(layer "B.Fab")
		)
		(fp_line
			(start 1.9939 -2.3876)
			(end 1.9812 -2.3876)
			(stroke
				(width 0.1)
				(type default)
			)
			(layer "B.Fab")
		)
		(fp_line
			(start -1.9939 -2.3876)
			(end -3.0988 -2.3876)
			(stroke
				(width 0.1)
				(type default)
			)
			(layer "B.Fab")
		)
		(fp_line
			(start -1.9939 -2.3876)
			(end -1.9939 2.3876)
			(stroke
				(width 0.1)
				(type default)
			)
			(layer "B.Fab")
		)
		(fp_line
			(start -3.0988 -2.3876)
			(end -3.0988 2.3876)
			(stroke
				(width 0.1)
				(type default)
			)
			(layer "B.Fab")
		)
		(fp_line
			(start -3.0988 -2.3876)
			(end -3.0988 2.3876)
			(stroke
				(width 0.1)
				(type default)
			)
			(layer "B.Fab")
		)
		(fp_line
			(start 3.0988 2.3876)
			(end 3.0988 -2.3876)
			(stroke
				(width 0.1)
				(type default)
			)
			(layer "B.Fab")
		)
		(fp_line
			(start 3.0988 2.3876)
			(end 3.0988 -2.3876)
			(stroke
				(width 0.1)
				(type default)
			)
			(layer "B.Fab")
		)
		(fp_line
			(start 1.9939 2.3876)
			(end 1.9939 -2.3876)
			(stroke
				(width 0.1)
				(type default)
			)
			(layer "B.Fab")
		)
		(fp_line
			(start 1.9939 2.3876)
			(end 3.0988 2.3876)
			(stroke
				(width 0.1)
				(type default)
			)
			(layer "B.Fab")
		)
		(fp_line
			(start -1.9939 2.3876)
			(end -1.9939 2.4892)
			(stroke
				(width 0.1)
				(type default)
			)
			(layer "B.Fab")
		)
		(fp_line
			(start -3.0988 2.3876)
			(end -1.9939 2.3876)
			(stroke
				(width 0.1)
				(type default)
			)
			(layer "B.Fab")
		)
		(fp_line
			(start 1.9939 2.4892)
			(end 1.9939 2.3876)
			(stroke
				(width 0.1)
				(type default)
			)
			(layer "B.Fab")
		)
		(fp_line
			(start -1.9939 2.4892)
			(end 1.9939 2.4892)
			(stroke
				(width 0.1)
				(type default)
			)
			(layer "B.Fab")
		)
		(fp_line
			(start -1.9939 2.4892)
			(end -2.0066 2.4892)
			(stroke
				(width 0.1)
				(type default)
			)
			(layer "B.Fab")
		)
		(fp_line
			(start -1.9939 2.5019)
			(end -1.9939 2.4892)
			(stroke
				(width 0.1)
				(type default)
			)
			(layer "B.Fab")
		)
		(fp_poly
			(pts
				(xy 4.23672 -1.989328) (xy 4.23672 -2.614168) (xy 3.683 -2.286)
			)
			(stroke
				(width 0)
				(type default)
			)
			(fill yes)
			(layer "B.Fab")
		)
		(pad "1" smd rect
			(at 2.7432 -2.2225)
			(size 0.3556 1.5494)
			(layers "B.Cu" "B.Mask" "B.Paste")
			(net "SEL_FLASH_PEX3_BUF_R")
		)
		(pad "2" smd rect
			(at 2.7432 -1.5875)
			(size 0.3556 1.5494)
			(layers "B.Cu" "B.Mask" "B.Paste")
			(net "SPI_PEX3_CS_R_N")
		)
		(pad "3" smd rect
			(at 2.7432 -0.9525)
			(size 0.3556 1.5494)
			(layers "B.Cu" "B.Mask" "B.Paste")
			(net "SPI_BIC1_CS0_LS23_R2_N")
		)
		(pad "4" smd rect
			(at 2.7432 -0.3175)
			(size 0.3556 1.5494)
			(layers "B.Cu" "B.Mask" "B.Paste")
			(net "SPI_PEX3_CS_MUX_N")
		)
		(pad "5" smd rect
			(at 2.7432 0.3175)
			(size 0.3556 1.5494)
			(layers "B.Cu" "B.Mask" "B.Paste")
			(net "SPI_PEX3_CLK_R")
		)
		(pad "6" smd rect
			(at 2.7432 0.9525)
			(size 0.3556 1.5494)
			(layers "B.Cu" "B.Mask" "B.Paste")
			(net "SPI_BIC1_CLK_LS23_R2")
		)
		(pad "7" smd rect
			(at 2.7432 1.5875)
			(size 0.3556 1.5494)
			(layers "B.Cu" "B.Mask" "B.Paste")
			(net "SPI_PEX3_CLK_MUX")
		)
		(pad "8" smd rect
			(at 2.7432 2.2225)
			(size 0.3556 1.5494)
			(layers "B.Cu" "B.Mask" "B.Paste")
			(net "GND")
		)
		(pad "9" smd rect
			(at -2.7432 2.2225)
			(size 0.3556 1.5494)
			(layers "B.Cu" "B.Mask" "B.Paste")
			(net "SPI_PEX3_SDIO0_MUX")
		)
		(pad "10" smd rect
			(at -2.7432 1.5875)
			(size 0.3556 1.5494)
			(layers "B.Cu" "B.Mask" "B.Paste")
			(net "SPI_BIC1_MOSI_LS23_R2")
		)
		(pad "11" smd rect
			(at -2.7432 0.9525)
			(size 0.3556 1.5494)
			(layers "B.Cu" "B.Mask" "B.Paste")
			(net "SPI_PEX3_SDIO0_R")
		)
		(pad "12" smd rect
			(at -2.7432 0.3175)
			(size 0.3556 1.5494)
			(layers "B.Cu" "B.Mask" "B.Paste")
			(net "SPI_PEX3_SDIO1_MUX")
		)
		(pad "13" smd rect
			(at -2.7432 -0.3175)
			(size 0.3556 1.5494)
			(layers "B.Cu" "B.Mask" "B.Paste")
			(net "SPI_BIC1_MISO_LS23_R2")
		)
		(pad "14" smd rect
			(at -2.7432 -0.9525)
			(size 0.3556 1.5494)
			(layers "B.Cu" "B.Mask" "B.Paste")
			(net "SPI_PEX3_SDIO1_R")
		)
		(pad "15" smd rect
			(at -2.7432 -1.5875)
			(size 0.3556 1.5494)
			(layers "B.Cu" "B.Mask" "B.Paste")
			(net "SPI_MUX_PEX3_EN_N")
		)
		(pad "16" smd rect
			(at -2.7432 -2.2225)
			(size 0.3556 1.5494)
			(layers "B.Cu" "B.Mask" "B.Paste")
			(net "P3V3_AUX")
		)
	)
	(footprint ""
		(layer "B.Cu")
		(at 414.599882 -299.699934 -90)
		(property "Reference" "C1949"
			(at 0 0 90)
			(layer "B.SilkS")
			(hide yes)
			(effects
				(font
					(size 1.27 1.27)
				)
				(justify mirror)
			)
		)
		(property "Value" ""
			(at 0 0 90)
			(layer "B.Fab")
			(effects
				(font
					(size 1.27 1.27)
				)
				(justify mirror)
			)
		)
		(duplicate_pad_numbers_are_jumpers no)
		(fp_line
			(start -0.299974 0.150114)
			(end 0.299974 0.150114)
			(stroke
				(width 0.1)
				(type default)
			)
			(layer "B.Fab")
		)
		(fp_line
			(start 0.299974 0.150114)
			(end 0.299974 -0.150114)
			(stroke
				(width 0.1)
				(type default)
			)
			(layer "B.Fab")
		)
		(fp_line
			(start -0.299974 -0.150114)
			(end -0.299974 0.150114)
			(stroke
				(width 0.1)
				(type default)
			)
			(layer "B.Fab")
		)
		(fp_line
			(start 0.299974 -0.150114)
			(end -0.299974 -0.150114)
			(stroke
				(width 0.1)
				(type default)
			)
			(layer "B.Fab")
		)
		(pad "1" smd rect
			(at 0.2667 0 90)
			(size 0.3048 0.381)
			(layers "B.Cu" "B.Mask" "B.Paste")
			(net "P0V8_SERDES_VDDA_PEX3")
		)
		(pad "2" smd rect
			(at -0.2667 0 90)
			(size 0.3048 0.381)
			(layers "B.Cu" "B.Mask" "B.Paste")
			(net "GND")
		)
	)
	(footprint ""
		(layer "B.Cu")
		(at 280.020268 -302.028606)
		(property "Reference" "C3336"
			(at 0 0 0)
			(layer "B.SilkS")
			(hide yes)
			(effects
				(font
					(size 1.27 1.27)
				)
				(justify mirror)
			)
		)
		(property "Value" ""
			(at 0 0 0)
			(layer "B.Fab")
			(effects
				(font
					(size 1.27 1.27)
				)
				(justify mirror)
			)
		)
		(duplicate_pad_numbers_are_jumpers no)
		(fp_line
			(start -1.2954 -0.5842)
			(end -1.2954 0.5842)
			(stroke
				(width 0.1524)
				(type default)
			)
			(layer "B.SilkS")
		)
		(fp_line
			(start -1.2954 0.5842)
			(end 1.2954 0.5842)
			(stroke
				(width 0.1524)
				(type default)
			)
			(layer "B.SilkS")
		)
		(fp_line
			(start 1.2954 -0.5842)
			(end -1.2954 -0.5842)
			(stroke
				(width 0.1524)
				(type default)
			)
			(layer "B.SilkS")
		)
		(fp_line
			(start 1.2954 0.5842)
			(end 1.2954 -0.5842)
			(stroke
				(width 0.1524)
				(type default)
			)
			(layer "B.SilkS")
		)
		(fp_line
			(start -1.1938 -0.4064)
			(end -1.1938 0.4064)
			(stroke
				(width 0.1)
				(type default)
			)
			(layer "B.Fab")
		)
		(fp_line
			(start -1.1938 0.4064)
			(end -0.8636 0.4064)
			(stroke
				(width 0.1)
				(type default)
			)
			(layer "B.Fab")
		)
		(fp_line
			(start -0.8636 -0.4572)
			(end -0.8636 -0.4064)
			(stroke
				(width 0.1)
				(type default)
			)
			(layer "B.Fab")
		)
		(fp_line
			(start -0.8636 -0.4064)
			(end -1.1938 -0.4064)
			(stroke
				(width 0.1)
				(type default)
			)
			(layer "B.Fab")
		)
		(fp_line
			(start -0.8636 0.4064)
			(end -0.8636 0.4572)
			(stroke
				(width 0.1)
				(type default)
			)
			(layer "B.Fab")
		)
		(fp_line
			(start -0.8636 0.4572)
			(end 0.8636 0.4572)
			(stroke
				(width 0.1)
				(type default)
			)
			(layer "B.Fab")
		)
		(fp_line
			(start 0.8636 -0.4572)
			(end -0.8636 -0.4572)
			(stroke
				(width 0.1)
				(type default)
			)
			(layer "B.Fab")
		)
		(fp_line
			(start 0.8636 -0.4064)
			(end 0.8636 -0.4572)
			(stroke
				(width 0.1)
				(type default)
			)
			(layer "B.Fab")
		)
		(fp_line
			(start 0.8636 0.4064)
			(end 1.1938 0.4064)
			(stroke
				(width 0.1)
				(type default)
			)
			(layer "B.Fab")
		)
		(fp_line
			(start 0.8636 0.4572)
			(end 0.8636 0.4064)
			(stroke
				(width 0.1)
				(type default)
			)
			(layer "B.Fab")
		)
		(fp_line
			(start 1.1938 -0.4064)
			(end 0.8636 -0.4064)
			(stroke
				(width 0.1)
				(type default)
			)
			(layer "B.Fab")
		)
		(fp_line
			(start 1.1938 0.4064)
			(end 1.1938 -0.4064)
			(stroke
				(width 0.1)
				(type default)
			)
			(layer "B.Fab")
		)
		(pad "1" smd rect
			(at 0.7366 0 270)
			(size 0.7112 0.8128)
			(layers "B.Cu" "B.Mask" "B.Paste")
			(net "P1V8_VDDA_PEX2")
		)
		(pad "2" smd rect
			(at -0.7366 0 270)
			(size 0.7112 0.8128)
			(layers "B.Cu" "B.Mask" "B.Paste")
			(net "GND")
		)
	)
	(footprint ""
		(layer "B.Cu")
		(at 378.079 -245.872 180)
		(property "Reference" "R966"
			(at 0 0 0)
			(layer "B.SilkS")
			(hide yes)
			(effects
				(font
					(size 1.27 1.27)
				)
				(justify mirror)
			)
		)
		(property "Value" ""
			(at 0 0 0)
			(layer "B.Fab")
			(effects
				(font
					(size 1.27 1.27)
				)
				(justify mirror)
			)
		)
		(duplicate_pad_numbers_are_jumpers no)
		(fp_line
			(start 0.7874 0.4064)
			(end 0.7874 -0.4064)
			(stroke
				(width 0.1524)
				(type default)
			)
			(layer "B.SilkS")
		)
		(fp_line
			(start 0.7874 -0.4064)
			(end -0.7874 -0.4064)
			(stroke
				(width 0.1524)
				(type default)
			)
			(layer "B.SilkS")
		)
		(fp_line
			(start -0.7874 0.4064)
			(end 0.7874 0.4064)
			(stroke
				(width 0.1524)
				(type default)
			)
			(layer "B.SilkS")
		)
		(fp_line
			(start -0.7874 -0.4064)
			(end -0.7874 0.4064)
			(stroke
				(width 0.1524)
				(type default)
			)
			(layer "B.SilkS")
		)
		(fp_line
			(start 0.67945 0.3048)
			(end 0.67945 -0.305054)
			(stroke
				(width 0.1)
				(type default)
			)
			(layer "B.Fab")
		)
		(fp_line
			(start 0.67945 -0.305054)
			(end 0.12065 -0.305054)
			(stroke
				(width 0.1)
				(type default)
			)
			(layer "B.Fab")
		)
		(fp_line
			(start 0.12065 0.3048)
			(end 0.67945 0.3048)
			(stroke
				(width 0.1)
				(type default)
			)
			(layer "B.Fab")
		)
		(fp_line
			(start 0.12065 0.2794)
			(end 0.12065 0.3048)
			(stroke
				(width 0.1)
				(type default)
			)
			(layer "B.Fab")
		)
		(fp_line
			(start 0.12065 -0.2794)
			(end -0.12065 -0.2794)
			(stroke
				(width 0.1)
				(type default)
			)
			(layer "B.Fab")
		)
		(fp_line
			(start 0.12065 -0.305054)
			(end 0.12065 -0.2794)
			(stroke
				(width 0.1)
				(type default)
			)
			(layer "B.Fab")
		)
		(fp_line
			(start -0.120396 0.3048)
			(end -0.120396 0.2794)
			(stroke
				(width 0.1)
				(type default)
			)
			(layer "B.Fab")
		)
		(fp_line
			(start -0.120396 0.2794)
			(end 0.12065 0.2794)
			(stroke
				(width 0.1)
				(type default)
			)
			(layer "B.Fab")
		)
		(fp_line
			(start -0.12065 -0.2794)
			(end -0.12065 -0.3048)
			(stroke
				(width 0.1)
				(type default)
			)
			(layer "B.Fab")
		)
		(fp_line
			(start -0.12065 -0.3048)
			(end -0.67945 -0.3048)
			(stroke
				(width 0.1)
				(type default)
			)
			(layer "B.Fab")
		)
		(fp_line
			(start -0.67945 0.3048)
			(end -0.120396 0.3048)
			(stroke
				(width 0.1)
				(type default)
			)
			(layer "B.Fab")
		)
		(fp_line
			(start -0.67945 -0.3048)
			(end -0.67945 0.3048)
			(stroke
				(width 0.1)
				(type default)
			)
			(layer "B.Fab")
		)
		(pad "1" smd circle
			(at 0.40005 0)
			(size 0 0)
			(layers "B.Cu" "B.Mask" "B.Paste")
			(net "UART_PEX2_SDB_BUF_R_TX")
		)
		(pad "2" smd circle
			(at -0.40005 0)
			(size 0 0)
			(layers "B.Cu" "B.Mask" "B.Paste")
			(net "UART_PEX2_SDB_BUF_TX")
		)
	)
	(footprint ""
		(layer "B.Cu")
		(at 161.964116 -142.795752 180)
		(property "Reference" "C877"
			(at 0 0 0)
			(layer "B.SilkS")
			(hide yes)
			(effects
				(font
					(size 1.27 1.27)
				)
				(justify mirror)
			)
		)
		(property "Value" ""
			(at 0 0 0)
			(layer "B.Fab")
			(effects
				(font
					(size 1.27 1.27)
				)
				(justify mirror)
			)
		)
		(duplicate_pad_numbers_are_jumpers no)
		(fp_line
			(start 0.299974 0.150114)
			(end 0.299974 -0.150114)
			(stroke
				(width 0.1)
				(type default)
			)
			(layer "B.Fab")
		)
		(fp_line
			(start 0.299974 -0.150114)
			(end -0.299974 -0.150114)
			(stroke
				(width 0.1)
				(type default)
			)
			(layer "B.Fab")
		)
		(fp_line
			(start -0.299974 0.150114)
			(end 0.299974 0.150114)
			(stroke
				(width 0.1)
				(type default)
			)
			(layer "B.Fab")
		)
		(fp_line
			(start -0.299974 -0.150114)
			(end -0.299974 0.150114)
			(stroke
				(width 0.1)
				(type default)
			)
			(layer "B.Fab")
		)
		(pad "1" smd rect
			(at 0.2667 0)
			(size 0.3048 0.381)
			(layers "B.Cu" "B.Mask" "B.Paste")
			(net "P12V_NIC2")
		)
		(pad "2" smd rect
			(at -0.2667 0)
			(size 0.3048 0.381)
			(layers "B.Cu" "B.Mask" "B.Paste")
			(net "GND")
		)
	)
	(footprint ""
		(layer "B.Cu")
		(at 65.349882 -288.299906 90)
		(property "Reference" "C2936"
			(at 0 0 90)
			(layer "B.SilkS")
			(hide yes)
			(effects
				(font
					(size 1.27 1.27)
				)
				(justify mirror)
			)
		)
		(property "Value" ""
			(at 0 0 90)
			(layer "B.Fab")
			(effects
				(font
					(size 1.27 1.27)
				)
				(justify mirror)
			)
		)
		(duplicate_pad_numbers_are_jumpers no)
		(fp_line
			(start 0.299974 -0.150114)
			(end -0.299974 -0.150114)
			(stroke
				(width 0.1)
				(type default)
			)
			(layer "B.Fab")
		)
		(fp_line
			(start -0.299974 -0.150114)
			(end -0.299974 0.150114)
			(stroke
				(width 0.1)
				(type default)
			)
			(layer "B.Fab")
		)
		(fp_line
			(start 0.299974 0.150114)
			(end 0.299974 -0.150114)
			(stroke
				(width 0.1)
				(type default)
			)
			(layer "B.Fab")
		)
		(fp_line
			(start -0.299974 0.150114)
			(end 0.299974 0.150114)
			(stroke
				(width 0.1)
				(type default)
			)
			(layer "B.Fab")
		)
		(pad "1" smd rect
			(at 0.2667 0 270)
			(size 0.3048 0.381)
			(layers "B.Cu" "B.Mask" "B.Paste")
			(net "P1V25_PEX0")
		)
		(pad "2" smd rect
			(at -0.2667 0 270)
			(size 0.3048 0.381)
			(layers "B.Cu" "B.Mask" "B.Paste")
			(net "GND")
		)
	)
	(footprint ""
		(layer "B.Cu")
		(at 213.832694 -217.270838 180)
		(property "Reference" "R4862"
			(at 0 0 0)
			(layer "B.SilkS")
			(hide yes)
			(effects
				(font
					(size 1.27 1.27)
				)
				(justify mirror)
			)
		)
		(property "Value" ""
			(at 0 0 0)
			(layer "B.Fab")
			(effects
				(font
					(size 1.27 1.27)
				)
				(justify mirror)
			)
		)
		(duplicate_pad_numbers_are_jumpers no)
		(fp_line
			(start 0.7874 0.4064)
			(end 0.7874 -0.4064)
			(stroke
				(width 0.1524)
				(type default)
			)
			(layer "B.SilkS")
		)
		(fp_line
			(start 0.7874 -0.4064)
			(end -0.7874 -0.4064)
			(stroke
				(width 0.1524)
				(type default)
			)
			(layer "B.SilkS")
		)
		(fp_line
			(start -0.7874 0.4064)
			(end 0.7874 0.4064)
			(stroke
				(width 0.1524)
				(type default)
			)
			(layer "B.SilkS")
		)
		(fp_line
			(start -0.7874 -0.4064)
			(end -0.7874 0.4064)
			(stroke
				(width 0.1524)
				(type default)
			)
			(layer "B.SilkS")
		)
		(fp_line
			(start 0.67945 0.3048)
			(end 0.67945 -0.305054)
			(stroke
				(width 0.1)
				(type default)
			)
			(layer "B.Fab")
		)
		(fp_line
			(start 0.67945 -0.305054)
			(end 0.12065 -0.305054)
			(stroke
				(width 0.1)
				(type default)
			)
			(layer "B.Fab")
		)
		(fp_line
			(start 0.12065 0.3048)
			(end 0.67945 0.3048)
			(stroke
				(width 0.1)
				(type default)
			)
			(layer "B.Fab")
		)
		(fp_line
			(start 0.12065 0.2794)
			(end 0.12065 0.3048)
			(stroke
				(width 0.1)
				(type default)
			)
			(layer "B.Fab")
		)
		(fp_line
			(start 0.12065 -0.2794)
			(end -0.12065 -0.2794)
			(stroke
				(width 0.1)
				(type default)
			)
			(layer "B.Fab")
		)
		(fp_line
			(start 0.12065 -0.305054)
			(end 0.12065 -0.2794)
			(stroke
				(width 0.1)
				(type default)
			)
			(layer "B.Fab")
		)
		(fp_line
			(start -0.120396 0.3048)
			(end -0.120396 0.2794)
			(stroke
				(width 0.1)
				(type default)
			)
			(layer "B.Fab")
		)
		(fp_line
			(start -0.120396 0.2794)
			(end 0.12065 0.2794)
			(stroke
				(width 0.1)
				(type default)
			)
			(layer "B.Fab")
		)
		(fp_line
			(start -0.12065 -0.2794)
			(end -0.12065 -0.3048)
			(stroke
				(width 0.1)
				(type default)
			)
			(layer "B.Fab")
		)
		(fp_line
			(start -0.12065 -0.3048)
			(end -0.67945 -0.3048)
			(stroke
				(width 0.1)
				(type default)
			)
			(layer "B.Fab")
		)
		(fp_line
			(start -0.67945 0.3048)
			(end -0.120396 0.3048)
			(stroke
				(width 0.1)
				(type default)
			)
			(layer "B.Fab")
		)
		(fp_line
			(start -0.67945 -0.3048)
			(end -0.67945 0.3048)
			(stroke
				(width 0.1)
				(type default)
			)
			(layer "B.Fab")
		)
		(pad "1" smd circle
			(at 0.40005 0)
			(size 0 0)
			(layers "B.Cu" "B.Mask" "B.Paste")
			(net "P1V2_AUX")
		)
		(pad "2" smd circle
			(at -0.40005 0)
			(size 0 0)
			(layers "B.Cu" "B.Mask" "B.Paste")
			(net "PECI_VDD")
		)
	)
	(footprint ""
		(layer "B.Cu")
		(at 257.322574 -220.924374 90)
		(property "Reference" "R3486"
			(at 0 0 90)
			(layer "B.SilkS")
			(hide yes)
			(effects
				(font
					(size 1.27 1.27)
				)
				(justify mirror)
			)
		)
		(property "Value" ""
			(at 0 0 90)
			(layer "B.Fab")
			(effects
				(font
					(size 1.27 1.27)
				)
				(justify mirror)
			)
		)
		(duplicate_pad_numbers_are_jumpers no)
		(fp_line
			(start 0.7874 -0.4064)
			(end -0.7874 -0.4064)
			(stroke
				(width 0.1524)
				(type default)
			)
			(layer "B.SilkS")
		)
		(fp_line
			(start -0.7874 -0.4064)
			(end -0.7874 0.4064)
			(stroke
				(width 0.1524)
				(type default)
			)
			(layer "B.SilkS")
		)
		(fp_line
			(start 0.7874 0.4064)
			(end 0.7874 -0.4064)
			(stroke
				(width 0.1524)
				(type default)
			)
			(layer "B.SilkS")
		)
		(fp_line
			(start -0.7874 0.4064)
			(end 0.7874 0.4064)
			(stroke
				(width 0.1524)
				(type default)
			)
			(layer "B.SilkS")
		)
		(fp_line
			(start 0.67945 -0.305054)
			(end 0.12065 -0.305054)
			(stroke
				(width 0.1)
				(type default)
			)
			(layer "B.Fab")
		)
		(fp_line
			(start 0.12065 -0.305054)
			(end 0.12065 -0.2794)
			(stroke
				(width 0.1)
				(type default)
			)
			(layer "B.Fab")
		)
		(fp_line
			(start -0.12065 -0.3048)
			(end -0.67945 -0.3048)
			(stroke
				(width 0.1)
				(type default)
			)
			(layer "B.Fab")
		)
		(fp_line
			(start -0.67945 -0.3048)
			(end -0.67945 0.3048)
			(stroke
				(width 0.1)
				(type default)
			)
			(layer "B.Fab")
		)
		(fp_line
			(start 0.12065 -0.2794)
			(end -0.12065 -0.2794)
			(stroke
				(width 0.1)
				(type default)
			)
			(layer "B.Fab")
		)
		(fp_line
			(start -0.12065 -0.2794)
			(end -0.12065 -0.3048)
			(stroke
				(width 0.1)
				(type default)
			)
			(layer "B.Fab")
		)
		(fp_line
			(start 0.12065 0.2794)
			(end 0.12065 0.3048)
			(stroke
				(width 0.1)
				(type default)
			)
			(layer "B.Fab")
		)
		(fp_line
			(start -0.120396 0.2794)
			(end 0.12065 0.2794)
			(stroke
				(width 0.1)
				(type default)
			)
			(layer "B.Fab")
		)
		(fp_line
			(start 0.67945 0.3048)
			(end 0.67945 -0.305054)
			(stroke
				(width 0.1)
				(type default)
			)
			(layer "B.Fab")
		)
		(fp_line
			(start 0.12065 0.3048)
			(end 0.67945 0.3048)
			(stroke
				(width 0.1)
				(type default)
			)
			(layer "B.Fab")
		)
		(fp_line
			(start -0.120396 0.3048)
			(end -0.120396 0.2794)
			(stroke
				(width 0.1)
				(type default)
			)
			(layer "B.Fab")
		)
		(fp_line
			(start -0.67945 0.3048)
			(end -0.120396 0.3048)
			(stroke
				(width 0.1)
				(type default)
			)
			(layer "B.Fab")
		)
		(pad "1" smd circle
			(at 0.40005 0 270)
			(size 0 0)
			(layers "B.Cu" "B.Mask" "B.Paste")
			(net "P1V8_PEX")
		)
		(pad "2" smd circle
			(at -0.40005 0 270)
			(size 0 0)
			(layers "B.Cu" "B.Mask" "B.Paste")
			(net "SPI_PEX2_SDIO3_R1")
		)
	)
	(footprint ""
		(layer "B.Cu")
		(at 185.349134 -115.613434 -90)
		(property "Reference" "U23"
			(at 0.268986 4.072382 0)
			(unlocked yes)
			(layer "B.SilkS")
			(effects
				(font
					(size 0.7874 0.5842)
					(thickness 0.1524)
				)
				(justify mirror)
			)
		)
		(property "Value" ""
			(at 0 0 90)
			(layer "B.Fab")
			(effects
				(font
					(size 1.27 1.27)
				)
				(justify mirror)
			)
		)
		(duplicate_pad_numbers_are_jumpers no)
		(fp_line
			(start -1.3462 1.1938)
			(end -1.3462 -1.1938)
			(stroke
				(width 0.1524)
				(type default)
			)
			(layer "B.SilkS")
		)
		(fp_line
			(start 1.3462 1.1938)
			(end -1.3462 1.1938)
			(stroke
				(width 0.1524)
				(type default)
			)
			(layer "B.SilkS")
		)
		(fp_line
			(start -1.3462 -1.1938)
			(end 1.3462 -1.1938)
			(stroke
				(width 0.1524)
				(type default)
			)
			(layer "B.SilkS")
		)
		(fp_line
			(start 1.3462 -1.1938)
			(end 1.3462 1.1684)
			(stroke
				(width 0.1524)
				(type default)
			)
			(layer "B.SilkS")
		)
		(fp_poly
			(pts
				(xy 1.447038 -0.760476) (xy 2.052066 -0.457962) (xy 2.052066 -1.06299)
			)
			(stroke
				(width 0)
				(type default)
			)
			(fill yes)
			(layer "B.SilkS")
		)
		(fp_line
			(start -0.674878 1.124966)
			(end -0.674878 -1.124966)
			(stroke
				(width 0.1)
				(type default)
			)
			(layer "B.Fab")
		)
		(fp_line
			(start 0.674878 1.124966)
			(end -0.674878 1.124966)
			(stroke
				(width 0.1)
				(type default)
			)
			(layer "B.Fab")
		)
		(fp_line
			(start -0.674878 -1.124966)
			(end 0.674878 -1.124966)
			(stroke
				(width 0.1)
				(type default)
			)
			(layer "B.Fab")
		)
		(fp_line
			(start 0.674878 -1.124966)
			(end 0.674878 1.124966)
			(stroke
				(width 0.1)
				(type default)
			)
			(layer "B.Fab")
		)
		(fp_poly
			(pts
				(xy 1.447038 -0.760476) (xy 2.052066 -0.457962) (xy 2.052066 -1.06299)
			)
			(stroke
				(width 0)
				(type default)
			)
			(fill yes)
			(layer "B.Fab")
		)
		(pad "1" smd rect
			(at 0.899922 -0.750062 90)
			(size 0.6096 0.6096)
			(layers "B.Cu" "B.Mask" "B.Paste")
			(net "NIC3_AUX_PWR_EN_R")
		)
		(pad "2" smd rect
			(at 0.899922 0)
			(size 0.4064 0.6096)
			(layers "B.Cu" "B.Mask" "B.Paste")
			(net "RST_SMB_NIC3_MUX_N")
		)
		(pad "3" smd rect
			(at 0.899922 0.750062 90)
			(size 0.6096 0.6096)
			(layers "B.Cu" "B.Mask" "B.Paste")
			(net "GND")
		)
		(pad "4" smd rect
			(at -0.899922 0.750062 90)
			(size 0.6096 0.6096)
			(layers "B.Cu" "B.Mask" "B.Paste")
			(net "RST_SMB_NIC3_MUX_ISO_N")
		)
		(pad "5" smd rect
			(at -0.899922 -0.750062 90)
			(size 0.6096 0.6096)
			(layers "B.Cu" "B.Mask" "B.Paste")
			(net "P3V3_AUX")
		)
	)
	(footprint ""
		(layer "B.Cu")
		(at 408.451304 -305.399948 -90)
		(property "Reference" "C3495"
			(at 0 0 90)
			(layer "B.SilkS")
			(hide yes)
			(effects
				(font
					(size 1.27 1.27)
				)
				(justify mirror)
			)
		)
		(property "Value" ""
			(at 0 0 90)
			(layer "B.Fab")
			(effects
				(font
					(size 1.27 1.27)
				)
				(justify mirror)
			)
		)
		(duplicate_pad_numbers_are_jumpers no)
		(fp_line
			(start -0.299974 0.150114)
			(end 0.299974 0.150114)
			(stroke
				(width 0.1)
				(type default)
			)
			(layer "B.Fab")
		)
		(fp_line
			(start 0.299974 0.150114)
			(end 0.299974 -0.150114)
			(stroke
				(width 0.1)
				(type default)
			)
			(layer "B.Fab")
		)
		(fp_line
			(start -0.299974 -0.150114)
			(end -0.299974 0.150114)
			(stroke
				(width 0.1)
				(type default)
			)
			(layer "B.Fab")
		)
		(fp_line
			(start 0.299974 -0.150114)
			(end -0.299974 -0.150114)
			(stroke
				(width 0.1)
				(type default)
			)
			(layer "B.Fab")
		)
		(pad "1" smd rect
			(at 0.2667 0 90)
			(size 0.3048 0.381)
			(layers "B.Cu" "B.Mask" "B.Paste")
			(net "P1V25_SERDES_VDDPLL_PEX3")
		)
		(pad "2" smd rect
			(at -0.2667 0 90)
			(size 0.3048 0.381)
			(layers "B.Cu" "B.Mask" "B.Paste")
			(net "GND")
		)
	)
	(footprint ""
		(layer "B.Cu")
		(at 365.34344 -308.613556 90)
		(property "Reference" "C4372"
			(at 0 0 90)
			(layer "B.SilkS")
			(hide yes)
			(effects
				(font
					(size 1.27 1.27)
				)
				(justify mirror)
			)
		)
		(property "Value" ""
			(at 0 0 90)
			(layer "B.Fab")
			(effects
				(font
					(size 1.27 1.27)
				)
				(justify mirror)
			)
		)
		(duplicate_pad_numbers_are_jumpers no)
		(fp_line
			(start 1.2954 -0.5842)
			(end -1.2954 -0.5842)
			(stroke
				(width 0.1524)
				(type default)
			)
			(layer "B.SilkS")
		)
		(fp_line
			(start -1.2954 -0.5842)
			(end -1.2954 0.5842)
			(stroke
				(width 0.1524)
				(type default)
			)
			(layer "B.SilkS")
		)
		(fp_line
			(start 1.2954 0.5842)
			(end 1.2954 -0.5842)
			(stroke
				(width 0.1524)
				(type default)
			)
			(layer "B.SilkS")
		)
		(fp_line
			(start -1.2954 0.5842)
			(end 1.2954 0.5842)
			(stroke
				(width 0.1524)
				(type default)
			)
			(layer "B.SilkS")
		)
		(fp_line
			(start 0.8636 -0.4572)
			(end -0.8636 -0.4572)
			(stroke
				(width 0.1)
				(type default)
			)
			(layer "B.Fab")
		)
		(fp_line
			(start -0.8636 -0.4572)
			(end -0.8636 -0.4064)
			(stroke
				(width 0.1)
				(type default)
			)
			(layer "B.Fab")
		)
		(fp_line
			(start 1.1938 -0.4064)
			(end 0.8636 -0.4064)
			(stroke
				(width 0.1)
				(type default)
			)
			(layer "B.Fab")
		)
		(fp_line
			(start 0.8636 -0.4064)
			(end 0.8636 -0.4572)
			(stroke
				(width 0.1)
				(type default)
			)
			(layer "B.Fab")
		)
		(fp_line
			(start -0.8636 -0.4064)
			(end -1.1938 -0.4064)
			(stroke
				(width 0.1)
				(type default)
			)
			(layer "B.Fab")
		)
		(fp_line
			(start -1.1938 -0.4064)
			(end -1.1938 0.4064)
			(stroke
				(width 0.1)
				(type default)
			)
			(layer "B.Fab")
		)
		(fp_line
			(start 1.1938 0.4064)
			(end 1.1938 -0.4064)
			(stroke
				(width 0.1)
				(type default)
			)
			(layer "B.Fab")
		)
		(fp_line
			(start 0.8636 0.4064)
			(end 1.1938 0.4064)
			(stroke
				(width 0.1)
				(type default)
			)
			(layer "B.Fab")
		)
		(fp_line
			(start -0.8636 0.4064)
			(end -0.8636 0.4572)
			(stroke
				(width 0.1)
				(type default)
			)
			(layer "B.Fab")
		)
		(fp_line
			(start -1.1938 0.4064)
			(end -0.8636 0.4064)
			(stroke
				(width 0.1)
				(type default)
			)
			(layer "B.Fab")
		)
		(fp_line
			(start 0.8636 0.4572)
			(end 0.8636 0.4064)
			(stroke
				(width 0.1)
				(type default)
			)
			(layer "B.Fab")
		)
		(fp_line
			(start -0.8636 0.4572)
			(end 0.8636 0.4572)
			(stroke
				(width 0.1)
				(type default)
			)
			(layer "B.Fab")
		)
		(pad "1" smd rect
			(at 0.7366 0)
			(size 0.7112 0.8128)
			(layers "B.Cu" "B.Mask" "B.Paste")
			(net "P0V8_PEX3")
		)
		(pad "2" smd rect
			(at -0.7366 0)
			(size 0.7112 0.8128)
			(layers "B.Cu" "B.Mask" "B.Paste")
			(net "GND")
		)
	)
	(footprint ""
		(layer "B.Cu")
		(at 170.524932 -293.99992 90)
		(property "Reference" "C1389"
			(at 0 0 90)
			(layer "B.SilkS")
			(hide yes)
			(effects
				(font
					(size 1.27 1.27)
				)
				(justify mirror)
			)
		)
		(property "Value" ""
			(at 0 0 90)
			(layer "B.Fab")
			(effects
				(font
					(size 1.27 1.27)
				)
				(justify mirror)
			)
		)
		(duplicate_pad_numbers_are_jumpers no)
		(fp_line
			(start 0.299974 -0.150114)
			(end -0.299974 -0.150114)
			(stroke
				(width 0.1)
				(type default)
			)
			(layer "B.Fab")
		)
		(fp_line
			(start -0.299974 -0.150114)
			(end -0.299974 0.150114)
			(stroke
				(width 0.1)
				(type default)
			)
			(layer "B.Fab")
		)
		(fp_line
			(start 0.299974 0.150114)
			(end 0.299974 -0.150114)
			(stroke
				(width 0.1)
				(type default)
			)
			(layer "B.Fab")
		)
		(fp_line
			(start -0.299974 0.150114)
			(end 0.299974 0.150114)
			(stroke
				(width 0.1)
				(type default)
			)
			(layer "B.Fab")
		)
		(pad "1" smd rect
			(at 0.2667 0 270)
			(size 0.3048 0.381)
			(layers "B.Cu" "B.Mask" "B.Paste")
			(net "P0V8_PEX1")
		)
		(pad "2" smd rect
			(at -0.2667 0 270)
			(size 0.3048 0.381)
			(layers "B.Cu" "B.Mask" "B.Paste")
			(net "GND")
		)
	)
	(footprint ""
		(layer "B.Cu")
		(at 106.35869 -326.152256 -90)
		(property "Reference" "R1225"
			(at 0 0 90)
			(layer "B.SilkS")
			(hide yes)
			(effects
				(font
					(size 1.27 1.27)
				)
				(justify mirror)
			)
		)
		(property "Value" ""
			(at 0 0 90)
			(layer "B.Fab")
			(effects
				(font
					(size 1.27 1.27)
				)
				(justify mirror)
			)
		)
		(duplicate_pad_numbers_are_jumpers no)
		(fp_line
			(start -0.7874 0.4064)
			(end 0.7874 0.4064)
			(stroke
				(width 0.1524)
				(type default)
			)
			(layer "B.SilkS")
		)
		(fp_line
			(start 0.7874 0.4064)
			(end 0.7874 -0.4064)
			(stroke
				(width 0.1524)
				(type default)
			)
			(layer "B.SilkS")
		)
		(fp_line
			(start -0.7874 -0.4064)
			(end -0.7874 0.4064)
			(stroke
				(width 0.1524)
				(type default)
			)
			(layer "B.SilkS")
		)
		(fp_line
			(start 0.7874 -0.4064)
			(end -0.7874 -0.4064)
			(stroke
				(width 0.1524)
				(type default)
			)
			(layer "B.SilkS")
		)
		(fp_line
			(start -0.67945 0.3048)
			(end -0.120396 0.3048)
			(stroke
				(width 0.1)
				(type default)
			)
			(layer "B.Fab")
		)
		(fp_line
			(start -0.120396 0.3048)
			(end -0.120396 0.2794)
			(stroke
				(width 0.1)
				(type default)
			)
			(layer "B.Fab")
		)
		(fp_line
			(start 0.12065 0.3048)
			(end 0.67945 0.3048)
			(stroke
				(width 0.1)
				(type default)
			)
			(layer "B.Fab")
		)
		(fp_line
			(start 0.67945 0.3048)
			(end 0.67945 -0.305054)
			(stroke
				(width 0.1)
				(type default)
			)
			(layer "B.Fab")
		)
		(fp_line
			(start -0.120396 0.2794)
			(end 0.12065 0.2794)
			(stroke
				(width 0.1)
				(type default)
			)
			(layer "B.Fab")
		)
		(fp_line
			(start 0.12065 0.2794)
			(end 0.12065 0.3048)
			(stroke
				(width 0.1)
				(type default)
			)
			(layer "B.Fab")
		)
		(fp_line
			(start -0.12065 -0.2794)
			(end -0.12065 -0.3048)
			(stroke
				(width 0.1)
				(type default)
			)
			(layer "B.Fab")
		)
		(fp_line
			(start 0.12065 -0.2794)
			(end -0.12065 -0.2794)
			(stroke
				(width 0.1)
				(type default)
			)
			(layer "B.Fab")
		)
		(fp_line
			(start -0.67945 -0.3048)
			(end -0.67945 0.3048)
			(stroke
				(width 0.1)
				(type default)
			)
			(layer "B.Fab")
		)
		(fp_line
			(start -0.12065 -0.3048)
			(end -0.67945 -0.3048)
			(stroke
				(width 0.1)
				(type default)
			)
			(layer "B.Fab")
		)
		(fp_line
			(start 0.12065 -0.305054)
			(end 0.12065 -0.2794)
			(stroke
				(width 0.1)
				(type default)
			)
			(layer "B.Fab")
		)
		(fp_line
			(start 0.67945 -0.305054)
			(end 0.12065 -0.305054)
			(stroke
				(width 0.1)
				(type default)
			)
			(layer "B.Fab")
		)
		(pad "1" smd circle
			(at 0.40005 0 90)
			(size 0 0)
			(layers "B.Cu" "B.Mask" "B.Paste")
			(net "CLK_100M_DB800ZL_PEX0_S0_R_DP")
		)
		(pad "2" smd circle
			(at -0.40005 0 90)
			(size 0 0)
			(layers "B.Cu" "B.Mask" "B.Paste")
			(net "CLK_100M_DB800ZL_PEX0_S0_DP")
		)
	)
	(footprint ""
		(layer "B.Cu")
		(at 177.42027 -196.890386 180)
		(property "Reference" "R1030"
			(at 0 0 0)
			(layer "B.SilkS")
			(hide yes)
			(effects
				(font
					(size 1.27 1.27)
				)
				(justify mirror)
			)
		)
		(property "Value" ""
			(at 0 0 0)
			(layer "B.Fab")
			(effects
				(font
					(size 1.27 1.27)
				)
				(justify mirror)
			)
		)
		(duplicate_pad_numbers_are_jumpers no)
		(fp_line
			(start 0.7874 0.4064)
			(end 0.7874 -0.4064)
			(stroke
				(width 0.1524)
				(type default)
			)
			(layer "B.SilkS")
		)
		(fp_line
			(start 0.7874 -0.4064)
			(end -0.7874 -0.4064)
			(stroke
				(width 0.1524)
				(type default)
			)
			(layer "B.SilkS")
		)
		(fp_line
			(start -0.7874 0.4064)
			(end 0.7874 0.4064)
			(stroke
				(width 0.1524)
				(type default)
			)
			(layer "B.SilkS")
		)
		(fp_line
			(start -0.7874 -0.4064)
			(end -0.7874 0.4064)
			(stroke
				(width 0.1524)
				(type default)
			)
			(layer "B.SilkS")
		)
		(fp_line
			(start 0.67945 0.3048)
			(end 0.67945 -0.305054)
			(stroke
				(width 0.1)
				(type default)
			)
			(layer "B.Fab")
		)
		(fp_line
			(start 0.67945 -0.305054)
			(end 0.12065 -0.305054)
			(stroke
				(width 0.1)
				(type default)
			)
			(layer "B.Fab")
		)
		(fp_line
			(start 0.12065 0.3048)
			(end 0.67945 0.3048)
			(stroke
				(width 0.1)
				(type default)
			)
			(layer "B.Fab")
		)
		(fp_line
			(start 0.12065 0.2794)
			(end 0.12065 0.3048)
			(stroke
				(width 0.1)
				(type default)
			)
			(layer "B.Fab")
		)
		(fp_line
			(start 0.12065 -0.2794)
			(end -0.12065 -0.2794)
			(stroke
				(width 0.1)
				(type default)
			)
			(layer "B.Fab")
		)
		(fp_line
			(start 0.12065 -0.305054)
			(end 0.12065 -0.2794)
			(stroke
				(width 0.1)
				(type default)
			)
			(layer "B.Fab")
		)
		(fp_line
			(start -0.120396 0.3048)
			(end -0.120396 0.2794)
			(stroke
				(width 0.1)
				(type default)
			)
			(layer "B.Fab")
		)
		(fp_line
			(start -0.120396 0.2794)
			(end 0.12065 0.2794)
			(stroke
				(width 0.1)
				(type default)
			)
			(layer "B.Fab")
		)
		(fp_line
			(start -0.12065 -0.2794)
			(end -0.12065 -0.3048)
			(stroke
				(width 0.1)
				(type default)
			)
			(layer "B.Fab")
		)
		(fp_line
			(start -0.12065 -0.3048)
			(end -0.67945 -0.3048)
			(stroke
				(width 0.1)
				(type default)
			)
			(layer "B.Fab")
		)
		(fp_line
			(start -0.67945 0.3048)
			(end -0.120396 0.3048)
			(stroke
				(width 0.1)
				(type default)
			)
			(layer "B.Fab")
		)
		(fp_line
			(start -0.67945 -0.3048)
			(end -0.67945 0.3048)
			(stroke
				(width 0.1)
				(type default)
			)
			(layer "B.Fab")
		)
		(pad "1" smd circle
			(at 0.40005 0)
			(size 0 0)
			(layers "B.Cu" "B.Mask" "B.Paste")
			(net "SPI_BIC1_CLK_LS01_DIR2")
		)
		(pad "2" smd circle
			(at -0.40005 0)
			(size 0 0)
			(layers "B.Cu" "B.Mask" "B.Paste")
			(net "P1V8_PEX")
		)
	)
	(footprint ""
		(layer "B.Cu")
		(at 165.299898 -299.2755 180)
		(property "Reference" "C1392"
			(at 0 0 0)
			(layer "B.SilkS")
			(hide yes)
			(effects
				(font
					(size 1.27 1.27)
				)
				(justify mirror)
			)
		)
		(property "Value" ""
			(at 0 0 0)
			(layer "B.Fab")
			(effects
				(font
					(size 1.27 1.27)
				)
				(justify mirror)
			)
		)
		(duplicate_pad_numbers_are_jumpers no)
		(fp_line
			(start 0.299974 0.150114)
			(end 0.299974 -0.150114)
			(stroke
				(width 0.1)
				(type default)
			)
			(layer "B.Fab")
		)
		(fp_line
			(start 0.299974 -0.150114)
			(end -0.299974 -0.150114)
			(stroke
				(width 0.1)
				(type default)
			)
			(layer "B.Fab")
		)
		(fp_line
			(start -0.299974 0.150114)
			(end 0.299974 0.150114)
			(stroke
				(width 0.1)
				(type default)
			)
			(layer "B.Fab")
		)
		(fp_line
			(start -0.299974 -0.150114)
			(end -0.299974 0.150114)
			(stroke
				(width 0.1)
				(type default)
			)
			(layer "B.Fab")
		)
		(pad "1" smd rect
			(at 0.2667 0)
			(size 0.3048 0.381)
			(layers "B.Cu" "B.Mask" "B.Paste")
			(net "P0V8_PEX1")
		)
		(pad "2" smd rect
			(at -0.2667 0)
			(size 0.3048 0.381)
			(layers "B.Cu" "B.Mask" "B.Paste")
			(net "GND")
		)
	)
	(footprint ""
		(layer "B.Cu")
		(at 400.349974 -290.199826 90)
		(property "Reference" "C1941"
			(at 0 0 90)
			(layer "B.SilkS")
			(hide yes)
			(effects
				(font
					(size 1.27 1.27)
				)
				(justify mirror)
			)
		)
		(property "Value" ""
			(at 0 0 90)
			(layer "B.Fab")
			(effects
				(font
					(size 1.27 1.27)
				)
				(justify mirror)
			)
		)
		(duplicate_pad_numbers_are_jumpers no)
		(fp_line
			(start 0.299974 -0.150114)
			(end -0.299974 -0.150114)
			(stroke
				(width 0.1)
				(type default)
			)
			(layer "B.Fab")
		)
		(fp_line
			(start -0.299974 -0.150114)
			(end -0.299974 0.150114)
			(stroke
				(width 0.1)
				(type default)
			)
			(layer "B.Fab")
		)
		(fp_line
			(start 0.299974 0.150114)
			(end 0.299974 -0.150114)
			(stroke
				(width 0.1)
				(type default)
			)
			(layer "B.Fab")
		)
		(fp_line
			(start -0.299974 0.150114)
			(end 0.299974 0.150114)
			(stroke
				(width 0.1)
				(type default)
			)
			(layer "B.Fab")
		)
		(pad "1" smd rect
			(at 0.2667 0 270)
			(size 0.3048 0.381)
			(layers "B.Cu" "B.Mask" "B.Paste")
			(net "P0V8_SERDES_VDDA_PEX3")
		)
		(pad "2" smd rect
			(at -0.2667 0 270)
			(size 0.3048 0.381)
			(layers "B.Cu" "B.Mask" "B.Paste")
			(net "GND")
		)
	)
	(footprint ""
		(layer "B.Cu")
		(at 179.55006 -288.299906 90)
		(property "Reference" "C3109"
			(at 0 0 90)
			(layer "B.SilkS")
			(hide yes)
			(effects
				(font
					(size 1.27 1.27)
				)
				(justify mirror)
			)
		)
		(property "Value" ""
			(at 0 0 90)
			(layer "B.Fab")
			(effects
				(font
					(size 1.27 1.27)
				)
				(justify mirror)
			)
		)
		(duplicate_pad_numbers_are_jumpers no)
		(fp_line
			(start 0.299974 -0.150114)
			(end -0.299974 -0.150114)
			(stroke
				(width 0.1)
				(type default)
			)
			(layer "B.Fab")
		)
		(fp_line
			(start -0.299974 -0.150114)
			(end -0.299974 0.150114)
			(stroke
				(width 0.1)
				(type default)
			)
			(layer "B.Fab")
		)
		(fp_line
			(start 0.299974 0.150114)
			(end 0.299974 -0.150114)
			(stroke
				(width 0.1)
				(type default)
			)
			(layer "B.Fab")
		)
		(fp_line
			(start -0.299974 0.150114)
			(end 0.299974 0.150114)
			(stroke
				(width 0.1)
				(type default)
			)
			(layer "B.Fab")
		)
		(pad "1" smd rect
			(at 0.2667 0 270)
			(size 0.3048 0.381)
			(layers "B.Cu" "B.Mask" "B.Paste")
			(net "P1V25_PEX1")
		)
		(pad "2" smd rect
			(at -0.2667 0 270)
			(size 0.3048 0.381)
			(layers "B.Cu" "B.Mask" "B.Paste")
			(net "GND")
		)
	)
	(footprint ""
		(layer "B.Cu")
		(at 305.149758 -293.99992 180)
		(property "Reference" "C3298"
			(at 0 0 0)
			(layer "B.SilkS")
			(hide yes)
			(effects
				(font
					(size 1.27 1.27)
				)
				(justify mirror)
			)
		)
		(property "Value" ""
			(at 0 0 0)
			(layer "B.Fab")
			(effects
				(font
					(size 1.27 1.27)
				)
				(justify mirror)
			)
		)
		(duplicate_pad_numbers_are_jumpers no)
		(fp_line
			(start 0.299974 0.150114)
			(end 0.299974 -0.150114)
			(stroke
				(width 0.1)
				(type default)
			)
			(layer "B.Fab")
		)
		(fp_line
			(start 0.299974 -0.150114)
			(end -0.299974 -0.150114)
			(stroke
				(width 0.1)
				(type default)
			)
			(layer "B.Fab")
		)
		(fp_line
			(start -0.299974 0.150114)
			(end 0.299974 0.150114)
			(stroke
				(width 0.1)
				(type default)
			)
			(layer "B.Fab")
		)
		(fp_line
			(start -0.299974 -0.150114)
			(end -0.299974 0.150114)
			(stroke
				(width 0.1)
				(type default)
			)
			(layer "B.Fab")
		)
		(pad "1" smd rect
			(at 0.2667 0)
			(size 0.3048 0.381)
			(layers "B.Cu" "B.Mask" "B.Paste")
			(net "P1V25_SERDES_VDDPLL_PEX2")
		)
		(pad "2" smd rect
			(at -0.2667 0)
			(size 0.3048 0.381)
			(layers "B.Cu" "B.Mask" "B.Paste")
			(net "GND")
		)
	)
	(footprint ""
		(layer "B.Cu")
		(at 212.09 -198.755 90)
		(property "Reference" "R1528"
			(at 0 0 90)
			(layer "B.SilkS")
			(hide yes)
			(effects
				(font
					(size 1.27 1.27)
				)
				(justify mirror)
			)
		)
		(property "Value" ""
			(at 0 0 90)
			(layer "B.Fab")
			(effects
				(font
					(size 1.27 1.27)
				)
				(justify mirror)
			)
		)
		(duplicate_pad_numbers_are_jumpers no)
		(fp_line
			(start 0.7874 -0.4064)
			(end -0.7874 -0.4064)
			(stroke
				(width 0.1524)
				(type default)
			)
			(layer "B.SilkS")
		)
		(fp_line
			(start -0.7874 -0.4064)
			(end -0.7874 0.4064)
			(stroke
				(width 0.1524)
				(type default)
			)
			(layer "B.SilkS")
		)
		(fp_line
			(start 0.7874 0.4064)
			(end 0.7874 -0.4064)
			(stroke
				(width 0.1524)
				(type default)
			)
			(layer "B.SilkS")
		)
		(fp_line
			(start -0.7874 0.4064)
			(end 0.7874 0.4064)
			(stroke
				(width 0.1524)
				(type default)
			)
			(layer "B.SilkS")
		)
		(fp_line
			(start 0.67945 -0.305054)
			(end 0.12065 -0.305054)
			(stroke
				(width 0.1)
				(type default)
			)
			(layer "B.Fab")
		)
		(fp_line
			(start 0.12065 -0.305054)
			(end 0.12065 -0.2794)
			(stroke
				(width 0.1)
				(type default)
			)
			(layer "B.Fab")
		)
		(fp_line
			(start -0.12065 -0.3048)
			(end -0.67945 -0.3048)
			(stroke
				(width 0.1)
				(type default)
			)
			(layer "B.Fab")
		)
		(fp_line
			(start -0.67945 -0.3048)
			(end -0.67945 0.3048)
			(stroke
				(width 0.1)
				(type default)
			)
			(layer "B.Fab")
		)
		(fp_line
			(start 0.12065 -0.2794)
			(end -0.12065 -0.2794)
			(stroke
				(width 0.1)
				(type default)
			)
			(layer "B.Fab")
		)
		(fp_line
			(start -0.12065 -0.2794)
			(end -0.12065 -0.3048)
			(stroke
				(width 0.1)
				(type default)
			)
			(layer "B.Fab")
		)
		(fp_line
			(start 0.12065 0.2794)
			(end 0.12065 0.3048)
			(stroke
				(width 0.1)
				(type default)
			)
			(layer "B.Fab")
		)
		(fp_line
			(start -0.120396 0.2794)
			(end 0.12065 0.2794)
			(stroke
				(width 0.1)
				(type default)
			)
			(layer "B.Fab")
		)
		(fp_line
			(start 0.67945 0.3048)
			(end 0.67945 -0.305054)
			(stroke
				(width 0.1)
				(type default)
			)
			(layer "B.Fab")
		)
		(fp_line
			(start 0.12065 0.3048)
			(end 0.67945 0.3048)
			(stroke
				(width 0.1)
				(type default)
			)
			(layer "B.Fab")
		)
		(fp_line
			(start -0.120396 0.3048)
			(end -0.120396 0.2794)
			(stroke
				(width 0.1)
				(type default)
			)
			(layer "B.Fab")
		)
		(fp_line
			(start -0.67945 0.3048)
			(end -0.120396 0.3048)
			(stroke
				(width 0.1)
				(type default)
			)
			(layer "B.Fab")
		)
		(pad "1" smd circle
			(at 0.40005 0 270)
			(size 0 0)
			(layers "B.Cu" "B.Mask" "B.Paste")
			(net "SMB_NIC6_LS_R_SDA")
		)
		(pad "2" smd circle
			(at -0.40005 0 270)
			(size 0 0)
			(layers "B.Cu" "B.Mask" "B.Paste")
			(net "SMB_NIC6_R_SDA")
		)
	)
	(footprint ""
		(layer "B.Cu")
		(at 53.474874 -293.99992 -90)
		(property "Reference" "C1153"
			(at 0 0 90)
			(layer "B.SilkS")
			(hide yes)
			(effects
				(font
					(size 1.27 1.27)
				)
				(justify mirror)
			)
		)
		(property "Value" ""
			(at 0 0 90)
			(layer "B.Fab")
			(effects
				(font
					(size 1.27 1.27)
				)
				(justify mirror)
			)
		)
		(duplicate_pad_numbers_are_jumpers no)
		(fp_line
			(start -0.299974 0.150114)
			(end 0.299974 0.150114)
			(stroke
				(width 0.1)
				(type default)
			)
			(layer "B.Fab")
		)
		(fp_line
			(start 0.299974 0.150114)
			(end 0.299974 -0.150114)
			(stroke
				(width 0.1)
				(type default)
			)
			(layer "B.Fab")
		)
		(fp_line
			(start -0.299974 -0.150114)
			(end -0.299974 0.150114)
			(stroke
				(width 0.1)
				(type default)
			)
			(layer "B.Fab")
		)
		(fp_line
			(start 0.299974 -0.150114)
			(end -0.299974 -0.150114)
			(stroke
				(width 0.1)
				(type default)
			)
			(layer "B.Fab")
		)
		(pad "1" smd rect
			(at 0.2667 0 90)
			(size 0.3048 0.381)
			(layers "B.Cu" "B.Mask" "B.Paste")
			(net "P0V8_PEX0")
		)
		(pad "2" smd rect
			(at -0.2667 0 90)
			(size 0.3048 0.381)
			(layers "B.Cu" "B.Mask" "B.Paste")
			(net "GND")
		)
	)
	(footprint ""
		(layer "B.Cu")
		(at 290.42487 -293.99992 90)
		(property "Reference" "C1654"
			(at 0 0 90)
			(layer "B.SilkS")
			(hide yes)
			(effects
				(font
					(size 1.27 1.27)
				)
				(justify mirror)
			)
		)
		(property "Value" ""
			(at 0 0 90)
			(layer "B.Fab")
			(effects
				(font
					(size 1.27 1.27)
				)
				(justify mirror)
			)
		)
		(duplicate_pad_numbers_are_jumpers no)
		(fp_line
			(start 0.299974 -0.150114)
			(end -0.299974 -0.150114)
			(stroke
				(width 0.1)
				(type default)
			)
			(layer "B.Fab")
		)
		(fp_line
			(start -0.299974 -0.150114)
			(end -0.299974 0.150114)
			(stroke
				(width 0.1)
				(type default)
			)
			(layer "B.Fab")
		)
		(fp_line
			(start 0.299974 0.150114)
			(end 0.299974 -0.150114)
			(stroke
				(width 0.1)
				(type default)
			)
			(layer "B.Fab")
		)
		(fp_line
			(start -0.299974 0.150114)
			(end 0.299974 0.150114)
			(stroke
				(width 0.1)
				(type default)
			)
			(layer "B.Fab")
		)
		(pad "1" smd rect
			(at 0.2667 0 270)
			(size 0.3048 0.381)
			(layers "B.Cu" "B.Mask" "B.Paste")
			(net "P0V8_PEX2")
		)
		(pad "2" smd rect
			(at -0.2667 0 270)
			(size 0.3048 0.381)
			(layers "B.Cu" "B.Mask" "B.Paste")
			(net "GND")
		)
	)
	(footprint ""
		(layer "B.Cu")
		(at 229.556564 -208.78546 90)
		(property "Reference" "R5294"
			(at 0 0 90)
			(layer "B.SilkS")
			(hide yes)
			(effects
				(font
					(size 1.27 1.27)
				)
				(justify mirror)
			)
		)
		(property "Value" ""
			(at 0 0 90)
			(layer "B.Fab")
			(effects
				(font
					(size 1.27 1.27)
				)
				(justify mirror)
			)
		)
		(duplicate_pad_numbers_are_jumpers no)
		(fp_line
			(start 0.7874 -0.4064)
			(end -0.7874 -0.4064)
			(stroke
				(width 0.1524)
				(type default)
			)
			(layer "B.SilkS")
		)
		(fp_line
			(start -0.7874 -0.4064)
			(end -0.7874 0.4064)
			(stroke
				(width 0.1524)
				(type default)
			)
			(layer "B.SilkS")
		)
		(fp_line
			(start 0.7874 0.4064)
			(end 0.7874 -0.4064)
			(stroke
				(width 0.1524)
				(type default)
			)
			(layer "B.SilkS")
		)
		(fp_line
			(start -0.7874 0.4064)
			(end 0.7874 0.4064)
			(stroke
				(width 0.1524)
				(type default)
			)
			(layer "B.SilkS")
		)
		(fp_line
			(start 0.67945 -0.305054)
			(end 0.12065 -0.305054)
			(stroke
				(width 0.1)
				(type default)
			)
			(layer "B.Fab")
		)
		(fp_line
			(start 0.12065 -0.305054)
			(end 0.12065 -0.2794)
			(stroke
				(width 0.1)
				(type default)
			)
			(layer "B.Fab")
		)
		(fp_line
			(start -0.12065 -0.3048)
			(end -0.67945 -0.3048)
			(stroke
				(width 0.1)
				(type default)
			)
			(layer "B.Fab")
		)
		(fp_line
			(start -0.67945 -0.3048)
			(end -0.67945 0.3048)
			(stroke
				(width 0.1)
				(type default)
			)
			(layer "B.Fab")
		)
		(fp_line
			(start 0.12065 -0.2794)
			(end -0.12065 -0.2794)
			(stroke
				(width 0.1)
				(type default)
			)
			(layer "B.Fab")
		)
		(fp_line
			(start -0.12065 -0.2794)
			(end -0.12065 -0.3048)
			(stroke
				(width 0.1)
				(type default)
			)
			(layer "B.Fab")
		)
		(fp_line
			(start 0.12065 0.2794)
			(end 0.12065 0.3048)
			(stroke
				(width 0.1)
				(type default)
			)
			(layer "B.Fab")
		)
		(fp_line
			(start -0.120396 0.2794)
			(end 0.12065 0.2794)
			(stroke
				(width 0.1)
				(type default)
			)
			(layer "B.Fab")
		)
		(fp_line
			(start 0.67945 0.3048)
			(end 0.67945 -0.305054)
			(stroke
				(width 0.1)
				(type default)
			)
			(layer "B.Fab")
		)
		(fp_line
			(start 0.12065 0.3048)
			(end 0.67945 0.3048)
			(stroke
				(width 0.1)
				(type default)
			)
			(layer "B.Fab")
		)
		(fp_line
			(start -0.120396 0.3048)
			(end -0.120396 0.2794)
			(stroke
				(width 0.1)
				(type default)
			)
			(layer "B.Fab")
		)
		(fp_line
			(start -0.67945 0.3048)
			(end -0.120396 0.3048)
			(stroke
				(width 0.1)
				(type default)
			)
			(layer "B.Fab")
		)
		(pad "1" smd circle
			(at 0.40005 0 270)
			(size 0 0)
			(layers "B.Cu" "B.Mask" "B.Paste")
			(net "BIC_SEL_FLASH_SW1")
		)
		(pad "2" smd circle
			(at -0.40005 0 270)
			(size 0 0)
			(layers "B.Cu" "B.Mask" "B.Paste")
			(net "BIC_SEL_FLASH_SW1_R")
		)
	)
	(footprint ""
		(layer "B.Cu")
		(at 301.141384 -287.824926)
		(property "Reference" "C3345"
			(at 0 0 0)
			(layer "B.SilkS")
			(hide yes)
			(effects
				(font
					(size 1.27 1.27)
				)
				(justify mirror)
			)
		)
		(property "Value" ""
			(at 0 0 0)
			(layer "B.Fab")
			(effects
				(font
					(size 1.27 1.27)
				)
				(justify mirror)
			)
		)
		(duplicate_pad_numbers_are_jumpers no)
		(fp_line
			(start -0.299974 -0.150114)
			(end -0.299974 0.150114)
			(stroke
				(width 0.1)
				(type default)
			)
			(layer "B.Fab")
		)
		(fp_line
			(start -0.299974 0.150114)
			(end 0.299974 0.150114)
			(stroke
				(width 0.1)
				(type default)
			)
			(layer "B.Fab")
		)
		(fp_line
			(start 0.299974 -0.150114)
			(end -0.299974 -0.150114)
			(stroke
				(width 0.1)
				(type default)
			)
			(layer "B.Fab")
		)
		(fp_line
			(start 0.299974 0.150114)
			(end 0.299974 -0.150114)
			(stroke
				(width 0.1)
				(type default)
			)
			(layer "B.Fab")
		)
		(pad "1" smd rect
			(at 0.2667 0 180)
			(size 0.3048 0.381)
			(layers "B.Cu" "B.Mask" "B.Paste")
			(net "P1V8_VDDA_PEX2")
		)
		(pad "2" smd rect
			(at -0.2667 0 180)
			(size 0.3048 0.381)
			(layers "B.Cu" "B.Mask" "B.Paste")
			(net "GND")
		)
	)
	(footprint ""
		(layer "B.Cu")
		(at 133.230366 -181.249574 180)
		(property "Reference" "C2654"
			(at 0 0 0)
			(layer "B.SilkS")
			(hide yes)
			(effects
				(font
					(size 1.27 1.27)
				)
				(justify mirror)
			)
		)
		(property "Value" ""
			(at 0 0 0)
			(layer "B.Fab")
			(effects
				(font
					(size 1.27 1.27)
				)
				(justify mirror)
			)
		)
		(duplicate_pad_numbers_are_jumpers no)
		(fp_line
			(start 0.7874 0.4064)
			(end 0.7874 -0.4064)
			(stroke
				(width 0.1524)
				(type default)
			)
			(layer "B.SilkS")
		)
		(fp_line
			(start 0.7874 -0.4064)
			(end -0.7874 -0.4064)
			(stroke
				(width 0.1524)
				(type default)
			)
			(layer "B.SilkS")
		)
		(fp_line
			(start -0.7874 0.4064)
			(end 0.7874 0.4064)
			(stroke
				(width 0.1524)
				(type default)
			)
			(layer "B.SilkS")
		)
		(fp_line
			(start -0.7874 -0.4064)
			(end -0.7874 0.4064)
			(stroke
				(width 0.1524)
				(type default)
			)
			(layer "B.SilkS")
		)
		(fp_line
			(start 0.67945 0.3048)
			(end 0.67945 -0.305054)
			(stroke
				(width 0.1)
				(type default)
			)
			(layer "B.Fab")
		)
		(fp_line
			(start 0.67945 -0.305054)
			(end 0.12065 -0.305054)
			(stroke
				(width 0.1)
				(type default)
			)
			(layer "B.Fab")
		)
		(fp_line
			(start 0.12065 0.3048)
			(end 0.67945 0.3048)
			(stroke
				(width 0.1)
				(type default)
			)
			(layer "B.Fab")
		)
		(fp_line
			(start 0.12065 0.2794)
			(end 0.12065 0.3048)
			(stroke
				(width 0.1)
				(type default)
			)
			(layer "B.Fab")
		)
		(fp_line
			(start 0.12065 -0.2794)
			(end -0.12065 -0.2794)
			(stroke
				(width 0.1)
				(type default)
			)
			(layer "B.Fab")
		)
		(fp_line
			(start 0.12065 -0.305054)
			(end 0.12065 -0.2794)
			(stroke
				(width 0.1)
				(type default)
			)
			(layer "B.Fab")
		)
		(fp_line
			(start -0.120396 0.3048)
			(end -0.120396 0.2794)
			(stroke
				(width 0.1)
				(type default)
			)
			(layer "B.Fab")
		)
		(fp_line
			(start -0.120396 0.2794)
			(end 0.12065 0.2794)
			(stroke
				(width 0.1)
				(type default)
			)
			(layer "B.Fab")
		)
		(fp_line
			(start -0.12065 -0.2794)
			(end -0.12065 -0.3048)
			(stroke
				(width 0.1)
				(type default)
			)
			(layer "B.Fab")
		)
		(fp_line
			(start -0.12065 -0.3048)
			(end -0.67945 -0.3048)
			(stroke
				(width 0.1)
				(type default)
			)
			(layer "B.Fab")
		)
		(fp_line
			(start -0.67945 0.3048)
			(end -0.120396 0.3048)
			(stroke
				(width 0.1)
				(type default)
			)
			(layer "B.Fab")
		)
		(fp_line
			(start -0.67945 -0.3048)
			(end -0.67945 0.3048)
			(stroke
				(width 0.1)
				(type default)
			)
			(layer "B.Fab")
		)
		(pad "1" smd circle
			(at 0.40005 0)
			(size 0 0)
			(layers "B.Cu" "B.Mask" "B.Paste")
			(net "P3V3_DB2000QL_VDDA")
		)
		(pad "2" smd circle
			(at -0.40005 0)
			(size 0 0)
			(layers "B.Cu" "B.Mask" "B.Paste")
			(net "GND")
		)
	)
	(footprint ""
		(layer "B.Cu")
		(at 52.999894 -288.299906 90)
		(property "Reference" "C2935"
			(at 0 0 90)
			(layer "B.SilkS")
			(hide yes)
			(effects
				(font
					(size 1.27 1.27)
				)
				(justify mirror)
			)
		)
		(property "Value" ""
			(at 0 0 90)
			(layer "B.Fab")
			(effects
				(font
					(size 1.27 1.27)
				)
				(justify mirror)
			)
		)
		(duplicate_pad_numbers_are_jumpers no)
		(fp_line
			(start 0.299974 -0.150114)
			(end -0.299974 -0.150114)
			(stroke
				(width 0.1)
				(type default)
			)
			(layer "B.Fab")
		)
		(fp_line
			(start -0.299974 -0.150114)
			(end -0.299974 0.150114)
			(stroke
				(width 0.1)
				(type default)
			)
			(layer "B.Fab")
		)
		(fp_line
			(start 0.299974 0.150114)
			(end 0.299974 -0.150114)
			(stroke
				(width 0.1)
				(type default)
			)
			(layer "B.Fab")
		)
		(fp_line
			(start -0.299974 0.150114)
			(end 0.299974 0.150114)
			(stroke
				(width 0.1)
				(type default)
			)
			(layer "B.Fab")
		)
		(pad "1" smd rect
			(at 0.2667 0 270)
			(size 0.3048 0.381)
			(layers "B.Cu" "B.Mask" "B.Paste")
			(net "P1V25_PEX0")
		)
		(pad "2" smd rect
			(at -0.2667 0 270)
			(size 0.3048 0.381)
			(layers "B.Cu" "B.Mask" "B.Paste")
			(net "GND")
		)
	)
	(footprint ""
		(layer "B.Cu")
		(at 412.224982 -286.399732 90)
		(property "Reference" "C3505"
			(at 0 0 90)
			(layer "B.SilkS")
			(hide yes)
			(effects
				(font
					(size 1.27 1.27)
				)
				(justify mirror)
			)
		)
		(property "Value" ""
			(at 0 0 90)
			(layer "B.Fab")
			(effects
				(font
					(size 1.27 1.27)
				)
				(justify mirror)
			)
		)
		(duplicate_pad_numbers_are_jumpers no)
		(fp_line
			(start 0.299974 -0.150114)
			(end -0.299974 -0.150114)
			(stroke
				(width 0.1)
				(type default)
			)
			(layer "B.Fab")
		)
		(fp_line
			(start -0.299974 -0.150114)
			(end -0.299974 0.150114)
			(stroke
				(width 0.1)
				(type default)
			)
			(layer "B.Fab")
		)
		(fp_line
			(start 0.299974 0.150114)
			(end 0.299974 -0.150114)
			(stroke
				(width 0.1)
				(type default)
			)
			(layer "B.Fab")
		)
		(fp_line
			(start -0.299974 0.150114)
			(end 0.299974 0.150114)
			(stroke
				(width 0.1)
				(type default)
			)
			(layer "B.Fab")
		)
		(pad "1" smd rect
			(at 0.2667 0 270)
			(size 0.3048 0.381)
			(layers "B.Cu" "B.Mask" "B.Paste")
			(net "P1V25_SERDES_VDDPLL_PEX3")
		)
		(pad "2" smd rect
			(at -0.2667 0 270)
			(size 0.3048 0.381)
			(layers "B.Cu" "B.Mask" "B.Paste")
			(net "GND")
		)
	)
	(footprint ""
		(layer "B.Cu")
		(at 19.755612 -227.084382 90)
		(property "Reference" "U65"
			(at -2.069592 3.18135 270)
			(unlocked yes)
			(layer "B.SilkS")
			(effects
				(font
					(size 0.7874 0.5842)
					(thickness 0.1524)
				)
				(justify mirror)
			)
		)
		(property "Value" ""
			(at 0 0 90)
			(layer "B.Fab")
			(effects
				(font
					(size 1.27 1.27)
				)
				(justify mirror)
			)
		)
		(duplicate_pad_numbers_are_jumpers no)
		(fp_line
			(start 1.8288 -2.4892)
			(end 0.5588 -2.4892)
			(stroke
				(width 0.1524)
				(type default)
			)
			(layer "B.SilkS")
		)
		(fp_line
			(start 0.5588 -2.4892)
			(end 0 -1.9304)
			(stroke
				(width 0.1524)
				(type default)
			)
			(layer "B.SilkS")
		)
		(fp_line
			(start -0.5588 -2.4892)
			(end -1.8288 -2.4892)
			(stroke
				(width 0.1524)
				(type default)
			)
			(layer "B.SilkS")
		)
		(fp_line
			(start -1.8288 -2.4892)
			(end -1.8161 2.4892)
			(stroke
				(width 0.1524)
				(type default)
			)
			(layer "B.SilkS")
		)
		(fp_line
			(start 0 -1.9304)
			(end -0.5588 -2.4892)
			(stroke
				(width 0.1524)
				(type default)
			)
			(layer "B.SilkS")
		)
		(fp_line
			(start 1.8288 2.4892)
			(end 1.8288 -2.4892)
			(stroke
				(width 0.1524)
				(type default)
			)
			(layer "B.SilkS")
		)
		(fp_line
			(start -1.8161 2.4892)
			(end 1.8288 2.4892)
			(stroke
				(width 0.1524)
				(type default)
			)
			(layer "B.SilkS")
		)
		(fp_poly
			(pts
				(xy 4.12242 -2.832862) (xy 3.680714 -3.274822) (xy 3.521202 -2.650998)
			)
			(stroke
				(width 0)
				(type default)
			)
			(fill yes)
			(layer "B.SilkS")
		)
		(fp_line
			(start 1.9939 -2.4892)
			(end -1.9939 -2.4892)
			(stroke
				(width 0.1)
				(type default)
			)
			(layer "B.Fab")
		)
		(fp_line
			(start -1.9939 -2.4892)
			(end -1.9939 -2.3876)
			(stroke
				(width 0.1)
				(type default)
			)
			(layer "B.Fab")
		)
		(fp_line
			(start 3.0988 -2.3876)
			(end 1.9939 -2.3876)
			(stroke
				(width 0.1)
				(type default)
			)
			(layer "B.Fab")
		)
		(fp_line
			(start 1.9939 -2.3876)
			(end 1.9939 -2.4892)
			(stroke
				(width 0.1)
				(type default)
			)
			(layer "B.Fab")
		)
		(fp_line
			(start 1.9939 -2.3876)
			(end 1.9812 -2.3876)
			(stroke
				(width 0.1)
				(type default)
			)
			(layer "B.Fab")
		)
		(fp_line
			(start -1.9939 -2.3876)
			(end -3.0988 -2.3876)
			(stroke
				(width 0.1)
				(type default)
			)
			(layer "B.Fab")
		)
		(fp_line
			(start -1.9939 -2.3876)
			(end -1.9939 2.3876)
			(stroke
				(width 0.1)
				(type default)
			)
			(layer "B.Fab")
		)
		(fp_line
			(start -3.0988 -2.3876)
			(end -3.0988 2.3876)
			(stroke
				(width 0.1)
				(type default)
			)
			(layer "B.Fab")
		)
		(fp_line
			(start -3.0988 -2.3876)
			(end -3.0988 2.3876)
			(stroke
				(width 0.1)
				(type default)
			)
			(layer "B.Fab")
		)
		(fp_line
			(start 3.0988 2.3876)
			(end 3.0988 -2.3876)
			(stroke
				(width 0.1)
				(type default)
			)
			(layer "B.Fab")
		)
		(fp_line
			(start 3.0988 2.3876)
			(end 3.0988 -2.3876)
			(stroke
				(width 0.1)
				(type default)
			)
			(layer "B.Fab")
		)
		(fp_line
			(start 1.9939 2.3876)
			(end 1.9939 -2.3876)
			(stroke
				(width 0.1)
				(type default)
			)
			(layer "B.Fab")
		)
		(fp_line
			(start 1.9939 2.3876)
			(end 3.0988 2.3876)
			(stroke
				(width 0.1)
				(type default)
			)
			(layer "B.Fab")
		)
		(fp_line
			(start -1.9939 2.3876)
			(end -1.9939 2.4892)
			(stroke
				(width 0.1)
				(type default)
			)
			(layer "B.Fab")
		)
		(fp_line
			(start -3.0988 2.3876)
			(end -1.9939 2.3876)
			(stroke
				(width 0.1)
				(type default)
			)
			(layer "B.Fab")
		)
		(fp_line
			(start 1.9939 2.4892)
			(end 1.9939 2.3876)
			(stroke
				(width 0.1)
				(type default)
			)
			(layer "B.Fab")
		)
		(fp_line
			(start -1.9939 2.4892)
			(end 1.9939 2.4892)
			(stroke
				(width 0.1)
				(type default)
			)
			(layer "B.Fab")
		)
		(fp_line
			(start -1.9939 2.4892)
			(end -2.0066 2.4892)
			(stroke
				(width 0.1)
				(type default)
			)
			(layer "B.Fab")
		)
		(fp_line
			(start -1.9939 2.5019)
			(end -1.9939 2.4892)
			(stroke
				(width 0.1)
				(type default)
			)
			(layer "B.Fab")
		)
		(fp_poly
			(pts
				(xy 4.23672 -1.989328) (xy 4.23672 -2.614168) (xy 3.683 -2.286)
			)
			(stroke
				(width 0)
				(type default)
			)
			(fill yes)
			(layer "B.Fab")
		)
		(pad "1" smd rect
			(at 2.7432 -2.2225)
			(size 0.3556 1.5494)
			(layers "B.Cu" "B.Mask" "B.Paste")
			(net "SEL_FLASH_PEX0_BUF_R")
		)
		(pad "2" smd rect
			(at 2.7432 -1.5875)
			(size 0.3556 1.5494)
			(layers "B.Cu" "B.Mask" "B.Paste")
			(net "SPI_PEX0_CS_R_N")
		)
		(pad "3" smd rect
			(at 2.7432 -0.9525)
			(size 0.3556 1.5494)
			(layers "B.Cu" "B.Mask" "B.Paste")
			(net "SPI_BIC1_CS0_LS01_R1_N")
		)
		(pad "4" smd rect
			(at 2.7432 -0.3175)
			(size 0.3556 1.5494)
			(layers "B.Cu" "B.Mask" "B.Paste")
			(net "SPI_PEX0_CS_MUX_N")
		)
		(pad "5" smd rect
			(at 2.7432 0.3175)
			(size 0.3556 1.5494)
			(layers "B.Cu" "B.Mask" "B.Paste")
			(net "SPI_PEX0_CLK_R")
		)
		(pad "6" smd rect
			(at 2.7432 0.9525)
			(size 0.3556 1.5494)
			(layers "B.Cu" "B.Mask" "B.Paste")
			(net "SPI_BIC1_CLK_LS01_R1")
		)
		(pad "7" smd rect
			(at 2.7432 1.5875)
			(size 0.3556 1.5494)
			(layers "B.Cu" "B.Mask" "B.Paste")
			(net "SPI_PEX0_CLK_MUX")
		)
		(pad "8" smd rect
			(at 2.7432 2.2225)
			(size 0.3556 1.5494)
			(layers "B.Cu" "B.Mask" "B.Paste")
			(net "GND")
		)
		(pad "9" smd rect
			(at -2.7432 2.2225)
			(size 0.3556 1.5494)
			(layers "B.Cu" "B.Mask" "B.Paste")
			(net "SPI_PEX0_SDIO0_MUX")
		)
		(pad "10" smd rect
			(at -2.7432 1.5875)
			(size 0.3556 1.5494)
			(layers "B.Cu" "B.Mask" "B.Paste")
			(net "SPI_BIC1_MOSI_LS01_R1")
		)
		(pad "11" smd rect
			(at -2.7432 0.9525)
			(size 0.3556 1.5494)
			(layers "B.Cu" "B.Mask" "B.Paste")
			(net "SPI_PEX0_SDIO0_R")
		)
		(pad "12" smd rect
			(at -2.7432 0.3175)
			(size 0.3556 1.5494)
			(layers "B.Cu" "B.Mask" "B.Paste")
			(net "SPI_PEX0_SDIO1_MUX")
		)
		(pad "13" smd rect
			(at -2.7432 -0.3175)
			(size 0.3556 1.5494)
			(layers "B.Cu" "B.Mask" "B.Paste")
			(net "SPI_BIC1_MISO_LS01_R1")
		)
		(pad "14" smd rect
			(at -2.7432 -0.9525)
			(size 0.3556 1.5494)
			(layers "B.Cu" "B.Mask" "B.Paste")
			(net "SPI_PEX0_SDIO1_R")
		)
		(pad "15" smd rect
			(at -2.7432 -1.5875)
			(size 0.3556 1.5494)
			(layers "B.Cu" "B.Mask" "B.Paste")
			(net "SPI_MUX_PEX0_EN_N")
		)
		(pad "16" smd rect
			(at -2.7432 -2.2225)
			(size 0.3556 1.5494)
			(layers "B.Cu" "B.Mask" "B.Paste")
			(net "P3V3_AUX")
		)
	)
	(footprint ""
		(layer "B.Cu")
		(at 292.32479 -293.99992 -90)
		(property "Reference" "C1650"
			(at 0 0 90)
			(layer "B.SilkS")
			(hide yes)
			(effects
				(font
					(size 1.27 1.27)
				)
				(justify mirror)
			)
		)
		(property "Value" ""
			(at 0 0 90)
			(layer "B.Fab")
			(effects
				(font
					(size 1.27 1.27)
				)
				(justify mirror)
			)
		)
		(duplicate_pad_numbers_are_jumpers no)
		(fp_line
			(start -0.299974 0.150114)
			(end 0.299974 0.150114)
			(stroke
				(width 0.1)
				(type default)
			)
			(layer "B.Fab")
		)
		(fp_line
			(start 0.299974 0.150114)
			(end 0.299974 -0.150114)
			(stroke
				(width 0.1)
				(type default)
			)
			(layer "B.Fab")
		)
		(fp_line
			(start -0.299974 -0.150114)
			(end -0.299974 0.150114)
			(stroke
				(width 0.1)
				(type default)
			)
			(layer "B.Fab")
		)
		(fp_line
			(start 0.299974 -0.150114)
			(end -0.299974 -0.150114)
			(stroke
				(width 0.1)
				(type default)
			)
			(layer "B.Fab")
		)
		(pad "1" smd rect
			(at 0.2667 0 90)
			(size 0.3048 0.381)
			(layers "B.Cu" "B.Mask" "B.Paste")
			(net "P0V8_PEX2")
		)
		(pad "2" smd rect
			(at -0.2667 0 90)
			(size 0.3048 0.381)
			(layers "B.Cu" "B.Mask" "B.Paste")
			(net "GND")
		)
	)
	(footprint ""
		(layer "B.Cu")
		(at 401.299934 -301.599854 -90)
		(property "Reference" "C1945"
			(at 0 0 90)
			(layer "B.SilkS")
			(hide yes)
			(effects
				(font
					(size 1.27 1.27)
				)
				(justify mirror)
			)
		)
		(property "Value" ""
			(at 0 0 90)
			(layer "B.Fab")
			(effects
				(font
					(size 1.27 1.27)
				)
				(justify mirror)
			)
		)
		(duplicate_pad_numbers_are_jumpers no)
		(fp_line
			(start -0.299974 0.150114)
			(end 0.299974 0.150114)
			(stroke
				(width 0.1)
				(type default)
			)
			(layer "B.Fab")
		)
		(fp_line
			(start 0.299974 0.150114)
			(end 0.299974 -0.150114)
			(stroke
				(width 0.1)
				(type default)
			)
			(layer "B.Fab")
		)
		(fp_line
			(start -0.299974 -0.150114)
			(end -0.299974 0.150114)
			(stroke
				(width 0.1)
				(type default)
			)
			(layer "B.Fab")
		)
		(fp_line
			(start 0.299974 -0.150114)
			(end -0.299974 -0.150114)
			(stroke
				(width 0.1)
				(type default)
			)
			(layer "B.Fab")
		)
		(pad "1" smd rect
			(at 0.2667 0 90)
			(size 0.3048 0.381)
			(layers "B.Cu" "B.Mask" "B.Paste")
			(net "P0V8_SERDES_VDDA_PEX3")
		)
		(pad "2" smd rect
			(at -0.2667 0 90)
			(size 0.3048 0.381)
			(layers "B.Cu" "B.Mask" "B.Paste")
			(net "GND")
		)
	)
	(footprint ""
		(layer "B.Cu")
		(at 174.800006 -301.599854 -90)
		(property "Reference" "C1430"
			(at 0 0 90)
			(layer "B.SilkS")
			(hide yes)
			(effects
				(font
					(size 1.27 1.27)
				)
				(justify mirror)
			)
		)
		(property "Value" ""
			(at 0 0 90)
			(layer "B.Fab")
			(effects
				(font
					(size 1.27 1.27)
				)
				(justify mirror)
			)
		)
		(duplicate_pad_numbers_are_jumpers no)
		(fp_line
			(start -0.299974 0.150114)
			(end 0.299974 0.150114)
			(stroke
				(width 0.1)
				(type default)
			)
			(layer "B.Fab")
		)
		(fp_line
			(start 0.299974 0.150114)
			(end 0.299974 -0.150114)
			(stroke
				(width 0.1)
				(type default)
			)
			(layer "B.Fab")
		)
		(fp_line
			(start -0.299974 -0.150114)
			(end -0.299974 0.150114)
			(stroke
				(width 0.1)
				(type default)
			)
			(layer "B.Fab")
		)
		(fp_line
			(start 0.299974 -0.150114)
			(end -0.299974 -0.150114)
			(stroke
				(width 0.1)
				(type default)
			)
			(layer "B.Fab")
		)
		(pad "1" smd rect
			(at 0.2667 0 90)
			(size 0.3048 0.381)
			(layers "B.Cu" "B.Mask" "B.Paste")
			(net "P0V8_SERDES_VDDA_PEX1")
		)
		(pad "2" smd rect
			(at -0.2667 0 90)
			(size 0.3048 0.381)
			(layers "B.Cu" "B.Mask" "B.Paste")
			(net "GND")
		)
	)
	(footprint ""
		(layer "B.Cu")
		(at 134.717536 -215.85682 180)
		(property "Reference" "R995"
			(at 0 0 0)
			(layer "B.SilkS")
			(hide yes)
			(effects
				(font
					(size 1.27 1.27)
				)
				(justify mirror)
			)
		)
		(property "Value" ""
			(at 0 0 0)
			(layer "B.Fab")
			(effects
				(font
					(size 1.27 1.27)
				)
				(justify mirror)
			)
		)
		(duplicate_pad_numbers_are_jumpers no)
		(fp_line
			(start 0.7874 0.4064)
			(end 0.7874 -0.4064)
			(stroke
				(width 0.1524)
				(type default)
			)
			(layer "B.SilkS")
		)
		(fp_line
			(start 0.7874 -0.4064)
			(end -0.7874 -0.4064)
			(stroke
				(width 0.1524)
				(type default)
			)
			(layer "B.SilkS")
		)
		(fp_line
			(start -0.7874 0.4064)
			(end 0.7874 0.4064)
			(stroke
				(width 0.1524)
				(type default)
			)
			(layer "B.SilkS")
		)
		(fp_line
			(start -0.7874 -0.4064)
			(end -0.7874 0.4064)
			(stroke
				(width 0.1524)
				(type default)
			)
			(layer "B.SilkS")
		)
		(fp_line
			(start 0.67945 0.3048)
			(end 0.67945 -0.305054)
			(stroke
				(width 0.1)
				(type default)
			)
			(layer "B.Fab")
		)
		(fp_line
			(start 0.67945 -0.305054)
			(end 0.12065 -0.305054)
			(stroke
				(width 0.1)
				(type default)
			)
			(layer "B.Fab")
		)
		(fp_line
			(start 0.12065 0.3048)
			(end 0.67945 0.3048)
			(stroke
				(width 0.1)
				(type default)
			)
			(layer "B.Fab")
		)
		(fp_line
			(start 0.12065 0.2794)
			(end 0.12065 0.3048)
			(stroke
				(width 0.1)
				(type default)
			)
			(layer "B.Fab")
		)
		(fp_line
			(start 0.12065 -0.2794)
			(end -0.12065 -0.2794)
			(stroke
				(width 0.1)
				(type default)
			)
			(layer "B.Fab")
		)
		(fp_line
			(start 0.12065 -0.305054)
			(end 0.12065 -0.2794)
			(stroke
				(width 0.1)
				(type default)
			)
			(layer "B.Fab")
		)
		(fp_line
			(start -0.120396 0.3048)
			(end -0.120396 0.2794)
			(stroke
				(width 0.1)
				(type default)
			)
			(layer "B.Fab")
		)
		(fp_line
			(start -0.120396 0.2794)
			(end 0.12065 0.2794)
			(stroke
				(width 0.1)
				(type default)
			)
			(layer "B.Fab")
		)
		(fp_line
			(start -0.12065 -0.2794)
			(end -0.12065 -0.3048)
			(stroke
				(width 0.1)
				(type default)
			)
			(layer "B.Fab")
		)
		(fp_line
			(start -0.12065 -0.3048)
			(end -0.67945 -0.3048)
			(stroke
				(width 0.1)
				(type default)
			)
			(layer "B.Fab")
		)
		(fp_line
			(start -0.67945 0.3048)
			(end -0.120396 0.3048)
			(stroke
				(width 0.1)
				(type default)
			)
			(layer "B.Fab")
		)
		(fp_line
			(start -0.67945 -0.3048)
			(end -0.67945 0.3048)
			(stroke
				(width 0.1)
				(type default)
			)
			(layer "B.Fab")
		)
		(pad "1" smd circle
			(at 0.40005 0)
			(size 0 0)
			(layers "B.Cu" "B.Mask" "B.Paste")
			(net "UART_PEX3_CLI_BUF_TX")
		)
		(pad "2" smd circle
			(at -0.40005 0)
			(size 0 0)
			(layers "B.Cu" "B.Mask" "B.Paste")
			(net "P3V3_AUX")
		)
	)
	(footprint ""
		(layer "B.Cu")
		(at 185.2676 -295.3512 180)
		(property "Reference" "C1418"
			(at 0 0 0)
			(layer "B.SilkS")
			(hide yes)
			(effects
				(font
					(size 1.27 1.27)
				)
				(justify mirror)
			)
		)
		(property "Value" ""
			(at 0 0 0)
			(layer "B.Fab")
			(effects
				(font
					(size 1.27 1.27)
				)
				(justify mirror)
			)
		)
		(duplicate_pad_numbers_are_jumpers no)
		(fp_line
			(start 0.299974 0.150114)
			(end 0.299974 -0.150114)
			(stroke
				(width 0.1)
				(type default)
			)
			(layer "B.Fab")
		)
		(fp_line
			(start 0.299974 -0.150114)
			(end -0.299974 -0.150114)
			(stroke
				(width 0.1)
				(type default)
			)
			(layer "B.Fab")
		)
		(fp_line
			(start -0.299974 0.150114)
			(end 0.299974 0.150114)
			(stroke
				(width 0.1)
				(type default)
			)
			(layer "B.Fab")
		)
		(fp_line
			(start -0.299974 -0.150114)
			(end -0.299974 0.150114)
			(stroke
				(width 0.1)
				(type default)
			)
			(layer "B.Fab")
		)
		(pad "1" smd rect
			(at 0.2667 0)
			(size 0.3048 0.381)
			(layers "B.Cu" "B.Mask" "B.Paste")
			(net "P0V8_SERDES_VDDA_PEX1")
		)
		(pad "2" smd rect
			(at -0.2667 0)
			(size 0.3048 0.381)
			(layers "B.Cu" "B.Mask" "B.Paste")
			(net "GND")
		)
	)
	(footprint ""
		(layer "B.Cu")
		(at 189.049914 -296.8498 180)
		(property "Reference" "C3122"
			(at 0 0 0)
			(layer "B.SilkS")
			(hide yes)
			(effects
				(font
					(size 1.27 1.27)
				)
				(justify mirror)
			)
		)
		(property "Value" ""
			(at 0 0 0)
			(layer "B.Fab")
			(effects
				(font
					(size 1.27 1.27)
				)
				(justify mirror)
			)
		)
		(duplicate_pad_numbers_are_jumpers no)
		(fp_line
			(start 0.299974 0.150114)
			(end 0.299974 -0.150114)
			(stroke
				(width 0.1)
				(type default)
			)
			(layer "B.Fab")
		)
		(fp_line
			(start 0.299974 -0.150114)
			(end -0.299974 -0.150114)
			(stroke
				(width 0.1)
				(type default)
			)
			(layer "B.Fab")
		)
		(fp_line
			(start -0.299974 0.150114)
			(end 0.299974 0.150114)
			(stroke
				(width 0.1)
				(type default)
			)
			(layer "B.Fab")
		)
		(fp_line
			(start -0.299974 -0.150114)
			(end -0.299974 0.150114)
			(stroke
				(width 0.1)
				(type default)
			)
			(layer "B.Fab")
		)
		(pad "1" smd rect
			(at 0.2667 0)
			(size 0.3048 0.381)
			(layers "B.Cu" "B.Mask" "B.Paste")
			(net "P1V25_SERDES_VDDPLL_PEX1")
		)
		(pad "2" smd rect
			(at -0.2667 0)
			(size 0.3048 0.381)
			(layers "B.Cu" "B.Mask" "B.Paste")
			(net "GND")
		)
	)
	(footprint ""
		(layer "B.Cu")
		(at 224.851976 -370.042186)
		(property "Reference" "PR35"
			(at 0 0 0)
			(layer "B.SilkS")
			(hide yes)
			(effects
				(font
					(size 1.27 1.27)
				)
				(justify mirror)
			)
		)
		(property "Value" ""
			(at 0 0 0)
			(layer "B.Fab")
			(effects
				(font
					(size 1.27 1.27)
				)
				(justify mirror)
			)
		)
		(duplicate_pad_numbers_are_jumpers no)
		(fp_line
			(start -0.7874 -0.4064)
			(end -0.7874 0.4064)
			(stroke
				(width 0.1524)
				(type default)
			)
			(layer "B.SilkS")
		)
		(fp_line
			(start -0.7874 0.4064)
			(end 0.7874 0.4064)
			(stroke
				(width 0.1524)
				(type default)
			)
			(layer "B.SilkS")
		)
		(fp_line
			(start 0.7874 -0.4064)
			(end -0.7874 -0.4064)
			(stroke
				(width 0.1524)
				(type default)
			)
			(layer "B.SilkS")
		)
		(fp_line
			(start 0.7874 0.4064)
			(end 0.7874 -0.4064)
			(stroke
				(width 0.1524)
				(type default)
			)
			(layer "B.SilkS")
		)
		(fp_line
			(start -0.67945 -0.3048)
			(end -0.67945 0.3048)
			(stroke
				(width 0.1)
				(type default)
			)
			(layer "B.Fab")
		)
		(fp_line
			(start -0.67945 0.3048)
			(end -0.120396 0.3048)
			(stroke
				(width 0.1)
				(type default)
			)
			(layer "B.Fab")
		)
		(fp_line
			(start -0.12065 -0.3048)
			(end -0.67945 -0.3048)
			(stroke
				(width 0.1)
				(type default)
			)
			(layer "B.Fab")
		)
		(fp_line
			(start -0.12065 -0.2794)
			(end -0.12065 -0.3048)
			(stroke
				(width 0.1)
				(type default)
			)
			(layer "B.Fab")
		)
		(fp_line
			(start -0.120396 0.2794)
			(end 0.12065 0.2794)
			(stroke
				(width 0.1)
				(type default)
			)
			(layer "B.Fab")
		)
		(fp_line
			(start -0.120396 0.3048)
			(end -0.120396 0.2794)
			(stroke
				(width 0.1)
				(type default)
			)
			(layer "B.Fab")
		)
		(fp_line
			(start 0.12065 -0.305054)
			(end 0.12065 -0.2794)
			(stroke
				(width 0.1)
				(type default)
			)
			(layer "B.Fab")
		)
		(fp_line
			(start 0.12065 -0.2794)
			(end -0.12065 -0.2794)
			(stroke
				(width 0.1)
				(type default)
			)
			(layer "B.Fab")
		)
		(fp_line
			(start 0.12065 0.2794)
			(end 0.12065 0.3048)
			(stroke
				(width 0.1)
				(type default)
			)
			(layer "B.Fab")
		)
		(fp_line
			(start 0.12065 0.3048)
			(end 0.67945 0.3048)
			(stroke
				(width 0.1)
				(type default)
			)
			(layer "B.Fab")
		)
		(fp_line
			(start 0.67945 -0.305054)
			(end 0.12065 -0.305054)
			(stroke
				(width 0.1)
				(type default)
			)
			(layer "B.Fab")
		)
		(fp_line
			(start 0.67945 0.3048)
			(end 0.67945 -0.305054)
			(stroke
				(width 0.1)
				(type default)
			)
			(layer "B.Fab")
		)
		(pad "1" smd circle
			(at 0.40005 0 180)
			(size 0 0)
			(layers "B.Cu" "B.Mask" "B.Paste")
			(net "HSC_VDD_2")
		)
		(pad "2" smd circle
			(at -0.40005 0 180)
			(size 0 0)
			(layers "B.Cu" "B.Mask" "B.Paste")
			(net "HSC_VDD")
		)
	)
	(footprint ""
		(layer "B.Cu")
		(at 231.901746 -149.000464)
		(property "Reference" "C2786"
			(at 0 0 0)
			(layer "B.SilkS")
			(hide yes)
			(effects
				(font
					(size 1.27 1.27)
				)
				(justify mirror)
			)
		)
		(property "Value" ""
			(at 0 0 0)
			(layer "B.Fab")
			(effects
				(font
					(size 1.27 1.27)
				)
				(justify mirror)
			)
		)
		(duplicate_pad_numbers_are_jumpers no)
		(fp_line
			(start -0.7874 -0.4064)
			(end -0.7874 0.4064)
			(stroke
				(width 0.1524)
				(type default)
			)
			(layer "B.SilkS")
		)
		(fp_line
			(start -0.7874 0.4064)
			(end 0.7874 0.4064)
			(stroke
				(width 0.1524)
				(type default)
			)
			(layer "B.SilkS")
		)
		(fp_line
			(start 0.7874 -0.4064)
			(end -0.7874 -0.4064)
			(stroke
				(width 0.1524)
				(type default)
			)
			(layer "B.SilkS")
		)
		(fp_line
			(start 0.7874 0.4064)
			(end 0.7874 -0.4064)
			(stroke
				(width 0.1524)
				(type default)
			)
			(layer "B.SilkS")
		)
		(fp_line
			(start -0.67945 -0.3048)
			(end -0.67945 0.3048)
			(stroke
				(width 0.1)
				(type default)
			)
			(layer "B.Fab")
		)
		(fp_line
			(start -0.67945 0.3048)
			(end -0.120396 0.3048)
			(stroke
				(width 0.1)
				(type default)
			)
			(layer "B.Fab")
		)
		(fp_line
			(start -0.12065 -0.3048)
			(end -0.67945 -0.3048)
			(stroke
				(width 0.1)
				(type default)
			)
			(layer "B.Fab")
		)
		(fp_line
			(start -0.12065 -0.2794)
			(end -0.12065 -0.3048)
			(stroke
				(width 0.1)
				(type default)
			)
			(layer "B.Fab")
		)
		(fp_line
			(start -0.120396 0.2794)
			(end 0.12065 0.2794)
			(stroke
				(width 0.1)
				(type default)
			)
			(layer "B.Fab")
		)
		(fp_line
			(start -0.120396 0.3048)
			(end -0.120396 0.2794)
			(stroke
				(width 0.1)
				(type default)
			)
			(layer "B.Fab")
		)
		(fp_line
			(start 0.12065 -0.305054)
			(end 0.12065 -0.2794)
			(stroke
				(width 0.1)
				(type default)
			)
			(layer "B.Fab")
		)
		(fp_line
			(start 0.12065 -0.2794)
			(end -0.12065 -0.2794)
			(stroke
				(width 0.1)
				(type default)
			)
			(layer "B.Fab")
		)
		(fp_line
			(start 0.12065 0.2794)
			(end 0.12065 0.3048)
			(stroke
				(width 0.1)
				(type default)
			)
			(layer "B.Fab")
		)
		(fp_line
			(start 0.12065 0.3048)
			(end 0.67945 0.3048)
			(stroke
				(width 0.1)
				(type default)
			)
			(layer "B.Fab")
		)
		(fp_line
			(start 0.67945 -0.305054)
			(end 0.12065 -0.305054)
			(stroke
				(width 0.1)
				(type default)
			)
			(layer "B.Fab")
		)
		(fp_line
			(start 0.67945 0.3048)
			(end 0.67945 -0.305054)
			(stroke
				(width 0.1)
				(type default)
			)
			(layer "B.Fab")
		)
		(pad "1" smd circle
			(at 0.40005 0 180)
			(size 0 0)
			(layers "B.Cu" "B.Mask" "B.Paste")
			(net "P3V3_CLK_GEN_VDD_CK440_PEX")
		)
		(pad "2" smd circle
			(at -0.40005 0 180)
			(size 0 0)
			(layers "B.Cu" "B.Mask" "B.Paste")
			(net "GND")
		)
	)
	(footprint ""
		(layer "B.Cu")
		(at 49.5554 -155.0416)
		(property "Reference" "R27"
			(at 0 0 0)
			(layer "B.SilkS")
			(hide yes)
			(effects
				(font
					(size 1.27 1.27)
				)
				(justify mirror)
			)
		)
		(property "Value" ""
			(at 0 0 0)
			(layer "B.Fab")
			(effects
				(font
					(size 1.27 1.27)
				)
				(justify mirror)
			)
		)
		(duplicate_pad_numbers_are_jumpers no)
		(fp_line
			(start -0.7874 -0.4064)
			(end -0.7874 0.4064)
			(stroke
				(width 0.1524)
				(type default)
			)
			(layer "B.SilkS")
		)
		(fp_line
			(start -0.7874 0.4064)
			(end 0.7874 0.4064)
			(stroke
				(width 0.1524)
				(type default)
			)
			(layer "B.SilkS")
		)
		(fp_line
			(start 0.7874 -0.4064)
			(end -0.7874 -0.4064)
			(stroke
				(width 0.1524)
				(type default)
			)
			(layer "B.SilkS")
		)
		(fp_line
			(start 0.7874 0.4064)
			(end 0.7874 -0.4064)
			(stroke
				(width 0.1524)
				(type default)
			)
			(layer "B.SilkS")
		)
		(fp_line
			(start -0.67945 -0.3048)
			(end -0.67945 0.3048)
			(stroke
				(width 0.1)
				(type default)
			)
			(layer "B.Fab")
		)
		(fp_line
			(start -0.67945 0.3048)
			(end -0.120396 0.3048)
			(stroke
				(width 0.1)
				(type default)
			)
			(layer "B.Fab")
		)
		(fp_line
			(start -0.12065 -0.3048)
			(end -0.67945 -0.3048)
			(stroke
				(width 0.1)
				(type default)
			)
			(layer "B.Fab")
		)
		(fp_line
			(start -0.12065 -0.2794)
			(end -0.12065 -0.3048)
			(stroke
				(width 0.1)
				(type default)
			)
			(layer "B.Fab")
		)
		(fp_line
			(start -0.120396 0.2794)
			(end 0.12065 0.2794)
			(stroke
				(width 0.1)
				(type default)
			)
			(layer "B.Fab")
		)
		(fp_line
			(start -0.120396 0.3048)
			(end -0.120396 0.2794)
			(stroke
				(width 0.1)
				(type default)
			)
			(layer "B.Fab")
		)
		(fp_line
			(start 0.12065 -0.305054)
			(end 0.12065 -0.2794)
			(stroke
				(width 0.1)
				(type default)
			)
			(layer "B.Fab")
		)
		(fp_line
			(start 0.12065 -0.2794)
			(end -0.12065 -0.2794)
			(stroke
				(width 0.1)
				(type default)
			)
			(layer "B.Fab")
		)
		(fp_line
			(start 0.12065 0.2794)
			(end 0.12065 0.3048)
			(stroke
				(width 0.1)
				(type default)
			)
			(layer "B.Fab")
		)
		(fp_line
			(start 0.12065 0.3048)
			(end 0.67945 0.3048)
			(stroke
				(width 0.1)
				(type default)
			)
			(layer "B.Fab")
		)
		(fp_line
			(start 0.67945 -0.305054)
			(end 0.12065 -0.305054)
			(stroke
				(width 0.1)
				(type default)
			)
			(layer "B.Fab")
		)
		(fp_line
			(start 0.67945 0.3048)
			(end 0.67945 -0.305054)
			(stroke
				(width 0.1)
				(type default)
			)
			(layer "B.Fab")
		)
		(pad "1" smd circle
			(at 0.40005 0 180)
			(size 0 0)
			(layers "B.Cu" "B.Mask" "B.Paste")
			(net "NIC0_SLOT_ID1")
		)
		(pad "2" smd circle
			(at -0.40005 0 180)
			(size 0 0)
			(layers "B.Cu" "B.Mask" "B.Paste")
			(net "P3V3_NIC0")
		)
	)
	(footprint ""
		(layer "B.Cu")
		(at 379.857 -244.729 180)
		(property "Reference" "R932"
			(at 0 0 0)
			(layer "B.SilkS")
			(hide yes)
			(effects
				(font
					(size 1.27 1.27)
				)
				(justify mirror)
			)
		)
		(property "Value" ""
			(at 0 0 0)
			(layer "B.Fab")
			(effects
				(font
					(size 1.27 1.27)
				)
				(justify mirror)
			)
		)
		(duplicate_pad_numbers_are_jumpers no)
		(fp_line
			(start 0.7874 0.4064)
			(end 0.7874 -0.4064)
			(stroke
				(width 0.1524)
				(type default)
			)
			(layer "B.SilkS")
		)
		(fp_line
			(start 0.7874 -0.4064)
			(end -0.7874 -0.4064)
			(stroke
				(width 0.1524)
				(type default)
			)
			(layer "B.SilkS")
		)
		(fp_line
			(start -0.7874 0.4064)
			(end 0.7874 0.4064)
			(stroke
				(width 0.1524)
				(type default)
			)
			(layer "B.SilkS")
		)
		(fp_line
			(start -0.7874 -0.4064)
			(end -0.7874 0.4064)
			(stroke
				(width 0.1524)
				(type default)
			)
			(layer "B.SilkS")
		)
		(fp_line
			(start 0.67945 0.3048)
			(end 0.67945 -0.305054)
			(stroke
				(width 0.1)
				(type default)
			)
			(layer "B.Fab")
		)
		(fp_line
			(start 0.67945 -0.305054)
			(end 0.12065 -0.305054)
			(stroke
				(width 0.1)
				(type default)
			)
			(layer "B.Fab")
		)
		(fp_line
			(start 0.12065 0.3048)
			(end 0.67945 0.3048)
			(stroke
				(width 0.1)
				(type default)
			)
			(layer "B.Fab")
		)
		(fp_line
			(start 0.12065 0.2794)
			(end 0.12065 0.3048)
			(stroke
				(width 0.1)
				(type default)
			)
			(layer "B.Fab")
		)
		(fp_line
			(start 0.12065 -0.2794)
			(end -0.12065 -0.2794)
			(stroke
				(width 0.1)
				(type default)
			)
			(layer "B.Fab")
		)
		(fp_line
			(start 0.12065 -0.305054)
			(end 0.12065 -0.2794)
			(stroke
				(width 0.1)
				(type default)
			)
			(layer "B.Fab")
		)
		(fp_line
			(start -0.120396 0.3048)
			(end -0.120396 0.2794)
			(stroke
				(width 0.1)
				(type default)
			)
			(layer "B.Fab")
		)
		(fp_line
			(start -0.120396 0.2794)
			(end 0.12065 0.2794)
			(stroke
				(width 0.1)
				(type default)
			)
			(layer "B.Fab")
		)
		(fp_line
			(start -0.12065 -0.2794)
			(end -0.12065 -0.3048)
			(stroke
				(width 0.1)
				(type default)
			)
			(layer "B.Fab")
		)
		(fp_line
			(start -0.12065 -0.3048)
			(end -0.67945 -0.3048)
			(stroke
				(width 0.1)
				(type default)
			)
			(layer "B.Fab")
		)
		(fp_line
			(start -0.67945 0.3048)
			(end -0.120396 0.3048)
			(stroke
				(width 0.1)
				(type default)
			)
			(layer "B.Fab")
		)
		(fp_line
			(start -0.67945 -0.3048)
			(end -0.67945 0.3048)
			(stroke
				(width 0.1)
				(type default)
			)
			(layer "B.Fab")
		)
		(pad "1" smd circle
			(at 0.40005 0)
			(size 0 0)
			(layers "B.Cu" "B.Mask" "B.Paste")
			(net "UART_PEX1_SDB_BUF_TX")
		)
		(pad "2" smd circle
			(at -0.40005 0)
			(size 0 0)
			(layers "B.Cu" "B.Mask" "B.Paste")
			(net "P3V3_AUX")
		)
	)
	(footprint ""
		(layer "B.Cu")
		(at 73.400158 -110.978696)
		(property "Reference" "C866"
			(at 0 0 0)
			(layer "B.SilkS")
			(hide yes)
			(effects
				(font
					(size 1.27 1.27)
				)
				(justify mirror)
			)
		)
		(property "Value" ""
			(at 0 0 0)
			(layer "B.Fab")
			(effects
				(font
					(size 1.27 1.27)
				)
				(justify mirror)
			)
		)
		(duplicate_pad_numbers_are_jumpers no)
		(fp_line
			(start -0.299974 -0.150114)
			(end -0.299974 0.150114)
			(stroke
				(width 0.1)
				(type default)
			)
			(layer "B.Fab")
		)
		(fp_line
			(start -0.299974 0.150114)
			(end 0.299974 0.150114)
			(stroke
				(width 0.1)
				(type default)
			)
			(layer "B.Fab")
		)
		(fp_line
			(start 0.299974 -0.150114)
			(end -0.299974 -0.150114)
			(stroke
				(width 0.1)
				(type default)
			)
			(layer "B.Fab")
		)
		(fp_line
			(start 0.299974 0.150114)
			(end 0.299974 -0.150114)
			(stroke
				(width 0.1)
				(type default)
			)
			(layer "B.Fab")
		)
		(pad "1" smd rect
			(at 0.2667 0 180)
			(size 0.3048 0.381)
			(layers "B.Cu" "B.Mask" "B.Paste")
			(net "P12V_NIC1")
		)
		(pad "2" smd rect
			(at -0.2667 0 180)
			(size 0.3048 0.381)
			(layers "B.Cu" "B.Mask" "B.Paste")
			(net "GND")
		)
	)
	(footprint ""
		(layer "B.Cu")
		(at 46.355 -301.0408)
		(property "Reference" "C3001"
			(at 0 0 0)
			(layer "B.SilkS")
			(hide yes)
			(effects
				(font
					(size 1.27 1.27)
				)
				(justify mirror)
			)
		)
		(property "Value" ""
			(at 0 0 0)
			(layer "B.Fab")
			(effects
				(font
					(size 1.27 1.27)
				)
				(justify mirror)
			)
		)
		(duplicate_pad_numbers_are_jumpers no)
		(fp_line
			(start -0.299974 -0.150114)
			(end -0.299974 0.150114)
			(stroke
				(width 0.1)
				(type default)
			)
			(layer "B.Fab")
		)
		(fp_line
			(start -0.299974 0.150114)
			(end 0.299974 0.150114)
			(stroke
				(width 0.1)
				(type default)
			)
			(layer "B.Fab")
		)
		(fp_line
			(start 0.299974 -0.150114)
			(end -0.299974 -0.150114)
			(stroke
				(width 0.1)
				(type default)
			)
			(layer "B.Fab")
		)
		(fp_line
			(start 0.299974 0.150114)
			(end 0.299974 -0.150114)
			(stroke
				(width 0.1)
				(type default)
			)
			(layer "B.Fab")
		)
		(pad "1" smd rect
			(at 0.2667 0 180)
			(size 0.3048 0.381)
			(layers "B.Cu" "B.Mask" "B.Paste")
			(net "P1V8_PEX")
		)
		(pad "2" smd rect
			(at -0.2667 0 180)
			(size 0.3048 0.381)
			(layers "B.Cu" "B.Mask" "B.Paste")
			(net "GND")
		)
	)
	(footprint ""
		(layer "B.Cu")
		(at 116.788184 -316.868048 180)
		(property "Reference" "C4210"
			(at 0 0 0)
			(layer "B.SilkS")
			(hide yes)
			(effects
				(font
					(size 1.27 1.27)
				)
				(justify mirror)
			)
		)
		(property "Value" ""
			(at 0 0 0)
			(layer "B.Fab")
			(effects
				(font
					(size 1.27 1.27)
				)
				(justify mirror)
			)
		)
		(duplicate_pad_numbers_are_jumpers no)
		(fp_line
			(start 0.299974 0.150114)
			(end 0.299974 -0.150114)
			(stroke
				(width 0.1)
				(type default)
			)
			(layer "B.Fab")
		)
		(fp_line
			(start 0.299974 -0.150114)
			(end -0.299974 -0.150114)
			(stroke
				(width 0.1)
				(type default)
			)
			(layer "B.Fab")
		)
		(fp_line
			(start -0.299974 0.150114)
			(end 0.299974 0.150114)
			(stroke
				(width 0.1)
				(type default)
			)
			(layer "B.Fab")
		)
		(fp_line
			(start -0.299974 -0.150114)
			(end -0.299974 0.150114)
			(stroke
				(width 0.1)
				(type default)
			)
			(layer "B.Fab")
		)
		(pad "1" smd rect
			(at 0.2667 0)
			(size 0.3048 0.381)
			(layers "B.Cu" "B.Mask" "B.Paste")
			(net "P0V8_SERDES_VDDA_PEX0")
		)
		(pad "2" smd rect
			(at -0.2667 0)
			(size 0.3048 0.381)
			(layers "B.Cu" "B.Mask" "B.Paste")
			(net "GND")
		)
	)
	(footprint ""
		(layer "B.Cu")
		(at 342.09355 -221.98711 90)
		(property "Reference" "C2036"
			(at 0 0 90)
			(layer "B.SilkS")
			(hide yes)
			(effects
				(font
					(size 1.27 1.27)
				)
				(justify mirror)
			)
		)
		(property "Value" ""
			(at 0 0 90)
			(layer "B.Fab")
			(effects
				(font
					(size 1.27 1.27)
				)
				(justify mirror)
			)
		)
		(duplicate_pad_numbers_are_jumpers no)
		(fp_line
			(start 0.69215 -0.2921)
			(end -0.69215 -0.2921)
			(stroke
				(width 0.1524)
				(type default)
			)
			(layer "B.SilkS")
		)
		(fp_line
			(start -0.69215 -0.2921)
			(end -0.69215 0.2921)
			(stroke
				(width 0.1524)
				(type default)
			)
			(layer "B.SilkS")
		)
		(fp_line
			(start 0.69215 0.2921)
			(end 0.69215 -0.2921)
			(stroke
				(width 0.1524)
				(type default)
			)
			(layer "B.SilkS")
		)
		(fp_line
			(start -0.69215 0.2921)
			(end 0.69215 0.2921)
			(stroke
				(width 0.1524)
				(type default)
			)
			(layer "B.SilkS")
		)
		(fp_line
			(start 0.51435 -0.2794)
			(end -0.51435 -0.2794)
			(stroke
				(width 0.1)
				(type default)
			)
			(layer "B.Fab")
		)
		(fp_line
			(start -0.51435 -0.2794)
			(end -0.51435 0.2794)
			(stroke
				(width 0.1)
				(type default)
			)
			(layer "B.Fab")
		)
		(fp_line
			(start 0.51435 0.2794)
			(end 0.51435 -0.2794)
			(stroke
				(width 0.1)
				(type default)
			)
			(layer "B.Fab")
		)
		(fp_line
			(start -0.51435 0.2794)
			(end 0.51435 0.2794)
			(stroke
				(width 0.1)
				(type default)
			)
			(layer "B.Fab")
		)
		(pad "1" smd circle
			(at 0.40005 0 270)
			(size 0 0)
			(layers "B.Cu" "B.Mask" "B.Paste")
			(net "P3V3_FPGA_VCCIO0")
		)
		(pad "2" smd circle
			(at -0.40005 0 270)
			(size 0 0)
			(layers "B.Cu" "B.Mask" "B.Paste")
			(net "GND")
		)
		(zone
			(layer "B.Cu")
			(hatch none 0.5)
			(connect_pads
				(clearance 0)
			)
			(min_thickness 0.25)
			(keepout
				(tracks not_allowed)
				(vias allowed)
				(pads allowed)
				(copperpour not_allowed)
				(footprints allowed)
			)
			(placement
				(enabled no)
				(sheetname "")
			)
			(fill
				(thermal_gap 0.5)
				(thermal_bridge_width 0.5)
				(island_removal_mode 0)
			)
			(polygon
				(pts
					(xy 342.18118 -222.17761) (xy 342.239346 -222.08617) (xy 342.239346 -221.88678) (xy 342.18118 -221.79661)
					(xy 342.00592 -221.79661) (xy 341.9475 -221.88678) (xy 341.9475 -222.08617) (xy 342.005666 -222.17761)
				)
			)
		)
	)
	(footprint ""
		(layer "B.Cu")
		(at 224.005394 -444.94831 180)
		(property "Reference" "X77"
			(at 0.1778 -1.92913 180)
			(unlocked yes)
			(layer "B.SilkS")
			(effects
				(font
					(size 0.7874 0.5842)
					(thickness 0.1524)
				)
				(justify left mirror)
			)
		)
		(property "Value" ""
			(at 0 0 0)
			(layer "B.Fab")
			(effects
				(font
					(size 1.27 1.27)
				)
				(justify mirror)
			)
		)
		(property "Device Type" "TP_TDR_4P_FTS_MPKT4_H025P0200_IO_TP15_TP_TDR_4P_DIP"
			(at -1.30175 1.27 90)
			(unlocked yes)
			(layer "B.Fab")
			(hide yes)
			(effects
				(font
					(size 0.635 0.4064)
					(thickness 0.1524)
				)
				(justify mirror)
			)
		)
		(property "User Part Number" "TP15"
			(at -1.30175 1.27 90)
			(unlocked yes)
			(layer "Cmts.User")
			(hide yes)
			(effects
				(font
					(size 0.635 0.4064)
					(thickness 0.1524)
				)
				(justify mirror)
			)
		)
		(duplicate_pad_numbers_are_jumpers no)
		(fp_line
			(start 0 3.81)
			(end -2.54 3.81)
			(stroke
				(width 0.1524)
				(type default)
			)
			(layer "B.SilkS")
		)
		(fp_line
			(start 0 3.175)
			(end 0 3.81)
			(stroke
				(width 0.1524)
				(type default)
			)
			(layer "B.SilkS")
		)
		(fp_line
			(start 0 0.635)
			(end 0 1.905)
			(stroke
				(width 0.1524)
				(type default)
			)
			(layer "B.SilkS")
		)
		(fp_line
			(start 0 -1.27)
			(end 0 -0.635)
			(stroke
				(width 0.1524)
				(type default)
			)
			(layer "B.SilkS")
		)
		(fp_line
			(start -2.54 3.81)
			(end -2.54 3.6703)
			(stroke
				(width 0.1524)
				(type default)
			)
			(layer "B.SilkS")
		)
		(fp_line
			(start -2.54 1.4097)
			(end -2.54 1.1303)
			(stroke
				(width 0.1524)
				(type default)
			)
			(layer "B.SilkS")
		)
		(fp_line
			(start -2.54 -1.1303)
			(end -2.54 -1.27)
			(stroke
				(width 0.1524)
				(type default)
			)
			(layer "B.SilkS")
		)
		(fp_line
			(start -2.54 -1.27)
			(end 0 -1.27)
			(stroke
				(width 0.1524)
				(type default)
			)
			(layer "B.SilkS")
		)
		(fp_poly
			(pts
				(xy 0.761746 0) (xy 2.285746 -0.762) (xy 2.285746 0.762)
			)
			(stroke
				(width 0)
				(type default)
			)
			(fill yes)
			(layer "B.SilkS")
		)
		(fp_line
			(start 0 3.81)
			(end -2.54 3.81)
			(stroke
				(width 0.1)
				(type default)
			)
			(layer "B.Fab")
		)
		(fp_line
			(start 0 -1.27)
			(end 0 3.81)
			(stroke
				(width 0.1)
				(type default)
			)
			(layer "B.Fab")
		)
		(fp_line
			(start -2.54 3.81)
			(end -2.54 -1.27)
			(stroke
				(width 0.1)
				(type default)
			)
			(layer "B.Fab")
		)
		(fp_line
			(start -2.54 -1.27)
			(end 0 -1.27)
			(stroke
				(width 0.1)
				(type default)
			)
			(layer "B.Fab")
		)
		(fp_poly
			(pts
				(xy 0.761746 0) (xy 2.285746 -0.762) (xy 2.285746 0.762)
			)
			(stroke
				(width 0)
				(type default)
			)
			(fill yes)
			(layer "B.Fab")
		)
		(pad "1" thru_hole circle
			(at 0 0)
			(size 1.0033 1.0033)
			(drill 0.249936)
			(layers "*.Cu" "*.Mask")
			(remove_unused_layers no)
			(net "TDR_DIFF_100_IN5_DIN")
			(clearance 0.10795)
			(padstack
				(mode front_inner_back)
				(layer "Inner"
					(shape circle)
					(size 0.8001 0.8001)
					(clearance 0.1524)
				)
				(layer "B.Cu"
					(shape circle)
					(size 1.0033 1.0033)
					(thermal_gap 0.10795)
					(clearance 0.10795)
				)
			)
		)
		(pad "2" thru_hole circle
			(at -2.54 0)
			(size 1.9939 1.9939)
			(drill 0.249936)
			(layers "*.Cu" "*.Mask")
			(remove_unused_layers no)
			(net "COUPON_GND1")
			(clearance 0.10795)
			(padstack
				(mode front_inner_back)
				(layer "Inner"
					(shape circle)
					(size 0.8001 0.8001)
					(clearance 0.1524)
				)
				(layer "B.Cu"
					(shape circle)
					(size 1.9939 1.9939)
					(thermal_gap 0.10795)
					(clearance 0.10795)
				)
			)
		)
		(pad "3" thru_hole circle
			(at -2.54 2.54)
			(size 1.9939 1.9939)
			(drill 0.249936)
			(layers "*.Cu" "*.Mask")
			(remove_unused_layers no)
			(net "COUPON_GND1")
			(clearance 0.10795)
			(padstack
				(mode front_inner_back)
				(layer "Inner"
					(shape circle)
					(size 0.8001 0.8001)
					(clearance 0.1524)
				)
				(layer "B.Cu"
					(shape circle)
					(size 1.9939 1.9939)
					(thermal_gap 0.10795)
					(clearance 0.10795)
				)
			)
		)
		(pad "4" thru_hole circle
			(at 0 2.54)
			(size 1.0033 1.0033)
			(drill 0.249936)
			(layers "*.Cu" "*.Mask")
			(remove_unused_layers no)
			(net "TDR_DIFF_100_IN5_DIP")
			(clearance 0.10795)
			(padstack
				(mode front_inner_back)
				(layer "Inner"
					(shape circle)
					(size 0.8001 0.8001)
					(clearance 0.1524)
				)
				(layer "B.Cu"
					(shape circle)
					(size 1.0033 1.0033)
					(thermal_gap 0.10795)
					(clearance 0.10795)
				)
			)
		)
	)
	(footprint ""
		(layer "B.Cu")
		(at 125.357128 -285.600648 -90)
		(property "Reference" "PR7178"
			(at 0 0 90)
			(layer "B.SilkS")
			(hide yes)
			(effects
				(font
					(size 1.27 1.27)
				)
				(justify mirror)
			)
		)
		(property "Value" ""
			(at 0 0 90)
			(layer "B.Fab")
			(effects
				(font
					(size 1.27 1.27)
				)
				(justify mirror)
			)
		)
		(duplicate_pad_numbers_are_jumpers no)
		(fp_line
			(start -0.7874 0.4064)
			(end 0.7874 0.4064)
			(stroke
				(width 0.1524)
				(type default)
			)
			(layer "B.SilkS")
		)
		(fp_line
			(start 0.7874 0.4064)
			(end 0.7874 -0.4064)
			(stroke
				(width 0.1524)
				(type default)
			)
			(layer "B.SilkS")
		)
		(fp_line
			(start -0.7874 -0.4064)
			(end -0.7874 0.4064)
			(stroke
				(width 0.1524)
				(type default)
			)
			(layer "B.SilkS")
		)
		(fp_line
			(start 0.7874 -0.4064)
			(end -0.7874 -0.4064)
			(stroke
				(width 0.1524)
				(type default)
			)
			(layer "B.SilkS")
		)
		(fp_line
			(start -0.67945 0.3048)
			(end -0.120396 0.3048)
			(stroke
				(width 0.1)
				(type default)
			)
			(layer "B.Fab")
		)
		(fp_line
			(start -0.120396 0.3048)
			(end -0.120396 0.2794)
			(stroke
				(width 0.1)
				(type default)
			)
			(layer "B.Fab")
		)
		(fp_line
			(start 0.12065 0.3048)
			(end 0.67945 0.3048)
			(stroke
				(width 0.1)
				(type default)
			)
			(layer "B.Fab")
		)
		(fp_line
			(start 0.67945 0.3048)
			(end 0.67945 -0.305054)
			(stroke
				(width 0.1)
				(type default)
			)
			(layer "B.Fab")
		)
		(fp_line
			(start -0.120396 0.2794)
			(end 0.12065 0.2794)
			(stroke
				(width 0.1)
				(type default)
			)
			(layer "B.Fab")
		)
		(fp_line
			(start 0.12065 0.2794)
			(end 0.12065 0.3048)
			(stroke
				(width 0.1)
				(type default)
			)
			(layer "B.Fab")
		)
		(fp_line
			(start -0.12065 -0.2794)
			(end -0.12065 -0.3048)
			(stroke
				(width 0.1)
				(type default)
			)
			(layer "B.Fab")
		)
		(fp_line
			(start 0.12065 -0.2794)
			(end -0.12065 -0.2794)
			(stroke
				(width 0.1)
				(type default)
			)
			(layer "B.Fab")
		)
		(fp_line
			(start -0.67945 -0.3048)
			(end -0.67945 0.3048)
			(stroke
				(width 0.1)
				(type default)
			)
			(layer "B.Fab")
		)
		(fp_line
			(start -0.12065 -0.3048)
			(end -0.67945 -0.3048)
			(stroke
				(width 0.1)
				(type default)
			)
			(layer "B.Fab")
		)
		(fp_line
			(start 0.12065 -0.305054)
			(end 0.12065 -0.2794)
			(stroke
				(width 0.1)
				(type default)
			)
			(layer "B.Fab")
		)
		(fp_line
			(start 0.67945 -0.305054)
			(end 0.12065 -0.305054)
			(stroke
				(width 0.1)
				(type default)
			)
			(layer "B.Fab")
		)
		(pad "1" smd circle
			(at 0.40005 0 90)
			(size 0 0)
			(layers "B.Cu" "B.Mask" "B.Paste")
			(net "P0V8_PEX1_PVCC")
		)
		(pad "2" smd circle
			(at -0.40005 0 90)
			(size 0 0)
			(layers "B.Cu" "B.Mask" "B.Paste")
			(net "P5V_AUX")
		)
	)
	(footprint ""
		(layer "B.Cu")
		(at 425.841922 -103.104696 180)
		(property "Reference" "R373"
			(at 0 0 0)
			(layer "B.SilkS")
			(hide yes)
			(effects
				(font
					(size 1.27 1.27)
				)
				(justify mirror)
			)
		)
		(property "Value" ""
			(at 0 0 0)
			(layer "B.Fab")
			(effects
				(font
					(size 1.27 1.27)
				)
				(justify mirror)
			)
		)
		(duplicate_pad_numbers_are_jumpers no)
		(fp_line
			(start 0.7874 0.4064)
			(end 0.7874 -0.4064)
			(stroke
				(width 0.1524)
				(type default)
			)
			(layer "B.SilkS")
		)
		(fp_line
			(start 0.7874 -0.4064)
			(end -0.7874 -0.4064)
			(stroke
				(width 0.1524)
				(type default)
			)
			(layer "B.SilkS")
		)
		(fp_line
			(start -0.7874 0.4064)
			(end 0.7874 0.4064)
			(stroke
				(width 0.1524)
				(type default)
			)
			(layer "B.SilkS")
		)
		(fp_line
			(start -0.7874 -0.4064)
			(end -0.7874 0.4064)
			(stroke
				(width 0.1524)
				(type default)
			)
			(layer "B.SilkS")
		)
		(fp_line
			(start 0.67945 0.3048)
			(end 0.67945 -0.305054)
			(stroke
				(width 0.1)
				(type default)
			)
			(layer "B.Fab")
		)
		(fp_line
			(start 0.67945 -0.305054)
			(end 0.12065 -0.305054)
			(stroke
				(width 0.1)
				(type default)
			)
			(layer "B.Fab")
		)
		(fp_line
			(start 0.12065 0.3048)
			(end 0.67945 0.3048)
			(stroke
				(width 0.1)
				(type default)
			)
			(layer "B.Fab")
		)
		(fp_line
			(start 0.12065 0.2794)
			(end 0.12065 0.3048)
			(stroke
				(width 0.1)
				(type default)
			)
			(layer "B.Fab")
		)
		(fp_line
			(start 0.12065 -0.2794)
			(end -0.12065 -0.2794)
			(stroke
				(width 0.1)
				(type default)
			)
			(layer "B.Fab")
		)
		(fp_line
			(start 0.12065 -0.305054)
			(end 0.12065 -0.2794)
			(stroke
				(width 0.1)
				(type default)
			)
			(layer "B.Fab")
		)
		(fp_line
			(start -0.120396 0.3048)
			(end -0.120396 0.2794)
			(stroke
				(width 0.1)
				(type default)
			)
			(layer "B.Fab")
		)
		(fp_line
			(start -0.120396 0.2794)
			(end 0.12065 0.2794)
			(stroke
				(width 0.1)
				(type default)
			)
			(layer "B.Fab")
		)
		(fp_line
			(start -0.12065 -0.2794)
			(end -0.12065 -0.3048)
			(stroke
				(width 0.1)
				(type default)
			)
			(layer "B.Fab")
		)
		(fp_line
			(start -0.12065 -0.3048)
			(end -0.67945 -0.3048)
			(stroke
				(width 0.1)
				(type default)
			)
			(layer "B.Fab")
		)
		(fp_line
			(start -0.67945 0.3048)
			(end -0.120396 0.3048)
			(stroke
				(width 0.1)
				(type default)
			)
			(layer "B.Fab")
		)
		(fp_line
			(start -0.67945 -0.3048)
			(end -0.67945 0.3048)
			(stroke
				(width 0.1)
				(type default)
			)
			(layer "B.Fab")
		)
		(pad "1" smd circle
			(at 0.40005 0)
			(size 0 0)
			(layers "B.Cu" "B.Mask" "B.Paste")
			(net "NCSI_NIC7_RXD0")
		)
		(pad "2" smd circle
			(at -0.40005 0)
			(size 0 0)
			(layers "B.Cu" "B.Mask" "B.Paste")
			(net "GND")
		)
	)
	(footprint ""
		(layer "B.Cu")
		(at 70.099936 -290.674806 180)
		(property "Reference" "C2994"
			(at 0 0 0)
			(layer "B.SilkS")
			(hide yes)
			(effects
				(font
					(size 1.27 1.27)
				)
				(justify mirror)
			)
		)
		(property "Value" ""
			(at 0 0 0)
			(layer "B.Fab")
			(effects
				(font
					(size 1.27 1.27)
				)
				(justify mirror)
			)
		)
		(duplicate_pad_numbers_are_jumpers no)
		(fp_line
			(start 0.299974 0.150114)
			(end 0.299974 -0.150114)
			(stroke
				(width 0.1)
				(type default)
			)
			(layer "B.Fab")
		)
		(fp_line
			(start 0.299974 -0.150114)
			(end -0.299974 -0.150114)
			(stroke
				(width 0.1)
				(type default)
			)
			(layer "B.Fab")
		)
		(fp_line
			(start -0.299974 0.150114)
			(end 0.299974 0.150114)
			(stroke
				(width 0.1)
				(type default)
			)
			(layer "B.Fab")
		)
		(fp_line
			(start -0.299974 -0.150114)
			(end -0.299974 0.150114)
			(stroke
				(width 0.1)
				(type default)
			)
			(layer "B.Fab")
		)
		(pad "1" smd rect
			(at 0.2667 0)
			(size 0.3048 0.381)
			(layers "B.Cu" "B.Mask" "B.Paste")
			(net "P1V8_PEX")
		)
		(pad "2" smd rect
			(at -0.2667 0)
			(size 0.3048 0.381)
			(layers "B.Cu" "B.Mask" "B.Paste")
			(net "GND")
		)
	)
	(footprint ""
		(layer "B.Cu")
		(at 443.802262 -457.938886 90)
		(property "Reference" "J49"
			(at 3.5052 -5.552948 90)
			(unlocked yes)
			(layer "B.SilkS")
			(effects
				(font
					(size 0.7874 0.5842)
					(thickness 0.1524)
				)
				(justify left mirror)
			)
		)
		(property "Value" ""
			(at 0 0 90)
			(layer "B.Fab")
			(effects
				(font
					(size 1.27 1.27)
				)
				(justify mirror)
			)
		)
		(duplicate_pad_numbers_are_jumpers no)
		(fp_line
			(start 3.330702 -4.771136)
			(end -3.330702 -4.771136)
			(stroke
				(width 0.1524)
				(type default)
			)
			(layer "B.SilkS")
		)
		(fp_line
			(start -3.330702 -4.771136)
			(end 0 4.011168)
			(stroke
				(width 0.1524)
				(type default)
			)
			(layer "B.SilkS")
		)
		(fp_line
			(start 0 4.011168)
			(end 3.330702 -4.771136)
			(stroke
				(width 0.1524)
				(type default)
			)
			(layer "B.SilkS")
		)
		(fp_line
			(start 3.330702 -4.771136)
			(end -3.330702 -4.771136)
			(stroke
				(width 0.1)
				(type default)
			)
			(layer "B.Fab")
		)
		(fp_line
			(start -3.330702 -4.771136)
			(end 0 4.011168)
			(stroke
				(width 0.1)
				(type default)
			)
			(layer "B.Fab")
		)
		(fp_line
			(start 0 4.011168)
			(end 3.330702 -4.771136)
			(stroke
				(width 0.1)
				(type default)
			)
			(layer "B.Fab")
		)
		(pad "1" thru_hole circle
			(at 0 0 270)
			(size 2.159 2.159)
			(drill 1.7018)
			(layers "*.Cu" "*.Mask")
			(remove_unused_layers no)
			(net "COUPON_GND1")
			(clearance 0.0254)
			(thermal_gap 0.0254)
		)
		(pad "2" thru_hole circle
			(at 1.27 -3.348736 270)
			(size 2.159 2.159)
			(drill 1.7018)
			(layers "*.Cu" "*.Mask")
			(remove_unused_layers no)
			(net "TDR_SE_50_OHM_IN3")
			(clearance 0.0254)
			(thermal_gap 0.0254)
		)
		(pad "3" thru_hole circle
			(at -1.27 -3.348736 270)
			(size 2.159 2.159)
			(drill 1.7018)
			(layers "*.Cu" "*.Mask")
			(remove_unused_layers no)
			(net "TDR_SE_50_OHM_IN3")
			(clearance 0.0254)
			(thermal_gap 0.0254)
		)
	)
	(footprint ""
		(layer "B.Cu")
		(at 181.92496 -305.399948 -90)
		(property "Reference" "C3129"
			(at 0 0 90)
			(layer "B.SilkS")
			(hide yes)
			(effects
				(font
					(size 1.27 1.27)
				)
				(justify mirror)
			)
		)
		(property "Value" ""
			(at 0 0 90)
			(layer "B.Fab")
			(effects
				(font
					(size 1.27 1.27)
				)
				(justify mirror)
			)
		)
		(duplicate_pad_numbers_are_jumpers no)
		(fp_line
			(start -0.299974 0.150114)
			(end 0.299974 0.150114)
			(stroke
				(width 0.1)
				(type default)
			)
			(layer "B.Fab")
		)
		(fp_line
			(start 0.299974 0.150114)
			(end 0.299974 -0.150114)
			(stroke
				(width 0.1)
				(type default)
			)
			(layer "B.Fab")
		)
		(fp_line
			(start -0.299974 -0.150114)
			(end -0.299974 0.150114)
			(stroke
				(width 0.1)
				(type default)
			)
			(layer "B.Fab")
		)
		(fp_line
			(start 0.299974 -0.150114)
			(end -0.299974 -0.150114)
			(stroke
				(width 0.1)
				(type default)
			)
			(layer "B.Fab")
		)
		(pad "1" smd rect
			(at 0.2667 0 90)
			(size 0.3048 0.381)
			(layers "B.Cu" "B.Mask" "B.Paste")
			(net "P1V25_SERDES_VDDPLL_PEX1")
		)
		(pad "2" smd rect
			(at -0.2667 0 90)
			(size 0.3048 0.381)
			(layers "B.Cu" "B.Mask" "B.Paste")
			(net "GND")
		)
	)
	(footprint ""
		(layer "B.Cu")
		(at 406.524968 -293.99992 90)
		(property "Reference" "C1908"
			(at 0 0 90)
			(layer "B.SilkS")
			(hide yes)
			(effects
				(font
					(size 1.27 1.27)
				)
				(justify mirror)
			)
		)
		(property "Value" ""
			(at 0 0 90)
			(layer "B.Fab")
			(effects
				(font
					(size 1.27 1.27)
				)
				(justify mirror)
			)
		)
		(duplicate_pad_numbers_are_jumpers no)
		(fp_line
			(start 0.299974 -0.150114)
			(end -0.299974 -0.150114)
			(stroke
				(width 0.1)
				(type default)
			)
			(layer "B.Fab")
		)
		(fp_line
			(start -0.299974 -0.150114)
			(end -0.299974 0.150114)
			(stroke
				(width 0.1)
				(type default)
			)
			(layer "B.Fab")
		)
		(fp_line
			(start 0.299974 0.150114)
			(end 0.299974 -0.150114)
			(stroke
				(width 0.1)
				(type default)
			)
			(layer "B.Fab")
		)
		(fp_line
			(start -0.299974 0.150114)
			(end 0.299974 0.150114)
			(stroke
				(width 0.1)
				(type default)
			)
			(layer "B.Fab")
		)
		(pad "1" smd rect
			(at 0.2667 0 270)
			(size 0.3048 0.381)
			(layers "B.Cu" "B.Mask" "B.Paste")
			(net "P0V8_PEX3")
		)
		(pad "2" smd rect
			(at -0.2667 0 270)
			(size 0.3048 0.381)
			(layers "B.Cu" "B.Mask" "B.Paste")
			(net "GND")
		)
	)
	(footprint ""
		(layer "B.Cu")
		(at 168.625012 -286.399732 90)
		(property "Reference" "C3146"
			(at 0 0 90)
			(layer "B.SilkS")
			(hide yes)
			(effects
				(font
					(size 1.27 1.27)
				)
				(justify mirror)
			)
		)
		(property "Value" ""
			(at 0 0 90)
			(layer "B.Fab")
			(effects
				(font
					(size 1.27 1.27)
				)
				(justify mirror)
			)
		)
		(duplicate_pad_numbers_are_jumpers no)
		(fp_line
			(start 0.299974 -0.150114)
			(end -0.299974 -0.150114)
			(stroke
				(width 0.1)
				(type default)
			)
			(layer "B.Fab")
		)
		(fp_line
			(start -0.299974 -0.150114)
			(end -0.299974 0.150114)
			(stroke
				(width 0.1)
				(type default)
			)
			(layer "B.Fab")
		)
		(fp_line
			(start 0.299974 0.150114)
			(end 0.299974 -0.150114)
			(stroke
				(width 0.1)
				(type default)
			)
			(layer "B.Fab")
		)
		(fp_line
			(start -0.299974 0.150114)
			(end 0.299974 0.150114)
			(stroke
				(width 0.1)
				(type default)
			)
			(layer "B.Fab")
		)
		(pad "1" smd rect
			(at 0.2667 0 270)
			(size 0.3048 0.381)
			(layers "B.Cu" "B.Mask" "B.Paste")
			(net "P1V25_SERDES_VDDPLL_PEX1")
		)
		(pad "2" smd rect
			(at -0.2667 0 270)
			(size 0.3048 0.381)
			(layers "B.Cu" "B.Mask" "B.Paste")
			(net "GND")
		)
	)
	(footprint ""
		(layer "B.Cu")
		(at 364.807754 -324.163944 -90)
		(property "Reference" "C4370"
			(at 0 0 90)
			(layer "B.SilkS")
			(hide yes)
			(effects
				(font
					(size 1.27 1.27)
				)
				(justify mirror)
			)
		)
		(property "Value" ""
			(at 0 0 90)
			(layer "B.Fab")
			(effects
				(font
					(size 1.27 1.27)
				)
				(justify mirror)
			)
		)
		(duplicate_pad_numbers_are_jumpers no)
		(fp_line
			(start -1.2954 0.5842)
			(end 1.2954 0.5842)
			(stroke
				(width 0.1524)
				(type default)
			)
			(layer "B.SilkS")
		)
		(fp_line
			(start 1.2954 0.5842)
			(end 1.2954 -0.5842)
			(stroke
				(width 0.1524)
				(type default)
			)
			(layer "B.SilkS")
		)
		(fp_line
			(start -1.2954 -0.5842)
			(end -1.2954 0.5842)
			(stroke
				(width 0.1524)
				(type default)
			)
			(layer "B.SilkS")
		)
		(fp_line
			(start 1.2954 -0.5842)
			(end -1.2954 -0.5842)
			(stroke
				(width 0.1524)
				(type default)
			)
			(layer "B.SilkS")
		)
		(fp_line
			(start -0.8636 0.4572)
			(end 0.8636 0.4572)
			(stroke
				(width 0.1)
				(type default)
			)
			(layer "B.Fab")
		)
		(fp_line
			(start 0.8636 0.4572)
			(end 0.8636 0.4064)
			(stroke
				(width 0.1)
				(type default)
			)
			(layer "B.Fab")
		)
		(fp_line
			(start -1.1938 0.4064)
			(end -0.8636 0.4064)
			(stroke
				(width 0.1)
				(type default)
			)
			(layer "B.Fab")
		)
		(fp_line
			(start -0.8636 0.4064)
			(end -0.8636 0.4572)
			(stroke
				(width 0.1)
				(type default)
			)
			(layer "B.Fab")
		)
		(fp_line
			(start 0.8636 0.4064)
			(end 1.1938 0.4064)
			(stroke
				(width 0.1)
				(type default)
			)
			(layer "B.Fab")
		)
		(fp_line
			(start 1.1938 0.4064)
			(end 1.1938 -0.4064)
			(stroke
				(width 0.1)
				(type default)
			)
			(layer "B.Fab")
		)
		(fp_line
			(start -1.1938 -0.4064)
			(end -1.1938 0.4064)
			(stroke
				(width 0.1)
				(type default)
			)
			(layer "B.Fab")
		)
		(fp_line
			(start -0.8636 -0.4064)
			(end -1.1938 -0.4064)
			(stroke
				(width 0.1)
				(type default)
			)
			(layer "B.Fab")
		)
		(fp_line
			(start 0.8636 -0.4064)
			(end 0.8636 -0.4572)
			(stroke
				(width 0.1)
				(type default)
			)
			(layer "B.Fab")
		)
		(fp_line
			(start 1.1938 -0.4064)
			(end 0.8636 -0.4064)
			(stroke
				(width 0.1)
				(type default)
			)
			(layer "B.Fab")
		)
		(fp_line
			(start -0.8636 -0.4572)
			(end -0.8636 -0.4064)
			(stroke
				(width 0.1)
				(type default)
			)
			(layer "B.Fab")
		)
		(fp_line
			(start 0.8636 -0.4572)
			(end -0.8636 -0.4572)
			(stroke
				(width 0.1)
				(type default)
			)
			(layer "B.Fab")
		)
		(pad "1" smd rect
			(at 0.7366 0 180)
			(size 0.7112 0.8128)
			(layers "B.Cu" "B.Mask" "B.Paste")
			(net "P0V8_SERDES_VDDA_PEX3_C4")
		)
		(pad "2" smd rect
			(at -0.7366 0 180)
			(size 0.7112 0.8128)
			(layers "B.Cu" "B.Mask" "B.Paste")
			(net "GND")
		)
	)
	(footprint ""
		(layer "B.Cu")
		(at 228.968046 -138.649202 180)
		(property "Reference" "L80"
			(at 0 0 0)
			(layer "B.SilkS")
			(hide yes)
			(effects
				(font
					(size 1.27 1.27)
				)
				(justify mirror)
			)
		)
		(property "Value" ""
			(at 0 0 0)
			(layer "B.Fab")
			(effects
				(font
					(size 1.27 1.27)
				)
				(justify mirror)
			)
		)
		(duplicate_pad_numbers_are_jumpers no)
		(fp_line
			(start 1.63576 -0.8128)
			(end 1.63576 0.8128)
			(stroke
				(width 0.1524)
				(type default)
			)
			(layer "B.SilkS")
		)
		(fp_line
			(start 1.63576 -0.8128)
			(end -1.63576 -0.8128)
			(stroke
				(width 0.1524)
				(type default)
			)
			(layer "B.SilkS")
		)
		(fp_line
			(start -1.63576 0.8128)
			(end 1.63576 0.8128)
			(stroke
				(width 0.1524)
				(type default)
			)
			(layer "B.SilkS")
		)
		(fp_line
			(start -1.63576 -0.8128)
			(end -1.63576 0.8128)
			(stroke
				(width 0.1524)
				(type default)
			)
			(layer "B.SilkS")
		)
		(fp_line
			(start 1.56083 0.7366)
			(end 1.524 0.7366)
			(stroke
				(width 0.1)
				(type default)
			)
			(layer "B.Fab")
		)
		(fp_line
			(start 1.56083 -0.738632)
			(end 1.56083 0.7366)
			(stroke
				(width 0.1)
				(type default)
			)
			(layer "B.Fab")
		)
		(fp_line
			(start 1.524 0.7366)
			(end -1.524 0.7366)
			(stroke
				(width 0.1)
				(type default)
			)
			(layer "B.Fab")
		)
		(fp_line
			(start -1.524 0.7366)
			(end -1.560576 0.7366)
			(stroke
				(width 0.1)
				(type default)
			)
			(layer "B.Fab")
		)
		(fp_line
			(start -1.560576 0.7366)
			(end -1.560576 -0.738632)
			(stroke
				(width 0.1)
				(type default)
			)
			(layer "B.Fab")
		)
		(fp_line
			(start -1.560576 -0.738632)
			(end 1.56083 -0.738632)
			(stroke
				(width 0.1)
				(type default)
			)
			(layer "B.Fab")
		)
		(pad "1" smd rect
			(at 0.94996 0 180)
			(size 1.1176 1.3716)
			(layers "B.Cu" "B.Mask" "B.Paste")
			(net "P3V3")
		)
		(pad "2" smd rect
			(at -0.94996 0 180)
			(size 1.1176 1.3716)
			(layers "B.Cu" "B.Mask" "B.Paste")
			(net "P3V3_CLK_GEN_VDDXTAL_CK440_PEX")
		)
	)
	(footprint ""
		(layer "B.Cu")
		(at 261.904226 -226.78263 180)
		(property "Reference" "R6168"
			(at 0 0 0)
			(layer "B.SilkS")
			(hide yes)
			(effects
				(font
					(size 1.27 1.27)
				)
				(justify mirror)
			)
		)
		(property "Value" ""
			(at 0 0 0)
			(layer "B.Fab")
			(effects
				(font
					(size 1.27 1.27)
				)
				(justify mirror)
			)
		)
		(duplicate_pad_numbers_are_jumpers no)
		(fp_line
			(start 0.7874 0.4064)
			(end 0.7874 -0.4064)
			(stroke
				(width 0.1524)
				(type default)
			)
			(layer "B.SilkS")
		)
		(fp_line
			(start 0.7874 -0.4064)
			(end -0.7874 -0.4064)
			(stroke
				(width 0.1524)
				(type default)
			)
			(layer "B.SilkS")
		)
		(fp_line
			(start -0.7874 0.4064)
			(end 0.7874 0.4064)
			(stroke
				(width 0.1524)
				(type default)
			)
			(layer "B.SilkS")
		)
		(fp_line
			(start -0.7874 -0.4064)
			(end -0.7874 0.4064)
			(stroke
				(width 0.1524)
				(type default)
			)
			(layer "B.SilkS")
		)
		(fp_line
			(start 0.67945 0.3048)
			(end 0.67945 -0.305054)
			(stroke
				(width 0.1)
				(type default)
			)
			(layer "B.Fab")
		)
		(fp_line
			(start 0.67945 -0.305054)
			(end 0.12065 -0.305054)
			(stroke
				(width 0.1)
				(type default)
			)
			(layer "B.Fab")
		)
		(fp_line
			(start 0.12065 0.3048)
			(end 0.67945 0.3048)
			(stroke
				(width 0.1)
				(type default)
			)
			(layer "B.Fab")
		)
		(fp_line
			(start 0.12065 0.2794)
			(end 0.12065 0.3048)
			(stroke
				(width 0.1)
				(type default)
			)
			(layer "B.Fab")
		)
		(fp_line
			(start 0.12065 -0.2794)
			(end -0.12065 -0.2794)
			(stroke
				(width 0.1)
				(type default)
			)
			(layer "B.Fab")
		)
		(fp_line
			(start 0.12065 -0.305054)
			(end 0.12065 -0.2794)
			(stroke
				(width 0.1)
				(type default)
			)
			(layer "B.Fab")
		)
		(fp_line
			(start -0.120396 0.3048)
			(end -0.120396 0.2794)
			(stroke
				(width 0.1)
				(type default)
			)
			(layer "B.Fab")
		)
		(fp_line
			(start -0.120396 0.2794)
			(end 0.12065 0.2794)
			(stroke
				(width 0.1)
				(type default)
			)
			(layer "B.Fab")
		)
		(fp_line
			(start -0.12065 -0.2794)
			(end -0.12065 -0.3048)
			(stroke
				(width 0.1)
				(type default)
			)
			(layer "B.Fab")
		)
		(fp_line
			(start -0.12065 -0.3048)
			(end -0.67945 -0.3048)
			(stroke
				(width 0.1)
				(type default)
			)
			(layer "B.Fab")
		)
		(fp_line
			(start -0.67945 0.3048)
			(end -0.120396 0.3048)
			(stroke
				(width 0.1)
				(type default)
			)
			(layer "B.Fab")
		)
		(fp_line
			(start -0.67945 -0.3048)
			(end -0.67945 0.3048)
			(stroke
				(width 0.1)
				(type default)
			)
			(layer "B.Fab")
		)
		(pad "1" smd circle
			(at 0.40005 0)
			(size 0 0)
			(layers "B.Cu" "B.Mask" "B.Paste")
			(net "SPI_PEX2_RST_R_N")
		)
		(pad "2" smd circle
			(at -0.40005 0)
			(size 0 0)
			(layers "B.Cu" "B.Mask" "B.Paste")
			(net "SPI_PEX2_RST_N")
		)
	)
	(footprint ""
		(layer "B.Cu")
		(at 49.5554 -151.9936)
		(property "Reference" "R18"
			(at 0 0 0)
			(layer "B.SilkS")
			(hide yes)
			(effects
				(font
					(size 1.27 1.27)
				)
				(justify mirror)
			)
		)
		(property "Value" ""
			(at 0 0 0)
			(layer "B.Fab")
			(effects
				(font
					(size 1.27 1.27)
				)
				(justify mirror)
			)
		)
		(duplicate_pad_numbers_are_jumpers no)
		(fp_line
			(start -0.7874 -0.4064)
			(end -0.7874 0.4064)
			(stroke
				(width 0.1524)
				(type default)
			)
			(layer "B.SilkS")
		)
		(fp_line
			(start -0.7874 0.4064)
			(end 0.7874 0.4064)
			(stroke
				(width 0.1524)
				(type default)
			)
			(layer "B.SilkS")
		)
		(fp_line
			(start 0.7874 -0.4064)
			(end -0.7874 -0.4064)
			(stroke
				(width 0.1524)
				(type default)
			)
			(layer "B.SilkS")
		)
		(fp_line
			(start 0.7874 0.4064)
			(end 0.7874 -0.4064)
			(stroke
				(width 0.1524)
				(type default)
			)
			(layer "B.SilkS")
		)
		(fp_line
			(start -0.67945 -0.3048)
			(end -0.67945 0.3048)
			(stroke
				(width 0.1)
				(type default)
			)
			(layer "B.Fab")
		)
		(fp_line
			(start -0.67945 0.3048)
			(end -0.120396 0.3048)
			(stroke
				(width 0.1)
				(type default)
			)
			(layer "B.Fab")
		)
		(fp_line
			(start -0.12065 -0.3048)
			(end -0.67945 -0.3048)
			(stroke
				(width 0.1)
				(type default)
			)
			(layer "B.Fab")
		)
		(fp_line
			(start -0.12065 -0.2794)
			(end -0.12065 -0.3048)
			(stroke
				(width 0.1)
				(type default)
			)
			(layer "B.Fab")
		)
		(fp_line
			(start -0.120396 0.2794)
			(end 0.12065 0.2794)
			(stroke
				(width 0.1)
				(type default)
			)
			(layer "B.Fab")
		)
		(fp_line
			(start -0.120396 0.3048)
			(end -0.120396 0.2794)
			(stroke
				(width 0.1)
				(type default)
			)
			(layer "B.Fab")
		)
		(fp_line
			(start 0.12065 -0.305054)
			(end 0.12065 -0.2794)
			(stroke
				(width 0.1)
				(type default)
			)
			(layer "B.Fab")
		)
		(fp_line
			(start 0.12065 -0.2794)
			(end -0.12065 -0.2794)
			(stroke
				(width 0.1)
				(type default)
			)
			(layer "B.Fab")
		)
		(fp_line
			(start 0.12065 0.2794)
			(end 0.12065 0.3048)
			(stroke
				(width 0.1)
				(type default)
			)
			(layer "B.Fab")
		)
		(fp_line
			(start 0.12065 0.3048)
			(end 0.67945 0.3048)
			(stroke
				(width 0.1)
				(type default)
			)
			(layer "B.Fab")
		)
		(fp_line
			(start 0.67945 -0.305054)
			(end 0.12065 -0.305054)
			(stroke
				(width 0.1)
				(type default)
			)
			(layer "B.Fab")
		)
		(fp_line
			(start 0.67945 0.3048)
			(end 0.67945 -0.305054)
			(stroke
				(width 0.1)
				(type default)
			)
			(layer "B.Fab")
		)
		(pad "1" smd circle
			(at 0.40005 0 180)
			(size 0 0)
			(layers "B.Cu" "B.Mask" "B.Paste")
			(net "NCSI_NIC0_TXD0")
		)
		(pad "2" smd circle
			(at -0.40005 0 180)
			(size 0 0)
			(layers "B.Cu" "B.Mask" "B.Paste")
			(net "GND")
		)
	)
	(footprint ""
		(layer "B.Cu")
		(at 356.38232 -308.613556 90)
		(property "Reference" "C4375"
			(at 0 0 90)
			(layer "B.SilkS")
			(hide yes)
			(effects
				(font
					(size 1.27 1.27)
				)
				(justify mirror)
			)
		)
		(property "Value" ""
			(at 0 0 90)
			(layer "B.Fab")
			(effects
				(font
					(size 1.27 1.27)
				)
				(justify mirror)
			)
		)
		(duplicate_pad_numbers_are_jumpers no)
		(fp_line
			(start 1.2954 -0.5842)
			(end -1.2954 -0.5842)
			(stroke
				(width 0.1524)
				(type default)
			)
			(layer "B.SilkS")
		)
		(fp_line
			(start -1.2954 -0.5842)
			(end -1.2954 0.5842)
			(stroke
				(width 0.1524)
				(type default)
			)
			(layer "B.SilkS")
		)
		(fp_line
			(start 1.2954 0.5842)
			(end 1.2954 -0.5842)
			(stroke
				(width 0.1524)
				(type default)
			)
			(layer "B.SilkS")
		)
		(fp_line
			(start -1.2954 0.5842)
			(end 1.2954 0.5842)
			(stroke
				(width 0.1524)
				(type default)
			)
			(layer "B.SilkS")
		)
		(fp_line
			(start 0.8636 -0.4572)
			(end -0.8636 -0.4572)
			(stroke
				(width 0.1)
				(type default)
			)
			(layer "B.Fab")
		)
		(fp_line
			(start -0.8636 -0.4572)
			(end -0.8636 -0.4064)
			(stroke
				(width 0.1)
				(type default)
			)
			(layer "B.Fab")
		)
		(fp_line
			(start 1.1938 -0.4064)
			(end 0.8636 -0.4064)
			(stroke
				(width 0.1)
				(type default)
			)
			(layer "B.Fab")
		)
		(fp_line
			(start 0.8636 -0.4064)
			(end 0.8636 -0.4572)
			(stroke
				(width 0.1)
				(type default)
			)
			(layer "B.Fab")
		)
		(fp_line
			(start -0.8636 -0.4064)
			(end -1.1938 -0.4064)
			(stroke
				(width 0.1)
				(type default)
			)
			(layer "B.Fab")
		)
		(fp_line
			(start -1.1938 -0.4064)
			(end -1.1938 0.4064)
			(stroke
				(width 0.1)
				(type default)
			)
			(layer "B.Fab")
		)
		(fp_line
			(start 1.1938 0.4064)
			(end 1.1938 -0.4064)
			(stroke
				(width 0.1)
				(type default)
			)
			(layer "B.Fab")
		)
		(fp_line
			(start 0.8636 0.4064)
			(end 1.1938 0.4064)
			(stroke
				(width 0.1)
				(type default)
			)
			(layer "B.Fab")
		)
		(fp_line
			(start -0.8636 0.4064)
			(end -0.8636 0.4572)
			(stroke
				(width 0.1)
				(type default)
			)
			(layer "B.Fab")
		)
		(fp_line
			(start -1.1938 0.4064)
			(end -0.8636 0.4064)
			(stroke
				(width 0.1)
				(type default)
			)
			(layer "B.Fab")
		)
		(fp_line
			(start 0.8636 0.4572)
			(end 0.8636 0.4064)
			(stroke
				(width 0.1)
				(type default)
			)
			(layer "B.Fab")
		)
		(fp_line
			(start -0.8636 0.4572)
			(end 0.8636 0.4572)
			(stroke
				(width 0.1)
				(type default)
			)
			(layer "B.Fab")
		)
		(pad "1" smd rect
			(at 0.7366 0)
			(size 0.7112 0.8128)
			(layers "B.Cu" "B.Mask" "B.Paste")
			(net "P0V8_PEX3")
		)
		(pad "2" smd rect
			(at -0.7366 0)
			(size 0.7112 0.8128)
			(layers "B.Cu" "B.Mask" "B.Paste")
			(net "GND")
		)
	)
	(footprint ""
		(layer "B.Cu")
		(at 421.700198 -112.604296)
		(property "Reference" "C955"
			(at 0 0 0)
			(layer "B.SilkS")
			(hide yes)
			(effects
				(font
					(size 1.27 1.27)
				)
				(justify mirror)
			)
		)
		(property "Value" ""
			(at 0 0 0)
			(layer "B.Fab")
			(effects
				(font
					(size 1.27 1.27)
				)
				(justify mirror)
			)
		)
		(duplicate_pad_numbers_are_jumpers no)
		(fp_line
			(start -0.299974 -0.150114)
			(end -0.299974 0.150114)
			(stroke
				(width 0.1)
				(type default)
			)
			(layer "B.Fab")
		)
		(fp_line
			(start -0.299974 0.150114)
			(end 0.299974 0.150114)
			(stroke
				(width 0.1)
				(type default)
			)
			(layer "B.Fab")
		)
		(fp_line
			(start 0.299974 -0.150114)
			(end -0.299974 -0.150114)
			(stroke
				(width 0.1)
				(type default)
			)
			(layer "B.Fab")
		)
		(fp_line
			(start 0.299974 0.150114)
			(end 0.299974 -0.150114)
			(stroke
				(width 0.1)
				(type default)
			)
			(layer "B.Fab")
		)
		(pad "1" smd rect
			(at 0.2667 0 180)
			(size 0.3048 0.381)
			(layers "B.Cu" "B.Mask" "B.Paste")
			(net "P12V_NIC7")
		)
		(pad "2" smd rect
			(at -0.2667 0 180)
			(size 0.3048 0.381)
			(layers "B.Cu" "B.Mask" "B.Paste")
			(net "GND")
		)
	)
	(footprint ""
		(layer "B.Cu")
		(at 54.424834 -286.399732 90)
		(property "Reference" "C2972"
			(at 0 0 90)
			(layer "B.SilkS")
			(hide yes)
			(effects
				(font
					(size 1.27 1.27)
				)
				(justify mirror)
			)
		)
		(property "Value" ""
			(at 0 0 90)
			(layer "B.Fab")
			(effects
				(font
					(size 1.27 1.27)
				)
				(justify mirror)
			)
		)
		(duplicate_pad_numbers_are_jumpers no)
		(fp_line
			(start 0.299974 -0.150114)
			(end -0.299974 -0.150114)
			(stroke
				(width 0.1)
				(type default)
			)
			(layer "B.Fab")
		)
		(fp_line
			(start -0.299974 -0.150114)
			(end -0.299974 0.150114)
			(stroke
				(width 0.1)
				(type default)
			)
			(layer "B.Fab")
		)
		(fp_line
			(start 0.299974 0.150114)
			(end 0.299974 -0.150114)
			(stroke
				(width 0.1)
				(type default)
			)
			(layer "B.Fab")
		)
		(fp_line
			(start -0.299974 0.150114)
			(end 0.299974 0.150114)
			(stroke
				(width 0.1)
				(type default)
			)
			(layer "B.Fab")
		)
		(pad "1" smd rect
			(at 0.2667 0 270)
			(size 0.3048 0.381)
			(layers "B.Cu" "B.Mask" "B.Paste")
			(net "P1V25_SERDES_VDDPLL_PEX0")
		)
		(pad "2" smd rect
			(at -0.2667 0 270)
			(size 0.3048 0.381)
			(layers "B.Cu" "B.Mask" "B.Paste")
			(net "GND")
		)
	)
	(footprint ""
		(layer "B.Cu")
		(at 66.774822 -286.399732 90)
		(property "Reference" "C2963"
			(at 0 0 90)
			(layer "B.SilkS")
			(hide yes)
			(effects
				(font
					(size 1.27 1.27)
				)
				(justify mirror)
			)
		)
		(property "Value" ""
			(at 0 0 90)
			(layer "B.Fab")
			(effects
				(font
					(size 1.27 1.27)
				)
				(justify mirror)
			)
		)
		(duplicate_pad_numbers_are_jumpers no)
		(fp_line
			(start 0.299974 -0.150114)
			(end -0.299974 -0.150114)
			(stroke
				(width 0.1)
				(type default)
			)
			(layer "B.Fab")
		)
		(fp_line
			(start -0.299974 -0.150114)
			(end -0.299974 0.150114)
			(stroke
				(width 0.1)
				(type default)
			)
			(layer "B.Fab")
		)
		(fp_line
			(start 0.299974 0.150114)
			(end 0.299974 -0.150114)
			(stroke
				(width 0.1)
				(type default)
			)
			(layer "B.Fab")
		)
		(fp_line
			(start -0.299974 0.150114)
			(end 0.299974 0.150114)
			(stroke
				(width 0.1)
				(type default)
			)
			(layer "B.Fab")
		)
		(pad "1" smd rect
			(at 0.2667 0 270)
			(size 0.3048 0.381)
			(layers "B.Cu" "B.Mask" "B.Paste")
			(net "P1V25_SERDES_VDDPLL_PEX0")
		)
		(pad "2" smd rect
			(at -0.2667 0 270)
			(size 0.3048 0.381)
			(layers "B.Cu" "B.Mask" "B.Paste")
			(net "GND")
		)
	)
	(footprint ""
		(layer "B.Cu")
		(at 169.099992 -299.699934 -90)
		(property "Reference" "C1436"
			(at 0 0 90)
			(layer "B.SilkS")
			(hide yes)
			(effects
				(font
					(size 1.27 1.27)
				)
				(justify mirror)
			)
		)
		(property "Value" ""
			(at 0 0 90)
			(layer "B.Fab")
			(effects
				(font
					(size 1.27 1.27)
				)
				(justify mirror)
			)
		)
		(duplicate_pad_numbers_are_jumpers no)
		(fp_line
			(start -0.299974 0.150114)
			(end 0.299974 0.150114)
			(stroke
				(width 0.1)
				(type default)
			)
			(layer "B.Fab")
		)
		(fp_line
			(start 0.299974 0.150114)
			(end 0.299974 -0.150114)
			(stroke
				(width 0.1)
				(type default)
			)
			(layer "B.Fab")
		)
		(fp_line
			(start -0.299974 -0.150114)
			(end -0.299974 0.150114)
			(stroke
				(width 0.1)
				(type default)
			)
			(layer "B.Fab")
		)
		(fp_line
			(start 0.299974 -0.150114)
			(end -0.299974 -0.150114)
			(stroke
				(width 0.1)
				(type default)
			)
			(layer "B.Fab")
		)
		(pad "1" smd rect
			(at 0.2667 0 90)
			(size 0.3048 0.381)
			(layers "B.Cu" "B.Mask" "B.Paste")
			(net "P0V8_SERDES_VDDA_PEX1")
		)
		(pad "2" smd rect
			(at -0.2667 0 90)
			(size 0.3048 0.381)
			(layers "B.Cu" "B.Mask" "B.Paste")
			(net "GND")
		)
	)
	(footprint ""
		(layer "B.Cu")
		(at 279.974802 -292.84168 90)
		(property "Reference" "C3394"
			(at 0 0 90)
			(layer "B.SilkS")
			(hide yes)
			(effects
				(font
					(size 1.27 1.27)
				)
				(justify mirror)
			)
		)
		(property "Value" ""
			(at 0 0 90)
			(layer "B.Fab")
			(effects
				(font
					(size 1.27 1.27)
				)
				(justify mirror)
			)
		)
		(duplicate_pad_numbers_are_jumpers no)
		(fp_line
			(start 0.299974 -0.150114)
			(end -0.299974 -0.150114)
			(stroke
				(width 0.1)
				(type default)
			)
			(layer "B.Fab")
		)
		(fp_line
			(start -0.299974 -0.150114)
			(end -0.299974 0.150114)
			(stroke
				(width 0.1)
				(type default)
			)
			(layer "B.Fab")
		)
		(fp_line
			(start 0.299974 0.150114)
			(end 0.299974 -0.150114)
			(stroke
				(width 0.1)
				(type default)
			)
			(layer "B.Fab")
		)
		(fp_line
			(start -0.299974 0.150114)
			(end 0.299974 0.150114)
			(stroke
				(width 0.1)
				(type default)
			)
			(layer "B.Fab")
		)
		(pad "1" smd rect
			(at 0.2667 0 270)
			(size 0.3048 0.381)
			(layers "B.Cu" "B.Mask" "B.Paste")
			(net "PCEPLL5_VDDA18_PEX2")
		)
		(pad "2" smd rect
			(at -0.2667 0 270)
			(size 0.3048 0.381)
			(layers "B.Cu" "B.Mask" "B.Paste")
			(net "GND")
		)
	)
	(footprint ""
		(layer "B.Cu")
		(at 156.750004 -288.774886 -90)
		(property "Reference" "R3451"
			(at 0 0 90)
			(layer "B.SilkS")
			(hide yes)
			(effects
				(font
					(size 1.27 1.27)
				)
				(justify mirror)
			)
		)
		(property "Value" ""
			(at 0 0 90)
			(layer "B.Fab")
			(effects
				(font
					(size 1.27 1.27)
				)
				(justify mirror)
			)
		)
		(duplicate_pad_numbers_are_jumpers no)
		(fp_line
			(start -0.7874 0.4064)
			(end 0.7874 0.4064)
			(stroke
				(width 0.1524)
				(type default)
			)
			(layer "B.SilkS")
		)
		(fp_line
			(start 0.7874 0.4064)
			(end 0.7874 -0.4064)
			(stroke
				(width 0.1524)
				(type default)
			)
			(layer "B.SilkS")
		)
		(fp_line
			(start -0.7874 -0.4064)
			(end -0.7874 0.4064)
			(stroke
				(width 0.1524)
				(type default)
			)
			(layer "B.SilkS")
		)
		(fp_line
			(start 0.7874 -0.4064)
			(end -0.7874 -0.4064)
			(stroke
				(width 0.1524)
				(type default)
			)
			(layer "B.SilkS")
		)
		(fp_line
			(start -0.67945 0.3048)
			(end -0.120396 0.3048)
			(stroke
				(width 0.1)
				(type default)
			)
			(layer "B.Fab")
		)
		(fp_line
			(start -0.120396 0.3048)
			(end -0.120396 0.2794)
			(stroke
				(width 0.1)
				(type default)
			)
			(layer "B.Fab")
		)
		(fp_line
			(start 0.12065 0.3048)
			(end 0.67945 0.3048)
			(stroke
				(width 0.1)
				(type default)
			)
			(layer "B.Fab")
		)
		(fp_line
			(start 0.67945 0.3048)
			(end 0.67945 -0.305054)
			(stroke
				(width 0.1)
				(type default)
			)
			(layer "B.Fab")
		)
		(fp_line
			(start -0.120396 0.2794)
			(end 0.12065 0.2794)
			(stroke
				(width 0.1)
				(type default)
			)
			(layer "B.Fab")
		)
		(fp_line
			(start 0.12065 0.2794)
			(end 0.12065 0.3048)
			(stroke
				(width 0.1)
				(type default)
			)
			(layer "B.Fab")
		)
		(fp_line
			(start -0.12065 -0.2794)
			(end -0.12065 -0.3048)
			(stroke
				(width 0.1)
				(type default)
			)
			(layer "B.Fab")
		)
		(fp_line
			(start 0.12065 -0.2794)
			(end -0.12065 -0.2794)
			(stroke
				(width 0.1)
				(type default)
			)
			(layer "B.Fab")
		)
		(fp_line
			(start -0.67945 -0.3048)
			(end -0.67945 0.3048)
			(stroke
				(width 0.1)
				(type default)
			)
			(layer "B.Fab")
		)
		(fp_line
			(start -0.12065 -0.3048)
			(end -0.67945 -0.3048)
			(stroke
				(width 0.1)
				(type default)
			)
			(layer "B.Fab")
		)
		(fp_line
			(start 0.12065 -0.305054)
			(end 0.12065 -0.2794)
			(stroke
				(width 0.1)
				(type default)
			)
			(layer "B.Fab")
		)
		(fp_line
			(start 0.67945 -0.305054)
			(end 0.12065 -0.305054)
			(stroke
				(width 0.1)
				(type default)
			)
			(layer "B.Fab")
		)
		(pad "1" smd circle
			(at 0.40005 0 90)
			(size 0 0)
			(layers "B.Cu" "B.Mask" "B.Paste")
			(net "SPI_PEX1_CS_R_N")
		)
		(pad "2" smd circle
			(at -0.40005 0 90)
			(size 0 0)
			(layers "B.Cu" "B.Mask" "B.Paste")
			(net "SPI_PEX1_CS_N")
		)
	)
	(footprint ""
		(layer "B.Cu")
		(at 221.257114 -210.201002)
		(property "Reference" "C2011"
			(at 0 0 0)
			(layer "B.SilkS")
			(hide yes)
			(effects
				(font
					(size 1.27 1.27)
				)
				(justify mirror)
			)
		)
		(property "Value" ""
			(at 0 0 0)
			(layer "B.Fab")
			(effects
				(font
					(size 1.27 1.27)
				)
				(justify mirror)
			)
		)
		(duplicate_pad_numbers_are_jumpers no)
		(fp_line
			(start -1.2954 -0.5842)
			(end -1.2954 0.5842)
			(stroke
				(width 0.1524)
				(type default)
			)
			(layer "B.SilkS")
		)
		(fp_line
			(start -1.2954 0.5842)
			(end 1.2954 0.5842)
			(stroke
				(width 0.1524)
				(type default)
			)
			(layer "B.SilkS")
		)
		(fp_line
			(start 1.2954 -0.5842)
			(end -1.2954 -0.5842)
			(stroke
				(width 0.1524)
				(type default)
			)
			(layer "B.SilkS")
		)
		(fp_line
			(start 1.2954 0.5842)
			(end 1.2954 -0.5842)
			(stroke
				(width 0.1524)
				(type default)
			)
			(layer "B.SilkS")
		)
		(fp_line
			(start -1.1938 -0.4064)
			(end -1.1938 0.4064)
			(stroke
				(width 0.1)
				(type default)
			)
			(layer "B.Fab")
		)
		(fp_line
			(start -1.1938 0.4064)
			(end -0.8636 0.4064)
			(stroke
				(width 0.1)
				(type default)
			)
			(layer "B.Fab")
		)
		(fp_line
			(start -0.8636 -0.4572)
			(end -0.8636 -0.4064)
			(stroke
				(width 0.1)
				(type default)
			)
			(layer "B.Fab")
		)
		(fp_line
			(start -0.8636 -0.4064)
			(end -1.1938 -0.4064)
			(stroke
				(width 0.1)
				(type default)
			)
			(layer "B.Fab")
		)
		(fp_line
			(start -0.8636 0.4064)
			(end -0.8636 0.4572)
			(stroke
				(width 0.1)
				(type default)
			)
			(layer "B.Fab")
		)
		(fp_line
			(start -0.8636 0.4572)
			(end 0.8636 0.4572)
			(stroke
				(width 0.1)
				(type default)
			)
			(layer "B.Fab")
		)
		(fp_line
			(start 0.8636 -0.4572)
			(end -0.8636 -0.4572)
			(stroke
				(width 0.1)
				(type default)
			)
			(layer "B.Fab")
		)
		(fp_line
			(start 0.8636 -0.4064)
			(end 0.8636 -0.4572)
			(stroke
				(width 0.1)
				(type default)
			)
			(layer "B.Fab")
		)
		(fp_line
			(start 0.8636 0.4064)
			(end 1.1938 0.4064)
			(stroke
				(width 0.1)
				(type default)
			)
			(layer "B.Fab")
		)
		(fp_line
			(start 0.8636 0.4572)
			(end 0.8636 0.4064)
			(stroke
				(width 0.1)
				(type default)
			)
			(layer "B.Fab")
		)
		(fp_line
			(start 1.1938 -0.4064)
			(end 0.8636 -0.4064)
			(stroke
				(width 0.1)
				(type default)
			)
			(layer "B.Fab")
		)
		(fp_line
			(start 1.1938 0.4064)
			(end 1.1938 -0.4064)
			(stroke
				(width 0.1)
				(type default)
			)
			(layer "B.Fab")
		)
		(pad "1" smd rect
			(at 0.7366 0 270)
			(size 0.7112 0.8128)
			(layers "B.Cu" "B.Mask" "B.Paste")
			(net "P3V3_AUX")
		)
		(pad "2" smd rect
			(at -0.7366 0 270)
			(size 0.7112 0.8128)
			(layers "B.Cu" "B.Mask" "B.Paste")
			(net "GND")
		)
	)
	(footprint ""
		(layer "B.Cu")
		(at 253.97968 -86.856316 180)
		(property "Reference" "R1048"
			(at 0 0 0)
			(layer "B.SilkS")
			(hide yes)
			(effects
				(font
					(size 1.27 1.27)
				)
				(justify mirror)
			)
		)
		(property "Value" ""
			(at 0 0 0)
			(layer "B.Fab")
			(effects
				(font
					(size 1.27 1.27)
				)
				(justify mirror)
			)
		)
		(duplicate_pad_numbers_are_jumpers no)
		(fp_line
			(start 1.2954 0.5842)
			(end 1.2954 -0.5842)
			(stroke
				(width 0.1524)
				(type default)
			)
			(layer "B.SilkS")
		)
		(fp_line
			(start 1.2954 -0.5842)
			(end -1.2954 -0.5842)
			(stroke
				(width 0.1524)
				(type default)
			)
			(layer "B.SilkS")
		)
		(fp_line
			(start -1.2954 0.5842)
			(end 1.2954 0.5842)
			(stroke
				(width 0.1524)
				(type default)
			)
			(layer "B.SilkS")
		)
		(fp_line
			(start -1.2954 -0.5842)
			(end -1.2954 0.5842)
			(stroke
				(width 0.1524)
				(type default)
			)
			(layer "B.SilkS")
		)
		(fp_line
			(start 1.1938 0.4064)
			(end 1.1938 -0.406654)
			(stroke
				(width 0.1)
				(type default)
			)
			(layer "B.Fab")
		)
		(fp_line
			(start 1.1938 -0.406654)
			(end 0.8636 -0.406654)
			(stroke
				(width 0.1)
				(type default)
			)
			(layer "B.Fab")
		)
		(fp_line
			(start 0.8636 0.4572)
			(end 0.8636 0.4318)
			(stroke
				(width 0.1)
				(type default)
			)
			(layer "B.Fab")
		)
		(fp_line
			(start 0.8636 0.4318)
			(end 0.8636 0.4064)
			(stroke
				(width 0.1)
				(type default)
			)
			(layer "B.Fab")
		)
		(fp_line
			(start 0.8636 0.4064)
			(end 1.1938 0.4064)
			(stroke
				(width 0.1)
				(type default)
			)
			(layer "B.Fab")
		)
		(fp_line
			(start 0.8636 -0.406654)
			(end 0.8636 -0.4572)
			(stroke
				(width 0.1)
				(type default)
			)
			(layer "B.Fab")
		)
		(fp_line
			(start 0.8636 -0.4572)
			(end -0.8636 -0.4572)
			(stroke
				(width 0.1)
				(type default)
			)
			(layer "B.Fab")
		)
		(fp_line
			(start -0.8636 0.4572)
			(end 0.8636 0.4572)
			(stroke
				(width 0.1)
				(type default)
			)
			(layer "B.Fab")
		)
		(fp_line
			(start -0.8636 0.4064)
			(end -0.8636 0.4572)
			(stroke
				(width 0.1)
				(type default)
			)
			(layer "B.Fab")
		)
		(fp_line
			(start -0.8636 -0.406654)
			(end -1.1938 -0.406654)
			(stroke
				(width 0.1)
				(type default)
			)
			(layer "B.Fab")
		)
		(fp_line
			(start -0.8636 -0.4572)
			(end -0.8636 -0.406654)
			(stroke
				(width 0.1)
				(type default)
			)
			(layer "B.Fab")
		)
		(fp_line
			(start -1.1938 0.4064)
			(end -0.8636 0.4064)
			(stroke
				(width 0.1)
				(type default)
			)
			(layer "B.Fab")
		)
		(fp_line
			(start -1.1938 -0.406654)
			(end -1.1938 0.4064)
			(stroke
				(width 0.1)
				(type default)
			)
			(layer "B.Fab")
		)
		(pad "1" smd rect
			(at 0.7366 0 90)
			(size 0.7112 0.8128)
			(layers "B.Cu" "B.Mask" "B.Paste")
			(net "P3V3_CLK_GEN_VDDMXCK_CK440")
		)
		(pad "2" smd rect
			(at -0.7366 0 90)
			(size 0.7112 0.8128)
			(layers "B.Cu" "B.Mask" "B.Paste")
			(net "P3V3_CLK_GEN_VDDPT_CK440")
		)
	)
	(footprint ""
		(layer "B.Cu")
		(at 12.964922 -391.185146 -90)
		(property "Reference" "L151"
			(at -0.766064 1.406906 0)
			(unlocked yes)
			(layer "B.SilkS")
			(effects
				(font
					(size 0.7874 0.5842)
					(thickness 0.1524)
				)
				(justify left mirror)
			)
		)
		(property "Value" ""
			(at 0 0 90)
			(layer "B.Fab")
			(effects
				(font
					(size 1.27 1.27)
				)
				(justify mirror)
			)
		)
		(duplicate_pad_numbers_are_jumpers no)
		(fp_line
			(start -1.63576 0.8128)
			(end 1.63576 0.8128)
			(stroke
				(width 0.1524)
				(type default)
			)
			(layer "B.SilkS")
		)
		(fp_line
			(start -1.63576 -0.8128)
			(end -1.63576 0.8128)
			(stroke
				(width 0.1524)
				(type default)
			)
			(layer "B.SilkS")
		)
		(fp_line
			(start 1.63576 -0.8128)
			(end 1.63576 0.8128)
			(stroke
				(width 0.1524)
				(type default)
			)
			(layer "B.SilkS")
		)
		(fp_line
			(start 1.63576 -0.8128)
			(end -1.63576 -0.8128)
			(stroke
				(width 0.1524)
				(type default)
			)
			(layer "B.SilkS")
		)
		(fp_line
			(start -1.560576 0.7366)
			(end -1.560576 -0.738632)
			(stroke
				(width 0.1)
				(type default)
			)
			(layer "B.Fab")
		)
		(fp_line
			(start -1.524 0.7366)
			(end -1.560576 0.7366)
			(stroke
				(width 0.1)
				(type default)
			)
			(layer "B.Fab")
		)
		(fp_line
			(start 1.524 0.7366)
			(end -1.524 0.7366)
			(stroke
				(width 0.1)
				(type default)
			)
			(layer "B.Fab")
		)
		(fp_line
			(start 1.56083 0.7366)
			(end 1.524 0.7366)
			(stroke
				(width 0.1)
				(type default)
			)
			(layer "B.Fab")
		)
		(fp_line
			(start -1.560576 -0.738632)
			(end 1.56083 -0.738632)
			(stroke
				(width 0.1)
				(type default)
			)
			(layer "B.Fab")
		)
		(fp_line
			(start 1.56083 -0.738632)
			(end 1.56083 0.7366)
			(stroke
				(width 0.1)
				(type default)
			)
			(layer "B.Fab")
		)
		(pad "1" smd rect
			(at 0.94996 0 270)
			(size 1.1176 1.3716)
			(layers "B.Cu" "B.Mask" "B.Paste")
			(net "P1V2_USB_8042")
		)
		(pad "2" smd rect
			(at -0.94996 0 270)
			(size 1.1176 1.3716)
			(layers "B.Cu" "B.Mask" "B.Paste")
			(net "P1V2_AUX")
		)
	)
	(footprint ""
		(layer "B.Cu")
		(at 102.02926 -277.639272)
		(property "Reference" "PC6607"
			(at 0 0 0)
			(layer "B.SilkS")
			(hide yes)
			(effects
				(font
					(size 1.27 1.27)
				)
				(justify mirror)
			)
		)
		(property "Value" ""
			(at 0 0 0)
			(layer "B.Fab")
			(effects
				(font
					(size 1.27 1.27)
				)
				(justify mirror)
			)
		)
		(duplicate_pad_numbers_are_jumpers no)
		(fp_line
			(start -1.524 -0.762)
			(end -1.524 0.762)
			(stroke
				(width 0.1524)
				(type default)
			)
			(layer "B.SilkS")
		)
		(fp_line
			(start -1.524 0.762)
			(end 1.524 0.762)
			(stroke
				(width 0.1524)
				(type default)
			)
			(layer "B.SilkS")
		)
		(fp_line
			(start 1.524 -0.762)
			(end -1.524 -0.762)
			(stroke
				(width 0.1524)
				(type default)
			)
			(layer "B.SilkS")
		)
		(fp_line
			(start 1.524 0.762)
			(end 1.524 -0.762)
			(stroke
				(width 0.1524)
				(type default)
			)
			(layer "B.SilkS")
		)
		(fp_line
			(start -1.1049 -0.724916)
			(end 1.1049 -0.724916)
			(stroke
				(width 0.1)
				(type default)
			)
			(layer "B.Fab")
		)
		(fp_line
			(start -1.1049 0.724916)
			(end -1.1049 -0.724916)
			(stroke
				(width 0.1)
				(type default)
			)
			(layer "B.Fab")
		)
		(fp_line
			(start 1.1049 -0.724916)
			(end 1.1049 0.724916)
			(stroke
				(width 0.1)
				(type default)
			)
			(layer "B.Fab")
		)
		(fp_line
			(start 1.1049 0.724916)
			(end -1.1049 0.724916)
			(stroke
				(width 0.1)
				(type default)
			)
			(layer "B.Fab")
		)
		(pad "1" smd rect
			(at 0.889 0)
			(size 1.016 1.27)
			(layers "B.Cu" "B.Mask" "B.Paste")
			(net "SW_P12V_P0V8_PEX0_FLT")
		)
		(pad "2" smd rect
			(at -0.889 0)
			(size 1.016 1.27)
			(layers "B.Cu" "B.Mask" "B.Paste")
			(net "GND")
		)
	)
	(footprint ""
		(layer "B.Cu")
		(at 373.370602 -243.936012 180)
		(property "Reference" "U101"
			(at 0.102108 -1.873758 0)
			(unlocked yes)
			(layer "B.SilkS")
			(effects
				(font
					(size 0.7874 0.5842)
					(thickness 0.1524)
				)
				(justify mirror)
			)
		)
		(property "Value" ""
			(at 0 0 0)
			(layer "B.Fab")
			(effects
				(font
					(size 1.27 1.27)
				)
				(justify mirror)
			)
		)
		(duplicate_pad_numbers_are_jumpers no)
		(fp_line
			(start 1.7272 1.1176)
			(end 1.7272 -1.1176)
			(stroke
				(width 0.1524)
				(type default)
			)
			(layer "B.SilkS")
		)
		(fp_line
			(start 0.254 -1.1176)
			(end 1.7272 -1.1176)
			(stroke
				(width 0.1524)
				(type default)
			)
			(layer "B.SilkS")
		)
		(fp_line
			(start 0 -0.7366)
			(end 0.254 -1.1176)
			(stroke
				(width 0.1524)
				(type default)
			)
			(layer "B.SilkS")
		)
		(fp_line
			(start -0.254 -1.1176)
			(end 0 -0.7366)
			(stroke
				(width 0.1524)
				(type default)
			)
			(layer "B.SilkS")
		)
		(fp_line
			(start -1.7272 1.1176)
			(end 1.7272 1.1176)
			(stroke
				(width 0.1524)
				(type default)
			)
			(layer "B.SilkS")
		)
		(fp_line
			(start -1.7272 -1.1176)
			(end -0.254 -1.1176)
			(stroke
				(width 0.1524)
				(type default)
			)
			(layer "B.SilkS")
		)
		(fp_line
			(start -1.7272 -1.1176)
			(end -1.7272 1.1176)
			(stroke
				(width 0.1524)
				(type default)
			)
			(layer "B.SilkS")
		)
		(fp_poly
			(pts
				(xy 1.9558 -0.649986) (xy 2.7178 -0.268986) (xy 2.7178 -1.030986)
			)
			(stroke
				(width 0)
				(type default)
			)
			(fill yes)
			(layer "B.SilkS")
		)
		(fp_line
			(start 1.5748 1.1176)
			(end -1.5748 1.1176)
			(stroke
				(width 0.1)
				(type default)
			)
			(layer "B.Fab")
		)
		(fp_line
			(start 1.5748 -1.1176)
			(end 1.5748 1.1176)
			(stroke
				(width 0.1)
				(type default)
			)
			(layer "B.Fab")
		)
		(fp_line
			(start -1.5748 1.1176)
			(end -1.5748 -1.1176)
			(stroke
				(width 0.1)
				(type default)
			)
			(layer "B.Fab")
		)
		(fp_line
			(start -1.5748 -1.1176)
			(end 1.5748 -1.1176)
			(stroke
				(width 0.1)
				(type default)
			)
			(layer "B.Fab")
		)
		(fp_poly
			(pts
				(xy 1.9558 -0.649986) (xy 2.7178 -0.268986) (xy 2.7178 -1.030986)
			)
			(stroke
				(width 0)
				(type default)
			)
			(fill yes)
			(layer "B.Fab")
		)
		(pad "1" smd rect
			(at 0.999998 -0.649986 90)
			(size 0.3556 1.1176)
			(layers "B.Cu" "B.Mask" "B.Paste")
			(net "UART_PEX0_SDB_R_TX")
		)
		(pad "2" smd rect
			(at 0.999998 0 90)
			(size 0.3556 1.1176)
			(layers "B.Cu" "B.Mask" "B.Paste")
			(net "GND")
		)
		(pad "3" smd rect
			(at 0.999998 0.649986 90)
			(size 0.3556 1.1176)
			(layers "B.Cu" "B.Mask" "B.Paste")
			(net "UART_PEX1_SDB_R_TX")
		)
		(pad "4" smd rect
			(at -0.999998 0.649986 90)
			(size 0.3556 1.1176)
			(layers "B.Cu" "B.Mask" "B.Paste")
			(net "UART_PEX1_SDB_BUF_R_TX")
		)
		(pad "5" smd rect
			(at -0.999998 0 90)
			(size 0.3556 1.1176)
			(layers "B.Cu" "B.Mask" "B.Paste")
			(net "P1V8_PEX")
		)
		(pad "6" smd rect
			(at -0.999998 -0.649986 90)
			(size 0.3556 1.1176)
			(layers "B.Cu" "B.Mask" "B.Paste")
			(net "UART_PEX0_SDB_BUF_R_TX")
		)
	)
	(footprint ""
		(layer "B.Cu")
		(at 46.355 -296.37482)
		(property "Reference" "C3029"
			(at 0 0 0)
			(layer "B.SilkS")
			(hide yes)
			(effects
				(font
					(size 1.27 1.27)
				)
				(justify mirror)
			)
		)
		(property "Value" ""
			(at 0 0 0)
			(layer "B.Fab")
			(effects
				(font
					(size 1.27 1.27)
				)
				(justify mirror)
			)
		)
		(duplicate_pad_numbers_are_jumpers no)
		(fp_line
			(start -0.299974 -0.150114)
			(end -0.299974 0.150114)
			(stroke
				(width 0.1)
				(type default)
			)
			(layer "B.Fab")
		)
		(fp_line
			(start -0.299974 0.150114)
			(end 0.299974 0.150114)
			(stroke
				(width 0.1)
				(type default)
			)
			(layer "B.Fab")
		)
		(fp_line
			(start 0.299974 -0.150114)
			(end -0.299974 -0.150114)
			(stroke
				(width 0.1)
				(type default)
			)
			(layer "B.Fab")
		)
		(fp_line
			(start 0.299974 0.150114)
			(end 0.299974 -0.150114)
			(stroke
				(width 0.1)
				(type default)
			)
			(layer "B.Fab")
		)
		(pad "1" smd rect
			(at 0.2667 0 180)
			(size 0.3048 0.381)
			(layers "B.Cu" "B.Mask" "B.Paste")
			(net "PCEPLL2_VDDA18_PEX0")
		)
		(pad "2" smd rect
			(at -0.2667 0 180)
			(size 0.3048 0.381)
			(layers "B.Cu" "B.Mask" "B.Paste")
			(net "GND")
		)
	)
	(footprint ""
		(layer "B.Cu")
		(at 59.167776 -286.18434 90)
		(property "Reference" "C2944"
			(at 0 0 90)
			(layer "B.SilkS")
			(hide yes)
			(effects
				(font
					(size 1.27 1.27)
				)
				(justify mirror)
			)
		)
		(property "Value" ""
			(at 0 0 90)
			(layer "B.Fab")
			(effects
				(font
					(size 1.27 1.27)
				)
				(justify mirror)
			)
		)
		(duplicate_pad_numbers_are_jumpers no)
		(fp_line
			(start 1.2954 -0.5842)
			(end -1.2954 -0.5842)
			(stroke
				(width 0.1524)
				(type default)
			)
			(layer "B.SilkS")
		)
		(fp_line
			(start -1.2954 -0.5842)
			(end -1.2954 0.5842)
			(stroke
				(width 0.1524)
				(type default)
			)
			(layer "B.SilkS")
		)
		(fp_line
			(start 1.2954 0.5842)
			(end 1.2954 -0.5842)
			(stroke
				(width 0.1524)
				(type default)
			)
			(layer "B.SilkS")
		)
		(fp_line
			(start -1.2954 0.5842)
			(end 1.2954 0.5842)
			(stroke
				(width 0.1524)
				(type default)
			)
			(layer "B.SilkS")
		)
		(fp_line
			(start 0.8636 -0.4572)
			(end -0.8636 -0.4572)
			(stroke
				(width 0.1)
				(type default)
			)
			(layer "B.Fab")
		)
		(fp_line
			(start -0.8636 -0.4572)
			(end -0.8636 -0.4064)
			(stroke
				(width 0.1)
				(type default)
			)
			(layer "B.Fab")
		)
		(fp_line
			(start 1.1938 -0.4064)
			(end 0.8636 -0.4064)
			(stroke
				(width 0.1)
				(type default)
			)
			(layer "B.Fab")
		)
		(fp_line
			(start 0.8636 -0.4064)
			(end 0.8636 -0.4572)
			(stroke
				(width 0.1)
				(type default)
			)
			(layer "B.Fab")
		)
		(fp_line
			(start -0.8636 -0.4064)
			(end -1.1938 -0.4064)
			(stroke
				(width 0.1)
				(type default)
			)
			(layer "B.Fab")
		)
		(fp_line
			(start -1.1938 -0.4064)
			(end -1.1938 0.4064)
			(stroke
				(width 0.1)
				(type default)
			)
			(layer "B.Fab")
		)
		(fp_line
			(start 1.1938 0.4064)
			(end 1.1938 -0.4064)
			(stroke
				(width 0.1)
				(type default)
			)
			(layer "B.Fab")
		)
		(fp_line
			(start 0.8636 0.4064)
			(end 1.1938 0.4064)
			(stroke
				(width 0.1)
				(type default)
			)
			(layer "B.Fab")
		)
		(fp_line
			(start -0.8636 0.4064)
			(end -0.8636 0.4572)
			(stroke
				(width 0.1)
				(type default)
			)
			(layer "B.Fab")
		)
		(fp_line
			(start -1.1938 0.4064)
			(end -0.8636 0.4064)
			(stroke
				(width 0.1)
				(type default)
			)
			(layer "B.Fab")
		)
		(fp_line
			(start 0.8636 0.4572)
			(end 0.8636 0.4064)
			(stroke
				(width 0.1)
				(type default)
			)
			(layer "B.Fab")
		)
		(fp_line
			(start -0.8636 0.4572)
			(end 0.8636 0.4572)
			(stroke
				(width 0.1)
				(type default)
			)
			(layer "B.Fab")
		)
		(pad "1" smd rect
			(at 0.7366 0)
			(size 0.7112 0.8128)
			(layers "B.Cu" "B.Mask" "B.Paste")
			(net "P1V25_SERDES_VDDPLL_PEX0")
		)
		(pad "2" smd rect
			(at -0.7366 0)
			(size 0.7112 0.8128)
			(layers "B.Cu" "B.Mask" "B.Paste")
			(net "GND")
		)
	)
	(footprint ""
		(layer "B.Cu")
		(at 137.846816 -212.188806)
		(property "Reference" "C2588"
			(at 0 0 0)
			(layer "B.SilkS")
			(hide yes)
			(effects
				(font
					(size 1.27 1.27)
				)
				(justify mirror)
			)
		)
		(property "Value" ""
			(at 0 0 0)
			(layer "B.Fab")
			(effects
				(font
					(size 1.27 1.27)
				)
				(justify mirror)
			)
		)
		(duplicate_pad_numbers_are_jumpers no)
		(fp_line
			(start -0.7874 -0.4064)
			(end -0.7874 0.4064)
			(stroke
				(width 0.1524)
				(type default)
			)
			(layer "B.SilkS")
		)
		(fp_line
			(start -0.7874 0.4064)
			(end 0.7874 0.4064)
			(stroke
				(width 0.1524)
				(type default)
			)
			(layer "B.SilkS")
		)
		(fp_line
			(start 0.7874 -0.4064)
			(end -0.7874 -0.4064)
			(stroke
				(width 0.1524)
				(type default)
			)
			(layer "B.SilkS")
		)
		(fp_line
			(start 0.7874 0.4064)
			(end 0.7874 -0.4064)
			(stroke
				(width 0.1524)
				(type default)
			)
			(layer "B.SilkS")
		)
		(fp_line
			(start -0.67945 -0.3048)
			(end -0.67945 0.3048)
			(stroke
				(width 0.1)
				(type default)
			)
			(layer "B.Fab")
		)
		(fp_line
			(start -0.67945 0.3048)
			(end -0.120396 0.3048)
			(stroke
				(width 0.1)
				(type default)
			)
			(layer "B.Fab")
		)
		(fp_line
			(start -0.12065 -0.3048)
			(end -0.67945 -0.3048)
			(stroke
				(width 0.1)
				(type default)
			)
			(layer "B.Fab")
		)
		(fp_line
			(start -0.12065 -0.2794)
			(end -0.12065 -0.3048)
			(stroke
				(width 0.1)
				(type default)
			)
			(layer "B.Fab")
		)
		(fp_line
			(start -0.120396 0.2794)
			(end 0.12065 0.2794)
			(stroke
				(width 0.1)
				(type default)
			)
			(layer "B.Fab")
		)
		(fp_line
			(start -0.120396 0.3048)
			(end -0.120396 0.2794)
			(stroke
				(width 0.1)
				(type default)
			)
			(layer "B.Fab")
		)
		(fp_line
			(start 0.12065 -0.305054)
			(end 0.12065 -0.2794)
			(stroke
				(width 0.1)
				(type default)
			)
			(layer "B.Fab")
		)
		(fp_line
			(start 0.12065 -0.2794)
			(end -0.12065 -0.2794)
			(stroke
				(width 0.1)
				(type default)
			)
			(layer "B.Fab")
		)
		(fp_line
			(start 0.12065 0.2794)
			(end 0.12065 0.3048)
			(stroke
				(width 0.1)
				(type default)
			)
			(layer "B.Fab")
		)
		(fp_line
			(start 0.12065 0.3048)
			(end 0.67945 0.3048)
			(stroke
				(width 0.1)
				(type default)
			)
			(layer "B.Fab")
		)
		(fp_line
			(start 0.67945 -0.305054)
			(end 0.12065 -0.305054)
			(stroke
				(width 0.1)
				(type default)
			)
			(layer "B.Fab")
		)
		(fp_line
			(start 0.67945 0.3048)
			(end 0.67945 -0.305054)
			(stroke
				(width 0.1)
				(type default)
			)
			(layer "B.Fab")
		)
		(pad "1" smd circle
			(at 0.40005 0 180)
			(size 0 0)
			(layers "B.Cu" "B.Mask" "B.Paste")
			(net "P3V3_AUX")
		)
		(pad "2" smd circle
			(at -0.40005 0 180)
			(size 0 0)
			(layers "B.Cu" "B.Mask" "B.Paste")
			(net "GND")
		)
	)
	(footprint ""
		(layer "B.Cu")
		(at 183.3499 -301.599854 -90)
		(property "Reference" "C1450"
			(at 0 0 90)
			(layer "B.SilkS")
			(hide yes)
			(effects
				(font
					(size 1.27 1.27)
				)
				(justify mirror)
			)
		)
		(property "Value" ""
			(at 0 0 90)
			(layer "B.Fab")
			(effects
				(font
					(size 1.27 1.27)
				)
				(justify mirror)
			)
		)
		(duplicate_pad_numbers_are_jumpers no)
		(fp_line
			(start -0.299974 0.150114)
			(end 0.299974 0.150114)
			(stroke
				(width 0.1)
				(type default)
			)
			(layer "B.Fab")
		)
		(fp_line
			(start 0.299974 0.150114)
			(end 0.299974 -0.150114)
			(stroke
				(width 0.1)
				(type default)
			)
			(layer "B.Fab")
		)
		(fp_line
			(start -0.299974 -0.150114)
			(end -0.299974 0.150114)
			(stroke
				(width 0.1)
				(type default)
			)
			(layer "B.Fab")
		)
		(fp_line
			(start 0.299974 -0.150114)
			(end -0.299974 -0.150114)
			(stroke
				(width 0.1)
				(type default)
			)
			(layer "B.Fab")
		)
		(pad "1" smd rect
			(at 0.2667 0 90)
			(size 0.3048 0.381)
			(layers "B.Cu" "B.Mask" "B.Paste")
			(net "P0V8_SERDES_VDDA_PEX1")
		)
		(pad "2" smd rect
			(at -0.2667 0 90)
			(size 0.3048 0.381)
			(layers "B.Cu" "B.Mask" "B.Paste")
			(net "GND")
		)
	)
	(footprint ""
		(layer "B.Cu")
		(at 281.348942 -301.0154 180)
		(property "Reference" "C1639"
			(at 0 0 0)
			(layer "B.SilkS")
			(hide yes)
			(effects
				(font
					(size 1.27 1.27)
				)
				(justify mirror)
			)
		)
		(property "Value" ""
			(at 0 0 0)
			(layer "B.Fab")
			(effects
				(font
					(size 1.27 1.27)
				)
				(justify mirror)
			)
		)
		(duplicate_pad_numbers_are_jumpers no)
		(fp_line
			(start 0.299974 0.150114)
			(end 0.299974 -0.150114)
			(stroke
				(width 0.1)
				(type default)
			)
			(layer "B.Fab")
		)
		(fp_line
			(start 0.299974 -0.150114)
			(end -0.299974 -0.150114)
			(stroke
				(width 0.1)
				(type default)
			)
			(layer "B.Fab")
		)
		(fp_line
			(start -0.299974 0.150114)
			(end 0.299974 0.150114)
			(stroke
				(width 0.1)
				(type default)
			)
			(layer "B.Fab")
		)
		(fp_line
			(start -0.299974 -0.150114)
			(end -0.299974 0.150114)
			(stroke
				(width 0.1)
				(type default)
			)
			(layer "B.Fab")
		)
		(pad "1" smd rect
			(at 0.2667 0)
			(size 0.3048 0.381)
			(layers "B.Cu" "B.Mask" "B.Paste")
			(net "P0V8_PEX2")
		)
		(pad "2" smd rect
			(at -0.2667 0)
			(size 0.3048 0.381)
			(layers "B.Cu" "B.Mask" "B.Paste")
			(net "GND")
		)
	)
	(footprint ""
		(layer "B.Cu")
		(at 221.257114 -208.832704)
		(property "Reference" "C2012"
			(at 0 0 0)
			(layer "B.SilkS")
			(hide yes)
			(effects
				(font
					(size 1.27 1.27)
				)
				(justify mirror)
			)
		)
		(property "Value" ""
			(at 0 0 0)
			(layer "B.Fab")
			(effects
				(font
					(size 1.27 1.27)
				)
				(justify mirror)
			)
		)
		(duplicate_pad_numbers_are_jumpers no)
		(fp_line
			(start -1.2954 -0.5842)
			(end -1.2954 0.5842)
			(stroke
				(width 0.1524)
				(type default)
			)
			(layer "B.SilkS")
		)
		(fp_line
			(start -1.2954 0.5842)
			(end 1.2954 0.5842)
			(stroke
				(width 0.1524)
				(type default)
			)
			(layer "B.SilkS")
		)
		(fp_line
			(start 1.2954 -0.5842)
			(end -1.2954 -0.5842)
			(stroke
				(width 0.1524)
				(type default)
			)
			(layer "B.SilkS")
		)
		(fp_line
			(start 1.2954 0.5842)
			(end 1.2954 -0.5842)
			(stroke
				(width 0.1524)
				(type default)
			)
			(layer "B.SilkS")
		)
		(fp_line
			(start -1.1938 -0.4064)
			(end -1.1938 0.4064)
			(stroke
				(width 0.1)
				(type default)
			)
			(layer "B.Fab")
		)
		(fp_line
			(start -1.1938 0.4064)
			(end -0.8636 0.4064)
			(stroke
				(width 0.1)
				(type default)
			)
			(layer "B.Fab")
		)
		(fp_line
			(start -0.8636 -0.4572)
			(end -0.8636 -0.4064)
			(stroke
				(width 0.1)
				(type default)
			)
			(layer "B.Fab")
		)
		(fp_line
			(start -0.8636 -0.4064)
			(end -1.1938 -0.4064)
			(stroke
				(width 0.1)
				(type default)
			)
			(layer "B.Fab")
		)
		(fp_line
			(start -0.8636 0.4064)
			(end -0.8636 0.4572)
			(stroke
				(width 0.1)
				(type default)
			)
			(layer "B.Fab")
		)
		(fp_line
			(start -0.8636 0.4572)
			(end 0.8636 0.4572)
			(stroke
				(width 0.1)
				(type default)
			)
			(layer "B.Fab")
		)
		(fp_line
			(start 0.8636 -0.4572)
			(end -0.8636 -0.4572)
			(stroke
				(width 0.1)
				(type default)
			)
			(layer "B.Fab")
		)
		(fp_line
			(start 0.8636 -0.4064)
			(end 0.8636 -0.4572)
			(stroke
				(width 0.1)
				(type default)
			)
			(layer "B.Fab")
		)
		(fp_line
			(start 0.8636 0.4064)
			(end 1.1938 0.4064)
			(stroke
				(width 0.1)
				(type default)
			)
			(layer "B.Fab")
		)
		(fp_line
			(start 0.8636 0.4572)
			(end 0.8636 0.4064)
			(stroke
				(width 0.1)
				(type default)
			)
			(layer "B.Fab")
		)
		(fp_line
			(start 1.1938 -0.4064)
			(end 0.8636 -0.4064)
			(stroke
				(width 0.1)
				(type default)
			)
			(layer "B.Fab")
		)
		(fp_line
			(start 1.1938 0.4064)
			(end 1.1938 -0.4064)
			(stroke
				(width 0.1)
				(type default)
			)
			(layer "B.Fab")
		)
		(pad "1" smd rect
			(at 0.7366 0 270)
			(size 0.7112 0.8128)
			(layers "B.Cu" "B.Mask" "B.Paste")
			(net "P3V3_AUX")
		)
		(pad "2" smd rect
			(at -0.7366 0 270)
			(size 0.7112 0.8128)
			(layers "B.Cu" "B.Mask" "B.Paste")
			(net "GND")
		)
	)
	(footprint ""
		(layer "B.Cu")
		(at 405.575008 -297.79976 90)
		(property "Reference" "C1919"
			(at 0 0 90)
			(layer "B.SilkS")
			(hide yes)
			(effects
				(font
					(size 1.27 1.27)
				)
				(justify mirror)
			)
		)
		(property "Value" ""
			(at 0 0 90)
			(layer "B.Fab")
			(effects
				(font
					(size 1.27 1.27)
				)
				(justify mirror)
			)
		)
		(duplicate_pad_numbers_are_jumpers no)
		(fp_line
			(start 0.299974 -0.150114)
			(end -0.299974 -0.150114)
			(stroke
				(width 0.1)
				(type default)
			)
			(layer "B.Fab")
		)
		(fp_line
			(start -0.299974 -0.150114)
			(end -0.299974 0.150114)
			(stroke
				(width 0.1)
				(type default)
			)
			(layer "B.Fab")
		)
		(fp_line
			(start 0.299974 0.150114)
			(end 0.299974 -0.150114)
			(stroke
				(width 0.1)
				(type default)
			)
			(layer "B.Fab")
		)
		(fp_line
			(start -0.299974 0.150114)
			(end 0.299974 0.150114)
			(stroke
				(width 0.1)
				(type default)
			)
			(layer "B.Fab")
		)
		(pad "1" smd rect
			(at 0.2667 0 270)
			(size 0.3048 0.381)
			(layers "B.Cu" "B.Mask" "B.Paste")
			(net "P0V8_PEX3")
		)
		(pad "2" smd rect
			(at -0.2667 0 270)
			(size 0.3048 0.381)
			(layers "B.Cu" "B.Mask" "B.Paste")
			(net "GND")
		)
	)
	(footprint ""
		(layer "B.Cu")
		(at 232.960164 -459.85049)
		(property "Reference" "X75"
			(at 0.1778 -1.92913 0)
			(unlocked yes)
			(layer "B.SilkS")
			(effects
				(font
					(size 0.7874 0.5842)
					(thickness 0.1524)
				)
				(justify left mirror)
			)
		)
		(property "Value" ""
			(at 0 0 0)
			(layer "B.Fab")
			(effects
				(font
					(size 1.27 1.27)
				)
				(justify mirror)
			)
		)
		(property "Device Type" "TP_TDR_4P_FTS_MPKT4_H025P0200_IO_TP15_TP_TDR_4P_DIP"
			(at -1.30175 1.27 270)
			(unlocked yes)
			(layer "B.Fab")
			(hide yes)
			(effects
				(font
					(size 0.635 0.4064)
					(thickness 0.1524)
				)
				(justify mirror)
			)
		)
		(property "User Part Number" "TP15"
			(at -1.30175 1.27 270)
			(unlocked yes)
			(layer "Cmts.User")
			(hide yes)
			(effects
				(font
					(size 0.635 0.4064)
					(thickness 0.1524)
				)
				(justify mirror)
			)
		)
		(duplicate_pad_numbers_are_jumpers no)
		(fp_line
			(start -2.54 -1.27)
			(end 0 -1.27)
			(stroke
				(width 0.1524)
				(type default)
			)
			(layer "B.SilkS")
		)
		(fp_line
			(start -2.54 -1.1303)
			(end -2.54 -1.27)
			(stroke
				(width 0.1524)
				(type default)
			)
			(layer "B.SilkS")
		)
		(fp_line
			(start -2.54 1.4097)
			(end -2.54 1.1303)
			(stroke
				(width 0.1524)
				(type default)
			)
			(layer "B.SilkS")
		)
		(fp_line
			(start -2.54 3.81)
			(end -2.54 3.6703)
			(stroke
				(width 0.1524)
				(type default)
			)
			(layer "B.SilkS")
		)
		(fp_line
			(start 0 -1.27)
			(end 0 -0.635)
			(stroke
				(width 0.1524)
				(type default)
			)
			(layer "B.SilkS")
		)
		(fp_line
			(start 0 0.635)
			(end 0 1.905)
			(stroke
				(width 0.1524)
				(type default)
			)
			(layer "B.SilkS")
		)
		(fp_line
			(start 0 3.175)
			(end 0 3.81)
			(stroke
				(width 0.1524)
				(type default)
			)
			(layer "B.SilkS")
		)
		(fp_line
			(start 0 3.81)
			(end -2.54 3.81)
			(stroke
				(width 0.1524)
				(type default)
			)
			(layer "B.SilkS")
		)
		(fp_poly
			(pts
				(xy 0.761746 0) (xy 2.285746 -0.762) (xy 2.285746 0.762)
			)
			(stroke
				(width 0)
				(type default)
			)
			(fill yes)
			(layer "B.SilkS")
		)
		(fp_line
			(start -2.54 -1.27)
			(end 0 -1.27)
			(stroke
				(width 0.1)
				(type default)
			)
			(layer "B.Fab")
		)
		(fp_line
			(start -2.54 3.81)
			(end -2.54 -1.27)
			(stroke
				(width 0.1)
				(type default)
			)
			(layer "B.Fab")
		)
		(fp_line
			(start 0 -1.27)
			(end 0 3.81)
			(stroke
				(width 0.1)
				(type default)
			)
			(layer "B.Fab")
		)
		(fp_line
			(start 0 3.81)
			(end -2.54 3.81)
			(stroke
				(width 0.1)
				(type default)
			)
			(layer "B.Fab")
		)
		(fp_poly
			(pts
				(xy 0.761746 0) (xy 2.285746 -0.762) (xy 2.285746 0.762)
			)
			(stroke
				(width 0)
				(type default)
			)
			(fill yes)
			(layer "B.Fab")
		)
		(pad "1" thru_hole circle
			(at 0 0 180)
			(size 1.0033 1.0033)
			(drill 0.249936)
			(layers "*.Cu" "*.Mask")
			(remove_unused_layers no)
			(net "TDR_DIFF_100_IN4_DIN")
			(clearance 0.10795)
			(padstack
				(mode front_inner_back)
				(layer "Inner"
					(shape circle)
					(size 0.8001 0.8001)
					(clearance 0.1524)
				)
				(layer "B.Cu"
					(shape circle)
					(size 1.0033 1.0033)
					(thermal_gap 0.10795)
					(clearance 0.10795)
				)
			)
		)
		(pad "2" thru_hole circle
			(at -2.54 0 180)
			(size 1.9939 1.9939)
			(drill 0.249936)
			(layers "*.Cu" "*.Mask")
			(remove_unused_layers no)
			(net "COUPON_GND1")
			(clearance 0.10795)
			(padstack
				(mode front_inner_back)
				(layer "Inner"
					(shape circle)
					(size 0.8001 0.8001)
					(clearance 0.1524)
				)
				(layer "B.Cu"
					(shape circle)
					(size 1.9939 1.9939)
					(thermal_gap 0.10795)
					(clearance 0.10795)
				)
			)
		)
		(pad "3" thru_hole circle
			(at -2.54 2.54 180)
			(size 1.9939 1.9939)
			(drill 0.249936)
			(layers "*.Cu" "*.Mask")
			(remove_unused_layers no)
			(net "COUPON_GND1")
			(clearance 0.10795)
			(padstack
				(mode front_inner_back)
				(layer "Inner"
					(shape circle)
					(size 0.8001 0.8001)
					(clearance 0.1524)
				)
				(layer "B.Cu"
					(shape circle)
					(size 1.9939 1.9939)
					(thermal_gap 0.10795)
					(clearance 0.10795)
				)
			)
		)
		(pad "4" thru_hole circle
			(at 0 2.54 180)
			(size 1.0033 1.0033)
			(drill 0.249936)
			(layers "*.Cu" "*.Mask")
			(remove_unused_layers no)
			(net "TDR_DIFF_100_IN4_DIP")
			(clearance 0.10795)
			(padstack
				(mode front_inner_back)
				(layer "Inner"
					(shape circle)
					(size 0.8001 0.8001)
					(clearance 0.1524)
				)
				(layer "B.Cu"
					(shape circle)
					(size 1.0033 1.0033)
					(thermal_gap 0.10795)
					(clearance 0.10795)
				)
			)
		)
	)
	(footprint ""
		(layer "B.Cu")
		(at 212.09 -207.899 90)
		(property "Reference" "R1514"
			(at 0 0 90)
			(layer "B.SilkS")
			(hide yes)
			(effects
				(font
					(size 1.27 1.27)
				)
				(justify mirror)
			)
		)
		(property "Value" ""
			(at 0 0 90)
			(layer "B.Fab")
			(effects
				(font
					(size 1.27 1.27)
				)
				(justify mirror)
			)
		)
		(duplicate_pad_numbers_are_jumpers no)
		(fp_line
			(start 0.7874 -0.4064)
			(end -0.7874 -0.4064)
			(stroke
				(width 0.1524)
				(type default)
			)
			(layer "B.SilkS")
		)
		(fp_line
			(start -0.7874 -0.4064)
			(end -0.7874 0.4064)
			(stroke
				(width 0.1524)
				(type default)
			)
			(layer "B.SilkS")
		)
		(fp_line
			(start 0.7874 0.4064)
			(end 0.7874 -0.4064)
			(stroke
				(width 0.1524)
				(type default)
			)
			(layer "B.SilkS")
		)
		(fp_line
			(start -0.7874 0.4064)
			(end 0.7874 0.4064)
			(stroke
				(width 0.1524)
				(type default)
			)
			(layer "B.SilkS")
		)
		(fp_line
			(start 0.67945 -0.305054)
			(end 0.12065 -0.305054)
			(stroke
				(width 0.1)
				(type default)
			)
			(layer "B.Fab")
		)
		(fp_line
			(start 0.12065 -0.305054)
			(end 0.12065 -0.2794)
			(stroke
				(width 0.1)
				(type default)
			)
			(layer "B.Fab")
		)
		(fp_line
			(start -0.12065 -0.3048)
			(end -0.67945 -0.3048)
			(stroke
				(width 0.1)
				(type default)
			)
			(layer "B.Fab")
		)
		(fp_line
			(start -0.67945 -0.3048)
			(end -0.67945 0.3048)
			(stroke
				(width 0.1)
				(type default)
			)
			(layer "B.Fab")
		)
		(fp_line
			(start 0.12065 -0.2794)
			(end -0.12065 -0.2794)
			(stroke
				(width 0.1)
				(type default)
			)
			(layer "B.Fab")
		)
		(fp_line
			(start -0.12065 -0.2794)
			(end -0.12065 -0.3048)
			(stroke
				(width 0.1)
				(type default)
			)
			(layer "B.Fab")
		)
		(fp_line
			(start 0.12065 0.2794)
			(end 0.12065 0.3048)
			(stroke
				(width 0.1)
				(type default)
			)
			(layer "B.Fab")
		)
		(fp_line
			(start -0.120396 0.2794)
			(end 0.12065 0.2794)
			(stroke
				(width 0.1)
				(type default)
			)
			(layer "B.Fab")
		)
		(fp_line
			(start 0.67945 0.3048)
			(end 0.67945 -0.305054)
			(stroke
				(width 0.1)
				(type default)
			)
			(layer "B.Fab")
		)
		(fp_line
			(start 0.12065 0.3048)
			(end 0.67945 0.3048)
			(stroke
				(width 0.1)
				(type default)
			)
			(layer "B.Fab")
		)
		(fp_line
			(start -0.120396 0.3048)
			(end -0.120396 0.2794)
			(stroke
				(width 0.1)
				(type default)
			)
			(layer "B.Fab")
		)
		(fp_line
			(start -0.67945 0.3048)
			(end -0.120396 0.3048)
			(stroke
				(width 0.1)
				(type default)
			)
			(layer "B.Fab")
		)
		(pad "1" smd circle
			(at 0.40005 0 270)
			(size 0 0)
			(layers "B.Cu" "B.Mask" "B.Paste")
			(net "SMB_NIC4_LS_R_SDA")
		)
		(pad "2" smd circle
			(at -0.40005 0 270)
			(size 0 0)
			(layers "B.Cu" "B.Mask" "B.Paste")
			(net "SMB_NIC4_R_SDA")
		)
	)
	(footprint ""
		(layer "B.Cu")
		(at 119.722392 -308.580028 90)
		(property "Reference" "C1413"
			(at 0 0 90)
			(layer "B.SilkS")
			(hide yes)
			(effects
				(font
					(size 1.27 1.27)
				)
				(justify mirror)
			)
		)
		(property "Value" ""
			(at 0 0 90)
			(layer "B.Fab")
			(effects
				(font
					(size 1.27 1.27)
				)
				(justify mirror)
			)
		)
		(duplicate_pad_numbers_are_jumpers no)
		(fp_line
			(start 1.2954 -0.5842)
			(end -1.2954 -0.5842)
			(stroke
				(width 0.1524)
				(type default)
			)
			(layer "B.SilkS")
		)
		(fp_line
			(start -1.2954 -0.5842)
			(end -1.2954 0.5842)
			(stroke
				(width 0.1524)
				(type default)
			)
			(layer "B.SilkS")
		)
		(fp_line
			(start 1.2954 0.5842)
			(end 1.2954 -0.5842)
			(stroke
				(width 0.1524)
				(type default)
			)
			(layer "B.SilkS")
		)
		(fp_line
			(start -1.2954 0.5842)
			(end 1.2954 0.5842)
			(stroke
				(width 0.1524)
				(type default)
			)
			(layer "B.SilkS")
		)
		(fp_line
			(start 0.8636 -0.4572)
			(end -0.8636 -0.4572)
			(stroke
				(width 0.1)
				(type default)
			)
			(layer "B.Fab")
		)
		(fp_line
			(start -0.8636 -0.4572)
			(end -0.8636 -0.4064)
			(stroke
				(width 0.1)
				(type default)
			)
			(layer "B.Fab")
		)
		(fp_line
			(start 1.1938 -0.4064)
			(end 0.8636 -0.4064)
			(stroke
				(width 0.1)
				(type default)
			)
			(layer "B.Fab")
		)
		(fp_line
			(start 0.8636 -0.4064)
			(end 0.8636 -0.4572)
			(stroke
				(width 0.1)
				(type default)
			)
			(layer "B.Fab")
		)
		(fp_line
			(start -0.8636 -0.4064)
			(end -1.1938 -0.4064)
			(stroke
				(width 0.1)
				(type default)
			)
			(layer "B.Fab")
		)
		(fp_line
			(start -1.1938 -0.4064)
			(end -1.1938 0.4064)
			(stroke
				(width 0.1)
				(type default)
			)
			(layer "B.Fab")
		)
		(fp_line
			(start 1.1938 0.4064)
			(end 1.1938 -0.4064)
			(stroke
				(width 0.1)
				(type default)
			)
			(layer "B.Fab")
		)
		(fp_line
			(start 0.8636 0.4064)
			(end 1.1938 0.4064)
			(stroke
				(width 0.1)
				(type default)
			)
			(layer "B.Fab")
		)
		(fp_line
			(start -0.8636 0.4064)
			(end -0.8636 0.4572)
			(stroke
				(width 0.1)
				(type default)
			)
			(layer "B.Fab")
		)
		(fp_line
			(start -1.1938 0.4064)
			(end -0.8636 0.4064)
			(stroke
				(width 0.1)
				(type default)
			)
			(layer "B.Fab")
		)
		(fp_line
			(start 0.8636 0.4572)
			(end 0.8636 0.4064)
			(stroke
				(width 0.1)
				(type default)
			)
			(layer "B.Fab")
		)
		(fp_line
			(start -0.8636 0.4572)
			(end 0.8636 0.4572)
			(stroke
				(width 0.1)
				(type default)
			)
			(layer "B.Fab")
		)
		(pad "1" smd rect
			(at 0.7366 0)
			(size 0.7112 0.8128)
			(layers "B.Cu" "B.Mask" "B.Paste")
			(net "P0V8_SERDES_VDDA_PEX1")
		)
		(pad "2" smd rect
			(at -0.7366 0)
			(size 0.7112 0.8128)
			(layers "B.Cu" "B.Mask" "B.Paste")
			(net "GND")
		)
	)
	(footprint ""
		(layer "B.Cu")
		(at 358.604566 -285.607506 -90)
		(property "Reference" "PR7182"
			(at 0 0 90)
			(layer "B.SilkS")
			(hide yes)
			(effects
				(font
					(size 1.27 1.27)
				)
				(justify mirror)
			)
		)
		(property "Value" ""
			(at 0 0 90)
			(layer "B.Fab")
			(effects
				(font
					(size 1.27 1.27)
				)
				(justify mirror)
			)
		)
		(duplicate_pad_numbers_are_jumpers no)
		(fp_line
			(start -0.7874 0.4064)
			(end 0.7874 0.4064)
			(stroke
				(width 0.1524)
				(type default)
			)
			(layer "B.SilkS")
		)
		(fp_line
			(start 0.7874 0.4064)
			(end 0.7874 -0.4064)
			(stroke
				(width 0.1524)
				(type default)
			)
			(layer "B.SilkS")
		)
		(fp_line
			(start -0.7874 -0.4064)
			(end -0.7874 0.4064)
			(stroke
				(width 0.1524)
				(type default)
			)
			(layer "B.SilkS")
		)
		(fp_line
			(start 0.7874 -0.4064)
			(end -0.7874 -0.4064)
			(stroke
				(width 0.1524)
				(type default)
			)
			(layer "B.SilkS")
		)
		(fp_line
			(start -0.67945 0.3048)
			(end -0.120396 0.3048)
			(stroke
				(width 0.1)
				(type default)
			)
			(layer "B.Fab")
		)
		(fp_line
			(start -0.120396 0.3048)
			(end -0.120396 0.2794)
			(stroke
				(width 0.1)
				(type default)
			)
			(layer "B.Fab")
		)
		(fp_line
			(start 0.12065 0.3048)
			(end 0.67945 0.3048)
			(stroke
				(width 0.1)
				(type default)
			)
			(layer "B.Fab")
		)
		(fp_line
			(start 0.67945 0.3048)
			(end 0.67945 -0.305054)
			(stroke
				(width 0.1)
				(type default)
			)
			(layer "B.Fab")
		)
		(fp_line
			(start -0.120396 0.2794)
			(end 0.12065 0.2794)
			(stroke
				(width 0.1)
				(type default)
			)
			(layer "B.Fab")
		)
		(fp_line
			(start 0.12065 0.2794)
			(end 0.12065 0.3048)
			(stroke
				(width 0.1)
				(type default)
			)
			(layer "B.Fab")
		)
		(fp_line
			(start -0.12065 -0.2794)
			(end -0.12065 -0.3048)
			(stroke
				(width 0.1)
				(type default)
			)
			(layer "B.Fab")
		)
		(fp_line
			(start 0.12065 -0.2794)
			(end -0.12065 -0.2794)
			(stroke
				(width 0.1)
				(type default)
			)
			(layer "B.Fab")
		)
		(fp_line
			(start -0.67945 -0.3048)
			(end -0.67945 0.3048)
			(stroke
				(width 0.1)
				(type default)
			)
			(layer "B.Fab")
		)
		(fp_line
			(start -0.12065 -0.3048)
			(end -0.67945 -0.3048)
			(stroke
				(width 0.1)
				(type default)
			)
			(layer "B.Fab")
		)
		(fp_line
			(start 0.12065 -0.305054)
			(end 0.12065 -0.2794)
			(stroke
				(width 0.1)
				(type default)
			)
			(layer "B.Fab")
		)
		(fp_line
			(start 0.67945 -0.305054)
			(end 0.12065 -0.305054)
			(stroke
				(width 0.1)
				(type default)
			)
			(layer "B.Fab")
		)
		(pad "1" smd circle
			(at 0.40005 0 90)
			(size 0 0)
			(layers "B.Cu" "B.Mask" "B.Paste")
			(net "P0V8_PEX3_PVCC")
		)
		(pad "2" smd circle
			(at -0.40005 0 90)
			(size 0 0)
			(layers "B.Cu" "B.Mask" "B.Paste")
			(net "P5V_AUX")
		)
	)
	(footprint ""
		(layer "B.Cu")
		(at 129.207006 -275.81606 180)
		(property "Reference" "PC6613"
			(at 0 0 0)
			(layer "B.SilkS")
			(hide yes)
			(effects
				(font
					(size 1.27 1.27)
				)
				(justify mirror)
			)
		)
		(property "Value" ""
			(at 0 0 0)
			(layer "B.Fab")
			(effects
				(font
					(size 1.27 1.27)
				)
				(justify mirror)
			)
		)
		(duplicate_pad_numbers_are_jumpers no)
		(fp_line
			(start 1.524 0.762)
			(end 1.524 -0.762)
			(stroke
				(width 0.1524)
				(type default)
			)
			(layer "B.SilkS")
		)
		(fp_line
			(start 1.524 -0.762)
			(end -1.524 -0.762)
			(stroke
				(width 0.1524)
				(type default)
			)
			(layer "B.SilkS")
		)
		(fp_line
			(start -1.524 0.762)
			(end 1.524 0.762)
			(stroke
				(width 0.1524)
				(type default)
			)
			(layer "B.SilkS")
		)
		(fp_line
			(start -1.524 -0.762)
			(end -1.524 0.762)
			(stroke
				(width 0.1524)
				(type default)
			)
			(layer "B.SilkS")
		)
		(fp_line
			(start 1.1049 0.724916)
			(end -1.1049 0.724916)
			(stroke
				(width 0.1)
				(type default)
			)
			(layer "B.Fab")
		)
		(fp_line
			(start 1.1049 -0.724916)
			(end 1.1049 0.724916)
			(stroke
				(width 0.1)
				(type default)
			)
			(layer "B.Fab")
		)
		(fp_line
			(start -1.1049 0.724916)
			(end -1.1049 -0.724916)
			(stroke
				(width 0.1)
				(type default)
			)
			(layer "B.Fab")
		)
		(fp_line
			(start -1.1049 -0.724916)
			(end 1.1049 -0.724916)
			(stroke
				(width 0.1)
				(type default)
			)
			(layer "B.Fab")
		)
		(pad "1" smd rect
			(at 0.889 0 180)
			(size 1.016 1.27)
			(layers "B.Cu" "B.Mask" "B.Paste")
			(net "SW_P12V_P0V8_PEX1_FLT")
		)
		(pad "2" smd rect
			(at -0.889 0 180)
			(size 1.016 1.27)
			(layers "B.Cu" "B.Mask" "B.Paste")
			(net "GND")
		)
	)
	(footprint ""
		(layer "B.Cu")
		(at 234.74553 -275.632672)
		(property "Reference" "C4331"
			(at 0 0 0)
			(layer "B.SilkS")
			(hide yes)
			(effects
				(font
					(size 1.27 1.27)
				)
				(justify mirror)
			)
		)
		(property "Value" ""
			(at 0 0 0)
			(layer "B.Fab")
			(effects
				(font
					(size 1.27 1.27)
				)
				(justify mirror)
			)
		)
		(duplicate_pad_numbers_are_jumpers no)
		(fp_line
			(start -1.2954 -0.5842)
			(end -1.2954 0.5842)
			(stroke
				(width 0.1524)
				(type default)
			)
			(layer "B.SilkS")
		)
		(fp_line
			(start -1.2954 0.5842)
			(end 1.2954 0.5842)
			(stroke
				(width 0.1524)
				(type default)
			)
			(layer "B.SilkS")
		)
		(fp_line
			(start 1.2954 -0.5842)
			(end -1.2954 -0.5842)
			(stroke
				(width 0.1524)
				(type default)
			)
			(layer "B.SilkS")
		)
		(fp_line
			(start 1.2954 0.5842)
			(end 1.2954 -0.5842)
			(stroke
				(width 0.1524)
				(type default)
			)
			(layer "B.SilkS")
		)
		(fp_line
			(start -1.1938 -0.4064)
			(end -1.1938 0.4064)
			(stroke
				(width 0.1)
				(type default)
			)
			(layer "B.Fab")
		)
		(fp_line
			(start -1.1938 0.4064)
			(end -0.8636 0.4064)
			(stroke
				(width 0.1)
				(type default)
			)
			(layer "B.Fab")
		)
		(fp_line
			(start -0.8636 -0.4572)
			(end -0.8636 -0.4064)
			(stroke
				(width 0.1)
				(type default)
			)
			(layer "B.Fab")
		)
		(fp_line
			(start -0.8636 -0.4064)
			(end -1.1938 -0.4064)
			(stroke
				(width 0.1)
				(type default)
			)
			(layer "B.Fab")
		)
		(fp_line
			(start -0.8636 0.4064)
			(end -0.8636 0.4572)
			(stroke
				(width 0.1)
				(type default)
			)
			(layer "B.Fab")
		)
		(fp_line
			(start -0.8636 0.4572)
			(end 0.8636 0.4572)
			(stroke
				(width 0.1)
				(type default)
			)
			(layer "B.Fab")
		)
		(fp_line
			(start 0.8636 -0.4572)
			(end -0.8636 -0.4572)
			(stroke
				(width 0.1)
				(type default)
			)
			(layer "B.Fab")
		)
		(fp_line
			(start 0.8636 -0.4064)
			(end 0.8636 -0.4572)
			(stroke
				(width 0.1)
				(type default)
			)
			(layer "B.Fab")
		)
		(fp_line
			(start 0.8636 0.4064)
			(end 1.1938 0.4064)
			(stroke
				(width 0.1)
				(type default)
			)
			(layer "B.Fab")
		)
		(fp_line
			(start 0.8636 0.4572)
			(end 0.8636 0.4064)
			(stroke
				(width 0.1)
				(type default)
			)
			(layer "B.Fab")
		)
		(fp_line
			(start 1.1938 -0.4064)
			(end 0.8636 -0.4064)
			(stroke
				(width 0.1)
				(type default)
			)
			(layer "B.Fab")
		)
		(fp_line
			(start 1.1938 0.4064)
			(end 1.1938 -0.4064)
			(stroke
				(width 0.1)
				(type default)
			)
			(layer "B.Fab")
		)
		(pad "1" smd rect
			(at 0.7366 0 270)
			(size 0.7112 0.8128)
			(layers "B.Cu" "B.Mask" "B.Paste")
			(net "P1V25_PEX2")
		)
		(pad "2" smd rect
			(at -0.7366 0 270)
			(size 0.7112 0.8128)
			(layers "B.Cu" "B.Mask" "B.Paste")
			(net "GND")
		)
	)
	(footprint ""
		(layer "B.Cu")
		(at 404.149814 -303.499774 -90)
		(property "Reference" "C3431"
			(at 0 0 90)
			(layer "B.SilkS")
			(hide yes)
			(effects
				(font
					(size 1.27 1.27)
				)
				(justify mirror)
			)
		)
		(property "Value" ""
			(at 0 0 90)
			(layer "B.Fab")
			(effects
				(font
					(size 1.27 1.27)
				)
				(justify mirror)
			)
		)
		(duplicate_pad_numbers_are_jumpers no)
		(fp_line
			(start -0.299974 0.150114)
			(end 0.299974 0.150114)
			(stroke
				(width 0.1)
				(type default)
			)
			(layer "B.Fab")
		)
		(fp_line
			(start 0.299974 0.150114)
			(end 0.299974 -0.150114)
			(stroke
				(width 0.1)
				(type default)
			)
			(layer "B.Fab")
		)
		(fp_line
			(start -0.299974 -0.150114)
			(end -0.299974 0.150114)
			(stroke
				(width 0.1)
				(type default)
			)
			(layer "B.Fab")
		)
		(fp_line
			(start 0.299974 -0.150114)
			(end -0.299974 -0.150114)
			(stroke
				(width 0.1)
				(type default)
			)
			(layer "B.Fab")
		)
		(pad "1" smd rect
			(at 0.2667 0 90)
			(size 0.3048 0.381)
			(layers "B.Cu" "B.Mask" "B.Paste")
			(net "P1V25_PEX3")
		)
		(pad "2" smd rect
			(at -0.2667 0 90)
			(size 0.3048 0.381)
			(layers "B.Cu" "B.Mask" "B.Paste")
			(net "GND")
		)
	)
	(footprint ""
		(layer "B.Cu")
		(at 289.630104 -295.221914)
		(property "Reference" "C1610"
			(at 0 0 0)
			(layer "B.SilkS")
			(hide yes)
			(effects
				(font
					(size 1.27 1.27)
				)
				(justify mirror)
			)
		)
		(property "Value" ""
			(at 0 0 0)
			(layer "B.Fab")
			(effects
				(font
					(size 1.27 1.27)
				)
				(justify mirror)
			)
		)
		(duplicate_pad_numbers_are_jumpers no)
		(fp_line
			(start -1.2954 -0.5842)
			(end -1.2954 0.5842)
			(stroke
				(width 0.1524)
				(type default)
			)
			(layer "B.SilkS")
		)
		(fp_line
			(start -1.2954 0.5842)
			(end 1.2954 0.5842)
			(stroke
				(width 0.1524)
				(type default)
			)
			(layer "B.SilkS")
		)
		(fp_line
			(start 1.2954 -0.5842)
			(end -1.2954 -0.5842)
			(stroke
				(width 0.1524)
				(type default)
			)
			(layer "B.SilkS")
		)
		(fp_line
			(start 1.2954 0.5842)
			(end 1.2954 -0.5842)
			(stroke
				(width 0.1524)
				(type default)
			)
			(layer "B.SilkS")
		)
		(fp_line
			(start -1.1938 -0.4064)
			(end -1.1938 0.4064)
			(stroke
				(width 0.1)
				(type default)
			)
			(layer "B.Fab")
		)
		(fp_line
			(start -1.1938 0.4064)
			(end -0.8636 0.4064)
			(stroke
				(width 0.1)
				(type default)
			)
			(layer "B.Fab")
		)
		(fp_line
			(start -0.8636 -0.4572)
			(end -0.8636 -0.4064)
			(stroke
				(width 0.1)
				(type default)
			)
			(layer "B.Fab")
		)
		(fp_line
			(start -0.8636 -0.4064)
			(end -1.1938 -0.4064)
			(stroke
				(width 0.1)
				(type default)
			)
			(layer "B.Fab")
		)
		(fp_line
			(start -0.8636 0.4064)
			(end -0.8636 0.4572)
			(stroke
				(width 0.1)
				(type default)
			)
			(layer "B.Fab")
		)
		(fp_line
			(start -0.8636 0.4572)
			(end 0.8636 0.4572)
			(stroke
				(width 0.1)
				(type default)
			)
			(layer "B.Fab")
		)
		(fp_line
			(start 0.8636 -0.4572)
			(end -0.8636 -0.4572)
			(stroke
				(width 0.1)
				(type default)
			)
			(layer "B.Fab")
		)
		(fp_line
			(start 0.8636 -0.4064)
			(end 0.8636 -0.4572)
			(stroke
				(width 0.1)
				(type default)
			)
			(layer "B.Fab")
		)
		(fp_line
			(start 0.8636 0.4064)
			(end 1.1938 0.4064)
			(stroke
				(width 0.1)
				(type default)
			)
			(layer "B.Fab")
		)
		(fp_line
			(start 0.8636 0.4572)
			(end 0.8636 0.4064)
			(stroke
				(width 0.1)
				(type default)
			)
			(layer "B.Fab")
		)
		(fp_line
			(start 1.1938 -0.4064)
			(end 0.8636 -0.4064)
			(stroke
				(width 0.1)
				(type default)
			)
			(layer "B.Fab")
		)
		(fp_line
			(start 1.1938 0.4064)
			(end 1.1938 -0.4064)
			(stroke
				(width 0.1)
				(type default)
			)
			(layer "B.Fab")
		)
		(pad "1" smd rect
			(at 0.7366 0 270)
			(size 0.7112 0.8128)
			(layers "B.Cu" "B.Mask" "B.Paste")
			(net "P0V8_PEX2")
		)
		(pad "2" smd rect
			(at -0.7366 0 270)
			(size 0.7112 0.8128)
			(layers "B.Cu" "B.Mask" "B.Paste")
			(net "GND")
		)
	)
	(footprint ""
		(layer "B.Cu")
		(at 460.169006 -284.375606 180)
		(property "Reference" "PC274"
			(at 0 0 0)
			(layer "B.SilkS")
			(hide yes)
			(effects
				(font
					(size 1.27 1.27)
				)
				(justify mirror)
			)
		)
		(property "Value" ""
			(at 0 0 0)
			(layer "B.Fab")
			(effects
				(font
					(size 1.27 1.27)
				)
				(justify mirror)
			)
		)
		(duplicate_pad_numbers_are_jumpers no)
		(fp_line
			(start 1.524 0.762)
			(end 1.524 -0.762)
			(stroke
				(width 0.1524)
				(type default)
			)
			(layer "B.SilkS")
		)
		(fp_line
			(start 1.524 -0.762)
			(end -1.524 -0.762)
			(stroke
				(width 0.1524)
				(type default)
			)
			(layer "B.SilkS")
		)
		(fp_line
			(start -1.524 0.762)
			(end 1.524 0.762)
			(stroke
				(width 0.1524)
				(type default)
			)
			(layer "B.SilkS")
		)
		(fp_line
			(start -1.524 -0.762)
			(end -1.524 0.762)
			(stroke
				(width 0.1524)
				(type default)
			)
			(layer "B.SilkS")
		)
		(fp_line
			(start 1.1049 0.724916)
			(end -1.1049 0.724916)
			(stroke
				(width 0.1)
				(type default)
			)
			(layer "B.Fab")
		)
		(fp_line
			(start 1.1049 -0.724916)
			(end 1.1049 0.724916)
			(stroke
				(width 0.1)
				(type default)
			)
			(layer "B.Fab")
		)
		(fp_line
			(start -1.1049 0.724916)
			(end -1.1049 -0.724916)
			(stroke
				(width 0.1)
				(type default)
			)
			(layer "B.Fab")
		)
		(fp_line
			(start -1.1049 -0.724916)
			(end 1.1049 -0.724916)
			(stroke
				(width 0.1)
				(type default)
			)
			(layer "B.Fab")
		)
		(pad "1" smd rect
			(at 0.889 0 180)
			(size 1.016 1.27)
			(layers "B.Cu" "B.Mask" "B.Paste")
			(net "P1V25_PEX3_R")
		)
		(pad "2" smd rect
			(at -0.889 0 180)
			(size 1.016 1.27)
			(layers "B.Cu" "B.Mask" "B.Paste")
			(net "GND")
		)
	)
	(footprint ""
		(layer "B.Cu")
		(at 297.10126 -305.399948 -90)
		(property "Reference" "C3302"
			(at 0 0 90)
			(layer "B.SilkS")
			(hide yes)
			(effects
				(font
					(size 1.27 1.27)
				)
				(justify mirror)
			)
		)
		(property "Value" ""
			(at 0 0 90)
			(layer "B.Fab")
			(effects
				(font
					(size 1.27 1.27)
				)
				(justify mirror)
			)
		)
		(duplicate_pad_numbers_are_jumpers no)
		(fp_line
			(start -0.299974 0.150114)
			(end 0.299974 0.150114)
			(stroke
				(width 0.1)
				(type default)
			)
			(layer "B.Fab")
		)
		(fp_line
			(start 0.299974 0.150114)
			(end 0.299974 -0.150114)
			(stroke
				(width 0.1)
				(type default)
			)
			(layer "B.Fab")
		)
		(fp_line
			(start -0.299974 -0.150114)
			(end -0.299974 0.150114)
			(stroke
				(width 0.1)
				(type default)
			)
			(layer "B.Fab")
		)
		(fp_line
			(start 0.299974 -0.150114)
			(end -0.299974 -0.150114)
			(stroke
				(width 0.1)
				(type default)
			)
			(layer "B.Fab")
		)
		(pad "1" smd rect
			(at 0.2667 0 90)
			(size 0.3048 0.381)
			(layers "B.Cu" "B.Mask" "B.Paste")
			(net "P1V25_SERDES_VDDPLL_PEX2")
		)
		(pad "2" smd rect
			(at -0.2667 0 90)
			(size 0.3048 0.381)
			(layers "B.Cu" "B.Mask" "B.Paste")
			(net "GND")
		)
	)
	(footprint ""
		(layer "B.Cu")
		(at 224.675192 -277.73503 180)
		(property "Reference" "C4289"
			(at 0 0 0)
			(layer "B.SilkS")
			(hide yes)
			(effects
				(font
					(size 1.27 1.27)
				)
				(justify mirror)
			)
		)
		(property "Value" ""
			(at 0 0 0)
			(layer "B.Fab")
			(effects
				(font
					(size 1.27 1.27)
				)
				(justify mirror)
			)
		)
		(duplicate_pad_numbers_are_jumpers no)
		(fp_line
			(start 1.2954 0.5842)
			(end 1.2954 -0.5842)
			(stroke
				(width 0.1524)
				(type default)
			)
			(layer "B.SilkS")
		)
		(fp_line
			(start 1.2954 -0.5842)
			(end -1.2954 -0.5842)
			(stroke
				(width 0.1524)
				(type default)
			)
			(layer "B.SilkS")
		)
		(fp_line
			(start -1.2954 0.5842)
			(end 1.2954 0.5842)
			(stroke
				(width 0.1524)
				(type default)
			)
			(layer "B.SilkS")
		)
		(fp_line
			(start -1.2954 -0.5842)
			(end -1.2954 0.5842)
			(stroke
				(width 0.1524)
				(type default)
			)
			(layer "B.SilkS")
		)
		(fp_line
			(start 1.1938 0.4064)
			(end 1.1938 -0.4064)
			(stroke
				(width 0.1)
				(type default)
			)
			(layer "B.Fab")
		)
		(fp_line
			(start 1.1938 -0.4064)
			(end 0.8636 -0.4064)
			(stroke
				(width 0.1)
				(type default)
			)
			(layer "B.Fab")
		)
		(fp_line
			(start 0.8636 0.4572)
			(end 0.8636 0.4064)
			(stroke
				(width 0.1)
				(type default)
			)
			(layer "B.Fab")
		)
		(fp_line
			(start 0.8636 0.4064)
			(end 1.1938 0.4064)
			(stroke
				(width 0.1)
				(type default)
			)
			(layer "B.Fab")
		)
		(fp_line
			(start 0.8636 -0.4064)
			(end 0.8636 -0.4572)
			(stroke
				(width 0.1)
				(type default)
			)
			(layer "B.Fab")
		)
		(fp_line
			(start 0.8636 -0.4572)
			(end -0.8636 -0.4572)
			(stroke
				(width 0.1)
				(type default)
			)
			(layer "B.Fab")
		)
		(fp_line
			(start -0.8636 0.4572)
			(end 0.8636 0.4572)
			(stroke
				(width 0.1)
				(type default)
			)
			(layer "B.Fab")
		)
		(fp_line
			(start -0.8636 0.4064)
			(end -0.8636 0.4572)
			(stroke
				(width 0.1)
				(type default)
			)
			(layer "B.Fab")
		)
		(fp_line
			(start -0.8636 -0.4064)
			(end -1.1938 -0.4064)
			(stroke
				(width 0.1)
				(type default)
			)
			(layer "B.Fab")
		)
		(fp_line
			(start -0.8636 -0.4572)
			(end -0.8636 -0.4064)
			(stroke
				(width 0.1)
				(type default)
			)
			(layer "B.Fab")
		)
		(fp_line
			(start -1.1938 0.4064)
			(end -0.8636 0.4064)
			(stroke
				(width 0.1)
				(type default)
			)
			(layer "B.Fab")
		)
		(fp_line
			(start -1.1938 -0.4064)
			(end -1.1938 0.4064)
			(stroke
				(width 0.1)
				(type default)
			)
			(layer "B.Fab")
		)
		(pad "1" smd rect
			(at 0.7366 0 90)
			(size 0.7112 0.8128)
			(layers "B.Cu" "B.Mask" "B.Paste")
			(net "P1V25_PEX1")
		)
		(pad "2" smd rect
			(at -0.7366 0 90)
			(size 0.7112 0.8128)
			(layers "B.Cu" "B.Mask" "B.Paste")
			(net "GND")
		)
	)
	(footprint ""
		(layer "B.Cu")
		(at 380.990602 -236.40796 180)
		(property "Reference" "L5"
			(at 0 0 0)
			(layer "B.SilkS")
			(hide yes)
			(effects
				(font
					(size 1.27 1.27)
				)
				(justify mirror)
			)
		)
		(property "Value" ""
			(at 0 0 0)
			(layer "B.Fab")
			(effects
				(font
					(size 1.27 1.27)
				)
				(justify mirror)
			)
		)
		(duplicate_pad_numbers_are_jumpers no)
		(fp_line
			(start 1.27 0.5842)
			(end 1.27 -0.5842)
			(stroke
				(width 0.1524)
				(type default)
			)
			(layer "B.SilkS")
		)
		(fp_line
			(start 1.27 -0.5588)
			(end 1.27 -0.5842)
			(stroke
				(width 0.1524)
				(type default)
			)
			(layer "B.SilkS")
		)
		(fp_line
			(start 1.27 -0.5842)
			(end -1.27 -0.5842)
			(stroke
				(width 0.1524)
				(type default)
			)
			(layer "B.SilkS")
		)
		(fp_line
			(start -1.27 0.5842)
			(end 1.27 0.5842)
			(stroke
				(width 0.1524)
				(type default)
			)
			(layer "B.SilkS")
		)
		(fp_line
			(start -1.27 0.5842)
			(end -1.27 -0.5842)
			(stroke
				(width 0.1524)
				(type default)
			)
			(layer "B.SilkS")
		)
		(fp_line
			(start 1.194308 0.406654)
			(end 1.194308 -0.406654)
			(stroke
				(width 0.1)
				(type default)
			)
			(layer "B.Fab")
		)
		(fp_line
			(start 1.194308 -0.406654)
			(end 0.9144 -0.406654)
			(stroke
				(width 0.1)
				(type default)
			)
			(layer "B.Fab")
		)
		(fp_line
			(start 0.9144 0.508)
			(end 0.9144 0.406654)
			(stroke
				(width 0.1)
				(type default)
			)
			(layer "B.Fab")
		)
		(fp_line
			(start 0.9144 0.406654)
			(end 1.194308 0.406654)
			(stroke
				(width 0.1)
				(type default)
			)
			(layer "B.Fab")
		)
		(fp_line
			(start 0.9144 -0.406654)
			(end 0.9144 -0.508)
			(stroke
				(width 0.1)
				(type default)
			)
			(layer "B.Fab")
		)
		(fp_line
			(start 0.9144 -0.508)
			(end -0.9144 -0.508)
			(stroke
				(width 0.1)
				(type default)
			)
			(layer "B.Fab")
		)
		(fp_line
			(start -0.9144 0.508)
			(end 0.9144 0.508)
			(stroke
				(width 0.1)
				(type default)
			)
			(layer "B.Fab")
		)
		(fp_line
			(start -0.9144 0.4064)
			(end -0.9144 0.508)
			(stroke
				(width 0.1)
				(type default)
			)
			(layer "B.Fab")
		)
		(fp_line
			(start -0.9144 -0.406654)
			(end -1.1938 -0.406654)
			(stroke
				(width 0.1)
				(type default)
			)
			(layer "B.Fab")
		)
		(fp_line
			(start -0.9144 -0.508)
			(end -0.9144 -0.406654)
			(stroke
				(width 0.1)
				(type default)
			)
			(layer "B.Fab")
		)
		(fp_line
			(start -1.1938 0.4064)
			(end -0.9144 0.4064)
			(stroke
				(width 0.1)
				(type default)
			)
			(layer "B.Fab")
		)
		(fp_line
			(start -1.1938 -0.406654)
			(end -1.1938 0.4064)
			(stroke
				(width 0.1)
				(type default)
			)
			(layer "B.Fab")
		)
		(pad "1" smd rect
			(at 0.7366 0 90)
			(size 0.7112 0.8128)
			(layers "B.Cu" "B.Mask" "B.Paste")
			(net "P3V3_AUX")
		)
		(pad "2" smd rect
			(at -0.7366 0 90)
			(size 0.7112 0.8128)
			(layers "B.Cu" "B.Mask" "B.Paste")
			(net "P3V3_SDB_VPHY")
		)
	)
	(footprint ""
		(layer "B.Cu")
		(at 193.641726 -104.120696 180)
		(property "Reference" "R168"
			(at 0 0 0)
			(layer "B.SilkS")
			(hide yes)
			(effects
				(font
					(size 1.27 1.27)
				)
				(justify mirror)
			)
		)
		(property "Value" ""
			(at 0 0 0)
			(layer "B.Fab")
			(effects
				(font
					(size 1.27 1.27)
				)
				(justify mirror)
			)
		)
		(duplicate_pad_numbers_are_jumpers no)
		(fp_line
			(start 0.7874 0.4064)
			(end 0.7874 -0.4064)
			(stroke
				(width 0.1524)
				(type default)
			)
			(layer "B.SilkS")
		)
		(fp_line
			(start 0.7874 -0.4064)
			(end -0.7874 -0.4064)
			(stroke
				(width 0.1524)
				(type default)
			)
			(layer "B.SilkS")
		)
		(fp_line
			(start -0.7874 0.4064)
			(end 0.7874 0.4064)
			(stroke
				(width 0.1524)
				(type default)
			)
			(layer "B.SilkS")
		)
		(fp_line
			(start -0.7874 -0.4064)
			(end -0.7874 0.4064)
			(stroke
				(width 0.1524)
				(type default)
			)
			(layer "B.SilkS")
		)
		(fp_line
			(start 0.67945 0.3048)
			(end 0.67945 -0.305054)
			(stroke
				(width 0.1)
				(type default)
			)
			(layer "B.Fab")
		)
		(fp_line
			(start 0.67945 -0.305054)
			(end 0.12065 -0.305054)
			(stroke
				(width 0.1)
				(type default)
			)
			(layer "B.Fab")
		)
		(fp_line
			(start 0.12065 0.3048)
			(end 0.67945 0.3048)
			(stroke
				(width 0.1)
				(type default)
			)
			(layer "B.Fab")
		)
		(fp_line
			(start 0.12065 0.2794)
			(end 0.12065 0.3048)
			(stroke
				(width 0.1)
				(type default)
			)
			(layer "B.Fab")
		)
		(fp_line
			(start 0.12065 -0.2794)
			(end -0.12065 -0.2794)
			(stroke
				(width 0.1)
				(type default)
			)
			(layer "B.Fab")
		)
		(fp_line
			(start 0.12065 -0.305054)
			(end 0.12065 -0.2794)
			(stroke
				(width 0.1)
				(type default)
			)
			(layer "B.Fab")
		)
		(fp_line
			(start -0.120396 0.3048)
			(end -0.120396 0.2794)
			(stroke
				(width 0.1)
				(type default)
			)
			(layer "B.Fab")
		)
		(fp_line
			(start -0.120396 0.2794)
			(end 0.12065 0.2794)
			(stroke
				(width 0.1)
				(type default)
			)
			(layer "B.Fab")
		)
		(fp_line
			(start -0.12065 -0.2794)
			(end -0.12065 -0.3048)
			(stroke
				(width 0.1)
				(type default)
			)
			(layer "B.Fab")
		)
		(fp_line
			(start -0.12065 -0.3048)
			(end -0.67945 -0.3048)
			(stroke
				(width 0.1)
				(type default)
			)
			(layer "B.Fab")
		)
		(fp_line
			(start -0.67945 0.3048)
			(end -0.120396 0.3048)
			(stroke
				(width 0.1)
				(type default)
			)
			(layer "B.Fab")
		)
		(fp_line
			(start -0.67945 -0.3048)
			(end -0.67945 0.3048)
			(stroke
				(width 0.1)
				(type default)
			)
			(layer "B.Fab")
		)
		(pad "1" smd circle
			(at 0.40005 0)
			(size 0 0)
			(layers "B.Cu" "B.Mask" "B.Paste")
			(net "NCSI_NIC3_CRS_DV")
		)
		(pad "2" smd circle
			(at -0.40005 0)
			(size 0 0)
			(layers "B.Cu" "B.Mask" "B.Paste")
			(net "GND")
		)
	)
	(footprint ""
		(layer "B.Cu")
		(at 339.725 -207.772 90)
		(property "Reference" "R4129"
			(at 0 0 90)
			(layer "B.SilkS")
			(hide yes)
			(effects
				(font
					(size 1.27 1.27)
				)
				(justify mirror)
			)
		)
		(property "Value" ""
			(at 0 0 90)
			(layer "B.Fab")
			(effects
				(font
					(size 1.27 1.27)
				)
				(justify mirror)
			)
		)
		(duplicate_pad_numbers_are_jumpers no)
		(fp_line
			(start 0.7874 -0.4064)
			(end -0.7874 -0.4064)
			(stroke
				(width 0.1524)
				(type default)
			)
			(layer "B.SilkS")
		)
		(fp_line
			(start -0.7874 -0.4064)
			(end -0.7874 0.4064)
			(stroke
				(width 0.1524)
				(type default)
			)
			(layer "B.SilkS")
		)
		(fp_line
			(start 0.7874 0.4064)
			(end 0.7874 -0.4064)
			(stroke
				(width 0.1524)
				(type default)
			)
			(layer "B.SilkS")
		)
		(fp_line
			(start -0.7874 0.4064)
			(end 0.7874 0.4064)
			(stroke
				(width 0.1524)
				(type default)
			)
			(layer "B.SilkS")
		)
		(fp_line
			(start 0.67945 -0.305054)
			(end 0.12065 -0.305054)
			(stroke
				(width 0.1)
				(type default)
			)
			(layer "B.Fab")
		)
		(fp_line
			(start 0.12065 -0.305054)
			(end 0.12065 -0.2794)
			(stroke
				(width 0.1)
				(type default)
			)
			(layer "B.Fab")
		)
		(fp_line
			(start -0.12065 -0.3048)
			(end -0.67945 -0.3048)
			(stroke
				(width 0.1)
				(type default)
			)
			(layer "B.Fab")
		)
		(fp_line
			(start -0.67945 -0.3048)
			(end -0.67945 0.3048)
			(stroke
				(width 0.1)
				(type default)
			)
			(layer "B.Fab")
		)
		(fp_line
			(start 0.12065 -0.2794)
			(end -0.12065 -0.2794)
			(stroke
				(width 0.1)
				(type default)
			)
			(layer "B.Fab")
		)
		(fp_line
			(start -0.12065 -0.2794)
			(end -0.12065 -0.3048)
			(stroke
				(width 0.1)
				(type default)
			)
			(layer "B.Fab")
		)
		(fp_line
			(start 0.12065 0.2794)
			(end 0.12065 0.3048)
			(stroke
				(width 0.1)
				(type default)
			)
			(layer "B.Fab")
		)
		(fp_line
			(start -0.120396 0.2794)
			(end 0.12065 0.2794)
			(stroke
				(width 0.1)
				(type default)
			)
			(layer "B.Fab")
		)
		(fp_line
			(start 0.67945 0.3048)
			(end 0.67945 -0.305054)
			(stroke
				(width 0.1)
				(type default)
			)
			(layer "B.Fab")
		)
		(fp_line
			(start 0.12065 0.3048)
			(end 0.67945 0.3048)
			(stroke
				(width 0.1)
				(type default)
			)
			(layer "B.Fab")
		)
		(fp_line
			(start -0.120396 0.3048)
			(end -0.120396 0.2794)
			(stroke
				(width 0.1)
				(type default)
			)
			(layer "B.Fab")
		)
		(fp_line
			(start -0.67945 0.3048)
			(end -0.120396 0.3048)
			(stroke
				(width 0.1)
				(type default)
			)
			(layer "B.Fab")
		)
		(pad "1" smd circle
			(at 0.40005 0 270)
			(size 0 0)
			(layers "B.Cu" "B.Mask" "B.Paste")
			(net "RST_SSD11_PERST_N")
		)
		(pad "2" smd circle
			(at -0.40005 0 270)
			(size 0 0)
			(layers "B.Cu" "B.Mask" "B.Paste")
			(net "RST_SSD11_PERST_R_N")
		)
	)
	(footprint ""
		(layer "B.Cu")
		(at 222.482664 -207.02016 -90)
		(property "Reference" "R5528"
			(at 0 0 90)
			(layer "B.SilkS")
			(hide yes)
			(effects
				(font
					(size 1.27 1.27)
				)
				(justify mirror)
			)
		)
		(property "Value" ""
			(at 0 0 90)
			(layer "B.Fab")
			(effects
				(font
					(size 1.27 1.27)
				)
				(justify mirror)
			)
		)
		(duplicate_pad_numbers_are_jumpers no)
		(fp_line
			(start -0.7874 0.4064)
			(end 0.7874 0.4064)
			(stroke
				(width 0.1524)
				(type default)
			)
			(layer "B.SilkS")
		)
		(fp_line
			(start 0.7874 0.4064)
			(end 0.7874 -0.4064)
			(stroke
				(width 0.1524)
				(type default)
			)
			(layer "B.SilkS")
		)
		(fp_line
			(start -0.7874 -0.4064)
			(end -0.7874 0.4064)
			(stroke
				(width 0.1524)
				(type default)
			)
			(layer "B.SilkS")
		)
		(fp_line
			(start 0.7874 -0.4064)
			(end -0.7874 -0.4064)
			(stroke
				(width 0.1524)
				(type default)
			)
			(layer "B.SilkS")
		)
		(fp_line
			(start -0.67945 0.3048)
			(end -0.120396 0.3048)
			(stroke
				(width 0.1)
				(type default)
			)
			(layer "B.Fab")
		)
		(fp_line
			(start -0.120396 0.3048)
			(end -0.120396 0.2794)
			(stroke
				(width 0.1)
				(type default)
			)
			(layer "B.Fab")
		)
		(fp_line
			(start 0.12065 0.3048)
			(end 0.67945 0.3048)
			(stroke
				(width 0.1)
				(type default)
			)
			(layer "B.Fab")
		)
		(fp_line
			(start 0.67945 0.3048)
			(end 0.67945 -0.305054)
			(stroke
				(width 0.1)
				(type default)
			)
			(layer "B.Fab")
		)
		(fp_line
			(start -0.120396 0.2794)
			(end 0.12065 0.2794)
			(stroke
				(width 0.1)
				(type default)
			)
			(layer "B.Fab")
		)
		(fp_line
			(start 0.12065 0.2794)
			(end 0.12065 0.3048)
			(stroke
				(width 0.1)
				(type default)
			)
			(layer "B.Fab")
		)
		(fp_line
			(start -0.12065 -0.2794)
			(end -0.12065 -0.3048)
			(stroke
				(width 0.1)
				(type default)
			)
			(layer "B.Fab")
		)
		(fp_line
			(start 0.12065 -0.2794)
			(end -0.12065 -0.2794)
			(stroke
				(width 0.1)
				(type default)
			)
			(layer "B.Fab")
		)
		(fp_line
			(start -0.67945 -0.3048)
			(end -0.67945 0.3048)
			(stroke
				(width 0.1)
				(type default)
			)
			(layer "B.Fab")
		)
		(fp_line
			(start -0.12065 -0.3048)
			(end -0.67945 -0.3048)
			(stroke
				(width 0.1)
				(type default)
			)
			(layer "B.Fab")
		)
		(fp_line
			(start 0.12065 -0.305054)
			(end 0.12065 -0.2794)
			(stroke
				(width 0.1)
				(type default)
			)
			(layer "B.Fab")
		)
		(fp_line
			(start 0.67945 -0.305054)
			(end 0.12065 -0.305054)
			(stroke
				(width 0.1)
				(type default)
			)
			(layer "B.Fab")
		)
		(pad "1" smd circle
			(at 0.40005 0 90)
			(size 0 0)
			(layers "B.Cu" "B.Mask" "B.Paste")
			(net "GND")
		)
		(pad "2" smd circle
			(at -0.40005 0 90)
			(size 0 0)
			(layers "B.Cu" "B.Mask" "B.Paste")
			(net "SGPIO_BIC_DOUT")
		)
	)
	(footprint ""
		(layer "B.Cu")
		(at 417.450016 -303.024794)
		(property "Reference" "C3513"
			(at 0 0 0)
			(layer "B.SilkS")
			(hide yes)
			(effects
				(font
					(size 1.27 1.27)
				)
				(justify mirror)
			)
		)
		(property "Value" ""
			(at 0 0 0)
			(layer "B.Fab")
			(effects
				(font
					(size 1.27 1.27)
				)
				(justify mirror)
			)
		)
		(duplicate_pad_numbers_are_jumpers no)
		(fp_line
			(start -0.299974 -0.150114)
			(end -0.299974 0.150114)
			(stroke
				(width 0.1)
				(type default)
			)
			(layer "B.Fab")
		)
		(fp_line
			(start -0.299974 0.150114)
			(end 0.299974 0.150114)
			(stroke
				(width 0.1)
				(type default)
			)
			(layer "B.Fab")
		)
		(fp_line
			(start 0.299974 -0.150114)
			(end -0.299974 -0.150114)
			(stroke
				(width 0.1)
				(type default)
			)
			(layer "B.Fab")
		)
		(fp_line
			(start 0.299974 0.150114)
			(end 0.299974 -0.150114)
			(stroke
				(width 0.1)
				(type default)
			)
			(layer "B.Fab")
		)
		(pad "1" smd rect
			(at 0.2667 0 180)
			(size 0.3048 0.381)
			(layers "B.Cu" "B.Mask" "B.Paste")
			(net "P1V8_PEX")
		)
		(pad "2" smd rect
			(at -0.2667 0 180)
			(size 0.3048 0.381)
			(layers "B.Cu" "B.Mask" "B.Paste")
			(net "GND")
		)
	)
	(footprint ""
		(layer "B.Cu")
		(at 207.110076 -221.694248 180)
		(property "Reference" "C4488"
			(at 0 0 0)
			(layer "B.SilkS")
			(hide yes)
			(effects
				(font
					(size 1.27 1.27)
				)
				(justify mirror)
			)
		)
		(property "Value" ""
			(at 0 0 0)
			(layer "B.Fab")
			(effects
				(font
					(size 1.27 1.27)
				)
				(justify mirror)
			)
		)
		(duplicate_pad_numbers_are_jumpers no)
		(fp_line
			(start 0.7874 0.4064)
			(end 0.7874 -0.4064)
			(stroke
				(width 0.1524)
				(type default)
			)
			(layer "B.SilkS")
		)
		(fp_line
			(start 0.7874 -0.4064)
			(end -0.7874 -0.4064)
			(stroke
				(width 0.1524)
				(type default)
			)
			(layer "B.SilkS")
		)
		(fp_line
			(start -0.7874 0.4064)
			(end 0.7874 0.4064)
			(stroke
				(width 0.1524)
				(type default)
			)
			(layer "B.SilkS")
		)
		(fp_line
			(start -0.7874 -0.4064)
			(end -0.7874 0.4064)
			(stroke
				(width 0.1524)
				(type default)
			)
			(layer "B.SilkS")
		)
		(fp_line
			(start 0.67945 0.3048)
			(end 0.67945 -0.305054)
			(stroke
				(width 0.1)
				(type default)
			)
			(layer "B.Fab")
		)
		(fp_line
			(start 0.67945 -0.305054)
			(end 0.12065 -0.305054)
			(stroke
				(width 0.1)
				(type default)
			)
			(layer "B.Fab")
		)
		(fp_line
			(start 0.12065 0.3048)
			(end 0.67945 0.3048)
			(stroke
				(width 0.1)
				(type default)
			)
			(layer "B.Fab")
		)
		(fp_line
			(start 0.12065 0.2794)
			(end 0.12065 0.3048)
			(stroke
				(width 0.1)
				(type default)
			)
			(layer "B.Fab")
		)
		(fp_line
			(start 0.12065 -0.2794)
			(end -0.12065 -0.2794)
			(stroke
				(width 0.1)
				(type default)
			)
			(layer "B.Fab")
		)
		(fp_line
			(start 0.12065 -0.305054)
			(end 0.12065 -0.2794)
			(stroke
				(width 0.1)
				(type default)
			)
			(layer "B.Fab")
		)
		(fp_line
			(start -0.120396 0.3048)
			(end -0.120396 0.2794)
			(stroke
				(width 0.1)
				(type default)
			)
			(layer "B.Fab")
		)
		(fp_line
			(start -0.120396 0.2794)
			(end 0.12065 0.2794)
			(stroke
				(width 0.1)
				(type default)
			)
			(layer "B.Fab")
		)
		(fp_line
			(start -0.12065 -0.2794)
			(end -0.12065 -0.3048)
			(stroke
				(width 0.1)
				(type default)
			)
			(layer "B.Fab")
		)
		(fp_line
			(start -0.12065 -0.3048)
			(end -0.67945 -0.3048)
			(stroke
				(width 0.1)
				(type default)
			)
			(layer "B.Fab")
		)
		(fp_line
			(start -0.67945 0.3048)
			(end -0.120396 0.3048)
			(stroke
				(width 0.1)
				(type default)
			)
			(layer "B.Fab")
		)
		(fp_line
			(start -0.67945 -0.3048)
			(end -0.67945 0.3048)
			(stroke
				(width 0.1)
				(type default)
			)
			(layer "B.Fab")
		)
		(pad "1" smd circle
			(at 0.40005 0)
			(size 0 0)
			(layers "B.Cu" "B.Mask" "B.Paste")
			(net "BOARD_TYPE_1_ADC_R")
		)
		(pad "2" smd circle
			(at -0.40005 0)
			(size 0 0)
			(layers "B.Cu" "B.Mask" "B.Paste")
			(net "GND")
		)
	)
	(footprint ""
		(layer "B.Cu")
		(at 193.641726 -95.989648 180)
		(property "Reference" "R164"
			(at 0 0 0)
			(layer "B.SilkS")
			(hide yes)
			(effects
				(font
					(size 1.27 1.27)
				)
				(justify mirror)
			)
		)
		(property "Value" ""
			(at 0 0 0)
			(layer "B.Fab")
			(effects
				(font
					(size 1.27 1.27)
				)
				(justify mirror)
			)
		)
		(duplicate_pad_numbers_are_jumpers no)
		(fp_line
			(start 0.7874 0.4064)
			(end 0.7874 -0.4064)
			(stroke
				(width 0.1524)
				(type default)
			)
			(layer "B.SilkS")
		)
		(fp_line
			(start 0.7874 -0.4064)
			(end -0.7874 -0.4064)
			(stroke
				(width 0.1524)
				(type default)
			)
			(layer "B.SilkS")
		)
		(fp_line
			(start -0.7874 0.4064)
			(end 0.7874 0.4064)
			(stroke
				(width 0.1524)
				(type default)
			)
			(layer "B.SilkS")
		)
		(fp_line
			(start -0.7874 -0.4064)
			(end -0.7874 0.4064)
			(stroke
				(width 0.1524)
				(type default)
			)
			(layer "B.SilkS")
		)
		(fp_line
			(start 0.67945 0.3048)
			(end 0.67945 -0.305054)
			(stroke
				(width 0.1)
				(type default)
			)
			(layer "B.Fab")
		)
		(fp_line
			(start 0.67945 -0.305054)
			(end 0.12065 -0.305054)
			(stroke
				(width 0.1)
				(type default)
			)
			(layer "B.Fab")
		)
		(fp_line
			(start 0.12065 0.3048)
			(end 0.67945 0.3048)
			(stroke
				(width 0.1)
				(type default)
			)
			(layer "B.Fab")
		)
		(fp_line
			(start 0.12065 0.2794)
			(end 0.12065 0.3048)
			(stroke
				(width 0.1)
				(type default)
			)
			(layer "B.Fab")
		)
		(fp_line
			(start 0.12065 -0.2794)
			(end -0.12065 -0.2794)
			(stroke
				(width 0.1)
				(type default)
			)
			(layer "B.Fab")
		)
		(fp_line
			(start 0.12065 -0.305054)
			(end 0.12065 -0.2794)
			(stroke
				(width 0.1)
				(type default)
			)
			(layer "B.Fab")
		)
		(fp_line
			(start -0.120396 0.3048)
			(end -0.120396 0.2794)
			(stroke
				(width 0.1)
				(type default)
			)
			(layer "B.Fab")
		)
		(fp_line
			(start -0.120396 0.2794)
			(end 0.12065 0.2794)
			(stroke
				(width 0.1)
				(type default)
			)
			(layer "B.Fab")
		)
		(fp_line
			(start -0.12065 -0.2794)
			(end -0.12065 -0.3048)
			(stroke
				(width 0.1)
				(type default)
			)
			(layer "B.Fab")
		)
		(fp_line
			(start -0.12065 -0.3048)
			(end -0.67945 -0.3048)
			(stroke
				(width 0.1)
				(type default)
			)
			(layer "B.Fab")
		)
		(fp_line
			(start -0.67945 0.3048)
			(end -0.120396 0.3048)
			(stroke
				(width 0.1)
				(type default)
			)
			(layer "B.Fab")
		)
		(fp_line
			(start -0.67945 -0.3048)
			(end -0.67945 0.3048)
			(stroke
				(width 0.1)
				(type default)
			)
			(layer "B.Fab")
		)
		(pad "1" smd circle
			(at 0.40005 0)
			(size 0 0)
			(layers "B.Cu" "B.Mask" "B.Paste")
			(net "NIC3_LD_N")
		)
		(pad "2" smd circle
			(at -0.40005 0)
			(size 0 0)
			(layers "B.Cu" "B.Mask" "B.Paste")
			(net "P3V3_NIC3")
		)
	)
	(footprint ""
		(layer "B.Cu")
		(at 290.89985 -299.699934 -90)
		(property "Reference" "C1701"
			(at 0 0 90)
			(layer "B.SilkS")
			(hide yes)
			(effects
				(font
					(size 1.27 1.27)
				)
				(justify mirror)
			)
		)
		(property "Value" ""
			(at 0 0 90)
			(layer "B.Fab")
			(effects
				(font
					(size 1.27 1.27)
				)
				(justify mirror)
			)
		)
		(duplicate_pad_numbers_are_jumpers no)
		(fp_line
			(start -0.299974 0.150114)
			(end 0.299974 0.150114)
			(stroke
				(width 0.1)
				(type default)
			)
			(layer "B.Fab")
		)
		(fp_line
			(start 0.299974 0.150114)
			(end 0.299974 -0.150114)
			(stroke
				(width 0.1)
				(type default)
			)
			(layer "B.Fab")
		)
		(fp_line
			(start -0.299974 -0.150114)
			(end -0.299974 0.150114)
			(stroke
				(width 0.1)
				(type default)
			)
			(layer "B.Fab")
		)
		(fp_line
			(start 0.299974 -0.150114)
			(end -0.299974 -0.150114)
			(stroke
				(width 0.1)
				(type default)
			)
			(layer "B.Fab")
		)
		(pad "1" smd rect
			(at 0.2667 0 90)
			(size 0.3048 0.381)
			(layers "B.Cu" "B.Mask" "B.Paste")
			(net "P0V8_SERDES_VDDA_PEX2")
		)
		(pad "2" smd rect
			(at -0.2667 0 90)
			(size 0.3048 0.381)
			(layers "B.Cu" "B.Mask" "B.Paste")
			(net "GND")
		)
	)
	(footprint ""
		(layer "B.Cu")
		(at 54.899814 -290.199826 90)
		(property "Reference" "C1199"
			(at 0 0 90)
			(layer "B.SilkS")
			(hide yes)
			(effects
				(font
					(size 1.27 1.27)
				)
				(justify mirror)
			)
		)
		(property "Value" ""
			(at 0 0 90)
			(layer "B.Fab")
			(effects
				(font
					(size 1.27 1.27)
				)
				(justify mirror)
			)
		)
		(duplicate_pad_numbers_are_jumpers no)
		(fp_line
			(start 0.299974 -0.150114)
			(end -0.299974 -0.150114)
			(stroke
				(width 0.1)
				(type default)
			)
			(layer "B.Fab")
		)
		(fp_line
			(start -0.299974 -0.150114)
			(end -0.299974 0.150114)
			(stroke
				(width 0.1)
				(type default)
			)
			(layer "B.Fab")
		)
		(fp_line
			(start 0.299974 0.150114)
			(end 0.299974 -0.150114)
			(stroke
				(width 0.1)
				(type default)
			)
			(layer "B.Fab")
		)
		(fp_line
			(start -0.299974 0.150114)
			(end 0.299974 0.150114)
			(stroke
				(width 0.1)
				(type default)
			)
			(layer "B.Fab")
		)
		(pad "1" smd rect
			(at 0.2667 0 270)
			(size 0.3048 0.381)
			(layers "B.Cu" "B.Mask" "B.Paste")
			(net "P0V8_SERDES_VDDA_PEX0")
		)
		(pad "2" smd rect
			(at -0.2667 0 270)
			(size 0.3048 0.381)
			(layers "B.Cu" "B.Mask" "B.Paste")
			(net "GND")
		)
	)
	(footprint ""
		(layer "B.Cu")
		(at 62.974982 -297.79976 -90)
		(property "Reference" "C1145"
			(at 0 0 90)
			(layer "B.SilkS")
			(hide yes)
			(effects
				(font
					(size 1.27 1.27)
				)
				(justify mirror)
			)
		)
		(property "Value" ""
			(at 0 0 90)
			(layer "B.Fab")
			(effects
				(font
					(size 1.27 1.27)
				)
				(justify mirror)
			)
		)
		(duplicate_pad_numbers_are_jumpers no)
		(fp_line
			(start -0.299974 0.150114)
			(end 0.299974 0.150114)
			(stroke
				(width 0.1)
				(type default)
			)
			(layer "B.Fab")
		)
		(fp_line
			(start 0.299974 0.150114)
			(end 0.299974 -0.150114)
			(stroke
				(width 0.1)
				(type default)
			)
			(layer "B.Fab")
		)
		(fp_line
			(start -0.299974 -0.150114)
			(end -0.299974 0.150114)
			(stroke
				(width 0.1)
				(type default)
			)
			(layer "B.Fab")
		)
		(fp_line
			(start 0.299974 -0.150114)
			(end -0.299974 -0.150114)
			(stroke
				(width 0.1)
				(type default)
			)
			(layer "B.Fab")
		)
		(pad "1" smd rect
			(at 0.2667 0 90)
			(size 0.3048 0.381)
			(layers "B.Cu" "B.Mask" "B.Paste")
			(net "P0V8_PEX0")
		)
		(pad "2" smd rect
			(at -0.2667 0 90)
			(size 0.3048 0.381)
			(layers "B.Cu" "B.Mask" "B.Paste")
			(net "GND")
		)
	)
	(footprint ""
		(layer "B.Cu")
		(at 417.924996 -305.608228 -90)
		(property "Reference" "C3518"
			(at 0 0 90)
			(layer "B.SilkS")
			(hide yes)
			(effects
				(font
					(size 1.27 1.27)
				)
				(justify mirror)
			)
		)
		(property "Value" ""
			(at 0 0 90)
			(layer "B.Fab")
			(effects
				(font
					(size 1.27 1.27)
				)
				(justify mirror)
			)
		)
		(duplicate_pad_numbers_are_jumpers no)
		(fp_line
			(start -0.299974 0.150114)
			(end 0.299974 0.150114)
			(stroke
				(width 0.1)
				(type default)
			)
			(layer "B.Fab")
		)
		(fp_line
			(start 0.299974 0.150114)
			(end 0.299974 -0.150114)
			(stroke
				(width 0.1)
				(type default)
			)
			(layer "B.Fab")
		)
		(fp_line
			(start -0.299974 -0.150114)
			(end -0.299974 0.150114)
			(stroke
				(width 0.1)
				(type default)
			)
			(layer "B.Fab")
		)
		(fp_line
			(start 0.299974 -0.150114)
			(end -0.299974 -0.150114)
			(stroke
				(width 0.1)
				(type default)
			)
			(layer "B.Fab")
		)
		(pad "1" smd rect
			(at 0.2667 0 90)
			(size 0.3048 0.381)
			(layers "B.Cu" "B.Mask" "B.Paste")
			(net "P1V8_VDDA_PEX3")
		)
		(pad "2" smd rect
			(at -0.2667 0 90)
			(size 0.3048 0.381)
			(layers "B.Cu" "B.Mask" "B.Paste")
			(net "GND")
		)
	)
	(footprint ""
		(layer "B.Cu")
		(at 217.235786 -215.254586 180)
		(property "Reference" "R5716"
			(at 0 0 0)
			(layer "B.SilkS")
			(hide yes)
			(effects
				(font
					(size 1.27 1.27)
				)
				(justify mirror)
			)
		)
		(property "Value" ""
			(at 0 0 0)
			(layer "B.Fab")
			(effects
				(font
					(size 1.27 1.27)
				)
				(justify mirror)
			)
		)
		(duplicate_pad_numbers_are_jumpers no)
		(fp_line
			(start 0.7874 0.4064)
			(end 0.7874 -0.4064)
			(stroke
				(width 0.1524)
				(type default)
			)
			(layer "B.SilkS")
		)
		(fp_line
			(start 0.7874 -0.4064)
			(end -0.7874 -0.4064)
			(stroke
				(width 0.1524)
				(type default)
			)
			(layer "B.SilkS")
		)
		(fp_line
			(start -0.7874 0.4064)
			(end 0.7874 0.4064)
			(stroke
				(width 0.1524)
				(type default)
			)
			(layer "B.SilkS")
		)
		(fp_line
			(start -0.7874 -0.4064)
			(end -0.7874 0.4064)
			(stroke
				(width 0.1524)
				(type default)
			)
			(layer "B.SilkS")
		)
		(fp_line
			(start 0.67945 0.3048)
			(end 0.67945 -0.305054)
			(stroke
				(width 0.1)
				(type default)
			)
			(layer "B.Fab")
		)
		(fp_line
			(start 0.67945 -0.305054)
			(end 0.12065 -0.305054)
			(stroke
				(width 0.1)
				(type default)
			)
			(layer "B.Fab")
		)
		(fp_line
			(start 0.12065 0.3048)
			(end 0.67945 0.3048)
			(stroke
				(width 0.1)
				(type default)
			)
			(layer "B.Fab")
		)
		(fp_line
			(start 0.12065 0.2794)
			(end 0.12065 0.3048)
			(stroke
				(width 0.1)
				(type default)
			)
			(layer "B.Fab")
		)
		(fp_line
			(start 0.12065 -0.2794)
			(end -0.12065 -0.2794)
			(stroke
				(width 0.1)
				(type default)
			)
			(layer "B.Fab")
		)
		(fp_line
			(start 0.12065 -0.305054)
			(end 0.12065 -0.2794)
			(stroke
				(width 0.1)
				(type default)
			)
			(layer "B.Fab")
		)
		(fp_line
			(start -0.120396 0.3048)
			(end -0.120396 0.2794)
			(stroke
				(width 0.1)
				(type default)
			)
			(layer "B.Fab")
		)
		(fp_line
			(start -0.120396 0.2794)
			(end 0.12065 0.2794)
			(stroke
				(width 0.1)
				(type default)
			)
			(layer "B.Fab")
		)
		(fp_line
			(start -0.12065 -0.2794)
			(end -0.12065 -0.3048)
			(stroke
				(width 0.1)
				(type default)
			)
			(layer "B.Fab")
		)
		(fp_line
			(start -0.12065 -0.3048)
			(end -0.67945 -0.3048)
			(stroke
				(width 0.1)
				(type default)
			)
			(layer "B.Fab")
		)
		(fp_line
			(start -0.67945 0.3048)
			(end -0.120396 0.3048)
			(stroke
				(width 0.1)
				(type default)
			)
			(layer "B.Fab")
		)
		(fp_line
			(start -0.67945 -0.3048)
			(end -0.67945 0.3048)
			(stroke
				(width 0.1)
				(type default)
			)
			(layer "B.Fab")
		)
		(pad "1" smd circle
			(at 0.40005 0)
			(size 0 0)
			(layers "B.Cu" "B.Mask" "B.Paste")
			(net "BIC_UART_BIC_SEL_R")
		)
		(pad "2" smd circle
			(at -0.40005 0)
			(size 0 0)
			(layers "B.Cu" "B.Mask" "B.Paste")
			(net "BIC_UART_BIC_SEL")
		)
	)
	(footprint ""
		(layer "B.Cu")
		(at 136.403842 -182.052468 -90)
		(property "Reference" "R1121"
			(at 0 0 90)
			(layer "B.SilkS")
			(hide yes)
			(effects
				(font
					(size 1.27 1.27)
				)
				(justify mirror)
			)
		)
		(property "Value" ""
			(at 0 0 90)
			(layer "B.Fab")
			(effects
				(font
					(size 1.27 1.27)
				)
				(justify mirror)
			)
		)
		(duplicate_pad_numbers_are_jumpers no)
		(fp_line
			(start -0.7874 0.4064)
			(end 0.7874 0.4064)
			(stroke
				(width 0.1524)
				(type default)
			)
			(layer "B.SilkS")
		)
		(fp_line
			(start 0.7874 0.4064)
			(end 0.7874 -0.4064)
			(stroke
				(width 0.1524)
				(type default)
			)
			(layer "B.SilkS")
		)
		(fp_line
			(start -0.7874 -0.4064)
			(end -0.7874 0.4064)
			(stroke
				(width 0.1524)
				(type default)
			)
			(layer "B.SilkS")
		)
		(fp_line
			(start 0.7874 -0.4064)
			(end -0.7874 -0.4064)
			(stroke
				(width 0.1524)
				(type default)
			)
			(layer "B.SilkS")
		)
		(fp_line
			(start -0.67945 0.3048)
			(end -0.120396 0.3048)
			(stroke
				(width 0.1)
				(type default)
			)
			(layer "B.Fab")
		)
		(fp_line
			(start -0.120396 0.3048)
			(end -0.120396 0.2794)
			(stroke
				(width 0.1)
				(type default)
			)
			(layer "B.Fab")
		)
		(fp_line
			(start 0.12065 0.3048)
			(end 0.67945 0.3048)
			(stroke
				(width 0.1)
				(type default)
			)
			(layer "B.Fab")
		)
		(fp_line
			(start 0.67945 0.3048)
			(end 0.67945 -0.305054)
			(stroke
				(width 0.1)
				(type default)
			)
			(layer "B.Fab")
		)
		(fp_line
			(start -0.120396 0.2794)
			(end 0.12065 0.2794)
			(stroke
				(width 0.1)
				(type default)
			)
			(layer "B.Fab")
		)
		(fp_line
			(start 0.12065 0.2794)
			(end 0.12065 0.3048)
			(stroke
				(width 0.1)
				(type default)
			)
			(layer "B.Fab")
		)
		(fp_line
			(start -0.12065 -0.2794)
			(end -0.12065 -0.3048)
			(stroke
				(width 0.1)
				(type default)
			)
			(layer "B.Fab")
		)
		(fp_line
			(start 0.12065 -0.2794)
			(end -0.12065 -0.2794)
			(stroke
				(width 0.1)
				(type default)
			)
			(layer "B.Fab")
		)
		(fp_line
			(start -0.67945 -0.3048)
			(end -0.67945 0.3048)
			(stroke
				(width 0.1)
				(type default)
			)
			(layer "B.Fab")
		)
		(fp_line
			(start -0.12065 -0.3048)
			(end -0.67945 -0.3048)
			(stroke
				(width 0.1)
				(type default)
			)
			(layer "B.Fab")
		)
		(fp_line
			(start 0.12065 -0.305054)
			(end 0.12065 -0.2794)
			(stroke
				(width 0.1)
				(type default)
			)
			(layer "B.Fab")
		)
		(fp_line
			(start 0.67945 -0.305054)
			(end 0.12065 -0.305054)
			(stroke
				(width 0.1)
				(type default)
			)
			(layer "B.Fab")
		)
		(pad "1" smd circle
			(at 0.40005 0 90)
			(size 0 0)
			(layers "B.Cu" "B.Mask" "B.Paste")
			(net "FM_DB2000QL_SMB_SA1")
		)
		(pad "2" smd circle
			(at -0.40005 0 90)
			(size 0 0)
			(layers "B.Cu" "B.Mask" "B.Paste")
			(net "P3V3")
		)
	)
	(footprint ""
		(layer "B.Cu")
		(at 278.554942 -293.52494)
		(property "Reference" "C3405"
			(at 0 0 0)
			(layer "B.SilkS")
			(hide yes)
			(effects
				(font
					(size 1.27 1.27)
				)
				(justify mirror)
			)
		)
		(property "Value" ""
			(at 0 0 0)
			(layer "B.Fab")
			(effects
				(font
					(size 1.27 1.27)
				)
				(justify mirror)
			)
		)
		(duplicate_pad_numbers_are_jumpers no)
		(fp_line
			(start -0.299974 -0.150114)
			(end -0.299974 0.150114)
			(stroke
				(width 0.1)
				(type default)
			)
			(layer "B.Fab")
		)
		(fp_line
			(start -0.299974 0.150114)
			(end 0.299974 0.150114)
			(stroke
				(width 0.1)
				(type default)
			)
			(layer "B.Fab")
		)
		(fp_line
			(start 0.299974 -0.150114)
			(end -0.299974 -0.150114)
			(stroke
				(width 0.1)
				(type default)
			)
			(layer "B.Fab")
		)
		(fp_line
			(start 0.299974 0.150114)
			(end 0.299974 -0.150114)
			(stroke
				(width 0.1)
				(type default)
			)
			(layer "B.Fab")
		)
		(pad "1" smd rect
			(at 0.2667 0 180)
			(size 0.3048 0.381)
			(layers "B.Cu" "B.Mask" "B.Paste")
			(net "PCEPLL6_VDDA18_PEX2")
		)
		(pad "2" smd rect
			(at -0.2667 0 180)
			(size 0.3048 0.381)
			(layers "B.Cu" "B.Mask" "B.Paste")
			(net "GND")
		)
	)
	(footprint ""
		(layer "B.Cu")
		(at 283.299916 -290.199826 90)
		(property "Reference" "C1686"
			(at 0 0 90)
			(layer "B.SilkS")
			(hide yes)
			(effects
				(font
					(size 1.27 1.27)
				)
				(justify mirror)
			)
		)
		(property "Value" ""
			(at 0 0 90)
			(layer "B.Fab")
			(effects
				(font
					(size 1.27 1.27)
				)
				(justify mirror)
			)
		)
		(duplicate_pad_numbers_are_jumpers no)
		(fp_line
			(start 0.299974 -0.150114)
			(end -0.299974 -0.150114)
			(stroke
				(width 0.1)
				(type default)
			)
			(layer "B.Fab")
		)
		(fp_line
			(start -0.299974 -0.150114)
			(end -0.299974 0.150114)
			(stroke
				(width 0.1)
				(type default)
			)
			(layer "B.Fab")
		)
		(fp_line
			(start 0.299974 0.150114)
			(end 0.299974 -0.150114)
			(stroke
				(width 0.1)
				(type default)
			)
			(layer "B.Fab")
		)
		(fp_line
			(start -0.299974 0.150114)
			(end 0.299974 0.150114)
			(stroke
				(width 0.1)
				(type default)
			)
			(layer "B.Fab")
		)
		(pad "1" smd rect
			(at 0.2667 0 270)
			(size 0.3048 0.381)
			(layers "B.Cu" "B.Mask" "B.Paste")
			(net "P0V8_SERDES_VDDA_PEX2")
		)
		(pad "2" smd rect
			(at -0.2667 0 270)
			(size 0.3048 0.381)
			(layers "B.Cu" "B.Mask" "B.Paste")
			(net "GND")
		)
	)
	(footprint ""
		(layer "B.Cu")
		(at 335.153 -207.772 90)
		(property "Reference" "R4124"
			(at 0 0 90)
			(layer "B.SilkS")
			(hide yes)
			(effects
				(font
					(size 1.27 1.27)
				)
				(justify mirror)
			)
		)
		(property "Value" ""
			(at 0 0 90)
			(layer "B.Fab")
			(effects
				(font
					(size 1.27 1.27)
				)
				(justify mirror)
			)
		)
		(duplicate_pad_numbers_are_jumpers no)
		(fp_line
			(start 0.7874 -0.4064)
			(end -0.7874 -0.4064)
			(stroke
				(width 0.1524)
				(type default)
			)
			(layer "B.SilkS")
		)
		(fp_line
			(start -0.7874 -0.4064)
			(end -0.7874 0.4064)
			(stroke
				(width 0.1524)
				(type default)
			)
			(layer "B.SilkS")
		)
		(fp_line
			(start 0.7874 0.4064)
			(end 0.7874 -0.4064)
			(stroke
				(width 0.1524)
				(type default)
			)
			(layer "B.SilkS")
		)
		(fp_line
			(start -0.7874 0.4064)
			(end 0.7874 0.4064)
			(stroke
				(width 0.1524)
				(type default)
			)
			(layer "B.SilkS")
		)
		(fp_line
			(start 0.67945 -0.305054)
			(end 0.12065 -0.305054)
			(stroke
				(width 0.1)
				(type default)
			)
			(layer "B.Fab")
		)
		(fp_line
			(start 0.12065 -0.305054)
			(end 0.12065 -0.2794)
			(stroke
				(width 0.1)
				(type default)
			)
			(layer "B.Fab")
		)
		(fp_line
			(start -0.12065 -0.3048)
			(end -0.67945 -0.3048)
			(stroke
				(width 0.1)
				(type default)
			)
			(layer "B.Fab")
		)
		(fp_line
			(start -0.67945 -0.3048)
			(end -0.67945 0.3048)
			(stroke
				(width 0.1)
				(type default)
			)
			(layer "B.Fab")
		)
		(fp_line
			(start 0.12065 -0.2794)
			(end -0.12065 -0.2794)
			(stroke
				(width 0.1)
				(type default)
			)
			(layer "B.Fab")
		)
		(fp_line
			(start -0.12065 -0.2794)
			(end -0.12065 -0.3048)
			(stroke
				(width 0.1)
				(type default)
			)
			(layer "B.Fab")
		)
		(fp_line
			(start 0.12065 0.2794)
			(end 0.12065 0.3048)
			(stroke
				(width 0.1)
				(type default)
			)
			(layer "B.Fab")
		)
		(fp_line
			(start -0.120396 0.2794)
			(end 0.12065 0.2794)
			(stroke
				(width 0.1)
				(type default)
			)
			(layer "B.Fab")
		)
		(fp_line
			(start 0.67945 0.3048)
			(end 0.67945 -0.305054)
			(stroke
				(width 0.1)
				(type default)
			)
			(layer "B.Fab")
		)
		(fp_line
			(start 0.12065 0.3048)
			(end 0.67945 0.3048)
			(stroke
				(width 0.1)
				(type default)
			)
			(layer "B.Fab")
		)
		(fp_line
			(start -0.120396 0.3048)
			(end -0.120396 0.2794)
			(stroke
				(width 0.1)
				(type default)
			)
			(layer "B.Fab")
		)
		(fp_line
			(start -0.67945 0.3048)
			(end -0.120396 0.3048)
			(stroke
				(width 0.1)
				(type default)
			)
			(layer "B.Fab")
		)
		(pad "1" smd circle
			(at 0.40005 0 270)
			(size 0 0)
			(layers "B.Cu" "B.Mask" "B.Paste")
			(net "SSD10_PWRDIS")
		)
		(pad "2" smd circle
			(at -0.40005 0 270)
			(size 0 0)
			(layers "B.Cu" "B.Mask" "B.Paste")
			(net "SSD10_PWRDIS_R")
		)
	)
	(footprint ""
		(layer "B.Cu")
		(at 272.257012 -291.72662 180)
		(property "Reference" "R3471"
			(at 0 0 0)
			(layer "B.SilkS")
			(hide yes)
			(effects
				(font
					(size 1.27 1.27)
				)
				(justify mirror)
			)
		)
		(property "Value" ""
			(at 0 0 0)
			(layer "B.Fab")
			(effects
				(font
					(size 1.27 1.27)
				)
				(justify mirror)
			)
		)
		(duplicate_pad_numbers_are_jumpers no)
		(fp_line
			(start 0.7874 0.4064)
			(end 0.7874 -0.4064)
			(stroke
				(width 0.1524)
				(type default)
			)
			(layer "B.SilkS")
		)
		(fp_line
			(start 0.7874 -0.4064)
			(end -0.7874 -0.4064)
			(stroke
				(width 0.1524)
				(type default)
			)
			(layer "B.SilkS")
		)
		(fp_line
			(start -0.7874 0.4064)
			(end 0.7874 0.4064)
			(stroke
				(width 0.1524)
				(type default)
			)
			(layer "B.SilkS")
		)
		(fp_line
			(start -0.7874 -0.4064)
			(end -0.7874 0.4064)
			(stroke
				(width 0.1524)
				(type default)
			)
			(layer "B.SilkS")
		)
		(fp_line
			(start 0.67945 0.3048)
			(end 0.67945 -0.305054)
			(stroke
				(width 0.1)
				(type default)
			)
			(layer "B.Fab")
		)
		(fp_line
			(start 0.67945 -0.305054)
			(end 0.12065 -0.305054)
			(stroke
				(width 0.1)
				(type default)
			)
			(layer "B.Fab")
		)
		(fp_line
			(start 0.12065 0.3048)
			(end 0.67945 0.3048)
			(stroke
				(width 0.1)
				(type default)
			)
			(layer "B.Fab")
		)
		(fp_line
			(start 0.12065 0.2794)
			(end 0.12065 0.3048)
			(stroke
				(width 0.1)
				(type default)
			)
			(layer "B.Fab")
		)
		(fp_line
			(start 0.12065 -0.2794)
			(end -0.12065 -0.2794)
			(stroke
				(width 0.1)
				(type default)
			)
			(layer "B.Fab")
		)
		(fp_line
			(start 0.12065 -0.305054)
			(end 0.12065 -0.2794)
			(stroke
				(width 0.1)
				(type default)
			)
			(layer "B.Fab")
		)
		(fp_line
			(start -0.120396 0.3048)
			(end -0.120396 0.2794)
			(stroke
				(width 0.1)
				(type default)
			)
			(layer "B.Fab")
		)
		(fp_line
			(start -0.120396 0.2794)
			(end 0.12065 0.2794)
			(stroke
				(width 0.1)
				(type default)
			)
			(layer "B.Fab")
		)
		(fp_line
			(start -0.12065 -0.2794)
			(end -0.12065 -0.3048)
			(stroke
				(width 0.1)
				(type default)
			)
			(layer "B.Fab")
		)
		(fp_line
			(start -0.12065 -0.3048)
			(end -0.67945 -0.3048)
			(stroke
				(width 0.1)
				(type default)
			)
			(layer "B.Fab")
		)
		(fp_line
			(start -0.67945 0.3048)
			(end -0.120396 0.3048)
			(stroke
				(width 0.1)
				(type default)
			)
			(layer "B.Fab")
		)
		(fp_line
			(start -0.67945 -0.3048)
			(end -0.67945 0.3048)
			(stroke
				(width 0.1)
				(type default)
			)
			(layer "B.Fab")
		)
		(pad "1" smd circle
			(at 0.40005 0)
			(size 0 0)
			(layers "B.Cu" "B.Mask" "B.Paste")
			(net "SPI_PEX2_CLK_R")
		)
		(pad "2" smd circle
			(at -0.40005 0)
			(size 0 0)
			(layers "B.Cu" "B.Mask" "B.Paste")
			(net "SPI_PEX2_CLK")
		)
	)
	(footprint ""
		(layer "B.Cu")
		(at 232.482644 -231.225598 -90)
		(property "Reference" "R4518"
			(at 0 0 90)
			(layer "B.SilkS")
			(hide yes)
			(effects
				(font
					(size 1.27 1.27)
				)
				(justify mirror)
			)
		)
		(property "Value" ""
			(at 0 0 90)
			(layer "B.Fab")
			(effects
				(font
					(size 1.27 1.27)
				)
				(justify mirror)
			)
		)
		(duplicate_pad_numbers_are_jumpers no)
		(fp_line
			(start -0.7874 0.4064)
			(end 0.7874 0.4064)
			(stroke
				(width 0.1524)
				(type default)
			)
			(layer "B.SilkS")
		)
		(fp_line
			(start 0.7874 0.4064)
			(end 0.7874 -0.4064)
			(stroke
				(width 0.1524)
				(type default)
			)
			(layer "B.SilkS")
		)
		(fp_line
			(start -0.7874 -0.4064)
			(end -0.7874 0.4064)
			(stroke
				(width 0.1524)
				(type default)
			)
			(layer "B.SilkS")
		)
		(fp_line
			(start 0.7874 -0.4064)
			(end -0.7874 -0.4064)
			(stroke
				(width 0.1524)
				(type default)
			)
			(layer "B.SilkS")
		)
		(fp_line
			(start -0.67945 0.3048)
			(end -0.120396 0.3048)
			(stroke
				(width 0.1)
				(type default)
			)
			(layer "B.Fab")
		)
		(fp_line
			(start -0.120396 0.3048)
			(end -0.120396 0.2794)
			(stroke
				(width 0.1)
				(type default)
			)
			(layer "B.Fab")
		)
		(fp_line
			(start 0.12065 0.3048)
			(end 0.67945 0.3048)
			(stroke
				(width 0.1)
				(type default)
			)
			(layer "B.Fab")
		)
		(fp_line
			(start 0.67945 0.3048)
			(end 0.67945 -0.305054)
			(stroke
				(width 0.1)
				(type default)
			)
			(layer "B.Fab")
		)
		(fp_line
			(start -0.120396 0.2794)
			(end 0.12065 0.2794)
			(stroke
				(width 0.1)
				(type default)
			)
			(layer "B.Fab")
		)
		(fp_line
			(start 0.12065 0.2794)
			(end 0.12065 0.3048)
			(stroke
				(width 0.1)
				(type default)
			)
			(layer "B.Fab")
		)
		(fp_line
			(start -0.12065 -0.2794)
			(end -0.12065 -0.3048)
			(stroke
				(width 0.1)
				(type default)
			)
			(layer "B.Fab")
		)
		(fp_line
			(start 0.12065 -0.2794)
			(end -0.12065 -0.2794)
			(stroke
				(width 0.1)
				(type default)
			)
			(layer "B.Fab")
		)
		(fp_line
			(start -0.67945 -0.3048)
			(end -0.67945 0.3048)
			(stroke
				(width 0.1)
				(type default)
			)
			(layer "B.Fab")
		)
		(fp_line
			(start -0.12065 -0.3048)
			(end -0.67945 -0.3048)
			(stroke
				(width 0.1)
				(type default)
			)
			(layer "B.Fab")
		)
		(fp_line
			(start 0.12065 -0.305054)
			(end 0.12065 -0.2794)
			(stroke
				(width 0.1)
				(type default)
			)
			(layer "B.Fab")
		)
		(fp_line
			(start 0.67945 -0.305054)
			(end 0.12065 -0.305054)
			(stroke
				(width 0.1)
				(type default)
			)
			(layer "B.Fab")
		)
		(pad "1" smd circle
			(at 0.40005 0 90)
			(size 0 0)
			(layers "B.Cu" "B.Mask" "B.Paste")
			(net "SSD4_PWRDIS_BIC")
		)
		(pad "2" smd circle
			(at -0.40005 0 90)
			(size 0 0)
			(layers "B.Cu" "B.Mask" "B.Paste")
			(net "SSD4_PWRDIS_BIC_R")
		)
	)
	(footprint ""
		(layer "B.Cu")
		(at 185.725054 -305.608228 -90)
		(property "Reference" "C3172"
			(at 0 0 90)
			(layer "B.SilkS")
			(hide yes)
			(effects
				(font
					(size 1.27 1.27)
				)
				(justify mirror)
			)
		)
		(property "Value" ""
			(at 0 0 90)
			(layer "B.Fab")
			(effects
				(font
					(size 1.27 1.27)
				)
				(justify mirror)
			)
		)
		(duplicate_pad_numbers_are_jumpers no)
		(fp_line
			(start -0.299974 0.150114)
			(end 0.299974 0.150114)
			(stroke
				(width 0.1)
				(type default)
			)
			(layer "B.Fab")
		)
		(fp_line
			(start 0.299974 0.150114)
			(end 0.299974 -0.150114)
			(stroke
				(width 0.1)
				(type default)
			)
			(layer "B.Fab")
		)
		(fp_line
			(start -0.299974 -0.150114)
			(end -0.299974 0.150114)
			(stroke
				(width 0.1)
				(type default)
			)
			(layer "B.Fab")
		)
		(fp_line
			(start 0.299974 -0.150114)
			(end -0.299974 -0.150114)
			(stroke
				(width 0.1)
				(type default)
			)
			(layer "B.Fab")
		)
		(pad "1" smd rect
			(at 0.2667 0 90)
			(size 0.3048 0.381)
			(layers "B.Cu" "B.Mask" "B.Paste")
			(net "P1V8_VDDA_PEX1")
		)
		(pad "2" smd rect
			(at -0.2667 0 90)
			(size 0.3048 0.381)
			(layers "B.Cu" "B.Mask" "B.Paste")
			(net "GND")
		)
	)
	(footprint ""
		(layer "B.Cu")
		(at 167.200072 -288.299906 90)
		(property "Reference" "C3094"
			(at 0 0 90)
			(layer "B.SilkS")
			(hide yes)
			(effects
				(font
					(size 1.27 1.27)
				)
				(justify mirror)
			)
		)
		(property "Value" ""
			(at 0 0 90)
			(layer "B.Fab")
			(effects
				(font
					(size 1.27 1.27)
				)
				(justify mirror)
			)
		)
		(duplicate_pad_numbers_are_jumpers no)
		(fp_line
			(start 0.299974 -0.150114)
			(end -0.299974 -0.150114)
			(stroke
				(width 0.1)
				(type default)
			)
			(layer "B.Fab")
		)
		(fp_line
			(start -0.299974 -0.150114)
			(end -0.299974 0.150114)
			(stroke
				(width 0.1)
				(type default)
			)
			(layer "B.Fab")
		)
		(fp_line
			(start 0.299974 0.150114)
			(end 0.299974 -0.150114)
			(stroke
				(width 0.1)
				(type default)
			)
			(layer "B.Fab")
		)
		(fp_line
			(start -0.299974 0.150114)
			(end 0.299974 0.150114)
			(stroke
				(width 0.1)
				(type default)
			)
			(layer "B.Fab")
		)
		(pad "1" smd rect
			(at 0.2667 0 270)
			(size 0.3048 0.381)
			(layers "B.Cu" "B.Mask" "B.Paste")
			(net "P1V25_PEX1")
		)
		(pad "2" smd rect
			(at -0.2667 0 270)
			(size 0.3048 0.381)
			(layers "B.Cu" "B.Mask" "B.Paste")
			(net "GND")
		)
	)
	(footprint ""
		(layer "B.Cu")
		(at 189.049914 -295.89984 180)
		(property "Reference" "C3149"
			(at 0 0 0)
			(layer "B.SilkS")
			(hide yes)
			(effects
				(font
					(size 1.27 1.27)
				)
				(justify mirror)
			)
		)
		(property "Value" ""
			(at 0 0 0)
			(layer "B.Fab")
			(effects
				(font
					(size 1.27 1.27)
				)
				(justify mirror)
			)
		)
		(duplicate_pad_numbers_are_jumpers no)
		(fp_line
			(start 0.299974 0.150114)
			(end 0.299974 -0.150114)
			(stroke
				(width 0.1)
				(type default)
			)
			(layer "B.Fab")
		)
		(fp_line
			(start 0.299974 -0.150114)
			(end -0.299974 -0.150114)
			(stroke
				(width 0.1)
				(type default)
			)
			(layer "B.Fab")
		)
		(fp_line
			(start -0.299974 0.150114)
			(end 0.299974 0.150114)
			(stroke
				(width 0.1)
				(type default)
			)
			(layer "B.Fab")
		)
		(fp_line
			(start -0.299974 -0.150114)
			(end -0.299974 0.150114)
			(stroke
				(width 0.1)
				(type default)
			)
			(layer "B.Fab")
		)
		(pad "1" smd rect
			(at 0.2667 0)
			(size 0.3048 0.381)
			(layers "B.Cu" "B.Mask" "B.Paste")
			(net "P1V25_SERDES_VDDPLL_PEX1")
		)
		(pad "2" smd rect
			(at -0.2667 0)
			(size 0.3048 0.381)
			(layers "B.Cu" "B.Mask" "B.Paste")
			(net "GND")
		)
	)
	(footprint ""
		(layer "B.Cu")
		(at 106.463846 -87.12327 180)
		(property "Reference" "C2671"
			(at 0 0 0)
			(layer "B.SilkS")
			(hide yes)
			(effects
				(font
					(size 1.27 1.27)
				)
				(justify mirror)
			)
		)
		(property "Value" ""
			(at 0 0 0)
			(layer "B.Fab")
			(effects
				(font
					(size 1.27 1.27)
				)
				(justify mirror)
			)
		)
		(duplicate_pad_numbers_are_jumpers no)
		(fp_line
			(start 0.7874 0.4064)
			(end 0.7874 -0.4064)
			(stroke
				(width 0.1524)
				(type default)
			)
			(layer "B.SilkS")
		)
		(fp_line
			(start 0.7874 -0.4064)
			(end -0.7874 -0.4064)
			(stroke
				(width 0.1524)
				(type default)
			)
			(layer "B.SilkS")
		)
		(fp_line
			(start -0.7874 0.4064)
			(end 0.7874 0.4064)
			(stroke
				(width 0.1524)
				(type default)
			)
			(layer "B.SilkS")
		)
		(fp_line
			(start -0.7874 -0.4064)
			(end -0.7874 0.4064)
			(stroke
				(width 0.1524)
				(type default)
			)
			(layer "B.SilkS")
		)
		(fp_line
			(start 0.67945 0.3048)
			(end 0.67945 -0.305054)
			(stroke
				(width 0.1)
				(type default)
			)
			(layer "B.Fab")
		)
		(fp_line
			(start 0.67945 -0.305054)
			(end 0.12065 -0.305054)
			(stroke
				(width 0.1)
				(type default)
			)
			(layer "B.Fab")
		)
		(fp_line
			(start 0.12065 0.3048)
			(end 0.67945 0.3048)
			(stroke
				(width 0.1)
				(type default)
			)
			(layer "B.Fab")
		)
		(fp_line
			(start 0.12065 0.2794)
			(end 0.12065 0.3048)
			(stroke
				(width 0.1)
				(type default)
			)
			(layer "B.Fab")
		)
		(fp_line
			(start 0.12065 -0.2794)
			(end -0.12065 -0.2794)
			(stroke
				(width 0.1)
				(type default)
			)
			(layer "B.Fab")
		)
		(fp_line
			(start 0.12065 -0.305054)
			(end 0.12065 -0.2794)
			(stroke
				(width 0.1)
				(type default)
			)
			(layer "B.Fab")
		)
		(fp_line
			(start -0.120396 0.3048)
			(end -0.120396 0.2794)
			(stroke
				(width 0.1)
				(type default)
			)
			(layer "B.Fab")
		)
		(fp_line
			(start -0.120396 0.2794)
			(end 0.12065 0.2794)
			(stroke
				(width 0.1)
				(type default)
			)
			(layer "B.Fab")
		)
		(fp_line
			(start -0.12065 -0.2794)
			(end -0.12065 -0.3048)
			(stroke
				(width 0.1)
				(type default)
			)
			(layer "B.Fab")
		)
		(fp_line
			(start -0.12065 -0.3048)
			(end -0.67945 -0.3048)
			(stroke
				(width 0.1)
				(type default)
			)
			(layer "B.Fab")
		)
		(fp_line
			(start -0.67945 0.3048)
			(end -0.120396 0.3048)
			(stroke
				(width 0.1)
				(type default)
			)
			(layer "B.Fab")
		)
		(fp_line
			(start -0.67945 -0.3048)
			(end -0.67945 0.3048)
			(stroke
				(width 0.1)
				(type default)
			)
			(layer "B.Fab")
		)
		(pad "1" smd circle
			(at 0.40005 0)
			(size 0 0)
			(layers "B.Cu" "B.Mask" "B.Paste")
			(net "P3V3_VDDAR_9ZXL0851_0_7")
		)
		(pad "2" smd circle
			(at -0.40005 0)
			(size 0 0)
			(layers "B.Cu" "B.Mask" "B.Paste")
			(net "GND")
		)
	)
	(footprint ""
		(layer "B.Cu")
		(at 382.895602 -243.39296)
		(property "Reference" "C2563"
			(at 0 0 0)
			(layer "B.SilkS")
			(hide yes)
			(effects
				(font
					(size 1.27 1.27)
				)
				(justify mirror)
			)
		)
		(property "Value" ""
			(at 0 0 0)
			(layer "B.Fab")
			(effects
				(font
					(size 1.27 1.27)
				)
				(justify mirror)
			)
		)
		(duplicate_pad_numbers_are_jumpers no)
		(fp_line
			(start -0.7874 -0.4064)
			(end -0.7874 0.4064)
			(stroke
				(width 0.1524)
				(type default)
			)
			(layer "B.SilkS")
		)
		(fp_line
			(start -0.7874 0.4064)
			(end 0.7874 0.4064)
			(stroke
				(width 0.1524)
				(type default)
			)
			(layer "B.SilkS")
		)
		(fp_line
			(start 0.7874 -0.4064)
			(end -0.7874 -0.4064)
			(stroke
				(width 0.1524)
				(type default)
			)
			(layer "B.SilkS")
		)
		(fp_line
			(start 0.7874 0.4064)
			(end 0.7874 -0.4064)
			(stroke
				(width 0.1524)
				(type default)
			)
			(layer "B.SilkS")
		)
		(fp_line
			(start -0.67945 -0.3048)
			(end -0.67945 0.3048)
			(stroke
				(width 0.1)
				(type default)
			)
			(layer "B.Fab")
		)
		(fp_line
			(start -0.67945 0.3048)
			(end -0.120396 0.3048)
			(stroke
				(width 0.1)
				(type default)
			)
			(layer "B.Fab")
		)
		(fp_line
			(start -0.12065 -0.3048)
			(end -0.67945 -0.3048)
			(stroke
				(width 0.1)
				(type default)
			)
			(layer "B.Fab")
		)
		(fp_line
			(start -0.12065 -0.2794)
			(end -0.12065 -0.3048)
			(stroke
				(width 0.1)
				(type default)
			)
			(layer "B.Fab")
		)
		(fp_line
			(start -0.120396 0.2794)
			(end 0.12065 0.2794)
			(stroke
				(width 0.1)
				(type default)
			)
			(layer "B.Fab")
		)
		(fp_line
			(start -0.120396 0.3048)
			(end -0.120396 0.2794)
			(stroke
				(width 0.1)
				(type default)
			)
			(layer "B.Fab")
		)
		(fp_line
			(start 0.12065 -0.305054)
			(end 0.12065 -0.2794)
			(stroke
				(width 0.1)
				(type default)
			)
			(layer "B.Fab")
		)
		(fp_line
			(start 0.12065 -0.2794)
			(end -0.12065 -0.2794)
			(stroke
				(width 0.1)
				(type default)
			)
			(layer "B.Fab")
		)
		(fp_line
			(start 0.12065 0.2794)
			(end 0.12065 0.3048)
			(stroke
				(width 0.1)
				(type default)
			)
			(layer "B.Fab")
		)
		(fp_line
			(start 0.12065 0.3048)
			(end 0.67945 0.3048)
			(stroke
				(width 0.1)
				(type default)
			)
			(layer "B.Fab")
		)
		(fp_line
			(start 0.67945 -0.305054)
			(end 0.12065 -0.305054)
			(stroke
				(width 0.1)
				(type default)
			)
			(layer "B.Fab")
		)
		(fp_line
			(start 0.67945 0.3048)
			(end 0.67945 -0.305054)
			(stroke
				(width 0.1)
				(type default)
			)
			(layer "B.Fab")
		)
		(pad "1" smd circle
			(at 0.40005 0 180)
			(size 0 0)
			(layers "B.Cu" "B.Mask" "B.Paste")
			(net "P3V3_AUX")
		)
		(pad "2" smd circle
			(at -0.40005 0 180)
			(size 0 0)
			(layers "B.Cu" "B.Mask" "B.Paste")
			(net "GND")
		)
	)
	(footprint ""
		(layer "B.Cu")
		(at 406.049988 -299.699934 -90)
		(property "Reference" "C1939"
			(at 0 0 90)
			(layer "B.SilkS")
			(hide yes)
			(effects
				(font
					(size 1.27 1.27)
				)
				(justify mirror)
			)
		)
		(property "Value" ""
			(at 0 0 90)
			(layer "B.Fab")
			(effects
				(font
					(size 1.27 1.27)
				)
				(justify mirror)
			)
		)
		(duplicate_pad_numbers_are_jumpers no)
		(fp_line
			(start -0.299974 0.150114)
			(end 0.299974 0.150114)
			(stroke
				(width 0.1)
				(type default)
			)
			(layer "B.Fab")
		)
		(fp_line
			(start 0.299974 0.150114)
			(end 0.299974 -0.150114)
			(stroke
				(width 0.1)
				(type default)
			)
			(layer "B.Fab")
		)
		(fp_line
			(start -0.299974 -0.150114)
			(end -0.299974 0.150114)
			(stroke
				(width 0.1)
				(type default)
			)
			(layer "B.Fab")
		)
		(fp_line
			(start 0.299974 -0.150114)
			(end -0.299974 -0.150114)
			(stroke
				(width 0.1)
				(type default)
			)
			(layer "B.Fab")
		)
		(pad "1" smd rect
			(at 0.2667 0 90)
			(size 0.3048 0.381)
			(layers "B.Cu" "B.Mask" "B.Paste")
			(net "P0V8_SERDES_VDDA_PEX3")
		)
		(pad "2" smd rect
			(at -0.2667 0 90)
			(size 0.3048 0.381)
			(layers "B.Cu" "B.Mask" "B.Paste")
			(net "GND")
		)
	)
	(footprint ""
		(layer "B.Cu")
		(at 226.546664 -208.78546 -90)
		(property "Reference" "R4894"
			(at 0 0 90)
			(layer "B.SilkS")
			(hide yes)
			(effects
				(font
					(size 1.27 1.27)
				)
				(justify mirror)
			)
		)
		(property "Value" ""
			(at 0 0 90)
			(layer "B.Fab")
			(effects
				(font
					(size 1.27 1.27)
				)
				(justify mirror)
			)
		)
		(duplicate_pad_numbers_are_jumpers no)
		(fp_line
			(start -0.7874 0.4064)
			(end 0.7874 0.4064)
			(stroke
				(width 0.1524)
				(type default)
			)
			(layer "B.SilkS")
		)
		(fp_line
			(start 0.7874 0.4064)
			(end 0.7874 -0.4064)
			(stroke
				(width 0.1524)
				(type default)
			)
			(layer "B.SilkS")
		)
		(fp_line
			(start -0.7874 -0.4064)
			(end -0.7874 0.4064)
			(stroke
				(width 0.1524)
				(type default)
			)
			(layer "B.SilkS")
		)
		(fp_line
			(start 0.7874 -0.4064)
			(end -0.7874 -0.4064)
			(stroke
				(width 0.1524)
				(type default)
			)
			(layer "B.SilkS")
		)
		(fp_line
			(start -0.67945 0.3048)
			(end -0.120396 0.3048)
			(stroke
				(width 0.1)
				(type default)
			)
			(layer "B.Fab")
		)
		(fp_line
			(start -0.120396 0.3048)
			(end -0.120396 0.2794)
			(stroke
				(width 0.1)
				(type default)
			)
			(layer "B.Fab")
		)
		(fp_line
			(start 0.12065 0.3048)
			(end 0.67945 0.3048)
			(stroke
				(width 0.1)
				(type default)
			)
			(layer "B.Fab")
		)
		(fp_line
			(start 0.67945 0.3048)
			(end 0.67945 -0.305054)
			(stroke
				(width 0.1)
				(type default)
			)
			(layer "B.Fab")
		)
		(fp_line
			(start -0.120396 0.2794)
			(end 0.12065 0.2794)
			(stroke
				(width 0.1)
				(type default)
			)
			(layer "B.Fab")
		)
		(fp_line
			(start 0.12065 0.2794)
			(end 0.12065 0.3048)
			(stroke
				(width 0.1)
				(type default)
			)
			(layer "B.Fab")
		)
		(fp_line
			(start -0.12065 -0.2794)
			(end -0.12065 -0.3048)
			(stroke
				(width 0.1)
				(type default)
			)
			(layer "B.Fab")
		)
		(fp_line
			(start 0.12065 -0.2794)
			(end -0.12065 -0.2794)
			(stroke
				(width 0.1)
				(type default)
			)
			(layer "B.Fab")
		)
		(fp_line
			(start -0.67945 -0.3048)
			(end -0.67945 0.3048)
			(stroke
				(width 0.1)
				(type default)
			)
			(layer "B.Fab")
		)
		(fp_line
			(start -0.12065 -0.3048)
			(end -0.67945 -0.3048)
			(stroke
				(width 0.1)
				(type default)
			)
			(layer "B.Fab")
		)
		(fp_line
			(start 0.12065 -0.305054)
			(end 0.12065 -0.2794)
			(stroke
				(width 0.1)
				(type default)
			)
			(layer "B.Fab")
		)
		(fp_line
			(start 0.67945 -0.305054)
			(end 0.12065 -0.305054)
			(stroke
				(width 0.1)
				(type default)
			)
			(layer "B.Fab")
		)
		(pad "1" smd circle
			(at 0.40005 0 90)
			(size 0 0)
			(layers "B.Cu" "B.Mask" "B.Paste")
			(net "JTAG_BIC_TMS_R")
		)
		(pad "2" smd circle
			(at -0.40005 0 90)
			(size 0 0)
			(layers "B.Cu" "B.Mask" "B.Paste")
			(net "JTAG_BIC_TMS")
		)
	)
	(footprint ""
		(layer "B.Cu")
		(at 340.641432 -303.649634 -90)
		(property "Reference" "PC149"
			(at 0 0 90)
			(layer "B.SilkS")
			(hide yes)
			(effects
				(font
					(size 1.27 1.27)
				)
				(justify mirror)
			)
		)
		(property "Value" ""
			(at 0 0 90)
			(layer "B.Fab")
			(effects
				(font
					(size 1.27 1.27)
				)
				(justify mirror)
			)
		)
		(duplicate_pad_numbers_are_jumpers no)
		(fp_line
			(start -1.524 0.762)
			(end 1.524 0.762)
			(stroke
				(width 0.1524)
				(type default)
			)
			(layer "B.SilkS")
		)
		(fp_line
			(start 1.524 0.762)
			(end 1.524 -0.762)
			(stroke
				(width 0.1524)
				(type default)
			)
			(layer "B.SilkS")
		)
		(fp_line
			(start -1.524 -0.762)
			(end -1.524 0.762)
			(stroke
				(width 0.1524)
				(type default)
			)
			(layer "B.SilkS")
		)
		(fp_line
			(start 1.524 -0.762)
			(end -1.524 -0.762)
			(stroke
				(width 0.1524)
				(type default)
			)
			(layer "B.SilkS")
		)
		(fp_line
			(start -1.1049 0.724916)
			(end -1.1049 -0.724916)
			(stroke
				(width 0.1)
				(type default)
			)
			(layer "B.Fab")
		)
		(fp_line
			(start 1.1049 0.724916)
			(end -1.1049 0.724916)
			(stroke
				(width 0.1)
				(type default)
			)
			(layer "B.Fab")
		)
		(fp_line
			(start -1.1049 -0.724916)
			(end 1.1049 -0.724916)
			(stroke
				(width 0.1)
				(type default)
			)
			(layer "B.Fab")
		)
		(fp_line
			(start 1.1049 -0.724916)
			(end 1.1049 0.724916)
			(stroke
				(width 0.1)
				(type default)
			)
			(layer "B.Fab")
		)
		(pad "1" smd rect
			(at 0.889 0 270)
			(size 1.016 1.27)
			(layers "B.Cu" "B.Mask" "B.Paste")
			(net "P0V8_PEX2")
		)
		(pad "2" smd rect
			(at -0.889 0 270)
			(size 1.016 1.27)
			(layers "B.Cu" "B.Mask" "B.Paste")
			(net "GND")
		)
	)
	(footprint ""
		(layer "B.Cu")
		(at 175.749966 -290.199826 90)
		(property "Reference" "C1483"
			(at 0 0 90)
			(layer "B.SilkS")
			(hide yes)
			(effects
				(font
					(size 1.27 1.27)
				)
				(justify mirror)
			)
		)
		(property "Value" ""
			(at 0 0 90)
			(layer "B.Fab")
			(effects
				(font
					(size 1.27 1.27)
				)
				(justify mirror)
			)
		)
		(duplicate_pad_numbers_are_jumpers no)
		(fp_line
			(start 0.299974 -0.150114)
			(end -0.299974 -0.150114)
			(stroke
				(width 0.1)
				(type default)
			)
			(layer "B.Fab")
		)
		(fp_line
			(start -0.299974 -0.150114)
			(end -0.299974 0.150114)
			(stroke
				(width 0.1)
				(type default)
			)
			(layer "B.Fab")
		)
		(fp_line
			(start 0.299974 0.150114)
			(end 0.299974 -0.150114)
			(stroke
				(width 0.1)
				(type default)
			)
			(layer "B.Fab")
		)
		(fp_line
			(start -0.299974 0.150114)
			(end 0.299974 0.150114)
			(stroke
				(width 0.1)
				(type default)
			)
			(layer "B.Fab")
		)
		(pad "1" smd rect
			(at 0.2667 0 270)
			(size 0.3048 0.381)
			(layers "B.Cu" "B.Mask" "B.Paste")
			(net "P0V8_SERDES_VDDA_PEX1")
		)
		(pad "2" smd rect
			(at -0.2667 0 270)
			(size 0.3048 0.381)
			(layers "B.Cu" "B.Mask" "B.Paste")
			(net "GND")
		)
	)
	(footprint ""
		(layer "B.Cu")
		(at 355.962712 -321.15125 -90)
		(property "Reference" "R6538"
			(at 0 0 90)
			(layer "B.SilkS")
			(hide yes)
			(effects
				(font
					(size 1.27 1.27)
				)
				(justify mirror)
			)
		)
		(property "Value" ""
			(at 0 0 90)
			(layer "B.Fab")
			(effects
				(font
					(size 1.27 1.27)
				)
				(justify mirror)
			)
		)
		(duplicate_pad_numbers_are_jumpers no)
		(fp_line
			(start -0.7874 0.4064)
			(end 0.7874 0.4064)
			(stroke
				(width 0.1524)
				(type default)
			)
			(layer "B.SilkS")
		)
		(fp_line
			(start 0.7874 0.4064)
			(end 0.7874 -0.4064)
			(stroke
				(width 0.1524)
				(type default)
			)
			(layer "B.SilkS")
		)
		(fp_line
			(start -0.7874 -0.4064)
			(end -0.7874 0.4064)
			(stroke
				(width 0.1524)
				(type default)
			)
			(layer "B.SilkS")
		)
		(fp_line
			(start 0.7874 -0.4064)
			(end -0.7874 -0.4064)
			(stroke
				(width 0.1524)
				(type default)
			)
			(layer "B.SilkS")
		)
		(fp_line
			(start -0.67945 0.3048)
			(end -0.120396 0.3048)
			(stroke
				(width 0.1)
				(type default)
			)
			(layer "B.Fab")
		)
		(fp_line
			(start -0.120396 0.3048)
			(end -0.120396 0.2794)
			(stroke
				(width 0.1)
				(type default)
			)
			(layer "B.Fab")
		)
		(fp_line
			(start 0.12065 0.3048)
			(end 0.67945 0.3048)
			(stroke
				(width 0.1)
				(type default)
			)
			(layer "B.Fab")
		)
		(fp_line
			(start 0.67945 0.3048)
			(end 0.67945 -0.305054)
			(stroke
				(width 0.1)
				(type default)
			)
			(layer "B.Fab")
		)
		(fp_line
			(start -0.120396 0.2794)
			(end 0.12065 0.2794)
			(stroke
				(width 0.1)
				(type default)
			)
			(layer "B.Fab")
		)
		(fp_line
			(start 0.12065 0.2794)
			(end 0.12065 0.3048)
			(stroke
				(width 0.1)
				(type default)
			)
			(layer "B.Fab")
		)
		(fp_line
			(start -0.12065 -0.2794)
			(end -0.12065 -0.3048)
			(stroke
				(width 0.1)
				(type default)
			)
			(layer "B.Fab")
		)
		(fp_line
			(start 0.12065 -0.2794)
			(end -0.12065 -0.2794)
			(stroke
				(width 0.1)
				(type default)
			)
			(layer "B.Fab")
		)
		(fp_line
			(start -0.67945 -0.3048)
			(end -0.67945 0.3048)
			(stroke
				(width 0.1)
				(type default)
			)
			(layer "B.Fab")
		)
		(fp_line
			(start -0.12065 -0.3048)
			(end -0.67945 -0.3048)
			(stroke
				(width 0.1)
				(type default)
			)
			(layer "B.Fab")
		)
		(fp_line
			(start 0.12065 -0.305054)
			(end 0.12065 -0.2794)
			(stroke
				(width 0.1)
				(type default)
			)
			(layer "B.Fab")
		)
		(fp_line
			(start 0.67945 -0.305054)
			(end 0.12065 -0.305054)
			(stroke
				(width 0.1)
				(type default)
			)
			(layer "B.Fab")
		)
		(pad "1" smd circle
			(at 0.40005 0 90)
			(size 0 0)
			(layers "B.Cu" "B.Mask" "B.Paste")
			(net "P0V8_SERDES_VDDA_PEX3")
		)
		(pad "2" smd circle
			(at -0.40005 0 90)
			(size 0 0)
			(layers "B.Cu" "B.Mask" "B.Paste")
			(net "P0V8_SERDES_VDDA_PEX3_C3")
		)
	)
	(footprint ""
		(layer "B.Cu")
		(at 346.026232 -323.15531 -90)
		(property "Reference" "R6514"
			(at 0 0 90)
			(layer "B.SilkS")
			(hide yes)
			(effects
				(font
					(size 1.27 1.27)
				)
				(justify mirror)
			)
		)
		(property "Value" ""
			(at 0 0 90)
			(layer "B.Fab")
			(effects
				(font
					(size 1.27 1.27)
				)
				(justify mirror)
			)
		)
		(duplicate_pad_numbers_are_jumpers no)
		(fp_line
			(start -0.7874 0.4064)
			(end 0.7874 0.4064)
			(stroke
				(width 0.1524)
				(type default)
			)
			(layer "B.SilkS")
		)
		(fp_line
			(start 0.7874 0.4064)
			(end 0.7874 -0.4064)
			(stroke
				(width 0.1524)
				(type default)
			)
			(layer "B.SilkS")
		)
		(fp_line
			(start -0.7874 -0.4064)
			(end -0.7874 0.4064)
			(stroke
				(width 0.1524)
				(type default)
			)
			(layer "B.SilkS")
		)
		(fp_line
			(start 0.7874 -0.4064)
			(end -0.7874 -0.4064)
			(stroke
				(width 0.1524)
				(type default)
			)
			(layer "B.SilkS")
		)
		(fp_line
			(start -0.67945 0.3048)
			(end -0.120396 0.3048)
			(stroke
				(width 0.1)
				(type default)
			)
			(layer "B.Fab")
		)
		(fp_line
			(start -0.120396 0.3048)
			(end -0.120396 0.2794)
			(stroke
				(width 0.1)
				(type default)
			)
			(layer "B.Fab")
		)
		(fp_line
			(start 0.12065 0.3048)
			(end 0.67945 0.3048)
			(stroke
				(width 0.1)
				(type default)
			)
			(layer "B.Fab")
		)
		(fp_line
			(start 0.67945 0.3048)
			(end 0.67945 -0.305054)
			(stroke
				(width 0.1)
				(type default)
			)
			(layer "B.Fab")
		)
		(fp_line
			(start -0.120396 0.2794)
			(end 0.12065 0.2794)
			(stroke
				(width 0.1)
				(type default)
			)
			(layer "B.Fab")
		)
		(fp_line
			(start 0.12065 0.2794)
			(end 0.12065 0.3048)
			(stroke
				(width 0.1)
				(type default)
			)
			(layer "B.Fab")
		)
		(fp_line
			(start -0.12065 -0.2794)
			(end -0.12065 -0.3048)
			(stroke
				(width 0.1)
				(type default)
			)
			(layer "B.Fab")
		)
		(fp_line
			(start 0.12065 -0.2794)
			(end -0.12065 -0.2794)
			(stroke
				(width 0.1)
				(type default)
			)
			(layer "B.Fab")
		)
		(fp_line
			(start -0.67945 -0.3048)
			(end -0.67945 0.3048)
			(stroke
				(width 0.1)
				(type default)
			)
			(layer "B.Fab")
		)
		(fp_line
			(start -0.12065 -0.3048)
			(end -0.67945 -0.3048)
			(stroke
				(width 0.1)
				(type default)
			)
			(layer "B.Fab")
		)
		(fp_line
			(start 0.12065 -0.305054)
			(end 0.12065 -0.2794)
			(stroke
				(width 0.1)
				(type default)
			)
			(layer "B.Fab")
		)
		(fp_line
			(start 0.67945 -0.305054)
			(end 0.12065 -0.305054)
			(stroke
				(width 0.1)
				(type default)
			)
			(layer "B.Fab")
		)
		(pad "1" smd circle
			(at 0.40005 0 90)
			(size 0 0)
			(layers "B.Cu" "B.Mask" "B.Paste")
			(net "P0V8_SERDES_VDDA_PEX2")
		)
		(pad "2" smd circle
			(at -0.40005 0 90)
			(size 0 0)
			(layers "B.Cu" "B.Mask" "B.Paste")
			(net "P0V8_SERDES_VDDA_PEX2_C7")
		)
	)
	(footprint ""
		(layer "B.Cu")
		(at 408.899868 -290.199826 90)
		(property "Reference" "C1962"
			(at 0 0 90)
			(layer "B.SilkS")
			(hide yes)
			(effects
				(font
					(size 1.27 1.27)
				)
				(justify mirror)
			)
		)
		(property "Value" ""
			(at 0 0 90)
			(layer "B.Fab")
			(effects
				(font
					(size 1.27 1.27)
				)
				(justify mirror)
			)
		)
		(duplicate_pad_numbers_are_jumpers no)
		(fp_line
			(start 0.299974 -0.150114)
			(end -0.299974 -0.150114)
			(stroke
				(width 0.1)
				(type default)
			)
			(layer "B.Fab")
		)
		(fp_line
			(start -0.299974 -0.150114)
			(end -0.299974 0.150114)
			(stroke
				(width 0.1)
				(type default)
			)
			(layer "B.Fab")
		)
		(fp_line
			(start 0.299974 0.150114)
			(end 0.299974 -0.150114)
			(stroke
				(width 0.1)
				(type default)
			)
			(layer "B.Fab")
		)
		(fp_line
			(start -0.299974 0.150114)
			(end 0.299974 0.150114)
			(stroke
				(width 0.1)
				(type default)
			)
			(layer "B.Fab")
		)
		(pad "1" smd rect
			(at 0.2667 0 270)
			(size 0.3048 0.381)
			(layers "B.Cu" "B.Mask" "B.Paste")
			(net "P0V8_SERDES_VDDA_PEX3")
		)
		(pad "2" smd rect
			(at -0.2667 0 270)
			(size 0.3048 0.381)
			(layers "B.Cu" "B.Mask" "B.Paste")
			(net "GND")
		)
	)
	(footprint ""
		(layer "B.Cu")
		(at 228.29901 -143.815054 -90)
		(property "Reference" "C2806"
			(at 0 0 90)
			(layer "B.SilkS")
			(hide yes)
			(effects
				(font
					(size 1.27 1.27)
				)
				(justify mirror)
			)
		)
		(property "Value" ""
			(at 0 0 90)
			(layer "B.Fab")
			(effects
				(font
					(size 1.27 1.27)
				)
				(justify mirror)
			)
		)
		(duplicate_pad_numbers_are_jumpers no)
		(fp_line
			(start -0.7874 0.4064)
			(end 0.7874 0.4064)
			(stroke
				(width 0.1524)
				(type default)
			)
			(layer "B.SilkS")
		)
		(fp_line
			(start 0.7874 0.4064)
			(end 0.7874 -0.4064)
			(stroke
				(width 0.1524)
				(type default)
			)
			(layer "B.SilkS")
		)
		(fp_line
			(start -0.7874 -0.4064)
			(end -0.7874 0.4064)
			(stroke
				(width 0.1524)
				(type default)
			)
			(layer "B.SilkS")
		)
		(fp_line
			(start 0.7874 -0.4064)
			(end -0.7874 -0.4064)
			(stroke
				(width 0.1524)
				(type default)
			)
			(layer "B.SilkS")
		)
		(fp_line
			(start -0.67945 0.3048)
			(end -0.120396 0.3048)
			(stroke
				(width 0.1)
				(type default)
			)
			(layer "B.Fab")
		)
		(fp_line
			(start -0.120396 0.3048)
			(end -0.120396 0.2794)
			(stroke
				(width 0.1)
				(type default)
			)
			(layer "B.Fab")
		)
		(fp_line
			(start 0.12065 0.3048)
			(end 0.67945 0.3048)
			(stroke
				(width 0.1)
				(type default)
			)
			(layer "B.Fab")
		)
		(fp_line
			(start 0.67945 0.3048)
			(end 0.67945 -0.305054)
			(stroke
				(width 0.1)
				(type default)
			)
			(layer "B.Fab")
		)
		(fp_line
			(start -0.120396 0.2794)
			(end 0.12065 0.2794)
			(stroke
				(width 0.1)
				(type default)
			)
			(layer "B.Fab")
		)
		(fp_line
			(start 0.12065 0.2794)
			(end 0.12065 0.3048)
			(stroke
				(width 0.1)
				(type default)
			)
			(layer "B.Fab")
		)
		(fp_line
			(start -0.12065 -0.2794)
			(end -0.12065 -0.3048)
			(stroke
				(width 0.1)
				(type default)
			)
			(layer "B.Fab")
		)
		(fp_line
			(start 0.12065 -0.2794)
			(end -0.12065 -0.2794)
			(stroke
				(width 0.1)
				(type default)
			)
			(layer "B.Fab")
		)
		(fp_line
			(start -0.67945 -0.3048)
			(end -0.67945 0.3048)
			(stroke
				(width 0.1)
				(type default)
			)
			(layer "B.Fab")
		)
		(fp_line
			(start -0.12065 -0.3048)
			(end -0.67945 -0.3048)
			(stroke
				(width 0.1)
				(type default)
			)
			(layer "B.Fab")
		)
		(fp_line
			(start 0.12065 -0.305054)
			(end 0.12065 -0.2794)
			(stroke
				(width 0.1)
				(type default)
			)
			(layer "B.Fab")
		)
		(fp_line
			(start 0.67945 -0.305054)
			(end 0.12065 -0.305054)
			(stroke
				(width 0.1)
				(type default)
			)
			(layer "B.Fab")
		)
		(pad "1" smd circle
			(at 0.40005 0 90)
			(size 0 0)
			(layers "B.Cu" "B.Mask" "B.Paste")
			(net "P3V3_CLK_GEN_VDDPT_CK440_PEX")
		)
		(pad "2" smd circle
			(at -0.40005 0 90)
			(size 0 0)
			(layers "B.Cu" "B.Mask" "B.Paste")
			(net "GND")
		)
	)
	(footprint ""
		(layer "B.Cu")
		(at 309.741824 -99.037648 180)
		(property "Reference" "R269"
			(at 0 0 0)
			(layer "B.SilkS")
			(hide yes)
			(effects
				(font
					(size 1.27 1.27)
				)
				(justify mirror)
			)
		)
		(property "Value" ""
			(at 0 0 0)
			(layer "B.Fab")
			(effects
				(font
					(size 1.27 1.27)
				)
				(justify mirror)
			)
		)
		(duplicate_pad_numbers_are_jumpers no)
		(fp_line
			(start 0.7874 0.4064)
			(end 0.7874 -0.4064)
			(stroke
				(width 0.1524)
				(type default)
			)
			(layer "B.SilkS")
		)
		(fp_line
			(start 0.7874 -0.4064)
			(end -0.7874 -0.4064)
			(stroke
				(width 0.1524)
				(type default)
			)
			(layer "B.SilkS")
		)
		(fp_line
			(start -0.7874 0.4064)
			(end 0.7874 0.4064)
			(stroke
				(width 0.1524)
				(type default)
			)
			(layer "B.SilkS")
		)
		(fp_line
			(start -0.7874 -0.4064)
			(end -0.7874 0.4064)
			(stroke
				(width 0.1524)
				(type default)
			)
			(layer "B.SilkS")
		)
		(fp_line
			(start 0.67945 0.3048)
			(end 0.67945 -0.305054)
			(stroke
				(width 0.1)
				(type default)
			)
			(layer "B.Fab")
		)
		(fp_line
			(start 0.67945 -0.305054)
			(end 0.12065 -0.305054)
			(stroke
				(width 0.1)
				(type default)
			)
			(layer "B.Fab")
		)
		(fp_line
			(start 0.12065 0.3048)
			(end 0.67945 0.3048)
			(stroke
				(width 0.1)
				(type default)
			)
			(layer "B.Fab")
		)
		(fp_line
			(start 0.12065 0.2794)
			(end 0.12065 0.3048)
			(stroke
				(width 0.1)
				(type default)
			)
			(layer "B.Fab")
		)
		(fp_line
			(start 0.12065 -0.2794)
			(end -0.12065 -0.2794)
			(stroke
				(width 0.1)
				(type default)
			)
			(layer "B.Fab")
		)
		(fp_line
			(start 0.12065 -0.305054)
			(end 0.12065 -0.2794)
			(stroke
				(width 0.1)
				(type default)
			)
			(layer "B.Fab")
		)
		(fp_line
			(start -0.120396 0.3048)
			(end -0.120396 0.2794)
			(stroke
				(width 0.1)
				(type default)
			)
			(layer "B.Fab")
		)
		(fp_line
			(start -0.120396 0.2794)
			(end 0.12065 0.2794)
			(stroke
				(width 0.1)
				(type default)
			)
			(layer "B.Fab")
		)
		(fp_line
			(start -0.12065 -0.2794)
			(end -0.12065 -0.3048)
			(stroke
				(width 0.1)
				(type default)
			)
			(layer "B.Fab")
		)
		(fp_line
			(start -0.12065 -0.3048)
			(end -0.67945 -0.3048)
			(stroke
				(width 0.1)
				(type default)
			)
			(layer "B.Fab")
		)
		(fp_line
			(start -0.67945 0.3048)
			(end -0.120396 0.3048)
			(stroke
				(width 0.1)
				(type default)
			)
			(layer "B.Fab")
		)
		(fp_line
			(start -0.67945 -0.3048)
			(end -0.67945 0.3048)
			(stroke
				(width 0.1)
				(type default)
			)
			(layer "B.Fab")
		)
		(pad "1" smd circle
			(at 0.40005 0)
			(size 0 0)
			(layers "B.Cu" "B.Mask" "B.Paste")
			(net "NIC5_CLK")
		)
		(pad "2" smd circle
			(at -0.40005 0)
			(size 0 0)
			(layers "B.Cu" "B.Mask" "B.Paste")
			(net "GND")
		)
	)
	(footprint ""
		(layer "B.Cu")
		(at 107.837986 -357.638604 90)
		(property "Reference" "L149"
			(at -1.393698 1.636776 270)
			(unlocked yes)
			(layer "B.SilkS")
			(effects
				(font
					(size 0.7874 0.5842)
					(thickness 0.1524)
				)
				(justify left mirror)
			)
		)
		(property "Value" ""
			(at 0 0 90)
			(layer "B.Fab")
			(effects
				(font
					(size 1.27 1.27)
				)
				(justify mirror)
			)
		)
		(duplicate_pad_numbers_are_jumpers no)
		(fp_line
			(start 1.63576 -0.8128)
			(end -1.63576 -0.8128)
			(stroke
				(width 0.1524)
				(type default)
			)
			(layer "B.SilkS")
		)
		(fp_line
			(start 1.63576 -0.8128)
			(end 1.63576 0.8128)
			(stroke
				(width 0.1524)
				(type default)
			)
			(layer "B.SilkS")
		)
		(fp_line
			(start -1.63576 -0.8128)
			(end -1.63576 0.8128)
			(stroke
				(width 0.1524)
				(type default)
			)
			(layer "B.SilkS")
		)
		(fp_line
			(start -1.63576 0.8128)
			(end 1.63576 0.8128)
			(stroke
				(width 0.1524)
				(type default)
			)
			(layer "B.SilkS")
		)
		(fp_line
			(start 1.56083 -0.738632)
			(end 1.56083 0.7366)
			(stroke
				(width 0.1)
				(type default)
			)
			(layer "B.Fab")
		)
		(fp_line
			(start -1.560576 -0.738632)
			(end 1.56083 -0.738632)
			(stroke
				(width 0.1)
				(type default)
			)
			(layer "B.Fab")
		)
		(fp_line
			(start 1.56083 0.7366)
			(end 1.524 0.7366)
			(stroke
				(width 0.1)
				(type default)
			)
			(layer "B.Fab")
		)
		(fp_line
			(start 1.524 0.7366)
			(end -1.524 0.7366)
			(stroke
				(width 0.1)
				(type default)
			)
			(layer "B.Fab")
		)
		(fp_line
			(start -1.524 0.7366)
			(end -1.560576 0.7366)
			(stroke
				(width 0.1)
				(type default)
			)
			(layer "B.Fab")
		)
		(fp_line
			(start -1.560576 0.7366)
			(end -1.560576 -0.738632)
			(stroke
				(width 0.1)
				(type default)
			)
			(layer "B.Fab")
		)
		(pad "1" smd rect
			(at 0.94996 0 90)
			(size 1.1176 1.3716)
			(layers "B.Cu" "B.Mask" "B.Paste")
			(net "P3V3")
		)
		(pad "2" smd rect
			(at -0.94996 0 90)
			(size 1.1176 1.3716)
			(layers "B.Cu" "B.Mask" "B.Paste")
			(net "P3V3_CLK_BUFFER_9ZXL0451E_S3_VZX3P3")
		)
	)
	(footprint ""
		(layer "B.Cu")
		(at 359.455974 -321.84594 -90)
		(property "Reference" "R6545"
			(at 0 0 90)
			(layer "B.SilkS")
			(hide yes)
			(effects
				(font
					(size 1.27 1.27)
				)
				(justify mirror)
			)
		)
		(property "Value" ""
			(at 0 0 90)
			(layer "B.Fab")
			(effects
				(font
					(size 1.27 1.27)
				)
				(justify mirror)
			)
		)
		(duplicate_pad_numbers_are_jumpers no)
		(fp_line
			(start -0.7874 0.4064)
			(end 0.7874 0.4064)
			(stroke
				(width 0.1524)
				(type default)
			)
			(layer "B.SilkS")
		)
		(fp_line
			(start 0.7874 0.4064)
			(end 0.7874 -0.4064)
			(stroke
				(width 0.1524)
				(type default)
			)
			(layer "B.SilkS")
		)
		(fp_line
			(start -0.7874 -0.4064)
			(end -0.7874 0.4064)
			(stroke
				(width 0.1524)
				(type default)
			)
			(layer "B.SilkS")
		)
		(fp_line
			(start 0.7874 -0.4064)
			(end -0.7874 -0.4064)
			(stroke
				(width 0.1524)
				(type default)
			)
			(layer "B.SilkS")
		)
		(fp_line
			(start -0.67945 0.3048)
			(end -0.120396 0.3048)
			(stroke
				(width 0.1)
				(type default)
			)
			(layer "B.Fab")
		)
		(fp_line
			(start -0.120396 0.3048)
			(end -0.120396 0.2794)
			(stroke
				(width 0.1)
				(type default)
			)
			(layer "B.Fab")
		)
		(fp_line
			(start 0.12065 0.3048)
			(end 0.67945 0.3048)
			(stroke
				(width 0.1)
				(type default)
			)
			(layer "B.Fab")
		)
		(fp_line
			(start 0.67945 0.3048)
			(end 0.67945 -0.305054)
			(stroke
				(width 0.1)
				(type default)
			)
			(layer "B.Fab")
		)
		(fp_line
			(start -0.120396 0.2794)
			(end 0.12065 0.2794)
			(stroke
				(width 0.1)
				(type default)
			)
			(layer "B.Fab")
		)
		(fp_line
			(start 0.12065 0.2794)
			(end 0.12065 0.3048)
			(stroke
				(width 0.1)
				(type default)
			)
			(layer "B.Fab")
		)
		(fp_line
			(start -0.12065 -0.2794)
			(end -0.12065 -0.3048)
			(stroke
				(width 0.1)
				(type default)
			)
			(layer "B.Fab")
		)
		(fp_line
			(start 0.12065 -0.2794)
			(end -0.12065 -0.2794)
			(stroke
				(width 0.1)
				(type default)
			)
			(layer "B.Fab")
		)
		(fp_line
			(start -0.67945 -0.3048)
			(end -0.67945 0.3048)
			(stroke
				(width 0.1)
				(type default)
			)
			(layer "B.Fab")
		)
		(fp_line
			(start -0.12065 -0.3048)
			(end -0.67945 -0.3048)
			(stroke
				(width 0.1)
				(type default)
			)
			(layer "B.Fab")
		)
		(fp_line
			(start 0.12065 -0.305054)
			(end 0.12065 -0.2794)
			(stroke
				(width 0.1)
				(type default)
			)
			(layer "B.Fab")
		)
		(fp_line
			(start 0.67945 -0.305054)
			(end 0.12065 -0.305054)
			(stroke
				(width 0.1)
				(type default)
			)
			(layer "B.Fab")
		)
		(pad "1" smd circle
			(at 0.40005 0 90)
			(size 0 0)
			(layers "B.Cu" "B.Mask" "B.Paste")
			(net "P0V8_SERDES_VDDA_PEX3")
		)
		(pad "2" smd circle
			(at -0.40005 0 90)
			(size 0 0)
			(layers "B.Cu" "B.Mask" "B.Paste")
			(net "P0V8_SERDES_VDDA_PEX3_C8")
		)
	)
	(footprint ""
		(layer "B.Cu")
		(at 295.575228 -110.497366 180)
		(property "Reference" "R289"
			(at 0 0 0)
			(layer "B.SilkS")
			(hide yes)
			(effects
				(font
					(size 1.27 1.27)
				)
				(justify mirror)
			)
		)
		(property "Value" ""
			(at 0 0 0)
			(layer "B.Fab")
			(effects
				(font
					(size 1.27 1.27)
				)
				(justify mirror)
			)
		)
		(duplicate_pad_numbers_are_jumpers no)
		(fp_line
			(start 0.7874 0.4064)
			(end 0.7874 -0.4064)
			(stroke
				(width 0.1524)
				(type default)
			)
			(layer "B.SilkS")
		)
		(fp_line
			(start 0.7874 -0.4064)
			(end -0.7874 -0.4064)
			(stroke
				(width 0.1524)
				(type default)
			)
			(layer "B.SilkS")
		)
		(fp_line
			(start -0.7874 0.4064)
			(end 0.7874 0.4064)
			(stroke
				(width 0.1524)
				(type default)
			)
			(layer "B.SilkS")
		)
		(fp_line
			(start -0.7874 -0.4064)
			(end -0.7874 0.4064)
			(stroke
				(width 0.1524)
				(type default)
			)
			(layer "B.SilkS")
		)
		(fp_line
			(start 0.67945 0.3048)
			(end 0.67945 -0.305054)
			(stroke
				(width 0.1)
				(type default)
			)
			(layer "B.Fab")
		)
		(fp_line
			(start 0.67945 -0.305054)
			(end 0.12065 -0.305054)
			(stroke
				(width 0.1)
				(type default)
			)
			(layer "B.Fab")
		)
		(fp_line
			(start 0.12065 0.3048)
			(end 0.67945 0.3048)
			(stroke
				(width 0.1)
				(type default)
			)
			(layer "B.Fab")
		)
		(fp_line
			(start 0.12065 0.2794)
			(end 0.12065 0.3048)
			(stroke
				(width 0.1)
				(type default)
			)
			(layer "B.Fab")
		)
		(fp_line
			(start 0.12065 -0.2794)
			(end -0.12065 -0.2794)
			(stroke
				(width 0.1)
				(type default)
			)
			(layer "B.Fab")
		)
		(fp_line
			(start 0.12065 -0.305054)
			(end 0.12065 -0.2794)
			(stroke
				(width 0.1)
				(type default)
			)
			(layer "B.Fab")
		)
		(fp_line
			(start -0.120396 0.3048)
			(end -0.120396 0.2794)
			(stroke
				(width 0.1)
				(type default)
			)
			(layer "B.Fab")
		)
		(fp_line
			(start -0.120396 0.2794)
			(end 0.12065 0.2794)
			(stroke
				(width 0.1)
				(type default)
			)
			(layer "B.Fab")
		)
		(fp_line
			(start -0.12065 -0.2794)
			(end -0.12065 -0.3048)
			(stroke
				(width 0.1)
				(type default)
			)
			(layer "B.Fab")
		)
		(fp_line
			(start -0.12065 -0.3048)
			(end -0.67945 -0.3048)
			(stroke
				(width 0.1)
				(type default)
			)
			(layer "B.Fab")
		)
		(fp_line
			(start -0.67945 0.3048)
			(end -0.120396 0.3048)
			(stroke
				(width 0.1)
				(type default)
			)
			(layer "B.Fab")
		)
		(fp_line
			(start -0.67945 -0.3048)
			(end -0.67945 0.3048)
			(stroke
				(width 0.1)
				(type default)
			)
			(layer "B.Fab")
		)
		(pad "1" smd circle
			(at 0.40005 0)
			(size 0 0)
			(layers "B.Cu" "B.Mask" "B.Paste")
			(net "NIC5_BIF2_N")
		)
		(pad "2" smd circle
			(at -0.40005 0)
			(size 0 0)
			(layers "B.Cu" "B.Mask" "B.Paste")
			(net "GND")
		)
	)
	(footprint ""
		(layer "B.Cu")
		(at 134.798816 -211.080858 180)
		(property "Reference" "R982"
			(at 0 0 0)
			(layer "B.SilkS")
			(hide yes)
			(effects
				(font
					(size 1.27 1.27)
				)
				(justify mirror)
			)
		)
		(property "Value" ""
			(at 0 0 0)
			(layer "B.Fab")
			(effects
				(font
					(size 1.27 1.27)
				)
				(justify mirror)
			)
		)
		(duplicate_pad_numbers_are_jumpers no)
		(fp_line
			(start 0.7874 0.4064)
			(end 0.7874 -0.4064)
			(stroke
				(width 0.1524)
				(type default)
			)
			(layer "B.SilkS")
		)
		(fp_line
			(start 0.7874 -0.4064)
			(end -0.7874 -0.4064)
			(stroke
				(width 0.1524)
				(type default)
			)
			(layer "B.SilkS")
		)
		(fp_line
			(start -0.7874 0.4064)
			(end 0.7874 0.4064)
			(stroke
				(width 0.1524)
				(type default)
			)
			(layer "B.SilkS")
		)
		(fp_line
			(start -0.7874 -0.4064)
			(end -0.7874 0.4064)
			(stroke
				(width 0.1524)
				(type default)
			)
			(layer "B.SilkS")
		)
		(fp_line
			(start 0.67945 0.3048)
			(end 0.67945 -0.305054)
			(stroke
				(width 0.1)
				(type default)
			)
			(layer "B.Fab")
		)
		(fp_line
			(start 0.67945 -0.305054)
			(end 0.12065 -0.305054)
			(stroke
				(width 0.1)
				(type default)
			)
			(layer "B.Fab")
		)
		(fp_line
			(start 0.12065 0.3048)
			(end 0.67945 0.3048)
			(stroke
				(width 0.1)
				(type default)
			)
			(layer "B.Fab")
		)
		(fp_line
			(start 0.12065 0.2794)
			(end 0.12065 0.3048)
			(stroke
				(width 0.1)
				(type default)
			)
			(layer "B.Fab")
		)
		(fp_line
			(start 0.12065 -0.2794)
			(end -0.12065 -0.2794)
			(stroke
				(width 0.1)
				(type default)
			)
			(layer "B.Fab")
		)
		(fp_line
			(start 0.12065 -0.305054)
			(end 0.12065 -0.2794)
			(stroke
				(width 0.1)
				(type default)
			)
			(layer "B.Fab")
		)
		(fp_line
			(start -0.120396 0.3048)
			(end -0.120396 0.2794)
			(stroke
				(width 0.1)
				(type default)
			)
			(layer "B.Fab")
		)
		(fp_line
			(start -0.120396 0.2794)
			(end 0.12065 0.2794)
			(stroke
				(width 0.1)
				(type default)
			)
			(layer "B.Fab")
		)
		(fp_line
			(start -0.12065 -0.2794)
			(end -0.12065 -0.3048)
			(stroke
				(width 0.1)
				(type default)
			)
			(layer "B.Fab")
		)
		(fp_line
			(start -0.12065 -0.3048)
			(end -0.67945 -0.3048)
			(stroke
				(width 0.1)
				(type default)
			)
			(layer "B.Fab")
		)
		(fp_line
			(start -0.67945 0.3048)
			(end -0.120396 0.3048)
			(stroke
				(width 0.1)
				(type default)
			)
			(layer "B.Fab")
		)
		(fp_line
			(start -0.67945 -0.3048)
			(end -0.67945 0.3048)
			(stroke
				(width 0.1)
				(type default)
			)
			(layer "B.Fab")
		)
		(pad "1" smd circle
			(at 0.40005 0)
			(size 0 0)
			(layers "B.Cu" "B.Mask" "B.Paste")
			(net "UART_PEX0_CLI_BUF_TX")
		)
		(pad "2" smd circle
			(at -0.40005 0)
			(size 0 0)
			(layers "B.Cu" "B.Mask" "B.Paste")
			(net "P3V3_AUX")
		)
	)
	(footprint ""
		(layer "B.Cu")
		(at 301.204122 -117.723666)
		(property "Reference" "C421"
			(at 0 0 0)
			(layer "B.SilkS")
			(hide yes)
			(effects
				(font
					(size 1.27 1.27)
				)
				(justify mirror)
			)
		)
		(property "Value" ""
			(at 0 0 0)
			(layer "B.Fab")
			(effects
				(font
					(size 1.27 1.27)
				)
				(justify mirror)
			)
		)
		(duplicate_pad_numbers_are_jumpers no)
		(fp_line
			(start -0.7874 -0.4064)
			(end -0.7874 0.4064)
			(stroke
				(width 0.1524)
				(type default)
			)
			(layer "B.SilkS")
		)
		(fp_line
			(start -0.7874 0.4064)
			(end 0.7874 0.4064)
			(stroke
				(width 0.1524)
				(type default)
			)
			(layer "B.SilkS")
		)
		(fp_line
			(start 0.7874 -0.4064)
			(end -0.7874 -0.4064)
			(stroke
				(width 0.1524)
				(type default)
			)
			(layer "B.SilkS")
		)
		(fp_line
			(start 0.7874 0.4064)
			(end 0.7874 -0.4064)
			(stroke
				(width 0.1524)
				(type default)
			)
			(layer "B.SilkS")
		)
		(fp_line
			(start -0.67945 -0.3048)
			(end -0.67945 0.3048)
			(stroke
				(width 0.1)
				(type default)
			)
			(layer "B.Fab")
		)
		(fp_line
			(start -0.67945 0.3048)
			(end -0.120396 0.3048)
			(stroke
				(width 0.1)
				(type default)
			)
			(layer "B.Fab")
		)
		(fp_line
			(start -0.12065 -0.3048)
			(end -0.67945 -0.3048)
			(stroke
				(width 0.1)
				(type default)
			)
			(layer "B.Fab")
		)
		(fp_line
			(start -0.12065 -0.2794)
			(end -0.12065 -0.3048)
			(stroke
				(width 0.1)
				(type default)
			)
			(layer "B.Fab")
		)
		(fp_line
			(start -0.120396 0.2794)
			(end 0.12065 0.2794)
			(stroke
				(width 0.1)
				(type default)
			)
			(layer "B.Fab")
		)
		(fp_line
			(start -0.120396 0.3048)
			(end -0.120396 0.2794)
			(stroke
				(width 0.1)
				(type default)
			)
			(layer "B.Fab")
		)
		(fp_line
			(start 0.12065 -0.305054)
			(end 0.12065 -0.2794)
			(stroke
				(width 0.1)
				(type default)
			)
			(layer "B.Fab")
		)
		(fp_line
			(start 0.12065 -0.2794)
			(end -0.12065 -0.2794)
			(stroke
				(width 0.1)
				(type default)
			)
			(layer "B.Fab")
		)
		(fp_line
			(start 0.12065 0.2794)
			(end 0.12065 0.3048)
			(stroke
				(width 0.1)
				(type default)
			)
			(layer "B.Fab")
		)
		(fp_line
			(start 0.12065 0.3048)
			(end 0.67945 0.3048)
			(stroke
				(width 0.1)
				(type default)
			)
			(layer "B.Fab")
		)
		(fp_line
			(start 0.67945 -0.305054)
			(end 0.12065 -0.305054)
			(stroke
				(width 0.1)
				(type default)
			)
			(layer "B.Fab")
		)
		(fp_line
			(start 0.67945 0.3048)
			(end 0.67945 -0.305054)
			(stroke
				(width 0.1)
				(type default)
			)
			(layer "B.Fab")
		)
		(pad "1" smd circle
			(at 0.40005 0 180)
			(size 0 0)
			(layers "B.Cu" "B.Mask" "B.Paste")
			(net "P3V3_AUX")
		)
		(pad "2" smd circle
			(at -0.40005 0 180)
			(size 0 0)
			(layers "B.Cu" "B.Mask" "B.Paste")
			(net "GND")
		)
	)
	(footprint ""
		(layer "B.Cu")
		(at 301.824898 -305.608228 -90)
		(property "Reference" "C3346"
			(at 0 0 90)
			(layer "B.SilkS")
			(hide yes)
			(effects
				(font
					(size 1.27 1.27)
				)
				(justify mirror)
			)
		)
		(property "Value" ""
			(at 0 0 90)
			(layer "B.Fab")
			(effects
				(font
					(size 1.27 1.27)
				)
				(justify mirror)
			)
		)
		(duplicate_pad_numbers_are_jumpers no)
		(fp_line
			(start -0.299974 0.150114)
			(end 0.299974 0.150114)
			(stroke
				(width 0.1)
				(type default)
			)
			(layer "B.Fab")
		)
		(fp_line
			(start 0.299974 0.150114)
			(end 0.299974 -0.150114)
			(stroke
				(width 0.1)
				(type default)
			)
			(layer "B.Fab")
		)
		(fp_line
			(start -0.299974 -0.150114)
			(end -0.299974 0.150114)
			(stroke
				(width 0.1)
				(type default)
			)
			(layer "B.Fab")
		)
		(fp_line
			(start 0.299974 -0.150114)
			(end -0.299974 -0.150114)
			(stroke
				(width 0.1)
				(type default)
			)
			(layer "B.Fab")
		)
		(pad "1" smd rect
			(at 0.2667 0 90)
			(size 0.3048 0.381)
			(layers "B.Cu" "B.Mask" "B.Paste")
			(net "P1V8_VDDA_PEX2")
		)
		(pad "2" smd rect
			(at -0.2667 0 90)
			(size 0.3048 0.381)
			(layers "B.Cu" "B.Mask" "B.Paste")
			(net "GND")
		)
	)
	(footprint ""
		(layer "B.Cu")
		(at 194.601846 -295.422066 180)
		(property "Reference" "C3082"
			(at 0 0 0)
			(layer "B.SilkS")
			(hide yes)
			(effects
				(font
					(size 1.27 1.27)
				)
				(justify mirror)
			)
		)
		(property "Value" ""
			(at 0 0 0)
			(layer "B.Fab")
			(effects
				(font
					(size 1.27 1.27)
				)
				(justify mirror)
			)
		)
		(duplicate_pad_numbers_are_jumpers no)
		(fp_line
			(start 1.2954 0.5842)
			(end 1.2954 -0.5842)
			(stroke
				(width 0.1524)
				(type default)
			)
			(layer "B.SilkS")
		)
		(fp_line
			(start 1.2954 -0.5842)
			(end -1.2954 -0.5842)
			(stroke
				(width 0.1524)
				(type default)
			)
			(layer "B.SilkS")
		)
		(fp_line
			(start -1.2954 0.5842)
			(end 1.2954 0.5842)
			(stroke
				(width 0.1524)
				(type default)
			)
			(layer "B.SilkS")
		)
		(fp_line
			(start -1.2954 -0.5842)
			(end -1.2954 0.5842)
			(stroke
				(width 0.1524)
				(type default)
			)
			(layer "B.SilkS")
		)
		(fp_line
			(start 1.1938 0.4064)
			(end 1.1938 -0.4064)
			(stroke
				(width 0.1)
				(type default)
			)
			(layer "B.Fab")
		)
		(fp_line
			(start 1.1938 -0.4064)
			(end 0.8636 -0.4064)
			(stroke
				(width 0.1)
				(type default)
			)
			(layer "B.Fab")
		)
		(fp_line
			(start 0.8636 0.4572)
			(end 0.8636 0.4064)
			(stroke
				(width 0.1)
				(type default)
			)
			(layer "B.Fab")
		)
		(fp_line
			(start 0.8636 0.4064)
			(end 1.1938 0.4064)
			(stroke
				(width 0.1)
				(type default)
			)
			(layer "B.Fab")
		)
		(fp_line
			(start 0.8636 -0.4064)
			(end 0.8636 -0.4572)
			(stroke
				(width 0.1)
				(type default)
			)
			(layer "B.Fab")
		)
		(fp_line
			(start 0.8636 -0.4572)
			(end -0.8636 -0.4572)
			(stroke
				(width 0.1)
				(type default)
			)
			(layer "B.Fab")
		)
		(fp_line
			(start -0.8636 0.4572)
			(end 0.8636 0.4572)
			(stroke
				(width 0.1)
				(type default)
			)
			(layer "B.Fab")
		)
		(fp_line
			(start -0.8636 0.4064)
			(end -0.8636 0.4572)
			(stroke
				(width 0.1)
				(type default)
			)
			(layer "B.Fab")
		)
		(fp_line
			(start -0.8636 -0.4064)
			(end -1.1938 -0.4064)
			(stroke
				(width 0.1)
				(type default)
			)
			(layer "B.Fab")
		)
		(fp_line
			(start -0.8636 -0.4572)
			(end -0.8636 -0.4064)
			(stroke
				(width 0.1)
				(type default)
			)
			(layer "B.Fab")
		)
		(fp_line
			(start -1.1938 0.4064)
			(end -0.8636 0.4064)
			(stroke
				(width 0.1)
				(type default)
			)
			(layer "B.Fab")
		)
		(fp_line
			(start -1.1938 -0.4064)
			(end -1.1938 0.4064)
			(stroke
				(width 0.1)
				(type default)
			)
			(layer "B.Fab")
		)
		(pad "1" smd rect
			(at 0.7366 0 90)
			(size 0.7112 0.8128)
			(layers "B.Cu" "B.Mask" "B.Paste")
			(net "P1V25_PEX1")
		)
		(pad "2" smd rect
			(at -0.7366 0 90)
			(size 0.7112 0.8128)
			(layers "B.Cu" "B.Mask" "B.Paste")
			(net "GND")
		)
	)
	(footprint ""
		(layer "B.Cu")
		(at 256.351532 -82.140044 180)
		(property "Reference" "C2639"
			(at 0 0 0)
			(layer "B.SilkS")
			(hide yes)
			(effects
				(font
					(size 1.27 1.27)
				)
				(justify mirror)
			)
		)
		(property "Value" ""
			(at 0 0 0)
			(layer "B.Fab")
			(effects
				(font
					(size 1.27 1.27)
				)
				(justify mirror)
			)
		)
		(duplicate_pad_numbers_are_jumpers no)
		(fp_line
			(start 0.7874 0.4064)
			(end 0.7874 -0.4064)
			(stroke
				(width 0.1524)
				(type default)
			)
			(layer "B.SilkS")
		)
		(fp_line
			(start 0.7874 -0.4064)
			(end -0.7874 -0.4064)
			(stroke
				(width 0.1524)
				(type default)
			)
			(layer "B.SilkS")
		)
		(fp_line
			(start -0.7874 0.4064)
			(end 0.7874 0.4064)
			(stroke
				(width 0.1524)
				(type default)
			)
			(layer "B.SilkS")
		)
		(fp_line
			(start -0.7874 -0.4064)
			(end -0.7874 0.4064)
			(stroke
				(width 0.1524)
				(type default)
			)
			(layer "B.SilkS")
		)
		(fp_line
			(start 0.67945 0.3048)
			(end 0.67945 -0.305054)
			(stroke
				(width 0.1)
				(type default)
			)
			(layer "B.Fab")
		)
		(fp_line
			(start 0.67945 -0.305054)
			(end 0.12065 -0.305054)
			(stroke
				(width 0.1)
				(type default)
			)
			(layer "B.Fab")
		)
		(fp_line
			(start 0.12065 0.3048)
			(end 0.67945 0.3048)
			(stroke
				(width 0.1)
				(type default)
			)
			(layer "B.Fab")
		)
		(fp_line
			(start 0.12065 0.2794)
			(end 0.12065 0.3048)
			(stroke
				(width 0.1)
				(type default)
			)
			(layer "B.Fab")
		)
		(fp_line
			(start 0.12065 -0.2794)
			(end -0.12065 -0.2794)
			(stroke
				(width 0.1)
				(type default)
			)
			(layer "B.Fab")
		)
		(fp_line
			(start 0.12065 -0.305054)
			(end 0.12065 -0.2794)
			(stroke
				(width 0.1)
				(type default)
			)
			(layer "B.Fab")
		)
		(fp_line
			(start -0.120396 0.3048)
			(end -0.120396 0.2794)
			(stroke
				(width 0.1)
				(type default)
			)
			(layer "B.Fab")
		)
		(fp_line
			(start -0.120396 0.2794)
			(end 0.12065 0.2794)
			(stroke
				(width 0.1)
				(type default)
			)
			(layer "B.Fab")
		)
		(fp_line
			(start -0.12065 -0.2794)
			(end -0.12065 -0.3048)
			(stroke
				(width 0.1)
				(type default)
			)
			(layer "B.Fab")
		)
		(fp_line
			(start -0.12065 -0.3048)
			(end -0.67945 -0.3048)
			(stroke
				(width 0.1)
				(type default)
			)
			(layer "B.Fab")
		)
		(fp_line
			(start -0.67945 0.3048)
			(end -0.120396 0.3048)
			(stroke
				(width 0.1)
				(type default)
			)
			(layer "B.Fab")
		)
		(fp_line
			(start -0.67945 -0.3048)
			(end -0.67945 0.3048)
			(stroke
				(width 0.1)
				(type default)
			)
			(layer "B.Fab")
		)
		(pad "1" smd circle
			(at 0.40005 0)
			(size 0 0)
			(layers "B.Cu" "B.Mask" "B.Paste")
			(net "P3V3_CLK_GEN_VDDXTAL_CK440")
		)
		(pad "2" smd circle
			(at -0.40005 0)
			(size 0 0)
			(layers "B.Cu" "B.Mask" "B.Paste")
			(net "GND")
		)
	)
	(footprint ""
		(layer "B.Cu")
		(at 416.972242 -113.437924)
		(property "Reference" "R367"
			(at 0 0 0)
			(layer "B.SilkS")
			(hide yes)
			(effects
				(font
					(size 1.27 1.27)
				)
				(justify mirror)
			)
		)
		(property "Value" ""
			(at 0 0 0)
			(layer "B.Fab")
			(effects
				(font
					(size 1.27 1.27)
				)
				(justify mirror)
			)
		)
		(duplicate_pad_numbers_are_jumpers no)
		(fp_line
			(start -0.7874 -0.4064)
			(end -0.7874 0.4064)
			(stroke
				(width 0.1524)
				(type default)
			)
			(layer "B.SilkS")
		)
		(fp_line
			(start -0.7874 0.4064)
			(end 0.7874 0.4064)
			(stroke
				(width 0.1524)
				(type default)
			)
			(layer "B.SilkS")
		)
		(fp_line
			(start 0.7874 -0.4064)
			(end -0.7874 -0.4064)
			(stroke
				(width 0.1524)
				(type default)
			)
			(layer "B.SilkS")
		)
		(fp_line
			(start 0.7874 0.4064)
			(end 0.7874 -0.4064)
			(stroke
				(width 0.1524)
				(type default)
			)
			(layer "B.SilkS")
		)
		(fp_line
			(start -0.67945 -0.3048)
			(end -0.67945 0.3048)
			(stroke
				(width 0.1)
				(type default)
			)
			(layer "B.Fab")
		)
		(fp_line
			(start -0.67945 0.3048)
			(end -0.120396 0.3048)
			(stroke
				(width 0.1)
				(type default)
			)
			(layer "B.Fab")
		)
		(fp_line
			(start -0.12065 -0.3048)
			(end -0.67945 -0.3048)
			(stroke
				(width 0.1)
				(type default)
			)
			(layer "B.Fab")
		)
		(fp_line
			(start -0.12065 -0.2794)
			(end -0.12065 -0.3048)
			(stroke
				(width 0.1)
				(type default)
			)
			(layer "B.Fab")
		)
		(fp_line
			(start -0.120396 0.2794)
			(end 0.12065 0.2794)
			(stroke
				(width 0.1)
				(type default)
			)
			(layer "B.Fab")
		)
		(fp_line
			(start -0.120396 0.3048)
			(end -0.120396 0.2794)
			(stroke
				(width 0.1)
				(type default)
			)
			(layer "B.Fab")
		)
		(fp_line
			(start 0.12065 -0.305054)
			(end 0.12065 -0.2794)
			(stroke
				(width 0.1)
				(type default)
			)
			(layer "B.Fab")
		)
		(fp_line
			(start 0.12065 -0.2794)
			(end -0.12065 -0.2794)
			(stroke
				(width 0.1)
				(type default)
			)
			(layer "B.Fab")
		)
		(fp_line
			(start 0.12065 0.2794)
			(end 0.12065 0.3048)
			(stroke
				(width 0.1)
				(type default)
			)
			(layer "B.Fab")
		)
		(fp_line
			(start 0.12065 0.3048)
			(end 0.67945 0.3048)
			(stroke
				(width 0.1)
				(type default)
			)
			(layer "B.Fab")
		)
		(fp_line
			(start 0.67945 -0.305054)
			(end 0.12065 -0.305054)
			(stroke
				(width 0.1)
				(type default)
			)
			(layer "B.Fab")
		)
		(fp_line
			(start 0.67945 0.3048)
			(end 0.67945 -0.305054)
			(stroke
				(width 0.1)
				(type default)
			)
			(layer "B.Fab")
		)
		(pad "1" smd circle
			(at 0.40005 0 180)
			(size 0 0)
			(layers "B.Cu" "B.Mask" "B.Paste")
			(net "P3V3_NIC7")
		)
		(pad "2" smd circle
			(at -0.40005 0 180)
			(size 0 0)
			(layers "B.Cu" "B.Mask" "B.Paste")
			(net "SMB_NIC7_LS_SDA")
		)
	)
	(footprint ""
		(layer "B.Cu")
		(at 456.818238 -266.996672 180)
		(property "Reference" "R6139"
			(at 0 0 0)
			(layer "B.SilkS")
			(hide yes)
			(effects
				(font
					(size 1.27 1.27)
				)
				(justify mirror)
			)
		)
		(property "Value" ""
			(at 0 0 0)
			(layer "B.Fab")
			(effects
				(font
					(size 1.27 1.27)
				)
				(justify mirror)
			)
		)
		(duplicate_pad_numbers_are_jumpers no)
		(fp_line
			(start 2.576322 1.1303)
			(end 2.576322 -1.1303)
			(stroke
				(width 0.1524)
				(type default)
			)
			(layer "B.SilkS")
		)
		(fp_line
			(start 2.576322 -1.1303)
			(end -2.576322 -1.1303)
			(stroke
				(width 0.1524)
				(type default)
			)
			(layer "B.SilkS")
		)
		(fp_line
			(start -2.576322 1.1303)
			(end 2.576322 1.1303)
			(stroke
				(width 0.1524)
				(type default)
			)
			(layer "B.SilkS")
		)
		(fp_line
			(start -2.576322 -1.1303)
			(end -2.576322 1.1303)
			(stroke
				(width 0.1524)
				(type default)
			)
			(layer "B.SilkS")
		)
		(fp_line
			(start 1.649984 0.899922)
			(end -1.649984 0.899922)
			(stroke
				(width 0.1)
				(type default)
			)
			(layer "B.Fab")
		)
		(fp_line
			(start 1.649984 -0.899922)
			(end 1.649984 0.899922)
			(stroke
				(width 0.1)
				(type default)
			)
			(layer "B.Fab")
		)
		(fp_line
			(start -1.649984 0.899922)
			(end -1.649984 -0.899922)
			(stroke
				(width 0.1)
				(type default)
			)
			(layer "B.Fab")
		)
		(fp_line
			(start -1.649984 -0.899922)
			(end 1.649984 -0.899922)
			(stroke
				(width 0.1)
				(type default)
			)
			(layer "B.Fab")
		)
		(pad "1A" smd rect
			(at 1.700022 0)
			(size 1.4986 2.0066)
			(layers "B.Cu" "B.Mask" "B.Paste")
			(net "P1V25_PEX3")
		)
		(pad "1B" smd rect
			(at 1.077722 0)
			(size 0.254 0.508)
			(layers "B.Cu" "B.Mask" "B.Paste")
			(net "P1V25_PEX3")
		)
		(pad "2A" smd rect
			(at -1.700022 0)
			(size 1.4986 2.0066)
			(layers "B.Cu" "B.Mask" "B.Paste")
			(net "P1V25_SERDES_VDDPLL_PEX3")
		)
		(pad "2B" smd rect
			(at -1.077722 0)
			(size 0.254 0.508)
			(layers "B.Cu" "B.Mask" "B.Paste")
			(net "P1V25_SERDES_VDDPLL_PEX3")
		)
	)
	(footprint ""
		(layer "B.Cu")
		(at 335.298288 -325.895208 -90)
		(property "Reference" "C4310"
			(at 0 0 90)
			(layer "B.SilkS")
			(hide yes)
			(effects
				(font
					(size 1.27 1.27)
				)
				(justify mirror)
			)
		)
		(property "Value" ""
			(at 0 0 90)
			(layer "B.Fab")
			(effects
				(font
					(size 1.27 1.27)
				)
				(justify mirror)
			)
		)
		(duplicate_pad_numbers_are_jumpers no)
		(fp_line
			(start -1.2954 0.5842)
			(end 1.2954 0.5842)
			(stroke
				(width 0.1524)
				(type default)
			)
			(layer "B.SilkS")
		)
		(fp_line
			(start 1.2954 0.5842)
			(end 1.2954 -0.5842)
			(stroke
				(width 0.1524)
				(type default)
			)
			(layer "B.SilkS")
		)
		(fp_line
			(start -1.2954 -0.5842)
			(end -1.2954 0.5842)
			(stroke
				(width 0.1524)
				(type default)
			)
			(layer "B.SilkS")
		)
		(fp_line
			(start 1.2954 -0.5842)
			(end -1.2954 -0.5842)
			(stroke
				(width 0.1524)
				(type default)
			)
			(layer "B.SilkS")
		)
		(fp_line
			(start -0.8636 0.4572)
			(end 0.8636 0.4572)
			(stroke
				(width 0.1)
				(type default)
			)
			(layer "B.Fab")
		)
		(fp_line
			(start 0.8636 0.4572)
			(end 0.8636 0.4064)
			(stroke
				(width 0.1)
				(type default)
			)
			(layer "B.Fab")
		)
		(fp_line
			(start -1.1938 0.4064)
			(end -0.8636 0.4064)
			(stroke
				(width 0.1)
				(type default)
			)
			(layer "B.Fab")
		)
		(fp_line
			(start -0.8636 0.4064)
			(end -0.8636 0.4572)
			(stroke
				(width 0.1)
				(type default)
			)
			(layer "B.Fab")
		)
		(fp_line
			(start 0.8636 0.4064)
			(end 1.1938 0.4064)
			(stroke
				(width 0.1)
				(type default)
			)
			(layer "B.Fab")
		)
		(fp_line
			(start 1.1938 0.4064)
			(end 1.1938 -0.4064)
			(stroke
				(width 0.1)
				(type default)
			)
			(layer "B.Fab")
		)
		(fp_line
			(start -1.1938 -0.4064)
			(end -1.1938 0.4064)
			(stroke
				(width 0.1)
				(type default)
			)
			(layer "B.Fab")
		)
		(fp_line
			(start -0.8636 -0.4064)
			(end -1.1938 -0.4064)
			(stroke
				(width 0.1)
				(type default)
			)
			(layer "B.Fab")
		)
		(fp_line
			(start 0.8636 -0.4064)
			(end 0.8636 -0.4572)
			(stroke
				(width 0.1)
				(type default)
			)
			(layer "B.Fab")
		)
		(fp_line
			(start 1.1938 -0.4064)
			(end 0.8636 -0.4064)
			(stroke
				(width 0.1)
				(type default)
			)
			(layer "B.Fab")
		)
		(fp_line
			(start -0.8636 -0.4572)
			(end -0.8636 -0.4064)
			(stroke
				(width 0.1)
				(type default)
			)
			(layer "B.Fab")
		)
		(fp_line
			(start 0.8636 -0.4572)
			(end -0.8636 -0.4572)
			(stroke
				(width 0.1)
				(type default)
			)
			(layer "B.Fab")
		)
		(pad "1" smd rect
			(at 0.7366 0 180)
			(size 0.7112 0.8128)
			(layers "B.Cu" "B.Mask" "B.Paste")
			(net "P0V8_SERDES_VDDA_PEX2_C0")
		)
		(pad "2" smd rect
			(at -0.7366 0 180)
			(size 0.7112 0.8128)
			(layers "B.Cu" "B.Mask" "B.Paste")
			(net "GND")
		)
	)
	(footprint ""
		(layer "B.Cu")
		(at 183.82488 -286.399732 90)
		(property "Reference" "C3126"
			(at 0 0 90)
			(layer "B.SilkS")
			(hide yes)
			(effects
				(font
					(size 1.27 1.27)
				)
				(justify mirror)
			)
		)
		(property "Value" ""
			(at 0 0 90)
			(layer "B.Fab")
			(effects
				(font
					(size 1.27 1.27)
				)
				(justify mirror)
			)
		)
		(duplicate_pad_numbers_are_jumpers no)
		(fp_line
			(start 0.299974 -0.150114)
			(end -0.299974 -0.150114)
			(stroke
				(width 0.1)
				(type default)
			)
			(layer "B.Fab")
		)
		(fp_line
			(start -0.299974 -0.150114)
			(end -0.299974 0.150114)
			(stroke
				(width 0.1)
				(type default)
			)
			(layer "B.Fab")
		)
		(fp_line
			(start 0.299974 0.150114)
			(end 0.299974 -0.150114)
			(stroke
				(width 0.1)
				(type default)
			)
			(layer "B.Fab")
		)
		(fp_line
			(start -0.299974 0.150114)
			(end 0.299974 0.150114)
			(stroke
				(width 0.1)
				(type default)
			)
			(layer "B.Fab")
		)
		(pad "1" smd rect
			(at 0.2667 0 270)
			(size 0.3048 0.381)
			(layers "B.Cu" "B.Mask" "B.Paste")
			(net "P1V25_SERDES_VDDPLL_PEX1")
		)
		(pad "2" smd rect
			(at -0.2667 0 270)
			(size 0.3048 0.381)
			(layers "B.Cu" "B.Mask" "B.Paste")
			(net "GND")
		)
	)
	(footprint ""
		(layer "B.Cu")
		(at 107.573318 -349.904558 90)
		(property "Reference" "C4184"
			(at 0 0 90)
			(layer "B.SilkS")
			(hide yes)
			(effects
				(font
					(size 1.27 1.27)
				)
				(justify mirror)
			)
		)
		(property "Value" ""
			(at 0 0 90)
			(layer "B.Fab")
			(effects
				(font
					(size 1.27 1.27)
				)
				(justify mirror)
			)
		)
		(duplicate_pad_numbers_are_jumpers no)
		(fp_line
			(start 0.7874 -0.4064)
			(end -0.7874 -0.4064)
			(stroke
				(width 0.1524)
				(type default)
			)
			(layer "B.SilkS")
		)
		(fp_line
			(start -0.7874 -0.4064)
			(end -0.7874 0.4064)
			(stroke
				(width 0.1524)
				(type default)
			)
			(layer "B.SilkS")
		)
		(fp_line
			(start 0.7874 0.4064)
			(end 0.7874 -0.4064)
			(stroke
				(width 0.1524)
				(type default)
			)
			(layer "B.SilkS")
		)
		(fp_line
			(start -0.7874 0.4064)
			(end 0.7874 0.4064)
			(stroke
				(width 0.1524)
				(type default)
			)
			(layer "B.SilkS")
		)
		(fp_line
			(start 0.67945 -0.305054)
			(end 0.12065 -0.305054)
			(stroke
				(width 0.1)
				(type default)
			)
			(layer "B.Fab")
		)
		(fp_line
			(start 0.12065 -0.305054)
			(end 0.12065 -0.2794)
			(stroke
				(width 0.1)
				(type default)
			)
			(layer "B.Fab")
		)
		(fp_line
			(start -0.12065 -0.3048)
			(end -0.67945 -0.3048)
			(stroke
				(width 0.1)
				(type default)
			)
			(layer "B.Fab")
		)
		(fp_line
			(start -0.67945 -0.3048)
			(end -0.67945 0.3048)
			(stroke
				(width 0.1)
				(type default)
			)
			(layer "B.Fab")
		)
		(fp_line
			(start 0.12065 -0.2794)
			(end -0.12065 -0.2794)
			(stroke
				(width 0.1)
				(type default)
			)
			(layer "B.Fab")
		)
		(fp_line
			(start -0.12065 -0.2794)
			(end -0.12065 -0.3048)
			(stroke
				(width 0.1)
				(type default)
			)
			(layer "B.Fab")
		)
		(fp_line
			(start 0.12065 0.2794)
			(end 0.12065 0.3048)
			(stroke
				(width 0.1)
				(type default)
			)
			(layer "B.Fab")
		)
		(fp_line
			(start -0.120396 0.2794)
			(end 0.12065 0.2794)
			(stroke
				(width 0.1)
				(type default)
			)
			(layer "B.Fab")
		)
		(fp_line
			(start 0.67945 0.3048)
			(end 0.67945 -0.305054)
			(stroke
				(width 0.1)
				(type default)
			)
			(layer "B.Fab")
		)
		(fp_line
			(start 0.12065 0.3048)
			(end 0.67945 0.3048)
			(stroke
				(width 0.1)
				(type default)
			)
			(layer "B.Fab")
		)
		(fp_line
			(start -0.120396 0.3048)
			(end -0.120396 0.2794)
			(stroke
				(width 0.1)
				(type default)
			)
			(layer "B.Fab")
		)
		(fp_line
			(start -0.67945 0.3048)
			(end -0.120396 0.3048)
			(stroke
				(width 0.1)
				(type default)
			)
			(layer "B.Fab")
		)
		(pad "1" smd circle
			(at 0.40005 0 270)
			(size 0 0)
			(layers "B.Cu" "B.Mask" "B.Paste")
			(net "P3V3_CLK_BUFFER_9ZXL0451E_S3_VZX3P3A")
		)
		(pad "2" smd circle
			(at -0.40005 0 270)
			(size 0 0)
			(layers "B.Cu" "B.Mask" "B.Paste")
			(net "GND")
		)
	)
	(footprint ""
		(layer "B.Cu")
		(at 299.449744 -301.599854 -90)
		(property "Reference" "C1703"
			(at 0 0 90)
			(layer "B.SilkS")
			(hide yes)
			(effects
				(font
					(size 1.27 1.27)
				)
				(justify mirror)
			)
		)
		(property "Value" ""
			(at 0 0 90)
			(layer "B.Fab")
			(effects
				(font
					(size 1.27 1.27)
				)
				(justify mirror)
			)
		)
		(duplicate_pad_numbers_are_jumpers no)
		(fp_line
			(start -0.299974 0.150114)
			(end 0.299974 0.150114)
			(stroke
				(width 0.1)
				(type default)
			)
			(layer "B.Fab")
		)
		(fp_line
			(start 0.299974 0.150114)
			(end 0.299974 -0.150114)
			(stroke
				(width 0.1)
				(type default)
			)
			(layer "B.Fab")
		)
		(fp_line
			(start -0.299974 -0.150114)
			(end -0.299974 0.150114)
			(stroke
				(width 0.1)
				(type default)
			)
			(layer "B.Fab")
		)
		(fp_line
			(start 0.299974 -0.150114)
			(end -0.299974 -0.150114)
			(stroke
				(width 0.1)
				(type default)
			)
			(layer "B.Fab")
		)
		(pad "1" smd rect
			(at 0.2667 0 90)
			(size 0.3048 0.381)
			(layers "B.Cu" "B.Mask" "B.Paste")
			(net "P0V8_SERDES_VDDA_PEX2")
		)
		(pad "2" smd rect
			(at -0.2667 0 90)
			(size 0.3048 0.381)
			(layers "B.Cu" "B.Mask" "B.Paste")
			(net "GND")
		)
	)
	(footprint ""
		(layer "B.Cu")
		(at 106.964734 -237.306612 -90)
		(property "Reference" "PC1002"
			(at 0 0 90)
			(layer "B.SilkS")
			(hide yes)
			(effects
				(font
					(size 1.27 1.27)
				)
				(justify mirror)
			)
		)
		(property "Value" ""
			(at 0 0 90)
			(layer "B.Fab")
			(effects
				(font
					(size 1.27 1.27)
				)
				(justify mirror)
			)
		)
		(duplicate_pad_numbers_are_jumpers no)
		(fp_line
			(start -1.524 0.762)
			(end 1.524 0.762)
			(stroke
				(width 0.1524)
				(type default)
			)
			(layer "B.SilkS")
		)
		(fp_line
			(start 1.524 0.762)
			(end 1.524 -0.762)
			(stroke
				(width 0.1524)
				(type default)
			)
			(layer "B.SilkS")
		)
		(fp_line
			(start -1.524 -0.762)
			(end -1.524 0.762)
			(stroke
				(width 0.1524)
				(type default)
			)
			(layer "B.SilkS")
		)
		(fp_line
			(start 1.524 -0.762)
			(end -1.524 -0.762)
			(stroke
				(width 0.1524)
				(type default)
			)
			(layer "B.SilkS")
		)
		(fp_line
			(start -1.1049 0.724916)
			(end -1.1049 -0.724916)
			(stroke
				(width 0.1)
				(type default)
			)
			(layer "B.Fab")
		)
		(fp_line
			(start 1.1049 0.724916)
			(end -1.1049 0.724916)
			(stroke
				(width 0.1)
				(type default)
			)
			(layer "B.Fab")
		)
		(fp_line
			(start -1.1049 -0.724916)
			(end 1.1049 -0.724916)
			(stroke
				(width 0.1)
				(type default)
			)
			(layer "B.Fab")
		)
		(fp_line
			(start 1.1049 -0.724916)
			(end 1.1049 0.724916)
			(stroke
				(width 0.1)
				(type default)
			)
			(layer "B.Fab")
		)
		(pad "1" smd rect
			(at 0.889 0 270)
			(size 1.016 1.27)
			(layers "B.Cu" "B.Mask" "B.Paste")
			(net "P1V8_PEX_R")
		)
		(pad "2" smd rect
			(at -0.889 0 270)
			(size 1.016 1.27)
			(layers "B.Cu" "B.Mask" "B.Paste")
			(net "GND")
		)
	)
	(footprint ""
		(layer "B.Cu")
		(at 351.645982 -142.494)
		(property "Reference" "R4804"
			(at 0 0 0)
			(layer "B.SilkS")
			(hide yes)
			(effects
				(font
					(size 1.27 1.27)
				)
				(justify mirror)
			)
		)
		(property "Value" ""
			(at 0 0 0)
			(layer "B.Fab")
			(effects
				(font
					(size 1.27 1.27)
				)
				(justify mirror)
			)
		)
		(duplicate_pad_numbers_are_jumpers no)
		(fp_line
			(start -0.7874 -0.4064)
			(end -0.7874 0.4064)
			(stroke
				(width 0.1524)
				(type default)
			)
			(layer "B.SilkS")
		)
		(fp_line
			(start -0.7874 0.4064)
			(end 0.7874 0.4064)
			(stroke
				(width 0.1524)
				(type default)
			)
			(layer "B.SilkS")
		)
		(fp_line
			(start 0.7874 -0.4064)
			(end -0.7874 -0.4064)
			(stroke
				(width 0.1524)
				(type default)
			)
			(layer "B.SilkS")
		)
		(fp_line
			(start 0.7874 0.4064)
			(end 0.7874 -0.4064)
			(stroke
				(width 0.1524)
				(type default)
			)
			(layer "B.SilkS")
		)
		(fp_line
			(start -0.67945 -0.3048)
			(end -0.67945 0.3048)
			(stroke
				(width 0.1)
				(type default)
			)
			(layer "B.Fab")
		)
		(fp_line
			(start -0.67945 0.3048)
			(end -0.120396 0.3048)
			(stroke
				(width 0.1)
				(type default)
			)
			(layer "B.Fab")
		)
		(fp_line
			(start -0.12065 -0.3048)
			(end -0.67945 -0.3048)
			(stroke
				(width 0.1)
				(type default)
			)
			(layer "B.Fab")
		)
		(fp_line
			(start -0.12065 -0.2794)
			(end -0.12065 -0.3048)
			(stroke
				(width 0.1)
				(type default)
			)
			(layer "B.Fab")
		)
		(fp_line
			(start -0.120396 0.2794)
			(end 0.12065 0.2794)
			(stroke
				(width 0.1)
				(type default)
			)
			(layer "B.Fab")
		)
		(fp_line
			(start -0.120396 0.3048)
			(end -0.120396 0.2794)
			(stroke
				(width 0.1)
				(type default)
			)
			(layer "B.Fab")
		)
		(fp_line
			(start 0.12065 -0.305054)
			(end 0.12065 -0.2794)
			(stroke
				(width 0.1)
				(type default)
			)
			(layer "B.Fab")
		)
		(fp_line
			(start 0.12065 -0.2794)
			(end -0.12065 -0.2794)
			(stroke
				(width 0.1)
				(type default)
			)
			(layer "B.Fab")
		)
		(fp_line
			(start 0.12065 0.2794)
			(end 0.12065 0.3048)
			(stroke
				(width 0.1)
				(type default)
			)
			(layer "B.Fab")
		)
		(fp_line
			(start 0.12065 0.3048)
			(end 0.67945 0.3048)
			(stroke
				(width 0.1)
				(type default)
			)
			(layer "B.Fab")
		)
		(fp_line
			(start 0.67945 -0.305054)
			(end 0.12065 -0.305054)
			(stroke
				(width 0.1)
				(type default)
			)
			(layer "B.Fab")
		)
		(fp_line
			(start 0.67945 0.3048)
			(end 0.67945 -0.305054)
			(stroke
				(width 0.1)
				(type default)
			)
			(layer "B.Fab")
		)
		(pad "1" smd circle
			(at 0.40005 0 180)
			(size 0 0)
			(layers "B.Cu" "B.Mask" "B.Paste")
			(net "NIC7_PEX_PWR_EN_R")
		)
		(pad "2" smd circle
			(at -0.40005 0 180)
			(size 0 0)
			(layers "B.Cu" "B.Mask" "B.Paste")
			(net "GND")
		)
	)
	(footprint ""
		(layer "B.Cu")
		(at 252.0188 -351.8408 180)
		(property "Reference" "PR7163"
			(at 0 0 0)
			(layer "B.SilkS")
			(hide yes)
			(effects
				(font
					(size 1.27 1.27)
				)
				(justify mirror)
			)
		)
		(property "Value" ""
			(at 0 0 0)
			(layer "B.Fab")
			(effects
				(font
					(size 1.27 1.27)
				)
				(justify mirror)
			)
		)
		(duplicate_pad_numbers_are_jumpers no)
		(fp_line
			(start 0.7874 0.4064)
			(end 0.7874 -0.4064)
			(stroke
				(width 0.1524)
				(type default)
			)
			(layer "B.SilkS")
		)
		(fp_line
			(start 0.7874 -0.4064)
			(end -0.7874 -0.4064)
			(stroke
				(width 0.1524)
				(type default)
			)
			(layer "B.SilkS")
		)
		(fp_line
			(start -0.7874 0.4064)
			(end 0.7874 0.4064)
			(stroke
				(width 0.1524)
				(type default)
			)
			(layer "B.SilkS")
		)
		(fp_line
			(start -0.7874 -0.4064)
			(end -0.7874 0.4064)
			(stroke
				(width 0.1524)
				(type default)
			)
			(layer "B.SilkS")
		)
		(fp_line
			(start 0.67945 0.3048)
			(end 0.67945 -0.305054)
			(stroke
				(width 0.1)
				(type default)
			)
			(layer "B.Fab")
		)
		(fp_line
			(start 0.67945 -0.305054)
			(end 0.12065 -0.305054)
			(stroke
				(width 0.1)
				(type default)
			)
			(layer "B.Fab")
		)
		(fp_line
			(start 0.12065 0.3048)
			(end 0.67945 0.3048)
			(stroke
				(width 0.1)
				(type default)
			)
			(layer "B.Fab")
		)
		(fp_line
			(start 0.12065 0.2794)
			(end 0.12065 0.3048)
			(stroke
				(width 0.1)
				(type default)
			)
			(layer "B.Fab")
		)
		(fp_line
			(start 0.12065 -0.2794)
			(end -0.12065 -0.2794)
			(stroke
				(width 0.1)
				(type default)
			)
			(layer "B.Fab")
		)
		(fp_line
			(start 0.12065 -0.305054)
			(end 0.12065 -0.2794)
			(stroke
				(width 0.1)
				(type default)
			)
			(layer "B.Fab")
		)
		(fp_line
			(start -0.120396 0.3048)
			(end -0.120396 0.2794)
			(stroke
				(width 0.1)
				(type default)
			)
			(layer "B.Fab")
		)
		(fp_line
			(start -0.120396 0.2794)
			(end 0.12065 0.2794)
			(stroke
				(width 0.1)
				(type default)
			)
			(layer "B.Fab")
		)
		(fp_line
			(start -0.12065 -0.2794)
			(end -0.12065 -0.3048)
			(stroke
				(width 0.1)
				(type default)
			)
			(layer "B.Fab")
		)
		(fp_line
			(start -0.12065 -0.3048)
			(end -0.67945 -0.3048)
			(stroke
				(width 0.1)
				(type default)
			)
			(layer "B.Fab")
		)
		(fp_line
			(start -0.67945 0.3048)
			(end -0.120396 0.3048)
			(stroke
				(width 0.1)
				(type default)
			)
			(layer "B.Fab")
		)
		(fp_line
			(start -0.67945 -0.3048)
			(end -0.67945 0.3048)
			(stroke
				(width 0.1)
				(type default)
			)
			(layer "B.Fab")
		)
		(pad "1" smd circle
			(at 0.40005 0)
			(size 0 0)
			(layers "B.Cu" "B.Mask" "B.Paste")
			(net "MB0_P12V_STBY_PWRGD")
		)
		(pad "2" smd circle
			(at -0.40005 0)
			(size 0 0)
			(layers "B.Cu" "B.Mask" "B.Paste")
			(net "PWRGD_P12V_AUX_R")
		)
	)
	(footprint ""
		(layer "B.Cu")
		(at 45.864272 -146.148552 180)
		(property "Reference" "C851"
			(at 0 0 0)
			(layer "B.SilkS")
			(hide yes)
			(effects
				(font
					(size 1.27 1.27)
				)
				(justify mirror)
			)
		)
		(property "Value" ""
			(at 0 0 0)
			(layer "B.Fab")
			(effects
				(font
					(size 1.27 1.27)
				)
				(justify mirror)
			)
		)
		(duplicate_pad_numbers_are_jumpers no)
		(fp_line
			(start 0.299974 0.150114)
			(end 0.299974 -0.150114)
			(stroke
				(width 0.1)
				(type default)
			)
			(layer "B.Fab")
		)
		(fp_line
			(start 0.299974 -0.150114)
			(end -0.299974 -0.150114)
			(stroke
				(width 0.1)
				(type default)
			)
			(layer "B.Fab")
		)
		(fp_line
			(start -0.299974 0.150114)
			(end 0.299974 0.150114)
			(stroke
				(width 0.1)
				(type default)
			)
			(layer "B.Fab")
		)
		(fp_line
			(start -0.299974 -0.150114)
			(end -0.299974 0.150114)
			(stroke
				(width 0.1)
				(type default)
			)
			(layer "B.Fab")
		)
		(pad "1" smd rect
			(at 0.2667 0)
			(size 0.3048 0.381)
			(layers "B.Cu" "B.Mask" "B.Paste")
			(net "P12V_NIC0")
		)
		(pad "2" smd rect
			(at -0.2667 0)
			(size 0.3048 0.381)
			(layers "B.Cu" "B.Mask" "B.Paste")
			(net "GND")
		)
	)
	(footprint ""
		(layer "B.Cu")
		(at 100.12045 -356.333806 -90)
		(property "Reference" "C4176"
			(at 0 0 90)
			(layer "B.SilkS")
			(hide yes)
			(effects
				(font
					(size 1.27 1.27)
				)
				(justify mirror)
			)
		)
		(property "Value" ""
			(at 0 0 90)
			(layer "B.Fab")
			(effects
				(font
					(size 1.27 1.27)
				)
				(justify mirror)
			)
		)
		(duplicate_pad_numbers_are_jumpers no)
		(fp_line
			(start -1.524 0.762)
			(end 1.524 0.762)
			(stroke
				(width 0.1524)
				(type default)
			)
			(layer "B.SilkS")
		)
		(fp_line
			(start 1.524 0.762)
			(end 1.524 -0.762)
			(stroke
				(width 0.1524)
				(type default)
			)
			(layer "B.SilkS")
		)
		(fp_line
			(start -1.524 -0.762)
			(end -1.524 0.762)
			(stroke
				(width 0.1524)
				(type default)
			)
			(layer "B.SilkS")
		)
		(fp_line
			(start 1.524 -0.762)
			(end -1.524 -0.762)
			(stroke
				(width 0.1524)
				(type default)
			)
			(layer "B.SilkS")
		)
		(fp_line
			(start -1.1049 0.724916)
			(end -1.1049 -0.724916)
			(stroke
				(width 0.1)
				(type default)
			)
			(layer "B.Fab")
		)
		(fp_line
			(start 1.1049 0.724916)
			(end -1.1049 0.724916)
			(stroke
				(width 0.1)
				(type default)
			)
			(layer "B.Fab")
		)
		(fp_line
			(start -1.1049 -0.724916)
			(end 1.1049 -0.724916)
			(stroke
				(width 0.1)
				(type default)
			)
			(layer "B.Fab")
		)
		(fp_line
			(start 1.1049 -0.724916)
			(end 1.1049 0.724916)
			(stroke
				(width 0.1)
				(type default)
			)
			(layer "B.Fab")
		)
		(pad "1" smd rect
			(at 0.889 0 270)
			(size 1.016 1.27)
			(layers "B.Cu" "B.Mask" "B.Paste")
			(net "P3V3_CLK_BUFFER_9ZXL0451E_S3_VZX3P3")
		)
		(pad "2" smd rect
			(at -0.889 0 270)
			(size 1.016 1.27)
			(layers "B.Cu" "B.Mask" "B.Paste")
			(net "GND")
		)
	)
	(footprint ""
		(layer "B.Cu")
		(at 148.209254 -203.466192 -90)
		(property "Reference" "U104"
			(at 0.08763 1.838706 270)
			(unlocked yes)
			(layer "B.SilkS")
			(effects
				(font
					(size 0.7874 0.5842)
					(thickness 0.1524)
				)
				(justify mirror)
			)
		)
		(property "Value" ""
			(at 0 0 90)
			(layer "B.Fab")
			(effects
				(font
					(size 1.27 1.27)
				)
				(justify mirror)
			)
		)
		(duplicate_pad_numbers_are_jumpers no)
		(fp_line
			(start -1.7272 1.1176)
			(end 1.7272 1.1176)
			(stroke
				(width 0.1524)
				(type default)
			)
			(layer "B.SilkS")
		)
		(fp_line
			(start 1.7272 1.1176)
			(end 1.7272 -1.1176)
			(stroke
				(width 0.1524)
				(type default)
			)
			(layer "B.SilkS")
		)
		(fp_line
			(start 0 -0.7366)
			(end 0.254 -1.1176)
			(stroke
				(width 0.1524)
				(type default)
			)
			(layer "B.SilkS")
		)
		(fp_line
			(start -1.7272 -1.1176)
			(end -1.7272 1.1176)
			(stroke
				(width 0.1524)
				(type default)
			)
			(layer "B.SilkS")
		)
		(fp_line
			(start -1.7272 -1.1176)
			(end -0.254 -1.1176)
			(stroke
				(width 0.1524)
				(type default)
			)
			(layer "B.SilkS")
		)
		(fp_line
			(start -0.254 -1.1176)
			(end 0 -0.7366)
			(stroke
				(width 0.1524)
				(type default)
			)
			(layer "B.SilkS")
		)
		(fp_line
			(start 0.254 -1.1176)
			(end 1.7272 -1.1176)
			(stroke
				(width 0.1524)
				(type default)
			)
			(layer "B.SilkS")
		)
		(fp_poly
			(pts
				(xy 1.9558 -0.649986) (xy 2.7178 -0.268986) (xy 2.7178 -1.030986)
			)
			(stroke
				(width 0)
				(type default)
			)
			(fill yes)
			(layer "B.SilkS")
		)
		(fp_line
			(start -1.5748 1.1176)
			(end -1.5748 -1.1176)
			(stroke
				(width 0.1)
				(type default)
			)
			(layer "B.Fab")
		)
		(fp_line
			(start 1.5748 1.1176)
			(end -1.5748 1.1176)
			(stroke
				(width 0.1)
				(type default)
			)
			(layer "B.Fab")
		)
		(fp_line
			(start -1.5748 -1.1176)
			(end 1.5748 -1.1176)
			(stroke
				(width 0.1)
				(type default)
			)
			(layer "B.Fab")
		)
		(fp_line
			(start 1.5748 -1.1176)
			(end 1.5748 1.1176)
			(stroke
				(width 0.1)
				(type default)
			)
			(layer "B.Fab")
		)
		(fp_poly
			(pts
				(xy 1.9558 -0.649986) (xy 2.7178 -0.268986) (xy 2.7178 -1.030986)
			)
			(stroke
				(width 0)
				(type default)
			)
			(fill yes)
			(layer "B.Fab")
		)
		(pad "1" smd rect
			(at 0.999998 -0.649986 180)
			(size 0.3556 1.1176)
			(layers "B.Cu" "B.Mask" "B.Paste")
			(net "UART_PEX0_CLI_R_RX")
		)
		(pad "2" smd rect
			(at 0.999998 0 180)
			(size 0.3556 1.1176)
			(layers "B.Cu" "B.Mask" "B.Paste")
			(net "GND")
		)
		(pad "3" smd rect
			(at 0.999998 0.649986 180)
			(size 0.3556 1.1176)
			(layers "B.Cu" "B.Mask" "B.Paste")
			(net "UART_PEX1_CLI_R_RX")
		)
		(pad "4" smd rect
			(at -0.999998 0.649986 180)
			(size 0.3556 1.1176)
			(layers "B.Cu" "B.Mask" "B.Paste")
			(net "UART_PEX1_CLI_BUF_R_RX")
		)
		(pad "5" smd rect
			(at -0.999998 0 180)
			(size 0.3556 1.1176)
			(layers "B.Cu" "B.Mask" "B.Paste")
			(net "P3V3_AUX")
		)
		(pad "6" smd rect
			(at -0.999998 -0.649986 180)
			(size 0.3556 1.1176)
			(layers "B.Cu" "B.Mask" "B.Paste")
			(net "UART_PEX0_CLI_BUF_R_RX")
		)
	)
	(footprint ""
		(layer "B.Cu")
		(at 332.940914 -323.76745 -90)
		(property "Reference" "C4308"
			(at 0 0 90)
			(layer "B.SilkS")
			(hide yes)
			(effects
				(font
					(size 1.27 1.27)
				)
				(justify mirror)
			)
		)
		(property "Value" ""
			(at 0 0 90)
			(layer "B.Fab")
			(effects
				(font
					(size 1.27 1.27)
				)
				(justify mirror)
			)
		)
		(duplicate_pad_numbers_are_jumpers no)
		(fp_line
			(start -0.299974 0.150114)
			(end 0.299974 0.150114)
			(stroke
				(width 0.1)
				(type default)
			)
			(layer "B.Fab")
		)
		(fp_line
			(start 0.299974 0.150114)
			(end 0.299974 -0.150114)
			(stroke
				(width 0.1)
				(type default)
			)
			(layer "B.Fab")
		)
		(fp_line
			(start -0.299974 -0.150114)
			(end -0.299974 0.150114)
			(stroke
				(width 0.1)
				(type default)
			)
			(layer "B.Fab")
		)
		(fp_line
			(start 0.299974 -0.150114)
			(end -0.299974 -0.150114)
			(stroke
				(width 0.1)
				(type default)
			)
			(layer "B.Fab")
		)
		(pad "1" smd rect
			(at 0.2667 0 90)
			(size 0.3048 0.381)
			(layers "B.Cu" "B.Mask" "B.Paste")
			(net "P0V8_SERDES_VDDA_PEX2")
		)
		(pad "2" smd rect
			(at -0.2667 0 90)
			(size 0.3048 0.381)
			(layers "B.Cu" "B.Mask" "B.Paste")
			(net "GND")
		)
	)
	(footprint ""
		(layer "B.Cu")
		(at 265.53668 -85.713316 180)
		(property "Reference" "C2649"
			(at 0 0 0)
			(layer "B.SilkS")
			(hide yes)
			(effects
				(font
					(size 1.27 1.27)
				)
				(justify mirror)
			)
		)
		(property "Value" ""
			(at 0 0 0)
			(layer "B.Fab")
			(effects
				(font
					(size 1.27 1.27)
				)
				(justify mirror)
			)
		)
		(duplicate_pad_numbers_are_jumpers no)
		(fp_line
			(start 0.7874 0.4064)
			(end 0.7874 -0.4064)
			(stroke
				(width 0.1524)
				(type default)
			)
			(layer "B.SilkS")
		)
		(fp_line
			(start 0.7874 -0.4064)
			(end -0.7874 -0.4064)
			(stroke
				(width 0.1524)
				(type default)
			)
			(layer "B.SilkS")
		)
		(fp_line
			(start -0.7874 0.4064)
			(end 0.7874 0.4064)
			(stroke
				(width 0.1524)
				(type default)
			)
			(layer "B.SilkS")
		)
		(fp_line
			(start -0.7874 -0.4064)
			(end -0.7874 0.4064)
			(stroke
				(width 0.1524)
				(type default)
			)
			(layer "B.SilkS")
		)
		(fp_line
			(start 0.67945 0.3048)
			(end 0.67945 -0.305054)
			(stroke
				(width 0.1)
				(type default)
			)
			(layer "B.Fab")
		)
		(fp_line
			(start 0.67945 -0.305054)
			(end 0.12065 -0.305054)
			(stroke
				(width 0.1)
				(type default)
			)
			(layer "B.Fab")
		)
		(fp_line
			(start 0.12065 0.3048)
			(end 0.67945 0.3048)
			(stroke
				(width 0.1)
				(type default)
			)
			(layer "B.Fab")
		)
		(fp_line
			(start 0.12065 0.2794)
			(end 0.12065 0.3048)
			(stroke
				(width 0.1)
				(type default)
			)
			(layer "B.Fab")
		)
		(fp_line
			(start 0.12065 -0.2794)
			(end -0.12065 -0.2794)
			(stroke
				(width 0.1)
				(type default)
			)
			(layer "B.Fab")
		)
		(fp_line
			(start 0.12065 -0.305054)
			(end 0.12065 -0.2794)
			(stroke
				(width 0.1)
				(type default)
			)
			(layer "B.Fab")
		)
		(fp_line
			(start -0.120396 0.3048)
			(end -0.120396 0.2794)
			(stroke
				(width 0.1)
				(type default)
			)
			(layer "B.Fab")
		)
		(fp_line
			(start -0.120396 0.2794)
			(end 0.12065 0.2794)
			(stroke
				(width 0.1)
				(type default)
			)
			(layer "B.Fab")
		)
		(fp_line
			(start -0.12065 -0.2794)
			(end -0.12065 -0.3048)
			(stroke
				(width 0.1)
				(type default)
			)
			(layer "B.Fab")
		)
		(fp_line
			(start -0.12065 -0.3048)
			(end -0.67945 -0.3048)
			(stroke
				(width 0.1)
				(type default)
			)
			(layer "B.Fab")
		)
		(fp_line
			(start -0.67945 0.3048)
			(end -0.120396 0.3048)
			(stroke
				(width 0.1)
				(type default)
			)
			(layer "B.Fab")
		)
		(fp_line
			(start -0.67945 -0.3048)
			(end -0.67945 0.3048)
			(stroke
				(width 0.1)
				(type default)
			)
			(layer "B.Fab")
		)
		(pad "1" smd circle
			(at 0.40005 0)
			(size 0 0)
			(layers "B.Cu" "B.Mask" "B.Paste")
			(net "P3V3_CLK_GEN_VDDMXCK_CK440")
		)
		(pad "2" smd circle
			(at -0.40005 0)
			(size 0 0)
			(layers "B.Cu" "B.Mask" "B.Paste")
			(net "GND")
		)
	)
	(footprint ""
		(layer "B.Cu")
		(at 232.645712 -207.767428)
		(property "Reference" "R6151"
			(at 0 0 0)
			(layer "B.SilkS")
			(hide yes)
			(effects
				(font
					(size 1.27 1.27)
				)
				(justify mirror)
			)
		)
		(property "Value" ""
			(at 0 0 0)
			(layer "B.Fab")
			(effects
				(font
					(size 1.27 1.27)
				)
				(justify mirror)
			)
		)
		(duplicate_pad_numbers_are_jumpers no)
		(fp_line
			(start -0.7874 -0.4064)
			(end -0.7874 0.4064)
			(stroke
				(width 0.1524)
				(type default)
			)
			(layer "B.SilkS")
		)
		(fp_line
			(start -0.7874 0.4064)
			(end 0.7874 0.4064)
			(stroke
				(width 0.1524)
				(type default)
			)
			(layer "B.SilkS")
		)
		(fp_line
			(start 0.7874 -0.4064)
			(end -0.7874 -0.4064)
			(stroke
				(width 0.1524)
				(type default)
			)
			(layer "B.SilkS")
		)
		(fp_line
			(start 0.7874 0.4064)
			(end 0.7874 -0.4064)
			(stroke
				(width 0.1524)
				(type default)
			)
			(layer "B.SilkS")
		)
		(fp_line
			(start -0.67945 -0.3048)
			(end -0.67945 0.3048)
			(stroke
				(width 0.1)
				(type default)
			)
			(layer "B.Fab")
		)
		(fp_line
			(start -0.67945 0.3048)
			(end -0.120396 0.3048)
			(stroke
				(width 0.1)
				(type default)
			)
			(layer "B.Fab")
		)
		(fp_line
			(start -0.12065 -0.3048)
			(end -0.67945 -0.3048)
			(stroke
				(width 0.1)
				(type default)
			)
			(layer "B.Fab")
		)
		(fp_line
			(start -0.12065 -0.2794)
			(end -0.12065 -0.3048)
			(stroke
				(width 0.1)
				(type default)
			)
			(layer "B.Fab")
		)
		(fp_line
			(start -0.120396 0.2794)
			(end 0.12065 0.2794)
			(stroke
				(width 0.1)
				(type default)
			)
			(layer "B.Fab")
		)
		(fp_line
			(start -0.120396 0.3048)
			(end -0.120396 0.2794)
			(stroke
				(width 0.1)
				(type default)
			)
			(layer "B.Fab")
		)
		(fp_line
			(start 0.12065 -0.305054)
			(end 0.12065 -0.2794)
			(stroke
				(width 0.1)
				(type default)
			)
			(layer "B.Fab")
		)
		(fp_line
			(start 0.12065 -0.2794)
			(end -0.12065 -0.2794)
			(stroke
				(width 0.1)
				(type default)
			)
			(layer "B.Fab")
		)
		(fp_line
			(start 0.12065 0.2794)
			(end 0.12065 0.3048)
			(stroke
				(width 0.1)
				(type default)
			)
			(layer "B.Fab")
		)
		(fp_line
			(start 0.12065 0.3048)
			(end 0.67945 0.3048)
			(stroke
				(width 0.1)
				(type default)
			)
			(layer "B.Fab")
		)
		(fp_line
			(start 0.67945 -0.305054)
			(end 0.12065 -0.305054)
			(stroke
				(width 0.1)
				(type default)
			)
			(layer "B.Fab")
		)
		(fp_line
			(start 0.67945 0.3048)
			(end 0.67945 -0.305054)
			(stroke
				(width 0.1)
				(type default)
			)
			(layer "B.Fab")
		)
		(pad "1" smd circle
			(at 0.40005 0 180)
			(size 0 0)
			(layers "B.Cu" "B.Mask" "B.Paste")
			(net "BIC_SPI1DQ2")
		)
		(pad "2" smd circle
			(at -0.40005 0 180)
			(size 0 0)
			(layers "B.Cu" "B.Mask" "B.Paste")
			(net "P3V3_AUX")
		)
	)
	(footprint ""
		(layer "B.Cu")
		(at 409.374848 -286.399732 90)
		(property "Reference" "C3478"
			(at 0 0 90)
			(layer "B.SilkS")
			(hide yes)
			(effects
				(font
					(size 1.27 1.27)
				)
				(justify mirror)
			)
		)
		(property "Value" ""
			(at 0 0 90)
			(layer "B.Fab")
			(effects
				(font
					(size 1.27 1.27)
				)
				(justify mirror)
			)
		)
		(duplicate_pad_numbers_are_jumpers no)
		(fp_line
			(start 0.299974 -0.150114)
			(end -0.299974 -0.150114)
			(stroke
				(width 0.1)
				(type default)
			)
			(layer "B.Fab")
		)
		(fp_line
			(start -0.299974 -0.150114)
			(end -0.299974 0.150114)
			(stroke
				(width 0.1)
				(type default)
			)
			(layer "B.Fab")
		)
		(fp_line
			(start 0.299974 0.150114)
			(end 0.299974 -0.150114)
			(stroke
				(width 0.1)
				(type default)
			)
			(layer "B.Fab")
		)
		(fp_line
			(start -0.299974 0.150114)
			(end 0.299974 0.150114)
			(stroke
				(width 0.1)
				(type default)
			)
			(layer "B.Fab")
		)
		(pad "1" smd rect
			(at 0.2667 0 270)
			(size 0.3048 0.381)
			(layers "B.Cu" "B.Mask" "B.Paste")
			(net "P1V25_SERDES_VDDPLL_PEX3")
		)
		(pad "2" smd rect
			(at -0.2667 0 270)
			(size 0.3048 0.381)
			(layers "B.Cu" "B.Mask" "B.Paste")
			(net "GND")
		)
	)
	(footprint ""
		(layer "B.Cu")
		(at 345.44 -207.772 -90)
		(property "Reference" "R4146"
			(at 0 0 90)
			(layer "B.SilkS")
			(hide yes)
			(effects
				(font
					(size 1.27 1.27)
				)
				(justify mirror)
			)
		)
		(property "Value" ""
			(at 0 0 90)
			(layer "B.Fab")
			(effects
				(font
					(size 1.27 1.27)
				)
				(justify mirror)
			)
		)
		(duplicate_pad_numbers_are_jumpers no)
		(fp_line
			(start -0.7874 0.4064)
			(end 0.7874 0.4064)
			(stroke
				(width 0.1524)
				(type default)
			)
			(layer "B.SilkS")
		)
		(fp_line
			(start 0.7874 0.4064)
			(end 0.7874 -0.4064)
			(stroke
				(width 0.1524)
				(type default)
			)
			(layer "B.SilkS")
		)
		(fp_line
			(start -0.7874 -0.4064)
			(end -0.7874 0.4064)
			(stroke
				(width 0.1524)
				(type default)
			)
			(layer "B.SilkS")
		)
		(fp_line
			(start 0.7874 -0.4064)
			(end -0.7874 -0.4064)
			(stroke
				(width 0.1524)
				(type default)
			)
			(layer "B.SilkS")
		)
		(fp_line
			(start -0.67945 0.3048)
			(end -0.120396 0.3048)
			(stroke
				(width 0.1)
				(type default)
			)
			(layer "B.Fab")
		)
		(fp_line
			(start -0.120396 0.3048)
			(end -0.120396 0.2794)
			(stroke
				(width 0.1)
				(type default)
			)
			(layer "B.Fab")
		)
		(fp_line
			(start 0.12065 0.3048)
			(end 0.67945 0.3048)
			(stroke
				(width 0.1)
				(type default)
			)
			(layer "B.Fab")
		)
		(fp_line
			(start 0.67945 0.3048)
			(end 0.67945 -0.305054)
			(stroke
				(width 0.1)
				(type default)
			)
			(layer "B.Fab")
		)
		(fp_line
			(start -0.120396 0.2794)
			(end 0.12065 0.2794)
			(stroke
				(width 0.1)
				(type default)
			)
			(layer "B.Fab")
		)
		(fp_line
			(start 0.12065 0.2794)
			(end 0.12065 0.3048)
			(stroke
				(width 0.1)
				(type default)
			)
			(layer "B.Fab")
		)
		(fp_line
			(start -0.12065 -0.2794)
			(end -0.12065 -0.3048)
			(stroke
				(width 0.1)
				(type default)
			)
			(layer "B.Fab")
		)
		(fp_line
			(start 0.12065 -0.2794)
			(end -0.12065 -0.2794)
			(stroke
				(width 0.1)
				(type default)
			)
			(layer "B.Fab")
		)
		(fp_line
			(start -0.67945 -0.3048)
			(end -0.67945 0.3048)
			(stroke
				(width 0.1)
				(type default)
			)
			(layer "B.Fab")
		)
		(fp_line
			(start -0.12065 -0.3048)
			(end -0.67945 -0.3048)
			(stroke
				(width 0.1)
				(type default)
			)
			(layer "B.Fab")
		)
		(fp_line
			(start 0.12065 -0.305054)
			(end 0.12065 -0.2794)
			(stroke
				(width 0.1)
				(type default)
			)
			(layer "B.Fab")
		)
		(fp_line
			(start 0.67945 -0.305054)
			(end 0.12065 -0.305054)
			(stroke
				(width 0.1)
				(type default)
			)
			(layer "B.Fab")
		)
		(pad "1" smd circle
			(at 0.40005 0 90)
			(size 0 0)
			(layers "B.Cu" "B.Mask" "B.Paste")
			(net "SSD15_CLK_EN_R_N")
		)
		(pad "2" smd circle
			(at -0.40005 0 90)
			(size 0 0)
			(layers "B.Cu" "B.Mask" "B.Paste")
			(net "SSD15_CLK_EN_N")
		)
	)
	(footprint ""
		(layer "B.Cu")
		(at 170.049952 -290.199826 90)
		(property "Reference" "C1486"
			(at 0 0 90)
			(layer "B.SilkS")
			(hide yes)
			(effects
				(font
					(size 1.27 1.27)
				)
				(justify mirror)
			)
		)
		(property "Value" ""
			(at 0 0 90)
			(layer "B.Fab")
			(effects
				(font
					(size 1.27 1.27)
				)
				(justify mirror)
			)
		)
		(duplicate_pad_numbers_are_jumpers no)
		(fp_line
			(start 0.299974 -0.150114)
			(end -0.299974 -0.150114)
			(stroke
				(width 0.1)
				(type default)
			)
			(layer "B.Fab")
		)
		(fp_line
			(start -0.299974 -0.150114)
			(end -0.299974 0.150114)
			(stroke
				(width 0.1)
				(type default)
			)
			(layer "B.Fab")
		)
		(fp_line
			(start 0.299974 0.150114)
			(end 0.299974 -0.150114)
			(stroke
				(width 0.1)
				(type default)
			)
			(layer "B.Fab")
		)
		(fp_line
			(start -0.299974 0.150114)
			(end 0.299974 0.150114)
			(stroke
				(width 0.1)
				(type default)
			)
			(layer "B.Fab")
		)
		(pad "1" smd rect
			(at 0.2667 0 270)
			(size 0.3048 0.381)
			(layers "B.Cu" "B.Mask" "B.Paste")
			(net "P0V8_SERDES_VDDA_PEX1")
		)
		(pad "2" smd rect
			(at -0.2667 0 270)
			(size 0.3048 0.381)
			(layers "B.Cu" "B.Mask" "B.Paste")
			(net "GND")
		)
	)
	(footprint ""
		(layer "B.Cu")
		(at 395.915388 -360.376724 180)
		(property "Reference" "R6297"
			(at 0 0 0)
			(layer "B.SilkS")
			(hide yes)
			(effects
				(font
					(size 1.27 1.27)
				)
				(justify mirror)
			)
		)
		(property "Value" ""
			(at 0 0 0)
			(layer "B.Fab")
			(effects
				(font
					(size 1.27 1.27)
				)
				(justify mirror)
			)
		)
		(duplicate_pad_numbers_are_jumpers no)
		(fp_line
			(start 0.7874 0.4064)
			(end 0.7874 -0.4064)
			(stroke
				(width 0.1524)
				(type default)
			)
			(layer "B.SilkS")
		)
		(fp_line
			(start 0.7874 -0.4064)
			(end -0.7874 -0.4064)
			(stroke
				(width 0.1524)
				(type default)
			)
			(layer "B.SilkS")
		)
		(fp_line
			(start -0.7874 0.4064)
			(end 0.7874 0.4064)
			(stroke
				(width 0.1524)
				(type default)
			)
			(layer "B.SilkS")
		)
		(fp_line
			(start -0.7874 -0.4064)
			(end -0.7874 0.4064)
			(stroke
				(width 0.1524)
				(type default)
			)
			(layer "B.SilkS")
		)
		(fp_line
			(start 0.67945 0.3048)
			(end 0.67945 -0.305054)
			(stroke
				(width 0.1)
				(type default)
			)
			(layer "B.Fab")
		)
		(fp_line
			(start 0.67945 -0.305054)
			(end 0.12065 -0.305054)
			(stroke
				(width 0.1)
				(type default)
			)
			(layer "B.Fab")
		)
		(fp_line
			(start 0.12065 0.3048)
			(end 0.67945 0.3048)
			(stroke
				(width 0.1)
				(type default)
			)
			(layer "B.Fab")
		)
		(fp_line
			(start 0.12065 0.2794)
			(end 0.12065 0.3048)
			(stroke
				(width 0.1)
				(type default)
			)
			(layer "B.Fab")
		)
		(fp_line
			(start 0.12065 -0.2794)
			(end -0.12065 -0.2794)
			(stroke
				(width 0.1)
				(type default)
			)
			(layer "B.Fab")
		)
		(fp_line
			(start 0.12065 -0.305054)
			(end 0.12065 -0.2794)
			(stroke
				(width 0.1)
				(type default)
			)
			(layer "B.Fab")
		)
		(fp_line
			(start -0.120396 0.3048)
			(end -0.120396 0.2794)
			(stroke
				(width 0.1)
				(type default)
			)
			(layer "B.Fab")
		)
		(fp_line
			(start -0.120396 0.2794)
			(end 0.12065 0.2794)
			(stroke
				(width 0.1)
				(type default)
			)
			(layer "B.Fab")
		)
		(fp_line
			(start -0.12065 -0.2794)
			(end -0.12065 -0.3048)
			(stroke
				(width 0.1)
				(type default)
			)
			(layer "B.Fab")
		)
		(fp_line
			(start -0.12065 -0.3048)
			(end -0.67945 -0.3048)
			(stroke
				(width 0.1)
				(type default)
			)
			(layer "B.Fab")
		)
		(fp_line
			(start -0.67945 0.3048)
			(end -0.120396 0.3048)
			(stroke
				(width 0.1)
				(type default)
			)
			(layer "B.Fab")
		)
		(fp_line
			(start -0.67945 -0.3048)
			(end -0.67945 0.3048)
			(stroke
				(width 0.1)
				(type default)
			)
			(layer "B.Fab")
		)
		(pad "1" smd circle
			(at 0.40005 0)
			(size 0 0)
			(layers "B.Cu" "B.Mask" "B.Paste")
			(net "UART_MB_BIC_RX")
		)
		(pad "2" smd circle
			(at -0.40005 0)
			(size 0 0)
			(layers "B.Cu" "B.Mask" "B.Paste")
			(net "GND")
		)
	)
	(footprint ""
		(layer "B.Cu")
		(at 309.741824 -104.120696 180)
		(property "Reference" "R270"
			(at 0 0 0)
			(layer "B.SilkS")
			(hide yes)
			(effects
				(font
					(size 1.27 1.27)
				)
				(justify mirror)
			)
		)
		(property "Value" ""
			(at 0 0 0)
			(layer "B.Fab")
			(effects
				(font
					(size 1.27 1.27)
				)
				(justify mirror)
			)
		)
		(duplicate_pad_numbers_are_jumpers no)
		(fp_line
			(start 0.7874 0.4064)
			(end 0.7874 -0.4064)
			(stroke
				(width 0.1524)
				(type default)
			)
			(layer "B.SilkS")
		)
		(fp_line
			(start 0.7874 -0.4064)
			(end -0.7874 -0.4064)
			(stroke
				(width 0.1524)
				(type default)
			)
			(layer "B.SilkS")
		)
		(fp_line
			(start -0.7874 0.4064)
			(end 0.7874 0.4064)
			(stroke
				(width 0.1524)
				(type default)
			)
			(layer "B.SilkS")
		)
		(fp_line
			(start -0.7874 -0.4064)
			(end -0.7874 0.4064)
			(stroke
				(width 0.1524)
				(type default)
			)
			(layer "B.SilkS")
		)
		(fp_line
			(start 0.67945 0.3048)
			(end 0.67945 -0.305054)
			(stroke
				(width 0.1)
				(type default)
			)
			(layer "B.Fab")
		)
		(fp_line
			(start 0.67945 -0.305054)
			(end 0.12065 -0.305054)
			(stroke
				(width 0.1)
				(type default)
			)
			(layer "B.Fab")
		)
		(fp_line
			(start 0.12065 0.3048)
			(end 0.67945 0.3048)
			(stroke
				(width 0.1)
				(type default)
			)
			(layer "B.Fab")
		)
		(fp_line
			(start 0.12065 0.2794)
			(end 0.12065 0.3048)
			(stroke
				(width 0.1)
				(type default)
			)
			(layer "B.Fab")
		)
		(fp_line
			(start 0.12065 -0.2794)
			(end -0.12065 -0.2794)
			(stroke
				(width 0.1)
				(type default)
			)
			(layer "B.Fab")
		)
		(fp_line
			(start 0.12065 -0.305054)
			(end 0.12065 -0.2794)
			(stroke
				(width 0.1)
				(type default)
			)
			(layer "B.Fab")
		)
		(fp_line
			(start -0.120396 0.3048)
			(end -0.120396 0.2794)
			(stroke
				(width 0.1)
				(type default)
			)
			(layer "B.Fab")
		)
		(fp_line
			(start -0.120396 0.2794)
			(end 0.12065 0.2794)
			(stroke
				(width 0.1)
				(type default)
			)
			(layer "B.Fab")
		)
		(fp_line
			(start -0.12065 -0.2794)
			(end -0.12065 -0.3048)
			(stroke
				(width 0.1)
				(type default)
			)
			(layer "B.Fab")
		)
		(fp_line
			(start -0.12065 -0.3048)
			(end -0.67945 -0.3048)
			(stroke
				(width 0.1)
				(type default)
			)
			(layer "B.Fab")
		)
		(fp_line
			(start -0.67945 0.3048)
			(end -0.120396 0.3048)
			(stroke
				(width 0.1)
				(type default)
			)
			(layer "B.Fab")
		)
		(fp_line
			(start -0.67945 -0.3048)
			(end -0.67945 0.3048)
			(stroke
				(width 0.1)
				(type default)
			)
			(layer "B.Fab")
		)
		(pad "1" smd circle
			(at 0.40005 0)
			(size 0 0)
			(layers "B.Cu" "B.Mask" "B.Paste")
			(net "NCSI_NIC5_CRS_DV")
		)
		(pad "2" smd circle
			(at -0.40005 0)
			(size 0 0)
			(layers "B.Cu" "B.Mask" "B.Paste")
			(net "GND")
		)
	)
	(footprint ""
		(layer "B.Cu")
		(at 118.387114 -257.699764 180)
		(property "Reference" "PC53"
			(at 0 0 0)
			(layer "B.SilkS")
			(hide yes)
			(effects
				(font
					(size 1.27 1.27)
				)
				(justify mirror)
			)
		)
		(property "Value" ""
			(at 0 0 0)
			(layer "B.Fab")
			(effects
				(font
					(size 1.27 1.27)
				)
				(justify mirror)
			)
		)
		(duplicate_pad_numbers_are_jumpers no)
		(fp_line
			(start 0.7874 0.4064)
			(end 0.7874 -0.4064)
			(stroke
				(width 0.1524)
				(type default)
			)
			(layer "B.SilkS")
		)
		(fp_line
			(start 0.7874 -0.4064)
			(end -0.7874 -0.4064)
			(stroke
				(width 0.1524)
				(type default)
			)
			(layer "B.SilkS")
		)
		(fp_line
			(start -0.7874 0.4064)
			(end 0.7874 0.4064)
			(stroke
				(width 0.1524)
				(type default)
			)
			(layer "B.SilkS")
		)
		(fp_line
			(start -0.7874 -0.4064)
			(end -0.7874 0.4064)
			(stroke
				(width 0.1524)
				(type default)
			)
			(layer "B.SilkS")
		)
		(fp_line
			(start 0.67945 0.3048)
			(end 0.67945 -0.305054)
			(stroke
				(width 0.1)
				(type default)
			)
			(layer "B.Fab")
		)
		(fp_line
			(start 0.67945 -0.305054)
			(end 0.12065 -0.305054)
			(stroke
				(width 0.1)
				(type default)
			)
			(layer "B.Fab")
		)
		(fp_line
			(start 0.12065 0.3048)
			(end 0.67945 0.3048)
			(stroke
				(width 0.1)
				(type default)
			)
			(layer "B.Fab")
		)
		(fp_line
			(start 0.12065 0.2794)
			(end 0.12065 0.3048)
			(stroke
				(width 0.1)
				(type default)
			)
			(layer "B.Fab")
		)
		(fp_line
			(start 0.12065 -0.2794)
			(end -0.12065 -0.2794)
			(stroke
				(width 0.1)
				(type default)
			)
			(layer "B.Fab")
		)
		(fp_line
			(start 0.12065 -0.305054)
			(end 0.12065 -0.2794)
			(stroke
				(width 0.1)
				(type default)
			)
			(layer "B.Fab")
		)
		(fp_line
			(start -0.120396 0.3048)
			(end -0.120396 0.2794)
			(stroke
				(width 0.1)
				(type default)
			)
			(layer "B.Fab")
		)
		(fp_line
			(start -0.120396 0.2794)
			(end 0.12065 0.2794)
			(stroke
				(width 0.1)
				(type default)
			)
			(layer "B.Fab")
		)
		(fp_line
			(start -0.12065 -0.2794)
			(end -0.12065 -0.3048)
			(stroke
				(width 0.1)
				(type default)
			)
			(layer "B.Fab")
		)
		(fp_line
			(start -0.12065 -0.3048)
			(end -0.67945 -0.3048)
			(stroke
				(width 0.1)
				(type default)
			)
			(layer "B.Fab")
		)
		(fp_line
			(start -0.67945 0.3048)
			(end -0.120396 0.3048)
			(stroke
				(width 0.1)
				(type default)
			)
			(layer "B.Fab")
		)
		(fp_line
			(start -0.67945 -0.3048)
			(end -0.67945 0.3048)
			(stroke
				(width 0.1)
				(type default)
			)
			(layer "B.Fab")
		)
		(pad "1" smd circle
			(at 0.40005 0)
			(size 0 0)
			(layers "B.Cu" "B.Mask" "B.Paste")
			(net "P0V8_PEX1_TSEN_R")
		)
		(pad "2" smd circle
			(at -0.40005 0)
			(size 0 0)
			(layers "B.Cu" "B.Mask" "B.Paste")
			(net "GND")
		)
	)
	(footprint ""
		(layer "B.Cu")
		(at 127.986536 -215.09482 180)
		(property "Reference" "U107"
			(at 0.195834 1.785874 0)
			(unlocked yes)
			(layer "B.SilkS")
			(effects
				(font
					(size 0.7874 0.5842)
					(thickness 0.1524)
				)
				(justify mirror)
			)
		)
		(property "Value" ""
			(at 0 0 0)
			(layer "B.Fab")
			(effects
				(font
					(size 1.27 1.27)
				)
				(justify mirror)
			)
		)
		(duplicate_pad_numbers_are_jumpers no)
		(fp_line
			(start 1.7272 1.1176)
			(end 1.7272 -1.1176)
			(stroke
				(width 0.1524)
				(type default)
			)
			(layer "B.SilkS")
		)
		(fp_line
			(start 0.254 -1.1176)
			(end 1.7272 -1.1176)
			(stroke
				(width 0.1524)
				(type default)
			)
			(layer "B.SilkS")
		)
		(fp_line
			(start 0 -0.7366)
			(end 0.254 -1.1176)
			(stroke
				(width 0.1524)
				(type default)
			)
			(layer "B.SilkS")
		)
		(fp_line
			(start -0.254 -1.1176)
			(end 0 -0.7366)
			(stroke
				(width 0.1524)
				(type default)
			)
			(layer "B.SilkS")
		)
		(fp_line
			(start -1.7272 1.1176)
			(end 1.7272 1.1176)
			(stroke
				(width 0.1524)
				(type default)
			)
			(layer "B.SilkS")
		)
		(fp_line
			(start -1.7272 -1.1176)
			(end -0.254 -1.1176)
			(stroke
				(width 0.1524)
				(type default)
			)
			(layer "B.SilkS")
		)
		(fp_line
			(start -1.7272 -1.1176)
			(end -1.7272 1.1176)
			(stroke
				(width 0.1524)
				(type default)
			)
			(layer "B.SilkS")
		)
		(fp_poly
			(pts
				(xy 1.9558 -0.649986) (xy 2.7178 -0.268986) (xy 2.7178 -1.030986)
			)
			(stroke
				(width 0)
				(type default)
			)
			(fill yes)
			(layer "B.SilkS")
		)
		(fp_line
			(start 1.5748 1.1176)
			(end -1.5748 1.1176)
			(stroke
				(width 0.1)
				(type default)
			)
			(layer "B.Fab")
		)
		(fp_line
			(start 1.5748 -1.1176)
			(end 1.5748 1.1176)
			(stroke
				(width 0.1)
				(type default)
			)
			(layer "B.Fab")
		)
		(fp_line
			(start -1.5748 1.1176)
			(end -1.5748 -1.1176)
			(stroke
				(width 0.1)
				(type default)
			)
			(layer "B.Fab")
		)
		(fp_line
			(start -1.5748 -1.1176)
			(end 1.5748 -1.1176)
			(stroke
				(width 0.1)
				(type default)
			)
			(layer "B.Fab")
		)
		(fp_poly
			(pts
				(xy 1.9558 -0.649986) (xy 2.7178 -0.268986) (xy 2.7178 -1.030986)
			)
			(stroke
				(width 0)
				(type default)
			)
			(fill yes)
			(layer "B.Fab")
		)
		(pad "1" smd rect
			(at 0.999998 -0.649986 90)
			(size 0.3556 1.1176)
			(layers "B.Cu" "B.Mask" "B.Paste")
			(net "UART_PEX2_CLI_R_TX")
		)
		(pad "2" smd rect
			(at 0.999998 0 90)
			(size 0.3556 1.1176)
			(layers "B.Cu" "B.Mask" "B.Paste")
			(net "GND")
		)
		(pad "3" smd rect
			(at 0.999998 0.649986 90)
			(size 0.3556 1.1176)
			(layers "B.Cu" "B.Mask" "B.Paste")
			(net "UART_PEX3_CLI_R_TX")
		)
		(pad "4" smd rect
			(at -0.999998 0.649986 90)
			(size 0.3556 1.1176)
			(layers "B.Cu" "B.Mask" "B.Paste")
			(net "UART_PEX3_CLI_BUF_R_TX")
		)
		(pad "5" smd rect
			(at -0.999998 0 90)
			(size 0.3556 1.1176)
			(layers "B.Cu" "B.Mask" "B.Paste")
			(net "P1V8_PEX")
		)
		(pad "6" smd rect
			(at -0.999998 -0.649986 90)
			(size 0.3556 1.1176)
			(layers "B.Cu" "B.Mask" "B.Paste")
			(net "UART_PEX2_CLI_BUF_R_TX")
		)
	)
	(footprint ""
		(layer "B.Cu")
		(at 281.399742 -300.174914)
		(property "Reference" "C1619"
			(at 0 0 0)
			(layer "B.SilkS")
			(hide yes)
			(effects
				(font
					(size 1.27 1.27)
				)
				(justify mirror)
			)
		)
		(property "Value" ""
			(at 0 0 0)
			(layer "B.Fab")
			(effects
				(font
					(size 1.27 1.27)
				)
				(justify mirror)
			)
		)
		(duplicate_pad_numbers_are_jumpers no)
		(fp_line
			(start -0.299974 -0.150114)
			(end -0.299974 0.150114)
			(stroke
				(width 0.1)
				(type default)
			)
			(layer "B.Fab")
		)
		(fp_line
			(start -0.299974 0.150114)
			(end 0.299974 0.150114)
			(stroke
				(width 0.1)
				(type default)
			)
			(layer "B.Fab")
		)
		(fp_line
			(start 0.299974 -0.150114)
			(end -0.299974 -0.150114)
			(stroke
				(width 0.1)
				(type default)
			)
			(layer "B.Fab")
		)
		(fp_line
			(start 0.299974 0.150114)
			(end 0.299974 -0.150114)
			(stroke
				(width 0.1)
				(type default)
			)
			(layer "B.Fab")
		)
		(pad "1" smd rect
			(at 0.2667 0 180)
			(size 0.3048 0.381)
			(layers "B.Cu" "B.Mask" "B.Paste")
			(net "P0V8_PEX2")
		)
		(pad "2" smd rect
			(at -0.2667 0 180)
			(size 0.3048 0.381)
			(layers "B.Cu" "B.Mask" "B.Paste")
			(net "GND")
		)
	)
	(footprint ""
		(layer "B.Cu")
		(at 405.575008 -286.399732 90)
		(property "Reference" "C3476"
			(at 0 0 90)
			(layer "B.SilkS")
			(hide yes)
			(effects
				(font
					(size 1.27 1.27)
				)
				(justify mirror)
			)
		)
		(property "Value" ""
			(at 0 0 90)
			(layer "B.Fab")
			(effects
				(font
					(size 1.27 1.27)
				)
				(justify mirror)
			)
		)
		(duplicate_pad_numbers_are_jumpers no)
		(fp_line
			(start 0.299974 -0.150114)
			(end -0.299974 -0.150114)
			(stroke
				(width 0.1)
				(type default)
			)
			(layer "B.Fab")
		)
		(fp_line
			(start -0.299974 -0.150114)
			(end -0.299974 0.150114)
			(stroke
				(width 0.1)
				(type default)
			)
			(layer "B.Fab")
		)
		(fp_line
			(start 0.299974 0.150114)
			(end 0.299974 -0.150114)
			(stroke
				(width 0.1)
				(type default)
			)
			(layer "B.Fab")
		)
		(fp_line
			(start -0.299974 0.150114)
			(end 0.299974 0.150114)
			(stroke
				(width 0.1)
				(type default)
			)
			(layer "B.Fab")
		)
		(pad "1" smd rect
			(at 0.2667 0 270)
			(size 0.3048 0.381)
			(layers "B.Cu" "B.Mask" "B.Paste")
			(net "P1V25_SERDES_VDDPLL_PEX3")
		)
		(pad "2" smd rect
			(at -0.2667 0 270)
			(size 0.3048 0.381)
			(layers "B.Cu" "B.Mask" "B.Paste")
			(net "GND")
		)
	)
	(footprint ""
		(layer "B.Cu")
		(at 51.574954 -293.99992 -90)
		(property "Reference" "C1139"
			(at 0 0 90)
			(layer "B.SilkS")
			(hide yes)
			(effects
				(font
					(size 1.27 1.27)
				)
				(justify mirror)
			)
		)
		(property "Value" ""
			(at 0 0 90)
			(layer "B.Fab")
			(effects
				(font
					(size 1.27 1.27)
				)
				(justify mirror)
			)
		)
		(duplicate_pad_numbers_are_jumpers no)
		(fp_line
			(start -0.299974 0.150114)
			(end 0.299974 0.150114)
			(stroke
				(width 0.1)
				(type default)
			)
			(layer "B.Fab")
		)
		(fp_line
			(start 0.299974 0.150114)
			(end 0.299974 -0.150114)
			(stroke
				(width 0.1)
				(type default)
			)
			(layer "B.Fab")
		)
		(fp_line
			(start -0.299974 -0.150114)
			(end -0.299974 0.150114)
			(stroke
				(width 0.1)
				(type default)
			)
			(layer "B.Fab")
		)
		(fp_line
			(start 0.299974 -0.150114)
			(end -0.299974 -0.150114)
			(stroke
				(width 0.1)
				(type default)
			)
			(layer "B.Fab")
		)
		(pad "1" smd rect
			(at 0.2667 0 90)
			(size 0.3048 0.381)
			(layers "B.Cu" "B.Mask" "B.Paste")
			(net "P0V8_PEX0")
		)
		(pad "2" smd rect
			(at -0.2667 0 90)
			(size 0.3048 0.381)
			(layers "B.Cu" "B.Mask" "B.Paste")
			(net "GND")
		)
	)
	(footprint ""
		(layer "B.Cu")
		(at 397.85544 -150.9776)
		(property "Reference" "R326"
			(at 0 0 0)
			(layer "B.SilkS")
			(hide yes)
			(effects
				(font
					(size 1.27 1.27)
				)
				(justify mirror)
			)
		)
		(property "Value" ""
			(at 0 0 0)
			(layer "B.Fab")
			(effects
				(font
					(size 1.27 1.27)
				)
				(justify mirror)
			)
		)
		(duplicate_pad_numbers_are_jumpers no)
		(fp_line
			(start -0.7874 -0.4064)
			(end -0.7874 0.4064)
			(stroke
				(width 0.1524)
				(type default)
			)
			(layer "B.SilkS")
		)
		(fp_line
			(start -0.7874 0.4064)
			(end 0.7874 0.4064)
			(stroke
				(width 0.1524)
				(type default)
			)
			(layer "B.SilkS")
		)
		(fp_line
			(start 0.7874 -0.4064)
			(end -0.7874 -0.4064)
			(stroke
				(width 0.1524)
				(type default)
			)
			(layer "B.SilkS")
		)
		(fp_line
			(start 0.7874 0.4064)
			(end 0.7874 -0.4064)
			(stroke
				(width 0.1524)
				(type default)
			)
			(layer "B.SilkS")
		)
		(fp_line
			(start -0.67945 -0.3048)
			(end -0.67945 0.3048)
			(stroke
				(width 0.1)
				(type default)
			)
			(layer "B.Fab")
		)
		(fp_line
			(start -0.67945 0.3048)
			(end -0.120396 0.3048)
			(stroke
				(width 0.1)
				(type default)
			)
			(layer "B.Fab")
		)
		(fp_line
			(start -0.12065 -0.3048)
			(end -0.67945 -0.3048)
			(stroke
				(width 0.1)
				(type default)
			)
			(layer "B.Fab")
		)
		(fp_line
			(start -0.12065 -0.2794)
			(end -0.12065 -0.3048)
			(stroke
				(width 0.1)
				(type default)
			)
			(layer "B.Fab")
		)
		(fp_line
			(start -0.120396 0.2794)
			(end 0.12065 0.2794)
			(stroke
				(width 0.1)
				(type default)
			)
			(layer "B.Fab")
		)
		(fp_line
			(start -0.120396 0.3048)
			(end -0.120396 0.2794)
			(stroke
				(width 0.1)
				(type default)
			)
			(layer "B.Fab")
		)
		(fp_line
			(start 0.12065 -0.305054)
			(end 0.12065 -0.2794)
			(stroke
				(width 0.1)
				(type default)
			)
			(layer "B.Fab")
		)
		(fp_line
			(start 0.12065 -0.2794)
			(end -0.12065 -0.2794)
			(stroke
				(width 0.1)
				(type default)
			)
			(layer "B.Fab")
		)
		(fp_line
			(start 0.12065 0.2794)
			(end 0.12065 0.3048)
			(stroke
				(width 0.1)
				(type default)
			)
			(layer "B.Fab")
		)
		(fp_line
			(start 0.12065 0.3048)
			(end 0.67945 0.3048)
			(stroke
				(width 0.1)
				(type default)
			)
			(layer "B.Fab")
		)
		(fp_line
			(start 0.67945 -0.305054)
			(end 0.12065 -0.305054)
			(stroke
				(width 0.1)
				(type default)
			)
			(layer "B.Fab")
		)
		(fp_line
			(start 0.67945 0.3048)
			(end 0.67945 -0.305054)
			(stroke
				(width 0.1)
				(type default)
			)
			(layer "B.Fab")
		)
		(pad "1" smd circle
			(at 0.40005 0 180)
			(size 0 0)
			(layers "B.Cu" "B.Mask" "B.Paste")
			(net "CLK_50M_NIC6_RBT_REF")
		)
		(pad "2" smd circle
			(at -0.40005 0 180)
			(size 0 0)
			(layers "B.Cu" "B.Mask" "B.Paste")
			(net "GND")
		)
	)
	(footprint ""
		(layer "B.Cu")
		(at 407.949908 -292.099746 90)
		(property "Reference" "C1988"
			(at 0 0 90)
			(layer "B.SilkS")
			(hide yes)
			(effects
				(font
					(size 1.27 1.27)
				)
				(justify mirror)
			)
		)
		(property "Value" ""
			(at 0 0 90)
			(layer "B.Fab")
			(effects
				(font
					(size 1.27 1.27)
				)
				(justify mirror)
			)
		)
		(duplicate_pad_numbers_are_jumpers no)
		(fp_line
			(start 0.299974 -0.150114)
			(end -0.299974 -0.150114)
			(stroke
				(width 0.1)
				(type default)
			)
			(layer "B.Fab")
		)
		(fp_line
			(start -0.299974 -0.150114)
			(end -0.299974 0.150114)
			(stroke
				(width 0.1)
				(type default)
			)
			(layer "B.Fab")
		)
		(fp_line
			(start 0.299974 0.150114)
			(end 0.299974 -0.150114)
			(stroke
				(width 0.1)
				(type default)
			)
			(layer "B.Fab")
		)
		(fp_line
			(start -0.299974 0.150114)
			(end 0.299974 0.150114)
			(stroke
				(width 0.1)
				(type default)
			)
			(layer "B.Fab")
		)
		(pad "1" smd rect
			(at 0.2667 0 270)
			(size 0.3048 0.381)
			(layers "B.Cu" "B.Mask" "B.Paste")
			(net "P0V8_SERDES_VDDA_PEX3")
		)
		(pad "2" smd rect
			(at -0.2667 0 270)
			(size 0.3048 0.381)
			(layers "B.Cu" "B.Mask" "B.Paste")
			(net "GND")
		)
	)
	(footprint ""
		(layer "B.Cu")
		(at 213.106 -196.977 90)
		(property "Reference" "R6311"
			(at 0 0 90)
			(layer "B.SilkS")
			(hide yes)
			(effects
				(font
					(size 1.27 1.27)
				)
				(justify mirror)
			)
		)
		(property "Value" ""
			(at 0 0 90)
			(layer "B.Fab")
			(effects
				(font
					(size 1.27 1.27)
				)
				(justify mirror)
			)
		)
		(duplicate_pad_numbers_are_jumpers no)
		(fp_line
			(start 0.7874 -0.4064)
			(end -0.7874 -0.4064)
			(stroke
				(width 0.1524)
				(type default)
			)
			(layer "B.SilkS")
		)
		(fp_line
			(start -0.7874 -0.4064)
			(end -0.7874 0.4064)
			(stroke
				(width 0.1524)
				(type default)
			)
			(layer "B.SilkS")
		)
		(fp_line
			(start 0.7874 0.4064)
			(end 0.7874 -0.4064)
			(stroke
				(width 0.1524)
				(type default)
			)
			(layer "B.SilkS")
		)
		(fp_line
			(start -0.7874 0.4064)
			(end 0.7874 0.4064)
			(stroke
				(width 0.1524)
				(type default)
			)
			(layer "B.SilkS")
		)
		(fp_line
			(start 0.67945 -0.305054)
			(end 0.12065 -0.305054)
			(stroke
				(width 0.1)
				(type default)
			)
			(layer "B.Fab")
		)
		(fp_line
			(start 0.12065 -0.305054)
			(end 0.12065 -0.2794)
			(stroke
				(width 0.1)
				(type default)
			)
			(layer "B.Fab")
		)
		(fp_line
			(start -0.12065 -0.3048)
			(end -0.67945 -0.3048)
			(stroke
				(width 0.1)
				(type default)
			)
			(layer "B.Fab")
		)
		(fp_line
			(start -0.67945 -0.3048)
			(end -0.67945 0.3048)
			(stroke
				(width 0.1)
				(type default)
			)
			(layer "B.Fab")
		)
		(fp_line
			(start 0.12065 -0.2794)
			(end -0.12065 -0.2794)
			(stroke
				(width 0.1)
				(type default)
			)
			(layer "B.Fab")
		)
		(fp_line
			(start -0.12065 -0.2794)
			(end -0.12065 -0.3048)
			(stroke
				(width 0.1)
				(type default)
			)
			(layer "B.Fab")
		)
		(fp_line
			(start 0.12065 0.2794)
			(end 0.12065 0.3048)
			(stroke
				(width 0.1)
				(type default)
			)
			(layer "B.Fab")
		)
		(fp_line
			(start -0.120396 0.2794)
			(end 0.12065 0.2794)
			(stroke
				(width 0.1)
				(type default)
			)
			(layer "B.Fab")
		)
		(fp_line
			(start 0.67945 0.3048)
			(end 0.67945 -0.305054)
			(stroke
				(width 0.1)
				(type default)
			)
			(layer "B.Fab")
		)
		(fp_line
			(start 0.12065 0.3048)
			(end 0.67945 0.3048)
			(stroke
				(width 0.1)
				(type default)
			)
			(layer "B.Fab")
		)
		(fp_line
			(start -0.120396 0.3048)
			(end -0.120396 0.2794)
			(stroke
				(width 0.1)
				(type default)
			)
			(layer "B.Fab")
		)
		(fp_line
			(start -0.67945 0.3048)
			(end -0.120396 0.3048)
			(stroke
				(width 0.1)
				(type default)
			)
			(layer "B.Fab")
		)
		(pad "1" smd circle
			(at 0.40005 0 270)
			(size 0 0)
			(layers "B.Cu" "B.Mask" "B.Paste")
			(net "SMB_NIC6_LS_SCL")
		)
		(pad "2" smd circle
			(at -0.40005 0 270)
			(size 0 0)
			(layers "B.Cu" "B.Mask" "B.Paste")
			(net "SMB_NIC6_LS_R_SCL")
		)
	)
	(footprint ""
		(layer "B.Cu")
		(at 339.694012 -217.187018 90)
		(property "Reference" "C2079"
			(at 0 0 90)
			(layer "B.SilkS")
			(hide yes)
			(effects
				(font
					(size 1.27 1.27)
				)
				(justify mirror)
			)
		)
		(property "Value" ""
			(at 0 0 90)
			(layer "B.Fab")
			(effects
				(font
					(size 1.27 1.27)
				)
				(justify mirror)
			)
		)
		(duplicate_pad_numbers_are_jumpers no)
		(fp_line
			(start 0.69215 -0.2921)
			(end -0.69215 -0.2921)
			(stroke
				(width 0.1524)
				(type default)
			)
			(layer "B.SilkS")
		)
		(fp_line
			(start -0.69215 -0.2921)
			(end -0.69215 0.2921)
			(stroke
				(width 0.1524)
				(type default)
			)
			(layer "B.SilkS")
		)
		(fp_line
			(start 0.69215 0.2921)
			(end 0.69215 -0.2921)
			(stroke
				(width 0.1524)
				(type default)
			)
			(layer "B.SilkS")
		)
		(fp_line
			(start -0.69215 0.2921)
			(end 0.69215 0.2921)
			(stroke
				(width 0.1524)
				(type default)
			)
			(layer "B.SilkS")
		)
		(fp_line
			(start 0.51435 -0.2794)
			(end -0.51435 -0.2794)
			(stroke
				(width 0.1)
				(type default)
			)
			(layer "B.Fab")
		)
		(fp_line
			(start -0.51435 -0.2794)
			(end -0.51435 0.2794)
			(stroke
				(width 0.1)
				(type default)
			)
			(layer "B.Fab")
		)
		(fp_line
			(start 0.51435 0.2794)
			(end 0.51435 -0.2794)
			(stroke
				(width 0.1)
				(type default)
			)
			(layer "B.Fab")
		)
		(fp_line
			(start -0.51435 0.2794)
			(end 0.51435 0.2794)
			(stroke
				(width 0.1)
				(type default)
			)
			(layer "B.Fab")
		)
		(pad "1" smd circle
			(at 0.40005 0 270)
			(size 0 0)
			(layers "B.Cu" "B.Mask" "B.Paste")
			(net "P3V3_FPGA_VCCIO3")
		)
		(pad "2" smd circle
			(at -0.40005 0 270)
			(size 0 0)
			(layers "B.Cu" "B.Mask" "B.Paste")
			(net "GND")
		)
		(zone
			(layer "B.Cu")
			(hatch none 0.5)
			(connect_pads
				(clearance 0)
			)
			(min_thickness 0.25)
			(keepout
				(tracks not_allowed)
				(vias allowed)
				(pads allowed)
				(copperpour not_allowed)
				(footprints allowed)
			)
			(placement
				(enabled no)
				(sheetname "")
			)
			(fill
				(thermal_gap 0.5)
				(thermal_bridge_width 0.5)
				(island_removal_mode 0)
			)
			(polygon
				(pts
					(xy 339.781642 -217.377518) (xy 339.839808 -217.286078) (xy 339.839808 -217.086688) (xy 339.781642 -216.996518)
					(xy 339.606382 -216.996518) (xy 339.547962 -217.086688) (xy 339.547962 -217.286078) (xy 339.606128 -217.377518)
				)
			)
		)
	)
	(footprint ""
		(layer "B.Cu")
		(at 407.467816 -286.18434 90)
		(property "Reference" "C3467"
			(at 0 0 90)
			(layer "B.SilkS")
			(hide yes)
			(effects
				(font
					(size 1.27 1.27)
				)
				(justify mirror)
			)
		)
		(property "Value" ""
			(at 0 0 90)
			(layer "B.Fab")
			(effects
				(font
					(size 1.27 1.27)
				)
				(justify mirror)
			)
		)
		(duplicate_pad_numbers_are_jumpers no)
		(fp_line
			(start 1.2954 -0.5842)
			(end -1.2954 -0.5842)
			(stroke
				(width 0.1524)
				(type default)
			)
			(layer "B.SilkS")
		)
		(fp_line
			(start -1.2954 -0.5842)
			(end -1.2954 0.5842)
			(stroke
				(width 0.1524)
				(type default)
			)
			(layer "B.SilkS")
		)
		(fp_line
			(start 1.2954 0.5842)
			(end 1.2954 -0.5842)
			(stroke
				(width 0.1524)
				(type default)
			)
			(layer "B.SilkS")
		)
		(fp_line
			(start -1.2954 0.5842)
			(end 1.2954 0.5842)
			(stroke
				(width 0.1524)
				(type default)
			)
			(layer "B.SilkS")
		)
		(fp_line
			(start 0.8636 -0.4572)
			(end -0.8636 -0.4572)
			(stroke
				(width 0.1)
				(type default)
			)
			(layer "B.Fab")
		)
		(fp_line
			(start -0.8636 -0.4572)
			(end -0.8636 -0.4064)
			(stroke
				(width 0.1)
				(type default)
			)
			(layer "B.Fab")
		)
		(fp_line
			(start 1.1938 -0.4064)
			(end 0.8636 -0.4064)
			(stroke
				(width 0.1)
				(type default)
			)
			(layer "B.Fab")
		)
		(fp_line
			(start 0.8636 -0.4064)
			(end 0.8636 -0.4572)
			(stroke
				(width 0.1)
				(type default)
			)
			(layer "B.Fab")
		)
		(fp_line
			(start -0.8636 -0.4064)
			(end -1.1938 -0.4064)
			(stroke
				(width 0.1)
				(type default)
			)
			(layer "B.Fab")
		)
		(fp_line
			(start -1.1938 -0.4064)
			(end -1.1938 0.4064)
			(stroke
				(width 0.1)
				(type default)
			)
			(layer "B.Fab")
		)
		(fp_line
			(start 1.1938 0.4064)
			(end 1.1938 -0.4064)
			(stroke
				(width 0.1)
				(type default)
			)
			(layer "B.Fab")
		)
		(fp_line
			(start 0.8636 0.4064)
			(end 1.1938 0.4064)
			(stroke
				(width 0.1)
				(type default)
			)
			(layer "B.Fab")
		)
		(fp_line
			(start -0.8636 0.4064)
			(end -0.8636 0.4572)
			(stroke
				(width 0.1)
				(type default)
			)
			(layer "B.Fab")
		)
		(fp_line
			(start -1.1938 0.4064)
			(end -0.8636 0.4064)
			(stroke
				(width 0.1)
				(type default)
			)
			(layer "B.Fab")
		)
		(fp_line
			(start 0.8636 0.4572)
			(end 0.8636 0.4064)
			(stroke
				(width 0.1)
				(type default)
			)
			(layer "B.Fab")
		)
		(fp_line
			(start -0.8636 0.4572)
			(end 0.8636 0.4572)
			(stroke
				(width 0.1)
				(type default)
			)
			(layer "B.Fab")
		)
		(pad "1" smd rect
			(at 0.7366 0)
			(size 0.7112 0.8128)
			(layers "B.Cu" "B.Mask" "B.Paste")
			(net "P1V25_SERDES_VDDPLL_PEX3")
		)
		(pad "2" smd rect
			(at -0.7366 0)
			(size 0.7112 0.8128)
			(layers "B.Cu" "B.Mask" "B.Paste")
			(net "GND")
		)
	)
	(footprint ""
		(layer "B.Cu")
		(at 162.450018 -290.674806)
		(property "Reference" "C3180"
			(at 0 0 0)
			(layer "B.SilkS")
			(hide yes)
			(effects
				(font
					(size 1.27 1.27)
				)
				(justify mirror)
			)
		)
		(property "Value" ""
			(at 0 0 0)
			(layer "B.Fab")
			(effects
				(font
					(size 1.27 1.27)
				)
				(justify mirror)
			)
		)
		(duplicate_pad_numbers_are_jumpers no)
		(fp_line
			(start -0.299974 -0.150114)
			(end -0.299974 0.150114)
			(stroke
				(width 0.1)
				(type default)
			)
			(layer "B.Fab")
		)
		(fp_line
			(start -0.299974 0.150114)
			(end 0.299974 0.150114)
			(stroke
				(width 0.1)
				(type default)
			)
			(layer "B.Fab")
		)
		(fp_line
			(start 0.299974 -0.150114)
			(end -0.299974 -0.150114)
			(stroke
				(width 0.1)
				(type default)
			)
			(layer "B.Fab")
		)
		(fp_line
			(start 0.299974 0.150114)
			(end 0.299974 -0.150114)
			(stroke
				(width 0.1)
				(type default)
			)
			(layer "B.Fab")
		)
		(pad "1" smd rect
			(at 0.2667 0 180)
			(size 0.3048 0.381)
			(layers "B.Cu" "B.Mask" "B.Paste")
			(net "P1V8_PEX")
		)
		(pad "2" smd rect
			(at -0.2667 0 180)
			(size 0.3048 0.381)
			(layers "B.Cu" "B.Mask" "B.Paste")
			(net "GND")
		)
	)
	(footprint ""
		(layer "B.Cu")
		(at 44.449746 -298.27474)
		(property "Reference" "C3007"
			(at 0 0 0)
			(layer "B.SilkS")
			(hide yes)
			(effects
				(font
					(size 1.27 1.27)
				)
				(justify mirror)
			)
		)
		(property "Value" ""
			(at 0 0 0)
			(layer "B.Fab")
			(effects
				(font
					(size 1.27 1.27)
				)
				(justify mirror)
			)
		)
		(duplicate_pad_numbers_are_jumpers no)
		(fp_line
			(start -0.299974 -0.150114)
			(end -0.299974 0.150114)
			(stroke
				(width 0.1)
				(type default)
			)
			(layer "B.Fab")
		)
		(fp_line
			(start -0.299974 0.150114)
			(end 0.299974 0.150114)
			(stroke
				(width 0.1)
				(type default)
			)
			(layer "B.Fab")
		)
		(fp_line
			(start 0.299974 -0.150114)
			(end -0.299974 -0.150114)
			(stroke
				(width 0.1)
				(type default)
			)
			(layer "B.Fab")
		)
		(fp_line
			(start 0.299974 0.150114)
			(end 0.299974 -0.150114)
			(stroke
				(width 0.1)
				(type default)
			)
			(layer "B.Fab")
		)
		(pad "1" smd rect
			(at 0.2667 0 180)
			(size 0.3048 0.381)
			(layers "B.Cu" "B.Mask" "B.Paste")
			(net "P1V8_VDDA_PEX0")
		)
		(pad "2" smd rect
			(at -0.2667 0 180)
			(size 0.3048 0.381)
			(layers "B.Cu" "B.Mask" "B.Paste")
			(net "GND")
		)
	)
	(footprint ""
		(layer "B.Cu")
		(at 257.264916 -366.906048 180)
		(property "Reference" "PR6610"
			(at 0 0 0)
			(layer "B.SilkS")
			(hide yes)
			(effects
				(font
					(size 1.27 1.27)
				)
				(justify mirror)
			)
		)
		(property "Value" ""
			(at 0 0 0)
			(layer "B.Fab")
			(effects
				(font
					(size 1.27 1.27)
				)
				(justify mirror)
			)
		)
		(duplicate_pad_numbers_are_jumpers no)
		(fp_line
			(start 0.7874 0.4064)
			(end 0.7874 -0.4064)
			(stroke
				(width 0.1524)
				(type default)
			)
			(layer "B.SilkS")
		)
		(fp_line
			(start 0.7874 -0.4064)
			(end -0.7874 -0.4064)
			(stroke
				(width 0.1524)
				(type default)
			)
			(layer "B.SilkS")
		)
		(fp_line
			(start -0.7874 0.4064)
			(end 0.7874 0.4064)
			(stroke
				(width 0.1524)
				(type default)
			)
			(layer "B.SilkS")
		)
		(fp_line
			(start -0.7874 -0.4064)
			(end -0.7874 0.4064)
			(stroke
				(width 0.1524)
				(type default)
			)
			(layer "B.SilkS")
		)
		(fp_line
			(start 0.67945 0.3048)
			(end 0.67945 -0.305054)
			(stroke
				(width 0.1)
				(type default)
			)
			(layer "B.Fab")
		)
		(fp_line
			(start 0.67945 -0.305054)
			(end 0.12065 -0.305054)
			(stroke
				(width 0.1)
				(type default)
			)
			(layer "B.Fab")
		)
		(fp_line
			(start 0.12065 0.3048)
			(end 0.67945 0.3048)
			(stroke
				(width 0.1)
				(type default)
			)
			(layer "B.Fab")
		)
		(fp_line
			(start 0.12065 0.2794)
			(end 0.12065 0.3048)
			(stroke
				(width 0.1)
				(type default)
			)
			(layer "B.Fab")
		)
		(fp_line
			(start 0.12065 -0.2794)
			(end -0.12065 -0.2794)
			(stroke
				(width 0.1)
				(type default)
			)
			(layer "B.Fab")
		)
		(fp_line
			(start 0.12065 -0.305054)
			(end 0.12065 -0.2794)
			(stroke
				(width 0.1)
				(type default)
			)
			(layer "B.Fab")
		)
		(fp_line
			(start -0.120396 0.3048)
			(end -0.120396 0.2794)
			(stroke
				(width 0.1)
				(type default)
			)
			(layer "B.Fab")
		)
		(fp_line
			(start -0.120396 0.2794)
			(end 0.12065 0.2794)
			(stroke
				(width 0.1)
				(type default)
			)
			(layer "B.Fab")
		)
		(fp_line
			(start -0.12065 -0.2794)
			(end -0.12065 -0.3048)
			(stroke
				(width 0.1)
				(type default)
			)
			(layer "B.Fab")
		)
		(fp_line
			(start -0.12065 -0.3048)
			(end -0.67945 -0.3048)
			(stroke
				(width 0.1)
				(type default)
			)
			(layer "B.Fab")
		)
		(fp_line
			(start -0.67945 0.3048)
			(end -0.120396 0.3048)
			(stroke
				(width 0.1)
				(type default)
			)
			(layer "B.Fab")
		)
		(fp_line
			(start -0.67945 -0.3048)
			(end -0.67945 0.3048)
			(stroke
				(width 0.1)
				(type default)
			)
			(layer "B.Fab")
		)
		(pad "1" smd circle
			(at 0.40005 0)
			(size 0 0)
			(layers "B.Cu" "B.Mask" "B.Paste")
			(net "P12V_HSC_GATE2")
		)
		(pad "2" smd circle
			(at -0.40005 0)
			(size 0 0)
			(layers "B.Cu" "B.Mask" "B.Paste")
			(net "HS_GATE2_R_3")
		)
	)
	(footprint ""
		(layer "B.Cu")
		(at 51.099974 -292.099746 90)
		(property "Reference" "C1185"
			(at 0 0 90)
			(layer "B.SilkS")
			(hide yes)
			(effects
				(font
					(size 1.27 1.27)
				)
				(justify mirror)
			)
		)
		(property "Value" ""
			(at 0 0 90)
			(layer "B.Fab")
			(effects
				(font
					(size 1.27 1.27)
				)
				(justify mirror)
			)
		)
		(duplicate_pad_numbers_are_jumpers no)
		(fp_line
			(start 0.299974 -0.150114)
			(end -0.299974 -0.150114)
			(stroke
				(width 0.1)
				(type default)
			)
			(layer "B.Fab")
		)
		(fp_line
			(start -0.299974 -0.150114)
			(end -0.299974 0.150114)
			(stroke
				(width 0.1)
				(type default)
			)
			(layer "B.Fab")
		)
		(fp_line
			(start 0.299974 0.150114)
			(end 0.299974 -0.150114)
			(stroke
				(width 0.1)
				(type default)
			)
			(layer "B.Fab")
		)
		(fp_line
			(start -0.299974 0.150114)
			(end 0.299974 0.150114)
			(stroke
				(width 0.1)
				(type default)
			)
			(layer "B.Fab")
		)
		(pad "1" smd rect
			(at 0.2667 0 270)
			(size 0.3048 0.381)
			(layers "B.Cu" "B.Mask" "B.Paste")
			(net "P0V8_SERDES_VDDA_PEX0")
		)
		(pad "2" smd rect
			(at -0.2667 0 270)
			(size 0.3048 0.381)
			(layers "B.Cu" "B.Mask" "B.Paste")
			(net "GND")
		)
	)
	(footprint ""
		(layer "B.Cu")
		(at 358.278684 -282.040584 90)
		(property "Reference" "PR158"
			(at 0 0 90)
			(layer "B.SilkS")
			(hide yes)
			(effects
				(font
					(size 1.27 1.27)
				)
				(justify mirror)
			)
		)
		(property "Value" ""
			(at 0 0 90)
			(layer "B.Fab")
			(effects
				(font
					(size 1.27 1.27)
				)
				(justify mirror)
			)
		)
		(duplicate_pad_numbers_are_jumpers no)
		(fp_line
			(start 0.7874 -0.4064)
			(end -0.7874 -0.4064)
			(stroke
				(width 0.1524)
				(type default)
			)
			(layer "B.SilkS")
		)
		(fp_line
			(start -0.7874 -0.4064)
			(end -0.7874 0.4064)
			(stroke
				(width 0.1524)
				(type default)
			)
			(layer "B.SilkS")
		)
		(fp_line
			(start 0.7874 0.4064)
			(end 0.7874 -0.4064)
			(stroke
				(width 0.1524)
				(type default)
			)
			(layer "B.SilkS")
		)
		(fp_line
			(start -0.7874 0.4064)
			(end 0.7874 0.4064)
			(stroke
				(width 0.1524)
				(type default)
			)
			(layer "B.SilkS")
		)
		(fp_line
			(start 0.67945 -0.305054)
			(end 0.12065 -0.305054)
			(stroke
				(width 0.1)
				(type default)
			)
			(layer "B.Fab")
		)
		(fp_line
			(start 0.12065 -0.305054)
			(end 0.12065 -0.2794)
			(stroke
				(width 0.1)
				(type default)
			)
			(layer "B.Fab")
		)
		(fp_line
			(start -0.12065 -0.3048)
			(end -0.67945 -0.3048)
			(stroke
				(width 0.1)
				(type default)
			)
			(layer "B.Fab")
		)
		(fp_line
			(start -0.67945 -0.3048)
			(end -0.67945 0.3048)
			(stroke
				(width 0.1)
				(type default)
			)
			(layer "B.Fab")
		)
		(fp_line
			(start 0.12065 -0.2794)
			(end -0.12065 -0.2794)
			(stroke
				(width 0.1)
				(type default)
			)
			(layer "B.Fab")
		)
		(fp_line
			(start -0.12065 -0.2794)
			(end -0.12065 -0.3048)
			(stroke
				(width 0.1)
				(type default)
			)
			(layer "B.Fab")
		)
		(fp_line
			(start 0.12065 0.2794)
			(end 0.12065 0.3048)
			(stroke
				(width 0.1)
				(type default)
			)
			(layer "B.Fab")
		)
		(fp_line
			(start -0.120396 0.2794)
			(end 0.12065 0.2794)
			(stroke
				(width 0.1)
				(type default)
			)
			(layer "B.Fab")
		)
		(fp_line
			(start 0.67945 0.3048)
			(end 0.67945 -0.305054)
			(stroke
				(width 0.1)
				(type default)
			)
			(layer "B.Fab")
		)
		(fp_line
			(start 0.12065 0.3048)
			(end 0.67945 0.3048)
			(stroke
				(width 0.1)
				(type default)
			)
			(layer "B.Fab")
		)
		(fp_line
			(start -0.120396 0.3048)
			(end -0.120396 0.2794)
			(stroke
				(width 0.1)
				(type default)
			)
			(layer "B.Fab")
		)
		(fp_line
			(start -0.67945 0.3048)
			(end -0.120396 0.3048)
			(stroke
				(width 0.1)
				(type default)
			)
			(layer "B.Fab")
		)
		(pad "1" smd circle
			(at 0.40005 0 270)
			(size 0 0)
			(layers "B.Cu" "B.Mask" "B.Paste")
			(net "SW_P0V8_PEX3_VOS1")
		)
		(pad "2" smd circle
			(at -0.40005 0 270)
			(size 0 0)
			(layers "B.Cu" "B.Mask" "B.Paste")
			(net "P0V8_PEX3")
		)
	)
	(footprint ""
		(layer "B.Cu")
		(at 286.149796 -303.499774 -90)
		(property "Reference" "C3261"
			(at 0 0 90)
			(layer "B.SilkS")
			(hide yes)
			(effects
				(font
					(size 1.27 1.27)
				)
				(justify mirror)
			)
		)
		(property "Value" ""
			(at 0 0 90)
			(layer "B.Fab")
			(effects
				(font
					(size 1.27 1.27)
				)
				(justify mirror)
			)
		)
		(duplicate_pad_numbers_are_jumpers no)
		(fp_line
			(start -0.299974 0.150114)
			(end 0.299974 0.150114)
			(stroke
				(width 0.1)
				(type default)
			)
			(layer "B.Fab")
		)
		(fp_line
			(start 0.299974 0.150114)
			(end 0.299974 -0.150114)
			(stroke
				(width 0.1)
				(type default)
			)
			(layer "B.Fab")
		)
		(fp_line
			(start -0.299974 -0.150114)
			(end -0.299974 0.150114)
			(stroke
				(width 0.1)
				(type default)
			)
			(layer "B.Fab")
		)
		(fp_line
			(start 0.299974 -0.150114)
			(end -0.299974 -0.150114)
			(stroke
				(width 0.1)
				(type default)
			)
			(layer "B.Fab")
		)
		(pad "1" smd rect
			(at 0.2667 0 90)
			(size 0.3048 0.381)
			(layers "B.Cu" "B.Mask" "B.Paste")
			(net "P1V25_PEX2")
		)
		(pad "2" smd rect
			(at -0.2667 0 90)
			(size 0.3048 0.381)
			(layers "B.Cu" "B.Mask" "B.Paste")
			(net "GND")
		)
	)
	(footprint ""
		(layer "B.Cu")
		(at 327.78827 -227.943664 180)
		(property "Reference" "R5641"
			(at 0 0 0)
			(layer "B.SilkS")
			(hide yes)
			(effects
				(font
					(size 1.27 1.27)
				)
				(justify mirror)
			)
		)
		(property "Value" ""
			(at 0 0 0)
			(layer "B.Fab")
			(effects
				(font
					(size 1.27 1.27)
				)
				(justify mirror)
			)
		)
		(duplicate_pad_numbers_are_jumpers no)
		(fp_line
			(start 1.2954 0.5842)
			(end 1.2954 -0.5842)
			(stroke
				(width 0.1524)
				(type default)
			)
			(layer "B.SilkS")
		)
		(fp_line
			(start 1.2954 -0.5842)
			(end -1.2954 -0.5842)
			(stroke
				(width 0.1524)
				(type default)
			)
			(layer "B.SilkS")
		)
		(fp_line
			(start -1.2954 0.5842)
			(end 1.2954 0.5842)
			(stroke
				(width 0.1524)
				(type default)
			)
			(layer "B.SilkS")
		)
		(fp_line
			(start -1.2954 -0.5842)
			(end -1.2954 0.5842)
			(stroke
				(width 0.1524)
				(type default)
			)
			(layer "B.SilkS")
		)
		(fp_line
			(start 1.1938 0.4064)
			(end 1.1938 -0.406654)
			(stroke
				(width 0.1)
				(type default)
			)
			(layer "B.Fab")
		)
		(fp_line
			(start 1.1938 -0.406654)
			(end 0.8636 -0.406654)
			(stroke
				(width 0.1)
				(type default)
			)
			(layer "B.Fab")
		)
		(fp_line
			(start 0.8636 0.4572)
			(end 0.8636 0.4318)
			(stroke
				(width 0.1)
				(type default)
			)
			(layer "B.Fab")
		)
		(fp_line
			(start 0.8636 0.4318)
			(end 0.8636 0.4064)
			(stroke
				(width 0.1)
				(type default)
			)
			(layer "B.Fab")
		)
		(fp_line
			(start 0.8636 0.4064)
			(end 1.1938 0.4064)
			(stroke
				(width 0.1)
				(type default)
			)
			(layer "B.Fab")
		)
		(fp_line
			(start 0.8636 -0.406654)
			(end 0.8636 -0.4572)
			(stroke
				(width 0.1)
				(type default)
			)
			(layer "B.Fab")
		)
		(fp_line
			(start 0.8636 -0.4572)
			(end -0.8636 -0.4572)
			(stroke
				(width 0.1)
				(type default)
			)
			(layer "B.Fab")
		)
		(fp_line
			(start -0.8636 0.4572)
			(end 0.8636 0.4572)
			(stroke
				(width 0.1)
				(type default)
			)
			(layer "B.Fab")
		)
		(fp_line
			(start -0.8636 0.4064)
			(end -0.8636 0.4572)
			(stroke
				(width 0.1)
				(type default)
			)
			(layer "B.Fab")
		)
		(fp_line
			(start -0.8636 -0.406654)
			(end -1.1938 -0.406654)
			(stroke
				(width 0.1)
				(type default)
			)
			(layer "B.Fab")
		)
		(fp_line
			(start -0.8636 -0.4572)
			(end -0.8636 -0.406654)
			(stroke
				(width 0.1)
				(type default)
			)
			(layer "B.Fab")
		)
		(fp_line
			(start -1.1938 0.4064)
			(end -0.8636 0.4064)
			(stroke
				(width 0.1)
				(type default)
			)
			(layer "B.Fab")
		)
		(fp_line
			(start -1.1938 -0.406654)
			(end -1.1938 0.4064)
			(stroke
				(width 0.1)
				(type default)
			)
			(layer "B.Fab")
		)
		(pad "1" smd rect
			(at 0.7366 0 90)
			(size 0.7112 0.8128)
			(layers "B.Cu" "B.Mask" "B.Paste")
			(net "P3V3_AUX")
		)
		(pad "2" smd rect
			(at -0.7366 0 90)
			(size 0.7112 0.8128)
			(layers "B.Cu" "B.Mask" "B.Paste")
			(net "P3V3_FPGA_VCCIO5")
		)
	)
	(footprint ""
		(layer "B.Cu")
		(at 62.180216 -295.221914)
		(property "Reference" "C1102"
			(at 0 0 0)
			(layer "B.SilkS")
			(hide yes)
			(effects
				(font
					(size 1.27 1.27)
				)
				(justify mirror)
			)
		)
		(property "Value" ""
			(at 0 0 0)
			(layer "B.Fab")
			(effects
				(font
					(size 1.27 1.27)
				)
				(justify mirror)
			)
		)
		(duplicate_pad_numbers_are_jumpers no)
		(fp_line
			(start -1.2954 -0.5842)
			(end -1.2954 0.5842)
			(stroke
				(width 0.1524)
				(type default)
			)
			(layer "B.SilkS")
		)
		(fp_line
			(start -1.2954 0.5842)
			(end 1.2954 0.5842)
			(stroke
				(width 0.1524)
				(type default)
			)
			(layer "B.SilkS")
		)
		(fp_line
			(start 1.2954 -0.5842)
			(end -1.2954 -0.5842)
			(stroke
				(width 0.1524)
				(type default)
			)
			(layer "B.SilkS")
		)
		(fp_line
			(start 1.2954 0.5842)
			(end 1.2954 -0.5842)
			(stroke
				(width 0.1524)
				(type default)
			)
			(layer "B.SilkS")
		)
		(fp_line
			(start -1.1938 -0.4064)
			(end -1.1938 0.4064)
			(stroke
				(width 0.1)
				(type default)
			)
			(layer "B.Fab")
		)
		(fp_line
			(start -1.1938 0.4064)
			(end -0.8636 0.4064)
			(stroke
				(width 0.1)
				(type default)
			)
			(layer "B.Fab")
		)
		(fp_line
			(start -0.8636 -0.4572)
			(end -0.8636 -0.4064)
			(stroke
				(width 0.1)
				(type default)
			)
			(layer "B.Fab")
		)
		(fp_line
			(start -0.8636 -0.4064)
			(end -1.1938 -0.4064)
			(stroke
				(width 0.1)
				(type default)
			)
			(layer "B.Fab")
		)
		(fp_line
			(start -0.8636 0.4064)
			(end -0.8636 0.4572)
			(stroke
				(width 0.1)
				(type default)
			)
			(layer "B.Fab")
		)
		(fp_line
			(start -0.8636 0.4572)
			(end 0.8636 0.4572)
			(stroke
				(width 0.1)
				(type default)
			)
			(layer "B.Fab")
		)
		(fp_line
			(start 0.8636 -0.4572)
			(end -0.8636 -0.4572)
			(stroke
				(width 0.1)
				(type default)
			)
			(layer "B.Fab")
		)
		(fp_line
			(start 0.8636 -0.4064)
			(end 0.8636 -0.4572)
			(stroke
				(width 0.1)
				(type default)
			)
			(layer "B.Fab")
		)
		(fp_line
			(start 0.8636 0.4064)
			(end 1.1938 0.4064)
			(stroke
				(width 0.1)
				(type default)
			)
			(layer "B.Fab")
		)
		(fp_line
			(start 0.8636 0.4572)
			(end 0.8636 0.4064)
			(stroke
				(width 0.1)
				(type default)
			)
			(layer "B.Fab")
		)
		(fp_line
			(start 1.1938 -0.4064)
			(end 0.8636 -0.4064)
			(stroke
				(width 0.1)
				(type default)
			)
			(layer "B.Fab")
		)
		(fp_line
			(start 1.1938 0.4064)
			(end 1.1938 -0.4064)
			(stroke
				(width 0.1)
				(type default)
			)
			(layer "B.Fab")
		)
		(pad "1" smd rect
			(at 0.7366 0 270)
			(size 0.7112 0.8128)
			(layers "B.Cu" "B.Mask" "B.Paste")
			(net "P0V8_PEX0")
		)
		(pad "2" smd rect
			(at -0.7366 0 270)
			(size 0.7112 0.8128)
			(layers "B.Cu" "B.Mask" "B.Paste")
			(net "GND")
		)
	)
	(footprint ""
		(layer "B.Cu")
		(at 51.099974 -303.499774 -90)
		(property "Reference" "C2914"
			(at 0 0 90)
			(layer "B.SilkS")
			(hide yes)
			(effects
				(font
					(size 1.27 1.27)
				)
				(justify mirror)
			)
		)
		(property "Value" ""
			(at 0 0 90)
			(layer "B.Fab")
			(effects
				(font
					(size 1.27 1.27)
				)
				(justify mirror)
			)
		)
		(duplicate_pad_numbers_are_jumpers no)
		(fp_line
			(start -0.299974 0.150114)
			(end 0.299974 0.150114)
			(stroke
				(width 0.1)
				(type default)
			)
			(layer "B.Fab")
		)
		(fp_line
			(start 0.299974 0.150114)
			(end 0.299974 -0.150114)
			(stroke
				(width 0.1)
				(type default)
			)
			(layer "B.Fab")
		)
		(fp_line
			(start -0.299974 -0.150114)
			(end -0.299974 0.150114)
			(stroke
				(width 0.1)
				(type default)
			)
			(layer "B.Fab")
		)
		(fp_line
			(start 0.299974 -0.150114)
			(end -0.299974 -0.150114)
			(stroke
				(width 0.1)
				(type default)
			)
			(layer "B.Fab")
		)
		(pad "1" smd rect
			(at 0.2667 0 90)
			(size 0.3048 0.381)
			(layers "B.Cu" "B.Mask" "B.Paste")
			(net "P1V25_PEX0")
		)
		(pad "2" smd rect
			(at -0.2667 0 90)
			(size 0.3048 0.381)
			(layers "B.Cu" "B.Mask" "B.Paste")
			(net "GND")
		)
	)
	(footprint ""
		(layer "B.Cu")
		(at 105.265474 -337.402932 90)
		(property "Reference" "R1231"
			(at 0 0 90)
			(layer "B.SilkS")
			(hide yes)
			(effects
				(font
					(size 1.27 1.27)
				)
				(justify mirror)
			)
		)
		(property "Value" ""
			(at 0 0 90)
			(layer "B.Fab")
			(effects
				(font
					(size 1.27 1.27)
				)
				(justify mirror)
			)
		)
		(duplicate_pad_numbers_are_jumpers no)
		(fp_line
			(start 0.7874 -0.4064)
			(end -0.7874 -0.4064)
			(stroke
				(width 0.1524)
				(type default)
			)
			(layer "B.SilkS")
		)
		(fp_line
			(start -0.7874 -0.4064)
			(end -0.7874 0.4064)
			(stroke
				(width 0.1524)
				(type default)
			)
			(layer "B.SilkS")
		)
		(fp_line
			(start 0.7874 0.4064)
			(end 0.7874 -0.4064)
			(stroke
				(width 0.1524)
				(type default)
			)
			(layer "B.SilkS")
		)
		(fp_line
			(start -0.7874 0.4064)
			(end 0.7874 0.4064)
			(stroke
				(width 0.1524)
				(type default)
			)
			(layer "B.SilkS")
		)
		(fp_line
			(start 0.67945 -0.305054)
			(end 0.12065 -0.305054)
			(stroke
				(width 0.1)
				(type default)
			)
			(layer "B.Fab")
		)
		(fp_line
			(start 0.12065 -0.305054)
			(end 0.12065 -0.2794)
			(stroke
				(width 0.1)
				(type default)
			)
			(layer "B.Fab")
		)
		(fp_line
			(start -0.12065 -0.3048)
			(end -0.67945 -0.3048)
			(stroke
				(width 0.1)
				(type default)
			)
			(layer "B.Fab")
		)
		(fp_line
			(start -0.67945 -0.3048)
			(end -0.67945 0.3048)
			(stroke
				(width 0.1)
				(type default)
			)
			(layer "B.Fab")
		)
		(fp_line
			(start 0.12065 -0.2794)
			(end -0.12065 -0.2794)
			(stroke
				(width 0.1)
				(type default)
			)
			(layer "B.Fab")
		)
		(fp_line
			(start -0.12065 -0.2794)
			(end -0.12065 -0.3048)
			(stroke
				(width 0.1)
				(type default)
			)
			(layer "B.Fab")
		)
		(fp_line
			(start 0.12065 0.2794)
			(end 0.12065 0.3048)
			(stroke
				(width 0.1)
				(type default)
			)
			(layer "B.Fab")
		)
		(fp_line
			(start -0.120396 0.2794)
			(end 0.12065 0.2794)
			(stroke
				(width 0.1)
				(type default)
			)
			(layer "B.Fab")
		)
		(fp_line
			(start 0.67945 0.3048)
			(end 0.67945 -0.305054)
			(stroke
				(width 0.1)
				(type default)
			)
			(layer "B.Fab")
		)
		(fp_line
			(start 0.12065 0.3048)
			(end 0.67945 0.3048)
			(stroke
				(width 0.1)
				(type default)
			)
			(layer "B.Fab")
		)
		(fp_line
			(start -0.120396 0.3048)
			(end -0.120396 0.2794)
			(stroke
				(width 0.1)
				(type default)
			)
			(layer "B.Fab")
		)
		(fp_line
			(start -0.67945 0.3048)
			(end -0.120396 0.3048)
			(stroke
				(width 0.1)
				(type default)
			)
			(layer "B.Fab")
		)
		(pad "1" smd circle
			(at 0.40005 0 270)
			(size 0 0)
			(layers "B.Cu" "B.Mask" "B.Paste")
			(net "CLK_100M_DB800ZL_PEX3_S0_R_DP")
		)
		(pad "2" smd circle
			(at -0.40005 0 270)
			(size 0 0)
			(layers "B.Cu" "B.Mask" "B.Paste")
			(net "CLK_100M_DB800ZL_PEX3_S0_DP")
		)
	)
	(footprint ""
		(layer "B.Cu")
		(at 302.044354 -229.370636 90)
		(property "Reference" "U309"
			(at -1.453896 2.279904 270)
			(unlocked yes)
			(layer "B.SilkS")
			(effects
				(font
					(size 0.7874 0.5842)
					(thickness 0.1524)
				)
				(justify left mirror)
			)
		)
		(property "Value" ""
			(at 0 0 90)
			(layer "B.Fab")
			(effects
				(font
					(size 1.27 1.27)
				)
				(justify mirror)
			)
		)
		(duplicate_pad_numbers_are_jumpers no)
		(fp_line
			(start 1.0414 -1.575054)
			(end 0.254 -1.575054)
			(stroke
				(width 0.1524)
				(type default)
			)
			(layer "B.SilkS")
		)
		(fp_line
			(start -0.2286 -1.575054)
			(end 0 -1.272032)
			(stroke
				(width 0.1524)
				(type default)
			)
			(layer "B.SilkS")
		)
		(fp_line
			(start -0.254 -1.575054)
			(end -1.0414 -1.575054)
			(stroke
				(width 0.1524)
				(type default)
			)
			(layer "B.SilkS")
		)
		(fp_line
			(start -1.0414 -1.575054)
			(end -1.0414 1.575054)
			(stroke
				(width 0.1524)
				(type default)
			)
			(layer "B.SilkS")
		)
		(fp_line
			(start 0 -1.272032)
			(end 0.254 -1.575054)
			(stroke
				(width 0.1524)
				(type default)
			)
			(layer "B.SilkS")
		)
		(fp_line
			(start 1.0414 1.575054)
			(end 1.0414 -1.575054)
			(stroke
				(width 0.1524)
				(type default)
			)
			(layer "B.SilkS")
		)
		(fp_line
			(start -1.0414 1.575054)
			(end 1.0414 1.575054)
			(stroke
				(width 0.1524)
				(type default)
			)
			(layer "B.SilkS")
		)
		(fp_poly
			(pts
				(xy 2.710688 -1.209294) (xy 3.726688 -1.717294) (xy 3.726688 -0.701294)
			)
			(stroke
				(width 0)
				(type default)
			)
			(fill yes)
			(layer "B.SilkS")
		)
		(fp_line
			(start 1.4478 -1.5748)
			(end -1.4478 -1.5748)
			(stroke
				(width 0.1)
				(type default)
			)
			(layer "B.Fab")
		)
		(fp_line
			(start -1.4478 -1.5748)
			(end -1.4478 -1.2192)
			(stroke
				(width 0.1)
				(type default)
			)
			(layer "B.Fab")
		)
		(fp_line
			(start 2.5654 -1.2192)
			(end 1.4478 -1.2192)
			(stroke
				(width 0.1)
				(type default)
			)
			(layer "B.Fab")
		)
		(fp_line
			(start 1.4478 -1.2192)
			(end 1.4478 -1.5748)
			(stroke
				(width 0.1)
				(type default)
			)
			(layer "B.Fab")
		)
		(fp_line
			(start -1.4478 -1.2192)
			(end -2.5654 -1.2192)
			(stroke
				(width 0.1)
				(type default)
			)
			(layer "B.Fab")
		)
		(fp_line
			(start -2.5654 -1.2192)
			(end -2.5654 1.2192)
			(stroke
				(width 0.1)
				(type default)
			)
			(layer "B.Fab")
		)
		(fp_line
			(start 2.5654 1.2192)
			(end 2.5654 -1.2192)
			(stroke
				(width 0.1)
				(type default)
			)
			(layer "B.Fab")
		)
		(fp_line
			(start 1.4478 1.2192)
			(end 2.5654 1.2192)
			(stroke
				(width 0.1)
				(type default)
			)
			(layer "B.Fab")
		)
		(fp_line
			(start -1.4478 1.2192)
			(end -1.4478 1.5748)
			(stroke
				(width 0.1)
				(type default)
			)
			(layer "B.Fab")
		)
		(fp_line
			(start -2.5654 1.2192)
			(end -1.4478 1.2192)
			(stroke
				(width 0.1)
				(type default)
			)
			(layer "B.Fab")
		)
		(fp_line
			(start 1.4478 1.5748)
			(end 1.4478 1.2192)
			(stroke
				(width 0.1)
				(type default)
			)
			(layer "B.Fab")
		)
		(fp_line
			(start -1.4478 1.5748)
			(end 1.4478 1.5748)
			(stroke
				(width 0.1)
				(type default)
			)
			(layer "B.Fab")
		)
		(fp_poly
			(pts
				(xy 2.710688 -0.975106) (xy 3.726688 -1.483106) (xy 3.726688 -0.467106)
			)
			(stroke
				(width 0)
				(type default)
			)
			(fill yes)
			(layer "B.Fab")
		)
		(pad "1" smd rect
			(at 1.849882 -0.975106)
			(size 0.3556 1.3208)
			(layers "B.Cu" "B.Mask" "B.Paste")
			(net "RST_GPU_PERST_0_R_N")
		)
		(pad "2" smd rect
			(at 1.849882 -0.32512)
			(size 0.3556 1.3208)
			(layers "B.Cu" "B.Mask" "B.Paste")
			(net "RST_GPU_PERST_2_BUF_N")
		)
		(pad "3" smd rect
			(at 1.849882 0.32512)
			(size 0.3556 1.3208)
			(layers "B.Cu" "B.Mask" "B.Paste")
			(net "RST_GPU_PERST_1_R_N")
		)
		(pad "4" smd rect
			(at 1.849882 0.975106)
			(size 0.3556 1.3208)
			(layers "B.Cu" "B.Mask" "B.Paste")
			(net "GND")
		)
		(pad "5" smd rect
			(at -1.849882 0.975106)
			(size 0.3556 1.3208)
			(layers "B.Cu" "B.Mask" "B.Paste")
			(net "RST_GPU_PERST_1_BUF_N")
		)
		(pad "6" smd rect
			(at -1.849882 0.32512)
			(size 0.3556 1.3208)
			(layers "B.Cu" "B.Mask" "B.Paste")
			(net "RST_GPU_PERST_2_R_N")
		)
		(pad "7" smd rect
			(at -1.849882 -0.32512)
			(size 0.3556 1.3208)
			(layers "B.Cu" "B.Mask" "B.Paste")
			(net "RST_GPU_PERST_0_BUF_N")
		)
		(pad "8" smd rect
			(at -1.849882 -0.975106)
			(size 0.3556 1.3208)
			(layers "B.Cu" "B.Mask" "B.Paste")
			(net "P3V3_AUX")
		)
	)
	(footprint ""
		(layer "B.Cu")
		(at 165.655244 -155.0416)
		(property "Reference" "R129"
			(at 0 0 0)
			(layer "B.SilkS")
			(hide yes)
			(effects
				(font
					(size 1.27 1.27)
				)
				(justify mirror)
			)
		)
		(property "Value" ""
			(at 0 0 0)
			(layer "B.Fab")
			(effects
				(font
					(size 1.27 1.27)
				)
				(justify mirror)
			)
		)
		(duplicate_pad_numbers_are_jumpers no)
		(fp_line
			(start -0.7874 -0.4064)
			(end -0.7874 0.4064)
			(stroke
				(width 0.1524)
				(type default)
			)
			(layer "B.SilkS")
		)
		(fp_line
			(start -0.7874 0.4064)
			(end 0.7874 0.4064)
			(stroke
				(width 0.1524)
				(type default)
			)
			(layer "B.SilkS")
		)
		(fp_line
			(start 0.7874 -0.4064)
			(end -0.7874 -0.4064)
			(stroke
				(width 0.1524)
				(type default)
			)
			(layer "B.SilkS")
		)
		(fp_line
			(start 0.7874 0.4064)
			(end 0.7874 -0.4064)
			(stroke
				(width 0.1524)
				(type default)
			)
			(layer "B.SilkS")
		)
		(fp_line
			(start -0.67945 -0.3048)
			(end -0.67945 0.3048)
			(stroke
				(width 0.1)
				(type default)
			)
			(layer "B.Fab")
		)
		(fp_line
			(start -0.67945 0.3048)
			(end -0.120396 0.3048)
			(stroke
				(width 0.1)
				(type default)
			)
			(layer "B.Fab")
		)
		(fp_line
			(start -0.12065 -0.3048)
			(end -0.67945 -0.3048)
			(stroke
				(width 0.1)
				(type default)
			)
			(layer "B.Fab")
		)
		(fp_line
			(start -0.12065 -0.2794)
			(end -0.12065 -0.3048)
			(stroke
				(width 0.1)
				(type default)
			)
			(layer "B.Fab")
		)
		(fp_line
			(start -0.120396 0.2794)
			(end 0.12065 0.2794)
			(stroke
				(width 0.1)
				(type default)
			)
			(layer "B.Fab")
		)
		(fp_line
			(start -0.120396 0.3048)
			(end -0.120396 0.2794)
			(stroke
				(width 0.1)
				(type default)
			)
			(layer "B.Fab")
		)
		(fp_line
			(start 0.12065 -0.305054)
			(end 0.12065 -0.2794)
			(stroke
				(width 0.1)
				(type default)
			)
			(layer "B.Fab")
		)
		(fp_line
			(start 0.12065 -0.2794)
			(end -0.12065 -0.2794)
			(stroke
				(width 0.1)
				(type default)
			)
			(layer "B.Fab")
		)
		(fp_line
			(start 0.12065 0.2794)
			(end 0.12065 0.3048)
			(stroke
				(width 0.1)
				(type default)
			)
			(layer "B.Fab")
		)
		(fp_line
			(start 0.12065 0.3048)
			(end 0.67945 0.3048)
			(stroke
				(width 0.1)
				(type default)
			)
			(layer "B.Fab")
		)
		(fp_line
			(start 0.67945 -0.305054)
			(end 0.12065 -0.305054)
			(stroke
				(width 0.1)
				(type default)
			)
			(layer "B.Fab")
		)
		(fp_line
			(start 0.67945 0.3048)
			(end 0.67945 -0.305054)
			(stroke
				(width 0.1)
				(type default)
			)
			(layer "B.Fab")
		)
		(pad "1" smd circle
			(at 0.40005 0 180)
			(size 0 0)
			(layers "B.Cu" "B.Mask" "B.Paste")
			(net "NIC2_SLOT_ID1")
		)
		(pad "2" smd circle
			(at -0.40005 0 180)
			(size 0 0)
			(layers "B.Cu" "B.Mask" "B.Paste")
			(net "P3V3_NIC2")
		)
	)
	(footprint ""
		(layer "B.Cu")
		(at 351.787968 -284.796738 -90)
		(property "Reference" "PC173"
			(at 0 0 90)
			(layer "B.SilkS")
			(hide yes)
			(effects
				(font
					(size 1.27 1.27)
				)
				(justify mirror)
			)
		)
		(property "Value" ""
			(at 0 0 90)
			(layer "B.Fab")
			(effects
				(font
					(size 1.27 1.27)
				)
				(justify mirror)
			)
		)
		(duplicate_pad_numbers_are_jumpers no)
		(fp_line
			(start -1.524 0.762)
			(end 1.524 0.762)
			(stroke
				(width 0.1524)
				(type default)
			)
			(layer "B.SilkS")
		)
		(fp_line
			(start 1.524 0.762)
			(end 1.524 -0.762)
			(stroke
				(width 0.1524)
				(type default)
			)
			(layer "B.SilkS")
		)
		(fp_line
			(start -1.524 -0.762)
			(end -1.524 0.762)
			(stroke
				(width 0.1524)
				(type default)
			)
			(layer "B.SilkS")
		)
		(fp_line
			(start 1.524 -0.762)
			(end -1.524 -0.762)
			(stroke
				(width 0.1524)
				(type default)
			)
			(layer "B.SilkS")
		)
		(fp_line
			(start -1.1049 0.724916)
			(end -1.1049 -0.724916)
			(stroke
				(width 0.1)
				(type default)
			)
			(layer "B.Fab")
		)
		(fp_line
			(start 1.1049 0.724916)
			(end -1.1049 0.724916)
			(stroke
				(width 0.1)
				(type default)
			)
			(layer "B.Fab")
		)
		(fp_line
			(start -1.1049 -0.724916)
			(end 1.1049 -0.724916)
			(stroke
				(width 0.1)
				(type default)
			)
			(layer "B.Fab")
		)
		(fp_line
			(start 1.1049 -0.724916)
			(end 1.1049 0.724916)
			(stroke
				(width 0.1)
				(type default)
			)
			(layer "B.Fab")
		)
		(pad "1" smd rect
			(at 0.889 0 270)
			(size 1.016 1.27)
			(layers "B.Cu" "B.Mask" "B.Paste")
			(net "SW_P12V_P0V8_PEX3_FLT")
		)
		(pad "2" smd rect
			(at -0.889 0 270)
			(size 1.016 1.27)
			(layers "B.Cu" "B.Mask" "B.Paste")
			(net "GND")
		)
	)
	(footprint ""
		(layer "B.Cu")
		(at 296.599864 -288.299906 90)
		(property "Reference" "C3275"
			(at 0 0 90)
			(layer "B.SilkS")
			(hide yes)
			(effects
				(font
					(size 1.27 1.27)
				)
				(justify mirror)
			)
		)
		(property "Value" ""
			(at 0 0 90)
			(layer "B.Fab")
			(effects
				(font
					(size 1.27 1.27)
				)
				(justify mirror)
			)
		)
		(duplicate_pad_numbers_are_jumpers no)
		(fp_line
			(start 0.299974 -0.150114)
			(end -0.299974 -0.150114)
			(stroke
				(width 0.1)
				(type default)
			)
			(layer "B.Fab")
		)
		(fp_line
			(start -0.299974 -0.150114)
			(end -0.299974 0.150114)
			(stroke
				(width 0.1)
				(type default)
			)
			(layer "B.Fab")
		)
		(fp_line
			(start 0.299974 0.150114)
			(end 0.299974 -0.150114)
			(stroke
				(width 0.1)
				(type default)
			)
			(layer "B.Fab")
		)
		(fp_line
			(start -0.299974 0.150114)
			(end 0.299974 0.150114)
			(stroke
				(width 0.1)
				(type default)
			)
			(layer "B.Fab")
		)
		(pad "1" smd rect
			(at 0.2667 0 270)
			(size 0.3048 0.381)
			(layers "B.Cu" "B.Mask" "B.Paste")
			(net "P1V25_PEX2")
		)
		(pad "2" smd rect
			(at -0.2667 0 270)
			(size 0.3048 0.381)
			(layers "B.Cu" "B.Mask" "B.Paste")
			(net "GND")
		)
	)
	(footprint ""
		(layer "B.Cu")
		(at 409.849828 -301.599854 -90)
		(property "Reference" "C2002"
			(at 0 0 90)
			(layer "B.SilkS")
			(hide yes)
			(effects
				(font
					(size 1.27 1.27)
				)
				(justify mirror)
			)
		)
		(property "Value" ""
			(at 0 0 90)
			(layer "B.Fab")
			(effects
				(font
					(size 1.27 1.27)
				)
				(justify mirror)
			)
		)
		(duplicate_pad_numbers_are_jumpers no)
		(fp_line
			(start -0.299974 0.150114)
			(end 0.299974 0.150114)
			(stroke
				(width 0.1)
				(type default)
			)
			(layer "B.Fab")
		)
		(fp_line
			(start 0.299974 0.150114)
			(end 0.299974 -0.150114)
			(stroke
				(width 0.1)
				(type default)
			)
			(layer "B.Fab")
		)
		(fp_line
			(start -0.299974 -0.150114)
			(end -0.299974 0.150114)
			(stroke
				(width 0.1)
				(type default)
			)
			(layer "B.Fab")
		)
		(fp_line
			(start 0.299974 -0.150114)
			(end -0.299974 -0.150114)
			(stroke
				(width 0.1)
				(type default)
			)
			(layer "B.Fab")
		)
		(pad "1" smd rect
			(at 0.2667 0 90)
			(size 0.3048 0.381)
			(layers "B.Cu" "B.Mask" "B.Paste")
			(net "P0V8_SERDES_VDDA_PEX3")
		)
		(pad "2" smd rect
			(at -0.2667 0 90)
			(size 0.3048 0.381)
			(layers "B.Cu" "B.Mask" "B.Paste")
			(net "GND")
		)
	)
	(footprint ""
		(layer "B.Cu")
		(at 303.559972 -236.736636 90)
		(property "Reference" "R6175"
			(at 0 0 90)
			(layer "B.SilkS")
			(hide yes)
			(effects
				(font
					(size 1.27 1.27)
				)
				(justify mirror)
			)
		)
		(property "Value" ""
			(at 0 0 90)
			(layer "B.Fab")
			(effects
				(font
					(size 1.27 1.27)
				)
				(justify mirror)
			)
		)
		(duplicate_pad_numbers_are_jumpers no)
		(fp_line
			(start 0.7874 -0.4064)
			(end -0.7874 -0.4064)
			(stroke
				(width 0.1524)
				(type default)
			)
			(layer "B.SilkS")
		)
		(fp_line
			(start -0.7874 -0.4064)
			(end -0.7874 0.4064)
			(stroke
				(width 0.1524)
				(type default)
			)
			(layer "B.SilkS")
		)
		(fp_line
			(start 0.7874 0.4064)
			(end 0.7874 -0.4064)
			(stroke
				(width 0.1524)
				(type default)
			)
			(layer "B.SilkS")
		)
		(fp_line
			(start -0.7874 0.4064)
			(end 0.7874 0.4064)
			(stroke
				(width 0.1524)
				(type default)
			)
			(layer "B.SilkS")
		)
		(fp_line
			(start 0.67945 -0.305054)
			(end 0.12065 -0.305054)
			(stroke
				(width 0.1)
				(type default)
			)
			(layer "B.Fab")
		)
		(fp_line
			(start 0.12065 -0.305054)
			(end 0.12065 -0.2794)
			(stroke
				(width 0.1)
				(type default)
			)
			(layer "B.Fab")
		)
		(fp_line
			(start -0.12065 -0.3048)
			(end -0.67945 -0.3048)
			(stroke
				(width 0.1)
				(type default)
			)
			(layer "B.Fab")
		)
		(fp_line
			(start -0.67945 -0.3048)
			(end -0.67945 0.3048)
			(stroke
				(width 0.1)
				(type default)
			)
			(layer "B.Fab")
		)
		(fp_line
			(start 0.12065 -0.2794)
			(end -0.12065 -0.2794)
			(stroke
				(width 0.1)
				(type default)
			)
			(layer "B.Fab")
		)
		(fp_line
			(start -0.12065 -0.2794)
			(end -0.12065 -0.3048)
			(stroke
				(width 0.1)
				(type default)
			)
			(layer "B.Fab")
		)
		(fp_line
			(start 0.12065 0.2794)
			(end 0.12065 0.3048)
			(stroke
				(width 0.1)
				(type default)
			)
			(layer "B.Fab")
		)
		(fp_line
			(start -0.120396 0.2794)
			(end 0.12065 0.2794)
			(stroke
				(width 0.1)
				(type default)
			)
			(layer "B.Fab")
		)
		(fp_line
			(start 0.67945 0.3048)
			(end 0.67945 -0.305054)
			(stroke
				(width 0.1)
				(type default)
			)
			(layer "B.Fab")
		)
		(fp_line
			(start 0.12065 0.3048)
			(end 0.67945 0.3048)
			(stroke
				(width 0.1)
				(type default)
			)
			(layer "B.Fab")
		)
		(fp_line
			(start -0.120396 0.3048)
			(end -0.120396 0.2794)
			(stroke
				(width 0.1)
				(type default)
			)
			(layer "B.Fab")
		)
		(fp_line
			(start -0.67945 0.3048)
			(end -0.120396 0.3048)
			(stroke
				(width 0.1)
				(type default)
			)
			(layer "B.Fab")
		)
		(pad "1" smd circle
			(at 0.40005 0 270)
			(size 0 0)
			(layers "B.Cu" "B.Mask" "B.Paste")
			(net "GND")
		)
		(pad "2" smd circle
			(at -0.40005 0 270)
			(size 0 0)
			(layers "B.Cu" "B.Mask" "B.Paste")
			(net "RST_GPU_PERST_1_N")
		)
	)
	(footprint ""
		(layer "B.Cu")
		(at 110.303564 -349.238062 -90)
		(property "Reference" "C4182"
			(at 0 0 90)
			(layer "B.SilkS")
			(hide yes)
			(effects
				(font
					(size 1.27 1.27)
				)
				(justify mirror)
			)
		)
		(property "Value" ""
			(at 0 0 90)
			(layer "B.Fab")
			(effects
				(font
					(size 1.27 1.27)
				)
				(justify mirror)
			)
		)
		(duplicate_pad_numbers_are_jumpers no)
		(fp_line
			(start -1.524 0.762)
			(end 1.524 0.762)
			(stroke
				(width 0.1524)
				(type default)
			)
			(layer "B.SilkS")
		)
		(fp_line
			(start 1.524 0.762)
			(end 1.524 -0.762)
			(stroke
				(width 0.1524)
				(type default)
			)
			(layer "B.SilkS")
		)
		(fp_line
			(start -1.524 -0.762)
			(end -1.524 0.762)
			(stroke
				(width 0.1524)
				(type default)
			)
			(layer "B.SilkS")
		)
		(fp_line
			(start 1.524 -0.762)
			(end -1.524 -0.762)
			(stroke
				(width 0.1524)
				(type default)
			)
			(layer "B.SilkS")
		)
		(fp_line
			(start -1.1049 0.724916)
			(end -1.1049 -0.724916)
			(stroke
				(width 0.1)
				(type default)
			)
			(layer "B.Fab")
		)
		(fp_line
			(start 1.1049 0.724916)
			(end -1.1049 0.724916)
			(stroke
				(width 0.1)
				(type default)
			)
			(layer "B.Fab")
		)
		(fp_line
			(start -1.1049 -0.724916)
			(end 1.1049 -0.724916)
			(stroke
				(width 0.1)
				(type default)
			)
			(layer "B.Fab")
		)
		(fp_line
			(start 1.1049 -0.724916)
			(end 1.1049 0.724916)
			(stroke
				(width 0.1)
				(type default)
			)
			(layer "B.Fab")
		)
		(pad "1" smd rect
			(at 0.889 0 270)
			(size 1.016 1.27)
			(layers "B.Cu" "B.Mask" "B.Paste")
			(net "P3V3_CLK_BUFFER_9ZXL0451E_S3_VZX3P3A")
		)
		(pad "2" smd rect
			(at -0.889 0 270)
			(size 1.016 1.27)
			(layers "B.Cu" "B.Mask" "B.Paste")
			(net "GND")
		)
	)
	(footprint ""
		(layer "B.Cu")
		(at 133.030214 -212.381846 180)
		(property "Reference" "R987"
			(at 0 0 0)
			(layer "B.SilkS")
			(hide yes)
			(effects
				(font
					(size 1.27 1.27)
				)
				(justify mirror)
			)
		)
		(property "Value" ""
			(at 0 0 0)
			(layer "B.Fab")
			(effects
				(font
					(size 1.27 1.27)
				)
				(justify mirror)
			)
		)
		(duplicate_pad_numbers_are_jumpers no)
		(fp_line
			(start 0.7874 0.4064)
			(end 0.7874 -0.4064)
			(stroke
				(width 0.1524)
				(type default)
			)
			(layer "B.SilkS")
		)
		(fp_line
			(start 0.7874 -0.4064)
			(end -0.7874 -0.4064)
			(stroke
				(width 0.1524)
				(type default)
			)
			(layer "B.SilkS")
		)
		(fp_line
			(start -0.7874 0.4064)
			(end 0.7874 0.4064)
			(stroke
				(width 0.1524)
				(type default)
			)
			(layer "B.SilkS")
		)
		(fp_line
			(start -0.7874 -0.4064)
			(end -0.7874 0.4064)
			(stroke
				(width 0.1524)
				(type default)
			)
			(layer "B.SilkS")
		)
		(fp_line
			(start 0.67945 0.3048)
			(end 0.67945 -0.305054)
			(stroke
				(width 0.1)
				(type default)
			)
			(layer "B.Fab")
		)
		(fp_line
			(start 0.67945 -0.305054)
			(end 0.12065 -0.305054)
			(stroke
				(width 0.1)
				(type default)
			)
			(layer "B.Fab")
		)
		(fp_line
			(start 0.12065 0.3048)
			(end 0.67945 0.3048)
			(stroke
				(width 0.1)
				(type default)
			)
			(layer "B.Fab")
		)
		(fp_line
			(start 0.12065 0.2794)
			(end 0.12065 0.3048)
			(stroke
				(width 0.1)
				(type default)
			)
			(layer "B.Fab")
		)
		(fp_line
			(start 0.12065 -0.2794)
			(end -0.12065 -0.2794)
			(stroke
				(width 0.1)
				(type default)
			)
			(layer "B.Fab")
		)
		(fp_line
			(start 0.12065 -0.305054)
			(end 0.12065 -0.2794)
			(stroke
				(width 0.1)
				(type default)
			)
			(layer "B.Fab")
		)
		(fp_line
			(start -0.120396 0.3048)
			(end -0.120396 0.2794)
			(stroke
				(width 0.1)
				(type default)
			)
			(layer "B.Fab")
		)
		(fp_line
			(start -0.120396 0.2794)
			(end 0.12065 0.2794)
			(stroke
				(width 0.1)
				(type default)
			)
			(layer "B.Fab")
		)
		(fp_line
			(start -0.12065 -0.2794)
			(end -0.12065 -0.3048)
			(stroke
				(width 0.1)
				(type default)
			)
			(layer "B.Fab")
		)
		(fp_line
			(start -0.12065 -0.3048)
			(end -0.67945 -0.3048)
			(stroke
				(width 0.1)
				(type default)
			)
			(layer "B.Fab")
		)
		(fp_line
			(start -0.67945 0.3048)
			(end -0.120396 0.3048)
			(stroke
				(width 0.1)
				(type default)
			)
			(layer "B.Fab")
		)
		(fp_line
			(start -0.67945 -0.3048)
			(end -0.67945 0.3048)
			(stroke
				(width 0.1)
				(type default)
			)
			(layer "B.Fab")
		)
		(pad "1" smd circle
			(at 0.40005 0)
			(size 0 0)
			(layers "B.Cu" "B.Mask" "B.Paste")
			(net "UART_PEX1_CLI_BUF_R_TX")
		)
		(pad "2" smd circle
			(at -0.40005 0)
			(size 0 0)
			(layers "B.Cu" "B.Mask" "B.Paste")
			(net "UART_PEX1_CLI_BUF_TX")
		)
	)
	(footprint ""
		(layer "B.Cu")
		(at 98.90125 -376.488706)
		(property "Reference" "R1832"
			(at 0 0 0)
			(layer "B.SilkS")
			(hide yes)
			(effects
				(font
					(size 1.27 1.27)
				)
				(justify mirror)
			)
		)
		(property "Value" ""
			(at 0 0 0)
			(layer "B.Fab")
			(effects
				(font
					(size 1.27 1.27)
				)
				(justify mirror)
			)
		)
		(duplicate_pad_numbers_are_jumpers no)
		(fp_line
			(start -0.7874 -0.4064)
			(end -0.7874 0.4064)
			(stroke
				(width 0.1524)
				(type default)
			)
			(layer "B.SilkS")
		)
		(fp_line
			(start -0.7874 0.4064)
			(end 0.7874 0.4064)
			(stroke
				(width 0.1524)
				(type default)
			)
			(layer "B.SilkS")
		)
		(fp_line
			(start 0.7874 -0.4064)
			(end -0.7874 -0.4064)
			(stroke
				(width 0.1524)
				(type default)
			)
			(layer "B.SilkS")
		)
		(fp_line
			(start 0.7874 0.4064)
			(end 0.7874 -0.4064)
			(stroke
				(width 0.1524)
				(type default)
			)
			(layer "B.SilkS")
		)
		(fp_line
			(start -0.67945 -0.3048)
			(end -0.67945 0.3048)
			(stroke
				(width 0.1)
				(type default)
			)
			(layer "B.Fab")
		)
		(fp_line
			(start -0.67945 0.3048)
			(end -0.120396 0.3048)
			(stroke
				(width 0.1)
				(type default)
			)
			(layer "B.Fab")
		)
		(fp_line
			(start -0.12065 -0.3048)
			(end -0.67945 -0.3048)
			(stroke
				(width 0.1)
				(type default)
			)
			(layer "B.Fab")
		)
		(fp_line
			(start -0.12065 -0.2794)
			(end -0.12065 -0.3048)
			(stroke
				(width 0.1)
				(type default)
			)
			(layer "B.Fab")
		)
		(fp_line
			(start -0.120396 0.2794)
			(end 0.12065 0.2794)
			(stroke
				(width 0.1)
				(type default)
			)
			(layer "B.Fab")
		)
		(fp_line
			(start -0.120396 0.3048)
			(end -0.120396 0.2794)
			(stroke
				(width 0.1)
				(type default)
			)
			(layer "B.Fab")
		)
		(fp_line
			(start 0.12065 -0.305054)
			(end 0.12065 -0.2794)
			(stroke
				(width 0.1)
				(type default)
			)
			(layer "B.Fab")
		)
		(fp_line
			(start 0.12065 -0.2794)
			(end -0.12065 -0.2794)
			(stroke
				(width 0.1)
				(type default)
			)
			(layer "B.Fab")
		)
		(fp_line
			(start 0.12065 0.2794)
			(end 0.12065 0.3048)
			(stroke
				(width 0.1)
				(type default)
			)
			(layer "B.Fab")
		)
		(fp_line
			(start 0.12065 0.3048)
			(end 0.67945 0.3048)
			(stroke
				(width 0.1)
				(type default)
			)
			(layer "B.Fab")
		)
		(fp_line
			(start 0.67945 -0.305054)
			(end 0.12065 -0.305054)
			(stroke
				(width 0.1)
				(type default)
			)
			(layer "B.Fab")
		)
		(fp_line
			(start 0.67945 0.3048)
			(end 0.67945 -0.305054)
			(stroke
				(width 0.1)
				(type default)
			)
			(layer "B.Fab")
		)
		(pad "1" smd circle
			(at 0.40005 0 180)
			(size 0 0)
			(layers "B.Cu" "B.Mask" "B.Paste")
			(net "SMB_GPU_2_R_SDA")
		)
		(pad "2" smd circle
			(at -0.40005 0 180)
			(size 0 0)
			(layers "B.Cu" "B.Mask" "B.Paste")
			(net "SMB_GPU_2_SDA")
		)
	)
	(footprint ""
		(layer "B.Cu")
		(at 415.07664 -293.99992 90)
		(property "Reference" "C1930"
			(at 0 0 90)
			(layer "B.SilkS")
			(hide yes)
			(effects
				(font
					(size 1.27 1.27)
				)
				(justify mirror)
			)
		)
		(property "Value" ""
			(at 0 0 90)
			(layer "B.Fab")
			(effects
				(font
					(size 1.27 1.27)
				)
				(justify mirror)
			)
		)
		(duplicate_pad_numbers_are_jumpers no)
		(fp_line
			(start 0.299974 -0.150114)
			(end -0.299974 -0.150114)
			(stroke
				(width 0.1)
				(type default)
			)
			(layer "B.Fab")
		)
		(fp_line
			(start -0.299974 -0.150114)
			(end -0.299974 0.150114)
			(stroke
				(width 0.1)
				(type default)
			)
			(layer "B.Fab")
		)
		(fp_line
			(start 0.299974 0.150114)
			(end 0.299974 -0.150114)
			(stroke
				(width 0.1)
				(type default)
			)
			(layer "B.Fab")
		)
		(fp_line
			(start -0.299974 0.150114)
			(end 0.299974 0.150114)
			(stroke
				(width 0.1)
				(type default)
			)
			(layer "B.Fab")
		)
		(pad "1" smd rect
			(at 0.2667 0 270)
			(size 0.3048 0.381)
			(layers "B.Cu" "B.Mask" "B.Paste")
			(net "P0V8_SERDES_VDDA_PEX3")
		)
		(pad "2" smd rect
			(at -0.2667 0 270)
			(size 0.3048 0.381)
			(layers "B.Cu" "B.Mask" "B.Paste")
			(net "GND")
		)
	)
	(footprint ""
		(layer "B.Cu")
		(at 338.582 -207.772 90)
		(property "Reference" "R4135"
			(at 0 0 90)
			(layer "B.SilkS")
			(hide yes)
			(effects
				(font
					(size 1.27 1.27)
				)
				(justify mirror)
			)
		)
		(property "Value" ""
			(at 0 0 90)
			(layer "B.Fab")
			(effects
				(font
					(size 1.27 1.27)
				)
				(justify mirror)
			)
		)
		(duplicate_pad_numbers_are_jumpers no)
		(fp_line
			(start 0.7874 -0.4064)
			(end -0.7874 -0.4064)
			(stroke
				(width 0.1524)
				(type default)
			)
			(layer "B.SilkS")
		)
		(fp_line
			(start -0.7874 -0.4064)
			(end -0.7874 0.4064)
			(stroke
				(width 0.1524)
				(type default)
			)
			(layer "B.SilkS")
		)
		(fp_line
			(start 0.7874 0.4064)
			(end 0.7874 -0.4064)
			(stroke
				(width 0.1524)
				(type default)
			)
			(layer "B.SilkS")
		)
		(fp_line
			(start -0.7874 0.4064)
			(end 0.7874 0.4064)
			(stroke
				(width 0.1524)
				(type default)
			)
			(layer "B.SilkS")
		)
		(fp_line
			(start 0.67945 -0.305054)
			(end 0.12065 -0.305054)
			(stroke
				(width 0.1)
				(type default)
			)
			(layer "B.Fab")
		)
		(fp_line
			(start 0.12065 -0.305054)
			(end 0.12065 -0.2794)
			(stroke
				(width 0.1)
				(type default)
			)
			(layer "B.Fab")
		)
		(fp_line
			(start -0.12065 -0.3048)
			(end -0.67945 -0.3048)
			(stroke
				(width 0.1)
				(type default)
			)
			(layer "B.Fab")
		)
		(fp_line
			(start -0.67945 -0.3048)
			(end -0.67945 0.3048)
			(stroke
				(width 0.1)
				(type default)
			)
			(layer "B.Fab")
		)
		(fp_line
			(start 0.12065 -0.2794)
			(end -0.12065 -0.2794)
			(stroke
				(width 0.1)
				(type default)
			)
			(layer "B.Fab")
		)
		(fp_line
			(start -0.12065 -0.2794)
			(end -0.12065 -0.3048)
			(stroke
				(width 0.1)
				(type default)
			)
			(layer "B.Fab")
		)
		(fp_line
			(start 0.12065 0.2794)
			(end 0.12065 0.3048)
			(stroke
				(width 0.1)
				(type default)
			)
			(layer "B.Fab")
		)
		(fp_line
			(start -0.120396 0.2794)
			(end 0.12065 0.2794)
			(stroke
				(width 0.1)
				(type default)
			)
			(layer "B.Fab")
		)
		(fp_line
			(start 0.67945 0.3048)
			(end 0.67945 -0.305054)
			(stroke
				(width 0.1)
				(type default)
			)
			(layer "B.Fab")
		)
		(fp_line
			(start 0.12065 0.3048)
			(end 0.67945 0.3048)
			(stroke
				(width 0.1)
				(type default)
			)
			(layer "B.Fab")
		)
		(fp_line
			(start -0.120396 0.3048)
			(end -0.120396 0.2794)
			(stroke
				(width 0.1)
				(type default)
			)
			(layer "B.Fab")
		)
		(fp_line
			(start -0.67945 0.3048)
			(end -0.120396 0.3048)
			(stroke
				(width 0.1)
				(type default)
			)
			(layer "B.Fab")
		)
		(pad "1" smd circle
			(at 0.40005 0 270)
			(size 0 0)
			(layers "B.Cu" "B.Mask" "B.Paste")
			(net "SSD13_PWR_EN")
		)
		(pad "2" smd circle
			(at -0.40005 0 270)
			(size 0 0)
			(layers "B.Cu" "B.Mask" "B.Paste")
			(net "SSD13_PWR_EN_R")
		)
	)
	(footprint ""
		(layer "B.Cu")
		(at 206.164942 -259.311648 90)
		(property "Reference" "R6344"
			(at 0 0 90)
			(layer "B.SilkS")
			(hide yes)
			(effects
				(font
					(size 1.27 1.27)
				)
				(justify mirror)
			)
		)
		(property "Value" ""
			(at 0 0 90)
			(layer "B.Fab")
			(effects
				(font
					(size 1.27 1.27)
				)
				(justify mirror)
			)
		)
		(duplicate_pad_numbers_are_jumpers no)
		(fp_line
			(start 0.7874 -0.4064)
			(end -0.7874 -0.4064)
			(stroke
				(width 0.1524)
				(type default)
			)
			(layer "B.SilkS")
		)
		(fp_line
			(start -0.7874 -0.4064)
			(end -0.7874 0.4064)
			(stroke
				(width 0.1524)
				(type default)
			)
			(layer "B.SilkS")
		)
		(fp_line
			(start 0.7874 0.4064)
			(end 0.7874 -0.4064)
			(stroke
				(width 0.1524)
				(type default)
			)
			(layer "B.SilkS")
		)
		(fp_line
			(start -0.7874 0.4064)
			(end 0.7874 0.4064)
			(stroke
				(width 0.1524)
				(type default)
			)
			(layer "B.SilkS")
		)
		(fp_line
			(start 0.67945 -0.305054)
			(end 0.12065 -0.305054)
			(stroke
				(width 0.1)
				(type default)
			)
			(layer "B.Fab")
		)
		(fp_line
			(start 0.12065 -0.305054)
			(end 0.12065 -0.2794)
			(stroke
				(width 0.1)
				(type default)
			)
			(layer "B.Fab")
		)
		(fp_line
			(start -0.12065 -0.3048)
			(end -0.67945 -0.3048)
			(stroke
				(width 0.1)
				(type default)
			)
			(layer "B.Fab")
		)
		(fp_line
			(start -0.67945 -0.3048)
			(end -0.67945 0.3048)
			(stroke
				(width 0.1)
				(type default)
			)
			(layer "B.Fab")
		)
		(fp_line
			(start 0.12065 -0.2794)
			(end -0.12065 -0.2794)
			(stroke
				(width 0.1)
				(type default)
			)
			(layer "B.Fab")
		)
		(fp_line
			(start -0.12065 -0.2794)
			(end -0.12065 -0.3048)
			(stroke
				(width 0.1)
				(type default)
			)
			(layer "B.Fab")
		)
		(fp_line
			(start 0.12065 0.2794)
			(end 0.12065 0.3048)
			(stroke
				(width 0.1)
				(type default)
			)
			(layer "B.Fab")
		)
		(fp_line
			(start -0.120396 0.2794)
			(end 0.12065 0.2794)
			(stroke
				(width 0.1)
				(type default)
			)
			(layer "B.Fab")
		)
		(fp_line
			(start 0.67945 0.3048)
			(end 0.67945 -0.305054)
			(stroke
				(width 0.1)
				(type default)
			)
			(layer "B.Fab")
		)
		(fp_line
			(start 0.12065 0.3048)
			(end 0.67945 0.3048)
			(stroke
				(width 0.1)
				(type default)
			)
			(layer "B.Fab")
		)
		(fp_line
			(start -0.120396 0.3048)
			(end -0.120396 0.2794)
			(stroke
				(width 0.1)
				(type default)
			)
			(layer "B.Fab")
		)
		(fp_line
			(start -0.67945 0.3048)
			(end -0.120396 0.3048)
			(stroke
				(width 0.1)
				(type default)
			)
			(layer "B.Fab")
		)
		(pad "1" smd circle
			(at 0.40005 0 270)
			(size 0 0)
			(layers "B.Cu" "B.Mask" "B.Paste")
			(net "P1V8_PEX")
		)
		(pad "2" smd circle
			(at -0.40005 0 270)
			(size 0 0)
			(layers "B.Cu" "B.Mask" "B.Paste")
			(net "SMB_PEX1_MUX_SDA")
		)
	)
	(footprint ""
		(layer "B.Cu")
		(at 411.683454 -108.462318 180)
		(property "Reference" "R387"
			(at 0 0 0)
			(layer "B.SilkS")
			(hide yes)
			(effects
				(font
					(size 1.27 1.27)
				)
				(justify mirror)
			)
		)
		(property "Value" ""
			(at 0 0 0)
			(layer "B.Fab")
			(effects
				(font
					(size 1.27 1.27)
				)
				(justify mirror)
			)
		)
		(duplicate_pad_numbers_are_jumpers no)
		(fp_line
			(start 0.7874 0.4064)
			(end 0.7874 -0.4064)
			(stroke
				(width 0.1524)
				(type default)
			)
			(layer "B.SilkS")
		)
		(fp_line
			(start 0.7874 -0.4064)
			(end -0.7874 -0.4064)
			(stroke
				(width 0.1524)
				(type default)
			)
			(layer "B.SilkS")
		)
		(fp_line
			(start -0.7874 0.4064)
			(end 0.7874 0.4064)
			(stroke
				(width 0.1524)
				(type default)
			)
			(layer "B.SilkS")
		)
		(fp_line
			(start -0.7874 -0.4064)
			(end -0.7874 0.4064)
			(stroke
				(width 0.1524)
				(type default)
			)
			(layer "B.SilkS")
		)
		(fp_line
			(start 0.67945 0.3048)
			(end 0.67945 -0.305054)
			(stroke
				(width 0.1)
				(type default)
			)
			(layer "B.Fab")
		)
		(fp_line
			(start 0.67945 -0.305054)
			(end 0.12065 -0.305054)
			(stroke
				(width 0.1)
				(type default)
			)
			(layer "B.Fab")
		)
		(fp_line
			(start 0.12065 0.3048)
			(end 0.67945 0.3048)
			(stroke
				(width 0.1)
				(type default)
			)
			(layer "B.Fab")
		)
		(fp_line
			(start 0.12065 0.2794)
			(end 0.12065 0.3048)
			(stroke
				(width 0.1)
				(type default)
			)
			(layer "B.Fab")
		)
		(fp_line
			(start 0.12065 -0.2794)
			(end -0.12065 -0.2794)
			(stroke
				(width 0.1)
				(type default)
			)
			(layer "B.Fab")
		)
		(fp_line
			(start 0.12065 -0.305054)
			(end 0.12065 -0.2794)
			(stroke
				(width 0.1)
				(type default)
			)
			(layer "B.Fab")
		)
		(fp_line
			(start -0.120396 0.3048)
			(end -0.120396 0.2794)
			(stroke
				(width 0.1)
				(type default)
			)
			(layer "B.Fab")
		)
		(fp_line
			(start -0.120396 0.2794)
			(end 0.12065 0.2794)
			(stroke
				(width 0.1)
				(type default)
			)
			(layer "B.Fab")
		)
		(fp_line
			(start -0.12065 -0.2794)
			(end -0.12065 -0.3048)
			(stroke
				(width 0.1)
				(type default)
			)
			(layer "B.Fab")
		)
		(fp_line
			(start -0.12065 -0.3048)
			(end -0.67945 -0.3048)
			(stroke
				(width 0.1)
				(type default)
			)
			(layer "B.Fab")
		)
		(fp_line
			(start -0.67945 0.3048)
			(end -0.120396 0.3048)
			(stroke
				(width 0.1)
				(type default)
			)
			(layer "B.Fab")
		)
		(fp_line
			(start -0.67945 -0.3048)
			(end -0.67945 0.3048)
			(stroke
				(width 0.1)
				(type default)
			)
			(layer "B.Fab")
		)
		(pad "1" smd circle
			(at 0.40005 0)
			(size 0 0)
			(layers "B.Cu" "B.Mask" "B.Paste")
			(net "NIC7_BIF0_N")
		)
		(pad "2" smd circle
			(at -0.40005 0)
			(size 0 0)
			(layers "B.Cu" "B.Mask" "B.Paste")
			(net "GND")
		)
	)
	(footprint ""
		(layer "B.Cu")
		(at 344.043 -233.553 90)
		(property "Reference" "R3566"
			(at 0 0 90)
			(layer "B.SilkS")
			(hide yes)
			(effects
				(font
					(size 1.27 1.27)
				)
				(justify mirror)
			)
		)
		(property "Value" ""
			(at 0 0 90)
			(layer "B.Fab")
			(effects
				(font
					(size 1.27 1.27)
				)
				(justify mirror)
			)
		)
		(duplicate_pad_numbers_are_jumpers no)
		(fp_line
			(start 0.7874 -0.4064)
			(end -0.7874 -0.4064)
			(stroke
				(width 0.1524)
				(type default)
			)
			(layer "B.SilkS")
		)
		(fp_line
			(start -0.7874 -0.4064)
			(end -0.7874 0.4064)
			(stroke
				(width 0.1524)
				(type default)
			)
			(layer "B.SilkS")
		)
		(fp_line
			(start 0.7874 0.4064)
			(end 0.7874 -0.4064)
			(stroke
				(width 0.1524)
				(type default)
			)
			(layer "B.SilkS")
		)
		(fp_line
			(start -0.7874 0.4064)
			(end 0.7874 0.4064)
			(stroke
				(width 0.1524)
				(type default)
			)
			(layer "B.SilkS")
		)
		(fp_line
			(start 0.67945 -0.305054)
			(end 0.12065 -0.305054)
			(stroke
				(width 0.1)
				(type default)
			)
			(layer "B.Fab")
		)
		(fp_line
			(start 0.12065 -0.305054)
			(end 0.12065 -0.2794)
			(stroke
				(width 0.1)
				(type default)
			)
			(layer "B.Fab")
		)
		(fp_line
			(start -0.12065 -0.3048)
			(end -0.67945 -0.3048)
			(stroke
				(width 0.1)
				(type default)
			)
			(layer "B.Fab")
		)
		(fp_line
			(start -0.67945 -0.3048)
			(end -0.67945 0.3048)
			(stroke
				(width 0.1)
				(type default)
			)
			(layer "B.Fab")
		)
		(fp_line
			(start 0.12065 -0.2794)
			(end -0.12065 -0.2794)
			(stroke
				(width 0.1)
				(type default)
			)
			(layer "B.Fab")
		)
		(fp_line
			(start -0.12065 -0.2794)
			(end -0.12065 -0.3048)
			(stroke
				(width 0.1)
				(type default)
			)
			(layer "B.Fab")
		)
		(fp_line
			(start 0.12065 0.2794)
			(end 0.12065 0.3048)
			(stroke
				(width 0.1)
				(type default)
			)
			(layer "B.Fab")
		)
		(fp_line
			(start -0.120396 0.2794)
			(end 0.12065 0.2794)
			(stroke
				(width 0.1)
				(type default)
			)
			(layer "B.Fab")
		)
		(fp_line
			(start 0.67945 0.3048)
			(end 0.67945 -0.305054)
			(stroke
				(width 0.1)
				(type default)
			)
			(layer "B.Fab")
		)
		(fp_line
			(start 0.12065 0.3048)
			(end 0.67945 0.3048)
			(stroke
				(width 0.1)
				(type default)
			)
			(layer "B.Fab")
		)
		(fp_line
			(start -0.120396 0.3048)
			(end -0.120396 0.2794)
			(stroke
				(width 0.1)
				(type default)
			)
			(layer "B.Fab")
		)
		(fp_line
			(start -0.67945 0.3048)
			(end -0.120396 0.3048)
			(stroke
				(width 0.1)
				(type default)
			)
			(layer "B.Fab")
		)
		(pad "1" smd circle
			(at 0.40005 0 270)
			(size 0 0)
			(layers "B.Cu" "B.Mask" "B.Paste")
			(net "SSD5_PWRDIS_R")
		)
		(pad "2" smd circle
			(at -0.40005 0 270)
			(size 0 0)
			(layers "B.Cu" "B.Mask" "B.Paste")
			(net "SSD5_PWRDIS")
		)
	)
	(footprint ""
		(layer "B.Cu")
		(at 247.099582 -228.981)
		(property "Reference" "R3485"
			(at 0 0 0)
			(layer "B.SilkS")
			(hide yes)
			(effects
				(font
					(size 1.27 1.27)
				)
				(justify mirror)
			)
		)
		(property "Value" ""
			(at 0 0 0)
			(layer "B.Fab")
			(effects
				(font
					(size 1.27 1.27)
				)
				(justify mirror)
			)
		)
		(duplicate_pad_numbers_are_jumpers no)
		(fp_line
			(start -0.7874 -0.4064)
			(end -0.7874 0.4064)
			(stroke
				(width 0.1524)
				(type default)
			)
			(layer "B.SilkS")
		)
		(fp_line
			(start -0.7874 0.4064)
			(end 0.7874 0.4064)
			(stroke
				(width 0.1524)
				(type default)
			)
			(layer "B.SilkS")
		)
		(fp_line
			(start 0.7874 -0.4064)
			(end -0.7874 -0.4064)
			(stroke
				(width 0.1524)
				(type default)
			)
			(layer "B.SilkS")
		)
		(fp_line
			(start 0.7874 0.4064)
			(end 0.7874 -0.4064)
			(stroke
				(width 0.1524)
				(type default)
			)
			(layer "B.SilkS")
		)
		(fp_line
			(start -0.67945 -0.3048)
			(end -0.67945 0.3048)
			(stroke
				(width 0.1)
				(type default)
			)
			(layer "B.Fab")
		)
		(fp_line
			(start -0.67945 0.3048)
			(end -0.120396 0.3048)
			(stroke
				(width 0.1)
				(type default)
			)
			(layer "B.Fab")
		)
		(fp_line
			(start -0.12065 -0.3048)
			(end -0.67945 -0.3048)
			(stroke
				(width 0.1)
				(type default)
			)
			(layer "B.Fab")
		)
		(fp_line
			(start -0.12065 -0.2794)
			(end -0.12065 -0.3048)
			(stroke
				(width 0.1)
				(type default)
			)
			(layer "B.Fab")
		)
		(fp_line
			(start -0.120396 0.2794)
			(end 0.12065 0.2794)
			(stroke
				(width 0.1)
				(type default)
			)
			(layer "B.Fab")
		)
		(fp_line
			(start -0.120396 0.3048)
			(end -0.120396 0.2794)
			(stroke
				(width 0.1)
				(type default)
			)
			(layer "B.Fab")
		)
		(fp_line
			(start 0.12065 -0.305054)
			(end 0.12065 -0.2794)
			(stroke
				(width 0.1)
				(type default)
			)
			(layer "B.Fab")
		)
		(fp_line
			(start 0.12065 -0.2794)
			(end -0.12065 -0.2794)
			(stroke
				(width 0.1)
				(type default)
			)
			(layer "B.Fab")
		)
		(fp_line
			(start 0.12065 0.2794)
			(end 0.12065 0.3048)
			(stroke
				(width 0.1)
				(type default)
			)
			(layer "B.Fab")
		)
		(fp_line
			(start 0.12065 0.3048)
			(end 0.67945 0.3048)
			(stroke
				(width 0.1)
				(type default)
			)
			(layer "B.Fab")
		)
		(fp_line
			(start 0.67945 -0.305054)
			(end 0.12065 -0.305054)
			(stroke
				(width 0.1)
				(type default)
			)
			(layer "B.Fab")
		)
		(fp_line
			(start 0.67945 0.3048)
			(end 0.67945 -0.305054)
			(stroke
				(width 0.1)
				(type default)
			)
			(layer "B.Fab")
		)
		(pad "1" smd circle
			(at 0.40005 0 180)
			(size 0 0)
			(layers "B.Cu" "B.Mask" "B.Paste")
			(net "P1V8_PEX")
		)
		(pad "2" smd circle
			(at -0.40005 0 180)
			(size 0 0)
			(layers "B.Cu" "B.Mask" "B.Paste")
			(net "SPI_PEX2_SDIO2_R1")
		)
	)
	(footprint ""
		(layer "B.Cu")
		(at 456.818238 -266.91844 180)
		(property "Reference" "L132"
			(at 0 0 0)
			(layer "B.SilkS")
			(hide yes)
			(effects
				(font
					(size 1.27 1.27)
				)
				(justify mirror)
			)
		)
		(property "Value" ""
			(at 0 0 0)
			(layer "B.Fab")
			(effects
				(font
					(size 1.27 1.27)
				)
				(justify mirror)
			)
		)
		(duplicate_pad_numbers_are_jumpers no)
		(fp_line
			(start 2.248154 4.9911)
			(end -2.248154 4.9911)
			(stroke
				(width 0.1524)
				(type default)
			)
			(layer "B.SilkS")
		)
		(fp_line
			(start 2.248154 1.976882)
			(end 2.248154 4.9911)
			(stroke
				(width 0.1524)
				(type default)
			)
			(layer "B.SilkS")
		)
		(fp_line
			(start 2.248154 -4.9911)
			(end 2.248154 -2.21488)
			(stroke
				(width 0.1524)
				(type default)
			)
			(layer "B.SilkS")
		)
		(fp_line
			(start -2.248154 4.9911)
			(end -2.248154 1.976882)
			(stroke
				(width 0.1524)
				(type default)
			)
			(layer "B.SilkS")
		)
		(fp_line
			(start -2.248154 -2.21488)
			(end -2.248154 -4.9911)
			(stroke
				(width 0.1524)
				(type default)
			)
			(layer "B.SilkS")
		)
		(fp_line
			(start -2.248154 -4.9911)
			(end 2.248154 -4.9911)
			(stroke
				(width 0.1524)
				(type default)
			)
			(layer "B.SilkS")
		)
		(fp_line
			(start 1.700022 0.899922)
			(end -1.700022 0.899922)
			(stroke
				(width 0.1)
				(type default)
			)
			(layer "B.Fab")
		)
		(fp_line
			(start 1.700022 -0.899922)
			(end 1.700022 0.899922)
			(stroke
				(width 0.1)
				(type default)
			)
			(layer "B.Fab")
		)
		(fp_line
			(start -1.700022 0.899922)
			(end -1.700022 -0.899922)
			(stroke
				(width 0.1)
				(type default)
			)
			(layer "B.Fab")
		)
		(fp_line
			(start -1.700022 -0.899922)
			(end 1.700022 -0.899922)
			(stroke
				(width 0.1)
				(type default)
			)
			(layer "B.Fab")
		)
		(pad "1" smd rect
			(at 1.575054 0)
			(size 1.1684 9.8044)
			(layers "B.Cu" "B.Mask" "B.Paste")
			(net "P1V25_PEX3")
		)
		(pad "2" smd rect
			(at -1.575054 0)
			(size 1.1684 9.8044)
			(layers "B.Cu" "B.Mask" "B.Paste")
			(net "P1V25_SERDES_VDDPLL_PEX3")
		)
	)
	(footprint ""
		(layer "B.Cu")
		(at 229.067614 -214.704168 90)
		(property "Reference" "C2008"
			(at 0 0 90)
			(layer "B.SilkS")
			(hide yes)
			(effects
				(font
					(size 1.27 1.27)
				)
				(justify mirror)
			)
		)
		(property "Value" ""
			(at 0 0 90)
			(layer "B.Fab")
			(effects
				(font
					(size 1.27 1.27)
				)
				(justify mirror)
			)
		)
		(duplicate_pad_numbers_are_jumpers no)
		(fp_line
			(start 0.69215 -0.2921)
			(end -0.69215 -0.2921)
			(stroke
				(width 0.1524)
				(type default)
			)
			(layer "B.SilkS")
		)
		(fp_line
			(start -0.69215 -0.2921)
			(end -0.69215 0.2921)
			(stroke
				(width 0.1524)
				(type default)
			)
			(layer "B.SilkS")
		)
		(fp_line
			(start 0.69215 0.2921)
			(end 0.69215 -0.2921)
			(stroke
				(width 0.1524)
				(type default)
			)
			(layer "B.SilkS")
		)
		(fp_line
			(start -0.69215 0.2921)
			(end 0.69215 0.2921)
			(stroke
				(width 0.1524)
				(type default)
			)
			(layer "B.SilkS")
		)
		(fp_line
			(start 0.51435 -0.2794)
			(end -0.51435 -0.2794)
			(stroke
				(width 0.1)
				(type default)
			)
			(layer "B.Fab")
		)
		(fp_line
			(start -0.51435 -0.2794)
			(end -0.51435 0.2794)
			(stroke
				(width 0.1)
				(type default)
			)
			(layer "B.Fab")
		)
		(fp_line
			(start 0.51435 0.2794)
			(end 0.51435 -0.2794)
			(stroke
				(width 0.1)
				(type default)
			)
			(layer "B.Fab")
		)
		(fp_line
			(start -0.51435 0.2794)
			(end 0.51435 0.2794)
			(stroke
				(width 0.1)
				(type default)
			)
			(layer "B.Fab")
		)
		(pad "1" smd circle
			(at 0.40005 0 270)
			(size 0 0)
			(layers "B.Cu" "B.Mask" "B.Paste")
			(net "P3V3_AUX")
		)
		(pad "2" smd circle
			(at -0.40005 0 270)
			(size 0 0)
			(layers "B.Cu" "B.Mask" "B.Paste")
			(net "GND")
		)
		(zone
			(layer "B.Cu")
			(hatch none 0.5)
			(connect_pads
				(clearance 0)
			)
			(min_thickness 0.25)
			(keepout
				(tracks not_allowed)
				(vias allowed)
				(pads allowed)
				(copperpour not_allowed)
				(footprints allowed)
			)
			(placement
				(enabled no)
				(sheetname "")
			)
			(fill
				(thermal_gap 0.5)
				(thermal_bridge_width 0.5)
				(island_removal_mode 0)
			)
			(polygon
				(pts
					(xy 229.155244 -214.894668) (xy 229.21341 -214.803228) (xy 229.21341 -214.603838) (xy 229.155244 -214.513668)
					(xy 228.979984 -214.513668) (xy 228.921564 -214.603838) (xy 228.921564 -214.803228) (xy 228.97973 -214.894668)
				)
			)
		)
	)
	(footprint ""
		(layer "B.Cu")
		(at 123.330208 -282.238958 180)
		(property "Reference" "PR7168"
			(at 0 0 0)
			(layer "B.SilkS")
			(hide yes)
			(effects
				(font
					(size 1.27 1.27)
				)
				(justify mirror)
			)
		)
		(property "Value" ""
			(at 0 0 0)
			(layer "B.Fab")
			(effects
				(font
					(size 1.27 1.27)
				)
				(justify mirror)
			)
		)
		(duplicate_pad_numbers_are_jumpers no)
		(fp_line
			(start 0.7874 0.4064)
			(end 0.7874 -0.4064)
			(stroke
				(width 0.1524)
				(type default)
			)
			(layer "B.SilkS")
		)
		(fp_line
			(start 0.7874 -0.4064)
			(end -0.7874 -0.4064)
			(stroke
				(width 0.1524)
				(type default)
			)
			(layer "B.SilkS")
		)
		(fp_line
			(start -0.7874 0.4064)
			(end 0.7874 0.4064)
			(stroke
				(width 0.1524)
				(type default)
			)
			(layer "B.SilkS")
		)
		(fp_line
			(start -0.7874 -0.4064)
			(end -0.7874 0.4064)
			(stroke
				(width 0.1524)
				(type default)
			)
			(layer "B.SilkS")
		)
		(fp_line
			(start 0.67945 0.3048)
			(end 0.67945 -0.305054)
			(stroke
				(width 0.1)
				(type default)
			)
			(layer "B.Fab")
		)
		(fp_line
			(start 0.67945 -0.305054)
			(end 0.12065 -0.305054)
			(stroke
				(width 0.1)
				(type default)
			)
			(layer "B.Fab")
		)
		(fp_line
			(start 0.12065 0.3048)
			(end 0.67945 0.3048)
			(stroke
				(width 0.1)
				(type default)
			)
			(layer "B.Fab")
		)
		(fp_line
			(start 0.12065 0.2794)
			(end 0.12065 0.3048)
			(stroke
				(width 0.1)
				(type default)
			)
			(layer "B.Fab")
		)
		(fp_line
			(start 0.12065 -0.2794)
			(end -0.12065 -0.2794)
			(stroke
				(width 0.1)
				(type default)
			)
			(layer "B.Fab")
		)
		(fp_line
			(start 0.12065 -0.305054)
			(end 0.12065 -0.2794)
			(stroke
				(width 0.1)
				(type default)
			)
			(layer "B.Fab")
		)
		(fp_line
			(start -0.120396 0.3048)
			(end -0.120396 0.2794)
			(stroke
				(width 0.1)
				(type default)
			)
			(layer "B.Fab")
		)
		(fp_line
			(start -0.120396 0.2794)
			(end 0.12065 0.2794)
			(stroke
				(width 0.1)
				(type default)
			)
			(layer "B.Fab")
		)
		(fp_line
			(start -0.12065 -0.2794)
			(end -0.12065 -0.3048)
			(stroke
				(width 0.1)
				(type default)
			)
			(layer "B.Fab")
		)
		(fp_line
			(start -0.12065 -0.3048)
			(end -0.67945 -0.3048)
			(stroke
				(width 0.1)
				(type default)
			)
			(layer "B.Fab")
		)
		(fp_line
			(start -0.67945 0.3048)
			(end -0.120396 0.3048)
			(stroke
				(width 0.1)
				(type default)
			)
			(layer "B.Fab")
		)
		(fp_line
			(start -0.67945 -0.3048)
			(end -0.67945 0.3048)
			(stroke
				(width 0.1)
				(type default)
			)
			(layer "B.Fab")
		)
		(pad "1" smd circle
			(at 0.40005 0)
			(size 0 0)
			(layers "B.Cu" "B.Mask" "B.Paste")
			(net "P0V8_PEX0_EN3")
		)
		(pad "2" smd circle
			(at -0.40005 0)
			(size 0 0)
			(layers "B.Cu" "B.Mask" "B.Paste")
			(net "P0V8_PEX1_VCC1")
		)
	)
	(footprint ""
		(layer "B.Cu")
		(at 140.282168 -228.346 90)
		(property "Reference" "R3462"
			(at 0 0 90)
			(layer "B.SilkS")
			(hide yes)
			(effects
				(font
					(size 1.27 1.27)
				)
				(justify mirror)
			)
		)
		(property "Value" ""
			(at 0 0 90)
			(layer "B.Fab")
			(effects
				(font
					(size 1.27 1.27)
				)
				(justify mirror)
			)
		)
		(duplicate_pad_numbers_are_jumpers no)
		(fp_line
			(start 0.7874 -0.4064)
			(end -0.7874 -0.4064)
			(stroke
				(width 0.1524)
				(type default)
			)
			(layer "B.SilkS")
		)
		(fp_line
			(start -0.7874 -0.4064)
			(end -0.7874 0.4064)
			(stroke
				(width 0.1524)
				(type default)
			)
			(layer "B.SilkS")
		)
		(fp_line
			(start 0.7874 0.4064)
			(end 0.7874 -0.4064)
			(stroke
				(width 0.1524)
				(type default)
			)
			(layer "B.SilkS")
		)
		(fp_line
			(start -0.7874 0.4064)
			(end 0.7874 0.4064)
			(stroke
				(width 0.1524)
				(type default)
			)
			(layer "B.SilkS")
		)
		(fp_line
			(start 0.67945 -0.305054)
			(end 0.12065 -0.305054)
			(stroke
				(width 0.1)
				(type default)
			)
			(layer "B.Fab")
		)
		(fp_line
			(start 0.12065 -0.305054)
			(end 0.12065 -0.2794)
			(stroke
				(width 0.1)
				(type default)
			)
			(layer "B.Fab")
		)
		(fp_line
			(start -0.12065 -0.3048)
			(end -0.67945 -0.3048)
			(stroke
				(width 0.1)
				(type default)
			)
			(layer "B.Fab")
		)
		(fp_line
			(start -0.67945 -0.3048)
			(end -0.67945 0.3048)
			(stroke
				(width 0.1)
				(type default)
			)
			(layer "B.Fab")
		)
		(fp_line
			(start 0.12065 -0.2794)
			(end -0.12065 -0.2794)
			(stroke
				(width 0.1)
				(type default)
			)
			(layer "B.Fab")
		)
		(fp_line
			(start -0.12065 -0.2794)
			(end -0.12065 -0.3048)
			(stroke
				(width 0.1)
				(type default)
			)
			(layer "B.Fab")
		)
		(fp_line
			(start 0.12065 0.2794)
			(end 0.12065 0.3048)
			(stroke
				(width 0.1)
				(type default)
			)
			(layer "B.Fab")
		)
		(fp_line
			(start -0.120396 0.2794)
			(end 0.12065 0.2794)
			(stroke
				(width 0.1)
				(type default)
			)
			(layer "B.Fab")
		)
		(fp_line
			(start 0.67945 0.3048)
			(end 0.67945 -0.305054)
			(stroke
				(width 0.1)
				(type default)
			)
			(layer "B.Fab")
		)
		(fp_line
			(start 0.12065 0.3048)
			(end 0.67945 0.3048)
			(stroke
				(width 0.1)
				(type default)
			)
			(layer "B.Fab")
		)
		(fp_line
			(start -0.120396 0.3048)
			(end -0.120396 0.2794)
			(stroke
				(width 0.1)
				(type default)
			)
			(layer "B.Fab")
		)
		(fp_line
			(start -0.67945 0.3048)
			(end -0.120396 0.3048)
			(stroke
				(width 0.1)
				(type default)
			)
			(layer "B.Fab")
		)
		(pad "1" smd circle
			(at 0.40005 0 270)
			(size 0 0)
			(layers "B.Cu" "B.Mask" "B.Paste")
			(net "SPI_PEX1_CS_MUX_N")
		)
		(pad "2" smd circle
			(at -0.40005 0 270)
			(size 0 0)
			(layers "B.Cu" "B.Mask" "B.Paste")
			(net "SPI_PEX1_CS_MUX_R_N")
		)
	)
	(footprint ""
		(layer "B.Cu")
		(at 417.450016 -297.32478 180)
		(property "Reference" "C1929"
			(at 0 0 0)
			(layer "B.SilkS")
			(hide yes)
			(effects
				(font
					(size 1.27 1.27)
				)
				(justify mirror)
			)
		)
		(property "Value" ""
			(at 0 0 0)
			(layer "B.Fab")
			(effects
				(font
					(size 1.27 1.27)
				)
				(justify mirror)
			)
		)
		(duplicate_pad_numbers_are_jumpers no)
		(fp_line
			(start 0.299974 0.150114)
			(end 0.299974 -0.150114)
			(stroke
				(width 0.1)
				(type default)
			)
			(layer "B.Fab")
		)
		(fp_line
			(start 0.299974 -0.150114)
			(end -0.299974 -0.150114)
			(stroke
				(width 0.1)
				(type default)
			)
			(layer "B.Fab")
		)
		(fp_line
			(start -0.299974 0.150114)
			(end 0.299974 0.150114)
			(stroke
				(width 0.1)
				(type default)
			)
			(layer "B.Fab")
		)
		(fp_line
			(start -0.299974 -0.150114)
			(end -0.299974 0.150114)
			(stroke
				(width 0.1)
				(type default)
			)
			(layer "B.Fab")
		)
		(pad "1" smd rect
			(at 0.2667 0)
			(size 0.3048 0.381)
			(layers "B.Cu" "B.Mask" "B.Paste")
			(net "P0V8_SERDES_VDDA_PEX3")
		)
		(pad "2" smd rect
			(at -0.2667 0)
			(size 0.3048 0.381)
			(layers "B.Cu" "B.Mask" "B.Paste")
			(net "GND")
		)
	)
	(footprint ""
		(layer "B.Cu")
		(at 46.1264 -139.8016 180)
		(property "Reference" "C854"
			(at 0 0 0)
			(layer "B.SilkS")
			(hide yes)
			(effects
				(font
					(size 1.27 1.27)
				)
				(justify mirror)
			)
		)
		(property "Value" ""
			(at 0 0 0)
			(layer "B.Fab")
			(effects
				(font
					(size 1.27 1.27)
				)
				(justify mirror)
			)
		)
		(duplicate_pad_numbers_are_jumpers no)
		(fp_line
			(start 0.7874 0.4064)
			(end 0.7874 -0.4064)
			(stroke
				(width 0.1524)
				(type default)
			)
			(layer "B.SilkS")
		)
		(fp_line
			(start 0.7874 -0.4064)
			(end -0.7874 -0.4064)
			(stroke
				(width 0.1524)
				(type default)
			)
			(layer "B.SilkS")
		)
		(fp_line
			(start -0.7874 0.4064)
			(end 0.7874 0.4064)
			(stroke
				(width 0.1524)
				(type default)
			)
			(layer "B.SilkS")
		)
		(fp_line
			(start -0.7874 -0.4064)
			(end -0.7874 0.4064)
			(stroke
				(width 0.1524)
				(type default)
			)
			(layer "B.SilkS")
		)
		(fp_line
			(start 0.67945 0.3048)
			(end 0.67945 -0.305054)
			(stroke
				(width 0.1)
				(type default)
			)
			(layer "B.Fab")
		)
		(fp_line
			(start 0.67945 -0.305054)
			(end 0.12065 -0.305054)
			(stroke
				(width 0.1)
				(type default)
			)
			(layer "B.Fab")
		)
		(fp_line
			(start 0.12065 0.3048)
			(end 0.67945 0.3048)
			(stroke
				(width 0.1)
				(type default)
			)
			(layer "B.Fab")
		)
		(fp_line
			(start 0.12065 0.2794)
			(end 0.12065 0.3048)
			(stroke
				(width 0.1)
				(type default)
			)
			(layer "B.Fab")
		)
		(fp_line
			(start 0.12065 -0.2794)
			(end -0.12065 -0.2794)
			(stroke
				(width 0.1)
				(type default)
			)
			(layer "B.Fab")
		)
		(fp_line
			(start 0.12065 -0.305054)
			(end 0.12065 -0.2794)
			(stroke
				(width 0.1)
				(type default)
			)
			(layer "B.Fab")
		)
		(fp_line
			(start -0.120396 0.3048)
			(end -0.120396 0.2794)
			(stroke
				(width 0.1)
				(type default)
			)
			(layer "B.Fab")
		)
		(fp_line
			(start -0.120396 0.2794)
			(end 0.12065 0.2794)
			(stroke
				(width 0.1)
				(type default)
			)
			(layer "B.Fab")
		)
		(fp_line
			(start -0.12065 -0.2794)
			(end -0.12065 -0.3048)
			(stroke
				(width 0.1)
				(type default)
			)
			(layer "B.Fab")
		)
		(fp_line
			(start -0.12065 -0.3048)
			(end -0.67945 -0.3048)
			(stroke
				(width 0.1)
				(type default)
			)
			(layer "B.Fab")
		)
		(fp_line
			(start -0.67945 0.3048)
			(end -0.120396 0.3048)
			(stroke
				(width 0.1)
				(type default)
			)
			(layer "B.Fab")
		)
		(fp_line
			(start -0.67945 -0.3048)
			(end -0.67945 0.3048)
			(stroke
				(width 0.1)
				(type default)
			)
			(layer "B.Fab")
		)
		(pad "1" smd circle
			(at 0.40005 0)
			(size 0 0)
			(layers "B.Cu" "B.Mask" "B.Paste")
			(net "P3V3_NIC0")
		)
		(pad "2" smd circle
			(at -0.40005 0)
			(size 0 0)
			(layers "B.Cu" "B.Mask" "B.Paste")
			(net "GND")
		)
	)
	(footprint ""
		(layer "B.Cu")
		(at 107.621832 -347.210888)
		(property "Reference" "R6369"
			(at 0 0 0)
			(layer "B.SilkS")
			(hide yes)
			(effects
				(font
					(size 1.27 1.27)
				)
				(justify mirror)
			)
		)
		(property "Value" ""
			(at 0 0 0)
			(layer "B.Fab")
			(effects
				(font
					(size 1.27 1.27)
				)
				(justify mirror)
			)
		)
		(duplicate_pad_numbers_are_jumpers no)
		(fp_line
			(start -0.7874 -0.4064)
			(end -0.7874 0.4064)
			(stroke
				(width 0.1524)
				(type default)
			)
			(layer "B.SilkS")
		)
		(fp_line
			(start -0.7874 0.4064)
			(end 0.7874 0.4064)
			(stroke
				(width 0.1524)
				(type default)
			)
			(layer "B.SilkS")
		)
		(fp_line
			(start 0.7874 -0.4064)
			(end -0.7874 -0.4064)
			(stroke
				(width 0.1524)
				(type default)
			)
			(layer "B.SilkS")
		)
		(fp_line
			(start 0.7874 0.4064)
			(end 0.7874 -0.4064)
			(stroke
				(width 0.1524)
				(type default)
			)
			(layer "B.SilkS")
		)
		(fp_line
			(start -0.67945 -0.3048)
			(end -0.67945 0.3048)
			(stroke
				(width 0.1)
				(type default)
			)
			(layer "B.Fab")
		)
		(fp_line
			(start -0.67945 0.3048)
			(end -0.120396 0.3048)
			(stroke
				(width 0.1)
				(type default)
			)
			(layer "B.Fab")
		)
		(fp_line
			(start -0.12065 -0.3048)
			(end -0.67945 -0.3048)
			(stroke
				(width 0.1)
				(type default)
			)
			(layer "B.Fab")
		)
		(fp_line
			(start -0.12065 -0.2794)
			(end -0.12065 -0.3048)
			(stroke
				(width 0.1)
				(type default)
			)
			(layer "B.Fab")
		)
		(fp_line
			(start -0.120396 0.2794)
			(end 0.12065 0.2794)
			(stroke
				(width 0.1)
				(type default)
			)
			(layer "B.Fab")
		)
		(fp_line
			(start -0.120396 0.3048)
			(end -0.120396 0.2794)
			(stroke
				(width 0.1)
				(type default)
			)
			(layer "B.Fab")
		)
		(fp_line
			(start 0.12065 -0.305054)
			(end 0.12065 -0.2794)
			(stroke
				(width 0.1)
				(type default)
			)
			(layer "B.Fab")
		)
		(fp_line
			(start 0.12065 -0.2794)
			(end -0.12065 -0.2794)
			(stroke
				(width 0.1)
				(type default)
			)
			(layer "B.Fab")
		)
		(fp_line
			(start 0.12065 0.2794)
			(end 0.12065 0.3048)
			(stroke
				(width 0.1)
				(type default)
			)
			(layer "B.Fab")
		)
		(fp_line
			(start 0.12065 0.3048)
			(end 0.67945 0.3048)
			(stroke
				(width 0.1)
				(type default)
			)
			(layer "B.Fab")
		)
		(fp_line
			(start 0.67945 -0.305054)
			(end 0.12065 -0.305054)
			(stroke
				(width 0.1)
				(type default)
			)
			(layer "B.Fab")
		)
		(fp_line
			(start 0.67945 0.3048)
			(end 0.67945 -0.305054)
			(stroke
				(width 0.1)
				(type default)
			)
			(layer "B.Fab")
		)
		(pad "1" smd circle
			(at 0.40005 0 180)
			(size 0 0)
			(layers "B.Cu" "B.Mask" "B.Paste")
			(net "P3V3")
		)
		(pad "2" smd circle
			(at -0.40005 0 180)
			(size 0 0)
			(layers "B.Cu" "B.Mask" "B.Paste")
			(net "PU_9ZXL0451E_S3_HBW")
		)
	)
	(footprint ""
		(layer "B.Cu")
		(at 452.08444 -290.530788)
		(property "Reference" "PC1000"
			(at 0 0 0)
			(layer "B.SilkS")
			(hide yes)
			(effects
				(font
					(size 1.27 1.27)
				)
				(justify mirror)
			)
		)
		(property "Value" ""
			(at 0 0 0)
			(layer "B.Fab")
			(effects
				(font
					(size 1.27 1.27)
				)
				(justify mirror)
			)
		)
		(duplicate_pad_numbers_are_jumpers no)
		(fp_line
			(start -1.524 -0.762)
			(end -1.524 0.762)
			(stroke
				(width 0.1524)
				(type default)
			)
			(layer "B.SilkS")
		)
		(fp_line
			(start -1.524 0.762)
			(end 1.524 0.762)
			(stroke
				(width 0.1524)
				(type default)
			)
			(layer "B.SilkS")
		)
		(fp_line
			(start 1.524 -0.762)
			(end -1.524 -0.762)
			(stroke
				(width 0.1524)
				(type default)
			)
			(layer "B.SilkS")
		)
		(fp_line
			(start 1.524 0.762)
			(end 1.524 -0.762)
			(stroke
				(width 0.1524)
				(type default)
			)
			(layer "B.SilkS")
		)
		(fp_line
			(start -1.1049 -0.724916)
			(end 1.1049 -0.724916)
			(stroke
				(width 0.1)
				(type default)
			)
			(layer "B.Fab")
		)
		(fp_line
			(start -1.1049 0.724916)
			(end -1.1049 -0.724916)
			(stroke
				(width 0.1)
				(type default)
			)
			(layer "B.Fab")
		)
		(fp_line
			(start 1.1049 -0.724916)
			(end 1.1049 0.724916)
			(stroke
				(width 0.1)
				(type default)
			)
			(layer "B.Fab")
		)
		(fp_line
			(start 1.1049 0.724916)
			(end -1.1049 0.724916)
			(stroke
				(width 0.1)
				(type default)
			)
			(layer "B.Fab")
		)
		(pad "1" smd rect
			(at 0.889 0)
			(size 1.016 1.27)
			(layers "B.Cu" "B.Mask" "B.Paste")
			(net "P1V25_PEX3_R")
		)
		(pad "2" smd rect
			(at -0.889 0)
			(size 1.016 1.27)
			(layers "B.Cu" "B.Mask" "B.Paste")
			(net "GND")
		)
	)
	(footprint ""
		(layer "B.Cu")
		(at 61.597286 -110.497366)
		(property "Reference" "R84"
			(at 0 0 0)
			(layer "B.SilkS")
			(hide yes)
			(effects
				(font
					(size 1.27 1.27)
				)
				(justify mirror)
			)
		)
		(property "Value" ""
			(at 0 0 0)
			(layer "B.Fab")
			(effects
				(font
					(size 1.27 1.27)
				)
				(justify mirror)
			)
		)
		(duplicate_pad_numbers_are_jumpers no)
		(fp_line
			(start -0.7874 -0.4064)
			(end -0.7874 0.4064)
			(stroke
				(width 0.1524)
				(type default)
			)
			(layer "B.SilkS")
		)
		(fp_line
			(start -0.7874 0.4064)
			(end 0.7874 0.4064)
			(stroke
				(width 0.1524)
				(type default)
			)
			(layer "B.SilkS")
		)
		(fp_line
			(start 0.7874 -0.4064)
			(end -0.7874 -0.4064)
			(stroke
				(width 0.1524)
				(type default)
			)
			(layer "B.SilkS")
		)
		(fp_line
			(start 0.7874 0.4064)
			(end 0.7874 -0.4064)
			(stroke
				(width 0.1524)
				(type default)
			)
			(layer "B.SilkS")
		)
		(fp_line
			(start -0.67945 -0.3048)
			(end -0.67945 0.3048)
			(stroke
				(width 0.1)
				(type default)
			)
			(layer "B.Fab")
		)
		(fp_line
			(start -0.67945 0.3048)
			(end -0.120396 0.3048)
			(stroke
				(width 0.1)
				(type default)
			)
			(layer "B.Fab")
		)
		(fp_line
			(start -0.12065 -0.3048)
			(end -0.67945 -0.3048)
			(stroke
				(width 0.1)
				(type default)
			)
			(layer "B.Fab")
		)
		(fp_line
			(start -0.12065 -0.2794)
			(end -0.12065 -0.3048)
			(stroke
				(width 0.1)
				(type default)
			)
			(layer "B.Fab")
		)
		(fp_line
			(start -0.120396 0.2794)
			(end 0.12065 0.2794)
			(stroke
				(width 0.1)
				(type default)
			)
			(layer "B.Fab")
		)
		(fp_line
			(start -0.120396 0.3048)
			(end -0.120396 0.2794)
			(stroke
				(width 0.1)
				(type default)
			)
			(layer "B.Fab")
		)
		(fp_line
			(start 0.12065 -0.305054)
			(end 0.12065 -0.2794)
			(stroke
				(width 0.1)
				(type default)
			)
			(layer "B.Fab")
		)
		(fp_line
			(start 0.12065 -0.2794)
			(end -0.12065 -0.2794)
			(stroke
				(width 0.1)
				(type default)
			)
			(layer "B.Fab")
		)
		(fp_line
			(start 0.12065 0.2794)
			(end 0.12065 0.3048)
			(stroke
				(width 0.1)
				(type default)
			)
			(layer "B.Fab")
		)
		(fp_line
			(start 0.12065 0.3048)
			(end 0.67945 0.3048)
			(stroke
				(width 0.1)
				(type default)
			)
			(layer "B.Fab")
		)
		(fp_line
			(start 0.67945 -0.305054)
			(end 0.12065 -0.305054)
			(stroke
				(width 0.1)
				(type default)
			)
			(layer "B.Fab")
		)
		(fp_line
			(start 0.67945 0.3048)
			(end 0.67945 -0.305054)
			(stroke
				(width 0.1)
				(type default)
			)
			(layer "B.Fab")
		)
		(pad "1" smd circle
			(at 0.40005 0 180)
			(size 0 0)
			(layers "B.Cu" "B.Mask" "B.Paste")
			(net "NIC1_BIF2_N")
		)
		(pad "2" smd circle
			(at -0.40005 0 180)
			(size 0 0)
			(layers "B.Cu" "B.Mask" "B.Paste")
			(net "P3V3_AUX")
		)
	)
	(footprint ""
		(layer "B.Cu")
		(at 278.935942 -298.27474)
		(property "Reference" "C3416"
			(at 0 0 0)
			(layer "B.SilkS")
			(hide yes)
			(effects
				(font
					(size 1.27 1.27)
				)
				(justify mirror)
			)
		)
		(property "Value" ""
			(at 0 0 0)
			(layer "B.Fab")
			(effects
				(font
					(size 1.27 1.27)
				)
				(justify mirror)
			)
		)
		(duplicate_pad_numbers_are_jumpers no)
		(fp_line
			(start -0.299974 -0.150114)
			(end -0.299974 0.150114)
			(stroke
				(width 0.1)
				(type default)
			)
			(layer "B.Fab")
		)
		(fp_line
			(start -0.299974 0.150114)
			(end 0.299974 0.150114)
			(stroke
				(width 0.1)
				(type default)
			)
			(layer "B.Fab")
		)
		(fp_line
			(start 0.299974 -0.150114)
			(end -0.299974 -0.150114)
			(stroke
				(width 0.1)
				(type default)
			)
			(layer "B.Fab")
		)
		(fp_line
			(start 0.299974 0.150114)
			(end 0.299974 -0.150114)
			(stroke
				(width 0.1)
				(type default)
			)
			(layer "B.Fab")
		)
		(pad "1" smd rect
			(at 0.2667 0 180)
			(size 0.3048 0.381)
			(layers "B.Cu" "B.Mask" "B.Paste")
			(net "SYSPLL_VDDA18_PEX2")
		)
		(pad "2" smd rect
			(at -0.2667 0 180)
			(size 0.3048 0.381)
			(layers "B.Cu" "B.Mask" "B.Paste")
			(net "GND")
		)
	)
	(footprint ""
		(layer "B.Cu")
		(at 412.699962 -301.599854 -90)
		(property "Reference" "C1993"
			(at 0 0 90)
			(layer "B.SilkS")
			(hide yes)
			(effects
				(font
					(size 1.27 1.27)
				)
				(justify mirror)
			)
		)
		(property "Value" ""
			(at 0 0 90)
			(layer "B.Fab")
			(effects
				(font
					(size 1.27 1.27)
				)
				(justify mirror)
			)
		)
		(duplicate_pad_numbers_are_jumpers no)
		(fp_line
			(start -0.299974 0.150114)
			(end 0.299974 0.150114)
			(stroke
				(width 0.1)
				(type default)
			)
			(layer "B.Fab")
		)
		(fp_line
			(start 0.299974 0.150114)
			(end 0.299974 -0.150114)
			(stroke
				(width 0.1)
				(type default)
			)
			(layer "B.Fab")
		)
		(fp_line
			(start -0.299974 -0.150114)
			(end -0.299974 0.150114)
			(stroke
				(width 0.1)
				(type default)
			)
			(layer "B.Fab")
		)
		(fp_line
			(start 0.299974 -0.150114)
			(end -0.299974 -0.150114)
			(stroke
				(width 0.1)
				(type default)
			)
			(layer "B.Fab")
		)
		(pad "1" smd rect
			(at 0.2667 0 90)
			(size 0.3048 0.381)
			(layers "B.Cu" "B.Mask" "B.Paste")
			(net "P0V8_SERDES_VDDA_PEX3")
		)
		(pad "2" smd rect
			(at -0.2667 0 90)
			(size 0.3048 0.381)
			(layers "B.Cu" "B.Mask" "B.Paste")
			(net "GND")
		)
	)
	(footprint ""
		(layer "B.Cu")
		(at 132.78231 -325.30923 -90)
		(property "Reference" "C4259"
			(at 0 0 90)
			(layer "B.SilkS")
			(hide yes)
			(effects
				(font
					(size 1.27 1.27)
				)
				(justify mirror)
			)
		)
		(property "Value" ""
			(at 0 0 90)
			(layer "B.Fab")
			(effects
				(font
					(size 1.27 1.27)
				)
				(justify mirror)
			)
		)
		(duplicate_pad_numbers_are_jumpers no)
		(fp_line
			(start -1.2954 0.5842)
			(end 1.2954 0.5842)
			(stroke
				(width 0.1524)
				(type default)
			)
			(layer "B.SilkS")
		)
		(fp_line
			(start 1.2954 0.5842)
			(end 1.2954 -0.5842)
			(stroke
				(width 0.1524)
				(type default)
			)
			(layer "B.SilkS")
		)
		(fp_line
			(start -1.2954 -0.5842)
			(end -1.2954 0.5842)
			(stroke
				(width 0.1524)
				(type default)
			)
			(layer "B.SilkS")
		)
		(fp_line
			(start 1.2954 -0.5842)
			(end -1.2954 -0.5842)
			(stroke
				(width 0.1524)
				(type default)
			)
			(layer "B.SilkS")
		)
		(fp_line
			(start -0.8636 0.4572)
			(end 0.8636 0.4572)
			(stroke
				(width 0.1)
				(type default)
			)
			(layer "B.Fab")
		)
		(fp_line
			(start 0.8636 0.4572)
			(end 0.8636 0.4064)
			(stroke
				(width 0.1)
				(type default)
			)
			(layer "B.Fab")
		)
		(fp_line
			(start -1.1938 0.4064)
			(end -0.8636 0.4064)
			(stroke
				(width 0.1)
				(type default)
			)
			(layer "B.Fab")
		)
		(fp_line
			(start -0.8636 0.4064)
			(end -0.8636 0.4572)
			(stroke
				(width 0.1)
				(type default)
			)
			(layer "B.Fab")
		)
		(fp_line
			(start 0.8636 0.4064)
			(end 1.1938 0.4064)
			(stroke
				(width 0.1)
				(type default)
			)
			(layer "B.Fab")
		)
		(fp_line
			(start 1.1938 0.4064)
			(end 1.1938 -0.4064)
			(stroke
				(width 0.1)
				(type default)
			)
			(layer "B.Fab")
		)
		(fp_line
			(start -1.1938 -0.4064)
			(end -1.1938 0.4064)
			(stroke
				(width 0.1)
				(type default)
			)
			(layer "B.Fab")
		)
		(fp_line
			(start -0.8636 -0.4064)
			(end -1.1938 -0.4064)
			(stroke
				(width 0.1)
				(type default)
			)
			(layer "B.Fab")
		)
		(fp_line
			(start 0.8636 -0.4064)
			(end 0.8636 -0.4572)
			(stroke
				(width 0.1)
				(type default)
			)
			(layer "B.Fab")
		)
		(fp_line
			(start 1.1938 -0.4064)
			(end 0.8636 -0.4064)
			(stroke
				(width 0.1)
				(type default)
			)
			(layer "B.Fab")
		)
		(fp_line
			(start -0.8636 -0.4572)
			(end -0.8636 -0.4064)
			(stroke
				(width 0.1)
				(type default)
			)
			(layer "B.Fab")
		)
		(fp_line
			(start 0.8636 -0.4572)
			(end -0.8636 -0.4572)
			(stroke
				(width 0.1)
				(type default)
			)
			(layer "B.Fab")
		)
		(pad "1" smd rect
			(at 0.7366 0 180)
			(size 0.7112 0.8128)
			(layers "B.Cu" "B.Mask" "B.Paste")
			(net "P0V8_SERDES_VDDA_PEX1_C5")
		)
		(pad "2" smd rect
			(at -0.7366 0 180)
			(size 0.7112 0.8128)
			(layers "B.Cu" "B.Mask" "B.Paste")
			(net "GND")
		)
	)
	(footprint ""
		(layer "B.Cu")
		(at 48.04156 -303.024794)
		(property "Reference" "C2995"
			(at 0 0 0)
			(layer "B.SilkS")
			(hide yes)
			(effects
				(font
					(size 1.27 1.27)
				)
				(justify mirror)
			)
		)
		(property "Value" ""
			(at 0 0 0)
			(layer "B.Fab")
			(effects
				(font
					(size 1.27 1.27)
				)
				(justify mirror)
			)
		)
		(duplicate_pad_numbers_are_jumpers no)
		(fp_line
			(start -0.299974 -0.150114)
			(end -0.299974 0.150114)
			(stroke
				(width 0.1)
				(type default)
			)
			(layer "B.Fab")
		)
		(fp_line
			(start -0.299974 0.150114)
			(end 0.299974 0.150114)
			(stroke
				(width 0.1)
				(type default)
			)
			(layer "B.Fab")
		)
		(fp_line
			(start 0.299974 -0.150114)
			(end -0.299974 -0.150114)
			(stroke
				(width 0.1)
				(type default)
			)
			(layer "B.Fab")
		)
		(fp_line
			(start 0.299974 0.150114)
			(end 0.299974 -0.150114)
			(stroke
				(width 0.1)
				(type default)
			)
			(layer "B.Fab")
		)
		(pad "1" smd rect
			(at 0.2667 0 180)
			(size 0.3048 0.381)
			(layers "B.Cu" "B.Mask" "B.Paste")
			(net "P1V8_VDDA_PEX0")
		)
		(pad "2" smd rect
			(at -0.2667 0 180)
			(size 0.3048 0.381)
			(layers "B.Cu" "B.Mask" "B.Paste")
			(net "GND")
		)
	)
	(footprint ""
		(layer "B.Cu")
		(at 302.303942 -97.663)
		(property "Reference" "R259"
			(at 0 0 0)
			(layer "B.SilkS")
			(hide yes)
			(effects
				(font
					(size 1.27 1.27)
				)
				(justify mirror)
			)
		)
		(property "Value" ""
			(at 0 0 0)
			(layer "B.Fab")
			(effects
				(font
					(size 1.27 1.27)
				)
				(justify mirror)
			)
		)
		(duplicate_pad_numbers_are_jumpers no)
		(fp_line
			(start -0.7874 -0.4064)
			(end -0.7874 0.4064)
			(stroke
				(width 0.1524)
				(type default)
			)
			(layer "B.SilkS")
		)
		(fp_line
			(start -0.7874 0.4064)
			(end 0.7874 0.4064)
			(stroke
				(width 0.1524)
				(type default)
			)
			(layer "B.SilkS")
		)
		(fp_line
			(start 0.7874 -0.4064)
			(end -0.7874 -0.4064)
			(stroke
				(width 0.1524)
				(type default)
			)
			(layer "B.SilkS")
		)
		(fp_line
			(start 0.7874 0.4064)
			(end 0.7874 -0.4064)
			(stroke
				(width 0.1524)
				(type default)
			)
			(layer "B.SilkS")
		)
		(fp_line
			(start -0.67945 -0.3048)
			(end -0.67945 0.3048)
			(stroke
				(width 0.1)
				(type default)
			)
			(layer "B.Fab")
		)
		(fp_line
			(start -0.67945 0.3048)
			(end -0.120396 0.3048)
			(stroke
				(width 0.1)
				(type default)
			)
			(layer "B.Fab")
		)
		(fp_line
			(start -0.12065 -0.3048)
			(end -0.67945 -0.3048)
			(stroke
				(width 0.1)
				(type default)
			)
			(layer "B.Fab")
		)
		(fp_line
			(start -0.12065 -0.2794)
			(end -0.12065 -0.3048)
			(stroke
				(width 0.1)
				(type default)
			)
			(layer "B.Fab")
		)
		(fp_line
			(start -0.120396 0.2794)
			(end 0.12065 0.2794)
			(stroke
				(width 0.1)
				(type default)
			)
			(layer "B.Fab")
		)
		(fp_line
			(start -0.120396 0.3048)
			(end -0.120396 0.2794)
			(stroke
				(width 0.1)
				(type default)
			)
			(layer "B.Fab")
		)
		(fp_line
			(start 0.12065 -0.305054)
			(end 0.12065 -0.2794)
			(stroke
				(width 0.1)
				(type default)
			)
			(layer "B.Fab")
		)
		(fp_line
			(start 0.12065 -0.2794)
			(end -0.12065 -0.2794)
			(stroke
				(width 0.1)
				(type default)
			)
			(layer "B.Fab")
		)
		(fp_line
			(start 0.12065 0.2794)
			(end 0.12065 0.3048)
			(stroke
				(width 0.1)
				(type default)
			)
			(layer "B.Fab")
		)
		(fp_line
			(start 0.12065 0.3048)
			(end 0.67945 0.3048)
			(stroke
				(width 0.1)
				(type default)
			)
			(layer "B.Fab")
		)
		(fp_line
			(start 0.67945 -0.305054)
			(end 0.12065 -0.305054)
			(stroke
				(width 0.1)
				(type default)
			)
			(layer "B.Fab")
		)
		(fp_line
			(start 0.67945 0.3048)
			(end 0.67945 -0.305054)
			(stroke
				(width 0.1)
				(type default)
			)
			(layer "B.Fab")
		)
		(pad "1" smd circle
			(at 0.40005 0 180)
			(size 0 0)
			(layers "B.Cu" "B.Mask" "B.Paste")
			(net "PWRGD_NIC5_PWR_GOOD")
		)
		(pad "2" smd circle
			(at -0.40005 0 180)
			(size 0 0)
			(layers "B.Cu" "B.Mask" "B.Paste")
			(net "PWRGD_NIC5_PWR_GOOD_R")
		)
	)
	(footprint ""
		(layer "B.Cu")
		(at 288.46272 -197.910196)
		(property "Reference" "Q241"
			(at 1.651 -2.25933 0)
			(unlocked yes)
			(layer "B.SilkS")
			(effects
				(font
					(size 0.7874 0.5842)
					(thickness 0.1524)
				)
				(justify left mirror)
			)
		)
		(property "Value" ""
			(at 0 0 0)
			(layer "B.Fab")
			(effects
				(font
					(size 1.27 1.27)
				)
				(justify mirror)
			)
		)
		(duplicate_pad_numbers_are_jumpers no)
		(fp_line
			(start -1.603248 -1.500124)
			(end -1.603248 1.500124)
			(stroke
				(width 0.1524)
				(type default)
			)
			(layer "B.SilkS")
		)
		(fp_line
			(start -1.603248 1.500124)
			(end 1.603248 1.500124)
			(stroke
				(width 0.1524)
				(type default)
			)
			(layer "B.SilkS")
		)
		(fp_line
			(start 1.603248 -1.500124)
			(end -1.603248 -1.500124)
			(stroke
				(width 0.1524)
				(type default)
			)
			(layer "B.SilkS")
		)
		(fp_line
			(start 1.603248 1.500124)
			(end 1.603248 -1.500124)
			(stroke
				(width 0.1524)
				(type default)
			)
			(layer "B.SilkS")
		)
		(fp_line
			(start -1.249934 -0.219964)
			(end -0.700024 -0.219964)
			(stroke
				(width 0.1)
				(type default)
			)
			(layer "B.Fab")
		)
		(fp_line
			(start -1.249934 0.219964)
			(end -1.249934 -0.219964)
			(stroke
				(width 0.1)
				(type default)
			)
			(layer "B.Fab")
		)
		(fp_line
			(start -0.700024 -1.500124)
			(end 0.700024 -1.500124)
			(stroke
				(width 0.1)
				(type default)
			)
			(layer "B.Fab")
		)
		(fp_line
			(start -0.700024 -0.219964)
			(end -0.700024 -1.500124)
			(stroke
				(width 0.1)
				(type default)
			)
			(layer "B.Fab")
		)
		(fp_line
			(start -0.700024 0.219964)
			(end -1.249934 0.219964)
			(stroke
				(width 0.1)
				(type default)
			)
			(layer "B.Fab")
		)
		(fp_line
			(start -0.700024 1.500124)
			(end -0.700024 0.219964)
			(stroke
				(width 0.1)
				(type default)
			)
			(layer "B.Fab")
		)
		(fp_line
			(start 0.6985 -0.729996)
			(end 0.6985 0.729996)
			(stroke
				(width 0.1)
				(type default)
			)
			(layer "B.Fab")
		)
		(fp_line
			(start 0.6985 0.729996)
			(end 1.249934 0.729996)
			(stroke
				(width 0.1)
				(type default)
			)
			(layer "B.Fab")
		)
		(fp_line
			(start 0.700024 -1.500124)
			(end 0.700024 -1.169924)
			(stroke
				(width 0.1)
				(type default)
			)
			(layer "B.Fab")
		)
		(fp_line
			(start 0.700024 -1.169924)
			(end 1.249934 -1.169924)
			(stroke
				(width 0.1)
				(type default)
			)
			(layer "B.Fab")
		)
		(fp_line
			(start 0.700024 1.169924)
			(end 0.700024 1.500124)
			(stroke
				(width 0.1)
				(type default)
			)
			(layer "B.Fab")
		)
		(fp_line
			(start 0.700024 1.500124)
			(end -0.700024 1.500124)
			(stroke
				(width 0.1)
				(type default)
			)
			(layer "B.Fab")
		)
		(fp_line
			(start 1.249934 -1.169924)
			(end 1.249934 -0.729996)
			(stroke
				(width 0.1)
				(type default)
			)
			(layer "B.Fab")
		)
		(fp_line
			(start 1.249934 -0.729996)
			(end 0.6985 -0.729996)
			(stroke
				(width 0.1)
				(type default)
			)
			(layer "B.Fab")
		)
		(fp_line
			(start 1.249934 0.729996)
			(end 1.249934 1.169924)
			(stroke
				(width 0.1)
				(type default)
			)
			(layer "B.Fab")
		)
		(fp_line
			(start 1.249934 1.169924)
			(end 0.700024 1.169924)
			(stroke
				(width 0.1)
				(type default)
			)
			(layer "B.Fab")
		)
		(fp_rect
			(start 0.700024 1.500124)
			(end -0.700024 -1.500124)
			(stroke
				(width 0)
				(type default)
			)
			(fill no)
			(layer "B.Fab")
		)
		(pad "D" smd rect
			(at -0.999998 0 270)
			(size 0.8128 0.9144)
			(layers "B.Cu" "B.Mask" "B.Paste")
			(net "SPI_BIC1_LS23_EN_N")
		)
		(pad "G" smd rect
			(at 0.999998 -0.94996 270)
			(size 0.8128 0.9144)
			(layers "B.Cu" "B.Mask" "B.Paste")
			(net "SPI_BIC1_LS23_EN")
		)
		(pad "S" smd rect
			(at 0.999998 0.94996 270)
			(size 0.8128 0.9144)
			(layers "B.Cu" "B.Mask" "B.Paste")
			(net "GND")
		)
	)
	(footprint ""
		(layer "B.Cu")
		(at 208.279238 -227.04679)
		(property "Reference" "R6822"
			(at 0 0 0)
			(layer "B.SilkS")
			(hide yes)
			(effects
				(font
					(size 1.27 1.27)
				)
				(justify mirror)
			)
		)
		(property "Value" ""
			(at 0 0 0)
			(layer "B.Fab")
			(effects
				(font
					(size 1.27 1.27)
				)
				(justify mirror)
			)
		)
		(duplicate_pad_numbers_are_jumpers no)
		(fp_line
			(start -0.7874 -0.4064)
			(end -0.7874 0.4064)
			(stroke
				(width 0.1524)
				(type default)
			)
			(layer "B.SilkS")
		)
		(fp_line
			(start -0.7874 0.4064)
			(end 0.7874 0.4064)
			(stroke
				(width 0.1524)
				(type default)
			)
			(layer "B.SilkS")
		)
		(fp_line
			(start 0.7874 -0.4064)
			(end -0.7874 -0.4064)
			(stroke
				(width 0.1524)
				(type default)
			)
			(layer "B.SilkS")
		)
		(fp_line
			(start 0.7874 0.4064)
			(end 0.7874 -0.4064)
			(stroke
				(width 0.1524)
				(type default)
			)
			(layer "B.SilkS")
		)
		(fp_line
			(start -0.67945 -0.3048)
			(end -0.67945 0.3048)
			(stroke
				(width 0.1)
				(type default)
			)
			(layer "B.Fab")
		)
		(fp_line
			(start -0.67945 0.3048)
			(end -0.120396 0.3048)
			(stroke
				(width 0.1)
				(type default)
			)
			(layer "B.Fab")
		)
		(fp_line
			(start -0.12065 -0.3048)
			(end -0.67945 -0.3048)
			(stroke
				(width 0.1)
				(type default)
			)
			(layer "B.Fab")
		)
		(fp_line
			(start -0.12065 -0.2794)
			(end -0.12065 -0.3048)
			(stroke
				(width 0.1)
				(type default)
			)
			(layer "B.Fab")
		)
		(fp_line
			(start -0.120396 0.2794)
			(end 0.12065 0.2794)
			(stroke
				(width 0.1)
				(type default)
			)
			(layer "B.Fab")
		)
		(fp_line
			(start -0.120396 0.3048)
			(end -0.120396 0.2794)
			(stroke
				(width 0.1)
				(type default)
			)
			(layer "B.Fab")
		)
		(fp_line
			(start 0.12065 -0.305054)
			(end 0.12065 -0.2794)
			(stroke
				(width 0.1)
				(type default)
			)
			(layer "B.Fab")
		)
		(fp_line
			(start 0.12065 -0.2794)
			(end -0.12065 -0.2794)
			(stroke
				(width 0.1)
				(type default)
			)
			(layer "B.Fab")
		)
		(fp_line
			(start 0.12065 0.2794)
			(end 0.12065 0.3048)
			(stroke
				(width 0.1)
				(type default)
			)
			(layer "B.Fab")
		)
		(fp_line
			(start 0.12065 0.3048)
			(end 0.67945 0.3048)
			(stroke
				(width 0.1)
				(type default)
			)
			(layer "B.Fab")
		)
		(fp_line
			(start 0.67945 -0.305054)
			(end 0.12065 -0.305054)
			(stroke
				(width 0.1)
				(type default)
			)
			(layer "B.Fab")
		)
		(fp_line
			(start 0.67945 0.3048)
			(end 0.67945 -0.305054)
			(stroke
				(width 0.1)
				(type default)
			)
			(layer "B.Fab")
		)
		(pad "1" smd circle
			(at 0.40005 0 180)
			(size 0 0)
			(layers "B.Cu" "B.Mask" "B.Paste")
			(net "ADC_TYPE_ADC_R")
		)
		(pad "2" smd circle
			(at -0.40005 0 180)
			(size 0 0)
			(layers "B.Cu" "B.Mask" "B.Paste")
			(net "P3V3_AUX")
		)
	)
	(footprint ""
		(layer "B.Cu")
		(at 112.73536 -308.580028 90)
		(property "Reference" "C4198"
			(at 0 0 90)
			(layer "B.SilkS")
			(hide yes)
			(effects
				(font
					(size 1.27 1.27)
				)
				(justify mirror)
			)
		)
		(property "Value" ""
			(at 0 0 90)
			(layer "B.Fab")
			(effects
				(font
					(size 1.27 1.27)
				)
				(justify mirror)
			)
		)
		(duplicate_pad_numbers_are_jumpers no)
		(fp_line
			(start 1.2954 -0.5842)
			(end -1.2954 -0.5842)
			(stroke
				(width 0.1524)
				(type default)
			)
			(layer "B.SilkS")
		)
		(fp_line
			(start -1.2954 -0.5842)
			(end -1.2954 0.5842)
			(stroke
				(width 0.1524)
				(type default)
			)
			(layer "B.SilkS")
		)
		(fp_line
			(start 1.2954 0.5842)
			(end 1.2954 -0.5842)
			(stroke
				(width 0.1524)
				(type default)
			)
			(layer "B.SilkS")
		)
		(fp_line
			(start -1.2954 0.5842)
			(end 1.2954 0.5842)
			(stroke
				(width 0.1524)
				(type default)
			)
			(layer "B.SilkS")
		)
		(fp_line
			(start 0.8636 -0.4572)
			(end -0.8636 -0.4572)
			(stroke
				(width 0.1)
				(type default)
			)
			(layer "B.Fab")
		)
		(fp_line
			(start -0.8636 -0.4572)
			(end -0.8636 -0.4064)
			(stroke
				(width 0.1)
				(type default)
			)
			(layer "B.Fab")
		)
		(fp_line
			(start 1.1938 -0.4064)
			(end 0.8636 -0.4064)
			(stroke
				(width 0.1)
				(type default)
			)
			(layer "B.Fab")
		)
		(fp_line
			(start 0.8636 -0.4064)
			(end 0.8636 -0.4572)
			(stroke
				(width 0.1)
				(type default)
			)
			(layer "B.Fab")
		)
		(fp_line
			(start -0.8636 -0.4064)
			(end -1.1938 -0.4064)
			(stroke
				(width 0.1)
				(type default)
			)
			(layer "B.Fab")
		)
		(fp_line
			(start -1.1938 -0.4064)
			(end -1.1938 0.4064)
			(stroke
				(width 0.1)
				(type default)
			)
			(layer "B.Fab")
		)
		(fp_line
			(start 1.1938 0.4064)
			(end 1.1938 -0.4064)
			(stroke
				(width 0.1)
				(type default)
			)
			(layer "B.Fab")
		)
		(fp_line
			(start 0.8636 0.4064)
			(end 1.1938 0.4064)
			(stroke
				(width 0.1)
				(type default)
			)
			(layer "B.Fab")
		)
		(fp_line
			(start -0.8636 0.4064)
			(end -0.8636 0.4572)
			(stroke
				(width 0.1)
				(type default)
			)
			(layer "B.Fab")
		)
		(fp_line
			(start -1.1938 0.4064)
			(end -0.8636 0.4064)
			(stroke
				(width 0.1)
				(type default)
			)
			(layer "B.Fab")
		)
		(fp_line
			(start 0.8636 0.4572)
			(end 0.8636 0.4064)
			(stroke
				(width 0.1)
				(type default)
			)
			(layer "B.Fab")
		)
		(fp_line
			(start -0.8636 0.4572)
			(end 0.8636 0.4572)
			(stroke
				(width 0.1)
				(type default)
			)
			(layer "B.Fab")
		)
		(pad "1" smd rect
			(at 0.7366 0)
			(size 0.7112 0.8128)
			(layers "B.Cu" "B.Mask" "B.Paste")
			(net "P0V8_PEX0")
		)
		(pad "2" smd rect
			(at -0.7366 0)
			(size 0.7112 0.8128)
			(layers "B.Cu" "B.Mask" "B.Paste")
			(net "GND")
		)
	)
	(footprint ""
		(layer "B.Cu")
		(at 353.277424 -281.024838 90)
		(property "Reference" "PC174"
			(at 0 0 90)
			(layer "B.SilkS")
			(hide yes)
			(effects
				(font
					(size 1.27 1.27)
				)
				(justify mirror)
			)
		)
		(property "Value" ""
			(at 0 0 90)
			(layer "B.Fab")
			(effects
				(font
					(size 1.27 1.27)
				)
				(justify mirror)
			)
		)
		(duplicate_pad_numbers_are_jumpers no)
		(fp_line
			(start 1.524 -0.762)
			(end -1.524 -0.762)
			(stroke
				(width 0.1524)
				(type default)
			)
			(layer "B.SilkS")
		)
		(fp_line
			(start -1.524 -0.762)
			(end -1.524 0.762)
			(stroke
				(width 0.1524)
				(type default)
			)
			(layer "B.SilkS")
		)
		(fp_line
			(start 1.524 0.762)
			(end 1.524 -0.762)
			(stroke
				(width 0.1524)
				(type default)
			)
			(layer "B.SilkS")
		)
		(fp_line
			(start -1.524 0.762)
			(end 1.524 0.762)
			(stroke
				(width 0.1524)
				(type default)
			)
			(layer "B.SilkS")
		)
		(fp_line
			(start 1.1049 -0.724916)
			(end 1.1049 0.724916)
			(stroke
				(width 0.1)
				(type default)
			)
			(layer "B.Fab")
		)
		(fp_line
			(start -1.1049 -0.724916)
			(end 1.1049 -0.724916)
			(stroke
				(width 0.1)
				(type default)
			)
			(layer "B.Fab")
		)
		(fp_line
			(start 1.1049 0.724916)
			(end -1.1049 0.724916)
			(stroke
				(width 0.1)
				(type default)
			)
			(layer "B.Fab")
		)
		(fp_line
			(start -1.1049 0.724916)
			(end -1.1049 -0.724916)
			(stroke
				(width 0.1)
				(type default)
			)
			(layer "B.Fab")
		)
		(pad "1" smd rect
			(at 0.889 0 90)
			(size 1.016 1.27)
			(layers "B.Cu" "B.Mask" "B.Paste")
			(net "SW_P12V_P0V8_PEX3_FLT")
		)
		(pad "2" smd rect
			(at -0.889 0 90)
			(size 1.016 1.27)
			(layers "B.Cu" "B.Mask" "B.Paste")
			(net "GND")
		)
	)
	(footprint ""
		(layer "B.Cu")
		(at 72.949816 -295.89984 180)
		(property "Reference" "C2977"
			(at 0 0 0)
			(layer "B.SilkS")
			(hide yes)
			(effects
				(font
					(size 1.27 1.27)
				)
				(justify mirror)
			)
		)
		(property "Value" ""
			(at 0 0 0)
			(layer "B.Fab")
			(effects
				(font
					(size 1.27 1.27)
				)
				(justify mirror)
			)
		)
		(duplicate_pad_numbers_are_jumpers no)
		(fp_line
			(start 0.299974 0.150114)
			(end 0.299974 -0.150114)
			(stroke
				(width 0.1)
				(type default)
			)
			(layer "B.Fab")
		)
		(fp_line
			(start 0.299974 -0.150114)
			(end -0.299974 -0.150114)
			(stroke
				(width 0.1)
				(type default)
			)
			(layer "B.Fab")
		)
		(fp_line
			(start -0.299974 0.150114)
			(end 0.299974 0.150114)
			(stroke
				(width 0.1)
				(type default)
			)
			(layer "B.Fab")
		)
		(fp_line
			(start -0.299974 -0.150114)
			(end -0.299974 0.150114)
			(stroke
				(width 0.1)
				(type default)
			)
			(layer "B.Fab")
		)
		(pad "1" smd rect
			(at 0.2667 0)
			(size 0.3048 0.381)
			(layers "B.Cu" "B.Mask" "B.Paste")
			(net "P1V25_SERDES_VDDPLL_PEX0")
		)
		(pad "2" smd rect
			(at -0.2667 0)
			(size 0.3048 0.381)
			(layers "B.Cu" "B.Mask" "B.Paste")
			(net "GND")
		)
	)
	(footprint ""
		(layer "B.Cu")
		(at 55.849774 -290.199826 90)
		(property "Reference" "C1215"
			(at 0 0 90)
			(layer "B.SilkS")
			(hide yes)
			(effects
				(font
					(size 1.27 1.27)
				)
				(justify mirror)
			)
		)
		(property "Value" ""
			(at 0 0 90)
			(layer "B.Fab")
			(effects
				(font
					(size 1.27 1.27)
				)
				(justify mirror)
			)
		)
		(duplicate_pad_numbers_are_jumpers no)
		(fp_line
			(start 0.299974 -0.150114)
			(end -0.299974 -0.150114)
			(stroke
				(width 0.1)
				(type default)
			)
			(layer "B.Fab")
		)
		(fp_line
			(start -0.299974 -0.150114)
			(end -0.299974 0.150114)
			(stroke
				(width 0.1)
				(type default)
			)
			(layer "B.Fab")
		)
		(fp_line
			(start 0.299974 0.150114)
			(end 0.299974 -0.150114)
			(stroke
				(width 0.1)
				(type default)
			)
			(layer "B.Fab")
		)
		(fp_line
			(start -0.299974 0.150114)
			(end 0.299974 0.150114)
			(stroke
				(width 0.1)
				(type default)
			)
			(layer "B.Fab")
		)
		(pad "1" smd rect
			(at 0.2667 0 270)
			(size 0.3048 0.381)
			(layers "B.Cu" "B.Mask" "B.Paste")
			(net "P0V8_SERDES_VDDA_PEX0")
		)
		(pad "2" smd rect
			(at -0.2667 0 270)
			(size 0.3048 0.381)
			(layers "B.Cu" "B.Mask" "B.Paste")
			(net "GND")
		)
	)
	(footprint ""
		(layer "B.Cu")
		(at 133.175756 -182.347362 180)
		(property "Reference" "C2653"
			(at 0 0 0)
			(layer "B.SilkS")
			(hide yes)
			(effects
				(font
					(size 1.27 1.27)
				)
				(justify mirror)
			)
		)
		(property "Value" ""
			(at 0 0 0)
			(layer "B.Fab")
			(effects
				(font
					(size 1.27 1.27)
				)
				(justify mirror)
			)
		)
		(duplicate_pad_numbers_are_jumpers no)
		(fp_line
			(start 1.2954 0.5842)
			(end 1.2954 -0.5842)
			(stroke
				(width 0.1524)
				(type default)
			)
			(layer "B.SilkS")
		)
		(fp_line
			(start 1.2954 -0.5842)
			(end -1.2954 -0.5842)
			(stroke
				(width 0.1524)
				(type default)
			)
			(layer "B.SilkS")
		)
		(fp_line
			(start -1.2954 0.5842)
			(end 1.2954 0.5842)
			(stroke
				(width 0.1524)
				(type default)
			)
			(layer "B.SilkS")
		)
		(fp_line
			(start -1.2954 -0.5842)
			(end -1.2954 0.5842)
			(stroke
				(width 0.1524)
				(type default)
			)
			(layer "B.SilkS")
		)
		(fp_line
			(start 1.1938 0.4064)
			(end 1.1938 -0.4064)
			(stroke
				(width 0.1)
				(type default)
			)
			(layer "B.Fab")
		)
		(fp_line
			(start 1.1938 -0.4064)
			(end 0.8636 -0.4064)
			(stroke
				(width 0.1)
				(type default)
			)
			(layer "B.Fab")
		)
		(fp_line
			(start 0.8636 0.4572)
			(end 0.8636 0.4064)
			(stroke
				(width 0.1)
				(type default)
			)
			(layer "B.Fab")
		)
		(fp_line
			(start 0.8636 0.4064)
			(end 1.1938 0.4064)
			(stroke
				(width 0.1)
				(type default)
			)
			(layer "B.Fab")
		)
		(fp_line
			(start 0.8636 -0.4064)
			(end 0.8636 -0.4572)
			(stroke
				(width 0.1)
				(type default)
			)
			(layer "B.Fab")
		)
		(fp_line
			(start 0.8636 -0.4572)
			(end -0.8636 -0.4572)
			(stroke
				(width 0.1)
				(type default)
			)
			(layer "B.Fab")
		)
		(fp_line
			(start -0.8636 0.4572)
			(end 0.8636 0.4572)
			(stroke
				(width 0.1)
				(type default)
			)
			(layer "B.Fab")
		)
		(fp_line
			(start -0.8636 0.4064)
			(end -0.8636 0.4572)
			(stroke
				(width 0.1)
				(type default)
			)
			(layer "B.Fab")
		)
		(fp_line
			(start -0.8636 -0.4064)
			(end -1.1938 -0.4064)
			(stroke
				(width 0.1)
				(type default)
			)
			(layer "B.Fab")
		)
		(fp_line
			(start -0.8636 -0.4572)
			(end -0.8636 -0.4064)
			(stroke
				(width 0.1)
				(type default)
			)
			(layer "B.Fab")
		)
		(fp_line
			(start -1.1938 0.4064)
			(end -0.8636 0.4064)
			(stroke
				(width 0.1)
				(type default)
			)
			(layer "B.Fab")
		)
		(fp_line
			(start -1.1938 -0.4064)
			(end -1.1938 0.4064)
			(stroke
				(width 0.1)
				(type default)
			)
			(layer "B.Fab")
		)
		(pad "1" smd rect
			(at 0.7366 0 90)
			(size 0.7112 0.8128)
			(layers "B.Cu" "B.Mask" "B.Paste")
			(net "P3V3_DB2000QL_VDDA")
		)
		(pad "2" smd rect
			(at -0.7366 0 90)
			(size 0.7112 0.8128)
			(layers "B.Cu" "B.Mask" "B.Paste")
			(net "GND")
		)
	)
	(footprint ""
		(layer "B.Cu")
		(at 122.809762 -321.387978 -90)
		(property "Reference" "R6486"
			(at 0 0 90)
			(layer "B.SilkS")
			(hide yes)
			(effects
				(font
					(size 1.27 1.27)
				)
				(justify mirror)
			)
		)
		(property "Value" ""
			(at 0 0 90)
			(layer "B.Fab")
			(effects
				(font
					(size 1.27 1.27)
				)
				(justify mirror)
			)
		)
		(duplicate_pad_numbers_are_jumpers no)
		(fp_line
			(start -0.7874 0.4064)
			(end 0.7874 0.4064)
			(stroke
				(width 0.1524)
				(type default)
			)
			(layer "B.SilkS")
		)
		(fp_line
			(start 0.7874 0.4064)
			(end 0.7874 -0.4064)
			(stroke
				(width 0.1524)
				(type default)
			)
			(layer "B.SilkS")
		)
		(fp_line
			(start -0.7874 -0.4064)
			(end -0.7874 0.4064)
			(stroke
				(width 0.1524)
				(type default)
			)
			(layer "B.SilkS")
		)
		(fp_line
			(start 0.7874 -0.4064)
			(end -0.7874 -0.4064)
			(stroke
				(width 0.1524)
				(type default)
			)
			(layer "B.SilkS")
		)
		(fp_line
			(start -0.67945 0.3048)
			(end -0.120396 0.3048)
			(stroke
				(width 0.1)
				(type default)
			)
			(layer "B.Fab")
		)
		(fp_line
			(start -0.120396 0.3048)
			(end -0.120396 0.2794)
			(stroke
				(width 0.1)
				(type default)
			)
			(layer "B.Fab")
		)
		(fp_line
			(start 0.12065 0.3048)
			(end 0.67945 0.3048)
			(stroke
				(width 0.1)
				(type default)
			)
			(layer "B.Fab")
		)
		(fp_line
			(start 0.67945 0.3048)
			(end 0.67945 -0.305054)
			(stroke
				(width 0.1)
				(type default)
			)
			(layer "B.Fab")
		)
		(fp_line
			(start -0.120396 0.2794)
			(end 0.12065 0.2794)
			(stroke
				(width 0.1)
				(type default)
			)
			(layer "B.Fab")
		)
		(fp_line
			(start 0.12065 0.2794)
			(end 0.12065 0.3048)
			(stroke
				(width 0.1)
				(type default)
			)
			(layer "B.Fab")
		)
		(fp_line
			(start -0.12065 -0.2794)
			(end -0.12065 -0.3048)
			(stroke
				(width 0.1)
				(type default)
			)
			(layer "B.Fab")
		)
		(fp_line
			(start 0.12065 -0.2794)
			(end -0.12065 -0.2794)
			(stroke
				(width 0.1)
				(type default)
			)
			(layer "B.Fab")
		)
		(fp_line
			(start -0.67945 -0.3048)
			(end -0.67945 0.3048)
			(stroke
				(width 0.1)
				(type default)
			)
			(layer "B.Fab")
		)
		(fp_line
			(start -0.12065 -0.3048)
			(end -0.67945 -0.3048)
			(stroke
				(width 0.1)
				(type default)
			)
			(layer "B.Fab")
		)
		(fp_line
			(start 0.12065 -0.305054)
			(end 0.12065 -0.2794)
			(stroke
				(width 0.1)
				(type default)
			)
			(layer "B.Fab")
		)
		(fp_line
			(start 0.67945 -0.305054)
			(end 0.12065 -0.305054)
			(stroke
				(width 0.1)
				(type default)
			)
			(layer "B.Fab")
		)
		(pad "1" smd circle
			(at 0.40005 0 90)
			(size 0 0)
			(layers "B.Cu" "B.Mask" "B.Paste")
			(net "P0V8_SERDES_VDDA_PEX1")
		)
		(pad "2" smd circle
			(at -0.40005 0 90)
			(size 0 0)
			(layers "B.Cu" "B.Mask" "B.Paste")
			(net "P0V8_SERDES_VDDA_PEX1_C9")
		)
	)
	(footprint ""
		(layer "B.Cu")
		(at 279.974802 -296.64152 -90)
		(property "Reference" "C3389"
			(at 0 0 90)
			(layer "B.SilkS")
			(hide yes)
			(effects
				(font
					(size 1.27 1.27)
				)
				(justify mirror)
			)
		)
		(property "Value" ""
			(at 0 0 90)
			(layer "B.Fab")
			(effects
				(font
					(size 1.27 1.27)
				)
				(justify mirror)
			)
		)
		(duplicate_pad_numbers_are_jumpers no)
		(fp_line
			(start -0.299974 0.150114)
			(end 0.299974 0.150114)
			(stroke
				(width 0.1)
				(type default)
			)
			(layer "B.Fab")
		)
		(fp_line
			(start 0.299974 0.150114)
			(end 0.299974 -0.150114)
			(stroke
				(width 0.1)
				(type default)
			)
			(layer "B.Fab")
		)
		(fp_line
			(start -0.299974 -0.150114)
			(end -0.299974 0.150114)
			(stroke
				(width 0.1)
				(type default)
			)
			(layer "B.Fab")
		)
		(fp_line
			(start 0.299974 -0.150114)
			(end -0.299974 -0.150114)
			(stroke
				(width 0.1)
				(type default)
			)
			(layer "B.Fab")
		)
		(pad "1" smd rect
			(at 0.2667 0 90)
			(size 0.3048 0.381)
			(layers "B.Cu" "B.Mask" "B.Paste")
			(net "PCEPLL3_VDDA18_PEX2")
		)
		(pad "2" smd rect
			(at -0.2667 0 90)
			(size 0.3048 0.381)
			(layers "B.Cu" "B.Mask" "B.Paste")
			(net "GND")
		)
	)
	(footprint ""
		(layer "B.Cu")
		(at 294.690038 -202.16114 -90)
		(property "Reference" "R1042"
			(at 0 0 90)
			(layer "B.SilkS")
			(hide yes)
			(effects
				(font
					(size 1.27 1.27)
				)
				(justify mirror)
			)
		)
		(property "Value" ""
			(at 0 0 90)
			(layer "B.Fab")
			(effects
				(font
					(size 1.27 1.27)
				)
				(justify mirror)
			)
		)
		(duplicate_pad_numbers_are_jumpers no)
		(fp_line
			(start -0.7874 0.4064)
			(end 0.7874 0.4064)
			(stroke
				(width 0.1524)
				(type default)
			)
			(layer "B.SilkS")
		)
		(fp_line
			(start 0.7874 0.4064)
			(end 0.7874 -0.4064)
			(stroke
				(width 0.1524)
				(type default)
			)
			(layer "B.SilkS")
		)
		(fp_line
			(start -0.7874 -0.4064)
			(end -0.7874 0.4064)
			(stroke
				(width 0.1524)
				(type default)
			)
			(layer "B.SilkS")
		)
		(fp_line
			(start 0.7874 -0.4064)
			(end -0.7874 -0.4064)
			(stroke
				(width 0.1524)
				(type default)
			)
			(layer "B.SilkS")
		)
		(fp_line
			(start -0.67945 0.3048)
			(end -0.120396 0.3048)
			(stroke
				(width 0.1)
				(type default)
			)
			(layer "B.Fab")
		)
		(fp_line
			(start -0.120396 0.3048)
			(end -0.120396 0.2794)
			(stroke
				(width 0.1)
				(type default)
			)
			(layer "B.Fab")
		)
		(fp_line
			(start 0.12065 0.3048)
			(end 0.67945 0.3048)
			(stroke
				(width 0.1)
				(type default)
			)
			(layer "B.Fab")
		)
		(fp_line
			(start 0.67945 0.3048)
			(end 0.67945 -0.305054)
			(stroke
				(width 0.1)
				(type default)
			)
			(layer "B.Fab")
		)
		(fp_line
			(start -0.120396 0.2794)
			(end 0.12065 0.2794)
			(stroke
				(width 0.1)
				(type default)
			)
			(layer "B.Fab")
		)
		(fp_line
			(start 0.12065 0.2794)
			(end 0.12065 0.3048)
			(stroke
				(width 0.1)
				(type default)
			)
			(layer "B.Fab")
		)
		(fp_line
			(start -0.12065 -0.2794)
			(end -0.12065 -0.3048)
			(stroke
				(width 0.1)
				(type default)
			)
			(layer "B.Fab")
		)
		(fp_line
			(start 0.12065 -0.2794)
			(end -0.12065 -0.2794)
			(stroke
				(width 0.1)
				(type default)
			)
			(layer "B.Fab")
		)
		(fp_line
			(start -0.67945 -0.3048)
			(end -0.67945 0.3048)
			(stroke
				(width 0.1)
				(type default)
			)
			(layer "B.Fab")
		)
		(fp_line
			(start -0.12065 -0.3048)
			(end -0.67945 -0.3048)
			(stroke
				(width 0.1)
				(type default)
			)
			(layer "B.Fab")
		)
		(fp_line
			(start 0.12065 -0.305054)
			(end 0.12065 -0.2794)
			(stroke
				(width 0.1)
				(type default)
			)
			(layer "B.Fab")
		)
		(fp_line
			(start 0.67945 -0.305054)
			(end 0.12065 -0.305054)
			(stroke
				(width 0.1)
				(type default)
			)
			(layer "B.Fab")
		)
		(pad "1" smd circle
			(at 0.40005 0 90)
			(size 0 0)
			(layers "B.Cu" "B.Mask" "B.Paste")
			(net "GND")
		)
		(pad "2" smd circle
			(at -0.40005 0 90)
			(size 0 0)
			(layers "B.Cu" "B.Mask" "B.Paste")
			(net "SPI_BIC1_CLK_LS23_DIR2")
		)
	)
	(footprint ""
		(layer "B.Cu")
		(at 54.899814 -288.299906 90)
		(property "Reference" "C2932"
			(at 0 0 90)
			(layer "B.SilkS")
			(hide yes)
			(effects
				(font
					(size 1.27 1.27)
				)
				(justify mirror)
			)
		)
		(property "Value" ""
			(at 0 0 90)
			(layer "B.Fab")
			(effects
				(font
					(size 1.27 1.27)
				)
				(justify mirror)
			)
		)
		(duplicate_pad_numbers_are_jumpers no)
		(fp_line
			(start 0.299974 -0.150114)
			(end -0.299974 -0.150114)
			(stroke
				(width 0.1)
				(type default)
			)
			(layer "B.Fab")
		)
		(fp_line
			(start -0.299974 -0.150114)
			(end -0.299974 0.150114)
			(stroke
				(width 0.1)
				(type default)
			)
			(layer "B.Fab")
		)
		(fp_line
			(start 0.299974 0.150114)
			(end 0.299974 -0.150114)
			(stroke
				(width 0.1)
				(type default)
			)
			(layer "B.Fab")
		)
		(fp_line
			(start -0.299974 0.150114)
			(end 0.299974 0.150114)
			(stroke
				(width 0.1)
				(type default)
			)
			(layer "B.Fab")
		)
		(pad "1" smd rect
			(at 0.2667 0 270)
			(size 0.3048 0.381)
			(layers "B.Cu" "B.Mask" "B.Paste")
			(net "P1V25_PEX0")
		)
		(pad "2" smd rect
			(at -0.2667 0 270)
			(size 0.3048 0.381)
			(layers "B.Cu" "B.Mask" "B.Paste")
			(net "GND")
		)
	)
	(footprint ""
		(layer "B.Cu")
		(at 219.98432 -292.62832)
		(property "Reference" "PC992"
			(at 0 0 0)
			(layer "B.SilkS")
			(hide yes)
			(effects
				(font
					(size 1.27 1.27)
				)
				(justify mirror)
			)
		)
		(property "Value" ""
			(at 0 0 0)
			(layer "B.Fab")
			(effects
				(font
					(size 1.27 1.27)
				)
				(justify mirror)
			)
		)
		(duplicate_pad_numbers_are_jumpers no)
		(fp_line
			(start -1.524 -0.762)
			(end -1.524 0.762)
			(stroke
				(width 0.1524)
				(type default)
			)
			(layer "B.SilkS")
		)
		(fp_line
			(start -1.524 0.762)
			(end 1.524 0.762)
			(stroke
				(width 0.1524)
				(type default)
			)
			(layer "B.SilkS")
		)
		(fp_line
			(start 1.524 -0.762)
			(end -1.524 -0.762)
			(stroke
				(width 0.1524)
				(type default)
			)
			(layer "B.SilkS")
		)
		(fp_line
			(start 1.524 0.762)
			(end 1.524 -0.762)
			(stroke
				(width 0.1524)
				(type default)
			)
			(layer "B.SilkS")
		)
		(fp_line
			(start -1.1049 -0.724916)
			(end 1.1049 -0.724916)
			(stroke
				(width 0.1)
				(type default)
			)
			(layer "B.Fab")
		)
		(fp_line
			(start -1.1049 0.724916)
			(end -1.1049 -0.724916)
			(stroke
				(width 0.1)
				(type default)
			)
			(layer "B.Fab")
		)
		(fp_line
			(start 1.1049 -0.724916)
			(end 1.1049 0.724916)
			(stroke
				(width 0.1)
				(type default)
			)
			(layer "B.Fab")
		)
		(fp_line
			(start 1.1049 0.724916)
			(end -1.1049 0.724916)
			(stroke
				(width 0.1)
				(type default)
			)
			(layer "B.Fab")
		)
		(pad "1" smd rect
			(at 0.889 0)
			(size 1.016 1.27)
			(layers "B.Cu" "B.Mask" "B.Paste")
			(net "P1V25_PEX1_R")
		)
		(pad "2" smd rect
			(at -0.889 0)
			(size 1.016 1.27)
			(layers "B.Cu" "B.Mask" "B.Paste")
			(net "GND")
		)
	)
	(footprint ""
		(layer "B.Cu")
		(at 187.386214 -117.66169)
		(property "Reference" "R156"
			(at 0 0 0)
			(layer "B.SilkS")
			(hide yes)
			(effects
				(font
					(size 1.27 1.27)
				)
				(justify mirror)
			)
		)
		(property "Value" ""
			(at 0 0 0)
			(layer "B.Fab")
			(effects
				(font
					(size 1.27 1.27)
				)
				(justify mirror)
			)
		)
		(duplicate_pad_numbers_are_jumpers no)
		(fp_line
			(start -0.7874 -0.4064)
			(end -0.7874 0.4064)
			(stroke
				(width 0.1524)
				(type default)
			)
			(layer "B.SilkS")
		)
		(fp_line
			(start -0.7874 0.4064)
			(end 0.7874 0.4064)
			(stroke
				(width 0.1524)
				(type default)
			)
			(layer "B.SilkS")
		)
		(fp_line
			(start 0.7874 -0.4064)
			(end -0.7874 -0.4064)
			(stroke
				(width 0.1524)
				(type default)
			)
			(layer "B.SilkS")
		)
		(fp_line
			(start 0.7874 0.4064)
			(end 0.7874 -0.4064)
			(stroke
				(width 0.1524)
				(type default)
			)
			(layer "B.SilkS")
		)
		(fp_line
			(start -0.67945 -0.3048)
			(end -0.67945 0.3048)
			(stroke
				(width 0.1)
				(type default)
			)
			(layer "B.Fab")
		)
		(fp_line
			(start -0.67945 0.3048)
			(end -0.120396 0.3048)
			(stroke
				(width 0.1)
				(type default)
			)
			(layer "B.Fab")
		)
		(fp_line
			(start -0.12065 -0.3048)
			(end -0.67945 -0.3048)
			(stroke
				(width 0.1)
				(type default)
			)
			(layer "B.Fab")
		)
		(fp_line
			(start -0.12065 -0.2794)
			(end -0.12065 -0.3048)
			(stroke
				(width 0.1)
				(type default)
			)
			(layer "B.Fab")
		)
		(fp_line
			(start -0.120396 0.2794)
			(end 0.12065 0.2794)
			(stroke
				(width 0.1)
				(type default)
			)
			(layer "B.Fab")
		)
		(fp_line
			(start -0.120396 0.3048)
			(end -0.120396 0.2794)
			(stroke
				(width 0.1)
				(type default)
			)
			(layer "B.Fab")
		)
		(fp_line
			(start 0.12065 -0.305054)
			(end 0.12065 -0.2794)
			(stroke
				(width 0.1)
				(type default)
			)
			(layer "B.Fab")
		)
		(fp_line
			(start 0.12065 -0.2794)
			(end -0.12065 -0.2794)
			(stroke
				(width 0.1)
				(type default)
			)
			(layer "B.Fab")
		)
		(fp_line
			(start 0.12065 0.2794)
			(end 0.12065 0.3048)
			(stroke
				(width 0.1)
				(type default)
			)
			(layer "B.Fab")
		)
		(fp_line
			(start 0.12065 0.3048)
			(end 0.67945 0.3048)
			(stroke
				(width 0.1)
				(type default)
			)
			(layer "B.Fab")
		)
		(fp_line
			(start 0.67945 -0.305054)
			(end 0.12065 -0.305054)
			(stroke
				(width 0.1)
				(type default)
			)
			(layer "B.Fab")
		)
		(fp_line
			(start 0.67945 0.3048)
			(end 0.67945 -0.305054)
			(stroke
				(width 0.1)
				(type default)
			)
			(layer "B.Fab")
		)
		(pad "1" smd circle
			(at 0.40005 0 180)
			(size 0 0)
			(layers "B.Cu" "B.Mask" "B.Paste")
			(net "NIC3_AUX_PWR_EN_R")
		)
		(pad "2" smd circle
			(at -0.40005 0 180)
			(size 0 0)
			(layers "B.Cu" "B.Mask" "B.Paste")
			(net "NIC3_AUX_PWR_EN")
		)
	)
	(footprint ""
		(layer "B.Cu")
		(at 165.655244 -151.9936)
		(property "Reference" "R120"
			(at 0 0 0)
			(layer "B.SilkS")
			(hide yes)
			(effects
				(font
					(size 1.27 1.27)
				)
				(justify mirror)
			)
		)
		(property "Value" ""
			(at 0 0 0)
			(layer "B.Fab")
			(effects
				(font
					(size 1.27 1.27)
				)
				(justify mirror)
			)
		)
		(duplicate_pad_numbers_are_jumpers no)
		(fp_line
			(start -0.7874 -0.4064)
			(end -0.7874 0.4064)
			(stroke
				(width 0.1524)
				(type default)
			)
			(layer "B.SilkS")
		)
		(fp_line
			(start -0.7874 0.4064)
			(end 0.7874 0.4064)
			(stroke
				(width 0.1524)
				(type default)
			)
			(layer "B.SilkS")
		)
		(fp_line
			(start 0.7874 -0.4064)
			(end -0.7874 -0.4064)
			(stroke
				(width 0.1524)
				(type default)
			)
			(layer "B.SilkS")
		)
		(fp_line
			(start 0.7874 0.4064)
			(end 0.7874 -0.4064)
			(stroke
				(width 0.1524)
				(type default)
			)
			(layer "B.SilkS")
		)
		(fp_line
			(start -0.67945 -0.3048)
			(end -0.67945 0.3048)
			(stroke
				(width 0.1)
				(type default)
			)
			(layer "B.Fab")
		)
		(fp_line
			(start -0.67945 0.3048)
			(end -0.120396 0.3048)
			(stroke
				(width 0.1)
				(type default)
			)
			(layer "B.Fab")
		)
		(fp_line
			(start -0.12065 -0.3048)
			(end -0.67945 -0.3048)
			(stroke
				(width 0.1)
				(type default)
			)
			(layer "B.Fab")
		)
		(fp_line
			(start -0.12065 -0.2794)
			(end -0.12065 -0.3048)
			(stroke
				(width 0.1)
				(type default)
			)
			(layer "B.Fab")
		)
		(fp_line
			(start -0.120396 0.2794)
			(end 0.12065 0.2794)
			(stroke
				(width 0.1)
				(type default)
			)
			(layer "B.Fab")
		)
		(fp_line
			(start -0.120396 0.3048)
			(end -0.120396 0.2794)
			(stroke
				(width 0.1)
				(type default)
			)
			(layer "B.Fab")
		)
		(fp_line
			(start 0.12065 -0.305054)
			(end 0.12065 -0.2794)
			(stroke
				(width 0.1)
				(type default)
			)
			(layer "B.Fab")
		)
		(fp_line
			(start 0.12065 -0.2794)
			(end -0.12065 -0.2794)
			(stroke
				(width 0.1)
				(type default)
			)
			(layer "B.Fab")
		)
		(fp_line
			(start 0.12065 0.2794)
			(end 0.12065 0.3048)
			(stroke
				(width 0.1)
				(type default)
			)
			(layer "B.Fab")
		)
		(fp_line
			(start 0.12065 0.3048)
			(end 0.67945 0.3048)
			(stroke
				(width 0.1)
				(type default)
			)
			(layer "B.Fab")
		)
		(fp_line
			(start 0.67945 -0.305054)
			(end 0.12065 -0.305054)
			(stroke
				(width 0.1)
				(type default)
			)
			(layer "B.Fab")
		)
		(fp_line
			(start 0.67945 0.3048)
			(end 0.67945 -0.305054)
			(stroke
				(width 0.1)
				(type default)
			)
			(layer "B.Fab")
		)
		(pad "1" smd circle
			(at 0.40005 0 180)
			(size 0 0)
			(layers "B.Cu" "B.Mask" "B.Paste")
			(net "NCSI_NIC2_TXD0")
		)
		(pad "2" smd circle
			(at -0.40005 0 180)
			(size 0 0)
			(layers "B.Cu" "B.Mask" "B.Paste")
			(net "GND")
		)
	)
	(footprint ""
		(layer "B.Cu")
		(at 67.249802 -292.099746 90)
		(property "Reference" "C1191"
			(at 0 0 90)
			(layer "B.SilkS")
			(hide yes)
			(effects
				(font
					(size 1.27 1.27)
				)
				(justify mirror)
			)
		)
		(property "Value" ""
			(at 0 0 90)
			(layer "B.Fab")
			(effects
				(font
					(size 1.27 1.27)
				)
				(justify mirror)
			)
		)
		(duplicate_pad_numbers_are_jumpers no)
		(fp_line
			(start 0.299974 -0.150114)
			(end -0.299974 -0.150114)
			(stroke
				(width 0.1)
				(type default)
			)
			(layer "B.Fab")
		)
		(fp_line
			(start -0.299974 -0.150114)
			(end -0.299974 0.150114)
			(stroke
				(width 0.1)
				(type default)
			)
			(layer "B.Fab")
		)
		(fp_line
			(start 0.299974 0.150114)
			(end 0.299974 -0.150114)
			(stroke
				(width 0.1)
				(type default)
			)
			(layer "B.Fab")
		)
		(fp_line
			(start -0.299974 0.150114)
			(end 0.299974 0.150114)
			(stroke
				(width 0.1)
				(type default)
			)
			(layer "B.Fab")
		)
		(pad "1" smd rect
			(at 0.2667 0 270)
			(size 0.3048 0.381)
			(layers "B.Cu" "B.Mask" "B.Paste")
			(net "P0V8_SERDES_VDDA_PEX0")
		)
		(pad "2" smd rect
			(at -0.2667 0 270)
			(size 0.3048 0.381)
			(layers "B.Cu" "B.Mask" "B.Paste")
			(net "GND")
		)
	)
	(footprint ""
		(layer "B.Cu")
		(at 288.99993 -290.199826 90)
		(property "Reference" "C1721"
			(at 0 0 90)
			(layer "B.SilkS")
			(hide yes)
			(effects
				(font
					(size 1.27 1.27)
				)
				(justify mirror)
			)
		)
		(property "Value" ""
			(at 0 0 90)
			(layer "B.Fab")
			(effects
				(font
					(size 1.27 1.27)
				)
				(justify mirror)
			)
		)
		(duplicate_pad_numbers_are_jumpers no)
		(fp_line
			(start 0.299974 -0.150114)
			(end -0.299974 -0.150114)
			(stroke
				(width 0.1)
				(type default)
			)
			(layer "B.Fab")
		)
		(fp_line
			(start -0.299974 -0.150114)
			(end -0.299974 0.150114)
			(stroke
				(width 0.1)
				(type default)
			)
			(layer "B.Fab")
		)
		(fp_line
			(start 0.299974 0.150114)
			(end 0.299974 -0.150114)
			(stroke
				(width 0.1)
				(type default)
			)
			(layer "B.Fab")
		)
		(fp_line
			(start -0.299974 0.150114)
			(end 0.299974 0.150114)
			(stroke
				(width 0.1)
				(type default)
			)
			(layer "B.Fab")
		)
		(pad "1" smd rect
			(at 0.2667 0 270)
			(size 0.3048 0.381)
			(layers "B.Cu" "B.Mask" "B.Paste")
			(net "P0V8_SERDES_VDDA_PEX2")
		)
		(pad "2" smd rect
			(at -0.2667 0 270)
			(size 0.3048 0.381)
			(layers "B.Cu" "B.Mask" "B.Paste")
			(net "GND")
		)
	)
	(footprint ""
		(layer "B.Cu")
		(at 122.689366 -313.620404)
		(property "Reference" "R5788"
			(at 0 0 0)
			(layer "B.SilkS")
			(hide yes)
			(effects
				(font
					(size 1.27 1.27)
				)
				(justify mirror)
			)
		)
		(property "Value" ""
			(at 0 0 0)
			(layer "B.Fab")
			(effects
				(font
					(size 1.27 1.27)
				)
				(justify mirror)
			)
		)
		(duplicate_pad_numbers_are_jumpers no)
		(fp_line
			(start -2.576322 -1.1303)
			(end -2.576322 1.1303)
			(stroke
				(width 0.1524)
				(type default)
			)
			(layer "B.SilkS")
		)
		(fp_line
			(start -2.576322 1.1303)
			(end 2.576322 1.1303)
			(stroke
				(width 0.1524)
				(type default)
			)
			(layer "B.SilkS")
		)
		(fp_line
			(start 2.576322 -1.1303)
			(end -2.576322 -1.1303)
			(stroke
				(width 0.1524)
				(type default)
			)
			(layer "B.SilkS")
		)
		(fp_line
			(start 2.576322 1.1303)
			(end 2.576322 -1.1303)
			(stroke
				(width 0.1524)
				(type default)
			)
			(layer "B.SilkS")
		)
		(fp_line
			(start -1.649984 -0.899922)
			(end 1.649984 -0.899922)
			(stroke
				(width 0.1)
				(type default)
			)
			(layer "B.Fab")
		)
		(fp_line
			(start -1.649984 0.899922)
			(end -1.649984 -0.899922)
			(stroke
				(width 0.1)
				(type default)
			)
			(layer "B.Fab")
		)
		(fp_line
			(start 1.649984 -0.899922)
			(end 1.649984 0.899922)
			(stroke
				(width 0.1)
				(type default)
			)
			(layer "B.Fab")
		)
		(fp_line
			(start 1.649984 0.899922)
			(end -1.649984 0.899922)
			(stroke
				(width 0.1)
				(type default)
			)
			(layer "B.Fab")
		)
		(pad "1A" smd rect
			(at 1.700022 0 180)
			(size 1.4986 2.0066)
			(layers "B.Cu" "B.Mask" "B.Paste")
			(net "P0V8_PEX1")
		)
		(pad "1B" smd rect
			(at 1.077722 0 180)
			(size 0.254 0.508)
			(layers "B.Cu" "B.Mask" "B.Paste")
			(net "P0V8_PEX1")
		)
		(pad "2A" smd rect
			(at -1.700022 0 180)
			(size 1.4986 2.0066)
			(layers "B.Cu" "B.Mask" "B.Paste")
			(net "P0V8_SERDES_VDDA_PEX1")
		)
		(pad "2B" smd rect
			(at -1.077722 0 180)
			(size 0.254 0.508)
			(layers "B.Cu" "B.Mask" "B.Paste")
			(net "P0V8_SERDES_VDDA_PEX1")
		)
	)
	(footprint ""
		(layer "B.Cu")
		(at 401.299934 -290.199826 90)
		(property "Reference" "C1953"
			(at 0 0 90)
			(layer "B.SilkS")
			(hide yes)
			(effects
				(font
					(size 1.27 1.27)
				)
				(justify mirror)
			)
		)
		(property "Value" ""
			(at 0 0 90)
			(layer "B.Fab")
			(effects
				(font
					(size 1.27 1.27)
				)
				(justify mirror)
			)
		)
		(duplicate_pad_numbers_are_jumpers no)
		(fp_line
			(start 0.299974 -0.150114)
			(end -0.299974 -0.150114)
			(stroke
				(width 0.1)
				(type default)
			)
			(layer "B.Fab")
		)
		(fp_line
			(start -0.299974 -0.150114)
			(end -0.299974 0.150114)
			(stroke
				(width 0.1)
				(type default)
			)
			(layer "B.Fab")
		)
		(fp_line
			(start 0.299974 0.150114)
			(end 0.299974 -0.150114)
			(stroke
				(width 0.1)
				(type default)
			)
			(layer "B.Fab")
		)
		(fp_line
			(start -0.299974 0.150114)
			(end 0.299974 0.150114)
			(stroke
				(width 0.1)
				(type default)
			)
			(layer "B.Fab")
		)
		(pad "1" smd rect
			(at 0.2667 0 270)
			(size 0.3048 0.381)
			(layers "B.Cu" "B.Mask" "B.Paste")
			(net "P0V8_SERDES_VDDA_PEX3")
		)
		(pad "2" smd rect
			(at -0.2667 0 270)
			(size 0.3048 0.381)
			(layers "B.Cu" "B.Mask" "B.Paste")
			(net "GND")
		)
	)
	(footprint ""
		(layer "B.Cu")
		(at 366.657382 -152.674066)
		(property "Reference" "R5624"
			(at 0 0 0)
			(layer "B.SilkS")
			(hide yes)
			(effects
				(font
					(size 1.27 1.27)
				)
				(justify mirror)
			)
		)
		(property "Value" ""
			(at 0 0 0)
			(layer "B.Fab")
			(effects
				(font
					(size 1.27 1.27)
				)
				(justify mirror)
			)
		)
		(duplicate_pad_numbers_are_jumpers no)
		(fp_line
			(start -0.7874 -0.4064)
			(end -0.7874 0.4064)
			(stroke
				(width 0.1524)
				(type default)
			)
			(layer "B.SilkS")
		)
		(fp_line
			(start -0.7874 0.4064)
			(end 0.7874 0.4064)
			(stroke
				(width 0.1524)
				(type default)
			)
			(layer "B.SilkS")
		)
		(fp_line
			(start 0.7874 -0.4064)
			(end -0.7874 -0.4064)
			(stroke
				(width 0.1524)
				(type default)
			)
			(layer "B.SilkS")
		)
		(fp_line
			(start 0.7874 0.4064)
			(end 0.7874 -0.4064)
			(stroke
				(width 0.1524)
				(type default)
			)
			(layer "B.SilkS")
		)
		(fp_line
			(start -0.67945 -0.3048)
			(end -0.67945 0.3048)
			(stroke
				(width 0.1)
				(type default)
			)
			(layer "B.Fab")
		)
		(fp_line
			(start -0.67945 0.3048)
			(end -0.120396 0.3048)
			(stroke
				(width 0.1)
				(type default)
			)
			(layer "B.Fab")
		)
		(fp_line
			(start -0.12065 -0.3048)
			(end -0.67945 -0.3048)
			(stroke
				(width 0.1)
				(type default)
			)
			(layer "B.Fab")
		)
		(fp_line
			(start -0.12065 -0.2794)
			(end -0.12065 -0.3048)
			(stroke
				(width 0.1)
				(type default)
			)
			(layer "B.Fab")
		)
		(fp_line
			(start -0.120396 0.2794)
			(end 0.12065 0.2794)
			(stroke
				(width 0.1)
				(type default)
			)
			(layer "B.Fab")
		)
		(fp_line
			(start -0.120396 0.3048)
			(end -0.120396 0.2794)
			(stroke
				(width 0.1)
				(type default)
			)
			(layer "B.Fab")
		)
		(fp_line
			(start 0.12065 -0.305054)
			(end 0.12065 -0.2794)
			(stroke
				(width 0.1)
				(type default)
			)
			(layer "B.Fab")
		)
		(fp_line
			(start 0.12065 -0.2794)
			(end -0.12065 -0.2794)
			(stroke
				(width 0.1)
				(type default)
			)
			(layer "B.Fab")
		)
		(fp_line
			(start 0.12065 0.2794)
			(end 0.12065 0.3048)
			(stroke
				(width 0.1)
				(type default)
			)
			(layer "B.Fab")
		)
		(fp_line
			(start 0.12065 0.3048)
			(end 0.67945 0.3048)
			(stroke
				(width 0.1)
				(type default)
			)
			(layer "B.Fab")
		)
		(fp_line
			(start 0.67945 -0.305054)
			(end 0.12065 -0.305054)
			(stroke
				(width 0.1)
				(type default)
			)
			(layer "B.Fab")
		)
		(fp_line
			(start 0.67945 0.3048)
			(end 0.67945 -0.305054)
			(stroke
				(width 0.1)
				(type default)
			)
			(layer "B.Fab")
		)
		(pad "1" smd circle
			(at 0.40005 0 180)
			(size 0 0)
			(layers "B.Cu" "B.Mask" "B.Paste")
			(net "NIC6_ADC_A0")
		)
		(pad "2" smd circle
			(at -0.40005 0 180)
			(size 0 0)
			(layers "B.Cu" "B.Mask" "B.Paste")
			(net "SMB_NIC6_ADC_SDA")
		)
	)
	(footprint ""
		(layer "B.Cu")
		(at 61.074808 -297.79976 -90)
		(property "Reference" "C1117"
			(at 0 0 90)
			(layer "B.SilkS")
			(hide yes)
			(effects
				(font
					(size 1.27 1.27)
				)
				(justify mirror)
			)
		)
		(property "Value" ""
			(at 0 0 90)
			(layer "B.Fab")
			(effects
				(font
					(size 1.27 1.27)
				)
				(justify mirror)
			)
		)
		(duplicate_pad_numbers_are_jumpers no)
		(fp_line
			(start -0.299974 0.150114)
			(end 0.299974 0.150114)
			(stroke
				(width 0.1)
				(type default)
			)
			(layer "B.Fab")
		)
		(fp_line
			(start 0.299974 0.150114)
			(end 0.299974 -0.150114)
			(stroke
				(width 0.1)
				(type default)
			)
			(layer "B.Fab")
		)
		(fp_line
			(start -0.299974 -0.150114)
			(end -0.299974 0.150114)
			(stroke
				(width 0.1)
				(type default)
			)
			(layer "B.Fab")
		)
		(fp_line
			(start 0.299974 -0.150114)
			(end -0.299974 -0.150114)
			(stroke
				(width 0.1)
				(type default)
			)
			(layer "B.Fab")
		)
		(pad "1" smd rect
			(at 0.2667 0 90)
			(size 0.3048 0.381)
			(layers "B.Cu" "B.Mask" "B.Paste")
			(net "P0V8_PEX0")
		)
		(pad "2" smd rect
			(at -0.2667 0 90)
			(size 0.3048 0.381)
			(layers "B.Cu" "B.Mask" "B.Paste")
			(net "GND")
		)
	)
	(footprint ""
		(layer "B.Cu")
		(at 73.271634 -115.608608)
		(property "Reference" "C874"
			(at 0 0 0)
			(layer "B.SilkS")
			(hide yes)
			(effects
				(font
					(size 1.27 1.27)
				)
				(justify mirror)
			)
		)
		(property "Value" ""
			(at 0 0 0)
			(layer "B.Fab")
			(effects
				(font
					(size 1.27 1.27)
				)
				(justify mirror)
			)
		)
		(duplicate_pad_numbers_are_jumpers no)
		(fp_line
			(start -0.7874 -0.4064)
			(end -0.7874 0.4064)
			(stroke
				(width 0.1524)
				(type default)
			)
			(layer "B.SilkS")
		)
		(fp_line
			(start -0.7874 0.4064)
			(end 0.7874 0.4064)
			(stroke
				(width 0.1524)
				(type default)
			)
			(layer "B.SilkS")
		)
		(fp_line
			(start 0.7874 -0.4064)
			(end -0.7874 -0.4064)
			(stroke
				(width 0.1524)
				(type default)
			)
			(layer "B.SilkS")
		)
		(fp_line
			(start 0.7874 0.4064)
			(end 0.7874 -0.4064)
			(stroke
				(width 0.1524)
				(type default)
			)
			(layer "B.SilkS")
		)
		(fp_line
			(start -0.67945 -0.3048)
			(end -0.67945 0.3048)
			(stroke
				(width 0.1)
				(type default)
			)
			(layer "B.Fab")
		)
		(fp_line
			(start -0.67945 0.3048)
			(end -0.120396 0.3048)
			(stroke
				(width 0.1)
				(type default)
			)
			(layer "B.Fab")
		)
		(fp_line
			(start -0.12065 -0.3048)
			(end -0.67945 -0.3048)
			(stroke
				(width 0.1)
				(type default)
			)
			(layer "B.Fab")
		)
		(fp_line
			(start -0.12065 -0.2794)
			(end -0.12065 -0.3048)
			(stroke
				(width 0.1)
				(type default)
			)
			(layer "B.Fab")
		)
		(fp_line
			(start -0.120396 0.2794)
			(end 0.12065 0.2794)
			(stroke
				(width 0.1)
				(type default)
			)
			(layer "B.Fab")
		)
		(fp_line
			(start -0.120396 0.3048)
			(end -0.120396 0.2794)
			(stroke
				(width 0.1)
				(type default)
			)
			(layer "B.Fab")
		)
		(fp_line
			(start 0.12065 -0.305054)
			(end 0.12065 -0.2794)
			(stroke
				(width 0.1)
				(type default)
			)
			(layer "B.Fab")
		)
		(fp_line
			(start 0.12065 -0.2794)
			(end -0.12065 -0.2794)
			(stroke
				(width 0.1)
				(type default)
			)
			(layer "B.Fab")
		)
		(fp_line
			(start 0.12065 0.2794)
			(end 0.12065 0.3048)
			(stroke
				(width 0.1)
				(type default)
			)
			(layer "B.Fab")
		)
		(fp_line
			(start 0.12065 0.3048)
			(end 0.67945 0.3048)
			(stroke
				(width 0.1)
				(type default)
			)
			(layer "B.Fab")
		)
		(fp_line
			(start 0.67945 -0.305054)
			(end 0.12065 -0.305054)
			(stroke
				(width 0.1)
				(type default)
			)
			(layer "B.Fab")
		)
		(fp_line
			(start 0.67945 0.3048)
			(end 0.67945 -0.305054)
			(stroke
				(width 0.1)
				(type default)
			)
			(layer "B.Fab")
		)
		(pad "1" smd circle
			(at 0.40005 0 180)
			(size 0 0)
			(layers "B.Cu" "B.Mask" "B.Paste")
			(net "P3V3_NIC1")
		)
		(pad "2" smd circle
			(at -0.40005 0 180)
			(size 0 0)
			(layers "B.Cu" "B.Mask" "B.Paste")
			(net "GND")
		)
	)
	(footprint ""
		(layer "B.Cu")
		(at 294.22471 -293.99992 -90)
		(property "Reference" "C1658"
			(at 0 0 90)
			(layer "B.SilkS")
			(hide yes)
			(effects
				(font
					(size 1.27 1.27)
				)
				(justify mirror)
			)
		)
		(property "Value" ""
			(at 0 0 90)
			(layer "B.Fab")
			(effects
				(font
					(size 1.27 1.27)
				)
				(justify mirror)
			)
		)
		(duplicate_pad_numbers_are_jumpers no)
		(fp_line
			(start -0.299974 0.150114)
			(end 0.299974 0.150114)
			(stroke
				(width 0.1)
				(type default)
			)
			(layer "B.Fab")
		)
		(fp_line
			(start 0.299974 0.150114)
			(end 0.299974 -0.150114)
			(stroke
				(width 0.1)
				(type default)
			)
			(layer "B.Fab")
		)
		(fp_line
			(start -0.299974 -0.150114)
			(end -0.299974 0.150114)
			(stroke
				(width 0.1)
				(type default)
			)
			(layer "B.Fab")
		)
		(fp_line
			(start 0.299974 -0.150114)
			(end -0.299974 -0.150114)
			(stroke
				(width 0.1)
				(type default)
			)
			(layer "B.Fab")
		)
		(pad "1" smd rect
			(at 0.2667 0 90)
			(size 0.3048 0.381)
			(layers "B.Cu" "B.Mask" "B.Paste")
			(net "P0V8_PEX2")
		)
		(pad "2" smd rect
			(at -0.2667 0 90)
			(size 0.3048 0.381)
			(layers "B.Cu" "B.Mask" "B.Paste")
			(net "GND")
		)
	)
	(footprint ""
		(layer "B.Cu")
		(at 176.699926 -290.199826 90)
		(property "Reference" "C1489"
			(at 0 0 90)
			(layer "B.SilkS")
			(hide yes)
			(effects
				(font
					(size 1.27 1.27)
				)
				(justify mirror)
			)
		)
		(property "Value" ""
			(at 0 0 90)
			(layer "B.Fab")
			(effects
				(font
					(size 1.27 1.27)
				)
				(justify mirror)
			)
		)
		(duplicate_pad_numbers_are_jumpers no)
		(fp_line
			(start 0.299974 -0.150114)
			(end -0.299974 -0.150114)
			(stroke
				(width 0.1)
				(type default)
			)
			(layer "B.Fab")
		)
		(fp_line
			(start -0.299974 -0.150114)
			(end -0.299974 0.150114)
			(stroke
				(width 0.1)
				(type default)
			)
			(layer "B.Fab")
		)
		(fp_line
			(start 0.299974 0.150114)
			(end 0.299974 -0.150114)
			(stroke
				(width 0.1)
				(type default)
			)
			(layer "B.Fab")
		)
		(fp_line
			(start -0.299974 0.150114)
			(end 0.299974 0.150114)
			(stroke
				(width 0.1)
				(type default)
			)
			(layer "B.Fab")
		)
		(pad "1" smd rect
			(at 0.2667 0 270)
			(size 0.3048 0.381)
			(layers "B.Cu" "B.Mask" "B.Paste")
			(net "P0V8_SERDES_VDDA_PEX1")
		)
		(pad "2" smd rect
			(at -0.2667 0 270)
			(size 0.3048 0.381)
			(layers "B.Cu" "B.Mask" "B.Paste")
			(net "GND")
		)
	)
	(footprint ""
		(layer "B.Cu")
		(at 331.343 -239.776)
		(property "Reference" "R6314"
			(at 0 0 0)
			(layer "B.SilkS")
			(hide yes)
			(effects
				(font
					(size 1.27 1.27)
				)
				(justify mirror)
			)
		)
		(property "Value" ""
			(at 0 0 0)
			(layer "B.Fab")
			(effects
				(font
					(size 1.27 1.27)
				)
				(justify mirror)
			)
		)
		(duplicate_pad_numbers_are_jumpers no)
		(fp_line
			(start -0.7874 -0.4064)
			(end -0.7874 0.4064)
			(stroke
				(width 0.1524)
				(type default)
			)
			(layer "B.SilkS")
		)
		(fp_line
			(start -0.7874 0.4064)
			(end 0.7874 0.4064)
			(stroke
				(width 0.1524)
				(type default)
			)
			(layer "B.SilkS")
		)
		(fp_line
			(start 0.7874 -0.4064)
			(end -0.7874 -0.4064)
			(stroke
				(width 0.1524)
				(type default)
			)
			(layer "B.SilkS")
		)
		(fp_line
			(start 0.7874 0.4064)
			(end 0.7874 -0.4064)
			(stroke
				(width 0.1524)
				(type default)
			)
			(layer "B.SilkS")
		)
		(fp_line
			(start -0.67945 -0.3048)
			(end -0.67945 0.3048)
			(stroke
				(width 0.1)
				(type default)
			)
			(layer "B.Fab")
		)
		(fp_line
			(start -0.67945 0.3048)
			(end -0.120396 0.3048)
			(stroke
				(width 0.1)
				(type default)
			)
			(layer "B.Fab")
		)
		(fp_line
			(start -0.12065 -0.3048)
			(end -0.67945 -0.3048)
			(stroke
				(width 0.1)
				(type default)
			)
			(layer "B.Fab")
		)
		(fp_line
			(start -0.12065 -0.2794)
			(end -0.12065 -0.3048)
			(stroke
				(width 0.1)
				(type default)
			)
			(layer "B.Fab")
		)
		(fp_line
			(start -0.120396 0.2794)
			(end 0.12065 0.2794)
			(stroke
				(width 0.1)
				(type default)
			)
			(layer "B.Fab")
		)
		(fp_line
			(start -0.120396 0.3048)
			(end -0.120396 0.2794)
			(stroke
				(width 0.1)
				(type default)
			)
			(layer "B.Fab")
		)
		(fp_line
			(start 0.12065 -0.305054)
			(end 0.12065 -0.2794)
			(stroke
				(width 0.1)
				(type default)
			)
			(layer "B.Fab")
		)
		(fp_line
			(start 0.12065 -0.2794)
			(end -0.12065 -0.2794)
			(stroke
				(width 0.1)
				(type default)
			)
			(layer "B.Fab")
		)
		(fp_line
			(start 0.12065 0.2794)
			(end 0.12065 0.3048)
			(stroke
				(width 0.1)
				(type default)
			)
			(layer "B.Fab")
		)
		(fp_line
			(start 0.12065 0.3048)
			(end 0.67945 0.3048)
			(stroke
				(width 0.1)
				(type default)
			)
			(layer "B.Fab")
		)
		(fp_line
			(start 0.67945 -0.305054)
			(end 0.12065 -0.305054)
			(stroke
				(width 0.1)
				(type default)
			)
			(layer "B.Fab")
		)
		(fp_line
			(start 0.67945 0.3048)
			(end 0.67945 -0.305054)
			(stroke
				(width 0.1)
				(type default)
			)
			(layer "B.Fab")
		)
		(pad "1" smd circle
			(at 0.40005 0 180)
			(size 0 0)
			(layers "B.Cu" "B.Mask" "B.Paste")
			(net "MB_SWB_PWRGD_R")
		)
		(pad "2" smd circle
			(at -0.40005 0 180)
			(size 0 0)
			(layers "B.Cu" "B.Mask" "B.Paste")
			(net "GND")
		)
	)
	(footprint ""
		(layer "B.Cu")
		(at 116.128292 -304.157634)
		(property "Reference" "PR78"
			(at 0 0 0)
			(layer "B.SilkS")
			(hide yes)
			(effects
				(font
					(size 1.27 1.27)
				)
				(justify mirror)
			)
		)
		(property "Value" ""
			(at 0 0 0)
			(layer "B.Fab")
			(effects
				(font
					(size 1.27 1.27)
				)
				(justify mirror)
			)
		)
		(duplicate_pad_numbers_are_jumpers no)
		(fp_line
			(start -0.7874 -0.4064)
			(end -0.7874 0.4064)
			(stroke
				(width 0.1524)
				(type default)
			)
			(layer "B.SilkS")
		)
		(fp_line
			(start -0.7874 0.4064)
			(end 0.7874 0.4064)
			(stroke
				(width 0.1524)
				(type default)
			)
			(layer "B.SilkS")
		)
		(fp_line
			(start 0.7874 -0.4064)
			(end -0.7874 -0.4064)
			(stroke
				(width 0.1524)
				(type default)
			)
			(layer "B.SilkS")
		)
		(fp_line
			(start 0.7874 0.4064)
			(end 0.7874 -0.4064)
			(stroke
				(width 0.1524)
				(type default)
			)
			(layer "B.SilkS")
		)
		(fp_line
			(start -0.67945 -0.3048)
			(end -0.67945 0.3048)
			(stroke
				(width 0.1)
				(type default)
			)
			(layer "B.Fab")
		)
		(fp_line
			(start -0.67945 0.3048)
			(end -0.120396 0.3048)
			(stroke
				(width 0.1)
				(type default)
			)
			(layer "B.Fab")
		)
		(fp_line
			(start -0.12065 -0.3048)
			(end -0.67945 -0.3048)
			(stroke
				(width 0.1)
				(type default)
			)
			(layer "B.Fab")
		)
		(fp_line
			(start -0.12065 -0.2794)
			(end -0.12065 -0.3048)
			(stroke
				(width 0.1)
				(type default)
			)
			(layer "B.Fab")
		)
		(fp_line
			(start -0.120396 0.2794)
			(end 0.12065 0.2794)
			(stroke
				(width 0.1)
				(type default)
			)
			(layer "B.Fab")
		)
		(fp_line
			(start -0.120396 0.3048)
			(end -0.120396 0.2794)
			(stroke
				(width 0.1)
				(type default)
			)
			(layer "B.Fab")
		)
		(fp_line
			(start 0.12065 -0.305054)
			(end 0.12065 -0.2794)
			(stroke
				(width 0.1)
				(type default)
			)
			(layer "B.Fab")
		)
		(fp_line
			(start 0.12065 -0.2794)
			(end -0.12065 -0.2794)
			(stroke
				(width 0.1)
				(type default)
			)
			(layer "B.Fab")
		)
		(fp_line
			(start 0.12065 0.2794)
			(end 0.12065 0.3048)
			(stroke
				(width 0.1)
				(type default)
			)
			(layer "B.Fab")
		)
		(fp_line
			(start 0.12065 0.3048)
			(end 0.67945 0.3048)
			(stroke
				(width 0.1)
				(type default)
			)
			(layer "B.Fab")
		)
		(fp_line
			(start 0.67945 -0.305054)
			(end 0.12065 -0.305054)
			(stroke
				(width 0.1)
				(type default)
			)
			(layer "B.Fab")
		)
		(fp_line
			(start 0.67945 0.3048)
			(end 0.67945 -0.305054)
			(stroke
				(width 0.1)
				(type default)
			)
			(layer "B.Fab")
		)
		(pad "1" smd circle
			(at 0.40005 0 180)
			(size 0 0)
			(layers "B.Cu" "B.Mask" "B.Paste")
			(net "SH_P0V8_PEX0_RGND0")
		)
		(pad "2" smd circle
			(at -0.40005 0 180)
			(size 0 0)
			(layers "B.Cu" "B.Mask" "B.Paste")
			(net "GND")
		)
	)
	(footprint ""
		(layer "B.Cu")
		(at 412.699962 -303.499774 -90)
		(property "Reference" "C3460"
			(at 0 0 90)
			(layer "B.SilkS")
			(hide yes)
			(effects
				(font
					(size 1.27 1.27)
				)
				(justify mirror)
			)
		)
		(property "Value" ""
			(at 0 0 90)
			(layer "B.Fab")
			(effects
				(font
					(size 1.27 1.27)
				)
				(justify mirror)
			)
		)
		(duplicate_pad_numbers_are_jumpers no)
		(fp_line
			(start -0.299974 0.150114)
			(end 0.299974 0.150114)
			(stroke
				(width 0.1)
				(type default)
			)
			(layer "B.Fab")
		)
		(fp_line
			(start 0.299974 0.150114)
			(end 0.299974 -0.150114)
			(stroke
				(width 0.1)
				(type default)
			)
			(layer "B.Fab")
		)
		(fp_line
			(start -0.299974 -0.150114)
			(end -0.299974 0.150114)
			(stroke
				(width 0.1)
				(type default)
			)
			(layer "B.Fab")
		)
		(fp_line
			(start 0.299974 -0.150114)
			(end -0.299974 -0.150114)
			(stroke
				(width 0.1)
				(type default)
			)
			(layer "B.Fab")
		)
		(pad "1" smd rect
			(at 0.2667 0 90)
			(size 0.3048 0.381)
			(layers "B.Cu" "B.Mask" "B.Paste")
			(net "P1V25_PEX3")
		)
		(pad "2" smd rect
			(at -0.2667 0 90)
			(size 0.3048 0.381)
			(layers "B.Cu" "B.Mask" "B.Paste")
			(net "GND")
		)
	)
	(footprint ""
		(layer "B.Cu")
		(at 172.900086 -299.699934 -90)
		(property "Reference" "C1455"
			(at 0 0 90)
			(layer "B.SilkS")
			(hide yes)
			(effects
				(font
					(size 1.27 1.27)
				)
				(justify mirror)
			)
		)
		(property "Value" ""
			(at 0 0 90)
			(layer "B.Fab")
			(effects
				(font
					(size 1.27 1.27)
				)
				(justify mirror)
			)
		)
		(duplicate_pad_numbers_are_jumpers no)
		(fp_line
			(start -0.299974 0.150114)
			(end 0.299974 0.150114)
			(stroke
				(width 0.1)
				(type default)
			)
			(layer "B.Fab")
		)
		(fp_line
			(start 0.299974 0.150114)
			(end 0.299974 -0.150114)
			(stroke
				(width 0.1)
				(type default)
			)
			(layer "B.Fab")
		)
		(fp_line
			(start -0.299974 -0.150114)
			(end -0.299974 0.150114)
			(stroke
				(width 0.1)
				(type default)
			)
			(layer "B.Fab")
		)
		(fp_line
			(start 0.299974 -0.150114)
			(end -0.299974 -0.150114)
			(stroke
				(width 0.1)
				(type default)
			)
			(layer "B.Fab")
		)
		(pad "1" smd rect
			(at 0.2667 0 90)
			(size 0.3048 0.381)
			(layers "B.Cu" "B.Mask" "B.Paste")
			(net "P0V8_SERDES_VDDA_PEX1")
		)
		(pad "2" smd rect
			(at -0.2667 0 90)
			(size 0.3048 0.381)
			(layers "B.Cu" "B.Mask" "B.Paste")
			(net "GND")
		)
	)
	(footprint ""
		(layer "B.Cu")
		(at 296.1513 -305.399948 -90)
		(property "Reference" "C3301"
			(at 0 0 90)
			(layer "B.SilkS")
			(hide yes)
			(effects
				(font
					(size 1.27 1.27)
				)
				(justify mirror)
			)
		)
		(property "Value" ""
			(at 0 0 90)
			(layer "B.Fab")
			(effects
				(font
					(size 1.27 1.27)
				)
				(justify mirror)
			)
		)
		(duplicate_pad_numbers_are_jumpers no)
		(fp_line
			(start -0.299974 0.150114)
			(end 0.299974 0.150114)
			(stroke
				(width 0.1)
				(type default)
			)
			(layer "B.Fab")
		)
		(fp_line
			(start 0.299974 0.150114)
			(end 0.299974 -0.150114)
			(stroke
				(width 0.1)
				(type default)
			)
			(layer "B.Fab")
		)
		(fp_line
			(start -0.299974 -0.150114)
			(end -0.299974 0.150114)
			(stroke
				(width 0.1)
				(type default)
			)
			(layer "B.Fab")
		)
		(fp_line
			(start 0.299974 -0.150114)
			(end -0.299974 -0.150114)
			(stroke
				(width 0.1)
				(type default)
			)
			(layer "B.Fab")
		)
		(pad "1" smd rect
			(at 0.2667 0 90)
			(size 0.3048 0.381)
			(layers "B.Cu" "B.Mask" "B.Paste")
			(net "P1V25_SERDES_VDDPLL_PEX2")
		)
		(pad "2" smd rect
			(at -0.2667 0 90)
			(size 0.3048 0.381)
			(layers "B.Cu" "B.Mask" "B.Paste")
			(net "GND")
		)
	)
	(footprint ""
		(layer "B.Cu")
		(at 49.1998 -300.174914)
		(property "Reference" "C1131"
			(at 0 0 0)
			(layer "B.SilkS")
			(hide yes)
			(effects
				(font
					(size 1.27 1.27)
				)
				(justify mirror)
			)
		)
		(property "Value" ""
			(at 0 0 0)
			(layer "B.Fab")
			(effects
				(font
					(size 1.27 1.27)
				)
				(justify mirror)
			)
		)
		(duplicate_pad_numbers_are_jumpers no)
		(fp_line
			(start -0.299974 -0.150114)
			(end -0.299974 0.150114)
			(stroke
				(width 0.1)
				(type default)
			)
			(layer "B.Fab")
		)
		(fp_line
			(start -0.299974 0.150114)
			(end 0.299974 0.150114)
			(stroke
				(width 0.1)
				(type default)
			)
			(layer "B.Fab")
		)
		(fp_line
			(start 0.299974 -0.150114)
			(end -0.299974 -0.150114)
			(stroke
				(width 0.1)
				(type default)
			)
			(layer "B.Fab")
		)
		(fp_line
			(start 0.299974 0.150114)
			(end 0.299974 -0.150114)
			(stroke
				(width 0.1)
				(type default)
			)
			(layer "B.Fab")
		)
		(pad "1" smd rect
			(at 0.2667 0 180)
			(size 0.3048 0.381)
			(layers "B.Cu" "B.Mask" "B.Paste")
			(net "P0V8_PEX0")
		)
		(pad "2" smd rect
			(at -0.2667 0 180)
			(size 0.3048 0.381)
			(layers "B.Cu" "B.Mask" "B.Paste")
			(net "GND")
		)
	)
	(footprint ""
		(layer "B.Cu")
		(at 180.02504 -293.99992 -90)
		(property "Reference" "C1408"
			(at 0 0 90)
			(layer "B.SilkS")
			(hide yes)
			(effects
				(font
					(size 1.27 1.27)
				)
				(justify mirror)
			)
		)
		(property "Value" ""
			(at 0 0 90)
			(layer "B.Fab")
			(effects
				(font
					(size 1.27 1.27)
				)
				(justify mirror)
			)
		)
		(duplicate_pad_numbers_are_jumpers no)
		(fp_line
			(start -0.299974 0.150114)
			(end 0.299974 0.150114)
			(stroke
				(width 0.1)
				(type default)
			)
			(layer "B.Fab")
		)
		(fp_line
			(start 0.299974 0.150114)
			(end 0.299974 -0.150114)
			(stroke
				(width 0.1)
				(type default)
			)
			(layer "B.Fab")
		)
		(fp_line
			(start -0.299974 -0.150114)
			(end -0.299974 0.150114)
			(stroke
				(width 0.1)
				(type default)
			)
			(layer "B.Fab")
		)
		(fp_line
			(start 0.299974 -0.150114)
			(end -0.299974 -0.150114)
			(stroke
				(width 0.1)
				(type default)
			)
			(layer "B.Fab")
		)
		(pad "1" smd rect
			(at 0.2667 0 90)
			(size 0.3048 0.381)
			(layers "B.Cu" "B.Mask" "B.Paste")
			(net "P0V8_PEX1")
		)
		(pad "2" smd rect
			(at -0.2667 0 90)
			(size 0.3048 0.381)
			(layers "B.Cu" "B.Mask" "B.Paste")
			(net "GND")
		)
	)
	(footprint ""
		(layer "B.Cu")
		(at 174.820326 -296.37482)
		(property "Reference" "C1362"
			(at 0 0 0)
			(layer "B.SilkS")
			(hide yes)
			(effects
				(font
					(size 1.27 1.27)
				)
				(justify mirror)
			)
		)
		(property "Value" ""
			(at 0 0 0)
			(layer "B.Fab")
			(effects
				(font
					(size 1.27 1.27)
				)
				(justify mirror)
			)
		)
		(duplicate_pad_numbers_are_jumpers no)
		(fp_line
			(start -0.299974 -0.150114)
			(end -0.299974 0.150114)
			(stroke
				(width 0.1)
				(type default)
			)
			(layer "B.Fab")
		)
		(fp_line
			(start -0.299974 0.150114)
			(end 0.299974 0.150114)
			(stroke
				(width 0.1)
				(type default)
			)
			(layer "B.Fab")
		)
		(fp_line
			(start 0.299974 -0.150114)
			(end -0.299974 -0.150114)
			(stroke
				(width 0.1)
				(type default)
			)
			(layer "B.Fab")
		)
		(fp_line
			(start 0.299974 0.150114)
			(end 0.299974 -0.150114)
			(stroke
				(width 0.1)
				(type default)
			)
			(layer "B.Fab")
		)
		(pad "1" smd rect
			(at 0.2667 0 180)
			(size 0.3048 0.381)
			(layers "B.Cu" "B.Mask" "B.Paste")
			(net "P0V8_PEX1")
		)
		(pad "2" smd rect
			(at -0.2667 0 180)
			(size 0.3048 0.381)
			(layers "B.Cu" "B.Mask" "B.Paste")
			(net "GND")
		)
	)
	(footprint ""
		(layer "B.Cu")
		(at 293.797228 -110.497366)
		(property "Reference" "R288"
			(at 0 0 0)
			(layer "B.SilkS")
			(hide yes)
			(effects
				(font
					(size 1.27 1.27)
				)
				(justify mirror)
			)
		)
		(property "Value" ""
			(at 0 0 0)
			(layer "B.Fab")
			(effects
				(font
					(size 1.27 1.27)
				)
				(justify mirror)
			)
		)
		(duplicate_pad_numbers_are_jumpers no)
		(fp_line
			(start -0.7874 -0.4064)
			(end -0.7874 0.4064)
			(stroke
				(width 0.1524)
				(type default)
			)
			(layer "B.SilkS")
		)
		(fp_line
			(start -0.7874 0.4064)
			(end 0.7874 0.4064)
			(stroke
				(width 0.1524)
				(type default)
			)
			(layer "B.SilkS")
		)
		(fp_line
			(start 0.7874 -0.4064)
			(end -0.7874 -0.4064)
			(stroke
				(width 0.1524)
				(type default)
			)
			(layer "B.SilkS")
		)
		(fp_line
			(start 0.7874 0.4064)
			(end 0.7874 -0.4064)
			(stroke
				(width 0.1524)
				(type default)
			)
			(layer "B.SilkS")
		)
		(fp_line
			(start -0.67945 -0.3048)
			(end -0.67945 0.3048)
			(stroke
				(width 0.1)
				(type default)
			)
			(layer "B.Fab")
		)
		(fp_line
			(start -0.67945 0.3048)
			(end -0.120396 0.3048)
			(stroke
				(width 0.1)
				(type default)
			)
			(layer "B.Fab")
		)
		(fp_line
			(start -0.12065 -0.3048)
			(end -0.67945 -0.3048)
			(stroke
				(width 0.1)
				(type default)
			)
			(layer "B.Fab")
		)
		(fp_line
			(start -0.12065 -0.2794)
			(end -0.12065 -0.3048)
			(stroke
				(width 0.1)
				(type default)
			)
			(layer "B.Fab")
		)
		(fp_line
			(start -0.120396 0.2794)
			(end 0.12065 0.2794)
			(stroke
				(width 0.1)
				(type default)
			)
			(layer "B.Fab")
		)
		(fp_line
			(start -0.120396 0.3048)
			(end -0.120396 0.2794)
			(stroke
				(width 0.1)
				(type default)
			)
			(layer "B.Fab")
		)
		(fp_line
			(start 0.12065 -0.305054)
			(end 0.12065 -0.2794)
			(stroke
				(width 0.1)
				(type default)
			)
			(layer "B.Fab")
		)
		(fp_line
			(start 0.12065 -0.2794)
			(end -0.12065 -0.2794)
			(stroke
				(width 0.1)
				(type default)
			)
			(layer "B.Fab")
		)
		(fp_line
			(start 0.12065 0.2794)
			(end 0.12065 0.3048)
			(stroke
				(width 0.1)
				(type default)
			)
			(layer "B.Fab")
		)
		(fp_line
			(start 0.12065 0.3048)
			(end 0.67945 0.3048)
			(stroke
				(width 0.1)
				(type default)
			)
			(layer "B.Fab")
		)
		(fp_line
			(start 0.67945 -0.305054)
			(end 0.12065 -0.305054)
			(stroke
				(width 0.1)
				(type default)
			)
			(layer "B.Fab")
		)
		(fp_line
			(start 0.67945 0.3048)
			(end 0.67945 -0.305054)
			(stroke
				(width 0.1)
				(type default)
			)
			(layer "B.Fab")
		)
		(pad "1" smd circle
			(at 0.40005 0 180)
			(size 0 0)
			(layers "B.Cu" "B.Mask" "B.Paste")
			(net "NIC5_BIF2_N")
		)
		(pad "2" smd circle
			(at -0.40005 0 180)
			(size 0 0)
			(layers "B.Cu" "B.Mask" "B.Paste")
			(net "P3V3_AUX")
		)
	)
	(footprint ""
		(layer "B.Cu")
		(at 24.219408 -228.346 90)
		(property "Reference" "R3447"
			(at 0 0 90)
			(layer "B.SilkS")
			(hide yes)
			(effects
				(font
					(size 1.27 1.27)
				)
				(justify mirror)
			)
		)
		(property "Value" ""
			(at 0 0 90)
			(layer "B.Fab")
			(effects
				(font
					(size 1.27 1.27)
				)
				(justify mirror)
			)
		)
		(duplicate_pad_numbers_are_jumpers no)
		(fp_line
			(start 0.7874 -0.4064)
			(end -0.7874 -0.4064)
			(stroke
				(width 0.1524)
				(type default)
			)
			(layer "B.SilkS")
		)
		(fp_line
			(start -0.7874 -0.4064)
			(end -0.7874 0.4064)
			(stroke
				(width 0.1524)
				(type default)
			)
			(layer "B.SilkS")
		)
		(fp_line
			(start 0.7874 0.4064)
			(end 0.7874 -0.4064)
			(stroke
				(width 0.1524)
				(type default)
			)
			(layer "B.SilkS")
		)
		(fp_line
			(start -0.7874 0.4064)
			(end 0.7874 0.4064)
			(stroke
				(width 0.1524)
				(type default)
			)
			(layer "B.SilkS")
		)
		(fp_line
			(start 0.67945 -0.305054)
			(end 0.12065 -0.305054)
			(stroke
				(width 0.1)
				(type default)
			)
			(layer "B.Fab")
		)
		(fp_line
			(start 0.12065 -0.305054)
			(end 0.12065 -0.2794)
			(stroke
				(width 0.1)
				(type default)
			)
			(layer "B.Fab")
		)
		(fp_line
			(start -0.12065 -0.3048)
			(end -0.67945 -0.3048)
			(stroke
				(width 0.1)
				(type default)
			)
			(layer "B.Fab")
		)
		(fp_line
			(start -0.67945 -0.3048)
			(end -0.67945 0.3048)
			(stroke
				(width 0.1)
				(type default)
			)
			(layer "B.Fab")
		)
		(fp_line
			(start 0.12065 -0.2794)
			(end -0.12065 -0.2794)
			(stroke
				(width 0.1)
				(type default)
			)
			(layer "B.Fab")
		)
		(fp_line
			(start -0.12065 -0.2794)
			(end -0.12065 -0.3048)
			(stroke
				(width 0.1)
				(type default)
			)
			(layer "B.Fab")
		)
		(fp_line
			(start 0.12065 0.2794)
			(end 0.12065 0.3048)
			(stroke
				(width 0.1)
				(type default)
			)
			(layer "B.Fab")
		)
		(fp_line
			(start -0.120396 0.2794)
			(end 0.12065 0.2794)
			(stroke
				(width 0.1)
				(type default)
			)
			(layer "B.Fab")
		)
		(fp_line
			(start 0.67945 0.3048)
			(end 0.67945 -0.305054)
			(stroke
				(width 0.1)
				(type default)
			)
			(layer "B.Fab")
		)
		(fp_line
			(start 0.12065 0.3048)
			(end 0.67945 0.3048)
			(stroke
				(width 0.1)
				(type default)
			)
			(layer "B.Fab")
		)
		(fp_line
			(start -0.120396 0.3048)
			(end -0.120396 0.2794)
			(stroke
				(width 0.1)
				(type default)
			)
			(layer "B.Fab")
		)
		(fp_line
			(start -0.67945 0.3048)
			(end -0.120396 0.3048)
			(stroke
				(width 0.1)
				(type default)
			)
			(layer "B.Fab")
		)
		(pad "1" smd circle
			(at 0.40005 0 270)
			(size 0 0)
			(layers "B.Cu" "B.Mask" "B.Paste")
			(net "SPI_PEX0_CS_MUX_N")
		)
		(pad "2" smd circle
			(at -0.40005 0 270)
			(size 0 0)
			(layers "B.Cu" "B.Mask" "B.Paste")
			(net "SPI_PEX0_CS_MUX_R_N")
		)
	)
	(footprint ""
		(layer "B.Cu")
		(at 403.199854 -288.299906 90)
		(property "Reference" "C3461"
			(at 0 0 90)
			(layer "B.SilkS")
			(hide yes)
			(effects
				(font
					(size 1.27 1.27)
				)
				(justify mirror)
			)
		)
		(property "Value" ""
			(at 0 0 90)
			(layer "B.Fab")
			(effects
				(font
					(size 1.27 1.27)
				)
				(justify mirror)
			)
		)
		(duplicate_pad_numbers_are_jumpers no)
		(fp_line
			(start 0.299974 -0.150114)
			(end -0.299974 -0.150114)
			(stroke
				(width 0.1)
				(type default)
			)
			(layer "B.Fab")
		)
		(fp_line
			(start -0.299974 -0.150114)
			(end -0.299974 0.150114)
			(stroke
				(width 0.1)
				(type default)
			)
			(layer "B.Fab")
		)
		(fp_line
			(start 0.299974 0.150114)
			(end 0.299974 -0.150114)
			(stroke
				(width 0.1)
				(type default)
			)
			(layer "B.Fab")
		)
		(fp_line
			(start -0.299974 0.150114)
			(end 0.299974 0.150114)
			(stroke
				(width 0.1)
				(type default)
			)
			(layer "B.Fab")
		)
		(pad "1" smd rect
			(at 0.2667 0 270)
			(size 0.3048 0.381)
			(layers "B.Cu" "B.Mask" "B.Paste")
			(net "P1V25_PEX3")
		)
		(pad "2" smd rect
			(at -0.2667 0 270)
			(size 0.3048 0.381)
			(layers "B.Cu" "B.Mask" "B.Paste")
			(net "GND")
		)
	)
	(footprint ""
		(layer "B.Cu")
		(at 286.569912 -305.399948 -90)
		(property "Reference" "C3319"
			(at 0 0 90)
			(layer "B.SilkS")
			(hide yes)
			(effects
				(font
					(size 1.27 1.27)
				)
				(justify mirror)
			)
		)
		(property "Value" ""
			(at 0 0 90)
			(layer "B.Fab")
			(effects
				(font
					(size 1.27 1.27)
				)
				(justify mirror)
			)
		)
		(duplicate_pad_numbers_are_jumpers no)
		(fp_line
			(start -0.299974 0.150114)
			(end 0.299974 0.150114)
			(stroke
				(width 0.1)
				(type default)
			)
			(layer "B.Fab")
		)
		(fp_line
			(start 0.299974 0.150114)
			(end 0.299974 -0.150114)
			(stroke
				(width 0.1)
				(type default)
			)
			(layer "B.Fab")
		)
		(fp_line
			(start -0.299974 -0.150114)
			(end -0.299974 0.150114)
			(stroke
				(width 0.1)
				(type default)
			)
			(layer "B.Fab")
		)
		(fp_line
			(start 0.299974 -0.150114)
			(end -0.299974 -0.150114)
			(stroke
				(width 0.1)
				(type default)
			)
			(layer "B.Fab")
		)
		(pad "1" smd rect
			(at 0.2667 0 90)
			(size 0.3048 0.381)
			(layers "B.Cu" "B.Mask" "B.Paste")
			(net "P1V25_SERDES_VDDPLL_PEX2")
		)
		(pad "2" smd rect
			(at -0.2667 0 90)
			(size 0.3048 0.381)
			(layers "B.Cu" "B.Mask" "B.Paste")
			(net "GND")
		)
	)
	(footprint ""
		(layer "B.Cu")
		(at 174.270162 -305.399948 -90)
		(property "Reference" "C3154"
			(at 0 0 90)
			(layer "B.SilkS")
			(hide yes)
			(effects
				(font
					(size 1.27 1.27)
				)
				(justify mirror)
			)
		)
		(property "Value" ""
			(at 0 0 90)
			(layer "B.Fab")
			(effects
				(font
					(size 1.27 1.27)
				)
				(justify mirror)
			)
		)
		(duplicate_pad_numbers_are_jumpers no)
		(fp_line
			(start -0.299974 0.150114)
			(end 0.299974 0.150114)
			(stroke
				(width 0.1)
				(type default)
			)
			(layer "B.Fab")
		)
		(fp_line
			(start 0.299974 0.150114)
			(end 0.299974 -0.150114)
			(stroke
				(width 0.1)
				(type default)
			)
			(layer "B.Fab")
		)
		(fp_line
			(start -0.299974 -0.150114)
			(end -0.299974 0.150114)
			(stroke
				(width 0.1)
				(type default)
			)
			(layer "B.Fab")
		)
		(fp_line
			(start 0.299974 -0.150114)
			(end -0.299974 -0.150114)
			(stroke
				(width 0.1)
				(type default)
			)
			(layer "B.Fab")
		)
		(pad "1" smd rect
			(at 0.2667 0 90)
			(size 0.3048 0.381)
			(layers "B.Cu" "B.Mask" "B.Paste")
			(net "P1V25_SERDES_VDDPLL_PEX1")
		)
		(pad "2" smd rect
			(at -0.2667 0 90)
			(size 0.3048 0.381)
			(layers "B.Cu" "B.Mask" "B.Paste")
			(net "GND")
		)
	)
	(footprint ""
		(layer "B.Cu")
		(at 78.501748 -295.422066 180)
		(property "Reference" "C2903"
			(at 0 0 0)
			(layer "B.SilkS")
			(hide yes)
			(effects
				(font
					(size 1.27 1.27)
				)
				(justify mirror)
			)
		)
		(property "Value" ""
			(at 0 0 0)
			(layer "B.Fab")
			(effects
				(font
					(size 1.27 1.27)
				)
				(justify mirror)
			)
		)
		(duplicate_pad_numbers_are_jumpers no)
		(fp_line
			(start 1.2954 0.5842)
			(end 1.2954 -0.5842)
			(stroke
				(width 0.1524)
				(type default)
			)
			(layer "B.SilkS")
		)
		(fp_line
			(start 1.2954 -0.5842)
			(end -1.2954 -0.5842)
			(stroke
				(width 0.1524)
				(type default)
			)
			(layer "B.SilkS")
		)
		(fp_line
			(start -1.2954 0.5842)
			(end 1.2954 0.5842)
			(stroke
				(width 0.1524)
				(type default)
			)
			(layer "B.SilkS")
		)
		(fp_line
			(start -1.2954 -0.5842)
			(end -1.2954 0.5842)
			(stroke
				(width 0.1524)
				(type default)
			)
			(layer "B.SilkS")
		)
		(fp_line
			(start 1.1938 0.4064)
			(end 1.1938 -0.4064)
			(stroke
				(width 0.1)
				(type default)
			)
			(layer "B.Fab")
		)
		(fp_line
			(start 1.1938 -0.4064)
			(end 0.8636 -0.4064)
			(stroke
				(width 0.1)
				(type default)
			)
			(layer "B.Fab")
		)
		(fp_line
			(start 0.8636 0.4572)
			(end 0.8636 0.4064)
			(stroke
				(width 0.1)
				(type default)
			)
			(layer "B.Fab")
		)
		(fp_line
			(start 0.8636 0.4064)
			(end 1.1938 0.4064)
			(stroke
				(width 0.1)
				(type default)
			)
			(layer "B.Fab")
		)
		(fp_line
			(start 0.8636 -0.4064)
			(end 0.8636 -0.4572)
			(stroke
				(width 0.1)
				(type default)
			)
			(layer "B.Fab")
		)
		(fp_line
			(start 0.8636 -0.4572)
			(end -0.8636 -0.4572)
			(stroke
				(width 0.1)
				(type default)
			)
			(layer "B.Fab")
		)
		(fp_line
			(start -0.8636 0.4572)
			(end 0.8636 0.4572)
			(stroke
				(width 0.1)
				(type default)
			)
			(layer "B.Fab")
		)
		(fp_line
			(start -0.8636 0.4064)
			(end -0.8636 0.4572)
			(stroke
				(width 0.1)
				(type default)
			)
			(layer "B.Fab")
		)
		(fp_line
			(start -0.8636 -0.4064)
			(end -1.1938 -0.4064)
			(stroke
				(width 0.1)
				(type default)
			)
			(layer "B.Fab")
		)
		(fp_line
			(start -0.8636 -0.4572)
			(end -0.8636 -0.4064)
			(stroke
				(width 0.1)
				(type default)
			)
			(layer "B.Fab")
		)
		(fp_line
			(start -1.1938 0.4064)
			(end -0.8636 0.4064)
			(stroke
				(width 0.1)
				(type default)
			)
			(layer "B.Fab")
		)
		(fp_line
			(start -1.1938 -0.4064)
			(end -1.1938 0.4064)
			(stroke
				(width 0.1)
				(type default)
			)
			(layer "B.Fab")
		)
		(pad "1" smd rect
			(at 0.7366 0 90)
			(size 0.7112 0.8128)
			(layers "B.Cu" "B.Mask" "B.Paste")
			(net "P1V25_PEX0")
		)
		(pad "2" smd rect
			(at -0.7366 0 90)
			(size 0.7112 0.8128)
			(layers "B.Cu" "B.Mask" "B.Paste")
			(net "GND")
		)
	)
	(footprint ""
		(layer "B.Cu")
		(at 56.26989 -305.399948 -90)
		(property "Reference" "C2970"
			(at 0 0 90)
			(layer "B.SilkS")
			(hide yes)
			(effects
				(font
					(size 1.27 1.27)
				)
				(justify mirror)
			)
		)
		(property "Value" ""
			(at 0 0 90)
			(layer "B.Fab")
			(effects
				(font
					(size 1.27 1.27)
				)
				(justify mirror)
			)
		)
		(duplicate_pad_numbers_are_jumpers no)
		(fp_line
			(start -0.299974 0.150114)
			(end 0.299974 0.150114)
			(stroke
				(width 0.1)
				(type default)
			)
			(layer "B.Fab")
		)
		(fp_line
			(start 0.299974 0.150114)
			(end 0.299974 -0.150114)
			(stroke
				(width 0.1)
				(type default)
			)
			(layer "B.Fab")
		)
		(fp_line
			(start -0.299974 -0.150114)
			(end -0.299974 0.150114)
			(stroke
				(width 0.1)
				(type default)
			)
			(layer "B.Fab")
		)
		(fp_line
			(start 0.299974 -0.150114)
			(end -0.299974 -0.150114)
			(stroke
				(width 0.1)
				(type default)
			)
			(layer "B.Fab")
		)
		(pad "1" smd rect
			(at 0.2667 0 90)
			(size 0.3048 0.381)
			(layers "B.Cu" "B.Mask" "B.Paste")
			(net "P1V25_SERDES_VDDPLL_PEX0")
		)
		(pad "2" smd rect
			(at -0.2667 0 90)
			(size 0.3048 0.381)
			(layers "B.Cu" "B.Mask" "B.Paste")
			(net "GND")
		)
	)
	(footprint ""
		(layer "B.Cu")
		(at 60.599828 -292.099746 90)
		(property "Reference" "C1223"
			(at 0 0 90)
			(layer "B.SilkS")
			(hide yes)
			(effects
				(font
					(size 1.27 1.27)
				)
				(justify mirror)
			)
		)
		(property "Value" ""
			(at 0 0 90)
			(layer "B.Fab")
			(effects
				(font
					(size 1.27 1.27)
				)
				(justify mirror)
			)
		)
		(duplicate_pad_numbers_are_jumpers no)
		(fp_line
			(start 0.299974 -0.150114)
			(end -0.299974 -0.150114)
			(stroke
				(width 0.1)
				(type default)
			)
			(layer "B.Fab")
		)
		(fp_line
			(start -0.299974 -0.150114)
			(end -0.299974 0.150114)
			(stroke
				(width 0.1)
				(type default)
			)
			(layer "B.Fab")
		)
		(fp_line
			(start 0.299974 0.150114)
			(end 0.299974 -0.150114)
			(stroke
				(width 0.1)
				(type default)
			)
			(layer "B.Fab")
		)
		(fp_line
			(start -0.299974 0.150114)
			(end 0.299974 0.150114)
			(stroke
				(width 0.1)
				(type default)
			)
			(layer "B.Fab")
		)
		(pad "1" smd rect
			(at 0.2667 0 270)
			(size 0.3048 0.381)
			(layers "B.Cu" "B.Mask" "B.Paste")
			(net "P0V8_SERDES_VDDA_PEX0")
		)
		(pad "2" smd rect
			(at -0.2667 0 270)
			(size 0.3048 0.381)
			(layers "B.Cu" "B.Mask" "B.Paste")
			(net "GND")
		)
	)
	(footprint ""
		(layer "B.Cu")
		(at 412.699962 -290.199826 90)
		(property "Reference" "C2003"
			(at 0 0 90)
			(layer "B.SilkS")
			(hide yes)
			(effects
				(font
					(size 1.27 1.27)
				)
				(justify mirror)
			)
		)
		(property "Value" ""
			(at 0 0 90)
			(layer "B.Fab")
			(effects
				(font
					(size 1.27 1.27)
				)
				(justify mirror)
			)
		)
		(duplicate_pad_numbers_are_jumpers no)
		(fp_line
			(start 0.299974 -0.150114)
			(end -0.299974 -0.150114)
			(stroke
				(width 0.1)
				(type default)
			)
			(layer "B.Fab")
		)
		(fp_line
			(start -0.299974 -0.150114)
			(end -0.299974 0.150114)
			(stroke
				(width 0.1)
				(type default)
			)
			(layer "B.Fab")
		)
		(fp_line
			(start 0.299974 0.150114)
			(end 0.299974 -0.150114)
			(stroke
				(width 0.1)
				(type default)
			)
			(layer "B.Fab")
		)
		(fp_line
			(start -0.299974 0.150114)
			(end 0.299974 0.150114)
			(stroke
				(width 0.1)
				(type default)
			)
			(layer "B.Fab")
		)
		(pad "1" smd rect
			(at 0.2667 0 270)
			(size 0.3048 0.381)
			(layers "B.Cu" "B.Mask" "B.Paste")
			(net "P0V8_SERDES_VDDA_PEX3")
		)
		(pad "2" smd rect
			(at -0.2667 0 270)
			(size 0.3048 0.381)
			(layers "B.Cu" "B.Mask" "B.Paste")
			(net "GND")
		)
	)
	(footprint ""
		(layer "B.Cu")
		(at 140.640816 -202.282806 180)
		(property "Reference" "C2599"
			(at 0 0 0)
			(layer "B.SilkS")
			(hide yes)
			(effects
				(font
					(size 1.27 1.27)
				)
				(justify mirror)
			)
		)
		(property "Value" ""
			(at 0 0 0)
			(layer "B.Fab")
			(effects
				(font
					(size 1.27 1.27)
				)
				(justify mirror)
			)
		)
		(duplicate_pad_numbers_are_jumpers no)
		(fp_line
			(start 0.7874 0.4064)
			(end 0.7874 -0.4064)
			(stroke
				(width 0.1524)
				(type default)
			)
			(layer "B.SilkS")
		)
		(fp_line
			(start 0.7874 -0.4064)
			(end -0.7874 -0.4064)
			(stroke
				(width 0.1524)
				(type default)
			)
			(layer "B.SilkS")
		)
		(fp_line
			(start -0.7874 0.4064)
			(end 0.7874 0.4064)
			(stroke
				(width 0.1524)
				(type default)
			)
			(layer "B.SilkS")
		)
		(fp_line
			(start -0.7874 -0.4064)
			(end -0.7874 0.4064)
			(stroke
				(width 0.1524)
				(type default)
			)
			(layer "B.SilkS")
		)
		(fp_line
			(start 0.67945 0.3048)
			(end 0.67945 -0.305054)
			(stroke
				(width 0.1)
				(type default)
			)
			(layer "B.Fab")
		)
		(fp_line
			(start 0.67945 -0.305054)
			(end 0.12065 -0.305054)
			(stroke
				(width 0.1)
				(type default)
			)
			(layer "B.Fab")
		)
		(fp_line
			(start 0.12065 0.3048)
			(end 0.67945 0.3048)
			(stroke
				(width 0.1)
				(type default)
			)
			(layer "B.Fab")
		)
		(fp_line
			(start 0.12065 0.2794)
			(end 0.12065 0.3048)
			(stroke
				(width 0.1)
				(type default)
			)
			(layer "B.Fab")
		)
		(fp_line
			(start 0.12065 -0.2794)
			(end -0.12065 -0.2794)
			(stroke
				(width 0.1)
				(type default)
			)
			(layer "B.Fab")
		)
		(fp_line
			(start 0.12065 -0.305054)
			(end 0.12065 -0.2794)
			(stroke
				(width 0.1)
				(type default)
			)
			(layer "B.Fab")
		)
		(fp_line
			(start -0.120396 0.3048)
			(end -0.120396 0.2794)
			(stroke
				(width 0.1)
				(type default)
			)
			(layer "B.Fab")
		)
		(fp_line
			(start -0.120396 0.2794)
			(end 0.12065 0.2794)
			(stroke
				(width 0.1)
				(type default)
			)
			(layer "B.Fab")
		)
		(fp_line
			(start -0.12065 -0.2794)
			(end -0.12065 -0.3048)
			(stroke
				(width 0.1)
				(type default)
			)
			(layer "B.Fab")
		)
		(fp_line
			(start -0.12065 -0.3048)
			(end -0.67945 -0.3048)
			(stroke
				(width 0.1)
				(type default)
			)
			(layer "B.Fab")
		)
		(fp_line
			(start -0.67945 0.3048)
			(end -0.120396 0.3048)
			(stroke
				(width 0.1)
				(type default)
			)
			(layer "B.Fab")
		)
		(fp_line
			(start -0.67945 -0.3048)
			(end -0.67945 0.3048)
			(stroke
				(width 0.1)
				(type default)
			)
			(layer "B.Fab")
		)
		(pad "1" smd circle
			(at 0.40005 0)
			(size 0 0)
			(layers "B.Cu" "B.Mask" "B.Paste")
			(net "P3V3_CLI_VPLL")
		)
		(pad "2" smd circle
			(at -0.40005 0)
			(size 0 0)
			(layers "B.Cu" "B.Mask" "B.Paste")
			(net "GND")
		)
	)
	(footprint ""
		(layer "B.Cu")
		(at 305.149758 -296.8498 180)
		(property "Reference" "C3296"
			(at 0 0 0)
			(layer "B.SilkS")
			(hide yes)
			(effects
				(font
					(size 1.27 1.27)
				)
				(justify mirror)
			)
		)
		(property "Value" ""
			(at 0 0 0)
			(layer "B.Fab")
			(effects
				(font
					(size 1.27 1.27)
				)
				(justify mirror)
			)
		)
		(duplicate_pad_numbers_are_jumpers no)
		(fp_line
			(start 0.299974 0.150114)
			(end 0.299974 -0.150114)
			(stroke
				(width 0.1)
				(type default)
			)
			(layer "B.Fab")
		)
		(fp_line
			(start 0.299974 -0.150114)
			(end -0.299974 -0.150114)
			(stroke
				(width 0.1)
				(type default)
			)
			(layer "B.Fab")
		)
		(fp_line
			(start -0.299974 0.150114)
			(end 0.299974 0.150114)
			(stroke
				(width 0.1)
				(type default)
			)
			(layer "B.Fab")
		)
		(fp_line
			(start -0.299974 -0.150114)
			(end -0.299974 0.150114)
			(stroke
				(width 0.1)
				(type default)
			)
			(layer "B.Fab")
		)
		(pad "1" smd rect
			(at 0.2667 0)
			(size 0.3048 0.381)
			(layers "B.Cu" "B.Mask" "B.Paste")
			(net "P1V25_SERDES_VDDPLL_PEX2")
		)
		(pad "2" smd rect
			(at -0.2667 0)
			(size 0.3048 0.381)
			(layers "B.Cu" "B.Mask" "B.Paste")
			(net "GND")
		)
	)
	(footprint ""
		(layer "B.Cu")
		(at 174.800006 -290.199826 90)
		(property "Reference" "C1433"
			(at 0 0 90)
			(layer "B.SilkS")
			(hide yes)
			(effects
				(font
					(size 1.27 1.27)
				)
				(justify mirror)
			)
		)
		(property "Value" ""
			(at 0 0 90)
			(layer "B.Fab")
			(effects
				(font
					(size 1.27 1.27)
				)
				(justify mirror)
			)
		)
		(duplicate_pad_numbers_are_jumpers no)
		(fp_line
			(start 0.299974 -0.150114)
			(end -0.299974 -0.150114)
			(stroke
				(width 0.1)
				(type default)
			)
			(layer "B.Fab")
		)
		(fp_line
			(start -0.299974 -0.150114)
			(end -0.299974 0.150114)
			(stroke
				(width 0.1)
				(type default)
			)
			(layer "B.Fab")
		)
		(fp_line
			(start 0.299974 0.150114)
			(end 0.299974 -0.150114)
			(stroke
				(width 0.1)
				(type default)
			)
			(layer "B.Fab")
		)
		(fp_line
			(start -0.299974 0.150114)
			(end 0.299974 0.150114)
			(stroke
				(width 0.1)
				(type default)
			)
			(layer "B.Fab")
		)
		(pad "1" smd rect
			(at 0.2667 0 270)
			(size 0.3048 0.381)
			(layers "B.Cu" "B.Mask" "B.Paste")
			(net "P0V8_SERDES_VDDA_PEX1")
		)
		(pad "2" smd rect
			(at -0.2667 0 270)
			(size 0.3048 0.381)
			(layers "B.Cu" "B.Mask" "B.Paste")
			(net "GND")
		)
	)
	(footprint ""
		(layer "B.Cu")
		(at 67.249802 -303.499774 -90)
		(property "Reference" "C2924"
			(at 0 0 90)
			(layer "B.SilkS")
			(hide yes)
			(effects
				(font
					(size 1.27 1.27)
				)
				(justify mirror)
			)
		)
		(property "Value" ""
			(at 0 0 90)
			(layer "B.Fab")
			(effects
				(font
					(size 1.27 1.27)
				)
				(justify mirror)
			)
		)
		(duplicate_pad_numbers_are_jumpers no)
		(fp_line
			(start -0.299974 0.150114)
			(end 0.299974 0.150114)
			(stroke
				(width 0.1)
				(type default)
			)
			(layer "B.Fab")
		)
		(fp_line
			(start 0.299974 0.150114)
			(end 0.299974 -0.150114)
			(stroke
				(width 0.1)
				(type default)
			)
			(layer "B.Fab")
		)
		(fp_line
			(start -0.299974 -0.150114)
			(end -0.299974 0.150114)
			(stroke
				(width 0.1)
				(type default)
			)
			(layer "B.Fab")
		)
		(fp_line
			(start 0.299974 -0.150114)
			(end -0.299974 -0.150114)
			(stroke
				(width 0.1)
				(type default)
			)
			(layer "B.Fab")
		)
		(pad "1" smd rect
			(at 0.2667 0 90)
			(size 0.3048 0.381)
			(layers "B.Cu" "B.Mask" "B.Paste")
			(net "P1V25_PEX0")
		)
		(pad "2" smd rect
			(at -0.2667 0 90)
			(size 0.3048 0.381)
			(layers "B.Cu" "B.Mask" "B.Paste")
			(net "GND")
		)
	)
	(footprint ""
		(layer "B.Cu")
		(at 398.87017 -305.399948 -90)
		(property "Reference" "C3493"
			(at 0 0 90)
			(layer "B.SilkS")
			(hide yes)
			(effects
				(font
					(size 1.27 1.27)
				)
				(justify mirror)
			)
		)
		(property "Value" ""
			(at 0 0 90)
			(layer "B.Fab")
			(effects
				(font
					(size 1.27 1.27)
				)
				(justify mirror)
			)
		)
		(duplicate_pad_numbers_are_jumpers no)
		(fp_line
			(start -0.299974 0.150114)
			(end 0.299974 0.150114)
			(stroke
				(width 0.1)
				(type default)
			)
			(layer "B.Fab")
		)
		(fp_line
			(start 0.299974 0.150114)
			(end 0.299974 -0.150114)
			(stroke
				(width 0.1)
				(type default)
			)
			(layer "B.Fab")
		)
		(fp_line
			(start -0.299974 -0.150114)
			(end -0.299974 0.150114)
			(stroke
				(width 0.1)
				(type default)
			)
			(layer "B.Fab")
		)
		(fp_line
			(start 0.299974 -0.150114)
			(end -0.299974 -0.150114)
			(stroke
				(width 0.1)
				(type default)
			)
			(layer "B.Fab")
		)
		(pad "1" smd rect
			(at 0.2667 0 90)
			(size 0.3048 0.381)
			(layers "B.Cu" "B.Mask" "B.Paste")
			(net "P1V25_SERDES_VDDPLL_PEX3")
		)
		(pad "2" smd rect
			(at -0.2667 0 90)
			(size 0.3048 0.381)
			(layers "B.Cu" "B.Mask" "B.Paste")
			(net "GND")
		)
	)
	(footprint ""
		(layer "B.Cu")
		(at 373.422672 -220.924374 90)
		(property "Reference" "R3505"
			(at 0 0 90)
			(layer "B.SilkS")
			(hide yes)
			(effects
				(font
					(size 1.27 1.27)
				)
				(justify mirror)
			)
		)
		(property "Value" ""
			(at 0 0 90)
			(layer "B.Fab")
			(effects
				(font
					(size 1.27 1.27)
				)
				(justify mirror)
			)
		)
		(duplicate_pad_numbers_are_jumpers no)
		(fp_line
			(start 0.7874 -0.4064)
			(end -0.7874 -0.4064)
			(stroke
				(width 0.1524)
				(type default)
			)
			(layer "B.SilkS")
		)
		(fp_line
			(start -0.7874 -0.4064)
			(end -0.7874 0.4064)
			(stroke
				(width 0.1524)
				(type default)
			)
			(layer "B.SilkS")
		)
		(fp_line
			(start 0.7874 0.4064)
			(end 0.7874 -0.4064)
			(stroke
				(width 0.1524)
				(type default)
			)
			(layer "B.SilkS")
		)
		(fp_line
			(start -0.7874 0.4064)
			(end 0.7874 0.4064)
			(stroke
				(width 0.1524)
				(type default)
			)
			(layer "B.SilkS")
		)
		(fp_line
			(start 0.67945 -0.305054)
			(end 0.12065 -0.305054)
			(stroke
				(width 0.1)
				(type default)
			)
			(layer "B.Fab")
		)
		(fp_line
			(start 0.12065 -0.305054)
			(end 0.12065 -0.2794)
			(stroke
				(width 0.1)
				(type default)
			)
			(layer "B.Fab")
		)
		(fp_line
			(start -0.12065 -0.3048)
			(end -0.67945 -0.3048)
			(stroke
				(width 0.1)
				(type default)
			)
			(layer "B.Fab")
		)
		(fp_line
			(start -0.67945 -0.3048)
			(end -0.67945 0.3048)
			(stroke
				(width 0.1)
				(type default)
			)
			(layer "B.Fab")
		)
		(fp_line
			(start 0.12065 -0.2794)
			(end -0.12065 -0.2794)
			(stroke
				(width 0.1)
				(type default)
			)
			(layer "B.Fab")
		)
		(fp_line
			(start -0.12065 -0.2794)
			(end -0.12065 -0.3048)
			(stroke
				(width 0.1)
				(type default)
			)
			(layer "B.Fab")
		)
		(fp_line
			(start 0.12065 0.2794)
			(end 0.12065 0.3048)
			(stroke
				(width 0.1)
				(type default)
			)
			(layer "B.Fab")
		)
		(fp_line
			(start -0.120396 0.2794)
			(end 0.12065 0.2794)
			(stroke
				(width 0.1)
				(type default)
			)
			(layer "B.Fab")
		)
		(fp_line
			(start 0.67945 0.3048)
			(end 0.67945 -0.305054)
			(stroke
				(width 0.1)
				(type default)
			)
			(layer "B.Fab")
		)
		(fp_line
			(start 0.12065 0.3048)
			(end 0.67945 0.3048)
			(stroke
				(width 0.1)
				(type default)
			)
			(layer "B.Fab")
		)
		(fp_line
			(start -0.120396 0.3048)
			(end -0.120396 0.2794)
			(stroke
				(width 0.1)
				(type default)
			)
			(layer "B.Fab")
		)
		(fp_line
			(start -0.67945 0.3048)
			(end -0.120396 0.3048)
			(stroke
				(width 0.1)
				(type default)
			)
			(layer "B.Fab")
		)
		(pad "1" smd circle
			(at 0.40005 0 270)
			(size 0 0)
			(layers "B.Cu" "B.Mask" "B.Paste")
			(net "P1V8_PEX")
		)
		(pad "2" smd circle
			(at -0.40005 0 270)
			(size 0 0)
			(layers "B.Cu" "B.Mask" "B.Paste")
			(net "SPI_PEX3_SDIO3_R1")
		)
	)
	(footprint ""
		(layer "B.Cu")
		(at 300.872144 -112.421924 180)
		(property "Reference" "R264"
			(at 0 0 0)
			(layer "B.SilkS")
			(hide yes)
			(effects
				(font
					(size 1.27 1.27)
				)
				(justify mirror)
			)
		)
		(property "Value" ""
			(at 0 0 0)
			(layer "B.Fab")
			(effects
				(font
					(size 1.27 1.27)
				)
				(justify mirror)
			)
		)
		(duplicate_pad_numbers_are_jumpers no)
		(fp_line
			(start 0.7874 0.4064)
			(end 0.7874 -0.4064)
			(stroke
				(width 0.1524)
				(type default)
			)
			(layer "B.SilkS")
		)
		(fp_line
			(start 0.7874 -0.4064)
			(end -0.7874 -0.4064)
			(stroke
				(width 0.1524)
				(type default)
			)
			(layer "B.SilkS")
		)
		(fp_line
			(start -0.7874 0.4064)
			(end 0.7874 0.4064)
			(stroke
				(width 0.1524)
				(type default)
			)
			(layer "B.SilkS")
		)
		(fp_line
			(start -0.7874 -0.4064)
			(end -0.7874 0.4064)
			(stroke
				(width 0.1524)
				(type default)
			)
			(layer "B.SilkS")
		)
		(fp_line
			(start 0.67945 0.3048)
			(end 0.67945 -0.305054)
			(stroke
				(width 0.1)
				(type default)
			)
			(layer "B.Fab")
		)
		(fp_line
			(start 0.67945 -0.305054)
			(end 0.12065 -0.305054)
			(stroke
				(width 0.1)
				(type default)
			)
			(layer "B.Fab")
		)
		(fp_line
			(start 0.12065 0.3048)
			(end 0.67945 0.3048)
			(stroke
				(width 0.1)
				(type default)
			)
			(layer "B.Fab")
		)
		(fp_line
			(start 0.12065 0.2794)
			(end 0.12065 0.3048)
			(stroke
				(width 0.1)
				(type default)
			)
			(layer "B.Fab")
		)
		(fp_line
			(start 0.12065 -0.2794)
			(end -0.12065 -0.2794)
			(stroke
				(width 0.1)
				(type default)
			)
			(layer "B.Fab")
		)
		(fp_line
			(start 0.12065 -0.305054)
			(end 0.12065 -0.2794)
			(stroke
				(width 0.1)
				(type default)
			)
			(layer "B.Fab")
		)
		(fp_line
			(start -0.120396 0.3048)
			(end -0.120396 0.2794)
			(stroke
				(width 0.1)
				(type default)
			)
			(layer "B.Fab")
		)
		(fp_line
			(start -0.120396 0.2794)
			(end 0.12065 0.2794)
			(stroke
				(width 0.1)
				(type default)
			)
			(layer "B.Fab")
		)
		(fp_line
			(start -0.12065 -0.2794)
			(end -0.12065 -0.3048)
			(stroke
				(width 0.1)
				(type default)
			)
			(layer "B.Fab")
		)
		(fp_line
			(start -0.12065 -0.3048)
			(end -0.67945 -0.3048)
			(stroke
				(width 0.1)
				(type default)
			)
			(layer "B.Fab")
		)
		(fp_line
			(start -0.67945 0.3048)
			(end -0.120396 0.3048)
			(stroke
				(width 0.1)
				(type default)
			)
			(layer "B.Fab")
		)
		(fp_line
			(start -0.67945 -0.3048)
			(end -0.67945 0.3048)
			(stroke
				(width 0.1)
				(type default)
			)
			(layer "B.Fab")
		)
		(pad "1" smd circle
			(at 0.40005 0)
			(size 0 0)
			(layers "B.Cu" "B.Mask" "B.Paste")
			(net "SMB_NIC5_LS_SCL")
		)
		(pad "2" smd circle
			(at -0.40005 0)
			(size 0 0)
			(layers "B.Cu" "B.Mask" "B.Paste")
			(net "P3V3_NIC5")
		)
	)
	(footprint ""
		(layer "B.Cu")
		(at 394.65504 -295.2623)
		(property "Reference" "C3565"
			(at 0 0 0)
			(layer "B.SilkS")
			(hide yes)
			(effects
				(font
					(size 1.27 1.27)
				)
				(justify mirror)
			)
		)
		(property "Value" ""
			(at 0 0 0)
			(layer "B.Fab")
			(effects
				(font
					(size 1.27 1.27)
				)
				(justify mirror)
			)
		)
		(duplicate_pad_numbers_are_jumpers no)
		(fp_line
			(start -0.299974 -0.150114)
			(end -0.299974 0.150114)
			(stroke
				(width 0.1)
				(type default)
			)
			(layer "B.Fab")
		)
		(fp_line
			(start -0.299974 0.150114)
			(end 0.299974 0.150114)
			(stroke
				(width 0.1)
				(type default)
			)
			(layer "B.Fab")
		)
		(fp_line
			(start 0.299974 -0.150114)
			(end -0.299974 -0.150114)
			(stroke
				(width 0.1)
				(type default)
			)
			(layer "B.Fab")
		)
		(fp_line
			(start 0.299974 0.150114)
			(end 0.299974 -0.150114)
			(stroke
				(width 0.1)
				(type default)
			)
			(layer "B.Fab")
		)
		(pad "1" smd rect
			(at 0.2667 0 180)
			(size 0.3048 0.381)
			(layers "B.Cu" "B.Mask" "B.Paste")
			(net "PCEPLL4_VDDA18_PEX3")
		)
		(pad "2" smd rect
			(at -0.2667 0 180)
			(size 0.3048 0.381)
			(layers "B.Cu" "B.Mask" "B.Paste")
			(net "GND")
		)
	)
	(footprint ""
		(layer "B.Cu")
		(at 15.78356 -215.297258 180)
		(property "Reference" "R6568"
			(at 0 0 0)
			(layer "B.SilkS")
			(hide yes)
			(effects
				(font
					(size 1.27 1.27)
				)
				(justify mirror)
			)
		)
		(property "Value" ""
			(at 0 0 0)
			(layer "B.Fab")
			(effects
				(font
					(size 1.27 1.27)
				)
				(justify mirror)
			)
		)
		(duplicate_pad_numbers_are_jumpers no)
		(fp_line
			(start 0.7874 0.4064)
			(end 0.7874 -0.4064)
			(stroke
				(width 0.1524)
				(type default)
			)
			(layer "B.SilkS")
		)
		(fp_line
			(start 0.7874 -0.4064)
			(end -0.7874 -0.4064)
			(stroke
				(width 0.1524)
				(type default)
			)
			(layer "B.SilkS")
		)
		(fp_line
			(start -0.7874 0.4064)
			(end 0.7874 0.4064)
			(stroke
				(width 0.1524)
				(type default)
			)
			(layer "B.SilkS")
		)
		(fp_line
			(start -0.7874 -0.4064)
			(end -0.7874 0.4064)
			(stroke
				(width 0.1524)
				(type default)
			)
			(layer "B.SilkS")
		)
		(fp_line
			(start 0.67945 0.3048)
			(end 0.67945 -0.305054)
			(stroke
				(width 0.1)
				(type default)
			)
			(layer "B.Fab")
		)
		(fp_line
			(start 0.67945 -0.305054)
			(end 0.12065 -0.305054)
			(stroke
				(width 0.1)
				(type default)
			)
			(layer "B.Fab")
		)
		(fp_line
			(start 0.12065 0.3048)
			(end 0.67945 0.3048)
			(stroke
				(width 0.1)
				(type default)
			)
			(layer "B.Fab")
		)
		(fp_line
			(start 0.12065 0.2794)
			(end 0.12065 0.3048)
			(stroke
				(width 0.1)
				(type default)
			)
			(layer "B.Fab")
		)
		(fp_line
			(start 0.12065 -0.2794)
			(end -0.12065 -0.2794)
			(stroke
				(width 0.1)
				(type default)
			)
			(layer "B.Fab")
		)
		(fp_line
			(start 0.12065 -0.305054)
			(end 0.12065 -0.2794)
			(stroke
				(width 0.1)
				(type default)
			)
			(layer "B.Fab")
		)
		(fp_line
			(start -0.120396 0.3048)
			(end -0.120396 0.2794)
			(stroke
				(width 0.1)
				(type default)
			)
			(layer "B.Fab")
		)
		(fp_line
			(start -0.120396 0.2794)
			(end 0.12065 0.2794)
			(stroke
				(width 0.1)
				(type default)
			)
			(layer "B.Fab")
		)
		(fp_line
			(start -0.12065 -0.2794)
			(end -0.12065 -0.3048)
			(stroke
				(width 0.1)
				(type default)
			)
			(layer "B.Fab")
		)
		(fp_line
			(start -0.12065 -0.3048)
			(end -0.67945 -0.3048)
			(stroke
				(width 0.1)
				(type default)
			)
			(layer "B.Fab")
		)
		(fp_line
			(start -0.67945 0.3048)
			(end -0.120396 0.3048)
			(stroke
				(width 0.1)
				(type default)
			)
			(layer "B.Fab")
		)
		(fp_line
			(start -0.67945 -0.3048)
			(end -0.67945 0.3048)
			(stroke
				(width 0.1)
				(type default)
			)
			(layer "B.Fab")
		)
		(pad "1" smd circle
			(at 0.40005 0)
			(size 0 0)
			(layers "B.Cu" "B.Mask" "B.Paste")
			(net "P3V3_AUX")
		)
		(pad "2" smd circle
			(at -0.40005 0)
			(size 0 0)
			(layers "B.Cu" "B.Mask" "B.Paste")
			(net "PWRGD_PEX0_P1V8_PLL")
		)
	)
	(footprint ""
		(layer "B.Cu")
		(at 289.420046 -305.399948 -90)
		(property "Reference" "C3329"
			(at 0 0 90)
			(layer "B.SilkS")
			(hide yes)
			(effects
				(font
					(size 1.27 1.27)
				)
				(justify mirror)
			)
		)
		(property "Value" ""
			(at 0 0 90)
			(layer "B.Fab")
			(effects
				(font
					(size 1.27 1.27)
				)
				(justify mirror)
			)
		)
		(duplicate_pad_numbers_are_jumpers no)
		(fp_line
			(start -0.299974 0.150114)
			(end 0.299974 0.150114)
			(stroke
				(width 0.1)
				(type default)
			)
			(layer "B.Fab")
		)
		(fp_line
			(start 0.299974 0.150114)
			(end 0.299974 -0.150114)
			(stroke
				(width 0.1)
				(type default)
			)
			(layer "B.Fab")
		)
		(fp_line
			(start -0.299974 -0.150114)
			(end -0.299974 0.150114)
			(stroke
				(width 0.1)
				(type default)
			)
			(layer "B.Fab")
		)
		(fp_line
			(start 0.299974 -0.150114)
			(end -0.299974 -0.150114)
			(stroke
				(width 0.1)
				(type default)
			)
			(layer "B.Fab")
		)
		(pad "1" smd rect
			(at 0.2667 0 90)
			(size 0.3048 0.381)
			(layers "B.Cu" "B.Mask" "B.Paste")
			(net "P1V25_SERDES_VDDPLL_PEX2")
		)
		(pad "2" smd rect
			(at -0.2667 0 90)
			(size 0.3048 0.381)
			(layers "B.Cu" "B.Mask" "B.Paste")
			(net "GND")
		)
	)
	(footprint ""
		(layer "B.Cu")
		(at 409.897326 -110.497366)
		(property "Reference" "R390"
			(at 0 0 0)
			(layer "B.SilkS")
			(hide yes)
			(effects
				(font
					(size 1.27 1.27)
				)
				(justify mirror)
			)
		)
		(property "Value" ""
			(at 0 0 0)
			(layer "B.Fab")
			(effects
				(font
					(size 1.27 1.27)
				)
				(justify mirror)
			)
		)
		(duplicate_pad_numbers_are_jumpers no)
		(fp_line
			(start -0.7874 -0.4064)
			(end -0.7874 0.4064)
			(stroke
				(width 0.1524)
				(type default)
			)
			(layer "B.SilkS")
		)
		(fp_line
			(start -0.7874 0.4064)
			(end 0.7874 0.4064)
			(stroke
				(width 0.1524)
				(type default)
			)
			(layer "B.SilkS")
		)
		(fp_line
			(start 0.7874 -0.4064)
			(end -0.7874 -0.4064)
			(stroke
				(width 0.1524)
				(type default)
			)
			(layer "B.SilkS")
		)
		(fp_line
			(start 0.7874 0.4064)
			(end 0.7874 -0.4064)
			(stroke
				(width 0.1524)
				(type default)
			)
			(layer "B.SilkS")
		)
		(fp_line
			(start -0.67945 -0.3048)
			(end -0.67945 0.3048)
			(stroke
				(width 0.1)
				(type default)
			)
			(layer "B.Fab")
		)
		(fp_line
			(start -0.67945 0.3048)
			(end -0.120396 0.3048)
			(stroke
				(width 0.1)
				(type default)
			)
			(layer "B.Fab")
		)
		(fp_line
			(start -0.12065 -0.3048)
			(end -0.67945 -0.3048)
			(stroke
				(width 0.1)
				(type default)
			)
			(layer "B.Fab")
		)
		(fp_line
			(start -0.12065 -0.2794)
			(end -0.12065 -0.3048)
			(stroke
				(width 0.1)
				(type default)
			)
			(layer "B.Fab")
		)
		(fp_line
			(start -0.120396 0.2794)
			(end 0.12065 0.2794)
			(stroke
				(width 0.1)
				(type default)
			)
			(layer "B.Fab")
		)
		(fp_line
			(start -0.120396 0.3048)
			(end -0.120396 0.2794)
			(stroke
				(width 0.1)
				(type default)
			)
			(layer "B.Fab")
		)
		(fp_line
			(start 0.12065 -0.305054)
			(end 0.12065 -0.2794)
			(stroke
				(width 0.1)
				(type default)
			)
			(layer "B.Fab")
		)
		(fp_line
			(start 0.12065 -0.2794)
			(end -0.12065 -0.2794)
			(stroke
				(width 0.1)
				(type default)
			)
			(layer "B.Fab")
		)
		(fp_line
			(start 0.12065 0.2794)
			(end 0.12065 0.3048)
			(stroke
				(width 0.1)
				(type default)
			)
			(layer "B.Fab")
		)
		(fp_line
			(start 0.12065 0.3048)
			(end 0.67945 0.3048)
			(stroke
				(width 0.1)
				(type default)
			)
			(layer "B.Fab")
		)
		(fp_line
			(start 0.67945 -0.305054)
			(end 0.12065 -0.305054)
			(stroke
				(width 0.1)
				(type default)
			)
			(layer "B.Fab")
		)
		(fp_line
			(start 0.67945 0.3048)
			(end 0.67945 -0.305054)
			(stroke
				(width 0.1)
				(type default)
			)
			(layer "B.Fab")
		)
		(pad "1" smd circle
			(at 0.40005 0 180)
			(size 0 0)
			(layers "B.Cu" "B.Mask" "B.Paste")
			(net "NIC7_BIF2_N")
		)
		(pad "2" smd circle
			(at -0.40005 0 180)
			(size 0 0)
			(layers "B.Cu" "B.Mask" "B.Paste")
			(net "P3V3_AUX")
		)
	)
	(footprint ""
		(layer "B.Cu")
		(at 266.67968 -78.855316)
		(property "Reference" "L8"
			(at 0 0 0)
			(layer "B.SilkS")
			(hide yes)
			(effects
				(font
					(size 1.27 1.27)
				)
				(justify mirror)
			)
		)
		(property "Value" ""
			(at 0 0 0)
			(layer "B.Fab")
			(effects
				(font
					(size 1.27 1.27)
				)
				(justify mirror)
			)
		)
		(duplicate_pad_numbers_are_jumpers no)
		(fp_line
			(start -1.63576 -0.8128)
			(end -1.63576 0.8128)
			(stroke
				(width 0.1524)
				(type default)
			)
			(layer "B.SilkS")
		)
		(fp_line
			(start -1.63576 0.8128)
			(end 1.63576 0.8128)
			(stroke
				(width 0.1524)
				(type default)
			)
			(layer "B.SilkS")
		)
		(fp_line
			(start 1.63576 -0.8128)
			(end -1.63576 -0.8128)
			(stroke
				(width 0.1524)
				(type default)
			)
			(layer "B.SilkS")
		)
		(fp_line
			(start 1.63576 -0.8128)
			(end 1.63576 0.8128)
			(stroke
				(width 0.1524)
				(type default)
			)
			(layer "B.SilkS")
		)
		(fp_line
			(start -1.560576 -0.738632)
			(end 1.56083 -0.738632)
			(stroke
				(width 0.1)
				(type default)
			)
			(layer "B.Fab")
		)
		(fp_line
			(start -1.560576 0.7366)
			(end -1.560576 -0.738632)
			(stroke
				(width 0.1)
				(type default)
			)
			(layer "B.Fab")
		)
		(fp_line
			(start -1.524 0.7366)
			(end -1.560576 0.7366)
			(stroke
				(width 0.1)
				(type default)
			)
			(layer "B.Fab")
		)
		(fp_line
			(start 1.524 0.7366)
			(end -1.524 0.7366)
			(stroke
				(width 0.1)
				(type default)
			)
			(layer "B.Fab")
		)
		(fp_line
			(start 1.56083 -0.738632)
			(end 1.56083 0.7366)
			(stroke
				(width 0.1)
				(type default)
			)
			(layer "B.Fab")
		)
		(fp_line
			(start 1.56083 0.7366)
			(end 1.524 0.7366)
			(stroke
				(width 0.1)
				(type default)
			)
			(layer "B.Fab")
		)
		(pad "1" smd rect
			(at 0.94996 0)
			(size 1.1176 1.3716)
			(layers "B.Cu" "B.Mask" "B.Paste")
			(net "P3V3")
		)
		(pad "2" smd rect
			(at -0.94996 0)
			(size 1.1176 1.3716)
			(layers "B.Cu" "B.Mask" "B.Paste")
			(net "P3V3_CLK_GEN_VDD_CK440")
		)
	)
	(footprint ""
		(layer "B.Cu")
		(at 213.106 -194.183 -90)
		(property "Reference" "R6312"
			(at 0 0 90)
			(layer "B.SilkS")
			(hide yes)
			(effects
				(font
					(size 1.27 1.27)
				)
				(justify mirror)
			)
		)
		(property "Value" ""
			(at 0 0 90)
			(layer "B.Fab")
			(effects
				(font
					(size 1.27 1.27)
				)
				(justify mirror)
			)
		)
		(duplicate_pad_numbers_are_jumpers no)
		(fp_line
			(start -0.7874 0.4064)
			(end 0.7874 0.4064)
			(stroke
				(width 0.1524)
				(type default)
			)
			(layer "B.SilkS")
		)
		(fp_line
			(start 0.7874 0.4064)
			(end 0.7874 -0.4064)
			(stroke
				(width 0.1524)
				(type default)
			)
			(layer "B.SilkS")
		)
		(fp_line
			(start -0.7874 -0.4064)
			(end -0.7874 0.4064)
			(stroke
				(width 0.1524)
				(type default)
			)
			(layer "B.SilkS")
		)
		(fp_line
			(start 0.7874 -0.4064)
			(end -0.7874 -0.4064)
			(stroke
				(width 0.1524)
				(type default)
			)
			(layer "B.SilkS")
		)
		(fp_line
			(start -0.67945 0.3048)
			(end -0.120396 0.3048)
			(stroke
				(width 0.1)
				(type default)
			)
			(layer "B.Fab")
		)
		(fp_line
			(start -0.120396 0.3048)
			(end -0.120396 0.2794)
			(stroke
				(width 0.1)
				(type default)
			)
			(layer "B.Fab")
		)
		(fp_line
			(start 0.12065 0.3048)
			(end 0.67945 0.3048)
			(stroke
				(width 0.1)
				(type default)
			)
			(layer "B.Fab")
		)
		(fp_line
			(start 0.67945 0.3048)
			(end 0.67945 -0.305054)
			(stroke
				(width 0.1)
				(type default)
			)
			(layer "B.Fab")
		)
		(fp_line
			(start -0.120396 0.2794)
			(end 0.12065 0.2794)
			(stroke
				(width 0.1)
				(type default)
			)
			(layer "B.Fab")
		)
		(fp_line
			(start 0.12065 0.2794)
			(end 0.12065 0.3048)
			(stroke
				(width 0.1)
				(type default)
			)
			(layer "B.Fab")
		)
		(fp_line
			(start -0.12065 -0.2794)
			(end -0.12065 -0.3048)
			(stroke
				(width 0.1)
				(type default)
			)
			(layer "B.Fab")
		)
		(fp_line
			(start 0.12065 -0.2794)
			(end -0.12065 -0.2794)
			(stroke
				(width 0.1)
				(type default)
			)
			(layer "B.Fab")
		)
		(fp_line
			(start -0.67945 -0.3048)
			(end -0.67945 0.3048)
			(stroke
				(width 0.1)
				(type default)
			)
			(layer "B.Fab")
		)
		(fp_line
			(start -0.12065 -0.3048)
			(end -0.67945 -0.3048)
			(stroke
				(width 0.1)
				(type default)
			)
			(layer "B.Fab")
		)
		(fp_line
			(start 0.12065 -0.305054)
			(end 0.12065 -0.2794)
			(stroke
				(width 0.1)
				(type default)
			)
			(layer "B.Fab")
		)
		(fp_line
			(start 0.67945 -0.305054)
			(end 0.12065 -0.305054)
			(stroke
				(width 0.1)
				(type default)
			)
			(layer "B.Fab")
		)
		(pad "1" smd circle
			(at 0.40005 0 90)
			(size 0 0)
			(layers "B.Cu" "B.Mask" "B.Paste")
			(net "SMB_NIC7_LS_SDA")
		)
		(pad "2" smd circle
			(at -0.40005 0 90)
			(size 0 0)
			(layers "B.Cu" "B.Mask" "B.Paste")
			(net "SMB_NIC7_LS_R_SDA")
		)
	)
	(footprint ""
		(layer "B.Cu")
		(at 118.611142 -325.186294 -90)
		(property "Reference" "C4268"
			(at 0 0 90)
			(layer "B.SilkS")
			(hide yes)
			(effects
				(font
					(size 1.27 1.27)
				)
				(justify mirror)
			)
		)
		(property "Value" ""
			(at 0 0 90)
			(layer "B.Fab")
			(effects
				(font
					(size 1.27 1.27)
				)
				(justify mirror)
			)
		)
		(duplicate_pad_numbers_are_jumpers no)
		(fp_line
			(start -1.2954 0.5842)
			(end 1.2954 0.5842)
			(stroke
				(width 0.1524)
				(type default)
			)
			(layer "B.SilkS")
		)
		(fp_line
			(start 1.2954 0.5842)
			(end 1.2954 -0.5842)
			(stroke
				(width 0.1524)
				(type default)
			)
			(layer "B.SilkS")
		)
		(fp_line
			(start -1.2954 -0.5842)
			(end -1.2954 0.5842)
			(stroke
				(width 0.1524)
				(type default)
			)
			(layer "B.SilkS")
		)
		(fp_line
			(start 1.2954 -0.5842)
			(end -1.2954 -0.5842)
			(stroke
				(width 0.1524)
				(type default)
			)
			(layer "B.SilkS")
		)
		(fp_line
			(start -0.8636 0.4572)
			(end 0.8636 0.4572)
			(stroke
				(width 0.1)
				(type default)
			)
			(layer "B.Fab")
		)
		(fp_line
			(start 0.8636 0.4572)
			(end 0.8636 0.4064)
			(stroke
				(width 0.1)
				(type default)
			)
			(layer "B.Fab")
		)
		(fp_line
			(start -1.1938 0.4064)
			(end -0.8636 0.4064)
			(stroke
				(width 0.1)
				(type default)
			)
			(layer "B.Fab")
		)
		(fp_line
			(start -0.8636 0.4064)
			(end -0.8636 0.4572)
			(stroke
				(width 0.1)
				(type default)
			)
			(layer "B.Fab")
		)
		(fp_line
			(start 0.8636 0.4064)
			(end 1.1938 0.4064)
			(stroke
				(width 0.1)
				(type default)
			)
			(layer "B.Fab")
		)
		(fp_line
			(start 1.1938 0.4064)
			(end 1.1938 -0.4064)
			(stroke
				(width 0.1)
				(type default)
			)
			(layer "B.Fab")
		)
		(fp_line
			(start -1.1938 -0.4064)
			(end -1.1938 0.4064)
			(stroke
				(width 0.1)
				(type default)
			)
			(layer "B.Fab")
		)
		(fp_line
			(start -0.8636 -0.4064)
			(end -1.1938 -0.4064)
			(stroke
				(width 0.1)
				(type default)
			)
			(layer "B.Fab")
		)
		(fp_line
			(start 0.8636 -0.4064)
			(end 0.8636 -0.4572)
			(stroke
				(width 0.1)
				(type default)
			)
			(layer "B.Fab")
		)
		(fp_line
			(start 1.1938 -0.4064)
			(end 0.8636 -0.4064)
			(stroke
				(width 0.1)
				(type default)
			)
			(layer "B.Fab")
		)
		(fp_line
			(start -0.8636 -0.4572)
			(end -0.8636 -0.4064)
			(stroke
				(width 0.1)
				(type default)
			)
			(layer "B.Fab")
		)
		(fp_line
			(start 0.8636 -0.4572)
			(end -0.8636 -0.4572)
			(stroke
				(width 0.1)
				(type default)
			)
			(layer "B.Fab")
		)
		(pad "1" smd rect
			(at 0.7366 0 180)
			(size 0.7112 0.8128)
			(layers "B.Cu" "B.Mask" "B.Paste")
			(net "P0V8_SERDES_VDDA_PEX1_C6")
		)
		(pad "2" smd rect
			(at -0.7366 0 180)
			(size 0.7112 0.8128)
			(layers "B.Cu" "B.Mask" "B.Paste")
			(net "GND")
		)
	)
	(footprint ""
		(layer "B.Cu")
		(at 103.172006 -357.923084 90)
		(property "Reference" "R6377"
			(at 0 0 90)
			(layer "B.SilkS")
			(hide yes)
			(effects
				(font
					(size 1.27 1.27)
				)
				(justify mirror)
			)
		)
		(property "Value" ""
			(at 0 0 90)
			(layer "B.Fab")
			(effects
				(font
					(size 1.27 1.27)
				)
				(justify mirror)
			)
		)
		(duplicate_pad_numbers_are_jumpers no)
		(fp_line
			(start 0.7874 -0.4064)
			(end -0.7874 -0.4064)
			(stroke
				(width 0.1524)
				(type default)
			)
			(layer "B.SilkS")
		)
		(fp_line
			(start -0.7874 -0.4064)
			(end -0.7874 0.4064)
			(stroke
				(width 0.1524)
				(type default)
			)
			(layer "B.SilkS")
		)
		(fp_line
			(start 0.7874 0.4064)
			(end 0.7874 -0.4064)
			(stroke
				(width 0.1524)
				(type default)
			)
			(layer "B.SilkS")
		)
		(fp_line
			(start -0.7874 0.4064)
			(end 0.7874 0.4064)
			(stroke
				(width 0.1524)
				(type default)
			)
			(layer "B.SilkS")
		)
		(fp_line
			(start 0.67945 -0.305054)
			(end 0.12065 -0.305054)
			(stroke
				(width 0.1)
				(type default)
			)
			(layer "B.Fab")
		)
		(fp_line
			(start 0.12065 -0.305054)
			(end 0.12065 -0.2794)
			(stroke
				(width 0.1)
				(type default)
			)
			(layer "B.Fab")
		)
		(fp_line
			(start -0.12065 -0.3048)
			(end -0.67945 -0.3048)
			(stroke
				(width 0.1)
				(type default)
			)
			(layer "B.Fab")
		)
		(fp_line
			(start -0.67945 -0.3048)
			(end -0.67945 0.3048)
			(stroke
				(width 0.1)
				(type default)
			)
			(layer "B.Fab")
		)
		(fp_line
			(start 0.12065 -0.2794)
			(end -0.12065 -0.2794)
			(stroke
				(width 0.1)
				(type default)
			)
			(layer "B.Fab")
		)
		(fp_line
			(start -0.12065 -0.2794)
			(end -0.12065 -0.3048)
			(stroke
				(width 0.1)
				(type default)
			)
			(layer "B.Fab")
		)
		(fp_line
			(start 0.12065 0.2794)
			(end 0.12065 0.3048)
			(stroke
				(width 0.1)
				(type default)
			)
			(layer "B.Fab")
		)
		(fp_line
			(start -0.120396 0.2794)
			(end 0.12065 0.2794)
			(stroke
				(width 0.1)
				(type default)
			)
			(layer "B.Fab")
		)
		(fp_line
			(start 0.67945 0.3048)
			(end 0.67945 -0.305054)
			(stroke
				(width 0.1)
				(type default)
			)
			(layer "B.Fab")
		)
		(fp_line
			(start 0.12065 0.3048)
			(end 0.67945 0.3048)
			(stroke
				(width 0.1)
				(type default)
			)
			(layer "B.Fab")
		)
		(fp_line
			(start -0.120396 0.3048)
			(end -0.120396 0.2794)
			(stroke
				(width 0.1)
				(type default)
			)
			(layer "B.Fab")
		)
		(fp_line
			(start -0.67945 0.3048)
			(end -0.120396 0.3048)
			(stroke
				(width 0.1)
				(type default)
			)
			(layer "B.Fab")
		)
		(pad "1" smd circle
			(at 0.40005 0 270)
			(size 0 0)
			(layers "B.Cu" "B.Mask" "B.Paste")
			(net "CLK_100M_DB800ZL_PEX1_S3_R_DN")
		)
		(pad "2" smd circle
			(at -0.40005 0 270)
			(size 0 0)
			(layers "B.Cu" "B.Mask" "B.Paste")
			(net "CLK_100M_DB800ZL_PEX1_S3_DN")
		)
	)
	(footprint ""
		(layer "B.Cu")
		(at 113.514124 -328.43343)
		(property "Reference" "R1224"
			(at 0 0 0)
			(layer "B.SilkS")
			(hide yes)
			(effects
				(font
					(size 1.27 1.27)
				)
				(justify mirror)
			)
		)
		(property "Value" ""
			(at 0 0 0)
			(layer "B.Fab")
			(effects
				(font
					(size 1.27 1.27)
				)
				(justify mirror)
			)
		)
		(duplicate_pad_numbers_are_jumpers no)
		(fp_line
			(start -0.7874 -0.4064)
			(end -0.7874 0.4064)
			(stroke
				(width 0.1524)
				(type default)
			)
			(layer "B.SilkS")
		)
		(fp_line
			(start -0.7874 0.4064)
			(end 0.7874 0.4064)
			(stroke
				(width 0.1524)
				(type default)
			)
			(layer "B.SilkS")
		)
		(fp_line
			(start 0.7874 -0.4064)
			(end -0.7874 -0.4064)
			(stroke
				(width 0.1524)
				(type default)
			)
			(layer "B.SilkS")
		)
		(fp_line
			(start 0.7874 0.4064)
			(end 0.7874 -0.4064)
			(stroke
				(width 0.1524)
				(type default)
			)
			(layer "B.SilkS")
		)
		(fp_line
			(start -0.67945 -0.3048)
			(end -0.67945 0.3048)
			(stroke
				(width 0.1)
				(type default)
			)
			(layer "B.Fab")
		)
		(fp_line
			(start -0.67945 0.3048)
			(end -0.120396 0.3048)
			(stroke
				(width 0.1)
				(type default)
			)
			(layer "B.Fab")
		)
		(fp_line
			(start -0.12065 -0.3048)
			(end -0.67945 -0.3048)
			(stroke
				(width 0.1)
				(type default)
			)
			(layer "B.Fab")
		)
		(fp_line
			(start -0.12065 -0.2794)
			(end -0.12065 -0.3048)
			(stroke
				(width 0.1)
				(type default)
			)
			(layer "B.Fab")
		)
		(fp_line
			(start -0.120396 0.2794)
			(end 0.12065 0.2794)
			(stroke
				(width 0.1)
				(type default)
			)
			(layer "B.Fab")
		)
		(fp_line
			(start -0.120396 0.3048)
			(end -0.120396 0.2794)
			(stroke
				(width 0.1)
				(type default)
			)
			(layer "B.Fab")
		)
		(fp_line
			(start 0.12065 -0.305054)
			(end 0.12065 -0.2794)
			(stroke
				(width 0.1)
				(type default)
			)
			(layer "B.Fab")
		)
		(fp_line
			(start 0.12065 -0.2794)
			(end -0.12065 -0.2794)
			(stroke
				(width 0.1)
				(type default)
			)
			(layer "B.Fab")
		)
		(fp_line
			(start 0.12065 0.2794)
			(end 0.12065 0.3048)
			(stroke
				(width 0.1)
				(type default)
			)
			(layer "B.Fab")
		)
		(fp_line
			(start 0.12065 0.3048)
			(end 0.67945 0.3048)
			(stroke
				(width 0.1)
				(type default)
			)
			(layer "B.Fab")
		)
		(fp_line
			(start 0.67945 -0.305054)
			(end 0.12065 -0.305054)
			(stroke
				(width 0.1)
				(type default)
			)
			(layer "B.Fab")
		)
		(fp_line
			(start 0.67945 0.3048)
			(end 0.67945 -0.305054)
			(stroke
				(width 0.1)
				(type default)
			)
			(layer "B.Fab")
		)
		(pad "1" smd circle
			(at 0.40005 0 180)
			(size 0 0)
			(layers "B.Cu" "B.Mask" "B.Paste")
			(net "GND")
		)
		(pad "2" smd circle
			(at -0.40005 0 180)
			(size 0 0)
			(layers "B.Cu" "B.Mask" "B.Paste")
			(net "SMB_9ZXL0451E_ADDR0")
		)
	)
	(footprint ""
		(layer "B.Cu")
		(at 411.750002 -299.699934 -90)
		(property "Reference" "C2004"
			(at 0 0 90)
			(layer "B.SilkS")
			(hide yes)
			(effects
				(font
					(size 1.27 1.27)
				)
				(justify mirror)
			)
		)
		(property "Value" ""
			(at 0 0 90)
			(layer "B.Fab")
			(effects
				(font
					(size 1.27 1.27)
				)
				(justify mirror)
			)
		)
		(duplicate_pad_numbers_are_jumpers no)
		(fp_line
			(start -0.299974 0.150114)
			(end 0.299974 0.150114)
			(stroke
				(width 0.1)
				(type default)
			)
			(layer "B.Fab")
		)
		(fp_line
			(start 0.299974 0.150114)
			(end 0.299974 -0.150114)
			(stroke
				(width 0.1)
				(type default)
			)
			(layer "B.Fab")
		)
		(fp_line
			(start -0.299974 -0.150114)
			(end -0.299974 0.150114)
			(stroke
				(width 0.1)
				(type default)
			)
			(layer "B.Fab")
		)
		(fp_line
			(start 0.299974 -0.150114)
			(end -0.299974 -0.150114)
			(stroke
				(width 0.1)
				(type default)
			)
			(layer "B.Fab")
		)
		(pad "1" smd rect
			(at 0.2667 0 90)
			(size 0.3048 0.381)
			(layers "B.Cu" "B.Mask" "B.Paste")
			(net "P0V8_SERDES_VDDA_PEX3")
		)
		(pad "2" smd rect
			(at -0.2667 0 90)
			(size 0.3048 0.381)
			(layers "B.Cu" "B.Mask" "B.Paste")
			(net "GND")
		)
	)
	(footprint ""
		(layer "B.Cu")
		(at 134.93369 -308.67604 90)
		(property "Reference" "C4250"
			(at 0 0 90)
			(layer "B.SilkS")
			(hide yes)
			(effects
				(font
					(size 1.27 1.27)
				)
				(justify mirror)
			)
		)
		(property "Value" ""
			(at 0 0 90)
			(layer "B.Fab")
			(effects
				(font
					(size 1.27 1.27)
				)
				(justify mirror)
			)
		)
		(duplicate_pad_numbers_are_jumpers no)
		(fp_line
			(start 0.299974 -0.150114)
			(end -0.299974 -0.150114)
			(stroke
				(width 0.1)
				(type default)
			)
			(layer "B.Fab")
		)
		(fp_line
			(start -0.299974 -0.150114)
			(end -0.299974 0.150114)
			(stroke
				(width 0.1)
				(type default)
			)
			(layer "B.Fab")
		)
		(fp_line
			(start 0.299974 0.150114)
			(end 0.299974 -0.150114)
			(stroke
				(width 0.1)
				(type default)
			)
			(layer "B.Fab")
		)
		(fp_line
			(start -0.299974 0.150114)
			(end 0.299974 0.150114)
			(stroke
				(width 0.1)
				(type default)
			)
			(layer "B.Fab")
		)
		(pad "1" smd rect
			(at 0.2667 0 270)
			(size 0.3048 0.381)
			(layers "B.Cu" "B.Mask" "B.Paste")
			(net "P0V8_PEX1")
		)
		(pad "2" smd rect
			(at -0.2667 0 270)
			(size 0.3048 0.381)
			(layers "B.Cu" "B.Mask" "B.Paste")
			(net "GND")
		)
	)
	(footprint ""
		(layer "B.Cu")
		(at 278.554942 -295.2623)
		(property "Reference" "C3391"
			(at 0 0 0)
			(layer "B.SilkS")
			(hide yes)
			(effects
				(font
					(size 1.27 1.27)
				)
				(justify mirror)
			)
		)
		(property "Value" ""
			(at 0 0 0)
			(layer "B.Fab")
			(effects
				(font
					(size 1.27 1.27)
				)
				(justify mirror)
			)
		)
		(duplicate_pad_numbers_are_jumpers no)
		(fp_line
			(start -0.299974 -0.150114)
			(end -0.299974 0.150114)
			(stroke
				(width 0.1)
				(type default)
			)
			(layer "B.Fab")
		)
		(fp_line
			(start -0.299974 0.150114)
			(end 0.299974 0.150114)
			(stroke
				(width 0.1)
				(type default)
			)
			(layer "B.Fab")
		)
		(fp_line
			(start 0.299974 -0.150114)
			(end -0.299974 -0.150114)
			(stroke
				(width 0.1)
				(type default)
			)
			(layer "B.Fab")
		)
		(fp_line
			(start 0.299974 0.150114)
			(end 0.299974 -0.150114)
			(stroke
				(width 0.1)
				(type default)
			)
			(layer "B.Fab")
		)
		(pad "1" smd rect
			(at 0.2667 0 180)
			(size 0.3048 0.381)
			(layers "B.Cu" "B.Mask" "B.Paste")
			(net "PCEPLL4_VDDA18_PEX2")
		)
		(pad "2" smd rect
			(at -0.2667 0 180)
			(size 0.3048 0.381)
			(layers "B.Cu" "B.Mask" "B.Paste")
			(net "GND")
		)
	)
	(footprint ""
		(layer "B.Cu")
		(at 125.570488 -283.818584 90)
		(property "Reference" "PR107"
			(at 0 0 90)
			(layer "B.SilkS")
			(hide yes)
			(effects
				(font
					(size 1.27 1.27)
				)
				(justify mirror)
			)
		)
		(property "Value" ""
			(at 0 0 90)
			(layer "B.Fab")
			(effects
				(font
					(size 1.27 1.27)
				)
				(justify mirror)
			)
		)
		(duplicate_pad_numbers_are_jumpers no)
		(fp_line
			(start 0.7874 -0.4064)
			(end -0.7874 -0.4064)
			(stroke
				(width 0.1524)
				(type default)
			)
			(layer "B.SilkS")
		)
		(fp_line
			(start -0.7874 -0.4064)
			(end -0.7874 0.4064)
			(stroke
				(width 0.1524)
				(type default)
			)
			(layer "B.SilkS")
		)
		(fp_line
			(start 0.7874 0.4064)
			(end 0.7874 -0.4064)
			(stroke
				(width 0.1524)
				(type default)
			)
			(layer "B.SilkS")
		)
		(fp_line
			(start -0.7874 0.4064)
			(end 0.7874 0.4064)
			(stroke
				(width 0.1524)
				(type default)
			)
			(layer "B.SilkS")
		)
		(fp_line
			(start 0.67945 -0.305054)
			(end 0.12065 -0.305054)
			(stroke
				(width 0.1)
				(type default)
			)
			(layer "B.Fab")
		)
		(fp_line
			(start 0.12065 -0.305054)
			(end 0.12065 -0.2794)
			(stroke
				(width 0.1)
				(type default)
			)
			(layer "B.Fab")
		)
		(fp_line
			(start -0.12065 -0.3048)
			(end -0.67945 -0.3048)
			(stroke
				(width 0.1)
				(type default)
			)
			(layer "B.Fab")
		)
		(fp_line
			(start -0.67945 -0.3048)
			(end -0.67945 0.3048)
			(stroke
				(width 0.1)
				(type default)
			)
			(layer "B.Fab")
		)
		(fp_line
			(start 0.12065 -0.2794)
			(end -0.12065 -0.2794)
			(stroke
				(width 0.1)
				(type default)
			)
			(layer "B.Fab")
		)
		(fp_line
			(start -0.12065 -0.2794)
			(end -0.12065 -0.3048)
			(stroke
				(width 0.1)
				(type default)
			)
			(layer "B.Fab")
		)
		(fp_line
			(start 0.12065 0.2794)
			(end 0.12065 0.3048)
			(stroke
				(width 0.1)
				(type default)
			)
			(layer "B.Fab")
		)
		(fp_line
			(start -0.120396 0.2794)
			(end 0.12065 0.2794)
			(stroke
				(width 0.1)
				(type default)
			)
			(layer "B.Fab")
		)
		(fp_line
			(start 0.67945 0.3048)
			(end 0.67945 -0.305054)
			(stroke
				(width 0.1)
				(type default)
			)
			(layer "B.Fab")
		)
		(fp_line
			(start 0.12065 0.3048)
			(end 0.67945 0.3048)
			(stroke
				(width 0.1)
				(type default)
			)
			(layer "B.Fab")
		)
		(fp_line
			(start -0.120396 0.3048)
			(end -0.120396 0.2794)
			(stroke
				(width 0.1)
				(type default)
			)
			(layer "B.Fab")
		)
		(fp_line
			(start -0.67945 0.3048)
			(end -0.120396 0.3048)
			(stroke
				(width 0.1)
				(type default)
			)
			(layer "B.Fab")
		)
		(pad "1" smd circle
			(at 0.40005 0 270)
			(size 0 0)
			(layers "B.Cu" "B.Mask" "B.Paste")
			(net "P0V8_PEX1_PVCC")
		)
		(pad "2" smd circle
			(at -0.40005 0 270)
			(size 0 0)
			(layers "B.Cu" "B.Mask" "B.Paste")
			(net "P0V8_PEX1_VCC1")
		)
	)
	(footprint ""
		(layer "B.Cu")
		(at 288.049716 -299.699934 -90)
		(property "Reference" "C1729"
			(at 0 0 90)
			(layer "B.SilkS")
			(hide yes)
			(effects
				(font
					(size 1.27 1.27)
				)
				(justify mirror)
			)
		)
		(property "Value" ""
			(at 0 0 90)
			(layer "B.Fab")
			(effects
				(font
					(size 1.27 1.27)
				)
				(justify mirror)
			)
		)
		(duplicate_pad_numbers_are_jumpers no)
		(fp_line
			(start -0.299974 0.150114)
			(end 0.299974 0.150114)
			(stroke
				(width 0.1)
				(type default)
			)
			(layer "B.Fab")
		)
		(fp_line
			(start 0.299974 0.150114)
			(end 0.299974 -0.150114)
			(stroke
				(width 0.1)
				(type default)
			)
			(layer "B.Fab")
		)
		(fp_line
			(start -0.299974 -0.150114)
			(end -0.299974 0.150114)
			(stroke
				(width 0.1)
				(type default)
			)
			(layer "B.Fab")
		)
		(fp_line
			(start 0.299974 -0.150114)
			(end -0.299974 -0.150114)
			(stroke
				(width 0.1)
				(type default)
			)
			(layer "B.Fab")
		)
		(pad "1" smd rect
			(at 0.2667 0 90)
			(size 0.3048 0.381)
			(layers "B.Cu" "B.Mask" "B.Paste")
			(net "P0V8_SERDES_VDDA_PEX2")
		)
		(pad "2" smd rect
			(at -0.2667 0 90)
			(size 0.3048 0.381)
			(layers "B.Cu" "B.Mask" "B.Paste")
			(net "GND")
		)
	)
	(footprint ""
		(layer "B.Cu")
		(at 118.456964 -318.542416)
		(property "Reference" "C4253"
			(at 0 0 0)
			(layer "B.SilkS")
			(hide yes)
			(effects
				(font
					(size 1.27 1.27)
				)
				(justify mirror)
			)
		)
		(property "Value" ""
			(at 0 0 0)
			(layer "B.Fab")
			(effects
				(font
					(size 1.27 1.27)
				)
				(justify mirror)
			)
		)
		(duplicate_pad_numbers_are_jumpers no)
		(fp_line
			(start -0.299974 -0.150114)
			(end -0.299974 0.150114)
			(stroke
				(width 0.1)
				(type default)
			)
			(layer "B.Fab")
		)
		(fp_line
			(start -0.299974 0.150114)
			(end 0.299974 0.150114)
			(stroke
				(width 0.1)
				(type default)
			)
			(layer "B.Fab")
		)
		(fp_line
			(start 0.299974 -0.150114)
			(end -0.299974 -0.150114)
			(stroke
				(width 0.1)
				(type default)
			)
			(layer "B.Fab")
		)
		(fp_line
			(start 0.299974 0.150114)
			(end 0.299974 -0.150114)
			(stroke
				(width 0.1)
				(type default)
			)
			(layer "B.Fab")
		)
		(pad "1" smd rect
			(at 0.2667 0 180)
			(size 0.3048 0.381)
			(layers "B.Cu" "B.Mask" "B.Paste")
			(net "P0V8_SERDES_VDDA_PEX1")
		)
		(pad "2" smd rect
			(at -0.2667 0 180)
			(size 0.3048 0.381)
			(layers "B.Cu" "B.Mask" "B.Paste")
			(net "GND")
		)
	)
	(footprint ""
		(layer "B.Cu")
		(at 342.894158 -217.187018 -90)
		(property "Reference" "C2060"
			(at 0 0 90)
			(layer "B.SilkS")
			(hide yes)
			(effects
				(font
					(size 1.27 1.27)
				)
				(justify mirror)
			)
		)
		(property "Value" ""
			(at 0 0 90)
			(layer "B.Fab")
			(effects
				(font
					(size 1.27 1.27)
				)
				(justify mirror)
			)
		)
		(duplicate_pad_numbers_are_jumpers no)
		(fp_line
			(start -0.69215 0.2921)
			(end 0.69215 0.2921)
			(stroke
				(width 0.1524)
				(type default)
			)
			(layer "B.SilkS")
		)
		(fp_line
			(start 0.69215 0.2921)
			(end 0.69215 -0.2921)
			(stroke
				(width 0.1524)
				(type default)
			)
			(layer "B.SilkS")
		)
		(fp_line
			(start -0.69215 -0.2921)
			(end -0.69215 0.2921)
			(stroke
				(width 0.1524)
				(type default)
			)
			(layer "B.SilkS")
		)
		(fp_line
			(start 0.69215 -0.2921)
			(end -0.69215 -0.2921)
			(stroke
				(width 0.1524)
				(type default)
			)
			(layer "B.SilkS")
		)
		(fp_line
			(start -0.51435 0.2794)
			(end 0.51435 0.2794)
			(stroke
				(width 0.1)
				(type default)
			)
			(layer "B.Fab")
		)
		(fp_line
			(start 0.51435 0.2794)
			(end 0.51435 -0.2794)
			(stroke
				(width 0.1)
				(type default)
			)
			(layer "B.Fab")
		)
		(fp_line
			(start -0.51435 -0.2794)
			(end -0.51435 0.2794)
			(stroke
				(width 0.1)
				(type default)
			)
			(layer "B.Fab")
		)
		(fp_line
			(start 0.51435 -0.2794)
			(end -0.51435 -0.2794)
			(stroke
				(width 0.1)
				(type default)
			)
			(layer "B.Fab")
		)
		(pad "1" smd circle
			(at 0.40005 0 90)
			(size 0 0)
			(layers "B.Cu" "B.Mask" "B.Paste")
			(net "P3V3_FPGA_VCCIO2")
		)
		(pad "2" smd circle
			(at -0.40005 0 90)
			(size 0 0)
			(layers "B.Cu" "B.Mask" "B.Paste")
			(net "GND")
		)
		(zone
			(layer "B.Cu")
			(hatch none 0.5)
			(connect_pads
				(clearance 0)
			)
			(min_thickness 0.25)
			(keepout
				(tracks not_allowed)
				(vias allowed)
				(pads allowed)
				(copperpour not_allowed)
				(footprints allowed)
			)
			(placement
				(enabled no)
				(sheetname "")
			)
			(fill
				(thermal_gap 0.5)
				(thermal_bridge_width 0.5)
				(island_removal_mode 0)
			)
			(polygon
				(pts
					(xy 342.806528 -216.996518) (xy 342.748362 -217.087958) (xy 342.748362 -217.287348) (xy 342.806528 -217.377518)
					(xy 342.981788 -217.377518) (xy 343.040208 -217.287348) (xy 343.040208 -217.087958) (xy 342.982042 -216.996518)
				)
			)
		)
	)
	(footprint ""
		(layer "B.Cu")
		(at 386.842 -243.205 -90)
		(property "Reference" "U102"
			(at -0.005334 1.827276 270)
			(unlocked yes)
			(layer "B.SilkS")
			(effects
				(font
					(size 0.7874 0.5842)
					(thickness 0.1524)
				)
				(justify mirror)
			)
		)
		(property "Value" ""
			(at 0 0 90)
			(layer "B.Fab")
			(effects
				(font
					(size 1.27 1.27)
				)
				(justify mirror)
			)
		)
		(duplicate_pad_numbers_are_jumpers no)
		(fp_line
			(start -1.7272 1.1176)
			(end 1.7272 1.1176)
			(stroke
				(width 0.1524)
				(type default)
			)
			(layer "B.SilkS")
		)
		(fp_line
			(start 1.7272 1.1176)
			(end 1.7272 -1.1176)
			(stroke
				(width 0.1524)
				(type default)
			)
			(layer "B.SilkS")
		)
		(fp_line
			(start 0 -0.7366)
			(end 0.254 -1.1176)
			(stroke
				(width 0.1524)
				(type default)
			)
			(layer "B.SilkS")
		)
		(fp_line
			(start -1.7272 -1.1176)
			(end -1.7272 1.1176)
			(stroke
				(width 0.1524)
				(type default)
			)
			(layer "B.SilkS")
		)
		(fp_line
			(start -1.7272 -1.1176)
			(end -0.254 -1.1176)
			(stroke
				(width 0.1524)
				(type default)
			)
			(layer "B.SilkS")
		)
		(fp_line
			(start -0.254 -1.1176)
			(end 0 -0.7366)
			(stroke
				(width 0.1524)
				(type default)
			)
			(layer "B.SilkS")
		)
		(fp_line
			(start 0.254 -1.1176)
			(end 1.7272 -1.1176)
			(stroke
				(width 0.1524)
				(type default)
			)
			(layer "B.SilkS")
		)
		(fp_poly
			(pts
				(xy 1.9558 -0.649986) (xy 2.7178 -0.268986) (xy 2.7178 -1.030986)
			)
			(stroke
				(width 0)
				(type default)
			)
			(fill yes)
			(layer "B.SilkS")
		)
		(fp_line
			(start -1.5748 1.1176)
			(end -1.5748 -1.1176)
			(stroke
				(width 0.1)
				(type default)
			)
			(layer "B.Fab")
		)
		(fp_line
			(start 1.5748 1.1176)
			(end -1.5748 1.1176)
			(stroke
				(width 0.1)
				(type default)
			)
			(layer "B.Fab")
		)
		(fp_line
			(start -1.5748 -1.1176)
			(end 1.5748 -1.1176)
			(stroke
				(width 0.1)
				(type default)
			)
			(layer "B.Fab")
		)
		(fp_line
			(start 1.5748 -1.1176)
			(end 1.5748 1.1176)
			(stroke
				(width 0.1)
				(type default)
			)
			(layer "B.Fab")
		)
		(fp_poly
			(pts
				(xy 1.9558 -0.649986) (xy 2.7178 -0.268986) (xy 2.7178 -1.030986)
			)
			(stroke
				(width 0)
				(type default)
			)
			(fill yes)
			(layer "B.Fab")
		)
		(pad "1" smd rect
			(at 0.999998 -0.649986 180)
			(size 0.3556 1.1176)
			(layers "B.Cu" "B.Mask" "B.Paste")
			(net "UART_PEX2_SDB_R_RX")
		)
		(pad "2" smd rect
			(at 0.999998 0 180)
			(size 0.3556 1.1176)
			(layers "B.Cu" "B.Mask" "B.Paste")
			(net "GND")
		)
		(pad "3" smd rect
			(at 0.999998 0.649986 180)
			(size 0.3556 1.1176)
			(layers "B.Cu" "B.Mask" "B.Paste")
			(net "UART_PEX3_SDB_R_RX")
		)
		(pad "4" smd rect
			(at -0.999998 0.649986 180)
			(size 0.3556 1.1176)
			(layers "B.Cu" "B.Mask" "B.Paste")
			(net "UART_PEX3_SDB_BUF_R_RX")
		)
		(pad "5" smd rect
			(at -0.999998 0 180)
			(size 0.3556 1.1176)
			(layers "B.Cu" "B.Mask" "B.Paste")
			(net "P3V3_AUX")
		)
		(pad "6" smd rect
			(at -0.999998 -0.649986 180)
			(size 0.3556 1.1176)
			(layers "B.Cu" "B.Mask" "B.Paste")
			(net "UART_PEX2_SDB_BUF_R_RX")
		)
	)
	(footprint ""
		(layer "B.Cu")
		(at 133.538214 -208.952846 90)
		(property "Reference" "C2603"
			(at 0 0 90)
			(layer "B.SilkS")
			(hide yes)
			(effects
				(font
					(size 1.27 1.27)
				)
				(justify mirror)
			)
		)
		(property "Value" ""
			(at 0 0 90)
			(layer "B.Fab")
			(effects
				(font
					(size 1.27 1.27)
				)
				(justify mirror)
			)
		)
		(duplicate_pad_numbers_are_jumpers no)
		(fp_line
			(start 0.7874 -0.4064)
			(end -0.7874 -0.4064)
			(stroke
				(width 0.1524)
				(type default)
			)
			(layer "B.SilkS")
		)
		(fp_line
			(start -0.7874 -0.4064)
			(end -0.7874 0.4064)
			(stroke
				(width 0.1524)
				(type default)
			)
			(layer "B.SilkS")
		)
		(fp_line
			(start 0.7874 0.4064)
			(end 0.7874 -0.4064)
			(stroke
				(width 0.1524)
				(type default)
			)
			(layer "B.SilkS")
		)
		(fp_line
			(start -0.7874 0.4064)
			(end 0.7874 0.4064)
			(stroke
				(width 0.1524)
				(type default)
			)
			(layer "B.SilkS")
		)
		(fp_line
			(start 0.67945 -0.305054)
			(end 0.12065 -0.305054)
			(stroke
				(width 0.1)
				(type default)
			)
			(layer "B.Fab")
		)
		(fp_line
			(start 0.12065 -0.305054)
			(end 0.12065 -0.2794)
			(stroke
				(width 0.1)
				(type default)
			)
			(layer "B.Fab")
		)
		(fp_line
			(start -0.12065 -0.3048)
			(end -0.67945 -0.3048)
			(stroke
				(width 0.1)
				(type default)
			)
			(layer "B.Fab")
		)
		(fp_line
			(start -0.67945 -0.3048)
			(end -0.67945 0.3048)
			(stroke
				(width 0.1)
				(type default)
			)
			(layer "B.Fab")
		)
		(fp_line
			(start 0.12065 -0.2794)
			(end -0.12065 -0.2794)
			(stroke
				(width 0.1)
				(type default)
			)
			(layer "B.Fab")
		)
		(fp_line
			(start -0.12065 -0.2794)
			(end -0.12065 -0.3048)
			(stroke
				(width 0.1)
				(type default)
			)
			(layer "B.Fab")
		)
		(fp_line
			(start 0.12065 0.2794)
			(end 0.12065 0.3048)
			(stroke
				(width 0.1)
				(type default)
			)
			(layer "B.Fab")
		)
		(fp_line
			(start -0.120396 0.2794)
			(end 0.12065 0.2794)
			(stroke
				(width 0.1)
				(type default)
			)
			(layer "B.Fab")
		)
		(fp_line
			(start 0.67945 0.3048)
			(end 0.67945 -0.305054)
			(stroke
				(width 0.1)
				(type default)
			)
			(layer "B.Fab")
		)
		(fp_line
			(start 0.12065 0.3048)
			(end 0.67945 0.3048)
			(stroke
				(width 0.1)
				(type default)
			)
			(layer "B.Fab")
		)
		(fp_line
			(start -0.120396 0.3048)
			(end -0.120396 0.2794)
			(stroke
				(width 0.1)
				(type default)
			)
			(layer "B.Fab")
		)
		(fp_line
			(start -0.67945 0.3048)
			(end -0.120396 0.3048)
			(stroke
				(width 0.1)
				(type default)
			)
			(layer "B.Fab")
		)
		(pad "1" smd circle
			(at 0.40005 0 270)
			(size 0 0)
			(layers "B.Cu" "B.Mask" "B.Paste")
			(net "P3V3_AUX")
		)
		(pad "2" smd circle
			(at -0.40005 0 270)
			(size 0 0)
			(layers "B.Cu" "B.Mask" "B.Paste")
			(net "GND")
		)
	)
	(footprint ""
		(layer "B.Cu")
		(at 278.064214 -142.795752 180)
		(property "Reference" "C907"
			(at 0 0 0)
			(layer "B.SilkS")
			(hide yes)
			(effects
				(font
					(size 1.27 1.27)
				)
				(justify mirror)
			)
		)
		(property "Value" ""
			(at 0 0 0)
			(layer "B.Fab")
			(effects
				(font
					(size 1.27 1.27)
				)
				(justify mirror)
			)
		)
		(duplicate_pad_numbers_are_jumpers no)
		(fp_line
			(start 0.299974 0.150114)
			(end 0.299974 -0.150114)
			(stroke
				(width 0.1)
				(type default)
			)
			(layer "B.Fab")
		)
		(fp_line
			(start 0.299974 -0.150114)
			(end -0.299974 -0.150114)
			(stroke
				(width 0.1)
				(type default)
			)
			(layer "B.Fab")
		)
		(fp_line
			(start -0.299974 0.150114)
			(end 0.299974 0.150114)
			(stroke
				(width 0.1)
				(type default)
			)
			(layer "B.Fab")
		)
		(fp_line
			(start -0.299974 -0.150114)
			(end -0.299974 0.150114)
			(stroke
				(width 0.1)
				(type default)
			)
			(layer "B.Fab")
		)
		(pad "1" smd rect
			(at 0.2667 0)
			(size 0.3048 0.381)
			(layers "B.Cu" "B.Mask" "B.Paste")
			(net "P12V_NIC4")
		)
		(pad "2" smd rect
			(at -0.2667 0)
			(size 0.3048 0.381)
			(layers "B.Cu" "B.Mask" "B.Paste")
			(net "GND")
		)
	)
	(footprint ""
		(layer "B.Cu")
		(at 170.999912 -301.599854 -90)
		(property "Reference" "C1466"
			(at 0 0 90)
			(layer "B.SilkS")
			(hide yes)
			(effects
				(font
					(size 1.27 1.27)
				)
				(justify mirror)
			)
		)
		(property "Value" ""
			(at 0 0 90)
			(layer "B.Fab")
			(effects
				(font
					(size 1.27 1.27)
				)
				(justify mirror)
			)
		)
		(duplicate_pad_numbers_are_jumpers no)
		(fp_line
			(start -0.299974 0.150114)
			(end 0.299974 0.150114)
			(stroke
				(width 0.1)
				(type default)
			)
			(layer "B.Fab")
		)
		(fp_line
			(start 0.299974 0.150114)
			(end 0.299974 -0.150114)
			(stroke
				(width 0.1)
				(type default)
			)
			(layer "B.Fab")
		)
		(fp_line
			(start -0.299974 -0.150114)
			(end -0.299974 0.150114)
			(stroke
				(width 0.1)
				(type default)
			)
			(layer "B.Fab")
		)
		(fp_line
			(start 0.299974 -0.150114)
			(end -0.299974 -0.150114)
			(stroke
				(width 0.1)
				(type default)
			)
			(layer "B.Fab")
		)
		(pad "1" smd rect
			(at 0.2667 0 90)
			(size 0.3048 0.381)
			(layers "B.Cu" "B.Mask" "B.Paste")
			(net "P0V8_SERDES_VDDA_PEX1")
		)
		(pad "2" smd rect
			(at -0.2667 0 90)
			(size 0.3048 0.381)
			(layers "B.Cu" "B.Mask" "B.Paste")
			(net "GND")
		)
	)
	(footprint ""
		(layer "B.Cu")
		(at 56.799988 -301.599854 -90)
		(property "Reference" "C1198"
			(at 0 0 90)
			(layer "B.SilkS")
			(hide yes)
			(effects
				(font
					(size 1.27 1.27)
				)
				(justify mirror)
			)
		)
		(property "Value" ""
			(at 0 0 90)
			(layer "B.Fab")
			(effects
				(font
					(size 1.27 1.27)
				)
				(justify mirror)
			)
		)
		(duplicate_pad_numbers_are_jumpers no)
		(fp_line
			(start -0.299974 0.150114)
			(end 0.299974 0.150114)
			(stroke
				(width 0.1)
				(type default)
			)
			(layer "B.Fab")
		)
		(fp_line
			(start 0.299974 0.150114)
			(end 0.299974 -0.150114)
			(stroke
				(width 0.1)
				(type default)
			)
			(layer "B.Fab")
		)
		(fp_line
			(start -0.299974 -0.150114)
			(end -0.299974 0.150114)
			(stroke
				(width 0.1)
				(type default)
			)
			(layer "B.Fab")
		)
		(fp_line
			(start 0.299974 -0.150114)
			(end -0.299974 -0.150114)
			(stroke
				(width 0.1)
				(type default)
			)
			(layer "B.Fab")
		)
		(pad "1" smd rect
			(at 0.2667 0 90)
			(size 0.3048 0.381)
			(layers "B.Cu" "B.Mask" "B.Paste")
			(net "P0V8_SERDES_VDDA_PEX0")
		)
		(pad "2" smd rect
			(at -0.2667 0 90)
			(size 0.3048 0.381)
			(layers "B.Cu" "B.Mask" "B.Paste")
			(net "GND")
		)
	)
	(footprint ""
		(layer "B.Cu")
		(at 366.439196 -282.040584 90)
		(property "Reference" "PR162"
			(at 0 0 90)
			(layer "B.SilkS")
			(hide yes)
			(effects
				(font
					(size 1.27 1.27)
				)
				(justify mirror)
			)
		)
		(property "Value" ""
			(at 0 0 90)
			(layer "B.Fab")
			(effects
				(font
					(size 1.27 1.27)
				)
				(justify mirror)
			)
		)
		(duplicate_pad_numbers_are_jumpers no)
		(fp_line
			(start 0.7874 -0.4064)
			(end -0.7874 -0.4064)
			(stroke
				(width 0.1524)
				(type default)
			)
			(layer "B.SilkS")
		)
		(fp_line
			(start -0.7874 -0.4064)
			(end -0.7874 0.4064)
			(stroke
				(width 0.1524)
				(type default)
			)
			(layer "B.SilkS")
		)
		(fp_line
			(start 0.7874 0.4064)
			(end 0.7874 -0.4064)
			(stroke
				(width 0.1524)
				(type default)
			)
			(layer "B.SilkS")
		)
		(fp_line
			(start -0.7874 0.4064)
			(end 0.7874 0.4064)
			(stroke
				(width 0.1524)
				(type default)
			)
			(layer "B.SilkS")
		)
		(fp_line
			(start 0.67945 -0.305054)
			(end 0.12065 -0.305054)
			(stroke
				(width 0.1)
				(type default)
			)
			(layer "B.Fab")
		)
		(fp_line
			(start 0.12065 -0.305054)
			(end 0.12065 -0.2794)
			(stroke
				(width 0.1)
				(type default)
			)
			(layer "B.Fab")
		)
		(fp_line
			(start -0.12065 -0.3048)
			(end -0.67945 -0.3048)
			(stroke
				(width 0.1)
				(type default)
			)
			(layer "B.Fab")
		)
		(fp_line
			(start -0.67945 -0.3048)
			(end -0.67945 0.3048)
			(stroke
				(width 0.1)
				(type default)
			)
			(layer "B.Fab")
		)
		(fp_line
			(start 0.12065 -0.2794)
			(end -0.12065 -0.2794)
			(stroke
				(width 0.1)
				(type default)
			)
			(layer "B.Fab")
		)
		(fp_line
			(start -0.12065 -0.2794)
			(end -0.12065 -0.3048)
			(stroke
				(width 0.1)
				(type default)
			)
			(layer "B.Fab")
		)
		(fp_line
			(start 0.12065 0.2794)
			(end 0.12065 0.3048)
			(stroke
				(width 0.1)
				(type default)
			)
			(layer "B.Fab")
		)
		(fp_line
			(start -0.120396 0.2794)
			(end 0.12065 0.2794)
			(stroke
				(width 0.1)
				(type default)
			)
			(layer "B.Fab")
		)
		(fp_line
			(start 0.67945 0.3048)
			(end 0.67945 -0.305054)
			(stroke
				(width 0.1)
				(type default)
			)
			(layer "B.Fab")
		)
		(fp_line
			(start 0.12065 0.3048)
			(end 0.67945 0.3048)
			(stroke
				(width 0.1)
				(type default)
			)
			(layer "B.Fab")
		)
		(fp_line
			(start -0.120396 0.3048)
			(end -0.120396 0.2794)
			(stroke
				(width 0.1)
				(type default)
			)
			(layer "B.Fab")
		)
		(fp_line
			(start -0.67945 0.3048)
			(end -0.120396 0.3048)
			(stroke
				(width 0.1)
				(type default)
			)
			(layer "B.Fab")
		)
		(pad "1" smd circle
			(at 0.40005 0 270)
			(size 0 0)
			(layers "B.Cu" "B.Mask" "B.Paste")
			(net "SW_P0V8_PEX3_VOS2")
		)
		(pad "2" smd circle
			(at -0.40005 0 270)
			(size 0 0)
			(layers "B.Cu" "B.Mask" "B.Paste")
			(net "P0V8_PEX3")
		)
	)
	(footprint ""
		(layer "B.Cu")
		(at 294.380158 -295.221914)
		(property "Reference" "C1612"
			(at 0 0 0)
			(layer "B.SilkS")
			(hide yes)
			(effects
				(font
					(size 1.27 1.27)
				)
				(justify mirror)
			)
		)
		(property "Value" ""
			(at 0 0 0)
			(layer "B.Fab")
			(effects
				(font
					(size 1.27 1.27)
				)
				(justify mirror)
			)
		)
		(duplicate_pad_numbers_are_jumpers no)
		(fp_line
			(start -1.2954 -0.5842)
			(end -1.2954 0.5842)
			(stroke
				(width 0.1524)
				(type default)
			)
			(layer "B.SilkS")
		)
		(fp_line
			(start -1.2954 0.5842)
			(end 1.2954 0.5842)
			(stroke
				(width 0.1524)
				(type default)
			)
			(layer "B.SilkS")
		)
		(fp_line
			(start 1.2954 -0.5842)
			(end -1.2954 -0.5842)
			(stroke
				(width 0.1524)
				(type default)
			)
			(layer "B.SilkS")
		)
		(fp_line
			(start 1.2954 0.5842)
			(end 1.2954 -0.5842)
			(stroke
				(width 0.1524)
				(type default)
			)
			(layer "B.SilkS")
		)
		(fp_line
			(start -1.1938 -0.4064)
			(end -1.1938 0.4064)
			(stroke
				(width 0.1)
				(type default)
			)
			(layer "B.Fab")
		)
		(fp_line
			(start -1.1938 0.4064)
			(end -0.8636 0.4064)
			(stroke
				(width 0.1)
				(type default)
			)
			(layer "B.Fab")
		)
		(fp_line
			(start -0.8636 -0.4572)
			(end -0.8636 -0.4064)
			(stroke
				(width 0.1)
				(type default)
			)
			(layer "B.Fab")
		)
		(fp_line
			(start -0.8636 -0.4064)
			(end -1.1938 -0.4064)
			(stroke
				(width 0.1)
				(type default)
			)
			(layer "B.Fab")
		)
		(fp_line
			(start -0.8636 0.4064)
			(end -0.8636 0.4572)
			(stroke
				(width 0.1)
				(type default)
			)
			(layer "B.Fab")
		)
		(fp_line
			(start -0.8636 0.4572)
			(end 0.8636 0.4572)
			(stroke
				(width 0.1)
				(type default)
			)
			(layer "B.Fab")
		)
		(fp_line
			(start 0.8636 -0.4572)
			(end -0.8636 -0.4572)
			(stroke
				(width 0.1)
				(type default)
			)
			(layer "B.Fab")
		)
		(fp_line
			(start 0.8636 -0.4064)
			(end 0.8636 -0.4572)
			(stroke
				(width 0.1)
				(type default)
			)
			(layer "B.Fab")
		)
		(fp_line
			(start 0.8636 0.4064)
			(end 1.1938 0.4064)
			(stroke
				(width 0.1)
				(type default)
			)
			(layer "B.Fab")
		)
		(fp_line
			(start 0.8636 0.4572)
			(end 0.8636 0.4064)
			(stroke
				(width 0.1)
				(type default)
			)
			(layer "B.Fab")
		)
		(fp_line
			(start 1.1938 -0.4064)
			(end 0.8636 -0.4064)
			(stroke
				(width 0.1)
				(type default)
			)
			(layer "B.Fab")
		)
		(fp_line
			(start 1.1938 0.4064)
			(end 1.1938 -0.4064)
			(stroke
				(width 0.1)
				(type default)
			)
			(layer "B.Fab")
		)
		(pad "1" smd rect
			(at 0.7366 0 270)
			(size 0.7112 0.8128)
			(layers "B.Cu" "B.Mask" "B.Paste")
			(net "P0V8_PEX2")
		)
		(pad "2" smd rect
			(at -0.7366 0 270)
			(size 0.7112 0.8128)
			(layers "B.Cu" "B.Mask" "B.Paste")
			(net "GND")
		)
	)
	(footprint ""
		(layer "B.Cu")
		(at 77.541882 -99.037648 180)
		(property "Reference" "R65"
			(at 0 0 0)
			(layer "B.SilkS")
			(hide yes)
			(effects
				(font
					(size 1.27 1.27)
				)
				(justify mirror)
			)
		)
		(property "Value" ""
			(at 0 0 0)
			(layer "B.Fab")
			(effects
				(font
					(size 1.27 1.27)
				)
				(justify mirror)
			)
		)
		(duplicate_pad_numbers_are_jumpers no)
		(fp_line
			(start 0.7874 0.4064)
			(end 0.7874 -0.4064)
			(stroke
				(width 0.1524)
				(type default)
			)
			(layer "B.SilkS")
		)
		(fp_line
			(start 0.7874 -0.4064)
			(end -0.7874 -0.4064)
			(stroke
				(width 0.1524)
				(type default)
			)
			(layer "B.SilkS")
		)
		(fp_line
			(start -0.7874 0.4064)
			(end 0.7874 0.4064)
			(stroke
				(width 0.1524)
				(type default)
			)
			(layer "B.SilkS")
		)
		(fp_line
			(start -0.7874 -0.4064)
			(end -0.7874 0.4064)
			(stroke
				(width 0.1524)
				(type default)
			)
			(layer "B.SilkS")
		)
		(fp_line
			(start 0.67945 0.3048)
			(end 0.67945 -0.305054)
			(stroke
				(width 0.1)
				(type default)
			)
			(layer "B.Fab")
		)
		(fp_line
			(start 0.67945 -0.305054)
			(end 0.12065 -0.305054)
			(stroke
				(width 0.1)
				(type default)
			)
			(layer "B.Fab")
		)
		(fp_line
			(start 0.12065 0.3048)
			(end 0.67945 0.3048)
			(stroke
				(width 0.1)
				(type default)
			)
			(layer "B.Fab")
		)
		(fp_line
			(start 0.12065 0.2794)
			(end 0.12065 0.3048)
			(stroke
				(width 0.1)
				(type default)
			)
			(layer "B.Fab")
		)
		(fp_line
			(start 0.12065 -0.2794)
			(end -0.12065 -0.2794)
			(stroke
				(width 0.1)
				(type default)
			)
			(layer "B.Fab")
		)
		(fp_line
			(start 0.12065 -0.305054)
			(end 0.12065 -0.2794)
			(stroke
				(width 0.1)
				(type default)
			)
			(layer "B.Fab")
		)
		(fp_line
			(start -0.120396 0.3048)
			(end -0.120396 0.2794)
			(stroke
				(width 0.1)
				(type default)
			)
			(layer "B.Fab")
		)
		(fp_line
			(start -0.120396 0.2794)
			(end 0.12065 0.2794)
			(stroke
				(width 0.1)
				(type default)
			)
			(layer "B.Fab")
		)
		(fp_line
			(start -0.12065 -0.2794)
			(end -0.12065 -0.3048)
			(stroke
				(width 0.1)
				(type default)
			)
			(layer "B.Fab")
		)
		(fp_line
			(start -0.12065 -0.3048)
			(end -0.67945 -0.3048)
			(stroke
				(width 0.1)
				(type default)
			)
			(layer "B.Fab")
		)
		(fp_line
			(start -0.67945 0.3048)
			(end -0.120396 0.3048)
			(stroke
				(width 0.1)
				(type default)
			)
			(layer "B.Fab")
		)
		(fp_line
			(start -0.67945 -0.3048)
			(end -0.67945 0.3048)
			(stroke
				(width 0.1)
				(type default)
			)
			(layer "B.Fab")
		)
		(pad "1" smd circle
			(at 0.40005 0)
			(size 0 0)
			(layers "B.Cu" "B.Mask" "B.Paste")
			(net "NIC1_CLK")
		)
		(pad "2" smd circle
			(at -0.40005 0)
			(size 0 0)
			(layers "B.Cu" "B.Mask" "B.Paste")
			(net "GND")
		)
	)
	(footprint ""
		(layer "B.Cu")
		(at 415.549842 -292.099746 90)
		(property "Reference" "C1935"
			(at 0 0 90)
			(layer "B.SilkS")
			(hide yes)
			(effects
				(font
					(size 1.27 1.27)
				)
				(justify mirror)
			)
		)
		(property "Value" ""
			(at 0 0 90)
			(layer "B.Fab")
			(effects
				(font
					(size 1.27 1.27)
				)
				(justify mirror)
			)
		)
		(duplicate_pad_numbers_are_jumpers no)
		(fp_line
			(start 0.299974 -0.150114)
			(end -0.299974 -0.150114)
			(stroke
				(width 0.1)
				(type default)
			)
			(layer "B.Fab")
		)
		(fp_line
			(start -0.299974 -0.150114)
			(end -0.299974 0.150114)
			(stroke
				(width 0.1)
				(type default)
			)
			(layer "B.Fab")
		)
		(fp_line
			(start 0.299974 0.150114)
			(end 0.299974 -0.150114)
			(stroke
				(width 0.1)
				(type default)
			)
			(layer "B.Fab")
		)
		(fp_line
			(start -0.299974 0.150114)
			(end 0.299974 0.150114)
			(stroke
				(width 0.1)
				(type default)
			)
			(layer "B.Fab")
		)
		(pad "1" smd rect
			(at 0.2667 0 270)
			(size 0.3048 0.381)
			(layers "B.Cu" "B.Mask" "B.Paste")
			(net "P0V8_SERDES_VDDA_PEX3")
		)
		(pad "2" smd rect
			(at -0.2667 0 270)
			(size 0.3048 0.381)
			(layers "B.Cu" "B.Mask" "B.Paste")
			(net "GND")
		)
	)
	(footprint ""
		(layer "B.Cu")
		(at 211.393532 -230.644446 90)
		(property "Reference" "R6322"
			(at 0 0 90)
			(layer "B.SilkS")
			(hide yes)
			(effects
				(font
					(size 1.27 1.27)
				)
				(justify mirror)
			)
		)
		(property "Value" ""
			(at 0 0 90)
			(layer "B.Fab")
			(effects
				(font
					(size 1.27 1.27)
				)
				(justify mirror)
			)
		)
		(duplicate_pad_numbers_are_jumpers no)
		(fp_line
			(start 0.7874 -0.4064)
			(end -0.7874 -0.4064)
			(stroke
				(width 0.1524)
				(type default)
			)
			(layer "B.SilkS")
		)
		(fp_line
			(start -0.7874 -0.4064)
			(end -0.7874 0.4064)
			(stroke
				(width 0.1524)
				(type default)
			)
			(layer "B.SilkS")
		)
		(fp_line
			(start 0.7874 0.4064)
			(end 0.7874 -0.4064)
			(stroke
				(width 0.1524)
				(type default)
			)
			(layer "B.SilkS")
		)
		(fp_line
			(start -0.7874 0.4064)
			(end 0.7874 0.4064)
			(stroke
				(width 0.1524)
				(type default)
			)
			(layer "B.SilkS")
		)
		(fp_line
			(start 0.67945 -0.305054)
			(end 0.12065 -0.305054)
			(stroke
				(width 0.1)
				(type default)
			)
			(layer "B.Fab")
		)
		(fp_line
			(start 0.12065 -0.305054)
			(end 0.12065 -0.2794)
			(stroke
				(width 0.1)
				(type default)
			)
			(layer "B.Fab")
		)
		(fp_line
			(start -0.12065 -0.3048)
			(end -0.67945 -0.3048)
			(stroke
				(width 0.1)
				(type default)
			)
			(layer "B.Fab")
		)
		(fp_line
			(start -0.67945 -0.3048)
			(end -0.67945 0.3048)
			(stroke
				(width 0.1)
				(type default)
			)
			(layer "B.Fab")
		)
		(fp_line
			(start 0.12065 -0.2794)
			(end -0.12065 -0.2794)
			(stroke
				(width 0.1)
				(type default)
			)
			(layer "B.Fab")
		)
		(fp_line
			(start -0.12065 -0.2794)
			(end -0.12065 -0.3048)
			(stroke
				(width 0.1)
				(type default)
			)
			(layer "B.Fab")
		)
		(fp_line
			(start 0.12065 0.2794)
			(end 0.12065 0.3048)
			(stroke
				(width 0.1)
				(type default)
			)
			(layer "B.Fab")
		)
		(fp_line
			(start -0.120396 0.2794)
			(end 0.12065 0.2794)
			(stroke
				(width 0.1)
				(type default)
			)
			(layer "B.Fab")
		)
		(fp_line
			(start 0.67945 0.3048)
			(end 0.67945 -0.305054)
			(stroke
				(width 0.1)
				(type default)
			)
			(layer "B.Fab")
		)
		(fp_line
			(start 0.12065 0.3048)
			(end 0.67945 0.3048)
			(stroke
				(width 0.1)
				(type default)
			)
			(layer "B.Fab")
		)
		(fp_line
			(start -0.120396 0.3048)
			(end -0.120396 0.2794)
			(stroke
				(width 0.1)
				(type default)
			)
			(layer "B.Fab")
		)
		(fp_line
			(start -0.67945 0.3048)
			(end -0.120396 0.3048)
			(stroke
				(width 0.1)
				(type default)
			)
			(layer "B.Fab")
		)
		(pad "1" smd circle
			(at 0.40005 0 270)
			(size 0 0)
			(layers "B.Cu" "B.Mask" "B.Paste")
			(net "SMB_PEX0_SCL")
		)
		(pad "2" smd circle
			(at -0.40005 0 270)
			(size 0 0)
			(layers "B.Cu" "B.Mask" "B.Paste")
			(net "SMB_PEX0_MUX_SCL")
		)
	)
	(footprint ""
		(layer "B.Cu")
		(at 353.383088 -321.151758 -90)
		(property "Reference" "R6543"
			(at 0 0 90)
			(layer "B.SilkS")
			(hide yes)
			(effects
				(font
					(size 1.27 1.27)
				)
				(justify mirror)
			)
		)
		(property "Value" ""
			(at 0 0 90)
			(layer "B.Fab")
			(effects
				(font
					(size 1.27 1.27)
				)
				(justify mirror)
			)
		)
		(duplicate_pad_numbers_are_jumpers no)
		(fp_line
			(start -0.7874 0.4064)
			(end 0.7874 0.4064)
			(stroke
				(width 0.1524)
				(type default)
			)
			(layer "B.SilkS")
		)
		(fp_line
			(start 0.7874 0.4064)
			(end 0.7874 -0.4064)
			(stroke
				(width 0.1524)
				(type default)
			)
			(layer "B.SilkS")
		)
		(fp_line
			(start -0.7874 -0.4064)
			(end -0.7874 0.4064)
			(stroke
				(width 0.1524)
				(type default)
			)
			(layer "B.SilkS")
		)
		(fp_line
			(start 0.7874 -0.4064)
			(end -0.7874 -0.4064)
			(stroke
				(width 0.1524)
				(type default)
			)
			(layer "B.SilkS")
		)
		(fp_line
			(start -0.67945 0.3048)
			(end -0.120396 0.3048)
			(stroke
				(width 0.1)
				(type default)
			)
			(layer "B.Fab")
		)
		(fp_line
			(start -0.120396 0.3048)
			(end -0.120396 0.2794)
			(stroke
				(width 0.1)
				(type default)
			)
			(layer "B.Fab")
		)
		(fp_line
			(start 0.12065 0.3048)
			(end 0.67945 0.3048)
			(stroke
				(width 0.1)
				(type default)
			)
			(layer "B.Fab")
		)
		(fp_line
			(start 0.67945 0.3048)
			(end 0.67945 -0.305054)
			(stroke
				(width 0.1)
				(type default)
			)
			(layer "B.Fab")
		)
		(fp_line
			(start -0.120396 0.2794)
			(end 0.12065 0.2794)
			(stroke
				(width 0.1)
				(type default)
			)
			(layer "B.Fab")
		)
		(fp_line
			(start 0.12065 0.2794)
			(end 0.12065 0.3048)
			(stroke
				(width 0.1)
				(type default)
			)
			(layer "B.Fab")
		)
		(fp_line
			(start -0.12065 -0.2794)
			(end -0.12065 -0.3048)
			(stroke
				(width 0.1)
				(type default)
			)
			(layer "B.Fab")
		)
		(fp_line
			(start 0.12065 -0.2794)
			(end -0.12065 -0.2794)
			(stroke
				(width 0.1)
				(type default)
			)
			(layer "B.Fab")
		)
		(fp_line
			(start -0.67945 -0.3048)
			(end -0.67945 0.3048)
			(stroke
				(width 0.1)
				(type default)
			)
			(layer "B.Fab")
		)
		(fp_line
			(start -0.12065 -0.3048)
			(end -0.67945 -0.3048)
			(stroke
				(width 0.1)
				(type default)
			)
			(layer "B.Fab")
		)
		(fp_line
			(start 0.12065 -0.305054)
			(end 0.12065 -0.2794)
			(stroke
				(width 0.1)
				(type default)
			)
			(layer "B.Fab")
		)
		(fp_line
			(start 0.67945 -0.305054)
			(end 0.12065 -0.305054)
			(stroke
				(width 0.1)
				(type default)
			)
			(layer "B.Fab")
		)
		(pad "1" smd circle
			(at 0.40005 0 90)
			(size 0 0)
			(layers "B.Cu" "B.Mask" "B.Paste")
			(net "P0V8_SERDES_VDDA_PEX3")
		)
		(pad "2" smd circle
			(at -0.40005 0 90)
			(size 0 0)
			(layers "B.Cu" "B.Mask" "B.Paste")
			(net "P0V8_SERDES_VDDA_PEX3_C6")
		)
	)
	(footprint ""
		(layer "B.Cu")
		(at 233.467656 -215.104218 180)
		(property "Reference" "C3605"
			(at 0 0 0)
			(layer "B.SilkS")
			(hide yes)
			(effects
				(font
					(size 1.27 1.27)
				)
				(justify mirror)
			)
		)
		(property "Value" ""
			(at 0 0 0)
			(layer "B.Fab")
			(effects
				(font
					(size 1.27 1.27)
				)
				(justify mirror)
			)
		)
		(duplicate_pad_numbers_are_jumpers no)
		(fp_line
			(start 0.69215 0.2921)
			(end 0.69215 -0.2921)
			(stroke
				(width 0.1524)
				(type default)
			)
			(layer "B.SilkS")
		)
		(fp_line
			(start 0.69215 -0.2921)
			(end -0.69215 -0.2921)
			(stroke
				(width 0.1524)
				(type default)
			)
			(layer "B.SilkS")
		)
		(fp_line
			(start -0.69215 0.2921)
			(end 0.69215 0.2921)
			(stroke
				(width 0.1524)
				(type default)
			)
			(layer "B.SilkS")
		)
		(fp_line
			(start -0.69215 -0.2921)
			(end -0.69215 0.2921)
			(stroke
				(width 0.1524)
				(type default)
			)
			(layer "B.SilkS")
		)
		(fp_line
			(start 0.51435 0.2794)
			(end 0.51435 -0.2794)
			(stroke
				(width 0.1)
				(type default)
			)
			(layer "B.Fab")
		)
		(fp_line
			(start 0.51435 -0.2794)
			(end -0.51435 -0.2794)
			(stroke
				(width 0.1)
				(type default)
			)
			(layer "B.Fab")
		)
		(fp_line
			(start -0.51435 0.2794)
			(end 0.51435 0.2794)
			(stroke
				(width 0.1)
				(type default)
			)
			(layer "B.Fab")
		)
		(fp_line
			(start -0.51435 -0.2794)
			(end -0.51435 0.2794)
			(stroke
				(width 0.1)
				(type default)
			)
			(layer "B.Fab")
		)
		(pad "1" smd circle
			(at 0.40005 0)
			(size 0 0)
			(layers "B.Cu" "B.Mask" "B.Paste")
			(net "P1V2_BIC_USB2AV12")
		)
		(pad "2" smd circle
			(at -0.40005 0)
			(size 0 0)
			(layers "B.Cu" "B.Mask" "B.Paste")
			(net "GND")
		)
		(zone
			(layer "B.Cu")
			(hatch none 0.5)
			(connect_pads
				(clearance 0)
			)
			(min_thickness 0.25)
			(keepout
				(tracks not_allowed)
				(vias allowed)
				(pads allowed)
				(copperpour not_allowed)
				(footprints allowed)
			)
			(placement
				(enabled no)
				(sheetname "")
			)
			(fill
				(thermal_gap 0.5)
				(thermal_bridge_width 0.5)
				(island_removal_mode 0)
			)
			(polygon
				(pts
					(xy 233.277156 -215.191848) (xy 233.368596 -215.250014) (xy 233.567986 -215.250014) (xy 233.658156 -215.191848)
					(xy 233.658156 -215.016588) (xy 233.567986 -214.958168) (xy 233.368596 -214.958168) (xy 233.277156 -215.016334)
				)
			)
		)
	)
	(footprint ""
		(layer "B.Cu")
		(at 421.249856 -295.89984 180)
		(property "Reference" "C3508"
			(at 0 0 0)
			(layer "B.SilkS")
			(hide yes)
			(effects
				(font
					(size 1.27 1.27)
				)
				(justify mirror)
			)
		)
		(property "Value" ""
			(at 0 0 0)
			(layer "B.Fab")
			(effects
				(font
					(size 1.27 1.27)
				)
				(justify mirror)
			)
		)
		(duplicate_pad_numbers_are_jumpers no)
		(fp_line
			(start 0.299974 0.150114)
			(end 0.299974 -0.150114)
			(stroke
				(width 0.1)
				(type default)
			)
			(layer "B.Fab")
		)
		(fp_line
			(start 0.299974 -0.150114)
			(end -0.299974 -0.150114)
			(stroke
				(width 0.1)
				(type default)
			)
			(layer "B.Fab")
		)
		(fp_line
			(start -0.299974 0.150114)
			(end 0.299974 0.150114)
			(stroke
				(width 0.1)
				(type default)
			)
			(layer "B.Fab")
		)
		(fp_line
			(start -0.299974 -0.150114)
			(end -0.299974 0.150114)
			(stroke
				(width 0.1)
				(type default)
			)
			(layer "B.Fab")
		)
		(pad "1" smd rect
			(at 0.2667 0)
			(size 0.3048 0.381)
			(layers "B.Cu" "B.Mask" "B.Paste")
			(net "P1V25_SERDES_VDDPLL_PEX3")
		)
		(pad "2" smd rect
			(at -0.2667 0)
			(size 0.3048 0.381)
			(layers "B.Cu" "B.Mask" "B.Paste")
			(net "GND")
		)
	)
	(footprint ""
		(layer "B.Cu")
		(at 380.746 -241.681 90)
		(property "Reference" "C2573"
			(at 0 0 90)
			(layer "B.SilkS")
			(hide yes)
			(effects
				(font
					(size 1.27 1.27)
				)
				(justify mirror)
			)
		)
		(property "Value" ""
			(at 0 0 90)
			(layer "B.Fab")
			(effects
				(font
					(size 1.27 1.27)
				)
				(justify mirror)
			)
		)
		(duplicate_pad_numbers_are_jumpers no)
		(fp_line
			(start 0.7874 -0.4064)
			(end -0.7874 -0.4064)
			(stroke
				(width 0.1524)
				(type default)
			)
			(layer "B.SilkS")
		)
		(fp_line
			(start -0.7874 -0.4064)
			(end -0.7874 0.4064)
			(stroke
				(width 0.1524)
				(type default)
			)
			(layer "B.SilkS")
		)
		(fp_line
			(start 0.7874 0.4064)
			(end 0.7874 -0.4064)
			(stroke
				(width 0.1524)
				(type default)
			)
			(layer "B.SilkS")
		)
		(fp_line
			(start -0.7874 0.4064)
			(end 0.7874 0.4064)
			(stroke
				(width 0.1524)
				(type default)
			)
			(layer "B.SilkS")
		)
		(fp_line
			(start 0.67945 -0.305054)
			(end 0.12065 -0.305054)
			(stroke
				(width 0.1)
				(type default)
			)
			(layer "B.Fab")
		)
		(fp_line
			(start 0.12065 -0.305054)
			(end 0.12065 -0.2794)
			(stroke
				(width 0.1)
				(type default)
			)
			(layer "B.Fab")
		)
		(fp_line
			(start -0.12065 -0.3048)
			(end -0.67945 -0.3048)
			(stroke
				(width 0.1)
				(type default)
			)
			(layer "B.Fab")
		)
		(fp_line
			(start -0.67945 -0.3048)
			(end -0.67945 0.3048)
			(stroke
				(width 0.1)
				(type default)
			)
			(layer "B.Fab")
		)
		(fp_line
			(start 0.12065 -0.2794)
			(end -0.12065 -0.2794)
			(stroke
				(width 0.1)
				(type default)
			)
			(layer "B.Fab")
		)
		(fp_line
			(start -0.12065 -0.2794)
			(end -0.12065 -0.3048)
			(stroke
				(width 0.1)
				(type default)
			)
			(layer "B.Fab")
		)
		(fp_line
			(start 0.12065 0.2794)
			(end 0.12065 0.3048)
			(stroke
				(width 0.1)
				(type default)
			)
			(layer "B.Fab")
		)
		(fp_line
			(start -0.120396 0.2794)
			(end 0.12065 0.2794)
			(stroke
				(width 0.1)
				(type default)
			)
			(layer "B.Fab")
		)
		(fp_line
			(start 0.67945 0.3048)
			(end 0.67945 -0.305054)
			(stroke
				(width 0.1)
				(type default)
			)
			(layer "B.Fab")
		)
		(fp_line
			(start 0.12065 0.3048)
			(end 0.67945 0.3048)
			(stroke
				(width 0.1)
				(type default)
			)
			(layer "B.Fab")
		)
		(fp_line
			(start -0.120396 0.3048)
			(end -0.120396 0.2794)
			(stroke
				(width 0.1)
				(type default)
			)
			(layer "B.Fab")
		)
		(fp_line
			(start -0.67945 0.3048)
			(end -0.120396 0.3048)
			(stroke
				(width 0.1)
				(type default)
			)
			(layer "B.Fab")
		)
		(pad "1" smd circle
			(at 0.40005 0 270)
			(size 0 0)
			(layers "B.Cu" "B.Mask" "B.Paste")
			(net "P1V8_SDB_VCORE")
		)
		(pad "2" smd circle
			(at -0.40005 0 270)
			(size 0 0)
			(layers "B.Cu" "B.Mask" "B.Paste")
			(net "GND")
		)
	)
	(footprint ""
		(layer "B.Cu")
		(at 285.674816 -293.99992 -90)
		(property "Reference" "C1665"
			(at 0 0 90)
			(layer "B.SilkS")
			(hide yes)
			(effects
				(font
					(size 1.27 1.27)
				)
				(justify mirror)
			)
		)
		(property "Value" ""
			(at 0 0 90)
			(layer "B.Fab")
			(effects
				(font
					(size 1.27 1.27)
				)
				(justify mirror)
			)
		)
		(duplicate_pad_numbers_are_jumpers no)
		(fp_line
			(start -0.299974 0.150114)
			(end 0.299974 0.150114)
			(stroke
				(width 0.1)
				(type default)
			)
			(layer "B.Fab")
		)
		(fp_line
			(start 0.299974 0.150114)
			(end 0.299974 -0.150114)
			(stroke
				(width 0.1)
				(type default)
			)
			(layer "B.Fab")
		)
		(fp_line
			(start -0.299974 -0.150114)
			(end -0.299974 0.150114)
			(stroke
				(width 0.1)
				(type default)
			)
			(layer "B.Fab")
		)
		(fp_line
			(start 0.299974 -0.150114)
			(end -0.299974 -0.150114)
			(stroke
				(width 0.1)
				(type default)
			)
			(layer "B.Fab")
		)
		(pad "1" smd rect
			(at 0.2667 0 90)
			(size 0.3048 0.381)
			(layers "B.Cu" "B.Mask" "B.Paste")
			(net "P0V8_PEX2")
		)
		(pad "2" smd rect
			(at -0.2667 0 90)
			(size 0.3048 0.381)
			(layers "B.Cu" "B.Mask" "B.Paste")
			(net "GND")
		)
	)
	(footprint ""
		(layer "B.Cu")
		(at 289.94989 -303.499774 -90)
		(property "Reference" "C3265"
			(at 0 0 90)
			(layer "B.SilkS")
			(hide yes)
			(effects
				(font
					(size 1.27 1.27)
				)
				(justify mirror)
			)
		)
		(property "Value" ""
			(at 0 0 90)
			(layer "B.Fab")
			(effects
				(font
					(size 1.27 1.27)
				)
				(justify mirror)
			)
		)
		(duplicate_pad_numbers_are_jumpers no)
		(fp_line
			(start -0.299974 0.150114)
			(end 0.299974 0.150114)
			(stroke
				(width 0.1)
				(type default)
			)
			(layer "B.Fab")
		)
		(fp_line
			(start 0.299974 0.150114)
			(end 0.299974 -0.150114)
			(stroke
				(width 0.1)
				(type default)
			)
			(layer "B.Fab")
		)
		(fp_line
			(start -0.299974 -0.150114)
			(end -0.299974 0.150114)
			(stroke
				(width 0.1)
				(type default)
			)
			(layer "B.Fab")
		)
		(fp_line
			(start 0.299974 -0.150114)
			(end -0.299974 -0.150114)
			(stroke
				(width 0.1)
				(type default)
			)
			(layer "B.Fab")
		)
		(pad "1" smd rect
			(at 0.2667 0 90)
			(size 0.3048 0.381)
			(layers "B.Cu" "B.Mask" "B.Paste")
			(net "P1V25_PEX2")
		)
		(pad "2" smd rect
			(at -0.2667 0 90)
			(size 0.3048 0.381)
			(layers "B.Cu" "B.Mask" "B.Paste")
			(net "GND")
		)
	)
	(footprint ""
		(layer "B.Cu")
		(at 176.699926 -301.599854 -90)
		(property "Reference" "C1454"
			(at 0 0 90)
			(layer "B.SilkS")
			(hide yes)
			(effects
				(font
					(size 1.27 1.27)
				)
				(justify mirror)
			)
		)
		(property "Value" ""
			(at 0 0 90)
			(layer "B.Fab")
			(effects
				(font
					(size 1.27 1.27)
				)
				(justify mirror)
			)
		)
		(duplicate_pad_numbers_are_jumpers no)
		(fp_line
			(start -0.299974 0.150114)
			(end 0.299974 0.150114)
			(stroke
				(width 0.1)
				(type default)
			)
			(layer "B.Fab")
		)
		(fp_line
			(start 0.299974 0.150114)
			(end 0.299974 -0.150114)
			(stroke
				(width 0.1)
				(type default)
			)
			(layer "B.Fab")
		)
		(fp_line
			(start -0.299974 -0.150114)
			(end -0.299974 0.150114)
			(stroke
				(width 0.1)
				(type default)
			)
			(layer "B.Fab")
		)
		(fp_line
			(start 0.299974 -0.150114)
			(end -0.299974 -0.150114)
			(stroke
				(width 0.1)
				(type default)
			)
			(layer "B.Fab")
		)
		(pad "1" smd rect
			(at 0.2667 0 90)
			(size 0.3048 0.381)
			(layers "B.Cu" "B.Mask" "B.Paste")
			(net "P0V8_SERDES_VDDA_PEX1")
		)
		(pad "2" smd rect
			(at -0.2667 0 90)
			(size 0.3048 0.381)
			(layers "B.Cu" "B.Mask" "B.Paste")
			(net "GND")
		)
	)
	(footprint ""
		(layer "B.Cu")
		(at 338.76615 -84.500974 -90)
		(property "Reference" "C2676"
			(at 0 0 90)
			(layer "B.SilkS")
			(hide yes)
			(effects
				(font
					(size 1.27 1.27)
				)
				(justify mirror)
			)
		)
		(property "Value" ""
			(at 0 0 90)
			(layer "B.Fab")
			(effects
				(font
					(size 1.27 1.27)
				)
				(justify mirror)
			)
		)
		(duplicate_pad_numbers_are_jumpers no)
		(fp_line
			(start -0.7874 0.4064)
			(end 0.7874 0.4064)
			(stroke
				(width 0.1524)
				(type default)
			)
			(layer "B.SilkS")
		)
		(fp_line
			(start 0.7874 0.4064)
			(end 0.7874 -0.4064)
			(stroke
				(width 0.1524)
				(type default)
			)
			(layer "B.SilkS")
		)
		(fp_line
			(start -0.7874 -0.4064)
			(end -0.7874 0.4064)
			(stroke
				(width 0.1524)
				(type default)
			)
			(layer "B.SilkS")
		)
		(fp_line
			(start 0.7874 -0.4064)
			(end -0.7874 -0.4064)
			(stroke
				(width 0.1524)
				(type default)
			)
			(layer "B.SilkS")
		)
		(fp_line
			(start -0.67945 0.3048)
			(end -0.120396 0.3048)
			(stroke
				(width 0.1)
				(type default)
			)
			(layer "B.Fab")
		)
		(fp_line
			(start -0.120396 0.3048)
			(end -0.120396 0.2794)
			(stroke
				(width 0.1)
				(type default)
			)
			(layer "B.Fab")
		)
		(fp_line
			(start 0.12065 0.3048)
			(end 0.67945 0.3048)
			(stroke
				(width 0.1)
				(type default)
			)
			(layer "B.Fab")
		)
		(fp_line
			(start 0.67945 0.3048)
			(end 0.67945 -0.305054)
			(stroke
				(width 0.1)
				(type default)
			)
			(layer "B.Fab")
		)
		(fp_line
			(start -0.120396 0.2794)
			(end 0.12065 0.2794)
			(stroke
				(width 0.1)
				(type default)
			)
			(layer "B.Fab")
		)
		(fp_line
			(start 0.12065 0.2794)
			(end 0.12065 0.3048)
			(stroke
				(width 0.1)
				(type default)
			)
			(layer "B.Fab")
		)
		(fp_line
			(start -0.12065 -0.2794)
			(end -0.12065 -0.3048)
			(stroke
				(width 0.1)
				(type default)
			)
			(layer "B.Fab")
		)
		(fp_line
			(start 0.12065 -0.2794)
			(end -0.12065 -0.2794)
			(stroke
				(width 0.1)
				(type default)
			)
			(layer "B.Fab")
		)
		(fp_line
			(start -0.67945 -0.3048)
			(end -0.67945 0.3048)
			(stroke
				(width 0.1)
				(type default)
			)
			(layer "B.Fab")
		)
		(fp_line
			(start -0.12065 -0.3048)
			(end -0.67945 -0.3048)
			(stroke
				(width 0.1)
				(type default)
			)
			(layer "B.Fab")
		)
		(fp_line
			(start 0.12065 -0.305054)
			(end 0.12065 -0.2794)
			(stroke
				(width 0.1)
				(type default)
			)
			(layer "B.Fab")
		)
		(fp_line
			(start 0.67945 -0.305054)
			(end 0.12065 -0.305054)
			(stroke
				(width 0.1)
				(type default)
			)
			(layer "B.Fab")
		)
		(pad "1" smd circle
			(at 0.40005 0 90)
			(size 0 0)
			(layers "B.Cu" "B.Mask" "B.Paste")
			(net "P3V3_VDD_9ZXL0851_8_15")
		)
		(pad "2" smd circle
			(at -0.40005 0 90)
			(size 0 0)
			(layers "B.Cu" "B.Mask" "B.Paste")
			(net "GND")
		)
	)
	(footprint ""
		(layer "B.Cu")
		(at 377.587002 -221.066106)
		(property "Reference" "R926"
			(at 0 0 0)
			(layer "B.SilkS")
			(hide yes)
			(effects
				(font
					(size 1.27 1.27)
				)
				(justify mirror)
			)
		)
		(property "Value" ""
			(at 0 0 0)
			(layer "B.Fab")
			(effects
				(font
					(size 1.27 1.27)
				)
				(justify mirror)
			)
		)
		(duplicate_pad_numbers_are_jumpers no)
		(fp_line
			(start -0.7874 -0.4064)
			(end -0.7874 0.4064)
			(stroke
				(width 0.1524)
				(type default)
			)
			(layer "B.SilkS")
		)
		(fp_line
			(start -0.7874 0.4064)
			(end 0.7874 0.4064)
			(stroke
				(width 0.1524)
				(type default)
			)
			(layer "B.SilkS")
		)
		(fp_line
			(start 0.7874 -0.4064)
			(end -0.7874 -0.4064)
			(stroke
				(width 0.1524)
				(type default)
			)
			(layer "B.SilkS")
		)
		(fp_line
			(start 0.7874 0.4064)
			(end 0.7874 -0.4064)
			(stroke
				(width 0.1524)
				(type default)
			)
			(layer "B.SilkS")
		)
		(fp_line
			(start -0.67945 -0.3048)
			(end -0.67945 0.3048)
			(stroke
				(width 0.1)
				(type default)
			)
			(layer "B.Fab")
		)
		(fp_line
			(start -0.67945 0.3048)
			(end -0.120396 0.3048)
			(stroke
				(width 0.1)
				(type default)
			)
			(layer "B.Fab")
		)
		(fp_line
			(start -0.12065 -0.3048)
			(end -0.67945 -0.3048)
			(stroke
				(width 0.1)
				(type default)
			)
			(layer "B.Fab")
		)
		(fp_line
			(start -0.12065 -0.2794)
			(end -0.12065 -0.3048)
			(stroke
				(width 0.1)
				(type default)
			)
			(layer "B.Fab")
		)
		(fp_line
			(start -0.120396 0.2794)
			(end 0.12065 0.2794)
			(stroke
				(width 0.1)
				(type default)
			)
			(layer "B.Fab")
		)
		(fp_line
			(start -0.120396 0.3048)
			(end -0.120396 0.2794)
			(stroke
				(width 0.1)
				(type default)
			)
			(layer "B.Fab")
		)
		(fp_line
			(start 0.12065 -0.305054)
			(end 0.12065 -0.2794)
			(stroke
				(width 0.1)
				(type default)
			)
			(layer "B.Fab")
		)
		(fp_line
			(start 0.12065 -0.2794)
			(end -0.12065 -0.2794)
			(stroke
				(width 0.1)
				(type default)
			)
			(layer "B.Fab")
		)
		(fp_line
			(start 0.12065 0.2794)
			(end 0.12065 0.3048)
			(stroke
				(width 0.1)
				(type default)
			)
			(layer "B.Fab")
		)
		(fp_line
			(start 0.12065 0.3048)
			(end 0.67945 0.3048)
			(stroke
				(width 0.1)
				(type default)
			)
			(layer "B.Fab")
		)
		(fp_line
			(start 0.67945 -0.305054)
			(end 0.12065 -0.305054)
			(stroke
				(width 0.1)
				(type default)
			)
			(layer "B.Fab")
		)
		(fp_line
			(start 0.67945 0.3048)
			(end 0.67945 -0.305054)
			(stroke
				(width 0.1)
				(type default)
			)
			(layer "B.Fab")
		)
		(pad "1" smd circle
			(at 0.40005 0 180)
			(size 0 0)
			(layers "B.Cu" "B.Mask" "B.Paste")
			(net "UART_PEX1_SDB_BUF_RX")
		)
		(pad "2" smd circle
			(at -0.40005 0 180)
			(size 0 0)
			(layers "B.Cu" "B.Mask" "B.Paste")
			(net "P1V8_PEX")
		)
	)
	(footprint ""
		(layer "B.Cu")
		(at 73.400158 -112.604296)
		(property "Reference" "C863"
			(at 0 0 0)
			(layer "B.SilkS")
			(hide yes)
			(effects
				(font
					(size 1.27 1.27)
				)
				(justify mirror)
			)
		)
		(property "Value" ""
			(at 0 0 0)
			(layer "B.Fab")
			(effects
				(font
					(size 1.27 1.27)
				)
				(justify mirror)
			)
		)
		(duplicate_pad_numbers_are_jumpers no)
		(fp_line
			(start -0.299974 -0.150114)
			(end -0.299974 0.150114)
			(stroke
				(width 0.1)
				(type default)
			)
			(layer "B.Fab")
		)
		(fp_line
			(start -0.299974 0.150114)
			(end 0.299974 0.150114)
			(stroke
				(width 0.1)
				(type default)
			)
			(layer "B.Fab")
		)
		(fp_line
			(start 0.299974 -0.150114)
			(end -0.299974 -0.150114)
			(stroke
				(width 0.1)
				(type default)
			)
			(layer "B.Fab")
		)
		(fp_line
			(start 0.299974 0.150114)
			(end 0.299974 -0.150114)
			(stroke
				(width 0.1)
				(type default)
			)
			(layer "B.Fab")
		)
		(pad "1" smd rect
			(at 0.2667 0 180)
			(size 0.3048 0.381)
			(layers "B.Cu" "B.Mask" "B.Paste")
			(net "P12V_NIC1")
		)
		(pad "2" smd rect
			(at -0.2667 0 180)
			(size 0.3048 0.381)
			(layers "B.Cu" "B.Mask" "B.Paste")
			(net "GND")
		)
	)
	(footprint ""
		(layer "B.Cu")
		(at 151.209248 -444.912496 180)
		(property "Reference" "X56"
			(at -4.769104 2.281428 90)
			(unlocked yes)
			(layer "B.SilkS")
			(effects
				(font
					(size 0.7874 0.5842)
					(thickness 0.1524)
				)
				(justify left mirror)
			)
		)
		(property "Value" ""
			(at 0 0 0)
			(layer "B.Fab")
			(effects
				(font
					(size 1.27 1.27)
				)
				(justify mirror)
			)
		)
		(property "Device Type" "TP_TDR_4P_FTS_MPKT4_H025P0200_IO_TP15_TP_TDR_4P_DIP"
			(at -1.30175 1.27 90)
			(unlocked yes)
			(layer "B.Fab")
			(hide yes)
			(effects
				(font
					(size 0.635 0.4064)
					(thickness 0.1524)
				)
				(justify mirror)
			)
		)
		(property "User Part Number" "TP15"
			(at -1.30175 1.27 90)
			(unlocked yes)
			(layer "Cmts.User")
			(hide yes)
			(effects
				(font
					(size 0.635 0.4064)
					(thickness 0.1524)
				)
				(justify mirror)
			)
		)
		(duplicate_pad_numbers_are_jumpers no)
		(fp_line
			(start 0 3.81)
			(end -2.54 3.81)
			(stroke
				(width 0.1524)
				(type default)
			)
			(layer "B.SilkS")
		)
		(fp_line
			(start 0 3.175)
			(end 0 3.81)
			(stroke
				(width 0.1524)
				(type default)
			)
			(layer "B.SilkS")
		)
		(fp_line
			(start 0 0.635)
			(end 0 1.905)
			(stroke
				(width 0.1524)
				(type default)
			)
			(layer "B.SilkS")
		)
		(fp_line
			(start 0 -1.27)
			(end 0 -0.635)
			(stroke
				(width 0.1524)
				(type default)
			)
			(layer "B.SilkS")
		)
		(fp_line
			(start -2.54 3.81)
			(end -2.54 3.6703)
			(stroke
				(width 0.1524)
				(type default)
			)
			(layer "B.SilkS")
		)
		(fp_line
			(start -2.54 1.4097)
			(end -2.54 1.1303)
			(stroke
				(width 0.1524)
				(type default)
			)
			(layer "B.SilkS")
		)
		(fp_line
			(start -2.54 -1.1303)
			(end -2.54 -1.27)
			(stroke
				(width 0.1524)
				(type default)
			)
			(layer "B.SilkS")
		)
		(fp_line
			(start -2.54 -1.27)
			(end 0 -1.27)
			(stroke
				(width 0.1524)
				(type default)
			)
			(layer "B.SilkS")
		)
		(fp_poly
			(pts
				(xy 0.761746 0) (xy 2.285746 -0.762) (xy 2.285746 0.762)
			)
			(stroke
				(width 0)
				(type default)
			)
			(fill yes)
			(layer "B.SilkS")
		)
		(fp_line
			(start 0 3.81)
			(end -2.54 3.81)
			(stroke
				(width 0.1)
				(type default)
			)
			(layer "B.Fab")
		)
		(fp_line
			(start 0 -1.27)
			(end 0 3.81)
			(stroke
				(width 0.1)
				(type default)
			)
			(layer "B.Fab")
		)
		(fp_line
			(start -2.54 3.81)
			(end -2.54 -1.27)
			(stroke
				(width 0.1)
				(type default)
			)
			(layer "B.Fab")
		)
		(fp_line
			(start -2.54 -1.27)
			(end 0 -1.27)
			(stroke
				(width 0.1)
				(type default)
			)
			(layer "B.Fab")
		)
		(fp_poly
			(pts
				(xy 0.761746 0) (xy 2.285746 -0.762) (xy 2.285746 0.762)
			)
			(stroke
				(width 0)
				(type default)
			)
			(fill yes)
			(layer "B.Fab")
		)
		(pad "1" thru_hole circle
			(at 0 0)
			(size 1.0033 1.0033)
			(drill 0.249936)
			(layers "*.Cu" "*.Mask")
			(remove_unused_layers no)
			(net "TDR_DIFF_85_BOT_DIP")
			(clearance 0.10795)
			(padstack
				(mode front_inner_back)
				(layer "Inner"
					(shape circle)
					(size 0.8001 0.8001)
					(clearance 0.1524)
				)
				(layer "B.Cu"
					(shape circle)
					(size 1.0033 1.0033)
					(thermal_gap 0.10795)
					(clearance 0.10795)
				)
			)
		)
		(pad "2" thru_hole circle
			(at -2.54 0)
			(size 1.9939 1.9939)
			(drill 0.249936)
			(layers "*.Cu" "*.Mask")
			(remove_unused_layers no)
			(net "COUPON_GND1")
			(clearance 0.10795)
			(padstack
				(mode front_inner_back)
				(layer "Inner"
					(shape circle)
					(size 0.8001 0.8001)
					(clearance 0.1524)
				)
				(layer "B.Cu"
					(shape circle)
					(size 1.9939 1.9939)
					(thermal_gap 0.10795)
					(clearance 0.10795)
				)
			)
		)
		(pad "3" thru_hole circle
			(at -2.54 2.54)
			(size 1.9939 1.9939)
			(drill 0.249936)
			(layers "*.Cu" "*.Mask")
			(remove_unused_layers no)
			(net "COUPON_GND1")
			(clearance 0.10795)
			(padstack
				(mode front_inner_back)
				(layer "Inner"
					(shape circle)
					(size 0.8001 0.8001)
					(clearance 0.1524)
				)
				(layer "B.Cu"
					(shape circle)
					(size 1.9939 1.9939)
					(thermal_gap 0.10795)
					(clearance 0.10795)
				)
			)
		)
		(pad "4" thru_hole circle
			(at 0 2.54)
			(size 1.0033 1.0033)
			(drill 0.249936)
			(layers "*.Cu" "*.Mask")
			(remove_unused_layers no)
			(net "TDR_DIFF_85_BOT_DIN")
			(clearance 0.10795)
			(padstack
				(mode front_inner_back)
				(layer "Inner"
					(shape circle)
					(size 0.8001 0.8001)
					(clearance 0.1524)
				)
				(layer "B.Cu"
					(shape circle)
					(size 1.0033 1.0033)
					(thermal_gap 0.10795)
					(clearance 0.10795)
				)
			)
		)
	)
	(footprint ""
		(layer "B.Cu")
		(at 47.77486 -292.84168 90)
		(property "Reference" "C3046"
			(at 0 0 90)
			(layer "B.SilkS")
			(hide yes)
			(effects
				(font
					(size 1.27 1.27)
				)
				(justify mirror)
			)
		)
		(property "Value" ""
			(at 0 0 90)
			(layer "B.Fab")
			(effects
				(font
					(size 1.27 1.27)
				)
				(justify mirror)
			)
		)
		(duplicate_pad_numbers_are_jumpers no)
		(fp_line
			(start 0.299974 -0.150114)
			(end -0.299974 -0.150114)
			(stroke
				(width 0.1)
				(type default)
			)
			(layer "B.Fab")
		)
		(fp_line
			(start -0.299974 -0.150114)
			(end -0.299974 0.150114)
			(stroke
				(width 0.1)
				(type default)
			)
			(layer "B.Fab")
		)
		(fp_line
			(start 0.299974 0.150114)
			(end 0.299974 -0.150114)
			(stroke
				(width 0.1)
				(type default)
			)
			(layer "B.Fab")
		)
		(fp_line
			(start -0.299974 0.150114)
			(end 0.299974 0.150114)
			(stroke
				(width 0.1)
				(type default)
			)
			(layer "B.Fab")
		)
		(pad "1" smd rect
			(at 0.2667 0 270)
			(size 0.3048 0.381)
			(layers "B.Cu" "B.Mask" "B.Paste")
			(net "PCEPLL5_VDDA18_PEX0")
		)
		(pad "2" smd rect
			(at -0.2667 0 270)
			(size 0.3048 0.381)
			(layers "B.Cu" "B.Mask" "B.Paste")
			(net "GND")
		)
	)
	(footprint ""
		(layer "B.Cu")
		(at 57.749948 -299.699934 -90)
		(property "Reference" "C1234"
			(at 0 0 90)
			(layer "B.SilkS")
			(hide yes)
			(effects
				(font
					(size 1.27 1.27)
				)
				(justify mirror)
			)
		)
		(property "Value" ""
			(at 0 0 90)
			(layer "B.Fab")
			(effects
				(font
					(size 1.27 1.27)
				)
				(justify mirror)
			)
		)
		(duplicate_pad_numbers_are_jumpers no)
		(fp_line
			(start -0.299974 0.150114)
			(end 0.299974 0.150114)
			(stroke
				(width 0.1)
				(type default)
			)
			(layer "B.Fab")
		)
		(fp_line
			(start 0.299974 0.150114)
			(end 0.299974 -0.150114)
			(stroke
				(width 0.1)
				(type default)
			)
			(layer "B.Fab")
		)
		(fp_line
			(start -0.299974 -0.150114)
			(end -0.299974 0.150114)
			(stroke
				(width 0.1)
				(type default)
			)
			(layer "B.Fab")
		)
		(fp_line
			(start 0.299974 -0.150114)
			(end -0.299974 -0.150114)
			(stroke
				(width 0.1)
				(type default)
			)
			(layer "B.Fab")
		)
		(pad "1" smd rect
			(at 0.2667 0 90)
			(size 0.3048 0.381)
			(layers "B.Cu" "B.Mask" "B.Paste")
			(net "P0V8_SERDES_VDDA_PEX0")
		)
		(pad "2" smd rect
			(at -0.2667 0 90)
			(size 0.3048 0.381)
			(layers "B.Cu" "B.Mask" "B.Paste")
			(net "GND")
		)
	)
	(footprint ""
		(layer "B.Cu")
		(at 170.999912 -288.299906 90)
		(property "Reference" "C3100"
			(at 0 0 90)
			(layer "B.SilkS")
			(hide yes)
			(effects
				(font
					(size 1.27 1.27)
				)
				(justify mirror)
			)
		)
		(property "Value" ""
			(at 0 0 90)
			(layer "B.Fab")
			(effects
				(font
					(size 1.27 1.27)
				)
				(justify mirror)
			)
		)
		(duplicate_pad_numbers_are_jumpers no)
		(fp_line
			(start 0.299974 -0.150114)
			(end -0.299974 -0.150114)
			(stroke
				(width 0.1)
				(type default)
			)
			(layer "B.Fab")
		)
		(fp_line
			(start -0.299974 -0.150114)
			(end -0.299974 0.150114)
			(stroke
				(width 0.1)
				(type default)
			)
			(layer "B.Fab")
		)
		(fp_line
			(start 0.299974 0.150114)
			(end 0.299974 -0.150114)
			(stroke
				(width 0.1)
				(type default)
			)
			(layer "B.Fab")
		)
		(fp_line
			(start -0.299974 0.150114)
			(end 0.299974 0.150114)
			(stroke
				(width 0.1)
				(type default)
			)
			(layer "B.Fab")
		)
		(pad "1" smd rect
			(at 0.2667 0 270)
			(size 0.3048 0.381)
			(layers "B.Cu" "B.Mask" "B.Paste")
			(net "P1V25_PEX1")
		)
		(pad "2" smd rect
			(at -0.2667 0 270)
			(size 0.3048 0.381)
			(layers "B.Cu" "B.Mask" "B.Paste")
			(net "GND")
		)
	)
	(footprint ""
		(layer "B.Cu")
		(at 344.641424 -323.15531 -90)
		(property "Reference" "R6507"
			(at 0 0 90)
			(layer "B.SilkS")
			(hide yes)
			(effects
				(font
					(size 1.27 1.27)
				)
				(justify mirror)
			)
		)
		(property "Value" ""
			(at 0 0 90)
			(layer "B.Fab")
			(effects
				(font
					(size 1.27 1.27)
				)
				(justify mirror)
			)
		)
		(duplicate_pad_numbers_are_jumpers no)
		(fp_line
			(start -0.7874 0.4064)
			(end 0.7874 0.4064)
			(stroke
				(width 0.1524)
				(type default)
			)
			(layer "B.SilkS")
		)
		(fp_line
			(start 0.7874 0.4064)
			(end 0.7874 -0.4064)
			(stroke
				(width 0.1524)
				(type default)
			)
			(layer "B.SilkS")
		)
		(fp_line
			(start -0.7874 -0.4064)
			(end -0.7874 0.4064)
			(stroke
				(width 0.1524)
				(type default)
			)
			(layer "B.SilkS")
		)
		(fp_line
			(start 0.7874 -0.4064)
			(end -0.7874 -0.4064)
			(stroke
				(width 0.1524)
				(type default)
			)
			(layer "B.SilkS")
		)
		(fp_line
			(start -0.67945 0.3048)
			(end -0.120396 0.3048)
			(stroke
				(width 0.1)
				(type default)
			)
			(layer "B.Fab")
		)
		(fp_line
			(start -0.120396 0.3048)
			(end -0.120396 0.2794)
			(stroke
				(width 0.1)
				(type default)
			)
			(layer "B.Fab")
		)
		(fp_line
			(start 0.12065 0.3048)
			(end 0.67945 0.3048)
			(stroke
				(width 0.1)
				(type default)
			)
			(layer "B.Fab")
		)
		(fp_line
			(start 0.67945 0.3048)
			(end 0.67945 -0.305054)
			(stroke
				(width 0.1)
				(type default)
			)
			(layer "B.Fab")
		)
		(fp_line
			(start -0.120396 0.2794)
			(end 0.12065 0.2794)
			(stroke
				(width 0.1)
				(type default)
			)
			(layer "B.Fab")
		)
		(fp_line
			(start 0.12065 0.2794)
			(end 0.12065 0.3048)
			(stroke
				(width 0.1)
				(type default)
			)
			(layer "B.Fab")
		)
		(fp_line
			(start -0.12065 -0.2794)
			(end -0.12065 -0.3048)
			(stroke
				(width 0.1)
				(type default)
			)
			(layer "B.Fab")
		)
		(fp_line
			(start 0.12065 -0.2794)
			(end -0.12065 -0.2794)
			(stroke
				(width 0.1)
				(type default)
			)
			(layer "B.Fab")
		)
		(fp_line
			(start -0.67945 -0.3048)
			(end -0.67945 0.3048)
			(stroke
				(width 0.1)
				(type default)
			)
			(layer "B.Fab")
		)
		(fp_line
			(start -0.12065 -0.3048)
			(end -0.67945 -0.3048)
			(stroke
				(width 0.1)
				(type default)
			)
			(layer "B.Fab")
		)
		(fp_line
			(start 0.12065 -0.305054)
			(end 0.12065 -0.2794)
			(stroke
				(width 0.1)
				(type default)
			)
			(layer "B.Fab")
		)
		(fp_line
			(start 0.67945 -0.305054)
			(end 0.12065 -0.305054)
			(stroke
				(width 0.1)
				(type default)
			)
			(layer "B.Fab")
		)
		(pad "1" smd circle
			(at 0.40005 0 90)
			(size 0 0)
			(layers "B.Cu" "B.Mask" "B.Paste")
			(net "P0V8_SERDES_VDDA_PEX2")
		)
		(pad "2" smd circle
			(at -0.40005 0 90)
			(size 0 0)
			(layers "B.Cu" "B.Mask" "B.Paste")
			(net "P0V8_SERDES_VDDA_PEX2_C2")
		)
	)
	(footprint ""
		(layer "B.Cu")
		(at 178.599846 -292.099746 90)
		(property "Reference" "C1461"
			(at 0 0 90)
			(layer "B.SilkS")
			(hide yes)
			(effects
				(font
					(size 1.27 1.27)
				)
				(justify mirror)
			)
		)
		(property "Value" ""
			(at 0 0 90)
			(layer "B.Fab")
			(effects
				(font
					(size 1.27 1.27)
				)
				(justify mirror)
			)
		)
		(duplicate_pad_numbers_are_jumpers no)
		(fp_line
			(start 0.299974 -0.150114)
			(end -0.299974 -0.150114)
			(stroke
				(width 0.1)
				(type default)
			)
			(layer "B.Fab")
		)
		(fp_line
			(start -0.299974 -0.150114)
			(end -0.299974 0.150114)
			(stroke
				(width 0.1)
				(type default)
			)
			(layer "B.Fab")
		)
		(fp_line
			(start 0.299974 0.150114)
			(end 0.299974 -0.150114)
			(stroke
				(width 0.1)
				(type default)
			)
			(layer "B.Fab")
		)
		(fp_line
			(start -0.299974 0.150114)
			(end 0.299974 0.150114)
			(stroke
				(width 0.1)
				(type default)
			)
			(layer "B.Fab")
		)
		(pad "1" smd rect
			(at 0.2667 0 270)
			(size 0.3048 0.381)
			(layers "B.Cu" "B.Mask" "B.Paste")
			(net "P0V8_SERDES_VDDA_PEX1")
		)
		(pad "2" smd rect
			(at -0.2667 0 270)
			(size 0.3048 0.381)
			(layers "B.Cu" "B.Mask" "B.Paste")
			(net "GND")
		)
	)
	(footprint ""
		(layer "B.Cu")
		(at 358.834944 -293.506906 90)
		(property "Reference" "PC181"
			(at 0 0 90)
			(layer "B.SilkS")
			(hide yes)
			(effects
				(font
					(size 1.27 1.27)
				)
				(justify mirror)
			)
		)
		(property "Value" ""
			(at 0 0 90)
			(layer "B.Fab")
			(effects
				(font
					(size 1.27 1.27)
				)
				(justify mirror)
			)
		)
		(duplicate_pad_numbers_are_jumpers no)
		(fp_line
			(start 1.524 -0.762)
			(end -1.524 -0.762)
			(stroke
				(width 0.1524)
				(type default)
			)
			(layer "B.SilkS")
		)
		(fp_line
			(start -1.524 -0.762)
			(end -1.524 0.762)
			(stroke
				(width 0.1524)
				(type default)
			)
			(layer "B.SilkS")
		)
		(fp_line
			(start 1.524 0.762)
			(end 1.524 -0.762)
			(stroke
				(width 0.1524)
				(type default)
			)
			(layer "B.SilkS")
		)
		(fp_line
			(start -1.524 0.762)
			(end 1.524 0.762)
			(stroke
				(width 0.1524)
				(type default)
			)
			(layer "B.SilkS")
		)
		(fp_line
			(start 1.1049 -0.724916)
			(end 1.1049 0.724916)
			(stroke
				(width 0.1)
				(type default)
			)
			(layer "B.Fab")
		)
		(fp_line
			(start -1.1049 -0.724916)
			(end 1.1049 -0.724916)
			(stroke
				(width 0.1)
				(type default)
			)
			(layer "B.Fab")
		)
		(fp_line
			(start 1.1049 0.724916)
			(end -1.1049 0.724916)
			(stroke
				(width 0.1)
				(type default)
			)
			(layer "B.Fab")
		)
		(fp_line
			(start -1.1049 0.724916)
			(end -1.1049 -0.724916)
			(stroke
				(width 0.1)
				(type default)
			)
			(layer "B.Fab")
		)
		(pad "1" smd rect
			(at 0.889 0 90)
			(size 1.016 1.27)
			(layers "B.Cu" "B.Mask" "B.Paste")
			(net "P0V8_PEX3")
		)
		(pad "2" smd rect
			(at -0.889 0 90)
			(size 1.016 1.27)
			(layers "B.Cu" "B.Mask" "B.Paste")
			(net "GND")
		)
	)
	(footprint ""
		(layer "B.Cu")
		(at 425.841922 -104.120696 180)
		(property "Reference" "R372"
			(at 0 0 0)
			(layer "B.SilkS")
			(hide yes)
			(effects
				(font
					(size 1.27 1.27)
				)
				(justify mirror)
			)
		)
		(property "Value" ""
			(at 0 0 0)
			(layer "B.Fab")
			(effects
				(font
					(size 1.27 1.27)
				)
				(justify mirror)
			)
		)
		(duplicate_pad_numbers_are_jumpers no)
		(fp_line
			(start 0.7874 0.4064)
			(end 0.7874 -0.4064)
			(stroke
				(width 0.1524)
				(type default)
			)
			(layer "B.SilkS")
		)
		(fp_line
			(start 0.7874 -0.4064)
			(end -0.7874 -0.4064)
			(stroke
				(width 0.1524)
				(type default)
			)
			(layer "B.SilkS")
		)
		(fp_line
			(start -0.7874 0.4064)
			(end 0.7874 0.4064)
			(stroke
				(width 0.1524)
				(type default)
			)
			(layer "B.SilkS")
		)
		(fp_line
			(start -0.7874 -0.4064)
			(end -0.7874 0.4064)
			(stroke
				(width 0.1524)
				(type default)
			)
			(layer "B.SilkS")
		)
		(fp_line
			(start 0.67945 0.3048)
			(end 0.67945 -0.305054)
			(stroke
				(width 0.1)
				(type default)
			)
			(layer "B.Fab")
		)
		(fp_line
			(start 0.67945 -0.305054)
			(end 0.12065 -0.305054)
			(stroke
				(width 0.1)
				(type default)
			)
			(layer "B.Fab")
		)
		(fp_line
			(start 0.12065 0.3048)
			(end 0.67945 0.3048)
			(stroke
				(width 0.1)
				(type default)
			)
			(layer "B.Fab")
		)
		(fp_line
			(start 0.12065 0.2794)
			(end 0.12065 0.3048)
			(stroke
				(width 0.1)
				(type default)
			)
			(layer "B.Fab")
		)
		(fp_line
			(start 0.12065 -0.2794)
			(end -0.12065 -0.2794)
			(stroke
				(width 0.1)
				(type default)
			)
			(layer "B.Fab")
		)
		(fp_line
			(start 0.12065 -0.305054)
			(end 0.12065 -0.2794)
			(stroke
				(width 0.1)
				(type default)
			)
			(layer "B.Fab")
		)
		(fp_line
			(start -0.120396 0.3048)
			(end -0.120396 0.2794)
			(stroke
				(width 0.1)
				(type default)
			)
			(layer "B.Fab")
		)
		(fp_line
			(start -0.120396 0.2794)
			(end 0.12065 0.2794)
			(stroke
				(width 0.1)
				(type default)
			)
			(layer "B.Fab")
		)
		(fp_line
			(start -0.12065 -0.2794)
			(end -0.12065 -0.3048)
			(stroke
				(width 0.1)
				(type default)
			)
			(layer "B.Fab")
		)
		(fp_line
			(start -0.12065 -0.3048)
			(end -0.67945 -0.3048)
			(stroke
				(width 0.1)
				(type default)
			)
			(layer "B.Fab")
		)
		(fp_line
			(start -0.67945 0.3048)
			(end -0.120396 0.3048)
			(stroke
				(width 0.1)
				(type default)
			)
			(layer "B.Fab")
		)
		(fp_line
			(start -0.67945 -0.3048)
			(end -0.67945 0.3048)
			(stroke
				(width 0.1)
				(type default)
			)
			(layer "B.Fab")
		)
		(pad "1" smd circle
			(at 0.40005 0)
			(size 0 0)
			(layers "B.Cu" "B.Mask" "B.Paste")
			(net "NCSI_NIC7_CRS_DV")
		)
		(pad "2" smd circle
			(at -0.40005 0)
			(size 0 0)
			(layers "B.Cu" "B.Mask" "B.Paste")
			(net "GND")
		)
	)
	(footprint ""
		(layer "B.Cu")
		(at 125.710188 -261.15391)
		(property "Reference" "PR7141"
			(at 0 0 0)
			(layer "B.SilkS")
			(hide yes)
			(effects
				(font
					(size 1.27 1.27)
				)
				(justify mirror)
			)
		)
		(property "Value" ""
			(at 0 0 0)
			(layer "B.Fab")
			(effects
				(font
					(size 1.27 1.27)
				)
				(justify mirror)
			)
		)
		(duplicate_pad_numbers_are_jumpers no)
		(fp_line
			(start -0.7874 -0.4064)
			(end -0.7874 0.4064)
			(stroke
				(width 0.1524)
				(type default)
			)
			(layer "B.SilkS")
		)
		(fp_line
			(start -0.7874 0.4064)
			(end 0.7874 0.4064)
			(stroke
				(width 0.1524)
				(type default)
			)
			(layer "B.SilkS")
		)
		(fp_line
			(start 0.7874 -0.4064)
			(end -0.7874 -0.4064)
			(stroke
				(width 0.1524)
				(type default)
			)
			(layer "B.SilkS")
		)
		(fp_line
			(start 0.7874 0.4064)
			(end 0.7874 -0.4064)
			(stroke
				(width 0.1524)
				(type default)
			)
			(layer "B.SilkS")
		)
		(fp_line
			(start -0.67945 -0.3048)
			(end -0.67945 0.3048)
			(stroke
				(width 0.1)
				(type default)
			)
			(layer "B.Fab")
		)
		(fp_line
			(start -0.67945 0.3048)
			(end -0.120396 0.3048)
			(stroke
				(width 0.1)
				(type default)
			)
			(layer "B.Fab")
		)
		(fp_line
			(start -0.12065 -0.3048)
			(end -0.67945 -0.3048)
			(stroke
				(width 0.1)
				(type default)
			)
			(layer "B.Fab")
		)
		(fp_line
			(start -0.12065 -0.2794)
			(end -0.12065 -0.3048)
			(stroke
				(width 0.1)
				(type default)
			)
			(layer "B.Fab")
		)
		(fp_line
			(start -0.120396 0.2794)
			(end 0.12065 0.2794)
			(stroke
				(width 0.1)
				(type default)
			)
			(layer "B.Fab")
		)
		(fp_line
			(start -0.120396 0.3048)
			(end -0.120396 0.2794)
			(stroke
				(width 0.1)
				(type default)
			)
			(layer "B.Fab")
		)
		(fp_line
			(start 0.12065 -0.305054)
			(end 0.12065 -0.2794)
			(stroke
				(width 0.1)
				(type default)
			)
			(layer "B.Fab")
		)
		(fp_line
			(start 0.12065 -0.2794)
			(end -0.12065 -0.2794)
			(stroke
				(width 0.1)
				(type default)
			)
			(layer "B.Fab")
		)
		(fp_line
			(start 0.12065 0.2794)
			(end 0.12065 0.3048)
			(stroke
				(width 0.1)
				(type default)
			)
			(layer "B.Fab")
		)
		(fp_line
			(start 0.12065 0.3048)
			(end 0.67945 0.3048)
			(stroke
				(width 0.1)
				(type default)
			)
			(layer "B.Fab")
		)
		(fp_line
			(start 0.67945 -0.305054)
			(end 0.12065 -0.305054)
			(stroke
				(width 0.1)
				(type default)
			)
			(layer "B.Fab")
		)
		(fp_line
			(start 0.67945 0.3048)
			(end 0.67945 -0.305054)
			(stroke
				(width 0.1)
				(type default)
			)
			(layer "B.Fab")
		)
		(pad "1" smd circle
			(at 0.40005 0 180)
			(size 0 0)
			(layers "B.Cu" "B.Mask" "B.Paste")
			(net "GND")
		)
		(pad "2" smd circle
			(at -0.40005 0 180)
			(size 0 0)
			(layers "B.Cu" "B.Mask" "B.Paste")
			(net "P0V8_PEX0_SVID")
		)
	)
	(footprint ""
		(layer "B.Cu")
		(at 170.049952 -288.299906 90)
		(property "Reference" "C3097"
			(at 0 0 90)
			(layer "B.SilkS")
			(hide yes)
			(effects
				(font
					(size 1.27 1.27)
				)
				(justify mirror)
			)
		)
		(property "Value" ""
			(at 0 0 90)
			(layer "B.Fab")
			(effects
				(font
					(size 1.27 1.27)
				)
				(justify mirror)
			)
		)
		(duplicate_pad_numbers_are_jumpers no)
		(fp_line
			(start 0.299974 -0.150114)
			(end -0.299974 -0.150114)
			(stroke
				(width 0.1)
				(type default)
			)
			(layer "B.Fab")
		)
		(fp_line
			(start -0.299974 -0.150114)
			(end -0.299974 0.150114)
			(stroke
				(width 0.1)
				(type default)
			)
			(layer "B.Fab")
		)
		(fp_line
			(start 0.299974 0.150114)
			(end 0.299974 -0.150114)
			(stroke
				(width 0.1)
				(type default)
			)
			(layer "B.Fab")
		)
		(fp_line
			(start -0.299974 0.150114)
			(end 0.299974 0.150114)
			(stroke
				(width 0.1)
				(type default)
			)
			(layer "B.Fab")
		)
		(pad "1" smd rect
			(at 0.2667 0 270)
			(size 0.3048 0.381)
			(layers "B.Cu" "B.Mask" "B.Paste")
			(net "P1V25_PEX1")
		)
		(pad "2" smd rect
			(at -0.2667 0 270)
			(size 0.3048 0.381)
			(layers "B.Cu" "B.Mask" "B.Paste")
			(net "GND")
		)
	)
	(footprint ""
		(layer "B.Cu")
		(at 102.016306 -329.68311)
		(property "Reference" "R4227"
			(at 0 0 0)
			(layer "B.SilkS")
			(hide yes)
			(effects
				(font
					(size 1.27 1.27)
				)
				(justify mirror)
			)
		)
		(property "Value" ""
			(at 0 0 0)
			(layer "B.Fab")
			(effects
				(font
					(size 1.27 1.27)
				)
				(justify mirror)
			)
		)
		(duplicate_pad_numbers_are_jumpers no)
		(fp_line
			(start -0.7874 -0.4064)
			(end -0.7874 0.4064)
			(stroke
				(width 0.1524)
				(type default)
			)
			(layer "B.SilkS")
		)
		(fp_line
			(start -0.7874 0.4064)
			(end 0.7874 0.4064)
			(stroke
				(width 0.1524)
				(type default)
			)
			(layer "B.SilkS")
		)
		(fp_line
			(start 0.7874 -0.4064)
			(end -0.7874 -0.4064)
			(stroke
				(width 0.1524)
				(type default)
			)
			(layer "B.SilkS")
		)
		(fp_line
			(start 0.7874 0.4064)
			(end 0.7874 -0.4064)
			(stroke
				(width 0.1524)
				(type default)
			)
			(layer "B.SilkS")
		)
		(fp_line
			(start -0.67945 -0.3048)
			(end -0.67945 0.3048)
			(stroke
				(width 0.1)
				(type default)
			)
			(layer "B.Fab")
		)
		(fp_line
			(start -0.67945 0.3048)
			(end -0.120396 0.3048)
			(stroke
				(width 0.1)
				(type default)
			)
			(layer "B.Fab")
		)
		(fp_line
			(start -0.12065 -0.3048)
			(end -0.67945 -0.3048)
			(stroke
				(width 0.1)
				(type default)
			)
			(layer "B.Fab")
		)
		(fp_line
			(start -0.12065 -0.2794)
			(end -0.12065 -0.3048)
			(stroke
				(width 0.1)
				(type default)
			)
			(layer "B.Fab")
		)
		(fp_line
			(start -0.120396 0.2794)
			(end 0.12065 0.2794)
			(stroke
				(width 0.1)
				(type default)
			)
			(layer "B.Fab")
		)
		(fp_line
			(start -0.120396 0.3048)
			(end -0.120396 0.2794)
			(stroke
				(width 0.1)
				(type default)
			)
			(layer "B.Fab")
		)
		(fp_line
			(start 0.12065 -0.305054)
			(end 0.12065 -0.2794)
			(stroke
				(width 0.1)
				(type default)
			)
			(layer "B.Fab")
		)
		(fp_line
			(start 0.12065 -0.2794)
			(end -0.12065 -0.2794)
			(stroke
				(width 0.1)
				(type default)
			)
			(layer "B.Fab")
		)
		(fp_line
			(start 0.12065 0.2794)
			(end 0.12065 0.3048)
			(stroke
				(width 0.1)
				(type default)
			)
			(layer "B.Fab")
		)
		(fp_line
			(start 0.12065 0.3048)
			(end 0.67945 0.3048)
			(stroke
				(width 0.1)
				(type default)
			)
			(layer "B.Fab")
		)
		(fp_line
			(start 0.67945 -0.305054)
			(end 0.12065 -0.305054)
			(stroke
				(width 0.1)
				(type default)
			)
			(layer "B.Fab")
		)
		(fp_line
			(start 0.67945 0.3048)
			(end 0.67945 -0.305054)
			(stroke
				(width 0.1)
				(type default)
			)
			(layer "B.Fab")
		)
		(pad "1" smd circle
			(at 0.40005 0 180)
			(size 0 0)
			(layers "B.Cu" "B.Mask" "B.Paste")
			(net "PEX_REF_CLK_BUFFER_EN_N")
		)
		(pad "2" smd circle
			(at -0.40005 0 180)
			(size 0 0)
			(layers "B.Cu" "B.Mask" "B.Paste")
			(net "GND")
		)
	)
	(footprint ""
		(layer "B.Cu")
		(at 228.267768 -221.904052 90)
		(property "Reference" "C2025"
			(at 0 0 90)
			(layer "B.SilkS")
			(hide yes)
			(effects
				(font
					(size 1.27 1.27)
				)
				(justify mirror)
			)
		)
		(property "Value" ""
			(at 0 0 90)
			(layer "B.Fab")
			(effects
				(font
					(size 1.27 1.27)
				)
				(justify mirror)
			)
		)
		(duplicate_pad_numbers_are_jumpers no)
		(fp_line
			(start 0.69215 -0.2921)
			(end -0.69215 -0.2921)
			(stroke
				(width 0.1524)
				(type default)
			)
			(layer "B.SilkS")
		)
		(fp_line
			(start -0.69215 -0.2921)
			(end -0.69215 0.2921)
			(stroke
				(width 0.1524)
				(type default)
			)
			(layer "B.SilkS")
		)
		(fp_line
			(start 0.69215 0.2921)
			(end 0.69215 -0.2921)
			(stroke
				(width 0.1524)
				(type default)
			)
			(layer "B.SilkS")
		)
		(fp_line
			(start -0.69215 0.2921)
			(end 0.69215 0.2921)
			(stroke
				(width 0.1524)
				(type default)
			)
			(layer "B.SilkS")
		)
		(fp_line
			(start 0.51435 -0.2794)
			(end -0.51435 -0.2794)
			(stroke
				(width 0.1)
				(type default)
			)
			(layer "B.Fab")
		)
		(fp_line
			(start -0.51435 -0.2794)
			(end -0.51435 0.2794)
			(stroke
				(width 0.1)
				(type default)
			)
			(layer "B.Fab")
		)
		(fp_line
			(start 0.51435 0.2794)
			(end 0.51435 -0.2794)
			(stroke
				(width 0.1)
				(type default)
			)
			(layer "B.Fab")
		)
		(fp_line
			(start -0.51435 0.2794)
			(end 0.51435 0.2794)
			(stroke
				(width 0.1)
				(type default)
			)
			(layer "B.Fab")
		)
		(pad "1" smd circle
			(at 0.40005 0 270)
			(size 0 0)
			(layers "B.Cu" "B.Mask" "B.Paste")
			(net "P3V3_AUX")
		)
		(pad "2" smd circle
			(at -0.40005 0 270)
			(size 0 0)
			(layers "B.Cu" "B.Mask" "B.Paste")
			(net "GND")
		)
		(zone
			(layer "B.Cu")
			(hatch none 0.5)
			(connect_pads
				(clearance 0)
			)
			(min_thickness 0.25)
			(keepout
				(tracks not_allowed)
				(vias allowed)
				(pads allowed)
				(copperpour not_allowed)
				(footprints allowed)
			)
			(placement
				(enabled no)
				(sheetname "")
			)
			(fill
				(thermal_gap 0.5)
				(thermal_bridge_width 0.5)
				(island_removal_mode 0)
			)
			(polygon
				(pts
					(xy 228.355398 -222.094552) (xy 228.413564 -222.003112) (xy 228.413564 -221.803722) (xy 228.355398 -221.713552)
					(xy 228.180138 -221.713552) (xy 228.121718 -221.803722) (xy 228.121718 -222.003112) (xy 228.179884 -222.094552)
				)
			)
		)
	)
	(footprint ""
		(layer "B.Cu")
		(at 367.938812 -222.214186)
		(property "Reference" "R3502"
			(at 0 0 0)
			(layer "B.SilkS")
			(hide yes)
			(effects
				(font
					(size 1.27 1.27)
				)
				(justify mirror)
			)
		)
		(property "Value" ""
			(at 0 0 0)
			(layer "B.Fab")
			(effects
				(font
					(size 1.27 1.27)
				)
				(justify mirror)
			)
		)
		(duplicate_pad_numbers_are_jumpers no)
		(fp_line
			(start -0.7874 -0.4064)
			(end -0.7874 0.4064)
			(stroke
				(width 0.1524)
				(type default)
			)
			(layer "B.SilkS")
		)
		(fp_line
			(start -0.7874 0.4064)
			(end 0.7874 0.4064)
			(stroke
				(width 0.1524)
				(type default)
			)
			(layer "B.SilkS")
		)
		(fp_line
			(start 0.7874 -0.4064)
			(end -0.7874 -0.4064)
			(stroke
				(width 0.1524)
				(type default)
			)
			(layer "B.SilkS")
		)
		(fp_line
			(start 0.7874 0.4064)
			(end 0.7874 -0.4064)
			(stroke
				(width 0.1524)
				(type default)
			)
			(layer "B.SilkS")
		)
		(fp_line
			(start -0.67945 -0.3048)
			(end -0.67945 0.3048)
			(stroke
				(width 0.1)
				(type default)
			)
			(layer "B.Fab")
		)
		(fp_line
			(start -0.67945 0.3048)
			(end -0.120396 0.3048)
			(stroke
				(width 0.1)
				(type default)
			)
			(layer "B.Fab")
		)
		(fp_line
			(start -0.12065 -0.3048)
			(end -0.67945 -0.3048)
			(stroke
				(width 0.1)
				(type default)
			)
			(layer "B.Fab")
		)
		(fp_line
			(start -0.12065 -0.2794)
			(end -0.12065 -0.3048)
			(stroke
				(width 0.1)
				(type default)
			)
			(layer "B.Fab")
		)
		(fp_line
			(start -0.120396 0.2794)
			(end 0.12065 0.2794)
			(stroke
				(width 0.1)
				(type default)
			)
			(layer "B.Fab")
		)
		(fp_line
			(start -0.120396 0.3048)
			(end -0.120396 0.2794)
			(stroke
				(width 0.1)
				(type default)
			)
			(layer "B.Fab")
		)
		(fp_line
			(start 0.12065 -0.305054)
			(end 0.12065 -0.2794)
			(stroke
				(width 0.1)
				(type default)
			)
			(layer "B.Fab")
		)
		(fp_line
			(start 0.12065 -0.2794)
			(end -0.12065 -0.2794)
			(stroke
				(width 0.1)
				(type default)
			)
			(layer "B.Fab")
		)
		(fp_line
			(start 0.12065 0.2794)
			(end 0.12065 0.3048)
			(stroke
				(width 0.1)
				(type default)
			)
			(layer "B.Fab")
		)
		(fp_line
			(start 0.12065 0.3048)
			(end 0.67945 0.3048)
			(stroke
				(width 0.1)
				(type default)
			)
			(layer "B.Fab")
		)
		(fp_line
			(start 0.67945 -0.305054)
			(end 0.12065 -0.305054)
			(stroke
				(width 0.1)
				(type default)
			)
			(layer "B.Fab")
		)
		(fp_line
			(start 0.67945 0.3048)
			(end 0.67945 -0.305054)
			(stroke
				(width 0.1)
				(type default)
			)
			(layer "B.Fab")
		)
		(pad "1" smd circle
			(at 0.40005 0 180)
			(size 0 0)
			(layers "B.Cu" "B.Mask" "B.Paste")
			(net "SPI_PEX3_SDIO0_MUX")
		)
		(pad "2" smd circle
			(at -0.40005 0 180)
			(size 0 0)
			(layers "B.Cu" "B.Mask" "B.Paste")
			(net "SPI_PEX3_SDIO0_MUX_R")
		)
	)
	(footprint ""
		(layer "B.Cu")
		(at 349.123 -233.553 -90)
		(property "Reference" "R3604"
			(at 0 0 90)
			(layer "B.SilkS")
			(hide yes)
			(effects
				(font
					(size 1.27 1.27)
				)
				(justify mirror)
			)
		)
		(property "Value" ""
			(at 0 0 90)
			(layer "B.Fab")
			(effects
				(font
					(size 1.27 1.27)
				)
				(justify mirror)
			)
		)
		(duplicate_pad_numbers_are_jumpers no)
		(fp_line
			(start -0.7874 0.4064)
			(end 0.7874 0.4064)
			(stroke
				(width 0.1524)
				(type default)
			)
			(layer "B.SilkS")
		)
		(fp_line
			(start 0.7874 0.4064)
			(end 0.7874 -0.4064)
			(stroke
				(width 0.1524)
				(type default)
			)
			(layer "B.SilkS")
		)
		(fp_line
			(start -0.7874 -0.4064)
			(end -0.7874 0.4064)
			(stroke
				(width 0.1524)
				(type default)
			)
			(layer "B.SilkS")
		)
		(fp_line
			(start 0.7874 -0.4064)
			(end -0.7874 -0.4064)
			(stroke
				(width 0.1524)
				(type default)
			)
			(layer "B.SilkS")
		)
		(fp_line
			(start -0.67945 0.3048)
			(end -0.120396 0.3048)
			(stroke
				(width 0.1)
				(type default)
			)
			(layer "B.Fab")
		)
		(fp_line
			(start -0.120396 0.3048)
			(end -0.120396 0.2794)
			(stroke
				(width 0.1)
				(type default)
			)
			(layer "B.Fab")
		)
		(fp_line
			(start 0.12065 0.3048)
			(end 0.67945 0.3048)
			(stroke
				(width 0.1)
				(type default)
			)
			(layer "B.Fab")
		)
		(fp_line
			(start 0.67945 0.3048)
			(end 0.67945 -0.305054)
			(stroke
				(width 0.1)
				(type default)
			)
			(layer "B.Fab")
		)
		(fp_line
			(start -0.120396 0.2794)
			(end 0.12065 0.2794)
			(stroke
				(width 0.1)
				(type default)
			)
			(layer "B.Fab")
		)
		(fp_line
			(start 0.12065 0.2794)
			(end 0.12065 0.3048)
			(stroke
				(width 0.1)
				(type default)
			)
			(layer "B.Fab")
		)
		(fp_line
			(start -0.12065 -0.2794)
			(end -0.12065 -0.3048)
			(stroke
				(width 0.1)
				(type default)
			)
			(layer "B.Fab")
		)
		(fp_line
			(start 0.12065 -0.2794)
			(end -0.12065 -0.2794)
			(stroke
				(width 0.1)
				(type default)
			)
			(layer "B.Fab")
		)
		(fp_line
			(start -0.67945 -0.3048)
			(end -0.67945 0.3048)
			(stroke
				(width 0.1)
				(type default)
			)
			(layer "B.Fab")
		)
		(fp_line
			(start -0.12065 -0.3048)
			(end -0.67945 -0.3048)
			(stroke
				(width 0.1)
				(type default)
			)
			(layer "B.Fab")
		)
		(fp_line
			(start 0.12065 -0.305054)
			(end 0.12065 -0.2794)
			(stroke
				(width 0.1)
				(type default)
			)
			(layer "B.Fab")
		)
		(fp_line
			(start 0.67945 -0.305054)
			(end 0.12065 -0.305054)
			(stroke
				(width 0.1)
				(type default)
			)
			(layer "B.Fab")
		)
		(pad "1" smd circle
			(at 0.40005 0 90)
			(size 0 0)
			(layers "B.Cu" "B.Mask" "B.Paste")
			(net "RST_NIC0_PERST_N")
		)
		(pad "2" smd circle
			(at -0.40005 0 90)
			(size 0 0)
			(layers "B.Cu" "B.Mask" "B.Paste")
			(net "RST_NIC0_PERST_R_N")
		)
	)
	(footprint ""
		(layer "B.Cu")
		(at 392.749786 -299.224954)
		(property "Reference" "C3535"
			(at 0 0 0)
			(layer "B.SilkS")
			(hide yes)
			(effects
				(font
					(size 1.27 1.27)
				)
				(justify mirror)
			)
		)
		(property "Value" ""
			(at 0 0 0)
			(layer "B.Fab")
			(effects
				(font
					(size 1.27 1.27)
				)
				(justify mirror)
			)
		)
		(duplicate_pad_numbers_are_jumpers no)
		(fp_line
			(start -0.299974 -0.150114)
			(end -0.299974 0.150114)
			(stroke
				(width 0.1)
				(type default)
			)
			(layer "B.Fab")
		)
		(fp_line
			(start -0.299974 0.150114)
			(end 0.299974 0.150114)
			(stroke
				(width 0.1)
				(type default)
			)
			(layer "B.Fab")
		)
		(fp_line
			(start 0.299974 -0.150114)
			(end -0.299974 -0.150114)
			(stroke
				(width 0.1)
				(type default)
			)
			(layer "B.Fab")
		)
		(fp_line
			(start 0.299974 0.150114)
			(end 0.299974 -0.150114)
			(stroke
				(width 0.1)
				(type default)
			)
			(layer "B.Fab")
		)
		(pad "1" smd rect
			(at 0.2667 0 180)
			(size 0.3048 0.381)
			(layers "B.Cu" "B.Mask" "B.Paste")
			(net "P1V8_VDDA_PEX3")
		)
		(pad "2" smd rect
			(at -0.2667 0 180)
			(size 0.3048 0.381)
			(layers "B.Cu" "B.Mask" "B.Paste")
			(net "GND")
		)
	)
	(footprint ""
		(layer "B.Cu")
		(at 289.08375 -308.724808 -90)
		(property "Reference" "R1392"
			(at 0 0 90)
			(layer "B.SilkS")
			(hide yes)
			(effects
				(font
					(size 1.27 1.27)
				)
				(justify mirror)
			)
		)
		(property "Value" ""
			(at 0 0 90)
			(layer "B.Fab")
			(effects
				(font
					(size 1.27 1.27)
				)
				(justify mirror)
			)
		)
		(duplicate_pad_numbers_are_jumpers no)
		(fp_line
			(start -0.7874 0.4064)
			(end 0.7874 0.4064)
			(stroke
				(width 0.1524)
				(type default)
			)
			(layer "B.SilkS")
		)
		(fp_line
			(start 0.7874 0.4064)
			(end 0.7874 -0.4064)
			(stroke
				(width 0.1524)
				(type default)
			)
			(layer "B.SilkS")
		)
		(fp_line
			(start -0.7874 -0.4064)
			(end -0.7874 0.4064)
			(stroke
				(width 0.1524)
				(type default)
			)
			(layer "B.SilkS")
		)
		(fp_line
			(start 0.7874 -0.4064)
			(end -0.7874 -0.4064)
			(stroke
				(width 0.1524)
				(type default)
			)
			(layer "B.SilkS")
		)
		(fp_line
			(start -0.67945 0.3048)
			(end -0.120396 0.3048)
			(stroke
				(width 0.1)
				(type default)
			)
			(layer "B.Fab")
		)
		(fp_line
			(start -0.120396 0.3048)
			(end -0.120396 0.2794)
			(stroke
				(width 0.1)
				(type default)
			)
			(layer "B.Fab")
		)
		(fp_line
			(start 0.12065 0.3048)
			(end 0.67945 0.3048)
			(stroke
				(width 0.1)
				(type default)
			)
			(layer "B.Fab")
		)
		(fp_line
			(start 0.67945 0.3048)
			(end 0.67945 -0.305054)
			(stroke
				(width 0.1)
				(type default)
			)
			(layer "B.Fab")
		)
		(fp_line
			(start -0.120396 0.2794)
			(end 0.12065 0.2794)
			(stroke
				(width 0.1)
				(type default)
			)
			(layer "B.Fab")
		)
		(fp_line
			(start 0.12065 0.2794)
			(end 0.12065 0.3048)
			(stroke
				(width 0.1)
				(type default)
			)
			(layer "B.Fab")
		)
		(fp_line
			(start -0.12065 -0.2794)
			(end -0.12065 -0.3048)
			(stroke
				(width 0.1)
				(type default)
			)
			(layer "B.Fab")
		)
		(fp_line
			(start 0.12065 -0.2794)
			(end -0.12065 -0.2794)
			(stroke
				(width 0.1)
				(type default)
			)
			(layer "B.Fab")
		)
		(fp_line
			(start -0.67945 -0.3048)
			(end -0.67945 0.3048)
			(stroke
				(width 0.1)
				(type default)
			)
			(layer "B.Fab")
		)
		(fp_line
			(start -0.12065 -0.3048)
			(end -0.67945 -0.3048)
			(stroke
				(width 0.1)
				(type default)
			)
			(layer "B.Fab")
		)
		(fp_line
			(start 0.12065 -0.305054)
			(end 0.12065 -0.2794)
			(stroke
				(width 0.1)
				(type default)
			)
			(layer "B.Fab")
		)
		(fp_line
			(start 0.67945 -0.305054)
			(end 0.12065 -0.305054)
			(stroke
				(width 0.1)
				(type default)
			)
			(layer "B.Fab")
		)
		(pad "1" smd circle
			(at 0.40005 0 90)
			(size 0 0)
			(layers "B.Cu" "B.Mask" "B.Paste")
			(net "TP_PEX2_TRST_L")
		)
		(pad "2" smd circle
			(at -0.40005 0 90)
			(size 0 0)
			(layers "B.Cu" "B.Mask" "B.Paste")
			(net "GND")
		)
	)
	(footprint ""
		(layer "B.Cu")
		(at 56.883808 -308.724808 -90)
		(property "Reference" "R1256"
			(at 0 0 90)
			(layer "B.SilkS")
			(hide yes)
			(effects
				(font
					(size 1.27 1.27)
				)
				(justify mirror)
			)
		)
		(property "Value" ""
			(at 0 0 90)
			(layer "B.Fab")
			(effects
				(font
					(size 1.27 1.27)
				)
				(justify mirror)
			)
		)
		(duplicate_pad_numbers_are_jumpers no)
		(fp_line
			(start -0.7874 0.4064)
			(end 0.7874 0.4064)
			(stroke
				(width 0.1524)
				(type default)
			)
			(layer "B.SilkS")
		)
		(fp_line
			(start 0.7874 0.4064)
			(end 0.7874 -0.4064)
			(stroke
				(width 0.1524)
				(type default)
			)
			(layer "B.SilkS")
		)
		(fp_line
			(start -0.7874 -0.4064)
			(end -0.7874 0.4064)
			(stroke
				(width 0.1524)
				(type default)
			)
			(layer "B.SilkS")
		)
		(fp_line
			(start 0.7874 -0.4064)
			(end -0.7874 -0.4064)
			(stroke
				(width 0.1524)
				(type default)
			)
			(layer "B.SilkS")
		)
		(fp_line
			(start -0.67945 0.3048)
			(end -0.120396 0.3048)
			(stroke
				(width 0.1)
				(type default)
			)
			(layer "B.Fab")
		)
		(fp_line
			(start -0.120396 0.3048)
			(end -0.120396 0.2794)
			(stroke
				(width 0.1)
				(type default)
			)
			(layer "B.Fab")
		)
		(fp_line
			(start 0.12065 0.3048)
			(end 0.67945 0.3048)
			(stroke
				(width 0.1)
				(type default)
			)
			(layer "B.Fab")
		)
		(fp_line
			(start 0.67945 0.3048)
			(end 0.67945 -0.305054)
			(stroke
				(width 0.1)
				(type default)
			)
			(layer "B.Fab")
		)
		(fp_line
			(start -0.120396 0.2794)
			(end 0.12065 0.2794)
			(stroke
				(width 0.1)
				(type default)
			)
			(layer "B.Fab")
		)
		(fp_line
			(start 0.12065 0.2794)
			(end 0.12065 0.3048)
			(stroke
				(width 0.1)
				(type default)
			)
			(layer "B.Fab")
		)
		(fp_line
			(start -0.12065 -0.2794)
			(end -0.12065 -0.3048)
			(stroke
				(width 0.1)
				(type default)
			)
			(layer "B.Fab")
		)
		(fp_line
			(start 0.12065 -0.2794)
			(end -0.12065 -0.2794)
			(stroke
				(width 0.1)
				(type default)
			)
			(layer "B.Fab")
		)
		(fp_line
			(start -0.67945 -0.3048)
			(end -0.67945 0.3048)
			(stroke
				(width 0.1)
				(type default)
			)
			(layer "B.Fab")
		)
		(fp_line
			(start -0.12065 -0.3048)
			(end -0.67945 -0.3048)
			(stroke
				(width 0.1)
				(type default)
			)
			(layer "B.Fab")
		)
		(fp_line
			(start 0.12065 -0.305054)
			(end 0.12065 -0.2794)
			(stroke
				(width 0.1)
				(type default)
			)
			(layer "B.Fab")
		)
		(fp_line
			(start 0.67945 -0.305054)
			(end 0.12065 -0.305054)
			(stroke
				(width 0.1)
				(type default)
			)
			(layer "B.Fab")
		)
		(pad "1" smd circle
			(at 0.40005 0 90)
			(size 0 0)
			(layers "B.Cu" "B.Mask" "B.Paste")
			(net "TP_PEX0_TRST_L")
		)
		(pad "2" smd circle
			(at -0.40005 0 90)
			(size 0 0)
			(layers "B.Cu" "B.Mask" "B.Paste")
			(net "GND")
		)
	)
	(footprint ""
		(layer "B.Cu")
		(at 229.434644 -231.225598 90)
		(property "Reference" "R4554"
			(at 0 0 90)
			(layer "B.SilkS")
			(hide yes)
			(effects
				(font
					(size 1.27 1.27)
				)
				(justify mirror)
			)
		)
		(property "Value" ""
			(at 0 0 90)
			(layer "B.Fab")
			(effects
				(font
					(size 1.27 1.27)
				)
				(justify mirror)
			)
		)
		(duplicate_pad_numbers_are_jumpers no)
		(fp_line
			(start 0.7874 -0.4064)
			(end -0.7874 -0.4064)
			(stroke
				(width 0.1524)
				(type default)
			)
			(layer "B.SilkS")
		)
		(fp_line
			(start -0.7874 -0.4064)
			(end -0.7874 0.4064)
			(stroke
				(width 0.1524)
				(type default)
			)
			(layer "B.SilkS")
		)
		(fp_line
			(start 0.7874 0.4064)
			(end 0.7874 -0.4064)
			(stroke
				(width 0.1524)
				(type default)
			)
			(layer "B.SilkS")
		)
		(fp_line
			(start -0.7874 0.4064)
			(end 0.7874 0.4064)
			(stroke
				(width 0.1524)
				(type default)
			)
			(layer "B.SilkS")
		)
		(fp_line
			(start 0.67945 -0.305054)
			(end 0.12065 -0.305054)
			(stroke
				(width 0.1)
				(type default)
			)
			(layer "B.Fab")
		)
		(fp_line
			(start 0.12065 -0.305054)
			(end 0.12065 -0.2794)
			(stroke
				(width 0.1)
				(type default)
			)
			(layer "B.Fab")
		)
		(fp_line
			(start -0.12065 -0.3048)
			(end -0.67945 -0.3048)
			(stroke
				(width 0.1)
				(type default)
			)
			(layer "B.Fab")
		)
		(fp_line
			(start -0.67945 -0.3048)
			(end -0.67945 0.3048)
			(stroke
				(width 0.1)
				(type default)
			)
			(layer "B.Fab")
		)
		(fp_line
			(start 0.12065 -0.2794)
			(end -0.12065 -0.2794)
			(stroke
				(width 0.1)
				(type default)
			)
			(layer "B.Fab")
		)
		(fp_line
			(start -0.12065 -0.2794)
			(end -0.12065 -0.3048)
			(stroke
				(width 0.1)
				(type default)
			)
			(layer "B.Fab")
		)
		(fp_line
			(start 0.12065 0.2794)
			(end 0.12065 0.3048)
			(stroke
				(width 0.1)
				(type default)
			)
			(layer "B.Fab")
		)
		(fp_line
			(start -0.120396 0.2794)
			(end 0.12065 0.2794)
			(stroke
				(width 0.1)
				(type default)
			)
			(layer "B.Fab")
		)
		(fp_line
			(start 0.67945 0.3048)
			(end 0.67945 -0.305054)
			(stroke
				(width 0.1)
				(type default)
			)
			(layer "B.Fab")
		)
		(fp_line
			(start 0.12065 0.3048)
			(end 0.67945 0.3048)
			(stroke
				(width 0.1)
				(type default)
			)
			(layer "B.Fab")
		)
		(fp_line
			(start -0.120396 0.3048)
			(end -0.120396 0.2794)
			(stroke
				(width 0.1)
				(type default)
			)
			(layer "B.Fab")
		)
		(fp_line
			(start -0.67945 0.3048)
			(end -0.120396 0.3048)
			(stroke
				(width 0.1)
				(type default)
			)
			(layer "B.Fab")
		)
		(pad "1" smd circle
			(at 0.40005 0 270)
			(size 0 0)
			(layers "B.Cu" "B.Mask" "B.Paste")
			(net "GND")
		)
		(pad "2" smd circle
			(at -0.40005 0 270)
			(size 0 0)
			(layers "B.Cu" "B.Mask" "B.Paste")
			(net "BOARD_ID1")
		)
	)
	(footprint ""
		(layer "B.Cu")
		(at 181.44998 -303.499774 -90)
		(property "Reference" "C3083"
			(at 0 0 90)
			(layer "B.SilkS")
			(hide yes)
			(effects
				(font
					(size 1.27 1.27)
				)
				(justify mirror)
			)
		)
		(property "Value" ""
			(at 0 0 90)
			(layer "B.Fab")
			(effects
				(font
					(size 1.27 1.27)
				)
				(justify mirror)
			)
		)
		(duplicate_pad_numbers_are_jumpers no)
		(fp_line
			(start -0.299974 0.150114)
			(end 0.299974 0.150114)
			(stroke
				(width 0.1)
				(type default)
			)
			(layer "B.Fab")
		)
		(fp_line
			(start 0.299974 0.150114)
			(end 0.299974 -0.150114)
			(stroke
				(width 0.1)
				(type default)
			)
			(layer "B.Fab")
		)
		(fp_line
			(start -0.299974 -0.150114)
			(end -0.299974 0.150114)
			(stroke
				(width 0.1)
				(type default)
			)
			(layer "B.Fab")
		)
		(fp_line
			(start 0.299974 -0.150114)
			(end -0.299974 -0.150114)
			(stroke
				(width 0.1)
				(type default)
			)
			(layer "B.Fab")
		)
		(pad "1" smd rect
			(at 0.2667 0 90)
			(size 0.3048 0.381)
			(layers "B.Cu" "B.Mask" "B.Paste")
			(net "P1V25_PEX1")
		)
		(pad "2" smd rect
			(at -0.2667 0 90)
			(size 0.3048 0.381)
			(layers "B.Cu" "B.Mask" "B.Paste")
			(net "GND")
		)
	)
	(footprint ""
		(layer "B.Cu")
		(at 397.49984 -290.674806 180)
		(property "Reference" "C1871"
			(at 0 0 0)
			(layer "B.SilkS")
			(hide yes)
			(effects
				(font
					(size 1.27 1.27)
				)
				(justify mirror)
			)
		)
		(property "Value" ""
			(at 0 0 0)
			(layer "B.Fab")
			(effects
				(font
					(size 1.27 1.27)
				)
				(justify mirror)
			)
		)
		(duplicate_pad_numbers_are_jumpers no)
		(fp_line
			(start 0.299974 0.150114)
			(end 0.299974 -0.150114)
			(stroke
				(width 0.1)
				(type default)
			)
			(layer "B.Fab")
		)
		(fp_line
			(start 0.299974 -0.150114)
			(end -0.299974 -0.150114)
			(stroke
				(width 0.1)
				(type default)
			)
			(layer "B.Fab")
		)
		(fp_line
			(start -0.299974 0.150114)
			(end 0.299974 0.150114)
			(stroke
				(width 0.1)
				(type default)
			)
			(layer "B.Fab")
		)
		(fp_line
			(start -0.299974 -0.150114)
			(end -0.299974 0.150114)
			(stroke
				(width 0.1)
				(type default)
			)
			(layer "B.Fab")
		)
		(pad "1" smd rect
			(at 0.2667 0)
			(size 0.3048 0.381)
			(layers "B.Cu" "B.Mask" "B.Paste")
			(net "P0V8_PEX3")
		)
		(pad "2" smd rect
			(at -0.2667 0)
			(size 0.3048 0.381)
			(layers "B.Cu" "B.Mask" "B.Paste")
			(net "GND")
		)
	)
	(footprint ""
		(layer "B.Cu")
		(at 147.1676 -244.298216 180)
		(property "Reference" "R6575"
			(at 0 0 0)
			(layer "B.SilkS")
			(hide yes)
			(effects
				(font
					(size 1.27 1.27)
				)
				(justify mirror)
			)
		)
		(property "Value" ""
			(at 0 0 0)
			(layer "B.Fab")
			(effects
				(font
					(size 1.27 1.27)
				)
				(justify mirror)
			)
		)
		(duplicate_pad_numbers_are_jumpers no)
		(fp_line
			(start 0.7874 0.4064)
			(end 0.7874 -0.4064)
			(stroke
				(width 0.1524)
				(type default)
			)
			(layer "B.SilkS")
		)
		(fp_line
			(start 0.7874 -0.4064)
			(end -0.7874 -0.4064)
			(stroke
				(width 0.1524)
				(type default)
			)
			(layer "B.SilkS")
		)
		(fp_line
			(start -0.7874 0.4064)
			(end 0.7874 0.4064)
			(stroke
				(width 0.1524)
				(type default)
			)
			(layer "B.SilkS")
		)
		(fp_line
			(start -0.7874 -0.4064)
			(end -0.7874 0.4064)
			(stroke
				(width 0.1524)
				(type default)
			)
			(layer "B.SilkS")
		)
		(fp_line
			(start 0.67945 0.3048)
			(end 0.67945 -0.305054)
			(stroke
				(width 0.1)
				(type default)
			)
			(layer "B.Fab")
		)
		(fp_line
			(start 0.67945 -0.305054)
			(end 0.12065 -0.305054)
			(stroke
				(width 0.1)
				(type default)
			)
			(layer "B.Fab")
		)
		(fp_line
			(start 0.12065 0.3048)
			(end 0.67945 0.3048)
			(stroke
				(width 0.1)
				(type default)
			)
			(layer "B.Fab")
		)
		(fp_line
			(start 0.12065 0.2794)
			(end 0.12065 0.3048)
			(stroke
				(width 0.1)
				(type default)
			)
			(layer "B.Fab")
		)
		(fp_line
			(start 0.12065 -0.2794)
			(end -0.12065 -0.2794)
			(stroke
				(width 0.1)
				(type default)
			)
			(layer "B.Fab")
		)
		(fp_line
			(start 0.12065 -0.305054)
			(end 0.12065 -0.2794)
			(stroke
				(width 0.1)
				(type default)
			)
			(layer "B.Fab")
		)
		(fp_line
			(start -0.120396 0.3048)
			(end -0.120396 0.2794)
			(stroke
				(width 0.1)
				(type default)
			)
			(layer "B.Fab")
		)
		(fp_line
			(start -0.120396 0.2794)
			(end 0.12065 0.2794)
			(stroke
				(width 0.1)
				(type default)
			)
			(layer "B.Fab")
		)
		(fp_line
			(start -0.12065 -0.2794)
			(end -0.12065 -0.3048)
			(stroke
				(width 0.1)
				(type default)
			)
			(layer "B.Fab")
		)
		(fp_line
			(start -0.12065 -0.3048)
			(end -0.67945 -0.3048)
			(stroke
				(width 0.1)
				(type default)
			)
			(layer "B.Fab")
		)
		(fp_line
			(start -0.67945 0.3048)
			(end -0.120396 0.3048)
			(stroke
				(width 0.1)
				(type default)
			)
			(layer "B.Fab")
		)
		(fp_line
			(start -0.67945 -0.3048)
			(end -0.67945 0.3048)
			(stroke
				(width 0.1)
				(type default)
			)
			(layer "B.Fab")
		)
		(pad "1" smd circle
			(at 0.40005 0)
			(size 0 0)
			(layers "B.Cu" "B.Mask" "B.Paste")
			(net "P3V3_AUX")
		)
		(pad "2" smd circle
			(at -0.40005 0)
			(size 0 0)
			(layers "B.Cu" "B.Mask" "B.Paste")
			(net "PWRGD_PEX1_P1V8_PLL")
		)
	)
	(footprint ""
		(layer "B.Cu")
		(at 62.66053 -161.211006 -90)
		(property "Reference" "R51"
			(at 0 0 90)
			(layer "B.SilkS")
			(hide yes)
			(effects
				(font
					(size 1.27 1.27)
				)
				(justify mirror)
			)
		)
		(property "Value" ""
			(at 0 0 90)
			(layer "B.Fab")
			(effects
				(font
					(size 1.27 1.27)
				)
				(justify mirror)
			)
		)
		(duplicate_pad_numbers_are_jumpers no)
		(fp_line
			(start -0.7874 0.4064)
			(end 0.7874 0.4064)
			(stroke
				(width 0.1524)
				(type default)
			)
			(layer "B.SilkS")
		)
		(fp_line
			(start 0.7874 0.4064)
			(end 0.7874 -0.4064)
			(stroke
				(width 0.1524)
				(type default)
			)
			(layer "B.SilkS")
		)
		(fp_line
			(start -0.7874 -0.4064)
			(end -0.7874 0.4064)
			(stroke
				(width 0.1524)
				(type default)
			)
			(layer "B.SilkS")
		)
		(fp_line
			(start 0.7874 -0.4064)
			(end -0.7874 -0.4064)
			(stroke
				(width 0.1524)
				(type default)
			)
			(layer "B.SilkS")
		)
		(fp_line
			(start -0.67945 0.3048)
			(end -0.120396 0.3048)
			(stroke
				(width 0.1)
				(type default)
			)
			(layer "B.Fab")
		)
		(fp_line
			(start -0.120396 0.3048)
			(end -0.120396 0.2794)
			(stroke
				(width 0.1)
				(type default)
			)
			(layer "B.Fab")
		)
		(fp_line
			(start 0.12065 0.3048)
			(end 0.67945 0.3048)
			(stroke
				(width 0.1)
				(type default)
			)
			(layer "B.Fab")
		)
		(fp_line
			(start 0.67945 0.3048)
			(end 0.67945 -0.305054)
			(stroke
				(width 0.1)
				(type default)
			)
			(layer "B.Fab")
		)
		(fp_line
			(start -0.120396 0.2794)
			(end 0.12065 0.2794)
			(stroke
				(width 0.1)
				(type default)
			)
			(layer "B.Fab")
		)
		(fp_line
			(start 0.12065 0.2794)
			(end 0.12065 0.3048)
			(stroke
				(width 0.1)
				(type default)
			)
			(layer "B.Fab")
		)
		(fp_line
			(start -0.12065 -0.2794)
			(end -0.12065 -0.3048)
			(stroke
				(width 0.1)
				(type default)
			)
			(layer "B.Fab")
		)
		(fp_line
			(start 0.12065 -0.2794)
			(end -0.12065 -0.2794)
			(stroke
				(width 0.1)
				(type default)
			)
			(layer "B.Fab")
		)
		(fp_line
			(start -0.67945 -0.3048)
			(end -0.67945 0.3048)
			(stroke
				(width 0.1)
				(type default)
			)
			(layer "B.Fab")
		)
		(fp_line
			(start -0.12065 -0.3048)
			(end -0.67945 -0.3048)
			(stroke
				(width 0.1)
				(type default)
			)
			(layer "B.Fab")
		)
		(fp_line
			(start 0.12065 -0.305054)
			(end 0.12065 -0.2794)
			(stroke
				(width 0.1)
				(type default)
			)
			(layer "B.Fab")
		)
		(fp_line
			(start 0.67945 -0.305054)
			(end 0.12065 -0.305054)
			(stroke
				(width 0.1)
				(type default)
			)
			(layer "B.Fab")
		)
		(pad "1" smd circle
			(at 0.40005 0 90)
			(size 0 0)
			(layers "B.Cu" "B.Mask" "B.Paste")
			(net "HP_NIC0_PWRGD_R")
		)
		(pad "2" smd circle
			(at -0.40005 0 90)
			(size 0 0)
			(layers "B.Cu" "B.Mask" "B.Paste")
			(net "HP_NIC0_PWRGD")
		)
	)
	(footprint ""
		(layer "B.Cu")
		(at 65.349882 -299.699934 -90)
		(property "Reference" "C1173"
			(at 0 0 90)
			(layer "B.SilkS")
			(hide yes)
			(effects
				(font
					(size 1.27 1.27)
				)
				(justify mirror)
			)
		)
		(property "Value" ""
			(at 0 0 90)
			(layer "B.Fab")
			(effects
				(font
					(size 1.27 1.27)
				)
				(justify mirror)
			)
		)
		(duplicate_pad_numbers_are_jumpers no)
		(fp_line
			(start -0.299974 0.150114)
			(end 0.299974 0.150114)
			(stroke
				(width 0.1)
				(type default)
			)
			(layer "B.Fab")
		)
		(fp_line
			(start 0.299974 0.150114)
			(end 0.299974 -0.150114)
			(stroke
				(width 0.1)
				(type default)
			)
			(layer "B.Fab")
		)
		(fp_line
			(start -0.299974 -0.150114)
			(end -0.299974 0.150114)
			(stroke
				(width 0.1)
				(type default)
			)
			(layer "B.Fab")
		)
		(fp_line
			(start 0.299974 -0.150114)
			(end -0.299974 -0.150114)
			(stroke
				(width 0.1)
				(type default)
			)
			(layer "B.Fab")
		)
		(pad "1" smd rect
			(at 0.2667 0 90)
			(size 0.3048 0.381)
			(layers "B.Cu" "B.Mask" "B.Paste")
			(net "P0V8_SERDES_VDDA_PEX0")
		)
		(pad "2" smd rect
			(at -0.2667 0 90)
			(size 0.3048 0.381)
			(layers "B.Cu" "B.Mask" "B.Paste")
			(net "GND")
		)
	)
	(footprint ""
		(layer "B.Cu")
		(at 284.249876 -290.199826 90)
		(property "Reference" "C1688"
			(at 0 0 90)
			(layer "B.SilkS")
			(hide yes)
			(effects
				(font
					(size 1.27 1.27)
				)
				(justify mirror)
			)
		)
		(property "Value" ""
			(at 0 0 90)
			(layer "B.Fab")
			(effects
				(font
					(size 1.27 1.27)
				)
				(justify mirror)
			)
		)
		(duplicate_pad_numbers_are_jumpers no)
		(fp_line
			(start 0.299974 -0.150114)
			(end -0.299974 -0.150114)
			(stroke
				(width 0.1)
				(type default)
			)
			(layer "B.Fab")
		)
		(fp_line
			(start -0.299974 -0.150114)
			(end -0.299974 0.150114)
			(stroke
				(width 0.1)
				(type default)
			)
			(layer "B.Fab")
		)
		(fp_line
			(start 0.299974 0.150114)
			(end 0.299974 -0.150114)
			(stroke
				(width 0.1)
				(type default)
			)
			(layer "B.Fab")
		)
		(fp_line
			(start -0.299974 0.150114)
			(end 0.299974 0.150114)
			(stroke
				(width 0.1)
				(type default)
			)
			(layer "B.Fab")
		)
		(pad "1" smd rect
			(at 0.2667 0 270)
			(size 0.3048 0.381)
			(layers "B.Cu" "B.Mask" "B.Paste")
			(net "P0V8_SERDES_VDDA_PEX2")
		)
		(pad "2" smd rect
			(at -0.2667 0 270)
			(size 0.3048 0.381)
			(layers "B.Cu" "B.Mask" "B.Paste")
			(net "GND")
		)
	)
	(footprint ""
		(layer "B.Cu")
		(at 336.928206 -89.427304 90)
		(property "Reference" "C2683"
			(at 0 0 90)
			(layer "B.SilkS")
			(hide yes)
			(effects
				(font
					(size 1.27 1.27)
				)
				(justify mirror)
			)
		)
		(property "Value" ""
			(at 0 0 90)
			(layer "B.Fab")
			(effects
				(font
					(size 1.27 1.27)
				)
				(justify mirror)
			)
		)
		(duplicate_pad_numbers_are_jumpers no)
		(fp_line
			(start 0.7874 -0.4064)
			(end -0.7874 -0.4064)
			(stroke
				(width 0.1524)
				(type default)
			)
			(layer "B.SilkS")
		)
		(fp_line
			(start -0.7874 -0.4064)
			(end -0.7874 0.4064)
			(stroke
				(width 0.1524)
				(type default)
			)
			(layer "B.SilkS")
		)
		(fp_line
			(start 0.7874 0.4064)
			(end 0.7874 -0.4064)
			(stroke
				(width 0.1524)
				(type default)
			)
			(layer "B.SilkS")
		)
		(fp_line
			(start -0.7874 0.4064)
			(end 0.7874 0.4064)
			(stroke
				(width 0.1524)
				(type default)
			)
			(layer "B.SilkS")
		)
		(fp_line
			(start 0.67945 -0.305054)
			(end 0.12065 -0.305054)
			(stroke
				(width 0.1)
				(type default)
			)
			(layer "B.Fab")
		)
		(fp_line
			(start 0.12065 -0.305054)
			(end 0.12065 -0.2794)
			(stroke
				(width 0.1)
				(type default)
			)
			(layer "B.Fab")
		)
		(fp_line
			(start -0.12065 -0.3048)
			(end -0.67945 -0.3048)
			(stroke
				(width 0.1)
				(type default)
			)
			(layer "B.Fab")
		)
		(fp_line
			(start -0.67945 -0.3048)
			(end -0.67945 0.3048)
			(stroke
				(width 0.1)
				(type default)
			)
			(layer "B.Fab")
		)
		(fp_line
			(start 0.12065 -0.2794)
			(end -0.12065 -0.2794)
			(stroke
				(width 0.1)
				(type default)
			)
			(layer "B.Fab")
		)
		(fp_line
			(start -0.12065 -0.2794)
			(end -0.12065 -0.3048)
			(stroke
				(width 0.1)
				(type default)
			)
			(layer "B.Fab")
		)
		(fp_line
			(start 0.12065 0.2794)
			(end 0.12065 0.3048)
			(stroke
				(width 0.1)
				(type default)
			)
			(layer "B.Fab")
		)
		(fp_line
			(start -0.120396 0.2794)
			(end 0.12065 0.2794)
			(stroke
				(width 0.1)
				(type default)
			)
			(layer "B.Fab")
		)
		(fp_line
			(start 0.67945 0.3048)
			(end 0.67945 -0.305054)
			(stroke
				(width 0.1)
				(type default)
			)
			(layer "B.Fab")
		)
		(fp_line
			(start 0.12065 0.3048)
			(end 0.67945 0.3048)
			(stroke
				(width 0.1)
				(type default)
			)
			(layer "B.Fab")
		)
		(fp_line
			(start -0.120396 0.3048)
			(end -0.120396 0.2794)
			(stroke
				(width 0.1)
				(type default)
			)
			(layer "B.Fab")
		)
		(fp_line
			(start -0.67945 0.3048)
			(end -0.120396 0.3048)
			(stroke
				(width 0.1)
				(type default)
			)
			(layer "B.Fab")
		)
		(pad "1" smd circle
			(at 0.40005 0 270)
			(size 0 0)
			(layers "B.Cu" "B.Mask" "B.Paste")
			(net "P3V3_VDDAR_9ZXL0851_8_15")
		)
		(pad "2" smd circle
			(at -0.40005 0 270)
			(size 0 0)
			(layers "B.Cu" "B.Mask" "B.Paste")
			(net "GND")
		)
	)
	(footprint ""
		(layer "B.Cu")
		(at 177.649886 -303.499774 -90)
		(property "Reference" "C3076"
			(at 0 0 90)
			(layer "B.SilkS")
			(hide yes)
			(effects
				(font
					(size 1.27 1.27)
				)
				(justify mirror)
			)
		)
		(property "Value" ""
			(at 0 0 90)
			(layer "B.Fab")
			(effects
				(font
					(size 1.27 1.27)
				)
				(justify mirror)
			)
		)
		(duplicate_pad_numbers_are_jumpers no)
		(fp_line
			(start -0.299974 0.150114)
			(end 0.299974 0.150114)
			(stroke
				(width 0.1)
				(type default)
			)
			(layer "B.Fab")
		)
		(fp_line
			(start 0.299974 0.150114)
			(end 0.299974 -0.150114)
			(stroke
				(width 0.1)
				(type default)
			)
			(layer "B.Fab")
		)
		(fp_line
			(start -0.299974 -0.150114)
			(end -0.299974 0.150114)
			(stroke
				(width 0.1)
				(type default)
			)
			(layer "B.Fab")
		)
		(fp_line
			(start 0.299974 -0.150114)
			(end -0.299974 -0.150114)
			(stroke
				(width 0.1)
				(type default)
			)
			(layer "B.Fab")
		)
		(pad "1" smd rect
			(at 0.2667 0 90)
			(size 0.3048 0.381)
			(layers "B.Cu" "B.Mask" "B.Paste")
			(net "P1V25_PEX1")
		)
		(pad "2" smd rect
			(at -0.2667 0 90)
			(size 0.3048 0.381)
			(layers "B.Cu" "B.Mask" "B.Paste")
			(net "GND")
		)
	)
	(footprint ""
		(layer "B.Cu")
		(at 227.105464 -200.984104 90)
		(property "Reference" "R459"
			(at 0 0 90)
			(layer "B.SilkS")
			(hide yes)
			(effects
				(font
					(size 1.27 1.27)
				)
				(justify mirror)
			)
		)
		(property "Value" ""
			(at 0 0 90)
			(layer "B.Fab")
			(effects
				(font
					(size 1.27 1.27)
				)
				(justify mirror)
			)
		)
		(duplicate_pad_numbers_are_jumpers no)
		(fp_line
			(start 0.7874 -0.4064)
			(end -0.7874 -0.4064)
			(stroke
				(width 0.1524)
				(type default)
			)
			(layer "B.SilkS")
		)
		(fp_line
			(start -0.7874 -0.4064)
			(end -0.7874 0.4064)
			(stroke
				(width 0.1524)
				(type default)
			)
			(layer "B.SilkS")
		)
		(fp_line
			(start 0.7874 0.4064)
			(end 0.7874 -0.4064)
			(stroke
				(width 0.1524)
				(type default)
			)
			(layer "B.SilkS")
		)
		(fp_line
			(start -0.7874 0.4064)
			(end 0.7874 0.4064)
			(stroke
				(width 0.1524)
				(type default)
			)
			(layer "B.SilkS")
		)
		(fp_line
			(start 0.67945 -0.305054)
			(end 0.12065 -0.305054)
			(stroke
				(width 0.1)
				(type default)
			)
			(layer "B.Fab")
		)
		(fp_line
			(start 0.12065 -0.305054)
			(end 0.12065 -0.2794)
			(stroke
				(width 0.1)
				(type default)
			)
			(layer "B.Fab")
		)
		(fp_line
			(start -0.12065 -0.3048)
			(end -0.67945 -0.3048)
			(stroke
				(width 0.1)
				(type default)
			)
			(layer "B.Fab")
		)
		(fp_line
			(start -0.67945 -0.3048)
			(end -0.67945 0.3048)
			(stroke
				(width 0.1)
				(type default)
			)
			(layer "B.Fab")
		)
		(fp_line
			(start 0.12065 -0.2794)
			(end -0.12065 -0.2794)
			(stroke
				(width 0.1)
				(type default)
			)
			(layer "B.Fab")
		)
		(fp_line
			(start -0.12065 -0.2794)
			(end -0.12065 -0.3048)
			(stroke
				(width 0.1)
				(type default)
			)
			(layer "B.Fab")
		)
		(fp_line
			(start 0.12065 0.2794)
			(end 0.12065 0.3048)
			(stroke
				(width 0.1)
				(type default)
			)
			(layer "B.Fab")
		)
		(fp_line
			(start -0.120396 0.2794)
			(end 0.12065 0.2794)
			(stroke
				(width 0.1)
				(type default)
			)
			(layer "B.Fab")
		)
		(fp_line
			(start 0.67945 0.3048)
			(end 0.67945 -0.305054)
			(stroke
				(width 0.1)
				(type default)
			)
			(layer "B.Fab")
		)
		(fp_line
			(start 0.12065 0.3048)
			(end 0.67945 0.3048)
			(stroke
				(width 0.1)
				(type default)
			)
			(layer "B.Fab")
		)
		(fp_line
			(start -0.120396 0.3048)
			(end -0.120396 0.2794)
			(stroke
				(width 0.1)
				(type default)
			)
			(layer "B.Fab")
		)
		(fp_line
			(start -0.67945 0.3048)
			(end -0.120396 0.3048)
			(stroke
				(width 0.1)
				(type default)
			)
			(layer "B.Fab")
		)
		(pad "1" smd circle
			(at 0.40005 0 270)
			(size 0 0)
			(layers "B.Cu" "B.Mask" "B.Paste")
			(net "SPI_BIC1_CLK")
		)
		(pad "2" smd circle
			(at -0.40005 0 270)
			(size 0 0)
			(layers "B.Cu" "B.Mask" "B.Paste")
			(net "SPI_BIC1_CLK_R")
		)
	)
	(footprint ""
		(layer "B.Cu")
		(at 190.126874 -299.2247 90)
		(property "Reference" "R1312"
			(at 0 0 90)
			(layer "B.SilkS")
			(hide yes)
			(effects
				(font
					(size 1.27 1.27)
				)
				(justify mirror)
			)
		)
		(property "Value" ""
			(at 0 0 90)
			(layer "B.Fab")
			(effects
				(font
					(size 1.27 1.27)
				)
				(justify mirror)
			)
		)
		(duplicate_pad_numbers_are_jumpers no)
		(fp_line
			(start 0.7874 -0.4064)
			(end -0.7874 -0.4064)
			(stroke
				(width 0.1524)
				(type default)
			)
			(layer "B.SilkS")
		)
		(fp_line
			(start -0.7874 -0.4064)
			(end -0.7874 0.4064)
			(stroke
				(width 0.1524)
				(type default)
			)
			(layer "B.SilkS")
		)
		(fp_line
			(start 0.7874 0.4064)
			(end 0.7874 -0.4064)
			(stroke
				(width 0.1524)
				(type default)
			)
			(layer "B.SilkS")
		)
		(fp_line
			(start -0.7874 0.4064)
			(end 0.7874 0.4064)
			(stroke
				(width 0.1524)
				(type default)
			)
			(layer "B.SilkS")
		)
		(fp_line
			(start 0.67945 -0.305054)
			(end 0.12065 -0.305054)
			(stroke
				(width 0.1)
				(type default)
			)
			(layer "B.Fab")
		)
		(fp_line
			(start 0.12065 -0.305054)
			(end 0.12065 -0.2794)
			(stroke
				(width 0.1)
				(type default)
			)
			(layer "B.Fab")
		)
		(fp_line
			(start -0.12065 -0.3048)
			(end -0.67945 -0.3048)
			(stroke
				(width 0.1)
				(type default)
			)
			(layer "B.Fab")
		)
		(fp_line
			(start -0.67945 -0.3048)
			(end -0.67945 0.3048)
			(stroke
				(width 0.1)
				(type default)
			)
			(layer "B.Fab")
		)
		(fp_line
			(start 0.12065 -0.2794)
			(end -0.12065 -0.2794)
			(stroke
				(width 0.1)
				(type default)
			)
			(layer "B.Fab")
		)
		(fp_line
			(start -0.12065 -0.2794)
			(end -0.12065 -0.3048)
			(stroke
				(width 0.1)
				(type default)
			)
			(layer "B.Fab")
		)
		(fp_line
			(start 0.12065 0.2794)
			(end 0.12065 0.3048)
			(stroke
				(width 0.1)
				(type default)
			)
			(layer "B.Fab")
		)
		(fp_line
			(start -0.120396 0.2794)
			(end 0.12065 0.2794)
			(stroke
				(width 0.1)
				(type default)
			)
			(layer "B.Fab")
		)
		(fp_line
			(start 0.67945 0.3048)
			(end 0.67945 -0.305054)
			(stroke
				(width 0.1)
				(type default)
			)
			(layer "B.Fab")
		)
		(fp_line
			(start 0.12065 0.3048)
			(end 0.67945 0.3048)
			(stroke
				(width 0.1)
				(type default)
			)
			(layer "B.Fab")
		)
		(fp_line
			(start -0.120396 0.3048)
			(end -0.120396 0.2794)
			(stroke
				(width 0.1)
				(type default)
			)
			(layer "B.Fab")
		)
		(fp_line
			(start -0.67945 0.3048)
			(end -0.120396 0.3048)
			(stroke
				(width 0.1)
				(type default)
			)
			(layer "B.Fab")
		)
		(pad "1" smd circle
			(at 0.40005 0 270)
			(size 0 0)
			(layers "B.Cu" "B.Mask" "B.Paste")
			(net "PEX1_ADCTEMP_VINP1")
		)
		(pad "2" smd circle
			(at -0.40005 0 270)
			(size 0 0)
			(layers "B.Cu" "B.Mask" "B.Paste")
			(net "GND")
		)
	)
	(footprint ""
		(layer "B.Cu")
		(at 401.774914 -293.99992 -90)
		(property "Reference" "C1916"
			(at 0 0 90)
			(layer "B.SilkS")
			(hide yes)
			(effects
				(font
					(size 1.27 1.27)
				)
				(justify mirror)
			)
		)
		(property "Value" ""
			(at 0 0 90)
			(layer "B.Fab")
			(effects
				(font
					(size 1.27 1.27)
				)
				(justify mirror)
			)
		)
		(duplicate_pad_numbers_are_jumpers no)
		(fp_line
			(start -0.299974 0.150114)
			(end 0.299974 0.150114)
			(stroke
				(width 0.1)
				(type default)
			)
			(layer "B.Fab")
		)
		(fp_line
			(start 0.299974 0.150114)
			(end 0.299974 -0.150114)
			(stroke
				(width 0.1)
				(type default)
			)
			(layer "B.Fab")
		)
		(fp_line
			(start -0.299974 -0.150114)
			(end -0.299974 0.150114)
			(stroke
				(width 0.1)
				(type default)
			)
			(layer "B.Fab")
		)
		(fp_line
			(start 0.299974 -0.150114)
			(end -0.299974 -0.150114)
			(stroke
				(width 0.1)
				(type default)
			)
			(layer "B.Fab")
		)
		(pad "1" smd rect
			(at 0.2667 0 90)
			(size 0.3048 0.381)
			(layers "B.Cu" "B.Mask" "B.Paste")
			(net "P0V8_PEX3")
		)
		(pad "2" smd rect
			(at -0.2667 0 90)
			(size 0.3048 0.381)
			(layers "B.Cu" "B.Mask" "B.Paste")
			(net "GND")
		)
	)
	(footprint ""
		(layer "B.Cu")
		(at 394.65504 -297.32478)
		(property "Reference" "C3550"
			(at 0 0 0)
			(layer "B.SilkS")
			(hide yes)
			(effects
				(font
					(size 1.27 1.27)
				)
				(justify mirror)
			)
		)
		(property "Value" ""
			(at 0 0 0)
			(layer "B.Fab")
			(effects
				(font
					(size 1.27 1.27)
				)
				(justify mirror)
			)
		)
		(duplicate_pad_numbers_are_jumpers no)
		(fp_line
			(start -0.299974 -0.150114)
			(end -0.299974 0.150114)
			(stroke
				(width 0.1)
				(type default)
			)
			(layer "B.Fab")
		)
		(fp_line
			(start -0.299974 0.150114)
			(end 0.299974 0.150114)
			(stroke
				(width 0.1)
				(type default)
			)
			(layer "B.Fab")
		)
		(fp_line
			(start 0.299974 -0.150114)
			(end -0.299974 -0.150114)
			(stroke
				(width 0.1)
				(type default)
			)
			(layer "B.Fab")
		)
		(fp_line
			(start 0.299974 0.150114)
			(end 0.299974 -0.150114)
			(stroke
				(width 0.1)
				(type default)
			)
			(layer "B.Fab")
		)
		(pad "1" smd rect
			(at 0.2667 0 180)
			(size 0.3048 0.381)
			(layers "B.Cu" "B.Mask" "B.Paste")
			(net "PCEPLL2_VDDA18_PEX3")
		)
		(pad "2" smd rect
			(at -0.2667 0 180)
			(size 0.3048 0.381)
			(layers "B.Cu" "B.Mask" "B.Paste")
			(net "GND")
		)
	)
	(footprint ""
		(layer "B.Cu")
		(at 182.87492 -297.79976 -90)
		(property "Reference" "C1447"
			(at 0 0 90)
			(layer "B.SilkS")
			(hide yes)
			(effects
				(font
					(size 1.27 1.27)
				)
				(justify mirror)
			)
		)
		(property "Value" ""
			(at 0 0 90)
			(layer "B.Fab")
			(effects
				(font
					(size 1.27 1.27)
				)
				(justify mirror)
			)
		)
		(duplicate_pad_numbers_are_jumpers no)
		(fp_line
			(start -0.299974 0.150114)
			(end 0.299974 0.150114)
			(stroke
				(width 0.1)
				(type default)
			)
			(layer "B.Fab")
		)
		(fp_line
			(start 0.299974 0.150114)
			(end 0.299974 -0.150114)
			(stroke
				(width 0.1)
				(type default)
			)
			(layer "B.Fab")
		)
		(fp_line
			(start -0.299974 -0.150114)
			(end -0.299974 0.150114)
			(stroke
				(width 0.1)
				(type default)
			)
			(layer "B.Fab")
		)
		(fp_line
			(start 0.299974 -0.150114)
			(end -0.299974 -0.150114)
			(stroke
				(width 0.1)
				(type default)
			)
			(layer "B.Fab")
		)
		(pad "1" smd rect
			(at 0.2667 0 90)
			(size 0.3048 0.381)
			(layers "B.Cu" "B.Mask" "B.Paste")
			(net "P0V8_SERDES_VDDA_PEX1")
		)
		(pad "2" smd rect
			(at -0.2667 0 90)
			(size 0.3048 0.381)
			(layers "B.Cu" "B.Mask" "B.Paste")
			(net "GND")
		)
	)
	(footprint ""
		(layer "B.Cu")
		(at 286.624776 -293.99992 90)
		(property "Reference" "C1657"
			(at 0 0 90)
			(layer "B.SilkS")
			(hide yes)
			(effects
				(font
					(size 1.27 1.27)
				)
				(justify mirror)
			)
		)
		(property "Value" ""
			(at 0 0 90)
			(layer "B.Fab")
			(effects
				(font
					(size 1.27 1.27)
				)
				(justify mirror)
			)
		)
		(duplicate_pad_numbers_are_jumpers no)
		(fp_line
			(start 0.299974 -0.150114)
			(end -0.299974 -0.150114)
			(stroke
				(width 0.1)
				(type default)
			)
			(layer "B.Fab")
		)
		(fp_line
			(start -0.299974 -0.150114)
			(end -0.299974 0.150114)
			(stroke
				(width 0.1)
				(type default)
			)
			(layer "B.Fab")
		)
		(fp_line
			(start 0.299974 0.150114)
			(end 0.299974 -0.150114)
			(stroke
				(width 0.1)
				(type default)
			)
			(layer "B.Fab")
		)
		(fp_line
			(start -0.299974 0.150114)
			(end 0.299974 0.150114)
			(stroke
				(width 0.1)
				(type default)
			)
			(layer "B.Fab")
		)
		(pad "1" smd rect
			(at 0.2667 0 270)
			(size 0.3048 0.381)
			(layers "B.Cu" "B.Mask" "B.Paste")
			(net "P0V8_PEX2")
		)
		(pad "2" smd rect
			(at -0.2667 0 270)
			(size 0.3048 0.381)
			(layers "B.Cu" "B.Mask" "B.Paste")
			(net "GND")
		)
	)
	(footprint ""
		(layer "B.Cu")
		(at 285.199836 -290.199826 90)
		(property "Reference" "C1698"
			(at 0 0 90)
			(layer "B.SilkS")
			(hide yes)
			(effects
				(font
					(size 1.27 1.27)
				)
				(justify mirror)
			)
		)
		(property "Value" ""
			(at 0 0 90)
			(layer "B.Fab")
			(effects
				(font
					(size 1.27 1.27)
				)
				(justify mirror)
			)
		)
		(duplicate_pad_numbers_are_jumpers no)
		(fp_line
			(start 0.299974 -0.150114)
			(end -0.299974 -0.150114)
			(stroke
				(width 0.1)
				(type default)
			)
			(layer "B.Fab")
		)
		(fp_line
			(start -0.299974 -0.150114)
			(end -0.299974 0.150114)
			(stroke
				(width 0.1)
				(type default)
			)
			(layer "B.Fab")
		)
		(fp_line
			(start 0.299974 0.150114)
			(end 0.299974 -0.150114)
			(stroke
				(width 0.1)
				(type default)
			)
			(layer "B.Fab")
		)
		(fp_line
			(start -0.299974 0.150114)
			(end 0.299974 0.150114)
			(stroke
				(width 0.1)
				(type default)
			)
			(layer "B.Fab")
		)
		(pad "1" smd rect
			(at 0.2667 0 270)
			(size 0.3048 0.381)
			(layers "B.Cu" "B.Mask" "B.Paste")
			(net "P0V8_SERDES_VDDA_PEX2")
		)
		(pad "2" smd rect
			(at -0.2667 0 270)
			(size 0.3048 0.381)
			(layers "B.Cu" "B.Mask" "B.Paste")
			(net "GND")
		)
	)
	(footprint ""
		(layer "B.Cu")
		(at 337.970876 -326.945498 -90)
		(property "Reference" "C4329"
			(at 0 0 90)
			(layer "B.SilkS")
			(hide yes)
			(effects
				(font
					(size 1.27 1.27)
				)
				(justify mirror)
			)
		)
		(property "Value" ""
			(at 0 0 90)
			(layer "B.Fab")
			(effects
				(font
					(size 1.27 1.27)
				)
				(justify mirror)
			)
		)
		(duplicate_pad_numbers_are_jumpers no)
		(fp_line
			(start -1.2954 0.5842)
			(end 1.2954 0.5842)
			(stroke
				(width 0.1524)
				(type default)
			)
			(layer "B.SilkS")
		)
		(fp_line
			(start 1.2954 0.5842)
			(end 1.2954 -0.5842)
			(stroke
				(width 0.1524)
				(type default)
			)
			(layer "B.SilkS")
		)
		(fp_line
			(start -1.2954 -0.5842)
			(end -1.2954 0.5842)
			(stroke
				(width 0.1524)
				(type default)
			)
			(layer "B.SilkS")
		)
		(fp_line
			(start 1.2954 -0.5842)
			(end -1.2954 -0.5842)
			(stroke
				(width 0.1524)
				(type default)
			)
			(layer "B.SilkS")
		)
		(fp_line
			(start -0.8636 0.4572)
			(end 0.8636 0.4572)
			(stroke
				(width 0.1)
				(type default)
			)
			(layer "B.Fab")
		)
		(fp_line
			(start 0.8636 0.4572)
			(end 0.8636 0.4064)
			(stroke
				(width 0.1)
				(type default)
			)
			(layer "B.Fab")
		)
		(fp_line
			(start -1.1938 0.4064)
			(end -0.8636 0.4064)
			(stroke
				(width 0.1)
				(type default)
			)
			(layer "B.Fab")
		)
		(fp_line
			(start -0.8636 0.4064)
			(end -0.8636 0.4572)
			(stroke
				(width 0.1)
				(type default)
			)
			(layer "B.Fab")
		)
		(fp_line
			(start 0.8636 0.4064)
			(end 1.1938 0.4064)
			(stroke
				(width 0.1)
				(type default)
			)
			(layer "B.Fab")
		)
		(fp_line
			(start 1.1938 0.4064)
			(end 1.1938 -0.4064)
			(stroke
				(width 0.1)
				(type default)
			)
			(layer "B.Fab")
		)
		(fp_line
			(start -1.1938 -0.4064)
			(end -1.1938 0.4064)
			(stroke
				(width 0.1)
				(type default)
			)
			(layer "B.Fab")
		)
		(fp_line
			(start -0.8636 -0.4064)
			(end -1.1938 -0.4064)
			(stroke
				(width 0.1)
				(type default)
			)
			(layer "B.Fab")
		)
		(fp_line
			(start 0.8636 -0.4064)
			(end 0.8636 -0.4572)
			(stroke
				(width 0.1)
				(type default)
			)
			(layer "B.Fab")
		)
		(fp_line
			(start 1.1938 -0.4064)
			(end 0.8636 -0.4064)
			(stroke
				(width 0.1)
				(type default)
			)
			(layer "B.Fab")
		)
		(fp_line
			(start -0.8636 -0.4572)
			(end -0.8636 -0.4064)
			(stroke
				(width 0.1)
				(type default)
			)
			(layer "B.Fab")
		)
		(fp_line
			(start 0.8636 -0.4572)
			(end -0.8636 -0.4572)
			(stroke
				(width 0.1)
				(type default)
			)
			(layer "B.Fab")
		)
		(pad "1" smd rect
			(at 0.7366 0 180)
			(size 0.7112 0.8128)
			(layers "B.Cu" "B.Mask" "B.Paste")
			(net "P0V8_SERDES_VDDA_PEX2_C11")
		)
		(pad "2" smd rect
			(at -0.7366 0 180)
			(size 0.7112 0.8128)
			(layers "B.Cu" "B.Mask" "B.Paste")
			(net "GND")
		)
	)
	(footprint ""
		(layer "B.Cu")
		(at 182.39994 -299.699934 -90)
		(property "Reference" "C1423"
			(at 0 0 90)
			(layer "B.SilkS")
			(hide yes)
			(effects
				(font
					(size 1.27 1.27)
				)
				(justify mirror)
			)
		)
		(property "Value" ""
			(at 0 0 90)
			(layer "B.Fab")
			(effects
				(font
					(size 1.27 1.27)
				)
				(justify mirror)
			)
		)
		(duplicate_pad_numbers_are_jumpers no)
		(fp_line
			(start -0.299974 0.150114)
			(end 0.299974 0.150114)
			(stroke
				(width 0.1)
				(type default)
			)
			(layer "B.Fab")
		)
		(fp_line
			(start 0.299974 0.150114)
			(end 0.299974 -0.150114)
			(stroke
				(width 0.1)
				(type default)
			)
			(layer "B.Fab")
		)
		(fp_line
			(start -0.299974 -0.150114)
			(end -0.299974 0.150114)
			(stroke
				(width 0.1)
				(type default)
			)
			(layer "B.Fab")
		)
		(fp_line
			(start 0.299974 -0.150114)
			(end -0.299974 -0.150114)
			(stroke
				(width 0.1)
				(type default)
			)
			(layer "B.Fab")
		)
		(pad "1" smd rect
			(at 0.2667 0 90)
			(size 0.3048 0.381)
			(layers "B.Cu" "B.Mask" "B.Paste")
			(net "P0V8_SERDES_VDDA_PEX1")
		)
		(pad "2" smd rect
			(at -0.2667 0 90)
			(size 0.3048 0.381)
			(layers "B.Cu" "B.Mask" "B.Paste")
			(net "GND")
		)
	)
	(footprint ""
		(layer "B.Cu")
		(at 213.730332 -224.398586 180)
		(property "Reference" "R4113"
			(at 0 0 0)
			(layer "B.SilkS")
			(hide yes)
			(effects
				(font
					(size 1.27 1.27)
				)
				(justify mirror)
			)
		)
		(property "Value" ""
			(at 0 0 0)
			(layer "B.Fab")
			(effects
				(font
					(size 1.27 1.27)
				)
				(justify mirror)
			)
		)
		(duplicate_pad_numbers_are_jumpers no)
		(fp_line
			(start 0.7874 0.4064)
			(end 0.7874 -0.4064)
			(stroke
				(width 0.1524)
				(type default)
			)
			(layer "B.SilkS")
		)
		(fp_line
			(start 0.7874 -0.4064)
			(end -0.7874 -0.4064)
			(stroke
				(width 0.1524)
				(type default)
			)
			(layer "B.SilkS")
		)
		(fp_line
			(start -0.7874 0.4064)
			(end 0.7874 0.4064)
			(stroke
				(width 0.1524)
				(type default)
			)
			(layer "B.SilkS")
		)
		(fp_line
			(start -0.7874 -0.4064)
			(end -0.7874 0.4064)
			(stroke
				(width 0.1524)
				(type default)
			)
			(layer "B.SilkS")
		)
		(fp_line
			(start 0.67945 0.3048)
			(end 0.67945 -0.305054)
			(stroke
				(width 0.1)
				(type default)
			)
			(layer "B.Fab")
		)
		(fp_line
			(start 0.67945 -0.305054)
			(end 0.12065 -0.305054)
			(stroke
				(width 0.1)
				(type default)
			)
			(layer "B.Fab")
		)
		(fp_line
			(start 0.12065 0.3048)
			(end 0.67945 0.3048)
			(stroke
				(width 0.1)
				(type default)
			)
			(layer "B.Fab")
		)
		(fp_line
			(start 0.12065 0.2794)
			(end 0.12065 0.3048)
			(stroke
				(width 0.1)
				(type default)
			)
			(layer "B.Fab")
		)
		(fp_line
			(start 0.12065 -0.2794)
			(end -0.12065 -0.2794)
			(stroke
				(width 0.1)
				(type default)
			)
			(layer "B.Fab")
		)
		(fp_line
			(start 0.12065 -0.305054)
			(end 0.12065 -0.2794)
			(stroke
				(width 0.1)
				(type default)
			)
			(layer "B.Fab")
		)
		(fp_line
			(start -0.120396 0.3048)
			(end -0.120396 0.2794)
			(stroke
				(width 0.1)
				(type default)
			)
			(layer "B.Fab")
		)
		(fp_line
			(start -0.120396 0.2794)
			(end 0.12065 0.2794)
			(stroke
				(width 0.1)
				(type default)
			)
			(layer "B.Fab")
		)
		(fp_line
			(start -0.12065 -0.2794)
			(end -0.12065 -0.3048)
			(stroke
				(width 0.1)
				(type default)
			)
			(layer "B.Fab")
		)
		(fp_line
			(start -0.12065 -0.3048)
			(end -0.67945 -0.3048)
			(stroke
				(width 0.1)
				(type default)
			)
			(layer "B.Fab")
		)
		(fp_line
			(start -0.67945 0.3048)
			(end -0.120396 0.3048)
			(stroke
				(width 0.1)
				(type default)
			)
			(layer "B.Fab")
		)
		(fp_line
			(start -0.67945 -0.3048)
			(end -0.67945 0.3048)
			(stroke
				(width 0.1)
				(type default)
			)
			(layer "B.Fab")
		)
		(pad "1" smd circle
			(at 0.40005 0)
			(size 0 0)
			(layers "B.Cu" "B.Mask" "B.Paste")
			(net "P3V3_AUX")
		)
		(pad "2" smd circle
			(at -0.40005 0)
			(size 0 0)
			(layers "B.Cu" "B.Mask" "B.Paste")
			(net "SMB_BIC_I2C6_SCL")
		)
	)
	(footprint ""
		(layer "B.Cu")
		(at 209.212942 -259.311648 90)
		(property "Reference" "R6347"
			(at 0 0 90)
			(layer "B.SilkS")
			(hide yes)
			(effects
				(font
					(size 1.27 1.27)
				)
				(justify mirror)
			)
		)
		(property "Value" ""
			(at 0 0 90)
			(layer "B.Fab")
			(effects
				(font
					(size 1.27 1.27)
				)
				(justify mirror)
			)
		)
		(duplicate_pad_numbers_are_jumpers no)
		(fp_line
			(start 0.7874 -0.4064)
			(end -0.7874 -0.4064)
			(stroke
				(width 0.1524)
				(type default)
			)
			(layer "B.SilkS")
		)
		(fp_line
			(start -0.7874 -0.4064)
			(end -0.7874 0.4064)
			(stroke
				(width 0.1524)
				(type default)
			)
			(layer "B.SilkS")
		)
		(fp_line
			(start 0.7874 0.4064)
			(end 0.7874 -0.4064)
			(stroke
				(width 0.1524)
				(type default)
			)
			(layer "B.SilkS")
		)
		(fp_line
			(start -0.7874 0.4064)
			(end 0.7874 0.4064)
			(stroke
				(width 0.1524)
				(type default)
			)
			(layer "B.SilkS")
		)
		(fp_line
			(start 0.67945 -0.305054)
			(end 0.12065 -0.305054)
			(stroke
				(width 0.1)
				(type default)
			)
			(layer "B.Fab")
		)
		(fp_line
			(start 0.12065 -0.305054)
			(end 0.12065 -0.2794)
			(stroke
				(width 0.1)
				(type default)
			)
			(layer "B.Fab")
		)
		(fp_line
			(start -0.12065 -0.3048)
			(end -0.67945 -0.3048)
			(stroke
				(width 0.1)
				(type default)
			)
			(layer "B.Fab")
		)
		(fp_line
			(start -0.67945 -0.3048)
			(end -0.67945 0.3048)
			(stroke
				(width 0.1)
				(type default)
			)
			(layer "B.Fab")
		)
		(fp_line
			(start 0.12065 -0.2794)
			(end -0.12065 -0.2794)
			(stroke
				(width 0.1)
				(type default)
			)
			(layer "B.Fab")
		)
		(fp_line
			(start -0.12065 -0.2794)
			(end -0.12065 -0.3048)
			(stroke
				(width 0.1)
				(type default)
			)
			(layer "B.Fab")
		)
		(fp_line
			(start 0.12065 0.2794)
			(end 0.12065 0.3048)
			(stroke
				(width 0.1)
				(type default)
			)
			(layer "B.Fab")
		)
		(fp_line
			(start -0.120396 0.2794)
			(end 0.12065 0.2794)
			(stroke
				(width 0.1)
				(type default)
			)
			(layer "B.Fab")
		)
		(fp_line
			(start 0.67945 0.3048)
			(end 0.67945 -0.305054)
			(stroke
				(width 0.1)
				(type default)
			)
			(layer "B.Fab")
		)
		(fp_line
			(start 0.12065 0.3048)
			(end 0.67945 0.3048)
			(stroke
				(width 0.1)
				(type default)
			)
			(layer "B.Fab")
		)
		(fp_line
			(start -0.120396 0.3048)
			(end -0.120396 0.2794)
			(stroke
				(width 0.1)
				(type default)
			)
			(layer "B.Fab")
		)
		(fp_line
			(start -0.67945 0.3048)
			(end -0.120396 0.3048)
			(stroke
				(width 0.1)
				(type default)
			)
			(layer "B.Fab")
		)
		(pad "1" smd circle
			(at 0.40005 0 270)
			(size 0 0)
			(layers "B.Cu" "B.Mask" "B.Paste")
			(net "P1V8_PEX")
		)
		(pad "2" smd circle
			(at -0.40005 0 270)
			(size 0 0)
			(layers "B.Cu" "B.Mask" "B.Paste")
			(net "SMB_PEX2_MUX_SCL")
		)
	)
	(footprint ""
		(layer "B.Cu")
		(at 336.956654 -84.513928 -90)
		(property "Reference" "C2674"
			(at 0 0 90)
			(layer "B.SilkS")
			(hide yes)
			(effects
				(font
					(size 1.27 1.27)
				)
				(justify mirror)
			)
		)
		(property "Value" ""
			(at 0 0 90)
			(layer "B.Fab")
			(effects
				(font
					(size 1.27 1.27)
				)
				(justify mirror)
			)
		)
		(duplicate_pad_numbers_are_jumpers no)
		(fp_line
			(start -0.7874 0.4064)
			(end 0.7874 0.4064)
			(stroke
				(width 0.1524)
				(type default)
			)
			(layer "B.SilkS")
		)
		(fp_line
			(start 0.7874 0.4064)
			(end 0.7874 -0.4064)
			(stroke
				(width 0.1524)
				(type default)
			)
			(layer "B.SilkS")
		)
		(fp_line
			(start -0.7874 -0.4064)
			(end -0.7874 0.4064)
			(stroke
				(width 0.1524)
				(type default)
			)
			(layer "B.SilkS")
		)
		(fp_line
			(start 0.7874 -0.4064)
			(end -0.7874 -0.4064)
			(stroke
				(width 0.1524)
				(type default)
			)
			(layer "B.SilkS")
		)
		(fp_line
			(start -0.67945 0.3048)
			(end -0.120396 0.3048)
			(stroke
				(width 0.1)
				(type default)
			)
			(layer "B.Fab")
		)
		(fp_line
			(start -0.120396 0.3048)
			(end -0.120396 0.2794)
			(stroke
				(width 0.1)
				(type default)
			)
			(layer "B.Fab")
		)
		(fp_line
			(start 0.12065 0.3048)
			(end 0.67945 0.3048)
			(stroke
				(width 0.1)
				(type default)
			)
			(layer "B.Fab")
		)
		(fp_line
			(start 0.67945 0.3048)
			(end 0.67945 -0.305054)
			(stroke
				(width 0.1)
				(type default)
			)
			(layer "B.Fab")
		)
		(fp_line
			(start -0.120396 0.2794)
			(end 0.12065 0.2794)
			(stroke
				(width 0.1)
				(type default)
			)
			(layer "B.Fab")
		)
		(fp_line
			(start 0.12065 0.2794)
			(end 0.12065 0.3048)
			(stroke
				(width 0.1)
				(type default)
			)
			(layer "B.Fab")
		)
		(fp_line
			(start -0.12065 -0.2794)
			(end -0.12065 -0.3048)
			(stroke
				(width 0.1)
				(type default)
			)
			(layer "B.Fab")
		)
		(fp_line
			(start 0.12065 -0.2794)
			(end -0.12065 -0.2794)
			(stroke
				(width 0.1)
				(type default)
			)
			(layer "B.Fab")
		)
		(fp_line
			(start -0.67945 -0.3048)
			(end -0.67945 0.3048)
			(stroke
				(width 0.1)
				(type default)
			)
			(layer "B.Fab")
		)
		(fp_line
			(start -0.12065 -0.3048)
			(end -0.67945 -0.3048)
			(stroke
				(width 0.1)
				(type default)
			)
			(layer "B.Fab")
		)
		(fp_line
			(start 0.12065 -0.305054)
			(end 0.12065 -0.2794)
			(stroke
				(width 0.1)
				(type default)
			)
			(layer "B.Fab")
		)
		(fp_line
			(start 0.67945 -0.305054)
			(end 0.12065 -0.305054)
			(stroke
				(width 0.1)
				(type default)
			)
			(layer "B.Fab")
		)
		(pad "1" smd circle
			(at 0.40005 0 90)
			(size 0 0)
			(layers "B.Cu" "B.Mask" "B.Paste")
			(net "P3V3_VDD_9ZXL0851_8_15")
		)
		(pad "2" smd circle
			(at -0.40005 0 90)
			(size 0 0)
			(layers "B.Cu" "B.Mask" "B.Paste")
			(net "GND")
		)
	)
	(footprint ""
		(layer "B.Cu")
		(at 162.836098 -291.624766)
		(property "Reference" "C3234"
			(at 0 0 0)
			(layer "B.SilkS")
			(hide yes)
			(effects
				(font
					(size 1.27 1.27)
				)
				(justify mirror)
			)
		)
		(property "Value" ""
			(at 0 0 0)
			(layer "B.Fab")
			(effects
				(font
					(size 1.27 1.27)
				)
				(justify mirror)
			)
		)
		(duplicate_pad_numbers_are_jumpers no)
		(fp_line
			(start -0.299974 -0.150114)
			(end -0.299974 0.150114)
			(stroke
				(width 0.1)
				(type default)
			)
			(layer "B.Fab")
		)
		(fp_line
			(start -0.299974 0.150114)
			(end 0.299974 0.150114)
			(stroke
				(width 0.1)
				(type default)
			)
			(layer "B.Fab")
		)
		(fp_line
			(start 0.299974 -0.150114)
			(end -0.299974 -0.150114)
			(stroke
				(width 0.1)
				(type default)
			)
			(layer "B.Fab")
		)
		(fp_line
			(start 0.299974 0.150114)
			(end 0.299974 -0.150114)
			(stroke
				(width 0.1)
				(type default)
			)
			(layer "B.Fab")
		)
		(pad "1" smd rect
			(at 0.2667 0 180)
			(size 0.3048 0.381)
			(layers "B.Cu" "B.Mask" "B.Paste")
			(net "PCEPLL7_VDDA18_PEX1")
		)
		(pad "2" smd rect
			(at -0.2667 0 180)
			(size 0.3048 0.381)
			(layers "B.Cu" "B.Mask" "B.Paste")
			(net "GND")
		)
	)
	(footprint ""
		(layer "B.Cu")
		(at 227.118418 -150.425912 90)
		(property "Reference" "C2801"
			(at 0 0 90)
			(layer "B.SilkS")
			(hide yes)
			(effects
				(font
					(size 1.27 1.27)
				)
				(justify mirror)
			)
		)
		(property "Value" ""
			(at 0 0 90)
			(layer "B.Fab")
			(effects
				(font
					(size 1.27 1.27)
				)
				(justify mirror)
			)
		)
		(duplicate_pad_numbers_are_jumpers no)
		(fp_line
			(start 0.7874 -0.4064)
			(end -0.7874 -0.4064)
			(stroke
				(width 0.1524)
				(type default)
			)
			(layer "B.SilkS")
		)
		(fp_line
			(start -0.7874 -0.4064)
			(end -0.7874 0.4064)
			(stroke
				(width 0.1524)
				(type default)
			)
			(layer "B.SilkS")
		)
		(fp_line
			(start 0.7874 0.4064)
			(end 0.7874 -0.4064)
			(stroke
				(width 0.1524)
				(type default)
			)
			(layer "B.SilkS")
		)
		(fp_line
			(start -0.7874 0.4064)
			(end 0.7874 0.4064)
			(stroke
				(width 0.1524)
				(type default)
			)
			(layer "B.SilkS")
		)
		(fp_line
			(start 0.67945 -0.305054)
			(end 0.12065 -0.305054)
			(stroke
				(width 0.1)
				(type default)
			)
			(layer "B.Fab")
		)
		(fp_line
			(start 0.12065 -0.305054)
			(end 0.12065 -0.2794)
			(stroke
				(width 0.1)
				(type default)
			)
			(layer "B.Fab")
		)
		(fp_line
			(start -0.12065 -0.3048)
			(end -0.67945 -0.3048)
			(stroke
				(width 0.1)
				(type default)
			)
			(layer "B.Fab")
		)
		(fp_line
			(start -0.67945 -0.3048)
			(end -0.67945 0.3048)
			(stroke
				(width 0.1)
				(type default)
			)
			(layer "B.Fab")
		)
		(fp_line
			(start 0.12065 -0.2794)
			(end -0.12065 -0.2794)
			(stroke
				(width 0.1)
				(type default)
			)
			(layer "B.Fab")
		)
		(fp_line
			(start -0.12065 -0.2794)
			(end -0.12065 -0.3048)
			(stroke
				(width 0.1)
				(type default)
			)
			(layer "B.Fab")
		)
		(fp_line
			(start 0.12065 0.2794)
			(end 0.12065 0.3048)
			(stroke
				(width 0.1)
				(type default)
			)
			(layer "B.Fab")
		)
		(fp_line
			(start -0.120396 0.2794)
			(end 0.12065 0.2794)
			(stroke
				(width 0.1)
				(type default)
			)
			(layer "B.Fab")
		)
		(fp_line
			(start 0.67945 0.3048)
			(end 0.67945 -0.305054)
			(stroke
				(width 0.1)
				(type default)
			)
			(layer "B.Fab")
		)
		(fp_line
			(start 0.12065 0.3048)
			(end 0.67945 0.3048)
			(stroke
				(width 0.1)
				(type default)
			)
			(layer "B.Fab")
		)
		(fp_line
			(start -0.120396 0.3048)
			(end -0.120396 0.2794)
			(stroke
				(width 0.1)
				(type default)
			)
			(layer "B.Fab")
		)
		(fp_line
			(start -0.67945 0.3048)
			(end -0.120396 0.3048)
			(stroke
				(width 0.1)
				(type default)
			)
			(layer "B.Fab")
		)
		(pad "1" smd circle
			(at 0.40005 0 270)
			(size 0 0)
			(layers "B.Cu" "B.Mask" "B.Paste")
			(net "P3V3_CLK_GEN_VDDMXCK_CK440_PEX")
		)
		(pad "2" smd circle
			(at -0.40005 0 270)
			(size 0 0)
			(layers "B.Cu" "B.Mask" "B.Paste")
			(net "GND")
		)
	)
	(footprint ""
		(layer "B.Cu")
		(at 124.236734 -321.387978 -90)
		(property "Reference" "R6478"
			(at 0 0 90)
			(layer "B.SilkS")
			(hide yes)
			(effects
				(font
					(size 1.27 1.27)
				)
				(justify mirror)
			)
		)
		(property "Value" ""
			(at 0 0 90)
			(layer "B.Fab")
			(effects
				(font
					(size 1.27 1.27)
				)
				(justify mirror)
			)
		)
		(duplicate_pad_numbers_are_jumpers no)
		(fp_line
			(start -0.7874 0.4064)
			(end 0.7874 0.4064)
			(stroke
				(width 0.1524)
				(type default)
			)
			(layer "B.SilkS")
		)
		(fp_line
			(start 0.7874 0.4064)
			(end 0.7874 -0.4064)
			(stroke
				(width 0.1524)
				(type default)
			)
			(layer "B.SilkS")
		)
		(fp_line
			(start -0.7874 -0.4064)
			(end -0.7874 0.4064)
			(stroke
				(width 0.1524)
				(type default)
			)
			(layer "B.SilkS")
		)
		(fp_line
			(start 0.7874 -0.4064)
			(end -0.7874 -0.4064)
			(stroke
				(width 0.1524)
				(type default)
			)
			(layer "B.SilkS")
		)
		(fp_line
			(start -0.67945 0.3048)
			(end -0.120396 0.3048)
			(stroke
				(width 0.1)
				(type default)
			)
			(layer "B.Fab")
		)
		(fp_line
			(start -0.120396 0.3048)
			(end -0.120396 0.2794)
			(stroke
				(width 0.1)
				(type default)
			)
			(layer "B.Fab")
		)
		(fp_line
			(start 0.12065 0.3048)
			(end 0.67945 0.3048)
			(stroke
				(width 0.1)
				(type default)
			)
			(layer "B.Fab")
		)
		(fp_line
			(start 0.67945 0.3048)
			(end 0.67945 -0.305054)
			(stroke
				(width 0.1)
				(type default)
			)
			(layer "B.Fab")
		)
		(fp_line
			(start -0.120396 0.2794)
			(end 0.12065 0.2794)
			(stroke
				(width 0.1)
				(type default)
			)
			(layer "B.Fab")
		)
		(fp_line
			(start 0.12065 0.2794)
			(end 0.12065 0.3048)
			(stroke
				(width 0.1)
				(type default)
			)
			(layer "B.Fab")
		)
		(fp_line
			(start -0.12065 -0.2794)
			(end -0.12065 -0.3048)
			(stroke
				(width 0.1)
				(type default)
			)
			(layer "B.Fab")
		)
		(fp_line
			(start 0.12065 -0.2794)
			(end -0.12065 -0.2794)
			(stroke
				(width 0.1)
				(type default)
			)
			(layer "B.Fab")
		)
		(fp_line
			(start -0.67945 -0.3048)
			(end -0.67945 0.3048)
			(stroke
				(width 0.1)
				(type default)
			)
			(layer "B.Fab")
		)
		(fp_line
			(start -0.12065 -0.3048)
			(end -0.67945 -0.3048)
			(stroke
				(width 0.1)
				(type default)
			)
			(layer "B.Fab")
		)
		(fp_line
			(start 0.12065 -0.305054)
			(end 0.12065 -0.2794)
			(stroke
				(width 0.1)
				(type default)
			)
			(layer "B.Fab")
		)
		(fp_line
			(start 0.67945 -0.305054)
			(end 0.12065 -0.305054)
			(stroke
				(width 0.1)
				(type default)
			)
			(layer "B.Fab")
		)
		(pad "1" smd circle
			(at 0.40005 0 90)
			(size 0 0)
			(layers "B.Cu" "B.Mask" "B.Paste")
			(net "P0V8_SERDES_VDDA_PEX1")
		)
		(pad "2" smd circle
			(at -0.40005 0 90)
			(size 0 0)
			(layers "B.Cu" "B.Mask" "B.Paste")
			(net "P0V8_SERDES_VDDA_PEX1_C3")
		)
	)
	(footprint ""
		(layer "B.Cu")
		(at 420.05504 -97.663 180)
		(property "Reference" "R379"
			(at 0 0 0)
			(layer "B.SilkS")
			(hide yes)
			(effects
				(font
					(size 1.27 1.27)
				)
				(justify mirror)
			)
		)
		(property "Value" ""
			(at 0 0 0)
			(layer "B.Fab")
			(effects
				(font
					(size 1.27 1.27)
				)
				(justify mirror)
			)
		)
		(duplicate_pad_numbers_are_jumpers no)
		(fp_line
			(start 0.7874 0.4064)
			(end 0.7874 -0.4064)
			(stroke
				(width 0.1524)
				(type default)
			)
			(layer "B.SilkS")
		)
		(fp_line
			(start 0.7874 -0.4064)
			(end -0.7874 -0.4064)
			(stroke
				(width 0.1524)
				(type default)
			)
			(layer "B.SilkS")
		)
		(fp_line
			(start -0.7874 0.4064)
			(end 0.7874 0.4064)
			(stroke
				(width 0.1524)
				(type default)
			)
			(layer "B.SilkS")
		)
		(fp_line
			(start -0.7874 -0.4064)
			(end -0.7874 0.4064)
			(stroke
				(width 0.1524)
				(type default)
			)
			(layer "B.SilkS")
		)
		(fp_line
			(start 0.67945 0.3048)
			(end 0.67945 -0.305054)
			(stroke
				(width 0.1)
				(type default)
			)
			(layer "B.Fab")
		)
		(fp_line
			(start 0.67945 -0.305054)
			(end 0.12065 -0.305054)
			(stroke
				(width 0.1)
				(type default)
			)
			(layer "B.Fab")
		)
		(fp_line
			(start 0.12065 0.3048)
			(end 0.67945 0.3048)
			(stroke
				(width 0.1)
				(type default)
			)
			(layer "B.Fab")
		)
		(fp_line
			(start 0.12065 0.2794)
			(end 0.12065 0.3048)
			(stroke
				(width 0.1)
				(type default)
			)
			(layer "B.Fab")
		)
		(fp_line
			(start 0.12065 -0.2794)
			(end -0.12065 -0.2794)
			(stroke
				(width 0.1)
				(type default)
			)
			(layer "B.Fab")
		)
		(fp_line
			(start 0.12065 -0.305054)
			(end 0.12065 -0.2794)
			(stroke
				(width 0.1)
				(type default)
			)
			(layer "B.Fab")
		)
		(fp_line
			(start -0.120396 0.3048)
			(end -0.120396 0.2794)
			(stroke
				(width 0.1)
				(type default)
			)
			(layer "B.Fab")
		)
		(fp_line
			(start -0.120396 0.2794)
			(end 0.12065 0.2794)
			(stroke
				(width 0.1)
				(type default)
			)
			(layer "B.Fab")
		)
		(fp_line
			(start -0.12065 -0.2794)
			(end -0.12065 -0.3048)
			(stroke
				(width 0.1)
				(type default)
			)
			(layer "B.Fab")
		)
		(fp_line
			(start -0.12065 -0.3048)
			(end -0.67945 -0.3048)
			(stroke
				(width 0.1)
				(type default)
			)
			(layer "B.Fab")
		)
		(fp_line
			(start -0.67945 0.3048)
			(end -0.120396 0.3048)
			(stroke
				(width 0.1)
				(type default)
			)
			(layer "B.Fab")
		)
		(fp_line
			(start -0.67945 -0.3048)
			(end -0.67945 0.3048)
			(stroke
				(width 0.1)
				(type default)
			)
			(layer "B.Fab")
		)
		(pad "1" smd circle
			(at 0.40005 0)
			(size 0 0)
			(layers "B.Cu" "B.Mask" "B.Paste")
			(net "PWRGD_NIC7_PWR_GOOD")
		)
		(pad "2" smd circle
			(at -0.40005 0)
			(size 0 0)
			(layers "B.Cu" "B.Mask" "B.Paste")
			(net "GND")
		)
	)
	(footprint ""
		(layer "B.Cu")
		(at 60.124848 -297.79976 90)
		(property "Reference" "C1114"
			(at 0 0 90)
			(layer "B.SilkS")
			(hide yes)
			(effects
				(font
					(size 1.27 1.27)
				)
				(justify mirror)
			)
		)
		(property "Value" ""
			(at 0 0 90)
			(layer "B.Fab")
			(effects
				(font
					(size 1.27 1.27)
				)
				(justify mirror)
			)
		)
		(duplicate_pad_numbers_are_jumpers no)
		(fp_line
			(start 0.299974 -0.150114)
			(end -0.299974 -0.150114)
			(stroke
				(width 0.1)
				(type default)
			)
			(layer "B.Fab")
		)
		(fp_line
			(start -0.299974 -0.150114)
			(end -0.299974 0.150114)
			(stroke
				(width 0.1)
				(type default)
			)
			(layer "B.Fab")
		)
		(fp_line
			(start 0.299974 0.150114)
			(end 0.299974 -0.150114)
			(stroke
				(width 0.1)
				(type default)
			)
			(layer "B.Fab")
		)
		(fp_line
			(start -0.299974 0.150114)
			(end 0.299974 0.150114)
			(stroke
				(width 0.1)
				(type default)
			)
			(layer "B.Fab")
		)
		(pad "1" smd rect
			(at 0.2667 0 270)
			(size 0.3048 0.381)
			(layers "B.Cu" "B.Mask" "B.Paste")
			(net "P0V8_PEX0")
		)
		(pad "2" smd rect
			(at -0.2667 0 270)
			(size 0.3048 0.381)
			(layers "B.Cu" "B.Mask" "B.Paste")
			(net "GND")
		)
	)
	(footprint ""
		(layer "B.Cu")
		(at 379.766322 -248.203974 180)
		(property "Reference" "R964"
			(at 0 0 0)
			(layer "B.SilkS")
			(hide yes)
			(effects
				(font
					(size 1.27 1.27)
				)
				(justify mirror)
			)
		)
		(property "Value" ""
			(at 0 0 0)
			(layer "B.Fab")
			(effects
				(font
					(size 1.27 1.27)
				)
				(justify mirror)
			)
		)
		(duplicate_pad_numbers_are_jumpers no)
		(fp_line
			(start 0.7874 0.4064)
			(end 0.7874 -0.4064)
			(stroke
				(width 0.1524)
				(type default)
			)
			(layer "B.SilkS")
		)
		(fp_line
			(start 0.7874 -0.4064)
			(end -0.7874 -0.4064)
			(stroke
				(width 0.1524)
				(type default)
			)
			(layer "B.SilkS")
		)
		(fp_line
			(start -0.7874 0.4064)
			(end 0.7874 0.4064)
			(stroke
				(width 0.1524)
				(type default)
			)
			(layer "B.SilkS")
		)
		(fp_line
			(start -0.7874 -0.4064)
			(end -0.7874 0.4064)
			(stroke
				(width 0.1524)
				(type default)
			)
			(layer "B.SilkS")
		)
		(fp_line
			(start 0.67945 0.3048)
			(end 0.67945 -0.305054)
			(stroke
				(width 0.1)
				(type default)
			)
			(layer "B.Fab")
		)
		(fp_line
			(start 0.67945 -0.305054)
			(end 0.12065 -0.305054)
			(stroke
				(width 0.1)
				(type default)
			)
			(layer "B.Fab")
		)
		(fp_line
			(start 0.12065 0.3048)
			(end 0.67945 0.3048)
			(stroke
				(width 0.1)
				(type default)
			)
			(layer "B.Fab")
		)
		(fp_line
			(start 0.12065 0.2794)
			(end 0.12065 0.3048)
			(stroke
				(width 0.1)
				(type default)
			)
			(layer "B.Fab")
		)
		(fp_line
			(start 0.12065 -0.2794)
			(end -0.12065 -0.2794)
			(stroke
				(width 0.1)
				(type default)
			)
			(layer "B.Fab")
		)
		(fp_line
			(start 0.12065 -0.305054)
			(end 0.12065 -0.2794)
			(stroke
				(width 0.1)
				(type default)
			)
			(layer "B.Fab")
		)
		(fp_line
			(start -0.120396 0.3048)
			(end -0.120396 0.2794)
			(stroke
				(width 0.1)
				(type default)
			)
			(layer "B.Fab")
		)
		(fp_line
			(start -0.120396 0.2794)
			(end 0.12065 0.2794)
			(stroke
				(width 0.1)
				(type default)
			)
			(layer "B.Fab")
		)
		(fp_line
			(start -0.12065 -0.2794)
			(end -0.12065 -0.3048)
			(stroke
				(width 0.1)
				(type default)
			)
			(layer "B.Fab")
		)
		(fp_line
			(start -0.12065 -0.3048)
			(end -0.67945 -0.3048)
			(stroke
				(width 0.1)
				(type default)
			)
			(layer "B.Fab")
		)
		(fp_line
			(start -0.67945 0.3048)
			(end -0.120396 0.3048)
			(stroke
				(width 0.1)
				(type default)
			)
			(layer "B.Fab")
		)
		(fp_line
			(start -0.67945 -0.3048)
			(end -0.67945 0.3048)
			(stroke
				(width 0.1)
				(type default)
			)
			(layer "B.Fab")
		)
		(pad "1" smd circle
			(at 0.40005 0)
			(size 0 0)
			(layers "B.Cu" "B.Mask" "B.Paste")
			(net "UART_PEX3_SDB_BUF_TX")
		)
		(pad "2" smd circle
			(at -0.40005 0)
			(size 0 0)
			(layers "B.Cu" "B.Mask" "B.Paste")
			(net "P3V3_AUX")
		)
	)
	(footprint ""
		(layer "B.Cu")
		(at 378.741178 -225.092768 90)
		(property "Reference" "R6173"
			(at 0 0 90)
			(layer "B.SilkS")
			(hide yes)
			(effects
				(font
					(size 1.27 1.27)
				)
				(justify mirror)
			)
		)
		(property "Value" ""
			(at 0 0 90)
			(layer "B.Fab")
			(effects
				(font
					(size 1.27 1.27)
				)
				(justify mirror)
			)
		)
		(duplicate_pad_numbers_are_jumpers no)
		(fp_line
			(start 0.7874 -0.4064)
			(end -0.7874 -0.4064)
			(stroke
				(width 0.1524)
				(type default)
			)
			(layer "B.SilkS")
		)
		(fp_line
			(start -0.7874 -0.4064)
			(end -0.7874 0.4064)
			(stroke
				(width 0.1524)
				(type default)
			)
			(layer "B.SilkS")
		)
		(fp_line
			(start 0.7874 0.4064)
			(end 0.7874 -0.4064)
			(stroke
				(width 0.1524)
				(type default)
			)
			(layer "B.SilkS")
		)
		(fp_line
			(start -0.7874 0.4064)
			(end 0.7874 0.4064)
			(stroke
				(width 0.1524)
				(type default)
			)
			(layer "B.SilkS")
		)
		(fp_line
			(start 0.67945 -0.305054)
			(end 0.12065 -0.305054)
			(stroke
				(width 0.1)
				(type default)
			)
			(layer "B.Fab")
		)
		(fp_line
			(start 0.12065 -0.305054)
			(end 0.12065 -0.2794)
			(stroke
				(width 0.1)
				(type default)
			)
			(layer "B.Fab")
		)
		(fp_line
			(start -0.12065 -0.3048)
			(end -0.67945 -0.3048)
			(stroke
				(width 0.1)
				(type default)
			)
			(layer "B.Fab")
		)
		(fp_line
			(start -0.67945 -0.3048)
			(end -0.67945 0.3048)
			(stroke
				(width 0.1)
				(type default)
			)
			(layer "B.Fab")
		)
		(fp_line
			(start 0.12065 -0.2794)
			(end -0.12065 -0.2794)
			(stroke
				(width 0.1)
				(type default)
			)
			(layer "B.Fab")
		)
		(fp_line
			(start -0.12065 -0.2794)
			(end -0.12065 -0.3048)
			(stroke
				(width 0.1)
				(type default)
			)
			(layer "B.Fab")
		)
		(fp_line
			(start 0.12065 0.2794)
			(end 0.12065 0.3048)
			(stroke
				(width 0.1)
				(type default)
			)
			(layer "B.Fab")
		)
		(fp_line
			(start -0.120396 0.2794)
			(end 0.12065 0.2794)
			(stroke
				(width 0.1)
				(type default)
			)
			(layer "B.Fab")
		)
		(fp_line
			(start 0.67945 0.3048)
			(end 0.67945 -0.305054)
			(stroke
				(width 0.1)
				(type default)
			)
			(layer "B.Fab")
		)
		(fp_line
			(start 0.12065 0.3048)
			(end 0.67945 0.3048)
			(stroke
				(width 0.1)
				(type default)
			)
			(layer "B.Fab")
		)
		(fp_line
			(start -0.120396 0.3048)
			(end -0.120396 0.2794)
			(stroke
				(width 0.1)
				(type default)
			)
			(layer "B.Fab")
		)
		(fp_line
			(start -0.67945 0.3048)
			(end -0.120396 0.3048)
			(stroke
				(width 0.1)
				(type default)
			)
			(layer "B.Fab")
		)
		(pad "1" smd circle
			(at 0.40005 0 270)
			(size 0 0)
			(layers "B.Cu" "B.Mask" "B.Paste")
			(net "SPI_PEX3_RST_R_N")
		)
		(pad "2" smd circle
			(at -0.40005 0 270)
			(size 0 0)
			(layers "B.Cu" "B.Mask" "B.Paste")
			(net "GND")
		)
	)
	(footprint ""
		(layer "B.Cu")
		(at 163.874958 -291.149786 90)
		(property "Reference" "C3233"
			(at 0 0 90)
			(layer "B.SilkS")
			(hide yes)
			(effects
				(font
					(size 1.27 1.27)
				)
				(justify mirror)
			)
		)
		(property "Value" ""
			(at 0 0 90)
			(layer "B.Fab")
			(effects
				(font
					(size 1.27 1.27)
				)
				(justify mirror)
			)
		)
		(duplicate_pad_numbers_are_jumpers no)
		(fp_line
			(start 0.299974 -0.150114)
			(end -0.299974 -0.150114)
			(stroke
				(width 0.1)
				(type default)
			)
			(layer "B.Fab")
		)
		(fp_line
			(start -0.299974 -0.150114)
			(end -0.299974 0.150114)
			(stroke
				(width 0.1)
				(type default)
			)
			(layer "B.Fab")
		)
		(fp_line
			(start 0.299974 0.150114)
			(end 0.299974 -0.150114)
			(stroke
				(width 0.1)
				(type default)
			)
			(layer "B.Fab")
		)
		(fp_line
			(start -0.299974 0.150114)
			(end 0.299974 0.150114)
			(stroke
				(width 0.1)
				(type default)
			)
			(layer "B.Fab")
		)
		(pad "1" smd rect
			(at 0.2667 0 270)
			(size 0.3048 0.381)
			(layers "B.Cu" "B.Mask" "B.Paste")
			(net "PCEPLL7_VDDA18_PEX1")
		)
		(pad "2" smd rect
			(at -0.2667 0 270)
			(size 0.3048 0.381)
			(layers "B.Cu" "B.Mask" "B.Paste")
			(net "GND")
		)
	)
	(footprint ""
		(layer "B.Cu")
		(at 217.235786 -213.222586 180)
		(property "Reference" "R5770"
			(at 0 0 0)
			(layer "B.SilkS")
			(hide yes)
			(effects
				(font
					(size 1.27 1.27)
				)
				(justify mirror)
			)
		)
		(property "Value" ""
			(at 0 0 0)
			(layer "B.Fab")
			(effects
				(font
					(size 1.27 1.27)
				)
				(justify mirror)
			)
		)
		(duplicate_pad_numbers_are_jumpers no)
		(fp_line
			(start 0.7874 0.4064)
			(end 0.7874 -0.4064)
			(stroke
				(width 0.1524)
				(type default)
			)
			(layer "B.SilkS")
		)
		(fp_line
			(start 0.7874 -0.4064)
			(end -0.7874 -0.4064)
			(stroke
				(width 0.1524)
				(type default)
			)
			(layer "B.SilkS")
		)
		(fp_line
			(start -0.7874 0.4064)
			(end 0.7874 0.4064)
			(stroke
				(width 0.1524)
				(type default)
			)
			(layer "B.SilkS")
		)
		(fp_line
			(start -0.7874 -0.4064)
			(end -0.7874 0.4064)
			(stroke
				(width 0.1524)
				(type default)
			)
			(layer "B.SilkS")
		)
		(fp_line
			(start 0.67945 0.3048)
			(end 0.67945 -0.305054)
			(stroke
				(width 0.1)
				(type default)
			)
			(layer "B.Fab")
		)
		(fp_line
			(start 0.67945 -0.305054)
			(end 0.12065 -0.305054)
			(stroke
				(width 0.1)
				(type default)
			)
			(layer "B.Fab")
		)
		(fp_line
			(start 0.12065 0.3048)
			(end 0.67945 0.3048)
			(stroke
				(width 0.1)
				(type default)
			)
			(layer "B.Fab")
		)
		(fp_line
			(start 0.12065 0.2794)
			(end 0.12065 0.3048)
			(stroke
				(width 0.1)
				(type default)
			)
			(layer "B.Fab")
		)
		(fp_line
			(start 0.12065 -0.2794)
			(end -0.12065 -0.2794)
			(stroke
				(width 0.1)
				(type default)
			)
			(layer "B.Fab")
		)
		(fp_line
			(start 0.12065 -0.305054)
			(end 0.12065 -0.2794)
			(stroke
				(width 0.1)
				(type default)
			)
			(layer "B.Fab")
		)
		(fp_line
			(start -0.120396 0.3048)
			(end -0.120396 0.2794)
			(stroke
				(width 0.1)
				(type default)
			)
			(layer "B.Fab")
		)
		(fp_line
			(start -0.120396 0.2794)
			(end 0.12065 0.2794)
			(stroke
				(width 0.1)
				(type default)
			)
			(layer "B.Fab")
		)
		(fp_line
			(start -0.12065 -0.2794)
			(end -0.12065 -0.3048)
			(stroke
				(width 0.1)
				(type default)
			)
			(layer "B.Fab")
		)
		(fp_line
			(start -0.12065 -0.3048)
			(end -0.67945 -0.3048)
			(stroke
				(width 0.1)
				(type default)
			)
			(layer "B.Fab")
		)
		(fp_line
			(start -0.67945 0.3048)
			(end -0.120396 0.3048)
			(stroke
				(width 0.1)
				(type default)
			)
			(layer "B.Fab")
		)
		(fp_line
			(start -0.67945 -0.3048)
			(end -0.67945 0.3048)
			(stroke
				(width 0.1)
				(type default)
			)
			(layer "B.Fab")
		)
		(pad "1" smd circle
			(at 0.40005 0)
			(size 0 0)
			(layers "B.Cu" "B.Mask" "B.Paste")
			(net "RST_BIC_USB_HUB_R_N")
		)
		(pad "2" smd circle
			(at -0.40005 0)
			(size 0 0)
			(layers "B.Cu" "B.Mask" "B.Paste")
			(net "RST_BIC_USB_HUB_N")
		)
	)
	(footprint ""
		(layer "B.Cu")
		(at 295.20134 -305.399948 -90)
		(property "Reference" "C3321"
			(at 0 0 90)
			(layer "B.SilkS")
			(hide yes)
			(effects
				(font
					(size 1.27 1.27)
				)
				(justify mirror)
			)
		)
		(property "Value" ""
			(at 0 0 90)
			(layer "B.Fab")
			(effects
				(font
					(size 1.27 1.27)
				)
				(justify mirror)
			)
		)
		(duplicate_pad_numbers_are_jumpers no)
		(fp_line
			(start -0.299974 0.150114)
			(end 0.299974 0.150114)
			(stroke
				(width 0.1)
				(type default)
			)
			(layer "B.Fab")
		)
		(fp_line
			(start 0.299974 0.150114)
			(end 0.299974 -0.150114)
			(stroke
				(width 0.1)
				(type default)
			)
			(layer "B.Fab")
		)
		(fp_line
			(start -0.299974 -0.150114)
			(end -0.299974 0.150114)
			(stroke
				(width 0.1)
				(type default)
			)
			(layer "B.Fab")
		)
		(fp_line
			(start 0.299974 -0.150114)
			(end -0.299974 -0.150114)
			(stroke
				(width 0.1)
				(type default)
			)
			(layer "B.Fab")
		)
		(pad "1" smd rect
			(at 0.2667 0 90)
			(size 0.3048 0.381)
			(layers "B.Cu" "B.Mask" "B.Paste")
			(net "P1V25_SERDES_VDDPLL_PEX2")
		)
		(pad "2" smd rect
			(at -0.2667 0 90)
			(size 0.3048 0.381)
			(layers "B.Cu" "B.Mask" "B.Paste")
			(net "GND")
		)
	)
	(footprint ""
		(layer "B.Cu")
		(at 296.124884 -293.99992 -90)
		(property "Reference" "C1655"
			(at 0 0 90)
			(layer "B.SilkS")
			(hide yes)
			(effects
				(font
					(size 1.27 1.27)
				)
				(justify mirror)
			)
		)
		(property "Value" ""
			(at 0 0 90)
			(layer "B.Fab")
			(effects
				(font
					(size 1.27 1.27)
				)
				(justify mirror)
			)
		)
		(duplicate_pad_numbers_are_jumpers no)
		(fp_line
			(start -0.299974 0.150114)
			(end 0.299974 0.150114)
			(stroke
				(width 0.1)
				(type default)
			)
			(layer "B.Fab")
		)
		(fp_line
			(start 0.299974 0.150114)
			(end 0.299974 -0.150114)
			(stroke
				(width 0.1)
				(type default)
			)
			(layer "B.Fab")
		)
		(fp_line
			(start -0.299974 -0.150114)
			(end -0.299974 0.150114)
			(stroke
				(width 0.1)
				(type default)
			)
			(layer "B.Fab")
		)
		(fp_line
			(start 0.299974 -0.150114)
			(end -0.299974 -0.150114)
			(stroke
				(width 0.1)
				(type default)
			)
			(layer "B.Fab")
		)
		(pad "1" smd rect
			(at 0.2667 0 90)
			(size 0.3048 0.381)
			(layers "B.Cu" "B.Mask" "B.Paste")
			(net "P0V8_PEX2")
		)
		(pad "2" smd rect
			(at -0.2667 0 90)
			(size 0.3048 0.381)
			(layers "B.Cu" "B.Mask" "B.Paste")
			(net "GND")
		)
	)
	(footprint ""
		(layer "B.Cu")
		(at 234.048046 -154.143202 90)
		(property "Reference" "L79"
			(at 0 0 90)
			(layer "B.SilkS")
			(hide yes)
			(effects
				(font
					(size 1.27 1.27)
				)
				(justify mirror)
			)
		)
		(property "Value" ""
			(at 0 0 90)
			(layer "B.Fab")
			(effects
				(font
					(size 1.27 1.27)
				)
				(justify mirror)
			)
		)
		(duplicate_pad_numbers_are_jumpers no)
		(fp_line
			(start 1.63576 -0.8128)
			(end -1.63576 -0.8128)
			(stroke
				(width 0.1524)
				(type default)
			)
			(layer "B.SilkS")
		)
		(fp_line
			(start 1.63576 -0.8128)
			(end 1.63576 0.8128)
			(stroke
				(width 0.1524)
				(type default)
			)
			(layer "B.SilkS")
		)
		(fp_line
			(start -1.63576 -0.8128)
			(end -1.63576 0.8128)
			(stroke
				(width 0.1524)
				(type default)
			)
			(layer "B.SilkS")
		)
		(fp_line
			(start -1.63576 0.8128)
			(end 1.63576 0.8128)
			(stroke
				(width 0.1524)
				(type default)
			)
			(layer "B.SilkS")
		)
		(fp_line
			(start 1.56083 -0.738632)
			(end 1.56083 0.7366)
			(stroke
				(width 0.1)
				(type default)
			)
			(layer "B.Fab")
		)
		(fp_line
			(start -1.560576 -0.738632)
			(end 1.56083 -0.738632)
			(stroke
				(width 0.1)
				(type default)
			)
			(layer "B.Fab")
		)
		(fp_line
			(start 1.56083 0.7366)
			(end 1.524 0.7366)
			(stroke
				(width 0.1)
				(type default)
			)
			(layer "B.Fab")
		)
		(fp_line
			(start 1.524 0.7366)
			(end -1.524 0.7366)
			(stroke
				(width 0.1)
				(type default)
			)
			(layer "B.Fab")
		)
		(fp_line
			(start -1.524 0.7366)
			(end -1.560576 0.7366)
			(stroke
				(width 0.1)
				(type default)
			)
			(layer "B.Fab")
		)
		(fp_line
			(start -1.560576 0.7366)
			(end -1.560576 -0.738632)
			(stroke
				(width 0.1)
				(type default)
			)
			(layer "B.Fab")
		)
		(pad "1" smd rect
			(at 0.94996 0 90)
			(size 1.1176 1.3716)
			(layers "B.Cu" "B.Mask" "B.Paste")
			(net "P3V3")
		)
		(pad "2" smd rect
			(at -0.94996 0 90)
			(size 1.1176 1.3716)
			(layers "B.Cu" "B.Mask" "B.Paste")
			(net "P3V3_CLK_GEN_VDD_CK440_PEX")
		)
	)
	(footprint ""
		(layer "B.Cu")
		(at 178.599846 -303.499774 -90)
		(property "Reference" "C3085"
			(at 0 0 90)
			(layer "B.SilkS")
			(hide yes)
			(effects
				(font
					(size 1.27 1.27)
				)
				(justify mirror)
			)
		)
		(property "Value" ""
			(at 0 0 90)
			(layer "B.Fab")
			(effects
				(font
					(size 1.27 1.27)
				)
				(justify mirror)
			)
		)
		(duplicate_pad_numbers_are_jumpers no)
		(fp_line
			(start -0.299974 0.150114)
			(end 0.299974 0.150114)
			(stroke
				(width 0.1)
				(type default)
			)
			(layer "B.Fab")
		)
		(fp_line
			(start 0.299974 0.150114)
			(end 0.299974 -0.150114)
			(stroke
				(width 0.1)
				(type default)
			)
			(layer "B.Fab")
		)
		(fp_line
			(start -0.299974 -0.150114)
			(end -0.299974 0.150114)
			(stroke
				(width 0.1)
				(type default)
			)
			(layer "B.Fab")
		)
		(fp_line
			(start 0.299974 -0.150114)
			(end -0.299974 -0.150114)
			(stroke
				(width 0.1)
				(type default)
			)
			(layer "B.Fab")
		)
		(pad "1" smd rect
			(at 0.2667 0 90)
			(size 0.3048 0.381)
			(layers "B.Cu" "B.Mask" "B.Paste")
			(net "P1V25_PEX1")
		)
		(pad "2" smd rect
			(at -0.2667 0 90)
			(size 0.3048 0.381)
			(layers "B.Cu" "B.Mask" "B.Paste")
			(net "GND")
		)
	)
	(footprint ""
		(layer "B.Cu")
		(at 255.63068 -89.904316 180)
		(property "Reference" "R1047"
			(at 0 0 0)
			(layer "B.SilkS")
			(hide yes)
			(effects
				(font
					(size 1.27 1.27)
				)
				(justify mirror)
			)
		)
		(property "Value" ""
			(at 0 0 0)
			(layer "B.Fab")
			(effects
				(font
					(size 1.27 1.27)
				)
				(justify mirror)
			)
		)
		(duplicate_pad_numbers_are_jumpers no)
		(fp_line
			(start 1.2954 0.5842)
			(end 1.2954 -0.5842)
			(stroke
				(width 0.1524)
				(type default)
			)
			(layer "B.SilkS")
		)
		(fp_line
			(start 1.2954 -0.5842)
			(end -1.2954 -0.5842)
			(stroke
				(width 0.1524)
				(type default)
			)
			(layer "B.SilkS")
		)
		(fp_line
			(start -1.2954 0.5842)
			(end 1.2954 0.5842)
			(stroke
				(width 0.1524)
				(type default)
			)
			(layer "B.SilkS")
		)
		(fp_line
			(start -1.2954 -0.5842)
			(end -1.2954 0.5842)
			(stroke
				(width 0.1524)
				(type default)
			)
			(layer "B.SilkS")
		)
		(fp_line
			(start 1.1938 0.4064)
			(end 1.1938 -0.406654)
			(stroke
				(width 0.1)
				(type default)
			)
			(layer "B.Fab")
		)
		(fp_line
			(start 1.1938 -0.406654)
			(end 0.8636 -0.406654)
			(stroke
				(width 0.1)
				(type default)
			)
			(layer "B.Fab")
		)
		(fp_line
			(start 0.8636 0.4572)
			(end 0.8636 0.4318)
			(stroke
				(width 0.1)
				(type default)
			)
			(layer "B.Fab")
		)
		(fp_line
			(start 0.8636 0.4318)
			(end 0.8636 0.4064)
			(stroke
				(width 0.1)
				(type default)
			)
			(layer "B.Fab")
		)
		(fp_line
			(start 0.8636 0.4064)
			(end 1.1938 0.4064)
			(stroke
				(width 0.1)
				(type default)
			)
			(layer "B.Fab")
		)
		(fp_line
			(start 0.8636 -0.406654)
			(end 0.8636 -0.4572)
			(stroke
				(width 0.1)
				(type default)
			)
			(layer "B.Fab")
		)
		(fp_line
			(start 0.8636 -0.4572)
			(end -0.8636 -0.4572)
			(stroke
				(width 0.1)
				(type default)
			)
			(layer "B.Fab")
		)
		(fp_line
			(start -0.8636 0.4572)
			(end 0.8636 0.4572)
			(stroke
				(width 0.1)
				(type default)
			)
			(layer "B.Fab")
		)
		(fp_line
			(start -0.8636 0.4064)
			(end -0.8636 0.4572)
			(stroke
				(width 0.1)
				(type default)
			)
			(layer "B.Fab")
		)
		(fp_line
			(start -0.8636 -0.406654)
			(end -1.1938 -0.406654)
			(stroke
				(width 0.1)
				(type default)
			)
			(layer "B.Fab")
		)
		(fp_line
			(start -0.8636 -0.4572)
			(end -0.8636 -0.406654)
			(stroke
				(width 0.1)
				(type default)
			)
			(layer "B.Fab")
		)
		(fp_line
			(start -1.1938 0.4064)
			(end -0.8636 0.4064)
			(stroke
				(width 0.1)
				(type default)
			)
			(layer "B.Fab")
		)
		(fp_line
			(start -1.1938 -0.406654)
			(end -1.1938 0.4064)
			(stroke
				(width 0.1)
				(type default)
			)
			(layer "B.Fab")
		)
		(pad "1" smd rect
			(at 0.7366 0 90)
			(size 0.7112 0.8128)
			(layers "B.Cu" "B.Mask" "B.Paste")
			(net "P3V3_CLK_GEN_VDDXTAL_CK440")
		)
		(pad "2" smd rect
			(at -0.7366 0 90)
			(size 0.7112 0.8128)
			(layers "B.Cu" "B.Mask" "B.Paste")
			(net "P3V3_CLK_GEN_VDDA25M_CK440")
		)
	)
	(footprint ""
		(layer "B.Cu")
		(at 335.309464 -219.234512 180)
		(property "Reference" "C2080"
			(at 0 0 0)
			(layer "B.SilkS")
			(hide yes)
			(effects
				(font
					(size 1.27 1.27)
				)
				(justify mirror)
			)
		)
		(property "Value" ""
			(at 0 0 0)
			(layer "B.Fab")
			(effects
				(font
					(size 1.27 1.27)
				)
				(justify mirror)
			)
		)
		(duplicate_pad_numbers_are_jumpers no)
		(fp_line
			(start 0.69215 0.2921)
			(end 0.69215 -0.2921)
			(stroke
				(width 0.1524)
				(type default)
			)
			(layer "B.SilkS")
		)
		(fp_line
			(start 0.69215 -0.2921)
			(end -0.69215 -0.2921)
			(stroke
				(width 0.1524)
				(type default)
			)
			(layer "B.SilkS")
		)
		(fp_line
			(start -0.69215 0.2921)
			(end 0.69215 0.2921)
			(stroke
				(width 0.1524)
				(type default)
			)
			(layer "B.SilkS")
		)
		(fp_line
			(start -0.69215 -0.2921)
			(end -0.69215 0.2921)
			(stroke
				(width 0.1524)
				(type default)
			)
			(layer "B.SilkS")
		)
		(fp_line
			(start 0.51435 0.2794)
			(end 0.51435 -0.2794)
			(stroke
				(width 0.1)
				(type default)
			)
			(layer "B.Fab")
		)
		(fp_line
			(start 0.51435 -0.2794)
			(end -0.51435 -0.2794)
			(stroke
				(width 0.1)
				(type default)
			)
			(layer "B.Fab")
		)
		(fp_line
			(start -0.51435 0.2794)
			(end 0.51435 0.2794)
			(stroke
				(width 0.1)
				(type default)
			)
			(layer "B.Fab")
		)
		(fp_line
			(start -0.51435 -0.2794)
			(end -0.51435 0.2794)
			(stroke
				(width 0.1)
				(type default)
			)
			(layer "B.Fab")
		)
		(pad "1" smd circle
			(at 0.40005 0)
			(size 0 0)
			(layers "B.Cu" "B.Mask" "B.Paste")
			(net "P3V3_FPGA_VCCIO4")
		)
		(pad "2" smd circle
			(at -0.40005 0)
			(size 0 0)
			(layers "B.Cu" "B.Mask" "B.Paste")
			(net "GND")
		)
		(zone
			(layer "B.Cu")
			(hatch none 0.5)
			(connect_pads
				(clearance 0)
			)
			(min_thickness 0.25)
			(keepout
				(tracks not_allowed)
				(vias allowed)
				(pads allowed)
				(copperpour not_allowed)
				(footprints allowed)
			)
			(placement
				(enabled no)
				(sheetname "")
			)
			(fill
				(thermal_gap 0.5)
				(thermal_bridge_width 0.5)
				(island_removal_mode 0)
			)
			(polygon
				(pts
					(xy 335.118964 -219.322142) (xy 335.210404 -219.380308) (xy 335.409794 -219.380308) (xy 335.499964 -219.322142)
					(xy 335.499964 -219.146882) (xy 335.409794 -219.088462) (xy 335.210404 -219.088462) (xy 335.118964 -219.146628)
				)
			)
		)
	)
	(footprint ""
		(layer "B.Cu")
		(at 175.749966 -303.499774 -90)
		(property "Reference" "C3084"
			(at 0 0 90)
			(layer "B.SilkS")
			(hide yes)
			(effects
				(font
					(size 1.27 1.27)
				)
				(justify mirror)
			)
		)
		(property "Value" ""
			(at 0 0 90)
			(layer "B.Fab")
			(effects
				(font
					(size 1.27 1.27)
				)
				(justify mirror)
			)
		)
		(duplicate_pad_numbers_are_jumpers no)
		(fp_line
			(start -0.299974 0.150114)
			(end 0.299974 0.150114)
			(stroke
				(width 0.1)
				(type default)
			)
			(layer "B.Fab")
		)
		(fp_line
			(start 0.299974 0.150114)
			(end 0.299974 -0.150114)
			(stroke
				(width 0.1)
				(type default)
			)
			(layer "B.Fab")
		)
		(fp_line
			(start -0.299974 -0.150114)
			(end -0.299974 0.150114)
			(stroke
				(width 0.1)
				(type default)
			)
			(layer "B.Fab")
		)
		(fp_line
			(start 0.299974 -0.150114)
			(end -0.299974 -0.150114)
			(stroke
				(width 0.1)
				(type default)
			)
			(layer "B.Fab")
		)
		(pad "1" smd rect
			(at 0.2667 0 90)
			(size 0.3048 0.381)
			(layers "B.Cu" "B.Mask" "B.Paste")
			(net "P1V25_PEX1")
		)
		(pad "2" smd rect
			(at -0.2667 0 90)
			(size 0.3048 0.381)
			(layers "B.Cu" "B.Mask" "B.Paste")
			(net "GND")
		)
	)
	(footprint ""
		(layer "B.Cu")
		(at 133.030214 -213.524846 180)
		(property "Reference" "R997"
			(at 0 0 0)
			(layer "B.SilkS")
			(hide yes)
			(effects
				(font
					(size 1.27 1.27)
				)
				(justify mirror)
			)
		)
		(property "Value" ""
			(at 0 0 0)
			(layer "B.Fab")
			(effects
				(font
					(size 1.27 1.27)
				)
				(justify mirror)
			)
		)
		(duplicate_pad_numbers_are_jumpers no)
		(fp_line
			(start 0.7874 0.4064)
			(end 0.7874 -0.4064)
			(stroke
				(width 0.1524)
				(type default)
			)
			(layer "B.SilkS")
		)
		(fp_line
			(start 0.7874 -0.4064)
			(end -0.7874 -0.4064)
			(stroke
				(width 0.1524)
				(type default)
			)
			(layer "B.SilkS")
		)
		(fp_line
			(start -0.7874 0.4064)
			(end 0.7874 0.4064)
			(stroke
				(width 0.1524)
				(type default)
			)
			(layer "B.SilkS")
		)
		(fp_line
			(start -0.7874 -0.4064)
			(end -0.7874 0.4064)
			(stroke
				(width 0.1524)
				(type default)
			)
			(layer "B.SilkS")
		)
		(fp_line
			(start 0.67945 0.3048)
			(end 0.67945 -0.305054)
			(stroke
				(width 0.1)
				(type default)
			)
			(layer "B.Fab")
		)
		(fp_line
			(start 0.67945 -0.305054)
			(end 0.12065 -0.305054)
			(stroke
				(width 0.1)
				(type default)
			)
			(layer "B.Fab")
		)
		(fp_line
			(start 0.12065 0.3048)
			(end 0.67945 0.3048)
			(stroke
				(width 0.1)
				(type default)
			)
			(layer "B.Fab")
		)
		(fp_line
			(start 0.12065 0.2794)
			(end 0.12065 0.3048)
			(stroke
				(width 0.1)
				(type default)
			)
			(layer "B.Fab")
		)
		(fp_line
			(start 0.12065 -0.2794)
			(end -0.12065 -0.2794)
			(stroke
				(width 0.1)
				(type default)
			)
			(layer "B.Fab")
		)
		(fp_line
			(start 0.12065 -0.305054)
			(end 0.12065 -0.2794)
			(stroke
				(width 0.1)
				(type default)
			)
			(layer "B.Fab")
		)
		(fp_line
			(start -0.120396 0.3048)
			(end -0.120396 0.2794)
			(stroke
				(width 0.1)
				(type default)
			)
			(layer "B.Fab")
		)
		(fp_line
			(start -0.120396 0.2794)
			(end 0.12065 0.2794)
			(stroke
				(width 0.1)
				(type default)
			)
			(layer "B.Fab")
		)
		(fp_line
			(start -0.12065 -0.2794)
			(end -0.12065 -0.3048)
			(stroke
				(width 0.1)
				(type default)
			)
			(layer "B.Fab")
		)
		(fp_line
			(start -0.12065 -0.3048)
			(end -0.67945 -0.3048)
			(stroke
				(width 0.1)
				(type default)
			)
			(layer "B.Fab")
		)
		(fp_line
			(start -0.67945 0.3048)
			(end -0.120396 0.3048)
			(stroke
				(width 0.1)
				(type default)
			)
			(layer "B.Fab")
		)
		(fp_line
			(start -0.67945 -0.3048)
			(end -0.67945 0.3048)
			(stroke
				(width 0.1)
				(type default)
			)
			(layer "B.Fab")
		)
		(pad "1" smd circle
			(at 0.40005 0)
			(size 0 0)
			(layers "B.Cu" "B.Mask" "B.Paste")
			(net "UART_PEX2_CLI_BUF_R_TX")
		)
		(pad "2" smd circle
			(at -0.40005 0)
			(size 0 0)
			(layers "B.Cu" "B.Mask" "B.Paste")
			(net "UART_PEX2_CLI_BUF_TX")
		)
	)
	(footprint ""
		(layer "B.Cu")
		(at 411.750002 -288.299906 90)
		(property "Reference" "C3442"
			(at 0 0 90)
			(layer "B.SilkS")
			(hide yes)
			(effects
				(font
					(size 1.27 1.27)
				)
				(justify mirror)
			)
		)
		(property "Value" ""
			(at 0 0 90)
			(layer "B.Fab")
			(effects
				(font
					(size 1.27 1.27)
				)
				(justify mirror)
			)
		)
		(duplicate_pad_numbers_are_jumpers no)
		(fp_line
			(start 0.299974 -0.150114)
			(end -0.299974 -0.150114)
			(stroke
				(width 0.1)
				(type default)
			)
			(layer "B.Fab")
		)
		(fp_line
			(start -0.299974 -0.150114)
			(end -0.299974 0.150114)
			(stroke
				(width 0.1)
				(type default)
			)
			(layer "B.Fab")
		)
		(fp_line
			(start 0.299974 0.150114)
			(end 0.299974 -0.150114)
			(stroke
				(width 0.1)
				(type default)
			)
			(layer "B.Fab")
		)
		(fp_line
			(start -0.299974 0.150114)
			(end 0.299974 0.150114)
			(stroke
				(width 0.1)
				(type default)
			)
			(layer "B.Fab")
		)
		(pad "1" smd rect
			(at 0.2667 0 270)
			(size 0.3048 0.381)
			(layers "B.Cu" "B.Mask" "B.Paste")
			(net "P1V25_PEX3")
		)
		(pad "2" smd rect
			(at -0.2667 0 270)
			(size 0.3048 0.381)
			(layers "B.Cu" "B.Mask" "B.Paste")
			(net "GND")
		)
	)
	(footprint ""
		(layer "B.Cu")
		(at 130.893058 -227.965 180)
		(property "Reference" "R3469"
			(at 0 0 0)
			(layer "B.SilkS")
			(hide yes)
			(effects
				(font
					(size 1.27 1.27)
				)
				(justify mirror)
			)
		)
		(property "Value" ""
			(at 0 0 0)
			(layer "B.Fab")
			(effects
				(font
					(size 1.27 1.27)
				)
				(justify mirror)
			)
		)
		(duplicate_pad_numbers_are_jumpers no)
		(fp_line
			(start 0.7874 0.4064)
			(end 0.7874 -0.4064)
			(stroke
				(width 0.1524)
				(type default)
			)
			(layer "B.SilkS")
		)
		(fp_line
			(start 0.7874 -0.4064)
			(end -0.7874 -0.4064)
			(stroke
				(width 0.1524)
				(type default)
			)
			(layer "B.SilkS")
		)
		(fp_line
			(start -0.7874 0.4064)
			(end 0.7874 0.4064)
			(stroke
				(width 0.1524)
				(type default)
			)
			(layer "B.SilkS")
		)
		(fp_line
			(start -0.7874 -0.4064)
			(end -0.7874 0.4064)
			(stroke
				(width 0.1524)
				(type default)
			)
			(layer "B.SilkS")
		)
		(fp_line
			(start 0.67945 0.3048)
			(end 0.67945 -0.305054)
			(stroke
				(width 0.1)
				(type default)
			)
			(layer "B.Fab")
		)
		(fp_line
			(start 0.67945 -0.305054)
			(end 0.12065 -0.305054)
			(stroke
				(width 0.1)
				(type default)
			)
			(layer "B.Fab")
		)
		(fp_line
			(start 0.12065 0.3048)
			(end 0.67945 0.3048)
			(stroke
				(width 0.1)
				(type default)
			)
			(layer "B.Fab")
		)
		(fp_line
			(start 0.12065 0.2794)
			(end 0.12065 0.3048)
			(stroke
				(width 0.1)
				(type default)
			)
			(layer "B.Fab")
		)
		(fp_line
			(start 0.12065 -0.2794)
			(end -0.12065 -0.2794)
			(stroke
				(width 0.1)
				(type default)
			)
			(layer "B.Fab")
		)
		(fp_line
			(start 0.12065 -0.305054)
			(end 0.12065 -0.2794)
			(stroke
				(width 0.1)
				(type default)
			)
			(layer "B.Fab")
		)
		(fp_line
			(start -0.120396 0.3048)
			(end -0.120396 0.2794)
			(stroke
				(width 0.1)
				(type default)
			)
			(layer "B.Fab")
		)
		(fp_line
			(start -0.120396 0.2794)
			(end 0.12065 0.2794)
			(stroke
				(width 0.1)
				(type default)
			)
			(layer "B.Fab")
		)
		(fp_line
			(start -0.12065 -0.2794)
			(end -0.12065 -0.3048)
			(stroke
				(width 0.1)
				(type default)
			)
			(layer "B.Fab")
		)
		(fp_line
			(start -0.12065 -0.3048)
			(end -0.67945 -0.3048)
			(stroke
				(width 0.1)
				(type default)
			)
			(layer "B.Fab")
		)
		(fp_line
			(start -0.67945 0.3048)
			(end -0.120396 0.3048)
			(stroke
				(width 0.1)
				(type default)
			)
			(layer "B.Fab")
		)
		(fp_line
			(start -0.67945 -0.3048)
			(end -0.67945 0.3048)
			(stroke
				(width 0.1)
				(type default)
			)
			(layer "B.Fab")
		)
		(pad "1" smd circle
			(at 0.40005 0)
			(size 0 0)
			(layers "B.Cu" "B.Mask" "B.Paste")
			(net "SPI_PEX1_SDIO2_R1")
		)
		(pad "2" smd circle
			(at -0.40005 0)
			(size 0 0)
			(layers "B.Cu" "B.Mask" "B.Paste")
			(net "GND")
		)
	)
	(footprint ""
		(layer "B.Cu")
		(at 299.95114 -305.399948 -90)
		(property "Reference" "C3323"
			(at 0 0 90)
			(layer "B.SilkS")
			(hide yes)
			(effects
				(font
					(size 1.27 1.27)
				)
				(justify mirror)
			)
		)
		(property "Value" ""
			(at 0 0 90)
			(layer "B.Fab")
			(effects
				(font
					(size 1.27 1.27)
				)
				(justify mirror)
			)
		)
		(duplicate_pad_numbers_are_jumpers no)
		(fp_line
			(start -0.299974 0.150114)
			(end 0.299974 0.150114)
			(stroke
				(width 0.1)
				(type default)
			)
			(layer "B.Fab")
		)
		(fp_line
			(start 0.299974 0.150114)
			(end 0.299974 -0.150114)
			(stroke
				(width 0.1)
				(type default)
			)
			(layer "B.Fab")
		)
		(fp_line
			(start -0.299974 -0.150114)
			(end -0.299974 0.150114)
			(stroke
				(width 0.1)
				(type default)
			)
			(layer "B.Fab")
		)
		(fp_line
			(start 0.299974 -0.150114)
			(end -0.299974 -0.150114)
			(stroke
				(width 0.1)
				(type default)
			)
			(layer "B.Fab")
		)
		(pad "1" smd rect
			(at 0.2667 0 90)
			(size 0.3048 0.381)
			(layers "B.Cu" "B.Mask" "B.Paste")
			(net "P1V25_SERDES_VDDPLL_PEX2")
		)
		(pad "2" smd rect
			(at -0.2667 0 90)
			(size 0.3048 0.381)
			(layers "B.Cu" "B.Mask" "B.Paste")
			(net "GND")
		)
	)
	(footprint ""
		(layer "B.Cu")
		(at 398.46504 -301.599854 -90)
		(property "Reference" "C1952"
			(at 0 0 90)
			(layer "B.SilkS")
			(hide yes)
			(effects
				(font
					(size 1.27 1.27)
				)
				(justify mirror)
			)
		)
		(property "Value" ""
			(at 0 0 90)
			(layer "B.Fab")
			(effects
				(font
					(size 1.27 1.27)
				)
				(justify mirror)
			)
		)
		(duplicate_pad_numbers_are_jumpers no)
		(fp_line
			(start -0.299974 0.150114)
			(end 0.299974 0.150114)
			(stroke
				(width 0.1)
				(type default)
			)
			(layer "B.Fab")
		)
		(fp_line
			(start 0.299974 0.150114)
			(end 0.299974 -0.150114)
			(stroke
				(width 0.1)
				(type default)
			)
			(layer "B.Fab")
		)
		(fp_line
			(start -0.299974 -0.150114)
			(end -0.299974 0.150114)
			(stroke
				(width 0.1)
				(type default)
			)
			(layer "B.Fab")
		)
		(fp_line
			(start 0.299974 -0.150114)
			(end -0.299974 -0.150114)
			(stroke
				(width 0.1)
				(type default)
			)
			(layer "B.Fab")
		)
		(pad "1" smd rect
			(at 0.2667 0 90)
			(size 0.3048 0.381)
			(layers "B.Cu" "B.Mask" "B.Paste")
			(net "P0V8_SERDES_VDDA_PEX3")
		)
		(pad "2" smd rect
			(at -0.2667 0 90)
			(size 0.3048 0.381)
			(layers "B.Cu" "B.Mask" "B.Paste")
			(net "GND")
		)
	)
	(footprint ""
		(layer "B.Cu")
		(at 186.203844 -98.552)
		(property "Reference" "R176"
			(at 0 0 0)
			(layer "B.SilkS")
			(hide yes)
			(effects
				(font
					(size 1.27 1.27)
				)
				(justify mirror)
			)
		)
		(property "Value" ""
			(at 0 0 0)
			(layer "B.Fab")
			(effects
				(font
					(size 1.27 1.27)
				)
				(justify mirror)
			)
		)
		(duplicate_pad_numbers_are_jumpers no)
		(fp_line
			(start -0.7874 -0.4064)
			(end -0.7874 0.4064)
			(stroke
				(width 0.1524)
				(type default)
			)
			(layer "B.SilkS")
		)
		(fp_line
			(start -0.7874 0.4064)
			(end 0.7874 0.4064)
			(stroke
				(width 0.1524)
				(type default)
			)
			(layer "B.SilkS")
		)
		(fp_line
			(start 0.7874 -0.4064)
			(end -0.7874 -0.4064)
			(stroke
				(width 0.1524)
				(type default)
			)
			(layer "B.SilkS")
		)
		(fp_line
			(start 0.7874 0.4064)
			(end 0.7874 -0.4064)
			(stroke
				(width 0.1524)
				(type default)
			)
			(layer "B.SilkS")
		)
		(fp_line
			(start -0.67945 -0.3048)
			(end -0.67945 0.3048)
			(stroke
				(width 0.1)
				(type default)
			)
			(layer "B.Fab")
		)
		(fp_line
			(start -0.67945 0.3048)
			(end -0.120396 0.3048)
			(stroke
				(width 0.1)
				(type default)
			)
			(layer "B.Fab")
		)
		(fp_line
			(start -0.12065 -0.3048)
			(end -0.67945 -0.3048)
			(stroke
				(width 0.1)
				(type default)
			)
			(layer "B.Fab")
		)
		(fp_line
			(start -0.12065 -0.2794)
			(end -0.12065 -0.3048)
			(stroke
				(width 0.1)
				(type default)
			)
			(layer "B.Fab")
		)
		(fp_line
			(start -0.120396 0.2794)
			(end 0.12065 0.2794)
			(stroke
				(width 0.1)
				(type default)
			)
			(layer "B.Fab")
		)
		(fp_line
			(start -0.120396 0.3048)
			(end -0.120396 0.2794)
			(stroke
				(width 0.1)
				(type default)
			)
			(layer "B.Fab")
		)
		(fp_line
			(start 0.12065 -0.305054)
			(end 0.12065 -0.2794)
			(stroke
				(width 0.1)
				(type default)
			)
			(layer "B.Fab")
		)
		(fp_line
			(start 0.12065 -0.2794)
			(end -0.12065 -0.2794)
			(stroke
				(width 0.1)
				(type default)
			)
			(layer "B.Fab")
		)
		(fp_line
			(start 0.12065 0.2794)
			(end 0.12065 0.3048)
			(stroke
				(width 0.1)
				(type default)
			)
			(layer "B.Fab")
		)
		(fp_line
			(start 0.12065 0.3048)
			(end 0.67945 0.3048)
			(stroke
				(width 0.1)
				(type default)
			)
			(layer "B.Fab")
		)
		(fp_line
			(start 0.67945 -0.305054)
			(end 0.12065 -0.305054)
			(stroke
				(width 0.1)
				(type default)
			)
			(layer "B.Fab")
		)
		(fp_line
			(start 0.67945 0.3048)
			(end 0.67945 -0.305054)
			(stroke
				(width 0.1)
				(type default)
			)
			(layer "B.Fab")
		)
		(pad "1" smd circle
			(at 0.40005 0 180)
			(size 0 0)
			(layers "B.Cu" "B.Mask" "B.Paste")
			(net "NIC3_MAIN_PWR_EN")
		)
		(pad "2" smd circle
			(at -0.40005 0 180)
			(size 0 0)
			(layers "B.Cu" "B.Mask" "B.Paste")
			(net "GND")
		)
	)
	(footprint ""
		(layer "B.Cu")
		(at 342.893396 -221.98711 90)
		(property "Reference" "C2032"
			(at 0 0 90)
			(layer "B.SilkS")
			(hide yes)
			(effects
				(font
					(size 1.27 1.27)
				)
				(justify mirror)
			)
		)
		(property "Value" ""
			(at 0 0 90)
			(layer "B.Fab")
			(effects
				(font
					(size 1.27 1.27)
				)
				(justify mirror)
			)
		)
		(duplicate_pad_numbers_are_jumpers no)
		(fp_line
			(start 0.69215 -0.2921)
			(end -0.69215 -0.2921)
			(stroke
				(width 0.1524)
				(type default)
			)
			(layer "B.SilkS")
		)
		(fp_line
			(start -0.69215 -0.2921)
			(end -0.69215 0.2921)
			(stroke
				(width 0.1524)
				(type default)
			)
			(layer "B.SilkS")
		)
		(fp_line
			(start 0.69215 0.2921)
			(end 0.69215 -0.2921)
			(stroke
				(width 0.1524)
				(type default)
			)
			(layer "B.SilkS")
		)
		(fp_line
			(start -0.69215 0.2921)
			(end 0.69215 0.2921)
			(stroke
				(width 0.1524)
				(type default)
			)
			(layer "B.SilkS")
		)
		(fp_line
			(start 0.51435 -0.2794)
			(end -0.51435 -0.2794)
			(stroke
				(width 0.1)
				(type default)
			)
			(layer "B.Fab")
		)
		(fp_line
			(start -0.51435 -0.2794)
			(end -0.51435 0.2794)
			(stroke
				(width 0.1)
				(type default)
			)
			(layer "B.Fab")
		)
		(fp_line
			(start 0.51435 0.2794)
			(end 0.51435 -0.2794)
			(stroke
				(width 0.1)
				(type default)
			)
			(layer "B.Fab")
		)
		(fp_line
			(start -0.51435 0.2794)
			(end 0.51435 0.2794)
			(stroke
				(width 0.1)
				(type default)
			)
			(layer "B.Fab")
		)
		(pad "1" smd circle
			(at 0.40005 0 270)
			(size 0 0)
			(layers "B.Cu" "B.Mask" "B.Paste")
			(net "P3V3_FPGA_VCCIO0")
		)
		(pad "2" smd circle
			(at -0.40005 0 270)
			(size 0 0)
			(layers "B.Cu" "B.Mask" "B.Paste")
			(net "GND")
		)
		(zone
			(layer "B.Cu")
			(hatch none 0.5)
			(connect_pads
				(clearance 0)
			)
			(min_thickness 0.25)
			(keepout
				(tracks not_allowed)
				(vias allowed)
				(pads allowed)
				(copperpour not_allowed)
				(footprints allowed)
			)
			(placement
				(enabled no)
				(sheetname "")
			)
			(fill
				(thermal_gap 0.5)
				(thermal_bridge_width 0.5)
				(island_removal_mode 0)
			)
			(polygon
				(pts
					(xy 342.981026 -222.17761) (xy 343.039192 -222.08617) (xy 343.039192 -221.88678) (xy 342.981026 -221.79661)
					(xy 342.805766 -221.79661) (xy 342.747346 -221.88678) (xy 342.747346 -222.08617) (xy 342.805512 -222.17761)
				)
			)
		)
	)
	(footprint ""
		(layer "B.Cu")
		(at 240.43767 -219.639134 180)
		(property "Reference" "C3619"
			(at 0 0 0)
			(layer "B.SilkS")
			(hide yes)
			(effects
				(font
					(size 1.27 1.27)
				)
				(justify mirror)
			)
		)
		(property "Value" ""
			(at 0 0 0)
			(layer "B.Fab")
			(effects
				(font
					(size 1.27 1.27)
				)
				(justify mirror)
			)
		)
		(duplicate_pad_numbers_are_jumpers no)
		(fp_line
			(start 0.69215 0.2921)
			(end 0.69215 -0.2921)
			(stroke
				(width 0.1524)
				(type default)
			)
			(layer "B.SilkS")
		)
		(fp_line
			(start 0.69215 -0.2921)
			(end -0.69215 -0.2921)
			(stroke
				(width 0.1524)
				(type default)
			)
			(layer "B.SilkS")
		)
		(fp_line
			(start -0.69215 0.2921)
			(end 0.69215 0.2921)
			(stroke
				(width 0.1524)
				(type default)
			)
			(layer "B.SilkS")
		)
		(fp_line
			(start -0.69215 -0.2921)
			(end -0.69215 0.2921)
			(stroke
				(width 0.1524)
				(type default)
			)
			(layer "B.SilkS")
		)
		(fp_line
			(start 0.51435 0.2794)
			(end 0.51435 -0.2794)
			(stroke
				(width 0.1)
				(type default)
			)
			(layer "B.Fab")
		)
		(fp_line
			(start 0.51435 -0.2794)
			(end -0.51435 -0.2794)
			(stroke
				(width 0.1)
				(type default)
			)
			(layer "B.Fab")
		)
		(fp_line
			(start -0.51435 0.2794)
			(end 0.51435 0.2794)
			(stroke
				(width 0.1)
				(type default)
			)
			(layer "B.Fab")
		)
		(fp_line
			(start -0.51435 -0.2794)
			(end -0.51435 0.2794)
			(stroke
				(width 0.1)
				(type default)
			)
			(layer "B.Fab")
		)
		(pad "1" smd circle
			(at 0.40005 0)
			(size 0 0)
			(layers "B.Cu" "B.Mask" "B.Paste")
			(net "BIC_ADCVREFN1")
		)
		(pad "2" smd circle
			(at -0.40005 0)
			(size 0 0)
			(layers "B.Cu" "B.Mask" "B.Paste")
			(net "GND")
		)
		(zone
			(layer "B.Cu")
			(hatch none 0.5)
			(connect_pads
				(clearance 0)
			)
			(min_thickness 0.25)
			(keepout
				(tracks not_allowed)
				(vias allowed)
				(pads allowed)
				(copperpour not_allowed)
				(footprints allowed)
			)
			(placement
				(enabled no)
				(sheetname "")
			)
			(fill
				(thermal_gap 0.5)
				(thermal_bridge_width 0.5)
				(island_removal_mode 0)
			)
			(polygon
				(pts
					(xy 240.24717 -219.726764) (xy 240.33861 -219.78493) (xy 240.538 -219.78493) (xy 240.62817 -219.726764)
					(xy 240.62817 -219.551504) (xy 240.538 -219.493084) (xy 240.33861 -219.493084) (xy 240.24717 -219.55125)
				)
			)
		)
	)
	(footprint ""
		(layer "B.Cu")
		(at 53.949854 -301.599854 -90)
		(property "Reference" "C1222"
			(at 0 0 90)
			(layer "B.SilkS")
			(hide yes)
			(effects
				(font
					(size 1.27 1.27)
				)
				(justify mirror)
			)
		)
		(property "Value" ""
			(at 0 0 90)
			(layer "B.Fab")
			(effects
				(font
					(size 1.27 1.27)
				)
				(justify mirror)
			)
		)
		(duplicate_pad_numbers_are_jumpers no)
		(fp_line
			(start -0.299974 0.150114)
			(end 0.299974 0.150114)
			(stroke
				(width 0.1)
				(type default)
			)
			(layer "B.Fab")
		)
		(fp_line
			(start 0.299974 0.150114)
			(end 0.299974 -0.150114)
			(stroke
				(width 0.1)
				(type default)
			)
			(layer "B.Fab")
		)
		(fp_line
			(start -0.299974 -0.150114)
			(end -0.299974 0.150114)
			(stroke
				(width 0.1)
				(type default)
			)
			(layer "B.Fab")
		)
		(fp_line
			(start 0.299974 -0.150114)
			(end -0.299974 -0.150114)
			(stroke
				(width 0.1)
				(type default)
			)
			(layer "B.Fab")
		)
		(pad "1" smd rect
			(at 0.2667 0 90)
			(size 0.3048 0.381)
			(layers "B.Cu" "B.Mask" "B.Paste")
			(net "P0V8_SERDES_VDDA_PEX0")
		)
		(pad "2" smd rect
			(at -0.2667 0 90)
			(size 0.3048 0.381)
			(layers "B.Cu" "B.Mask" "B.Paste")
			(net "GND")
		)
	)
	(footprint ""
		(layer "B.Cu")
		(at 15.012416 -221.640908 90)
		(property "Reference" "R3450"
			(at 0 0 90)
			(layer "B.SilkS")
			(hide yes)
			(effects
				(font
					(size 1.27 1.27)
				)
				(justify mirror)
			)
		)
		(property "Value" ""
			(at 0 0 90)
			(layer "B.Fab")
			(effects
				(font
					(size 1.27 1.27)
				)
				(justify mirror)
			)
		)
		(duplicate_pad_numbers_are_jumpers no)
		(fp_line
			(start 0.7874 -0.4064)
			(end -0.7874 -0.4064)
			(stroke
				(width 0.1524)
				(type default)
			)
			(layer "B.SilkS")
		)
		(fp_line
			(start -0.7874 -0.4064)
			(end -0.7874 0.4064)
			(stroke
				(width 0.1524)
				(type default)
			)
			(layer "B.SilkS")
		)
		(fp_line
			(start 0.7874 0.4064)
			(end 0.7874 -0.4064)
			(stroke
				(width 0.1524)
				(type default)
			)
			(layer "B.SilkS")
		)
		(fp_line
			(start -0.7874 0.4064)
			(end 0.7874 0.4064)
			(stroke
				(width 0.1524)
				(type default)
			)
			(layer "B.SilkS")
		)
		(fp_line
			(start 0.67945 -0.305054)
			(end 0.12065 -0.305054)
			(stroke
				(width 0.1)
				(type default)
			)
			(layer "B.Fab")
		)
		(fp_line
			(start 0.12065 -0.305054)
			(end 0.12065 -0.2794)
			(stroke
				(width 0.1)
				(type default)
			)
			(layer "B.Fab")
		)
		(fp_line
			(start -0.12065 -0.3048)
			(end -0.67945 -0.3048)
			(stroke
				(width 0.1)
				(type default)
			)
			(layer "B.Fab")
		)
		(fp_line
			(start -0.67945 -0.3048)
			(end -0.67945 0.3048)
			(stroke
				(width 0.1)
				(type default)
			)
			(layer "B.Fab")
		)
		(fp_line
			(start 0.12065 -0.2794)
			(end -0.12065 -0.2794)
			(stroke
				(width 0.1)
				(type default)
			)
			(layer "B.Fab")
		)
		(fp_line
			(start -0.12065 -0.2794)
			(end -0.12065 -0.3048)
			(stroke
				(width 0.1)
				(type default)
			)
			(layer "B.Fab")
		)
		(fp_line
			(start 0.12065 0.2794)
			(end 0.12065 0.3048)
			(stroke
				(width 0.1)
				(type default)
			)
			(layer "B.Fab")
		)
		(fp_line
			(start -0.120396 0.2794)
			(end 0.12065 0.2794)
			(stroke
				(width 0.1)
				(type default)
			)
			(layer "B.Fab")
		)
		(fp_line
			(start 0.67945 0.3048)
			(end 0.67945 -0.305054)
			(stroke
				(width 0.1)
				(type default)
			)
			(layer "B.Fab")
		)
		(fp_line
			(start 0.12065 0.3048)
			(end 0.67945 0.3048)
			(stroke
				(width 0.1)
				(type default)
			)
			(layer "B.Fab")
		)
		(fp_line
			(start -0.120396 0.3048)
			(end -0.120396 0.2794)
			(stroke
				(width 0.1)
				(type default)
			)
			(layer "B.Fab")
		)
		(fp_line
			(start -0.67945 0.3048)
			(end -0.120396 0.3048)
			(stroke
				(width 0.1)
				(type default)
			)
			(layer "B.Fab")
		)
		(pad "1" smd circle
			(at 0.40005 0 270)
			(size 0 0)
			(layers "B.Cu" "B.Mask" "B.Paste")
			(net "SPI_PEX0_CLK_MUX")
		)
		(pad "2" smd circle
			(at -0.40005 0 270)
			(size 0 0)
			(layers "B.Cu" "B.Mask" "B.Paste")
			(net "SPI_PEX0_CLK_MUX_R")
		)
	)
	(footprint ""
		(layer "B.Cu")
		(at 224.354644 -231.225598 -90)
		(property "Reference" "R1479"
			(at 0 0 90)
			(layer "B.SilkS")
			(hide yes)
			(effects
				(font
					(size 1.27 1.27)
				)
				(justify mirror)
			)
		)
		(property "Value" ""
			(at 0 0 90)
			(layer "B.Fab")
			(effects
				(font
					(size 1.27 1.27)
				)
				(justify mirror)
			)
		)
		(duplicate_pad_numbers_are_jumpers no)
		(fp_line
			(start -0.7874 0.4064)
			(end 0.7874 0.4064)
			(stroke
				(width 0.1524)
				(type default)
			)
			(layer "B.SilkS")
		)
		(fp_line
			(start 0.7874 0.4064)
			(end 0.7874 -0.4064)
			(stroke
				(width 0.1524)
				(type default)
			)
			(layer "B.SilkS")
		)
		(fp_line
			(start -0.7874 -0.4064)
			(end -0.7874 0.4064)
			(stroke
				(width 0.1524)
				(type default)
			)
			(layer "B.SilkS")
		)
		(fp_line
			(start 0.7874 -0.4064)
			(end -0.7874 -0.4064)
			(stroke
				(width 0.1524)
				(type default)
			)
			(layer "B.SilkS")
		)
		(fp_line
			(start -0.67945 0.3048)
			(end -0.120396 0.3048)
			(stroke
				(width 0.1)
				(type default)
			)
			(layer "B.Fab")
		)
		(fp_line
			(start -0.120396 0.3048)
			(end -0.120396 0.2794)
			(stroke
				(width 0.1)
				(type default)
			)
			(layer "B.Fab")
		)
		(fp_line
			(start 0.12065 0.3048)
			(end 0.67945 0.3048)
			(stroke
				(width 0.1)
				(type default)
			)
			(layer "B.Fab")
		)
		(fp_line
			(start 0.67945 0.3048)
			(end 0.67945 -0.305054)
			(stroke
				(width 0.1)
				(type default)
			)
			(layer "B.Fab")
		)
		(fp_line
			(start -0.120396 0.2794)
			(end 0.12065 0.2794)
			(stroke
				(width 0.1)
				(type default)
			)
			(layer "B.Fab")
		)
		(fp_line
			(start 0.12065 0.2794)
			(end 0.12065 0.3048)
			(stroke
				(width 0.1)
				(type default)
			)
			(layer "B.Fab")
		)
		(fp_line
			(start -0.12065 -0.2794)
			(end -0.12065 -0.3048)
			(stroke
				(width 0.1)
				(type default)
			)
			(layer "B.Fab")
		)
		(fp_line
			(start 0.12065 -0.2794)
			(end -0.12065 -0.2794)
			(stroke
				(width 0.1)
				(type default)
			)
			(layer "B.Fab")
		)
		(fp_line
			(start -0.67945 -0.3048)
			(end -0.67945 0.3048)
			(stroke
				(width 0.1)
				(type default)
			)
			(layer "B.Fab")
		)
		(fp_line
			(start -0.12065 -0.3048)
			(end -0.67945 -0.3048)
			(stroke
				(width 0.1)
				(type default)
			)
			(layer "B.Fab")
		)
		(fp_line
			(start 0.12065 -0.305054)
			(end 0.12065 -0.2794)
			(stroke
				(width 0.1)
				(type default)
			)
			(layer "B.Fab")
		)
		(fp_line
			(start 0.67945 -0.305054)
			(end 0.12065 -0.305054)
			(stroke
				(width 0.1)
				(type default)
			)
			(layer "B.Fab")
		)
		(pad "1" smd circle
			(at 0.40005 0 90)
			(size 0 0)
			(layers "B.Cu" "B.Mask" "B.Paste")
			(net "SMB_NIC1_SCL")
		)
		(pad "2" smd circle
			(at -0.40005 0 90)
			(size 0 0)
			(layers "B.Cu" "B.Mask" "B.Paste")
			(net "SMB_NIC1_R_SCL")
		)
	)
	(footprint ""
		(layer "B.Cu")
		(at 13.472668 -281.9654 180)
		(property "Reference" "PC213"
			(at 0 0 0)
			(layer "B.SilkS")
			(hide yes)
			(effects
				(font
					(size 1.27 1.27)
				)
				(justify mirror)
			)
		)
		(property "Value" ""
			(at 0 0 0)
			(layer "B.Fab")
			(effects
				(font
					(size 1.27 1.27)
				)
				(justify mirror)
			)
		)
		(duplicate_pad_numbers_are_jumpers no)
		(fp_line
			(start 1.524 0.762)
			(end 1.524 -0.762)
			(stroke
				(width 0.1524)
				(type default)
			)
			(layer "B.SilkS")
		)
		(fp_line
			(start 1.524 -0.762)
			(end -1.524 -0.762)
			(stroke
				(width 0.1524)
				(type default)
			)
			(layer "B.SilkS")
		)
		(fp_line
			(start -1.524 0.762)
			(end 1.524 0.762)
			(stroke
				(width 0.1524)
				(type default)
			)
			(layer "B.SilkS")
		)
		(fp_line
			(start -1.524 -0.762)
			(end -1.524 0.762)
			(stroke
				(width 0.1524)
				(type default)
			)
			(layer "B.SilkS")
		)
		(fp_line
			(start 1.1049 0.724916)
			(end -1.1049 0.724916)
			(stroke
				(width 0.1)
				(type default)
			)
			(layer "B.Fab")
		)
		(fp_line
			(start 1.1049 -0.724916)
			(end 1.1049 0.724916)
			(stroke
				(width 0.1)
				(type default)
			)
			(layer "B.Fab")
		)
		(fp_line
			(start -1.1049 0.724916)
			(end -1.1049 -0.724916)
			(stroke
				(width 0.1)
				(type default)
			)
			(layer "B.Fab")
		)
		(fp_line
			(start -1.1049 -0.724916)
			(end 1.1049 -0.724916)
			(stroke
				(width 0.1)
				(type default)
			)
			(layer "B.Fab")
		)
		(pad "1" smd rect
			(at 0.889 0 180)
			(size 1.016 1.27)
			(layers "B.Cu" "B.Mask" "B.Paste")
			(net "P1V25_PEX0_R")
		)
		(pad "2" smd rect
			(at -0.889 0 180)
			(size 1.016 1.27)
			(layers "B.Cu" "B.Mask" "B.Paste")
			(net "GND")
		)
	)
	(footprint ""
		(layer "B.Cu")
		(at 174.277274 -286.399732 90)
		(property "Reference" "C3135"
			(at 0 0 90)
			(layer "B.SilkS")
			(hide yes)
			(effects
				(font
					(size 1.27 1.27)
				)
				(justify mirror)
			)
		)
		(property "Value" ""
			(at 0 0 90)
			(layer "B.Fab")
			(effects
				(font
					(size 1.27 1.27)
				)
				(justify mirror)
			)
		)
		(duplicate_pad_numbers_are_jumpers no)
		(fp_line
			(start 0.299974 -0.150114)
			(end -0.299974 -0.150114)
			(stroke
				(width 0.1)
				(type default)
			)
			(layer "B.Fab")
		)
		(fp_line
			(start -0.299974 -0.150114)
			(end -0.299974 0.150114)
			(stroke
				(width 0.1)
				(type default)
			)
			(layer "B.Fab")
		)
		(fp_line
			(start 0.299974 0.150114)
			(end 0.299974 -0.150114)
			(stroke
				(width 0.1)
				(type default)
			)
			(layer "B.Fab")
		)
		(fp_line
			(start -0.299974 0.150114)
			(end 0.299974 0.150114)
			(stroke
				(width 0.1)
				(type default)
			)
			(layer "B.Fab")
		)
		(pad "1" smd rect
			(at 0.2667 0 270)
			(size 0.3048 0.381)
			(layers "B.Cu" "B.Mask" "B.Paste")
			(net "P1V25_SERDES_VDDPLL_PEX1")
		)
		(pad "2" smd rect
			(at -0.2667 0 270)
			(size 0.3048 0.381)
			(layers "B.Cu" "B.Mask" "B.Paste")
			(net "GND")
		)
	)
	(footprint ""
		(layer "B.Cu")
		(at 336.662776 -326.945498 -90)
		(property "Reference" "C4326"
			(at 0 0 90)
			(layer "B.SilkS")
			(hide yes)
			(effects
				(font
					(size 1.27 1.27)
				)
				(justify mirror)
			)
		)
		(property "Value" ""
			(at 0 0 90)
			(layer "B.Fab")
			(effects
				(font
					(size 1.27 1.27)
				)
				(justify mirror)
			)
		)
		(duplicate_pad_numbers_are_jumpers no)
		(fp_line
			(start -1.2954 0.5842)
			(end 1.2954 0.5842)
			(stroke
				(width 0.1524)
				(type default)
			)
			(layer "B.SilkS")
		)
		(fp_line
			(start 1.2954 0.5842)
			(end 1.2954 -0.5842)
			(stroke
				(width 0.1524)
				(type default)
			)
			(layer "B.SilkS")
		)
		(fp_line
			(start -1.2954 -0.5842)
			(end -1.2954 0.5842)
			(stroke
				(width 0.1524)
				(type default)
			)
			(layer "B.SilkS")
		)
		(fp_line
			(start 1.2954 -0.5842)
			(end -1.2954 -0.5842)
			(stroke
				(width 0.1524)
				(type default)
			)
			(layer "B.SilkS")
		)
		(fp_line
			(start -0.8636 0.4572)
			(end 0.8636 0.4572)
			(stroke
				(width 0.1)
				(type default)
			)
			(layer "B.Fab")
		)
		(fp_line
			(start 0.8636 0.4572)
			(end 0.8636 0.4064)
			(stroke
				(width 0.1)
				(type default)
			)
			(layer "B.Fab")
		)
		(fp_line
			(start -1.1938 0.4064)
			(end -0.8636 0.4064)
			(stroke
				(width 0.1)
				(type default)
			)
			(layer "B.Fab")
		)
		(fp_line
			(start -0.8636 0.4064)
			(end -0.8636 0.4572)
			(stroke
				(width 0.1)
				(type default)
			)
			(layer "B.Fab")
		)
		(fp_line
			(start 0.8636 0.4064)
			(end 1.1938 0.4064)
			(stroke
				(width 0.1)
				(type default)
			)
			(layer "B.Fab")
		)
		(fp_line
			(start 1.1938 0.4064)
			(end 1.1938 -0.4064)
			(stroke
				(width 0.1)
				(type default)
			)
			(layer "B.Fab")
		)
		(fp_line
			(start -1.1938 -0.4064)
			(end -1.1938 0.4064)
			(stroke
				(width 0.1)
				(type default)
			)
			(layer "B.Fab")
		)
		(fp_line
			(start -0.8636 -0.4064)
			(end -1.1938 -0.4064)
			(stroke
				(width 0.1)
				(type default)
			)
			(layer "B.Fab")
		)
		(fp_line
			(start 0.8636 -0.4064)
			(end 0.8636 -0.4572)
			(stroke
				(width 0.1)
				(type default)
			)
			(layer "B.Fab")
		)
		(fp_line
			(start 1.1938 -0.4064)
			(end 0.8636 -0.4064)
			(stroke
				(width 0.1)
				(type default)
			)
			(layer "B.Fab")
		)
		(fp_line
			(start -0.8636 -0.4572)
			(end -0.8636 -0.4064)
			(stroke
				(width 0.1)
				(type default)
			)
			(layer "B.Fab")
		)
		(fp_line
			(start 0.8636 -0.4572)
			(end -0.8636 -0.4572)
			(stroke
				(width 0.1)
				(type default)
			)
			(layer "B.Fab")
		)
		(pad "1" smd rect
			(at 0.7366 0 180)
			(size 0.7112 0.8128)
			(layers "B.Cu" "B.Mask" "B.Paste")
			(net "P0V8_SERDES_VDDA_PEX2_C8")
		)
		(pad "2" smd rect
			(at -0.7366 0 180)
			(size 0.7112 0.8128)
			(layers "B.Cu" "B.Mask" "B.Paste")
			(net "GND")
		)
	)
	(footprint ""
		(layer "B.Cu")
		(at 396.3416 -303.024794)
		(property "Reference" "C3517"
			(at 0 0 0)
			(layer "B.SilkS")
			(hide yes)
			(effects
				(font
					(size 1.27 1.27)
				)
				(justify mirror)
			)
		)
		(property "Value" ""
			(at 0 0 0)
			(layer "B.Fab")
			(effects
				(font
					(size 1.27 1.27)
				)
				(justify mirror)
			)
		)
		(duplicate_pad_numbers_are_jumpers no)
		(fp_line
			(start -0.299974 -0.150114)
			(end -0.299974 0.150114)
			(stroke
				(width 0.1)
				(type default)
			)
			(layer "B.Fab")
		)
		(fp_line
			(start -0.299974 0.150114)
			(end 0.299974 0.150114)
			(stroke
				(width 0.1)
				(type default)
			)
			(layer "B.Fab")
		)
		(fp_line
			(start 0.299974 -0.150114)
			(end -0.299974 -0.150114)
			(stroke
				(width 0.1)
				(type default)
			)
			(layer "B.Fab")
		)
		(fp_line
			(start 0.299974 0.150114)
			(end 0.299974 -0.150114)
			(stroke
				(width 0.1)
				(type default)
			)
			(layer "B.Fab")
		)
		(pad "1" smd rect
			(at 0.2667 0 180)
			(size 0.3048 0.381)
			(layers "B.Cu" "B.Mask" "B.Paste")
			(net "P1V8_VDDA_PEX3")
		)
		(pad "2" smd rect
			(at -0.2667 0 180)
			(size 0.3048 0.381)
			(layers "B.Cu" "B.Mask" "B.Paste")
			(net "GND")
		)
	)
	(footprint ""
		(layer "B.Cu")
		(at 165.655244 -157.0736 180)
		(property "Reference" "R103"
			(at 0 0 0)
			(layer "B.SilkS")
			(hide yes)
			(effects
				(font
					(size 1.27 1.27)
				)
				(justify mirror)
			)
		)
		(property "Value" ""
			(at 0 0 0)
			(layer "B.Fab")
			(effects
				(font
					(size 1.27 1.27)
				)
				(justify mirror)
			)
		)
		(duplicate_pad_numbers_are_jumpers no)
		(fp_line
			(start 0.7874 0.4064)
			(end 0.7874 -0.4064)
			(stroke
				(width 0.1524)
				(type default)
			)
			(layer "B.SilkS")
		)
		(fp_line
			(start 0.7874 -0.4064)
			(end -0.7874 -0.4064)
			(stroke
				(width 0.1524)
				(type default)
			)
			(layer "B.SilkS")
		)
		(fp_line
			(start -0.7874 0.4064)
			(end 0.7874 0.4064)
			(stroke
				(width 0.1524)
				(type default)
			)
			(layer "B.SilkS")
		)
		(fp_line
			(start -0.7874 -0.4064)
			(end -0.7874 0.4064)
			(stroke
				(width 0.1524)
				(type default)
			)
			(layer "B.SilkS")
		)
		(fp_line
			(start 0.67945 0.3048)
			(end 0.67945 -0.305054)
			(stroke
				(width 0.1)
				(type default)
			)
			(layer "B.Fab")
		)
		(fp_line
			(start 0.67945 -0.305054)
			(end 0.12065 -0.305054)
			(stroke
				(width 0.1)
				(type default)
			)
			(layer "B.Fab")
		)
		(fp_line
			(start 0.12065 0.3048)
			(end 0.67945 0.3048)
			(stroke
				(width 0.1)
				(type default)
			)
			(layer "B.Fab")
		)
		(fp_line
			(start 0.12065 0.2794)
			(end 0.12065 0.3048)
			(stroke
				(width 0.1)
				(type default)
			)
			(layer "B.Fab")
		)
		(fp_line
			(start 0.12065 -0.2794)
			(end -0.12065 -0.2794)
			(stroke
				(width 0.1)
				(type default)
			)
			(layer "B.Fab")
		)
		(fp_line
			(start 0.12065 -0.305054)
			(end 0.12065 -0.2794)
			(stroke
				(width 0.1)
				(type default)
			)
			(layer "B.Fab")
		)
		(fp_line
			(start -0.120396 0.3048)
			(end -0.120396 0.2794)
			(stroke
				(width 0.1)
				(type default)
			)
			(layer "B.Fab")
		)
		(fp_line
			(start -0.120396 0.2794)
			(end 0.12065 0.2794)
			(stroke
				(width 0.1)
				(type default)
			)
			(layer "B.Fab")
		)
		(fp_line
			(start -0.12065 -0.2794)
			(end -0.12065 -0.3048)
			(stroke
				(width 0.1)
				(type default)
			)
			(layer "B.Fab")
		)
		(fp_line
			(start -0.12065 -0.3048)
			(end -0.67945 -0.3048)
			(stroke
				(width 0.1)
				(type default)
			)
			(layer "B.Fab")
		)
		(fp_line
			(start -0.67945 0.3048)
			(end -0.120396 0.3048)
			(stroke
				(width 0.1)
				(type default)
			)
			(layer "B.Fab")
		)
		(fp_line
			(start -0.67945 -0.3048)
			(end -0.67945 0.3048)
			(stroke
				(width 0.1)
				(type default)
			)
			(layer "B.Fab")
		)
		(pad "1" smd circle
			(at 0.40005 0)
			(size 0 0)
			(layers "B.Cu" "B.Mask" "B.Paste")
			(net "NIC2_RBT_ARB_OUT")
		)
		(pad "2" smd circle
			(at -0.40005 0)
			(size 0 0)
			(layers "B.Cu" "B.Mask" "B.Paste")
			(net "NIC2_RBT_ARB_IN")
		)
	)
	(footprint ""
		(layer "B.Cu")
		(at 305.6001 -110.115096)
		(property "Reference" "C925"
			(at 0 0 0)
			(layer "B.SilkS")
			(hide yes)
			(effects
				(font
					(size 1.27 1.27)
				)
				(justify mirror)
			)
		)
		(property "Value" ""
			(at 0 0 0)
			(layer "B.Fab")
			(effects
				(font
					(size 1.27 1.27)
				)
				(justify mirror)
			)
		)
		(duplicate_pad_numbers_are_jumpers no)
		(fp_line
			(start -0.299974 -0.150114)
			(end -0.299974 0.150114)
			(stroke
				(width 0.1)
				(type default)
			)
			(layer "B.Fab")
		)
		(fp_line
			(start -0.299974 0.150114)
			(end 0.299974 0.150114)
			(stroke
				(width 0.1)
				(type default)
			)
			(layer "B.Fab")
		)
		(fp_line
			(start 0.299974 -0.150114)
			(end -0.299974 -0.150114)
			(stroke
				(width 0.1)
				(type default)
			)
			(layer "B.Fab")
		)
		(fp_line
			(start 0.299974 0.150114)
			(end 0.299974 -0.150114)
			(stroke
				(width 0.1)
				(type default)
			)
			(layer "B.Fab")
		)
		(pad "1" smd rect
			(at 0.2667 0 180)
			(size 0.3048 0.381)
			(layers "B.Cu" "B.Mask" "B.Paste")
			(net "P12V_NIC5")
		)
		(pad "2" smd rect
			(at -0.2667 0 180)
			(size 0.3048 0.381)
			(layers "B.Cu" "B.Mask" "B.Paste")
			(net "GND")
		)
	)
	(footprint ""
		(layer "B.Cu")
		(at 293.74973 -288.299906 90)
		(property "Reference" "C3286"
			(at 0 0 90)
			(layer "B.SilkS")
			(hide yes)
			(effects
				(font
					(size 1.27 1.27)
				)
				(justify mirror)
			)
		)
		(property "Value" ""
			(at 0 0 90)
			(layer "B.Fab")
			(effects
				(font
					(size 1.27 1.27)
				)
				(justify mirror)
			)
		)
		(duplicate_pad_numbers_are_jumpers no)
		(fp_line
			(start 0.299974 -0.150114)
			(end -0.299974 -0.150114)
			(stroke
				(width 0.1)
				(type default)
			)
			(layer "B.Fab")
		)
		(fp_line
			(start -0.299974 -0.150114)
			(end -0.299974 0.150114)
			(stroke
				(width 0.1)
				(type default)
			)
			(layer "B.Fab")
		)
		(fp_line
			(start 0.299974 0.150114)
			(end 0.299974 -0.150114)
			(stroke
				(width 0.1)
				(type default)
			)
			(layer "B.Fab")
		)
		(fp_line
			(start -0.299974 0.150114)
			(end 0.299974 0.150114)
			(stroke
				(width 0.1)
				(type default)
			)
			(layer "B.Fab")
		)
		(pad "1" smd rect
			(at 0.2667 0 270)
			(size 0.3048 0.381)
			(layers "B.Cu" "B.Mask" "B.Paste")
			(net "P1V25_PEX2")
		)
		(pad "2" smd rect
			(at -0.2667 0 270)
			(size 0.3048 0.381)
			(layers "B.Cu" "B.Mask" "B.Paste")
			(net "GND")
		)
	)
	(footprint ""
		(layer "B.Cu")
		(at 58.720228 -296.37482)
		(property "Reference" "C1112"
			(at 0 0 0)
			(layer "B.SilkS")
			(hide yes)
			(effects
				(font
					(size 1.27 1.27)
				)
				(justify mirror)
			)
		)
		(property "Value" ""
			(at 0 0 0)
			(layer "B.Fab")
			(effects
				(font
					(size 1.27 1.27)
				)
				(justify mirror)
			)
		)
		(duplicate_pad_numbers_are_jumpers no)
		(fp_line
			(start -0.299974 -0.150114)
			(end -0.299974 0.150114)
			(stroke
				(width 0.1)
				(type default)
			)
			(layer "B.Fab")
		)
		(fp_line
			(start -0.299974 0.150114)
			(end 0.299974 0.150114)
			(stroke
				(width 0.1)
				(type default)
			)
			(layer "B.Fab")
		)
		(fp_line
			(start 0.299974 -0.150114)
			(end -0.299974 -0.150114)
			(stroke
				(width 0.1)
				(type default)
			)
			(layer "B.Fab")
		)
		(fp_line
			(start 0.299974 0.150114)
			(end 0.299974 -0.150114)
			(stroke
				(width 0.1)
				(type default)
			)
			(layer "B.Fab")
		)
		(pad "1" smd rect
			(at 0.2667 0 180)
			(size 0.3048 0.381)
			(layers "B.Cu" "B.Mask" "B.Paste")
			(net "P0V8_PEX0")
		)
		(pad "2" smd rect
			(at -0.2667 0 180)
			(size 0.3048 0.381)
			(layers "B.Cu" "B.Mask" "B.Paste")
			(net "GND")
		)
	)
	(footprint ""
		(layer "B.Cu")
		(at 58.699908 -288.299906 90)
		(property "Reference" "C2937"
			(at 0 0 90)
			(layer "B.SilkS")
			(hide yes)
			(effects
				(font
					(size 1.27 1.27)
				)
				(justify mirror)
			)
		)
		(property "Value" ""
			(at 0 0 90)
			(layer "B.Fab")
			(effects
				(font
					(size 1.27 1.27)
				)
				(justify mirror)
			)
		)
		(duplicate_pad_numbers_are_jumpers no)
		(fp_line
			(start 0.299974 -0.150114)
			(end -0.299974 -0.150114)
			(stroke
				(width 0.1)
				(type default)
			)
			(layer "B.Fab")
		)
		(fp_line
			(start -0.299974 -0.150114)
			(end -0.299974 0.150114)
			(stroke
				(width 0.1)
				(type default)
			)
			(layer "B.Fab")
		)
		(fp_line
			(start 0.299974 0.150114)
			(end 0.299974 -0.150114)
			(stroke
				(width 0.1)
				(type default)
			)
			(layer "B.Fab")
		)
		(fp_line
			(start -0.299974 0.150114)
			(end 0.299974 0.150114)
			(stroke
				(width 0.1)
				(type default)
			)
			(layer "B.Fab")
		)
		(pad "1" smd rect
			(at 0.2667 0 270)
			(size 0.3048 0.381)
			(layers "B.Cu" "B.Mask" "B.Paste")
			(net "P1V25_PEX0")
		)
		(pad "2" smd rect
			(at -0.2667 0 270)
			(size 0.3048 0.381)
			(layers "B.Cu" "B.Mask" "B.Paste")
			(net "GND")
		)
	)
	(footprint ""
		(layer "B.Cu")
		(at 421.571674 -115.608608)
		(property "Reference" "C964"
			(at 0 0 0)
			(layer "B.SilkS")
			(hide yes)
			(effects
				(font
					(size 1.27 1.27)
				)
				(justify mirror)
			)
		)
		(property "Value" ""
			(at 0 0 0)
			(layer "B.Fab")
			(effects
				(font
					(size 1.27 1.27)
				)
				(justify mirror)
			)
		)
		(duplicate_pad_numbers_are_jumpers no)
		(fp_line
			(start -0.7874 -0.4064)
			(end -0.7874 0.4064)
			(stroke
				(width 0.1524)
				(type default)
			)
			(layer "B.SilkS")
		)
		(fp_line
			(start -0.7874 0.4064)
			(end 0.7874 0.4064)
			(stroke
				(width 0.1524)
				(type default)
			)
			(layer "B.SilkS")
		)
		(fp_line
			(start 0.7874 -0.4064)
			(end -0.7874 -0.4064)
			(stroke
				(width 0.1524)
				(type default)
			)
			(layer "B.SilkS")
		)
		(fp_line
			(start 0.7874 0.4064)
			(end 0.7874 -0.4064)
			(stroke
				(width 0.1524)
				(type default)
			)
			(layer "B.SilkS")
		)
		(fp_line
			(start -0.67945 -0.3048)
			(end -0.67945 0.3048)
			(stroke
				(width 0.1)
				(type default)
			)
			(layer "B.Fab")
		)
		(fp_line
			(start -0.67945 0.3048)
			(end -0.120396 0.3048)
			(stroke
				(width 0.1)
				(type default)
			)
			(layer "B.Fab")
		)
		(fp_line
			(start -0.12065 -0.3048)
			(end -0.67945 -0.3048)
			(stroke
				(width 0.1)
				(type default)
			)
			(layer "B.Fab")
		)
		(fp_line
			(start -0.12065 -0.2794)
			(end -0.12065 -0.3048)
			(stroke
				(width 0.1)
				(type default)
			)
			(layer "B.Fab")
		)
		(fp_line
			(start -0.120396 0.2794)
			(end 0.12065 0.2794)
			(stroke
				(width 0.1)
				(type default)
			)
			(layer "B.Fab")
		)
		(fp_line
			(start -0.120396 0.3048)
			(end -0.120396 0.2794)
			(stroke
				(width 0.1)
				(type default)
			)
			(layer "B.Fab")
		)
		(fp_line
			(start 0.12065 -0.305054)
			(end 0.12065 -0.2794)
			(stroke
				(width 0.1)
				(type default)
			)
			(layer "B.Fab")
		)
		(fp_line
			(start 0.12065 -0.2794)
			(end -0.12065 -0.2794)
			(stroke
				(width 0.1)
				(type default)
			)
			(layer "B.Fab")
		)
		(fp_line
			(start 0.12065 0.2794)
			(end 0.12065 0.3048)
			(stroke
				(width 0.1)
				(type default)
			)
			(layer "B.Fab")
		)
		(fp_line
			(start 0.12065 0.3048)
			(end 0.67945 0.3048)
			(stroke
				(width 0.1)
				(type default)
			)
			(layer "B.Fab")
		)
		(fp_line
			(start 0.67945 -0.305054)
			(end 0.12065 -0.305054)
			(stroke
				(width 0.1)
				(type default)
			)
			(layer "B.Fab")
		)
		(fp_line
			(start 0.67945 0.3048)
			(end 0.67945 -0.305054)
			(stroke
				(width 0.1)
				(type default)
			)
			(layer "B.Fab")
		)
		(pad "1" smd circle
			(at 0.40005 0 180)
			(size 0 0)
			(layers "B.Cu" "B.Mask" "B.Paste")
			(net "P3V3_NIC7")
		)
		(pad "2" smd circle
			(at -0.40005 0 180)
			(size 0 0)
			(layers "B.Cu" "B.Mask" "B.Paste")
			(net "GND")
		)
	)
	(footprint ""
		(layer "B.Cu")
		(at 52.049934 -290.199826 90)
		(property "Reference" "C1176"
			(at 0 0 90)
			(layer "B.SilkS")
			(hide yes)
			(effects
				(font
					(size 1.27 1.27)
				)
				(justify mirror)
			)
		)
		(property "Value" ""
			(at 0 0 90)
			(layer "B.Fab")
			(effects
				(font
					(size 1.27 1.27)
				)
				(justify mirror)
			)
		)
		(duplicate_pad_numbers_are_jumpers no)
		(fp_line
			(start 0.299974 -0.150114)
			(end -0.299974 -0.150114)
			(stroke
				(width 0.1)
				(type default)
			)
			(layer "B.Fab")
		)
		(fp_line
			(start -0.299974 -0.150114)
			(end -0.299974 0.150114)
			(stroke
				(width 0.1)
				(type default)
			)
			(layer "B.Fab")
		)
		(fp_line
			(start 0.299974 0.150114)
			(end 0.299974 -0.150114)
			(stroke
				(width 0.1)
				(type default)
			)
			(layer "B.Fab")
		)
		(fp_line
			(start -0.299974 0.150114)
			(end 0.299974 0.150114)
			(stroke
				(width 0.1)
				(type default)
			)
			(layer "B.Fab")
		)
		(pad "1" smd rect
			(at 0.2667 0 270)
			(size 0.3048 0.381)
			(layers "B.Cu" "B.Mask" "B.Paste")
			(net "P0V8_SERDES_VDDA_PEX0")
		)
		(pad "2" smd rect
			(at -0.2667 0 270)
			(size 0.3048 0.381)
			(layers "B.Cu" "B.Mask" "B.Paste")
			(net "GND")
		)
	)
	(footprint ""
		(layer "B.Cu")
		(at 135.941816 -202.663806)
		(property "Reference" "C2602"
			(at 0 0 0)
			(layer "B.SilkS")
			(hide yes)
			(effects
				(font
					(size 1.27 1.27)
				)
				(justify mirror)
			)
		)
		(property "Value" ""
			(at 0 0 0)
			(layer "B.Fab")
			(effects
				(font
					(size 1.27 1.27)
				)
				(justify mirror)
			)
		)
		(duplicate_pad_numbers_are_jumpers no)
		(fp_line
			(start -1.2954 -0.5842)
			(end -1.2954 0.5842)
			(stroke
				(width 0.1524)
				(type default)
			)
			(layer "B.SilkS")
		)
		(fp_line
			(start -1.2954 0.5842)
			(end 1.2954 0.5842)
			(stroke
				(width 0.1524)
				(type default)
			)
			(layer "B.SilkS")
		)
		(fp_line
			(start 1.2954 -0.5842)
			(end -1.2954 -0.5842)
			(stroke
				(width 0.1524)
				(type default)
			)
			(layer "B.SilkS")
		)
		(fp_line
			(start 1.2954 0.5842)
			(end 1.2954 -0.5842)
			(stroke
				(width 0.1524)
				(type default)
			)
			(layer "B.SilkS")
		)
		(fp_line
			(start -1.1938 -0.4064)
			(end -1.1938 0.4064)
			(stroke
				(width 0.1)
				(type default)
			)
			(layer "B.Fab")
		)
		(fp_line
			(start -1.1938 0.4064)
			(end -0.8636 0.4064)
			(stroke
				(width 0.1)
				(type default)
			)
			(layer "B.Fab")
		)
		(fp_line
			(start -0.8636 -0.4572)
			(end -0.8636 -0.4064)
			(stroke
				(width 0.1)
				(type default)
			)
			(layer "B.Fab")
		)
		(fp_line
			(start -0.8636 -0.4064)
			(end -1.1938 -0.4064)
			(stroke
				(width 0.1)
				(type default)
			)
			(layer "B.Fab")
		)
		(fp_line
			(start -0.8636 0.4064)
			(end -0.8636 0.4572)
			(stroke
				(width 0.1)
				(type default)
			)
			(layer "B.Fab")
		)
		(fp_line
			(start -0.8636 0.4572)
			(end 0.8636 0.4572)
			(stroke
				(width 0.1)
				(type default)
			)
			(layer "B.Fab")
		)
		(fp_line
			(start 0.8636 -0.4572)
			(end -0.8636 -0.4572)
			(stroke
				(width 0.1)
				(type default)
			)
			(layer "B.Fab")
		)
		(fp_line
			(start 0.8636 -0.4064)
			(end 0.8636 -0.4572)
			(stroke
				(width 0.1)
				(type default)
			)
			(layer "B.Fab")
		)
		(fp_line
			(start 0.8636 0.4064)
			(end 1.1938 0.4064)
			(stroke
				(width 0.1)
				(type default)
			)
			(layer "B.Fab")
		)
		(fp_line
			(start 0.8636 0.4572)
			(end 0.8636 0.4064)
			(stroke
				(width 0.1)
				(type default)
			)
			(layer "B.Fab")
		)
		(fp_line
			(start 1.1938 -0.4064)
			(end 0.8636 -0.4064)
			(stroke
				(width 0.1)
				(type default)
			)
			(layer "B.Fab")
		)
		(fp_line
			(start 1.1938 0.4064)
			(end 1.1938 -0.4064)
			(stroke
				(width 0.1)
				(type default)
			)
			(layer "B.Fab")
		)
		(pad "1" smd rect
			(at 0.7366 0 270)
			(size 0.7112 0.8128)
			(layers "B.Cu" "B.Mask" "B.Paste")
			(net "P3V3_CLI_VPHY")
		)
		(pad "2" smd rect
			(at -0.7366 0 270)
			(size 0.7112 0.8128)
			(layers "B.Cu" "B.Mask" "B.Paste")
			(net "GND")
		)
	)
	(footprint ""
		(layer "B.Cu")
		(at 378.46 -234.315 90)
		(property "Reference" "C2575"
			(at 0 0 90)
			(layer "B.SilkS")
			(hide yes)
			(effects
				(font
					(size 1.27 1.27)
				)
				(justify mirror)
			)
		)
		(property "Value" ""
			(at 0 0 90)
			(layer "B.Fab")
			(effects
				(font
					(size 1.27 1.27)
				)
				(justify mirror)
			)
		)
		(duplicate_pad_numbers_are_jumpers no)
		(fp_line
			(start 0.7874 -0.4064)
			(end -0.7874 -0.4064)
			(stroke
				(width 0.1524)
				(type default)
			)
			(layer "B.SilkS")
		)
		(fp_line
			(start -0.7874 -0.4064)
			(end -0.7874 0.4064)
			(stroke
				(width 0.1524)
				(type default)
			)
			(layer "B.SilkS")
		)
		(fp_line
			(start 0.7874 0.4064)
			(end 0.7874 -0.4064)
			(stroke
				(width 0.1524)
				(type default)
			)
			(layer "B.SilkS")
		)
		(fp_line
			(start -0.7874 0.4064)
			(end 0.7874 0.4064)
			(stroke
				(width 0.1524)
				(type default)
			)
			(layer "B.SilkS")
		)
		(fp_line
			(start 0.67945 -0.305054)
			(end 0.12065 -0.305054)
			(stroke
				(width 0.1)
				(type default)
			)
			(layer "B.Fab")
		)
		(fp_line
			(start 0.12065 -0.305054)
			(end 0.12065 -0.2794)
			(stroke
				(width 0.1)
				(type default)
			)
			(layer "B.Fab")
		)
		(fp_line
			(start -0.12065 -0.3048)
			(end -0.67945 -0.3048)
			(stroke
				(width 0.1)
				(type default)
			)
			(layer "B.Fab")
		)
		(fp_line
			(start -0.67945 -0.3048)
			(end -0.67945 0.3048)
			(stroke
				(width 0.1)
				(type default)
			)
			(layer "B.Fab")
		)
		(fp_line
			(start 0.12065 -0.2794)
			(end -0.12065 -0.2794)
			(stroke
				(width 0.1)
				(type default)
			)
			(layer "B.Fab")
		)
		(fp_line
			(start -0.12065 -0.2794)
			(end -0.12065 -0.3048)
			(stroke
				(width 0.1)
				(type default)
			)
			(layer "B.Fab")
		)
		(fp_line
			(start 0.12065 0.2794)
			(end 0.12065 0.3048)
			(stroke
				(width 0.1)
				(type default)
			)
			(layer "B.Fab")
		)
		(fp_line
			(start -0.120396 0.2794)
			(end 0.12065 0.2794)
			(stroke
				(width 0.1)
				(type default)
			)
			(layer "B.Fab")
		)
		(fp_line
			(start 0.67945 0.3048)
			(end 0.67945 -0.305054)
			(stroke
				(width 0.1)
				(type default)
			)
			(layer "B.Fab")
		)
		(fp_line
			(start 0.12065 0.3048)
			(end 0.67945 0.3048)
			(stroke
				(width 0.1)
				(type default)
			)
			(layer "B.Fab")
		)
		(fp_line
			(start -0.120396 0.3048)
			(end -0.120396 0.2794)
			(stroke
				(width 0.1)
				(type default)
			)
			(layer "B.Fab")
		)
		(fp_line
			(start -0.67945 0.3048)
			(end -0.120396 0.3048)
			(stroke
				(width 0.1)
				(type default)
			)
			(layer "B.Fab")
		)
		(pad "1" smd circle
			(at 0.40005 0 270)
			(size 0 0)
			(layers "B.Cu" "B.Mask" "B.Paste")
			(net "P1V8_SDB_VCORE")
		)
		(pad "2" smd circle
			(at -0.40005 0 270)
			(size 0 0)
			(layers "B.Cu" "B.Mask" "B.Paste")
			(net "GND")
		)
	)
	(footprint ""
		(layer "B.Cu")
		(at 342.011 -233.553 90)
		(property "Reference" "R3537"
			(at 0 0 90)
			(layer "B.SilkS")
			(hide yes)
			(effects
				(font
					(size 1.27 1.27)
				)
				(justify mirror)
			)
		)
		(property "Value" ""
			(at 0 0 90)
			(layer "B.Fab")
			(effects
				(font
					(size 1.27 1.27)
				)
				(justify mirror)
			)
		)
		(duplicate_pad_numbers_are_jumpers no)
		(fp_line
			(start 0.7874 -0.4064)
			(end -0.7874 -0.4064)
			(stroke
				(width 0.1524)
				(type default)
			)
			(layer "B.SilkS")
		)
		(fp_line
			(start -0.7874 -0.4064)
			(end -0.7874 0.4064)
			(stroke
				(width 0.1524)
				(type default)
			)
			(layer "B.SilkS")
		)
		(fp_line
			(start 0.7874 0.4064)
			(end 0.7874 -0.4064)
			(stroke
				(width 0.1524)
				(type default)
			)
			(layer "B.SilkS")
		)
		(fp_line
			(start -0.7874 0.4064)
			(end 0.7874 0.4064)
			(stroke
				(width 0.1524)
				(type default)
			)
			(layer "B.SilkS")
		)
		(fp_line
			(start 0.67945 -0.305054)
			(end 0.12065 -0.305054)
			(stroke
				(width 0.1)
				(type default)
			)
			(layer "B.Fab")
		)
		(fp_line
			(start 0.12065 -0.305054)
			(end 0.12065 -0.2794)
			(stroke
				(width 0.1)
				(type default)
			)
			(layer "B.Fab")
		)
		(fp_line
			(start -0.12065 -0.3048)
			(end -0.67945 -0.3048)
			(stroke
				(width 0.1)
				(type default)
			)
			(layer "B.Fab")
		)
		(fp_line
			(start -0.67945 -0.3048)
			(end -0.67945 0.3048)
			(stroke
				(width 0.1)
				(type default)
			)
			(layer "B.Fab")
		)
		(fp_line
			(start 0.12065 -0.2794)
			(end -0.12065 -0.2794)
			(stroke
				(width 0.1)
				(type default)
			)
			(layer "B.Fab")
		)
		(fp_line
			(start -0.12065 -0.2794)
			(end -0.12065 -0.3048)
			(stroke
				(width 0.1)
				(type default)
			)
			(layer "B.Fab")
		)
		(fp_line
			(start 0.12065 0.2794)
			(end 0.12065 0.3048)
			(stroke
				(width 0.1)
				(type default)
			)
			(layer "B.Fab")
		)
		(fp_line
			(start -0.120396 0.2794)
			(end 0.12065 0.2794)
			(stroke
				(width 0.1)
				(type default)
			)
			(layer "B.Fab")
		)
		(fp_line
			(start 0.67945 0.3048)
			(end 0.67945 -0.305054)
			(stroke
				(width 0.1)
				(type default)
			)
			(layer "B.Fab")
		)
		(fp_line
			(start 0.12065 0.3048)
			(end 0.67945 0.3048)
			(stroke
				(width 0.1)
				(type default)
			)
			(layer "B.Fab")
		)
		(fp_line
			(start -0.120396 0.3048)
			(end -0.120396 0.2794)
			(stroke
				(width 0.1)
				(type default)
			)
			(layer "B.Fab")
		)
		(fp_line
			(start -0.67945 0.3048)
			(end -0.120396 0.3048)
			(stroke
				(width 0.1)
				(type default)
			)
			(layer "B.Fab")
		)
		(pad "1" smd circle
			(at 0.40005 0 270)
			(size 0 0)
			(layers "B.Cu" "B.Mask" "B.Paste")
			(net "SSD3_PWRDIS_R")
		)
		(pad "2" smd circle
			(at -0.40005 0 270)
			(size 0 0)
			(layers "B.Cu" "B.Mask" "B.Paste")
			(net "SSD3_PWRDIS")
		)
	)
	(footprint ""
		(layer "B.Cu")
		(at 340.868 -207.772 90)
		(property "Reference" "R4136"
			(at 0 0 90)
			(layer "B.SilkS")
			(hide yes)
			(effects
				(font
					(size 1.27 1.27)
				)
				(justify mirror)
			)
		)
		(property "Value" ""
			(at 0 0 90)
			(layer "B.Fab")
			(effects
				(font
					(size 1.27 1.27)
				)
				(justify mirror)
			)
		)
		(duplicate_pad_numbers_are_jumpers no)
		(fp_line
			(start 0.7874 -0.4064)
			(end -0.7874 -0.4064)
			(stroke
				(width 0.1524)
				(type default)
			)
			(layer "B.SilkS")
		)
		(fp_line
			(start -0.7874 -0.4064)
			(end -0.7874 0.4064)
			(stroke
				(width 0.1524)
				(type default)
			)
			(layer "B.SilkS")
		)
		(fp_line
			(start 0.7874 0.4064)
			(end 0.7874 -0.4064)
			(stroke
				(width 0.1524)
				(type default)
			)
			(layer "B.SilkS")
		)
		(fp_line
			(start -0.7874 0.4064)
			(end 0.7874 0.4064)
			(stroke
				(width 0.1524)
				(type default)
			)
			(layer "B.SilkS")
		)
		(fp_line
			(start 0.67945 -0.305054)
			(end 0.12065 -0.305054)
			(stroke
				(width 0.1)
				(type default)
			)
			(layer "B.Fab")
		)
		(fp_line
			(start 0.12065 -0.305054)
			(end 0.12065 -0.2794)
			(stroke
				(width 0.1)
				(type default)
			)
			(layer "B.Fab")
		)
		(fp_line
			(start -0.12065 -0.3048)
			(end -0.67945 -0.3048)
			(stroke
				(width 0.1)
				(type default)
			)
			(layer "B.Fab")
		)
		(fp_line
			(start -0.67945 -0.3048)
			(end -0.67945 0.3048)
			(stroke
				(width 0.1)
				(type default)
			)
			(layer "B.Fab")
		)
		(fp_line
			(start 0.12065 -0.2794)
			(end -0.12065 -0.2794)
			(stroke
				(width 0.1)
				(type default)
			)
			(layer "B.Fab")
		)
		(fp_line
			(start -0.12065 -0.2794)
			(end -0.12065 -0.3048)
			(stroke
				(width 0.1)
				(type default)
			)
			(layer "B.Fab")
		)
		(fp_line
			(start 0.12065 0.2794)
			(end 0.12065 0.3048)
			(stroke
				(width 0.1)
				(type default)
			)
			(layer "B.Fab")
		)
		(fp_line
			(start -0.120396 0.2794)
			(end 0.12065 0.2794)
			(stroke
				(width 0.1)
				(type default)
			)
			(layer "B.Fab")
		)
		(fp_line
			(start 0.67945 0.3048)
			(end 0.67945 -0.305054)
			(stroke
				(width 0.1)
				(type default)
			)
			(layer "B.Fab")
		)
		(fp_line
			(start 0.12065 0.3048)
			(end 0.67945 0.3048)
			(stroke
				(width 0.1)
				(type default)
			)
			(layer "B.Fab")
		)
		(fp_line
			(start -0.120396 0.3048)
			(end -0.120396 0.2794)
			(stroke
				(width 0.1)
				(type default)
			)
			(layer "B.Fab")
		)
		(fp_line
			(start -0.67945 0.3048)
			(end -0.120396 0.3048)
			(stroke
				(width 0.1)
				(type default)
			)
			(layer "B.Fab")
		)
		(pad "1" smd circle
			(at 0.40005 0 270)
			(size 0 0)
			(layers "B.Cu" "B.Mask" "B.Paste")
			(net "SSD13_PWRDIS")
		)
		(pad "2" smd circle
			(at -0.40005 0 270)
			(size 0 0)
			(layers "B.Cu" "B.Mask" "B.Paste")
			(net "SSD13_PWRDIS_R")
		)
	)
	(footprint ""
		(layer "B.Cu")
		(at 290.44011 -297.79976 -90)
		(property "Reference" "C1643"
			(at 0 0 90)
			(layer "B.SilkS")
			(hide yes)
			(effects
				(font
					(size 1.27 1.27)
				)
				(justify mirror)
			)
		)
		(property "Value" ""
			(at 0 0 90)
			(layer "B.Fab")
			(effects
				(font
					(size 1.27 1.27)
				)
				(justify mirror)
			)
		)
		(duplicate_pad_numbers_are_jumpers no)
		(fp_line
			(start -0.299974 0.150114)
			(end 0.299974 0.150114)
			(stroke
				(width 0.1)
				(type default)
			)
			(layer "B.Fab")
		)
		(fp_line
			(start 0.299974 0.150114)
			(end 0.299974 -0.150114)
			(stroke
				(width 0.1)
				(type default)
			)
			(layer "B.Fab")
		)
		(fp_line
			(start -0.299974 -0.150114)
			(end -0.299974 0.150114)
			(stroke
				(width 0.1)
				(type default)
			)
			(layer "B.Fab")
		)
		(fp_line
			(start 0.299974 -0.150114)
			(end -0.299974 -0.150114)
			(stroke
				(width 0.1)
				(type default)
			)
			(layer "B.Fab")
		)
		(pad "1" smd rect
			(at 0.2667 0 90)
			(size 0.3048 0.381)
			(layers "B.Cu" "B.Mask" "B.Paste")
			(net "P0V8_PEX2")
		)
		(pad "2" smd rect
			(at -0.2667 0 90)
			(size 0.3048 0.381)
			(layers "B.Cu" "B.Mask" "B.Paste")
			(net "GND")
		)
	)
	(footprint ""
		(layer "B.Cu")
		(at 62.024768 -293.99992 -90)
		(property "Reference" "C1146"
			(at 0 0 90)
			(layer "B.SilkS")
			(hide yes)
			(effects
				(font
					(size 1.27 1.27)
				)
				(justify mirror)
			)
		)
		(property "Value" ""
			(at 0 0 90)
			(layer "B.Fab")
			(effects
				(font
					(size 1.27 1.27)
				)
				(justify mirror)
			)
		)
		(duplicate_pad_numbers_are_jumpers no)
		(fp_line
			(start -0.299974 0.150114)
			(end 0.299974 0.150114)
			(stroke
				(width 0.1)
				(type default)
			)
			(layer "B.Fab")
		)
		(fp_line
			(start 0.299974 0.150114)
			(end 0.299974 -0.150114)
			(stroke
				(width 0.1)
				(type default)
			)
			(layer "B.Fab")
		)
		(fp_line
			(start -0.299974 -0.150114)
			(end -0.299974 0.150114)
			(stroke
				(width 0.1)
				(type default)
			)
			(layer "B.Fab")
		)
		(fp_line
			(start 0.299974 -0.150114)
			(end -0.299974 -0.150114)
			(stroke
				(width 0.1)
				(type default)
			)
			(layer "B.Fab")
		)
		(pad "1" smd rect
			(at 0.2667 0 90)
			(size 0.3048 0.381)
			(layers "B.Cu" "B.Mask" "B.Paste")
			(net "P0V8_PEX0")
		)
		(pad "2" smd rect
			(at -0.2667 0 90)
			(size 0.3048 0.381)
			(layers "B.Cu" "B.Mask" "B.Paste")
			(net "GND")
		)
	)
	(footprint ""
		(layer "B.Cu")
		(at 282.824936 -293.99992 90)
		(property "Reference" "C1644"
			(at 0 0 90)
			(layer "B.SilkS")
			(hide yes)
			(effects
				(font
					(size 1.27 1.27)
				)
				(justify mirror)
			)
		)
		(property "Value" ""
			(at 0 0 90)
			(layer "B.Fab")
			(effects
				(font
					(size 1.27 1.27)
				)
				(justify mirror)
			)
		)
		(duplicate_pad_numbers_are_jumpers no)
		(fp_line
			(start 0.299974 -0.150114)
			(end -0.299974 -0.150114)
			(stroke
				(width 0.1)
				(type default)
			)
			(layer "B.Fab")
		)
		(fp_line
			(start -0.299974 -0.150114)
			(end -0.299974 0.150114)
			(stroke
				(width 0.1)
				(type default)
			)
			(layer "B.Fab")
		)
		(fp_line
			(start 0.299974 0.150114)
			(end 0.299974 -0.150114)
			(stroke
				(width 0.1)
				(type default)
			)
			(layer "B.Fab")
		)
		(fp_line
			(start -0.299974 0.150114)
			(end 0.299974 0.150114)
			(stroke
				(width 0.1)
				(type default)
			)
			(layer "B.Fab")
		)
		(pad "1" smd rect
			(at 0.2667 0 270)
			(size 0.3048 0.381)
			(layers "B.Cu" "B.Mask" "B.Paste")
			(net "P0V8_PEX2")
		)
		(pad "2" smd rect
			(at -0.2667 0 270)
			(size 0.3048 0.381)
			(layers "B.Cu" "B.Mask" "B.Paste")
			(net "GND")
		)
	)
	(footprint ""
		(layer "B.Cu")
		(at 392.749786 -294.94988)
		(property "Reference" "C3524"
			(at 0 0 0)
			(layer "B.SilkS")
			(hide yes)
			(effects
				(font
					(size 1.27 1.27)
				)
				(justify mirror)
			)
		)
		(property "Value" ""
			(at 0 0 0)
			(layer "B.Fab")
			(effects
				(font
					(size 1.27 1.27)
				)
				(justify mirror)
			)
		)
		(duplicate_pad_numbers_are_jumpers no)
		(fp_line
			(start -0.299974 -0.150114)
			(end -0.299974 0.150114)
			(stroke
				(width 0.1)
				(type default)
			)
			(layer "B.Fab")
		)
		(fp_line
			(start -0.299974 0.150114)
			(end 0.299974 0.150114)
			(stroke
				(width 0.1)
				(type default)
			)
			(layer "B.Fab")
		)
		(fp_line
			(start 0.299974 -0.150114)
			(end -0.299974 -0.150114)
			(stroke
				(width 0.1)
				(type default)
			)
			(layer "B.Fab")
		)
		(fp_line
			(start 0.299974 0.150114)
			(end 0.299974 -0.150114)
			(stroke
				(width 0.1)
				(type default)
			)
			(layer "B.Fab")
		)
		(pad "1" smd rect
			(at 0.2667 0 180)
			(size 0.3048 0.381)
			(layers "B.Cu" "B.Mask" "B.Paste")
			(net "P1V8_PEX")
		)
		(pad "2" smd rect
			(at -0.2667 0 180)
			(size 0.3048 0.381)
			(layers "B.Cu" "B.Mask" "B.Paste")
			(net "GND")
		)
	)
	(footprint ""
		(layer "B.Cu")
		(at 303.249838 -294.4749 180)
		(property "Reference" "C3274"
			(at 0 0 0)
			(layer "B.SilkS")
			(hide yes)
			(effects
				(font
					(size 1.27 1.27)
				)
				(justify mirror)
			)
		)
		(property "Value" ""
			(at 0 0 0)
			(layer "B.Fab")
			(effects
				(font
					(size 1.27 1.27)
				)
				(justify mirror)
			)
		)
		(duplicate_pad_numbers_are_jumpers no)
		(fp_line
			(start 0.299974 0.150114)
			(end 0.299974 -0.150114)
			(stroke
				(width 0.1)
				(type default)
			)
			(layer "B.Fab")
		)
		(fp_line
			(start 0.299974 -0.150114)
			(end -0.299974 -0.150114)
			(stroke
				(width 0.1)
				(type default)
			)
			(layer "B.Fab")
		)
		(fp_line
			(start -0.299974 0.150114)
			(end 0.299974 0.150114)
			(stroke
				(width 0.1)
				(type default)
			)
			(layer "B.Fab")
		)
		(fp_line
			(start -0.299974 -0.150114)
			(end -0.299974 0.150114)
			(stroke
				(width 0.1)
				(type default)
			)
			(layer "B.Fab")
		)
		(pad "1" smd rect
			(at 0.2667 0)
			(size 0.3048 0.381)
			(layers "B.Cu" "B.Mask" "B.Paste")
			(net "P1V25_PEX2")
		)
		(pad "2" smd rect
			(at -0.2667 0)
			(size 0.3048 0.381)
			(layers "B.Cu" "B.Mask" "B.Paste")
			(net "GND")
		)
	)
	(footprint ""
		(layer "B.Cu")
		(at 54.424834 -293.99992 90)
		(property "Reference" "C1150"
			(at 0 0 90)
			(layer "B.SilkS")
			(hide yes)
			(effects
				(font
					(size 1.27 1.27)
				)
				(justify mirror)
			)
		)
		(property "Value" ""
			(at 0 0 90)
			(layer "B.Fab")
			(effects
				(font
					(size 1.27 1.27)
				)
				(justify mirror)
			)
		)
		(duplicate_pad_numbers_are_jumpers no)
		(fp_line
			(start 0.299974 -0.150114)
			(end -0.299974 -0.150114)
			(stroke
				(width 0.1)
				(type default)
			)
			(layer "B.Fab")
		)
		(fp_line
			(start -0.299974 -0.150114)
			(end -0.299974 0.150114)
			(stroke
				(width 0.1)
				(type default)
			)
			(layer "B.Fab")
		)
		(fp_line
			(start 0.299974 0.150114)
			(end 0.299974 -0.150114)
			(stroke
				(width 0.1)
				(type default)
			)
			(layer "B.Fab")
		)
		(fp_line
			(start -0.299974 0.150114)
			(end 0.299974 0.150114)
			(stroke
				(width 0.1)
				(type default)
			)
			(layer "B.Fab")
		)
		(pad "1" smd rect
			(at 0.2667 0 270)
			(size 0.3048 0.381)
			(layers "B.Cu" "B.Mask" "B.Paste")
			(net "P0V8_PEX0")
		)
		(pad "2" smd rect
			(at -0.2667 0 270)
			(size 0.3048 0.381)
			(layers "B.Cu" "B.Mask" "B.Paste")
			(net "GND")
		)
	)
	(footprint ""
		(layer "B.Cu")
		(at 52.999894 -301.599854 -90)
		(property "Reference" "C1194"
			(at 0 0 90)
			(layer "B.SilkS")
			(hide yes)
			(effects
				(font
					(size 1.27 1.27)
				)
				(justify mirror)
			)
		)
		(property "Value" ""
			(at 0 0 90)
			(layer "B.Fab")
			(effects
				(font
					(size 1.27 1.27)
				)
				(justify mirror)
			)
		)
		(duplicate_pad_numbers_are_jumpers no)
		(fp_line
			(start -0.299974 0.150114)
			(end 0.299974 0.150114)
			(stroke
				(width 0.1)
				(type default)
			)
			(layer "B.Fab")
		)
		(fp_line
			(start 0.299974 0.150114)
			(end 0.299974 -0.150114)
			(stroke
				(width 0.1)
				(type default)
			)
			(layer "B.Fab")
		)
		(fp_line
			(start -0.299974 -0.150114)
			(end -0.299974 0.150114)
			(stroke
				(width 0.1)
				(type default)
			)
			(layer "B.Fab")
		)
		(fp_line
			(start 0.299974 -0.150114)
			(end -0.299974 -0.150114)
			(stroke
				(width 0.1)
				(type default)
			)
			(layer "B.Fab")
		)
		(pad "1" smd rect
			(at 0.2667 0 90)
			(size 0.3048 0.381)
			(layers "B.Cu" "B.Mask" "B.Paste")
			(net "P0V8_SERDES_VDDA_PEX0")
		)
		(pad "2" smd rect
			(at -0.2667 0 90)
			(size 0.3048 0.381)
			(layers "B.Cu" "B.Mask" "B.Paste")
			(net "GND")
		)
	)
	(footprint ""
		(layer "B.Cu")
		(at 295.174924 -286.399732 90)
		(property "Reference" "C3327"
			(at 0 0 90)
			(layer "B.SilkS")
			(hide yes)
			(effects
				(font
					(size 1.27 1.27)
				)
				(justify mirror)
			)
		)
		(property "Value" ""
			(at 0 0 90)
			(layer "B.Fab")
			(effects
				(font
					(size 1.27 1.27)
				)
				(justify mirror)
			)
		)
		(duplicate_pad_numbers_are_jumpers no)
		(fp_line
			(start 0.299974 -0.150114)
			(end -0.299974 -0.150114)
			(stroke
				(width 0.1)
				(type default)
			)
			(layer "B.Fab")
		)
		(fp_line
			(start -0.299974 -0.150114)
			(end -0.299974 0.150114)
			(stroke
				(width 0.1)
				(type default)
			)
			(layer "B.Fab")
		)
		(fp_line
			(start 0.299974 0.150114)
			(end 0.299974 -0.150114)
			(stroke
				(width 0.1)
				(type default)
			)
			(layer "B.Fab")
		)
		(fp_line
			(start -0.299974 0.150114)
			(end 0.299974 0.150114)
			(stroke
				(width 0.1)
				(type default)
			)
			(layer "B.Fab")
		)
		(pad "1" smd rect
			(at 0.2667 0 270)
			(size 0.3048 0.381)
			(layers "B.Cu" "B.Mask" "B.Paste")
			(net "P1V25_SERDES_VDDPLL_PEX2")
		)
		(pad "2" smd rect
			(at -0.2667 0 270)
			(size 0.3048 0.381)
			(layers "B.Cu" "B.Mask" "B.Paste")
			(net "GND")
		)
	)
	(footprint ""
		(layer "B.Cu")
		(at 278.064214 -146.148552 180)
		(property "Reference" "C909"
			(at 0 0 0)
			(layer "B.SilkS")
			(hide yes)
			(effects
				(font
					(size 1.27 1.27)
				)
				(justify mirror)
			)
		)
		(property "Value" ""
			(at 0 0 0)
			(layer "B.Fab")
			(effects
				(font
					(size 1.27 1.27)
				)
				(justify mirror)
			)
		)
		(duplicate_pad_numbers_are_jumpers no)
		(fp_line
			(start 0.299974 0.150114)
			(end 0.299974 -0.150114)
			(stroke
				(width 0.1)
				(type default)
			)
			(layer "B.Fab")
		)
		(fp_line
			(start 0.299974 -0.150114)
			(end -0.299974 -0.150114)
			(stroke
				(width 0.1)
				(type default)
			)
			(layer "B.Fab")
		)
		(fp_line
			(start -0.299974 0.150114)
			(end 0.299974 0.150114)
			(stroke
				(width 0.1)
				(type default)
			)
			(layer "B.Fab")
		)
		(fp_line
			(start -0.299974 -0.150114)
			(end -0.299974 0.150114)
			(stroke
				(width 0.1)
				(type default)
			)
			(layer "B.Fab")
		)
		(pad "1" smd rect
			(at 0.2667 0)
			(size 0.3048 0.381)
			(layers "B.Cu" "B.Mask" "B.Paste")
			(net "P12V_NIC4")
		)
		(pad "2" smd rect
			(at -0.2667 0)
			(size 0.3048 0.381)
			(layers "B.Cu" "B.Mask" "B.Paste")
			(net "GND")
		)
	)
	(footprint ""
		(layer "B.Cu")
		(at 173.850046 -303.499774 -90)
		(property "Reference" "C3091"
			(at 0 0 90)
			(layer "B.SilkS")
			(hide yes)
			(effects
				(font
					(size 1.27 1.27)
				)
				(justify mirror)
			)
		)
		(property "Value" ""
			(at 0 0 90)
			(layer "B.Fab")
			(effects
				(font
					(size 1.27 1.27)
				)
				(justify mirror)
			)
		)
		(duplicate_pad_numbers_are_jumpers no)
		(fp_line
			(start -0.299974 0.150114)
			(end 0.299974 0.150114)
			(stroke
				(width 0.1)
				(type default)
			)
			(layer "B.Fab")
		)
		(fp_line
			(start 0.299974 0.150114)
			(end 0.299974 -0.150114)
			(stroke
				(width 0.1)
				(type default)
			)
			(layer "B.Fab")
		)
		(fp_line
			(start -0.299974 -0.150114)
			(end -0.299974 0.150114)
			(stroke
				(width 0.1)
				(type default)
			)
			(layer "B.Fab")
		)
		(fp_line
			(start 0.299974 -0.150114)
			(end -0.299974 -0.150114)
			(stroke
				(width 0.1)
				(type default)
			)
			(layer "B.Fab")
		)
		(pad "1" smd rect
			(at 0.2667 0 90)
			(size 0.3048 0.381)
			(layers "B.Cu" "B.Mask" "B.Paste")
			(net "P1V25_PEX1")
		)
		(pad "2" smd rect
			(at -0.2667 0 90)
			(size 0.3048 0.381)
			(layers "B.Cu" "B.Mask" "B.Paste")
			(net "GND")
		)
	)
	(footprint ""
		(layer "B.Cu")
		(at 213.70671 -225.42246 180)
		(property "Reference" "R4872"
			(at 0 0 0)
			(layer "B.SilkS")
			(hide yes)
			(effects
				(font
					(size 1.27 1.27)
				)
				(justify mirror)
			)
		)
		(property "Value" ""
			(at 0 0 0)
			(layer "B.Fab")
			(effects
				(font
					(size 1.27 1.27)
				)
				(justify mirror)
			)
		)
		(duplicate_pad_numbers_are_jumpers no)
		(fp_line
			(start 0.7874 0.4064)
			(end 0.7874 -0.4064)
			(stroke
				(width 0.1524)
				(type default)
			)
			(layer "B.SilkS")
		)
		(fp_line
			(start 0.7874 -0.4064)
			(end -0.7874 -0.4064)
			(stroke
				(width 0.1524)
				(type default)
			)
			(layer "B.SilkS")
		)
		(fp_line
			(start -0.7874 0.4064)
			(end 0.7874 0.4064)
			(stroke
				(width 0.1524)
				(type default)
			)
			(layer "B.SilkS")
		)
		(fp_line
			(start -0.7874 -0.4064)
			(end -0.7874 0.4064)
			(stroke
				(width 0.1524)
				(type default)
			)
			(layer "B.SilkS")
		)
		(fp_line
			(start 0.67945 0.3048)
			(end 0.67945 -0.305054)
			(stroke
				(width 0.1)
				(type default)
			)
			(layer "B.Fab")
		)
		(fp_line
			(start 0.67945 -0.305054)
			(end 0.12065 -0.305054)
			(stroke
				(width 0.1)
				(type default)
			)
			(layer "B.Fab")
		)
		(fp_line
			(start 0.12065 0.3048)
			(end 0.67945 0.3048)
			(stroke
				(width 0.1)
				(type default)
			)
			(layer "B.Fab")
		)
		(fp_line
			(start 0.12065 0.2794)
			(end 0.12065 0.3048)
			(stroke
				(width 0.1)
				(type default)
			)
			(layer "B.Fab")
		)
		(fp_line
			(start 0.12065 -0.2794)
			(end -0.12065 -0.2794)
			(stroke
				(width 0.1)
				(type default)
			)
			(layer "B.Fab")
		)
		(fp_line
			(start 0.12065 -0.305054)
			(end 0.12065 -0.2794)
			(stroke
				(width 0.1)
				(type default)
			)
			(layer "B.Fab")
		)
		(fp_line
			(start -0.120396 0.3048)
			(end -0.120396 0.2794)
			(stroke
				(width 0.1)
				(type default)
			)
			(layer "B.Fab")
		)
		(fp_line
			(start -0.120396 0.2794)
			(end 0.12065 0.2794)
			(stroke
				(width 0.1)
				(type default)
			)
			(layer "B.Fab")
		)
		(fp_line
			(start -0.12065 -0.2794)
			(end -0.12065 -0.3048)
			(stroke
				(width 0.1)
				(type default)
			)
			(layer "B.Fab")
		)
		(fp_line
			(start -0.12065 -0.3048)
			(end -0.67945 -0.3048)
			(stroke
				(width 0.1)
				(type default)
			)
			(layer "B.Fab")
		)
		(fp_line
			(start -0.67945 0.3048)
			(end -0.120396 0.3048)
			(stroke
				(width 0.1)
				(type default)
			)
			(layer "B.Fab")
		)
		(fp_line
			(start -0.67945 -0.3048)
			(end -0.67945 0.3048)
			(stroke
				(width 0.1)
				(type default)
			)
			(layer "B.Fab")
		)
		(pad "1" smd circle
			(at 0.40005 0)
			(size 0 0)
			(layers "B.Cu" "B.Mask" "B.Paste")
			(net "P3V3_AUX")
		)
		(pad "2" smd circle
			(at -0.40005 0)
			(size 0 0)
			(layers "B.Cu" "B.Mask" "B.Paste")
			(net "SMB_FIO_SDA")
		)
	)
	(footprint ""
		(layer "B.Cu")
		(at 415.549842 -299.699934 -90)
		(property "Reference" "C1961"
			(at 0 0 90)
			(layer "B.SilkS")
			(hide yes)
			(effects
				(font
					(size 1.27 1.27)
				)
				(justify mirror)
			)
		)
		(property "Value" ""
			(at 0 0 90)
			(layer "B.Fab")
			(effects
				(font
					(size 1.27 1.27)
				)
				(justify mirror)
			)
		)
		(duplicate_pad_numbers_are_jumpers no)
		(fp_line
			(start -0.299974 0.150114)
			(end 0.299974 0.150114)
			(stroke
				(width 0.1)
				(type default)
			)
			(layer "B.Fab")
		)
		(fp_line
			(start 0.299974 0.150114)
			(end 0.299974 -0.150114)
			(stroke
				(width 0.1)
				(type default)
			)
			(layer "B.Fab")
		)
		(fp_line
			(start -0.299974 -0.150114)
			(end -0.299974 0.150114)
			(stroke
				(width 0.1)
				(type default)
			)
			(layer "B.Fab")
		)
		(fp_line
			(start 0.299974 -0.150114)
			(end -0.299974 -0.150114)
			(stroke
				(width 0.1)
				(type default)
			)
			(layer "B.Fab")
		)
		(pad "1" smd rect
			(at 0.2667 0 90)
			(size 0.3048 0.381)
			(layers "B.Cu" "B.Mask" "B.Paste")
			(net "P0V8_SERDES_VDDA_PEX3")
		)
		(pad "2" smd rect
			(at -0.2667 0 90)
			(size 0.3048 0.381)
			(layers "B.Cu" "B.Mask" "B.Paste")
			(net "GND")
		)
	)
	(footprint ""
		(layer "B.Cu")
		(at 165.655244 -150.9776)
		(property "Reference" "R122"
			(at 0 0 0)
			(layer "B.SilkS")
			(hide yes)
			(effects
				(font
					(size 1.27 1.27)
				)
				(justify mirror)
			)
		)
		(property "Value" ""
			(at 0 0 0)
			(layer "B.Fab")
			(effects
				(font
					(size 1.27 1.27)
				)
				(justify mirror)
			)
		)
		(duplicate_pad_numbers_are_jumpers no)
		(fp_line
			(start -0.7874 -0.4064)
			(end -0.7874 0.4064)
			(stroke
				(width 0.1524)
				(type default)
			)
			(layer "B.SilkS")
		)
		(fp_line
			(start -0.7874 0.4064)
			(end 0.7874 0.4064)
			(stroke
				(width 0.1524)
				(type default)
			)
			(layer "B.SilkS")
		)
		(fp_line
			(start 0.7874 -0.4064)
			(end -0.7874 -0.4064)
			(stroke
				(width 0.1524)
				(type default)
			)
			(layer "B.SilkS")
		)
		(fp_line
			(start 0.7874 0.4064)
			(end 0.7874 -0.4064)
			(stroke
				(width 0.1524)
				(type default)
			)
			(layer "B.SilkS")
		)
		(fp_line
			(start -0.67945 -0.3048)
			(end -0.67945 0.3048)
			(stroke
				(width 0.1)
				(type default)
			)
			(layer "B.Fab")
		)
		(fp_line
			(start -0.67945 0.3048)
			(end -0.120396 0.3048)
			(stroke
				(width 0.1)
				(type default)
			)
			(layer "B.Fab")
		)
		(fp_line
			(start -0.12065 -0.3048)
			(end -0.67945 -0.3048)
			(stroke
				(width 0.1)
				(type default)
			)
			(layer "B.Fab")
		)
		(fp_line
			(start -0.12065 -0.2794)
			(end -0.12065 -0.3048)
			(stroke
				(width 0.1)
				(type default)
			)
			(layer "B.Fab")
		)
		(fp_line
			(start -0.120396 0.2794)
			(end 0.12065 0.2794)
			(stroke
				(width 0.1)
				(type default)
			)
			(layer "B.Fab")
		)
		(fp_line
			(start -0.120396 0.3048)
			(end -0.120396 0.2794)
			(stroke
				(width 0.1)
				(type default)
			)
			(layer "B.Fab")
		)
		(fp_line
			(start 0.12065 -0.305054)
			(end 0.12065 -0.2794)
			(stroke
				(width 0.1)
				(type default)
			)
			(layer "B.Fab")
		)
		(fp_line
			(start 0.12065 -0.2794)
			(end -0.12065 -0.2794)
			(stroke
				(width 0.1)
				(type default)
			)
			(layer "B.Fab")
		)
		(fp_line
			(start 0.12065 0.2794)
			(end 0.12065 0.3048)
			(stroke
				(width 0.1)
				(type default)
			)
			(layer "B.Fab")
		)
		(fp_line
			(start 0.12065 0.3048)
			(end 0.67945 0.3048)
			(stroke
				(width 0.1)
				(type default)
			)
			(layer "B.Fab")
		)
		(fp_line
			(start 0.67945 -0.305054)
			(end 0.12065 -0.305054)
			(stroke
				(width 0.1)
				(type default)
			)
			(layer "B.Fab")
		)
		(fp_line
			(start 0.67945 0.3048)
			(end 0.67945 -0.305054)
			(stroke
				(width 0.1)
				(type default)
			)
			(layer "B.Fab")
		)
		(pad "1" smd circle
			(at 0.40005 0 180)
			(size 0 0)
			(layers "B.Cu" "B.Mask" "B.Paste")
			(net "CLK_50M_NIC2_RBT_REF")
		)
		(pad "2" smd circle
			(at -0.40005 0 180)
			(size 0 0)
			(layers "B.Cu" "B.Mask" "B.Paste")
			(net "GND")
		)
	)
	(footprint ""
		(layer "B.Cu")
		(at 229.067614 -221.904052 90)
		(property "Reference" "C2017"
			(at 0 0 90)
			(layer "B.SilkS")
			(hide yes)
			(effects
				(font
					(size 1.27 1.27)
				)
				(justify mirror)
			)
		)
		(property "Value" ""
			(at 0 0 90)
			(layer "B.Fab")
			(effects
				(font
					(size 1.27 1.27)
				)
				(justify mirror)
			)
		)
		(duplicate_pad_numbers_are_jumpers no)
		(fp_line
			(start 0.69215 -0.2921)
			(end -0.69215 -0.2921)
			(stroke
				(width 0.1524)
				(type default)
			)
			(layer "B.SilkS")
		)
		(fp_line
			(start -0.69215 -0.2921)
			(end -0.69215 0.2921)
			(stroke
				(width 0.1524)
				(type default)
			)
			(layer "B.SilkS")
		)
		(fp_line
			(start 0.69215 0.2921)
			(end 0.69215 -0.2921)
			(stroke
				(width 0.1524)
				(type default)
			)
			(layer "B.SilkS")
		)
		(fp_line
			(start -0.69215 0.2921)
			(end 0.69215 0.2921)
			(stroke
				(width 0.1524)
				(type default)
			)
			(layer "B.SilkS")
		)
		(fp_line
			(start 0.51435 -0.2794)
			(end -0.51435 -0.2794)
			(stroke
				(width 0.1)
				(type default)
			)
			(layer "B.Fab")
		)
		(fp_line
			(start -0.51435 -0.2794)
			(end -0.51435 0.2794)
			(stroke
				(width 0.1)
				(type default)
			)
			(layer "B.Fab")
		)
		(fp_line
			(start 0.51435 0.2794)
			(end 0.51435 -0.2794)
			(stroke
				(width 0.1)
				(type default)
			)
			(layer "B.Fab")
		)
		(fp_line
			(start -0.51435 0.2794)
			(end 0.51435 0.2794)
			(stroke
				(width 0.1)
				(type default)
			)
			(layer "B.Fab")
		)
		(pad "1" smd circle
			(at 0.40005 0 270)
			(size 0 0)
			(layers "B.Cu" "B.Mask" "B.Paste")
			(net "P1V2_AUX")
		)
		(pad "2" smd circle
			(at -0.40005 0 270)
			(size 0 0)
			(layers "B.Cu" "B.Mask" "B.Paste")
			(net "GND")
		)
		(zone
			(layer "B.Cu")
			(hatch none 0.5)
			(connect_pads
				(clearance 0)
			)
			(min_thickness 0.25)
			(keepout
				(tracks not_allowed)
				(vias allowed)
				(pads allowed)
				(copperpour not_allowed)
				(footprints allowed)
			)
			(placement
				(enabled no)
				(sheetname "")
			)
			(fill
				(thermal_gap 0.5)
				(thermal_bridge_width 0.5)
				(island_removal_mode 0)
			)
			(polygon
				(pts
					(xy 229.155244 -222.094552) (xy 229.21341 -222.003112) (xy 229.21341 -221.803722) (xy 229.155244 -221.713552)
					(xy 228.979984 -221.713552) (xy 228.921564 -221.803722) (xy 228.921564 -222.003112) (xy 228.97973 -222.094552)
				)
			)
		)
	)
	(footprint ""
		(layer "B.Cu")
		(at 283.299916 -301.599854 -90)
		(property "Reference" "C1702"
			(at 0 0 90)
			(layer "B.SilkS")
			(hide yes)
			(effects
				(font
					(size 1.27 1.27)
				)
				(justify mirror)
			)
		)
		(property "Value" ""
			(at 0 0 90)
			(layer "B.Fab")
			(effects
				(font
					(size 1.27 1.27)
				)
				(justify mirror)
			)
		)
		(duplicate_pad_numbers_are_jumpers no)
		(fp_line
			(start -0.299974 0.150114)
			(end 0.299974 0.150114)
			(stroke
				(width 0.1)
				(type default)
			)
			(layer "B.Fab")
		)
		(fp_line
			(start 0.299974 0.150114)
			(end 0.299974 -0.150114)
			(stroke
				(width 0.1)
				(type default)
			)
			(layer "B.Fab")
		)
		(fp_line
			(start -0.299974 -0.150114)
			(end -0.299974 0.150114)
			(stroke
				(width 0.1)
				(type default)
			)
			(layer "B.Fab")
		)
		(fp_line
			(start 0.299974 -0.150114)
			(end -0.299974 -0.150114)
			(stroke
				(width 0.1)
				(type default)
			)
			(layer "B.Fab")
		)
		(pad "1" smd rect
			(at 0.2667 0 90)
			(size 0.3048 0.381)
			(layers "B.Cu" "B.Mask" "B.Paste")
			(net "P0V8_SERDES_VDDA_PEX2")
		)
		(pad "2" smd rect
			(at -0.2667 0 90)
			(size 0.3048 0.381)
			(layers "B.Cu" "B.Mask" "B.Paste")
			(net "GND")
		)
	)
	(footprint ""
		(layer "B.Cu")
		(at 63.449962 -292.099746 90)
		(property "Reference" "C1211"
			(at 0 0 90)
			(layer "B.SilkS")
			(hide yes)
			(effects
				(font
					(size 1.27 1.27)
				)
				(justify mirror)
			)
		)
		(property "Value" ""
			(at 0 0 90)
			(layer "B.Fab")
			(effects
				(font
					(size 1.27 1.27)
				)
				(justify mirror)
			)
		)
		(duplicate_pad_numbers_are_jumpers no)
		(fp_line
			(start 0.299974 -0.150114)
			(end -0.299974 -0.150114)
			(stroke
				(width 0.1)
				(type default)
			)
			(layer "B.Fab")
		)
		(fp_line
			(start -0.299974 -0.150114)
			(end -0.299974 0.150114)
			(stroke
				(width 0.1)
				(type default)
			)
			(layer "B.Fab")
		)
		(fp_line
			(start 0.299974 0.150114)
			(end 0.299974 -0.150114)
			(stroke
				(width 0.1)
				(type default)
			)
			(layer "B.Fab")
		)
		(fp_line
			(start -0.299974 0.150114)
			(end 0.299974 0.150114)
			(stroke
				(width 0.1)
				(type default)
			)
			(layer "B.Fab")
		)
		(pad "1" smd rect
			(at 0.2667 0 270)
			(size 0.3048 0.381)
			(layers "B.Cu" "B.Mask" "B.Paste")
			(net "P0V8_SERDES_VDDA_PEX0")
		)
		(pad "2" smd rect
			(at -0.2667 0 270)
			(size 0.3048 0.381)
			(layers "B.Cu" "B.Mask" "B.Paste")
			(net "GND")
		)
	)
	(footprint ""
		(layer "B.Cu")
		(at 401.299934 -288.299906 90)
		(property "Reference" "C3449"
			(at 0 0 90)
			(layer "B.SilkS")
			(hide yes)
			(effects
				(font
					(size 1.27 1.27)
				)
				(justify mirror)
			)
		)
		(property "Value" ""
			(at 0 0 90)
			(layer "B.Fab")
			(effects
				(font
					(size 1.27 1.27)
				)
				(justify mirror)
			)
		)
		(duplicate_pad_numbers_are_jumpers no)
		(fp_line
			(start 0.299974 -0.150114)
			(end -0.299974 -0.150114)
			(stroke
				(width 0.1)
				(type default)
			)
			(layer "B.Fab")
		)
		(fp_line
			(start -0.299974 -0.150114)
			(end -0.299974 0.150114)
			(stroke
				(width 0.1)
				(type default)
			)
			(layer "B.Fab")
		)
		(fp_line
			(start 0.299974 0.150114)
			(end 0.299974 -0.150114)
			(stroke
				(width 0.1)
				(type default)
			)
			(layer "B.Fab")
		)
		(fp_line
			(start -0.299974 0.150114)
			(end 0.299974 0.150114)
			(stroke
				(width 0.1)
				(type default)
			)
			(layer "B.Fab")
		)
		(pad "1" smd rect
			(at 0.2667 0 270)
			(size 0.3048 0.381)
			(layers "B.Cu" "B.Mask" "B.Paste")
			(net "P1V25_PEX3")
		)
		(pad "2" smd rect
			(at -0.2667 0 270)
			(size 0.3048 0.381)
			(layers "B.Cu" "B.Mask" "B.Paste")
			(net "GND")
		)
	)
	(footprint ""
		(layer "B.Cu")
		(at 73.400158 -111.791496)
		(property "Reference" "C862"
			(at 0 0 0)
			(layer "B.SilkS")
			(hide yes)
			(effects
				(font
					(size 1.27 1.27)
				)
				(justify mirror)
			)
		)
		(property "Value" ""
			(at 0 0 0)
			(layer "B.Fab")
			(effects
				(font
					(size 1.27 1.27)
				)
				(justify mirror)
			)
		)
		(duplicate_pad_numbers_are_jumpers no)
		(fp_line
			(start -0.299974 -0.150114)
			(end -0.299974 0.150114)
			(stroke
				(width 0.1)
				(type default)
			)
			(layer "B.Fab")
		)
		(fp_line
			(start -0.299974 0.150114)
			(end 0.299974 0.150114)
			(stroke
				(width 0.1)
				(type default)
			)
			(layer "B.Fab")
		)
		(fp_line
			(start 0.299974 -0.150114)
			(end -0.299974 -0.150114)
			(stroke
				(width 0.1)
				(type default)
			)
			(layer "B.Fab")
		)
		(fp_line
			(start 0.299974 0.150114)
			(end 0.299974 -0.150114)
			(stroke
				(width 0.1)
				(type default)
			)
			(layer "B.Fab")
		)
		(pad "1" smd rect
			(at 0.2667 0 180)
			(size 0.3048 0.381)
			(layers "B.Cu" "B.Mask" "B.Paste")
			(net "P12V_NIC1")
		)
		(pad "2" smd rect
			(at -0.2667 0 180)
			(size 0.3048 0.381)
			(layers "B.Cu" "B.Mask" "B.Paste")
			(net "GND")
		)
	)
	(footprint ""
		(layer "B.Cu")
		(at 295.17467 -293.99992 90)
		(property "Reference" "C1641"
			(at 0 0 90)
			(layer "B.SilkS")
			(hide yes)
			(effects
				(font
					(size 1.27 1.27)
				)
				(justify mirror)
			)
		)
		(property "Value" ""
			(at 0 0 90)
			(layer "B.Fab")
			(effects
				(font
					(size 1.27 1.27)
				)
				(justify mirror)
			)
		)
		(duplicate_pad_numbers_are_jumpers no)
		(fp_line
			(start 0.299974 -0.150114)
			(end -0.299974 -0.150114)
			(stroke
				(width 0.1)
				(type default)
			)
			(layer "B.Fab")
		)
		(fp_line
			(start -0.299974 -0.150114)
			(end -0.299974 0.150114)
			(stroke
				(width 0.1)
				(type default)
			)
			(layer "B.Fab")
		)
		(fp_line
			(start 0.299974 0.150114)
			(end 0.299974 -0.150114)
			(stroke
				(width 0.1)
				(type default)
			)
			(layer "B.Fab")
		)
		(fp_line
			(start -0.299974 0.150114)
			(end 0.299974 0.150114)
			(stroke
				(width 0.1)
				(type default)
			)
			(layer "B.Fab")
		)
		(pad "1" smd rect
			(at 0.2667 0 270)
			(size 0.3048 0.381)
			(layers "B.Cu" "B.Mask" "B.Paste")
			(net "P0V8_PEX2")
		)
		(pad "2" smd rect
			(at -0.2667 0 270)
			(size 0.3048 0.381)
			(layers "B.Cu" "B.Mask" "B.Paste")
			(net "GND")
		)
	)
	(footprint ""
		(layer "B.Cu")
		(at 333.912972 -325.909178 -90)
		(property "Reference" "C4328"
			(at 0 0 90)
			(layer "B.SilkS")
			(hide yes)
			(effects
				(font
					(size 1.27 1.27)
				)
				(justify mirror)
			)
		)
		(property "Value" ""
			(at 0 0 90)
			(layer "B.Fab")
			(effects
				(font
					(size 1.27 1.27)
				)
				(justify mirror)
			)
		)
		(duplicate_pad_numbers_are_jumpers no)
		(fp_line
			(start -1.2954 0.5842)
			(end 1.2954 0.5842)
			(stroke
				(width 0.1524)
				(type default)
			)
			(layer "B.SilkS")
		)
		(fp_line
			(start 1.2954 0.5842)
			(end 1.2954 -0.5842)
			(stroke
				(width 0.1524)
				(type default)
			)
			(layer "B.SilkS")
		)
		(fp_line
			(start -1.2954 -0.5842)
			(end -1.2954 0.5842)
			(stroke
				(width 0.1524)
				(type default)
			)
			(layer "B.SilkS")
		)
		(fp_line
			(start 1.2954 -0.5842)
			(end -1.2954 -0.5842)
			(stroke
				(width 0.1524)
				(type default)
			)
			(layer "B.SilkS")
		)
		(fp_line
			(start -0.8636 0.4572)
			(end 0.8636 0.4572)
			(stroke
				(width 0.1)
				(type default)
			)
			(layer "B.Fab")
		)
		(fp_line
			(start 0.8636 0.4572)
			(end 0.8636 0.4064)
			(stroke
				(width 0.1)
				(type default)
			)
			(layer "B.Fab")
		)
		(fp_line
			(start -1.1938 0.4064)
			(end -0.8636 0.4064)
			(stroke
				(width 0.1)
				(type default)
			)
			(layer "B.Fab")
		)
		(fp_line
			(start -0.8636 0.4064)
			(end -0.8636 0.4572)
			(stroke
				(width 0.1)
				(type default)
			)
			(layer "B.Fab")
		)
		(fp_line
			(start 0.8636 0.4064)
			(end 1.1938 0.4064)
			(stroke
				(width 0.1)
				(type default)
			)
			(layer "B.Fab")
		)
		(fp_line
			(start 1.1938 0.4064)
			(end 1.1938 -0.4064)
			(stroke
				(width 0.1)
				(type default)
			)
			(layer "B.Fab")
		)
		(fp_line
			(start -1.1938 -0.4064)
			(end -1.1938 0.4064)
			(stroke
				(width 0.1)
				(type default)
			)
			(layer "B.Fab")
		)
		(fp_line
			(start -0.8636 -0.4064)
			(end -1.1938 -0.4064)
			(stroke
				(width 0.1)
				(type default)
			)
			(layer "B.Fab")
		)
		(fp_line
			(start 0.8636 -0.4064)
			(end 0.8636 -0.4572)
			(stroke
				(width 0.1)
				(type default)
			)
			(layer "B.Fab")
		)
		(fp_line
			(start 1.1938 -0.4064)
			(end 0.8636 -0.4064)
			(stroke
				(width 0.1)
				(type default)
			)
			(layer "B.Fab")
		)
		(fp_line
			(start -0.8636 -0.4572)
			(end -0.8636 -0.4064)
			(stroke
				(width 0.1)
				(type default)
			)
			(layer "B.Fab")
		)
		(fp_line
			(start 0.8636 -0.4572)
			(end -0.8636 -0.4572)
			(stroke
				(width 0.1)
				(type default)
			)
			(layer "B.Fab")
		)
		(pad "1" smd rect
			(at 0.7366 0 180)
			(size 0.7112 0.8128)
			(layers "B.Cu" "B.Mask" "B.Paste")
			(net "P0V8_SERDES_VDDA_PEX2_C10")
		)
		(pad "2" smd rect
			(at -0.7366 0 180)
			(size 0.7112 0.8128)
			(layers "B.Cu" "B.Mask" "B.Paste")
			(net "GND")
		)
	)
	(footprint ""
		(layer "B.Cu")
		(at 350.65716 -316.003686)
		(property "Reference" "C4379"
			(at 0 0 0)
			(layer "B.SilkS")
			(hide yes)
			(effects
				(font
					(size 1.27 1.27)
				)
				(justify mirror)
			)
		)
		(property "Value" ""
			(at 0 0 0)
			(layer "B.Fab")
			(effects
				(font
					(size 1.27 1.27)
				)
				(justify mirror)
			)
		)
		(duplicate_pad_numbers_are_jumpers no)
		(fp_line
			(start -0.299974 -0.150114)
			(end -0.299974 0.150114)
			(stroke
				(width 0.1)
				(type default)
			)
			(layer "B.Fab")
		)
		(fp_line
			(start -0.299974 0.150114)
			(end 0.299974 0.150114)
			(stroke
				(width 0.1)
				(type default)
			)
			(layer "B.Fab")
		)
		(fp_line
			(start 0.299974 -0.150114)
			(end -0.299974 -0.150114)
			(stroke
				(width 0.1)
				(type default)
			)
			(layer "B.Fab")
		)
		(fp_line
			(start 0.299974 0.150114)
			(end 0.299974 -0.150114)
			(stroke
				(width 0.1)
				(type default)
			)
			(layer "B.Fab")
		)
		(pad "1" smd rect
			(at 0.2667 0 180)
			(size 0.3048 0.381)
			(layers "B.Cu" "B.Mask" "B.Paste")
			(net "P0V8_SERDES_VDDA_PEX3")
		)
		(pad "2" smd rect
			(at -0.2667 0 180)
			(size 0.3048 0.381)
			(layers "B.Cu" "B.Mask" "B.Paste")
			(net "GND")
		)
	)
	(footprint ""
		(layer "B.Cu")
		(at 168.625012 -293.99992 90)
		(property "Reference" "C1378"
			(at 0 0 90)
			(layer "B.SilkS")
			(hide yes)
			(effects
				(font
					(size 1.27 1.27)
				)
				(justify mirror)
			)
		)
		(property "Value" ""
			(at 0 0 90)
			(layer "B.Fab")
			(effects
				(font
					(size 1.27 1.27)
				)
				(justify mirror)
			)
		)
		(duplicate_pad_numbers_are_jumpers no)
		(fp_line
			(start 0.299974 -0.150114)
			(end -0.299974 -0.150114)
			(stroke
				(width 0.1)
				(type default)
			)
			(layer "B.Fab")
		)
		(fp_line
			(start -0.299974 -0.150114)
			(end -0.299974 0.150114)
			(stroke
				(width 0.1)
				(type default)
			)
			(layer "B.Fab")
		)
		(fp_line
			(start 0.299974 0.150114)
			(end 0.299974 -0.150114)
			(stroke
				(width 0.1)
				(type default)
			)
			(layer "B.Fab")
		)
		(fp_line
			(start -0.299974 0.150114)
			(end 0.299974 0.150114)
			(stroke
				(width 0.1)
				(type default)
			)
			(layer "B.Fab")
		)
		(pad "1" smd rect
			(at 0.2667 0 270)
			(size 0.3048 0.381)
			(layers "B.Cu" "B.Mask" "B.Paste")
			(net "P0V8_PEX1")
		)
		(pad "2" smd rect
			(at -0.2667 0 270)
			(size 0.3048 0.381)
			(layers "B.Cu" "B.Mask" "B.Paste")
			(net "GND")
		)
	)
	(footprint ""
		(layer "B.Cu")
		(at 354.889562 -313.620404)
		(property "Reference" "R5797"
			(at 0 0 0)
			(layer "B.SilkS")
			(hide yes)
			(effects
				(font
					(size 1.27 1.27)
				)
				(justify mirror)
			)
		)
		(property "Value" ""
			(at 0 0 0)
			(layer "B.Fab")
			(effects
				(font
					(size 1.27 1.27)
				)
				(justify mirror)
			)
		)
		(duplicate_pad_numbers_are_jumpers no)
		(fp_line
			(start -2.576322 -1.1303)
			(end -2.576322 1.1303)
			(stroke
				(width 0.1524)
				(type default)
			)
			(layer "B.SilkS")
		)
		(fp_line
			(start -2.576322 1.1303)
			(end 2.576322 1.1303)
			(stroke
				(width 0.1524)
				(type default)
			)
			(layer "B.SilkS")
		)
		(fp_line
			(start 2.576322 -1.1303)
			(end -2.576322 -1.1303)
			(stroke
				(width 0.1524)
				(type default)
			)
			(layer "B.SilkS")
		)
		(fp_line
			(start 2.576322 1.1303)
			(end 2.576322 -1.1303)
			(stroke
				(width 0.1524)
				(type default)
			)
			(layer "B.SilkS")
		)
		(fp_line
			(start -1.649984 -0.899922)
			(end 1.649984 -0.899922)
			(stroke
				(width 0.1)
				(type default)
			)
			(layer "B.Fab")
		)
		(fp_line
			(start -1.649984 0.899922)
			(end -1.649984 -0.899922)
			(stroke
				(width 0.1)
				(type default)
			)
			(layer "B.Fab")
		)
		(fp_line
			(start 1.649984 -0.899922)
			(end 1.649984 0.899922)
			(stroke
				(width 0.1)
				(type default)
			)
			(layer "B.Fab")
		)
		(fp_line
			(start 1.649984 0.899922)
			(end -1.649984 0.899922)
			(stroke
				(width 0.1)
				(type default)
			)
			(layer "B.Fab")
		)
		(pad "1A" smd rect
			(at 1.700022 0 180)
			(size 1.4986 2.0066)
			(layers "B.Cu" "B.Mask" "B.Paste")
			(net "P0V8_PEX3")
		)
		(pad "1B" smd rect
			(at 1.077722 0 180)
			(size 0.254 0.508)
			(layers "B.Cu" "B.Mask" "B.Paste")
			(net "P0V8_PEX3")
		)
		(pad "2A" smd rect
			(at -1.700022 0 180)
			(size 1.4986 2.0066)
			(layers "B.Cu" "B.Mask" "B.Paste")
			(net "P0V8_SERDES_VDDA_PEX3")
		)
		(pad "2B" smd rect
			(at -1.077722 0 180)
			(size 0.254 0.508)
			(layers "B.Cu" "B.Mask" "B.Paste")
			(net "P0V8_SERDES_VDDA_PEX3")
		)
	)
	(footprint ""
		(layer "B.Cu")
		(at 295.649904 -299.699934 -90)
		(property "Reference" "C1724"
			(at 0 0 90)
			(layer "B.SilkS")
			(hide yes)
			(effects
				(font
					(size 1.27 1.27)
				)
				(justify mirror)
			)
		)
		(property "Value" ""
			(at 0 0 90)
			(layer "B.Fab")
			(effects
				(font
					(size 1.27 1.27)
				)
				(justify mirror)
			)
		)
		(duplicate_pad_numbers_are_jumpers no)
		(fp_line
			(start -0.299974 0.150114)
			(end 0.299974 0.150114)
			(stroke
				(width 0.1)
				(type default)
			)
			(layer "B.Fab")
		)
		(fp_line
			(start 0.299974 0.150114)
			(end 0.299974 -0.150114)
			(stroke
				(width 0.1)
				(type default)
			)
			(layer "B.Fab")
		)
		(fp_line
			(start -0.299974 -0.150114)
			(end -0.299974 0.150114)
			(stroke
				(width 0.1)
				(type default)
			)
			(layer "B.Fab")
		)
		(fp_line
			(start 0.299974 -0.150114)
			(end -0.299974 -0.150114)
			(stroke
				(width 0.1)
				(type default)
			)
			(layer "B.Fab")
		)
		(pad "1" smd rect
			(at 0.2667 0 90)
			(size 0.3048 0.381)
			(layers "B.Cu" "B.Mask" "B.Paste")
			(net "P0V8_SERDES_VDDA_PEX2")
		)
		(pad "2" smd rect
			(at -0.2667 0 90)
			(size 0.3048 0.381)
			(layers "B.Cu" "B.Mask" "B.Paste")
			(net "GND")
		)
	)
	(footprint ""
		(layer "B.Cu")
		(at 234.89412 -94.421706)
		(property "Reference" "R1006"
			(at 0 0 0)
			(layer "B.SilkS")
			(hide yes)
			(effects
				(font
					(size 1.27 1.27)
				)
				(justify mirror)
			)
		)
		(property "Value" ""
			(at 0 0 0)
			(layer "B.Fab")
			(effects
				(font
					(size 1.27 1.27)
				)
				(justify mirror)
			)
		)
		(duplicate_pad_numbers_are_jumpers no)
		(fp_line
			(start -0.7874 -0.4064)
			(end -0.7874 0.4064)
			(stroke
				(width 0.1524)
				(type default)
			)
			(layer "B.SilkS")
		)
		(fp_line
			(start -0.7874 0.4064)
			(end 0.7874 0.4064)
			(stroke
				(width 0.1524)
				(type default)
			)
			(layer "B.SilkS")
		)
		(fp_line
			(start 0.7874 -0.4064)
			(end -0.7874 -0.4064)
			(stroke
				(width 0.1524)
				(type default)
			)
			(layer "B.SilkS")
		)
		(fp_line
			(start 0.7874 0.4064)
			(end 0.7874 -0.4064)
			(stroke
				(width 0.1524)
				(type default)
			)
			(layer "B.SilkS")
		)
		(fp_line
			(start -0.67945 -0.3048)
			(end -0.67945 0.3048)
			(stroke
				(width 0.1)
				(type default)
			)
			(layer "B.Fab")
		)
		(fp_line
			(start -0.67945 0.3048)
			(end -0.120396 0.3048)
			(stroke
				(width 0.1)
				(type default)
			)
			(layer "B.Fab")
		)
		(fp_line
			(start -0.12065 -0.3048)
			(end -0.67945 -0.3048)
			(stroke
				(width 0.1)
				(type default)
			)
			(layer "B.Fab")
		)
		(fp_line
			(start -0.12065 -0.2794)
			(end -0.12065 -0.3048)
			(stroke
				(width 0.1)
				(type default)
			)
			(layer "B.Fab")
		)
		(fp_line
			(start -0.120396 0.2794)
			(end 0.12065 0.2794)
			(stroke
				(width 0.1)
				(type default)
			)
			(layer "B.Fab")
		)
		(fp_line
			(start -0.120396 0.3048)
			(end -0.120396 0.2794)
			(stroke
				(width 0.1)
				(type default)
			)
			(layer "B.Fab")
		)
		(fp_line
			(start 0.12065 -0.305054)
			(end 0.12065 -0.2794)
			(stroke
				(width 0.1)
				(type default)
			)
			(layer "B.Fab")
		)
		(fp_line
			(start 0.12065 -0.2794)
			(end -0.12065 -0.2794)
			(stroke
				(width 0.1)
				(type default)
			)
			(layer "B.Fab")
		)
		(fp_line
			(start 0.12065 0.2794)
			(end 0.12065 0.3048)
			(stroke
				(width 0.1)
				(type default)
			)
			(layer "B.Fab")
		)
		(fp_line
			(start 0.12065 0.3048)
			(end 0.67945 0.3048)
			(stroke
				(width 0.1)
				(type default)
			)
			(layer "B.Fab")
		)
		(fp_line
			(start 0.67945 -0.305054)
			(end 0.12065 -0.305054)
			(stroke
				(width 0.1)
				(type default)
			)
			(layer "B.Fab")
		)
		(fp_line
			(start 0.67945 0.3048)
			(end 0.67945 -0.305054)
			(stroke
				(width 0.1)
				(type default)
			)
			(layer "B.Fab")
		)
		(pad "1" smd circle
			(at 0.40005 0 180)
			(size 0 0)
			(layers "B.Cu" "B.Mask" "B.Paste")
			(net "P3V3_AUX")
		)
		(pad "2" smd circle
			(at -0.40005 0 180)
			(size 0 0)
			(layers "B.Cu" "B.Mask" "B.Paste")
			(net "P3V3_PEX_USB_HUB")
		)
	)
	(footprint ""
		(layer "B.Cu")
		(at 178.124866 -305.399948 -90)
		(property "Reference" "C3140"
			(at 0 0 90)
			(layer "B.SilkS")
			(hide yes)
			(effects
				(font
					(size 1.27 1.27)
				)
				(justify mirror)
			)
		)
		(property "Value" ""
			(at 0 0 90)
			(layer "B.Fab")
			(effects
				(font
					(size 1.27 1.27)
				)
				(justify mirror)
			)
		)
		(duplicate_pad_numbers_are_jumpers no)
		(fp_line
			(start -0.299974 0.150114)
			(end 0.299974 0.150114)
			(stroke
				(width 0.1)
				(type default)
			)
			(layer "B.Fab")
		)
		(fp_line
			(start 0.299974 0.150114)
			(end 0.299974 -0.150114)
			(stroke
				(width 0.1)
				(type default)
			)
			(layer "B.Fab")
		)
		(fp_line
			(start -0.299974 -0.150114)
			(end -0.299974 0.150114)
			(stroke
				(width 0.1)
				(type default)
			)
			(layer "B.Fab")
		)
		(fp_line
			(start 0.299974 -0.150114)
			(end -0.299974 -0.150114)
			(stroke
				(width 0.1)
				(type default)
			)
			(layer "B.Fab")
		)
		(pad "1" smd rect
			(at 0.2667 0 90)
			(size 0.3048 0.381)
			(layers "B.Cu" "B.Mask" "B.Paste")
			(net "P1V25_SERDES_VDDPLL_PEX1")
		)
		(pad "2" smd rect
			(at -0.2667 0 90)
			(size 0.3048 0.381)
			(layers "B.Cu" "B.Mask" "B.Paste")
			(net "GND")
		)
	)
	(footprint ""
		(layer "B.Cu")
		(at 272.318988 -294.8051 180)
		(property "Reference" "R3473"
			(at 0 0 0)
			(layer "B.SilkS")
			(hide yes)
			(effects
				(font
					(size 1.27 1.27)
				)
				(justify mirror)
			)
		)
		(property "Value" ""
			(at 0 0 0)
			(layer "B.Fab")
			(effects
				(font
					(size 1.27 1.27)
				)
				(justify mirror)
			)
		)
		(duplicate_pad_numbers_are_jumpers no)
		(fp_line
			(start 0.7874 0.4064)
			(end 0.7874 -0.4064)
			(stroke
				(width 0.1524)
				(type default)
			)
			(layer "B.SilkS")
		)
		(fp_line
			(start 0.7874 -0.4064)
			(end -0.7874 -0.4064)
			(stroke
				(width 0.1524)
				(type default)
			)
			(layer "B.SilkS")
		)
		(fp_line
			(start -0.7874 0.4064)
			(end 0.7874 0.4064)
			(stroke
				(width 0.1524)
				(type default)
			)
			(layer "B.SilkS")
		)
		(fp_line
			(start -0.7874 -0.4064)
			(end -0.7874 0.4064)
			(stroke
				(width 0.1524)
				(type default)
			)
			(layer "B.SilkS")
		)
		(fp_line
			(start 0.67945 0.3048)
			(end 0.67945 -0.305054)
			(stroke
				(width 0.1)
				(type default)
			)
			(layer "B.Fab")
		)
		(fp_line
			(start 0.67945 -0.305054)
			(end 0.12065 -0.305054)
			(stroke
				(width 0.1)
				(type default)
			)
			(layer "B.Fab")
		)
		(fp_line
			(start 0.12065 0.3048)
			(end 0.67945 0.3048)
			(stroke
				(width 0.1)
				(type default)
			)
			(layer "B.Fab")
		)
		(fp_line
			(start 0.12065 0.2794)
			(end 0.12065 0.3048)
			(stroke
				(width 0.1)
				(type default)
			)
			(layer "B.Fab")
		)
		(fp_line
			(start 0.12065 -0.2794)
			(end -0.12065 -0.2794)
			(stroke
				(width 0.1)
				(type default)
			)
			(layer "B.Fab")
		)
		(fp_line
			(start 0.12065 -0.305054)
			(end 0.12065 -0.2794)
			(stroke
				(width 0.1)
				(type default)
			)
			(layer "B.Fab")
		)
		(fp_line
			(start -0.120396 0.3048)
			(end -0.120396 0.2794)
			(stroke
				(width 0.1)
				(type default)
			)
			(layer "B.Fab")
		)
		(fp_line
			(start -0.120396 0.2794)
			(end 0.12065 0.2794)
			(stroke
				(width 0.1)
				(type default)
			)
			(layer "B.Fab")
		)
		(fp_line
			(start -0.12065 -0.2794)
			(end -0.12065 -0.3048)
			(stroke
				(width 0.1)
				(type default)
			)
			(layer "B.Fab")
		)
		(fp_line
			(start -0.12065 -0.3048)
			(end -0.67945 -0.3048)
			(stroke
				(width 0.1)
				(type default)
			)
			(layer "B.Fab")
		)
		(fp_line
			(start -0.67945 0.3048)
			(end -0.120396 0.3048)
			(stroke
				(width 0.1)
				(type default)
			)
			(layer "B.Fab")
		)
		(fp_line
			(start -0.67945 -0.3048)
			(end -0.67945 0.3048)
			(stroke
				(width 0.1)
				(type default)
			)
			(layer "B.Fab")
		)
		(pad "1" smd circle
			(at 0.40005 0)
			(size 0 0)
			(layers "B.Cu" "B.Mask" "B.Paste")
			(net "SPI_PEX2_SDIO2_R")
		)
		(pad "2" smd circle
			(at -0.40005 0)
			(size 0 0)
			(layers "B.Cu" "B.Mask" "B.Paste")
			(net "SPI_PEX2_SDIO2")
		)
	)
	(footprint ""
		(layer "B.Cu")
		(at 120.03786 -325.186294 -90)
		(property "Reference" "C4269"
			(at 0 0 90)
			(layer "B.SilkS")
			(hide yes)
			(effects
				(font
					(size 1.27 1.27)
				)
				(justify mirror)
			)
		)
		(property "Value" ""
			(at 0 0 90)
			(layer "B.Fab")
			(effects
				(font
					(size 1.27 1.27)
				)
				(justify mirror)
			)
		)
		(duplicate_pad_numbers_are_jumpers no)
		(fp_line
			(start -1.2954 0.5842)
			(end 1.2954 0.5842)
			(stroke
				(width 0.1524)
				(type default)
			)
			(layer "B.SilkS")
		)
		(fp_line
			(start 1.2954 0.5842)
			(end 1.2954 -0.5842)
			(stroke
				(width 0.1524)
				(type default)
			)
			(layer "B.SilkS")
		)
		(fp_line
			(start -1.2954 -0.5842)
			(end -1.2954 0.5842)
			(stroke
				(width 0.1524)
				(type default)
			)
			(layer "B.SilkS")
		)
		(fp_line
			(start 1.2954 -0.5842)
			(end -1.2954 -0.5842)
			(stroke
				(width 0.1524)
				(type default)
			)
			(layer "B.SilkS")
		)
		(fp_line
			(start -0.8636 0.4572)
			(end 0.8636 0.4572)
			(stroke
				(width 0.1)
				(type default)
			)
			(layer "B.Fab")
		)
		(fp_line
			(start 0.8636 0.4572)
			(end 0.8636 0.4064)
			(stroke
				(width 0.1)
				(type default)
			)
			(layer "B.Fab")
		)
		(fp_line
			(start -1.1938 0.4064)
			(end -0.8636 0.4064)
			(stroke
				(width 0.1)
				(type default)
			)
			(layer "B.Fab")
		)
		(fp_line
			(start -0.8636 0.4064)
			(end -0.8636 0.4572)
			(stroke
				(width 0.1)
				(type default)
			)
			(layer "B.Fab")
		)
		(fp_line
			(start 0.8636 0.4064)
			(end 1.1938 0.4064)
			(stroke
				(width 0.1)
				(type default)
			)
			(layer "B.Fab")
		)
		(fp_line
			(start 1.1938 0.4064)
			(end 1.1938 -0.4064)
			(stroke
				(width 0.1)
				(type default)
			)
			(layer "B.Fab")
		)
		(fp_line
			(start -1.1938 -0.4064)
			(end -1.1938 0.4064)
			(stroke
				(width 0.1)
				(type default)
			)
			(layer "B.Fab")
		)
		(fp_line
			(start -0.8636 -0.4064)
			(end -1.1938 -0.4064)
			(stroke
				(width 0.1)
				(type default)
			)
			(layer "B.Fab")
		)
		(fp_line
			(start 0.8636 -0.4064)
			(end 0.8636 -0.4572)
			(stroke
				(width 0.1)
				(type default)
			)
			(layer "B.Fab")
		)
		(fp_line
			(start 1.1938 -0.4064)
			(end 0.8636 -0.4064)
			(stroke
				(width 0.1)
				(type default)
			)
			(layer "B.Fab")
		)
		(fp_line
			(start -0.8636 -0.4572)
			(end -0.8636 -0.4064)
			(stroke
				(width 0.1)
				(type default)
			)
			(layer "B.Fab")
		)
		(fp_line
			(start 0.8636 -0.4572)
			(end -0.8636 -0.4572)
			(stroke
				(width 0.1)
				(type default)
			)
			(layer "B.Fab")
		)
		(pad "1" smd rect
			(at 0.7366 0 180)
			(size 0.7112 0.8128)
			(layers "B.Cu" "B.Mask" "B.Paste")
			(net "P0V8_SERDES_VDDA_PEX1_C7")
		)
		(pad "2" smd rect
			(at -0.7366 0 180)
			(size 0.7112 0.8128)
			(layers "B.Cu" "B.Mask" "B.Paste")
			(net "GND")
		)
	)
	(footprint ""
		(layer "B.Cu")
		(at 283.774896 -286.399732 90)
		(property "Reference" "C3320"
			(at 0 0 90)
			(layer "B.SilkS")
			(hide yes)
			(effects
				(font
					(size 1.27 1.27)
				)
				(justify mirror)
			)
		)
		(property "Value" ""
			(at 0 0 90)
			(layer "B.Fab")
			(effects
				(font
					(size 1.27 1.27)
				)
				(justify mirror)
			)
		)
		(duplicate_pad_numbers_are_jumpers no)
		(fp_line
			(start 0.299974 -0.150114)
			(end -0.299974 -0.150114)
			(stroke
				(width 0.1)
				(type default)
			)
			(layer "B.Fab")
		)
		(fp_line
			(start -0.299974 -0.150114)
			(end -0.299974 0.150114)
			(stroke
				(width 0.1)
				(type default)
			)
			(layer "B.Fab")
		)
		(fp_line
			(start 0.299974 0.150114)
			(end 0.299974 -0.150114)
			(stroke
				(width 0.1)
				(type default)
			)
			(layer "B.Fab")
		)
		(fp_line
			(start -0.299974 0.150114)
			(end 0.299974 0.150114)
			(stroke
				(width 0.1)
				(type default)
			)
			(layer "B.Fab")
		)
		(pad "1" smd rect
			(at 0.2667 0 270)
			(size 0.3048 0.381)
			(layers "B.Cu" "B.Mask" "B.Paste")
			(net "P1V25_SERDES_VDDPLL_PEX2")
		)
		(pad "2" smd rect
			(at -0.2667 0 270)
			(size 0.3048 0.381)
			(layers "B.Cu" "B.Mask" "B.Paste")
			(net "GND")
		)
	)
	(footprint ""
		(layer "B.Cu")
		(at 376.178064 -243.589302)
		(property "Reference" "C2605"
			(at 0 0 0)
			(layer "B.SilkS")
			(hide yes)
			(effects
				(font
					(size 1.27 1.27)
				)
				(justify mirror)
			)
		)
		(property "Value" ""
			(at 0 0 0)
			(layer "B.Fab")
			(effects
				(font
					(size 1.27 1.27)
				)
				(justify mirror)
			)
		)
		(duplicate_pad_numbers_are_jumpers no)
		(fp_line
			(start -0.7874 -0.4064)
			(end -0.7874 0.4064)
			(stroke
				(width 0.1524)
				(type default)
			)
			(layer "B.SilkS")
		)
		(fp_line
			(start -0.7874 0.4064)
			(end 0.7874 0.4064)
			(stroke
				(width 0.1524)
				(type default)
			)
			(layer "B.SilkS")
		)
		(fp_line
			(start 0.7874 -0.4064)
			(end -0.7874 -0.4064)
			(stroke
				(width 0.1524)
				(type default)
			)
			(layer "B.SilkS")
		)
		(fp_line
			(start 0.7874 0.4064)
			(end 0.7874 -0.4064)
			(stroke
				(width 0.1524)
				(type default)
			)
			(layer "B.SilkS")
		)
		(fp_line
			(start -0.67945 -0.3048)
			(end -0.67945 0.3048)
			(stroke
				(width 0.1)
				(type default)
			)
			(layer "B.Fab")
		)
		(fp_line
			(start -0.67945 0.3048)
			(end -0.120396 0.3048)
			(stroke
				(width 0.1)
				(type default)
			)
			(layer "B.Fab")
		)
		(fp_line
			(start -0.12065 -0.3048)
			(end -0.67945 -0.3048)
			(stroke
				(width 0.1)
				(type default)
			)
			(layer "B.Fab")
		)
		(fp_line
			(start -0.12065 -0.2794)
			(end -0.12065 -0.3048)
			(stroke
				(width 0.1)
				(type default)
			)
			(layer "B.Fab")
		)
		(fp_line
			(start -0.120396 0.2794)
			(end 0.12065 0.2794)
			(stroke
				(width 0.1)
				(type default)
			)
			(layer "B.Fab")
		)
		(fp_line
			(start -0.120396 0.3048)
			(end -0.120396 0.2794)
			(stroke
				(width 0.1)
				(type default)
			)
			(layer "B.Fab")
		)
		(fp_line
			(start 0.12065 -0.305054)
			(end 0.12065 -0.2794)
			(stroke
				(width 0.1)
				(type default)
			)
			(layer "B.Fab")
		)
		(fp_line
			(start 0.12065 -0.2794)
			(end -0.12065 -0.2794)
			(stroke
				(width 0.1)
				(type default)
			)
			(layer "B.Fab")
		)
		(fp_line
			(start 0.12065 0.2794)
			(end 0.12065 0.3048)
			(stroke
				(width 0.1)
				(type default)
			)
			(layer "B.Fab")
		)
		(fp_line
			(start 0.12065 0.3048)
			(end 0.67945 0.3048)
			(stroke
				(width 0.1)
				(type default)
			)
			(layer "B.Fab")
		)
		(fp_line
			(start 0.67945 -0.305054)
			(end 0.12065 -0.305054)
			(stroke
				(width 0.1)
				(type default)
			)
			(layer "B.Fab")
		)
		(fp_line
			(start 0.67945 0.3048)
			(end 0.67945 -0.305054)
			(stroke
				(width 0.1)
				(type default)
			)
			(layer "B.Fab")
		)
		(pad "1" smd circle
			(at 0.40005 0 180)
			(size 0 0)
			(layers "B.Cu" "B.Mask" "B.Paste")
			(net "GND")
		)
		(pad "2" smd circle
			(at -0.40005 0 180)
			(size 0 0)
			(layers "B.Cu" "B.Mask" "B.Paste")
			(net "P1V8_PEX")
		)
	)
	(footprint ""
		(layer "B.Cu")
		(at 413.670242 -296.37482)
		(property "Reference" "C1878"
			(at 0 0 0)
			(layer "B.SilkS")
			(hide yes)
			(effects
				(font
					(size 1.27 1.27)
				)
				(justify mirror)
			)
		)
		(property "Value" ""
			(at 0 0 0)
			(layer "B.Fab")
			(effects
				(font
					(size 1.27 1.27)
				)
				(justify mirror)
			)
		)
		(duplicate_pad_numbers_are_jumpers no)
		(fp_line
			(start -0.299974 -0.150114)
			(end -0.299974 0.150114)
			(stroke
				(width 0.1)
				(type default)
			)
			(layer "B.Fab")
		)
		(fp_line
			(start -0.299974 0.150114)
			(end 0.299974 0.150114)
			(stroke
				(width 0.1)
				(type default)
			)
			(layer "B.Fab")
		)
		(fp_line
			(start 0.299974 -0.150114)
			(end -0.299974 -0.150114)
			(stroke
				(width 0.1)
				(type default)
			)
			(layer "B.Fab")
		)
		(fp_line
			(start 0.299974 0.150114)
			(end 0.299974 -0.150114)
			(stroke
				(width 0.1)
				(type default)
			)
			(layer "B.Fab")
		)
		(pad "1" smd rect
			(at 0.2667 0 180)
			(size 0.3048 0.381)
			(layers "B.Cu" "B.Mask" "B.Paste")
			(net "P0V8_PEX3")
		)
		(pad "2" smd rect
			(at -0.2667 0 180)
			(size 0.3048 0.381)
			(layers "B.Cu" "B.Mask" "B.Paste")
			(net "GND")
		)
	)
	(footprint ""
		(layer "B.Cu")
		(at 102.900734 -237.306612 -90)
		(property "Reference" "PC1004"
			(at 0 0 90)
			(layer "B.SilkS")
			(hide yes)
			(effects
				(font
					(size 1.27 1.27)
				)
				(justify mirror)
			)
		)
		(property "Value" ""
			(at 0 0 90)
			(layer "B.Fab")
			(effects
				(font
					(size 1.27 1.27)
				)
				(justify mirror)
			)
		)
		(duplicate_pad_numbers_are_jumpers no)
		(fp_line
			(start -1.524 0.762)
			(end 1.524 0.762)
			(stroke
				(width 0.1524)
				(type default)
			)
			(layer "B.SilkS")
		)
		(fp_line
			(start 1.524 0.762)
			(end 1.524 -0.762)
			(stroke
				(width 0.1524)
				(type default)
			)
			(layer "B.SilkS")
		)
		(fp_line
			(start -1.524 -0.762)
			(end -1.524 0.762)
			(stroke
				(width 0.1524)
				(type default)
			)
			(layer "B.SilkS")
		)
		(fp_line
			(start 1.524 -0.762)
			(end -1.524 -0.762)
			(stroke
				(width 0.1524)
				(type default)
			)
			(layer "B.SilkS")
		)
		(fp_line
			(start -1.1049 0.724916)
			(end -1.1049 -0.724916)
			(stroke
				(width 0.1)
				(type default)
			)
			(layer "B.Fab")
		)
		(fp_line
			(start 1.1049 0.724916)
			(end -1.1049 0.724916)
			(stroke
				(width 0.1)
				(type default)
			)
			(layer "B.Fab")
		)
		(fp_line
			(start -1.1049 -0.724916)
			(end 1.1049 -0.724916)
			(stroke
				(width 0.1)
				(type default)
			)
			(layer "B.Fab")
		)
		(fp_line
			(start 1.1049 -0.724916)
			(end 1.1049 0.724916)
			(stroke
				(width 0.1)
				(type default)
			)
			(layer "B.Fab")
		)
		(pad "1" smd rect
			(at 0.889 0 270)
			(size 1.016 1.27)
			(layers "B.Cu" "B.Mask" "B.Paste")
			(net "P1V8_PEX_R")
		)
		(pad "2" smd rect
			(at -0.889 0 270)
			(size 1.016 1.27)
			(layers "B.Cu" "B.Mask" "B.Paste")
			(net "GND")
		)
	)
	(footprint ""
		(layer "B.Cu")
		(at 16.251174 -308.261766 -90)
		(property "Reference" "R841"
			(at 0 0 90)
			(layer "B.SilkS")
			(hide yes)
			(effects
				(font
					(size 1.27 1.27)
				)
				(justify mirror)
			)
		)
		(property "Value" ""
			(at 0 0 90)
			(layer "B.Fab")
			(effects
				(font
					(size 1.27 1.27)
				)
				(justify mirror)
			)
		)
		(duplicate_pad_numbers_are_jumpers no)
		(fp_line
			(start -0.7874 0.4064)
			(end 0.7874 0.4064)
			(stroke
				(width 0.1524)
				(type default)
			)
			(layer "B.SilkS")
		)
		(fp_line
			(start 0.7874 0.4064)
			(end 0.7874 -0.4064)
			(stroke
				(width 0.1524)
				(type default)
			)
			(layer "B.SilkS")
		)
		(fp_line
			(start -0.7874 -0.4064)
			(end -0.7874 0.4064)
			(stroke
				(width 0.1524)
				(type default)
			)
			(layer "B.SilkS")
		)
		(fp_line
			(start 0.7874 -0.4064)
			(end -0.7874 -0.4064)
			(stroke
				(width 0.1524)
				(type default)
			)
			(layer "B.SilkS")
		)
		(fp_line
			(start -0.67945 0.3048)
			(end -0.120396 0.3048)
			(stroke
				(width 0.1)
				(type default)
			)
			(layer "B.Fab")
		)
		(fp_line
			(start -0.120396 0.3048)
			(end -0.120396 0.2794)
			(stroke
				(width 0.1)
				(type default)
			)
			(layer "B.Fab")
		)
		(fp_line
			(start 0.12065 0.3048)
			(end 0.67945 0.3048)
			(stroke
				(width 0.1)
				(type default)
			)
			(layer "B.Fab")
		)
		(fp_line
			(start 0.67945 0.3048)
			(end 0.67945 -0.305054)
			(stroke
				(width 0.1)
				(type default)
			)
			(layer "B.Fab")
		)
		(fp_line
			(start -0.120396 0.2794)
			(end 0.12065 0.2794)
			(stroke
				(width 0.1)
				(type default)
			)
			(layer "B.Fab")
		)
		(fp_line
			(start 0.12065 0.2794)
			(end 0.12065 0.3048)
			(stroke
				(width 0.1)
				(type default)
			)
			(layer "B.Fab")
		)
		(fp_line
			(start -0.12065 -0.2794)
			(end -0.12065 -0.3048)
			(stroke
				(width 0.1)
				(type default)
			)
			(layer "B.Fab")
		)
		(fp_line
			(start 0.12065 -0.2794)
			(end -0.12065 -0.2794)
			(stroke
				(width 0.1)
				(type default)
			)
			(layer "B.Fab")
		)
		(fp_line
			(start -0.67945 -0.3048)
			(end -0.67945 0.3048)
			(stroke
				(width 0.1)
				(type default)
			)
			(layer "B.Fab")
		)
		(fp_line
			(start -0.12065 -0.3048)
			(end -0.67945 -0.3048)
			(stroke
				(width 0.1)
				(type default)
			)
			(layer "B.Fab")
		)
		(fp_line
			(start 0.12065 -0.305054)
			(end 0.12065 -0.2794)
			(stroke
				(width 0.1)
				(type default)
			)
			(layer "B.Fab")
		)
		(fp_line
			(start 0.67945 -0.305054)
			(end 0.12065 -0.305054)
			(stroke
				(width 0.1)
				(type default)
			)
			(layer "B.Fab")
		)
		(pad "1" smd circle
			(at 0.40005 0 90)
			(size 0 0)
			(layers "B.Cu" "B.Mask" "B.Paste")
			(net "P1V25_PEX0_VCC")
		)
		(pad "2" smd circle
			(at -0.40005 0 90)
			(size 0 0)
			(layers "B.Cu" "B.Mask" "B.Paste")
			(net "PWRGD_P1V25_PEX0")
		)
	)
	(footprint ""
		(layer "B.Cu")
		(at 112.025176 -325.153528 -90)
		(property "Reference" "C4204"
			(at 0 0 90)
			(layer "B.SilkS")
			(hide yes)
			(effects
				(font
					(size 1.27 1.27)
				)
				(justify mirror)
			)
		)
		(property "Value" ""
			(at 0 0 90)
			(layer "B.Fab")
			(effects
				(font
					(size 1.27 1.27)
				)
				(justify mirror)
			)
		)
		(duplicate_pad_numbers_are_jumpers no)
		(fp_line
			(start -1.2954 0.5842)
			(end 1.2954 0.5842)
			(stroke
				(width 0.1524)
				(type default)
			)
			(layer "B.SilkS")
		)
		(fp_line
			(start 1.2954 0.5842)
			(end 1.2954 -0.5842)
			(stroke
				(width 0.1524)
				(type default)
			)
			(layer "B.SilkS")
		)
		(fp_line
			(start -1.2954 -0.5842)
			(end -1.2954 0.5842)
			(stroke
				(width 0.1524)
				(type default)
			)
			(layer "B.SilkS")
		)
		(fp_line
			(start 1.2954 -0.5842)
			(end -1.2954 -0.5842)
			(stroke
				(width 0.1524)
				(type default)
			)
			(layer "B.SilkS")
		)
		(fp_line
			(start -0.8636 0.4572)
			(end 0.8636 0.4572)
			(stroke
				(width 0.1)
				(type default)
			)
			(layer "B.Fab")
		)
		(fp_line
			(start 0.8636 0.4572)
			(end 0.8636 0.4064)
			(stroke
				(width 0.1)
				(type default)
			)
			(layer "B.Fab")
		)
		(fp_line
			(start -1.1938 0.4064)
			(end -0.8636 0.4064)
			(stroke
				(width 0.1)
				(type default)
			)
			(layer "B.Fab")
		)
		(fp_line
			(start -0.8636 0.4064)
			(end -0.8636 0.4572)
			(stroke
				(width 0.1)
				(type default)
			)
			(layer "B.Fab")
		)
		(fp_line
			(start 0.8636 0.4064)
			(end 1.1938 0.4064)
			(stroke
				(width 0.1)
				(type default)
			)
			(layer "B.Fab")
		)
		(fp_line
			(start 1.1938 0.4064)
			(end 1.1938 -0.4064)
			(stroke
				(width 0.1)
				(type default)
			)
			(layer "B.Fab")
		)
		(fp_line
			(start -1.1938 -0.4064)
			(end -1.1938 0.4064)
			(stroke
				(width 0.1)
				(type default)
			)
			(layer "B.Fab")
		)
		(fp_line
			(start -0.8636 -0.4064)
			(end -1.1938 -0.4064)
			(stroke
				(width 0.1)
				(type default)
			)
			(layer "B.Fab")
		)
		(fp_line
			(start 0.8636 -0.4064)
			(end 0.8636 -0.4572)
			(stroke
				(width 0.1)
				(type default)
			)
			(layer "B.Fab")
		)
		(fp_line
			(start 1.1938 -0.4064)
			(end 0.8636 -0.4064)
			(stroke
				(width 0.1)
				(type default)
			)
			(layer "B.Fab")
		)
		(fp_line
			(start -0.8636 -0.4572)
			(end -0.8636 -0.4064)
			(stroke
				(width 0.1)
				(type default)
			)
			(layer "B.Fab")
		)
		(fp_line
			(start 0.8636 -0.4572)
			(end -0.8636 -0.4572)
			(stroke
				(width 0.1)
				(type default)
			)
			(layer "B.Fab")
		)
		(pad "1" smd rect
			(at 0.7366 0 180)
			(size 0.7112 0.8128)
			(layers "B.Cu" "B.Mask" "B.Paste")
			(net "P0V8_SERDES_VDDA_PEX0_C2")
		)
		(pad "2" smd rect
			(at -0.7366 0 180)
			(size 0.7112 0.8128)
			(layers "B.Cu" "B.Mask" "B.Paste")
			(net "GND")
		)
	)
	(footprint ""
		(layer "B.Cu")
		(at 407.460704 -305.557936 -90)
		(property "Reference" "C3466"
			(at 0 0 90)
			(layer "B.SilkS")
			(hide yes)
			(effects
				(font
					(size 1.27 1.27)
				)
				(justify mirror)
			)
		)
		(property "Value" ""
			(at 0 0 90)
			(layer "B.Fab")
			(effects
				(font
					(size 1.27 1.27)
				)
				(justify mirror)
			)
		)
		(duplicate_pad_numbers_are_jumpers no)
		(fp_line
			(start -1.2954 0.5842)
			(end 1.2954 0.5842)
			(stroke
				(width 0.1524)
				(type default)
			)
			(layer "B.SilkS")
		)
		(fp_line
			(start 1.2954 0.5842)
			(end 1.2954 -0.5842)
			(stroke
				(width 0.1524)
				(type default)
			)
			(layer "B.SilkS")
		)
		(fp_line
			(start -1.2954 -0.5842)
			(end -1.2954 0.5842)
			(stroke
				(width 0.1524)
				(type default)
			)
			(layer "B.SilkS")
		)
		(fp_line
			(start 1.2954 -0.5842)
			(end -1.2954 -0.5842)
			(stroke
				(width 0.1524)
				(type default)
			)
			(layer "B.SilkS")
		)
		(fp_line
			(start -0.8636 0.4572)
			(end 0.8636 0.4572)
			(stroke
				(width 0.1)
				(type default)
			)
			(layer "B.Fab")
		)
		(fp_line
			(start 0.8636 0.4572)
			(end 0.8636 0.4064)
			(stroke
				(width 0.1)
				(type default)
			)
			(layer "B.Fab")
		)
		(fp_line
			(start -1.1938 0.4064)
			(end -0.8636 0.4064)
			(stroke
				(width 0.1)
				(type default)
			)
			(layer "B.Fab")
		)
		(fp_line
			(start -0.8636 0.4064)
			(end -0.8636 0.4572)
			(stroke
				(width 0.1)
				(type default)
			)
			(layer "B.Fab")
		)
		(fp_line
			(start 0.8636 0.4064)
			(end 1.1938 0.4064)
			(stroke
				(width 0.1)
				(type default)
			)
			(layer "B.Fab")
		)
		(fp_line
			(start 1.1938 0.4064)
			(end 1.1938 -0.4064)
			(stroke
				(width 0.1)
				(type default)
			)
			(layer "B.Fab")
		)
		(fp_line
			(start -1.1938 -0.4064)
			(end -1.1938 0.4064)
			(stroke
				(width 0.1)
				(type default)
			)
			(layer "B.Fab")
		)
		(fp_line
			(start -0.8636 -0.4064)
			(end -1.1938 -0.4064)
			(stroke
				(width 0.1)
				(type default)
			)
			(layer "B.Fab")
		)
		(fp_line
			(start 0.8636 -0.4064)
			(end 0.8636 -0.4572)
			(stroke
				(width 0.1)
				(type default)
			)
			(layer "B.Fab")
		)
		(fp_line
			(start 1.1938 -0.4064)
			(end 0.8636 -0.4064)
			(stroke
				(width 0.1)
				(type default)
			)
			(layer "B.Fab")
		)
		(fp_line
			(start -0.8636 -0.4572)
			(end -0.8636 -0.4064)
			(stroke
				(width 0.1)
				(type default)
			)
			(layer "B.Fab")
		)
		(fp_line
			(start 0.8636 -0.4572)
			(end -0.8636 -0.4572)
			(stroke
				(width 0.1)
				(type default)
			)
			(layer "B.Fab")
		)
		(pad "1" smd rect
			(at 0.7366 0 180)
			(size 0.7112 0.8128)
			(layers "B.Cu" "B.Mask" "B.Paste")
			(net "P1V25_SERDES_VDDPLL_PEX3")
		)
		(pad "2" smd rect
			(at -0.7366 0 180)
			(size 0.7112 0.8128)
			(layers "B.Cu" "B.Mask" "B.Paste")
			(net "GND")
		)
	)
	(footprint ""
		(layer "B.Cu")
		(at 281.874722 -293.99992 -90)
		(property "Reference" "C1622"
			(at 0 0 90)
			(layer "B.SilkS")
			(hide yes)
			(effects
				(font
					(size 1.27 1.27)
				)
				(justify mirror)
			)
		)
		(property "Value" ""
			(at 0 0 90)
			(layer "B.Fab")
			(effects
				(font
					(size 1.27 1.27)
				)
				(justify mirror)
			)
		)
		(duplicate_pad_numbers_are_jumpers no)
		(fp_line
			(start -0.299974 0.150114)
			(end 0.299974 0.150114)
			(stroke
				(width 0.1)
				(type default)
			)
			(layer "B.Fab")
		)
		(fp_line
			(start 0.299974 0.150114)
			(end 0.299974 -0.150114)
			(stroke
				(width 0.1)
				(type default)
			)
			(layer "B.Fab")
		)
		(fp_line
			(start -0.299974 -0.150114)
			(end -0.299974 0.150114)
			(stroke
				(width 0.1)
				(type default)
			)
			(layer "B.Fab")
		)
		(fp_line
			(start 0.299974 -0.150114)
			(end -0.299974 -0.150114)
			(stroke
				(width 0.1)
				(type default)
			)
			(layer "B.Fab")
		)
		(pad "1" smd rect
			(at 0.2667 0 90)
			(size 0.3048 0.381)
			(layers "B.Cu" "B.Mask" "B.Paste")
			(net "P0V8_PEX2")
		)
		(pad "2" smd rect
			(at -0.2667 0 90)
			(size 0.3048 0.381)
			(layers "B.Cu" "B.Mask" "B.Paste")
			(net "GND")
		)
	)
	(footprint ""
		(layer "B.Cu")
		(at 339.693758 -221.98711 -90)
		(property "Reference" "C2089"
			(at 0 0 90)
			(layer "B.SilkS")
			(hide yes)
			(effects
				(font
					(size 1.27 1.27)
				)
				(justify mirror)
			)
		)
		(property "Value" ""
			(at 0 0 90)
			(layer "B.Fab")
			(effects
				(font
					(size 1.27 1.27)
				)
				(justify mirror)
			)
		)
		(duplicate_pad_numbers_are_jumpers no)
		(fp_line
			(start -0.69215 0.2921)
			(end 0.69215 0.2921)
			(stroke
				(width 0.1524)
				(type default)
			)
			(layer "B.SilkS")
		)
		(fp_line
			(start 0.69215 0.2921)
			(end 0.69215 -0.2921)
			(stroke
				(width 0.1524)
				(type default)
			)
			(layer "B.SilkS")
		)
		(fp_line
			(start -0.69215 -0.2921)
			(end -0.69215 0.2921)
			(stroke
				(width 0.1524)
				(type default)
			)
			(layer "B.SilkS")
		)
		(fp_line
			(start 0.69215 -0.2921)
			(end -0.69215 -0.2921)
			(stroke
				(width 0.1524)
				(type default)
			)
			(layer "B.SilkS")
		)
		(fp_line
			(start -0.51435 0.2794)
			(end 0.51435 0.2794)
			(stroke
				(width 0.1)
				(type default)
			)
			(layer "B.Fab")
		)
		(fp_line
			(start 0.51435 0.2794)
			(end 0.51435 -0.2794)
			(stroke
				(width 0.1)
				(type default)
			)
			(layer "B.Fab")
		)
		(fp_line
			(start -0.51435 -0.2794)
			(end -0.51435 0.2794)
			(stroke
				(width 0.1)
				(type default)
			)
			(layer "B.Fab")
		)
		(fp_line
			(start 0.51435 -0.2794)
			(end -0.51435 -0.2794)
			(stroke
				(width 0.1)
				(type default)
			)
			(layer "B.Fab")
		)
		(pad "1" smd circle
			(at 0.40005 0 90)
			(size 0 0)
			(layers "B.Cu" "B.Mask" "B.Paste")
			(net "P3V3_FPGA_VCCIO5")
		)
		(pad "2" smd circle
			(at -0.40005 0 90)
			(size 0 0)
			(layers "B.Cu" "B.Mask" "B.Paste")
			(net "GND")
		)
		(zone
			(layer "B.Cu")
			(hatch none 0.5)
			(connect_pads
				(clearance 0)
			)
			(min_thickness 0.25)
			(keepout
				(tracks not_allowed)
				(vias allowed)
				(pads allowed)
				(copperpour not_allowed)
				(footprints allowed)
			)
			(placement
				(enabled no)
				(sheetname "")
			)
			(fill
				(thermal_gap 0.5)
				(thermal_bridge_width 0.5)
				(island_removal_mode 0)
			)
			(polygon
				(pts
					(xy 339.606128 -221.79661) (xy 339.547962 -221.88805) (xy 339.547962 -222.08744) (xy 339.606128 -222.17761)
					(xy 339.781388 -222.17761) (xy 339.839808 -222.08744) (xy 339.839808 -221.88805) (xy 339.781642 -221.79661)
				)
			)
		)
	)
	(footprint ""
		(layer "B.Cu")
		(at 123.614434 -303.649634 -90)
		(property "Reference" "PC121"
			(at 0 0 90)
			(layer "B.SilkS")
			(hide yes)
			(effects
				(font
					(size 1.27 1.27)
				)
				(justify mirror)
			)
		)
		(property "Value" ""
			(at 0 0 90)
			(layer "B.Fab")
			(effects
				(font
					(size 1.27 1.27)
				)
				(justify mirror)
			)
		)
		(duplicate_pad_numbers_are_jumpers no)
		(fp_line
			(start -1.524 0.762)
			(end 1.524 0.762)
			(stroke
				(width 0.1524)
				(type default)
			)
			(layer "B.SilkS")
		)
		(fp_line
			(start 1.524 0.762)
			(end 1.524 -0.762)
			(stroke
				(width 0.1524)
				(type default)
			)
			(layer "B.SilkS")
		)
		(fp_line
			(start -1.524 -0.762)
			(end -1.524 0.762)
			(stroke
				(width 0.1524)
				(type default)
			)
			(layer "B.SilkS")
		)
		(fp_line
			(start 1.524 -0.762)
			(end -1.524 -0.762)
			(stroke
				(width 0.1524)
				(type default)
			)
			(layer "B.SilkS")
		)
		(fp_line
			(start -1.1049 0.724916)
			(end -1.1049 -0.724916)
			(stroke
				(width 0.1)
				(type default)
			)
			(layer "B.Fab")
		)
		(fp_line
			(start 1.1049 0.724916)
			(end -1.1049 0.724916)
			(stroke
				(width 0.1)
				(type default)
			)
			(layer "B.Fab")
		)
		(fp_line
			(start -1.1049 -0.724916)
			(end 1.1049 -0.724916)
			(stroke
				(width 0.1)
				(type default)
			)
			(layer "B.Fab")
		)
		(fp_line
			(start 1.1049 -0.724916)
			(end 1.1049 0.724916)
			(stroke
				(width 0.1)
				(type default)
			)
			(layer "B.Fab")
		)
		(pad "1" smd rect
			(at 0.889 0 270)
			(size 1.016 1.27)
			(layers "B.Cu" "B.Mask" "B.Paste")
			(net "P0V8_PEX1")
		)
		(pad "2" smd rect
			(at -0.889 0 270)
			(size 1.016 1.27)
			(layers "B.Cu" "B.Mask" "B.Paste")
			(net "GND")
		)
	)
	(footprint ""
		(layer "B.Cu")
		(at 57.430162 -295.221914)
		(property "Reference" "C1101"
			(at 0 0 0)
			(layer "B.SilkS")
			(hide yes)
			(effects
				(font
					(size 1.27 1.27)
				)
				(justify mirror)
			)
		)
		(property "Value" ""
			(at 0 0 0)
			(layer "B.Fab")
			(effects
				(font
					(size 1.27 1.27)
				)
				(justify mirror)
			)
		)
		(duplicate_pad_numbers_are_jumpers no)
		(fp_line
			(start -1.2954 -0.5842)
			(end -1.2954 0.5842)
			(stroke
				(width 0.1524)
				(type default)
			)
			(layer "B.SilkS")
		)
		(fp_line
			(start -1.2954 0.5842)
			(end 1.2954 0.5842)
			(stroke
				(width 0.1524)
				(type default)
			)
			(layer "B.SilkS")
		)
		(fp_line
			(start 1.2954 -0.5842)
			(end -1.2954 -0.5842)
			(stroke
				(width 0.1524)
				(type default)
			)
			(layer "B.SilkS")
		)
		(fp_line
			(start 1.2954 0.5842)
			(end 1.2954 -0.5842)
			(stroke
				(width 0.1524)
				(type default)
			)
			(layer "B.SilkS")
		)
		(fp_line
			(start -1.1938 -0.4064)
			(end -1.1938 0.4064)
			(stroke
				(width 0.1)
				(type default)
			)
			(layer "B.Fab")
		)
		(fp_line
			(start -1.1938 0.4064)
			(end -0.8636 0.4064)
			(stroke
				(width 0.1)
				(type default)
			)
			(layer "B.Fab")
		)
		(fp_line
			(start -0.8636 -0.4572)
			(end -0.8636 -0.4064)
			(stroke
				(width 0.1)
				(type default)
			)
			(layer "B.Fab")
		)
		(fp_line
			(start -0.8636 -0.4064)
			(end -1.1938 -0.4064)
			(stroke
				(width 0.1)
				(type default)
			)
			(layer "B.Fab")
		)
		(fp_line
			(start -0.8636 0.4064)
			(end -0.8636 0.4572)
			(stroke
				(width 0.1)
				(type default)
			)
			(layer "B.Fab")
		)
		(fp_line
			(start -0.8636 0.4572)
			(end 0.8636 0.4572)
			(stroke
				(width 0.1)
				(type default)
			)
			(layer "B.Fab")
		)
		(fp_line
			(start 0.8636 -0.4572)
			(end -0.8636 -0.4572)
			(stroke
				(width 0.1)
				(type default)
			)
			(layer "B.Fab")
		)
		(fp_line
			(start 0.8636 -0.4064)
			(end 0.8636 -0.4572)
			(stroke
				(width 0.1)
				(type default)
			)
			(layer "B.Fab")
		)
		(fp_line
			(start 0.8636 0.4064)
			(end 1.1938 0.4064)
			(stroke
				(width 0.1)
				(type default)
			)
			(layer "B.Fab")
		)
		(fp_line
			(start 0.8636 0.4572)
			(end 0.8636 0.4064)
			(stroke
				(width 0.1)
				(type default)
			)
			(layer "B.Fab")
		)
		(fp_line
			(start 1.1938 -0.4064)
			(end 0.8636 -0.4064)
			(stroke
				(width 0.1)
				(type default)
			)
			(layer "B.Fab")
		)
		(fp_line
			(start 1.1938 0.4064)
			(end 1.1938 -0.4064)
			(stroke
				(width 0.1)
				(type default)
			)
			(layer "B.Fab")
		)
		(pad "1" smd rect
			(at 0.7366 0 270)
			(size 0.7112 0.8128)
			(layers "B.Cu" "B.Mask" "B.Paste")
			(net "P0V8_PEX0")
		)
		(pad "2" smd rect
			(at -0.7366 0 270)
			(size 0.7112 0.8128)
			(layers "B.Cu" "B.Mask" "B.Paste")
			(net "GND")
		)
	)
	(footprint ""
		(layer "B.Cu")
		(at 284.249876 -301.599854 -90)
		(property "Reference" "C1696"
			(at 0 0 90)
			(layer "B.SilkS")
			(hide yes)
			(effects
				(font
					(size 1.27 1.27)
				)
				(justify mirror)
			)
		)
		(property "Value" ""
			(at 0 0 90)
			(layer "B.Fab")
			(effects
				(font
					(size 1.27 1.27)
				)
				(justify mirror)
			)
		)
		(duplicate_pad_numbers_are_jumpers no)
		(fp_line
			(start -0.299974 0.150114)
			(end 0.299974 0.150114)
			(stroke
				(width 0.1)
				(type default)
			)
			(layer "B.Fab")
		)
		(fp_line
			(start 0.299974 0.150114)
			(end 0.299974 -0.150114)
			(stroke
				(width 0.1)
				(type default)
			)
			(layer "B.Fab")
		)
		(fp_line
			(start -0.299974 -0.150114)
			(end -0.299974 0.150114)
			(stroke
				(width 0.1)
				(type default)
			)
			(layer "B.Fab")
		)
		(fp_line
			(start 0.299974 -0.150114)
			(end -0.299974 -0.150114)
			(stroke
				(width 0.1)
				(type default)
			)
			(layer "B.Fab")
		)
		(pad "1" smd rect
			(at 0.2667 0 90)
			(size 0.3048 0.381)
			(layers "B.Cu" "B.Mask" "B.Paste")
			(net "P0V8_SERDES_VDDA_PEX2")
		)
		(pad "2" smd rect
			(at -0.2667 0 90)
			(size 0.3048 0.381)
			(layers "B.Cu" "B.Mask" "B.Paste")
			(net "GND")
		)
	)
	(footprint ""
		(layer "B.Cu")
		(at 57.749948 -290.199826 90)
		(property "Reference" "C1235"
			(at 0 0 90)
			(layer "B.SilkS")
			(hide yes)
			(effects
				(font
					(size 1.27 1.27)
				)
				(justify mirror)
			)
		)
		(property "Value" ""
			(at 0 0 90)
			(layer "B.Fab")
			(effects
				(font
					(size 1.27 1.27)
				)
				(justify mirror)
			)
		)
		(duplicate_pad_numbers_are_jumpers no)
		(fp_line
			(start 0.299974 -0.150114)
			(end -0.299974 -0.150114)
			(stroke
				(width 0.1)
				(type default)
			)
			(layer "B.Fab")
		)
		(fp_line
			(start -0.299974 -0.150114)
			(end -0.299974 0.150114)
			(stroke
				(width 0.1)
				(type default)
			)
			(layer "B.Fab")
		)
		(fp_line
			(start 0.299974 0.150114)
			(end 0.299974 -0.150114)
			(stroke
				(width 0.1)
				(type default)
			)
			(layer "B.Fab")
		)
		(fp_line
			(start -0.299974 0.150114)
			(end 0.299974 0.150114)
			(stroke
				(width 0.1)
				(type default)
			)
			(layer "B.Fab")
		)
		(pad "1" smd rect
			(at 0.2667 0 270)
			(size 0.3048 0.381)
			(layers "B.Cu" "B.Mask" "B.Paste")
			(net "P0V8_SERDES_VDDA_PEX0")
		)
		(pad "2" smd rect
			(at -0.2667 0 270)
			(size 0.3048 0.381)
			(layers "B.Cu" "B.Mask" "B.Paste")
			(net "GND")
		)
	)
	(footprint ""
		(layer "B.Cu")
		(at 223.533716 -193.759836 90)
		(property "Reference" "R468"
			(at 0 0 90)
			(layer "B.SilkS")
			(hide yes)
			(effects
				(font
					(size 1.27 1.27)
				)
				(justify mirror)
			)
		)
		(property "Value" ""
			(at 0 0 90)
			(layer "B.Fab")
			(effects
				(font
					(size 1.27 1.27)
				)
				(justify mirror)
			)
		)
		(duplicate_pad_numbers_are_jumpers no)
		(fp_line
			(start 0.7874 -0.4064)
			(end -0.7874 -0.4064)
			(stroke
				(width 0.1524)
				(type default)
			)
			(layer "B.SilkS")
		)
		(fp_line
			(start -0.7874 -0.4064)
			(end -0.7874 0.4064)
			(stroke
				(width 0.1524)
				(type default)
			)
			(layer "B.SilkS")
		)
		(fp_line
			(start 0.7874 0.4064)
			(end 0.7874 -0.4064)
			(stroke
				(width 0.1524)
				(type default)
			)
			(layer "B.SilkS")
		)
		(fp_line
			(start -0.7874 0.4064)
			(end 0.7874 0.4064)
			(stroke
				(width 0.1524)
				(type default)
			)
			(layer "B.SilkS")
		)
		(fp_line
			(start 0.67945 -0.305054)
			(end 0.12065 -0.305054)
			(stroke
				(width 0.1)
				(type default)
			)
			(layer "B.Fab")
		)
		(fp_line
			(start 0.12065 -0.305054)
			(end 0.12065 -0.2794)
			(stroke
				(width 0.1)
				(type default)
			)
			(layer "B.Fab")
		)
		(fp_line
			(start -0.12065 -0.3048)
			(end -0.67945 -0.3048)
			(stroke
				(width 0.1)
				(type default)
			)
			(layer "B.Fab")
		)
		(fp_line
			(start -0.67945 -0.3048)
			(end -0.67945 0.3048)
			(stroke
				(width 0.1)
				(type default)
			)
			(layer "B.Fab")
		)
		(fp_line
			(start 0.12065 -0.2794)
			(end -0.12065 -0.2794)
			(stroke
				(width 0.1)
				(type default)
			)
			(layer "B.Fab")
		)
		(fp_line
			(start -0.12065 -0.2794)
			(end -0.12065 -0.3048)
			(stroke
				(width 0.1)
				(type default)
			)
			(layer "B.Fab")
		)
		(fp_line
			(start 0.12065 0.2794)
			(end 0.12065 0.3048)
			(stroke
				(width 0.1)
				(type default)
			)
			(layer "B.Fab")
		)
		(fp_line
			(start -0.120396 0.2794)
			(end 0.12065 0.2794)
			(stroke
				(width 0.1)
				(type default)
			)
			(layer "B.Fab")
		)
		(fp_line
			(start 0.67945 0.3048)
			(end 0.67945 -0.305054)
			(stroke
				(width 0.1)
				(type default)
			)
			(layer "B.Fab")
		)
		(fp_line
			(start 0.12065 0.3048)
			(end 0.67945 0.3048)
			(stroke
				(width 0.1)
				(type default)
			)
			(layer "B.Fab")
		)
		(fp_line
			(start -0.120396 0.3048)
			(end -0.120396 0.2794)
			(stroke
				(width 0.1)
				(type default)
			)
			(layer "B.Fab")
		)
		(fp_line
			(start -0.67945 0.3048)
			(end -0.120396 0.3048)
			(stroke
				(width 0.1)
				(type default)
			)
			(layer "B.Fab")
		)
		(pad "1" smd circle
			(at 0.40005 0 270)
			(size 0 0)
			(layers "B.Cu" "B.Mask" "B.Paste")
			(net "SPI_BIC1_MISO_R1")
		)
		(pad "2" smd circle
			(at -0.40005 0 270)
			(size 0 0)
			(layers "B.Cu" "B.Mask" "B.Paste")
			(net "SPI_BIC1_MISO_R2")
		)
	)
	(footprint ""
		(layer "B.Cu")
		(at 286.624776 -297.79976 -90)
		(property "Reference" "C1663"
			(at 0 0 90)
			(layer "B.SilkS")
			(hide yes)
			(effects
				(font
					(size 1.27 1.27)
				)
				(justify mirror)
			)
		)
		(property "Value" ""
			(at 0 0 90)
			(layer "B.Fab")
			(effects
				(font
					(size 1.27 1.27)
				)
				(justify mirror)
			)
		)
		(duplicate_pad_numbers_are_jumpers no)
		(fp_line
			(start -0.299974 0.150114)
			(end 0.299974 0.150114)
			(stroke
				(width 0.1)
				(type default)
			)
			(layer "B.Fab")
		)
		(fp_line
			(start 0.299974 0.150114)
			(end 0.299974 -0.150114)
			(stroke
				(width 0.1)
				(type default)
			)
			(layer "B.Fab")
		)
		(fp_line
			(start -0.299974 -0.150114)
			(end -0.299974 0.150114)
			(stroke
				(width 0.1)
				(type default)
			)
			(layer "B.Fab")
		)
		(fp_line
			(start 0.299974 -0.150114)
			(end -0.299974 -0.150114)
			(stroke
				(width 0.1)
				(type default)
			)
			(layer "B.Fab")
		)
		(pad "1" smd rect
			(at 0.2667 0 90)
			(size 0.3048 0.381)
			(layers "B.Cu" "B.Mask" "B.Paste")
			(net "P0V8_PEX2")
		)
		(pad "2" smd rect
			(at -0.2667 0 90)
			(size 0.3048 0.381)
			(layers "B.Cu" "B.Mask" "B.Paste")
			(net "GND")
		)
	)
	(footprint ""
		(layer "B.Cu")
		(at 332.109826 -82.441034 -90)
		(property "Reference" "L14"
			(at 0 0 90)
			(layer "B.SilkS")
			(hide yes)
			(effects
				(font
					(size 1.27 1.27)
				)
				(justify mirror)
			)
		)
		(property "Value" ""
			(at 0 0 90)
			(layer "B.Fab")
			(effects
				(font
					(size 1.27 1.27)
				)
				(justify mirror)
			)
		)
		(duplicate_pad_numbers_are_jumpers no)
		(fp_line
			(start -1.27 0.5842)
			(end 1.27 0.5842)
			(stroke
				(width 0.1524)
				(type default)
			)
			(layer "B.SilkS")
		)
		(fp_line
			(start -1.27 0.5842)
			(end -1.27 -0.5842)
			(stroke
				(width 0.1524)
				(type default)
			)
			(layer "B.SilkS")
		)
		(fp_line
			(start 1.27 0.5842)
			(end 1.27 -0.5842)
			(stroke
				(width 0.1524)
				(type default)
			)
			(layer "B.SilkS")
		)
		(fp_line
			(start 1.27 -0.5588)
			(end 1.27 -0.5842)
			(stroke
				(width 0.1524)
				(type default)
			)
			(layer "B.SilkS")
		)
		(fp_line
			(start 1.27 -0.5842)
			(end -1.27 -0.5842)
			(stroke
				(width 0.1524)
				(type default)
			)
			(layer "B.SilkS")
		)
		(fp_line
			(start -0.9144 0.508)
			(end 0.9144 0.508)
			(stroke
				(width 0.1)
				(type default)
			)
			(layer "B.Fab")
		)
		(fp_line
			(start 0.9144 0.508)
			(end 0.9144 0.406654)
			(stroke
				(width 0.1)
				(type default)
			)
			(layer "B.Fab")
		)
		(fp_line
			(start 0.9144 0.406654)
			(end 1.194308 0.406654)
			(stroke
				(width 0.1)
				(type default)
			)
			(layer "B.Fab")
		)
		(fp_line
			(start 1.194308 0.406654)
			(end 1.194308 -0.406654)
			(stroke
				(width 0.1)
				(type default)
			)
			(layer "B.Fab")
		)
		(fp_line
			(start -1.1938 0.4064)
			(end -0.9144 0.4064)
			(stroke
				(width 0.1)
				(type default)
			)
			(layer "B.Fab")
		)
		(fp_line
			(start -0.9144 0.4064)
			(end -0.9144 0.508)
			(stroke
				(width 0.1)
				(type default)
			)
			(layer "B.Fab")
		)
		(fp_line
			(start -1.1938 -0.406654)
			(end -1.1938 0.4064)
			(stroke
				(width 0.1)
				(type default)
			)
			(layer "B.Fab")
		)
		(fp_line
			(start -0.9144 -0.406654)
			(end -1.1938 -0.406654)
			(stroke
				(width 0.1)
				(type default)
			)
			(layer "B.Fab")
		)
		(fp_line
			(start 0.9144 -0.406654)
			(end 0.9144 -0.508)
			(stroke
				(width 0.1)
				(type default)
			)
			(layer "B.Fab")
		)
		(fp_line
			(start 1.194308 -0.406654)
			(end 0.9144 -0.406654)
			(stroke
				(width 0.1)
				(type default)
			)
			(layer "B.Fab")
		)
		(fp_line
			(start -0.9144 -0.508)
			(end -0.9144 -0.406654)
			(stroke
				(width 0.1)
				(type default)
			)
			(layer "B.Fab")
		)
		(fp_line
			(start 0.9144 -0.508)
			(end -0.9144 -0.508)
			(stroke
				(width 0.1)
				(type default)
			)
			(layer "B.Fab")
		)
		(pad "1" smd rect
			(at 0.7366 0 180)
			(size 0.7112 0.8128)
			(layers "B.Cu" "B.Mask" "B.Paste")
			(net "P3V3")
		)
		(pad "2" smd rect
			(at -0.7366 0 180)
			(size 0.7112 0.8128)
			(layers "B.Cu" "B.Mask" "B.Paste")
			(net "P3V3_VDD_9ZXL0851_8_15")
		)
	)
	(footprint ""
		(layer "B.Cu")
		(at 54.899814 -301.599854 -90)
		(property "Reference" "C1217"
			(at 0 0 90)
			(layer "B.SilkS")
			(hide yes)
			(effects
				(font
					(size 1.27 1.27)
				)
				(justify mirror)
			)
		)
		(property "Value" ""
			(at 0 0 90)
			(layer "B.Fab")
			(effects
				(font
					(size 1.27 1.27)
				)
				(justify mirror)
			)
		)
		(duplicate_pad_numbers_are_jumpers no)
		(fp_line
			(start -0.299974 0.150114)
			(end 0.299974 0.150114)
			(stroke
				(width 0.1)
				(type default)
			)
			(layer "B.Fab")
		)
		(fp_line
			(start 0.299974 0.150114)
			(end 0.299974 -0.150114)
			(stroke
				(width 0.1)
				(type default)
			)
			(layer "B.Fab")
		)
		(fp_line
			(start -0.299974 -0.150114)
			(end -0.299974 0.150114)
			(stroke
				(width 0.1)
				(type default)
			)
			(layer "B.Fab")
		)
		(fp_line
			(start 0.299974 -0.150114)
			(end -0.299974 -0.150114)
			(stroke
				(width 0.1)
				(type default)
			)
			(layer "B.Fab")
		)
		(pad "1" smd rect
			(at 0.2667 0 90)
			(size 0.3048 0.381)
			(layers "B.Cu" "B.Mask" "B.Paste")
			(net "P0V8_SERDES_VDDA_PEX0")
		)
		(pad "2" smd rect
			(at -0.2667 0 90)
			(size 0.3048 0.381)
			(layers "B.Cu" "B.Mask" "B.Paste")
			(net "GND")
		)
	)
	(footprint ""
		(layer "B.Cu")
		(at 172.920406 -296.37482)
		(property "Reference" "C1363"
			(at 0 0 0)
			(layer "B.SilkS")
			(hide yes)
			(effects
				(font
					(size 1.27 1.27)
				)
				(justify mirror)
			)
		)
		(property "Value" ""
			(at 0 0 0)
			(layer "B.Fab")
			(effects
				(font
					(size 1.27 1.27)
				)
				(justify mirror)
			)
		)
		(duplicate_pad_numbers_are_jumpers no)
		(fp_line
			(start -0.299974 -0.150114)
			(end -0.299974 0.150114)
			(stroke
				(width 0.1)
				(type default)
			)
			(layer "B.Fab")
		)
		(fp_line
			(start -0.299974 0.150114)
			(end 0.299974 0.150114)
			(stroke
				(width 0.1)
				(type default)
			)
			(layer "B.Fab")
		)
		(fp_line
			(start 0.299974 -0.150114)
			(end -0.299974 -0.150114)
			(stroke
				(width 0.1)
				(type default)
			)
			(layer "B.Fab")
		)
		(fp_line
			(start 0.299974 0.150114)
			(end 0.299974 -0.150114)
			(stroke
				(width 0.1)
				(type default)
			)
			(layer "B.Fab")
		)
		(pad "1" smd rect
			(at 0.2667 0 180)
			(size 0.3048 0.381)
			(layers "B.Cu" "B.Mask" "B.Paste")
			(net "P0V8_PEX1")
		)
		(pad "2" smd rect
			(at -0.2667 0 180)
			(size 0.3048 0.381)
			(layers "B.Cu" "B.Mask" "B.Paste")
			(net "GND")
		)
	)
	(footprint ""
		(layer "B.Cu")
		(at 187.854844 -97.663 180)
		(property "Reference" "R175"
			(at 0 0 0)
			(layer "B.SilkS")
			(hide yes)
			(effects
				(font
					(size 1.27 1.27)
				)
				(justify mirror)
			)
		)
		(property "Value" ""
			(at 0 0 0)
			(layer "B.Fab")
			(effects
				(font
					(size 1.27 1.27)
				)
				(justify mirror)
			)
		)
		(duplicate_pad_numbers_are_jumpers no)
		(fp_line
			(start 0.7874 0.4064)
			(end 0.7874 -0.4064)
			(stroke
				(width 0.1524)
				(type default)
			)
			(layer "B.SilkS")
		)
		(fp_line
			(start 0.7874 -0.4064)
			(end -0.7874 -0.4064)
			(stroke
				(width 0.1524)
				(type default)
			)
			(layer "B.SilkS")
		)
		(fp_line
			(start -0.7874 0.4064)
			(end 0.7874 0.4064)
			(stroke
				(width 0.1524)
				(type default)
			)
			(layer "B.SilkS")
		)
		(fp_line
			(start -0.7874 -0.4064)
			(end -0.7874 0.4064)
			(stroke
				(width 0.1524)
				(type default)
			)
			(layer "B.SilkS")
		)
		(fp_line
			(start 0.67945 0.3048)
			(end 0.67945 -0.305054)
			(stroke
				(width 0.1)
				(type default)
			)
			(layer "B.Fab")
		)
		(fp_line
			(start 0.67945 -0.305054)
			(end 0.12065 -0.305054)
			(stroke
				(width 0.1)
				(type default)
			)
			(layer "B.Fab")
		)
		(fp_line
			(start 0.12065 0.3048)
			(end 0.67945 0.3048)
			(stroke
				(width 0.1)
				(type default)
			)
			(layer "B.Fab")
		)
		(fp_line
			(start 0.12065 0.2794)
			(end 0.12065 0.3048)
			(stroke
				(width 0.1)
				(type default)
			)
			(layer "B.Fab")
		)
		(fp_line
			(start 0.12065 -0.2794)
			(end -0.12065 -0.2794)
			(stroke
				(width 0.1)
				(type default)
			)
			(layer "B.Fab")
		)
		(fp_line
			(start 0.12065 -0.305054)
			(end 0.12065 -0.2794)
			(stroke
				(width 0.1)
				(type default)
			)
			(layer "B.Fab")
		)
		(fp_line
			(start -0.120396 0.3048)
			(end -0.120396 0.2794)
			(stroke
				(width 0.1)
				(type default)
			)
			(layer "B.Fab")
		)
		(fp_line
			(start -0.120396 0.2794)
			(end 0.12065 0.2794)
			(stroke
				(width 0.1)
				(type default)
			)
			(layer "B.Fab")
		)
		(fp_line
			(start -0.12065 -0.2794)
			(end -0.12065 -0.3048)
			(stroke
				(width 0.1)
				(type default)
			)
			(layer "B.Fab")
		)
		(fp_line
			(start -0.12065 -0.3048)
			(end -0.67945 -0.3048)
			(stroke
				(width 0.1)
				(type default)
			)
			(layer "B.Fab")
		)
		(fp_line
			(start -0.67945 0.3048)
			(end -0.120396 0.3048)
			(stroke
				(width 0.1)
				(type default)
			)
			(layer "B.Fab")
		)
		(fp_line
			(start -0.67945 -0.3048)
			(end -0.67945 0.3048)
			(stroke
				(width 0.1)
				(type default)
			)
			(layer "B.Fab")
		)
		(pad "1" smd circle
			(at 0.40005 0)
			(size 0 0)
			(layers "B.Cu" "B.Mask" "B.Paste")
			(net "PWRGD_NIC3_PWR_GOOD")
		)
		(pad "2" smd circle
			(at -0.40005 0)
			(size 0 0)
			(layers "B.Cu" "B.Mask" "B.Paste")
			(net "GND")
		)
	)
	(footprint ""
		(layer "B.Cu")
		(at 298.119038 -202.16114 -90)
		(property "Reference" "R1041"
			(at 0 0 90)
			(layer "B.SilkS")
			(hide yes)
			(effects
				(font
					(size 1.27 1.27)
				)
				(justify mirror)
			)
		)
		(property "Value" ""
			(at 0 0 90)
			(layer "B.Fab")
			(effects
				(font
					(size 1.27 1.27)
				)
				(justify mirror)
			)
		)
		(duplicate_pad_numbers_are_jumpers no)
		(fp_line
			(start -0.7874 0.4064)
			(end 0.7874 0.4064)
			(stroke
				(width 0.1524)
				(type default)
			)
			(layer "B.SilkS")
		)
		(fp_line
			(start 0.7874 0.4064)
			(end 0.7874 -0.4064)
			(stroke
				(width 0.1524)
				(type default)
			)
			(layer "B.SilkS")
		)
		(fp_line
			(start -0.7874 -0.4064)
			(end -0.7874 0.4064)
			(stroke
				(width 0.1524)
				(type default)
			)
			(layer "B.SilkS")
		)
		(fp_line
			(start 0.7874 -0.4064)
			(end -0.7874 -0.4064)
			(stroke
				(width 0.1524)
				(type default)
			)
			(layer "B.SilkS")
		)
		(fp_line
			(start -0.67945 0.3048)
			(end -0.120396 0.3048)
			(stroke
				(width 0.1)
				(type default)
			)
			(layer "B.Fab")
		)
		(fp_line
			(start -0.120396 0.3048)
			(end -0.120396 0.2794)
			(stroke
				(width 0.1)
				(type default)
			)
			(layer "B.Fab")
		)
		(fp_line
			(start 0.12065 0.3048)
			(end 0.67945 0.3048)
			(stroke
				(width 0.1)
				(type default)
			)
			(layer "B.Fab")
		)
		(fp_line
			(start 0.67945 0.3048)
			(end 0.67945 -0.305054)
			(stroke
				(width 0.1)
				(type default)
			)
			(layer "B.Fab")
		)
		(fp_line
			(start -0.120396 0.2794)
			(end 0.12065 0.2794)
			(stroke
				(width 0.1)
				(type default)
			)
			(layer "B.Fab")
		)
		(fp_line
			(start 0.12065 0.2794)
			(end 0.12065 0.3048)
			(stroke
				(width 0.1)
				(type default)
			)
			(layer "B.Fab")
		)
		(fp_line
			(start -0.12065 -0.2794)
			(end -0.12065 -0.3048)
			(stroke
				(width 0.1)
				(type default)
			)
			(layer "B.Fab")
		)
		(fp_line
			(start 0.12065 -0.2794)
			(end -0.12065 -0.2794)
			(stroke
				(width 0.1)
				(type default)
			)
			(layer "B.Fab")
		)
		(fp_line
			(start -0.67945 -0.3048)
			(end -0.67945 0.3048)
			(stroke
				(width 0.1)
				(type default)
			)
			(layer "B.Fab")
		)
		(fp_line
			(start -0.12065 -0.3048)
			(end -0.67945 -0.3048)
			(stroke
				(width 0.1)
				(type default)
			)
			(layer "B.Fab")
		)
		(fp_line
			(start 0.12065 -0.305054)
			(end 0.12065 -0.2794)
			(stroke
				(width 0.1)
				(type default)
			)
			(layer "B.Fab")
		)
		(fp_line
			(start 0.67945 -0.305054)
			(end 0.12065 -0.305054)
			(stroke
				(width 0.1)
				(type default)
			)
			(layer "B.Fab")
		)
		(pad "1" smd circle
			(at 0.40005 0 90)
			(size 0 0)
			(layers "B.Cu" "B.Mask" "B.Paste")
			(net "GND")
		)
		(pad "2" smd circle
			(at -0.40005 0 90)
			(size 0 0)
			(layers "B.Cu" "B.Mask" "B.Paste")
			(net "SPI_BIC1_CS0_LS23_N_DIR1")
		)
	)
	(footprint ""
		(layer "B.Cu")
		(at 163.874958 -296.7482 -90)
		(property "Reference" "C3215"
			(at 0 0 90)
			(layer "B.SilkS")
			(hide yes)
			(effects
				(font
					(size 1.27 1.27)
				)
				(justify mirror)
			)
		)
		(property "Value" ""
			(at 0 0 90)
			(layer "B.Fab")
			(effects
				(font
					(size 1.27 1.27)
				)
				(justify mirror)
			)
		)
		(duplicate_pad_numbers_are_jumpers no)
		(fp_line
			(start -0.299974 0.150114)
			(end 0.299974 0.150114)
			(stroke
				(width 0.1)
				(type default)
			)
			(layer "B.Fab")
		)
		(fp_line
			(start 0.299974 0.150114)
			(end 0.299974 -0.150114)
			(stroke
				(width 0.1)
				(type default)
			)
			(layer "B.Fab")
		)
		(fp_line
			(start -0.299974 -0.150114)
			(end -0.299974 0.150114)
			(stroke
				(width 0.1)
				(type default)
			)
			(layer "B.Fab")
		)
		(fp_line
			(start 0.299974 -0.150114)
			(end -0.299974 -0.150114)
			(stroke
				(width 0.1)
				(type default)
			)
			(layer "B.Fab")
		)
		(pad "1" smd rect
			(at 0.2667 0 90)
			(size 0.3048 0.381)
			(layers "B.Cu" "B.Mask" "B.Paste")
			(net "PCEPLL3_VDDA18_PEX1")
		)
		(pad "2" smd rect
			(at -0.2667 0 90)
			(size 0.3048 0.381)
			(layers "B.Cu" "B.Mask" "B.Paste")
			(net "GND")
		)
	)
	(footprint ""
		(layer "B.Cu")
		(at 271.899888 -288.774886 -90)
		(property "Reference" "R3472"
			(at 0 0 90)
			(layer "B.SilkS")
			(hide yes)
			(effects
				(font
					(size 1.27 1.27)
				)
				(justify mirror)
			)
		)
		(property "Value" ""
			(at 0 0 90)
			(layer "B.Fab")
			(effects
				(font
					(size 1.27 1.27)
				)
				(justify mirror)
			)
		)
		(duplicate_pad_numbers_are_jumpers no)
		(fp_line
			(start -0.7874 0.4064)
			(end 0.7874 0.4064)
			(stroke
				(width 0.1524)
				(type default)
			)
			(layer "B.SilkS")
		)
		(fp_line
			(start 0.7874 0.4064)
			(end 0.7874 -0.4064)
			(stroke
				(width 0.1524)
				(type default)
			)
			(layer "B.SilkS")
		)
		(fp_line
			(start -0.7874 -0.4064)
			(end -0.7874 0.4064)
			(stroke
				(width 0.1524)
				(type default)
			)
			(layer "B.SilkS")
		)
		(fp_line
			(start 0.7874 -0.4064)
			(end -0.7874 -0.4064)
			(stroke
				(width 0.1524)
				(type default)
			)
			(layer "B.SilkS")
		)
		(fp_line
			(start -0.67945 0.3048)
			(end -0.120396 0.3048)
			(stroke
				(width 0.1)
				(type default)
			)
			(layer "B.Fab")
		)
		(fp_line
			(start -0.120396 0.3048)
			(end -0.120396 0.2794)
			(stroke
				(width 0.1)
				(type default)
			)
			(layer "B.Fab")
		)
		(fp_line
			(start 0.12065 0.3048)
			(end 0.67945 0.3048)
			(stroke
				(width 0.1)
				(type default)
			)
			(layer "B.Fab")
		)
		(fp_line
			(start 0.67945 0.3048)
			(end 0.67945 -0.305054)
			(stroke
				(width 0.1)
				(type default)
			)
			(layer "B.Fab")
		)
		(fp_line
			(start -0.120396 0.2794)
			(end 0.12065 0.2794)
			(stroke
				(width 0.1)
				(type default)
			)
			(layer "B.Fab")
		)
		(fp_line
			(start 0.12065 0.2794)
			(end 0.12065 0.3048)
			(stroke
				(width 0.1)
				(type default)
			)
			(layer "B.Fab")
		)
		(fp_line
			(start -0.12065 -0.2794)
			(end -0.12065 -0.3048)
			(stroke
				(width 0.1)
				(type default)
			)
			(layer "B.Fab")
		)
		(fp_line
			(start 0.12065 -0.2794)
			(end -0.12065 -0.2794)
			(stroke
				(width 0.1)
				(type default)
			)
			(layer "B.Fab")
		)
		(fp_line
			(start -0.67945 -0.3048)
			(end -0.67945 0.3048)
			(stroke
				(width 0.1)
				(type default)
			)
			(layer "B.Fab")
		)
		(fp_line
			(start -0.12065 -0.3048)
			(end -0.67945 -0.3048)
			(stroke
				(width 0.1)
				(type default)
			)
			(layer "B.Fab")
		)
		(fp_line
			(start 0.12065 -0.305054)
			(end 0.12065 -0.2794)
			(stroke
				(width 0.1)
				(type default)
			)
			(layer "B.Fab")
		)
		(fp_line
			(start 0.67945 -0.305054)
			(end 0.12065 -0.305054)
			(stroke
				(width 0.1)
				(type default)
			)
			(layer "B.Fab")
		)
		(pad "1" smd circle
			(at 0.40005 0 90)
			(size 0 0)
			(layers "B.Cu" "B.Mask" "B.Paste")
			(net "SPI_PEX2_SDIO3_R")
		)
		(pad "2" smd circle
			(at -0.40005 0 90)
			(size 0 0)
			(layers "B.Cu" "B.Mask" "B.Paste")
			(net "SPI_PEX2_SDIO3")
		)
	)
	(footprint ""
		(layer "B.Cu")
		(at 299.250608 -225.780346 180)
		(property "Reference" "C2748"
			(at 0 0 0)
			(layer "B.SilkS")
			(hide yes)
			(effects
				(font
					(size 1.27 1.27)
				)
				(justify mirror)
			)
		)
		(property "Value" ""
			(at 0 0 0)
			(layer "B.Fab")
			(effects
				(font
					(size 1.27 1.27)
				)
				(justify mirror)
			)
		)
		(duplicate_pad_numbers_are_jumpers no)
		(fp_line
			(start 0.7874 0.4064)
			(end 0.7874 -0.4064)
			(stroke
				(width 0.1524)
				(type default)
			)
			(layer "B.SilkS")
		)
		(fp_line
			(start 0.7874 -0.4064)
			(end -0.7874 -0.4064)
			(stroke
				(width 0.1524)
				(type default)
			)
			(layer "B.SilkS")
		)
		(fp_line
			(start -0.7874 0.4064)
			(end 0.7874 0.4064)
			(stroke
				(width 0.1524)
				(type default)
			)
			(layer "B.SilkS")
		)
		(fp_line
			(start -0.7874 -0.4064)
			(end -0.7874 0.4064)
			(stroke
				(width 0.1524)
				(type default)
			)
			(layer "B.SilkS")
		)
		(fp_line
			(start 0.67945 0.3048)
			(end 0.67945 -0.305054)
			(stroke
				(width 0.1)
				(type default)
			)
			(layer "B.Fab")
		)
		(fp_line
			(start 0.67945 -0.305054)
			(end 0.12065 -0.305054)
			(stroke
				(width 0.1)
				(type default)
			)
			(layer "B.Fab")
		)
		(fp_line
			(start 0.12065 0.3048)
			(end 0.67945 0.3048)
			(stroke
				(width 0.1)
				(type default)
			)
			(layer "B.Fab")
		)
		(fp_line
			(start 0.12065 0.2794)
			(end 0.12065 0.3048)
			(stroke
				(width 0.1)
				(type default)
			)
			(layer "B.Fab")
		)
		(fp_line
			(start 0.12065 -0.2794)
			(end -0.12065 -0.2794)
			(stroke
				(width 0.1)
				(type default)
			)
			(layer "B.Fab")
		)
		(fp_line
			(start 0.12065 -0.305054)
			(end 0.12065 -0.2794)
			(stroke
				(width 0.1)
				(type default)
			)
			(layer "B.Fab")
		)
		(fp_line
			(start -0.120396 0.3048)
			(end -0.120396 0.2794)
			(stroke
				(width 0.1)
				(type default)
			)
			(layer "B.Fab")
		)
		(fp_line
			(start -0.120396 0.2794)
			(end 0.12065 0.2794)
			(stroke
				(width 0.1)
				(type default)
			)
			(layer "B.Fab")
		)
		(fp_line
			(start -0.12065 -0.2794)
			(end -0.12065 -0.3048)
			(stroke
				(width 0.1)
				(type default)
			)
			(layer "B.Fab")
		)
		(fp_line
			(start -0.12065 -0.3048)
			(end -0.67945 -0.3048)
			(stroke
				(width 0.1)
				(type default)
			)
			(layer "B.Fab")
		)
		(fp_line
			(start -0.67945 0.3048)
			(end -0.120396 0.3048)
			(stroke
				(width 0.1)
				(type default)
			)
			(layer "B.Fab")
		)
		(fp_line
			(start -0.67945 -0.3048)
			(end -0.67945 0.3048)
			(stroke
				(width 0.1)
				(type default)
			)
			(layer "B.Fab")
		)
		(pad "1" smd circle
			(at 0.40005 0)
			(size 0 0)
			(layers "B.Cu" "B.Mask" "B.Paste")
			(net "GND")
		)
		(pad "2" smd circle
			(at -0.40005 0)
			(size 0 0)
			(layers "B.Cu" "B.Mask" "B.Paste")
			(net "P3V3_AUX")
		)
	)
	(footprint ""
		(layer "B.Cu")
		(at 338.768436 -308.749954 90)
		(property "Reference" "C4307"
			(at 0 0 90)
			(layer "B.SilkS")
			(hide yes)
			(effects
				(font
					(size 1.27 1.27)
				)
				(justify mirror)
			)
		)
		(property "Value" ""
			(at 0 0 90)
			(layer "B.Fab")
			(effects
				(font
					(size 1.27 1.27)
				)
				(justify mirror)
			)
		)
		(duplicate_pad_numbers_are_jumpers no)
		(fp_line
			(start 0.299974 -0.150114)
			(end -0.299974 -0.150114)
			(stroke
				(width 0.1)
				(type default)
			)
			(layer "B.Fab")
		)
		(fp_line
			(start -0.299974 -0.150114)
			(end -0.299974 0.150114)
			(stroke
				(width 0.1)
				(type default)
			)
			(layer "B.Fab")
		)
		(fp_line
			(start 0.299974 0.150114)
			(end 0.299974 -0.150114)
			(stroke
				(width 0.1)
				(type default)
			)
			(layer "B.Fab")
		)
		(fp_line
			(start -0.299974 0.150114)
			(end 0.299974 0.150114)
			(stroke
				(width 0.1)
				(type default)
			)
			(layer "B.Fab")
		)
		(pad "1" smd rect
			(at 0.2667 0 270)
			(size 0.3048 0.381)
			(layers "B.Cu" "B.Mask" "B.Paste")
			(net "P0V8_PEX2")
		)
		(pad "2" smd rect
			(at -0.2667 0 270)
			(size 0.3048 0.381)
			(layers "B.Cu" "B.Mask" "B.Paste")
			(net "GND")
		)
	)
	(footprint ""
		(layer "B.Cu")
		(at 128.530604 -325.61149 -90)
		(property "Reference" "C4255"
			(at 0 0 90)
			(layer "B.SilkS")
			(hide yes)
			(effects
				(font
					(size 1.27 1.27)
				)
				(justify mirror)
			)
		)
		(property "Value" ""
			(at 0 0 90)
			(layer "B.Fab")
			(effects
				(font
					(size 1.27 1.27)
				)
				(justify mirror)
			)
		)
		(duplicate_pad_numbers_are_jumpers no)
		(fp_line
			(start -1.2954 0.5842)
			(end 1.2954 0.5842)
			(stroke
				(width 0.1524)
				(type default)
			)
			(layer "B.SilkS")
		)
		(fp_line
			(start 1.2954 0.5842)
			(end 1.2954 -0.5842)
			(stroke
				(width 0.1524)
				(type default)
			)
			(layer "B.SilkS")
		)
		(fp_line
			(start -1.2954 -0.5842)
			(end -1.2954 0.5842)
			(stroke
				(width 0.1524)
				(type default)
			)
			(layer "B.SilkS")
		)
		(fp_line
			(start 1.2954 -0.5842)
			(end -1.2954 -0.5842)
			(stroke
				(width 0.1524)
				(type default)
			)
			(layer "B.SilkS")
		)
		(fp_line
			(start -0.8636 0.4572)
			(end 0.8636 0.4572)
			(stroke
				(width 0.1)
				(type default)
			)
			(layer "B.Fab")
		)
		(fp_line
			(start 0.8636 0.4572)
			(end 0.8636 0.4064)
			(stroke
				(width 0.1)
				(type default)
			)
			(layer "B.Fab")
		)
		(fp_line
			(start -1.1938 0.4064)
			(end -0.8636 0.4064)
			(stroke
				(width 0.1)
				(type default)
			)
			(layer "B.Fab")
		)
		(fp_line
			(start -0.8636 0.4064)
			(end -0.8636 0.4572)
			(stroke
				(width 0.1)
				(type default)
			)
			(layer "B.Fab")
		)
		(fp_line
			(start 0.8636 0.4064)
			(end 1.1938 0.4064)
			(stroke
				(width 0.1)
				(type default)
			)
			(layer "B.Fab")
		)
		(fp_line
			(start 1.1938 0.4064)
			(end 1.1938 -0.4064)
			(stroke
				(width 0.1)
				(type default)
			)
			(layer "B.Fab")
		)
		(fp_line
			(start -1.1938 -0.4064)
			(end -1.1938 0.4064)
			(stroke
				(width 0.1)
				(type default)
			)
			(layer "B.Fab")
		)
		(fp_line
			(start -0.8636 -0.4064)
			(end -1.1938 -0.4064)
			(stroke
				(width 0.1)
				(type default)
			)
			(layer "B.Fab")
		)
		(fp_line
			(start 0.8636 -0.4064)
			(end 0.8636 -0.4572)
			(stroke
				(width 0.1)
				(type default)
			)
			(layer "B.Fab")
		)
		(fp_line
			(start 1.1938 -0.4064)
			(end 0.8636 -0.4064)
			(stroke
				(width 0.1)
				(type default)
			)
			(layer "B.Fab")
		)
		(fp_line
			(start -0.8636 -0.4572)
			(end -0.8636 -0.4064)
			(stroke
				(width 0.1)
				(type default)
			)
			(layer "B.Fab")
		)
		(fp_line
			(start 0.8636 -0.4572)
			(end -0.8636 -0.4572)
			(stroke
				(width 0.1)
				(type default)
			)
			(layer "B.Fab")
		)
		(pad "1" smd rect
			(at 0.7366 0 180)
			(size 0.7112 0.8128)
			(layers "B.Cu" "B.Mask" "B.Paste")
			(net "P0V8_SERDES_VDDA_PEX1_C1")
		)
		(pad "2" smd rect
			(at -0.7366 0 180)
			(size 0.7112 0.8128)
			(layers "B.Cu" "B.Mask" "B.Paste")
			(net "GND")
		)
	)
	(footprint ""
		(layer "B.Cu")
		(at 403.199854 -290.199826 90)
		(property "Reference" "C1982"
			(at 0 0 90)
			(layer "B.SilkS")
			(hide yes)
			(effects
				(font
					(size 1.27 1.27)
				)
				(justify mirror)
			)
		)
		(property "Value" ""
			(at 0 0 90)
			(layer "B.Fab")
			(effects
				(font
					(size 1.27 1.27)
				)
				(justify mirror)
			)
		)
		(duplicate_pad_numbers_are_jumpers no)
		(fp_line
			(start 0.299974 -0.150114)
			(end -0.299974 -0.150114)
			(stroke
				(width 0.1)
				(type default)
			)
			(layer "B.Fab")
		)
		(fp_line
			(start -0.299974 -0.150114)
			(end -0.299974 0.150114)
			(stroke
				(width 0.1)
				(type default)
			)
			(layer "B.Fab")
		)
		(fp_line
			(start 0.299974 0.150114)
			(end 0.299974 -0.150114)
			(stroke
				(width 0.1)
				(type default)
			)
			(layer "B.Fab")
		)
		(fp_line
			(start -0.299974 0.150114)
			(end 0.299974 0.150114)
			(stroke
				(width 0.1)
				(type default)
			)
			(layer "B.Fab")
		)
		(pad "1" smd rect
			(at 0.2667 0 270)
			(size 0.3048 0.381)
			(layers "B.Cu" "B.Mask" "B.Paste")
			(net "P0V8_SERDES_VDDA_PEX3")
		)
		(pad "2" smd rect
			(at -0.2667 0 270)
			(size 0.3048 0.381)
			(layers "B.Cu" "B.Mask" "B.Paste")
			(net "GND")
		)
	)
	(footprint ""
		(layer "B.Cu")
		(at 129.58826 -308.580028 90)
		(property "Reference" "C4249"
			(at 0 0 90)
			(layer "B.SilkS")
			(hide yes)
			(effects
				(font
					(size 1.27 1.27)
				)
				(justify mirror)
			)
		)
		(property "Value" ""
			(at 0 0 90)
			(layer "B.Fab")
			(effects
				(font
					(size 1.27 1.27)
				)
				(justify mirror)
			)
		)
		(duplicate_pad_numbers_are_jumpers no)
		(fp_line
			(start 1.2954 -0.5842)
			(end -1.2954 -0.5842)
			(stroke
				(width 0.1524)
				(type default)
			)
			(layer "B.SilkS")
		)
		(fp_line
			(start -1.2954 -0.5842)
			(end -1.2954 0.5842)
			(stroke
				(width 0.1524)
				(type default)
			)
			(layer "B.SilkS")
		)
		(fp_line
			(start 1.2954 0.5842)
			(end 1.2954 -0.5842)
			(stroke
				(width 0.1524)
				(type default)
			)
			(layer "B.SilkS")
		)
		(fp_line
			(start -1.2954 0.5842)
			(end 1.2954 0.5842)
			(stroke
				(width 0.1524)
				(type default)
			)
			(layer "B.SilkS")
		)
		(fp_line
			(start 0.8636 -0.4572)
			(end -0.8636 -0.4572)
			(stroke
				(width 0.1)
				(type default)
			)
			(layer "B.Fab")
		)
		(fp_line
			(start -0.8636 -0.4572)
			(end -0.8636 -0.4064)
			(stroke
				(width 0.1)
				(type default)
			)
			(layer "B.Fab")
		)
		(fp_line
			(start 1.1938 -0.4064)
			(end 0.8636 -0.4064)
			(stroke
				(width 0.1)
				(type default)
			)
			(layer "B.Fab")
		)
		(fp_line
			(start 0.8636 -0.4064)
			(end 0.8636 -0.4572)
			(stroke
				(width 0.1)
				(type default)
			)
			(layer "B.Fab")
		)
		(fp_line
			(start -0.8636 -0.4064)
			(end -1.1938 -0.4064)
			(stroke
				(width 0.1)
				(type default)
			)
			(layer "B.Fab")
		)
		(fp_line
			(start -1.1938 -0.4064)
			(end -1.1938 0.4064)
			(stroke
				(width 0.1)
				(type default)
			)
			(layer "B.Fab")
		)
		(fp_line
			(start 1.1938 0.4064)
			(end 1.1938 -0.4064)
			(stroke
				(width 0.1)
				(type default)
			)
			(layer "B.Fab")
		)
		(fp_line
			(start 0.8636 0.4064)
			(end 1.1938 0.4064)
			(stroke
				(width 0.1)
				(type default)
			)
			(layer "B.Fab")
		)
		(fp_line
			(start -0.8636 0.4064)
			(end -0.8636 0.4572)
			(stroke
				(width 0.1)
				(type default)
			)
			(layer "B.Fab")
		)
		(fp_line
			(start -1.1938 0.4064)
			(end -0.8636 0.4064)
			(stroke
				(width 0.1)
				(type default)
			)
			(layer "B.Fab")
		)
		(fp_line
			(start 0.8636 0.4572)
			(end 0.8636 0.4064)
			(stroke
				(width 0.1)
				(type default)
			)
			(layer "B.Fab")
		)
		(fp_line
			(start -0.8636 0.4572)
			(end 0.8636 0.4572)
			(stroke
				(width 0.1)
				(type default)
			)
			(layer "B.Fab")
		)
		(pad "1" smd rect
			(at 0.7366 0)
			(size 0.7112 0.8128)
			(layers "B.Cu" "B.Mask" "B.Paste")
			(net "P0V8_PEX1")
		)
		(pad "2" smd rect
			(at -0.7366 0)
			(size 0.7112 0.8128)
			(layers "B.Cu" "B.Mask" "B.Paste")
			(net "GND")
		)
	)
	(footprint ""
		(layer "B.Cu")
		(at 236.546644 -231.225598 -90)
		(property "Reference" "R4529"
			(at 0 0 90)
			(layer "B.SilkS")
			(hide yes)
			(effects
				(font
					(size 1.27 1.27)
				)
				(justify mirror)
			)
		)
		(property "Value" ""
			(at 0 0 90)
			(layer "B.Fab")
			(effects
				(font
					(size 1.27 1.27)
				)
				(justify mirror)
			)
		)
		(duplicate_pad_numbers_are_jumpers no)
		(fp_line
			(start -0.7874 0.4064)
			(end 0.7874 0.4064)
			(stroke
				(width 0.1524)
				(type default)
			)
			(layer "B.SilkS")
		)
		(fp_line
			(start 0.7874 0.4064)
			(end 0.7874 -0.4064)
			(stroke
				(width 0.1524)
				(type default)
			)
			(layer "B.SilkS")
		)
		(fp_line
			(start -0.7874 -0.4064)
			(end -0.7874 0.4064)
			(stroke
				(width 0.1524)
				(type default)
			)
			(layer "B.SilkS")
		)
		(fp_line
			(start 0.7874 -0.4064)
			(end -0.7874 -0.4064)
			(stroke
				(width 0.1524)
				(type default)
			)
			(layer "B.SilkS")
		)
		(fp_line
			(start -0.67945 0.3048)
			(end -0.120396 0.3048)
			(stroke
				(width 0.1)
				(type default)
			)
			(layer "B.Fab")
		)
		(fp_line
			(start -0.120396 0.3048)
			(end -0.120396 0.2794)
			(stroke
				(width 0.1)
				(type default)
			)
			(layer "B.Fab")
		)
		(fp_line
			(start 0.12065 0.3048)
			(end 0.67945 0.3048)
			(stroke
				(width 0.1)
				(type default)
			)
			(layer "B.Fab")
		)
		(fp_line
			(start 0.67945 0.3048)
			(end 0.67945 -0.305054)
			(stroke
				(width 0.1)
				(type default)
			)
			(layer "B.Fab")
		)
		(fp_line
			(start -0.120396 0.2794)
			(end 0.12065 0.2794)
			(stroke
				(width 0.1)
				(type default)
			)
			(layer "B.Fab")
		)
		(fp_line
			(start 0.12065 0.2794)
			(end 0.12065 0.3048)
			(stroke
				(width 0.1)
				(type default)
			)
			(layer "B.Fab")
		)
		(fp_line
			(start -0.12065 -0.2794)
			(end -0.12065 -0.3048)
			(stroke
				(width 0.1)
				(type default)
			)
			(layer "B.Fab")
		)
		(fp_line
			(start 0.12065 -0.2794)
			(end -0.12065 -0.2794)
			(stroke
				(width 0.1)
				(type default)
			)
			(layer "B.Fab")
		)
		(fp_line
			(start -0.67945 -0.3048)
			(end -0.67945 0.3048)
			(stroke
				(width 0.1)
				(type default)
			)
			(layer "B.Fab")
		)
		(fp_line
			(start -0.12065 -0.3048)
			(end -0.67945 -0.3048)
			(stroke
				(width 0.1)
				(type default)
			)
			(layer "B.Fab")
		)
		(fp_line
			(start 0.12065 -0.305054)
			(end 0.12065 -0.2794)
			(stroke
				(width 0.1)
				(type default)
			)
			(layer "B.Fab")
		)
		(fp_line
			(start 0.67945 -0.305054)
			(end 0.12065 -0.305054)
			(stroke
				(width 0.1)
				(type default)
			)
			(layer "B.Fab")
		)
		(pad "1" smd circle
			(at 0.40005 0 90)
			(size 0 0)
			(layers "B.Cu" "B.Mask" "B.Paste")
			(net "SSD15_PWRDIS_BIC")
		)
		(pad "2" smd circle
			(at -0.40005 0 90)
			(size 0 0)
			(layers "B.Cu" "B.Mask" "B.Paste")
			(net "SSD15_PWRDIS_BIC_R")
		)
	)
	(footprint ""
		(layer "B.Cu")
		(at 364.322106 -308.677818 90)
		(property "Reference" "C4377"
			(at 0 0 90)
			(layer "B.SilkS")
			(hide yes)
			(effects
				(font
					(size 1.27 1.27)
				)
				(justify mirror)
			)
		)
		(property "Value" ""
			(at 0 0 90)
			(layer "B.Fab")
			(effects
				(font
					(size 1.27 1.27)
				)
				(justify mirror)
			)
		)
		(duplicate_pad_numbers_are_jumpers no)
		(fp_line
			(start 0.299974 -0.150114)
			(end -0.299974 -0.150114)
			(stroke
				(width 0.1)
				(type default)
			)
			(layer "B.Fab")
		)
		(fp_line
			(start -0.299974 -0.150114)
			(end -0.299974 0.150114)
			(stroke
				(width 0.1)
				(type default)
			)
			(layer "B.Fab")
		)
		(fp_line
			(start 0.299974 0.150114)
			(end 0.299974 -0.150114)
			(stroke
				(width 0.1)
				(type default)
			)
			(layer "B.Fab")
		)
		(fp_line
			(start -0.299974 0.150114)
			(end 0.299974 0.150114)
			(stroke
				(width 0.1)
				(type default)
			)
			(layer "B.Fab")
		)
		(pad "1" smd rect
			(at 0.2667 0 270)
			(size 0.3048 0.381)
			(layers "B.Cu" "B.Mask" "B.Paste")
			(net "P0V8_PEX3")
		)
		(pad "2" smd rect
			(at -0.2667 0 270)
			(size 0.3048 0.381)
			(layers "B.Cu" "B.Mask" "B.Paste")
			(net "GND")
		)
	)
	(footprint ""
		(layer "B.Cu")
		(at 454.907396 -251.35586)
		(property "Reference" "R6583"
			(at 0 0 0)
			(layer "B.SilkS")
			(hide yes)
			(effects
				(font
					(size 1.27 1.27)
				)
				(justify mirror)
			)
		)
		(property "Value" ""
			(at 0 0 0)
			(layer "B.Fab")
			(effects
				(font
					(size 1.27 1.27)
				)
				(justify mirror)
			)
		)
		(duplicate_pad_numbers_are_jumpers no)
		(fp_line
			(start -0.7874 -0.4064)
			(end -0.7874 0.4064)
			(stroke
				(width 0.1524)
				(type default)
			)
			(layer "B.SilkS")
		)
		(fp_line
			(start -0.7874 0.4064)
			(end 0.7874 0.4064)
			(stroke
				(width 0.1524)
				(type default)
			)
			(layer "B.SilkS")
		)
		(fp_line
			(start 0.7874 -0.4064)
			(end -0.7874 -0.4064)
			(stroke
				(width 0.1524)
				(type default)
			)
			(layer "B.SilkS")
		)
		(fp_line
			(start 0.7874 0.4064)
			(end 0.7874 -0.4064)
			(stroke
				(width 0.1524)
				(type default)
			)
			(layer "B.SilkS")
		)
		(fp_line
			(start -0.67945 -0.3048)
			(end -0.67945 0.3048)
			(stroke
				(width 0.1)
				(type default)
			)
			(layer "B.Fab")
		)
		(fp_line
			(start -0.67945 0.3048)
			(end -0.120396 0.3048)
			(stroke
				(width 0.1)
				(type default)
			)
			(layer "B.Fab")
		)
		(fp_line
			(start -0.12065 -0.3048)
			(end -0.67945 -0.3048)
			(stroke
				(width 0.1)
				(type default)
			)
			(layer "B.Fab")
		)
		(fp_line
			(start -0.12065 -0.2794)
			(end -0.12065 -0.3048)
			(stroke
				(width 0.1)
				(type default)
			)
			(layer "B.Fab")
		)
		(fp_line
			(start -0.120396 0.2794)
			(end 0.12065 0.2794)
			(stroke
				(width 0.1)
				(type default)
			)
			(layer "B.Fab")
		)
		(fp_line
			(start -0.120396 0.3048)
			(end -0.120396 0.2794)
			(stroke
				(width 0.1)
				(type default)
			)
			(layer "B.Fab")
		)
		(fp_line
			(start 0.12065 -0.305054)
			(end 0.12065 -0.2794)
			(stroke
				(width 0.1)
				(type default)
			)
			(layer "B.Fab")
		)
		(fp_line
			(start 0.12065 -0.2794)
			(end -0.12065 -0.2794)
			(stroke
				(width 0.1)
				(type default)
			)
			(layer "B.Fab")
		)
		(fp_line
			(start 0.12065 0.2794)
			(end 0.12065 0.3048)
			(stroke
				(width 0.1)
				(type default)
			)
			(layer "B.Fab")
		)
		(fp_line
			(start 0.12065 0.3048)
			(end 0.67945 0.3048)
			(stroke
				(width 0.1)
				(type default)
			)
			(layer "B.Fab")
		)
		(fp_line
			(start 0.67945 -0.305054)
			(end 0.12065 -0.305054)
			(stroke
				(width 0.1)
				(type default)
			)
			(layer "B.Fab")
		)
		(fp_line
			(start 0.67945 0.3048)
			(end 0.67945 -0.305054)
			(stroke
				(width 0.1)
				(type default)
			)
			(layer "B.Fab")
		)
		(pad "1" smd circle
			(at 0.40005 0 180)
			(size 0 0)
			(layers "B.Cu" "B.Mask" "B.Paste")
			(net "P3V3_AUX")
		)
		(pad "2" smd circle
			(at -0.40005 0 180)
			(size 0 0)
			(layers "B.Cu" "B.Mask" "B.Paste")
			(net "PEX3_P1V8_PLL_EN")
		)
	)
	(footprint ""
		(layer "B.Cu")
		(at 60.452 -296.3926 180)
		(property "Reference" "C1128"
			(at 0 0 0)
			(layer "B.SilkS")
			(hide yes)
			(effects
				(font
					(size 1.27 1.27)
				)
				(justify mirror)
			)
		)
		(property "Value" ""
			(at 0 0 0)
			(layer "B.Fab")
			(effects
				(font
					(size 1.27 1.27)
				)
				(justify mirror)
			)
		)
		(duplicate_pad_numbers_are_jumpers no)
		(fp_line
			(start 0.299974 0.150114)
			(end 0.299974 -0.150114)
			(stroke
				(width 0.1)
				(type default)
			)
			(layer "B.Fab")
		)
		(fp_line
			(start 0.299974 -0.150114)
			(end -0.299974 -0.150114)
			(stroke
				(width 0.1)
				(type default)
			)
			(layer "B.Fab")
		)
		(fp_line
			(start -0.299974 0.150114)
			(end 0.299974 0.150114)
			(stroke
				(width 0.1)
				(type default)
			)
			(layer "B.Fab")
		)
		(fp_line
			(start -0.299974 -0.150114)
			(end -0.299974 0.150114)
			(stroke
				(width 0.1)
				(type default)
			)
			(layer "B.Fab")
		)
		(pad "1" smd rect
			(at 0.2667 0)
			(size 0.3048 0.381)
			(layers "B.Cu" "B.Mask" "B.Paste")
			(net "P0V8_PEX0")
		)
		(pad "2" smd rect
			(at -0.2667 0)
			(size 0.3048 0.381)
			(layers "B.Cu" "B.Mask" "B.Paste")
			(net "GND")
		)
	)
	(footprint ""
		(layer "B.Cu")
		(at 281.755342 -153.0096)
		(property "Reference" "R223"
			(at 0 0 0)
			(layer "B.SilkS")
			(hide yes)
			(effects
				(font
					(size 1.27 1.27)
				)
				(justify mirror)
			)
		)
		(property "Value" ""
			(at 0 0 0)
			(layer "B.Fab")
			(effects
				(font
					(size 1.27 1.27)
				)
				(justify mirror)
			)
		)
		(duplicate_pad_numbers_are_jumpers no)
		(fp_line
			(start -0.7874 -0.4064)
			(end -0.7874 0.4064)
			(stroke
				(width 0.1524)
				(type default)
			)
			(layer "B.SilkS")
		)
		(fp_line
			(start -0.7874 0.4064)
			(end 0.7874 0.4064)
			(stroke
				(width 0.1524)
				(type default)
			)
			(layer "B.SilkS")
		)
		(fp_line
			(start 0.7874 -0.4064)
			(end -0.7874 -0.4064)
			(stroke
				(width 0.1524)
				(type default)
			)
			(layer "B.SilkS")
		)
		(fp_line
			(start 0.7874 0.4064)
			(end 0.7874 -0.4064)
			(stroke
				(width 0.1524)
				(type default)
			)
			(layer "B.SilkS")
		)
		(fp_line
			(start -0.67945 -0.3048)
			(end -0.67945 0.3048)
			(stroke
				(width 0.1)
				(type default)
			)
			(layer "B.Fab")
		)
		(fp_line
			(start -0.67945 0.3048)
			(end -0.120396 0.3048)
			(stroke
				(width 0.1)
				(type default)
			)
			(layer "B.Fab")
		)
		(fp_line
			(start -0.12065 -0.3048)
			(end -0.67945 -0.3048)
			(stroke
				(width 0.1)
				(type default)
			)
			(layer "B.Fab")
		)
		(fp_line
			(start -0.12065 -0.2794)
			(end -0.12065 -0.3048)
			(stroke
				(width 0.1)
				(type default)
			)
			(layer "B.Fab")
		)
		(fp_line
			(start -0.120396 0.2794)
			(end 0.12065 0.2794)
			(stroke
				(width 0.1)
				(type default)
			)
			(layer "B.Fab")
		)
		(fp_line
			(start -0.120396 0.3048)
			(end -0.120396 0.2794)
			(stroke
				(width 0.1)
				(type default)
			)
			(layer "B.Fab")
		)
		(fp_line
			(start 0.12065 -0.305054)
			(end 0.12065 -0.2794)
			(stroke
				(width 0.1)
				(type default)
			)
			(layer "B.Fab")
		)
		(fp_line
			(start 0.12065 -0.2794)
			(end -0.12065 -0.2794)
			(stroke
				(width 0.1)
				(type default)
			)
			(layer "B.Fab")
		)
		(fp_line
			(start 0.12065 0.2794)
			(end 0.12065 0.3048)
			(stroke
				(width 0.1)
				(type default)
			)
			(layer "B.Fab")
		)
		(fp_line
			(start 0.12065 0.3048)
			(end 0.67945 0.3048)
			(stroke
				(width 0.1)
				(type default)
			)
			(layer "B.Fab")
		)
		(fp_line
			(start 0.67945 -0.305054)
			(end 0.12065 -0.305054)
			(stroke
				(width 0.1)
				(type default)
			)
			(layer "B.Fab")
		)
		(fp_line
			(start 0.67945 0.3048)
			(end 0.67945 -0.305054)
			(stroke
				(width 0.1)
				(type default)
			)
			(layer "B.Fab")
		)
		(pad "1" smd circle
			(at 0.40005 0 180)
			(size 0 0)
			(layers "B.Cu" "B.Mask" "B.Paste")
			(net "NCSI_NIC4_TXD1")
		)
		(pad "2" smd circle
			(at -0.40005 0 180)
			(size 0 0)
			(layers "B.Cu" "B.Mask" "B.Paste")
			(net "GND")
		)
	)
	(footprint ""
		(layer "B.Cu")
		(at 245.505732 -366.896396 180)
		(property "Reference" "PR6608"
			(at 0 0 0)
			(layer "B.SilkS")
			(hide yes)
			(effects
				(font
					(size 1.27 1.27)
				)
				(justify mirror)
			)
		)
		(property "Value" ""
			(at 0 0 0)
			(layer "B.Fab")
			(effects
				(font
					(size 1.27 1.27)
				)
				(justify mirror)
			)
		)
		(duplicate_pad_numbers_are_jumpers no)
		(fp_line
			(start 0.7874 0.4064)
			(end 0.7874 -0.4064)
			(stroke
				(width 0.1524)
				(type default)
			)
			(layer "B.SilkS")
		)
		(fp_line
			(start 0.7874 -0.4064)
			(end -0.7874 -0.4064)
			(stroke
				(width 0.1524)
				(type default)
			)
			(layer "B.SilkS")
		)
		(fp_line
			(start -0.7874 0.4064)
			(end 0.7874 0.4064)
			(stroke
				(width 0.1524)
				(type default)
			)
			(layer "B.SilkS")
		)
		(fp_line
			(start -0.7874 -0.4064)
			(end -0.7874 0.4064)
			(stroke
				(width 0.1524)
				(type default)
			)
			(layer "B.SilkS")
		)
		(fp_line
			(start 0.67945 0.3048)
			(end 0.67945 -0.305054)
			(stroke
				(width 0.1)
				(type default)
			)
			(layer "B.Fab")
		)
		(fp_line
			(start 0.67945 -0.305054)
			(end 0.12065 -0.305054)
			(stroke
				(width 0.1)
				(type default)
			)
			(layer "B.Fab")
		)
		(fp_line
			(start 0.12065 0.3048)
			(end 0.67945 0.3048)
			(stroke
				(width 0.1)
				(type default)
			)
			(layer "B.Fab")
		)
		(fp_line
			(start 0.12065 0.2794)
			(end 0.12065 0.3048)
			(stroke
				(width 0.1)
				(type default)
			)
			(layer "B.Fab")
		)
		(fp_line
			(start 0.12065 -0.2794)
			(end -0.12065 -0.2794)
			(stroke
				(width 0.1)
				(type default)
			)
			(layer "B.Fab")
		)
		(fp_line
			(start 0.12065 -0.305054)
			(end 0.12065 -0.2794)
			(stroke
				(width 0.1)
				(type default)
			)
			(layer "B.Fab")
		)
		(fp_line
			(start -0.120396 0.3048)
			(end -0.120396 0.2794)
			(stroke
				(width 0.1)
				(type default)
			)
			(layer "B.Fab")
		)
		(fp_line
			(start -0.120396 0.2794)
			(end 0.12065 0.2794)
			(stroke
				(width 0.1)
				(type default)
			)
			(layer "B.Fab")
		)
		(fp_line
			(start -0.12065 -0.2794)
			(end -0.12065 -0.3048)
			(stroke
				(width 0.1)
				(type default)
			)
			(layer "B.Fab")
		)
		(fp_line
			(start -0.12065 -0.3048)
			(end -0.67945 -0.3048)
			(stroke
				(width 0.1)
				(type default)
			)
			(layer "B.Fab")
		)
		(fp_line
			(start -0.67945 0.3048)
			(end -0.120396 0.3048)
			(stroke
				(width 0.1)
				(type default)
			)
			(layer "B.Fab")
		)
		(fp_line
			(start -0.67945 -0.3048)
			(end -0.67945 0.3048)
			(stroke
				(width 0.1)
				(type default)
			)
			(layer "B.Fab")
		)
		(pad "1" smd circle
			(at 0.40005 0)
			(size 0 0)
			(layers "B.Cu" "B.Mask" "B.Paste")
			(net "P12V_HSC_GATE2")
		)
		(pad "2" smd circle
			(at -0.40005 0)
			(size 0 0)
			(layers "B.Cu" "B.Mask" "B.Paste")
			(net "HS_GATE2_R_1")
		)
	)
	(footprint ""
		(layer "B.Cu")
		(at 334.229456 -277.639272)
		(property "Reference" "PC6616"
			(at 0 0 0)
			(layer "B.SilkS")
			(hide yes)
			(effects
				(font
					(size 1.27 1.27)
				)
				(justify mirror)
			)
		)
		(property "Value" ""
			(at 0 0 0)
			(layer "B.Fab")
			(effects
				(font
					(size 1.27 1.27)
				)
				(justify mirror)
			)
		)
		(duplicate_pad_numbers_are_jumpers no)
		(fp_line
			(start -1.524 -0.762)
			(end -1.524 0.762)
			(stroke
				(width 0.1524)
				(type default)
			)
			(layer "B.SilkS")
		)
		(fp_line
			(start -1.524 0.762)
			(end 1.524 0.762)
			(stroke
				(width 0.1524)
				(type default)
			)
			(layer "B.SilkS")
		)
		(fp_line
			(start 1.524 -0.762)
			(end -1.524 -0.762)
			(stroke
				(width 0.1524)
				(type default)
			)
			(layer "B.SilkS")
		)
		(fp_line
			(start 1.524 0.762)
			(end 1.524 -0.762)
			(stroke
				(width 0.1524)
				(type default)
			)
			(layer "B.SilkS")
		)
		(fp_line
			(start -1.1049 -0.724916)
			(end 1.1049 -0.724916)
			(stroke
				(width 0.1)
				(type default)
			)
			(layer "B.Fab")
		)
		(fp_line
			(start -1.1049 0.724916)
			(end -1.1049 -0.724916)
			(stroke
				(width 0.1)
				(type default)
			)
			(layer "B.Fab")
		)
		(fp_line
			(start 1.1049 -0.724916)
			(end 1.1049 0.724916)
			(stroke
				(width 0.1)
				(type default)
			)
			(layer "B.Fab")
		)
		(fp_line
			(start 1.1049 0.724916)
			(end -1.1049 0.724916)
			(stroke
				(width 0.1)
				(type default)
			)
			(layer "B.Fab")
		)
		(pad "1" smd rect
			(at 0.889 0)
			(size 1.016 1.27)
			(layers "B.Cu" "B.Mask" "B.Paste")
			(net "SW_P12V_P0V8_PEX2_FLT")
		)
		(pad "2" smd rect
			(at -0.889 0)
			(size 1.016 1.27)
			(layers "B.Cu" "B.Mask" "B.Paste")
			(net "GND")
		)
	)
	(footprint ""
		(layer "B.Cu")
		(at 107.671616 -88.641936 90)
		(property "Reference" "C2672"
			(at 0 0 90)
			(layer "B.SilkS")
			(hide yes)
			(effects
				(font
					(size 1.27 1.27)
				)
				(justify mirror)
			)
		)
		(property "Value" ""
			(at 0 0 90)
			(layer "B.Fab")
			(effects
				(font
					(size 1.27 1.27)
				)
				(justify mirror)
			)
		)
		(duplicate_pad_numbers_are_jumpers no)
		(fp_line
			(start 0.7874 -0.4064)
			(end -0.7874 -0.4064)
			(stroke
				(width 0.1524)
				(type default)
			)
			(layer "B.SilkS")
		)
		(fp_line
			(start -0.7874 -0.4064)
			(end -0.7874 0.4064)
			(stroke
				(width 0.1524)
				(type default)
			)
			(layer "B.SilkS")
		)
		(fp_line
			(start 0.7874 0.4064)
			(end 0.7874 -0.4064)
			(stroke
				(width 0.1524)
				(type default)
			)
			(layer "B.SilkS")
		)
		(fp_line
			(start -0.7874 0.4064)
			(end 0.7874 0.4064)
			(stroke
				(width 0.1524)
				(type default)
			)
			(layer "B.SilkS")
		)
		(fp_line
			(start 0.67945 -0.305054)
			(end 0.12065 -0.305054)
			(stroke
				(width 0.1)
				(type default)
			)
			(layer "B.Fab")
		)
		(fp_line
			(start 0.12065 -0.305054)
			(end 0.12065 -0.2794)
			(stroke
				(width 0.1)
				(type default)
			)
			(layer "B.Fab")
		)
		(fp_line
			(start -0.12065 -0.3048)
			(end -0.67945 -0.3048)
			(stroke
				(width 0.1)
				(type default)
			)
			(layer "B.Fab")
		)
		(fp_line
			(start -0.67945 -0.3048)
			(end -0.67945 0.3048)
			(stroke
				(width 0.1)
				(type default)
			)
			(layer "B.Fab")
		)
		(fp_line
			(start 0.12065 -0.2794)
			(end -0.12065 -0.2794)
			(stroke
				(width 0.1)
				(type default)
			)
			(layer "B.Fab")
		)
		(fp_line
			(start -0.12065 -0.2794)
			(end -0.12065 -0.3048)
			(stroke
				(width 0.1)
				(type default)
			)
			(layer "B.Fab")
		)
		(fp_line
			(start 0.12065 0.2794)
			(end 0.12065 0.3048)
			(stroke
				(width 0.1)
				(type default)
			)
			(layer "B.Fab")
		)
		(fp_line
			(start -0.120396 0.2794)
			(end 0.12065 0.2794)
			(stroke
				(width 0.1)
				(type default)
			)
			(layer "B.Fab")
		)
		(fp_line
			(start 0.67945 0.3048)
			(end 0.67945 -0.305054)
			(stroke
				(width 0.1)
				(type default)
			)
			(layer "B.Fab")
		)
		(fp_line
			(start 0.12065 0.3048)
			(end 0.67945 0.3048)
			(stroke
				(width 0.1)
				(type default)
			)
			(layer "B.Fab")
		)
		(fp_line
			(start -0.120396 0.3048)
			(end -0.120396 0.2794)
			(stroke
				(width 0.1)
				(type default)
			)
			(layer "B.Fab")
		)
		(fp_line
			(start -0.67945 0.3048)
			(end -0.120396 0.3048)
			(stroke
				(width 0.1)
				(type default)
			)
			(layer "B.Fab")
		)
		(pad "1" smd circle
			(at 0.40005 0 270)
			(size 0 0)
			(layers "B.Cu" "B.Mask" "B.Paste")
			(net "P3V3_VDDAR_9ZXL0851_0_7")
		)
		(pad "2" smd circle
			(at -0.40005 0 270)
			(size 0 0)
			(layers "B.Cu" "B.Mask" "B.Paste")
			(net "GND")
		)
	)
	(footprint ""
		(layer "B.Cu")
		(at 141.268196 -200.51141 90)
		(property "Reference" "C2594"
			(at 0 0 90)
			(layer "B.SilkS")
			(hide yes)
			(effects
				(font
					(size 1.27 1.27)
				)
				(justify mirror)
			)
		)
		(property "Value" ""
			(at 0 0 90)
			(layer "B.Fab")
			(effects
				(font
					(size 1.27 1.27)
				)
				(justify mirror)
			)
		)
		(duplicate_pad_numbers_are_jumpers no)
		(fp_line
			(start 0.7874 -0.4064)
			(end -0.7874 -0.4064)
			(stroke
				(width 0.1524)
				(type default)
			)
			(layer "B.SilkS")
		)
		(fp_line
			(start -0.7874 -0.4064)
			(end -0.7874 0.4064)
			(stroke
				(width 0.1524)
				(type default)
			)
			(layer "B.SilkS")
		)
		(fp_line
			(start 0.7874 0.4064)
			(end 0.7874 -0.4064)
			(stroke
				(width 0.1524)
				(type default)
			)
			(layer "B.SilkS")
		)
		(fp_line
			(start -0.7874 0.4064)
			(end 0.7874 0.4064)
			(stroke
				(width 0.1524)
				(type default)
			)
			(layer "B.SilkS")
		)
		(fp_line
			(start 0.67945 -0.305054)
			(end 0.12065 -0.305054)
			(stroke
				(width 0.1)
				(type default)
			)
			(layer "B.Fab")
		)
		(fp_line
			(start 0.12065 -0.305054)
			(end 0.12065 -0.2794)
			(stroke
				(width 0.1)
				(type default)
			)
			(layer "B.Fab")
		)
		(fp_line
			(start -0.12065 -0.3048)
			(end -0.67945 -0.3048)
			(stroke
				(width 0.1)
				(type default)
			)
			(layer "B.Fab")
		)
		(fp_line
			(start -0.67945 -0.3048)
			(end -0.67945 0.3048)
			(stroke
				(width 0.1)
				(type default)
			)
			(layer "B.Fab")
		)
		(fp_line
			(start 0.12065 -0.2794)
			(end -0.12065 -0.2794)
			(stroke
				(width 0.1)
				(type default)
			)
			(layer "B.Fab")
		)
		(fp_line
			(start -0.12065 -0.2794)
			(end -0.12065 -0.3048)
			(stroke
				(width 0.1)
				(type default)
			)
			(layer "B.Fab")
		)
		(fp_line
			(start 0.12065 0.2794)
			(end 0.12065 0.3048)
			(stroke
				(width 0.1)
				(type default)
			)
			(layer "B.Fab")
		)
		(fp_line
			(start -0.120396 0.2794)
			(end 0.12065 0.2794)
			(stroke
				(width 0.1)
				(type default)
			)
			(layer "B.Fab")
		)
		(fp_line
			(start 0.67945 0.3048)
			(end 0.67945 -0.305054)
			(stroke
				(width 0.1)
				(type default)
			)
			(layer "B.Fab")
		)
		(fp_line
			(start 0.12065 0.3048)
			(end 0.67945 0.3048)
			(stroke
				(width 0.1)
				(type default)
			)
			(layer "B.Fab")
		)
		(fp_line
			(start -0.120396 0.3048)
			(end -0.120396 0.2794)
			(stroke
				(width 0.1)
				(type default)
			)
			(layer "B.Fab")
		)
		(fp_line
			(start -0.67945 0.3048)
			(end -0.120396 0.3048)
			(stroke
				(width 0.1)
				(type default)
			)
			(layer "B.Fab")
		)
		(pad "1" smd circle
			(at 0.40005 0 270)
			(size 0 0)
			(layers "B.Cu" "B.Mask" "B.Paste")
			(net "P1V8_CLI_VCORE")
		)
		(pad "2" smd circle
			(at -0.40005 0 270)
			(size 0 0)
			(layers "B.Cu" "B.Mask" "B.Paste")
			(net "GND")
		)
	)
	(footprint ""
		(layer "B.Cu")
		(at 70.104 -97.663)
		(property "Reference" "R55"
			(at 0 0 0)
			(layer "B.SilkS")
			(hide yes)
			(effects
				(font
					(size 1.27 1.27)
				)
				(justify mirror)
			)
		)
		(property "Value" ""
			(at 0 0 0)
			(layer "B.Fab")
			(effects
				(font
					(size 1.27 1.27)
				)
				(justify mirror)
			)
		)
		(duplicate_pad_numbers_are_jumpers no)
		(fp_line
			(start -0.7874 -0.4064)
			(end -0.7874 0.4064)
			(stroke
				(width 0.1524)
				(type default)
			)
			(layer "B.SilkS")
		)
		(fp_line
			(start -0.7874 0.4064)
			(end 0.7874 0.4064)
			(stroke
				(width 0.1524)
				(type default)
			)
			(layer "B.SilkS")
		)
		(fp_line
			(start 0.7874 -0.4064)
			(end -0.7874 -0.4064)
			(stroke
				(width 0.1524)
				(type default)
			)
			(layer "B.SilkS")
		)
		(fp_line
			(start 0.7874 0.4064)
			(end 0.7874 -0.4064)
			(stroke
				(width 0.1524)
				(type default)
			)
			(layer "B.SilkS")
		)
		(fp_line
			(start -0.67945 -0.3048)
			(end -0.67945 0.3048)
			(stroke
				(width 0.1)
				(type default)
			)
			(layer "B.Fab")
		)
		(fp_line
			(start -0.67945 0.3048)
			(end -0.120396 0.3048)
			(stroke
				(width 0.1)
				(type default)
			)
			(layer "B.Fab")
		)
		(fp_line
			(start -0.12065 -0.3048)
			(end -0.67945 -0.3048)
			(stroke
				(width 0.1)
				(type default)
			)
			(layer "B.Fab")
		)
		(fp_line
			(start -0.12065 -0.2794)
			(end -0.12065 -0.3048)
			(stroke
				(width 0.1)
				(type default)
			)
			(layer "B.Fab")
		)
		(fp_line
			(start -0.120396 0.2794)
			(end 0.12065 0.2794)
			(stroke
				(width 0.1)
				(type default)
			)
			(layer "B.Fab")
		)
		(fp_line
			(start -0.120396 0.3048)
			(end -0.120396 0.2794)
			(stroke
				(width 0.1)
				(type default)
			)
			(layer "B.Fab")
		)
		(fp_line
			(start 0.12065 -0.305054)
			(end 0.12065 -0.2794)
			(stroke
				(width 0.1)
				(type default)
			)
			(layer "B.Fab")
		)
		(fp_line
			(start 0.12065 -0.2794)
			(end -0.12065 -0.2794)
			(stroke
				(width 0.1)
				(type default)
			)
			(layer "B.Fab")
		)
		(fp_line
			(start 0.12065 0.2794)
			(end 0.12065 0.3048)
			(stroke
				(width 0.1)
				(type default)
			)
			(layer "B.Fab")
		)
		(fp_line
			(start 0.12065 0.3048)
			(end 0.67945 0.3048)
			(stroke
				(width 0.1)
				(type default)
			)
			(layer "B.Fab")
		)
		(fp_line
			(start 0.67945 -0.305054)
			(end 0.12065 -0.305054)
			(stroke
				(width 0.1)
				(type default)
			)
			(layer "B.Fab")
		)
		(fp_line
			(start 0.67945 0.3048)
			(end 0.67945 -0.305054)
			(stroke
				(width 0.1)
				(type default)
			)
			(layer "B.Fab")
		)
		(pad "1" smd circle
			(at 0.40005 0 180)
			(size 0 0)
			(layers "B.Cu" "B.Mask" "B.Paste")
			(net "PWRGD_NIC1_PWR_GOOD")
		)
		(pad "2" smd circle
			(at -0.40005 0 180)
			(size 0 0)
			(layers "B.Cu" "B.Mask" "B.Paste")
			(net "PWRGD_NIC1_PWR_GOOD_R")
		)
	)
	(footprint ""
		(layer "B.Cu")
		(at 75.72375 -291.624766 90)
		(property "Reference" "R984"
			(at 0 0 90)
			(layer "B.SilkS")
			(hide yes)
			(effects
				(font
					(size 1.27 1.27)
				)
				(justify mirror)
			)
		)
		(property "Value" ""
			(at 0 0 90)
			(layer "B.Fab")
			(effects
				(font
					(size 1.27 1.27)
				)
				(justify mirror)
			)
		)
		(duplicate_pad_numbers_are_jumpers no)
		(fp_line
			(start 0.7874 -0.4064)
			(end -0.7874 -0.4064)
			(stroke
				(width 0.1524)
				(type default)
			)
			(layer "B.SilkS")
		)
		(fp_line
			(start -0.7874 -0.4064)
			(end -0.7874 0.4064)
			(stroke
				(width 0.1524)
				(type default)
			)
			(layer "B.SilkS")
		)
		(fp_line
			(start 0.7874 0.4064)
			(end 0.7874 -0.4064)
			(stroke
				(width 0.1524)
				(type default)
			)
			(layer "B.SilkS")
		)
		(fp_line
			(start -0.7874 0.4064)
			(end 0.7874 0.4064)
			(stroke
				(width 0.1524)
				(type default)
			)
			(layer "B.SilkS")
		)
		(fp_line
			(start 0.67945 -0.305054)
			(end 0.12065 -0.305054)
			(stroke
				(width 0.1)
				(type default)
			)
			(layer "B.Fab")
		)
		(fp_line
			(start 0.12065 -0.305054)
			(end 0.12065 -0.2794)
			(stroke
				(width 0.1)
				(type default)
			)
			(layer "B.Fab")
		)
		(fp_line
			(start -0.12065 -0.3048)
			(end -0.67945 -0.3048)
			(stroke
				(width 0.1)
				(type default)
			)
			(layer "B.Fab")
		)
		(fp_line
			(start -0.67945 -0.3048)
			(end -0.67945 0.3048)
			(stroke
				(width 0.1)
				(type default)
			)
			(layer "B.Fab")
		)
		(fp_line
			(start 0.12065 -0.2794)
			(end -0.12065 -0.2794)
			(stroke
				(width 0.1)
				(type default)
			)
			(layer "B.Fab")
		)
		(fp_line
			(start -0.12065 -0.2794)
			(end -0.12065 -0.3048)
			(stroke
				(width 0.1)
				(type default)
			)
			(layer "B.Fab")
		)
		(fp_line
			(start 0.12065 0.2794)
			(end 0.12065 0.3048)
			(stroke
				(width 0.1)
				(type default)
			)
			(layer "B.Fab")
		)
		(fp_line
			(start -0.120396 0.2794)
			(end 0.12065 0.2794)
			(stroke
				(width 0.1)
				(type default)
			)
			(layer "B.Fab")
		)
		(fp_line
			(start 0.67945 0.3048)
			(end 0.67945 -0.305054)
			(stroke
				(width 0.1)
				(type default)
			)
			(layer "B.Fab")
		)
		(fp_line
			(start 0.12065 0.3048)
			(end 0.67945 0.3048)
			(stroke
				(width 0.1)
				(type default)
			)
			(layer "B.Fab")
		)
		(fp_line
			(start -0.120396 0.3048)
			(end -0.120396 0.2794)
			(stroke
				(width 0.1)
				(type default)
			)
			(layer "B.Fab")
		)
		(fp_line
			(start -0.67945 0.3048)
			(end -0.120396 0.3048)
			(stroke
				(width 0.1)
				(type default)
			)
			(layer "B.Fab")
		)
		(pad "1" smd circle
			(at 0.40005 0 270)
			(size 0 0)
			(layers "B.Cu" "B.Mask" "B.Paste")
			(net "UART_PEX0_CLI_TX")
		)
		(pad "2" smd circle
			(at -0.40005 0 270)
			(size 0 0)
			(layers "B.Cu" "B.Mask" "B.Paste")
			(net "UART_PEX0_CLI_R_TX")
		)
	)
	(footprint ""
		(layer "B.Cu")
		(at 171.020232 -296.37482)
		(property "Reference" "C1366"
			(at 0 0 0)
			(layer "B.SilkS")
			(hide yes)
			(effects
				(font
					(size 1.27 1.27)
				)
				(justify mirror)
			)
		)
		(property "Value" ""
			(at 0 0 0)
			(layer "B.Fab")
			(effects
				(font
					(size 1.27 1.27)
				)
				(justify mirror)
			)
		)
		(duplicate_pad_numbers_are_jumpers no)
		(fp_line
			(start -0.299974 -0.150114)
			(end -0.299974 0.150114)
			(stroke
				(width 0.1)
				(type default)
			)
			(layer "B.Fab")
		)
		(fp_line
			(start -0.299974 0.150114)
			(end 0.299974 0.150114)
			(stroke
				(width 0.1)
				(type default)
			)
			(layer "B.Fab")
		)
		(fp_line
			(start 0.299974 -0.150114)
			(end -0.299974 -0.150114)
			(stroke
				(width 0.1)
				(type default)
			)
			(layer "B.Fab")
		)
		(fp_line
			(start 0.299974 0.150114)
			(end 0.299974 -0.150114)
			(stroke
				(width 0.1)
				(type default)
			)
			(layer "B.Fab")
		)
		(pad "1" smd rect
			(at 0.2667 0 180)
			(size 0.3048 0.381)
			(layers "B.Cu" "B.Mask" "B.Paste")
			(net "P0V8_PEX1")
		)
		(pad "2" smd rect
			(at -0.2667 0 180)
			(size 0.3048 0.381)
			(layers "B.Cu" "B.Mask" "B.Paste")
			(net "GND")
		)
	)
	(footprint ""
		(layer "B.Cu")
		(at 60.158376 -286.399732 90)
		(property "Reference" "C2959"
			(at 0 0 90)
			(layer "B.SilkS")
			(hide yes)
			(effects
				(font
					(size 1.27 1.27)
				)
				(justify mirror)
			)
		)
		(property "Value" ""
			(at 0 0 90)
			(layer "B.Fab")
			(effects
				(font
					(size 1.27 1.27)
				)
				(justify mirror)
			)
		)
		(duplicate_pad_numbers_are_jumpers no)
		(fp_line
			(start 0.299974 -0.150114)
			(end -0.299974 -0.150114)
			(stroke
				(width 0.1)
				(type default)
			)
			(layer "B.Fab")
		)
		(fp_line
			(start -0.299974 -0.150114)
			(end -0.299974 0.150114)
			(stroke
				(width 0.1)
				(type default)
			)
			(layer "B.Fab")
		)
		(fp_line
			(start 0.299974 0.150114)
			(end 0.299974 -0.150114)
			(stroke
				(width 0.1)
				(type default)
			)
			(layer "B.Fab")
		)
		(fp_line
			(start -0.299974 0.150114)
			(end 0.299974 0.150114)
			(stroke
				(width 0.1)
				(type default)
			)
			(layer "B.Fab")
		)
		(pad "1" smd rect
			(at 0.2667 0 270)
			(size 0.3048 0.381)
			(layers "B.Cu" "B.Mask" "B.Paste")
			(net "P1V25_SERDES_VDDPLL_PEX0")
		)
		(pad "2" smd rect
			(at -0.2667 0 270)
			(size 0.3048 0.381)
			(layers "B.Cu" "B.Mask" "B.Paste")
			(net "GND")
		)
	)
	(footprint ""
		(layer "B.Cu")
		(at 171.949872 -288.299906 90)
		(property "Reference" "C3101"
			(at 0 0 90)
			(layer "B.SilkS")
			(hide yes)
			(effects
				(font
					(size 1.27 1.27)
				)
				(justify mirror)
			)
		)
		(property "Value" ""
			(at 0 0 90)
			(layer "B.Fab")
			(effects
				(font
					(size 1.27 1.27)
				)
				(justify mirror)
			)
		)
		(duplicate_pad_numbers_are_jumpers no)
		(fp_line
			(start 0.299974 -0.150114)
			(end -0.299974 -0.150114)
			(stroke
				(width 0.1)
				(type default)
			)
			(layer "B.Fab")
		)
		(fp_line
			(start -0.299974 -0.150114)
			(end -0.299974 0.150114)
			(stroke
				(width 0.1)
				(type default)
			)
			(layer "B.Fab")
		)
		(fp_line
			(start 0.299974 0.150114)
			(end 0.299974 -0.150114)
			(stroke
				(width 0.1)
				(type default)
			)
			(layer "B.Fab")
		)
		(fp_line
			(start -0.299974 0.150114)
			(end 0.299974 0.150114)
			(stroke
				(width 0.1)
				(type default)
			)
			(layer "B.Fab")
		)
		(pad "1" smd rect
			(at 0.2667 0 270)
			(size 0.3048 0.381)
			(layers "B.Cu" "B.Mask" "B.Paste")
			(net "P1V25_PEX1")
		)
		(pad "2" smd rect
			(at -0.2667 0 270)
			(size 0.3048 0.381)
			(layers "B.Cu" "B.Mask" "B.Paste")
			(net "GND")
		)
	)
	(footprint ""
		(layer "B.Cu")
		(at 409.849828 -292.099746 90)
		(property "Reference" "C1963"
			(at 0 0 90)
			(layer "B.SilkS")
			(hide yes)
			(effects
				(font
					(size 1.27 1.27)
				)
				(justify mirror)
			)
		)
		(property "Value" ""
			(at 0 0 90)
			(layer "B.Fab")
			(effects
				(font
					(size 1.27 1.27)
				)
				(justify mirror)
			)
		)
		(duplicate_pad_numbers_are_jumpers no)
		(fp_line
			(start 0.299974 -0.150114)
			(end -0.299974 -0.150114)
			(stroke
				(width 0.1)
				(type default)
			)
			(layer "B.Fab")
		)
		(fp_line
			(start -0.299974 -0.150114)
			(end -0.299974 0.150114)
			(stroke
				(width 0.1)
				(type default)
			)
			(layer "B.Fab")
		)
		(fp_line
			(start 0.299974 0.150114)
			(end 0.299974 -0.150114)
			(stroke
				(width 0.1)
				(type default)
			)
			(layer "B.Fab")
		)
		(fp_line
			(start -0.299974 0.150114)
			(end 0.299974 0.150114)
			(stroke
				(width 0.1)
				(type default)
			)
			(layer "B.Fab")
		)
		(pad "1" smd rect
			(at 0.2667 0 270)
			(size 0.3048 0.381)
			(layers "B.Cu" "B.Mask" "B.Paste")
			(net "P0V8_SERDES_VDDA_PEX3")
		)
		(pad "2" smd rect
			(at -0.2667 0 270)
			(size 0.3048 0.381)
			(layers "B.Cu" "B.Mask" "B.Paste")
			(net "GND")
		)
	)
	(footprint ""
		(layer "B.Cu")
		(at 203.217018 -244.609112 90)
		(property "Reference" "C4007"
			(at 0 0 90)
			(layer "B.SilkS")
			(hide yes)
			(effects
				(font
					(size 1.27 1.27)
				)
				(justify mirror)
			)
		)
		(property "Value" ""
			(at 0 0 90)
			(layer "B.Fab")
			(effects
				(font
					(size 1.27 1.27)
				)
				(justify mirror)
			)
		)
		(duplicate_pad_numbers_are_jumpers no)
		(fp_line
			(start 0.7874 -0.4064)
			(end -0.7874 -0.4064)
			(stroke
				(width 0.1524)
				(type default)
			)
			(layer "B.SilkS")
		)
		(fp_line
			(start -0.7874 -0.4064)
			(end -0.7874 0.4064)
			(stroke
				(width 0.1524)
				(type default)
			)
			(layer "B.SilkS")
		)
		(fp_line
			(start 0.7874 0.4064)
			(end 0.7874 -0.4064)
			(stroke
				(width 0.1524)
				(type default)
			)
			(layer "B.SilkS")
		)
		(fp_line
			(start -0.7874 0.4064)
			(end 0.7874 0.4064)
			(stroke
				(width 0.1524)
				(type default)
			)
			(layer "B.SilkS")
		)
		(fp_line
			(start 0.67945 -0.305054)
			(end 0.12065 -0.305054)
			(stroke
				(width 0.1)
				(type default)
			)
			(layer "B.Fab")
		)
		(fp_line
			(start 0.12065 -0.305054)
			(end 0.12065 -0.2794)
			(stroke
				(width 0.1)
				(type default)
			)
			(layer "B.Fab")
		)
		(fp_line
			(start -0.12065 -0.3048)
			(end -0.67945 -0.3048)
			(stroke
				(width 0.1)
				(type default)
			)
			(layer "B.Fab")
		)
		(fp_line
			(start -0.67945 -0.3048)
			(end -0.67945 0.3048)
			(stroke
				(width 0.1)
				(type default)
			)
			(layer "B.Fab")
		)
		(fp_line
			(start 0.12065 -0.2794)
			(end -0.12065 -0.2794)
			(stroke
				(width 0.1)
				(type default)
			)
			(layer "B.Fab")
		)
		(fp_line
			(start -0.12065 -0.2794)
			(end -0.12065 -0.3048)
			(stroke
				(width 0.1)
				(type default)
			)
			(layer "B.Fab")
		)
		(fp_line
			(start 0.12065 0.2794)
			(end 0.12065 0.3048)
			(stroke
				(width 0.1)
				(type default)
			)
			(layer "B.Fab")
		)
		(fp_line
			(start -0.120396 0.2794)
			(end 0.12065 0.2794)
			(stroke
				(width 0.1)
				(type default)
			)
			(layer "B.Fab")
		)
		(fp_line
			(start 0.67945 0.3048)
			(end 0.67945 -0.305054)
			(stroke
				(width 0.1)
				(type default)
			)
			(layer "B.Fab")
		)
		(fp_line
			(start 0.12065 0.3048)
			(end 0.67945 0.3048)
			(stroke
				(width 0.1)
				(type default)
			)
			(layer "B.Fab")
		)
		(fp_line
			(start -0.120396 0.3048)
			(end -0.120396 0.2794)
			(stroke
				(width 0.1)
				(type default)
			)
			(layer "B.Fab")
		)
		(fp_line
			(start -0.67945 0.3048)
			(end -0.120396 0.3048)
			(stroke
				(width 0.1)
				(type default)
			)
			(layer "B.Fab")
		)
		(pad "1" smd circle
			(at 0.40005 0 270)
			(size 0 0)
			(layers "B.Cu" "B.Mask" "B.Paste")
			(net "P1V8_PEX")
		)
		(pad "2" smd circle
			(at -0.40005 0 270)
			(size 0 0)
			(layers "B.Cu" "B.Mask" "B.Paste")
			(net "GND")
		)
	)
	(footprint ""
		(layer "B.Cu")
		(at 410.799788 -290.199826 90)
		(property "Reference" "C1965"
			(at 0 0 90)
			(layer "B.SilkS")
			(hide yes)
			(effects
				(font
					(size 1.27 1.27)
				)
				(justify mirror)
			)
		)
		(property "Value" ""
			(at 0 0 90)
			(layer "B.Fab")
			(effects
				(font
					(size 1.27 1.27)
				)
				(justify mirror)
			)
		)
		(duplicate_pad_numbers_are_jumpers no)
		(fp_line
			(start 0.299974 -0.150114)
			(end -0.299974 -0.150114)
			(stroke
				(width 0.1)
				(type default)
			)
			(layer "B.Fab")
		)
		(fp_line
			(start -0.299974 -0.150114)
			(end -0.299974 0.150114)
			(stroke
				(width 0.1)
				(type default)
			)
			(layer "B.Fab")
		)
		(fp_line
			(start 0.299974 0.150114)
			(end 0.299974 -0.150114)
			(stroke
				(width 0.1)
				(type default)
			)
			(layer "B.Fab")
		)
		(fp_line
			(start -0.299974 0.150114)
			(end 0.299974 0.150114)
			(stroke
				(width 0.1)
				(type default)
			)
			(layer "B.Fab")
		)
		(pad "1" smd rect
			(at 0.2667 0 270)
			(size 0.3048 0.381)
			(layers "B.Cu" "B.Mask" "B.Paste")
			(net "P0V8_SERDES_VDDA_PEX3")
		)
		(pad "2" smd rect
			(at -0.2667 0 270)
			(size 0.3048 0.381)
			(layers "B.Cu" "B.Mask" "B.Paste")
			(net "GND")
		)
	)
	(footprint ""
		(layer "B.Cu")
		(at 71.049896 -298.27474 180)
		(property "Reference" "C2925"
			(at 0 0 0)
			(layer "B.SilkS")
			(hide yes)
			(effects
				(font
					(size 1.27 1.27)
				)
				(justify mirror)
			)
		)
		(property "Value" ""
			(at 0 0 0)
			(layer "B.Fab")
			(effects
				(font
					(size 1.27 1.27)
				)
				(justify mirror)
			)
		)
		(duplicate_pad_numbers_are_jumpers no)
		(fp_line
			(start 0.299974 0.150114)
			(end 0.299974 -0.150114)
			(stroke
				(width 0.1)
				(type default)
			)
			(layer "B.Fab")
		)
		(fp_line
			(start 0.299974 -0.150114)
			(end -0.299974 -0.150114)
			(stroke
				(width 0.1)
				(type default)
			)
			(layer "B.Fab")
		)
		(fp_line
			(start -0.299974 0.150114)
			(end 0.299974 0.150114)
			(stroke
				(width 0.1)
				(type default)
			)
			(layer "B.Fab")
		)
		(fp_line
			(start -0.299974 -0.150114)
			(end -0.299974 0.150114)
			(stroke
				(width 0.1)
				(type default)
			)
			(layer "B.Fab")
		)
		(pad "1" smd rect
			(at 0.2667 0)
			(size 0.3048 0.381)
			(layers "B.Cu" "B.Mask" "B.Paste")
			(net "P1V25_PEX0")
		)
		(pad "2" smd rect
			(at -0.2667 0)
			(size 0.3048 0.381)
			(layers "B.Cu" "B.Mask" "B.Paste")
			(net "GND")
		)
	)
	(footprint ""
		(layer "B.Cu")
		(at 235.14177 -212.332824 90)
		(property "Reference" "C195"
			(at 0 0 90)
			(layer "B.SilkS")
			(hide yes)
			(effects
				(font
					(size 1.27 1.27)
				)
				(justify mirror)
			)
		)
		(property "Value" ""
			(at 0 0 90)
			(layer "B.Fab")
			(effects
				(font
					(size 1.27 1.27)
				)
				(justify mirror)
			)
		)
		(duplicate_pad_numbers_are_jumpers no)
		(fp_line
			(start 0.7874 -0.4064)
			(end -0.7874 -0.4064)
			(stroke
				(width 0.1524)
				(type default)
			)
			(layer "B.SilkS")
		)
		(fp_line
			(start -0.7874 -0.4064)
			(end -0.7874 0.4064)
			(stroke
				(width 0.1524)
				(type default)
			)
			(layer "B.SilkS")
		)
		(fp_line
			(start 0.7874 0.4064)
			(end 0.7874 -0.4064)
			(stroke
				(width 0.1524)
				(type default)
			)
			(layer "B.SilkS")
		)
		(fp_line
			(start -0.7874 0.4064)
			(end 0.7874 0.4064)
			(stroke
				(width 0.1524)
				(type default)
			)
			(layer "B.SilkS")
		)
		(fp_line
			(start 0.67945 -0.305054)
			(end 0.12065 -0.305054)
			(stroke
				(width 0.1)
				(type default)
			)
			(layer "B.Fab")
		)
		(fp_line
			(start 0.12065 -0.305054)
			(end 0.12065 -0.2794)
			(stroke
				(width 0.1)
				(type default)
			)
			(layer "B.Fab")
		)
		(fp_line
			(start -0.12065 -0.3048)
			(end -0.67945 -0.3048)
			(stroke
				(width 0.1)
				(type default)
			)
			(layer "B.Fab")
		)
		(fp_line
			(start -0.67945 -0.3048)
			(end -0.67945 0.3048)
			(stroke
				(width 0.1)
				(type default)
			)
			(layer "B.Fab")
		)
		(fp_line
			(start 0.12065 -0.2794)
			(end -0.12065 -0.2794)
			(stroke
				(width 0.1)
				(type default)
			)
			(layer "B.Fab")
		)
		(fp_line
			(start -0.12065 -0.2794)
			(end -0.12065 -0.3048)
			(stroke
				(width 0.1)
				(type default)
			)
			(layer "B.Fab")
		)
		(fp_line
			(start 0.12065 0.2794)
			(end 0.12065 0.3048)
			(stroke
				(width 0.1)
				(type default)
			)
			(layer "B.Fab")
		)
		(fp_line
			(start -0.120396 0.2794)
			(end 0.12065 0.2794)
			(stroke
				(width 0.1)
				(type default)
			)
			(layer "B.Fab")
		)
		(fp_line
			(start 0.67945 0.3048)
			(end 0.67945 -0.305054)
			(stroke
				(width 0.1)
				(type default)
			)
			(layer "B.Fab")
		)
		(fp_line
			(start 0.12065 0.3048)
			(end 0.67945 0.3048)
			(stroke
				(width 0.1)
				(type default)
			)
			(layer "B.Fab")
		)
		(fp_line
			(start -0.120396 0.3048)
			(end -0.120396 0.2794)
			(stroke
				(width 0.1)
				(type default)
			)
			(layer "B.Fab")
		)
		(fp_line
			(start -0.67945 0.3048)
			(end -0.120396 0.3048)
			(stroke
				(width 0.1)
				(type default)
			)
			(layer "B.Fab")
		)
		(pad "1" smd circle
			(at 0.40005 0 270)
			(size 0 0)
			(layers "B.Cu" "B.Mask" "B.Paste")
			(net "P1V2_AUX_SCALED")
		)
		(pad "2" smd circle
			(at -0.40005 0 270)
			(size 0 0)
			(layers "B.Cu" "B.Mask" "B.Paste")
			(net "GND")
		)
	)
	(footprint ""
		(layer "B.Cu")
		(at 182.39994 -288.299906 90)
		(property "Reference" "C3106"
			(at 0 0 90)
			(layer "B.SilkS")
			(hide yes)
			(effects
				(font
					(size 1.27 1.27)
				)
				(justify mirror)
			)
		)
		(property "Value" ""
			(at 0 0 90)
			(layer "B.Fab")
			(effects
				(font
					(size 1.27 1.27)
				)
				(justify mirror)
			)
		)
		(duplicate_pad_numbers_are_jumpers no)
		(fp_line
			(start 0.299974 -0.150114)
			(end -0.299974 -0.150114)
			(stroke
				(width 0.1)
				(type default)
			)
			(layer "B.Fab")
		)
		(fp_line
			(start -0.299974 -0.150114)
			(end -0.299974 0.150114)
			(stroke
				(width 0.1)
				(type default)
			)
			(layer "B.Fab")
		)
		(fp_line
			(start 0.299974 0.150114)
			(end 0.299974 -0.150114)
			(stroke
				(width 0.1)
				(type default)
			)
			(layer "B.Fab")
		)
		(fp_line
			(start -0.299974 0.150114)
			(end 0.299974 0.150114)
			(stroke
				(width 0.1)
				(type default)
			)
			(layer "B.Fab")
		)
		(pad "1" smd rect
			(at 0.2667 0 270)
			(size 0.3048 0.381)
			(layers "B.Cu" "B.Mask" "B.Paste")
			(net "P1V25_PEX1")
		)
		(pad "2" smd rect
			(at -0.2667 0 270)
			(size 0.3048 0.381)
			(layers "B.Cu" "B.Mask" "B.Paste")
			(net "GND")
		)
	)
	(footprint ""
		(layer "B.Cu")
		(at 177.174906 -286.399732 90)
		(property "Reference" "C3131"
			(at 0 0 90)
			(layer "B.SilkS")
			(hide yes)
			(effects
				(font
					(size 1.27 1.27)
				)
				(justify mirror)
			)
		)
		(property "Value" ""
			(at 0 0 90)
			(layer "B.Fab")
			(effects
				(font
					(size 1.27 1.27)
				)
				(justify mirror)
			)
		)
		(duplicate_pad_numbers_are_jumpers no)
		(fp_line
			(start 0.299974 -0.150114)
			(end -0.299974 -0.150114)
			(stroke
				(width 0.1)
				(type default)
			)
			(layer "B.Fab")
		)
		(fp_line
			(start -0.299974 -0.150114)
			(end -0.299974 0.150114)
			(stroke
				(width 0.1)
				(type default)
			)
			(layer "B.Fab")
		)
		(fp_line
			(start 0.299974 0.150114)
			(end 0.299974 -0.150114)
			(stroke
				(width 0.1)
				(type default)
			)
			(layer "B.Fab")
		)
		(fp_line
			(start -0.299974 0.150114)
			(end 0.299974 0.150114)
			(stroke
				(width 0.1)
				(type default)
			)
			(layer "B.Fab")
		)
		(pad "1" smd rect
			(at 0.2667 0 270)
			(size 0.3048 0.381)
			(layers "B.Cu" "B.Mask" "B.Paste")
			(net "P1V25_SERDES_VDDPLL_PEX1")
		)
		(pad "2" smd rect
			(at -0.2667 0 270)
			(size 0.3048 0.381)
			(layers "B.Cu" "B.Mask" "B.Paste")
			(net "GND")
		)
	)
	(footprint ""
		(layer "B.Cu")
		(at 324.612 -83.947 180)
		(property "Reference" "R6264"
			(at 0 0 0)
			(layer "B.SilkS")
			(hide yes)
			(effects
				(font
					(size 1.27 1.27)
				)
				(justify mirror)
			)
		)
		(property "Value" ""
			(at 0 0 0)
			(layer "B.Fab")
			(effects
				(font
					(size 1.27 1.27)
				)
				(justify mirror)
			)
		)
		(duplicate_pad_numbers_are_jumpers no)
		(fp_line
			(start 0.7874 0.4064)
			(end 0.7874 -0.4064)
			(stroke
				(width 0.1524)
				(type default)
			)
			(layer "B.SilkS")
		)
		(fp_line
			(start 0.7874 -0.4064)
			(end -0.7874 -0.4064)
			(stroke
				(width 0.1524)
				(type default)
			)
			(layer "B.SilkS")
		)
		(fp_line
			(start -0.7874 0.4064)
			(end 0.7874 0.4064)
			(stroke
				(width 0.1524)
				(type default)
			)
			(layer "B.SilkS")
		)
		(fp_line
			(start -0.7874 -0.4064)
			(end -0.7874 0.4064)
			(stroke
				(width 0.1524)
				(type default)
			)
			(layer "B.SilkS")
		)
		(fp_line
			(start 0.67945 0.3048)
			(end 0.67945 -0.305054)
			(stroke
				(width 0.1)
				(type default)
			)
			(layer "B.Fab")
		)
		(fp_line
			(start 0.67945 -0.305054)
			(end 0.12065 -0.305054)
			(stroke
				(width 0.1)
				(type default)
			)
			(layer "B.Fab")
		)
		(fp_line
			(start 0.12065 0.3048)
			(end 0.67945 0.3048)
			(stroke
				(width 0.1)
				(type default)
			)
			(layer "B.Fab")
		)
		(fp_line
			(start 0.12065 0.2794)
			(end 0.12065 0.3048)
			(stroke
				(width 0.1)
				(type default)
			)
			(layer "B.Fab")
		)
		(fp_line
			(start 0.12065 -0.2794)
			(end -0.12065 -0.2794)
			(stroke
				(width 0.1)
				(type default)
			)
			(layer "B.Fab")
		)
		(fp_line
			(start 0.12065 -0.305054)
			(end 0.12065 -0.2794)
			(stroke
				(width 0.1)
				(type default)
			)
			(layer "B.Fab")
		)
		(fp_line
			(start -0.120396 0.3048)
			(end -0.120396 0.2794)
			(stroke
				(width 0.1)
				(type default)
			)
			(layer "B.Fab")
		)
		(fp_line
			(start -0.120396 0.2794)
			(end 0.12065 0.2794)
			(stroke
				(width 0.1)
				(type default)
			)
			(layer "B.Fab")
		)
		(fp_line
			(start -0.12065 -0.2794)
			(end -0.12065 -0.3048)
			(stroke
				(width 0.1)
				(type default)
			)
			(layer "B.Fab")
		)
		(fp_line
			(start -0.12065 -0.3048)
			(end -0.67945 -0.3048)
			(stroke
				(width 0.1)
				(type default)
			)
			(layer "B.Fab")
		)
		(fp_line
			(start -0.67945 0.3048)
			(end -0.120396 0.3048)
			(stroke
				(width 0.1)
				(type default)
			)
			(layer "B.Fab")
		)
		(fp_line
			(start -0.67945 -0.3048)
			(end -0.67945 0.3048)
			(stroke
				(width 0.1)
				(type default)
			)
			(layer "B.Fab")
		)
		(pad "1" smd circle
			(at 0.40005 0)
			(size 0 0)
			(layers "B.Cu" "B.Mask" "B.Paste")
			(net "SMB_BIC_I2C6_MUX_FRU_R_SCL")
		)
		(pad "2" smd circle
			(at -0.40005 0)
			(size 0 0)
			(layers "B.Cu" "B.Mask" "B.Paste")
			(net "SMB_ISO_CB_SCL")
		)
	)
	(footprint ""
		(layer "B.Cu")
		(at 176.258474 -286.399732 90)
		(property "Reference" "C3130"
			(at 0 0 90)
			(layer "B.SilkS")
			(hide yes)
			(effects
				(font
					(size 1.27 1.27)
				)
				(justify mirror)
			)
		)
		(property "Value" ""
			(at 0 0 90)
			(layer "B.Fab")
			(effects
				(font
					(size 1.27 1.27)
				)
				(justify mirror)
			)
		)
		(duplicate_pad_numbers_are_jumpers no)
		(fp_line
			(start 0.299974 -0.150114)
			(end -0.299974 -0.150114)
			(stroke
				(width 0.1)
				(type default)
			)
			(layer "B.Fab")
		)
		(fp_line
			(start -0.299974 -0.150114)
			(end -0.299974 0.150114)
			(stroke
				(width 0.1)
				(type default)
			)
			(layer "B.Fab")
		)
		(fp_line
			(start 0.299974 0.150114)
			(end 0.299974 -0.150114)
			(stroke
				(width 0.1)
				(type default)
			)
			(layer "B.Fab")
		)
		(fp_line
			(start -0.299974 0.150114)
			(end 0.299974 0.150114)
			(stroke
				(width 0.1)
				(type default)
			)
			(layer "B.Fab")
		)
		(pad "1" smd rect
			(at 0.2667 0 270)
			(size 0.3048 0.381)
			(layers "B.Cu" "B.Mask" "B.Paste")
			(net "P1V25_SERDES_VDDPLL_PEX1")
		)
		(pad "2" smd rect
			(at -0.2667 0 270)
			(size 0.3048 0.381)
			(layers "B.Cu" "B.Mask" "B.Paste")
			(net "GND")
		)
	)
	(footprint ""
		(layer "B.Cu")
		(at 213.806024 18.035524 180)
		(property "Reference" "DE02F_1"
			(at 3.6068 -2.962148 180)
			(unlocked yes)
			(layer "B.SilkS")
			(effects
				(font
					(size 0.7874 0.5842)
					(thickness 0.1524)
				)
				(justify left mirror)
			)
		)
		(property "Value" ""
			(at 0 0 0)
			(layer "B.Fab")
			(effects
				(font
					(size 1.27 1.27)
				)
				(justify mirror)
			)
		)
		(duplicate_pad_numbers_are_jumpers no)
		(fp_line
			(start 1.2192 2.1082)
			(end 1.2192 -2.1082)
			(stroke
				(width 0.1524)
				(type default)
			)
			(layer "B.SilkS")
		)
		(fp_line
			(start 1.2192 -2.1082)
			(end -1.2192 -2.1082)
			(stroke
				(width 0.1524)
				(type default)
			)
			(layer "B.SilkS")
		)
		(fp_line
			(start -1.2192 2.1082)
			(end 1.2192 2.1082)
			(stroke
				(width 0.1524)
				(type default)
			)
			(layer "B.SilkS")
		)
		(fp_line
			(start -1.2192 -2.1082)
			(end -1.2192 2.1082)
			(stroke
				(width 0.1524)
				(type default)
			)
			(layer "B.SilkS")
		)
		(pad "" np_thru_hole circle
			(at -3.4671 -1.27 90)
			(size 1.0414 1.0414)
			(drill 1.0414)
			(layers "*.Cu" "*.Mask")
			(clearance 0.381)
			(thermal_gap 0.381)
		)
		(pad "" np_thru_hole circle
			(at -3.4671 1.27 90)
			(size 1.0414 1.0414)
			(drill 1.0414)
			(layers "*.Cu" "*.Mask")
			(clearance 0.381)
			(thermal_gap 0.381)
		)
		(pad "" np_thru_hole circle
			(at 2.8829 -1.27 90)
			(size 1.0414 1.0414)
			(drill 1.0414)
			(layers "*.Cu" "*.Mask")
			(clearance 0.381)
			(thermal_gap 0.381)
		)
		(pad "" np_thru_hole circle
			(at 2.8829 1.27 90)
			(size 1.0414 1.0414)
			(drill 1.0414)
			(layers "*.Cu" "*.Mask")
			(clearance 0.381)
			(thermal_gap 0.381)
		)
		(pad "1" smd rect
			(at -0.8255 -0.249936 90)
			(size 0.3048 0.508)
			(layers "B.Cu" "B.Mask" "B.Paste")
			(net "85_5INCH_BOTTOM_DN")
		)
		(pad "2" smd rect
			(at -0.8255 0.249936 90)
			(size 0.3048 0.508)
			(layers "B.Cu" "B.Mask" "B.Paste")
			(net "85_5INCH_BOTTOM_DP")
		)
		(pad "3" smd circle
			(at 0 0)
			(size 0 0)
			(layers "B.Cu" "B.Mask" "B.Paste")
			(net "COUPON_GND2")
		)
		(zone
			(layers "F.Cu" "B.Cu" "In1.Cu" "In2.Cu" "In3.Cu" "In4.Cu" "In5.Cu" "In6.Cu"
				"In7.Cu" "In8.Cu" "In9.Cu" "In10.Cu" "In11.Cu" "In12.Cu" "In13.Cu" "In14.Cu"
				"In15.Cu" "In16.Cu"
			)
			(hatch none 0.5)
			(connect_pads
				(clearance 0)
			)
			(min_thickness 0.25)
			(keepout
				(tracks not_allowed)
				(vias allowed)
				(pads allowed)
				(copperpour not_allowed)
				(footprints allowed)
			)
			(placement
				(enabled no)
				(sheetname "")
			)
			(fill
				(thermal_gap 0.5)
				(thermal_bridge_width 0.5)
				(island_removal_mode 0)
			)
			(polygon
				(pts
					(arc
						(start 211.850224 16.765524)
						(mid 209.996024 16.765524)
						(end 211.850224 16.765524)
					)
				)
			)
		)
		(zone
			(layers "F.Cu" "B.Cu" "In1.Cu" "In2.Cu" "In3.Cu" "In4.Cu" "In5.Cu" "In6.Cu"
				"In7.Cu" "In8.Cu" "In9.Cu" "In10.Cu" "In11.Cu" "In12.Cu" "In13.Cu" "In14.Cu"
				"In15.Cu" "In16.Cu"
			)
			(hatch none 0.5)
			(connect_pads
				(clearance 0)
			)
			(min_thickness 0.25)
			(keepout
				(tracks not_allowed)
				(vias allowed)
				(pads allowed)
				(copperpour not_allowed)
				(footprints allowed)
			)
			(placement
				(enabled no)
				(sheetname "")
			)
			(fill
				(thermal_gap 0.5)
				(thermal_bridge_width 0.5)
				(island_removal_mode 0)
			)
			(polygon
				(pts
					(arc
						(start 211.850224 19.305524)
						(mid 209.996024 19.305524)
						(end 211.850224 19.305524)
					)
				)
			)
		)
		(zone
			(layers "F.Cu" "B.Cu" "In1.Cu" "In2.Cu" "In3.Cu" "In4.Cu" "In5.Cu" "In6.Cu"
				"In7.Cu" "In8.Cu" "In9.Cu" "In10.Cu" "In11.Cu" "In12.Cu" "In13.Cu" "In14.Cu"
				"In15.Cu" "In16.Cu"
			)
			(hatch none 0.5)
			(connect_pads
				(clearance 0)
			)
			(min_thickness 0.25)
			(keepout
				(tracks not_allowed)
				(vias allowed)
				(pads allowed)
				(copperpour not_allowed)
				(footprints allowed)
			)
			(placement
				(enabled no)
				(sheetname "")
			)
			(fill
				(thermal_gap 0.5)
				(thermal_bridge_width 0.5)
				(island_removal_mode 0)
			)
			(polygon
				(pts
					(arc
						(start 218.200224 16.765524)
						(mid 216.346024 16.765524)
						(end 218.200224 16.765524)
					)
				)
			)
		)
		(zone
			(layers "F.Cu" "B.Cu" "In1.Cu" "In2.Cu" "In3.Cu" "In4.Cu" "In5.Cu" "In6.Cu"
				"In7.Cu" "In8.Cu" "In9.Cu" "In10.Cu" "In11.Cu" "In12.Cu" "In13.Cu" "In14.Cu"
				"In15.Cu" "In16.Cu"
			)
			(hatch none 0.5)
			(connect_pads
				(clearance 0)
			)
			(min_thickness 0.25)
			(keepout
				(tracks not_allowed)
				(vias allowed)
				(pads allowed)
				(copperpour not_allowed)
				(footprints allowed)
			)
			(placement
				(enabled no)
				(sheetname "")
			)
			(fill
				(thermal_gap 0.5)
				(thermal_bridge_width 0.5)
				(island_removal_mode 0)
			)
			(polygon
				(pts
					(arc
						(start 218.200224 19.305524)
						(mid 216.346024 19.305524)
						(end 218.200224 19.305524)
					)
				)
			)
		)
		(zone
			(layer "B.Cu")
			(hatch none 0.5)
			(connect_pads
				(clearance 0)
			)
			(min_thickness 0.25)
			(keepout
				(tracks not_allowed)
				(vias allowed)
				(pads allowed)
				(copperpour not_allowed)
				(footprints allowed)
			)
			(placement
				(enabled no)
				(sheetname "")
			)
			(fill
				(thermal_gap 0.5)
				(thermal_bridge_width 0.5)
				(island_removal_mode 0)
			)
			(polygon
				(pts
					(xy 214.923624 18.584164) (xy 214.923624 18.48866) (xy 214.326724 18.48866) (xy 214.326724 18.08226)
					(xy 214.923624 18.08226) (xy 214.923624 17.988788) (xy 214.326724 17.988788) (xy 214.326724 17.582388)
					(xy 214.923624 17.582388) (xy 214.923624 17.486884) (xy 214.225124 17.486884) (xy 214.225124 18.584164)
				)
			)
		)
	)
	(footprint ""
		(layer "B.Cu")
		(at 187.149994 -296.37482 180)
		(property "Reference" "C3102"
			(at 0 0 0)
			(layer "B.SilkS")
			(hide yes)
			(effects
				(font
					(size 1.27 1.27)
				)
				(justify mirror)
			)
		)
		(property "Value" ""
			(at 0 0 0)
			(layer "B.Fab")
			(effects
				(font
					(size 1.27 1.27)
				)
				(justify mirror)
			)
		)
		(duplicate_pad_numbers_are_jumpers no)
		(fp_line
			(start 0.299974 0.150114)
			(end 0.299974 -0.150114)
			(stroke
				(width 0.1)
				(type default)
			)
			(layer "B.Fab")
		)
		(fp_line
			(start 0.299974 -0.150114)
			(end -0.299974 -0.150114)
			(stroke
				(width 0.1)
				(type default)
			)
			(layer "B.Fab")
		)
		(fp_line
			(start -0.299974 0.150114)
			(end 0.299974 0.150114)
			(stroke
				(width 0.1)
				(type default)
			)
			(layer "B.Fab")
		)
		(fp_line
			(start -0.299974 -0.150114)
			(end -0.299974 0.150114)
			(stroke
				(width 0.1)
				(type default)
			)
			(layer "B.Fab")
		)
		(pad "1" smd rect
			(at 0.2667 0)
			(size 0.3048 0.381)
			(layers "B.Cu" "B.Mask" "B.Paste")
			(net "P1V25_PEX1")
		)
		(pad "2" smd rect
			(at -0.2667 0)
			(size 0.3048 0.381)
			(layers "B.Cu" "B.Mask" "B.Paste")
			(net "GND")
		)
	)
	(footprint ""
		(layer "B.Cu")
		(at 417.54933 -115.613434 -90)
		(property "Reference" "U43"
			(at -1.658874 4.103878 0)
			(unlocked yes)
			(layer "B.SilkS")
			(effects
				(font
					(size 0.7874 0.5842)
					(thickness 0.1524)
				)
				(justify mirror)
			)
		)
		(property "Value" ""
			(at 0 0 90)
			(layer "B.Fab")
			(effects
				(font
					(size 1.27 1.27)
				)
				(justify mirror)
			)
		)
		(duplicate_pad_numbers_are_jumpers no)
		(fp_line
			(start -1.3462 1.1938)
			(end -1.3462 -1.1938)
			(stroke
				(width 0.1524)
				(type default)
			)
			(layer "B.SilkS")
		)
		(fp_line
			(start 1.3462 1.1938)
			(end -1.3462 1.1938)
			(stroke
				(width 0.1524)
				(type default)
			)
			(layer "B.SilkS")
		)
		(fp_line
			(start -1.3462 -1.1938)
			(end 1.3462 -1.1938)
			(stroke
				(width 0.1524)
				(type default)
			)
			(layer "B.SilkS")
		)
		(fp_line
			(start 1.3462 -1.1938)
			(end 1.3462 1.1684)
			(stroke
				(width 0.1524)
				(type default)
			)
			(layer "B.SilkS")
		)
		(fp_poly
			(pts
				(xy 1.447038 -0.760476) (xy 2.052066 -0.457962) (xy 2.052066 -1.06299)
			)
			(stroke
				(width 0)
				(type default)
			)
			(fill yes)
			(layer "B.SilkS")
		)
		(fp_line
			(start -0.674878 1.124966)
			(end -0.674878 -1.124966)
			(stroke
				(width 0.1)
				(type default)
			)
			(layer "B.Fab")
		)
		(fp_line
			(start 0.674878 1.124966)
			(end -0.674878 1.124966)
			(stroke
				(width 0.1)
				(type default)
			)
			(layer "B.Fab")
		)
		(fp_line
			(start -0.674878 -1.124966)
			(end 0.674878 -1.124966)
			(stroke
				(width 0.1)
				(type default)
			)
			(layer "B.Fab")
		)
		(fp_line
			(start 0.674878 -1.124966)
			(end 0.674878 1.124966)
			(stroke
				(width 0.1)
				(type default)
			)
			(layer "B.Fab")
		)
		(fp_poly
			(pts
				(xy 1.447038 -0.760476) (xy 2.052066 -0.457962) (xy 2.052066 -1.06299)
			)
			(stroke
				(width 0)
				(type default)
			)
			(fill yes)
			(layer "B.Fab")
		)
		(pad "1" smd rect
			(at 0.899922 -0.750062 90)
			(size 0.6096 0.6096)
			(layers "B.Cu" "B.Mask" "B.Paste")
			(net "NIC7_AUX_PWR_EN_R")
		)
		(pad "2" smd rect
			(at 0.899922 0)
			(size 0.4064 0.6096)
			(layers "B.Cu" "B.Mask" "B.Paste")
			(net "RST_SMB_NIC7_MUX_N")
		)
		(pad "3" smd rect
			(at 0.899922 0.750062 90)
			(size 0.6096 0.6096)
			(layers "B.Cu" "B.Mask" "B.Paste")
			(net "GND")
		)
		(pad "4" smd rect
			(at -0.899922 0.750062 90)
			(size 0.6096 0.6096)
			(layers "B.Cu" "B.Mask" "B.Paste")
			(net "RST_SMB_NIC7_MUX_ISO_N")
		)
		(pad "5" smd rect
			(at -0.899922 -0.750062 90)
			(size 0.6096 0.6096)
			(layers "B.Cu" "B.Mask" "B.Paste")
			(net "P3V3_AUX")
		)
	)
	(footprint ""
		(layer "B.Cu")
		(at 272.849848 -288.774886 -90)
		(property "Reference" "R3470"
			(at 0 0 90)
			(layer "B.SilkS")
			(hide yes)
			(effects
				(font
					(size 1.27 1.27)
				)
				(justify mirror)
			)
		)
		(property "Value" ""
			(at 0 0 90)
			(layer "B.Fab")
			(effects
				(font
					(size 1.27 1.27)
				)
				(justify mirror)
			)
		)
		(duplicate_pad_numbers_are_jumpers no)
		(fp_line
			(start -0.7874 0.4064)
			(end 0.7874 0.4064)
			(stroke
				(width 0.1524)
				(type default)
			)
			(layer "B.SilkS")
		)
		(fp_line
			(start 0.7874 0.4064)
			(end 0.7874 -0.4064)
			(stroke
				(width 0.1524)
				(type default)
			)
			(layer "B.SilkS")
		)
		(fp_line
			(start -0.7874 -0.4064)
			(end -0.7874 0.4064)
			(stroke
				(width 0.1524)
				(type default)
			)
			(layer "B.SilkS")
		)
		(fp_line
			(start 0.7874 -0.4064)
			(end -0.7874 -0.4064)
			(stroke
				(width 0.1524)
				(type default)
			)
			(layer "B.SilkS")
		)
		(fp_line
			(start -0.67945 0.3048)
			(end -0.120396 0.3048)
			(stroke
				(width 0.1)
				(type default)
			)
			(layer "B.Fab")
		)
		(fp_line
			(start -0.120396 0.3048)
			(end -0.120396 0.2794)
			(stroke
				(width 0.1)
				(type default)
			)
			(layer "B.Fab")
		)
		(fp_line
			(start 0.12065 0.3048)
			(end 0.67945 0.3048)
			(stroke
				(width 0.1)
				(type default)
			)
			(layer "B.Fab")
		)
		(fp_line
			(start 0.67945 0.3048)
			(end 0.67945 -0.305054)
			(stroke
				(width 0.1)
				(type default)
			)
			(layer "B.Fab")
		)
		(fp_line
			(start -0.120396 0.2794)
			(end 0.12065 0.2794)
			(stroke
				(width 0.1)
				(type default)
			)
			(layer "B.Fab")
		)
		(fp_line
			(start 0.12065 0.2794)
			(end 0.12065 0.3048)
			(stroke
				(width 0.1)
				(type default)
			)
			(layer "B.Fab")
		)
		(fp_line
			(start -0.12065 -0.2794)
			(end -0.12065 -0.3048)
			(stroke
				(width 0.1)
				(type default)
			)
			(layer "B.Fab")
		)
		(fp_line
			(start 0.12065 -0.2794)
			(end -0.12065 -0.2794)
			(stroke
				(width 0.1)
				(type default)
			)
			(layer "B.Fab")
		)
		(fp_line
			(start -0.67945 -0.3048)
			(end -0.67945 0.3048)
			(stroke
				(width 0.1)
				(type default)
			)
			(layer "B.Fab")
		)
		(fp_line
			(start -0.12065 -0.3048)
			(end -0.67945 -0.3048)
			(stroke
				(width 0.1)
				(type default)
			)
			(layer "B.Fab")
		)
		(fp_line
			(start 0.12065 -0.305054)
			(end 0.12065 -0.2794)
			(stroke
				(width 0.1)
				(type default)
			)
			(layer "B.Fab")
		)
		(fp_line
			(start 0.67945 -0.305054)
			(end 0.12065 -0.305054)
			(stroke
				(width 0.1)
				(type default)
			)
			(layer "B.Fab")
		)
		(pad "1" smd circle
			(at 0.40005 0 90)
			(size 0 0)
			(layers "B.Cu" "B.Mask" "B.Paste")
			(net "SPI_PEX2_CS_R_N")
		)
		(pad "2" smd circle
			(at -0.40005 0 90)
			(size 0 0)
			(layers "B.Cu" "B.Mask" "B.Paste")
			(net "SPI_PEX2_CS_N")
		)
	)
	(footprint ""
		(layer "B.Cu")
		(at 118.425214 -308.580028 90)
		(property "Reference" "C1414"
			(at 0 0 90)
			(layer "B.SilkS")
			(hide yes)
			(effects
				(font
					(size 1.27 1.27)
				)
				(justify mirror)
			)
		)
		(property "Value" ""
			(at 0 0 90)
			(layer "B.Fab")
			(effects
				(font
					(size 1.27 1.27)
				)
				(justify mirror)
			)
		)
		(duplicate_pad_numbers_are_jumpers no)
		(fp_line
			(start 1.2954 -0.5842)
			(end -1.2954 -0.5842)
			(stroke
				(width 0.1524)
				(type default)
			)
			(layer "B.SilkS")
		)
		(fp_line
			(start -1.2954 -0.5842)
			(end -1.2954 0.5842)
			(stroke
				(width 0.1524)
				(type default)
			)
			(layer "B.SilkS")
		)
		(fp_line
			(start 1.2954 0.5842)
			(end 1.2954 -0.5842)
			(stroke
				(width 0.1524)
				(type default)
			)
			(layer "B.SilkS")
		)
		(fp_line
			(start -1.2954 0.5842)
			(end 1.2954 0.5842)
			(stroke
				(width 0.1524)
				(type default)
			)
			(layer "B.SilkS")
		)
		(fp_line
			(start 0.8636 -0.4572)
			(end -0.8636 -0.4572)
			(stroke
				(width 0.1)
				(type default)
			)
			(layer "B.Fab")
		)
		(fp_line
			(start -0.8636 -0.4572)
			(end -0.8636 -0.4064)
			(stroke
				(width 0.1)
				(type default)
			)
			(layer "B.Fab")
		)
		(fp_line
			(start 1.1938 -0.4064)
			(end 0.8636 -0.4064)
			(stroke
				(width 0.1)
				(type default)
			)
			(layer "B.Fab")
		)
		(fp_line
			(start 0.8636 -0.4064)
			(end 0.8636 -0.4572)
			(stroke
				(width 0.1)
				(type default)
			)
			(layer "B.Fab")
		)
		(fp_line
			(start -0.8636 -0.4064)
			(end -1.1938 -0.4064)
			(stroke
				(width 0.1)
				(type default)
			)
			(layer "B.Fab")
		)
		(fp_line
			(start -1.1938 -0.4064)
			(end -1.1938 0.4064)
			(stroke
				(width 0.1)
				(type default)
			)
			(layer "B.Fab")
		)
		(fp_line
			(start 1.1938 0.4064)
			(end 1.1938 -0.4064)
			(stroke
				(width 0.1)
				(type default)
			)
			(layer "B.Fab")
		)
		(fp_line
			(start 0.8636 0.4064)
			(end 1.1938 0.4064)
			(stroke
				(width 0.1)
				(type default)
			)
			(layer "B.Fab")
		)
		(fp_line
			(start -0.8636 0.4064)
			(end -0.8636 0.4572)
			(stroke
				(width 0.1)
				(type default)
			)
			(layer "B.Fab")
		)
		(fp_line
			(start -1.1938 0.4064)
			(end -0.8636 0.4064)
			(stroke
				(width 0.1)
				(type default)
			)
			(layer "B.Fab")
		)
		(fp_line
			(start 0.8636 0.4572)
			(end 0.8636 0.4064)
			(stroke
				(width 0.1)
				(type default)
			)
			(layer "B.Fab")
		)
		(fp_line
			(start -0.8636 0.4572)
			(end 0.8636 0.4572)
			(stroke
				(width 0.1)
				(type default)
			)
			(layer "B.Fab")
		)
		(pad "1" smd rect
			(at 0.7366 0)
			(size 0.7112 0.8128)
			(layers "B.Cu" "B.Mask" "B.Paste")
			(net "P0V8_SERDES_VDDA_PEX1")
		)
		(pad "2" smd rect
			(at -0.7366 0)
			(size 0.7112 0.8128)
			(layers "B.Cu" "B.Mask" "B.Paste")
			(net "GND")
		)
	)
	(footprint ""
		(layer "B.Cu")
		(at 299.00118 -305.399948 -90)
		(property "Reference" "C3317"
			(at 0 0 90)
			(layer "B.SilkS")
			(hide yes)
			(effects
				(font
					(size 1.27 1.27)
				)
				(justify mirror)
			)
		)
		(property "Value" ""
			(at 0 0 90)
			(layer "B.Fab")
			(effects
				(font
					(size 1.27 1.27)
				)
				(justify mirror)
			)
		)
		(duplicate_pad_numbers_are_jumpers no)
		(fp_line
			(start -0.299974 0.150114)
			(end 0.299974 0.150114)
			(stroke
				(width 0.1)
				(type default)
			)
			(layer "B.Fab")
		)
		(fp_line
			(start 0.299974 0.150114)
			(end 0.299974 -0.150114)
			(stroke
				(width 0.1)
				(type default)
			)
			(layer "B.Fab")
		)
		(fp_line
			(start -0.299974 -0.150114)
			(end -0.299974 0.150114)
			(stroke
				(width 0.1)
				(type default)
			)
			(layer "B.Fab")
		)
		(fp_line
			(start 0.299974 -0.150114)
			(end -0.299974 -0.150114)
			(stroke
				(width 0.1)
				(type default)
			)
			(layer "B.Fab")
		)
		(pad "1" smd rect
			(at 0.2667 0 90)
			(size 0.3048 0.381)
			(layers "B.Cu" "B.Mask" "B.Paste")
			(net "P1V25_SERDES_VDDPLL_PEX2")
		)
		(pad "2" smd rect
			(at -0.2667 0 90)
			(size 0.3048 0.381)
			(layers "B.Cu" "B.Mask" "B.Paste")
			(net "GND")
		)
	)
	(footprint ""
		(layer "B.Cu")
		(at 106.281474 -337.402932 90)
		(property "Reference" "R1232"
			(at 0 0 90)
			(layer "B.SilkS")
			(hide yes)
			(effects
				(font
					(size 1.27 1.27)
				)
				(justify mirror)
			)
		)
		(property "Value" ""
			(at 0 0 90)
			(layer "B.Fab")
			(effects
				(font
					(size 1.27 1.27)
				)
				(justify mirror)
			)
		)
		(duplicate_pad_numbers_are_jumpers no)
		(fp_line
			(start 0.7874 -0.4064)
			(end -0.7874 -0.4064)
			(stroke
				(width 0.1524)
				(type default)
			)
			(layer "B.SilkS")
		)
		(fp_line
			(start -0.7874 -0.4064)
			(end -0.7874 0.4064)
			(stroke
				(width 0.1524)
				(type default)
			)
			(layer "B.SilkS")
		)
		(fp_line
			(start 0.7874 0.4064)
			(end 0.7874 -0.4064)
			(stroke
				(width 0.1524)
				(type default)
			)
			(layer "B.SilkS")
		)
		(fp_line
			(start -0.7874 0.4064)
			(end 0.7874 0.4064)
			(stroke
				(width 0.1524)
				(type default)
			)
			(layer "B.SilkS")
		)
		(fp_line
			(start 0.67945 -0.305054)
			(end 0.12065 -0.305054)
			(stroke
				(width 0.1)
				(type default)
			)
			(layer "B.Fab")
		)
		(fp_line
			(start 0.12065 -0.305054)
			(end 0.12065 -0.2794)
			(stroke
				(width 0.1)
				(type default)
			)
			(layer "B.Fab")
		)
		(fp_line
			(start -0.12065 -0.3048)
			(end -0.67945 -0.3048)
			(stroke
				(width 0.1)
				(type default)
			)
			(layer "B.Fab")
		)
		(fp_line
			(start -0.67945 -0.3048)
			(end -0.67945 0.3048)
			(stroke
				(width 0.1)
				(type default)
			)
			(layer "B.Fab")
		)
		(fp_line
			(start 0.12065 -0.2794)
			(end -0.12065 -0.2794)
			(stroke
				(width 0.1)
				(type default)
			)
			(layer "B.Fab")
		)
		(fp_line
			(start -0.12065 -0.2794)
			(end -0.12065 -0.3048)
			(stroke
				(width 0.1)
				(type default)
			)
			(layer "B.Fab")
		)
		(fp_line
			(start 0.12065 0.2794)
			(end 0.12065 0.3048)
			(stroke
				(width 0.1)
				(type default)
			)
			(layer "B.Fab")
		)
		(fp_line
			(start -0.120396 0.2794)
			(end 0.12065 0.2794)
			(stroke
				(width 0.1)
				(type default)
			)
			(layer "B.Fab")
		)
		(fp_line
			(start 0.67945 0.3048)
			(end 0.67945 -0.305054)
			(stroke
				(width 0.1)
				(type default)
			)
			(layer "B.Fab")
		)
		(fp_line
			(start 0.12065 0.3048)
			(end 0.67945 0.3048)
			(stroke
				(width 0.1)
				(type default)
			)
			(layer "B.Fab")
		)
		(fp_line
			(start -0.120396 0.3048)
			(end -0.120396 0.2794)
			(stroke
				(width 0.1)
				(type default)
			)
			(layer "B.Fab")
		)
		(fp_line
			(start -0.67945 0.3048)
			(end -0.120396 0.3048)
			(stroke
				(width 0.1)
				(type default)
			)
			(layer "B.Fab")
		)
		(pad "1" smd circle
			(at 0.40005 0 270)
			(size 0 0)
			(layers "B.Cu" "B.Mask" "B.Paste")
			(net "CLK_100M_DB800ZL_PEX3_S0_R_DN")
		)
		(pad "2" smd circle
			(at -0.40005 0 270)
			(size 0 0)
			(layers "B.Cu" "B.Mask" "B.Paste")
			(net "CLK_100M_DB800ZL_PEX3_S0_DN")
		)
	)
	(footprint ""
		(layer "B.Cu")
		(at 142.806674 -214.959184 -90)
		(property "Reference" "R991"
			(at 0 0 90)
			(layer "B.SilkS")
			(hide yes)
			(effects
				(font
					(size 1.27 1.27)
				)
				(justify mirror)
			)
		)
		(property "Value" ""
			(at 0 0 90)
			(layer "B.Fab")
			(effects
				(font
					(size 1.27 1.27)
				)
				(justify mirror)
			)
		)
		(duplicate_pad_numbers_are_jumpers no)
		(fp_line
			(start -0.7874 0.4064)
			(end 0.7874 0.4064)
			(stroke
				(width 0.1524)
				(type default)
			)
			(layer "B.SilkS")
		)
		(fp_line
			(start 0.7874 0.4064)
			(end 0.7874 -0.4064)
			(stroke
				(width 0.1524)
				(type default)
			)
			(layer "B.SilkS")
		)
		(fp_line
			(start -0.7874 -0.4064)
			(end -0.7874 0.4064)
			(stroke
				(width 0.1524)
				(type default)
			)
			(layer "B.SilkS")
		)
		(fp_line
			(start 0.7874 -0.4064)
			(end -0.7874 -0.4064)
			(stroke
				(width 0.1524)
				(type default)
			)
			(layer "B.SilkS")
		)
		(fp_line
			(start -0.67945 0.3048)
			(end -0.120396 0.3048)
			(stroke
				(width 0.1)
				(type default)
			)
			(layer "B.Fab")
		)
		(fp_line
			(start -0.120396 0.3048)
			(end -0.120396 0.2794)
			(stroke
				(width 0.1)
				(type default)
			)
			(layer "B.Fab")
		)
		(fp_line
			(start 0.12065 0.3048)
			(end 0.67945 0.3048)
			(stroke
				(width 0.1)
				(type default)
			)
			(layer "B.Fab")
		)
		(fp_line
			(start 0.67945 0.3048)
			(end 0.67945 -0.305054)
			(stroke
				(width 0.1)
				(type default)
			)
			(layer "B.Fab")
		)
		(fp_line
			(start -0.120396 0.2794)
			(end 0.12065 0.2794)
			(stroke
				(width 0.1)
				(type default)
			)
			(layer "B.Fab")
		)
		(fp_line
			(start 0.12065 0.2794)
			(end 0.12065 0.3048)
			(stroke
				(width 0.1)
				(type default)
			)
			(layer "B.Fab")
		)
		(fp_line
			(start -0.12065 -0.2794)
			(end -0.12065 -0.3048)
			(stroke
				(width 0.1)
				(type default)
			)
			(layer "B.Fab")
		)
		(fp_line
			(start 0.12065 -0.2794)
			(end -0.12065 -0.2794)
			(stroke
				(width 0.1)
				(type default)
			)
			(layer "B.Fab")
		)
		(fp_line
			(start -0.67945 -0.3048)
			(end -0.67945 0.3048)
			(stroke
				(width 0.1)
				(type default)
			)
			(layer "B.Fab")
		)
		(fp_line
			(start -0.12065 -0.3048)
			(end -0.67945 -0.3048)
			(stroke
				(width 0.1)
				(type default)
			)
			(layer "B.Fab")
		)
		(fp_line
			(start 0.12065 -0.305054)
			(end 0.12065 -0.2794)
			(stroke
				(width 0.1)
				(type default)
			)
			(layer "B.Fab")
		)
		(fp_line
			(start 0.67945 -0.305054)
			(end 0.12065 -0.305054)
			(stroke
				(width 0.1)
				(type default)
			)
			(layer "B.Fab")
		)
		(pad "1" smd circle
			(at 0.40005 0 90)
			(size 0 0)
			(layers "B.Cu" "B.Mask" "B.Paste")
			(net "UART_PEX2_CLI_BUF_R_RX")
		)
		(pad "2" smd circle
			(at -0.40005 0 90)
			(size 0 0)
			(layers "B.Cu" "B.Mask" "B.Paste")
			(net "UART_PEX2_CLI_BUF_RX")
		)
	)
	(footprint ""
		(layer "B.Cu")
		(at 394.164312 -144.421352 180)
		(property "Reference" "C940"
			(at 0 0 0)
			(layer "B.SilkS")
			(hide yes)
			(effects
				(font
					(size 1.27 1.27)
				)
				(justify mirror)
			)
		)
		(property "Value" ""
			(at 0 0 0)
			(layer "B.Fab")
			(effects
				(font
					(size 1.27 1.27)
				)
				(justify mirror)
			)
		)
		(duplicate_pad_numbers_are_jumpers no)
		(fp_line
			(start 0.299974 0.150114)
			(end 0.299974 -0.150114)
			(stroke
				(width 0.1)
				(type default)
			)
			(layer "B.Fab")
		)
		(fp_line
			(start 0.299974 -0.150114)
			(end -0.299974 -0.150114)
			(stroke
				(width 0.1)
				(type default)
			)
			(layer "B.Fab")
		)
		(fp_line
			(start -0.299974 0.150114)
			(end 0.299974 0.150114)
			(stroke
				(width 0.1)
				(type default)
			)
			(layer "B.Fab")
		)
		(fp_line
			(start -0.299974 -0.150114)
			(end -0.299974 0.150114)
			(stroke
				(width 0.1)
				(type default)
			)
			(layer "B.Fab")
		)
		(pad "1" smd rect
			(at 0.2667 0)
			(size 0.3048 0.381)
			(layers "B.Cu" "B.Mask" "B.Paste")
			(net "P12V_NIC6")
		)
		(pad "2" smd rect
			(at -0.2667 0)
			(size 0.3048 0.381)
			(layers "B.Cu" "B.Mask" "B.Paste")
			(net "GND")
		)
	)
	(footprint ""
		(layer "B.Cu")
		(at 47.820326 -302.028606)
		(property "Reference" "C2988"
			(at 0 0 0)
			(layer "B.SilkS")
			(hide yes)
			(effects
				(font
					(size 1.27 1.27)
				)
				(justify mirror)
			)
		)
		(property "Value" ""
			(at 0 0 0)
			(layer "B.Fab")
			(effects
				(font
					(size 1.27 1.27)
				)
				(justify mirror)
			)
		)
		(duplicate_pad_numbers_are_jumpers no)
		(fp_line
			(start -1.2954 -0.5842)
			(end -1.2954 0.5842)
			(stroke
				(width 0.1524)
				(type default)
			)
			(layer "B.SilkS")
		)
		(fp_line
			(start -1.2954 0.5842)
			(end 1.2954 0.5842)
			(stroke
				(width 0.1524)
				(type default)
			)
			(layer "B.SilkS")
		)
		(fp_line
			(start 1.2954 -0.5842)
			(end -1.2954 -0.5842)
			(stroke
				(width 0.1524)
				(type default)
			)
			(layer "B.SilkS")
		)
		(fp_line
			(start 1.2954 0.5842)
			(end 1.2954 -0.5842)
			(stroke
				(width 0.1524)
				(type default)
			)
			(layer "B.SilkS")
		)
		(fp_line
			(start -1.1938 -0.4064)
			(end -1.1938 0.4064)
			(stroke
				(width 0.1)
				(type default)
			)
			(layer "B.Fab")
		)
		(fp_line
			(start -1.1938 0.4064)
			(end -0.8636 0.4064)
			(stroke
				(width 0.1)
				(type default)
			)
			(layer "B.Fab")
		)
		(fp_line
			(start -0.8636 -0.4572)
			(end -0.8636 -0.4064)
			(stroke
				(width 0.1)
				(type default)
			)
			(layer "B.Fab")
		)
		(fp_line
			(start -0.8636 -0.4064)
			(end -1.1938 -0.4064)
			(stroke
				(width 0.1)
				(type default)
			)
			(layer "B.Fab")
		)
		(fp_line
			(start -0.8636 0.4064)
			(end -0.8636 0.4572)
			(stroke
				(width 0.1)
				(type default)
			)
			(layer "B.Fab")
		)
		(fp_line
			(start -0.8636 0.4572)
			(end 0.8636 0.4572)
			(stroke
				(width 0.1)
				(type default)
			)
			(layer "B.Fab")
		)
		(fp_line
			(start 0.8636 -0.4572)
			(end -0.8636 -0.4572)
			(stroke
				(width 0.1)
				(type default)
			)
			(layer "B.Fab")
		)
		(fp_line
			(start 0.8636 -0.4064)
			(end 0.8636 -0.4572)
			(stroke
				(width 0.1)
				(type default)
			)
			(layer "B.Fab")
		)
		(fp_line
			(start 0.8636 0.4064)
			(end 1.1938 0.4064)
			(stroke
				(width 0.1)
				(type default)
			)
			(layer "B.Fab")
		)
		(fp_line
			(start 0.8636 0.4572)
			(end 0.8636 0.4064)
			(stroke
				(width 0.1)
				(type default)
			)
			(layer "B.Fab")
		)
		(fp_line
			(start 1.1938 -0.4064)
			(end 0.8636 -0.4064)
			(stroke
				(width 0.1)
				(type default)
			)
			(layer "B.Fab")
		)
		(fp_line
			(start 1.1938 0.4064)
			(end 1.1938 -0.4064)
			(stroke
				(width 0.1)
				(type default)
			)
			(layer "B.Fab")
		)
		(pad "1" smd rect
			(at 0.7366 0 270)
			(size 0.7112 0.8128)
			(layers "B.Cu" "B.Mask" "B.Paste")
			(net "P1V8_VDDA_PEX0")
		)
		(pad "2" smd rect
			(at -0.7366 0 270)
			(size 0.7112 0.8128)
			(layers "B.Cu" "B.Mask" "B.Paste")
			(net "GND")
		)
	)
	(footprint ""
		(layer "B.Cu")
		(at 411.750002 -292.099746 90)
		(property "Reference" "C1979"
			(at 0 0 90)
			(layer "B.SilkS")
			(hide yes)
			(effects
				(font
					(size 1.27 1.27)
				)
				(justify mirror)
			)
		)
		(property "Value" ""
			(at 0 0 90)
			(layer "B.Fab")
			(effects
				(font
					(size 1.27 1.27)
				)
				(justify mirror)
			)
		)
		(duplicate_pad_numbers_are_jumpers no)
		(fp_line
			(start 0.299974 -0.150114)
			(end -0.299974 -0.150114)
			(stroke
				(width 0.1)
				(type default)
			)
			(layer "B.Fab")
		)
		(fp_line
			(start -0.299974 -0.150114)
			(end -0.299974 0.150114)
			(stroke
				(width 0.1)
				(type default)
			)
			(layer "B.Fab")
		)
		(fp_line
			(start 0.299974 0.150114)
			(end 0.299974 -0.150114)
			(stroke
				(width 0.1)
				(type default)
			)
			(layer "B.Fab")
		)
		(fp_line
			(start -0.299974 0.150114)
			(end 0.299974 0.150114)
			(stroke
				(width 0.1)
				(type default)
			)
			(layer "B.Fab")
		)
		(pad "1" smd rect
			(at 0.2667 0 270)
			(size 0.3048 0.381)
			(layers "B.Cu" "B.Mask" "B.Paste")
			(net "P0V8_SERDES_VDDA_PEX3")
		)
		(pad "2" smd rect
			(at -0.2667 0 270)
			(size 0.3048 0.381)
			(layers "B.Cu" "B.Mask" "B.Paste")
			(net "GND")
		)
	)
	(footprint ""
		(layer "B.Cu")
		(at 111.229648 -327.856342 90)
		(property "Reference" "R1475"
			(at 0 0 90)
			(layer "B.SilkS")
			(hide yes)
			(effects
				(font
					(size 1.27 1.27)
				)
				(justify mirror)
			)
		)
		(property "Value" ""
			(at 0 0 90)
			(layer "B.Fab")
			(effects
				(font
					(size 1.27 1.27)
				)
				(justify mirror)
			)
		)
		(duplicate_pad_numbers_are_jumpers no)
		(fp_line
			(start 0.7874 -0.4064)
			(end -0.7874 -0.4064)
			(stroke
				(width 0.1524)
				(type default)
			)
			(layer "B.SilkS")
		)
		(fp_line
			(start -0.7874 -0.4064)
			(end -0.7874 0.4064)
			(stroke
				(width 0.1524)
				(type default)
			)
			(layer "B.SilkS")
		)
		(fp_line
			(start 0.7874 0.4064)
			(end 0.7874 -0.4064)
			(stroke
				(width 0.1524)
				(type default)
			)
			(layer "B.SilkS")
		)
		(fp_line
			(start -0.7874 0.4064)
			(end 0.7874 0.4064)
			(stroke
				(width 0.1524)
				(type default)
			)
			(layer "B.SilkS")
		)
		(fp_line
			(start 0.67945 -0.305054)
			(end 0.12065 -0.305054)
			(stroke
				(width 0.1)
				(type default)
			)
			(layer "B.Fab")
		)
		(fp_line
			(start 0.12065 -0.305054)
			(end 0.12065 -0.2794)
			(stroke
				(width 0.1)
				(type default)
			)
			(layer "B.Fab")
		)
		(fp_line
			(start -0.12065 -0.3048)
			(end -0.67945 -0.3048)
			(stroke
				(width 0.1)
				(type default)
			)
			(layer "B.Fab")
		)
		(fp_line
			(start -0.67945 -0.3048)
			(end -0.67945 0.3048)
			(stroke
				(width 0.1)
				(type default)
			)
			(layer "B.Fab")
		)
		(fp_line
			(start 0.12065 -0.2794)
			(end -0.12065 -0.2794)
			(stroke
				(width 0.1)
				(type default)
			)
			(layer "B.Fab")
		)
		(fp_line
			(start -0.12065 -0.2794)
			(end -0.12065 -0.3048)
			(stroke
				(width 0.1)
				(type default)
			)
			(layer "B.Fab")
		)
		(fp_line
			(start 0.12065 0.2794)
			(end 0.12065 0.3048)
			(stroke
				(width 0.1)
				(type default)
			)
			(layer "B.Fab")
		)
		(fp_line
			(start -0.120396 0.2794)
			(end 0.12065 0.2794)
			(stroke
				(width 0.1)
				(type default)
			)
			(layer "B.Fab")
		)
		(fp_line
			(start 0.67945 0.3048)
			(end 0.67945 -0.305054)
			(stroke
				(width 0.1)
				(type default)
			)
			(layer "B.Fab")
		)
		(fp_line
			(start 0.12065 0.3048)
			(end 0.67945 0.3048)
			(stroke
				(width 0.1)
				(type default)
			)
			(layer "B.Fab")
		)
		(fp_line
			(start -0.120396 0.3048)
			(end -0.120396 0.2794)
			(stroke
				(width 0.1)
				(type default)
			)
			(layer "B.Fab")
		)
		(fp_line
			(start -0.67945 0.3048)
			(end -0.120396 0.3048)
			(stroke
				(width 0.1)
				(type default)
			)
			(layer "B.Fab")
		)
		(pad "1" smd circle
			(at 0.40005 0 270)
			(size 0 0)
			(layers "B.Cu" "B.Mask" "B.Paste")
			(net "SMB_BMC_9FGL0451E_SDA")
		)
		(pad "2" smd circle
			(at -0.40005 0 270)
			(size 0 0)
			(layers "B.Cu" "B.Mask" "B.Paste")
			(net "SMB_CLK_ISO_R_SDA")
		)
	)
	(footprint ""
		(layer "B.Cu")
		(at 344.493342 -220.38691 90)
		(property "Reference" "C2065"
			(at 0 0 90)
			(layer "B.SilkS")
			(hide yes)
			(effects
				(font
					(size 1.27 1.27)
				)
				(justify mirror)
			)
		)
		(property "Value" ""
			(at 0 0 90)
			(layer "B.Fab")
			(effects
				(font
					(size 1.27 1.27)
				)
				(justify mirror)
			)
		)
		(duplicate_pad_numbers_are_jumpers no)
		(fp_line
			(start 0.69215 -0.2921)
			(end -0.69215 -0.2921)
			(stroke
				(width 0.1524)
				(type default)
			)
			(layer "B.SilkS")
		)
		(fp_line
			(start -0.69215 -0.2921)
			(end -0.69215 0.2921)
			(stroke
				(width 0.1524)
				(type default)
			)
			(layer "B.SilkS")
		)
		(fp_line
			(start 0.69215 0.2921)
			(end 0.69215 -0.2921)
			(stroke
				(width 0.1524)
				(type default)
			)
			(layer "B.SilkS")
		)
		(fp_line
			(start -0.69215 0.2921)
			(end 0.69215 0.2921)
			(stroke
				(width 0.1524)
				(type default)
			)
			(layer "B.SilkS")
		)
		(fp_line
			(start 0.51435 -0.2794)
			(end -0.51435 -0.2794)
			(stroke
				(width 0.1)
				(type default)
			)
			(layer "B.Fab")
		)
		(fp_line
			(start -0.51435 -0.2794)
			(end -0.51435 0.2794)
			(stroke
				(width 0.1)
				(type default)
			)
			(layer "B.Fab")
		)
		(fp_line
			(start 0.51435 0.2794)
			(end 0.51435 -0.2794)
			(stroke
				(width 0.1)
				(type default)
			)
			(layer "B.Fab")
		)
		(fp_line
			(start -0.51435 0.2794)
			(end 0.51435 0.2794)
			(stroke
				(width 0.1)
				(type default)
			)
			(layer "B.Fab")
		)
		(pad "1" smd circle
			(at 0.40005 0 270)
			(size 0 0)
			(layers "B.Cu" "B.Mask" "B.Paste")
			(net "P3V3_VCC_FPGA_CORE")
		)
		(pad "2" smd circle
			(at -0.40005 0 270)
			(size 0 0)
			(layers "B.Cu" "B.Mask" "B.Paste")
			(net "GND")
		)
		(zone
			(layer "B.Cu")
			(hatch none 0.5)
			(connect_pads
				(clearance 0)
			)
			(min_thickness 0.25)
			(keepout
				(tracks not_allowed)
				(vias allowed)
				(pads allowed)
				(copperpour not_allowed)
				(footprints allowed)
			)
			(placement
				(enabled no)
				(sheetname "")
			)
			(fill
				(thermal_gap 0.5)
				(thermal_bridge_width 0.5)
				(island_removal_mode 0)
			)
			(polygon
				(pts
					(xy 344.580972 -220.57741) (xy 344.639138 -220.48597) (xy 344.639138 -220.28658) (xy 344.580972 -220.19641)
					(xy 344.405712 -220.19641) (xy 344.347292 -220.28658) (xy 344.347292 -220.48597) (xy 344.405458 -220.57741)
				)
			)
		)
	)
	(footprint ""
		(layer "B.Cu")
		(at 353.418902 -222.555816 180)
		(property "Reference" "C2073"
			(at 0 0 0)
			(layer "B.SilkS")
			(hide yes)
			(effects
				(font
					(size 1.27 1.27)
				)
				(justify mirror)
			)
		)
		(property "Value" ""
			(at 0 0 0)
			(layer "B.Fab")
			(effects
				(font
					(size 1.27 1.27)
				)
				(justify mirror)
			)
		)
		(duplicate_pad_numbers_are_jumpers no)
		(fp_line
			(start 0.69215 0.2921)
			(end 0.69215 -0.2921)
			(stroke
				(width 0.1524)
				(type default)
			)
			(layer "B.SilkS")
		)
		(fp_line
			(start 0.69215 -0.2921)
			(end -0.69215 -0.2921)
			(stroke
				(width 0.1524)
				(type default)
			)
			(layer "B.SilkS")
		)
		(fp_line
			(start -0.69215 0.2921)
			(end 0.69215 0.2921)
			(stroke
				(width 0.1524)
				(type default)
			)
			(layer "B.SilkS")
		)
		(fp_line
			(start -0.69215 -0.2921)
			(end -0.69215 0.2921)
			(stroke
				(width 0.1524)
				(type default)
			)
			(layer "B.SilkS")
		)
		(fp_line
			(start 0.51435 0.2794)
			(end 0.51435 -0.2794)
			(stroke
				(width 0.1)
				(type default)
			)
			(layer "B.Fab")
		)
		(fp_line
			(start 0.51435 -0.2794)
			(end -0.51435 -0.2794)
			(stroke
				(width 0.1)
				(type default)
			)
			(layer "B.Fab")
		)
		(fp_line
			(start -0.51435 0.2794)
			(end 0.51435 0.2794)
			(stroke
				(width 0.1)
				(type default)
			)
			(layer "B.Fab")
		)
		(fp_line
			(start -0.51435 -0.2794)
			(end -0.51435 0.2794)
			(stroke
				(width 0.1)
				(type default)
			)
			(layer "B.Fab")
		)
		(pad "1" smd circle
			(at 0.40005 0)
			(size 0 0)
			(layers "B.Cu" "B.Mask" "B.Paste")
			(net "P3V3_VCC_FPGA_CORE")
		)
		(pad "2" smd circle
			(at -0.40005 0)
			(size 0 0)
			(layers "B.Cu" "B.Mask" "B.Paste")
			(net "GND")
		)
		(zone
			(layer "B.Cu")
			(hatch none 0.5)
			(connect_pads
				(clearance 0)
			)
			(min_thickness 0.25)
			(keepout
				(tracks not_allowed)
				(vias allowed)
				(pads allowed)
				(copperpour not_allowed)
				(footprints allowed)
			)
			(placement
				(enabled no)
				(sheetname "")
			)
			(fill
				(thermal_gap 0.5)
				(thermal_bridge_width 0.5)
				(island_removal_mode 0)
			)
			(polygon
				(pts
					(xy 353.228402 -222.643446) (xy 353.319842 -222.701612) (xy 353.519232 -222.701612) (xy 353.609402 -222.643446)
					(xy 353.609402 -222.468186) (xy 353.519232 -222.409766) (xy 353.319842 -222.409766) (xy 353.228402 -222.467932)
				)
			)
		)
	)
	(footprint ""
		(layer "B.Cu")
		(at 219.98432 -290.59632)
		(property "Reference" "PC991"
			(at 0 0 0)
			(layer "B.SilkS")
			(hide yes)
			(effects
				(font
					(size 1.27 1.27)
				)
				(justify mirror)
			)
		)
		(property "Value" ""
			(at 0 0 0)
			(layer "B.Fab")
			(effects
				(font
					(size 1.27 1.27)
				)
				(justify mirror)
			)
		)
		(duplicate_pad_numbers_are_jumpers no)
		(fp_line
			(start -1.524 -0.762)
			(end -1.524 0.762)
			(stroke
				(width 0.1524)
				(type default)
			)
			(layer "B.SilkS")
		)
		(fp_line
			(start -1.524 0.762)
			(end 1.524 0.762)
			(stroke
				(width 0.1524)
				(type default)
			)
			(layer "B.SilkS")
		)
		(fp_line
			(start 1.524 -0.762)
			(end -1.524 -0.762)
			(stroke
				(width 0.1524)
				(type default)
			)
			(layer "B.SilkS")
		)
		(fp_line
			(start 1.524 0.762)
			(end 1.524 -0.762)
			(stroke
				(width 0.1524)
				(type default)
			)
			(layer "B.SilkS")
		)
		(fp_line
			(start -1.1049 -0.724916)
			(end 1.1049 -0.724916)
			(stroke
				(width 0.1)
				(type default)
			)
			(layer "B.Fab")
		)
		(fp_line
			(start -1.1049 0.724916)
			(end -1.1049 -0.724916)
			(stroke
				(width 0.1)
				(type default)
			)
			(layer "B.Fab")
		)
		(fp_line
			(start 1.1049 -0.724916)
			(end 1.1049 0.724916)
			(stroke
				(width 0.1)
				(type default)
			)
			(layer "B.Fab")
		)
		(fp_line
			(start 1.1049 0.724916)
			(end -1.1049 0.724916)
			(stroke
				(width 0.1)
				(type default)
			)
			(layer "B.Fab")
		)
		(pad "1" smd rect
			(at 0.889 0)
			(size 1.016 1.27)
			(layers "B.Cu" "B.Mask" "B.Paste")
			(net "P1V25_PEX1_R")
		)
		(pad "2" smd rect
			(at -0.889 0)
			(size 1.016 1.27)
			(layers "B.Cu" "B.Mask" "B.Paste")
			(net "GND")
		)
	)
	(footprint ""
		(layer "B.Cu")
		(at 400.824954 -286.399732 90)
		(property "Reference" "C3491"
			(at 0 0 90)
			(layer "B.SilkS")
			(hide yes)
			(effects
				(font
					(size 1.27 1.27)
				)
				(justify mirror)
			)
		)
		(property "Value" ""
			(at 0 0 90)
			(layer "B.Fab")
			(effects
				(font
					(size 1.27 1.27)
				)
				(justify mirror)
			)
		)
		(duplicate_pad_numbers_are_jumpers no)
		(fp_line
			(start 0.299974 -0.150114)
			(end -0.299974 -0.150114)
			(stroke
				(width 0.1)
				(type default)
			)
			(layer "B.Fab")
		)
		(fp_line
			(start -0.299974 -0.150114)
			(end -0.299974 0.150114)
			(stroke
				(width 0.1)
				(type default)
			)
			(layer "B.Fab")
		)
		(fp_line
			(start 0.299974 0.150114)
			(end 0.299974 -0.150114)
			(stroke
				(width 0.1)
				(type default)
			)
			(layer "B.Fab")
		)
		(fp_line
			(start -0.299974 0.150114)
			(end 0.299974 0.150114)
			(stroke
				(width 0.1)
				(type default)
			)
			(layer "B.Fab")
		)
		(pad "1" smd rect
			(at 0.2667 0 270)
			(size 0.3048 0.381)
			(layers "B.Cu" "B.Mask" "B.Paste")
			(net "P1V25_SERDES_VDDPLL_PEX3")
		)
		(pad "2" smd rect
			(at -0.2667 0 270)
			(size 0.3048 0.381)
			(layers "B.Cu" "B.Mask" "B.Paste")
			(net "GND")
		)
	)
	(footprint ""
		(layer "B.Cu")
		(at 184.29986 -298.27474 180)
		(property "Reference" "C1372"
			(at 0 0 0)
			(layer "B.SilkS")
			(hide yes)
			(effects
				(font
					(size 1.27 1.27)
				)
				(justify mirror)
			)
		)
		(property "Value" ""
			(at 0 0 0)
			(layer "B.Fab")
			(effects
				(font
					(size 1.27 1.27)
				)
				(justify mirror)
			)
		)
		(duplicate_pad_numbers_are_jumpers no)
		(fp_line
			(start 0.299974 0.150114)
			(end 0.299974 -0.150114)
			(stroke
				(width 0.1)
				(type default)
			)
			(layer "B.Fab")
		)
		(fp_line
			(start 0.299974 -0.150114)
			(end -0.299974 -0.150114)
			(stroke
				(width 0.1)
				(type default)
			)
			(layer "B.Fab")
		)
		(fp_line
			(start -0.299974 0.150114)
			(end 0.299974 0.150114)
			(stroke
				(width 0.1)
				(type default)
			)
			(layer "B.Fab")
		)
		(fp_line
			(start -0.299974 -0.150114)
			(end -0.299974 0.150114)
			(stroke
				(width 0.1)
				(type default)
			)
			(layer "B.Fab")
		)
		(pad "1" smd rect
			(at 0.2667 0)
			(size 0.3048 0.381)
			(layers "B.Cu" "B.Mask" "B.Paste")
			(net "P0V8_PEX1")
		)
		(pad "2" smd rect
			(at -0.2667 0)
			(size 0.3048 0.381)
			(layers "B.Cu" "B.Mask" "B.Paste")
			(net "GND")
		)
	)
	(footprint ""
		(layer "B.Cu")
		(at 204.430376 -364.80496 180)
		(property "Reference" "PR2"
			(at 0 0 0)
			(layer "B.SilkS")
			(hide yes)
			(effects
				(font
					(size 1.27 1.27)
				)
				(justify mirror)
			)
		)
		(property "Value" ""
			(at 0 0 0)
			(layer "B.Fab")
			(effects
				(font
					(size 1.27 1.27)
				)
				(justify mirror)
			)
		)
		(duplicate_pad_numbers_are_jumpers no)
		(fp_line
			(start 0.7874 0.4064)
			(end 0.7874 -0.4064)
			(stroke
				(width 0.1524)
				(type default)
			)
			(layer "B.SilkS")
		)
		(fp_line
			(start 0.7874 -0.4064)
			(end -0.7874 -0.4064)
			(stroke
				(width 0.1524)
				(type default)
			)
			(layer "B.SilkS")
		)
		(fp_line
			(start -0.7874 0.4064)
			(end 0.7874 0.4064)
			(stroke
				(width 0.1524)
				(type default)
			)
			(layer "B.SilkS")
		)
		(fp_line
			(start -0.7874 -0.4064)
			(end -0.7874 0.4064)
			(stroke
				(width 0.1524)
				(type default)
			)
			(layer "B.SilkS")
		)
		(fp_line
			(start 0.67945 0.3048)
			(end 0.67945 -0.305054)
			(stroke
				(width 0.1)
				(type default)
			)
			(layer "B.Fab")
		)
		(fp_line
			(start 0.67945 -0.305054)
			(end 0.12065 -0.305054)
			(stroke
				(width 0.1)
				(type default)
			)
			(layer "B.Fab")
		)
		(fp_line
			(start 0.12065 0.3048)
			(end 0.67945 0.3048)
			(stroke
				(width 0.1)
				(type default)
			)
			(layer "B.Fab")
		)
		(fp_line
			(start 0.12065 0.2794)
			(end 0.12065 0.3048)
			(stroke
				(width 0.1)
				(type default)
			)
			(layer "B.Fab")
		)
		(fp_line
			(start 0.12065 -0.2794)
			(end -0.12065 -0.2794)
			(stroke
				(width 0.1)
				(type default)
			)
			(layer "B.Fab")
		)
		(fp_line
			(start 0.12065 -0.305054)
			(end 0.12065 -0.2794)
			(stroke
				(width 0.1)
				(type default)
			)
			(layer "B.Fab")
		)
		(fp_line
			(start -0.120396 0.3048)
			(end -0.120396 0.2794)
			(stroke
				(width 0.1)
				(type default)
			)
			(layer "B.Fab")
		)
		(fp_line
			(start -0.120396 0.2794)
			(end 0.12065 0.2794)
			(stroke
				(width 0.1)
				(type default)
			)
			(layer "B.Fab")
		)
		(fp_line
			(start -0.12065 -0.2794)
			(end -0.12065 -0.3048)
			(stroke
				(width 0.1)
				(type default)
			)
			(layer "B.Fab")
		)
		(fp_line
			(start -0.12065 -0.3048)
			(end -0.67945 -0.3048)
			(stroke
				(width 0.1)
				(type default)
			)
			(layer "B.Fab")
		)
		(fp_line
			(start -0.67945 0.3048)
			(end -0.120396 0.3048)
			(stroke
				(width 0.1)
				(type default)
			)
			(layer "B.Fab")
		)
		(fp_line
			(start -0.67945 -0.3048)
			(end -0.67945 0.3048)
			(stroke
				(width 0.1)
				(type default)
			)
			(layer "B.Fab")
		)
		(pad "1" smd circle
			(at 0.40005 0)
			(size 0 0)
			(layers "B.Cu" "B.Mask" "B.Paste")
			(net "HSC_VOSEN")
		)
		(pad "2" smd circle
			(at -0.40005 0)
			(size 0 0)
			(layers "B.Cu" "B.Mask" "B.Paste")
			(net "P12V_AUX")
		)
	)
	(footprint ""
		(layer "B.Cu")
		(at 415.549842 -290.199826 90)
		(property "Reference" "C1959"
			(at 0 0 90)
			(layer "B.SilkS")
			(hide yes)
			(effects
				(font
					(size 1.27 1.27)
				)
				(justify mirror)
			)
		)
		(property "Value" ""
			(at 0 0 90)
			(layer "B.Fab")
			(effects
				(font
					(size 1.27 1.27)
				)
				(justify mirror)
			)
		)
		(duplicate_pad_numbers_are_jumpers no)
		(fp_line
			(start 0.299974 -0.150114)
			(end -0.299974 -0.150114)
			(stroke
				(width 0.1)
				(type default)
			)
			(layer "B.Fab")
		)
		(fp_line
			(start -0.299974 -0.150114)
			(end -0.299974 0.150114)
			(stroke
				(width 0.1)
				(type default)
			)
			(layer "B.Fab")
		)
		(fp_line
			(start 0.299974 0.150114)
			(end 0.299974 -0.150114)
			(stroke
				(width 0.1)
				(type default)
			)
			(layer "B.Fab")
		)
		(fp_line
			(start -0.299974 0.150114)
			(end 0.299974 0.150114)
			(stroke
				(width 0.1)
				(type default)
			)
			(layer "B.Fab")
		)
		(pad "1" smd rect
			(at 0.2667 0 270)
			(size 0.3048 0.381)
			(layers "B.Cu" "B.Mask" "B.Paste")
			(net "P0V8_SERDES_VDDA_PEX3")
		)
		(pad "2" smd rect
			(at -0.2667 0 270)
			(size 0.3048 0.381)
			(layers "B.Cu" "B.Mask" "B.Paste")
			(net "GND")
		)
	)
	(footprint ""
		(layer "B.Cu")
		(at 350.65716 -318.542416)
		(property "Reference" "C4364"
			(at 0 0 0)
			(layer "B.SilkS")
			(hide yes)
			(effects
				(font
					(size 1.27 1.27)
				)
				(justify mirror)
			)
		)
		(property "Value" ""
			(at 0 0 0)
			(layer "B.Fab")
			(effects
				(font
					(size 1.27 1.27)
				)
				(justify mirror)
			)
		)
		(duplicate_pad_numbers_are_jumpers no)
		(fp_line
			(start -0.299974 -0.150114)
			(end -0.299974 0.150114)
			(stroke
				(width 0.1)
				(type default)
			)
			(layer "B.Fab")
		)
		(fp_line
			(start -0.299974 0.150114)
			(end 0.299974 0.150114)
			(stroke
				(width 0.1)
				(type default)
			)
			(layer "B.Fab")
		)
		(fp_line
			(start 0.299974 -0.150114)
			(end -0.299974 -0.150114)
			(stroke
				(width 0.1)
				(type default)
			)
			(layer "B.Fab")
		)
		(fp_line
			(start 0.299974 0.150114)
			(end 0.299974 -0.150114)
			(stroke
				(width 0.1)
				(type default)
			)
			(layer "B.Fab")
		)
		(pad "1" smd rect
			(at 0.2667 0 180)
			(size 0.3048 0.381)
			(layers "B.Cu" "B.Mask" "B.Paste")
			(net "P0V8_SERDES_VDDA_PEX3")
		)
		(pad "2" smd rect
			(at -0.2667 0 180)
			(size 0.3048 0.381)
			(layers "B.Cu" "B.Mask" "B.Paste")
			(net "GND")
		)
	)
	(footprint ""
		(layer "B.Cu")
		(at 231.131364 -211.54517 180)
		(property "Reference" "R457"
			(at 0 0 0)
			(layer "B.SilkS")
			(hide yes)
			(effects
				(font
					(size 1.27 1.27)
				)
				(justify mirror)
			)
		)
		(property "Value" ""
			(at 0 0 0)
			(layer "B.Fab")
			(effects
				(font
					(size 1.27 1.27)
				)
				(justify mirror)
			)
		)
		(duplicate_pad_numbers_are_jumpers no)
		(fp_line
			(start 1.2954 0.5842)
			(end 1.2954 -0.5842)
			(stroke
				(width 0.1524)
				(type default)
			)
			(layer "B.SilkS")
		)
		(fp_line
			(start 1.2954 -0.5842)
			(end -1.2954 -0.5842)
			(stroke
				(width 0.1524)
				(type default)
			)
			(layer "B.SilkS")
		)
		(fp_line
			(start -1.2954 0.5842)
			(end 1.2954 0.5842)
			(stroke
				(width 0.1524)
				(type default)
			)
			(layer "B.SilkS")
		)
		(fp_line
			(start -1.2954 -0.5842)
			(end -1.2954 0.5842)
			(stroke
				(width 0.1524)
				(type default)
			)
			(layer "B.SilkS")
		)
		(fp_line
			(start 1.1938 0.4064)
			(end 1.1938 -0.406654)
			(stroke
				(width 0.1)
				(type default)
			)
			(layer "B.Fab")
		)
		(fp_line
			(start 1.1938 -0.406654)
			(end 0.8636 -0.406654)
			(stroke
				(width 0.1)
				(type default)
			)
			(layer "B.Fab")
		)
		(fp_line
			(start 0.8636 0.4572)
			(end 0.8636 0.4318)
			(stroke
				(width 0.1)
				(type default)
			)
			(layer "B.Fab")
		)
		(fp_line
			(start 0.8636 0.4318)
			(end 0.8636 0.4064)
			(stroke
				(width 0.1)
				(type default)
			)
			(layer "B.Fab")
		)
		(fp_line
			(start 0.8636 0.4064)
			(end 1.1938 0.4064)
			(stroke
				(width 0.1)
				(type default)
			)
			(layer "B.Fab")
		)
		(fp_line
			(start 0.8636 -0.406654)
			(end 0.8636 -0.4572)
			(stroke
				(width 0.1)
				(type default)
			)
			(layer "B.Fab")
		)
		(fp_line
			(start 0.8636 -0.4572)
			(end -0.8636 -0.4572)
			(stroke
				(width 0.1)
				(type default)
			)
			(layer "B.Fab")
		)
		(fp_line
			(start -0.8636 0.4572)
			(end 0.8636 0.4572)
			(stroke
				(width 0.1)
				(type default)
			)
			(layer "B.Fab")
		)
		(fp_line
			(start -0.8636 0.4064)
			(end -0.8636 0.4572)
			(stroke
				(width 0.1)
				(type default)
			)
			(layer "B.Fab")
		)
		(fp_line
			(start -0.8636 -0.406654)
			(end -1.1938 -0.406654)
			(stroke
				(width 0.1)
				(type default)
			)
			(layer "B.Fab")
		)
		(fp_line
			(start -0.8636 -0.4572)
			(end -0.8636 -0.406654)
			(stroke
				(width 0.1)
				(type default)
			)
			(layer "B.Fab")
		)
		(fp_line
			(start -1.1938 0.4064)
			(end -0.8636 0.4064)
			(stroke
				(width 0.1)
				(type default)
			)
			(layer "B.Fab")
		)
		(fp_line
			(start -1.1938 -0.406654)
			(end -1.1938 0.4064)
			(stroke
				(width 0.1)
				(type default)
			)
			(layer "B.Fab")
		)
		(pad "1" smd rect
			(at 0.7366 0 90)
			(size 0.7112 0.8128)
			(layers "B.Cu" "B.Mask" "B.Paste")
			(net "P3V3_BIC_SPI")
		)
		(pad "2" smd rect
			(at -0.7366 0 90)
			(size 0.7112 0.8128)
			(layers "B.Cu" "B.Mask" "B.Paste")
			(net "P3V3_AUX")
		)
	)
	(footprint ""
		(layer "B.Cu")
		(at 349.780098 -282.040584 90)
		(property "Reference" "PR154"
			(at 0 0 90)
			(layer "B.SilkS")
			(hide yes)
			(effects
				(font
					(size 1.27 1.27)
				)
				(justify mirror)
			)
		)
		(property "Value" ""
			(at 0 0 90)
			(layer "B.Fab")
			(effects
				(font
					(size 1.27 1.27)
				)
				(justify mirror)
			)
		)
		(duplicate_pad_numbers_are_jumpers no)
		(fp_line
			(start 0.7874 -0.4064)
			(end -0.7874 -0.4064)
			(stroke
				(width 0.1524)
				(type default)
			)
			(layer "B.SilkS")
		)
		(fp_line
			(start -0.7874 -0.4064)
			(end -0.7874 0.4064)
			(stroke
				(width 0.1524)
				(type default)
			)
			(layer "B.SilkS")
		)
		(fp_line
			(start 0.7874 0.4064)
			(end 0.7874 -0.4064)
			(stroke
				(width 0.1524)
				(type default)
			)
			(layer "B.SilkS")
		)
		(fp_line
			(start -0.7874 0.4064)
			(end 0.7874 0.4064)
			(stroke
				(width 0.1524)
				(type default)
			)
			(layer "B.SilkS")
		)
		(fp_line
			(start 0.67945 -0.305054)
			(end 0.12065 -0.305054)
			(stroke
				(width 0.1)
				(type default)
			)
			(layer "B.Fab")
		)
		(fp_line
			(start 0.12065 -0.305054)
			(end 0.12065 -0.2794)
			(stroke
				(width 0.1)
				(type default)
			)
			(layer "B.Fab")
		)
		(fp_line
			(start -0.12065 -0.3048)
			(end -0.67945 -0.3048)
			(stroke
				(width 0.1)
				(type default)
			)
			(layer "B.Fab")
		)
		(fp_line
			(start -0.67945 -0.3048)
			(end -0.67945 0.3048)
			(stroke
				(width 0.1)
				(type default)
			)
			(layer "B.Fab")
		)
		(fp_line
			(start 0.12065 -0.2794)
			(end -0.12065 -0.2794)
			(stroke
				(width 0.1)
				(type default)
			)
			(layer "B.Fab")
		)
		(fp_line
			(start -0.12065 -0.2794)
			(end -0.12065 -0.3048)
			(stroke
				(width 0.1)
				(type default)
			)
			(layer "B.Fab")
		)
		(fp_line
			(start 0.12065 0.2794)
			(end 0.12065 0.3048)
			(stroke
				(width 0.1)
				(type default)
			)
			(layer "B.Fab")
		)
		(fp_line
			(start -0.120396 0.2794)
			(end 0.12065 0.2794)
			(stroke
				(width 0.1)
				(type default)
			)
			(layer "B.Fab")
		)
		(fp_line
			(start 0.67945 0.3048)
			(end 0.67945 -0.305054)
			(stroke
				(width 0.1)
				(type default)
			)
			(layer "B.Fab")
		)
		(fp_line
			(start 0.12065 0.3048)
			(end 0.67945 0.3048)
			(stroke
				(width 0.1)
				(type default)
			)
			(layer "B.Fab")
		)
		(fp_line
			(start -0.120396 0.3048)
			(end -0.120396 0.2794)
			(stroke
				(width 0.1)
				(type default)
			)
			(layer "B.Fab")
		)
		(fp_line
			(start -0.67945 0.3048)
			(end -0.120396 0.3048)
			(stroke
				(width 0.1)
				(type default)
			)
			(layer "B.Fab")
		)
		(pad "1" smd circle
			(at 0.40005 0 270)
			(size 0 0)
			(layers "B.Cu" "B.Mask" "B.Paste")
			(net "SW_P0V8_PEX2_VOS2")
		)
		(pad "2" smd circle
			(at -0.40005 0 270)
			(size 0 0)
			(layers "B.Cu" "B.Mask" "B.Paste")
			(net "P0V8_PEX2")
		)
	)
	(footprint ""
		(layer "B.Cu")
		(at 283.299916 -288.299906 90)
		(property "Reference" "C3271"
			(at 0 0 90)
			(layer "B.SilkS")
			(hide yes)
			(effects
				(font
					(size 1.27 1.27)
				)
				(justify mirror)
			)
		)
		(property "Value" ""
			(at 0 0 90)
			(layer "B.Fab")
			(effects
				(font
					(size 1.27 1.27)
				)
				(justify mirror)
			)
		)
		(duplicate_pad_numbers_are_jumpers no)
		(fp_line
			(start 0.299974 -0.150114)
			(end -0.299974 -0.150114)
			(stroke
				(width 0.1)
				(type default)
			)
			(layer "B.Fab")
		)
		(fp_line
			(start -0.299974 -0.150114)
			(end -0.299974 0.150114)
			(stroke
				(width 0.1)
				(type default)
			)
			(layer "B.Fab")
		)
		(fp_line
			(start 0.299974 0.150114)
			(end 0.299974 -0.150114)
			(stroke
				(width 0.1)
				(type default)
			)
			(layer "B.Fab")
		)
		(fp_line
			(start -0.299974 0.150114)
			(end 0.299974 0.150114)
			(stroke
				(width 0.1)
				(type default)
			)
			(layer "B.Fab")
		)
		(pad "1" smd rect
			(at 0.2667 0 270)
			(size 0.3048 0.381)
			(layers "B.Cu" "B.Mask" "B.Paste")
			(net "P1V25_PEX2")
		)
		(pad "2" smd rect
			(at -0.2667 0 270)
			(size 0.3048 0.381)
			(layers "B.Cu" "B.Mask" "B.Paste")
			(net "GND")
		)
	)
	(footprint ""
		(layer "B.Cu")
		(at 217.235786 -218.302586)
		(property "Reference" "R1504"
			(at 0 0 0)
			(layer "B.SilkS")
			(hide yes)
			(effects
				(font
					(size 1.27 1.27)
				)
				(justify mirror)
			)
		)
		(property "Value" ""
			(at 0 0 0)
			(layer "B.Fab")
			(effects
				(font
					(size 1.27 1.27)
				)
				(justify mirror)
			)
		)
		(duplicate_pad_numbers_are_jumpers no)
		(fp_line
			(start -0.7874 -0.4064)
			(end -0.7874 0.4064)
			(stroke
				(width 0.1524)
				(type default)
			)
			(layer "B.SilkS")
		)
		(fp_line
			(start -0.7874 0.4064)
			(end 0.7874 0.4064)
			(stroke
				(width 0.1524)
				(type default)
			)
			(layer "B.SilkS")
		)
		(fp_line
			(start 0.7874 -0.4064)
			(end -0.7874 -0.4064)
			(stroke
				(width 0.1524)
				(type default)
			)
			(layer "B.SilkS")
		)
		(fp_line
			(start 0.7874 0.4064)
			(end 0.7874 -0.4064)
			(stroke
				(width 0.1524)
				(type default)
			)
			(layer "B.SilkS")
		)
		(fp_line
			(start -0.67945 -0.3048)
			(end -0.67945 0.3048)
			(stroke
				(width 0.1)
				(type default)
			)
			(layer "B.Fab")
		)
		(fp_line
			(start -0.67945 0.3048)
			(end -0.120396 0.3048)
			(stroke
				(width 0.1)
				(type default)
			)
			(layer "B.Fab")
		)
		(fp_line
			(start -0.12065 -0.3048)
			(end -0.67945 -0.3048)
			(stroke
				(width 0.1)
				(type default)
			)
			(layer "B.Fab")
		)
		(fp_line
			(start -0.12065 -0.2794)
			(end -0.12065 -0.3048)
			(stroke
				(width 0.1)
				(type default)
			)
			(layer "B.Fab")
		)
		(fp_line
			(start -0.120396 0.2794)
			(end 0.12065 0.2794)
			(stroke
				(width 0.1)
				(type default)
			)
			(layer "B.Fab")
		)
		(fp_line
			(start -0.120396 0.3048)
			(end -0.120396 0.2794)
			(stroke
				(width 0.1)
				(type default)
			)
			(layer "B.Fab")
		)
		(fp_line
			(start 0.12065 -0.305054)
			(end 0.12065 -0.2794)
			(stroke
				(width 0.1)
				(type default)
			)
			(layer "B.Fab")
		)
		(fp_line
			(start 0.12065 -0.2794)
			(end -0.12065 -0.2794)
			(stroke
				(width 0.1)
				(type default)
			)
			(layer "B.Fab")
		)
		(fp_line
			(start 0.12065 0.2794)
			(end 0.12065 0.3048)
			(stroke
				(width 0.1)
				(type default)
			)
			(layer "B.Fab")
		)
		(fp_line
			(start 0.12065 0.3048)
			(end 0.67945 0.3048)
			(stroke
				(width 0.1)
				(type default)
			)
			(layer "B.Fab")
		)
		(fp_line
			(start 0.67945 -0.305054)
			(end 0.12065 -0.305054)
			(stroke
				(width 0.1)
				(type default)
			)
			(layer "B.Fab")
		)
		(fp_line
			(start 0.67945 0.3048)
			(end 0.67945 -0.305054)
			(stroke
				(width 0.1)
				(type default)
			)
			(layer "B.Fab")
		)
		(pad "1" smd circle
			(at 0.40005 0 180)
			(size 0 0)
			(layers "B.Cu" "B.Mask" "B.Paste")
			(net "SMB_NIC7_SCL")
		)
		(pad "2" smd circle
			(at -0.40005 0 180)
			(size 0 0)
			(layers "B.Cu" "B.Mask" "B.Paste")
			(net "SMB_NIC7_R_SCL")
		)
	)
	(footprint ""
		(layer "B.Cu")
		(at 301.349918 -294.4749 180)
		(property "Reference" "C1672"
			(at 0 0 0)
			(layer "B.SilkS")
			(hide yes)
			(effects
				(font
					(size 1.27 1.27)
				)
				(justify mirror)
			)
		)
		(property "Value" ""
			(at 0 0 0)
			(layer "B.Fab")
			(effects
				(font
					(size 1.27 1.27)
				)
				(justify mirror)
			)
		)
		(duplicate_pad_numbers_are_jumpers no)
		(fp_line
			(start 0.299974 0.150114)
			(end 0.299974 -0.150114)
			(stroke
				(width 0.1)
				(type default)
			)
			(layer "B.Fab")
		)
		(fp_line
			(start 0.299974 -0.150114)
			(end -0.299974 -0.150114)
			(stroke
				(width 0.1)
				(type default)
			)
			(layer "B.Fab")
		)
		(fp_line
			(start -0.299974 0.150114)
			(end 0.299974 0.150114)
			(stroke
				(width 0.1)
				(type default)
			)
			(layer "B.Fab")
		)
		(fp_line
			(start -0.299974 -0.150114)
			(end -0.299974 0.150114)
			(stroke
				(width 0.1)
				(type default)
			)
			(layer "B.Fab")
		)
		(pad "1" smd rect
			(at 0.2667 0)
			(size 0.3048 0.381)
			(layers "B.Cu" "B.Mask" "B.Paste")
			(net "P0V8_SERDES_VDDA_PEX2")
		)
		(pad "2" smd rect
			(at -0.2667 0)
			(size 0.3048 0.381)
			(layers "B.Cu" "B.Mask" "B.Paste")
			(net "GND")
		)
	)
	(footprint ""
		(layer "B.Cu")
		(at 172.106844 -138.557 90)
		(property "Reference" "C901"
			(at 0 0 90)
			(layer "B.SilkS")
			(hide yes)
			(effects
				(font
					(size 1.27 1.27)
				)
				(justify mirror)
			)
		)
		(property "Value" ""
			(at 0 0 90)
			(layer "B.Fab")
			(effects
				(font
					(size 1.27 1.27)
				)
				(justify mirror)
			)
		)
		(duplicate_pad_numbers_are_jumpers no)
		(fp_line
			(start 0.7874 -0.4064)
			(end -0.7874 -0.4064)
			(stroke
				(width 0.1524)
				(type default)
			)
			(layer "B.SilkS")
		)
		(fp_line
			(start -0.7874 -0.4064)
			(end -0.7874 0.4064)
			(stroke
				(width 0.1524)
				(type default)
			)
			(layer "B.SilkS")
		)
		(fp_line
			(start 0.7874 0.4064)
			(end 0.7874 -0.4064)
			(stroke
				(width 0.1524)
				(type default)
			)
			(layer "B.SilkS")
		)
		(fp_line
			(start -0.7874 0.4064)
			(end 0.7874 0.4064)
			(stroke
				(width 0.1524)
				(type default)
			)
			(layer "B.SilkS")
		)
		(fp_line
			(start 0.67945 -0.305054)
			(end 0.12065 -0.305054)
			(stroke
				(width 0.1)
				(type default)
			)
			(layer "B.Fab")
		)
		(fp_line
			(start 0.12065 -0.305054)
			(end 0.12065 -0.2794)
			(stroke
				(width 0.1)
				(type default)
			)
			(layer "B.Fab")
		)
		(fp_line
			(start -0.12065 -0.3048)
			(end -0.67945 -0.3048)
			(stroke
				(width 0.1)
				(type default)
			)
			(layer "B.Fab")
		)
		(fp_line
			(start -0.67945 -0.3048)
			(end -0.67945 0.3048)
			(stroke
				(width 0.1)
				(type default)
			)
			(layer "B.Fab")
		)
		(fp_line
			(start 0.12065 -0.2794)
			(end -0.12065 -0.2794)
			(stroke
				(width 0.1)
				(type default)
			)
			(layer "B.Fab")
		)
		(fp_line
			(start -0.12065 -0.2794)
			(end -0.12065 -0.3048)
			(stroke
				(width 0.1)
				(type default)
			)
			(layer "B.Fab")
		)
		(fp_line
			(start 0.12065 0.2794)
			(end 0.12065 0.3048)
			(stroke
				(width 0.1)
				(type default)
			)
			(layer "B.Fab")
		)
		(fp_line
			(start -0.120396 0.2794)
			(end 0.12065 0.2794)
			(stroke
				(width 0.1)
				(type default)
			)
			(layer "B.Fab")
		)
		(fp_line
			(start 0.67945 0.3048)
			(end 0.67945 -0.305054)
			(stroke
				(width 0.1)
				(type default)
			)
			(layer "B.Fab")
		)
		(fp_line
			(start 0.12065 0.3048)
			(end 0.67945 0.3048)
			(stroke
				(width 0.1)
				(type default)
			)
			(layer "B.Fab")
		)
		(fp_line
			(start -0.120396 0.3048)
			(end -0.120396 0.2794)
			(stroke
				(width 0.1)
				(type default)
			)
			(layer "B.Fab")
		)
		(fp_line
			(start -0.67945 0.3048)
			(end -0.120396 0.3048)
			(stroke
				(width 0.1)
				(type default)
			)
			(layer "B.Fab")
		)
		(pad "1" smd circle
			(at 0.40005 0 270)
			(size 0 0)
			(layers "B.Cu" "B.Mask" "B.Paste")
			(net "P3V3_AUX")
		)
		(pad "2" smd circle
			(at -0.40005 0 270)
			(size 0 0)
			(layers "B.Cu" "B.Mask" "B.Paste")
			(net "GND")
		)
	)
	(footprint ""
		(layer "B.Cu")
		(at 175.267874 -286.18434 90)
		(property "Reference" "C3118"
			(at 0 0 90)
			(layer "B.SilkS")
			(hide yes)
			(effects
				(font
					(size 1.27 1.27)
				)
				(justify mirror)
			)
		)
		(property "Value" ""
			(at 0 0 90)
			(layer "B.Fab")
			(effects
				(font
					(size 1.27 1.27)
				)
				(justify mirror)
			)
		)
		(duplicate_pad_numbers_are_jumpers no)
		(fp_line
			(start 1.2954 -0.5842)
			(end -1.2954 -0.5842)
			(stroke
				(width 0.1524)
				(type default)
			)
			(layer "B.SilkS")
		)
		(fp_line
			(start -1.2954 -0.5842)
			(end -1.2954 0.5842)
			(stroke
				(width 0.1524)
				(type default)
			)
			(layer "B.SilkS")
		)
		(fp_line
			(start 1.2954 0.5842)
			(end 1.2954 -0.5842)
			(stroke
				(width 0.1524)
				(type default)
			)
			(layer "B.SilkS")
		)
		(fp_line
			(start -1.2954 0.5842)
			(end 1.2954 0.5842)
			(stroke
				(width 0.1524)
				(type default)
			)
			(layer "B.SilkS")
		)
		(fp_line
			(start 0.8636 -0.4572)
			(end -0.8636 -0.4572)
			(stroke
				(width 0.1)
				(type default)
			)
			(layer "B.Fab")
		)
		(fp_line
			(start -0.8636 -0.4572)
			(end -0.8636 -0.4064)
			(stroke
				(width 0.1)
				(type default)
			)
			(layer "B.Fab")
		)
		(fp_line
			(start 1.1938 -0.4064)
			(end 0.8636 -0.4064)
			(stroke
				(width 0.1)
				(type default)
			)
			(layer "B.Fab")
		)
		(fp_line
			(start 0.8636 -0.4064)
			(end 0.8636 -0.4572)
			(stroke
				(width 0.1)
				(type default)
			)
			(layer "B.Fab")
		)
		(fp_line
			(start -0.8636 -0.4064)
			(end -1.1938 -0.4064)
			(stroke
				(width 0.1)
				(type default)
			)
			(layer "B.Fab")
		)
		(fp_line
			(start -1.1938 -0.4064)
			(end -1.1938 0.4064)
			(stroke
				(width 0.1)
				(type default)
			)
			(layer "B.Fab")
		)
		(fp_line
			(start 1.1938 0.4064)
			(end 1.1938 -0.4064)
			(stroke
				(width 0.1)
				(type default)
			)
			(layer "B.Fab")
		)
		(fp_line
			(start 0.8636 0.4064)
			(end 1.1938 0.4064)
			(stroke
				(width 0.1)
				(type default)
			)
			(layer "B.Fab")
		)
		(fp_line
			(start -0.8636 0.4064)
			(end -0.8636 0.4572)
			(stroke
				(width 0.1)
				(type default)
			)
			(layer "B.Fab")
		)
		(fp_line
			(start -1.1938 0.4064)
			(end -0.8636 0.4064)
			(stroke
				(width 0.1)
				(type default)
			)
			(layer "B.Fab")
		)
		(fp_line
			(start 0.8636 0.4572)
			(end 0.8636 0.4064)
			(stroke
				(width 0.1)
				(type default)
			)
			(layer "B.Fab")
		)
		(fp_line
			(start -0.8636 0.4572)
			(end 0.8636 0.4572)
			(stroke
				(width 0.1)
				(type default)
			)
			(layer "B.Fab")
		)
		(pad "1" smd rect
			(at 0.7366 0)
			(size 0.7112 0.8128)
			(layers "B.Cu" "B.Mask" "B.Paste")
			(net "P1V25_SERDES_VDDPLL_PEX1")
		)
		(pad "2" smd rect
			(at -0.7366 0)
			(size 0.7112 0.8128)
			(layers "B.Cu" "B.Mask" "B.Paste")
			(net "GND")
		)
	)
	(footprint ""
		(layer "B.Cu")
		(at 298.499784 -299.699934 -90)
		(property "Reference" "C1684"
			(at 0 0 90)
			(layer "B.SilkS")
			(hide yes)
			(effects
				(font
					(size 1.27 1.27)
				)
				(justify mirror)
			)
		)
		(property "Value" ""
			(at 0 0 90)
			(layer "B.Fab")
			(effects
				(font
					(size 1.27 1.27)
				)
				(justify mirror)
			)
		)
		(duplicate_pad_numbers_are_jumpers no)
		(fp_line
			(start -0.299974 0.150114)
			(end 0.299974 0.150114)
			(stroke
				(width 0.1)
				(type default)
			)
			(layer "B.Fab")
		)
		(fp_line
			(start 0.299974 0.150114)
			(end 0.299974 -0.150114)
			(stroke
				(width 0.1)
				(type default)
			)
			(layer "B.Fab")
		)
		(fp_line
			(start -0.299974 -0.150114)
			(end -0.299974 0.150114)
			(stroke
				(width 0.1)
				(type default)
			)
			(layer "B.Fab")
		)
		(fp_line
			(start 0.299974 -0.150114)
			(end -0.299974 -0.150114)
			(stroke
				(width 0.1)
				(type default)
			)
			(layer "B.Fab")
		)
		(pad "1" smd rect
			(at 0.2667 0 90)
			(size 0.3048 0.381)
			(layers "B.Cu" "B.Mask" "B.Paste")
			(net "P0V8_SERDES_VDDA_PEX2")
		)
		(pad "2" smd rect
			(at -0.2667 0 90)
			(size 0.3048 0.381)
			(layers "B.Cu" "B.Mask" "B.Paste")
			(net "GND")
		)
	)
	(footprint ""
		(layer "B.Cu")
		(at 256.03327 -207.507078 180)
		(property "Reference" "R4299"
			(at 0 0 0)
			(layer "B.SilkS")
			(hide yes)
			(effects
				(font
					(size 1.27 1.27)
				)
				(justify mirror)
			)
		)
		(property "Value" ""
			(at 0 0 0)
			(layer "B.Fab")
			(effects
				(font
					(size 1.27 1.27)
				)
				(justify mirror)
			)
		)
		(duplicate_pad_numbers_are_jumpers no)
		(fp_line
			(start 0.7874 0.4064)
			(end 0.7874 -0.4064)
			(stroke
				(width 0.1524)
				(type default)
			)
			(layer "B.SilkS")
		)
		(fp_line
			(start 0.7874 -0.4064)
			(end -0.7874 -0.4064)
			(stroke
				(width 0.1524)
				(type default)
			)
			(layer "B.SilkS")
		)
		(fp_line
			(start -0.7874 0.4064)
			(end 0.7874 0.4064)
			(stroke
				(width 0.1524)
				(type default)
			)
			(layer "B.SilkS")
		)
		(fp_line
			(start -0.7874 -0.4064)
			(end -0.7874 0.4064)
			(stroke
				(width 0.1524)
				(type default)
			)
			(layer "B.SilkS")
		)
		(fp_line
			(start 0.67945 0.3048)
			(end 0.67945 -0.305054)
			(stroke
				(width 0.1)
				(type default)
			)
			(layer "B.Fab")
		)
		(fp_line
			(start 0.67945 -0.305054)
			(end 0.12065 -0.305054)
			(stroke
				(width 0.1)
				(type default)
			)
			(layer "B.Fab")
		)
		(fp_line
			(start 0.12065 0.3048)
			(end 0.67945 0.3048)
			(stroke
				(width 0.1)
				(type default)
			)
			(layer "B.Fab")
		)
		(fp_line
			(start 0.12065 0.2794)
			(end 0.12065 0.3048)
			(stroke
				(width 0.1)
				(type default)
			)
			(layer "B.Fab")
		)
		(fp_line
			(start 0.12065 -0.2794)
			(end -0.12065 -0.2794)
			(stroke
				(width 0.1)
				(type default)
			)
			(layer "B.Fab")
		)
		(fp_line
			(start 0.12065 -0.305054)
			(end 0.12065 -0.2794)
			(stroke
				(width 0.1)
				(type default)
			)
			(layer "B.Fab")
		)
		(fp_line
			(start -0.120396 0.3048)
			(end -0.120396 0.2794)
			(stroke
				(width 0.1)
				(type default)
			)
			(layer "B.Fab")
		)
		(fp_line
			(start -0.120396 0.2794)
			(end 0.12065 0.2794)
			(stroke
				(width 0.1)
				(type default)
			)
			(layer "B.Fab")
		)
		(fp_line
			(start -0.12065 -0.2794)
			(end -0.12065 -0.3048)
			(stroke
				(width 0.1)
				(type default)
			)
			(layer "B.Fab")
		)
		(fp_line
			(start -0.12065 -0.3048)
			(end -0.67945 -0.3048)
			(stroke
				(width 0.1)
				(type default)
			)
			(layer "B.Fab")
		)
		(fp_line
			(start -0.67945 0.3048)
			(end -0.120396 0.3048)
			(stroke
				(width 0.1)
				(type default)
			)
			(layer "B.Fab")
		)
		(fp_line
			(start -0.67945 -0.3048)
			(end -0.67945 0.3048)
			(stroke
				(width 0.1)
				(type default)
			)
			(layer "B.Fab")
		)
		(pad "1" smd circle
			(at 0.40005 0)
			(size 0 0)
			(layers "B.Cu" "B.Mask" "B.Paste")
			(net "JTAG_PLD_TDI")
		)
		(pad "2" smd circle
			(at -0.40005 0)
			(size 0 0)
			(layers "B.Cu" "B.Mask" "B.Paste")
			(net "JTAG_FPGA_TDI")
		)
	)
	(footprint ""
		(layer "B.Cu")
		(at 380.990602 -235.01096)
		(property "Reference" "C2583"
			(at 0 0 0)
			(layer "B.SilkS")
			(hide yes)
			(effects
				(font
					(size 1.27 1.27)
				)
				(justify mirror)
			)
		)
		(property "Value" ""
			(at 0 0 0)
			(layer "B.Fab")
			(effects
				(font
					(size 1.27 1.27)
				)
				(justify mirror)
			)
		)
		(duplicate_pad_numbers_are_jumpers no)
		(fp_line
			(start -1.2954 -0.5842)
			(end -1.2954 0.5842)
			(stroke
				(width 0.1524)
				(type default)
			)
			(layer "B.SilkS")
		)
		(fp_line
			(start -1.2954 0.5842)
			(end 1.2954 0.5842)
			(stroke
				(width 0.1524)
				(type default)
			)
			(layer "B.SilkS")
		)
		(fp_line
			(start 1.2954 -0.5842)
			(end -1.2954 -0.5842)
			(stroke
				(width 0.1524)
				(type default)
			)
			(layer "B.SilkS")
		)
		(fp_line
			(start 1.2954 0.5842)
			(end 1.2954 -0.5842)
			(stroke
				(width 0.1524)
				(type default)
			)
			(layer "B.SilkS")
		)
		(fp_line
			(start -1.1938 -0.4064)
			(end -1.1938 0.4064)
			(stroke
				(width 0.1)
				(type default)
			)
			(layer "B.Fab")
		)
		(fp_line
			(start -1.1938 0.4064)
			(end -0.8636 0.4064)
			(stroke
				(width 0.1)
				(type default)
			)
			(layer "B.Fab")
		)
		(fp_line
			(start -0.8636 -0.4572)
			(end -0.8636 -0.4064)
			(stroke
				(width 0.1)
				(type default)
			)
			(layer "B.Fab")
		)
		(fp_line
			(start -0.8636 -0.4064)
			(end -1.1938 -0.4064)
			(stroke
				(width 0.1)
				(type default)
			)
			(layer "B.Fab")
		)
		(fp_line
			(start -0.8636 0.4064)
			(end -0.8636 0.4572)
			(stroke
				(width 0.1)
				(type default)
			)
			(layer "B.Fab")
		)
		(fp_line
			(start -0.8636 0.4572)
			(end 0.8636 0.4572)
			(stroke
				(width 0.1)
				(type default)
			)
			(layer "B.Fab")
		)
		(fp_line
			(start 0.8636 -0.4572)
			(end -0.8636 -0.4572)
			(stroke
				(width 0.1)
				(type default)
			)
			(layer "B.Fab")
		)
		(fp_line
			(start 0.8636 -0.4064)
			(end 0.8636 -0.4572)
			(stroke
				(width 0.1)
				(type default)
			)
			(layer "B.Fab")
		)
		(fp_line
			(start 0.8636 0.4064)
			(end 1.1938 0.4064)
			(stroke
				(width 0.1)
				(type default)
			)
			(layer "B.Fab")
		)
		(fp_line
			(start 0.8636 0.4572)
			(end 0.8636 0.4064)
			(stroke
				(width 0.1)
				(type default)
			)
			(layer "B.Fab")
		)
		(fp_line
			(start 1.1938 -0.4064)
			(end 0.8636 -0.4064)
			(stroke
				(width 0.1)
				(type default)
			)
			(layer "B.Fab")
		)
		(fp_line
			(start 1.1938 0.4064)
			(end 1.1938 -0.4064)
			(stroke
				(width 0.1)
				(type default)
			)
			(layer "B.Fab")
		)
		(pad "1" smd rect
			(at 0.7366 0 270)
			(size 0.7112 0.8128)
			(layers "B.Cu" "B.Mask" "B.Paste")
			(net "P3V3_SDB_VPHY")
		)
		(pad "2" smd rect
			(at -0.7366 0 270)
			(size 0.7112 0.8128)
			(layers "B.Cu" "B.Mask" "B.Paste")
			(net "GND")
		)
	)
	(footprint ""
		(layer "B.Cu")
		(at 421.249856 -296.8498 180)
		(property "Reference" "C3468"
			(at 0 0 0)
			(layer "B.SilkS")
			(hide yes)
			(effects
				(font
					(size 1.27 1.27)
				)
				(justify mirror)
			)
		)
		(property "Value" ""
			(at 0 0 0)
			(layer "B.Fab")
			(effects
				(font
					(size 1.27 1.27)
				)
				(justify mirror)
			)
		)
		(duplicate_pad_numbers_are_jumpers no)
		(fp_line
			(start 0.299974 0.150114)
			(end 0.299974 -0.150114)
			(stroke
				(width 0.1)
				(type default)
			)
			(layer "B.Fab")
		)
		(fp_line
			(start 0.299974 -0.150114)
			(end -0.299974 -0.150114)
			(stroke
				(width 0.1)
				(type default)
			)
			(layer "B.Fab")
		)
		(fp_line
			(start -0.299974 0.150114)
			(end 0.299974 0.150114)
			(stroke
				(width 0.1)
				(type default)
			)
			(layer "B.Fab")
		)
		(fp_line
			(start -0.299974 -0.150114)
			(end -0.299974 0.150114)
			(stroke
				(width 0.1)
				(type default)
			)
			(layer "B.Fab")
		)
		(pad "1" smd rect
			(at 0.2667 0)
			(size 0.3048 0.381)
			(layers "B.Cu" "B.Mask" "B.Paste")
			(net "P1V25_SERDES_VDDPLL_PEX3")
		)
		(pad "2" smd rect
			(at -0.2667 0)
			(size 0.3048 0.381)
			(layers "B.Cu" "B.Mask" "B.Paste")
			(net "GND")
		)
	)
	(footprint ""
		(layer "B.Cu")
		(at 416.499802 -293.52494 180)
		(property "Reference" "C1868"
			(at 0 0 0)
			(layer "B.SilkS")
			(hide yes)
			(effects
				(font
					(size 1.27 1.27)
				)
				(justify mirror)
			)
		)
		(property "Value" ""
			(at 0 0 0)
			(layer "B.Fab")
			(effects
				(font
					(size 1.27 1.27)
				)
				(justify mirror)
			)
		)
		(duplicate_pad_numbers_are_jumpers no)
		(fp_line
			(start 0.299974 0.150114)
			(end 0.299974 -0.150114)
			(stroke
				(width 0.1)
				(type default)
			)
			(layer "B.Fab")
		)
		(fp_line
			(start 0.299974 -0.150114)
			(end -0.299974 -0.150114)
			(stroke
				(width 0.1)
				(type default)
			)
			(layer "B.Fab")
		)
		(fp_line
			(start -0.299974 0.150114)
			(end 0.299974 0.150114)
			(stroke
				(width 0.1)
				(type default)
			)
			(layer "B.Fab")
		)
		(fp_line
			(start -0.299974 -0.150114)
			(end -0.299974 0.150114)
			(stroke
				(width 0.1)
				(type default)
			)
			(layer "B.Fab")
		)
		(pad "1" smd rect
			(at 0.2667 0)
			(size 0.3048 0.381)
			(layers "B.Cu" "B.Mask" "B.Paste")
			(net "P0V8_PEX3")
		)
		(pad "2" smd rect
			(at -0.2667 0)
			(size 0.3048 0.381)
			(layers "B.Cu" "B.Mask" "B.Paste")
			(net "GND")
		)
	)
	(footprint ""
		(layer "B.Cu")
		(at 128.095248 -173.095412)
		(property "Reference" "L11"
			(at 0 0 0)
			(layer "B.SilkS")
			(hide yes)
			(effects
				(font
					(size 1.27 1.27)
				)
				(justify mirror)
			)
		)
		(property "Value" ""
			(at 0 0 0)
			(layer "B.Fab")
			(effects
				(font
					(size 1.27 1.27)
				)
				(justify mirror)
			)
		)
		(duplicate_pad_numbers_are_jumpers no)
		(fp_line
			(start -1.27 0.5842)
			(end -1.27 -0.5842)
			(stroke
				(width 0.1524)
				(type default)
			)
			(layer "B.SilkS")
		)
		(fp_line
			(start -1.27 0.5842)
			(end 1.27 0.5842)
			(stroke
				(width 0.1524)
				(type default)
			)
			(layer "B.SilkS")
		)
		(fp_line
			(start 1.27 -0.5842)
			(end -1.27 -0.5842)
			(stroke
				(width 0.1524)
				(type default)
			)
			(layer "B.SilkS")
		)
		(fp_line
			(start 1.27 -0.5588)
			(end 1.27 -0.5842)
			(stroke
				(width 0.1524)
				(type default)
			)
			(layer "B.SilkS")
		)
		(fp_line
			(start 1.27 0.5842)
			(end 1.27 -0.5842)
			(stroke
				(width 0.1524)
				(type default)
			)
			(layer "B.SilkS")
		)
		(fp_line
			(start -1.1938 -0.406654)
			(end -1.1938 0.4064)
			(stroke
				(width 0.1)
				(type default)
			)
			(layer "B.Fab")
		)
		(fp_line
			(start -1.1938 0.4064)
			(end -0.9144 0.4064)
			(stroke
				(width 0.1)
				(type default)
			)
			(layer "B.Fab")
		)
		(fp_line
			(start -0.9144 -0.508)
			(end -0.9144 -0.406654)
			(stroke
				(width 0.1)
				(type default)
			)
			(layer "B.Fab")
		)
		(fp_line
			(start -0.9144 -0.406654)
			(end -1.1938 -0.406654)
			(stroke
				(width 0.1)
				(type default)
			)
			(layer "B.Fab")
		)
		(fp_line
			(start -0.9144 0.4064)
			(end -0.9144 0.508)
			(stroke
				(width 0.1)
				(type default)
			)
			(layer "B.Fab")
		)
		(fp_line
			(start -0.9144 0.508)
			(end 0.9144 0.508)
			(stroke
				(width 0.1)
				(type default)
			)
			(layer "B.Fab")
		)
		(fp_line
			(start 0.9144 -0.508)
			(end -0.9144 -0.508)
			(stroke
				(width 0.1)
				(type default)
			)
			(layer "B.Fab")
		)
		(fp_line
			(start 0.9144 -0.406654)
			(end 0.9144 -0.508)
			(stroke
				(width 0.1)
				(type default)
			)
			(layer "B.Fab")
		)
		(fp_line
			(start 0.9144 0.406654)
			(end 1.194308 0.406654)
			(stroke
				(width 0.1)
				(type default)
			)
			(layer "B.Fab")
		)
		(fp_line
			(start 0.9144 0.508)
			(end 0.9144 0.406654)
			(stroke
				(width 0.1)
				(type default)
			)
			(layer "B.Fab")
		)
		(fp_line
			(start 1.194308 -0.406654)
			(end 0.9144 -0.406654)
			(stroke
				(width 0.1)
				(type default)
			)
			(layer "B.Fab")
		)
		(fp_line
			(start 1.194308 0.406654)
			(end 1.194308 -0.406654)
			(stroke
				(width 0.1)
				(type default)
			)
			(layer "B.Fab")
		)
		(pad "1" smd rect
			(at 0.7366 0 270)
			(size 0.7112 0.8128)
			(layers "B.Cu" "B.Mask" "B.Paste")
			(net "P3V3")
		)
		(pad "2" smd rect
			(at -0.7366 0 270)
			(size 0.7112 0.8128)
			(layers "B.Cu" "B.Mask" "B.Paste")
			(net "P3V3_DB2000QL_FB_VDD")
		)
	)
	(footprint ""
		(layer "B.Cu")
		(at 422.326816 -299.2247 90)
		(property "Reference" "R1448"
			(at 0 0 90)
			(layer "B.SilkS")
			(hide yes)
			(effects
				(font
					(size 1.27 1.27)
				)
				(justify mirror)
			)
		)
		(property "Value" ""
			(at 0 0 90)
			(layer "B.Fab")
			(effects
				(font
					(size 1.27 1.27)
				)
				(justify mirror)
			)
		)
		(duplicate_pad_numbers_are_jumpers no)
		(fp_line
			(start 0.7874 -0.4064)
			(end -0.7874 -0.4064)
			(stroke
				(width 0.1524)
				(type default)
			)
			(layer "B.SilkS")
		)
		(fp_line
			(start -0.7874 -0.4064)
			(end -0.7874 0.4064)
			(stroke
				(width 0.1524)
				(type default)
			)
			(layer "B.SilkS")
		)
		(fp_line
			(start 0.7874 0.4064)
			(end 0.7874 -0.4064)
			(stroke
				(width 0.1524)
				(type default)
			)
			(layer "B.SilkS")
		)
		(fp_line
			(start -0.7874 0.4064)
			(end 0.7874 0.4064)
			(stroke
				(width 0.1524)
				(type default)
			)
			(layer "B.SilkS")
		)
		(fp_line
			(start 0.67945 -0.305054)
			(end 0.12065 -0.305054)
			(stroke
				(width 0.1)
				(type default)
			)
			(layer "B.Fab")
		)
		(fp_line
			(start 0.12065 -0.305054)
			(end 0.12065 -0.2794)
			(stroke
				(width 0.1)
				(type default)
			)
			(layer "B.Fab")
		)
		(fp_line
			(start -0.12065 -0.3048)
			(end -0.67945 -0.3048)
			(stroke
				(width 0.1)
				(type default)
			)
			(layer "B.Fab")
		)
		(fp_line
			(start -0.67945 -0.3048)
			(end -0.67945 0.3048)
			(stroke
				(width 0.1)
				(type default)
			)
			(layer "B.Fab")
		)
		(fp_line
			(start 0.12065 -0.2794)
			(end -0.12065 -0.2794)
			(stroke
				(width 0.1)
				(type default)
			)
			(layer "B.Fab")
		)
		(fp_line
			(start -0.12065 -0.2794)
			(end -0.12065 -0.3048)
			(stroke
				(width 0.1)
				(type default)
			)
			(layer "B.Fab")
		)
		(fp_line
			(start 0.12065 0.2794)
			(end 0.12065 0.3048)
			(stroke
				(width 0.1)
				(type default)
			)
			(layer "B.Fab")
		)
		(fp_line
			(start -0.120396 0.2794)
			(end 0.12065 0.2794)
			(stroke
				(width 0.1)
				(type default)
			)
			(layer "B.Fab")
		)
		(fp_line
			(start 0.67945 0.3048)
			(end 0.67945 -0.305054)
			(stroke
				(width 0.1)
				(type default)
			)
			(layer "B.Fab")
		)
		(fp_line
			(start 0.12065 0.3048)
			(end 0.67945 0.3048)
			(stroke
				(width 0.1)
				(type default)
			)
			(layer "B.Fab")
		)
		(fp_line
			(start -0.120396 0.3048)
			(end -0.120396 0.2794)
			(stroke
				(width 0.1)
				(type default)
			)
			(layer "B.Fab")
		)
		(fp_line
			(start -0.67945 0.3048)
			(end -0.120396 0.3048)
			(stroke
				(width 0.1)
				(type default)
			)
			(layer "B.Fab")
		)
		(pad "1" smd circle
			(at 0.40005 0 270)
			(size 0 0)
			(layers "B.Cu" "B.Mask" "B.Paste")
			(net "PEX3_ADCTEMP_VINP1")
		)
		(pad "2" smd circle
			(at -0.40005 0 270)
			(size 0 0)
			(layers "B.Cu" "B.Mask" "B.Paste")
			(net "GND")
		)
	)
	(footprint ""
		(layer "B.Cu")
		(at 303.249838 -293.52494 180)
		(property "Reference" "C3288"
			(at 0 0 0)
			(layer "B.SilkS")
			(hide yes)
			(effects
				(font
					(size 1.27 1.27)
				)
				(justify mirror)
			)
		)
		(property "Value" ""
			(at 0 0 0)
			(layer "B.Fab")
			(effects
				(font
					(size 1.27 1.27)
				)
				(justify mirror)
			)
		)
		(duplicate_pad_numbers_are_jumpers no)
		(fp_line
			(start 0.299974 0.150114)
			(end 0.299974 -0.150114)
			(stroke
				(width 0.1)
				(type default)
			)
			(layer "B.Fab")
		)
		(fp_line
			(start 0.299974 -0.150114)
			(end -0.299974 -0.150114)
			(stroke
				(width 0.1)
				(type default)
			)
			(layer "B.Fab")
		)
		(fp_line
			(start -0.299974 0.150114)
			(end 0.299974 0.150114)
			(stroke
				(width 0.1)
				(type default)
			)
			(layer "B.Fab")
		)
		(fp_line
			(start -0.299974 -0.150114)
			(end -0.299974 0.150114)
			(stroke
				(width 0.1)
				(type default)
			)
			(layer "B.Fab")
		)
		(pad "1" smd rect
			(at 0.2667 0)
			(size 0.3048 0.381)
			(layers "B.Cu" "B.Mask" "B.Paste")
			(net "P1V25_PEX2")
		)
		(pad "2" smd rect
			(at -0.2667 0)
			(size 0.3048 0.381)
			(layers "B.Cu" "B.Mask" "B.Paste")
			(net "GND")
		)
	)
	(footprint ""
		(layer "B.Cu")
		(at 337.967828 -323.15531 -90)
		(property "Reference" "R6518"
			(at 0 0 90)
			(layer "B.SilkS")
			(hide yes)
			(effects
				(font
					(size 1.27 1.27)
				)
				(justify mirror)
			)
		)
		(property "Value" ""
			(at 0 0 90)
			(layer "B.Fab")
			(effects
				(font
					(size 1.27 1.27)
				)
				(justify mirror)
			)
		)
		(duplicate_pad_numbers_are_jumpers no)
		(fp_line
			(start -0.7874 0.4064)
			(end 0.7874 0.4064)
			(stroke
				(width 0.1524)
				(type default)
			)
			(layer "B.SilkS")
		)
		(fp_line
			(start 0.7874 0.4064)
			(end 0.7874 -0.4064)
			(stroke
				(width 0.1524)
				(type default)
			)
			(layer "B.SilkS")
		)
		(fp_line
			(start -0.7874 -0.4064)
			(end -0.7874 0.4064)
			(stroke
				(width 0.1524)
				(type default)
			)
			(layer "B.SilkS")
		)
		(fp_line
			(start 0.7874 -0.4064)
			(end -0.7874 -0.4064)
			(stroke
				(width 0.1524)
				(type default)
			)
			(layer "B.SilkS")
		)
		(fp_line
			(start -0.67945 0.3048)
			(end -0.120396 0.3048)
			(stroke
				(width 0.1)
				(type default)
			)
			(layer "B.Fab")
		)
		(fp_line
			(start -0.120396 0.3048)
			(end -0.120396 0.2794)
			(stroke
				(width 0.1)
				(type default)
			)
			(layer "B.Fab")
		)
		(fp_line
			(start 0.12065 0.3048)
			(end 0.67945 0.3048)
			(stroke
				(width 0.1)
				(type default)
			)
			(layer "B.Fab")
		)
		(fp_line
			(start 0.67945 0.3048)
			(end 0.67945 -0.305054)
			(stroke
				(width 0.1)
				(type default)
			)
			(layer "B.Fab")
		)
		(fp_line
			(start -0.120396 0.2794)
			(end 0.12065 0.2794)
			(stroke
				(width 0.1)
				(type default)
			)
			(layer "B.Fab")
		)
		(fp_line
			(start 0.12065 0.2794)
			(end 0.12065 0.3048)
			(stroke
				(width 0.1)
				(type default)
			)
			(layer "B.Fab")
		)
		(fp_line
			(start -0.12065 -0.2794)
			(end -0.12065 -0.3048)
			(stroke
				(width 0.1)
				(type default)
			)
			(layer "B.Fab")
		)
		(fp_line
			(start 0.12065 -0.2794)
			(end -0.12065 -0.2794)
			(stroke
				(width 0.1)
				(type default)
			)
			(layer "B.Fab")
		)
		(fp_line
			(start -0.67945 -0.3048)
			(end -0.67945 0.3048)
			(stroke
				(width 0.1)
				(type default)
			)
			(layer "B.Fab")
		)
		(fp_line
			(start -0.12065 -0.3048)
			(end -0.67945 -0.3048)
			(stroke
				(width 0.1)
				(type default)
			)
			(layer "B.Fab")
		)
		(fp_line
			(start 0.12065 -0.305054)
			(end 0.12065 -0.2794)
			(stroke
				(width 0.1)
				(type default)
			)
			(layer "B.Fab")
		)
		(fp_line
			(start 0.67945 -0.305054)
			(end 0.12065 -0.305054)
			(stroke
				(width 0.1)
				(type default)
			)
			(layer "B.Fab")
		)
		(pad "1" smd circle
			(at 0.40005 0 90)
			(size 0 0)
			(layers "B.Cu" "B.Mask" "B.Paste")
			(net "P0V8_SERDES_VDDA_PEX2")
		)
		(pad "2" smd circle
			(at -0.40005 0 90)
			(size 0 0)
			(layers "B.Cu" "B.Mask" "B.Paste")
			(net "P0V8_SERDES_VDDA_PEX2_C11")
		)
	)
	(footprint ""
		(layer "B.Cu")
		(at 278.554942 -299.212)
		(property "Reference" "C3374"
			(at 0 0 0)
			(layer "B.SilkS")
			(hide yes)
			(effects
				(font
					(size 1.27 1.27)
				)
				(justify mirror)
			)
		)
		(property "Value" ""
			(at 0 0 0)
			(layer "B.Fab")
			(effects
				(font
					(size 1.27 1.27)
				)
				(justify mirror)
			)
		)
		(duplicate_pad_numbers_are_jumpers no)
		(fp_line
			(start -0.299974 -0.150114)
			(end -0.299974 0.150114)
			(stroke
				(width 0.1)
				(type default)
			)
			(layer "B.Fab")
		)
		(fp_line
			(start -0.299974 0.150114)
			(end 0.299974 0.150114)
			(stroke
				(width 0.1)
				(type default)
			)
			(layer "B.Fab")
		)
		(fp_line
			(start 0.299974 -0.150114)
			(end -0.299974 -0.150114)
			(stroke
				(width 0.1)
				(type default)
			)
			(layer "B.Fab")
		)
		(fp_line
			(start 0.299974 0.150114)
			(end 0.299974 -0.150114)
			(stroke
				(width 0.1)
				(type default)
			)
			(layer "B.Fab")
		)
		(pad "1" smd rect
			(at 0.2667 0 180)
			(size 0.3048 0.381)
			(layers "B.Cu" "B.Mask" "B.Paste")
			(net "PCEPLL1_VDDA18_PEX2")
		)
		(pad "2" smd rect
			(at -0.2667 0 180)
			(size 0.3048 0.381)
			(layers "B.Cu" "B.Mask" "B.Paste")
			(net "GND")
		)
	)
	(footprint ""
		(layer "B.Cu")
		(at 347.025214 -282.244292 180)
		(property "Reference" "PR7172"
			(at 0 0 0)
			(layer "B.SilkS")
			(hide yes)
			(effects
				(font
					(size 1.27 1.27)
				)
				(justify mirror)
			)
		)
		(property "Value" ""
			(at 0 0 0)
			(layer "B.Fab")
			(effects
				(font
					(size 1.27 1.27)
				)
				(justify mirror)
			)
		)
		(duplicate_pad_numbers_are_jumpers no)
		(fp_line
			(start 0.7874 0.4064)
			(end 0.7874 -0.4064)
			(stroke
				(width 0.1524)
				(type default)
			)
			(layer "B.SilkS")
		)
		(fp_line
			(start 0.7874 -0.4064)
			(end -0.7874 -0.4064)
			(stroke
				(width 0.1524)
				(type default)
			)
			(layer "B.SilkS")
		)
		(fp_line
			(start -0.7874 0.4064)
			(end 0.7874 0.4064)
			(stroke
				(width 0.1524)
				(type default)
			)
			(layer "B.SilkS")
		)
		(fp_line
			(start -0.7874 -0.4064)
			(end -0.7874 0.4064)
			(stroke
				(width 0.1524)
				(type default)
			)
			(layer "B.SilkS")
		)
		(fp_line
			(start 0.67945 0.3048)
			(end 0.67945 -0.305054)
			(stroke
				(width 0.1)
				(type default)
			)
			(layer "B.Fab")
		)
		(fp_line
			(start 0.67945 -0.305054)
			(end 0.12065 -0.305054)
			(stroke
				(width 0.1)
				(type default)
			)
			(layer "B.Fab")
		)
		(fp_line
			(start 0.12065 0.3048)
			(end 0.67945 0.3048)
			(stroke
				(width 0.1)
				(type default)
			)
			(layer "B.Fab")
		)
		(fp_line
			(start 0.12065 0.2794)
			(end 0.12065 0.3048)
			(stroke
				(width 0.1)
				(type default)
			)
			(layer "B.Fab")
		)
		(fp_line
			(start 0.12065 -0.2794)
			(end -0.12065 -0.2794)
			(stroke
				(width 0.1)
				(type default)
			)
			(layer "B.Fab")
		)
		(fp_line
			(start 0.12065 -0.305054)
			(end 0.12065 -0.2794)
			(stroke
				(width 0.1)
				(type default)
			)
			(layer "B.Fab")
		)
		(fp_line
			(start -0.120396 0.3048)
			(end -0.120396 0.2794)
			(stroke
				(width 0.1)
				(type default)
			)
			(layer "B.Fab")
		)
		(fp_line
			(start -0.120396 0.2794)
			(end 0.12065 0.2794)
			(stroke
				(width 0.1)
				(type default)
			)
			(layer "B.Fab")
		)
		(fp_line
			(start -0.12065 -0.2794)
			(end -0.12065 -0.3048)
			(stroke
				(width 0.1)
				(type default)
			)
			(layer "B.Fab")
		)
		(fp_line
			(start -0.12065 -0.3048)
			(end -0.67945 -0.3048)
			(stroke
				(width 0.1)
				(type default)
			)
			(layer "B.Fab")
		)
		(fp_line
			(start -0.67945 0.3048)
			(end -0.120396 0.3048)
			(stroke
				(width 0.1)
				(type default)
			)
			(layer "B.Fab")
		)
		(fp_line
			(start -0.67945 -0.3048)
			(end -0.67945 0.3048)
			(stroke
				(width 0.1)
				(type default)
			)
			(layer "B.Fab")
		)
		(pad "1" smd circle
			(at 0.40005 0)
			(size 0 0)
			(layers "B.Cu" "B.Mask" "B.Paste")
			(net "P0V8_PEX2_EN2")
		)
		(pad "2" smd circle
			(at -0.40005 0)
			(size 0 0)
			(layers "B.Cu" "B.Mask" "B.Paste")
			(net "P0V8_PEX2_VCC2")
		)
	)
	(footprint ""
		(layer "B.Cu")
		(at 106.70032 -282.251404 180)
		(property "Reference" "PR7167"
			(at 0 0 0)
			(layer "B.SilkS")
			(hide yes)
			(effects
				(font
					(size 1.27 1.27)
				)
				(justify mirror)
			)
		)
		(property "Value" ""
			(at 0 0 0)
			(layer "B.Fab")
			(effects
				(font
					(size 1.27 1.27)
				)
				(justify mirror)
			)
		)
		(duplicate_pad_numbers_are_jumpers no)
		(fp_line
			(start 0.7874 0.4064)
			(end 0.7874 -0.4064)
			(stroke
				(width 0.1524)
				(type default)
			)
			(layer "B.SilkS")
		)
		(fp_line
			(start 0.7874 -0.4064)
			(end -0.7874 -0.4064)
			(stroke
				(width 0.1524)
				(type default)
			)
			(layer "B.SilkS")
		)
		(fp_line
			(start -0.7874 0.4064)
			(end 0.7874 0.4064)
			(stroke
				(width 0.1524)
				(type default)
			)
			(layer "B.SilkS")
		)
		(fp_line
			(start -0.7874 -0.4064)
			(end -0.7874 0.4064)
			(stroke
				(width 0.1524)
				(type default)
			)
			(layer "B.SilkS")
		)
		(fp_line
			(start 0.67945 0.3048)
			(end 0.67945 -0.305054)
			(stroke
				(width 0.1)
				(type default)
			)
			(layer "B.Fab")
		)
		(fp_line
			(start 0.67945 -0.305054)
			(end 0.12065 -0.305054)
			(stroke
				(width 0.1)
				(type default)
			)
			(layer "B.Fab")
		)
		(fp_line
			(start 0.12065 0.3048)
			(end 0.67945 0.3048)
			(stroke
				(width 0.1)
				(type default)
			)
			(layer "B.Fab")
		)
		(fp_line
			(start 0.12065 0.2794)
			(end 0.12065 0.3048)
			(stroke
				(width 0.1)
				(type default)
			)
			(layer "B.Fab")
		)
		(fp_line
			(start 0.12065 -0.2794)
			(end -0.12065 -0.2794)
			(stroke
				(width 0.1)
				(type default)
			)
			(layer "B.Fab")
		)
		(fp_line
			(start 0.12065 -0.305054)
			(end 0.12065 -0.2794)
			(stroke
				(width 0.1)
				(type default)
			)
			(layer "B.Fab")
		)
		(fp_line
			(start -0.120396 0.3048)
			(end -0.120396 0.2794)
			(stroke
				(width 0.1)
				(type default)
			)
			(layer "B.Fab")
		)
		(fp_line
			(start -0.120396 0.2794)
			(end 0.12065 0.2794)
			(stroke
				(width 0.1)
				(type default)
			)
			(layer "B.Fab")
		)
		(fp_line
			(start -0.12065 -0.2794)
			(end -0.12065 -0.3048)
			(stroke
				(width 0.1)
				(type default)
			)
			(layer "B.Fab")
		)
		(fp_line
			(start -0.12065 -0.3048)
			(end -0.67945 -0.3048)
			(stroke
				(width 0.1)
				(type default)
			)
			(layer "B.Fab")
		)
		(fp_line
			(start -0.67945 0.3048)
			(end -0.120396 0.3048)
			(stroke
				(width 0.1)
				(type default)
			)
			(layer "B.Fab")
		)
		(fp_line
			(start -0.67945 -0.3048)
			(end -0.67945 0.3048)
			(stroke
				(width 0.1)
				(type default)
			)
			(layer "B.Fab")
		)
		(pad "1" smd circle
			(at 0.40005 0)
			(size 0 0)
			(layers "B.Cu" "B.Mask" "B.Paste")
			(net "P0V8_PEX0_EN1")
		)
		(pad "2" smd circle
			(at -0.40005 0)
			(size 0 0)
			(layers "B.Cu" "B.Mask" "B.Paste")
			(net "P0V8_PEX0_VCC1")
		)
	)
	(footprint ""
		(layer "B.Cu")
		(at 135.190992 -174.192438 90)
		(property "Reference" "C2658"
			(at 0 0 90)
			(layer "B.SilkS")
			(hide yes)
			(effects
				(font
					(size 1.27 1.27)
				)
				(justify mirror)
			)
		)
		(property "Value" ""
			(at 0 0 90)
			(layer "B.Fab")
			(effects
				(font
					(size 1.27 1.27)
				)
				(justify mirror)
			)
		)
		(duplicate_pad_numbers_are_jumpers no)
		(fp_line
			(start 0.7874 -0.4064)
			(end -0.7874 -0.4064)
			(stroke
				(width 0.1524)
				(type default)
			)
			(layer "B.SilkS")
		)
		(fp_line
			(start -0.7874 -0.4064)
			(end -0.7874 0.4064)
			(stroke
				(width 0.1524)
				(type default)
			)
			(layer "B.SilkS")
		)
		(fp_line
			(start 0.7874 0.4064)
			(end 0.7874 -0.4064)
			(stroke
				(width 0.1524)
				(type default)
			)
			(layer "B.SilkS")
		)
		(fp_line
			(start -0.7874 0.4064)
			(end 0.7874 0.4064)
			(stroke
				(width 0.1524)
				(type default)
			)
			(layer "B.SilkS")
		)
		(fp_line
			(start 0.67945 -0.305054)
			(end 0.12065 -0.305054)
			(stroke
				(width 0.1)
				(type default)
			)
			(layer "B.Fab")
		)
		(fp_line
			(start 0.12065 -0.305054)
			(end 0.12065 -0.2794)
			(stroke
				(width 0.1)
				(type default)
			)
			(layer "B.Fab")
		)
		(fp_line
			(start -0.12065 -0.3048)
			(end -0.67945 -0.3048)
			(stroke
				(width 0.1)
				(type default)
			)
			(layer "B.Fab")
		)
		(fp_line
			(start -0.67945 -0.3048)
			(end -0.67945 0.3048)
			(stroke
				(width 0.1)
				(type default)
			)
			(layer "B.Fab")
		)
		(fp_line
			(start 0.12065 -0.2794)
			(end -0.12065 -0.2794)
			(stroke
				(width 0.1)
				(type default)
			)
			(layer "B.Fab")
		)
		(fp_line
			(start -0.12065 -0.2794)
			(end -0.12065 -0.3048)
			(stroke
				(width 0.1)
				(type default)
			)
			(layer "B.Fab")
		)
		(fp_line
			(start 0.12065 0.2794)
			(end 0.12065 0.3048)
			(stroke
				(width 0.1)
				(type default)
			)
			(layer "B.Fab")
		)
		(fp_line
			(start -0.120396 0.2794)
			(end 0.12065 0.2794)
			(stroke
				(width 0.1)
				(type default)
			)
			(layer "B.Fab")
		)
		(fp_line
			(start 0.67945 0.3048)
			(end 0.67945 -0.305054)
			(stroke
				(width 0.1)
				(type default)
			)
			(layer "B.Fab")
		)
		(fp_line
			(start 0.12065 0.3048)
			(end 0.67945 0.3048)
			(stroke
				(width 0.1)
				(type default)
			)
			(layer "B.Fab")
		)
		(fp_line
			(start -0.120396 0.3048)
			(end -0.120396 0.2794)
			(stroke
				(width 0.1)
				(type default)
			)
			(layer "B.Fab")
		)
		(fp_line
			(start -0.67945 0.3048)
			(end -0.120396 0.3048)
			(stroke
				(width 0.1)
				(type default)
			)
			(layer "B.Fab")
		)
		(pad "1" smd circle
			(at 0.40005 0 270)
			(size 0 0)
			(layers "B.Cu" "B.Mask" "B.Paste")
			(net "P3V3_DB2000QL_VDD")
		)
		(pad "2" smd circle
			(at -0.40005 0 270)
			(size 0 0)
			(layers "B.Cu" "B.Mask" "B.Paste")
			(net "GND")
		)
	)
	(footprint ""
		(layer "B.Cu")
		(at 70.841616 -300.174914)
		(property "Reference" "C2989"
			(at 0 0 0)
			(layer "B.SilkS")
			(hide yes)
			(effects
				(font
					(size 1.27 1.27)
				)
				(justify mirror)
			)
		)
		(property "Value" ""
			(at 0 0 0)
			(layer "B.Fab")
			(effects
				(font
					(size 1.27 1.27)
				)
				(justify mirror)
			)
		)
		(duplicate_pad_numbers_are_jumpers no)
		(fp_line
			(start -0.299974 -0.150114)
			(end -0.299974 0.150114)
			(stroke
				(width 0.1)
				(type default)
			)
			(layer "B.Fab")
		)
		(fp_line
			(start -0.299974 0.150114)
			(end 0.299974 0.150114)
			(stroke
				(width 0.1)
				(type default)
			)
			(layer "B.Fab")
		)
		(fp_line
			(start 0.299974 -0.150114)
			(end -0.299974 -0.150114)
			(stroke
				(width 0.1)
				(type default)
			)
			(layer "B.Fab")
		)
		(fp_line
			(start 0.299974 0.150114)
			(end 0.299974 -0.150114)
			(stroke
				(width 0.1)
				(type default)
			)
			(layer "B.Fab")
		)
		(pad "1" smd rect
			(at 0.2667 0 180)
			(size 0.3048 0.381)
			(layers "B.Cu" "B.Mask" "B.Paste")
			(net "P1V8_VDDA_PEX0")
		)
		(pad "2" smd rect
			(at -0.2667 0 180)
			(size 0.3048 0.381)
			(layers "B.Cu" "B.Mask" "B.Paste")
			(net "GND")
		)
	)
	(footprint ""
		(layer "B.Cu")
		(at 227.067618 -217.504264 180)
		(property "Reference" "C2009"
			(at 0 0 0)
			(layer "B.SilkS")
			(hide yes)
			(effects
				(font
					(size 1.27 1.27)
				)
				(justify mirror)
			)
		)
		(property "Value" ""
			(at 0 0 0)
			(layer "B.Fab")
			(effects
				(font
					(size 1.27 1.27)
				)
				(justify mirror)
			)
		)
		(duplicate_pad_numbers_are_jumpers no)
		(fp_line
			(start 0.69215 0.2921)
			(end 0.69215 -0.2921)
			(stroke
				(width 0.1524)
				(type default)
			)
			(layer "B.SilkS")
		)
		(fp_line
			(start 0.69215 -0.2921)
			(end -0.69215 -0.2921)
			(stroke
				(width 0.1524)
				(type default)
			)
			(layer "B.SilkS")
		)
		(fp_line
			(start -0.69215 0.2921)
			(end 0.69215 0.2921)
			(stroke
				(width 0.1524)
				(type default)
			)
			(layer "B.SilkS")
		)
		(fp_line
			(start -0.69215 -0.2921)
			(end -0.69215 0.2921)
			(stroke
				(width 0.1524)
				(type default)
			)
			(layer "B.SilkS")
		)
		(fp_line
			(start 0.51435 0.2794)
			(end 0.51435 -0.2794)
			(stroke
				(width 0.1)
				(type default)
			)
			(layer "B.Fab")
		)
		(fp_line
			(start 0.51435 -0.2794)
			(end -0.51435 -0.2794)
			(stroke
				(width 0.1)
				(type default)
			)
			(layer "B.Fab")
		)
		(fp_line
			(start -0.51435 0.2794)
			(end 0.51435 0.2794)
			(stroke
				(width 0.1)
				(type default)
			)
			(layer "B.Fab")
		)
		(fp_line
			(start -0.51435 -0.2794)
			(end -0.51435 0.2794)
			(stroke
				(width 0.1)
				(type default)
			)
			(layer "B.Fab")
		)
		(pad "1" smd circle
			(at 0.40005 0)
			(size 0 0)
			(layers "B.Cu" "B.Mask" "B.Paste")
			(net "P3V3_AUX")
		)
		(pad "2" smd circle
			(at -0.40005 0)
			(size 0 0)
			(layers "B.Cu" "B.Mask" "B.Paste")
			(net "GND")
		)
		(zone
			(layer "B.Cu")
			(hatch none 0.5)
			(connect_pads
				(clearance 0)
			)
			(min_thickness 0.25)
			(keepout
				(tracks not_allowed)
				(vias allowed)
				(pads allowed)
				(copperpour not_allowed)
				(footprints allowed)
			)
			(placement
				(enabled no)
				(sheetname "")
			)
			(fill
				(thermal_gap 0.5)
				(thermal_bridge_width 0.5)
				(island_removal_mode 0)
			)
			(polygon
				(pts
					(xy 226.877118 -217.591894) (xy 226.968558 -217.65006) (xy 227.167948 -217.65006) (xy 227.258118 -217.591894)
					(xy 227.258118 -217.416634) (xy 227.167948 -217.358214) (xy 226.968558 -217.358214) (xy 226.877118 -217.41638)
				)
			)
		)
	)
	(footprint ""
		(layer "B.Cu")
		(at 234.718098 -274.274534)
		(property "Reference" "C4347"
			(at 0 0 0)
			(layer "B.SilkS")
			(hide yes)
			(effects
				(font
					(size 1.27 1.27)
				)
				(justify mirror)
			)
		)
		(property "Value" ""
			(at 0 0 0)
			(layer "B.Fab")
			(effects
				(font
					(size 1.27 1.27)
				)
				(justify mirror)
			)
		)
		(duplicate_pad_numbers_are_jumpers no)
		(fp_line
			(start -1.2954 -0.5842)
			(end -1.2954 0.5842)
			(stroke
				(width 0.1524)
				(type default)
			)
			(layer "B.SilkS")
		)
		(fp_line
			(start -1.2954 0.5842)
			(end 1.2954 0.5842)
			(stroke
				(width 0.1524)
				(type default)
			)
			(layer "B.SilkS")
		)
		(fp_line
			(start 1.2954 -0.5842)
			(end -1.2954 -0.5842)
			(stroke
				(width 0.1524)
				(type default)
			)
			(layer "B.SilkS")
		)
		(fp_line
			(start 1.2954 0.5842)
			(end 1.2954 -0.5842)
			(stroke
				(width 0.1524)
				(type default)
			)
			(layer "B.SilkS")
		)
		(fp_line
			(start -1.1938 -0.4064)
			(end -1.1938 0.4064)
			(stroke
				(width 0.1)
				(type default)
			)
			(layer "B.Fab")
		)
		(fp_line
			(start -1.1938 0.4064)
			(end -0.8636 0.4064)
			(stroke
				(width 0.1)
				(type default)
			)
			(layer "B.Fab")
		)
		(fp_line
			(start -0.8636 -0.4572)
			(end -0.8636 -0.4064)
			(stroke
				(width 0.1)
				(type default)
			)
			(layer "B.Fab")
		)
		(fp_line
			(start -0.8636 -0.4064)
			(end -1.1938 -0.4064)
			(stroke
				(width 0.1)
				(type default)
			)
			(layer "B.Fab")
		)
		(fp_line
			(start -0.8636 0.4064)
			(end -0.8636 0.4572)
			(stroke
				(width 0.1)
				(type default)
			)
			(layer "B.Fab")
		)
		(fp_line
			(start -0.8636 0.4572)
			(end 0.8636 0.4572)
			(stroke
				(width 0.1)
				(type default)
			)
			(layer "B.Fab")
		)
		(fp_line
			(start 0.8636 -0.4572)
			(end -0.8636 -0.4572)
			(stroke
				(width 0.1)
				(type default)
			)
			(layer "B.Fab")
		)
		(fp_line
			(start 0.8636 -0.4064)
			(end 0.8636 -0.4572)
			(stroke
				(width 0.1)
				(type default)
			)
			(layer "B.Fab")
		)
		(fp_line
			(start 0.8636 0.4064)
			(end 1.1938 0.4064)
			(stroke
				(width 0.1)
				(type default)
			)
			(layer "B.Fab")
		)
		(fp_line
			(start 0.8636 0.4572)
			(end 0.8636 0.4064)
			(stroke
				(width 0.1)
				(type default)
			)
			(layer "B.Fab")
		)
		(fp_line
			(start 1.1938 -0.4064)
			(end 0.8636 -0.4064)
			(stroke
				(width 0.1)
				(type default)
			)
			(layer "B.Fab")
		)
		(fp_line
			(start 1.1938 0.4064)
			(end 1.1938 -0.4064)
			(stroke
				(width 0.1)
				(type default)
			)
			(layer "B.Fab")
		)
		(pad "1" smd rect
			(at 0.7366 0 270)
			(size 0.7112 0.8128)
			(layers "B.Cu" "B.Mask" "B.Paste")
			(net "P1V25_PEX2")
		)
		(pad "2" smd rect
			(at -0.7366 0 270)
			(size 0.7112 0.8128)
			(layers "B.Cu" "B.Mask" "B.Paste")
			(net "GND")
		)
	)
	(footprint ""
		(layer "B.Cu")
		(at 182.39994 -292.099746 90)
		(property "Reference" "C1441"
			(at 0 0 90)
			(layer "B.SilkS")
			(hide yes)
			(effects
				(font
					(size 1.27 1.27)
				)
				(justify mirror)
			)
		)
		(property "Value" ""
			(at 0 0 90)
			(layer "B.Fab")
			(effects
				(font
					(size 1.27 1.27)
				)
				(justify mirror)
			)
		)
		(duplicate_pad_numbers_are_jumpers no)
		(fp_line
			(start 0.299974 -0.150114)
			(end -0.299974 -0.150114)
			(stroke
				(width 0.1)
				(type default)
			)
			(layer "B.Fab")
		)
		(fp_line
			(start -0.299974 -0.150114)
			(end -0.299974 0.150114)
			(stroke
				(width 0.1)
				(type default)
			)
			(layer "B.Fab")
		)
		(fp_line
			(start 0.299974 0.150114)
			(end 0.299974 -0.150114)
			(stroke
				(width 0.1)
				(type default)
			)
			(layer "B.Fab")
		)
		(fp_line
			(start -0.299974 0.150114)
			(end 0.299974 0.150114)
			(stroke
				(width 0.1)
				(type default)
			)
			(layer "B.Fab")
		)
		(pad "1" smd rect
			(at 0.2667 0 270)
			(size 0.3048 0.381)
			(layers "B.Cu" "B.Mask" "B.Paste")
			(net "P0V8_SERDES_VDDA_PEX1")
		)
		(pad "2" smd rect
			(at -0.2667 0 270)
			(size 0.3048 0.381)
			(layers "B.Cu" "B.Mask" "B.Paste")
			(net "GND")
		)
	)
	(footprint ""
		(layer "B.Cu")
		(at 288.049716 -290.199826 90)
		(property "Reference" "C1741"
			(at 0 0 90)
			(layer "B.SilkS")
			(hide yes)
			(effects
				(font
					(size 1.27 1.27)
				)
				(justify mirror)
			)
		)
		(property "Value" ""
			(at 0 0 90)
			(layer "B.Fab")
			(effects
				(font
					(size 1.27 1.27)
				)
				(justify mirror)
			)
		)
		(duplicate_pad_numbers_are_jumpers no)
		(fp_line
			(start 0.299974 -0.150114)
			(end -0.299974 -0.150114)
			(stroke
				(width 0.1)
				(type default)
			)
			(layer "B.Fab")
		)
		(fp_line
			(start -0.299974 -0.150114)
			(end -0.299974 0.150114)
			(stroke
				(width 0.1)
				(type default)
			)
			(layer "B.Fab")
		)
		(fp_line
			(start 0.299974 0.150114)
			(end 0.299974 -0.150114)
			(stroke
				(width 0.1)
				(type default)
			)
			(layer "B.Fab")
		)
		(fp_line
			(start -0.299974 0.150114)
			(end 0.299974 0.150114)
			(stroke
				(width 0.1)
				(type default)
			)
			(layer "B.Fab")
		)
		(pad "1" smd rect
			(at 0.2667 0 270)
			(size 0.3048 0.381)
			(layers "B.Cu" "B.Mask" "B.Paste")
			(net "P0V8_SERDES_VDDA_PEX2")
		)
		(pad "2" smd rect
			(at -0.2667 0 270)
			(size 0.3048 0.381)
			(layers "B.Cu" "B.Mask" "B.Paste")
			(net "GND")
		)
	)
	(footprint ""
		(layer "B.Cu")
		(at 346.093796 -213.187026 90)
		(property "Reference" "C2050"
			(at 0 0 90)
			(layer "B.SilkS")
			(hide yes)
			(effects
				(font
					(size 1.27 1.27)
				)
				(justify mirror)
			)
		)
		(property "Value" ""
			(at 0 0 90)
			(layer "B.Fab")
			(effects
				(font
					(size 1.27 1.27)
				)
				(justify mirror)
			)
		)
		(duplicate_pad_numbers_are_jumpers no)
		(fp_line
			(start 0.69215 -0.2921)
			(end -0.69215 -0.2921)
			(stroke
				(width 0.1524)
				(type default)
			)
			(layer "B.SilkS")
		)
		(fp_line
			(start -0.69215 -0.2921)
			(end -0.69215 0.2921)
			(stroke
				(width 0.1524)
				(type default)
			)
			(layer "B.SilkS")
		)
		(fp_line
			(start 0.69215 0.2921)
			(end 0.69215 -0.2921)
			(stroke
				(width 0.1524)
				(type default)
			)
			(layer "B.SilkS")
		)
		(fp_line
			(start -0.69215 0.2921)
			(end 0.69215 0.2921)
			(stroke
				(width 0.1524)
				(type default)
			)
			(layer "B.SilkS")
		)
		(fp_line
			(start 0.51435 -0.2794)
			(end -0.51435 -0.2794)
			(stroke
				(width 0.1)
				(type default)
			)
			(layer "B.Fab")
		)
		(fp_line
			(start -0.51435 -0.2794)
			(end -0.51435 0.2794)
			(stroke
				(width 0.1)
				(type default)
			)
			(layer "B.Fab")
		)
		(fp_line
			(start 0.51435 0.2794)
			(end 0.51435 -0.2794)
			(stroke
				(width 0.1)
				(type default)
			)
			(layer "B.Fab")
		)
		(fp_line
			(start -0.51435 0.2794)
			(end 0.51435 0.2794)
			(stroke
				(width 0.1)
				(type default)
			)
			(layer "B.Fab")
		)
		(pad "1" smd circle
			(at 0.40005 0 270)
			(size 0 0)
			(layers "B.Cu" "B.Mask" "B.Paste")
			(net "P3V3_FPGA_VCCIO2")
		)
		(pad "2" smd circle
			(at -0.40005 0 270)
			(size 0 0)
			(layers "B.Cu" "B.Mask" "B.Paste")
			(net "GND")
		)
		(zone
			(layer "B.Cu")
			(hatch none 0.5)
			(connect_pads
				(clearance 0)
			)
			(min_thickness 0.25)
			(keepout
				(tracks not_allowed)
				(vias allowed)
				(pads allowed)
				(copperpour not_allowed)
				(footprints allowed)
			)
			(placement
				(enabled no)
				(sheetname "")
			)
			(fill
				(thermal_gap 0.5)
				(thermal_bridge_width 0.5)
				(island_removal_mode 0)
			)
			(polygon
				(pts
					(xy 346.181426 -213.377526) (xy 346.239592 -213.286086) (xy 346.239592 -213.086696) (xy 346.181426 -212.996526)
					(xy 346.006166 -212.996526) (xy 345.947746 -213.086696) (xy 345.947746 -213.286086) (xy 346.005912 -213.377526)
				)
			)
		)
	)
	(footprint ""
		(layer "B.Cu")
		(at 300.425866 -246.441722 90)
		(property "Reference" "R4100"
			(at 0 0 90)
			(layer "B.SilkS")
			(hide yes)
			(effects
				(font
					(size 1.27 1.27)
				)
				(justify mirror)
			)
		)
		(property "Value" ""
			(at 0 0 90)
			(layer "B.Fab")
			(effects
				(font
					(size 1.27 1.27)
				)
				(justify mirror)
			)
		)
		(duplicate_pad_numbers_are_jumpers no)
		(fp_line
			(start 0.7874 -0.4064)
			(end -0.7874 -0.4064)
			(stroke
				(width 0.1524)
				(type default)
			)
			(layer "B.SilkS")
		)
		(fp_line
			(start -0.7874 -0.4064)
			(end -0.7874 0.4064)
			(stroke
				(width 0.1524)
				(type default)
			)
			(layer "B.SilkS")
		)
		(fp_line
			(start 0.7874 0.4064)
			(end 0.7874 -0.4064)
			(stroke
				(width 0.1524)
				(type default)
			)
			(layer "B.SilkS")
		)
		(fp_line
			(start -0.7874 0.4064)
			(end 0.7874 0.4064)
			(stroke
				(width 0.1524)
				(type default)
			)
			(layer "B.SilkS")
		)
		(fp_line
			(start 0.67945 -0.305054)
			(end 0.12065 -0.305054)
			(stroke
				(width 0.1)
				(type default)
			)
			(layer "B.Fab")
		)
		(fp_line
			(start 0.12065 -0.305054)
			(end 0.12065 -0.2794)
			(stroke
				(width 0.1)
				(type default)
			)
			(layer "B.Fab")
		)
		(fp_line
			(start -0.12065 -0.3048)
			(end -0.67945 -0.3048)
			(stroke
				(width 0.1)
				(type default)
			)
			(layer "B.Fab")
		)
		(fp_line
			(start -0.67945 -0.3048)
			(end -0.67945 0.3048)
			(stroke
				(width 0.1)
				(type default)
			)
			(layer "B.Fab")
		)
		(fp_line
			(start 0.12065 -0.2794)
			(end -0.12065 -0.2794)
			(stroke
				(width 0.1)
				(type default)
			)
			(layer "B.Fab")
		)
		(fp_line
			(start -0.12065 -0.2794)
			(end -0.12065 -0.3048)
			(stroke
				(width 0.1)
				(type default)
			)
			(layer "B.Fab")
		)
		(fp_line
			(start 0.12065 0.2794)
			(end 0.12065 0.3048)
			(stroke
				(width 0.1)
				(type default)
			)
			(layer "B.Fab")
		)
		(fp_line
			(start -0.120396 0.2794)
			(end 0.12065 0.2794)
			(stroke
				(width 0.1)
				(type default)
			)
			(layer "B.Fab")
		)
		(fp_line
			(start 0.67945 0.3048)
			(end 0.67945 -0.305054)
			(stroke
				(width 0.1)
				(type default)
			)
			(layer "B.Fab")
		)
		(fp_line
			(start 0.12065 0.3048)
			(end 0.67945 0.3048)
			(stroke
				(width 0.1)
				(type default)
			)
			(layer "B.Fab")
		)
		(fp_line
			(start -0.120396 0.3048)
			(end -0.120396 0.2794)
			(stroke
				(width 0.1)
				(type default)
			)
			(layer "B.Fab")
		)
		(fp_line
			(start -0.67945 0.3048)
			(end -0.120396 0.3048)
			(stroke
				(width 0.1)
				(type default)
			)
			(layer "B.Fab")
		)
		(pad "1" smd circle
			(at 0.40005 0 270)
			(size 0 0)
			(layers "B.Cu" "B.Mask" "B.Paste")
			(net "MB_I2C_ISO_EN")
		)
		(pad "2" smd circle
			(at -0.40005 0 270)
			(size 0 0)
			(layers "B.Cu" "B.Mask" "B.Paste")
			(net "P3V3_AUX")
		)
	)
	(footprint ""
		(layer "B.Cu")
		(at 418.40404 -97.663)
		(property "Reference" "R361"
			(at 0 0 0)
			(layer "B.SilkS")
			(hide yes)
			(effects
				(font
					(size 1.27 1.27)
				)
				(justify mirror)
			)
		)
		(property "Value" ""
			(at 0 0 0)
			(layer "B.Fab")
			(effects
				(font
					(size 1.27 1.27)
				)
				(justify mirror)
			)
		)
		(duplicate_pad_numbers_are_jumpers no)
		(fp_line
			(start -0.7874 -0.4064)
			(end -0.7874 0.4064)
			(stroke
				(width 0.1524)
				(type default)
			)
			(layer "B.SilkS")
		)
		(fp_line
			(start -0.7874 0.4064)
			(end 0.7874 0.4064)
			(stroke
				(width 0.1524)
				(type default)
			)
			(layer "B.SilkS")
		)
		(fp_line
			(start 0.7874 -0.4064)
			(end -0.7874 -0.4064)
			(stroke
				(width 0.1524)
				(type default)
			)
			(layer "B.SilkS")
		)
		(fp_line
			(start 0.7874 0.4064)
			(end 0.7874 -0.4064)
			(stroke
				(width 0.1524)
				(type default)
			)
			(layer "B.SilkS")
		)
		(fp_line
			(start -0.67945 -0.3048)
			(end -0.67945 0.3048)
			(stroke
				(width 0.1)
				(type default)
			)
			(layer "B.Fab")
		)
		(fp_line
			(start -0.67945 0.3048)
			(end -0.120396 0.3048)
			(stroke
				(width 0.1)
				(type default)
			)
			(layer "B.Fab")
		)
		(fp_line
			(start -0.12065 -0.3048)
			(end -0.67945 -0.3048)
			(stroke
				(width 0.1)
				(type default)
			)
			(layer "B.Fab")
		)
		(fp_line
			(start -0.12065 -0.2794)
			(end -0.12065 -0.3048)
			(stroke
				(width 0.1)
				(type default)
			)
			(layer "B.Fab")
		)
		(fp_line
			(start -0.120396 0.2794)
			(end 0.12065 0.2794)
			(stroke
				(width 0.1)
				(type default)
			)
			(layer "B.Fab")
		)
		(fp_line
			(start -0.120396 0.3048)
			(end -0.120396 0.2794)
			(stroke
				(width 0.1)
				(type default)
			)
			(layer "B.Fab")
		)
		(fp_line
			(start 0.12065 -0.305054)
			(end 0.12065 -0.2794)
			(stroke
				(width 0.1)
				(type default)
			)
			(layer "B.Fab")
		)
		(fp_line
			(start 0.12065 -0.2794)
			(end -0.12065 -0.2794)
			(stroke
				(width 0.1)
				(type default)
			)
			(layer "B.Fab")
		)
		(fp_line
			(start 0.12065 0.2794)
			(end 0.12065 0.3048)
			(stroke
				(width 0.1)
				(type default)
			)
			(layer "B.Fab")
		)
		(fp_line
			(start 0.12065 0.3048)
			(end 0.67945 0.3048)
			(stroke
				(width 0.1)
				(type default)
			)
			(layer "B.Fab")
		)
		(fp_line
			(start 0.67945 -0.305054)
			(end 0.12065 -0.305054)
			(stroke
				(width 0.1)
				(type default)
			)
			(layer "B.Fab")
		)
		(fp_line
			(start 0.67945 0.3048)
			(end 0.67945 -0.305054)
			(stroke
				(width 0.1)
				(type default)
			)
			(layer "B.Fab")
		)
		(pad "1" smd circle
			(at 0.40005 0 180)
			(size 0 0)
			(layers "B.Cu" "B.Mask" "B.Paste")
			(net "PWRGD_NIC7_PWR_GOOD")
		)
		(pad "2" smd circle
			(at -0.40005 0 180)
			(size 0 0)
			(layers "B.Cu" "B.Mask" "B.Paste")
			(net "PWRGD_NIC7_PWR_GOOD_R")
		)
	)
	(footprint ""
		(layer "B.Cu")
		(at 406.049988 -288.299906 90)
		(property "Reference" "C3458"
			(at 0 0 90)
			(layer "B.SilkS")
			(hide yes)
			(effects
				(font
					(size 1.27 1.27)
				)
				(justify mirror)
			)
		)
		(property "Value" ""
			(at 0 0 90)
			(layer "B.Fab")
			(effects
				(font
					(size 1.27 1.27)
				)
				(justify mirror)
			)
		)
		(duplicate_pad_numbers_are_jumpers no)
		(fp_line
			(start 0.299974 -0.150114)
			(end -0.299974 -0.150114)
			(stroke
				(width 0.1)
				(type default)
			)
			(layer "B.Fab")
		)
		(fp_line
			(start -0.299974 -0.150114)
			(end -0.299974 0.150114)
			(stroke
				(width 0.1)
				(type default)
			)
			(layer "B.Fab")
		)
		(fp_line
			(start 0.299974 0.150114)
			(end 0.299974 -0.150114)
			(stroke
				(width 0.1)
				(type default)
			)
			(layer "B.Fab")
		)
		(fp_line
			(start -0.299974 0.150114)
			(end 0.299974 0.150114)
			(stroke
				(width 0.1)
				(type default)
			)
			(layer "B.Fab")
		)
		(pad "1" smd rect
			(at 0.2667 0 270)
			(size 0.3048 0.381)
			(layers "B.Cu" "B.Mask" "B.Paste")
			(net "P1V25_PEX3")
		)
		(pad "2" smd rect
			(at -0.2667 0 270)
			(size 0.3048 0.381)
			(layers "B.Cu" "B.Mask" "B.Paste")
			(net "GND")
		)
	)
	(footprint ""
		(layer "B.Cu")
		(at 23.212298 -228.346 90)
		(property "Reference" "R3445"
			(at 0 0 90)
			(layer "B.SilkS")
			(hide yes)
			(effects
				(font
					(size 1.27 1.27)
				)
				(justify mirror)
			)
		)
		(property "Value" ""
			(at 0 0 90)
			(layer "B.Fab")
			(effects
				(font
					(size 1.27 1.27)
				)
				(justify mirror)
			)
		)
		(duplicate_pad_numbers_are_jumpers no)
		(fp_line
			(start 0.7874 -0.4064)
			(end -0.7874 -0.4064)
			(stroke
				(width 0.1524)
				(type default)
			)
			(layer "B.SilkS")
		)
		(fp_line
			(start -0.7874 -0.4064)
			(end -0.7874 0.4064)
			(stroke
				(width 0.1524)
				(type default)
			)
			(layer "B.SilkS")
		)
		(fp_line
			(start 0.7874 0.4064)
			(end 0.7874 -0.4064)
			(stroke
				(width 0.1524)
				(type default)
			)
			(layer "B.SilkS")
		)
		(fp_line
			(start -0.7874 0.4064)
			(end 0.7874 0.4064)
			(stroke
				(width 0.1524)
				(type default)
			)
			(layer "B.SilkS")
		)
		(fp_line
			(start 0.67945 -0.305054)
			(end 0.12065 -0.305054)
			(stroke
				(width 0.1)
				(type default)
			)
			(layer "B.Fab")
		)
		(fp_line
			(start 0.12065 -0.305054)
			(end 0.12065 -0.2794)
			(stroke
				(width 0.1)
				(type default)
			)
			(layer "B.Fab")
		)
		(fp_line
			(start -0.12065 -0.3048)
			(end -0.67945 -0.3048)
			(stroke
				(width 0.1)
				(type default)
			)
			(layer "B.Fab")
		)
		(fp_line
			(start -0.67945 -0.3048)
			(end -0.67945 0.3048)
			(stroke
				(width 0.1)
				(type default)
			)
			(layer "B.Fab")
		)
		(fp_line
			(start 0.12065 -0.2794)
			(end -0.12065 -0.2794)
			(stroke
				(width 0.1)
				(type default)
			)
			(layer "B.Fab")
		)
		(fp_line
			(start -0.12065 -0.2794)
			(end -0.12065 -0.3048)
			(stroke
				(width 0.1)
				(type default)
			)
			(layer "B.Fab")
		)
		(fp_line
			(start 0.12065 0.2794)
			(end 0.12065 0.3048)
			(stroke
				(width 0.1)
				(type default)
			)
			(layer "B.Fab")
		)
		(fp_line
			(start -0.120396 0.2794)
			(end 0.12065 0.2794)
			(stroke
				(width 0.1)
				(type default)
			)
			(layer "B.Fab")
		)
		(fp_line
			(start 0.67945 0.3048)
			(end 0.67945 -0.305054)
			(stroke
				(width 0.1)
				(type default)
			)
			(layer "B.Fab")
		)
		(fp_line
			(start 0.12065 0.3048)
			(end 0.67945 0.3048)
			(stroke
				(width 0.1)
				(type default)
			)
			(layer "B.Fab")
		)
		(fp_line
			(start -0.120396 0.3048)
			(end -0.120396 0.2794)
			(stroke
				(width 0.1)
				(type default)
			)
			(layer "B.Fab")
		)
		(fp_line
			(start -0.67945 0.3048)
			(end -0.120396 0.3048)
			(stroke
				(width 0.1)
				(type default)
			)
			(layer "B.Fab")
		)
		(pad "1" smd circle
			(at 0.40005 0 270)
			(size 0 0)
			(layers "B.Cu" "B.Mask" "B.Paste")
			(net "SPI_PEX0_SDIO1_MUX_R")
		)
		(pad "2" smd circle
			(at -0.40005 0 270)
			(size 0 0)
			(layers "B.Cu" "B.Mask" "B.Paste")
			(net "SPI_PEX0_SDIO1_MUX")
		)
	)
	(footprint ""
		(layer "B.Cu")
		(at 276.93366 -390.463278)
		(property "Reference" "PR6618"
			(at 0 0 0)
			(layer "B.SilkS")
			(hide yes)
			(effects
				(font
					(size 1.27 1.27)
				)
				(justify mirror)
			)
		)
		(property "Value" ""
			(at 0 0 0)
			(layer "B.Fab")
			(effects
				(font
					(size 1.27 1.27)
				)
				(justify mirror)
			)
		)
		(duplicate_pad_numbers_are_jumpers no)
		(fp_line
			(start -0.7874 -0.4064)
			(end -0.7874 0.4064)
			(stroke
				(width 0.1524)
				(type default)
			)
			(layer "B.SilkS")
		)
		(fp_line
			(start -0.7874 0.4064)
			(end 0.7874 0.4064)
			(stroke
				(width 0.1524)
				(type default)
			)
			(layer "B.SilkS")
		)
		(fp_line
			(start 0.7874 -0.4064)
			(end -0.7874 -0.4064)
			(stroke
				(width 0.1524)
				(type default)
			)
			(layer "B.SilkS")
		)
		(fp_line
			(start 0.7874 0.4064)
			(end 0.7874 -0.4064)
			(stroke
				(width 0.1524)
				(type default)
			)
			(layer "B.SilkS")
		)
		(fp_line
			(start -0.67945 -0.3048)
			(end -0.67945 0.3048)
			(stroke
				(width 0.1)
				(type default)
			)
			(layer "B.Fab")
		)
		(fp_line
			(start -0.67945 0.3048)
			(end -0.120396 0.3048)
			(stroke
				(width 0.1)
				(type default)
			)
			(layer "B.Fab")
		)
		(fp_line
			(start -0.12065 -0.3048)
			(end -0.67945 -0.3048)
			(stroke
				(width 0.1)
				(type default)
			)
			(layer "B.Fab")
		)
		(fp_line
			(start -0.12065 -0.2794)
			(end -0.12065 -0.3048)
			(stroke
				(width 0.1)
				(type default)
			)
			(layer "B.Fab")
		)
		(fp_line
			(start -0.120396 0.2794)
			(end 0.12065 0.2794)
			(stroke
				(width 0.1)
				(type default)
			)
			(layer "B.Fab")
		)
		(fp_line
			(start -0.120396 0.3048)
			(end -0.120396 0.2794)
			(stroke
				(width 0.1)
				(type default)
			)
			(layer "B.Fab")
		)
		(fp_line
			(start 0.12065 -0.305054)
			(end 0.12065 -0.2794)
			(stroke
				(width 0.1)
				(type default)
			)
			(layer "B.Fab")
		)
		(fp_line
			(start 0.12065 -0.2794)
			(end -0.12065 -0.2794)
			(stroke
				(width 0.1)
				(type default)
			)
			(layer "B.Fab")
		)
		(fp_line
			(start 0.12065 0.2794)
			(end 0.12065 0.3048)
			(stroke
				(width 0.1)
				(type default)
			)
			(layer "B.Fab")
		)
		(fp_line
			(start 0.12065 0.3048)
			(end 0.67945 0.3048)
			(stroke
				(width 0.1)
				(type default)
			)
			(layer "B.Fab")
		)
		(fp_line
			(start 0.67945 -0.305054)
			(end 0.12065 -0.305054)
			(stroke
				(width 0.1)
				(type default)
			)
			(layer "B.Fab")
		)
		(fp_line
			(start 0.67945 0.3048)
			(end 0.67945 -0.305054)
			(stroke
				(width 0.1)
				(type default)
			)
			(layer "B.Fab")
		)
		(pad "1" smd circle
			(at 0.40005 0 180)
			(size 0 0)
			(layers "B.Cu" "B.Mask" "B.Paste")
			(net "LTC4282_ALERT1_R_N")
		)
		(pad "2" smd circle
			(at -0.40005 0 180)
			(size 0 0)
			(layers "B.Cu" "B.Mask" "B.Paste")
			(net "HSC_ALERT1_R_N")
		)
	)
	(footprint ""
		(layer "B.Cu")
		(at 162.4457 -293.52494)
		(property "Reference" "C3231"
			(at 0 0 0)
			(layer "B.SilkS")
			(hide yes)
			(effects
				(font
					(size 1.27 1.27)
				)
				(justify mirror)
			)
		)
		(property "Value" ""
			(at 0 0 0)
			(layer "B.Fab")
			(effects
				(font
					(size 1.27 1.27)
				)
				(justify mirror)
			)
		)
		(duplicate_pad_numbers_are_jumpers no)
		(fp_line
			(start -0.299974 -0.150114)
			(end -0.299974 0.150114)
			(stroke
				(width 0.1)
				(type default)
			)
			(layer "B.Fab")
		)
		(fp_line
			(start -0.299974 0.150114)
			(end 0.299974 0.150114)
			(stroke
				(width 0.1)
				(type default)
			)
			(layer "B.Fab")
		)
		(fp_line
			(start 0.299974 -0.150114)
			(end -0.299974 -0.150114)
			(stroke
				(width 0.1)
				(type default)
			)
			(layer "B.Fab")
		)
		(fp_line
			(start 0.299974 0.150114)
			(end 0.299974 -0.150114)
			(stroke
				(width 0.1)
				(type default)
			)
			(layer "B.Fab")
		)
		(pad "1" smd rect
			(at 0.2667 0 180)
			(size 0.3048 0.381)
			(layers "B.Cu" "B.Mask" "B.Paste")
			(net "PCEPLL6_VDDA18_PEX1")
		)
		(pad "2" smd rect
			(at -0.2667 0 180)
			(size 0.3048 0.381)
			(layers "B.Cu" "B.Mask" "B.Paste")
			(net "GND")
		)
	)
	(footprint ""
		(layer "B.Cu")
		(at 184.29986 -293.52494 180)
		(property "Reference" "C1358"
			(at 0 0 0)
			(layer "B.SilkS")
			(hide yes)
			(effects
				(font
					(size 1.27 1.27)
				)
				(justify mirror)
			)
		)
		(property "Value" ""
			(at 0 0 0)
			(layer "B.Fab")
			(effects
				(font
					(size 1.27 1.27)
				)
				(justify mirror)
			)
		)
		(duplicate_pad_numbers_are_jumpers no)
		(fp_line
			(start 0.299974 0.150114)
			(end 0.299974 -0.150114)
			(stroke
				(width 0.1)
				(type default)
			)
			(layer "B.Fab")
		)
		(fp_line
			(start 0.299974 -0.150114)
			(end -0.299974 -0.150114)
			(stroke
				(width 0.1)
				(type default)
			)
			(layer "B.Fab")
		)
		(fp_line
			(start -0.299974 0.150114)
			(end 0.299974 0.150114)
			(stroke
				(width 0.1)
				(type default)
			)
			(layer "B.Fab")
		)
		(fp_line
			(start -0.299974 -0.150114)
			(end -0.299974 0.150114)
			(stroke
				(width 0.1)
				(type default)
			)
			(layer "B.Fab")
		)
		(pad "1" smd rect
			(at 0.2667 0)
			(size 0.3048 0.381)
			(layers "B.Cu" "B.Mask" "B.Paste")
			(net "P0V8_PEX1")
		)
		(pad "2" smd rect
			(at -0.2667 0)
			(size 0.3048 0.381)
			(layers "B.Cu" "B.Mask" "B.Paste")
			(net "GND")
		)
	)
	(footprint ""
		(layer "B.Cu")
		(at 109.245654 -308.580028 90)
		(property "Reference" "C4193"
			(at 0 0 90)
			(layer "B.SilkS")
			(hide yes)
			(effects
				(font
					(size 1.27 1.27)
				)
				(justify mirror)
			)
		)
		(property "Value" ""
			(at 0 0 90)
			(layer "B.Fab")
			(effects
				(font
					(size 1.27 1.27)
				)
				(justify mirror)
			)
		)
		(duplicate_pad_numbers_are_jumpers no)
		(fp_line
			(start 1.2954 -0.5842)
			(end -1.2954 -0.5842)
			(stroke
				(width 0.1524)
				(type default)
			)
			(layer "B.SilkS")
		)
		(fp_line
			(start -1.2954 -0.5842)
			(end -1.2954 0.5842)
			(stroke
				(width 0.1524)
				(type default)
			)
			(layer "B.SilkS")
		)
		(fp_line
			(start 1.2954 0.5842)
			(end 1.2954 -0.5842)
			(stroke
				(width 0.1524)
				(type default)
			)
			(layer "B.SilkS")
		)
		(fp_line
			(start -1.2954 0.5842)
			(end 1.2954 0.5842)
			(stroke
				(width 0.1524)
				(type default)
			)
			(layer "B.SilkS")
		)
		(fp_line
			(start 0.8636 -0.4572)
			(end -0.8636 -0.4572)
			(stroke
				(width 0.1)
				(type default)
			)
			(layer "B.Fab")
		)
		(fp_line
			(start -0.8636 -0.4572)
			(end -0.8636 -0.4064)
			(stroke
				(width 0.1)
				(type default)
			)
			(layer "B.Fab")
		)
		(fp_line
			(start 1.1938 -0.4064)
			(end 0.8636 -0.4064)
			(stroke
				(width 0.1)
				(type default)
			)
			(layer "B.Fab")
		)
		(fp_line
			(start 0.8636 -0.4064)
			(end 0.8636 -0.4572)
			(stroke
				(width 0.1)
				(type default)
			)
			(layer "B.Fab")
		)
		(fp_line
			(start -0.8636 -0.4064)
			(end -1.1938 -0.4064)
			(stroke
				(width 0.1)
				(type default)
			)
			(layer "B.Fab")
		)
		(fp_line
			(start -1.1938 -0.4064)
			(end -1.1938 0.4064)
			(stroke
				(width 0.1)
				(type default)
			)
			(layer "B.Fab")
		)
		(fp_line
			(start 1.1938 0.4064)
			(end 1.1938 -0.4064)
			(stroke
				(width 0.1)
				(type default)
			)
			(layer "B.Fab")
		)
		(fp_line
			(start 0.8636 0.4064)
			(end 1.1938 0.4064)
			(stroke
				(width 0.1)
				(type default)
			)
			(layer "B.Fab")
		)
		(fp_line
			(start -0.8636 0.4064)
			(end -0.8636 0.4572)
			(stroke
				(width 0.1)
				(type default)
			)
			(layer "B.Fab")
		)
		(fp_line
			(start -1.1938 0.4064)
			(end -0.8636 0.4064)
			(stroke
				(width 0.1)
				(type default)
			)
			(layer "B.Fab")
		)
		(fp_line
			(start 0.8636 0.4572)
			(end 0.8636 0.4064)
			(stroke
				(width 0.1)
				(type default)
			)
			(layer "B.Fab")
		)
		(fp_line
			(start -0.8636 0.4572)
			(end 0.8636 0.4572)
			(stroke
				(width 0.1)
				(type default)
			)
			(layer "B.Fab")
		)
		(pad "1" smd rect
			(at 0.7366 0)
			(size 0.7112 0.8128)
			(layers "B.Cu" "B.Mask" "B.Paste")
			(net "P0V8_PEX0")
		)
		(pad "2" smd rect
			(at -0.7366 0)
			(size 0.7112 0.8128)
			(layers "B.Cu" "B.Mask" "B.Paste")
			(net "GND")
		)
	)
	(footprint ""
		(layer "B.Cu")
		(at 198.280274 -368.72164 -90)
		(property "Reference" "PR14"
			(at 0 0 90)
			(layer "B.SilkS")
			(hide yes)
			(effects
				(font
					(size 1.27 1.27)
				)
				(justify mirror)
			)
		)
		(property "Value" ""
			(at 0 0 90)
			(layer "B.Fab")
			(effects
				(font
					(size 1.27 1.27)
				)
				(justify mirror)
			)
		)
		(duplicate_pad_numbers_are_jumpers no)
		(fp_line
			(start -0.7874 0.4064)
			(end 0.7874 0.4064)
			(stroke
				(width 0.1524)
				(type default)
			)
			(layer "B.SilkS")
		)
		(fp_line
			(start 0.7874 0.4064)
			(end 0.7874 -0.4064)
			(stroke
				(width 0.1524)
				(type default)
			)
			(layer "B.SilkS")
		)
		(fp_line
			(start -0.7874 -0.4064)
			(end -0.7874 0.4064)
			(stroke
				(width 0.1524)
				(type default)
			)
			(layer "B.SilkS")
		)
		(fp_line
			(start 0.7874 -0.4064)
			(end -0.7874 -0.4064)
			(stroke
				(width 0.1524)
				(type default)
			)
			(layer "B.SilkS")
		)
		(fp_line
			(start -0.67945 0.3048)
			(end -0.120396 0.3048)
			(stroke
				(width 0.1)
				(type default)
			)
			(layer "B.Fab")
		)
		(fp_line
			(start -0.120396 0.3048)
			(end -0.120396 0.2794)
			(stroke
				(width 0.1)
				(type default)
			)
			(layer "B.Fab")
		)
		(fp_line
			(start 0.12065 0.3048)
			(end 0.67945 0.3048)
			(stroke
				(width 0.1)
				(type default)
			)
			(layer "B.Fab")
		)
		(fp_line
			(start 0.67945 0.3048)
			(end 0.67945 -0.305054)
			(stroke
				(width 0.1)
				(type default)
			)
			(layer "B.Fab")
		)
		(fp_line
			(start -0.120396 0.2794)
			(end 0.12065 0.2794)
			(stroke
				(width 0.1)
				(type default)
			)
			(layer "B.Fab")
		)
		(fp_line
			(start 0.12065 0.2794)
			(end 0.12065 0.3048)
			(stroke
				(width 0.1)
				(type default)
			)
			(layer "B.Fab")
		)
		(fp_line
			(start -0.12065 -0.2794)
			(end -0.12065 -0.3048)
			(stroke
				(width 0.1)
				(type default)
			)
			(layer "B.Fab")
		)
		(fp_line
			(start 0.12065 -0.2794)
			(end -0.12065 -0.2794)
			(stroke
				(width 0.1)
				(type default)
			)
			(layer "B.Fab")
		)
		(fp_line
			(start -0.67945 -0.3048)
			(end -0.67945 0.3048)
			(stroke
				(width 0.1)
				(type default)
			)
			(layer "B.Fab")
		)
		(fp_line
			(start -0.12065 -0.3048)
			(end -0.67945 -0.3048)
			(stroke
				(width 0.1)
				(type default)
			)
			(layer "B.Fab")
		)
		(fp_line
			(start 0.12065 -0.305054)
			(end 0.12065 -0.2794)
			(stroke
				(width 0.1)
				(type default)
			)
			(layer "B.Fab")
		)
		(fp_line
			(start 0.67945 -0.305054)
			(end 0.12065 -0.305054)
			(stroke
				(width 0.1)
				(type default)
			)
			(layer "B.Fab")
		)
		(pad "1" smd circle
			(at 0.40005 0 90)
			(size 0 0)
			(layers "B.Cu" "B.Mask" "B.Paste")
			(net "HSC_VDD")
		)
		(pad "2" smd circle
			(at -0.40005 0 90)
			(size 0 0)
			(layers "B.Cu" "B.Mask" "B.Paste")
			(net "HSC_VIN_UVW_N")
		)
	)
	(footprint ""
		(layer "B.Cu")
		(at 64.399922 -288.299906 90)
		(property "Reference" "C2920"
			(at 0 0 90)
			(layer "B.SilkS")
			(hide yes)
			(effects
				(font
					(size 1.27 1.27)
				)
				(justify mirror)
			)
		)
		(property "Value" ""
			(at 0 0 90)
			(layer "B.Fab")
			(effects
				(font
					(size 1.27 1.27)
				)
				(justify mirror)
			)
		)
		(duplicate_pad_numbers_are_jumpers no)
		(fp_line
			(start 0.299974 -0.150114)
			(end -0.299974 -0.150114)
			(stroke
				(width 0.1)
				(type default)
			)
			(layer "B.Fab")
		)
		(fp_line
			(start -0.299974 -0.150114)
			(end -0.299974 0.150114)
			(stroke
				(width 0.1)
				(type default)
			)
			(layer "B.Fab")
		)
		(fp_line
			(start 0.299974 0.150114)
			(end 0.299974 -0.150114)
			(stroke
				(width 0.1)
				(type default)
			)
			(layer "B.Fab")
		)
		(fp_line
			(start -0.299974 0.150114)
			(end 0.299974 0.150114)
			(stroke
				(width 0.1)
				(type default)
			)
			(layer "B.Fab")
		)
		(pad "1" smd rect
			(at 0.2667 0 270)
			(size 0.3048 0.381)
			(layers "B.Cu" "B.Mask" "B.Paste")
			(net "P1V25_PEX0")
		)
		(pad "2" smd rect
			(at -0.2667 0 270)
			(size 0.3048 0.381)
			(layers "B.Cu" "B.Mask" "B.Paste")
			(net "GND")
		)
	)
	(footprint ""
		(layer "B.Cu")
		(at 128.241044 -179.00777 180)
		(property "Reference" "R1125"
			(at 0 0 0)
			(layer "B.SilkS")
			(hide yes)
			(effects
				(font
					(size 1.27 1.27)
				)
				(justify mirror)
			)
		)
		(property "Value" ""
			(at 0 0 0)
			(layer "B.Fab")
			(effects
				(font
					(size 1.27 1.27)
				)
				(justify mirror)
			)
		)
		(duplicate_pad_numbers_are_jumpers no)
		(fp_line
			(start 0.7874 0.4064)
			(end 0.7874 -0.4064)
			(stroke
				(width 0.1524)
				(type default)
			)
			(layer "B.SilkS")
		)
		(fp_line
			(start 0.7874 -0.4064)
			(end -0.7874 -0.4064)
			(stroke
				(width 0.1524)
				(type default)
			)
			(layer "B.SilkS")
		)
		(fp_line
			(start -0.7874 0.4064)
			(end 0.7874 0.4064)
			(stroke
				(width 0.1524)
				(type default)
			)
			(layer "B.SilkS")
		)
		(fp_line
			(start -0.7874 -0.4064)
			(end -0.7874 0.4064)
			(stroke
				(width 0.1524)
				(type default)
			)
			(layer "B.SilkS")
		)
		(fp_line
			(start 0.67945 0.3048)
			(end 0.67945 -0.305054)
			(stroke
				(width 0.1)
				(type default)
			)
			(layer "B.Fab")
		)
		(fp_line
			(start 0.67945 -0.305054)
			(end 0.12065 -0.305054)
			(stroke
				(width 0.1)
				(type default)
			)
			(layer "B.Fab")
		)
		(fp_line
			(start 0.12065 0.3048)
			(end 0.67945 0.3048)
			(stroke
				(width 0.1)
				(type default)
			)
			(layer "B.Fab")
		)
		(fp_line
			(start 0.12065 0.2794)
			(end 0.12065 0.3048)
			(stroke
				(width 0.1)
				(type default)
			)
			(layer "B.Fab")
		)
		(fp_line
			(start 0.12065 -0.2794)
			(end -0.12065 -0.2794)
			(stroke
				(width 0.1)
				(type default)
			)
			(layer "B.Fab")
		)
		(fp_line
			(start 0.12065 -0.305054)
			(end 0.12065 -0.2794)
			(stroke
				(width 0.1)
				(type default)
			)
			(layer "B.Fab")
		)
		(fp_line
			(start -0.120396 0.3048)
			(end -0.120396 0.2794)
			(stroke
				(width 0.1)
				(type default)
			)
			(layer "B.Fab")
		)
		(fp_line
			(start -0.120396 0.2794)
			(end 0.12065 0.2794)
			(stroke
				(width 0.1)
				(type default)
			)
			(layer "B.Fab")
		)
		(fp_line
			(start -0.12065 -0.2794)
			(end -0.12065 -0.3048)
			(stroke
				(width 0.1)
				(type default)
			)
			(layer "B.Fab")
		)
		(fp_line
			(start -0.12065 -0.3048)
			(end -0.67945 -0.3048)
			(stroke
				(width 0.1)
				(type default)
			)
			(layer "B.Fab")
		)
		(fp_line
			(start -0.67945 0.3048)
			(end -0.120396 0.3048)
			(stroke
				(width 0.1)
				(type default)
			)
			(layer "B.Fab")
		)
		(fp_line
			(start -0.67945 -0.3048)
			(end -0.67945 0.3048)
			(stroke
				(width 0.1)
				(type default)
			)
			(layer "B.Fab")
		)
		(pad "1" smd circle
			(at 0.40005 0)
			(size 0 0)
			(layers "B.Cu" "B.Mask" "B.Paste")
			(net "GND")
		)
		(pad "2" smd circle
			(at -0.40005 0)
			(size 0 0)
			(layers "B.Cu" "B.Mask" "B.Paste")
			(net "FM_DB2000QL_VSBEN")
		)
	)
	(footprint ""
		(layer "B.Cu")
		(at 233.839512 -234.728004 90)
		(property "Reference" "R6184"
			(at 0 0 90)
			(layer "B.SilkS")
			(hide yes)
			(effects
				(font
					(size 1.27 1.27)
				)
				(justify mirror)
			)
		)
		(property "Value" ""
			(at 0 0 90)
			(layer "B.Fab")
			(effects
				(font
					(size 1.27 1.27)
				)
				(justify mirror)
			)
		)
		(duplicate_pad_numbers_are_jumpers no)
		(fp_line
			(start 0.7874 -0.4064)
			(end -0.7874 -0.4064)
			(stroke
				(width 0.1524)
				(type default)
			)
			(layer "B.SilkS")
		)
		(fp_line
			(start -0.7874 -0.4064)
			(end -0.7874 0.4064)
			(stroke
				(width 0.1524)
				(type default)
			)
			(layer "B.SilkS")
		)
		(fp_line
			(start 0.7874 0.4064)
			(end 0.7874 -0.4064)
			(stroke
				(width 0.1524)
				(type default)
			)
			(layer "B.SilkS")
		)
		(fp_line
			(start -0.7874 0.4064)
			(end 0.7874 0.4064)
			(stroke
				(width 0.1524)
				(type default)
			)
			(layer "B.SilkS")
		)
		(fp_line
			(start 0.67945 -0.305054)
			(end 0.12065 -0.305054)
			(stroke
				(width 0.1)
				(type default)
			)
			(layer "B.Fab")
		)
		(fp_line
			(start 0.12065 -0.305054)
			(end 0.12065 -0.2794)
			(stroke
				(width 0.1)
				(type default)
			)
			(layer "B.Fab")
		)
		(fp_line
			(start -0.12065 -0.3048)
			(end -0.67945 -0.3048)
			(stroke
				(width 0.1)
				(type default)
			)
			(layer "B.Fab")
		)
		(fp_line
			(start -0.67945 -0.3048)
			(end -0.67945 0.3048)
			(stroke
				(width 0.1)
				(type default)
			)
			(layer "B.Fab")
		)
		(fp_line
			(start 0.12065 -0.2794)
			(end -0.12065 -0.2794)
			(stroke
				(width 0.1)
				(type default)
			)
			(layer "B.Fab")
		)
		(fp_line
			(start -0.12065 -0.2794)
			(end -0.12065 -0.3048)
			(stroke
				(width 0.1)
				(type default)
			)
			(layer "B.Fab")
		)
		(fp_line
			(start 0.12065 0.2794)
			(end 0.12065 0.3048)
			(stroke
				(width 0.1)
				(type default)
			)
			(layer "B.Fab")
		)
		(fp_line
			(start -0.120396 0.2794)
			(end 0.12065 0.2794)
			(stroke
				(width 0.1)
				(type default)
			)
			(layer "B.Fab")
		)
		(fp_line
			(start 0.67945 0.3048)
			(end 0.67945 -0.305054)
			(stroke
				(width 0.1)
				(type default)
			)
			(layer "B.Fab")
		)
		(fp_line
			(start 0.12065 0.3048)
			(end 0.67945 0.3048)
			(stroke
				(width 0.1)
				(type default)
			)
			(layer "B.Fab")
		)
		(fp_line
			(start -0.120396 0.3048)
			(end -0.120396 0.2794)
			(stroke
				(width 0.1)
				(type default)
			)
			(layer "B.Fab")
		)
		(fp_line
			(start -0.67945 0.3048)
			(end -0.120396 0.3048)
			(stroke
				(width 0.1)
				(type default)
			)
			(layer "B.Fab")
		)
		(pad "1" smd circle
			(at 0.40005 0 270)
			(size 0 0)
			(layers "B.Cu" "B.Mask" "B.Paste")
			(net "GND")
		)
		(pad "2" smd circle
			(at -0.40005 0 270)
			(size 0 0)
			(layers "B.Cu" "B.Mask" "B.Paste")
			(net "SSD2_PWRDIS_BIC_R")
		)
	)
	(footprint ""
		(layer "B.Cu")
		(at 411.750002 -303.499774 -90)
		(property "Reference" "C3439"
			(at 0 0 90)
			(layer "B.SilkS")
			(hide yes)
			(effects
				(font
					(size 1.27 1.27)
				)
				(justify mirror)
			)
		)
		(property "Value" ""
			(at 0 0 90)
			(layer "B.Fab")
			(effects
				(font
					(size 1.27 1.27)
				)
				(justify mirror)
			)
		)
		(duplicate_pad_numbers_are_jumpers no)
		(fp_line
			(start -0.299974 0.150114)
			(end 0.299974 0.150114)
			(stroke
				(width 0.1)
				(type default)
			)
			(layer "B.Fab")
		)
		(fp_line
			(start 0.299974 0.150114)
			(end 0.299974 -0.150114)
			(stroke
				(width 0.1)
				(type default)
			)
			(layer "B.Fab")
		)
		(fp_line
			(start -0.299974 -0.150114)
			(end -0.299974 0.150114)
			(stroke
				(width 0.1)
				(type default)
			)
			(layer "B.Fab")
		)
		(fp_line
			(start 0.299974 -0.150114)
			(end -0.299974 -0.150114)
			(stroke
				(width 0.1)
				(type default)
			)
			(layer "B.Fab")
		)
		(pad "1" smd rect
			(at 0.2667 0 90)
			(size 0.3048 0.381)
			(layers "B.Cu" "B.Mask" "B.Paste")
			(net "P1V25_PEX3")
		)
		(pad "2" smd rect
			(at -0.2667 0 90)
			(size 0.3048 0.381)
			(layers "B.Cu" "B.Mask" "B.Paste")
			(net "GND")
		)
	)
	(footprint ""
		(layer "B.Cu")
		(at 128.454912 -321.813174 -90)
		(property "Reference" "R6476"
			(at 0 0 90)
			(layer "B.SilkS")
			(hide yes)
			(effects
				(font
					(size 1.27 1.27)
				)
				(justify mirror)
			)
		)
		(property "Value" ""
			(at 0 0 90)
			(layer "B.Fab")
			(effects
				(font
					(size 1.27 1.27)
				)
				(justify mirror)
			)
		)
		(duplicate_pad_numbers_are_jumpers no)
		(fp_line
			(start -0.7874 0.4064)
			(end 0.7874 0.4064)
			(stroke
				(width 0.1524)
				(type default)
			)
			(layer "B.SilkS")
		)
		(fp_line
			(start 0.7874 0.4064)
			(end 0.7874 -0.4064)
			(stroke
				(width 0.1524)
				(type default)
			)
			(layer "B.SilkS")
		)
		(fp_line
			(start -0.7874 -0.4064)
			(end -0.7874 0.4064)
			(stroke
				(width 0.1524)
				(type default)
			)
			(layer "B.SilkS")
		)
		(fp_line
			(start 0.7874 -0.4064)
			(end -0.7874 -0.4064)
			(stroke
				(width 0.1524)
				(type default)
			)
			(layer "B.SilkS")
		)
		(fp_line
			(start -0.67945 0.3048)
			(end -0.120396 0.3048)
			(stroke
				(width 0.1)
				(type default)
			)
			(layer "B.Fab")
		)
		(fp_line
			(start -0.120396 0.3048)
			(end -0.120396 0.2794)
			(stroke
				(width 0.1)
				(type default)
			)
			(layer "B.Fab")
		)
		(fp_line
			(start 0.12065 0.3048)
			(end 0.67945 0.3048)
			(stroke
				(width 0.1)
				(type default)
			)
			(layer "B.Fab")
		)
		(fp_line
			(start 0.67945 0.3048)
			(end 0.67945 -0.305054)
			(stroke
				(width 0.1)
				(type default)
			)
			(layer "B.Fab")
		)
		(fp_line
			(start -0.120396 0.2794)
			(end 0.12065 0.2794)
			(stroke
				(width 0.1)
				(type default)
			)
			(layer "B.Fab")
		)
		(fp_line
			(start 0.12065 0.2794)
			(end 0.12065 0.3048)
			(stroke
				(width 0.1)
				(type default)
			)
			(layer "B.Fab")
		)
		(fp_line
			(start -0.12065 -0.2794)
			(end -0.12065 -0.3048)
			(stroke
				(width 0.1)
				(type default)
			)
			(layer "B.Fab")
		)
		(fp_line
			(start 0.12065 -0.2794)
			(end -0.12065 -0.2794)
			(stroke
				(width 0.1)
				(type default)
			)
			(layer "B.Fab")
		)
		(fp_line
			(start -0.67945 -0.3048)
			(end -0.67945 0.3048)
			(stroke
				(width 0.1)
				(type default)
			)
			(layer "B.Fab")
		)
		(fp_line
			(start -0.12065 -0.3048)
			(end -0.67945 -0.3048)
			(stroke
				(width 0.1)
				(type default)
			)
			(layer "B.Fab")
		)
		(fp_line
			(start 0.12065 -0.305054)
			(end 0.12065 -0.2794)
			(stroke
				(width 0.1)
				(type default)
			)
			(layer "B.Fab")
		)
		(fp_line
			(start 0.67945 -0.305054)
			(end 0.12065 -0.305054)
			(stroke
				(width 0.1)
				(type default)
			)
			(layer "B.Fab")
		)
		(pad "1" smd circle
			(at 0.40005 0 90)
			(size 0 0)
			(layers "B.Cu" "B.Mask" "B.Paste")
			(net "P0V8_SERDES_VDDA_PEX1")
		)
		(pad "2" smd circle
			(at -0.40005 0 90)
			(size 0 0)
			(layers "B.Cu" "B.Mask" "B.Paste")
			(net "P0V8_SERDES_VDDA_PEX1_C1")
		)
	)
	(footprint ""
		(layer "B.Cu")
		(at 342.893396 -220.38691 90)
		(property "Reference" "C2074"
			(at 0 0 90)
			(layer "B.SilkS")
			(hide yes)
			(effects
				(font
					(size 1.27 1.27)
				)
				(justify mirror)
			)
		)
		(property "Value" ""
			(at 0 0 90)
			(layer "B.Fab")
			(effects
				(font
					(size 1.27 1.27)
				)
				(justify mirror)
			)
		)
		(duplicate_pad_numbers_are_jumpers no)
		(fp_line
			(start 0.69215 -0.2921)
			(end -0.69215 -0.2921)
			(stroke
				(width 0.1524)
				(type default)
			)
			(layer "B.SilkS")
		)
		(fp_line
			(start -0.69215 -0.2921)
			(end -0.69215 0.2921)
			(stroke
				(width 0.1524)
				(type default)
			)
			(layer "B.SilkS")
		)
		(fp_line
			(start 0.69215 0.2921)
			(end 0.69215 -0.2921)
			(stroke
				(width 0.1524)
				(type default)
			)
			(layer "B.SilkS")
		)
		(fp_line
			(start -0.69215 0.2921)
			(end 0.69215 0.2921)
			(stroke
				(width 0.1524)
				(type default)
			)
			(layer "B.SilkS")
		)
		(fp_line
			(start 0.51435 -0.2794)
			(end -0.51435 -0.2794)
			(stroke
				(width 0.1)
				(type default)
			)
			(layer "B.Fab")
		)
		(fp_line
			(start -0.51435 -0.2794)
			(end -0.51435 0.2794)
			(stroke
				(width 0.1)
				(type default)
			)
			(layer "B.Fab")
		)
		(fp_line
			(start 0.51435 0.2794)
			(end 0.51435 -0.2794)
			(stroke
				(width 0.1)
				(type default)
			)
			(layer "B.Fab")
		)
		(fp_line
			(start -0.51435 0.2794)
			(end 0.51435 0.2794)
			(stroke
				(width 0.1)
				(type default)
			)
			(layer "B.Fab")
		)
		(pad "1" smd circle
			(at 0.40005 0 270)
			(size 0 0)
			(layers "B.Cu" "B.Mask" "B.Paste")
			(net "P3V3_VCC_FPGA_CORE")
		)
		(pad "2" smd circle
			(at -0.40005 0 270)
			(size 0 0)
			(layers "B.Cu" "B.Mask" "B.Paste")
			(net "GND")
		)
		(zone
			(layer "B.Cu")
			(hatch none 0.5)
			(connect_pads
				(clearance 0)
			)
			(min_thickness 0.25)
			(keepout
				(tracks not_allowed)
				(vias allowed)
				(pads allowed)
				(copperpour not_allowed)
				(footprints allowed)
			)
			(placement
				(enabled no)
				(sheetname "")
			)
			(fill
				(thermal_gap 0.5)
				(thermal_bridge_width 0.5)
				(island_removal_mode 0)
			)
			(polygon
				(pts
					(xy 342.981026 -220.57741) (xy 343.039192 -220.48597) (xy 343.039192 -220.28658) (xy 342.981026 -220.19641)
					(xy 342.805766 -220.19641) (xy 342.747346 -220.28658) (xy 342.747346 -220.48597) (xy 342.805512 -220.57741)
				)
			)
		)
	)
	(footprint ""
		(layer "B.Cu")
		(at 425.841922 -97.005648 180)
		(property "Reference" "R369"
			(at 0 0 0)
			(layer "B.SilkS")
			(hide yes)
			(effects
				(font
					(size 1.27 1.27)
				)
				(justify mirror)
			)
		)
		(property "Value" ""
			(at 0 0 0)
			(layer "B.Fab")
			(effects
				(font
					(size 1.27 1.27)
				)
				(justify mirror)
			)
		)
		(duplicate_pad_numbers_are_jumpers no)
		(fp_line
			(start 0.7874 0.4064)
			(end 0.7874 -0.4064)
			(stroke
				(width 0.1524)
				(type default)
			)
			(layer "B.SilkS")
		)
		(fp_line
			(start 0.7874 -0.4064)
			(end -0.7874 -0.4064)
			(stroke
				(width 0.1524)
				(type default)
			)
			(layer "B.SilkS")
		)
		(fp_line
			(start -0.7874 0.4064)
			(end 0.7874 0.4064)
			(stroke
				(width 0.1524)
				(type default)
			)
			(layer "B.SilkS")
		)
		(fp_line
			(start -0.7874 -0.4064)
			(end -0.7874 0.4064)
			(stroke
				(width 0.1524)
				(type default)
			)
			(layer "B.SilkS")
		)
		(fp_line
			(start 0.67945 0.3048)
			(end 0.67945 -0.305054)
			(stroke
				(width 0.1)
				(type default)
			)
			(layer "B.Fab")
		)
		(fp_line
			(start 0.67945 -0.305054)
			(end 0.12065 -0.305054)
			(stroke
				(width 0.1)
				(type default)
			)
			(layer "B.Fab")
		)
		(fp_line
			(start 0.12065 0.3048)
			(end 0.67945 0.3048)
			(stroke
				(width 0.1)
				(type default)
			)
			(layer "B.Fab")
		)
		(fp_line
			(start 0.12065 0.2794)
			(end 0.12065 0.3048)
			(stroke
				(width 0.1)
				(type default)
			)
			(layer "B.Fab")
		)
		(fp_line
			(start 0.12065 -0.2794)
			(end -0.12065 -0.2794)
			(stroke
				(width 0.1)
				(type default)
			)
			(layer "B.Fab")
		)
		(fp_line
			(start 0.12065 -0.305054)
			(end 0.12065 -0.2794)
			(stroke
				(width 0.1)
				(type default)
			)
			(layer "B.Fab")
		)
		(fp_line
			(start -0.120396 0.3048)
			(end -0.120396 0.2794)
			(stroke
				(width 0.1)
				(type default)
			)
			(layer "B.Fab")
		)
		(fp_line
			(start -0.120396 0.2794)
			(end 0.12065 0.2794)
			(stroke
				(width 0.1)
				(type default)
			)
			(layer "B.Fab")
		)
		(fp_line
			(start -0.12065 -0.2794)
			(end -0.12065 -0.3048)
			(stroke
				(width 0.1)
				(type default)
			)
			(layer "B.Fab")
		)
		(fp_line
			(start -0.12065 -0.3048)
			(end -0.67945 -0.3048)
			(stroke
				(width 0.1)
				(type default)
			)
			(layer "B.Fab")
		)
		(fp_line
			(start -0.67945 0.3048)
			(end -0.120396 0.3048)
			(stroke
				(width 0.1)
				(type default)
			)
			(layer "B.Fab")
		)
		(fp_line
			(start -0.67945 -0.3048)
			(end -0.67945 0.3048)
			(stroke
				(width 0.1)
				(type default)
			)
			(layer "B.Fab")
		)
		(pad "1" smd circle
			(at 0.40005 0)
			(size 0 0)
			(layers "B.Cu" "B.Mask" "B.Paste")
			(net "NIC7_DATA_IN")
		)
		(pad "2" smd circle
			(at -0.40005 0)
			(size 0 0)
			(layers "B.Cu" "B.Mask" "B.Paste")
			(net "P3V3_NIC7")
		)
	)
	(footprint ""
		(layer "B.Cu")
		(at 59.087004 -157.429962)
		(property "Reference" "U11"
			(at 0.846074 -2.258314 0)
			(unlocked yes)
			(layer "B.SilkS")
			(effects
				(font
					(size 0.7874 0.5842)
					(thickness 0.1524)
				)
				(justify left mirror)
			)
		)
		(property "Value" ""
			(at 0 0 0)
			(layer "B.Fab")
			(effects
				(font
					(size 1.27 1.27)
				)
				(justify mirror)
			)
		)
		(duplicate_pad_numbers_are_jumpers no)
		(fp_line
			(start -2.0574 -1.651)
			(end -2.0574 1.651)
			(stroke
				(width 0.1524)
				(type default)
			)
			(layer "B.SilkS")
		)
		(fp_line
			(start -2.0574 1.651)
			(end 2.0574 1.651)
			(stroke
				(width 0.1524)
				(type default)
			)
			(layer "B.SilkS")
		)
		(fp_line
			(start -0.381 -1.651)
			(end -2.0574 -1.651)
			(stroke
				(width 0.1524)
				(type default)
			)
			(layer "B.SilkS")
		)
		(fp_line
			(start 0 -1.016)
			(end -0.381 -1.651)
			(stroke
				(width 0.1524)
				(type default)
			)
			(layer "B.SilkS")
		)
		(fp_line
			(start 0.381 -1.651)
			(end 0 -1.016)
			(stroke
				(width 0.1524)
				(type default)
			)
			(layer "B.SilkS")
		)
		(fp_line
			(start 2.0574 -1.651)
			(end 0.381 -1.651)
			(stroke
				(width 0.1524)
				(type default)
			)
			(layer "B.SilkS")
		)
		(fp_line
			(start 2.0574 1.651)
			(end 2.0574 -1.651)
			(stroke
				(width 0.1524)
				(type default)
			)
			(layer "B.SilkS")
		)
		(fp_poly
			(pts
				(xy 2.71272 -0.719328) (xy 2.71272 -1.344168) (xy 2.159 -1.016)
			)
			(stroke
				(width 0)
				(type default)
			)
			(fill yes)
			(layer "B.SilkS")
		)
		(fp_line
			(start -1.599946 -1.199896)
			(end -1.599946 1.199896)
			(stroke
				(width 0.1)
				(type default)
			)
			(layer "B.Fab")
		)
		(fp_line
			(start -1.599946 1.199896)
			(end -0.899922 1.199896)
			(stroke
				(width 0.1)
				(type default)
			)
			(layer "B.Fab")
		)
		(fp_line
			(start -0.899922 -1.549908)
			(end -0.899922 -1.199896)
			(stroke
				(width 0.1)
				(type default)
			)
			(layer "B.Fab")
		)
		(fp_line
			(start -0.899922 -1.199896)
			(end -1.599946 -1.199896)
			(stroke
				(width 0.1)
				(type default)
			)
			(layer "B.Fab")
		)
		(fp_line
			(start -0.899922 1.199896)
			(end -0.899922 1.549908)
			(stroke
				(width 0.1)
				(type default)
			)
			(layer "B.Fab")
		)
		(fp_line
			(start -0.899922 1.549908)
			(end 0.899922 1.549908)
			(stroke
				(width 0.1)
				(type default)
			)
			(layer "B.Fab")
		)
		(fp_line
			(start 0.899922 -1.549908)
			(end -0.899922 -1.549908)
			(stroke
				(width 0.1)
				(type default)
			)
			(layer "B.Fab")
		)
		(fp_line
			(start 0.899922 -1.199896)
			(end 0.899922 -1.549908)
			(stroke
				(width 0.1)
				(type default)
			)
			(layer "B.Fab")
		)
		(fp_line
			(start 0.899922 1.199896)
			(end 1.599946 1.199896)
			(stroke
				(width 0.1)
				(type default)
			)
			(layer "B.Fab")
		)
		(fp_line
			(start 0.899922 1.549908)
			(end 0.899922 1.199896)
			(stroke
				(width 0.1)
				(type default)
			)
			(layer "B.Fab")
		)
		(fp_line
			(start 1.599946 -1.199896)
			(end 0.899922 -1.199896)
			(stroke
				(width 0.1)
				(type default)
			)
			(layer "B.Fab")
		)
		(fp_line
			(start 1.599946 1.199896)
			(end 1.599946 -1.199896)
			(stroke
				(width 0.1)
				(type default)
			)
			(layer "B.Fab")
		)
		(fp_poly
			(pts
				(xy 2.71272 -0.719328) (xy 2.71272 -1.344168) (xy 2.159 -1.016)
			)
			(stroke
				(width 0)
				(type default)
			)
			(fill yes)
			(layer "B.Fab")
		)
		(pad "1" smd rect
			(at 1.225042 -0.94996 270)
			(size 0.5588 1.3462)
			(layers "B.Cu" "B.Mask" "B.Paste")
			(net "HP_NIC0_PWRGD_R")
		)
		(pad "2" smd rect
			(at 1.225042 0 270)
			(size 0.5588 1.3462)
			(layers "B.Cu" "B.Mask" "B.Paste")
			(net "RST_NIC0_PERST_R_N")
		)
		(pad "3" smd rect
			(at 1.225042 0.94996 270)
			(size 0.5588 1.3462)
			(layers "B.Cu" "B.Mask" "B.Paste")
			(net "GND")
		)
		(pad "4" smd rect
			(at -1.225042 0.94996 270)
			(size 0.5588 1.3462)
			(layers "B.Cu" "B.Mask" "B.Paste")
			(net "RST_HP_NIC0_N")
		)
		(pad "5" smd rect
			(at -1.225042 -0.94996 270)
			(size 0.5588 1.3462)
			(layers "B.Cu" "B.Mask" "B.Paste")
			(net "P3V3_AUX")
		)
	)
	(footprint ""
		(layer "B.Cu")
		(at 263.78408 -366.927384 180)
		(property "Reference" "PR6611"
			(at 0 0 0)
			(layer "B.SilkS")
			(hide yes)
			(effects
				(font
					(size 1.27 1.27)
				)
				(justify mirror)
			)
		)
		(property "Value" ""
			(at 0 0 0)
			(layer "B.Fab")
			(effects
				(font
					(size 1.27 1.27)
				)
				(justify mirror)
			)
		)
		(duplicate_pad_numbers_are_jumpers no)
		(fp_line
			(start 0.7874 0.4064)
			(end 0.7874 -0.4064)
			(stroke
				(width 0.1524)
				(type default)
			)
			(layer "B.SilkS")
		)
		(fp_line
			(start 0.7874 -0.4064)
			(end -0.7874 -0.4064)
			(stroke
				(width 0.1524)
				(type default)
			)
			(layer "B.SilkS")
		)
		(fp_line
			(start -0.7874 0.4064)
			(end 0.7874 0.4064)
			(stroke
				(width 0.1524)
				(type default)
			)
			(layer "B.SilkS")
		)
		(fp_line
			(start -0.7874 -0.4064)
			(end -0.7874 0.4064)
			(stroke
				(width 0.1524)
				(type default)
			)
			(layer "B.SilkS")
		)
		(fp_line
			(start 0.67945 0.3048)
			(end 0.67945 -0.305054)
			(stroke
				(width 0.1)
				(type default)
			)
			(layer "B.Fab")
		)
		(fp_line
			(start 0.67945 -0.305054)
			(end 0.12065 -0.305054)
			(stroke
				(width 0.1)
				(type default)
			)
			(layer "B.Fab")
		)
		(fp_line
			(start 0.12065 0.3048)
			(end 0.67945 0.3048)
			(stroke
				(width 0.1)
				(type default)
			)
			(layer "B.Fab")
		)
		(fp_line
			(start 0.12065 0.2794)
			(end 0.12065 0.3048)
			(stroke
				(width 0.1)
				(type default)
			)
			(layer "B.Fab")
		)
		(fp_line
			(start 0.12065 -0.2794)
			(end -0.12065 -0.2794)
			(stroke
				(width 0.1)
				(type default)
			)
			(layer "B.Fab")
		)
		(fp_line
			(start 0.12065 -0.305054)
			(end 0.12065 -0.2794)
			(stroke
				(width 0.1)
				(type default)
			)
			(layer "B.Fab")
		)
		(fp_line
			(start -0.120396 0.3048)
			(end -0.120396 0.2794)
			(stroke
				(width 0.1)
				(type default)
			)
			(layer "B.Fab")
		)
		(fp_line
			(start -0.120396 0.2794)
			(end 0.12065 0.2794)
			(stroke
				(width 0.1)
				(type default)
			)
			(layer "B.Fab")
		)
		(fp_line
			(start -0.12065 -0.2794)
			(end -0.12065 -0.3048)
			(stroke
				(width 0.1)
				(type default)
			)
			(layer "B.Fab")
		)
		(fp_line
			(start -0.12065 -0.3048)
			(end -0.67945 -0.3048)
			(stroke
				(width 0.1)
				(type default)
			)
			(layer "B.Fab")
		)
		(fp_line
			(start -0.67945 0.3048)
			(end -0.120396 0.3048)
			(stroke
				(width 0.1)
				(type default)
			)
			(layer "B.Fab")
		)
		(fp_line
			(start -0.67945 -0.3048)
			(end -0.67945 0.3048)
			(stroke
				(width 0.1)
				(type default)
			)
			(layer "B.Fab")
		)
		(pad "1" smd circle
			(at 0.40005 0)
			(size 0 0)
			(layers "B.Cu" "B.Mask" "B.Paste")
			(net "P12V_HSC_GATE2")
		)
		(pad "2" smd circle
			(at -0.40005 0)
			(size 0 0)
			(layers "B.Cu" "B.Mask" "B.Paste")
			(net "HS_GATE2_R_4")
		)
	)
	(footprint ""
		(layer "B.Cu")
		(at 281.755342 -157.0736 180)
		(property "Reference" "R205"
			(at 0 0 0)
			(layer "B.SilkS")
			(hide yes)
			(effects
				(font
					(size 1.27 1.27)
				)
				(justify mirror)
			)
		)
		(property "Value" ""
			(at 0 0 0)
			(layer "B.Fab")
			(effects
				(font
					(size 1.27 1.27)
				)
				(justify mirror)
			)
		)
		(duplicate_pad_numbers_are_jumpers no)
		(fp_line
			(start 0.7874 0.4064)
			(end 0.7874 -0.4064)
			(stroke
				(width 0.1524)
				(type default)
			)
			(layer "B.SilkS")
		)
		(fp_line
			(start 0.7874 -0.4064)
			(end -0.7874 -0.4064)
			(stroke
				(width 0.1524)
				(type default)
			)
			(layer "B.SilkS")
		)
		(fp_line
			(start -0.7874 0.4064)
			(end 0.7874 0.4064)
			(stroke
				(width 0.1524)
				(type default)
			)
			(layer "B.SilkS")
		)
		(fp_line
			(start -0.7874 -0.4064)
			(end -0.7874 0.4064)
			(stroke
				(width 0.1524)
				(type default)
			)
			(layer "B.SilkS")
		)
		(fp_line
			(start 0.67945 0.3048)
			(end 0.67945 -0.305054)
			(stroke
				(width 0.1)
				(type default)
			)
			(layer "B.Fab")
		)
		(fp_line
			(start 0.67945 -0.305054)
			(end 0.12065 -0.305054)
			(stroke
				(width 0.1)
				(type default)
			)
			(layer "B.Fab")
		)
		(fp_line
			(start 0.12065 0.3048)
			(end 0.67945 0.3048)
			(stroke
				(width 0.1)
				(type default)
			)
			(layer "B.Fab")
		)
		(fp_line
			(start 0.12065 0.2794)
			(end 0.12065 0.3048)
			(stroke
				(width 0.1)
				(type default)
			)
			(layer "B.Fab")
		)
		(fp_line
			(start 0.12065 -0.2794)
			(end -0.12065 -0.2794)
			(stroke
				(width 0.1)
				(type default)
			)
			(layer "B.Fab")
		)
		(fp_line
			(start 0.12065 -0.305054)
			(end 0.12065 -0.2794)
			(stroke
				(width 0.1)
				(type default)
			)
			(layer "B.Fab")
		)
		(fp_line
			(start -0.120396 0.3048)
			(end -0.120396 0.2794)
			(stroke
				(width 0.1)
				(type default)
			)
			(layer "B.Fab")
		)
		(fp_line
			(start -0.120396 0.2794)
			(end 0.12065 0.2794)
			(stroke
				(width 0.1)
				(type default)
			)
			(layer "B.Fab")
		)
		(fp_line
			(start -0.12065 -0.2794)
			(end -0.12065 -0.3048)
			(stroke
				(width 0.1)
				(type default)
			)
			(layer "B.Fab")
		)
		(fp_line
			(start -0.12065 -0.3048)
			(end -0.67945 -0.3048)
			(stroke
				(width 0.1)
				(type default)
			)
			(layer "B.Fab")
		)
		(fp_line
			(start -0.67945 0.3048)
			(end -0.120396 0.3048)
			(stroke
				(width 0.1)
				(type default)
			)
			(layer "B.Fab")
		)
		(fp_line
			(start -0.67945 -0.3048)
			(end -0.67945 0.3048)
			(stroke
				(width 0.1)
				(type default)
			)
			(layer "B.Fab")
		)
		(pad "1" smd circle
			(at 0.40005 0)
			(size 0 0)
			(layers "B.Cu" "B.Mask" "B.Paste")
			(net "NIC4_RBT_ARB_OUT")
		)
		(pad "2" smd circle
			(at -0.40005 0)
			(size 0 0)
			(layers "B.Cu" "B.Mask" "B.Paste")
			(net "NIC4_RBT_ARB_IN")
		)
	)
	(footprint ""
		(layer "B.Cu")
		(at 342.09355 -220.38691 90)
		(property "Reference" "C2070"
			(at 0 0 90)
			(layer "B.SilkS")
			(hide yes)
			(effects
				(font
					(size 1.27 1.27)
				)
				(justify mirror)
			)
		)
		(property "Value" ""
			(at 0 0 90)
			(layer "B.Fab")
			(effects
				(font
					(size 1.27 1.27)
				)
				(justify mirror)
			)
		)
		(duplicate_pad_numbers_are_jumpers no)
		(fp_line
			(start 0.69215 -0.2921)
			(end -0.69215 -0.2921)
			(stroke
				(width 0.1524)
				(type default)
			)
			(layer "B.SilkS")
		)
		(fp_line
			(start -0.69215 -0.2921)
			(end -0.69215 0.2921)
			(stroke
				(width 0.1524)
				(type default)
			)
			(layer "B.SilkS")
		)
		(fp_line
			(start 0.69215 0.2921)
			(end 0.69215 -0.2921)
			(stroke
				(width 0.1524)
				(type default)
			)
			(layer "B.SilkS")
		)
		(fp_line
			(start -0.69215 0.2921)
			(end 0.69215 0.2921)
			(stroke
				(width 0.1524)
				(type default)
			)
			(layer "B.SilkS")
		)
		(fp_line
			(start 0.51435 -0.2794)
			(end -0.51435 -0.2794)
			(stroke
				(width 0.1)
				(type default)
			)
			(layer "B.Fab")
		)
		(fp_line
			(start -0.51435 -0.2794)
			(end -0.51435 0.2794)
			(stroke
				(width 0.1)
				(type default)
			)
			(layer "B.Fab")
		)
		(fp_line
			(start 0.51435 0.2794)
			(end 0.51435 -0.2794)
			(stroke
				(width 0.1)
				(type default)
			)
			(layer "B.Fab")
		)
		(fp_line
			(start -0.51435 0.2794)
			(end 0.51435 0.2794)
			(stroke
				(width 0.1)
				(type default)
			)
			(layer "B.Fab")
		)
		(pad "1" smd circle
			(at 0.40005 0 270)
			(size 0 0)
			(layers "B.Cu" "B.Mask" "B.Paste")
			(net "P3V3_VCC_FPGA_CORE")
		)
		(pad "2" smd circle
			(at -0.40005 0 270)
			(size 0 0)
			(layers "B.Cu" "B.Mask" "B.Paste")
			(net "GND")
		)
		(zone
			(layer "B.Cu")
			(hatch none 0.5)
			(connect_pads
				(clearance 0)
			)
			(min_thickness 0.25)
			(keepout
				(tracks not_allowed)
				(vias allowed)
				(pads allowed)
				(copperpour not_allowed)
				(footprints allowed)
			)
			(placement
				(enabled no)
				(sheetname "")
			)
			(fill
				(thermal_gap 0.5)
				(thermal_bridge_width 0.5)
				(island_removal_mode 0)
			)
			(polygon
				(pts
					(xy 342.18118 -220.57741) (xy 342.239346 -220.48597) (xy 342.239346 -220.28658) (xy 342.18118 -220.19641)
					(xy 342.00592 -220.19641) (xy 341.9475 -220.28658) (xy 341.9475 -220.48597) (xy 342.005666 -220.57741)
				)
			)
		)
	)
	(footprint ""
		(layer "B.Cu")
		(at 372.38305 -220.932756 90)
		(property "Reference" "R3498"
			(at 0 0 90)
			(layer "B.SilkS")
			(hide yes)
			(effects
				(font
					(size 1.27 1.27)
				)
				(justify mirror)
			)
		)
		(property "Value" ""
			(at 0 0 90)
			(layer "B.Fab")
			(effects
				(font
					(size 1.27 1.27)
				)
				(justify mirror)
			)
		)
		(duplicate_pad_numbers_are_jumpers no)
		(fp_line
			(start 0.7874 -0.4064)
			(end -0.7874 -0.4064)
			(stroke
				(width 0.1524)
				(type default)
			)
			(layer "B.SilkS")
		)
		(fp_line
			(start -0.7874 -0.4064)
			(end -0.7874 0.4064)
			(stroke
				(width 0.1524)
				(type default)
			)
			(layer "B.SilkS")
		)
		(fp_line
			(start 0.7874 0.4064)
			(end 0.7874 -0.4064)
			(stroke
				(width 0.1524)
				(type default)
			)
			(layer "B.SilkS")
		)
		(fp_line
			(start -0.7874 0.4064)
			(end 0.7874 0.4064)
			(stroke
				(width 0.1524)
				(type default)
			)
			(layer "B.SilkS")
		)
		(fp_line
			(start 0.67945 -0.305054)
			(end 0.12065 -0.305054)
			(stroke
				(width 0.1)
				(type default)
			)
			(layer "B.Fab")
		)
		(fp_line
			(start 0.12065 -0.305054)
			(end 0.12065 -0.2794)
			(stroke
				(width 0.1)
				(type default)
			)
			(layer "B.Fab")
		)
		(fp_line
			(start -0.12065 -0.3048)
			(end -0.67945 -0.3048)
			(stroke
				(width 0.1)
				(type default)
			)
			(layer "B.Fab")
		)
		(fp_line
			(start -0.67945 -0.3048)
			(end -0.67945 0.3048)
			(stroke
				(width 0.1)
				(type default)
			)
			(layer "B.Fab")
		)
		(fp_line
			(start 0.12065 -0.2794)
			(end -0.12065 -0.2794)
			(stroke
				(width 0.1)
				(type default)
			)
			(layer "B.Fab")
		)
		(fp_line
			(start -0.12065 -0.2794)
			(end -0.12065 -0.3048)
			(stroke
				(width 0.1)
				(type default)
			)
			(layer "B.Fab")
		)
		(fp_line
			(start 0.12065 0.2794)
			(end 0.12065 0.3048)
			(stroke
				(width 0.1)
				(type default)
			)
			(layer "B.Fab")
		)
		(fp_line
			(start -0.120396 0.2794)
			(end 0.12065 0.2794)
			(stroke
				(width 0.1)
				(type default)
			)
			(layer "B.Fab")
		)
		(fp_line
			(start 0.67945 0.3048)
			(end 0.67945 -0.305054)
			(stroke
				(width 0.1)
				(type default)
			)
			(layer "B.Fab")
		)
		(fp_line
			(start 0.12065 0.3048)
			(end 0.67945 0.3048)
			(stroke
				(width 0.1)
				(type default)
			)
			(layer "B.Fab")
		)
		(fp_line
			(start -0.120396 0.3048)
			(end -0.120396 0.2794)
			(stroke
				(width 0.1)
				(type default)
			)
			(layer "B.Fab")
		)
		(fp_line
			(start -0.67945 0.3048)
			(end -0.120396 0.3048)
			(stroke
				(width 0.1)
				(type default)
			)
			(layer "B.Fab")
		)
		(pad "1" smd circle
			(at 0.40005 0 270)
			(size 0 0)
			(layers "B.Cu" "B.Mask" "B.Paste")
			(net "SPI_PEX3_SDIO3_R")
		)
		(pad "2" smd circle
			(at -0.40005 0 270)
			(size 0 0)
			(layers "B.Cu" "B.Mask" "B.Paste")
			(net "SPI_PEX3_SDIO3_R1")
		)
	)
	(footprint ""
		(layer "B.Cu")
		(at 57.749948 -303.499774 -90)
		(property "Reference" "C2917"
			(at 0 0 90)
			(layer "B.SilkS")
			(hide yes)
			(effects
				(font
					(size 1.27 1.27)
				)
				(justify mirror)
			)
		)
		(property "Value" ""
			(at 0 0 90)
			(layer "B.Fab")
			(effects
				(font
					(size 1.27 1.27)
				)
				(justify mirror)
			)
		)
		(duplicate_pad_numbers_are_jumpers no)
		(fp_line
			(start -0.299974 0.150114)
			(end 0.299974 0.150114)
			(stroke
				(width 0.1)
				(type default)
			)
			(layer "B.Fab")
		)
		(fp_line
			(start 0.299974 0.150114)
			(end 0.299974 -0.150114)
			(stroke
				(width 0.1)
				(type default)
			)
			(layer "B.Fab")
		)
		(fp_line
			(start -0.299974 -0.150114)
			(end -0.299974 0.150114)
			(stroke
				(width 0.1)
				(type default)
			)
			(layer "B.Fab")
		)
		(fp_line
			(start 0.299974 -0.150114)
			(end -0.299974 -0.150114)
			(stroke
				(width 0.1)
				(type default)
			)
			(layer "B.Fab")
		)
		(pad "1" smd rect
			(at 0.2667 0 90)
			(size 0.3048 0.381)
			(layers "B.Cu" "B.Mask" "B.Paste")
			(net "P1V25_PEX0")
		)
		(pad "2" smd rect
			(at -0.2667 0 90)
			(size 0.3048 0.381)
			(layers "B.Cu" "B.Mask" "B.Paste")
			(net "GND")
		)
	)
	(footprint ""
		(layer "B.Cu")
		(at 130.539744 -204.209142 180)
		(property "Reference" "R919"
			(at 0 0 0)
			(layer "B.SilkS")
			(hide yes)
			(effects
				(font
					(size 1.27 1.27)
				)
				(justify mirror)
			)
		)
		(property "Value" ""
			(at 0 0 0)
			(layer "B.Fab")
			(effects
				(font
					(size 1.27 1.27)
				)
				(justify mirror)
			)
		)
		(duplicate_pad_numbers_are_jumpers no)
		(fp_line
			(start 0.7874 0.4064)
			(end 0.7874 -0.4064)
			(stroke
				(width 0.1524)
				(type default)
			)
			(layer "B.SilkS")
		)
		(fp_line
			(start 0.7874 -0.4064)
			(end -0.7874 -0.4064)
			(stroke
				(width 0.1524)
				(type default)
			)
			(layer "B.SilkS")
		)
		(fp_line
			(start -0.7874 0.4064)
			(end 0.7874 0.4064)
			(stroke
				(width 0.1524)
				(type default)
			)
			(layer "B.SilkS")
		)
		(fp_line
			(start -0.7874 -0.4064)
			(end -0.7874 0.4064)
			(stroke
				(width 0.1524)
				(type default)
			)
			(layer "B.SilkS")
		)
		(fp_line
			(start 0.67945 0.3048)
			(end 0.67945 -0.305054)
			(stroke
				(width 0.1)
				(type default)
			)
			(layer "B.Fab")
		)
		(fp_line
			(start 0.67945 -0.305054)
			(end 0.12065 -0.305054)
			(stroke
				(width 0.1)
				(type default)
			)
			(layer "B.Fab")
		)
		(fp_line
			(start 0.12065 0.3048)
			(end 0.67945 0.3048)
			(stroke
				(width 0.1)
				(type default)
			)
			(layer "B.Fab")
		)
		(fp_line
			(start 0.12065 0.2794)
			(end 0.12065 0.3048)
			(stroke
				(width 0.1)
				(type default)
			)
			(layer "B.Fab")
		)
		(fp_line
			(start 0.12065 -0.2794)
			(end -0.12065 -0.2794)
			(stroke
				(width 0.1)
				(type default)
			)
			(layer "B.Fab")
		)
		(fp_line
			(start 0.12065 -0.305054)
			(end 0.12065 -0.2794)
			(stroke
				(width 0.1)
				(type default)
			)
			(layer "B.Fab")
		)
		(fp_line
			(start -0.120396 0.3048)
			(end -0.120396 0.2794)
			(stroke
				(width 0.1)
				(type default)
			)
			(layer "B.Fab")
		)
		(fp_line
			(start -0.120396 0.2794)
			(end 0.12065 0.2794)
			(stroke
				(width 0.1)
				(type default)
			)
			(layer "B.Fab")
		)
		(fp_line
			(start -0.12065 -0.2794)
			(end -0.12065 -0.3048)
			(stroke
				(width 0.1)
				(type default)
			)
			(layer "B.Fab")
		)
		(fp_line
			(start -0.12065 -0.3048)
			(end -0.67945 -0.3048)
			(stroke
				(width 0.1)
				(type default)
			)
			(layer "B.Fab")
		)
		(fp_line
			(start -0.67945 0.3048)
			(end -0.120396 0.3048)
			(stroke
				(width 0.1)
				(type default)
			)
			(layer "B.Fab")
		)
		(fp_line
			(start -0.67945 -0.3048)
			(end -0.67945 0.3048)
			(stroke
				(width 0.1)
				(type default)
			)
			(layer "B.Fab")
		)
		(pad "1" smd circle
			(at 0.40005 0)
			(size 0 0)
			(layers "B.Cu" "B.Mask" "B.Paste")
			(net "FT4232_CLI_EEPROM_R_CS")
		)
		(pad "2" smd circle
			(at -0.40005 0)
			(size 0 0)
			(layers "B.Cu" "B.Mask" "B.Paste")
			(net "P3V3_AUX")
		)
	)
	(footprint ""
		(layer "B.Cu")
		(at 117.265958 -321.396106 -90)
		(property "Reference" "R6449"
			(at 0 0 90)
			(layer "B.SilkS")
			(hide yes)
			(effects
				(font
					(size 1.27 1.27)
				)
				(justify mirror)
			)
		)
		(property "Value" ""
			(at 0 0 90)
			(layer "B.Fab")
			(effects
				(font
					(size 1.27 1.27)
				)
				(justify mirror)
			)
		)
		(duplicate_pad_numbers_are_jumpers no)
		(fp_line
			(start -0.7874 0.4064)
			(end 0.7874 0.4064)
			(stroke
				(width 0.1524)
				(type default)
			)
			(layer "B.SilkS")
		)
		(fp_line
			(start 0.7874 0.4064)
			(end 0.7874 -0.4064)
			(stroke
				(width 0.1524)
				(type default)
			)
			(layer "B.SilkS")
		)
		(fp_line
			(start -0.7874 -0.4064)
			(end -0.7874 0.4064)
			(stroke
				(width 0.1524)
				(type default)
			)
			(layer "B.SilkS")
		)
		(fp_line
			(start 0.7874 -0.4064)
			(end -0.7874 -0.4064)
			(stroke
				(width 0.1524)
				(type default)
			)
			(layer "B.SilkS")
		)
		(fp_line
			(start -0.67945 0.3048)
			(end -0.120396 0.3048)
			(stroke
				(width 0.1)
				(type default)
			)
			(layer "B.Fab")
		)
		(fp_line
			(start -0.120396 0.3048)
			(end -0.120396 0.2794)
			(stroke
				(width 0.1)
				(type default)
			)
			(layer "B.Fab")
		)
		(fp_line
			(start 0.12065 0.3048)
			(end 0.67945 0.3048)
			(stroke
				(width 0.1)
				(type default)
			)
			(layer "B.Fab")
		)
		(fp_line
			(start 0.67945 0.3048)
			(end 0.67945 -0.305054)
			(stroke
				(width 0.1)
				(type default)
			)
			(layer "B.Fab")
		)
		(fp_line
			(start -0.120396 0.2794)
			(end 0.12065 0.2794)
			(stroke
				(width 0.1)
				(type default)
			)
			(layer "B.Fab")
		)
		(fp_line
			(start 0.12065 0.2794)
			(end 0.12065 0.3048)
			(stroke
				(width 0.1)
				(type default)
			)
			(layer "B.Fab")
		)
		(fp_line
			(start -0.12065 -0.2794)
			(end -0.12065 -0.3048)
			(stroke
				(width 0.1)
				(type default)
			)
			(layer "B.Fab")
		)
		(fp_line
			(start 0.12065 -0.2794)
			(end -0.12065 -0.2794)
			(stroke
				(width 0.1)
				(type default)
			)
			(layer "B.Fab")
		)
		(fp_line
			(start -0.67945 -0.3048)
			(end -0.67945 0.3048)
			(stroke
				(width 0.1)
				(type default)
			)
			(layer "B.Fab")
		)
		(fp_line
			(start -0.12065 -0.3048)
			(end -0.67945 -0.3048)
			(stroke
				(width 0.1)
				(type default)
			)
			(layer "B.Fab")
		)
		(fp_line
			(start 0.12065 -0.305054)
			(end 0.12065 -0.2794)
			(stroke
				(width 0.1)
				(type default)
			)
			(layer "B.Fab")
		)
		(fp_line
			(start 0.67945 -0.305054)
			(end 0.12065 -0.305054)
			(stroke
				(width 0.1)
				(type default)
			)
			(layer "B.Fab")
		)
		(pad "1" smd circle
			(at 0.40005 0 90)
			(size 0 0)
			(layers "B.Cu" "B.Mask" "B.Paste")
			(net "P0V8_SERDES_VDDA_PEX0")
		)
		(pad "2" smd circle
			(at -0.40005 0 90)
			(size 0 0)
			(layers "B.Cu" "B.Mask" "B.Paste")
			(net "P0V8_SERDES_VDDA_PEX0_C0")
		)
	)
	(footprint ""
		(layer "B.Cu")
		(at 230.66756 -214.704168 90)
		(property "Reference" "C2026"
			(at 0 0 90)
			(layer "B.SilkS")
			(hide yes)
			(effects
				(font
					(size 1.27 1.27)
				)
				(justify mirror)
			)
		)
		(property "Value" ""
			(at 0 0 90)
			(layer "B.Fab")
			(effects
				(font
					(size 1.27 1.27)
				)
				(justify mirror)
			)
		)
		(duplicate_pad_numbers_are_jumpers no)
		(fp_line
			(start 0.69215 -0.2921)
			(end -0.69215 -0.2921)
			(stroke
				(width 0.1524)
				(type default)
			)
			(layer "B.SilkS")
		)
		(fp_line
			(start -0.69215 -0.2921)
			(end -0.69215 0.2921)
			(stroke
				(width 0.1524)
				(type default)
			)
			(layer "B.SilkS")
		)
		(fp_line
			(start 0.69215 0.2921)
			(end 0.69215 -0.2921)
			(stroke
				(width 0.1524)
				(type default)
			)
			(layer "B.SilkS")
		)
		(fp_line
			(start -0.69215 0.2921)
			(end 0.69215 0.2921)
			(stroke
				(width 0.1524)
				(type default)
			)
			(layer "B.SilkS")
		)
		(fp_line
			(start 0.51435 -0.2794)
			(end -0.51435 -0.2794)
			(stroke
				(width 0.1)
				(type default)
			)
			(layer "B.Fab")
		)
		(fp_line
			(start -0.51435 -0.2794)
			(end -0.51435 0.2794)
			(stroke
				(width 0.1)
				(type default)
			)
			(layer "B.Fab")
		)
		(fp_line
			(start 0.51435 0.2794)
			(end 0.51435 -0.2794)
			(stroke
				(width 0.1)
				(type default)
			)
			(layer "B.Fab")
		)
		(fp_line
			(start -0.51435 0.2794)
			(end 0.51435 0.2794)
			(stroke
				(width 0.1)
				(type default)
			)
			(layer "B.Fab")
		)
		(pad "1" smd circle
			(at 0.40005 0 270)
			(size 0 0)
			(layers "B.Cu" "B.Mask" "B.Paste")
			(net "P3V3_AUX")
		)
		(pad "2" smd circle
			(at -0.40005 0 270)
			(size 0 0)
			(layers "B.Cu" "B.Mask" "B.Paste")
			(net "GND")
		)
		(zone
			(layer "B.Cu")
			(hatch none 0.5)
			(connect_pads
				(clearance 0)
			)
			(min_thickness 0.25)
			(keepout
				(tracks not_allowed)
				(vias allowed)
				(pads allowed)
				(copperpour not_allowed)
				(footprints allowed)
			)
			(placement
				(enabled no)
				(sheetname "")
			)
			(fill
				(thermal_gap 0.5)
				(thermal_bridge_width 0.5)
				(island_removal_mode 0)
			)
			(polygon
				(pts
					(xy 230.75519 -214.894668) (xy 230.813356 -214.803228) (xy 230.813356 -214.603838) (xy 230.75519 -214.513668)
					(xy 230.57993 -214.513668) (xy 230.52151 -214.603838) (xy 230.52151 -214.803228) (xy 230.579676 -214.894668)
				)
			)
		)
	)
	(footprint ""
		(layer "B.Cu")
		(at 172.424852 -293.99992 90)
		(property "Reference" "C1376"
			(at 0 0 90)
			(layer "B.SilkS")
			(hide yes)
			(effects
				(font
					(size 1.27 1.27)
				)
				(justify mirror)
			)
		)
		(property "Value" ""
			(at 0 0 90)
			(layer "B.Fab")
			(effects
				(font
					(size 1.27 1.27)
				)
				(justify mirror)
			)
		)
		(duplicate_pad_numbers_are_jumpers no)
		(fp_line
			(start 0.299974 -0.150114)
			(end -0.299974 -0.150114)
			(stroke
				(width 0.1)
				(type default)
			)
			(layer "B.Fab")
		)
		(fp_line
			(start -0.299974 -0.150114)
			(end -0.299974 0.150114)
			(stroke
				(width 0.1)
				(type default)
			)
			(layer "B.Fab")
		)
		(fp_line
			(start 0.299974 0.150114)
			(end 0.299974 -0.150114)
			(stroke
				(width 0.1)
				(type default)
			)
			(layer "B.Fab")
		)
		(fp_line
			(start -0.299974 0.150114)
			(end 0.299974 0.150114)
			(stroke
				(width 0.1)
				(type default)
			)
			(layer "B.Fab")
		)
		(pad "1" smd rect
			(at 0.2667 0 270)
			(size 0.3048 0.381)
			(layers "B.Cu" "B.Mask" "B.Paste")
			(net "P0V8_PEX1")
		)
		(pad "2" smd rect
			(at -0.2667 0 270)
			(size 0.3048 0.381)
			(layers "B.Cu" "B.Mask" "B.Paste")
			(net "GND")
		)
	)
	(footprint ""
		(layer "B.Cu")
		(at 378.164344 -226.47021 180)
		(property "Reference" "R6171"
			(at 0 0 0)
			(layer "B.SilkS")
			(hide yes)
			(effects
				(font
					(size 1.27 1.27)
				)
				(justify mirror)
			)
		)
		(property "Value" ""
			(at 0 0 0)
			(layer "B.Fab")
			(effects
				(font
					(size 1.27 1.27)
				)
				(justify mirror)
			)
		)
		(duplicate_pad_numbers_are_jumpers no)
		(fp_line
			(start 0.7874 0.4064)
			(end 0.7874 -0.4064)
			(stroke
				(width 0.1524)
				(type default)
			)
			(layer "B.SilkS")
		)
		(fp_line
			(start 0.7874 -0.4064)
			(end -0.7874 -0.4064)
			(stroke
				(width 0.1524)
				(type default)
			)
			(layer "B.SilkS")
		)
		(fp_line
			(start -0.7874 0.4064)
			(end 0.7874 0.4064)
			(stroke
				(width 0.1524)
				(type default)
			)
			(layer "B.SilkS")
		)
		(fp_line
			(start -0.7874 -0.4064)
			(end -0.7874 0.4064)
			(stroke
				(width 0.1524)
				(type default)
			)
			(layer "B.SilkS")
		)
		(fp_line
			(start 0.67945 0.3048)
			(end 0.67945 -0.305054)
			(stroke
				(width 0.1)
				(type default)
			)
			(layer "B.Fab")
		)
		(fp_line
			(start 0.67945 -0.305054)
			(end 0.12065 -0.305054)
			(stroke
				(width 0.1)
				(type default)
			)
			(layer "B.Fab")
		)
		(fp_line
			(start 0.12065 0.3048)
			(end 0.67945 0.3048)
			(stroke
				(width 0.1)
				(type default)
			)
			(layer "B.Fab")
		)
		(fp_line
			(start 0.12065 0.2794)
			(end 0.12065 0.3048)
			(stroke
				(width 0.1)
				(type default)
			)
			(layer "B.Fab")
		)
		(fp_line
			(start 0.12065 -0.2794)
			(end -0.12065 -0.2794)
			(stroke
				(width 0.1)
				(type default)
			)
			(layer "B.Fab")
		)
		(fp_line
			(start 0.12065 -0.305054)
			(end 0.12065 -0.2794)
			(stroke
				(width 0.1)
				(type default)
			)
			(layer "B.Fab")
		)
		(fp_line
			(start -0.120396 0.3048)
			(end -0.120396 0.2794)
			(stroke
				(width 0.1)
				(type default)
			)
			(layer "B.Fab")
		)
		(fp_line
			(start -0.120396 0.2794)
			(end 0.12065 0.2794)
			(stroke
				(width 0.1)
				(type default)
			)
			(layer "B.Fab")
		)
		(fp_line
			(start -0.12065 -0.2794)
			(end -0.12065 -0.3048)
			(stroke
				(width 0.1)
				(type default)
			)
			(layer "B.Fab")
		)
		(fp_line
			(start -0.12065 -0.3048)
			(end -0.67945 -0.3048)
			(stroke
				(width 0.1)
				(type default)
			)
			(layer "B.Fab")
		)
		(fp_line
			(start -0.67945 0.3048)
			(end -0.120396 0.3048)
			(stroke
				(width 0.1)
				(type default)
			)
			(layer "B.Fab")
		)
		(fp_line
			(start -0.67945 -0.3048)
			(end -0.67945 0.3048)
			(stroke
				(width 0.1)
				(type default)
			)
			(layer "B.Fab")
		)
		(pad "1" smd circle
			(at 0.40005 0)
			(size 0 0)
			(layers "B.Cu" "B.Mask" "B.Paste")
			(net "SPI_PEX3_RST_R_N")
		)
		(pad "2" smd circle
			(at -0.40005 0)
			(size 0 0)
			(layers "B.Cu" "B.Mask" "B.Paste")
			(net "SPI_PEX3_RST_N")
		)
	)
	(footprint ""
		(layer "B.Cu")
		(at 108.91139 -283.818584 90)
		(property "Reference" "PR99"
			(at 0 0 90)
			(layer "B.SilkS")
			(hide yes)
			(effects
				(font
					(size 1.27 1.27)
				)
				(justify mirror)
			)
		)
		(property "Value" ""
			(at 0 0 90)
			(layer "B.Fab")
			(effects
				(font
					(size 1.27 1.27)
				)
				(justify mirror)
			)
		)
		(duplicate_pad_numbers_are_jumpers no)
		(fp_line
			(start 0.7874 -0.4064)
			(end -0.7874 -0.4064)
			(stroke
				(width 0.1524)
				(type default)
			)
			(layer "B.SilkS")
		)
		(fp_line
			(start -0.7874 -0.4064)
			(end -0.7874 0.4064)
			(stroke
				(width 0.1524)
				(type default)
			)
			(layer "B.SilkS")
		)
		(fp_line
			(start 0.7874 0.4064)
			(end 0.7874 -0.4064)
			(stroke
				(width 0.1524)
				(type default)
			)
			(layer "B.SilkS")
		)
		(fp_line
			(start -0.7874 0.4064)
			(end 0.7874 0.4064)
			(stroke
				(width 0.1524)
				(type default)
			)
			(layer "B.SilkS")
		)
		(fp_line
			(start 0.67945 -0.305054)
			(end 0.12065 -0.305054)
			(stroke
				(width 0.1)
				(type default)
			)
			(layer "B.Fab")
		)
		(fp_line
			(start 0.12065 -0.305054)
			(end 0.12065 -0.2794)
			(stroke
				(width 0.1)
				(type default)
			)
			(layer "B.Fab")
		)
		(fp_line
			(start -0.12065 -0.3048)
			(end -0.67945 -0.3048)
			(stroke
				(width 0.1)
				(type default)
			)
			(layer "B.Fab")
		)
		(fp_line
			(start -0.67945 -0.3048)
			(end -0.67945 0.3048)
			(stroke
				(width 0.1)
				(type default)
			)
			(layer "B.Fab")
		)
		(fp_line
			(start 0.12065 -0.2794)
			(end -0.12065 -0.2794)
			(stroke
				(width 0.1)
				(type default)
			)
			(layer "B.Fab")
		)
		(fp_line
			(start -0.12065 -0.2794)
			(end -0.12065 -0.3048)
			(stroke
				(width 0.1)
				(type default)
			)
			(layer "B.Fab")
		)
		(fp_line
			(start 0.12065 0.2794)
			(end 0.12065 0.3048)
			(stroke
				(width 0.1)
				(type default)
			)
			(layer "B.Fab")
		)
		(fp_line
			(start -0.120396 0.2794)
			(end 0.12065 0.2794)
			(stroke
				(width 0.1)
				(type default)
			)
			(layer "B.Fab")
		)
		(fp_line
			(start 0.67945 0.3048)
			(end 0.67945 -0.305054)
			(stroke
				(width 0.1)
				(type default)
			)
			(layer "B.Fab")
		)
		(fp_line
			(start 0.12065 0.3048)
			(end 0.67945 0.3048)
			(stroke
				(width 0.1)
				(type default)
			)
			(layer "B.Fab")
		)
		(fp_line
			(start -0.120396 0.3048)
			(end -0.120396 0.2794)
			(stroke
				(width 0.1)
				(type default)
			)
			(layer "B.Fab")
		)
		(fp_line
			(start -0.67945 0.3048)
			(end -0.120396 0.3048)
			(stroke
				(width 0.1)
				(type default)
			)
			(layer "B.Fab")
		)
		(pad "1" smd circle
			(at 0.40005 0 270)
			(size 0 0)
			(layers "B.Cu" "B.Mask" "B.Paste")
			(net "P0V8_PEX0_PVCC")
		)
		(pad "2" smd circle
			(at -0.40005 0 270)
			(size 0 0)
			(layers "B.Cu" "B.Mask" "B.Paste")
			(net "P0V8_PEX0_VCC1")
		)
	)
	(footprint ""
		(layer "B.Cu")
		(at 409.374848 -293.99992 90)
		(property "Reference" "C1921"
			(at 0 0 90)
			(layer "B.SilkS")
			(hide yes)
			(effects
				(font
					(size 1.27 1.27)
				)
				(justify mirror)
			)
		)
		(property "Value" ""
			(at 0 0 90)
			(layer "B.Fab")
			(effects
				(font
					(size 1.27 1.27)
				)
				(justify mirror)
			)
		)
		(duplicate_pad_numbers_are_jumpers no)
		(fp_line
			(start 0.299974 -0.150114)
			(end -0.299974 -0.150114)
			(stroke
				(width 0.1)
				(type default)
			)
			(layer "B.Fab")
		)
		(fp_line
			(start -0.299974 -0.150114)
			(end -0.299974 0.150114)
			(stroke
				(width 0.1)
				(type default)
			)
			(layer "B.Fab")
		)
		(fp_line
			(start 0.299974 0.150114)
			(end 0.299974 -0.150114)
			(stroke
				(width 0.1)
				(type default)
			)
			(layer "B.Fab")
		)
		(fp_line
			(start -0.299974 0.150114)
			(end 0.299974 0.150114)
			(stroke
				(width 0.1)
				(type default)
			)
			(layer "B.Fab")
		)
		(pad "1" smd rect
			(at 0.2667 0 270)
			(size 0.3048 0.381)
			(layers "B.Cu" "B.Mask" "B.Paste")
			(net "P0V8_PEX3")
		)
		(pad "2" smd rect
			(at -0.2667 0 270)
			(size 0.3048 0.381)
			(layers "B.Cu" "B.Mask" "B.Paste")
			(net "GND")
		)
	)
	(footprint ""
		(layer "B.Cu")
		(at 72.208136 -300.174914 180)
		(property "Reference" "C3012"
			(at 0 0 0)
			(layer "B.SilkS")
			(hide yes)
			(effects
				(font
					(size 1.27 1.27)
				)
				(justify mirror)
			)
		)
		(property "Value" ""
			(at 0 0 0)
			(layer "B.Fab")
			(effects
				(font
					(size 1.27 1.27)
				)
				(justify mirror)
			)
		)
		(duplicate_pad_numbers_are_jumpers no)
		(fp_line
			(start 0.299974 0.150114)
			(end 0.299974 -0.150114)
			(stroke
				(width 0.1)
				(type default)
			)
			(layer "B.Fab")
		)
		(fp_line
			(start 0.299974 -0.150114)
			(end -0.299974 -0.150114)
			(stroke
				(width 0.1)
				(type default)
			)
			(layer "B.Fab")
		)
		(fp_line
			(start -0.299974 0.150114)
			(end 0.299974 0.150114)
			(stroke
				(width 0.1)
				(type default)
			)
			(layer "B.Fab")
		)
		(fp_line
			(start -0.299974 -0.150114)
			(end -0.299974 0.150114)
			(stroke
				(width 0.1)
				(type default)
			)
			(layer "B.Fab")
		)
		(pad "1" smd rect
			(at 0.2667 0)
			(size 0.3048 0.381)
			(layers "B.Cu" "B.Mask" "B.Paste")
			(net "P1V8_VDDA_PEX0")
		)
		(pad "2" smd rect
			(at -0.2667 0)
			(size 0.3048 0.381)
			(layers "B.Cu" "B.Mask" "B.Paste")
			(net "GND")
		)
	)
	(footprint ""
		(layer "B.Cu")
		(at 305.149758 -294.94988 180)
		(property "Reference" "C3297"
			(at 0 0 0)
			(layer "B.SilkS")
			(hide yes)
			(effects
				(font
					(size 1.27 1.27)
				)
				(justify mirror)
			)
		)
		(property "Value" ""
			(at 0 0 0)
			(layer "B.Fab")
			(effects
				(font
					(size 1.27 1.27)
				)
				(justify mirror)
			)
		)
		(duplicate_pad_numbers_are_jumpers no)
		(fp_line
			(start 0.299974 0.150114)
			(end 0.299974 -0.150114)
			(stroke
				(width 0.1)
				(type default)
			)
			(layer "B.Fab")
		)
		(fp_line
			(start 0.299974 -0.150114)
			(end -0.299974 -0.150114)
			(stroke
				(width 0.1)
				(type default)
			)
			(layer "B.Fab")
		)
		(fp_line
			(start -0.299974 0.150114)
			(end 0.299974 0.150114)
			(stroke
				(width 0.1)
				(type default)
			)
			(layer "B.Fab")
		)
		(fp_line
			(start -0.299974 -0.150114)
			(end -0.299974 0.150114)
			(stroke
				(width 0.1)
				(type default)
			)
			(layer "B.Fab")
		)
		(pad "1" smd rect
			(at 0.2667 0)
			(size 0.3048 0.381)
			(layers "B.Cu" "B.Mask" "B.Paste")
			(net "P1V25_SERDES_VDDPLL_PEX2")
		)
		(pad "2" smd rect
			(at -0.2667 0)
			(size 0.3048 0.381)
			(layers "B.Cu" "B.Mask" "B.Paste")
			(net "GND")
		)
	)
	(footprint ""
		(layer "B.Cu")
		(at 291.84981 -288.299906 90)
		(property "Reference" "C3289"
			(at 0 0 90)
			(layer "B.SilkS")
			(hide yes)
			(effects
				(font
					(size 1.27 1.27)
				)
				(justify mirror)
			)
		)
		(property "Value" ""
			(at 0 0 90)
			(layer "B.Fab")
			(effects
				(font
					(size 1.27 1.27)
				)
				(justify mirror)
			)
		)
		(duplicate_pad_numbers_are_jumpers no)
		(fp_line
			(start 0.299974 -0.150114)
			(end -0.299974 -0.150114)
			(stroke
				(width 0.1)
				(type default)
			)
			(layer "B.Fab")
		)
		(fp_line
			(start -0.299974 -0.150114)
			(end -0.299974 0.150114)
			(stroke
				(width 0.1)
				(type default)
			)
			(layer "B.Fab")
		)
		(fp_line
			(start 0.299974 0.150114)
			(end 0.299974 -0.150114)
			(stroke
				(width 0.1)
				(type default)
			)
			(layer "B.Fab")
		)
		(fp_line
			(start -0.299974 0.150114)
			(end 0.299974 0.150114)
			(stroke
				(width 0.1)
				(type default)
			)
			(layer "B.Fab")
		)
		(pad "1" smd rect
			(at 0.2667 0 270)
			(size 0.3048 0.381)
			(layers "B.Cu" "B.Mask" "B.Paste")
			(net "P1V25_PEX2")
		)
		(pad "2" smd rect
			(at -0.2667 0 270)
			(size 0.3048 0.381)
			(layers "B.Cu" "B.Mask" "B.Paste")
			(net "GND")
		)
	)
	(footprint ""
		(layer "B.Cu")
		(at 174.325026 -297.79976 -90)
		(property "Reference" "C1383"
			(at 0 0 90)
			(layer "B.SilkS")
			(hide yes)
			(effects
				(font
					(size 1.27 1.27)
				)
				(justify mirror)
			)
		)
		(property "Value" ""
			(at 0 0 90)
			(layer "B.Fab")
			(effects
				(font
					(size 1.27 1.27)
				)
				(justify mirror)
			)
		)
		(duplicate_pad_numbers_are_jumpers no)
		(fp_line
			(start -0.299974 0.150114)
			(end 0.299974 0.150114)
			(stroke
				(width 0.1)
				(type default)
			)
			(layer "B.Fab")
		)
		(fp_line
			(start 0.299974 0.150114)
			(end 0.299974 -0.150114)
			(stroke
				(width 0.1)
				(type default)
			)
			(layer "B.Fab")
		)
		(fp_line
			(start -0.299974 -0.150114)
			(end -0.299974 0.150114)
			(stroke
				(width 0.1)
				(type default)
			)
			(layer "B.Fab")
		)
		(fp_line
			(start 0.299974 -0.150114)
			(end -0.299974 -0.150114)
			(stroke
				(width 0.1)
				(type default)
			)
			(layer "B.Fab")
		)
		(pad "1" smd rect
			(at 0.2667 0 90)
			(size 0.3048 0.381)
			(layers "B.Cu" "B.Mask" "B.Paste")
			(net "P0V8_PEX1")
		)
		(pad "2" smd rect
			(at -0.2667 0 90)
			(size 0.3048 0.381)
			(layers "B.Cu" "B.Mask" "B.Paste")
			(net "GND")
		)
	)
	(footprint ""
		(layer "B.Cu")
		(at 340.671404 -323.15531 -90)
		(property "Reference" "R6516"
			(at 0 0 90)
			(layer "B.SilkS")
			(hide yes)
			(effects
				(font
					(size 1.27 1.27)
				)
				(justify mirror)
			)
		)
		(property "Value" ""
			(at 0 0 90)
			(layer "B.Fab")
			(effects
				(font
					(size 1.27 1.27)
				)
				(justify mirror)
			)
		)
		(duplicate_pad_numbers_are_jumpers no)
		(fp_line
			(start -0.7874 0.4064)
			(end 0.7874 0.4064)
			(stroke
				(width 0.1524)
				(type default)
			)
			(layer "B.SilkS")
		)
		(fp_line
			(start 0.7874 0.4064)
			(end 0.7874 -0.4064)
			(stroke
				(width 0.1524)
				(type default)
			)
			(layer "B.SilkS")
		)
		(fp_line
			(start -0.7874 -0.4064)
			(end -0.7874 0.4064)
			(stroke
				(width 0.1524)
				(type default)
			)
			(layer "B.SilkS")
		)
		(fp_line
			(start 0.7874 -0.4064)
			(end -0.7874 -0.4064)
			(stroke
				(width 0.1524)
				(type default)
			)
			(layer "B.SilkS")
		)
		(fp_line
			(start -0.67945 0.3048)
			(end -0.120396 0.3048)
			(stroke
				(width 0.1)
				(type default)
			)
			(layer "B.Fab")
		)
		(fp_line
			(start -0.120396 0.3048)
			(end -0.120396 0.2794)
			(stroke
				(width 0.1)
				(type default)
			)
			(layer "B.Fab")
		)
		(fp_line
			(start 0.12065 0.3048)
			(end 0.67945 0.3048)
			(stroke
				(width 0.1)
				(type default)
			)
			(layer "B.Fab")
		)
		(fp_line
			(start 0.67945 0.3048)
			(end 0.67945 -0.305054)
			(stroke
				(width 0.1)
				(type default)
			)
			(layer "B.Fab")
		)
		(fp_line
			(start -0.120396 0.2794)
			(end 0.12065 0.2794)
			(stroke
				(width 0.1)
				(type default)
			)
			(layer "B.Fab")
		)
		(fp_line
			(start 0.12065 0.2794)
			(end 0.12065 0.3048)
			(stroke
				(width 0.1)
				(type default)
			)
			(layer "B.Fab")
		)
		(fp_line
			(start -0.12065 -0.2794)
			(end -0.12065 -0.3048)
			(stroke
				(width 0.1)
				(type default)
			)
			(layer "B.Fab")
		)
		(fp_line
			(start 0.12065 -0.2794)
			(end -0.12065 -0.2794)
			(stroke
				(width 0.1)
				(type default)
			)
			(layer "B.Fab")
		)
		(fp_line
			(start -0.67945 -0.3048)
			(end -0.67945 0.3048)
			(stroke
				(width 0.1)
				(type default)
			)
			(layer "B.Fab")
		)
		(fp_line
			(start -0.12065 -0.3048)
			(end -0.67945 -0.3048)
			(stroke
				(width 0.1)
				(type default)
			)
			(layer "B.Fab")
		)
		(fp_line
			(start 0.12065 -0.305054)
			(end 0.12065 -0.2794)
			(stroke
				(width 0.1)
				(type default)
			)
			(layer "B.Fab")
		)
		(fp_line
			(start 0.67945 -0.305054)
			(end 0.12065 -0.305054)
			(stroke
				(width 0.1)
				(type default)
			)
			(layer "B.Fab")
		)
		(pad "1" smd circle
			(at 0.40005 0 90)
			(size 0 0)
			(layers "B.Cu" "B.Mask" "B.Paste")
			(net "P0V8_SERDES_VDDA_PEX2")
		)
		(pad "2" smd circle
			(at -0.40005 0 90)
			(size 0 0)
			(layers "B.Cu" "B.Mask" "B.Paste")
			(net "P0V8_SERDES_VDDA_PEX2_C9")
		)
	)
	(footprint ""
		(layer "B.Cu")
		(at 107.839002 -308.580028 90)
		(property "Reference" "C4192"
			(at 0 0 90)
			(layer "B.SilkS")
			(hide yes)
			(effects
				(font
					(size 1.27 1.27)
				)
				(justify mirror)
			)
		)
		(property "Value" ""
			(at 0 0 90)
			(layer "B.Fab")
			(effects
				(font
					(size 1.27 1.27)
				)
				(justify mirror)
			)
		)
		(duplicate_pad_numbers_are_jumpers no)
		(fp_line
			(start 1.2954 -0.5842)
			(end -1.2954 -0.5842)
			(stroke
				(width 0.1524)
				(type default)
			)
			(layer "B.SilkS")
		)
		(fp_line
			(start -1.2954 -0.5842)
			(end -1.2954 0.5842)
			(stroke
				(width 0.1524)
				(type default)
			)
			(layer "B.SilkS")
		)
		(fp_line
			(start 1.2954 0.5842)
			(end 1.2954 -0.5842)
			(stroke
				(width 0.1524)
				(type default)
			)
			(layer "B.SilkS")
		)
		(fp_line
			(start -1.2954 0.5842)
			(end 1.2954 0.5842)
			(stroke
				(width 0.1524)
				(type default)
			)
			(layer "B.SilkS")
		)
		(fp_line
			(start 0.8636 -0.4572)
			(end -0.8636 -0.4572)
			(stroke
				(width 0.1)
				(type default)
			)
			(layer "B.Fab")
		)
		(fp_line
			(start -0.8636 -0.4572)
			(end -0.8636 -0.4064)
			(stroke
				(width 0.1)
				(type default)
			)
			(layer "B.Fab")
		)
		(fp_line
			(start 1.1938 -0.4064)
			(end 0.8636 -0.4064)
			(stroke
				(width 0.1)
				(type default)
			)
			(layer "B.Fab")
		)
		(fp_line
			(start 0.8636 -0.4064)
			(end 0.8636 -0.4572)
			(stroke
				(width 0.1)
				(type default)
			)
			(layer "B.Fab")
		)
		(fp_line
			(start -0.8636 -0.4064)
			(end -1.1938 -0.4064)
			(stroke
				(width 0.1)
				(type default)
			)
			(layer "B.Fab")
		)
		(fp_line
			(start -1.1938 -0.4064)
			(end -1.1938 0.4064)
			(stroke
				(width 0.1)
				(type default)
			)
			(layer "B.Fab")
		)
		(fp_line
			(start 1.1938 0.4064)
			(end 1.1938 -0.4064)
			(stroke
				(width 0.1)
				(type default)
			)
			(layer "B.Fab")
		)
		(fp_line
			(start 0.8636 0.4064)
			(end 1.1938 0.4064)
			(stroke
				(width 0.1)
				(type default)
			)
			(layer "B.Fab")
		)
		(fp_line
			(start -0.8636 0.4064)
			(end -0.8636 0.4572)
			(stroke
				(width 0.1)
				(type default)
			)
			(layer "B.Fab")
		)
		(fp_line
			(start -1.1938 0.4064)
			(end -0.8636 0.4064)
			(stroke
				(width 0.1)
				(type default)
			)
			(layer "B.Fab")
		)
		(fp_line
			(start 0.8636 0.4572)
			(end 0.8636 0.4064)
			(stroke
				(width 0.1)
				(type default)
			)
			(layer "B.Fab")
		)
		(fp_line
			(start -0.8636 0.4572)
			(end 0.8636 0.4572)
			(stroke
				(width 0.1)
				(type default)
			)
			(layer "B.Fab")
		)
		(pad "1" smd rect
			(at 0.7366 0)
			(size 0.7112 0.8128)
			(layers "B.Cu" "B.Mask" "B.Paste")
			(net "P0V8_PEX0")
		)
		(pad "2" smd rect
			(at -0.7366 0)
			(size 0.7112 0.8128)
			(layers "B.Cu" "B.Mask" "B.Paste")
			(net "GND")
		)
	)
	(footprint ""
		(layer "B.Cu")
		(at 248.421144 18.028412)
		(property "Reference" "DE02F_2"
			(at 2.784856 3.207258 0)
			(unlocked yes)
			(layer "B.SilkS")
			(effects
				(font
					(size 0.7874 0.5842)
					(thickness 0.1524)
				)
				(justify left mirror)
			)
		)
		(property "Value" ""
			(at 0 0 0)
			(layer "B.Fab")
			(effects
				(font
					(size 1.27 1.27)
				)
				(justify mirror)
			)
		)
		(duplicate_pad_numbers_are_jumpers no)
		(fp_line
			(start -1.2192 -2.1082)
			(end -1.2192 2.1082)
			(stroke
				(width 0.1524)
				(type default)
			)
			(layer "B.SilkS")
		)
		(fp_line
			(start -1.2192 2.1082)
			(end 1.2192 2.1082)
			(stroke
				(width 0.1524)
				(type default)
			)
			(layer "B.SilkS")
		)
		(fp_line
			(start 1.2192 -2.1082)
			(end -1.2192 -2.1082)
			(stroke
				(width 0.1524)
				(type default)
			)
			(layer "B.SilkS")
		)
		(fp_line
			(start 1.2192 2.1082)
			(end 1.2192 -2.1082)
			(stroke
				(width 0.1524)
				(type default)
			)
			(layer "B.SilkS")
		)
		(pad "" np_thru_hole circle
			(at -3.4671 -1.27 270)
			(size 1.0414 1.0414)
			(drill 1.0414)
			(layers "*.Cu" "*.Mask")
			(clearance 0.381)
			(thermal_gap 0.381)
		)
		(pad "" np_thru_hole circle
			(at -3.4671 1.27 270)
			(size 1.0414 1.0414)
			(drill 1.0414)
			(layers "*.Cu" "*.Mask")
			(clearance 0.381)
			(thermal_gap 0.381)
		)
		(pad "" np_thru_hole circle
			(at 2.8829 -1.27 270)
			(size 1.0414 1.0414)
			(drill 1.0414)
			(layers "*.Cu" "*.Mask")
			(clearance 0.381)
			(thermal_gap 0.381)
		)
		(pad "" np_thru_hole circle
			(at 2.8829 1.27 270)
			(size 1.0414 1.0414)
			(drill 1.0414)
			(layers "*.Cu" "*.Mask")
			(clearance 0.381)
			(thermal_gap 0.381)
		)
		(pad "1" smd rect
			(at -0.8255 -0.249936 270)
			(size 0.3048 0.508)
			(layers "B.Cu" "B.Mask" "B.Paste")
			(net "85_5INCH_BOTTOM_DP")
		)
		(pad "2" smd rect
			(at -0.8255 0.249936 270)
			(size 0.3048 0.508)
			(layers "B.Cu" "B.Mask" "B.Paste")
			(net "85_5INCH_BOTTOM_DN")
		)
		(pad "3" smd circle
			(at 0 0 180)
			(size 0 0)
			(layers "B.Cu" "B.Mask" "B.Paste")
			(net "COUPON_GND2")
		)
		(zone
			(layers "F.Cu" "B.Cu" "In1.Cu" "In2.Cu" "In3.Cu" "In4.Cu" "In5.Cu" "In6.Cu"
				"In7.Cu" "In8.Cu" "In9.Cu" "In10.Cu" "In11.Cu" "In12.Cu" "In13.Cu" "In14.Cu"
				"In15.Cu" "In16.Cu"
			)
			(hatch none 0.5)
			(connect_pads
				(clearance 0)
			)
			(min_thickness 0.25)
			(keepout
				(tracks not_allowed)
				(vias allowed)
				(pads allowed)
				(copperpour not_allowed)
				(footprints allowed)
			)
			(placement
				(enabled no)
				(sheetname "")
			)
			(fill
				(thermal_gap 0.5)
				(thermal_bridge_width 0.5)
				(island_removal_mode 0)
			)
			(polygon
				(pts
					(arc
						(start 245.881144 16.758412)
						(mid 244.026944 16.758412)
						(end 245.881144 16.758412)
					)
				)
			)
		)
		(zone
			(layers "F.Cu" "B.Cu" "In1.Cu" "In2.Cu" "In3.Cu" "In4.Cu" "In5.Cu" "In6.Cu"
				"In7.Cu" "In8.Cu" "In9.Cu" "In10.Cu" "In11.Cu" "In12.Cu" "In13.Cu" "In14.Cu"
				"In15.Cu" "In16.Cu"
			)
			(hatch none 0.5)
			(connect_pads
				(clearance 0)
			)
			(min_thickness 0.25)
			(keepout
				(tracks not_allowed)
				(vias allowed)
				(pads allowed)
				(copperpour not_allowed)
				(footprints allowed)
			)
			(placement
				(enabled no)
				(sheetname "")
			)
			(fill
				(thermal_gap 0.5)
				(thermal_bridge_width 0.5)
				(island_removal_mode 0)
			)
			(polygon
				(pts
					(arc
						(start 245.881144 19.298412)
						(mid 244.026944 19.298412)
						(end 245.881144 19.298412)
					)
				)
			)
		)
		(zone
			(layers "F.Cu" "B.Cu" "In1.Cu" "In2.Cu" "In3.Cu" "In4.Cu" "In5.Cu" "In6.Cu"
				"In7.Cu" "In8.Cu" "In9.Cu" "In10.Cu" "In11.Cu" "In12.Cu" "In13.Cu" "In14.Cu"
				"In15.Cu" "In16.Cu"
			)
			(hatch none 0.5)
			(connect_pads
				(clearance 0)
			)
			(min_thickness 0.25)
			(keepout
				(tracks not_allowed)
				(vias allowed)
				(pads allowed)
				(copperpour not_allowed)
				(footprints allowed)
			)
			(placement
				(enabled no)
				(sheetname "")
			)
			(fill
				(thermal_gap 0.5)
				(thermal_bridge_width 0.5)
				(island_removal_mode 0)
			)
			(polygon
				(pts
					(arc
						(start 252.231144 16.758412)
						(mid 250.376944 16.758412)
						(end 252.231144 16.758412)
					)
				)
			)
		)
		(zone
			(layers "F.Cu" "B.Cu" "In1.Cu" "In2.Cu" "In3.Cu" "In4.Cu" "In5.Cu" "In6.Cu"
				"In7.Cu" "In8.Cu" "In9.Cu" "In10.Cu" "In11.Cu" "In12.Cu" "In13.Cu" "In14.Cu"
				"In15.Cu" "In16.Cu"
			)
			(hatch none 0.5)
			(connect_pads
				(clearance 0)
			)
			(min_thickness 0.25)
			(keepout
				(tracks not_allowed)
				(vias allowed)
				(pads allowed)
				(copperpour not_allowed)
				(footprints allowed)
			)
			(placement
				(enabled no)
				(sheetname "")
			)
			(fill
				(thermal_gap 0.5)
				(thermal_bridge_width 0.5)
				(island_removal_mode 0)
			)
			(polygon
				(pts
					(arc
						(start 252.231144 19.298412)
						(mid 250.376944 19.298412)
						(end 252.231144 19.298412)
					)
				)
			)
		)
		(zone
			(layer "B.Cu")
			(hatch none 0.5)
			(connect_pads
				(clearance 0)
			)
			(min_thickness 0.25)
			(keepout
				(tracks not_allowed)
				(vias allowed)
				(pads allowed)
				(copperpour not_allowed)
				(footprints allowed)
			)
			(placement
				(enabled no)
				(sheetname "")
			)
			(fill
				(thermal_gap 0.5)
				(thermal_bridge_width 0.5)
				(island_removal_mode 0)
			)
			(polygon
				(pts
					(xy 247.303544 17.479772) (xy 247.303544 17.575276) (xy 247.900444 17.575276) (xy 247.900444 17.981676)
					(xy 247.303544 17.981676) (xy 247.303544 18.075148) (xy 247.900444 18.075148) (xy 247.900444 18.481548)
					(xy 247.303544 18.481548) (xy 247.303544 18.577052) (xy 248.002044 18.577052) (xy 248.002044 17.479772)
				)
			)
		)
	)
	(footprint ""
		(layer "B.Cu")
		(at 66.299842 -288.299906 90)
		(property "Reference" "C2940"
			(at 0 0 90)
			(layer "B.SilkS")
			(hide yes)
			(effects
				(font
					(size 1.27 1.27)
				)
				(justify mirror)
			)
		)
		(property "Value" ""
			(at 0 0 90)
			(layer "B.Fab")
			(effects
				(font
					(size 1.27 1.27)
				)
				(justify mirror)
			)
		)
		(duplicate_pad_numbers_are_jumpers no)
		(fp_line
			(start 0.299974 -0.150114)
			(end -0.299974 -0.150114)
			(stroke
				(width 0.1)
				(type default)
			)
			(layer "B.Fab")
		)
		(fp_line
			(start -0.299974 -0.150114)
			(end -0.299974 0.150114)
			(stroke
				(width 0.1)
				(type default)
			)
			(layer "B.Fab")
		)
		(fp_line
			(start 0.299974 0.150114)
			(end 0.299974 -0.150114)
			(stroke
				(width 0.1)
				(type default)
			)
			(layer "B.Fab")
		)
		(fp_line
			(start -0.299974 0.150114)
			(end 0.299974 0.150114)
			(stroke
				(width 0.1)
				(type default)
			)
			(layer "B.Fab")
		)
		(pad "1" smd rect
			(at 0.2667 0 270)
			(size 0.3048 0.381)
			(layers "B.Cu" "B.Mask" "B.Paste")
			(net "P1V25_PEX0")
		)
		(pad "2" smd rect
			(at -0.2667 0 270)
			(size 0.3048 0.381)
			(layers "B.Cu" "B.Mask" "B.Paste")
			(net "GND")
		)
	)
	(footprint ""
		(layer "B.Cu")
		(at 65.349882 -301.599854 -90)
		(property "Reference" "C1193"
			(at 0 0 90)
			(layer "B.SilkS")
			(hide yes)
			(effects
				(font
					(size 1.27 1.27)
				)
				(justify mirror)
			)
		)
		(property "Value" ""
			(at 0 0 90)
			(layer "B.Fab")
			(effects
				(font
					(size 1.27 1.27)
				)
				(justify mirror)
			)
		)
		(duplicate_pad_numbers_are_jumpers no)
		(fp_line
			(start -0.299974 0.150114)
			(end 0.299974 0.150114)
			(stroke
				(width 0.1)
				(type default)
			)
			(layer "B.Fab")
		)
		(fp_line
			(start 0.299974 0.150114)
			(end 0.299974 -0.150114)
			(stroke
				(width 0.1)
				(type default)
			)
			(layer "B.Fab")
		)
		(fp_line
			(start -0.299974 -0.150114)
			(end -0.299974 0.150114)
			(stroke
				(width 0.1)
				(type default)
			)
			(layer "B.Fab")
		)
		(fp_line
			(start 0.299974 -0.150114)
			(end -0.299974 -0.150114)
			(stroke
				(width 0.1)
				(type default)
			)
			(layer "B.Fab")
		)
		(pad "1" smd rect
			(at 0.2667 0 90)
			(size 0.3048 0.381)
			(layers "B.Cu" "B.Mask" "B.Paste")
			(net "P0V8_SERDES_VDDA_PEX0")
		)
		(pad "2" smd rect
			(at -0.2667 0 90)
			(size 0.3048 0.381)
			(layers "B.Cu" "B.Mask" "B.Paste")
			(net "GND")
		)
	)
	(footprint ""
		(layer "B.Cu")
		(at 342.894158 -218.787218 -90)
		(property "Reference" "C2068"
			(at 0 0 90)
			(layer "B.SilkS")
			(hide yes)
			(effects
				(font
					(size 1.27 1.27)
				)
				(justify mirror)
			)
		)
		(property "Value" ""
			(at 0 0 90)
			(layer "B.Fab")
			(effects
				(font
					(size 1.27 1.27)
				)
				(justify mirror)
			)
		)
		(duplicate_pad_numbers_are_jumpers no)
		(fp_line
			(start -0.69215 0.2921)
			(end 0.69215 0.2921)
			(stroke
				(width 0.1524)
				(type default)
			)
			(layer "B.SilkS")
		)
		(fp_line
			(start 0.69215 0.2921)
			(end 0.69215 -0.2921)
			(stroke
				(width 0.1524)
				(type default)
			)
			(layer "B.SilkS")
		)
		(fp_line
			(start -0.69215 -0.2921)
			(end -0.69215 0.2921)
			(stroke
				(width 0.1524)
				(type default)
			)
			(layer "B.SilkS")
		)
		(fp_line
			(start 0.69215 -0.2921)
			(end -0.69215 -0.2921)
			(stroke
				(width 0.1524)
				(type default)
			)
			(layer "B.SilkS")
		)
		(fp_line
			(start -0.51435 0.2794)
			(end 0.51435 0.2794)
			(stroke
				(width 0.1)
				(type default)
			)
			(layer "B.Fab")
		)
		(fp_line
			(start 0.51435 0.2794)
			(end 0.51435 -0.2794)
			(stroke
				(width 0.1)
				(type default)
			)
			(layer "B.Fab")
		)
		(fp_line
			(start -0.51435 -0.2794)
			(end -0.51435 0.2794)
			(stroke
				(width 0.1)
				(type default)
			)
			(layer "B.Fab")
		)
		(fp_line
			(start 0.51435 -0.2794)
			(end -0.51435 -0.2794)
			(stroke
				(width 0.1)
				(type default)
			)
			(layer "B.Fab")
		)
		(pad "1" smd circle
			(at 0.40005 0 90)
			(size 0 0)
			(layers "B.Cu" "B.Mask" "B.Paste")
			(net "P3V3_VCC_FPGA_CORE")
		)
		(pad "2" smd circle
			(at -0.40005 0 90)
			(size 0 0)
			(layers "B.Cu" "B.Mask" "B.Paste")
			(net "GND")
		)
		(zone
			(layer "B.Cu")
			(hatch none 0.5)
			(connect_pads
				(clearance 0)
			)
			(min_thickness 0.25)
			(keepout
				(tracks not_allowed)
				(vias allowed)
				(pads allowed)
				(copperpour not_allowed)
				(footprints allowed)
			)
			(placement
				(enabled no)
				(sheetname "")
			)
			(fill
				(thermal_gap 0.5)
				(thermal_bridge_width 0.5)
				(island_removal_mode 0)
			)
			(polygon
				(pts
					(xy 342.806528 -218.596718) (xy 342.748362 -218.688158) (xy 342.748362 -218.887548) (xy 342.806528 -218.977718)
					(xy 342.981788 -218.977718) (xy 343.040208 -218.887548) (xy 343.040208 -218.688158) (xy 342.982042 -218.596718)
				)
			)
		)
	)
	(footprint ""
		(layer "B.Cu")
		(at 180.02504 -305.399948 -90)
		(property "Reference" "C3127"
			(at 0 0 90)
			(layer "B.SilkS")
			(hide yes)
			(effects
				(font
					(size 1.27 1.27)
				)
				(justify mirror)
			)
		)
		(property "Value" ""
			(at 0 0 90)
			(layer "B.Fab")
			(effects
				(font
					(size 1.27 1.27)
				)
				(justify mirror)
			)
		)
		(duplicate_pad_numbers_are_jumpers no)
		(fp_line
			(start -0.299974 0.150114)
			(end 0.299974 0.150114)
			(stroke
				(width 0.1)
				(type default)
			)
			(layer "B.Fab")
		)
		(fp_line
			(start 0.299974 0.150114)
			(end 0.299974 -0.150114)
			(stroke
				(width 0.1)
				(type default)
			)
			(layer "B.Fab")
		)
		(fp_line
			(start -0.299974 -0.150114)
			(end -0.299974 0.150114)
			(stroke
				(width 0.1)
				(type default)
			)
			(layer "B.Fab")
		)
		(fp_line
			(start 0.299974 -0.150114)
			(end -0.299974 -0.150114)
			(stroke
				(width 0.1)
				(type default)
			)
			(layer "B.Fab")
		)
		(pad "1" smd rect
			(at 0.2667 0 90)
			(size 0.3048 0.381)
			(layers "B.Cu" "B.Mask" "B.Paste")
			(net "P1V25_SERDES_VDDPLL_PEX1")
		)
		(pad "2" smd rect
			(at -0.2667 0 90)
			(size 0.3048 0.381)
			(layers "B.Cu" "B.Mask" "B.Paste")
			(net "GND")
		)
	)
	(footprint ""
		(layer "B.Cu")
		(at 293.74973 -303.499774 -90)
		(property "Reference" "C3256"
			(at 0 0 90)
			(layer "B.SilkS")
			(hide yes)
			(effects
				(font
					(size 1.27 1.27)
				)
				(justify mirror)
			)
		)
		(property "Value" ""
			(at 0 0 90)
			(layer "B.Fab")
			(effects
				(font
					(size 1.27 1.27)
				)
				(justify mirror)
			)
		)
		(duplicate_pad_numbers_are_jumpers no)
		(fp_line
			(start -0.299974 0.150114)
			(end 0.299974 0.150114)
			(stroke
				(width 0.1)
				(type default)
			)
			(layer "B.Fab")
		)
		(fp_line
			(start 0.299974 0.150114)
			(end 0.299974 -0.150114)
			(stroke
				(width 0.1)
				(type default)
			)
			(layer "B.Fab")
		)
		(fp_line
			(start -0.299974 -0.150114)
			(end -0.299974 0.150114)
			(stroke
				(width 0.1)
				(type default)
			)
			(layer "B.Fab")
		)
		(fp_line
			(start 0.299974 -0.150114)
			(end -0.299974 -0.150114)
			(stroke
				(width 0.1)
				(type default)
			)
			(layer "B.Fab")
		)
		(pad "1" smd rect
			(at 0.2667 0 90)
			(size 0.3048 0.381)
			(layers "B.Cu" "B.Mask" "B.Paste")
			(net "P1V25_PEX2")
		)
		(pad "2" smd rect
			(at -0.2667 0 90)
			(size 0.3048 0.381)
			(layers "B.Cu" "B.Mask" "B.Paste")
			(net "GND")
		)
	)
	(footprint ""
		(layer "B.Cu")
		(at 134.292594 -327.3552)
		(property "Reference" "PJ21"
			(at 0 0 0)
			(layer "B.SilkS")
			(hide yes)
			(effects
				(font
					(size 1.27 1.27)
				)
				(justify mirror)
			)
		)
		(property "Value" ""
			(at 0 0 0)
			(layer "B.Fab")
			(effects
				(font
					(size 1.27 1.27)
				)
				(justify mirror)
			)
		)
		(duplicate_pad_numbers_are_jumpers no)
		(pad "1" smd circle
			(at 0.40005 0 90)
			(size 0 0)
			(layers "B.Cu" "B.Mask" "B.Paste")
			(net "VSENSE_P0V8_PEX1_SKT_VRTN")
		)
		(pad "2" smd rect
			(at -0.40005 0)
			(size 0.4572 0.508)
			(layers "B.Cu" "B.Mask" "B.Paste")
			(net "SH_P0V8_PEX1_RGND1")
		)
		(zone
			(layer "B.Cu")
			(hatch none 0.5)
			(connect_pads
				(clearance 0)
			)
			(min_thickness 0.25)
			(keepout
				(tracks allowed)
				(vias not_allowed)
				(pads allowed)
				(copperpour not_allowed)
				(footprints allowed)
			)
			(placement
				(enabled no)
				(sheetname "")
			)
			(fill
				(thermal_gap 0.5)
				(thermal_bridge_width 0.5)
				(island_removal_mode 0)
			)
			(polygon
				(pts
					(xy 133.606794 -327.0504) (xy 133.606794 -327.66) (xy 134.978394 -327.66) (xy 134.978394 -327.0504)
				)
			)
		)
	)
	(footprint ""
		(layer "B.Cu")
		(at 414.124902 -293.99992 -90)
		(property "Reference" "C1900"
			(at 0 0 90)
			(layer "B.SilkS")
			(hide yes)
			(effects
				(font
					(size 1.27 1.27)
				)
				(justify mirror)
			)
		)
		(property "Value" ""
			(at 0 0 90)
			(layer "B.Fab")
			(effects
				(font
					(size 1.27 1.27)
				)
				(justify mirror)
			)
		)
		(duplicate_pad_numbers_are_jumpers no)
		(fp_line
			(start -0.299974 0.150114)
			(end 0.299974 0.150114)
			(stroke
				(width 0.1)
				(type default)
			)
			(layer "B.Fab")
		)
		(fp_line
			(start 0.299974 0.150114)
			(end 0.299974 -0.150114)
			(stroke
				(width 0.1)
				(type default)
			)
			(layer "B.Fab")
		)
		(fp_line
			(start -0.299974 -0.150114)
			(end -0.299974 0.150114)
			(stroke
				(width 0.1)
				(type default)
			)
			(layer "B.Fab")
		)
		(fp_line
			(start 0.299974 -0.150114)
			(end -0.299974 -0.150114)
			(stroke
				(width 0.1)
				(type default)
			)
			(layer "B.Fab")
		)
		(pad "1" smd rect
			(at 0.2667 0 90)
			(size 0.3048 0.381)
			(layers "B.Cu" "B.Mask" "B.Paste")
			(net "P0V8_PEX3")
		)
		(pad "2" smd rect
			(at -0.2667 0 90)
			(size 0.3048 0.381)
			(layers "B.Cu" "B.Mask" "B.Paste")
			(net "GND")
		)
	)
	(footprint ""
		(layer "B.Cu")
		(at 406.524968 -286.399732 90)
		(property "Reference" "C3473"
			(at 0 0 90)
			(layer "B.SilkS")
			(hide yes)
			(effects
				(font
					(size 1.27 1.27)
				)
				(justify mirror)
			)
		)
		(property "Value" ""
			(at 0 0 90)
			(layer "B.Fab")
			(effects
				(font
					(size 1.27 1.27)
				)
				(justify mirror)
			)
		)
		(duplicate_pad_numbers_are_jumpers no)
		(fp_line
			(start 0.299974 -0.150114)
			(end -0.299974 -0.150114)
			(stroke
				(width 0.1)
				(type default)
			)
			(layer "B.Fab")
		)
		(fp_line
			(start -0.299974 -0.150114)
			(end -0.299974 0.150114)
			(stroke
				(width 0.1)
				(type default)
			)
			(layer "B.Fab")
		)
		(fp_line
			(start 0.299974 0.150114)
			(end 0.299974 -0.150114)
			(stroke
				(width 0.1)
				(type default)
			)
			(layer "B.Fab")
		)
		(fp_line
			(start -0.299974 0.150114)
			(end 0.299974 0.150114)
			(stroke
				(width 0.1)
				(type default)
			)
			(layer "B.Fab")
		)
		(pad "1" smd rect
			(at 0.2667 0 270)
			(size 0.3048 0.381)
			(layers "B.Cu" "B.Mask" "B.Paste")
			(net "P1V25_SERDES_VDDPLL_PEX3")
		)
		(pad "2" smd rect
			(at -0.2667 0 270)
			(size 0.3048 0.381)
			(layers "B.Cu" "B.Mask" "B.Paste")
			(net "GND")
		)
	)
	(footprint ""
		(layer "B.Cu")
		(at 46.355 -293.52494)
		(property "Reference" "C3057"
			(at 0 0 0)
			(layer "B.SilkS")
			(hide yes)
			(effects
				(font
					(size 1.27 1.27)
				)
				(justify mirror)
			)
		)
		(property "Value" ""
			(at 0 0 0)
			(layer "B.Fab")
			(effects
				(font
					(size 1.27 1.27)
				)
				(justify mirror)
			)
		)
		(duplicate_pad_numbers_are_jumpers no)
		(fp_line
			(start -0.299974 -0.150114)
			(end -0.299974 0.150114)
			(stroke
				(width 0.1)
				(type default)
			)
			(layer "B.Fab")
		)
		(fp_line
			(start -0.299974 0.150114)
			(end 0.299974 0.150114)
			(stroke
				(width 0.1)
				(type default)
			)
			(layer "B.Fab")
		)
		(fp_line
			(start 0.299974 -0.150114)
			(end -0.299974 -0.150114)
			(stroke
				(width 0.1)
				(type default)
			)
			(layer "B.Fab")
		)
		(fp_line
			(start 0.299974 0.150114)
			(end 0.299974 -0.150114)
			(stroke
				(width 0.1)
				(type default)
			)
			(layer "B.Fab")
		)
		(pad "1" smd rect
			(at 0.2667 0 180)
			(size 0.3048 0.381)
			(layers "B.Cu" "B.Mask" "B.Paste")
			(net "PCEPLL6_VDDA18_PEX0")
		)
		(pad "2" smd rect
			(at -0.2667 0 180)
			(size 0.3048 0.381)
			(layers "B.Cu" "B.Mask" "B.Paste")
			(net "GND")
		)
	)
	(footprint ""
		(layer "B.Cu")
		(at 69.24929 -115.613434 -90)
		(property "Reference" "U13"
			(at -1.805686 4.416806 0)
			(unlocked yes)
			(layer "B.SilkS")
			(effects
				(font
					(size 0.7874 0.5842)
					(thickness 0.1524)
				)
				(justify mirror)
			)
		)
		(property "Value" ""
			(at 0 0 90)
			(layer "B.Fab")
			(effects
				(font
					(size 1.27 1.27)
				)
				(justify mirror)
			)
		)
		(duplicate_pad_numbers_are_jumpers no)
		(fp_line
			(start -1.3462 1.1938)
			(end -1.3462 -1.1938)
			(stroke
				(width 0.1524)
				(type default)
			)
			(layer "B.SilkS")
		)
		(fp_line
			(start 1.3462 1.1938)
			(end -1.3462 1.1938)
			(stroke
				(width 0.1524)
				(type default)
			)
			(layer "B.SilkS")
		)
		(fp_line
			(start -1.3462 -1.1938)
			(end 1.3462 -1.1938)
			(stroke
				(width 0.1524)
				(type default)
			)
			(layer "B.SilkS")
		)
		(fp_line
			(start 1.3462 -1.1938)
			(end 1.3462 1.1684)
			(stroke
				(width 0.1524)
				(type default)
			)
			(layer "B.SilkS")
		)
		(fp_poly
			(pts
				(xy 1.447038 -0.760476) (xy 2.052066 -0.457962) (xy 2.052066 -1.06299)
			)
			(stroke
				(width 0)
				(type default)
			)
			(fill yes)
			(layer "B.SilkS")
		)
		(fp_line
			(start -0.674878 1.124966)
			(end -0.674878 -1.124966)
			(stroke
				(width 0.1)
				(type default)
			)
			(layer "B.Fab")
		)
		(fp_line
			(start 0.674878 1.124966)
			(end -0.674878 1.124966)
			(stroke
				(width 0.1)
				(type default)
			)
			(layer "B.Fab")
		)
		(fp_line
			(start -0.674878 -1.124966)
			(end 0.674878 -1.124966)
			(stroke
				(width 0.1)
				(type default)
			)
			(layer "B.Fab")
		)
		(fp_line
			(start 0.674878 -1.124966)
			(end 0.674878 1.124966)
			(stroke
				(width 0.1)
				(type default)
			)
			(layer "B.Fab")
		)
		(fp_poly
			(pts
				(xy 1.447038 -0.760476) (xy 2.052066 -0.457962) (xy 2.052066 -1.06299)
			)
			(stroke
				(width 0)
				(type default)
			)
			(fill yes)
			(layer "B.Fab")
		)
		(pad "1" smd rect
			(at 0.899922 -0.750062 90)
			(size 0.6096 0.6096)
			(layers "B.Cu" "B.Mask" "B.Paste")
			(net "NIC1_AUX_PWR_EN_R")
		)
		(pad "2" smd rect
			(at 0.899922 0)
			(size 0.4064 0.6096)
			(layers "B.Cu" "B.Mask" "B.Paste")
			(net "RST_SMB_NIC1_MUX_N")
		)
		(pad "3" smd rect
			(at 0.899922 0.750062 90)
			(size 0.6096 0.6096)
			(layers "B.Cu" "B.Mask" "B.Paste")
			(net "GND")
		)
		(pad "4" smd rect
			(at -0.899922 0.750062 90)
			(size 0.6096 0.6096)
			(layers "B.Cu" "B.Mask" "B.Paste")
			(net "RST_SMB_NIC1_MUX_ISO_N")
		)
		(pad "5" smd rect
			(at -0.899922 -0.750062 90)
			(size 0.6096 0.6096)
			(layers "B.Cu" "B.Mask" "B.Paste")
			(net "P3V3_AUX")
		)
	)
	(footprint ""
		(layer "B.Cu")
		(at 134.146544 -325.30923 -90)
		(property "Reference" "C4258"
			(at 0 0 90)
			(layer "B.SilkS")
			(hide yes)
			(effects
				(font
					(size 1.27 1.27)
				)
				(justify mirror)
			)
		)
		(property "Value" ""
			(at 0 0 90)
			(layer "B.Fab")
			(effects
				(font
					(size 1.27 1.27)
				)
				(justify mirror)
			)
		)
		(duplicate_pad_numbers_are_jumpers no)
		(fp_line
			(start -1.2954 0.5842)
			(end 1.2954 0.5842)
			(stroke
				(width 0.1524)
				(type default)
			)
			(layer "B.SilkS")
		)
		(fp_line
			(start 1.2954 0.5842)
			(end 1.2954 -0.5842)
			(stroke
				(width 0.1524)
				(type default)
			)
			(layer "B.SilkS")
		)
		(fp_line
			(start -1.2954 -0.5842)
			(end -1.2954 0.5842)
			(stroke
				(width 0.1524)
				(type default)
			)
			(layer "B.SilkS")
		)
		(fp_line
			(start 1.2954 -0.5842)
			(end -1.2954 -0.5842)
			(stroke
				(width 0.1524)
				(type default)
			)
			(layer "B.SilkS")
		)
		(fp_line
			(start -0.8636 0.4572)
			(end 0.8636 0.4572)
			(stroke
				(width 0.1)
				(type default)
			)
			(layer "B.Fab")
		)
		(fp_line
			(start 0.8636 0.4572)
			(end 0.8636 0.4064)
			(stroke
				(width 0.1)
				(type default)
			)
			(layer "B.Fab")
		)
		(fp_line
			(start -1.1938 0.4064)
			(end -0.8636 0.4064)
			(stroke
				(width 0.1)
				(type default)
			)
			(layer "B.Fab")
		)
		(fp_line
			(start -0.8636 0.4064)
			(end -0.8636 0.4572)
			(stroke
				(width 0.1)
				(type default)
			)
			(layer "B.Fab")
		)
		(fp_line
			(start 0.8636 0.4064)
			(end 1.1938 0.4064)
			(stroke
				(width 0.1)
				(type default)
			)
			(layer "B.Fab")
		)
		(fp_line
			(start 1.1938 0.4064)
			(end 1.1938 -0.4064)
			(stroke
				(width 0.1)
				(type default)
			)
			(layer "B.Fab")
		)
		(fp_line
			(start -1.1938 -0.4064)
			(end -1.1938 0.4064)
			(stroke
				(width 0.1)
				(type default)
			)
			(layer "B.Fab")
		)
		(fp_line
			(start -0.8636 -0.4064)
			(end -1.1938 -0.4064)
			(stroke
				(width 0.1)
				(type default)
			)
			(layer "B.Fab")
		)
		(fp_line
			(start 0.8636 -0.4064)
			(end 0.8636 -0.4572)
			(stroke
				(width 0.1)
				(type default)
			)
			(layer "B.Fab")
		)
		(fp_line
			(start 1.1938 -0.4064)
			(end 0.8636 -0.4064)
			(stroke
				(width 0.1)
				(type default)
			)
			(layer "B.Fab")
		)
		(fp_line
			(start -0.8636 -0.4572)
			(end -0.8636 -0.4064)
			(stroke
				(width 0.1)
				(type default)
			)
			(layer "B.Fab")
		)
		(fp_line
			(start 0.8636 -0.4572)
			(end -0.8636 -0.4572)
			(stroke
				(width 0.1)
				(type default)
			)
			(layer "B.Fab")
		)
		(pad "1" smd rect
			(at 0.7366 0 180)
			(size 0.7112 0.8128)
			(layers "B.Cu" "B.Mask" "B.Paste")
			(net "P0V8_SERDES_VDDA_PEX1_C4")
		)
		(pad "2" smd rect
			(at -0.7366 0 180)
			(size 0.7112 0.8128)
			(layers "B.Cu" "B.Mask" "B.Paste")
			(net "GND")
		)
	)
	(footprint ""
		(layer "B.Cu")
		(at 113.561114 -258.004564 90)
		(property "Reference" "PR96"
			(at 0 0 90)
			(layer "B.SilkS")
			(hide yes)
			(effects
				(font
					(size 1.27 1.27)
				)
				(justify mirror)
			)
		)
		(property "Value" ""
			(at 0 0 90)
			(layer "B.Fab")
			(effects
				(font
					(size 1.27 1.27)
				)
				(justify mirror)
			)
		)
		(duplicate_pad_numbers_are_jumpers no)
		(fp_line
			(start 0.7874 -0.4064)
			(end -0.7874 -0.4064)
			(stroke
				(width 0.1524)
				(type default)
			)
			(layer "B.SilkS")
		)
		(fp_line
			(start -0.7874 -0.4064)
			(end -0.7874 0.4064)
			(stroke
				(width 0.1524)
				(type default)
			)
			(layer "B.SilkS")
		)
		(fp_line
			(start 0.7874 0.4064)
			(end 0.7874 -0.4064)
			(stroke
				(width 0.1524)
				(type default)
			)
			(layer "B.SilkS")
		)
		(fp_line
			(start -0.7874 0.4064)
			(end 0.7874 0.4064)
			(stroke
				(width 0.1524)
				(type default)
			)
			(layer "B.SilkS")
		)
		(fp_line
			(start 0.67945 -0.305054)
			(end 0.12065 -0.305054)
			(stroke
				(width 0.1)
				(type default)
			)
			(layer "B.Fab")
		)
		(fp_line
			(start 0.12065 -0.305054)
			(end 0.12065 -0.2794)
			(stroke
				(width 0.1)
				(type default)
			)
			(layer "B.Fab")
		)
		(fp_line
			(start -0.12065 -0.3048)
			(end -0.67945 -0.3048)
			(stroke
				(width 0.1)
				(type default)
			)
			(layer "B.Fab")
		)
		(fp_line
			(start -0.67945 -0.3048)
			(end -0.67945 0.3048)
			(stroke
				(width 0.1)
				(type default)
			)
			(layer "B.Fab")
		)
		(fp_line
			(start 0.12065 -0.2794)
			(end -0.12065 -0.2794)
			(stroke
				(width 0.1)
				(type default)
			)
			(layer "B.Fab")
		)
		(fp_line
			(start -0.12065 -0.2794)
			(end -0.12065 -0.3048)
			(stroke
				(width 0.1)
				(type default)
			)
			(layer "B.Fab")
		)
		(fp_line
			(start 0.12065 0.2794)
			(end 0.12065 0.3048)
			(stroke
				(width 0.1)
				(type default)
			)
			(layer "B.Fab")
		)
		(fp_line
			(start -0.120396 0.2794)
			(end 0.12065 0.2794)
			(stroke
				(width 0.1)
				(type default)
			)
			(layer "B.Fab")
		)
		(fp_line
			(start 0.67945 0.3048)
			(end 0.67945 -0.305054)
			(stroke
				(width 0.1)
				(type default)
			)
			(layer "B.Fab")
		)
		(fp_line
			(start 0.12065 0.3048)
			(end 0.67945 0.3048)
			(stroke
				(width 0.1)
				(type default)
			)
			(layer "B.Fab")
		)
		(fp_line
			(start -0.120396 0.3048)
			(end -0.120396 0.2794)
			(stroke
				(width 0.1)
				(type default)
			)
			(layer "B.Fab")
		)
		(fp_line
			(start -0.67945 0.3048)
			(end -0.120396 0.3048)
			(stroke
				(width 0.1)
				(type default)
			)
			(layer "B.Fab")
		)
		(pad "1" smd circle
			(at 0.40005 0 270)
			(size 0 0)
			(layers "B.Cu" "B.Mask" "B.Paste")
			(net "P5V_AUX")
		)
		(pad "2" smd circle
			(at -0.40005 0 270)
			(size 0 0)
			(layers "B.Cu" "B.Mask" "B.Paste")
			(net "P0V8_PEX0_IINSEN")
		)
	)
	(footprint ""
		(layer "B.Cu")
		(at 149.352254 -209.562192 -90)
		(property "Reference" "R971"
			(at 0 0 90)
			(layer "B.SilkS")
			(hide yes)
			(effects
				(font
					(size 1.27 1.27)
				)
				(justify mirror)
			)
		)
		(property "Value" ""
			(at 0 0 90)
			(layer "B.Fab")
			(effects
				(font
					(size 1.27 1.27)
				)
				(justify mirror)
			)
		)
		(duplicate_pad_numbers_are_jumpers no)
		(fp_line
			(start -0.7874 0.4064)
			(end 0.7874 0.4064)
			(stroke
				(width 0.1524)
				(type default)
			)
			(layer "B.SilkS")
		)
		(fp_line
			(start 0.7874 0.4064)
			(end 0.7874 -0.4064)
			(stroke
				(width 0.1524)
				(type default)
			)
			(layer "B.SilkS")
		)
		(fp_line
			(start -0.7874 -0.4064)
			(end -0.7874 0.4064)
			(stroke
				(width 0.1524)
				(type default)
			)
			(layer "B.SilkS")
		)
		(fp_line
			(start 0.7874 -0.4064)
			(end -0.7874 -0.4064)
			(stroke
				(width 0.1524)
				(type default)
			)
			(layer "B.SilkS")
		)
		(fp_line
			(start -0.67945 0.3048)
			(end -0.120396 0.3048)
			(stroke
				(width 0.1)
				(type default)
			)
			(layer "B.Fab")
		)
		(fp_line
			(start -0.120396 0.3048)
			(end -0.120396 0.2794)
			(stroke
				(width 0.1)
				(type default)
			)
			(layer "B.Fab")
		)
		(fp_line
			(start 0.12065 0.3048)
			(end 0.67945 0.3048)
			(stroke
				(width 0.1)
				(type default)
			)
			(layer "B.Fab")
		)
		(fp_line
			(start 0.67945 0.3048)
			(end 0.67945 -0.305054)
			(stroke
				(width 0.1)
				(type default)
			)
			(layer "B.Fab")
		)
		(fp_line
			(start -0.120396 0.2794)
			(end 0.12065 0.2794)
			(stroke
				(width 0.1)
				(type default)
			)
			(layer "B.Fab")
		)
		(fp_line
			(start 0.12065 0.2794)
			(end 0.12065 0.3048)
			(stroke
				(width 0.1)
				(type default)
			)
			(layer "B.Fab")
		)
		(fp_line
			(start -0.12065 -0.2794)
			(end -0.12065 -0.3048)
			(stroke
				(width 0.1)
				(type default)
			)
			(layer "B.Fab")
		)
		(fp_line
			(start 0.12065 -0.2794)
			(end -0.12065 -0.2794)
			(stroke
				(width 0.1)
				(type default)
			)
			(layer "B.Fab")
		)
		(fp_line
			(start -0.67945 -0.3048)
			(end -0.67945 0.3048)
			(stroke
				(width 0.1)
				(type default)
			)
			(layer "B.Fab")
		)
		(fp_line
			(start -0.12065 -0.3048)
			(end -0.67945 -0.3048)
			(stroke
				(width 0.1)
				(type default)
			)
			(layer "B.Fab")
		)
		(fp_line
			(start 0.12065 -0.305054)
			(end 0.12065 -0.2794)
			(stroke
				(width 0.1)
				(type default)
			)
			(layer "B.Fab")
		)
		(fp_line
			(start 0.67945 -0.305054)
			(end 0.12065 -0.305054)
			(stroke
				(width 0.1)
				(type default)
			)
			(layer "B.Fab")
		)
		(pad "1" smd circle
			(at 0.40005 0 90)
			(size 0 0)
			(layers "B.Cu" "B.Mask" "B.Paste")
			(net "UART_PEX0_CLI_BUF_RX")
		)
		(pad "2" smd circle
			(at -0.40005 0 90)
			(size 0 0)
			(layers "B.Cu" "B.Mask" "B.Paste")
			(net "P1V8_PEX")
		)
	)
	(footprint ""
		(layer "B.Cu")
		(at 191.920622 -114.35207 90)
		(property "Reference" "C900"
			(at 0 0 90)
			(layer "B.SilkS")
			(hide yes)
			(effects
				(font
					(size 1.27 1.27)
				)
				(justify mirror)
			)
		)
		(property "Value" ""
			(at 0 0 90)
			(layer "B.Fab")
			(effects
				(font
					(size 1.27 1.27)
				)
				(justify mirror)
			)
		)
		(duplicate_pad_numbers_are_jumpers no)
		(fp_line
			(start 0.7874 -0.4064)
			(end -0.7874 -0.4064)
			(stroke
				(width 0.1524)
				(type default)
			)
			(layer "B.SilkS")
		)
		(fp_line
			(start -0.7874 -0.4064)
			(end -0.7874 0.4064)
			(stroke
				(width 0.1524)
				(type default)
			)
			(layer "B.SilkS")
		)
		(fp_line
			(start 0.7874 0.4064)
			(end 0.7874 -0.4064)
			(stroke
				(width 0.1524)
				(type default)
			)
			(layer "B.SilkS")
		)
		(fp_line
			(start -0.7874 0.4064)
			(end 0.7874 0.4064)
			(stroke
				(width 0.1524)
				(type default)
			)
			(layer "B.SilkS")
		)
		(fp_line
			(start 0.67945 -0.305054)
			(end 0.12065 -0.305054)
			(stroke
				(width 0.1)
				(type default)
			)
			(layer "B.Fab")
		)
		(fp_line
			(start 0.12065 -0.305054)
			(end 0.12065 -0.2794)
			(stroke
				(width 0.1)
				(type default)
			)
			(layer "B.Fab")
		)
		(fp_line
			(start -0.12065 -0.3048)
			(end -0.67945 -0.3048)
			(stroke
				(width 0.1)
				(type default)
			)
			(layer "B.Fab")
		)
		(fp_line
			(start -0.67945 -0.3048)
			(end -0.67945 0.3048)
			(stroke
				(width 0.1)
				(type default)
			)
			(layer "B.Fab")
		)
		(fp_line
			(start 0.12065 -0.2794)
			(end -0.12065 -0.2794)
			(stroke
				(width 0.1)
				(type default)
			)
			(layer "B.Fab")
		)
		(fp_line
			(start -0.12065 -0.2794)
			(end -0.12065 -0.3048)
			(stroke
				(width 0.1)
				(type default)
			)
			(layer "B.Fab")
		)
		(fp_line
			(start 0.12065 0.2794)
			(end 0.12065 0.3048)
			(stroke
				(width 0.1)
				(type default)
			)
			(layer "B.Fab")
		)
		(fp_line
			(start -0.120396 0.2794)
			(end 0.12065 0.2794)
			(stroke
				(width 0.1)
				(type default)
			)
			(layer "B.Fab")
		)
		(fp_line
			(start 0.67945 0.3048)
			(end 0.67945 -0.305054)
			(stroke
				(width 0.1)
				(type default)
			)
			(layer "B.Fab")
		)
		(fp_line
			(start 0.12065 0.3048)
			(end 0.67945 0.3048)
			(stroke
				(width 0.1)
				(type default)
			)
			(layer "B.Fab")
		)
		(fp_line
			(start -0.120396 0.3048)
			(end -0.120396 0.2794)
			(stroke
				(width 0.1)
				(type default)
			)
			(layer "B.Fab")
		)
		(fp_line
			(start -0.67945 0.3048)
			(end -0.120396 0.3048)
			(stroke
				(width 0.1)
				(type default)
			)
			(layer "B.Fab")
		)
		(pad "1" smd circle
			(at 0.40005 0 270)
			(size 0 0)
			(layers "B.Cu" "B.Mask" "B.Paste")
			(net "P3V3_NIC3")
		)
		(pad "2" smd circle
			(at -0.40005 0 270)
			(size 0 0)
			(layers "B.Cu" "B.Mask" "B.Paste")
			(net "GND")
		)
	)
	(footprint ""
		(layer "B.Cu")
		(at 410.324808 -293.99992 -90)
		(property "Reference" "C1886"
			(at 0 0 90)
			(layer "B.SilkS")
			(hide yes)
			(effects
				(font
					(size 1.27 1.27)
				)
				(justify mirror)
			)
		)
		(property "Value" ""
			(at 0 0 90)
			(layer "B.Fab")
			(effects
				(font
					(size 1.27 1.27)
				)
				(justify mirror)
			)
		)
		(duplicate_pad_numbers_are_jumpers no)
		(fp_line
			(start -0.299974 0.150114)
			(end 0.299974 0.150114)
			(stroke
				(width 0.1)
				(type default)
			)
			(layer "B.Fab")
		)
		(fp_line
			(start 0.299974 0.150114)
			(end 0.299974 -0.150114)
			(stroke
				(width 0.1)
				(type default)
			)
			(layer "B.Fab")
		)
		(fp_line
			(start -0.299974 -0.150114)
			(end -0.299974 0.150114)
			(stroke
				(width 0.1)
				(type default)
			)
			(layer "B.Fab")
		)
		(fp_line
			(start 0.299974 -0.150114)
			(end -0.299974 -0.150114)
			(stroke
				(width 0.1)
				(type default)
			)
			(layer "B.Fab")
		)
		(pad "1" smd rect
			(at 0.2667 0 90)
			(size 0.3048 0.381)
			(layers "B.Cu" "B.Mask" "B.Paste")
			(net "P0V8_PEX3")
		)
		(pad "2" smd rect
			(at -0.2667 0 90)
			(size 0.3048 0.381)
			(layers "B.Cu" "B.Mask" "B.Paste")
			(net "GND")
		)
	)
	(footprint ""
		(layer "B.Cu")
		(at 205.148942 -259.311648 90)
		(property "Reference" "R6343"
			(at 0 0 90)
			(layer "B.SilkS")
			(hide yes)
			(effects
				(font
					(size 1.27 1.27)
				)
				(justify mirror)
			)
		)
		(property "Value" ""
			(at 0 0 90)
			(layer "B.Fab")
			(effects
				(font
					(size 1.27 1.27)
				)
				(justify mirror)
			)
		)
		(duplicate_pad_numbers_are_jumpers no)
		(fp_line
			(start 0.7874 -0.4064)
			(end -0.7874 -0.4064)
			(stroke
				(width 0.1524)
				(type default)
			)
			(layer "B.SilkS")
		)
		(fp_line
			(start -0.7874 -0.4064)
			(end -0.7874 0.4064)
			(stroke
				(width 0.1524)
				(type default)
			)
			(layer "B.SilkS")
		)
		(fp_line
			(start 0.7874 0.4064)
			(end 0.7874 -0.4064)
			(stroke
				(width 0.1524)
				(type default)
			)
			(layer "B.SilkS")
		)
		(fp_line
			(start -0.7874 0.4064)
			(end 0.7874 0.4064)
			(stroke
				(width 0.1524)
				(type default)
			)
			(layer "B.SilkS")
		)
		(fp_line
			(start 0.67945 -0.305054)
			(end 0.12065 -0.305054)
			(stroke
				(width 0.1)
				(type default)
			)
			(layer "B.Fab")
		)
		(fp_line
			(start 0.12065 -0.305054)
			(end 0.12065 -0.2794)
			(stroke
				(width 0.1)
				(type default)
			)
			(layer "B.Fab")
		)
		(fp_line
			(start -0.12065 -0.3048)
			(end -0.67945 -0.3048)
			(stroke
				(width 0.1)
				(type default)
			)
			(layer "B.Fab")
		)
		(fp_line
			(start -0.67945 -0.3048)
			(end -0.67945 0.3048)
			(stroke
				(width 0.1)
				(type default)
			)
			(layer "B.Fab")
		)
		(fp_line
			(start 0.12065 -0.2794)
			(end -0.12065 -0.2794)
			(stroke
				(width 0.1)
				(type default)
			)
			(layer "B.Fab")
		)
		(fp_line
			(start -0.12065 -0.2794)
			(end -0.12065 -0.3048)
			(stroke
				(width 0.1)
				(type default)
			)
			(layer "B.Fab")
		)
		(fp_line
			(start 0.12065 0.2794)
			(end 0.12065 0.3048)
			(stroke
				(width 0.1)
				(type default)
			)
			(layer "B.Fab")
		)
		(fp_line
			(start -0.120396 0.2794)
			(end 0.12065 0.2794)
			(stroke
				(width 0.1)
				(type default)
			)
			(layer "B.Fab")
		)
		(fp_line
			(start 0.67945 0.3048)
			(end 0.67945 -0.305054)
			(stroke
				(width 0.1)
				(type default)
			)
			(layer "B.Fab")
		)
		(fp_line
			(start 0.12065 0.3048)
			(end 0.67945 0.3048)
			(stroke
				(width 0.1)
				(type default)
			)
			(layer "B.Fab")
		)
		(fp_line
			(start -0.120396 0.3048)
			(end -0.120396 0.2794)
			(stroke
				(width 0.1)
				(type default)
			)
			(layer "B.Fab")
		)
		(fp_line
			(start -0.67945 0.3048)
			(end -0.120396 0.3048)
			(stroke
				(width 0.1)
				(type default)
			)
			(layer "B.Fab")
		)
		(pad "1" smd circle
			(at 0.40005 0 270)
			(size 0 0)
			(layers "B.Cu" "B.Mask" "B.Paste")
			(net "P1V8_PEX")
		)
		(pad "2" smd circle
			(at -0.40005 0 270)
			(size 0 0)
			(layers "B.Cu" "B.Mask" "B.Paste")
			(net "SMB_PEX0_MUX_SCL")
		)
	)
	(footprint ""
		(layer "B.Cu")
		(at 298.499784 -303.499774 -90)
		(property "Reference" "C3255"
			(at 0 0 90)
			(layer "B.SilkS")
			(hide yes)
			(effects
				(font
					(size 1.27 1.27)
				)
				(justify mirror)
			)
		)
		(property "Value" ""
			(at 0 0 90)
			(layer "B.Fab")
			(effects
				(font
					(size 1.27 1.27)
				)
				(justify mirror)
			)
		)
		(duplicate_pad_numbers_are_jumpers no)
		(fp_line
			(start -0.299974 0.150114)
			(end 0.299974 0.150114)
			(stroke
				(width 0.1)
				(type default)
			)
			(layer "B.Fab")
		)
		(fp_line
			(start 0.299974 0.150114)
			(end 0.299974 -0.150114)
			(stroke
				(width 0.1)
				(type default)
			)
			(layer "B.Fab")
		)
		(fp_line
			(start -0.299974 -0.150114)
			(end -0.299974 0.150114)
			(stroke
				(width 0.1)
				(type default)
			)
			(layer "B.Fab")
		)
		(fp_line
			(start 0.299974 -0.150114)
			(end -0.299974 -0.150114)
			(stroke
				(width 0.1)
				(type default)
			)
			(layer "B.Fab")
		)
		(pad "1" smd rect
			(at 0.2667 0 90)
			(size 0.3048 0.381)
			(layers "B.Cu" "B.Mask" "B.Paste")
			(net "P1V25_PEX2")
		)
		(pad "2" smd rect
			(at -0.2667 0 90)
			(size 0.3048 0.381)
			(layers "B.Cu" "B.Mask" "B.Paste")
			(net "GND")
		)
	)
	(footprint ""
		(layer "B.Cu")
		(at 357.887524 -261.179818)
		(property "Reference" "PR7143"
			(at 0 0 0)
			(layer "B.SilkS")
			(hide yes)
			(effects
				(font
					(size 1.27 1.27)
				)
				(justify mirror)
			)
		)
		(property "Value" ""
			(at 0 0 0)
			(layer "B.Fab")
			(effects
				(font
					(size 1.27 1.27)
				)
				(justify mirror)
			)
		)
		(duplicate_pad_numbers_are_jumpers no)
		(fp_line
			(start -0.7874 -0.4064)
			(end -0.7874 0.4064)
			(stroke
				(width 0.1524)
				(type default)
			)
			(layer "B.SilkS")
		)
		(fp_line
			(start -0.7874 0.4064)
			(end 0.7874 0.4064)
			(stroke
				(width 0.1524)
				(type default)
			)
			(layer "B.SilkS")
		)
		(fp_line
			(start 0.7874 -0.4064)
			(end -0.7874 -0.4064)
			(stroke
				(width 0.1524)
				(type default)
			)
			(layer "B.SilkS")
		)
		(fp_line
			(start 0.7874 0.4064)
			(end 0.7874 -0.4064)
			(stroke
				(width 0.1524)
				(type default)
			)
			(layer "B.SilkS")
		)
		(fp_line
			(start -0.67945 -0.3048)
			(end -0.67945 0.3048)
			(stroke
				(width 0.1)
				(type default)
			)
			(layer "B.Fab")
		)
		(fp_line
			(start -0.67945 0.3048)
			(end -0.120396 0.3048)
			(stroke
				(width 0.1)
				(type default)
			)
			(layer "B.Fab")
		)
		(fp_line
			(start -0.12065 -0.3048)
			(end -0.67945 -0.3048)
			(stroke
				(width 0.1)
				(type default)
			)
			(layer "B.Fab")
		)
		(fp_line
			(start -0.12065 -0.2794)
			(end -0.12065 -0.3048)
			(stroke
				(width 0.1)
				(type default)
			)
			(layer "B.Fab")
		)
		(fp_line
			(start -0.120396 0.2794)
			(end 0.12065 0.2794)
			(stroke
				(width 0.1)
				(type default)
			)
			(layer "B.Fab")
		)
		(fp_line
			(start -0.120396 0.3048)
			(end -0.120396 0.2794)
			(stroke
				(width 0.1)
				(type default)
			)
			(layer "B.Fab")
		)
		(fp_line
			(start 0.12065 -0.305054)
			(end 0.12065 -0.2794)
			(stroke
				(width 0.1)
				(type default)
			)
			(layer "B.Fab")
		)
		(fp_line
			(start 0.12065 -0.2794)
			(end -0.12065 -0.2794)
			(stroke
				(width 0.1)
				(type default)
			)
			(layer "B.Fab")
		)
		(fp_line
			(start 0.12065 0.2794)
			(end 0.12065 0.3048)
			(stroke
				(width 0.1)
				(type default)
			)
			(layer "B.Fab")
		)
		(fp_line
			(start 0.12065 0.3048)
			(end 0.67945 0.3048)
			(stroke
				(width 0.1)
				(type default)
			)
			(layer "B.Fab")
		)
		(fp_line
			(start 0.67945 -0.305054)
			(end 0.12065 -0.305054)
			(stroke
				(width 0.1)
				(type default)
			)
			(layer "B.Fab")
		)
		(fp_line
			(start 0.67945 0.3048)
			(end 0.67945 -0.305054)
			(stroke
				(width 0.1)
				(type default)
			)
			(layer "B.Fab")
		)
		(pad "1" smd circle
			(at 0.40005 0 180)
			(size 0 0)
			(layers "B.Cu" "B.Mask" "B.Paste")
			(net "GND")
		)
		(pad "2" smd circle
			(at -0.40005 0 180)
			(size 0 0)
			(layers "B.Cu" "B.Mask" "B.Paste")
			(net "P0V8_PEX2_SVID")
		)
	)
	(footprint ""
		(layer "B.Cu")
		(at 345.057476 -313.620404 180)
		(property "Reference" "L61"
			(at 0 0 0)
			(layer "B.SilkS")
			(hide yes)
			(effects
				(font
					(size 1.27 1.27)
				)
				(justify mirror)
			)
		)
		(property "Value" ""
			(at 0 0 0)
			(layer "B.Fab")
			(effects
				(font
					(size 1.27 1.27)
				)
				(justify mirror)
			)
		)
		(duplicate_pad_numbers_are_jumpers no)
		(fp_line
			(start 2.248154 4.9911)
			(end -2.248154 4.9911)
			(stroke
				(width 0.1524)
				(type default)
			)
			(layer "B.SilkS")
		)
		(fp_line
			(start 2.248154 1.658112)
			(end 2.248154 4.9911)
			(stroke
				(width 0.1524)
				(type default)
			)
			(layer "B.SilkS")
		)
		(fp_line
			(start 2.248154 -4.9911)
			(end 2.248154 -2.282952)
			(stroke
				(width 0.1524)
				(type default)
			)
			(layer "B.SilkS")
		)
		(fp_line
			(start -2.248154 4.9911)
			(end -2.248154 1.658112)
			(stroke
				(width 0.1524)
				(type default)
			)
			(layer "B.SilkS")
		)
		(fp_line
			(start -2.248154 -2.282952)
			(end -2.248154 -4.9911)
			(stroke
				(width 0.1524)
				(type default)
			)
			(layer "B.SilkS")
		)
		(fp_line
			(start -2.248154 -4.9911)
			(end 2.248154 -4.9911)
			(stroke
				(width 0.1524)
				(type default)
			)
			(layer "B.SilkS")
		)
		(fp_line
			(start 1.700022 0.899922)
			(end -1.700022 0.899922)
			(stroke
				(width 0.1)
				(type default)
			)
			(layer "B.Fab")
		)
		(fp_line
			(start 1.700022 -0.899922)
			(end 1.700022 0.899922)
			(stroke
				(width 0.1)
				(type default)
			)
			(layer "B.Fab")
		)
		(fp_line
			(start -1.700022 0.899922)
			(end -1.700022 -0.899922)
			(stroke
				(width 0.1)
				(type default)
			)
			(layer "B.Fab")
		)
		(fp_line
			(start -1.700022 -0.899922)
			(end 1.700022 -0.899922)
			(stroke
				(width 0.1)
				(type default)
			)
			(layer "B.Fab")
		)
		(pad "1" smd rect
			(at 1.575054 0)
			(size 1.1684 9.8044)
			(layers "B.Cu" "B.Mask" "B.Paste")
			(net "P0V8_PEX2")
		)
		(pad "2" smd rect
			(at -1.575054 0)
			(size 1.1684 9.8044)
			(layers "B.Cu" "B.Mask" "B.Paste")
			(net "P0V8_SERDES_VDDA_PEX2")
		)
	)
	(footprint ""
		(layer "B.Cu")
		(at 409.849828 -303.499774 -90)
		(property "Reference" "C3427"
			(at 0 0 90)
			(layer "B.SilkS")
			(hide yes)
			(effects
				(font
					(size 1.27 1.27)
				)
				(justify mirror)
			)
		)
		(property "Value" ""
			(at 0 0 90)
			(layer "B.Fab")
			(effects
				(font
					(size 1.27 1.27)
				)
				(justify mirror)
			)
		)
		(duplicate_pad_numbers_are_jumpers no)
		(fp_line
			(start -0.299974 0.150114)
			(end 0.299974 0.150114)
			(stroke
				(width 0.1)
				(type default)
			)
			(layer "B.Fab")
		)
		(fp_line
			(start 0.299974 0.150114)
			(end 0.299974 -0.150114)
			(stroke
				(width 0.1)
				(type default)
			)
			(layer "B.Fab")
		)
		(fp_line
			(start -0.299974 -0.150114)
			(end -0.299974 0.150114)
			(stroke
				(width 0.1)
				(type default)
			)
			(layer "B.Fab")
		)
		(fp_line
			(start 0.299974 -0.150114)
			(end -0.299974 -0.150114)
			(stroke
				(width 0.1)
				(type default)
			)
			(layer "B.Fab")
		)
		(pad "1" smd rect
			(at 0.2667 0 90)
			(size 0.3048 0.381)
			(layers "B.Cu" "B.Mask" "B.Paste")
			(net "P1V25_PEX3")
		)
		(pad "2" smd rect
			(at -0.2667 0 90)
			(size 0.3048 0.381)
			(layers "B.Cu" "B.Mask" "B.Paste")
			(net "GND")
		)
	)
	(footprint ""
		(layer "B.Cu")
		(at 410.799788 -299.699934 -90)
		(property "Reference" "C1992"
			(at 0 0 90)
			(layer "B.SilkS")
			(hide yes)
			(effects
				(font
					(size 1.27 1.27)
				)
				(justify mirror)
			)
		)
		(property "Value" ""
			(at 0 0 90)
			(layer "B.Fab")
			(effects
				(font
					(size 1.27 1.27)
				)
				(justify mirror)
			)
		)
		(duplicate_pad_numbers_are_jumpers no)
		(fp_line
			(start -0.299974 0.150114)
			(end 0.299974 0.150114)
			(stroke
				(width 0.1)
				(type default)
			)
			(layer "B.Fab")
		)
		(fp_line
			(start 0.299974 0.150114)
			(end 0.299974 -0.150114)
			(stroke
				(width 0.1)
				(type default)
			)
			(layer "B.Fab")
		)
		(fp_line
			(start -0.299974 -0.150114)
			(end -0.299974 0.150114)
			(stroke
				(width 0.1)
				(type default)
			)
			(layer "B.Fab")
		)
		(fp_line
			(start 0.299974 -0.150114)
			(end -0.299974 -0.150114)
			(stroke
				(width 0.1)
				(type default)
			)
			(layer "B.Fab")
		)
		(pad "1" smd rect
			(at 0.2667 0 90)
			(size 0.3048 0.381)
			(layers "B.Cu" "B.Mask" "B.Paste")
			(net "P0V8_SERDES_VDDA_PEX3")
		)
		(pad "2" smd rect
			(at -0.2667 0 90)
			(size 0.3048 0.381)
			(layers "B.Cu" "B.Mask" "B.Paste")
			(net "GND")
		)
	)
	(footprint ""
		(layer "B.Cu")
		(at 417.30422 -117.723666)
		(property "Reference" "C961"
			(at 0 0 0)
			(layer "B.SilkS")
			(hide yes)
			(effects
				(font
					(size 1.27 1.27)
				)
				(justify mirror)
			)
		)
		(property "Value" ""
			(at 0 0 0)
			(layer "B.Fab")
			(effects
				(font
					(size 1.27 1.27)
				)
				(justify mirror)
			)
		)
		(duplicate_pad_numbers_are_jumpers no)
		(fp_line
			(start -0.7874 -0.4064)
			(end -0.7874 0.4064)
			(stroke
				(width 0.1524)
				(type default)
			)
			(layer "B.SilkS")
		)
		(fp_line
			(start -0.7874 0.4064)
			(end 0.7874 0.4064)
			(stroke
				(width 0.1524)
				(type default)
			)
			(layer "B.SilkS")
		)
		(fp_line
			(start 0.7874 -0.4064)
			(end -0.7874 -0.4064)
			(stroke
				(width 0.1524)
				(type default)
			)
			(layer "B.SilkS")
		)
		(fp_line
			(start 0.7874 0.4064)
			(end 0.7874 -0.4064)
			(stroke
				(width 0.1524)
				(type default)
			)
			(layer "B.SilkS")
		)
		(fp_line
			(start -0.67945 -0.3048)
			(end -0.67945 0.3048)
			(stroke
				(width 0.1)
				(type default)
			)
			(layer "B.Fab")
		)
		(fp_line
			(start -0.67945 0.3048)
			(end -0.120396 0.3048)
			(stroke
				(width 0.1)
				(type default)
			)
			(layer "B.Fab")
		)
		(fp_line
			(start -0.12065 -0.3048)
			(end -0.67945 -0.3048)
			(stroke
				(width 0.1)
				(type default)
			)
			(layer "B.Fab")
		)
		(fp_line
			(start -0.12065 -0.2794)
			(end -0.12065 -0.3048)
			(stroke
				(width 0.1)
				(type default)
			)
			(layer "B.Fab")
		)
		(fp_line
			(start -0.120396 0.2794)
			(end 0.12065 0.2794)
			(stroke
				(width 0.1)
				(type default)
			)
			(layer "B.Fab")
		)
		(fp_line
			(start -0.120396 0.3048)
			(end -0.120396 0.2794)
			(stroke
				(width 0.1)
				(type default)
			)
			(layer "B.Fab")
		)
		(fp_line
			(start 0.12065 -0.305054)
			(end 0.12065 -0.2794)
			(stroke
				(width 0.1)
				(type default)
			)
			(layer "B.Fab")
		)
		(fp_line
			(start 0.12065 -0.2794)
			(end -0.12065 -0.2794)
			(stroke
				(width 0.1)
				(type default)
			)
			(layer "B.Fab")
		)
		(fp_line
			(start 0.12065 0.2794)
			(end 0.12065 0.3048)
			(stroke
				(width 0.1)
				(type default)
			)
			(layer "B.Fab")
		)
		(fp_line
			(start 0.12065 0.3048)
			(end 0.67945 0.3048)
			(stroke
				(width 0.1)
				(type default)
			)
			(layer "B.Fab")
		)
		(fp_line
			(start 0.67945 -0.305054)
			(end 0.12065 -0.305054)
			(stroke
				(width 0.1)
				(type default)
			)
			(layer "B.Fab")
		)
		(fp_line
			(start 0.67945 0.3048)
			(end 0.67945 -0.305054)
			(stroke
				(width 0.1)
				(type default)
			)
			(layer "B.Fab")
		)
		(pad "1" smd circle
			(at 0.40005 0 180)
			(size 0 0)
			(layers "B.Cu" "B.Mask" "B.Paste")
			(net "P3V3_AUX")
		)
		(pad "2" smd circle
			(at -0.40005 0 180)
			(size 0 0)
			(layers "B.Cu" "B.Mask" "B.Paste")
			(net "GND")
		)
	)
	(footprint ""
		(layer "B.Cu")
		(at 396.0749 -290.941506 90)
		(property "Reference" "C3582"
			(at 0 0 90)
			(layer "B.SilkS")
			(hide yes)
			(effects
				(font
					(size 1.27 1.27)
				)
				(justify mirror)
			)
		)
		(property "Value" ""
			(at 0 0 90)
			(layer "B.Fab")
			(effects
				(font
					(size 1.27 1.27)
				)
				(justify mirror)
			)
		)
		(duplicate_pad_numbers_are_jumpers no)
		(fp_line
			(start 0.299974 -0.150114)
			(end -0.299974 -0.150114)
			(stroke
				(width 0.1)
				(type default)
			)
			(layer "B.Fab")
		)
		(fp_line
			(start -0.299974 -0.150114)
			(end -0.299974 0.150114)
			(stroke
				(width 0.1)
				(type default)
			)
			(layer "B.Fab")
		)
		(fp_line
			(start 0.299974 0.150114)
			(end 0.299974 -0.150114)
			(stroke
				(width 0.1)
				(type default)
			)
			(layer "B.Fab")
		)
		(fp_line
			(start -0.299974 0.150114)
			(end 0.299974 0.150114)
			(stroke
				(width 0.1)
				(type default)
			)
			(layer "B.Fab")
		)
		(pad "1" smd rect
			(at 0.2667 0 270)
			(size 0.3048 0.381)
			(layers "B.Cu" "B.Mask" "B.Paste")
			(net "PCEPLL7_VDDA18_PEX3")
		)
		(pad "2" smd rect
			(at -0.2667 0 270)
			(size 0.3048 0.381)
			(layers "B.Cu" "B.Mask" "B.Paste")
			(net "GND")
		)
	)
	(footprint ""
		(layer "B.Cu")
		(at 44.449746 -293.99992)
		(property "Reference" "C2987"
			(at 0 0 0)
			(layer "B.SilkS")
			(hide yes)
			(effects
				(font
					(size 1.27 1.27)
				)
				(justify mirror)
			)
		)
		(property "Value" ""
			(at 0 0 0)
			(layer "B.Fab")
			(effects
				(font
					(size 1.27 1.27)
				)
				(justify mirror)
			)
		)
		(duplicate_pad_numbers_are_jumpers no)
		(fp_line
			(start -0.299974 -0.150114)
			(end -0.299974 0.150114)
			(stroke
				(width 0.1)
				(type default)
			)
			(layer "B.Fab")
		)
		(fp_line
			(start -0.299974 0.150114)
			(end 0.299974 0.150114)
			(stroke
				(width 0.1)
				(type default)
			)
			(layer "B.Fab")
		)
		(fp_line
			(start 0.299974 -0.150114)
			(end -0.299974 -0.150114)
			(stroke
				(width 0.1)
				(type default)
			)
			(layer "B.Fab")
		)
		(fp_line
			(start 0.299974 0.150114)
			(end 0.299974 -0.150114)
			(stroke
				(width 0.1)
				(type default)
			)
			(layer "B.Fab")
		)
		(pad "1" smd rect
			(at 0.2667 0 180)
			(size 0.3048 0.381)
			(layers "B.Cu" "B.Mask" "B.Paste")
			(net "P1V8_PEX")
		)
		(pad "2" smd rect
			(at -0.2667 0 180)
			(size 0.3048 0.381)
			(layers "B.Cu" "B.Mask" "B.Paste")
			(net "GND")
		)
	)
	(footprint ""
		(layer "B.Cu")
		(at 165.320218 -296.37482)
		(property "Reference" "C1391"
			(at 0 0 0)
			(layer "B.SilkS")
			(hide yes)
			(effects
				(font
					(size 1.27 1.27)
				)
				(justify mirror)
			)
		)
		(property "Value" ""
			(at 0 0 0)
			(layer "B.Fab")
			(effects
				(font
					(size 1.27 1.27)
				)
				(justify mirror)
			)
		)
		(duplicate_pad_numbers_are_jumpers no)
		(fp_line
			(start -0.299974 -0.150114)
			(end -0.299974 0.150114)
			(stroke
				(width 0.1)
				(type default)
			)
			(layer "B.Fab")
		)
		(fp_line
			(start -0.299974 0.150114)
			(end 0.299974 0.150114)
			(stroke
				(width 0.1)
				(type default)
			)
			(layer "B.Fab")
		)
		(fp_line
			(start 0.299974 -0.150114)
			(end -0.299974 -0.150114)
			(stroke
				(width 0.1)
				(type default)
			)
			(layer "B.Fab")
		)
		(fp_line
			(start 0.299974 0.150114)
			(end 0.299974 -0.150114)
			(stroke
				(width 0.1)
				(type default)
			)
			(layer "B.Fab")
		)
		(pad "1" smd rect
			(at 0.2667 0 180)
			(size 0.3048 0.381)
			(layers "B.Cu" "B.Mask" "B.Paste")
			(net "P0V8_PEX1")
		)
		(pad "2" smd rect
			(at -0.2667 0 180)
			(size 0.3048 0.381)
			(layers "B.Cu" "B.Mask" "B.Paste")
			(net "GND")
		)
	)
	(footprint ""
		(layer "B.Cu")
		(at 61.597286 -109.481366)
		(property "Reference" "R82"
			(at 0 0 0)
			(layer "B.SilkS")
			(hide yes)
			(effects
				(font
					(size 1.27 1.27)
				)
				(justify mirror)
			)
		)
		(property "Value" ""
			(at 0 0 0)
			(layer "B.Fab")
			(effects
				(font
					(size 1.27 1.27)
				)
				(justify mirror)
			)
		)
		(duplicate_pad_numbers_are_jumpers no)
		(fp_line
			(start -0.7874 -0.4064)
			(end -0.7874 0.4064)
			(stroke
				(width 0.1524)
				(type default)
			)
			(layer "B.SilkS")
		)
		(fp_line
			(start -0.7874 0.4064)
			(end 0.7874 0.4064)
			(stroke
				(width 0.1524)
				(type default)
			)
			(layer "B.SilkS")
		)
		(fp_line
			(start 0.7874 -0.4064)
			(end -0.7874 -0.4064)
			(stroke
				(width 0.1524)
				(type default)
			)
			(layer "B.SilkS")
		)
		(fp_line
			(start 0.7874 0.4064)
			(end 0.7874 -0.4064)
			(stroke
				(width 0.1524)
				(type default)
			)
			(layer "B.SilkS")
		)
		(fp_line
			(start -0.67945 -0.3048)
			(end -0.67945 0.3048)
			(stroke
				(width 0.1)
				(type default)
			)
			(layer "B.Fab")
		)
		(fp_line
			(start -0.67945 0.3048)
			(end -0.120396 0.3048)
			(stroke
				(width 0.1)
				(type default)
			)
			(layer "B.Fab")
		)
		(fp_line
			(start -0.12065 -0.3048)
			(end -0.67945 -0.3048)
			(stroke
				(width 0.1)
				(type default)
			)
			(layer "B.Fab")
		)
		(fp_line
			(start -0.12065 -0.2794)
			(end -0.12065 -0.3048)
			(stroke
				(width 0.1)
				(type default)
			)
			(layer "B.Fab")
		)
		(fp_line
			(start -0.120396 0.2794)
			(end 0.12065 0.2794)
			(stroke
				(width 0.1)
				(type default)
			)
			(layer "B.Fab")
		)
		(fp_line
			(start -0.120396 0.3048)
			(end -0.120396 0.2794)
			(stroke
				(width 0.1)
				(type default)
			)
			(layer "B.Fab")
		)
		(fp_line
			(start 0.12065 -0.305054)
			(end 0.12065 -0.2794)
			(stroke
				(width 0.1)
				(type default)
			)
			(layer "B.Fab")
		)
		(fp_line
			(start 0.12065 -0.2794)
			(end -0.12065 -0.2794)
			(stroke
				(width 0.1)
				(type default)
			)
			(layer "B.Fab")
		)
		(fp_line
			(start 0.12065 0.2794)
			(end 0.12065 0.3048)
			(stroke
				(width 0.1)
				(type default)
			)
			(layer "B.Fab")
		)
		(fp_line
			(start 0.12065 0.3048)
			(end 0.67945 0.3048)
			(stroke
				(width 0.1)
				(type default)
			)
			(layer "B.Fab")
		)
		(fp_line
			(start 0.67945 -0.305054)
			(end 0.12065 -0.305054)
			(stroke
				(width 0.1)
				(type default)
			)
			(layer "B.Fab")
		)
		(fp_line
			(start 0.67945 0.3048)
			(end 0.67945 -0.305054)
			(stroke
				(width 0.1)
				(type default)
			)
			(layer "B.Fab")
		)
		(pad "1" smd circle
			(at 0.40005 0 180)
			(size 0 0)
			(layers "B.Cu" "B.Mask" "B.Paste")
			(net "NIC1_BIF1_N")
		)
		(pad "2" smd circle
			(at -0.40005 0 180)
			(size 0 0)
			(layers "B.Cu" "B.Mask" "B.Paste")
			(net "P3V3_AUX")
		)
	)
	(footprint ""
		(layer "B.Cu")
		(at 119.347488 -304.157634 180)
		(property "Reference" "PR81"
			(at 0 0 0)
			(layer "B.SilkS")
			(hide yes)
			(effects
				(font
					(size 1.27 1.27)
				)
				(justify mirror)
			)
		)
		(property "Value" ""
			(at 0 0 0)
			(layer "B.Fab")
			(effects
				(font
					(size 1.27 1.27)
				)
				(justify mirror)
			)
		)
		(duplicate_pad_numbers_are_jumpers no)
		(fp_line
			(start 0.7874 0.4064)
			(end 0.7874 -0.4064)
			(stroke
				(width 0.1524)
				(type default)
			)
			(layer "B.SilkS")
		)
		(fp_line
			(start 0.7874 -0.4064)
			(end -0.7874 -0.4064)
			(stroke
				(width 0.1524)
				(type default)
			)
			(layer "B.SilkS")
		)
		(fp_line
			(start -0.7874 0.4064)
			(end 0.7874 0.4064)
			(stroke
				(width 0.1524)
				(type default)
			)
			(layer "B.SilkS")
		)
		(fp_line
			(start -0.7874 -0.4064)
			(end -0.7874 0.4064)
			(stroke
				(width 0.1524)
				(type default)
			)
			(layer "B.SilkS")
		)
		(fp_line
			(start 0.67945 0.3048)
			(end 0.67945 -0.305054)
			(stroke
				(width 0.1)
				(type default)
			)
			(layer "B.Fab")
		)
		(fp_line
			(start 0.67945 -0.305054)
			(end 0.12065 -0.305054)
			(stroke
				(width 0.1)
				(type default)
			)
			(layer "B.Fab")
		)
		(fp_line
			(start 0.12065 0.3048)
			(end 0.67945 0.3048)
			(stroke
				(width 0.1)
				(type default)
			)
			(layer "B.Fab")
		)
		(fp_line
			(start 0.12065 0.2794)
			(end 0.12065 0.3048)
			(stroke
				(width 0.1)
				(type default)
			)
			(layer "B.Fab")
		)
		(fp_line
			(start 0.12065 -0.2794)
			(end -0.12065 -0.2794)
			(stroke
				(width 0.1)
				(type default)
			)
			(layer "B.Fab")
		)
		(fp_line
			(start 0.12065 -0.305054)
			(end 0.12065 -0.2794)
			(stroke
				(width 0.1)
				(type default)
			)
			(layer "B.Fab")
		)
		(fp_line
			(start -0.120396 0.3048)
			(end -0.120396 0.2794)
			(stroke
				(width 0.1)
				(type default)
			)
			(layer "B.Fab")
		)
		(fp_line
			(start -0.120396 0.2794)
			(end 0.12065 0.2794)
			(stroke
				(width 0.1)
				(type default)
			)
			(layer "B.Fab")
		)
		(fp_line
			(start -0.12065 -0.2794)
			(end -0.12065 -0.3048)
			(stroke
				(width 0.1)
				(type default)
			)
			(layer "B.Fab")
		)
		(fp_line
			(start -0.12065 -0.3048)
			(end -0.67945 -0.3048)
			(stroke
				(width 0.1)
				(type default)
			)
			(layer "B.Fab")
		)
		(fp_line
			(start -0.67945 0.3048)
			(end -0.120396 0.3048)
			(stroke
				(width 0.1)
				(type default)
			)
			(layer "B.Fab")
		)
		(fp_line
			(start -0.67945 -0.3048)
			(end -0.67945 0.3048)
			(stroke
				(width 0.1)
				(type default)
			)
			(layer "B.Fab")
		)
		(pad "1" smd circle
			(at 0.40005 0)
			(size 0 0)
			(layers "B.Cu" "B.Mask" "B.Paste")
			(net "SH_P0V8_PEX1_RGND1")
		)
		(pad "2" smd circle
			(at -0.40005 0)
			(size 0 0)
			(layers "B.Cu" "B.Mask" "B.Paste")
			(net "GND")
		)
	)
	(footprint ""
		(layer "B.Cu")
		(at 49.1998 -291.624766)
		(property "Reference" "C1103"
			(at 0 0 0)
			(layer "B.SilkS")
			(hide yes)
			(effects
				(font
					(size 1.27 1.27)
				)
				(justify mirror)
			)
		)
		(property "Value" ""
			(at 0 0 0)
			(layer "B.Fab")
			(effects
				(font
					(size 1.27 1.27)
				)
				(justify mirror)
			)
		)
		(duplicate_pad_numbers_are_jumpers no)
		(fp_line
			(start -0.299974 -0.150114)
			(end -0.299974 0.150114)
			(stroke
				(width 0.1)
				(type default)
			)
			(layer "B.Fab")
		)
		(fp_line
			(start -0.299974 0.150114)
			(end 0.299974 0.150114)
			(stroke
				(width 0.1)
				(type default)
			)
			(layer "B.Fab")
		)
		(fp_line
			(start 0.299974 -0.150114)
			(end -0.299974 -0.150114)
			(stroke
				(width 0.1)
				(type default)
			)
			(layer "B.Fab")
		)
		(fp_line
			(start 0.299974 0.150114)
			(end 0.299974 -0.150114)
			(stroke
				(width 0.1)
				(type default)
			)
			(layer "B.Fab")
		)
		(pad "1" smd rect
			(at 0.2667 0 180)
			(size 0.3048 0.381)
			(layers "B.Cu" "B.Mask" "B.Paste")
			(net "P0V8_PEX0")
		)
		(pad "2" smd rect
			(at -0.2667 0 180)
			(size 0.3048 0.381)
			(layers "B.Cu" "B.Mask" "B.Paste")
			(net "GND")
		)
	)
	(footprint ""
		(layer "B.Cu")
		(at 388.366 -227.203 90)
		(property "Reference" "R928"
			(at 0 0 90)
			(layer "B.SilkS")
			(hide yes)
			(effects
				(font
					(size 1.27 1.27)
				)
				(justify mirror)
			)
		)
		(property "Value" ""
			(at 0 0 90)
			(layer "B.Fab")
			(effects
				(font
					(size 1.27 1.27)
				)
				(justify mirror)
			)
		)
		(duplicate_pad_numbers_are_jumpers no)
		(fp_line
			(start 0.7874 -0.4064)
			(end -0.7874 -0.4064)
			(stroke
				(width 0.1524)
				(type default)
			)
			(layer "B.SilkS")
		)
		(fp_line
			(start -0.7874 -0.4064)
			(end -0.7874 0.4064)
			(stroke
				(width 0.1524)
				(type default)
			)
			(layer "B.SilkS")
		)
		(fp_line
			(start 0.7874 0.4064)
			(end 0.7874 -0.4064)
			(stroke
				(width 0.1524)
				(type default)
			)
			(layer "B.SilkS")
		)
		(fp_line
			(start -0.7874 0.4064)
			(end 0.7874 0.4064)
			(stroke
				(width 0.1524)
				(type default)
			)
			(layer "B.SilkS")
		)
		(fp_line
			(start 0.67945 -0.305054)
			(end 0.12065 -0.305054)
			(stroke
				(width 0.1)
				(type default)
			)
			(layer "B.Fab")
		)
		(fp_line
			(start 0.12065 -0.305054)
			(end 0.12065 -0.2794)
			(stroke
				(width 0.1)
				(type default)
			)
			(layer "B.Fab")
		)
		(fp_line
			(start -0.12065 -0.3048)
			(end -0.67945 -0.3048)
			(stroke
				(width 0.1)
				(type default)
			)
			(layer "B.Fab")
		)
		(fp_line
			(start -0.67945 -0.3048)
			(end -0.67945 0.3048)
			(stroke
				(width 0.1)
				(type default)
			)
			(layer "B.Fab")
		)
		(fp_line
			(start 0.12065 -0.2794)
			(end -0.12065 -0.2794)
			(stroke
				(width 0.1)
				(type default)
			)
			(layer "B.Fab")
		)
		(fp_line
			(start -0.12065 -0.2794)
			(end -0.12065 -0.3048)
			(stroke
				(width 0.1)
				(type default)
			)
			(layer "B.Fab")
		)
		(fp_line
			(start 0.12065 0.2794)
			(end 0.12065 0.3048)
			(stroke
				(width 0.1)
				(type default)
			)
			(layer "B.Fab")
		)
		(fp_line
			(start -0.120396 0.2794)
			(end 0.12065 0.2794)
			(stroke
				(width 0.1)
				(type default)
			)
			(layer "B.Fab")
		)
		(fp_line
			(start 0.67945 0.3048)
			(end 0.67945 -0.305054)
			(stroke
				(width 0.1)
				(type default)
			)
			(layer "B.Fab")
		)
		(fp_line
			(start 0.12065 0.3048)
			(end 0.67945 0.3048)
			(stroke
				(width 0.1)
				(type default)
			)
			(layer "B.Fab")
		)
		(fp_line
			(start -0.120396 0.3048)
			(end -0.120396 0.2794)
			(stroke
				(width 0.1)
				(type default)
			)
			(layer "B.Fab")
		)
		(fp_line
			(start -0.67945 0.3048)
			(end -0.120396 0.3048)
			(stroke
				(width 0.1)
				(type default)
			)
			(layer "B.Fab")
		)
		(pad "1" smd circle
			(at 0.40005 0 270)
			(size 0 0)
			(layers "B.Cu" "B.Mask" "B.Paste")
			(net "UART_PEX1_SDB_RX")
		)
		(pad "2" smd circle
			(at -0.40005 0 270)
			(size 0 0)
			(layers "B.Cu" "B.Mask" "B.Paste")
			(net "UART_PEX1_SDB_R_RX")
		)
	)
	(footprint ""
		(layer "B.Cu")
		(at 400.824954 -297.79976 -90)
		(property "Reference" "C1882"
			(at 0 0 90)
			(layer "B.SilkS")
			(hide yes)
			(effects
				(font
					(size 1.27 1.27)
				)
				(justify mirror)
			)
		)
		(property "Value" ""
			(at 0 0 90)
			(layer "B.Fab")
			(effects
				(font
					(size 1.27 1.27)
				)
				(justify mirror)
			)
		)
		(duplicate_pad_numbers_are_jumpers no)
		(fp_line
			(start -0.299974 0.150114)
			(end 0.299974 0.150114)
			(stroke
				(width 0.1)
				(type default)
			)
			(layer "B.Fab")
		)
		(fp_line
			(start 0.299974 0.150114)
			(end 0.299974 -0.150114)
			(stroke
				(width 0.1)
				(type default)
			)
			(layer "B.Fab")
		)
		(fp_line
			(start -0.299974 -0.150114)
			(end -0.299974 0.150114)
			(stroke
				(width 0.1)
				(type default)
			)
			(layer "B.Fab")
		)
		(fp_line
			(start 0.299974 -0.150114)
			(end -0.299974 -0.150114)
			(stroke
				(width 0.1)
				(type default)
			)
			(layer "B.Fab")
		)
		(pad "1" smd rect
			(at 0.2667 0 90)
			(size 0.3048 0.381)
			(layers "B.Cu" "B.Mask" "B.Paste")
			(net "P0V8_PEX3")
		)
		(pad "2" smd rect
			(at -0.2667 0 90)
			(size 0.3048 0.381)
			(layers "B.Cu" "B.Mask" "B.Paste")
			(net "GND")
		)
	)
	(footprint ""
		(layer "B.Cu")
		(at 54.899814 -292.099746 90)
		(property "Reference" "C1219"
			(at 0 0 90)
			(layer "B.SilkS")
			(hide yes)
			(effects
				(font
					(size 1.27 1.27)
				)
				(justify mirror)
			)
		)
		(property "Value" ""
			(at 0 0 90)
			(layer "B.Fab")
			(effects
				(font
					(size 1.27 1.27)
				)
				(justify mirror)
			)
		)
		(duplicate_pad_numbers_are_jumpers no)
		(fp_line
			(start 0.299974 -0.150114)
			(end -0.299974 -0.150114)
			(stroke
				(width 0.1)
				(type default)
			)
			(layer "B.Fab")
		)
		(fp_line
			(start -0.299974 -0.150114)
			(end -0.299974 0.150114)
			(stroke
				(width 0.1)
				(type default)
			)
			(layer "B.Fab")
		)
		(fp_line
			(start 0.299974 0.150114)
			(end 0.299974 -0.150114)
			(stroke
				(width 0.1)
				(type default)
			)
			(layer "B.Fab")
		)
		(fp_line
			(start -0.299974 0.150114)
			(end 0.299974 0.150114)
			(stroke
				(width 0.1)
				(type default)
			)
			(layer "B.Fab")
		)
		(pad "1" smd rect
			(at 0.2667 0 270)
			(size 0.3048 0.381)
			(layers "B.Cu" "B.Mask" "B.Paste")
			(net "P0V8_SERDES_VDDA_PEX0")
		)
		(pad "2" smd rect
			(at -0.2667 0 270)
			(size 0.3048 0.381)
			(layers "B.Cu" "B.Mask" "B.Paste")
			(net "GND")
		)
	)
	(footprint ""
		(layer "B.Cu")
		(at 244.901212 -289.856926 180)
		(property "Reference" "PC994"
			(at 0 0 0)
			(layer "B.SilkS")
			(hide yes)
			(effects
				(font
					(size 1.27 1.27)
				)
				(justify mirror)
			)
		)
		(property "Value" ""
			(at 0 0 0)
			(layer "B.Fab")
			(effects
				(font
					(size 1.27 1.27)
				)
				(justify mirror)
			)
		)
		(duplicate_pad_numbers_are_jumpers no)
		(fp_line
			(start 1.524 0.762)
			(end 1.524 -0.762)
			(stroke
				(width 0.1524)
				(type default)
			)
			(layer "B.SilkS")
		)
		(fp_line
			(start 1.524 -0.762)
			(end -1.524 -0.762)
			(stroke
				(width 0.1524)
				(type default)
			)
			(layer "B.SilkS")
		)
		(fp_line
			(start -1.524 0.762)
			(end 1.524 0.762)
			(stroke
				(width 0.1524)
				(type default)
			)
			(layer "B.SilkS")
		)
		(fp_line
			(start -1.524 -0.762)
			(end -1.524 0.762)
			(stroke
				(width 0.1524)
				(type default)
			)
			(layer "B.SilkS")
		)
		(fp_line
			(start 1.1049 0.724916)
			(end -1.1049 0.724916)
			(stroke
				(width 0.1)
				(type default)
			)
			(layer "B.Fab")
		)
		(fp_line
			(start 1.1049 -0.724916)
			(end 1.1049 0.724916)
			(stroke
				(width 0.1)
				(type default)
			)
			(layer "B.Fab")
		)
		(fp_line
			(start -1.1049 0.724916)
			(end -1.1049 -0.724916)
			(stroke
				(width 0.1)
				(type default)
			)
			(layer "B.Fab")
		)
		(fp_line
			(start -1.1049 -0.724916)
			(end 1.1049 -0.724916)
			(stroke
				(width 0.1)
				(type default)
			)
			(layer "B.Fab")
		)
		(pad "1" smd rect
			(at 0.889 0 180)
			(size 1.016 1.27)
			(layers "B.Cu" "B.Mask" "B.Paste")
			(net "P1V25_PEX2_R")
		)
		(pad "2" smd rect
			(at -0.889 0 180)
			(size 1.016 1.27)
			(layers "B.Cu" "B.Mask" "B.Paste")
			(net "GND")
		)
	)
	(footprint ""
		(layer "B.Cu")
		(at 53.949854 -303.499774 -90)
		(property "Reference" "C2916"
			(at 0 0 90)
			(layer "B.SilkS")
			(hide yes)
			(effects
				(font
					(size 1.27 1.27)
				)
				(justify mirror)
			)
		)
		(property "Value" ""
			(at 0 0 90)
			(layer "B.Fab")
			(effects
				(font
					(size 1.27 1.27)
				)
				(justify mirror)
			)
		)
		(duplicate_pad_numbers_are_jumpers no)
		(fp_line
			(start -0.299974 0.150114)
			(end 0.299974 0.150114)
			(stroke
				(width 0.1)
				(type default)
			)
			(layer "B.Fab")
		)
		(fp_line
			(start 0.299974 0.150114)
			(end 0.299974 -0.150114)
			(stroke
				(width 0.1)
				(type default)
			)
			(layer "B.Fab")
		)
		(fp_line
			(start -0.299974 -0.150114)
			(end -0.299974 0.150114)
			(stroke
				(width 0.1)
				(type default)
			)
			(layer "B.Fab")
		)
		(fp_line
			(start 0.299974 -0.150114)
			(end -0.299974 -0.150114)
			(stroke
				(width 0.1)
				(type default)
			)
			(layer "B.Fab")
		)
		(pad "1" smd rect
			(at 0.2667 0 90)
			(size 0.3048 0.381)
			(layers "B.Cu" "B.Mask" "B.Paste")
			(net "P1V25_PEX0")
		)
		(pad "2" smd rect
			(at -0.2667 0 90)
			(size 0.3048 0.381)
			(layers "B.Cu" "B.Mask" "B.Paste")
			(net "GND")
		)
	)
	(footprint ""
		(layer "B.Cu")
		(at 170.999912 -299.699934 -90)
		(property "Reference" "C1476"
			(at 0 0 90)
			(layer "B.SilkS")
			(hide yes)
			(effects
				(font
					(size 1.27 1.27)
				)
				(justify mirror)
			)
		)
		(property "Value" ""
			(at 0 0 90)
			(layer "B.Fab")
			(effects
				(font
					(size 1.27 1.27)
				)
				(justify mirror)
			)
		)
		(duplicate_pad_numbers_are_jumpers no)
		(fp_line
			(start -0.299974 0.150114)
			(end 0.299974 0.150114)
			(stroke
				(width 0.1)
				(type default)
			)
			(layer "B.Fab")
		)
		(fp_line
			(start 0.299974 0.150114)
			(end 0.299974 -0.150114)
			(stroke
				(width 0.1)
				(type default)
			)
			(layer "B.Fab")
		)
		(fp_line
			(start -0.299974 -0.150114)
			(end -0.299974 0.150114)
			(stroke
				(width 0.1)
				(type default)
			)
			(layer "B.Fab")
		)
		(fp_line
			(start 0.299974 -0.150114)
			(end -0.299974 -0.150114)
			(stroke
				(width 0.1)
				(type default)
			)
			(layer "B.Fab")
		)
		(pad "1" smd rect
			(at 0.2667 0 90)
			(size 0.3048 0.381)
			(layers "B.Cu" "B.Mask" "B.Paste")
			(net "P0V8_SERDES_VDDA_PEX1")
		)
		(pad "2" smd rect
			(at -0.2667 0 90)
			(size 0.3048 0.381)
			(layers "B.Cu" "B.Mask" "B.Paste")
			(net "GND")
		)
	)
	(footprint ""
		(layer "B.Cu")
		(at 99.35337 -333.067406 180)
		(property "Reference" "R1229"
			(at 0 0 0)
			(layer "B.SilkS")
			(hide yes)
			(effects
				(font
					(size 1.27 1.27)
				)
				(justify mirror)
			)
		)
		(property "Value" ""
			(at 0 0 0)
			(layer "B.Fab")
			(effects
				(font
					(size 1.27 1.27)
				)
				(justify mirror)
			)
		)
		(duplicate_pad_numbers_are_jumpers no)
		(fp_line
			(start 0.7874 0.4064)
			(end 0.7874 -0.4064)
			(stroke
				(width 0.1524)
				(type default)
			)
			(layer "B.SilkS")
		)
		(fp_line
			(start 0.7874 -0.4064)
			(end -0.7874 -0.4064)
			(stroke
				(width 0.1524)
				(type default)
			)
			(layer "B.SilkS")
		)
		(fp_line
			(start -0.7874 0.4064)
			(end 0.7874 0.4064)
			(stroke
				(width 0.1524)
				(type default)
			)
			(layer "B.SilkS")
		)
		(fp_line
			(start -0.7874 -0.4064)
			(end -0.7874 0.4064)
			(stroke
				(width 0.1524)
				(type default)
			)
			(layer "B.SilkS")
		)
		(fp_line
			(start 0.67945 0.3048)
			(end 0.67945 -0.305054)
			(stroke
				(width 0.1)
				(type default)
			)
			(layer "B.Fab")
		)
		(fp_line
			(start 0.67945 -0.305054)
			(end 0.12065 -0.305054)
			(stroke
				(width 0.1)
				(type default)
			)
			(layer "B.Fab")
		)
		(fp_line
			(start 0.12065 0.3048)
			(end 0.67945 0.3048)
			(stroke
				(width 0.1)
				(type default)
			)
			(layer "B.Fab")
		)
		(fp_line
			(start 0.12065 0.2794)
			(end 0.12065 0.3048)
			(stroke
				(width 0.1)
				(type default)
			)
			(layer "B.Fab")
		)
		(fp_line
			(start 0.12065 -0.2794)
			(end -0.12065 -0.2794)
			(stroke
				(width 0.1)
				(type default)
			)
			(layer "B.Fab")
		)
		(fp_line
			(start 0.12065 -0.305054)
			(end 0.12065 -0.2794)
			(stroke
				(width 0.1)
				(type default)
			)
			(layer "B.Fab")
		)
		(fp_line
			(start -0.120396 0.3048)
			(end -0.120396 0.2794)
			(stroke
				(width 0.1)
				(type default)
			)
			(layer "B.Fab")
		)
		(fp_line
			(start -0.120396 0.2794)
			(end 0.12065 0.2794)
			(stroke
				(width 0.1)
				(type default)
			)
			(layer "B.Fab")
		)
		(fp_line
			(start -0.12065 -0.2794)
			(end -0.12065 -0.3048)
			(stroke
				(width 0.1)
				(type default)
			)
			(layer "B.Fab")
		)
		(fp_line
			(start -0.12065 -0.3048)
			(end -0.67945 -0.3048)
			(stroke
				(width 0.1)
				(type default)
			)
			(layer "B.Fab")
		)
		(fp_line
			(start -0.67945 0.3048)
			(end -0.120396 0.3048)
			(stroke
				(width 0.1)
				(type default)
			)
			(layer "B.Fab")
		)
		(fp_line
			(start -0.67945 -0.3048)
			(end -0.67945 0.3048)
			(stroke
				(width 0.1)
				(type default)
			)
			(layer "B.Fab")
		)
		(pad "1" smd circle
			(at 0.40005 0)
			(size 0 0)
			(layers "B.Cu" "B.Mask" "B.Paste")
			(net "CLK_100M_DB800ZL_PEX2_S0_R_DP")
		)
		(pad "2" smd circle
			(at -0.40005 0)
			(size 0 0)
			(layers "B.Cu" "B.Mask" "B.Paste")
			(net "CLK_100M_DB800ZL_PEX2_S0_DP")
		)
	)
	(footprint ""
		(layer "B.Cu")
		(at 180.50002 -303.499774 -90)
		(property "Reference" "C3104"
			(at 0 0 90)
			(layer "B.SilkS")
			(hide yes)
			(effects
				(font
					(size 1.27 1.27)
				)
				(justify mirror)
			)
		)
		(property "Value" ""
			(at 0 0 90)
			(layer "B.Fab")
			(effects
				(font
					(size 1.27 1.27)
				)
				(justify mirror)
			)
		)
		(duplicate_pad_numbers_are_jumpers no)
		(fp_line
			(start -0.299974 0.150114)
			(end 0.299974 0.150114)
			(stroke
				(width 0.1)
				(type default)
			)
			(layer "B.Fab")
		)
		(fp_line
			(start 0.299974 0.150114)
			(end 0.299974 -0.150114)
			(stroke
				(width 0.1)
				(type default)
			)
			(layer "B.Fab")
		)
		(fp_line
			(start -0.299974 -0.150114)
			(end -0.299974 0.150114)
			(stroke
				(width 0.1)
				(type default)
			)
			(layer "B.Fab")
		)
		(fp_line
			(start 0.299974 -0.150114)
			(end -0.299974 -0.150114)
			(stroke
				(width 0.1)
				(type default)
			)
			(layer "B.Fab")
		)
		(pad "1" smd rect
			(at 0.2667 0 90)
			(size 0.3048 0.381)
			(layers "B.Cu" "B.Mask" "B.Paste")
			(net "P1V25_PEX1")
		)
		(pad "2" smd rect
			(at -0.2667 0 90)
			(size 0.3048 0.381)
			(layers "B.Cu" "B.Mask" "B.Paste")
			(net "GND")
		)
	)
	(footprint ""
		(layer "B.Cu")
		(at 238.890302 -366.750854 180)
		(property "Reference" "PR6607"
			(at 0 0 0)
			(layer "B.SilkS")
			(hide yes)
			(effects
				(font
					(size 1.27 1.27)
				)
				(justify mirror)
			)
		)
		(property "Value" ""
			(at 0 0 0)
			(layer "B.Fab")
			(effects
				(font
					(size 1.27 1.27)
				)
				(justify mirror)
			)
		)
		(duplicate_pad_numbers_are_jumpers no)
		(fp_line
			(start 0.7874 0.4064)
			(end 0.7874 -0.4064)
			(stroke
				(width 0.1524)
				(type default)
			)
			(layer "B.SilkS")
		)
		(fp_line
			(start 0.7874 -0.4064)
			(end -0.7874 -0.4064)
			(stroke
				(width 0.1524)
				(type default)
			)
			(layer "B.SilkS")
		)
		(fp_line
			(start -0.7874 0.4064)
			(end 0.7874 0.4064)
			(stroke
				(width 0.1524)
				(type default)
			)
			(layer "B.SilkS")
		)
		(fp_line
			(start -0.7874 -0.4064)
			(end -0.7874 0.4064)
			(stroke
				(width 0.1524)
				(type default)
			)
			(layer "B.SilkS")
		)
		(fp_line
			(start 0.67945 0.3048)
			(end 0.67945 -0.305054)
			(stroke
				(width 0.1)
				(type default)
			)
			(layer "B.Fab")
		)
		(fp_line
			(start 0.67945 -0.305054)
			(end 0.12065 -0.305054)
			(stroke
				(width 0.1)
				(type default)
			)
			(layer "B.Fab")
		)
		(fp_line
			(start 0.12065 0.3048)
			(end 0.67945 0.3048)
			(stroke
				(width 0.1)
				(type default)
			)
			(layer "B.Fab")
		)
		(fp_line
			(start 0.12065 0.2794)
			(end 0.12065 0.3048)
			(stroke
				(width 0.1)
				(type default)
			)
			(layer "B.Fab")
		)
		(fp_line
			(start 0.12065 -0.2794)
			(end -0.12065 -0.2794)
			(stroke
				(width 0.1)
				(type default)
			)
			(layer "B.Fab")
		)
		(fp_line
			(start 0.12065 -0.305054)
			(end 0.12065 -0.2794)
			(stroke
				(width 0.1)
				(type default)
			)
			(layer "B.Fab")
		)
		(fp_line
			(start -0.120396 0.3048)
			(end -0.120396 0.2794)
			(stroke
				(width 0.1)
				(type default)
			)
			(layer "B.Fab")
		)
		(fp_line
			(start -0.120396 0.2794)
			(end 0.12065 0.2794)
			(stroke
				(width 0.1)
				(type default)
			)
			(layer "B.Fab")
		)
		(fp_line
			(start -0.12065 -0.2794)
			(end -0.12065 -0.3048)
			(stroke
				(width 0.1)
				(type default)
			)
			(layer "B.Fab")
		)
		(fp_line
			(start -0.12065 -0.3048)
			(end -0.67945 -0.3048)
			(stroke
				(width 0.1)
				(type default)
			)
			(layer "B.Fab")
		)
		(fp_line
			(start -0.67945 0.3048)
			(end -0.120396 0.3048)
			(stroke
				(width 0.1)
				(type default)
			)
			(layer "B.Fab")
		)
		(fp_line
			(start -0.67945 -0.3048)
			(end -0.67945 0.3048)
			(stroke
				(width 0.1)
				(type default)
			)
			(layer "B.Fab")
		)
		(pad "1" smd circle
			(at 0.40005 0)
			(size 0 0)
			(layers "B.Cu" "B.Mask" "B.Paste")
			(net "P12V_HSC_GATE1")
		)
		(pad "2" smd circle
			(at -0.40005 0)
			(size 0 0)
			(layers "B.Cu" "B.Mask" "B.Paste")
			(net "HS_GATE1_R_1")
		)
	)
	(footprint ""
		(layer "B.Cu")
		(at 103.690674 -351.763584 -90)
		(property "Reference" "U424"
			(at 2.813304 4.248912 0)
			(unlocked yes)
			(layer "B.SilkS")
			(effects
				(font
					(size 0.7874 0.5842)
					(thickness 0.1524)
				)
				(justify mirror)
			)
		)
		(property "Value" ""
			(at 0 0 90)
			(layer "B.Fab")
			(effects
				(font
					(size 1.27 1.27)
				)
				(justify mirror)
			)
		)
		(duplicate_pad_numbers_are_jumpers no)
		(fp_line
			(start -2.500122 2.500122)
			(end -2.500122 2.01676)
			(stroke
				(width 0.1524)
				(type default)
			)
			(layer "B.SilkS")
		)
		(fp_line
			(start -2.01676 2.500122)
			(end -2.500122 2.500122)
			(stroke
				(width 0.1524)
				(type default)
			)
			(layer "B.SilkS")
		)
		(fp_line
			(start 2.500122 2.500122)
			(end 2.01676 2.500122)
			(stroke
				(width 0.1524)
				(type default)
			)
			(layer "B.SilkS")
		)
		(fp_line
			(start 2.500122 2.01676)
			(end 2.500122 2.500122)
			(stroke
				(width 0.1524)
				(type default)
			)
			(layer "B.SilkS")
		)
		(fp_line
			(start -2.500122 -2.01676)
			(end -2.500122 -2.500122)
			(stroke
				(width 0.1524)
				(type default)
			)
			(layer "B.SilkS")
		)
		(fp_line
			(start -2.500122 -2.500122)
			(end -2.01676 -2.500122)
			(stroke
				(width 0.1524)
				(type default)
			)
			(layer "B.SilkS")
		)
		(fp_line
			(start 2.01676 -2.500122)
			(end 2.500122 -2.500122)
			(stroke
				(width 0.1524)
				(type default)
			)
			(layer "B.SilkS")
		)
		(fp_line
			(start 2.500122 -2.500122)
			(end 2.500122 -2.01676)
			(stroke
				(width 0.1524)
				(type default)
			)
			(layer "B.SilkS")
		)
		(fp_poly
			(pts
				(xy 2.916936 -1.869948) (xy 3.514598 -3.065272) (xy 2.319274 -3.065272)
			)
			(stroke
				(width 0)
				(type default)
			)
			(fill yes)
			(layer "B.SilkS")
		)
		(fp_line
			(start -2.500122 2.500122)
			(end -2.500122 -2.500122)
			(stroke
				(width 0.1)
				(type default)
			)
			(layer "B.Fab")
		)
		(fp_line
			(start 2.500122 2.500122)
			(end -2.500122 2.500122)
			(stroke
				(width 0.1)
				(type default)
			)
			(layer "B.Fab")
		)
		(fp_line
			(start -2.500122 -2.500122)
			(end 2.500122 -2.500122)
			(stroke
				(width 0.1)
				(type default)
			)
			(layer "B.Fab")
		)
		(fp_line
			(start 2.500122 -2.500122)
			(end 2.500122 2.500122)
			(stroke
				(width 0.1)
				(type default)
			)
			(layer "B.Fab")
		)
		(fp_poly
			(pts
				(xy 3.044698 -1.75006) (xy 4.240022 -1.152398) (xy 4.240022 -2.347722)
			)
			(stroke
				(width 0)
				(type default)
			)
			(fill yes)
			(layer "B.Fab")
		)
		(pad "1" smd rect
			(at 2.3749 -1.75006 180)
			(size 0.254 0.5588)
			(layers "B.Cu" "B.Mask" "B.Paste")
			(net "FM_CLK_EN_R")
		)
		(pad "2" smd rect
			(at 2.3749 -1.249934 180)
			(size 0.254 0.5588)
			(layers "B.Cu" "B.Mask" "B.Paste")
			(net "P3V3_CLK_BUFFER_9ZXL0451E_S3_VZX3P3A")
		)
		(pad "3" smd rect
			(at 2.3749 -0.750062 180)
			(size 0.254 0.5588)
			(layers "B.Cu" "B.Mask" "B.Paste")
			(net "CLK_100M_MB_1_R_DP")
		)
		(pad "4" smd rect
			(at 2.3749 -0.249936 180)
			(size 0.254 0.5588)
			(layers "B.Cu" "B.Mask" "B.Paste")
			(net "CLK_100M_MB_1_R_DN")
		)
		(pad "5" smd rect
			(at 2.3749 0.249936 180)
			(size 0.254 0.5588)
			(layers "B.Cu" "B.Mask" "B.Paste")
			(net "SMB_9ZXL0451E_S3_ADDR0")
		)
		(pad "6" smd rect
			(at 2.3749 0.750062 180)
			(size 0.254 0.5588)
			(layers "B.Cu" "B.Mask" "B.Paste")
			(net "SMB_BMC_9FGL0451E_S3_SDA")
		)
		(pad "7" smd rect
			(at 2.3749 1.249934 180)
			(size 0.254 0.5588)
			(layers "B.Cu" "B.Mask" "B.Paste")
			(net "SMB_BMC_9FGL0451E_S3_SCL")
		)
		(pad "8" smd rect
			(at 2.3749 1.75006 180)
			(size 0.254 0.5588)
			(layers "B.Cu" "B.Mask" "B.Paste")
			(net "Net_9193")
		)
		(pad "9" smd rect
			(at 1.75006 2.3749 90)
			(size 0.254 0.5588)
			(layers "B.Cu" "B.Mask" "B.Paste")
			(net "Net_9194")
		)
		(pad "10" smd rect
			(at 1.249934 2.3749 90)
			(size 0.254 0.5588)
			(layers "B.Cu" "B.Mask" "B.Paste")
			(net "Net_9192")
		)
		(pad "11" smd rect
			(at 0.750062 2.3749 90)
			(size 0.254 0.5588)
			(layers "B.Cu" "B.Mask" "B.Paste")
			(net "Net_9191")
		)
		(pad "12" smd rect
			(at 0.249936 2.3749 90)
			(size 0.254 0.5588)
			(layers "B.Cu" "B.Mask" "B.Paste")
			(net "P3V3_CLK_BUFFER_9ZXL0451E_S3_VZX3P3")
		)
		(pad "13" smd rect
			(at -0.249936 2.3749 90)
			(size 0.254 0.5588)
			(layers "B.Cu" "B.Mask" "B.Paste")
			(net "CLK_100M_DB800ZL_PEX0_S3_DP")
		)
		(pad "14" smd rect
			(at -0.750062 2.3749 90)
			(size 0.254 0.5588)
			(layers "B.Cu" "B.Mask" "B.Paste")
			(net "CLK_100M_DB800ZL_PEX0_S3_DN")
		)
		(pad "15" smd rect
			(at -1.249934 2.3749 90)
			(size 0.254 0.5588)
			(layers "B.Cu" "B.Mask" "B.Paste")
			(net "PEX_S3_REF_CLK_BUFFER_EN_N")
		)
		(pad "16" smd rect
			(at -1.75006 2.3749 90)
			(size 0.254 0.5588)
			(layers "B.Cu" "B.Mask" "B.Paste")
			(net "P3V3_CLK_BUFFER_9ZXL0451E_S3_VZX3P3")
		)
		(pad "17" smd rect
			(at -2.3749 1.75006)
			(size 0.254 0.5588)
			(layers "B.Cu" "B.Mask" "B.Paste")
			(net "Net_9190")
		)
		(pad "18" smd rect
			(at -2.3749 1.249934)
			(size 0.254 0.5588)
			(layers "B.Cu" "B.Mask" "B.Paste")
			(net "PEX_S3_REF_CLK_BUFFER_EN_N")
		)
		(pad "19" smd rect
			(at -2.3749 0.750062)
			(size 0.254 0.5588)
			(layers "B.Cu" "B.Mask" "B.Paste")
			(net "CLK_100M_DB800ZL_PEX1_S3_DP")
		)
		(pad "20" smd rect
			(at -2.3749 0.249936)
			(size 0.254 0.5588)
			(layers "B.Cu" "B.Mask" "B.Paste")
			(net "CLK_100M_DB800ZL_PEX1_S3_DN")
		)
		(pad "21" smd rect
			(at -2.3749 -0.249936)
			(size 0.254 0.5588)
			(layers "B.Cu" "B.Mask" "B.Paste")
			(net "P3V3_CLK_BUFFER_9ZXL0451E_S3_VZX3P3")
		)
		(pad "22" smd rect
			(at -2.3749 -0.750062)
			(size 0.254 0.5588)
			(layers "B.Cu" "B.Mask" "B.Paste")
			(net "CLK_100M_DB800ZL_PEX2_S3_DP")
		)
		(pad "23" smd rect
			(at -2.3749 -1.249934)
			(size 0.254 0.5588)
			(layers "B.Cu" "B.Mask" "B.Paste")
			(net "CLK_100M_DB800ZL_PEX2_S3_DN")
		)
		(pad "24" smd rect
			(at -2.3749 -1.75006)
			(size 0.254 0.5588)
			(layers "B.Cu" "B.Mask" "B.Paste")
			(net "PEX_S3_REF_CLK_BUFFER_EN_N")
		)
		(pad "25" smd rect
			(at -1.75006 -2.3749 270)
			(size 0.254 0.5588)
			(layers "B.Cu" "B.Mask" "B.Paste")
			(net "P3V3_CLK_BUFFER_9ZXL0451E_S3_VZX3P3")
		)
		(pad "26" smd rect
			(at -1.249934 -2.3749 270)
			(size 0.254 0.5588)
			(layers "B.Cu" "B.Mask" "B.Paste")
			(net "PEX_S3_REF_CLK_BUFFER_EN_N")
		)
		(pad "27" smd rect
			(at -0.750062 -2.3749 270)
			(size 0.254 0.5588)
			(layers "B.Cu" "B.Mask" "B.Paste")
			(net "CLK_100M_DB800ZL_PEX3_S3_DP")
		)
		(pad "28" smd rect
			(at -0.249936 -2.3749 270)
			(size 0.254 0.5588)
			(layers "B.Cu" "B.Mask" "B.Paste")
			(net "CLK_100M_DB800ZL_PEX3_S3_DN")
		)
		(pad "29" smd rect
			(at 0.249936 -2.3749 270)
			(size 0.254 0.5588)
			(layers "B.Cu" "B.Mask" "B.Paste")
			(net "P3V3_CLK_BUFFER_9ZXL0451E_S3_VZX3P3")
		)
		(pad "30" smd rect
			(at 0.750062 -2.3749 270)
			(size 0.254 0.5588)
			(layers "B.Cu" "B.Mask" "B.Paste")
			(net "Net_9189")
		)
		(pad "31" smd rect
			(at 1.249934 -2.3749 270)
			(size 0.254 0.5588)
			(layers "B.Cu" "B.Mask" "B.Paste")
			(net "P3V3_CLK_BUFFER_9ZXL0451E_S3_VZX3P3A")
		)
		(pad "32" smd rect
			(at 1.75006 -2.3749 270)
			(size 0.254 0.5588)
			(layers "B.Cu" "B.Mask" "B.Paste")
			(net "PU_9ZXL0451E_S3_HBW")
		)
		(pad "33" smd rect
			(at 0 0 90)
			(size 3.1496 3.1496)
			(layers "B.Cu" "B.Mask" "B.Paste")
			(net "GND")
		)
		(zone
			(layer "B.Cu")
			(hatch none 0.5)
			(connect_pads
				(clearance 0)
			)
			(min_thickness 0.25)
			(keepout
				(tracks not_allowed)
				(vias allowed)
				(pads allowed)
				(copperpour not_allowed)
				(footprints allowed)
			)
			(placement
				(enabled no)
				(sheetname "")
			)
			(fill
				(thermal_gap 0.5)
				(thermal_bridge_width 0.5)
				(island_removal_mode 0)
			)
			(polygon
				(pts
					(xy 101.645974 -349.718884) (xy 104.915208 -349.718884) (xy 104.915208 -350.137984) (xy 102.065074 -350.137984)
					(xy 102.065074 -353.389184) (xy 105.316274 -353.389184) (xy 105.316274 -350.137984) (xy 104.940608 -350.137984)
					(xy 104.940608 -349.718884) (xy 105.735374 -349.718884) (xy 105.735374 -353.808284) (xy 101.645974 -353.808284)
				)
			)
		)
	)
	(footprint ""
		(layer "B.Cu")
		(at 123.100592 -293.660068 90)
		(property "Reference" "PC118"
			(at 0 0 90)
			(layer "B.SilkS")
			(hide yes)
			(effects
				(font
					(size 1.27 1.27)
				)
				(justify mirror)
			)
		)
		(property "Value" ""
			(at 0 0 90)
			(layer "B.Fab")
			(effects
				(font
					(size 1.27 1.27)
				)
				(justify mirror)
			)
		)
		(duplicate_pad_numbers_are_jumpers no)
		(fp_line
			(start 4.84378 -2.150618)
			(end 4.53898 -2.150618)
			(stroke
				(width 0.1524)
				(type default)
			)
			(layer "B.SilkS")
		)
		(fp_line
			(start 4.84378 -2.150618)
			(end 4.842256 2.163064)
			(stroke
				(width 0.1524)
				(type default)
			)
			(layer "B.SilkS")
		)
		(fp_line
			(start 4.69138 -2.150618)
			(end 4.692396 2.161032)
			(stroke
				(width 0.1524)
				(type default)
			)
			(layer "B.SilkS")
		)
		(fp_line
			(start 4.53898 -2.150618)
			(end 4.539742 2.152142)
			(stroke
				(width 0.1524)
				(type default)
			)
			(layer "B.SilkS")
		)
		(fp_line
			(start 4.53898 -2.15011)
			(end -4.53898 -2.15011)
			(stroke
				(width 0.1524)
				(type default)
			)
			(layer "B.SilkS")
		)
		(fp_line
			(start -4.53898 -2.15011)
			(end -4.53898 2.15011)
			(stroke
				(width 0.1524)
				(type default)
			)
			(layer "B.SilkS")
		)
		(fp_line
			(start 4.53898 2.15011)
			(end 4.53898 -2.15011)
			(stroke
				(width 0.1524)
				(type default)
			)
			(layer "B.SilkS")
		)
		(fp_line
			(start -4.53898 2.15011)
			(end 4.53898 2.15011)
			(stroke
				(width 0.1524)
				(type default)
			)
			(layer "B.SilkS")
		)
		(fp_line
			(start 4.83108 2.150364)
			(end 4.447794 2.149348)
			(stroke
				(width 0.1524)
				(type default)
			)
			(layer "B.SilkS")
		)
		(fp_line
			(start 3.64998 -2.15011)
			(end -3.64998 -2.15011)
			(stroke
				(width 0.1)
				(type default)
			)
			(layer "B.Fab")
		)
		(fp_line
			(start -3.64998 -2.15011)
			(end -3.64998 2.15011)
			(stroke
				(width 0.1)
				(type default)
			)
			(layer "B.Fab")
		)
		(fp_line
			(start 3.64998 2.15011)
			(end 3.64998 -2.15011)
			(stroke
				(width 0.1)
				(type default)
			)
			(layer "B.Fab")
		)
		(fp_line
			(start -3.64998 2.15011)
			(end 3.64998 2.15011)
			(stroke
				(width 0.1)
				(type default)
			)
			(layer "B.Fab")
		)
		(fp_text user "+"
			(at 6.214872 -0.337058 90)
			(unlocked yes)
			(layer "B.SilkS")
			(effects
				(font
					(size 1.905 1.4224)
					(thickness 0.1524)
				)
				(justify left mirror)
			)
		)
		(fp_text user "-"
			(at -4.313174 -0.094488 90)
			(unlocked yes)
			(layer "B.SilkS")
			(effects
				(font
					(size 1.905 1.4224)
					(thickness 0.1524)
				)
				(justify left mirror)
			)
		)
		(fp_text user "+"
			(at 6.214872 -0.337058 90)
			(unlocked yes)
			(layer "B.Fab")
			(effects
				(font
					(size 1.905 1.4224)
					(thickness 0.1524)
				)
				(justify left mirror)
			)
		)
		(fp_text user "-"
			(at -4.313174 -0.094488 90)
			(unlocked yes)
			(layer "B.Fab")
			(effects
				(font
					(size 1.905 1.4224)
					(thickness 0.1524)
				)
				(justify left mirror)
			)
		)
		(pad "1" smd rect
			(at 3.199892 0 270)
			(size 2.413 2.8194)
			(layers "B.Cu" "B.Mask" "B.Paste")
			(net "P0V8_PEX1")
		)
		(pad "2" smd rect
			(at -3.199892 0 270)
			(size 2.413 2.8194)
			(layers "B.Cu" "B.Mask" "B.Paste")
			(net "GND")
		)
	)
	(footprint ""
		(layer "B.Cu")
		(at 61.872622 -152.674574 90)
		(property "Reference" "C857"
			(at 0 0 90)
			(layer "B.SilkS")
			(hide yes)
			(effects
				(font
					(size 1.27 1.27)
				)
				(justify mirror)
			)
		)
		(property "Value" ""
			(at 0 0 90)
			(layer "B.Fab")
			(effects
				(font
					(size 1.27 1.27)
				)
				(justify mirror)
			)
		)
		(duplicate_pad_numbers_are_jumpers no)
		(fp_line
			(start 0.7874 -0.4064)
			(end -0.7874 -0.4064)
			(stroke
				(width 0.1524)
				(type default)
			)
			(layer "B.SilkS")
		)
		(fp_line
			(start -0.7874 -0.4064)
			(end -0.7874 0.4064)
			(stroke
				(width 0.1524)
				(type default)
			)
			(layer "B.SilkS")
		)
		(fp_line
			(start 0.7874 0.4064)
			(end 0.7874 -0.4064)
			(stroke
				(width 0.1524)
				(type default)
			)
			(layer "B.SilkS")
		)
		(fp_line
			(start -0.7874 0.4064)
			(end 0.7874 0.4064)
			(stroke
				(width 0.1524)
				(type default)
			)
			(layer "B.SilkS")
		)
		(fp_line
			(start 0.67945 -0.305054)
			(end 0.12065 -0.305054)
			(stroke
				(width 0.1)
				(type default)
			)
			(layer "B.Fab")
		)
		(fp_line
			(start 0.12065 -0.305054)
			(end 0.12065 -0.2794)
			(stroke
				(width 0.1)
				(type default)
			)
			(layer "B.Fab")
		)
		(fp_line
			(start -0.12065 -0.3048)
			(end -0.67945 -0.3048)
			(stroke
				(width 0.1)
				(type default)
			)
			(layer "B.Fab")
		)
		(fp_line
			(start -0.67945 -0.3048)
			(end -0.67945 0.3048)
			(stroke
				(width 0.1)
				(type default)
			)
			(layer "B.Fab")
		)
		(fp_line
			(start 0.12065 -0.2794)
			(end -0.12065 -0.2794)
			(stroke
				(width 0.1)
				(type default)
			)
			(layer "B.Fab")
		)
		(fp_line
			(start -0.12065 -0.2794)
			(end -0.12065 -0.3048)
			(stroke
				(width 0.1)
				(type default)
			)
			(layer "B.Fab")
		)
		(fp_line
			(start 0.12065 0.2794)
			(end 0.12065 0.3048)
			(stroke
				(width 0.1)
				(type default)
			)
			(layer "B.Fab")
		)
		(fp_line
			(start -0.120396 0.2794)
			(end 0.12065 0.2794)
			(stroke
				(width 0.1)
				(type default)
			)
			(layer "B.Fab")
		)
		(fp_line
			(start 0.67945 0.3048)
			(end 0.67945 -0.305054)
			(stroke
				(width 0.1)
				(type default)
			)
			(layer "B.Fab")
		)
		(fp_line
			(start 0.12065 0.3048)
			(end 0.67945 0.3048)
			(stroke
				(width 0.1)
				(type default)
			)
			(layer "B.Fab")
		)
		(fp_line
			(start -0.120396 0.3048)
			(end -0.120396 0.2794)
			(stroke
				(width 0.1)
				(type default)
			)
			(layer "B.Fab")
		)
		(fp_line
			(start -0.67945 0.3048)
			(end -0.120396 0.3048)
			(stroke
				(width 0.1)
				(type default)
			)
			(layer "B.Fab")
		)
		(pad "1" smd circle
			(at 0.40005 0 270)
			(size 0 0)
			(layers "B.Cu" "B.Mask" "B.Paste")
			(net "P3V3_AUX")
		)
		(pad "2" smd circle
			(at -0.40005 0 270)
			(size 0 0)
			(layers "B.Cu" "B.Mask" "B.Paste")
			(net "GND")
		)
	)
	(footprint ""
		(layer "B.Cu")
		(at 22.143974 -168.768522)
		(property "Reference" "R503"
			(at 0 0 0)
			(layer "B.SilkS")
			(hide yes)
			(effects
				(font
					(size 1.27 1.27)
				)
				(justify mirror)
			)
		)
		(property "Value" ""
			(at 0 0 0)
			(layer "B.Fab")
			(effects
				(font
					(size 1.27 1.27)
				)
				(justify mirror)
			)
		)
		(duplicate_pad_numbers_are_jumpers no)
		(fp_line
			(start -0.7874 -0.4064)
			(end -0.7874 0.4064)
			(stroke
				(width 0.1524)
				(type default)
			)
			(layer "B.SilkS")
		)
		(fp_line
			(start -0.7874 0.4064)
			(end 0.7874 0.4064)
			(stroke
				(width 0.1524)
				(type default)
			)
			(layer "B.SilkS")
		)
		(fp_line
			(start 0.7874 -0.4064)
			(end -0.7874 -0.4064)
			(stroke
				(width 0.1524)
				(type default)
			)
			(layer "B.SilkS")
		)
		(fp_line
			(start 0.7874 0.4064)
			(end 0.7874 -0.4064)
			(stroke
				(width 0.1524)
				(type default)
			)
			(layer "B.SilkS")
		)
		(fp_line
			(start -0.67945 -0.3048)
			(end -0.67945 0.3048)
			(stroke
				(width 0.1)
				(type default)
			)
			(layer "B.Fab")
		)
		(fp_line
			(start -0.67945 0.3048)
			(end -0.120396 0.3048)
			(stroke
				(width 0.1)
				(type default)
			)
			(layer "B.Fab")
		)
		(fp_line
			(start -0.12065 -0.3048)
			(end -0.67945 -0.3048)
			(stroke
				(width 0.1)
				(type default)
			)
			(layer "B.Fab")
		)
		(fp_line
			(start -0.12065 -0.2794)
			(end -0.12065 -0.3048)
			(stroke
				(width 0.1)
				(type default)
			)
			(layer "B.Fab")
		)
		(fp_line
			(start -0.120396 0.2794)
			(end 0.12065 0.2794)
			(stroke
				(width 0.1)
				(type default)
			)
			(layer "B.Fab")
		)
		(fp_line
			(start -0.120396 0.3048)
			(end -0.120396 0.2794)
			(stroke
				(width 0.1)
				(type default)
			)
			(layer "B.Fab")
		)
		(fp_line
			(start 0.12065 -0.305054)
			(end 0.12065 -0.2794)
			(stroke
				(width 0.1)
				(type default)
			)
			(layer "B.Fab")
		)
		(fp_line
			(start 0.12065 -0.2794)
			(end -0.12065 -0.2794)
			(stroke
				(width 0.1)
				(type default)
			)
			(layer "B.Fab")
		)
		(fp_line
			(start 0.12065 0.2794)
			(end 0.12065 0.3048)
			(stroke
				(width 0.1)
				(type default)
			)
			(layer "B.Fab")
		)
		(fp_line
			(start 0.12065 0.3048)
			(end 0.67945 0.3048)
			(stroke
				(width 0.1)
				(type default)
			)
			(layer "B.Fab")
		)
		(fp_line
			(start 0.67945 -0.305054)
			(end 0.12065 -0.305054)
			(stroke
				(width 0.1)
				(type default)
			)
			(layer "B.Fab")
		)
		(fp_line
			(start 0.67945 0.3048)
			(end 0.67945 -0.305054)
			(stroke
				(width 0.1)
				(type default)
			)
			(layer "B.Fab")
		)
		(pad "1" smd circle
			(at 0.40005 0 180)
			(size 0 0)
			(layers "B.Cu" "B.Mask" "B.Paste")
			(net "PWRGD_P12V_AUX_R")
		)
		(pad "2" smd circle
			(at -0.40005 0 180)
			(size 0 0)
			(layers "B.Cu" "B.Mask" "B.Paste")
			(net "P5V_AUX_EN")
		)
	)
	(footprint ""
		(layer "B.Cu")
		(at 242.447318 -266.794996 180)
		(property "Reference" "L115"
			(at 0 0 0)
			(layer "B.SilkS")
			(hide yes)
			(effects
				(font
					(size 1.27 1.27)
				)
				(justify mirror)
			)
		)
		(property "Value" ""
			(at 0 0 0)
			(layer "B.Fab")
			(effects
				(font
					(size 1.27 1.27)
				)
				(justify mirror)
			)
		)
		(duplicate_pad_numbers_are_jumpers no)
		(fp_line
			(start 2.248154 4.9911)
			(end -2.248154 4.9911)
			(stroke
				(width 0.1524)
				(type default)
			)
			(layer "B.SilkS")
		)
		(fp_line
			(start 2.248154 1.973326)
			(end 2.248154 4.9911)
			(stroke
				(width 0.1524)
				(type default)
			)
			(layer "B.SilkS")
		)
		(fp_line
			(start 2.248154 -4.9911)
			(end 2.248154 -1.990598)
			(stroke
				(width 0.1524)
				(type default)
			)
			(layer "B.SilkS")
		)
		(fp_line
			(start -2.248154 4.9911)
			(end -2.248154 1.973326)
			(stroke
				(width 0.1524)
				(type default)
			)
			(layer "B.SilkS")
		)
		(fp_line
			(start -2.248154 -1.990598)
			(end -2.248154 -4.9911)
			(stroke
				(width 0.1524)
				(type default)
			)
			(layer "B.SilkS")
		)
		(fp_line
			(start -2.248154 -4.9911)
			(end 2.248154 -4.9911)
			(stroke
				(width 0.1524)
				(type default)
			)
			(layer "B.SilkS")
		)
		(fp_line
			(start 1.700022 0.899922)
			(end -1.700022 0.899922)
			(stroke
				(width 0.1)
				(type default)
			)
			(layer "B.Fab")
		)
		(fp_line
			(start 1.700022 -0.899922)
			(end 1.700022 0.899922)
			(stroke
				(width 0.1)
				(type default)
			)
			(layer "B.Fab")
		)
		(fp_line
			(start -1.700022 0.899922)
			(end -1.700022 -0.899922)
			(stroke
				(width 0.1)
				(type default)
			)
			(layer "B.Fab")
		)
		(fp_line
			(start -1.700022 -0.899922)
			(end 1.700022 -0.899922)
			(stroke
				(width 0.1)
				(type default)
			)
			(layer "B.Fab")
		)
		(pad "1" smd rect
			(at 1.575054 0)
			(size 1.1684 9.8044)
			(layers "B.Cu" "B.Mask" "B.Paste")
			(net "P1V25_PEX2")
		)
		(pad "2" smd rect
			(at -1.575054 0)
			(size 1.1684 9.8044)
			(layers "B.Cu" "B.Mask" "B.Paste")
			(net "P1V25_SERDES_VDDPLL_PEX2")
		)
	)
	(footprint ""
		(layer "B.Cu")
		(at 47.77486 -296.64152 -90)
		(property "Reference" "C3041"
			(at 0 0 90)
			(layer "B.SilkS")
			(hide yes)
			(effects
				(font
					(size 1.27 1.27)
				)
				(justify mirror)
			)
		)
		(property "Value" ""
			(at 0 0 90)
			(layer "B.Fab")
			(effects
				(font
					(size 1.27 1.27)
				)
				(justify mirror)
			)
		)
		(duplicate_pad_numbers_are_jumpers no)
		(fp_line
			(start -0.299974 0.150114)
			(end 0.299974 0.150114)
			(stroke
				(width 0.1)
				(type default)
			)
			(layer "B.Fab")
		)
		(fp_line
			(start 0.299974 0.150114)
			(end 0.299974 -0.150114)
			(stroke
				(width 0.1)
				(type default)
			)
			(layer "B.Fab")
		)
		(fp_line
			(start -0.299974 -0.150114)
			(end -0.299974 0.150114)
			(stroke
				(width 0.1)
				(type default)
			)
			(layer "B.Fab")
		)
		(fp_line
			(start 0.299974 -0.150114)
			(end -0.299974 -0.150114)
			(stroke
				(width 0.1)
				(type default)
			)
			(layer "B.Fab")
		)
		(pad "1" smd rect
			(at 0.2667 0 90)
			(size 0.3048 0.381)
			(layers "B.Cu" "B.Mask" "B.Paste")
			(net "PCEPLL3_VDDA18_PEX0")
		)
		(pad "2" smd rect
			(at -0.2667 0 90)
			(size 0.3048 0.381)
			(layers "B.Cu" "B.Mask" "B.Paste")
			(net "GND")
		)
	)
	(footprint ""
		(layer "B.Cu")
		(at 291.46119 -202.474068 180)
		(property "Reference" "R1043"
			(at 0 0 0)
			(layer "B.SilkS")
			(hide yes)
			(effects
				(font
					(size 1.27 1.27)
				)
				(justify mirror)
			)
		)
		(property "Value" ""
			(at 0 0 0)
			(layer "B.Fab")
			(effects
				(font
					(size 1.27 1.27)
				)
				(justify mirror)
			)
		)
		(duplicate_pad_numbers_are_jumpers no)
		(fp_line
			(start 0.7874 0.4064)
			(end 0.7874 -0.4064)
			(stroke
				(width 0.1524)
				(type default)
			)
			(layer "B.SilkS")
		)
		(fp_line
			(start 0.7874 -0.4064)
			(end -0.7874 -0.4064)
			(stroke
				(width 0.1524)
				(type default)
			)
			(layer "B.SilkS")
		)
		(fp_line
			(start -0.7874 0.4064)
			(end 0.7874 0.4064)
			(stroke
				(width 0.1524)
				(type default)
			)
			(layer "B.SilkS")
		)
		(fp_line
			(start -0.7874 -0.4064)
			(end -0.7874 0.4064)
			(stroke
				(width 0.1524)
				(type default)
			)
			(layer "B.SilkS")
		)
		(fp_line
			(start 0.67945 0.3048)
			(end 0.67945 -0.305054)
			(stroke
				(width 0.1)
				(type default)
			)
			(layer "B.Fab")
		)
		(fp_line
			(start 0.67945 -0.305054)
			(end 0.12065 -0.305054)
			(stroke
				(width 0.1)
				(type default)
			)
			(layer "B.Fab")
		)
		(fp_line
			(start 0.12065 0.3048)
			(end 0.67945 0.3048)
			(stroke
				(width 0.1)
				(type default)
			)
			(layer "B.Fab")
		)
		(fp_line
			(start 0.12065 0.2794)
			(end 0.12065 0.3048)
			(stroke
				(width 0.1)
				(type default)
			)
			(layer "B.Fab")
		)
		(fp_line
			(start 0.12065 -0.2794)
			(end -0.12065 -0.2794)
			(stroke
				(width 0.1)
				(type default)
			)
			(layer "B.Fab")
		)
		(fp_line
			(start 0.12065 -0.305054)
			(end 0.12065 -0.2794)
			(stroke
				(width 0.1)
				(type default)
			)
			(layer "B.Fab")
		)
		(fp_line
			(start -0.120396 0.3048)
			(end -0.120396 0.2794)
			(stroke
				(width 0.1)
				(type default)
			)
			(layer "B.Fab")
		)
		(fp_line
			(start -0.120396 0.2794)
			(end 0.12065 0.2794)
			(stroke
				(width 0.1)
				(type default)
			)
			(layer "B.Fab")
		)
		(fp_line
			(start -0.12065 -0.2794)
			(end -0.12065 -0.3048)
			(stroke
				(width 0.1)
				(type default)
			)
			(layer "B.Fab")
		)
		(fp_line
			(start -0.12065 -0.3048)
			(end -0.67945 -0.3048)
			(stroke
				(width 0.1)
				(type default)
			)
			(layer "B.Fab")
		)
		(fp_line
			(start -0.67945 0.3048)
			(end -0.120396 0.3048)
			(stroke
				(width 0.1)
				(type default)
			)
			(layer "B.Fab")
		)
		(fp_line
			(start -0.67945 -0.3048)
			(end -0.67945 0.3048)
			(stroke
				(width 0.1)
				(type default)
			)
			(layer "B.Fab")
		)
		(pad "1" smd circle
			(at 0.40005 0)
			(size 0 0)
			(layers "B.Cu" "B.Mask" "B.Paste")
			(net "GND")
		)
		(pad "2" smd circle
			(at -0.40005 0)
			(size 0 0)
			(layers "B.Cu" "B.Mask" "B.Paste")
			(net "SPI_BIC1_MOSI_LS23_DIR3")
		)
	)
	(footprint ""
		(layer "B.Cu")
		(at 52.049934 -288.299906 90)
		(property "Reference" "C2931"
			(at 0 0 90)
			(layer "B.SilkS")
			(hide yes)
			(effects
				(font
					(size 1.27 1.27)
				)
				(justify mirror)
			)
		)
		(property "Value" ""
			(at 0 0 90)
			(layer "B.Fab")
			(effects
				(font
					(size 1.27 1.27)
				)
				(justify mirror)
			)
		)
		(duplicate_pad_numbers_are_jumpers no)
		(fp_line
			(start 0.299974 -0.150114)
			(end -0.299974 -0.150114)
			(stroke
				(width 0.1)
				(type default)
			)
			(layer "B.Fab")
		)
		(fp_line
			(start -0.299974 -0.150114)
			(end -0.299974 0.150114)
			(stroke
				(width 0.1)
				(type default)
			)
			(layer "B.Fab")
		)
		(fp_line
			(start 0.299974 0.150114)
			(end 0.299974 -0.150114)
			(stroke
				(width 0.1)
				(type default)
			)
			(layer "B.Fab")
		)
		(fp_line
			(start -0.299974 0.150114)
			(end 0.299974 0.150114)
			(stroke
				(width 0.1)
				(type default)
			)
			(layer "B.Fab")
		)
		(pad "1" smd rect
			(at 0.2667 0 270)
			(size 0.3048 0.381)
			(layers "B.Cu" "B.Mask" "B.Paste")
			(net "P1V25_PEX0")
		)
		(pad "2" smd rect
			(at -0.2667 0 270)
			(size 0.3048 0.381)
			(layers "B.Cu" "B.Mask" "B.Paste")
			(net "GND")
		)
	)
	(footprint ""
		(layer "B.Cu")
		(at 179.55006 -292.099746 90)
		(property "Reference" "C1495"
			(at 0 0 90)
			(layer "B.SilkS")
			(hide yes)
			(effects
				(font
					(size 1.27 1.27)
				)
				(justify mirror)
			)
		)
		(property "Value" ""
			(at 0 0 90)
			(layer "B.Fab")
			(effects
				(font
					(size 1.27 1.27)
				)
				(justify mirror)
			)
		)
		(duplicate_pad_numbers_are_jumpers no)
		(fp_line
			(start 0.299974 -0.150114)
			(end -0.299974 -0.150114)
			(stroke
				(width 0.1)
				(type default)
			)
			(layer "B.Fab")
		)
		(fp_line
			(start -0.299974 -0.150114)
			(end -0.299974 0.150114)
			(stroke
				(width 0.1)
				(type default)
			)
			(layer "B.Fab")
		)
		(fp_line
			(start 0.299974 0.150114)
			(end 0.299974 -0.150114)
			(stroke
				(width 0.1)
				(type default)
			)
			(layer "B.Fab")
		)
		(fp_line
			(start -0.299974 0.150114)
			(end 0.299974 0.150114)
			(stroke
				(width 0.1)
				(type default)
			)
			(layer "B.Fab")
		)
		(pad "1" smd rect
			(at 0.2667 0 270)
			(size 0.3048 0.381)
			(layers "B.Cu" "B.Mask" "B.Paste")
			(net "P0V8_SERDES_VDDA_PEX1")
		)
		(pad "2" smd rect
			(at -0.2667 0 270)
			(size 0.3048 0.381)
			(layers "B.Cu" "B.Mask" "B.Paste")
			(net "GND")
		)
	)
	(footprint ""
		(layer "B.Cu")
		(at 408.75204 -296.3926 180)
		(property "Reference" "C1876"
			(at 0 0 0)
			(layer "B.SilkS")
			(hide yes)
			(effects
				(font
					(size 1.27 1.27)
				)
				(justify mirror)
			)
		)
		(property "Value" ""
			(at 0 0 0)
			(layer "B.Fab")
			(effects
				(font
					(size 1.27 1.27)
				)
				(justify mirror)
			)
		)
		(duplicate_pad_numbers_are_jumpers no)
		(fp_line
			(start 0.299974 0.150114)
			(end 0.299974 -0.150114)
			(stroke
				(width 0.1)
				(type default)
			)
			(layer "B.Fab")
		)
		(fp_line
			(start 0.299974 -0.150114)
			(end -0.299974 -0.150114)
			(stroke
				(width 0.1)
				(type default)
			)
			(layer "B.Fab")
		)
		(fp_line
			(start -0.299974 0.150114)
			(end 0.299974 0.150114)
			(stroke
				(width 0.1)
				(type default)
			)
			(layer "B.Fab")
		)
		(fp_line
			(start -0.299974 -0.150114)
			(end -0.299974 0.150114)
			(stroke
				(width 0.1)
				(type default)
			)
			(layer "B.Fab")
		)
		(pad "1" smd rect
			(at 0.2667 0)
			(size 0.3048 0.381)
			(layers "B.Cu" "B.Mask" "B.Paste")
			(net "P0V8_PEX3")
		)
		(pad "2" smd rect
			(at -0.2667 0)
			(size 0.3048 0.381)
			(layers "B.Cu" "B.Mask" "B.Paste")
			(net "GND")
		)
	)
	(footprint ""
		(layer "B.Cu")
		(at 183.3499 -303.499774 -90)
		(property "Reference" "C3112"
			(at 0 0 90)
			(layer "B.SilkS")
			(hide yes)
			(effects
				(font
					(size 1.27 1.27)
				)
				(justify mirror)
			)
		)
		(property "Value" ""
			(at 0 0 90)
			(layer "B.Fab")
			(effects
				(font
					(size 1.27 1.27)
				)
				(justify mirror)
			)
		)
		(duplicate_pad_numbers_are_jumpers no)
		(fp_line
			(start -0.299974 0.150114)
			(end 0.299974 0.150114)
			(stroke
				(width 0.1)
				(type default)
			)
			(layer "B.Fab")
		)
		(fp_line
			(start 0.299974 0.150114)
			(end 0.299974 -0.150114)
			(stroke
				(width 0.1)
				(type default)
			)
			(layer "B.Fab")
		)
		(fp_line
			(start -0.299974 -0.150114)
			(end -0.299974 0.150114)
			(stroke
				(width 0.1)
				(type default)
			)
			(layer "B.Fab")
		)
		(fp_line
			(start 0.299974 -0.150114)
			(end -0.299974 -0.150114)
			(stroke
				(width 0.1)
				(type default)
			)
			(layer "B.Fab")
		)
		(pad "1" smd rect
			(at 0.2667 0 90)
			(size 0.3048 0.381)
			(layers "B.Cu" "B.Mask" "B.Paste")
			(net "P1V25_PEX1")
		)
		(pad "2" smd rect
			(at -0.2667 0 90)
			(size 0.3048 0.381)
			(layers "B.Cu" "B.Mask" "B.Paste")
			(net "GND")
		)
	)
	(footprint ""
		(layer "B.Cu")
		(at 231.81691 -90.197178 90)
		(property "Reference" "C2618"
			(at 0 0 90)
			(layer "B.SilkS")
			(hide yes)
			(effects
				(font
					(size 1.27 1.27)
				)
				(justify mirror)
			)
		)
		(property "Value" ""
			(at 0 0 90)
			(layer "B.Fab")
			(effects
				(font
					(size 1.27 1.27)
				)
				(justify mirror)
			)
		)
		(duplicate_pad_numbers_are_jumpers no)
		(fp_line
			(start 0.7874 -0.4064)
			(end -0.7874 -0.4064)
			(stroke
				(width 0.1524)
				(type default)
			)
			(layer "B.SilkS")
		)
		(fp_line
			(start -0.7874 -0.4064)
			(end -0.7874 0.4064)
			(stroke
				(width 0.1524)
				(type default)
			)
			(layer "B.SilkS")
		)
		(fp_line
			(start 0.7874 0.4064)
			(end 0.7874 -0.4064)
			(stroke
				(width 0.1524)
				(type default)
			)
			(layer "B.SilkS")
		)
		(fp_line
			(start -0.7874 0.4064)
			(end 0.7874 0.4064)
			(stroke
				(width 0.1524)
				(type default)
			)
			(layer "B.SilkS")
		)
		(fp_line
			(start 0.67945 -0.305054)
			(end 0.12065 -0.305054)
			(stroke
				(width 0.1)
				(type default)
			)
			(layer "B.Fab")
		)
		(fp_line
			(start 0.12065 -0.305054)
			(end 0.12065 -0.2794)
			(stroke
				(width 0.1)
				(type default)
			)
			(layer "B.Fab")
		)
		(fp_line
			(start -0.12065 -0.3048)
			(end -0.67945 -0.3048)
			(stroke
				(width 0.1)
				(type default)
			)
			(layer "B.Fab")
		)
		(fp_line
			(start -0.67945 -0.3048)
			(end -0.67945 0.3048)
			(stroke
				(width 0.1)
				(type default)
			)
			(layer "B.Fab")
		)
		(fp_line
			(start 0.12065 -0.2794)
			(end -0.12065 -0.2794)
			(stroke
				(width 0.1)
				(type default)
			)
			(layer "B.Fab")
		)
		(fp_line
			(start -0.12065 -0.2794)
			(end -0.12065 -0.3048)
			(stroke
				(width 0.1)
				(type default)
			)
			(layer "B.Fab")
		)
		(fp_line
			(start 0.12065 0.2794)
			(end 0.12065 0.3048)
			(stroke
				(width 0.1)
				(type default)
			)
			(layer "B.Fab")
		)
		(fp_line
			(start -0.120396 0.2794)
			(end 0.12065 0.2794)
			(stroke
				(width 0.1)
				(type default)
			)
			(layer "B.Fab")
		)
		(fp_line
			(start 0.67945 0.3048)
			(end 0.67945 -0.305054)
			(stroke
				(width 0.1)
				(type default)
			)
			(layer "B.Fab")
		)
		(fp_line
			(start 0.12065 0.3048)
			(end 0.67945 0.3048)
			(stroke
				(width 0.1)
				(type default)
			)
			(layer "B.Fab")
		)
		(fp_line
			(start -0.120396 0.3048)
			(end -0.120396 0.2794)
			(stroke
				(width 0.1)
				(type default)
			)
			(layer "B.Fab")
		)
		(fp_line
			(start -0.67945 0.3048)
			(end -0.120396 0.3048)
			(stroke
				(width 0.1)
				(type default)
			)
			(layer "B.Fab")
		)
		(pad "1" smd circle
			(at 0.40005 0 270)
			(size 0 0)
			(layers "B.Cu" "B.Mask" "B.Paste")
			(net "P3V3_PEX_USB_HUB")
		)
		(pad "2" smd circle
			(at -0.40005 0 270)
			(size 0 0)
			(layers "B.Cu" "B.Mask" "B.Paste")
			(net "GND")
		)
	)
	(footprint ""
		(layer "B.Cu")
		(at 169.099992 -301.599854 -90)
		(property "Reference" "C1445"
			(at 0 0 90)
			(layer "B.SilkS")
			(hide yes)
			(effects
				(font
					(size 1.27 1.27)
				)
				(justify mirror)
			)
		)
		(property "Value" ""
			(at 0 0 90)
			(layer "B.Fab")
			(effects
				(font
					(size 1.27 1.27)
				)
				(justify mirror)
			)
		)
		(duplicate_pad_numbers_are_jumpers no)
		(fp_line
			(start -0.299974 0.150114)
			(end 0.299974 0.150114)
			(stroke
				(width 0.1)
				(type default)
			)
			(layer "B.Fab")
		)
		(fp_line
			(start 0.299974 0.150114)
			(end 0.299974 -0.150114)
			(stroke
				(width 0.1)
				(type default)
			)
			(layer "B.Fab")
		)
		(fp_line
			(start -0.299974 -0.150114)
			(end -0.299974 0.150114)
			(stroke
				(width 0.1)
				(type default)
			)
			(layer "B.Fab")
		)
		(fp_line
			(start 0.299974 -0.150114)
			(end -0.299974 -0.150114)
			(stroke
				(width 0.1)
				(type default)
			)
			(layer "B.Fab")
		)
		(pad "1" smd rect
			(at 0.2667 0 90)
			(size 0.3048 0.381)
			(layers "B.Cu" "B.Mask" "B.Paste")
			(net "P0V8_SERDES_VDDA_PEX1")
		)
		(pad "2" smd rect
			(at -0.2667 0 90)
			(size 0.3048 0.381)
			(layers "B.Cu" "B.Mask" "B.Paste")
			(net "GND")
		)
	)
	(footprint ""
		(layer "B.Cu")
		(at 53.949854 -292.099746 90)
		(property "Reference" "C1225"
			(at 0 0 90)
			(layer "B.SilkS")
			(hide yes)
			(effects
				(font
					(size 1.27 1.27)
				)
				(justify mirror)
			)
		)
		(property "Value" ""
			(at 0 0 90)
			(layer "B.Fab")
			(effects
				(font
					(size 1.27 1.27)
				)
				(justify mirror)
			)
		)
		(duplicate_pad_numbers_are_jumpers no)
		(fp_line
			(start 0.299974 -0.150114)
			(end -0.299974 -0.150114)
			(stroke
				(width 0.1)
				(type default)
			)
			(layer "B.Fab")
		)
		(fp_line
			(start -0.299974 -0.150114)
			(end -0.299974 0.150114)
			(stroke
				(width 0.1)
				(type default)
			)
			(layer "B.Fab")
		)
		(fp_line
			(start 0.299974 0.150114)
			(end 0.299974 -0.150114)
			(stroke
				(width 0.1)
				(type default)
			)
			(layer "B.Fab")
		)
		(fp_line
			(start -0.299974 0.150114)
			(end 0.299974 0.150114)
			(stroke
				(width 0.1)
				(type default)
			)
			(layer "B.Fab")
		)
		(pad "1" smd rect
			(at 0.2667 0 270)
			(size 0.3048 0.381)
			(layers "B.Cu" "B.Mask" "B.Paste")
			(net "P0V8_SERDES_VDDA_PEX0")
		)
		(pad "2" smd rect
			(at -0.2667 0 270)
			(size 0.3048 0.381)
			(layers "B.Cu" "B.Mask" "B.Paste")
			(net "GND")
		)
	)
	(footprint ""
		(layer "B.Cu")
		(at 302.78959 -245.912386 -90)
		(property "Reference" "U318"
			(at 2.108708 2.230628 270)
			(unlocked yes)
			(layer "B.SilkS")
			(effects
				(font
					(size 0.7874 0.5842)
					(thickness 0.1524)
				)
				(justify mirror)
			)
		)
		(property "Value" ""
			(at 0 0 90)
			(layer "B.Fab")
			(effects
				(font
					(size 1.27 1.27)
				)
				(justify mirror)
			)
		)
		(duplicate_pad_numbers_are_jumpers no)
		(fp_line
			(start -1.463548 1.549908)
			(end 1.463548 1.549908)
			(stroke
				(width 0.1524)
				(type default)
			)
			(layer "B.SilkS")
		)
		(fp_line
			(start 1.463548 1.549908)
			(end 1.463548 -1.549908)
			(stroke
				(width 0.1524)
				(type default)
			)
			(layer "B.SilkS")
		)
		(fp_line
			(start 0 -0.762)
			(end -0.762 -1.549908)
			(stroke
				(width 0.1524)
				(type default)
			)
			(layer "B.SilkS")
		)
		(fp_line
			(start -1.463548 -1.549908)
			(end -1.463548 1.549908)
			(stroke
				(width 0.1524)
				(type default)
			)
			(layer "B.SilkS")
		)
		(fp_line
			(start -0.762 -1.549908)
			(end -1.463548 -1.549908)
			(stroke
				(width 0.1524)
				(type default)
			)
			(layer "B.SilkS")
		)
		(fp_line
			(start 0.787908 -1.549908)
			(end 0 -0.762)
			(stroke
				(width 0.1524)
				(type default)
			)
			(layer "B.SilkS")
		)
		(fp_line
			(start 1.463548 -1.549908)
			(end 0.787908 -1.549908)
			(stroke
				(width 0.1524)
				(type default)
			)
			(layer "B.SilkS")
		)
		(fp_poly
			(pts
				(xy 3.712718 -0.616204) (xy 3.055366 -0.835406) (xy 3.274568 -0.178054)
			)
			(stroke
				(width 0)
				(type default)
			)
			(fill yes)
			(layer "B.SilkS")
		)
		(fp_line
			(start -1.549908 1.549908)
			(end 1.549908 1.549908)
			(stroke
				(width 0.1)
				(type default)
			)
			(layer "B.Fab")
		)
		(fp_line
			(start 1.549908 1.549908)
			(end 1.549908 -1.549908)
			(stroke
				(width 0.1)
				(type default)
			)
			(layer "B.Fab")
		)
		(fp_line
			(start -1.549908 -1.549908)
			(end -1.549908 1.549908)
			(stroke
				(width 0.1)
				(type default)
			)
			(layer "B.Fab")
		)
		(fp_line
			(start 1.549908 -1.549908)
			(end -1.549908 -1.549908)
			(stroke
				(width 0.1)
				(type default)
			)
			(layer "B.Fab")
		)
		(fp_poly
			(pts
				(xy 3.4798 -1.359916) (xy 2.86004 -1.050036) (xy 3.4798 -0.740156)
			)
			(stroke
				(width 0)
				(type default)
			)
			(fill yes)
			(layer "B.Fab")
		)
		(pad "1" smd rect
			(at 2.175002 -1.050036)
			(size 0.6096 1.1684)
			(layers "B.Cu" "B.Mask" "B.Paste")
			(net "P3V3_AUX")
		)
		(pad "2" smd rect
			(at 2.175002 -0.32512)
			(size 0.4318 1.1684)
			(layers "B.Cu" "B.Mask" "B.Paste")
			(net "SMB_MB_BMC_ISO_SCL")
		)
		(pad "3" smd rect
			(at 2.175002 0.32512)
			(size 0.4318 1.1684)
			(layers "B.Cu" "B.Mask" "B.Paste")
			(net "SMB_MB_BMC_ISO_SDA")
		)
		(pad "4" smd rect
			(at 2.175002 1.050036)
			(size 0.6096 1.1684)
			(layers "B.Cu" "B.Mask" "B.Paste")
			(net "GND")
		)
		(pad "5" smd rect
			(at -2.175002 1.050036)
			(size 0.6096 1.1684)
			(layers "B.Cu" "B.Mask" "B.Paste")
			(net "MB_I2C_ISO_EN")
		)
		(pad "6" smd rect
			(at -2.175002 0.32512)
			(size 0.4318 1.1684)
			(layers "B.Cu" "B.Mask" "B.Paste")
			(net "SMB_MB_BMC_R_SDA")
		)
		(pad "7" smd rect
			(at -2.175002 -0.32512)
			(size 0.4318 1.1684)
			(layers "B.Cu" "B.Mask" "B.Paste")
			(net "SMB_MB_BMC_R_SCL")
		)
		(pad "8" smd rect
			(at -2.175002 -1.050036)
			(size 0.6096 1.1684)
			(layers "B.Cu" "B.Mask" "B.Paste")
			(net "P3V3_AUX")
		)
	)
	(footprint ""
		(layer "B.Cu")
		(at 289.94989 -288.299906 90)
		(property "Reference" "C3268"
			(at 0 0 90)
			(layer "B.SilkS")
			(hide yes)
			(effects
				(font
					(size 1.27 1.27)
				)
				(justify mirror)
			)
		)
		(property "Value" ""
			(at 0 0 90)
			(layer "B.Fab")
			(effects
				(font
					(size 1.27 1.27)
				)
				(justify mirror)
			)
		)
		(duplicate_pad_numbers_are_jumpers no)
		(fp_line
			(start 0.299974 -0.150114)
			(end -0.299974 -0.150114)
			(stroke
				(width 0.1)
				(type default)
			)
			(layer "B.Fab")
		)
		(fp_line
			(start -0.299974 -0.150114)
			(end -0.299974 0.150114)
			(stroke
				(width 0.1)
				(type default)
			)
			(layer "B.Fab")
		)
		(fp_line
			(start 0.299974 0.150114)
			(end 0.299974 -0.150114)
			(stroke
				(width 0.1)
				(type default)
			)
			(layer "B.Fab")
		)
		(fp_line
			(start -0.299974 0.150114)
			(end 0.299974 0.150114)
			(stroke
				(width 0.1)
				(type default)
			)
			(layer "B.Fab")
		)
		(pad "1" smd rect
			(at 0.2667 0 270)
			(size 0.3048 0.381)
			(layers "B.Cu" "B.Mask" "B.Paste")
			(net "P1V25_PEX2")
		)
		(pad "2" smd rect
			(at -0.2667 0 270)
			(size 0.3048 0.381)
			(layers "B.Cu" "B.Mask" "B.Paste")
			(net "GND")
		)
	)
	(footprint ""
		(layer "B.Cu")
		(at 407.020268 -296.37482)
		(property "Reference" "C1877"
			(at 0 0 0)
			(layer "B.SilkS")
			(hide yes)
			(effects
				(font
					(size 1.27 1.27)
				)
				(justify mirror)
			)
		)
		(property "Value" ""
			(at 0 0 0)
			(layer "B.Fab")
			(effects
				(font
					(size 1.27 1.27)
				)
				(justify mirror)
			)
		)
		(duplicate_pad_numbers_are_jumpers no)
		(fp_line
			(start -0.299974 -0.150114)
			(end -0.299974 0.150114)
			(stroke
				(width 0.1)
				(type default)
			)
			(layer "B.Fab")
		)
		(fp_line
			(start -0.299974 0.150114)
			(end 0.299974 0.150114)
			(stroke
				(width 0.1)
				(type default)
			)
			(layer "B.Fab")
		)
		(fp_line
			(start 0.299974 -0.150114)
			(end -0.299974 -0.150114)
			(stroke
				(width 0.1)
				(type default)
			)
			(layer "B.Fab")
		)
		(fp_line
			(start 0.299974 0.150114)
			(end 0.299974 -0.150114)
			(stroke
				(width 0.1)
				(type default)
			)
			(layer "B.Fab")
		)
		(pad "1" smd rect
			(at 0.2667 0 180)
			(size 0.3048 0.381)
			(layers "B.Cu" "B.Mask" "B.Paste")
			(net "P0V8_PEX3")
		)
		(pad "2" smd rect
			(at -0.2667 0 180)
			(size 0.3048 0.381)
			(layers "B.Cu" "B.Mask" "B.Paste")
			(net "GND")
		)
	)
	(footprint ""
		(layer "B.Cu")
		(at 101.408484 -308.436772 90)
		(property "Reference" "C4195"
			(at 0 0 90)
			(layer "B.SilkS")
			(hide yes)
			(effects
				(font
					(size 1.27 1.27)
				)
				(justify mirror)
			)
		)
		(property "Value" ""
			(at 0 0 90)
			(layer "B.Fab")
			(effects
				(font
					(size 1.27 1.27)
				)
				(justify mirror)
			)
		)
		(duplicate_pad_numbers_are_jumpers no)
		(fp_line
			(start 0.299974 -0.150114)
			(end -0.299974 -0.150114)
			(stroke
				(width 0.1)
				(type default)
			)
			(layer "B.Fab")
		)
		(fp_line
			(start -0.299974 -0.150114)
			(end -0.299974 0.150114)
			(stroke
				(width 0.1)
				(type default)
			)
			(layer "B.Fab")
		)
		(fp_line
			(start 0.299974 0.150114)
			(end 0.299974 -0.150114)
			(stroke
				(width 0.1)
				(type default)
			)
			(layer "B.Fab")
		)
		(fp_line
			(start -0.299974 0.150114)
			(end 0.299974 0.150114)
			(stroke
				(width 0.1)
				(type default)
			)
			(layer "B.Fab")
		)
		(pad "1" smd rect
			(at 0.2667 0 270)
			(size 0.3048 0.381)
			(layers "B.Cu" "B.Mask" "B.Paste")
			(net "P0V8_PEX0")
		)
		(pad "2" smd rect
			(at -0.2667 0 270)
			(size 0.3048 0.381)
			(layers "B.Cu" "B.Mask" "B.Paste")
			(net "GND")
		)
	)
	(footprint ""
		(layer "B.Cu")
		(at 118.61165 -321.396106 -90)
		(property "Reference" "R6483"
			(at 0 0 90)
			(layer "B.SilkS")
			(hide yes)
			(effects
				(font
					(size 1.27 1.27)
				)
				(justify mirror)
			)
		)
		(property "Value" ""
			(at 0 0 90)
			(layer "B.Fab")
			(effects
				(font
					(size 1.27 1.27)
				)
				(justify mirror)
			)
		)
		(duplicate_pad_numbers_are_jumpers no)
		(fp_line
			(start -0.7874 0.4064)
			(end 0.7874 0.4064)
			(stroke
				(width 0.1524)
				(type default)
			)
			(layer "B.SilkS")
		)
		(fp_line
			(start 0.7874 0.4064)
			(end 0.7874 -0.4064)
			(stroke
				(width 0.1524)
				(type default)
			)
			(layer "B.SilkS")
		)
		(fp_line
			(start -0.7874 -0.4064)
			(end -0.7874 0.4064)
			(stroke
				(width 0.1524)
				(type default)
			)
			(layer "B.SilkS")
		)
		(fp_line
			(start 0.7874 -0.4064)
			(end -0.7874 -0.4064)
			(stroke
				(width 0.1524)
				(type default)
			)
			(layer "B.SilkS")
		)
		(fp_line
			(start -0.67945 0.3048)
			(end -0.120396 0.3048)
			(stroke
				(width 0.1)
				(type default)
			)
			(layer "B.Fab")
		)
		(fp_line
			(start -0.120396 0.3048)
			(end -0.120396 0.2794)
			(stroke
				(width 0.1)
				(type default)
			)
			(layer "B.Fab")
		)
		(fp_line
			(start 0.12065 0.3048)
			(end 0.67945 0.3048)
			(stroke
				(width 0.1)
				(type default)
			)
			(layer "B.Fab")
		)
		(fp_line
			(start 0.67945 0.3048)
			(end 0.67945 -0.305054)
			(stroke
				(width 0.1)
				(type default)
			)
			(layer "B.Fab")
		)
		(fp_line
			(start -0.120396 0.2794)
			(end 0.12065 0.2794)
			(stroke
				(width 0.1)
				(type default)
			)
			(layer "B.Fab")
		)
		(fp_line
			(start 0.12065 0.2794)
			(end 0.12065 0.3048)
			(stroke
				(width 0.1)
				(type default)
			)
			(layer "B.Fab")
		)
		(fp_line
			(start -0.12065 -0.2794)
			(end -0.12065 -0.3048)
			(stroke
				(width 0.1)
				(type default)
			)
			(layer "B.Fab")
		)
		(fp_line
			(start 0.12065 -0.2794)
			(end -0.12065 -0.2794)
			(stroke
				(width 0.1)
				(type default)
			)
			(layer "B.Fab")
		)
		(fp_line
			(start -0.67945 -0.3048)
			(end -0.67945 0.3048)
			(stroke
				(width 0.1)
				(type default)
			)
			(layer "B.Fab")
		)
		(fp_line
			(start -0.12065 -0.3048)
			(end -0.67945 -0.3048)
			(stroke
				(width 0.1)
				(type default)
			)
			(layer "B.Fab")
		)
		(fp_line
			(start 0.12065 -0.305054)
			(end 0.12065 -0.2794)
			(stroke
				(width 0.1)
				(type default)
			)
			(layer "B.Fab")
		)
		(fp_line
			(start 0.67945 -0.305054)
			(end 0.12065 -0.305054)
			(stroke
				(width 0.1)
				(type default)
			)
			(layer "B.Fab")
		)
		(pad "1" smd circle
			(at 0.40005 0 90)
			(size 0 0)
			(layers "B.Cu" "B.Mask" "B.Paste")
			(net "P0V8_SERDES_VDDA_PEX1")
		)
		(pad "2" smd circle
			(at -0.40005 0 90)
			(size 0 0)
			(layers "B.Cu" "B.Mask" "B.Paste")
			(net "P0V8_SERDES_VDDA_PEX1_C6")
		)
	)
	(footprint ""
		(layer "B.Cu")
		(at 177.649886 -299.699934 -90)
		(property "Reference" "C1474"
			(at 0 0 90)
			(layer "B.SilkS")
			(hide yes)
			(effects
				(font
					(size 1.27 1.27)
				)
				(justify mirror)
			)
		)
		(property "Value" ""
			(at 0 0 90)
			(layer "B.Fab")
			(effects
				(font
					(size 1.27 1.27)
				)
				(justify mirror)
			)
		)
		(duplicate_pad_numbers_are_jumpers no)
		(fp_line
			(start -0.299974 0.150114)
			(end 0.299974 0.150114)
			(stroke
				(width 0.1)
				(type default)
			)
			(layer "B.Fab")
		)
		(fp_line
			(start 0.299974 0.150114)
			(end 0.299974 -0.150114)
			(stroke
				(width 0.1)
				(type default)
			)
			(layer "B.Fab")
		)
		(fp_line
			(start -0.299974 -0.150114)
			(end -0.299974 0.150114)
			(stroke
				(width 0.1)
				(type default)
			)
			(layer "B.Fab")
		)
		(fp_line
			(start 0.299974 -0.150114)
			(end -0.299974 -0.150114)
			(stroke
				(width 0.1)
				(type default)
			)
			(layer "B.Fab")
		)
		(pad "1" smd rect
			(at 0.2667 0 90)
			(size 0.3048 0.381)
			(layers "B.Cu" "B.Mask" "B.Paste")
			(net "P0V8_SERDES_VDDA_PEX1")
		)
		(pad "2" smd rect
			(at -0.2667 0 90)
			(size 0.3048 0.381)
			(layers "B.Cu" "B.Mask" "B.Paste")
			(net "GND")
		)
	)
	(footprint ""
		(layer "B.Cu")
		(at 55.374794 -293.99992 -90)
		(property "Reference" "C1147"
			(at 0 0 90)
			(layer "B.SilkS")
			(hide yes)
			(effects
				(font
					(size 1.27 1.27)
				)
				(justify mirror)
			)
		)
		(property "Value" ""
			(at 0 0 90)
			(layer "B.Fab")
			(effects
				(font
					(size 1.27 1.27)
				)
				(justify mirror)
			)
		)
		(duplicate_pad_numbers_are_jumpers no)
		(fp_line
			(start -0.299974 0.150114)
			(end 0.299974 0.150114)
			(stroke
				(width 0.1)
				(type default)
			)
			(layer "B.Fab")
		)
		(fp_line
			(start 0.299974 0.150114)
			(end 0.299974 -0.150114)
			(stroke
				(width 0.1)
				(type default)
			)
			(layer "B.Fab")
		)
		(fp_line
			(start -0.299974 -0.150114)
			(end -0.299974 0.150114)
			(stroke
				(width 0.1)
				(type default)
			)
			(layer "B.Fab")
		)
		(fp_line
			(start 0.299974 -0.150114)
			(end -0.299974 -0.150114)
			(stroke
				(width 0.1)
				(type default)
			)
			(layer "B.Fab")
		)
		(pad "1" smd rect
			(at 0.2667 0 90)
			(size 0.3048 0.381)
			(layers "B.Cu" "B.Mask" "B.Paste")
			(net "P0V8_PEX0")
		)
		(pad "2" smd rect
			(at -0.2667 0 90)
			(size 0.3048 0.381)
			(layers "B.Cu" "B.Mask" "B.Paste")
			(net "GND")
		)
	)
	(footprint ""
		(layer "B.Cu")
		(at 9.292844 -276.029928 180)
		(property "Reference" "C4218"
			(at 0 0 0)
			(layer "B.SilkS")
			(hide yes)
			(effects
				(font
					(size 1.27 1.27)
				)
				(justify mirror)
			)
		)
		(property "Value" ""
			(at 0 0 0)
			(layer "B.Fab")
			(effects
				(font
					(size 1.27 1.27)
				)
				(justify mirror)
			)
		)
		(duplicate_pad_numbers_are_jumpers no)
		(fp_line
			(start 1.2954 0.5842)
			(end 1.2954 -0.5842)
			(stroke
				(width 0.1524)
				(type default)
			)
			(layer "B.SilkS")
		)
		(fp_line
			(start 1.2954 -0.5842)
			(end -1.2954 -0.5842)
			(stroke
				(width 0.1524)
				(type default)
			)
			(layer "B.SilkS")
		)
		(fp_line
			(start -1.2954 0.5842)
			(end 1.2954 0.5842)
			(stroke
				(width 0.1524)
				(type default)
			)
			(layer "B.SilkS")
		)
		(fp_line
			(start -1.2954 -0.5842)
			(end -1.2954 0.5842)
			(stroke
				(width 0.1524)
				(type default)
			)
			(layer "B.SilkS")
		)
		(fp_line
			(start 1.1938 0.4064)
			(end 1.1938 -0.4064)
			(stroke
				(width 0.1)
				(type default)
			)
			(layer "B.Fab")
		)
		(fp_line
			(start 1.1938 -0.4064)
			(end 0.8636 -0.4064)
			(stroke
				(width 0.1)
				(type default)
			)
			(layer "B.Fab")
		)
		(fp_line
			(start 0.8636 0.4572)
			(end 0.8636 0.4064)
			(stroke
				(width 0.1)
				(type default)
			)
			(layer "B.Fab")
		)
		(fp_line
			(start 0.8636 0.4064)
			(end 1.1938 0.4064)
			(stroke
				(width 0.1)
				(type default)
			)
			(layer "B.Fab")
		)
		(fp_line
			(start 0.8636 -0.4064)
			(end 0.8636 -0.4572)
			(stroke
				(width 0.1)
				(type default)
			)
			(layer "B.Fab")
		)
		(fp_line
			(start 0.8636 -0.4572)
			(end -0.8636 -0.4572)
			(stroke
				(width 0.1)
				(type default)
			)
			(layer "B.Fab")
		)
		(fp_line
			(start -0.8636 0.4572)
			(end 0.8636 0.4572)
			(stroke
				(width 0.1)
				(type default)
			)
			(layer "B.Fab")
		)
		(fp_line
			(start -0.8636 0.4064)
			(end -0.8636 0.4572)
			(stroke
				(width 0.1)
				(type default)
			)
			(layer "B.Fab")
		)
		(fp_line
			(start -0.8636 -0.4064)
			(end -1.1938 -0.4064)
			(stroke
				(width 0.1)
				(type default)
			)
			(layer "B.Fab")
		)
		(fp_line
			(start -0.8636 -0.4572)
			(end -0.8636 -0.4064)
			(stroke
				(width 0.1)
				(type default)
			)
			(layer "B.Fab")
		)
		(fp_line
			(start -1.1938 0.4064)
			(end -0.8636 0.4064)
			(stroke
				(width 0.1)
				(type default)
			)
			(layer "B.Fab")
		)
		(fp_line
			(start -1.1938 -0.4064)
			(end -1.1938 0.4064)
			(stroke
				(width 0.1)
				(type default)
			)
			(layer "B.Fab")
		)
		(pad "1" smd rect
			(at 0.7366 0 90)
			(size 0.7112 0.8128)
			(layers "B.Cu" "B.Mask" "B.Paste")
			(net "P1V25_PEX0")
		)
		(pad "2" smd rect
			(at -0.7366 0 90)
			(size 0.7112 0.8128)
			(layers "B.Cu" "B.Mask" "B.Paste")
			(net "GND")
		)
	)
	(footprint ""
		(layer "B.Cu")
		(at 365.087408 -282.173426 90)
		(property "Reference" "R6769"
			(at 0 0 90)
			(layer "B.SilkS")
			(hide yes)
			(effects
				(font
					(size 1.27 1.27)
				)
				(justify mirror)
			)
		)
		(property "Value" ""
			(at 0 0 90)
			(layer "B.Fab")
			(effects
				(font
					(size 1.27 1.27)
				)
				(justify mirror)
			)
		)
		(duplicate_pad_numbers_are_jumpers no)
		(fp_line
			(start 0.7874 -0.4064)
			(end -0.7874 -0.4064)
			(stroke
				(width 0.1524)
				(type default)
			)
			(layer "B.SilkS")
		)
		(fp_line
			(start -0.7874 -0.4064)
			(end -0.7874 0.4064)
			(stroke
				(width 0.1524)
				(type default)
			)
			(layer "B.SilkS")
		)
		(fp_line
			(start 0.7874 0.4064)
			(end 0.7874 -0.4064)
			(stroke
				(width 0.1524)
				(type default)
			)
			(layer "B.SilkS")
		)
		(fp_line
			(start -0.7874 0.4064)
			(end 0.7874 0.4064)
			(stroke
				(width 0.1524)
				(type default)
			)
			(layer "B.SilkS")
		)
		(fp_line
			(start 0.67945 -0.305054)
			(end 0.12065 -0.305054)
			(stroke
				(width 0.1)
				(type default)
			)
			(layer "B.Fab")
		)
		(fp_line
			(start 0.12065 -0.305054)
			(end 0.12065 -0.2794)
			(stroke
				(width 0.1)
				(type default)
			)
			(layer "B.Fab")
		)
		(fp_line
			(start -0.12065 -0.3048)
			(end -0.67945 -0.3048)
			(stroke
				(width 0.1)
				(type default)
			)
			(layer "B.Fab")
		)
		(fp_line
			(start -0.67945 -0.3048)
			(end -0.67945 0.3048)
			(stroke
				(width 0.1)
				(type default)
			)
			(layer "B.Fab")
		)
		(fp_line
			(start 0.12065 -0.2794)
			(end -0.12065 -0.2794)
			(stroke
				(width 0.1)
				(type default)
			)
			(layer "B.Fab")
		)
		(fp_line
			(start -0.12065 -0.2794)
			(end -0.12065 -0.3048)
			(stroke
				(width 0.1)
				(type default)
			)
			(layer "B.Fab")
		)
		(fp_line
			(start 0.12065 0.2794)
			(end 0.12065 0.3048)
			(stroke
				(width 0.1)
				(type default)
			)
			(layer "B.Fab")
		)
		(fp_line
			(start -0.120396 0.2794)
			(end 0.12065 0.2794)
			(stroke
				(width 0.1)
				(type default)
			)
			(layer "B.Fab")
		)
		(fp_line
			(start 0.67945 0.3048)
			(end 0.67945 -0.305054)
			(stroke
				(width 0.1)
				(type default)
			)
			(layer "B.Fab")
		)
		(fp_line
			(start 0.12065 0.3048)
			(end 0.67945 0.3048)
			(stroke
				(width 0.1)
				(type default)
			)
			(layer "B.Fab")
		)
		(fp_line
			(start -0.120396 0.3048)
			(end -0.120396 0.2794)
			(stroke
				(width 0.1)
				(type default)
			)
			(layer "B.Fab")
		)
		(fp_line
			(start -0.67945 0.3048)
			(end -0.120396 0.3048)
			(stroke
				(width 0.1)
				(type default)
			)
			(layer "B.Fab")
		)
		(pad "1" smd circle
			(at 0.40005 0 270)
			(size 0 0)
			(layers "B.Cu" "B.Mask" "B.Paste")
			(net "P0V8_PEX3_VCC2")
		)
		(pad "2" smd circle
			(at -0.40005 0 270)
			(size 0 0)
			(layers "B.Cu" "B.Mask" "B.Paste")
			(net "P0V8_PEX2_EN4")
		)
	)
	(footprint ""
		(layer "B.Cu")
		(at 70.104 -98.552)
		(property "Reference" "R74"
			(at 0 0 0)
			(layer "B.SilkS")
			(hide yes)
			(effects
				(font
					(size 1.27 1.27)
				)
				(justify mirror)
			)
		)
		(property "Value" ""
			(at 0 0 0)
			(layer "B.Fab")
			(effects
				(font
					(size 1.27 1.27)
				)
				(justify mirror)
			)
		)
		(duplicate_pad_numbers_are_jumpers no)
		(fp_line
			(start -0.7874 -0.4064)
			(end -0.7874 0.4064)
			(stroke
				(width 0.1524)
				(type default)
			)
			(layer "B.SilkS")
		)
		(fp_line
			(start -0.7874 0.4064)
			(end 0.7874 0.4064)
			(stroke
				(width 0.1524)
				(type default)
			)
			(layer "B.SilkS")
		)
		(fp_line
			(start 0.7874 -0.4064)
			(end -0.7874 -0.4064)
			(stroke
				(width 0.1524)
				(type default)
			)
			(layer "B.SilkS")
		)
		(fp_line
			(start 0.7874 0.4064)
			(end 0.7874 -0.4064)
			(stroke
				(width 0.1524)
				(type default)
			)
			(layer "B.SilkS")
		)
		(fp_line
			(start -0.67945 -0.3048)
			(end -0.67945 0.3048)
			(stroke
				(width 0.1)
				(type default)
			)
			(layer "B.Fab")
		)
		(fp_line
			(start -0.67945 0.3048)
			(end -0.120396 0.3048)
			(stroke
				(width 0.1)
				(type default)
			)
			(layer "B.Fab")
		)
		(fp_line
			(start -0.12065 -0.3048)
			(end -0.67945 -0.3048)
			(stroke
				(width 0.1)
				(type default)
			)
			(layer "B.Fab")
		)
		(fp_line
			(start -0.12065 -0.2794)
			(end -0.12065 -0.3048)
			(stroke
				(width 0.1)
				(type default)
			)
			(layer "B.Fab")
		)
		(fp_line
			(start -0.120396 0.2794)
			(end 0.12065 0.2794)
			(stroke
				(width 0.1)
				(type default)
			)
			(layer "B.Fab")
		)
		(fp_line
			(start -0.120396 0.3048)
			(end -0.120396 0.2794)
			(stroke
				(width 0.1)
				(type default)
			)
			(layer "B.Fab")
		)
		(fp_line
			(start 0.12065 -0.305054)
			(end 0.12065 -0.2794)
			(stroke
				(width 0.1)
				(type default)
			)
			(layer "B.Fab")
		)
		(fp_line
			(start 0.12065 -0.2794)
			(end -0.12065 -0.2794)
			(stroke
				(width 0.1)
				(type default)
			)
			(layer "B.Fab")
		)
		(fp_line
			(start 0.12065 0.2794)
			(end 0.12065 0.3048)
			(stroke
				(width 0.1)
				(type default)
			)
			(layer "B.Fab")
		)
		(fp_line
			(start 0.12065 0.3048)
			(end 0.67945 0.3048)
			(stroke
				(width 0.1)
				(type default)
			)
			(layer "B.Fab")
		)
		(fp_line
			(start 0.67945 -0.305054)
			(end 0.12065 -0.305054)
			(stroke
				(width 0.1)
				(type default)
			)
			(layer "B.Fab")
		)
		(fp_line
			(start 0.67945 0.3048)
			(end 0.67945 -0.305054)
			(stroke
				(width 0.1)
				(type default)
			)
			(layer "B.Fab")
		)
		(pad "1" smd circle
			(at 0.40005 0 180)
			(size 0 0)
			(layers "B.Cu" "B.Mask" "B.Paste")
			(net "NIC1_MAIN_PWR_EN")
		)
		(pad "2" smd circle
			(at -0.40005 0 180)
			(size 0 0)
			(layers "B.Cu" "B.Mask" "B.Paste")
			(net "GND")
		)
	)
	(footprint ""
		(layer "B.Cu")
		(at 162.455098 -299.212)
		(property "Reference" "C3200"
			(at 0 0 0)
			(layer "B.SilkS")
			(hide yes)
			(effects
				(font
					(size 1.27 1.27)
				)
				(justify mirror)
			)
		)
		(property "Value" ""
			(at 0 0 0)
			(layer "B.Fab")
			(effects
				(font
					(size 1.27 1.27)
				)
				(justify mirror)
			)
		)
		(duplicate_pad_numbers_are_jumpers no)
		(fp_line
			(start -0.299974 -0.150114)
			(end -0.299974 0.150114)
			(stroke
				(width 0.1)
				(type default)
			)
			(layer "B.Fab")
		)
		(fp_line
			(start -0.299974 0.150114)
			(end 0.299974 0.150114)
			(stroke
				(width 0.1)
				(type default)
			)
			(layer "B.Fab")
		)
		(fp_line
			(start 0.299974 -0.150114)
			(end -0.299974 -0.150114)
			(stroke
				(width 0.1)
				(type default)
			)
			(layer "B.Fab")
		)
		(fp_line
			(start 0.299974 0.150114)
			(end 0.299974 -0.150114)
			(stroke
				(width 0.1)
				(type default)
			)
			(layer "B.Fab")
		)
		(pad "1" smd rect
			(at 0.2667 0 180)
			(size 0.3048 0.381)
			(layers "B.Cu" "B.Mask" "B.Paste")
			(net "PCEPLL1_VDDA18_PEX1")
		)
		(pad "2" smd rect
			(at -0.2667 0 180)
			(size 0.3048 0.381)
			(layers "B.Cu" "B.Mask" "B.Paste")
			(net "GND")
		)
	)
	(footprint ""
		(layer "B.Cu")
		(at 166.743888 -138.421618 180)
		(property "Reference" "R126"
			(at 0 0 0)
			(layer "B.SilkS")
			(hide yes)
			(effects
				(font
					(size 1.27 1.27)
				)
				(justify mirror)
			)
		)
		(property "Value" ""
			(at 0 0 0)
			(layer "B.Fab")
			(effects
				(font
					(size 1.27 1.27)
				)
				(justify mirror)
			)
		)
		(duplicate_pad_numbers_are_jumpers no)
		(fp_line
			(start 0.7874 0.4064)
			(end 0.7874 -0.4064)
			(stroke
				(width 0.1524)
				(type default)
			)
			(layer "B.SilkS")
		)
		(fp_line
			(start 0.7874 -0.4064)
			(end -0.7874 -0.4064)
			(stroke
				(width 0.1524)
				(type default)
			)
			(layer "B.SilkS")
		)
		(fp_line
			(start -0.7874 0.4064)
			(end 0.7874 0.4064)
			(stroke
				(width 0.1524)
				(type default)
			)
			(layer "B.SilkS")
		)
		(fp_line
			(start -0.7874 -0.4064)
			(end -0.7874 0.4064)
			(stroke
				(width 0.1524)
				(type default)
			)
			(layer "B.SilkS")
		)
		(fp_line
			(start 0.67945 0.3048)
			(end 0.67945 -0.305054)
			(stroke
				(width 0.1)
				(type default)
			)
			(layer "B.Fab")
		)
		(fp_line
			(start 0.67945 -0.305054)
			(end 0.12065 -0.305054)
			(stroke
				(width 0.1)
				(type default)
			)
			(layer "B.Fab")
		)
		(fp_line
			(start 0.12065 0.3048)
			(end 0.67945 0.3048)
			(stroke
				(width 0.1)
				(type default)
			)
			(layer "B.Fab")
		)
		(fp_line
			(start 0.12065 0.2794)
			(end 0.12065 0.3048)
			(stroke
				(width 0.1)
				(type default)
			)
			(layer "B.Fab")
		)
		(fp_line
			(start 0.12065 -0.2794)
			(end -0.12065 -0.2794)
			(stroke
				(width 0.1)
				(type default)
			)
			(layer "B.Fab")
		)
		(fp_line
			(start 0.12065 -0.305054)
			(end 0.12065 -0.2794)
			(stroke
				(width 0.1)
				(type default)
			)
			(layer "B.Fab")
		)
		(fp_line
			(start -0.120396 0.3048)
			(end -0.120396 0.2794)
			(stroke
				(width 0.1)
				(type default)
			)
			(layer "B.Fab")
		)
		(fp_line
			(start -0.120396 0.2794)
			(end 0.12065 0.2794)
			(stroke
				(width 0.1)
				(type default)
			)
			(layer "B.Fab")
		)
		(fp_line
			(start -0.12065 -0.2794)
			(end -0.12065 -0.3048)
			(stroke
				(width 0.1)
				(type default)
			)
			(layer "B.Fab")
		)
		(fp_line
			(start -0.12065 -0.3048)
			(end -0.67945 -0.3048)
			(stroke
				(width 0.1)
				(type default)
			)
			(layer "B.Fab")
		)
		(fp_line
			(start -0.67945 0.3048)
			(end -0.120396 0.3048)
			(stroke
				(width 0.1)
				(type default)
			)
			(layer "B.Fab")
		)
		(fp_line
			(start -0.67945 -0.3048)
			(end -0.67945 0.3048)
			(stroke
				(width 0.1)
				(type default)
			)
			(layer "B.Fab")
		)
		(pad "1" smd circle
			(at 0.40005 0)
			(size 0 0)
			(layers "B.Cu" "B.Mask" "B.Paste")
			(net "NIC2_AUX_PWR_EN")
		)
		(pad "2" smd circle
			(at -0.40005 0)
			(size 0 0)
			(layers "B.Cu" "B.Mask" "B.Paste")
			(net "GND")
		)
	)
	(footprint ""
		(layer "B.Cu")
		(at 231.901746 -146.912076)
		(property "Reference" "C2790"
			(at 0 0 0)
			(layer "B.SilkS")
			(hide yes)
			(effects
				(font
					(size 1.27 1.27)
				)
				(justify mirror)
			)
		)
		(property "Value" ""
			(at 0 0 0)
			(layer "B.Fab")
			(effects
				(font
					(size 1.27 1.27)
				)
				(justify mirror)
			)
		)
		(duplicate_pad_numbers_are_jumpers no)
		(fp_line
			(start -0.7874 -0.4064)
			(end -0.7874 0.4064)
			(stroke
				(width 0.1524)
				(type default)
			)
			(layer "B.SilkS")
		)
		(fp_line
			(start -0.7874 0.4064)
			(end 0.7874 0.4064)
			(stroke
				(width 0.1524)
				(type default)
			)
			(layer "B.SilkS")
		)
		(fp_line
			(start 0.7874 -0.4064)
			(end -0.7874 -0.4064)
			(stroke
				(width 0.1524)
				(type default)
			)
			(layer "B.SilkS")
		)
		(fp_line
			(start 0.7874 0.4064)
			(end 0.7874 -0.4064)
			(stroke
				(width 0.1524)
				(type default)
			)
			(layer "B.SilkS")
		)
		(fp_line
			(start -0.67945 -0.3048)
			(end -0.67945 0.3048)
			(stroke
				(width 0.1)
				(type default)
			)
			(layer "B.Fab")
		)
		(fp_line
			(start -0.67945 0.3048)
			(end -0.120396 0.3048)
			(stroke
				(width 0.1)
				(type default)
			)
			(layer "B.Fab")
		)
		(fp_line
			(start -0.12065 -0.3048)
			(end -0.67945 -0.3048)
			(stroke
				(width 0.1)
				(type default)
			)
			(layer "B.Fab")
		)
		(fp_line
			(start -0.12065 -0.2794)
			(end -0.12065 -0.3048)
			(stroke
				(width 0.1)
				(type default)
			)
			(layer "B.Fab")
		)
		(fp_line
			(start -0.120396 0.2794)
			(end 0.12065 0.2794)
			(stroke
				(width 0.1)
				(type default)
			)
			(layer "B.Fab")
		)
		(fp_line
			(start -0.120396 0.3048)
			(end -0.120396 0.2794)
			(stroke
				(width 0.1)
				(type default)
			)
			(layer "B.Fab")
		)
		(fp_line
			(start 0.12065 -0.305054)
			(end 0.12065 -0.2794)
			(stroke
				(width 0.1)
				(type default)
			)
			(layer "B.Fab")
		)
		(fp_line
			(start 0.12065 -0.2794)
			(end -0.12065 -0.2794)
			(stroke
				(width 0.1)
				(type default)
			)
			(layer "B.Fab")
		)
		(fp_line
			(start 0.12065 0.2794)
			(end 0.12065 0.3048)
			(stroke
				(width 0.1)
				(type default)
			)
			(layer "B.Fab")
		)
		(fp_line
			(start 0.12065 0.3048)
			(end 0.67945 0.3048)
			(stroke
				(width 0.1)
				(type default)
			)
			(layer "B.Fab")
		)
		(fp_line
			(start 0.67945 -0.305054)
			(end 0.12065 -0.305054)
			(stroke
				(width 0.1)
				(type default)
			)
			(layer "B.Fab")
		)
		(fp_line
			(start 0.67945 0.3048)
			(end 0.67945 -0.305054)
			(stroke
				(width 0.1)
				(type default)
			)
			(layer "B.Fab")
		)
		(pad "1" smd circle
			(at 0.40005 0 180)
			(size 0 0)
			(layers "B.Cu" "B.Mask" "B.Paste")
			(net "P3V3_CLK_GEN_VDDA100M_CK440_PEX")
		)
		(pad "2" smd circle
			(at -0.40005 0 180)
			(size 0 0)
			(layers "B.Cu" "B.Mask" "B.Paste")
			(net "GND")
		)
	)
	(footprint ""
		(layer "B.Cu")
		(at 103.199184 -308.62397 90)
		(property "Reference" "C4200"
			(at 0 0 90)
			(layer "B.SilkS")
			(hide yes)
			(effects
				(font
					(size 1.27 1.27)
				)
				(justify mirror)
			)
		)
		(property "Value" ""
			(at 0 0 90)
			(layer "B.Fab")
			(effects
				(font
					(size 1.27 1.27)
				)
				(justify mirror)
			)
		)
		(duplicate_pad_numbers_are_jumpers no)
		(fp_line
			(start 0.299974 -0.150114)
			(end -0.299974 -0.150114)
			(stroke
				(width 0.1)
				(type default)
			)
			(layer "B.Fab")
		)
		(fp_line
			(start -0.299974 -0.150114)
			(end -0.299974 0.150114)
			(stroke
				(width 0.1)
				(type default)
			)
			(layer "B.Fab")
		)
		(fp_line
			(start 0.299974 0.150114)
			(end 0.299974 -0.150114)
			(stroke
				(width 0.1)
				(type default)
			)
			(layer "B.Fab")
		)
		(fp_line
			(start -0.299974 0.150114)
			(end 0.299974 0.150114)
			(stroke
				(width 0.1)
				(type default)
			)
			(layer "B.Fab")
		)
		(pad "1" smd rect
			(at 0.2667 0 270)
			(size 0.3048 0.381)
			(layers "B.Cu" "B.Mask" "B.Paste")
			(net "P0V8_PEX0")
		)
		(pad "2" smd rect
			(at -0.2667 0 270)
			(size 0.3048 0.381)
			(layers "B.Cu" "B.Mask" "B.Paste")
			(net "GND")
		)
	)
	(footprint ""
		(layer "B.Cu")
		(at 408.424888 -297.79976 90)
		(property "Reference" "C1887"
			(at 0 0 90)
			(layer "B.SilkS")
			(hide yes)
			(effects
				(font
					(size 1.27 1.27)
				)
				(justify mirror)
			)
		)
		(property "Value" ""
			(at 0 0 90)
			(layer "B.Fab")
			(effects
				(font
					(size 1.27 1.27)
				)
				(justify mirror)
			)
		)
		(duplicate_pad_numbers_are_jumpers no)
		(fp_line
			(start 0.299974 -0.150114)
			(end -0.299974 -0.150114)
			(stroke
				(width 0.1)
				(type default)
			)
			(layer "B.Fab")
		)
		(fp_line
			(start -0.299974 -0.150114)
			(end -0.299974 0.150114)
			(stroke
				(width 0.1)
				(type default)
			)
			(layer "B.Fab")
		)
		(fp_line
			(start 0.299974 0.150114)
			(end 0.299974 -0.150114)
			(stroke
				(width 0.1)
				(type default)
			)
			(layer "B.Fab")
		)
		(fp_line
			(start -0.299974 0.150114)
			(end 0.299974 0.150114)
			(stroke
				(width 0.1)
				(type default)
			)
			(layer "B.Fab")
		)
		(pad "1" smd rect
			(at 0.2667 0 270)
			(size 0.3048 0.381)
			(layers "B.Cu" "B.Mask" "B.Paste")
			(net "P0V8_PEX3")
		)
		(pad "2" smd rect
			(at -0.2667 0 270)
			(size 0.3048 0.381)
			(layers "B.Cu" "B.Mask" "B.Paste")
			(net "GND")
		)
	)
	(footprint ""
		(layer "B.Cu")
		(at 220.981016 -279.898856 -90)
		(property "Reference" "C4293"
			(at 0 0 90)
			(layer "B.SilkS")
			(hide yes)
			(effects
				(font
					(size 1.27 1.27)
				)
				(justify mirror)
			)
		)
		(property "Value" ""
			(at 0 0 90)
			(layer "B.Fab")
			(effects
				(font
					(size 1.27 1.27)
				)
				(justify mirror)
			)
		)
		(duplicate_pad_numbers_are_jumpers no)
		(fp_line
			(start -0.299974 0.150114)
			(end 0.299974 0.150114)
			(stroke
				(width 0.1)
				(type default)
			)
			(layer "B.Fab")
		)
		(fp_line
			(start 0.299974 0.150114)
			(end 0.299974 -0.150114)
			(stroke
				(width 0.1)
				(type default)
			)
			(layer "B.Fab")
		)
		(fp_line
			(start -0.299974 -0.150114)
			(end -0.299974 0.150114)
			(stroke
				(width 0.1)
				(type default)
			)
			(layer "B.Fab")
		)
		(fp_line
			(start 0.299974 -0.150114)
			(end -0.299974 -0.150114)
			(stroke
				(width 0.1)
				(type default)
			)
			(layer "B.Fab")
		)
		(pad "1" smd rect
			(at 0.2667 0 90)
			(size 0.3048 0.381)
			(layers "B.Cu" "B.Mask" "B.Paste")
			(net "P1V25_PEX1")
		)
		(pad "2" smd rect
			(at -0.2667 0 90)
			(size 0.3048 0.381)
			(layers "B.Cu" "B.Mask" "B.Paste")
			(net "GND")
		)
	)
	(footprint ""
		(layer "B.Cu")
		(at 396.0749 -296.64152 -90)
		(property "Reference" "C3563"
			(at 0 0 90)
			(layer "B.SilkS")
			(hide yes)
			(effects
				(font
					(size 1.27 1.27)
				)
				(justify mirror)
			)
		)
		(property "Value" ""
			(at 0 0 90)
			(layer "B.Fab")
			(effects
				(font
					(size 1.27 1.27)
				)
				(justify mirror)
			)
		)
		(duplicate_pad_numbers_are_jumpers no)
		(fp_line
			(start -0.299974 0.150114)
			(end 0.299974 0.150114)
			(stroke
				(width 0.1)
				(type default)
			)
			(layer "B.Fab")
		)
		(fp_line
			(start 0.299974 0.150114)
			(end 0.299974 -0.150114)
			(stroke
				(width 0.1)
				(type default)
			)
			(layer "B.Fab")
		)
		(fp_line
			(start -0.299974 -0.150114)
			(end -0.299974 0.150114)
			(stroke
				(width 0.1)
				(type default)
			)
			(layer "B.Fab")
		)
		(fp_line
			(start 0.299974 -0.150114)
			(end -0.299974 -0.150114)
			(stroke
				(width 0.1)
				(type default)
			)
			(layer "B.Fab")
		)
		(pad "1" smd rect
			(at 0.2667 0 90)
			(size 0.3048 0.381)
			(layers "B.Cu" "B.Mask" "B.Paste")
			(net "PCEPLL3_VDDA18_PEX3")
		)
		(pad "2" smd rect
			(at -0.2667 0 90)
			(size 0.3048 0.381)
			(layers "B.Cu" "B.Mask" "B.Paste")
			(net "GND")
		)
	)
	(footprint ""
		(layer "B.Cu")
		(at 340.493858 -220.38691 90)
		(property "Reference" "C2072"
			(at 0 0 90)
			(layer "B.SilkS")
			(hide yes)
			(effects
				(font
					(size 1.27 1.27)
				)
				(justify mirror)
			)
		)
		(property "Value" ""
			(at 0 0 90)
			(layer "B.Fab")
			(effects
				(font
					(size 1.27 1.27)
				)
				(justify mirror)
			)
		)
		(duplicate_pad_numbers_are_jumpers no)
		(fp_line
			(start 0.69215 -0.2921)
			(end -0.69215 -0.2921)
			(stroke
				(width 0.1524)
				(type default)
			)
			(layer "B.SilkS")
		)
		(fp_line
			(start -0.69215 -0.2921)
			(end -0.69215 0.2921)
			(stroke
				(width 0.1524)
				(type default)
			)
			(layer "B.SilkS")
		)
		(fp_line
			(start 0.69215 0.2921)
			(end 0.69215 -0.2921)
			(stroke
				(width 0.1524)
				(type default)
			)
			(layer "B.SilkS")
		)
		(fp_line
			(start -0.69215 0.2921)
			(end 0.69215 0.2921)
			(stroke
				(width 0.1524)
				(type default)
			)
			(layer "B.SilkS")
		)
		(fp_line
			(start 0.51435 -0.2794)
			(end -0.51435 -0.2794)
			(stroke
				(width 0.1)
				(type default)
			)
			(layer "B.Fab")
		)
		(fp_line
			(start -0.51435 -0.2794)
			(end -0.51435 0.2794)
			(stroke
				(width 0.1)
				(type default)
			)
			(layer "B.Fab")
		)
		(fp_line
			(start 0.51435 0.2794)
			(end 0.51435 -0.2794)
			(stroke
				(width 0.1)
				(type default)
			)
			(layer "B.Fab")
		)
		(fp_line
			(start -0.51435 0.2794)
			(end 0.51435 0.2794)
			(stroke
				(width 0.1)
				(type default)
			)
			(layer "B.Fab")
		)
		(pad "1" smd circle
			(at 0.40005 0 270)
			(size 0 0)
			(layers "B.Cu" "B.Mask" "B.Paste")
			(net "P3V3_VCC_FPGA_CORE")
		)
		(pad "2" smd circle
			(at -0.40005 0 270)
			(size 0 0)
			(layers "B.Cu" "B.Mask" "B.Paste")
			(net "GND")
		)
		(zone
			(layer "B.Cu")
			(hatch none 0.5)
			(connect_pads
				(clearance 0)
			)
			(min_thickness 0.25)
			(keepout
				(tracks not_allowed)
				(vias allowed)
				(pads allowed)
				(copperpour not_allowed)
				(footprints allowed)
			)
			(placement
				(enabled no)
				(sheetname "")
			)
			(fill
				(thermal_gap 0.5)
				(thermal_bridge_width 0.5)
				(island_removal_mode 0)
			)
			(polygon
				(pts
					(xy 340.581488 -220.57741) (xy 340.639654 -220.48597) (xy 340.639654 -220.28658) (xy 340.581488 -220.19641)
					(xy 340.406228 -220.19641) (xy 340.347808 -220.28658) (xy 340.347808 -220.48597) (xy 340.405974 -220.57741)
				)
			)
		)
	)
	(footprint ""
		(layer "B.Cu")
		(at 294.69969 -299.699934 -90)
		(property "Reference" "C1719"
			(at 0 0 90)
			(layer "B.SilkS")
			(hide yes)
			(effects
				(font
					(size 1.27 1.27)
				)
				(justify mirror)
			)
		)
		(property "Value" ""
			(at 0 0 90)
			(layer "B.Fab")
			(effects
				(font
					(size 1.27 1.27)
				)
				(justify mirror)
			)
		)
		(duplicate_pad_numbers_are_jumpers no)
		(fp_line
			(start -0.299974 0.150114)
			(end 0.299974 0.150114)
			(stroke
				(width 0.1)
				(type default)
			)
			(layer "B.Fab")
		)
		(fp_line
			(start 0.299974 0.150114)
			(end 0.299974 -0.150114)
			(stroke
				(width 0.1)
				(type default)
			)
			(layer "B.Fab")
		)
		(fp_line
			(start -0.299974 -0.150114)
			(end -0.299974 0.150114)
			(stroke
				(width 0.1)
				(type default)
			)
			(layer "B.Fab")
		)
		(fp_line
			(start 0.299974 -0.150114)
			(end -0.299974 -0.150114)
			(stroke
				(width 0.1)
				(type default)
			)
			(layer "B.Fab")
		)
		(pad "1" smd rect
			(at 0.2667 0 90)
			(size 0.3048 0.381)
			(layers "B.Cu" "B.Mask" "B.Paste")
			(net "P0V8_SERDES_VDDA_PEX2")
		)
		(pad "2" smd rect
			(at -0.2667 0 90)
			(size 0.3048 0.381)
			(layers "B.Cu" "B.Mask" "B.Paste")
			(net "GND")
		)
	)
	(footprint ""
		(layer "B.Cu")
		(at 237.475776 -224.424494 -90)
		(property "Reference" "C4490"
			(at 0 0 90)
			(layer "B.SilkS")
			(hide yes)
			(effects
				(font
					(size 1.27 1.27)
				)
				(justify mirror)
			)
		)
		(property "Value" ""
			(at 0 0 90)
			(layer "B.Fab")
			(effects
				(font
					(size 1.27 1.27)
				)
				(justify mirror)
			)
		)
		(duplicate_pad_numbers_are_jumpers no)
		(fp_line
			(start -0.7874 0.4064)
			(end 0.7874 0.4064)
			(stroke
				(width 0.1524)
				(type default)
			)
			(layer "B.SilkS")
		)
		(fp_line
			(start 0.7874 0.4064)
			(end 0.7874 -0.4064)
			(stroke
				(width 0.1524)
				(type default)
			)
			(layer "B.SilkS")
		)
		(fp_line
			(start -0.7874 -0.4064)
			(end -0.7874 0.4064)
			(stroke
				(width 0.1524)
				(type default)
			)
			(layer "B.SilkS")
		)
		(fp_line
			(start 0.7874 -0.4064)
			(end -0.7874 -0.4064)
			(stroke
				(width 0.1524)
				(type default)
			)
			(layer "B.SilkS")
		)
		(fp_line
			(start -0.67945 0.3048)
			(end -0.120396 0.3048)
			(stroke
				(width 0.1)
				(type default)
			)
			(layer "B.Fab")
		)
		(fp_line
			(start -0.120396 0.3048)
			(end -0.120396 0.2794)
			(stroke
				(width 0.1)
				(type default)
			)
			(layer "B.Fab")
		)
		(fp_line
			(start 0.12065 0.3048)
			(end 0.67945 0.3048)
			(stroke
				(width 0.1)
				(type default)
			)
			(layer "B.Fab")
		)
		(fp_line
			(start 0.67945 0.3048)
			(end 0.67945 -0.305054)
			(stroke
				(width 0.1)
				(type default)
			)
			(layer "B.Fab")
		)
		(fp_line
			(start -0.120396 0.2794)
			(end 0.12065 0.2794)
			(stroke
				(width 0.1)
				(type default)
			)
			(layer "B.Fab")
		)
		(fp_line
			(start 0.12065 0.2794)
			(end 0.12065 0.3048)
			(stroke
				(width 0.1)
				(type default)
			)
			(layer "B.Fab")
		)
		(fp_line
			(start -0.12065 -0.2794)
			(end -0.12065 -0.3048)
			(stroke
				(width 0.1)
				(type default)
			)
			(layer "B.Fab")
		)
		(fp_line
			(start 0.12065 -0.2794)
			(end -0.12065 -0.2794)
			(stroke
				(width 0.1)
				(type default)
			)
			(layer "B.Fab")
		)
		(fp_line
			(start -0.67945 -0.3048)
			(end -0.67945 0.3048)
			(stroke
				(width 0.1)
				(type default)
			)
			(layer "B.Fab")
		)
		(fp_line
			(start -0.12065 -0.3048)
			(end -0.67945 -0.3048)
			(stroke
				(width 0.1)
				(type default)
			)
			(layer "B.Fab")
		)
		(fp_line
			(start 0.12065 -0.305054)
			(end 0.12065 -0.2794)
			(stroke
				(width 0.1)
				(type default)
			)
			(layer "B.Fab")
		)
		(fp_line
			(start 0.67945 -0.305054)
			(end 0.12065 -0.305054)
			(stroke
				(width 0.1)
				(type default)
			)
			(layer "B.Fab")
		)
		(pad "1" smd circle
			(at 0.40005 0 90)
			(size 0 0)
			(layers "B.Cu" "B.Mask" "B.Paste")
			(net "VR_TYPE_ADC_R")
		)
		(pad "2" smd circle
			(at -0.40005 0 90)
			(size 0 0)
			(layers "B.Cu" "B.Mask" "B.Paste")
			(net "GND")
		)
	)
	(footprint ""
		(layer "B.Cu")
		(at 223.533716 -196.989192 90)
		(property "Reference" "R464"
			(at 0 0 90)
			(layer "B.SilkS")
			(hide yes)
			(effects
				(font
					(size 1.27 1.27)
				)
				(justify mirror)
			)
		)
		(property "Value" ""
			(at 0 0 90)
			(layer "B.Fab")
			(effects
				(font
					(size 1.27 1.27)
				)
				(justify mirror)
			)
		)
		(duplicate_pad_numbers_are_jumpers no)
		(fp_line
			(start 0.7874 -0.4064)
			(end -0.7874 -0.4064)
			(stroke
				(width 0.1524)
				(type default)
			)
			(layer "B.SilkS")
		)
		(fp_line
			(start -0.7874 -0.4064)
			(end -0.7874 0.4064)
			(stroke
				(width 0.1524)
				(type default)
			)
			(layer "B.SilkS")
		)
		(fp_line
			(start 0.7874 0.4064)
			(end 0.7874 -0.4064)
			(stroke
				(width 0.1524)
				(type default)
			)
			(layer "B.SilkS")
		)
		(fp_line
			(start -0.7874 0.4064)
			(end 0.7874 0.4064)
			(stroke
				(width 0.1524)
				(type default)
			)
			(layer "B.SilkS")
		)
		(fp_line
			(start 0.67945 -0.305054)
			(end 0.12065 -0.305054)
			(stroke
				(width 0.1)
				(type default)
			)
			(layer "B.Fab")
		)
		(fp_line
			(start 0.12065 -0.305054)
			(end 0.12065 -0.2794)
			(stroke
				(width 0.1)
				(type default)
			)
			(layer "B.Fab")
		)
		(fp_line
			(start -0.12065 -0.3048)
			(end -0.67945 -0.3048)
			(stroke
				(width 0.1)
				(type default)
			)
			(layer "B.Fab")
		)
		(fp_line
			(start -0.67945 -0.3048)
			(end -0.67945 0.3048)
			(stroke
				(width 0.1)
				(type default)
			)
			(layer "B.Fab")
		)
		(fp_line
			(start 0.12065 -0.2794)
			(end -0.12065 -0.2794)
			(stroke
				(width 0.1)
				(type default)
			)
			(layer "B.Fab")
		)
		(fp_line
			(start -0.12065 -0.2794)
			(end -0.12065 -0.3048)
			(stroke
				(width 0.1)
				(type default)
			)
			(layer "B.Fab")
		)
		(fp_line
			(start 0.12065 0.2794)
			(end 0.12065 0.3048)
			(stroke
				(width 0.1)
				(type default)
			)
			(layer "B.Fab")
		)
		(fp_line
			(start -0.120396 0.2794)
			(end 0.12065 0.2794)
			(stroke
				(width 0.1)
				(type default)
			)
			(layer "B.Fab")
		)
		(fp_line
			(start 0.67945 0.3048)
			(end 0.67945 -0.305054)
			(stroke
				(width 0.1)
				(type default)
			)
			(layer "B.Fab")
		)
		(fp_line
			(start 0.12065 0.3048)
			(end 0.67945 0.3048)
			(stroke
				(width 0.1)
				(type default)
			)
			(layer "B.Fab")
		)
		(fp_line
			(start -0.120396 0.3048)
			(end -0.120396 0.2794)
			(stroke
				(width 0.1)
				(type default)
			)
			(layer "B.Fab")
		)
		(fp_line
			(start -0.67945 0.3048)
			(end -0.120396 0.3048)
			(stroke
				(width 0.1)
				(type default)
			)
			(layer "B.Fab")
		)
		(pad "1" smd circle
			(at 0.40005 0 270)
			(size 0 0)
			(layers "B.Cu" "B.Mask" "B.Paste")
			(net "SPI_BIC1_MISO_R")
		)
		(pad "2" smd circle
			(at -0.40005 0 270)
			(size 0 0)
			(layers "B.Cu" "B.Mask" "B.Paste")
			(net "SPI_BIC1_MISO_R1")
		)
	)
	(footprint ""
		(layer "B.Cu")
		(at 202.090274 -259.311648 90)
		(property "Reference" "R6337"
			(at 0 0 90)
			(layer "B.SilkS")
			(hide yes)
			(effects
				(font
					(size 1.27 1.27)
				)
				(justify mirror)
			)
		)
		(property "Value" ""
			(at 0 0 90)
			(layer "B.Fab")
			(effects
				(font
					(size 1.27 1.27)
				)
				(justify mirror)
			)
		)
		(duplicate_pad_numbers_are_jumpers no)
		(fp_line
			(start 0.7874 -0.4064)
			(end -0.7874 -0.4064)
			(stroke
				(width 0.1524)
				(type default)
			)
			(layer "B.SilkS")
		)
		(fp_line
			(start -0.7874 -0.4064)
			(end -0.7874 0.4064)
			(stroke
				(width 0.1524)
				(type default)
			)
			(layer "B.SilkS")
		)
		(fp_line
			(start 0.7874 0.4064)
			(end 0.7874 -0.4064)
			(stroke
				(width 0.1524)
				(type default)
			)
			(layer "B.SilkS")
		)
		(fp_line
			(start -0.7874 0.4064)
			(end 0.7874 0.4064)
			(stroke
				(width 0.1524)
				(type default)
			)
			(layer "B.SilkS")
		)
		(fp_line
			(start 0.67945 -0.305054)
			(end 0.12065 -0.305054)
			(stroke
				(width 0.1)
				(type default)
			)
			(layer "B.Fab")
		)
		(fp_line
			(start 0.12065 -0.305054)
			(end 0.12065 -0.2794)
			(stroke
				(width 0.1)
				(type default)
			)
			(layer "B.Fab")
		)
		(fp_line
			(start -0.12065 -0.3048)
			(end -0.67945 -0.3048)
			(stroke
				(width 0.1)
				(type default)
			)
			(layer "B.Fab")
		)
		(fp_line
			(start -0.67945 -0.3048)
			(end -0.67945 0.3048)
			(stroke
				(width 0.1)
				(type default)
			)
			(layer "B.Fab")
		)
		(fp_line
			(start 0.12065 -0.2794)
			(end -0.12065 -0.2794)
			(stroke
				(width 0.1)
				(type default)
			)
			(layer "B.Fab")
		)
		(fp_line
			(start -0.12065 -0.2794)
			(end -0.12065 -0.3048)
			(stroke
				(width 0.1)
				(type default)
			)
			(layer "B.Fab")
		)
		(fp_line
			(start 0.12065 0.2794)
			(end 0.12065 0.3048)
			(stroke
				(width 0.1)
				(type default)
			)
			(layer "B.Fab")
		)
		(fp_line
			(start -0.120396 0.2794)
			(end 0.12065 0.2794)
			(stroke
				(width 0.1)
				(type default)
			)
			(layer "B.Fab")
		)
		(fp_line
			(start 0.67945 0.3048)
			(end 0.67945 -0.305054)
			(stroke
				(width 0.1)
				(type default)
			)
			(layer "B.Fab")
		)
		(fp_line
			(start 0.12065 0.3048)
			(end 0.67945 0.3048)
			(stroke
				(width 0.1)
				(type default)
			)
			(layer "B.Fab")
		)
		(fp_line
			(start -0.120396 0.3048)
			(end -0.120396 0.2794)
			(stroke
				(width 0.1)
				(type default)
			)
			(layer "B.Fab")
		)
		(fp_line
			(start -0.67945 0.3048)
			(end -0.120396 0.3048)
			(stroke
				(width 0.1)
				(type default)
			)
			(layer "B.Fab")
		)
		(pad "1" smd circle
			(at 0.40005 0 270)
			(size 0 0)
			(layers "B.Cu" "B.Mask" "B.Paste")
			(net "P1V8_PEX")
		)
		(pad "2" smd circle
			(at -0.40005 0 270)
			(size 0 0)
			(layers "B.Cu" "B.Mask" "B.Paste")
			(net "PEX_MUX_A1")
		)
	)
	(footprint ""
		(layer "B.Cu")
		(at 217.664538 -275.315172)
		(property "Reference" "C4276"
			(at 0 0 0)
			(layer "B.SilkS")
			(hide yes)
			(effects
				(font
					(size 1.27 1.27)
				)
				(justify mirror)
			)
		)
		(property "Value" ""
			(at 0 0 0)
			(layer "B.Fab")
			(effects
				(font
					(size 1.27 1.27)
				)
				(justify mirror)
			)
		)
		(duplicate_pad_numbers_are_jumpers no)
		(fp_line
			(start -1.2954 -0.5842)
			(end -1.2954 0.5842)
			(stroke
				(width 0.1524)
				(type default)
			)
			(layer "B.SilkS")
		)
		(fp_line
			(start -1.2954 0.5842)
			(end 1.2954 0.5842)
			(stroke
				(width 0.1524)
				(type default)
			)
			(layer "B.SilkS")
		)
		(fp_line
			(start 1.2954 -0.5842)
			(end -1.2954 -0.5842)
			(stroke
				(width 0.1524)
				(type default)
			)
			(layer "B.SilkS")
		)
		(fp_line
			(start 1.2954 0.5842)
			(end 1.2954 -0.5842)
			(stroke
				(width 0.1524)
				(type default)
			)
			(layer "B.SilkS")
		)
		(fp_line
			(start -1.1938 -0.4064)
			(end -1.1938 0.4064)
			(stroke
				(width 0.1)
				(type default)
			)
			(layer "B.Fab")
		)
		(fp_line
			(start -1.1938 0.4064)
			(end -0.8636 0.4064)
			(stroke
				(width 0.1)
				(type default)
			)
			(layer "B.Fab")
		)
		(fp_line
			(start -0.8636 -0.4572)
			(end -0.8636 -0.4064)
			(stroke
				(width 0.1)
				(type default)
			)
			(layer "B.Fab")
		)
		(fp_line
			(start -0.8636 -0.4064)
			(end -1.1938 -0.4064)
			(stroke
				(width 0.1)
				(type default)
			)
			(layer "B.Fab")
		)
		(fp_line
			(start -0.8636 0.4064)
			(end -0.8636 0.4572)
			(stroke
				(width 0.1)
				(type default)
			)
			(layer "B.Fab")
		)
		(fp_line
			(start -0.8636 0.4572)
			(end 0.8636 0.4572)
			(stroke
				(width 0.1)
				(type default)
			)
			(layer "B.Fab")
		)
		(fp_line
			(start 0.8636 -0.4572)
			(end -0.8636 -0.4572)
			(stroke
				(width 0.1)
				(type default)
			)
			(layer "B.Fab")
		)
		(fp_line
			(start 0.8636 -0.4064)
			(end 0.8636 -0.4572)
			(stroke
				(width 0.1)
				(type default)
			)
			(layer "B.Fab")
		)
		(fp_line
			(start 0.8636 0.4064)
			(end 1.1938 0.4064)
			(stroke
				(width 0.1)
				(type default)
			)
			(layer "B.Fab")
		)
		(fp_line
			(start 0.8636 0.4572)
			(end 0.8636 0.4064)
			(stroke
				(width 0.1)
				(type default)
			)
			(layer "B.Fab")
		)
		(fp_line
			(start 1.1938 -0.4064)
			(end 0.8636 -0.4064)
			(stroke
				(width 0.1)
				(type default)
			)
			(layer "B.Fab")
		)
		(fp_line
			(start 1.1938 0.4064)
			(end 1.1938 -0.4064)
			(stroke
				(width 0.1)
				(type default)
			)
			(layer "B.Fab")
		)
		(pad "1" smd rect
			(at 0.7366 0 270)
			(size 0.7112 0.8128)
			(layers "B.Cu" "B.Mask" "B.Paste")
			(net "P1V25_PEX1")
		)
		(pad "2" smd rect
			(at -0.7366 0 270)
			(size 0.7112 0.8128)
			(layers "B.Cu" "B.Mask" "B.Paste")
			(net "GND")
		)
	)
	(footprint ""
		(layer "B.Cu")
		(at 140.774166 -223.315276 180)
		(property "Reference" "C2783"
			(at 0 0 0)
			(layer "B.SilkS")
			(hide yes)
			(effects
				(font
					(size 1.27 1.27)
				)
				(justify mirror)
			)
		)
		(property "Value" ""
			(at 0 0 0)
			(layer "B.Fab")
			(effects
				(font
					(size 1.27 1.27)
				)
				(justify mirror)
			)
		)
		(duplicate_pad_numbers_are_jumpers no)
		(fp_line
			(start 0.7874 0.4064)
			(end 0.7874 -0.4064)
			(stroke
				(width 0.1524)
				(type default)
			)
			(layer "B.SilkS")
		)
		(fp_line
			(start 0.7874 -0.4064)
			(end -0.7874 -0.4064)
			(stroke
				(width 0.1524)
				(type default)
			)
			(layer "B.SilkS")
		)
		(fp_line
			(start -0.7874 0.4064)
			(end 0.7874 0.4064)
			(stroke
				(width 0.1524)
				(type default)
			)
			(layer "B.SilkS")
		)
		(fp_line
			(start -0.7874 -0.4064)
			(end -0.7874 0.4064)
			(stroke
				(width 0.1524)
				(type default)
			)
			(layer "B.SilkS")
		)
		(fp_line
			(start 0.67945 0.3048)
			(end 0.67945 -0.305054)
			(stroke
				(width 0.1)
				(type default)
			)
			(layer "B.Fab")
		)
		(fp_line
			(start 0.67945 -0.305054)
			(end 0.12065 -0.305054)
			(stroke
				(width 0.1)
				(type default)
			)
			(layer "B.Fab")
		)
		(fp_line
			(start 0.12065 0.3048)
			(end 0.67945 0.3048)
			(stroke
				(width 0.1)
				(type default)
			)
			(layer "B.Fab")
		)
		(fp_line
			(start 0.12065 0.2794)
			(end 0.12065 0.3048)
			(stroke
				(width 0.1)
				(type default)
			)
			(layer "B.Fab")
		)
		(fp_line
			(start 0.12065 -0.2794)
			(end -0.12065 -0.2794)
			(stroke
				(width 0.1)
				(type default)
			)
			(layer "B.Fab")
		)
		(fp_line
			(start 0.12065 -0.305054)
			(end 0.12065 -0.2794)
			(stroke
				(width 0.1)
				(type default)
			)
			(layer "B.Fab")
		)
		(fp_line
			(start -0.120396 0.3048)
			(end -0.120396 0.2794)
			(stroke
				(width 0.1)
				(type default)
			)
			(layer "B.Fab")
		)
		(fp_line
			(start -0.120396 0.2794)
			(end 0.12065 0.2794)
			(stroke
				(width 0.1)
				(type default)
			)
			(layer "B.Fab")
		)
		(fp_line
			(start -0.12065 -0.2794)
			(end -0.12065 -0.3048)
			(stroke
				(width 0.1)
				(type default)
			)
			(layer "B.Fab")
		)
		(fp_line
			(start -0.12065 -0.3048)
			(end -0.67945 -0.3048)
			(stroke
				(width 0.1)
				(type default)
			)
			(layer "B.Fab")
		)
		(fp_line
			(start -0.67945 0.3048)
			(end -0.120396 0.3048)
			(stroke
				(width 0.1)
				(type default)
			)
			(layer "B.Fab")
		)
		(fp_line
			(start -0.67945 -0.3048)
			(end -0.67945 0.3048)
			(stroke
				(width 0.1)
				(type default)
			)
			(layer "B.Fab")
		)
		(pad "1" smd circle
			(at 0.40005 0)
			(size 0 0)
			(layers "B.Cu" "B.Mask" "B.Paste")
			(net "GND")
		)
		(pad "2" smd circle
			(at -0.40005 0)
			(size 0 0)
			(layers "B.Cu" "B.Mask" "B.Paste")
			(net "P1V8_PEX")
		)
	)
	(footprint ""
		(layer "B.Cu")
		(at 231.396286 -256.9845)
		(property "Reference" "C4351"
			(at 0 0 0)
			(layer "B.SilkS")
			(hide yes)
			(effects
				(font
					(size 1.27 1.27)
				)
				(justify mirror)
			)
		)
		(property "Value" ""
			(at 0 0 0)
			(layer "B.Fab")
			(effects
				(font
					(size 1.27 1.27)
				)
				(justify mirror)
			)
		)
		(duplicate_pad_numbers_are_jumpers no)
		(fp_line
			(start -0.299974 -0.150114)
			(end -0.299974 0.150114)
			(stroke
				(width 0.1)
				(type default)
			)
			(layer "B.Fab")
		)
		(fp_line
			(start -0.299974 0.150114)
			(end 0.299974 0.150114)
			(stroke
				(width 0.1)
				(type default)
			)
			(layer "B.Fab")
		)
		(fp_line
			(start 0.299974 -0.150114)
			(end -0.299974 -0.150114)
			(stroke
				(width 0.1)
				(type default)
			)
			(layer "B.Fab")
		)
		(fp_line
			(start 0.299974 0.150114)
			(end 0.299974 -0.150114)
			(stroke
				(width 0.1)
				(type default)
			)
			(layer "B.Fab")
		)
		(pad "1" smd rect
			(at 0.2667 0 180)
			(size 0.3048 0.381)
			(layers "B.Cu" "B.Mask" "B.Paste")
			(net "P1V25_SERDES_VDDPLL_PEX2")
		)
		(pad "2" smd rect
			(at -0.2667 0 180)
			(size 0.3048 0.381)
			(layers "B.Cu" "B.Mask" "B.Paste")
			(net "GND")
		)
	)
	(footprint ""
		(layer "B.Cu")
		(at 45.864272 -143.608552 180)
		(property "Reference" "C848"
			(at 0 0 0)
			(layer "B.SilkS")
			(hide yes)
			(effects
				(font
					(size 1.27 1.27)
				)
				(justify mirror)
			)
		)
		(property "Value" ""
			(at 0 0 0)
			(layer "B.Fab")
			(effects
				(font
					(size 1.27 1.27)
				)
				(justify mirror)
			)
		)
		(duplicate_pad_numbers_are_jumpers no)
		(fp_line
			(start 0.299974 0.150114)
			(end 0.299974 -0.150114)
			(stroke
				(width 0.1)
				(type default)
			)
			(layer "B.Fab")
		)
		(fp_line
			(start 0.299974 -0.150114)
			(end -0.299974 -0.150114)
			(stroke
				(width 0.1)
				(type default)
			)
			(layer "B.Fab")
		)
		(fp_line
			(start -0.299974 0.150114)
			(end 0.299974 0.150114)
			(stroke
				(width 0.1)
				(type default)
			)
			(layer "B.Fab")
		)
		(fp_line
			(start -0.299974 -0.150114)
			(end -0.299974 0.150114)
			(stroke
				(width 0.1)
				(type default)
			)
			(layer "B.Fab")
		)
		(pad "1" smd rect
			(at 0.2667 0)
			(size 0.3048 0.381)
			(layers "B.Cu" "B.Mask" "B.Paste")
			(net "P12V_NIC0")
		)
		(pad "2" smd rect
			(at -0.2667 0)
			(size 0.3048 0.381)
			(layers "B.Cu" "B.Mask" "B.Paste")
			(net "GND")
		)
	)
	(footprint ""
		(layer "B.Cu")
		(at 189.371478 -114.592608)
		(property "Reference" "C898"
			(at 0 0 0)
			(layer "B.SilkS")
			(hide yes)
			(effects
				(font
					(size 1.27 1.27)
				)
				(justify mirror)
			)
		)
		(property "Value" ""
			(at 0 0 0)
			(layer "B.Fab")
			(effects
				(font
					(size 1.27 1.27)
				)
				(justify mirror)
			)
		)
		(duplicate_pad_numbers_are_jumpers no)
		(fp_line
			(start -0.7874 -0.4064)
			(end -0.7874 0.4064)
			(stroke
				(width 0.1524)
				(type default)
			)
			(layer "B.SilkS")
		)
		(fp_line
			(start -0.7874 0.4064)
			(end 0.7874 0.4064)
			(stroke
				(width 0.1524)
				(type default)
			)
			(layer "B.SilkS")
		)
		(fp_line
			(start 0.7874 -0.4064)
			(end -0.7874 -0.4064)
			(stroke
				(width 0.1524)
				(type default)
			)
			(layer "B.SilkS")
		)
		(fp_line
			(start 0.7874 0.4064)
			(end 0.7874 -0.4064)
			(stroke
				(width 0.1524)
				(type default)
			)
			(layer "B.SilkS")
		)
		(fp_line
			(start -0.67945 -0.3048)
			(end -0.67945 0.3048)
			(stroke
				(width 0.1)
				(type default)
			)
			(layer "B.Fab")
		)
		(fp_line
			(start -0.67945 0.3048)
			(end -0.120396 0.3048)
			(stroke
				(width 0.1)
				(type default)
			)
			(layer "B.Fab")
		)
		(fp_line
			(start -0.12065 -0.3048)
			(end -0.67945 -0.3048)
			(stroke
				(width 0.1)
				(type default)
			)
			(layer "B.Fab")
		)
		(fp_line
			(start -0.12065 -0.2794)
			(end -0.12065 -0.3048)
			(stroke
				(width 0.1)
				(type default)
			)
			(layer "B.Fab")
		)
		(fp_line
			(start -0.120396 0.2794)
			(end 0.12065 0.2794)
			(stroke
				(width 0.1)
				(type default)
			)
			(layer "B.Fab")
		)
		(fp_line
			(start -0.120396 0.3048)
			(end -0.120396 0.2794)
			(stroke
				(width 0.1)
				(type default)
			)
			(layer "B.Fab")
		)
		(fp_line
			(start 0.12065 -0.305054)
			(end 0.12065 -0.2794)
			(stroke
				(width 0.1)
				(type default)
			)
			(layer "B.Fab")
		)
		(fp_line
			(start 0.12065 -0.2794)
			(end -0.12065 -0.2794)
			(stroke
				(width 0.1)
				(type default)
			)
			(layer "B.Fab")
		)
		(fp_line
			(start 0.12065 0.2794)
			(end 0.12065 0.3048)
			(stroke
				(width 0.1)
				(type default)
			)
			(layer "B.Fab")
		)
		(fp_line
			(start 0.12065 0.3048)
			(end 0.67945 0.3048)
			(stroke
				(width 0.1)
				(type default)
			)
			(layer "B.Fab")
		)
		(fp_line
			(start 0.67945 -0.305054)
			(end 0.12065 -0.305054)
			(stroke
				(width 0.1)
				(type default)
			)
			(layer "B.Fab")
		)
		(fp_line
			(start 0.67945 0.3048)
			(end 0.67945 -0.305054)
			(stroke
				(width 0.1)
				(type default)
			)
			(layer "B.Fab")
		)
		(pad "1" smd circle
			(at 0.40005 0 180)
			(size 0 0)
			(layers "B.Cu" "B.Mask" "B.Paste")
			(net "P3V3_NIC3")
		)
		(pad "2" smd circle
			(at -0.40005 0 180)
			(size 0 0)
			(layers "B.Cu" "B.Mask" "B.Paste")
			(net "GND")
		)
	)
	(footprint ""
		(layer "B.Cu")
		(at 212.09 -192.405 -90)
		(property "Reference" "R1534"
			(at 0 0 90)
			(layer "B.SilkS")
			(hide yes)
			(effects
				(font
					(size 1.27 1.27)
				)
				(justify mirror)
			)
		)
		(property "Value" ""
			(at 0 0 90)
			(layer "B.Fab")
			(effects
				(font
					(size 1.27 1.27)
				)
				(justify mirror)
			)
		)
		(duplicate_pad_numbers_are_jumpers no)
		(fp_line
			(start -0.7874 0.4064)
			(end 0.7874 0.4064)
			(stroke
				(width 0.1524)
				(type default)
			)
			(layer "B.SilkS")
		)
		(fp_line
			(start 0.7874 0.4064)
			(end 0.7874 -0.4064)
			(stroke
				(width 0.1524)
				(type default)
			)
			(layer "B.SilkS")
		)
		(fp_line
			(start -0.7874 -0.4064)
			(end -0.7874 0.4064)
			(stroke
				(width 0.1524)
				(type default)
			)
			(layer "B.SilkS")
		)
		(fp_line
			(start 0.7874 -0.4064)
			(end -0.7874 -0.4064)
			(stroke
				(width 0.1524)
				(type default)
			)
			(layer "B.SilkS")
		)
		(fp_line
			(start -0.67945 0.3048)
			(end -0.120396 0.3048)
			(stroke
				(width 0.1)
				(type default)
			)
			(layer "B.Fab")
		)
		(fp_line
			(start -0.120396 0.3048)
			(end -0.120396 0.2794)
			(stroke
				(width 0.1)
				(type default)
			)
			(layer "B.Fab")
		)
		(fp_line
			(start 0.12065 0.3048)
			(end 0.67945 0.3048)
			(stroke
				(width 0.1)
				(type default)
			)
			(layer "B.Fab")
		)
		(fp_line
			(start 0.67945 0.3048)
			(end 0.67945 -0.305054)
			(stroke
				(width 0.1)
				(type default)
			)
			(layer "B.Fab")
		)
		(fp_line
			(start -0.120396 0.2794)
			(end 0.12065 0.2794)
			(stroke
				(width 0.1)
				(type default)
			)
			(layer "B.Fab")
		)
		(fp_line
			(start 0.12065 0.2794)
			(end 0.12065 0.3048)
			(stroke
				(width 0.1)
				(type default)
			)
			(layer "B.Fab")
		)
		(fp_line
			(start -0.12065 -0.2794)
			(end -0.12065 -0.3048)
			(stroke
				(width 0.1)
				(type default)
			)
			(layer "B.Fab")
		)
		(fp_line
			(start 0.12065 -0.2794)
			(end -0.12065 -0.2794)
			(stroke
				(width 0.1)
				(type default)
			)
			(layer "B.Fab")
		)
		(fp_line
			(start -0.67945 -0.3048)
			(end -0.67945 0.3048)
			(stroke
				(width 0.1)
				(type default)
			)
			(layer "B.Fab")
		)
		(fp_line
			(start -0.12065 -0.3048)
			(end -0.67945 -0.3048)
			(stroke
				(width 0.1)
				(type default)
			)
			(layer "B.Fab")
		)
		(fp_line
			(start 0.12065 -0.305054)
			(end 0.12065 -0.2794)
			(stroke
				(width 0.1)
				(type default)
			)
			(layer "B.Fab")
		)
		(fp_line
			(start 0.67945 -0.305054)
			(end 0.12065 -0.305054)
			(stroke
				(width 0.1)
				(type default)
			)
			(layer "B.Fab")
		)
		(pad "1" smd circle
			(at 0.40005 0 90)
			(size 0 0)
			(layers "B.Cu" "B.Mask" "B.Paste")
			(net "SMB_NIC7_LS_R_SCL")
		)
		(pad "2" smd circle
			(at -0.40005 0 90)
			(size 0 0)
			(layers "B.Cu" "B.Mask" "B.Paste")
			(net "SMB_NIC7_R_SCL")
		)
	)
	(footprint ""
		(layer "B.Cu")
		(at 109.463586 -83.715606 -90)
		(property "Reference" "C2667"
			(at 0 0 90)
			(layer "B.SilkS")
			(hide yes)
			(effects
				(font
					(size 1.27 1.27)
				)
				(justify mirror)
			)
		)
		(property "Value" ""
			(at 0 0 90)
			(layer "B.Fab")
			(effects
				(font
					(size 1.27 1.27)
				)
				(justify mirror)
			)
		)
		(duplicate_pad_numbers_are_jumpers no)
		(fp_line
			(start -0.7874 0.4064)
			(end 0.7874 0.4064)
			(stroke
				(width 0.1524)
				(type default)
			)
			(layer "B.SilkS")
		)
		(fp_line
			(start 0.7874 0.4064)
			(end 0.7874 -0.4064)
			(stroke
				(width 0.1524)
				(type default)
			)
			(layer "B.SilkS")
		)
		(fp_line
			(start -0.7874 -0.4064)
			(end -0.7874 0.4064)
			(stroke
				(width 0.1524)
				(type default)
			)
			(layer "B.SilkS")
		)
		(fp_line
			(start 0.7874 -0.4064)
			(end -0.7874 -0.4064)
			(stroke
				(width 0.1524)
				(type default)
			)
			(layer "B.SilkS")
		)
		(fp_line
			(start -0.67945 0.3048)
			(end -0.120396 0.3048)
			(stroke
				(width 0.1)
				(type default)
			)
			(layer "B.Fab")
		)
		(fp_line
			(start -0.120396 0.3048)
			(end -0.120396 0.2794)
			(stroke
				(width 0.1)
				(type default)
			)
			(layer "B.Fab")
		)
		(fp_line
			(start 0.12065 0.3048)
			(end 0.67945 0.3048)
			(stroke
				(width 0.1)
				(type default)
			)
			(layer "B.Fab")
		)
		(fp_line
			(start 0.67945 0.3048)
			(end 0.67945 -0.305054)
			(stroke
				(width 0.1)
				(type default)
			)
			(layer "B.Fab")
		)
		(fp_line
			(start -0.120396 0.2794)
			(end 0.12065 0.2794)
			(stroke
				(width 0.1)
				(type default)
			)
			(layer "B.Fab")
		)
		(fp_line
			(start 0.12065 0.2794)
			(end 0.12065 0.3048)
			(stroke
				(width 0.1)
				(type default)
			)
			(layer "B.Fab")
		)
		(fp_line
			(start -0.12065 -0.2794)
			(end -0.12065 -0.3048)
			(stroke
				(width 0.1)
				(type default)
			)
			(layer "B.Fab")
		)
		(fp_line
			(start 0.12065 -0.2794)
			(end -0.12065 -0.2794)
			(stroke
				(width 0.1)
				(type default)
			)
			(layer "B.Fab")
		)
		(fp_line
			(start -0.67945 -0.3048)
			(end -0.67945 0.3048)
			(stroke
				(width 0.1)
				(type default)
			)
			(layer "B.Fab")
		)
		(fp_line
			(start -0.12065 -0.3048)
			(end -0.67945 -0.3048)
			(stroke
				(width 0.1)
				(type default)
			)
			(layer "B.Fab")
		)
		(fp_line
			(start 0.12065 -0.305054)
			(end 0.12065 -0.2794)
			(stroke
				(width 0.1)
				(type default)
			)
			(layer "B.Fab")
		)
		(fp_line
			(start 0.67945 -0.305054)
			(end 0.12065 -0.305054)
			(stroke
				(width 0.1)
				(type default)
			)
			(layer "B.Fab")
		)
		(pad "1" smd circle
			(at 0.40005 0 90)
			(size 0 0)
			(layers "B.Cu" "B.Mask" "B.Paste")
			(net "P3V3_VDD_9ZXL0851_0_7")
		)
		(pad "2" smd circle
			(at -0.40005 0 90)
			(size 0 0)
			(layers "B.Cu" "B.Mask" "B.Paste")
			(net "GND")
		)
	)
	(footprint ""
		(layer "B.Cu")
		(at 55.849774 -303.499774 -90)
		(property "Reference" "C2913"
			(at 0 0 90)
			(layer "B.SilkS")
			(hide yes)
			(effects
				(font
					(size 1.27 1.27)
				)
				(justify mirror)
			)
		)
		(property "Value" ""
			(at 0 0 90)
			(layer "B.Fab")
			(effects
				(font
					(size 1.27 1.27)
				)
				(justify mirror)
			)
		)
		(duplicate_pad_numbers_are_jumpers no)
		(fp_line
			(start -0.299974 0.150114)
			(end 0.299974 0.150114)
			(stroke
				(width 0.1)
				(type default)
			)
			(layer "B.Fab")
		)
		(fp_line
			(start 0.299974 0.150114)
			(end 0.299974 -0.150114)
			(stroke
				(width 0.1)
				(type default)
			)
			(layer "B.Fab")
		)
		(fp_line
			(start -0.299974 -0.150114)
			(end -0.299974 0.150114)
			(stroke
				(width 0.1)
				(type default)
			)
			(layer "B.Fab")
		)
		(fp_line
			(start 0.299974 -0.150114)
			(end -0.299974 -0.150114)
			(stroke
				(width 0.1)
				(type default)
			)
			(layer "B.Fab")
		)
		(pad "1" smd rect
			(at 0.2667 0 90)
			(size 0.3048 0.381)
			(layers "B.Cu" "B.Mask" "B.Paste")
			(net "P1V25_PEX0")
		)
		(pad "2" smd rect
			(at -0.2667 0 90)
			(size 0.3048 0.381)
			(layers "B.Cu" "B.Mask" "B.Paste")
			(net "GND")
		)
	)
	(footprint ""
		(layer "B.Cu")
		(at 59.649868 -288.299906 90)
		(property "Reference" "C2941"
			(at 0 0 90)
			(layer "B.SilkS")
			(hide yes)
			(effects
				(font
					(size 1.27 1.27)
				)
				(justify mirror)
			)
		)
		(property "Value" ""
			(at 0 0 90)
			(layer "B.Fab")
			(effects
				(font
					(size 1.27 1.27)
				)
				(justify mirror)
			)
		)
		(duplicate_pad_numbers_are_jumpers no)
		(fp_line
			(start 0.299974 -0.150114)
			(end -0.299974 -0.150114)
			(stroke
				(width 0.1)
				(type default)
			)
			(layer "B.Fab")
		)
		(fp_line
			(start -0.299974 -0.150114)
			(end -0.299974 0.150114)
			(stroke
				(width 0.1)
				(type default)
			)
			(layer "B.Fab")
		)
		(fp_line
			(start 0.299974 0.150114)
			(end 0.299974 -0.150114)
			(stroke
				(width 0.1)
				(type default)
			)
			(layer "B.Fab")
		)
		(fp_line
			(start -0.299974 0.150114)
			(end 0.299974 0.150114)
			(stroke
				(width 0.1)
				(type default)
			)
			(layer "B.Fab")
		)
		(pad "1" smd rect
			(at 0.2667 0 270)
			(size 0.3048 0.381)
			(layers "B.Cu" "B.Mask" "B.Paste")
			(net "P1V25_PEX0")
		)
		(pad "2" smd rect
			(at -0.2667 0 270)
			(size 0.3048 0.381)
			(layers "B.Cu" "B.Mask" "B.Paste")
			(net "GND")
		)
	)
	(footprint ""
		(layer "B.Cu")
		(at 60.599828 -299.699934 -90)
		(property "Reference" "C1229"
			(at 0 0 90)
			(layer "B.SilkS")
			(hide yes)
			(effects
				(font
					(size 1.27 1.27)
				)
				(justify mirror)
			)
		)
		(property "Value" ""
			(at 0 0 90)
			(layer "B.Fab")
			(effects
				(font
					(size 1.27 1.27)
				)
				(justify mirror)
			)
		)
		(duplicate_pad_numbers_are_jumpers no)
		(fp_line
			(start -0.299974 0.150114)
			(end 0.299974 0.150114)
			(stroke
				(width 0.1)
				(type default)
			)
			(layer "B.Fab")
		)
		(fp_line
			(start 0.299974 0.150114)
			(end 0.299974 -0.150114)
			(stroke
				(width 0.1)
				(type default)
			)
			(layer "B.Fab")
		)
		(fp_line
			(start -0.299974 -0.150114)
			(end -0.299974 0.150114)
			(stroke
				(width 0.1)
				(type default)
			)
			(layer "B.Fab")
		)
		(fp_line
			(start 0.299974 -0.150114)
			(end -0.299974 -0.150114)
			(stroke
				(width 0.1)
				(type default)
			)
			(layer "B.Fab")
		)
		(pad "1" smd rect
			(at 0.2667 0 90)
			(size 0.3048 0.381)
			(layers "B.Cu" "B.Mask" "B.Paste")
			(net "P0V8_SERDES_VDDA_PEX0")
		)
		(pad "2" smd rect
			(at -0.2667 0 90)
			(size 0.3048 0.381)
			(layers "B.Cu" "B.Mask" "B.Paste")
			(net "GND")
		)
	)
	(footprint ""
		(layer "B.Cu")
		(at 276.649688 -298.27474)
		(property "Reference" "C3358"
			(at 0 0 0)
			(layer "B.SilkS")
			(hide yes)
			(effects
				(font
					(size 1.27 1.27)
				)
				(justify mirror)
			)
		)
		(property "Value" ""
			(at 0 0 0)
			(layer "B.Fab")
			(effects
				(font
					(size 1.27 1.27)
				)
				(justify mirror)
			)
		)
		(duplicate_pad_numbers_are_jumpers no)
		(fp_line
			(start -0.299974 -0.150114)
			(end -0.299974 0.150114)
			(stroke
				(width 0.1)
				(type default)
			)
			(layer "B.Fab")
		)
		(fp_line
			(start -0.299974 0.150114)
			(end 0.299974 0.150114)
			(stroke
				(width 0.1)
				(type default)
			)
			(layer "B.Fab")
		)
		(fp_line
			(start 0.299974 -0.150114)
			(end -0.299974 -0.150114)
			(stroke
				(width 0.1)
				(type default)
			)
			(layer "B.Fab")
		)
		(fp_line
			(start 0.299974 0.150114)
			(end 0.299974 -0.150114)
			(stroke
				(width 0.1)
				(type default)
			)
			(layer "B.Fab")
		)
		(pad "1" smd rect
			(at 0.2667 0 180)
			(size 0.3048 0.381)
			(layers "B.Cu" "B.Mask" "B.Paste")
			(net "P1V8_VDDA_PEX2")
		)
		(pad "2" smd rect
			(at -0.2667 0 180)
			(size 0.3048 0.381)
			(layers "B.Cu" "B.Mask" "B.Paste")
			(net "GND")
		)
	)
	(footprint ""
		(layer "B.Cu")
		(at 77.541882 -100.056696 180)
		(property "Reference" "R77"
			(at 0 0 0)
			(layer "B.SilkS")
			(hide yes)
			(effects
				(font
					(size 1.27 1.27)
				)
				(justify mirror)
			)
		)
		(property "Value" ""
			(at 0 0 0)
			(layer "B.Fab")
			(effects
				(font
					(size 1.27 1.27)
				)
				(justify mirror)
			)
		)
		(duplicate_pad_numbers_are_jumpers no)
		(fp_line
			(start 0.7874 0.4064)
			(end 0.7874 -0.4064)
			(stroke
				(width 0.1524)
				(type default)
			)
			(layer "B.SilkS")
		)
		(fp_line
			(start 0.7874 -0.4064)
			(end -0.7874 -0.4064)
			(stroke
				(width 0.1524)
				(type default)
			)
			(layer "B.SilkS")
		)
		(fp_line
			(start -0.7874 0.4064)
			(end 0.7874 0.4064)
			(stroke
				(width 0.1524)
				(type default)
			)
			(layer "B.SilkS")
		)
		(fp_line
			(start -0.7874 -0.4064)
			(end -0.7874 0.4064)
			(stroke
				(width 0.1524)
				(type default)
			)
			(layer "B.SilkS")
		)
		(fp_line
			(start 0.67945 0.3048)
			(end 0.67945 -0.305054)
			(stroke
				(width 0.1)
				(type default)
			)
			(layer "B.Fab")
		)
		(fp_line
			(start 0.67945 -0.305054)
			(end 0.12065 -0.305054)
			(stroke
				(width 0.1)
				(type default)
			)
			(layer "B.Fab")
		)
		(fp_line
			(start 0.12065 0.3048)
			(end 0.67945 0.3048)
			(stroke
				(width 0.1)
				(type default)
			)
			(layer "B.Fab")
		)
		(fp_line
			(start 0.12065 0.2794)
			(end 0.12065 0.3048)
			(stroke
				(width 0.1)
				(type default)
			)
			(layer "B.Fab")
		)
		(fp_line
			(start 0.12065 -0.2794)
			(end -0.12065 -0.2794)
			(stroke
				(width 0.1)
				(type default)
			)
			(layer "B.Fab")
		)
		(fp_line
			(start 0.12065 -0.305054)
			(end 0.12065 -0.2794)
			(stroke
				(width 0.1)
				(type default)
			)
			(layer "B.Fab")
		)
		(fp_line
			(start -0.120396 0.3048)
			(end -0.120396 0.2794)
			(stroke
				(width 0.1)
				(type default)
			)
			(layer "B.Fab")
		)
		(fp_line
			(start -0.120396 0.2794)
			(end 0.12065 0.2794)
			(stroke
				(width 0.1)
				(type default)
			)
			(layer "B.Fab")
		)
		(fp_line
			(start -0.12065 -0.2794)
			(end -0.12065 -0.3048)
			(stroke
				(width 0.1)
				(type default)
			)
			(layer "B.Fab")
		)
		(fp_line
			(start -0.12065 -0.3048)
			(end -0.67945 -0.3048)
			(stroke
				(width 0.1)
				(type default)
			)
			(layer "B.Fab")
		)
		(fp_line
			(start -0.67945 0.3048)
			(end -0.120396 0.3048)
			(stroke
				(width 0.1)
				(type default)
			)
			(layer "B.Fab")
		)
		(fp_line
			(start -0.67945 -0.3048)
			(end -0.67945 0.3048)
			(stroke
				(width 0.1)
				(type default)
			)
			(layer "B.Fab")
		)
		(pad "1" smd circle
			(at 0.40005 0)
			(size 0 0)
			(layers "B.Cu" "B.Mask" "B.Paste")
			(net "NIC1_SLOT_ID0")
		)
		(pad "2" smd circle
			(at -0.40005 0)
			(size 0 0)
			(layers "B.Cu" "B.Mask" "B.Paste")
			(net "GND")
		)
	)
	(footprint ""
		(layer "B.Cu")
		(at 341.293958 -218.787218 -90)
		(property "Reference" "C2069"
			(at 0 0 90)
			(layer "B.SilkS")
			(hide yes)
			(effects
				(font
					(size 1.27 1.27)
				)
				(justify mirror)
			)
		)
		(property "Value" ""
			(at 0 0 90)
			(layer "B.Fab")
			(effects
				(font
					(size 1.27 1.27)
				)
				(justify mirror)
			)
		)
		(duplicate_pad_numbers_are_jumpers no)
		(fp_line
			(start -0.69215 0.2921)
			(end 0.69215 0.2921)
			(stroke
				(width 0.1524)
				(type default)
			)
			(layer "B.SilkS")
		)
		(fp_line
			(start 0.69215 0.2921)
			(end 0.69215 -0.2921)
			(stroke
				(width 0.1524)
				(type default)
			)
			(layer "B.SilkS")
		)
		(fp_line
			(start -0.69215 -0.2921)
			(end -0.69215 0.2921)
			(stroke
				(width 0.1524)
				(type default)
			)
			(layer "B.SilkS")
		)
		(fp_line
			(start 0.69215 -0.2921)
			(end -0.69215 -0.2921)
			(stroke
				(width 0.1524)
				(type default)
			)
			(layer "B.SilkS")
		)
		(fp_line
			(start -0.51435 0.2794)
			(end 0.51435 0.2794)
			(stroke
				(width 0.1)
				(type default)
			)
			(layer "B.Fab")
		)
		(fp_line
			(start 0.51435 0.2794)
			(end 0.51435 -0.2794)
			(stroke
				(width 0.1)
				(type default)
			)
			(layer "B.Fab")
		)
		(fp_line
			(start -0.51435 -0.2794)
			(end -0.51435 0.2794)
			(stroke
				(width 0.1)
				(type default)
			)
			(layer "B.Fab")
		)
		(fp_line
			(start 0.51435 -0.2794)
			(end -0.51435 -0.2794)
			(stroke
				(width 0.1)
				(type default)
			)
			(layer "B.Fab")
		)
		(pad "1" smd circle
			(at 0.40005 0 90)
			(size 0 0)
			(layers "B.Cu" "B.Mask" "B.Paste")
			(net "P3V3_VCC_FPGA_CORE")
		)
		(pad "2" smd circle
			(at -0.40005 0 90)
			(size 0 0)
			(layers "B.Cu" "B.Mask" "B.Paste")
			(net "GND")
		)
		(zone
			(layer "B.Cu")
			(hatch none 0.5)
			(connect_pads
				(clearance 0)
			)
			(min_thickness 0.25)
			(keepout
				(tracks not_allowed)
				(vias allowed)
				(pads allowed)
				(copperpour not_allowed)
				(footprints allowed)
			)
			(placement
				(enabled no)
				(sheetname "")
			)
			(fill
				(thermal_gap 0.5)
				(thermal_bridge_width 0.5)
				(island_removal_mode 0)
			)
			(polygon
				(pts
					(xy 341.206328 -218.596718) (xy 341.148162 -218.688158) (xy 341.148162 -218.887548) (xy 341.206328 -218.977718)
					(xy 341.381588 -218.977718) (xy 341.440008 -218.887548) (xy 341.440008 -218.688158) (xy 341.381842 -218.596718)
				)
			)
		)
	)
	(footprint ""
		(layer "B.Cu")
		(at 62.499748 -301.599854 -90)
		(property "Reference" "C1233"
			(at 0 0 90)
			(layer "B.SilkS")
			(hide yes)
			(effects
				(font
					(size 1.27 1.27)
				)
				(justify mirror)
			)
		)
		(property "Value" ""
			(at 0 0 90)
			(layer "B.Fab")
			(effects
				(font
					(size 1.27 1.27)
				)
				(justify mirror)
			)
		)
		(duplicate_pad_numbers_are_jumpers no)
		(fp_line
			(start -0.299974 0.150114)
			(end 0.299974 0.150114)
			(stroke
				(width 0.1)
				(type default)
			)
			(layer "B.Fab")
		)
		(fp_line
			(start 0.299974 0.150114)
			(end 0.299974 -0.150114)
			(stroke
				(width 0.1)
				(type default)
			)
			(layer "B.Fab")
		)
		(fp_line
			(start -0.299974 -0.150114)
			(end -0.299974 0.150114)
			(stroke
				(width 0.1)
				(type default)
			)
			(layer "B.Fab")
		)
		(fp_line
			(start 0.299974 -0.150114)
			(end -0.299974 -0.150114)
			(stroke
				(width 0.1)
				(type default)
			)
			(layer "B.Fab")
		)
		(pad "1" smd rect
			(at 0.2667 0 90)
			(size 0.3048 0.381)
			(layers "B.Cu" "B.Mask" "B.Paste")
			(net "P0V8_SERDES_VDDA_PEX0")
		)
		(pad "2" smd rect
			(at -0.2667 0 90)
			(size 0.3048 0.381)
			(layers "B.Cu" "B.Mask" "B.Paste")
			(net "GND")
		)
	)
	(footprint ""
		(layer "B.Cu")
		(at 404.30704 -138.557 90)
		(property "Reference" "C947"
			(at 0 0 90)
			(layer "B.SilkS")
			(hide yes)
			(effects
				(font
					(size 1.27 1.27)
				)
				(justify mirror)
			)
		)
		(property "Value" ""
			(at 0 0 90)
			(layer "B.Fab")
			(effects
				(font
					(size 1.27 1.27)
				)
				(justify mirror)
			)
		)
		(duplicate_pad_numbers_are_jumpers no)
		(fp_line
			(start 0.7874 -0.4064)
			(end -0.7874 -0.4064)
			(stroke
				(width 0.1524)
				(type default)
			)
			(layer "B.SilkS")
		)
		(fp_line
			(start -0.7874 -0.4064)
			(end -0.7874 0.4064)
			(stroke
				(width 0.1524)
				(type default)
			)
			(layer "B.SilkS")
		)
		(fp_line
			(start 0.7874 0.4064)
			(end 0.7874 -0.4064)
			(stroke
				(width 0.1524)
				(type default)
			)
			(layer "B.SilkS")
		)
		(fp_line
			(start -0.7874 0.4064)
			(end 0.7874 0.4064)
			(stroke
				(width 0.1524)
				(type default)
			)
			(layer "B.SilkS")
		)
		(fp_line
			(start 0.67945 -0.305054)
			(end 0.12065 -0.305054)
			(stroke
				(width 0.1)
				(type default)
			)
			(layer "B.Fab")
		)
		(fp_line
			(start 0.12065 -0.305054)
			(end 0.12065 -0.2794)
			(stroke
				(width 0.1)
				(type default)
			)
			(layer "B.Fab")
		)
		(fp_line
			(start -0.12065 -0.3048)
			(end -0.67945 -0.3048)
			(stroke
				(width 0.1)
				(type default)
			)
			(layer "B.Fab")
		)
		(fp_line
			(start -0.67945 -0.3048)
			(end -0.67945 0.3048)
			(stroke
				(width 0.1)
				(type default)
			)
			(layer "B.Fab")
		)
		(fp_line
			(start 0.12065 -0.2794)
			(end -0.12065 -0.2794)
			(stroke
				(width 0.1)
				(type default)
			)
			(layer "B.Fab")
		)
		(fp_line
			(start -0.12065 -0.2794)
			(end -0.12065 -0.3048)
			(stroke
				(width 0.1)
				(type default)
			)
			(layer "B.Fab")
		)
		(fp_line
			(start 0.12065 0.2794)
			(end 0.12065 0.3048)
			(stroke
				(width 0.1)
				(type default)
			)
			(layer "B.Fab")
		)
		(fp_line
			(start -0.120396 0.2794)
			(end 0.12065 0.2794)
			(stroke
				(width 0.1)
				(type default)
			)
			(layer "B.Fab")
		)
		(fp_line
			(start 0.67945 0.3048)
			(end 0.67945 -0.305054)
			(stroke
				(width 0.1)
				(type default)
			)
			(layer "B.Fab")
		)
		(fp_line
			(start 0.12065 0.3048)
			(end 0.67945 0.3048)
			(stroke
				(width 0.1)
				(type default)
			)
			(layer "B.Fab")
		)
		(fp_line
			(start -0.120396 0.3048)
			(end -0.120396 0.2794)
			(stroke
				(width 0.1)
				(type default)
			)
			(layer "B.Fab")
		)
		(fp_line
			(start -0.67945 0.3048)
			(end -0.120396 0.3048)
			(stroke
				(width 0.1)
				(type default)
			)
			(layer "B.Fab")
		)
		(pad "1" smd circle
			(at 0.40005 0 270)
			(size 0 0)
			(layers "B.Cu" "B.Mask" "B.Paste")
			(net "P3V3_AUX")
		)
		(pad "2" smd circle
			(at -0.40005 0 270)
			(size 0 0)
			(layers "B.Cu" "B.Mask" "B.Paste")
			(net "GND")
		)
	)
	(footprint ""
		(layer "B.Cu")
		(at 306.226718 -299.2247 90)
		(property "Reference" "R1381"
			(at 0 0 90)
			(layer "B.SilkS")
			(hide yes)
			(effects
				(font
					(size 1.27 1.27)
				)
				(justify mirror)
			)
		)
		(property "Value" ""
			(at 0 0 90)
			(layer "B.Fab")
			(effects
				(font
					(size 1.27 1.27)
				)
				(justify mirror)
			)
		)
		(duplicate_pad_numbers_are_jumpers no)
		(fp_line
			(start 0.7874 -0.4064)
			(end -0.7874 -0.4064)
			(stroke
				(width 0.1524)
				(type default)
			)
			(layer "B.SilkS")
		)
		(fp_line
			(start -0.7874 -0.4064)
			(end -0.7874 0.4064)
			(stroke
				(width 0.1524)
				(type default)
			)
			(layer "B.SilkS")
		)
		(fp_line
			(start 0.7874 0.4064)
			(end 0.7874 -0.4064)
			(stroke
				(width 0.1524)
				(type default)
			)
			(layer "B.SilkS")
		)
		(fp_line
			(start -0.7874 0.4064)
			(end 0.7874 0.4064)
			(stroke
				(width 0.1524)
				(type default)
			)
			(layer "B.SilkS")
		)
		(fp_line
			(start 0.67945 -0.305054)
			(end 0.12065 -0.305054)
			(stroke
				(width 0.1)
				(type default)
			)
			(layer "B.Fab")
		)
		(fp_line
			(start 0.12065 -0.305054)
			(end 0.12065 -0.2794)
			(stroke
				(width 0.1)
				(type default)
			)
			(layer "B.Fab")
		)
		(fp_line
			(start -0.12065 -0.3048)
			(end -0.67945 -0.3048)
			(stroke
				(width 0.1)
				(type default)
			)
			(layer "B.Fab")
		)
		(fp_line
			(start -0.67945 -0.3048)
			(end -0.67945 0.3048)
			(stroke
				(width 0.1)
				(type default)
			)
			(layer "B.Fab")
		)
		(fp_line
			(start 0.12065 -0.2794)
			(end -0.12065 -0.2794)
			(stroke
				(width 0.1)
				(type default)
			)
			(layer "B.Fab")
		)
		(fp_line
			(start -0.12065 -0.2794)
			(end -0.12065 -0.3048)
			(stroke
				(width 0.1)
				(type default)
			)
			(layer "B.Fab")
		)
		(fp_line
			(start 0.12065 0.2794)
			(end 0.12065 0.3048)
			(stroke
				(width 0.1)
				(type default)
			)
			(layer "B.Fab")
		)
		(fp_line
			(start -0.120396 0.2794)
			(end 0.12065 0.2794)
			(stroke
				(width 0.1)
				(type default)
			)
			(layer "B.Fab")
		)
		(fp_line
			(start 0.67945 0.3048)
			(end 0.67945 -0.305054)
			(stroke
				(width 0.1)
				(type default)
			)
			(layer "B.Fab")
		)
		(fp_line
			(start 0.12065 0.3048)
			(end 0.67945 0.3048)
			(stroke
				(width 0.1)
				(type default)
			)
			(layer "B.Fab")
		)
		(fp_line
			(start -0.120396 0.3048)
			(end -0.120396 0.2794)
			(stroke
				(width 0.1)
				(type default)
			)
			(layer "B.Fab")
		)
		(fp_line
			(start -0.67945 0.3048)
			(end -0.120396 0.3048)
			(stroke
				(width 0.1)
				(type default)
			)
			(layer "B.Fab")
		)
		(pad "1" smd circle
			(at 0.40005 0 270)
			(size 0 0)
			(layers "B.Cu" "B.Mask" "B.Paste")
			(net "PEX2_ADCTEMP_VINP1")
		)
		(pad "2" smd circle
			(at -0.40005 0 270)
			(size 0 0)
			(layers "B.Cu" "B.Mask" "B.Paste")
			(net "GND")
		)
	)
	(footprint ""
		(layer "B.Cu")
		(at 172.424852 -286.399732 90)
		(property "Reference" "C3134"
			(at 0 0 90)
			(layer "B.SilkS")
			(hide yes)
			(effects
				(font
					(size 1.27 1.27)
				)
				(justify mirror)
			)
		)
		(property "Value" ""
			(at 0 0 90)
			(layer "B.Fab")
			(effects
				(font
					(size 1.27 1.27)
				)
				(justify mirror)
			)
		)
		(duplicate_pad_numbers_are_jumpers no)
		(fp_line
			(start 0.299974 -0.150114)
			(end -0.299974 -0.150114)
			(stroke
				(width 0.1)
				(type default)
			)
			(layer "B.Fab")
		)
		(fp_line
			(start -0.299974 -0.150114)
			(end -0.299974 0.150114)
			(stroke
				(width 0.1)
				(type default)
			)
			(layer "B.Fab")
		)
		(fp_line
			(start 0.299974 0.150114)
			(end 0.299974 -0.150114)
			(stroke
				(width 0.1)
				(type default)
			)
			(layer "B.Fab")
		)
		(fp_line
			(start -0.299974 0.150114)
			(end 0.299974 0.150114)
			(stroke
				(width 0.1)
				(type default)
			)
			(layer "B.Fab")
		)
		(pad "1" smd rect
			(at 0.2667 0 270)
			(size 0.3048 0.381)
			(layers "B.Cu" "B.Mask" "B.Paste")
			(net "P1V25_SERDES_VDDPLL_PEX1")
		)
		(pad "2" smd rect
			(at -0.2667 0 270)
			(size 0.3048 0.381)
			(layers "B.Cu" "B.Mask" "B.Paste")
			(net "GND")
		)
	)
	(footprint ""
		(layer "B.Cu")
		(at 65.349882 -292.099746 90)
		(property "Reference" "C1167"
			(at 0 0 90)
			(layer "B.SilkS")
			(hide yes)
			(effects
				(font
					(size 1.27 1.27)
				)
				(justify mirror)
			)
		)
		(property "Value" ""
			(at 0 0 90)
			(layer "B.Fab")
			(effects
				(font
					(size 1.27 1.27)
				)
				(justify mirror)
			)
		)
		(duplicate_pad_numbers_are_jumpers no)
		(fp_line
			(start 0.299974 -0.150114)
			(end -0.299974 -0.150114)
			(stroke
				(width 0.1)
				(type default)
			)
			(layer "B.Fab")
		)
		(fp_line
			(start -0.299974 -0.150114)
			(end -0.299974 0.150114)
			(stroke
				(width 0.1)
				(type default)
			)
			(layer "B.Fab")
		)
		(fp_line
			(start 0.299974 0.150114)
			(end 0.299974 -0.150114)
			(stroke
				(width 0.1)
				(type default)
			)
			(layer "B.Fab")
		)
		(fp_line
			(start -0.299974 0.150114)
			(end 0.299974 0.150114)
			(stroke
				(width 0.1)
				(type default)
			)
			(layer "B.Fab")
		)
		(pad "1" smd rect
			(at 0.2667 0 270)
			(size 0.3048 0.381)
			(layers "B.Cu" "B.Mask" "B.Paste")
			(net "P0V8_SERDES_VDDA_PEX0")
		)
		(pad "2" smd rect
			(at -0.2667 0 270)
			(size 0.3048 0.381)
			(layers "B.Cu" "B.Mask" "B.Paste")
			(net "GND")
		)
	)
	(footprint ""
		(layer "B.Cu")
		(at 59.01817 -153.72461 180)
		(property "Reference" "U10"
			(at 0.7239 -1.901952 0)
			(unlocked yes)
			(layer "B.SilkS")
			(effects
				(font
					(size 0.7874 0.5842)
					(thickness 0.1524)
				)
				(justify mirror)
			)
		)
		(property "Value" ""
			(at 0 0 0)
			(layer "B.Fab")
			(effects
				(font
					(size 1.27 1.27)
				)
				(justify mirror)
			)
		)
		(duplicate_pad_numbers_are_jumpers no)
		(fp_line
			(start 1.684274 1.074928)
			(end 1.684274 -1.074928)
			(stroke
				(width 0.1524)
				(type default)
			)
			(layer "B.SilkS")
		)
		(fp_line
			(start 1.684274 -1.074928)
			(end 0.381 -1.074928)
			(stroke
				(width 0.1524)
				(type default)
			)
			(layer "B.SilkS")
		)
		(fp_line
			(start 0.381 -1.074928)
			(end 0 -0.625094)
			(stroke
				(width 0.1524)
				(type default)
			)
			(layer "B.SilkS")
		)
		(fp_line
			(start 0 -0.625094)
			(end -0.381 -1.074928)
			(stroke
				(width 0.1524)
				(type default)
			)
			(layer "B.SilkS")
		)
		(fp_line
			(start -0.381 -1.074928)
			(end -1.684274 -1.074928)
			(stroke
				(width 0.1524)
				(type default)
			)
			(layer "B.SilkS")
		)
		(fp_line
			(start -1.684274 1.074928)
			(end 1.684274 1.074928)
			(stroke
				(width 0.1524)
				(type default)
			)
			(layer "B.SilkS")
		)
		(fp_line
			(start -1.684274 -1.074928)
			(end -1.684274 1.074928)
			(stroke
				(width 0.1524)
				(type default)
			)
			(layer "B.SilkS")
		)
		(fp_poly
			(pts
				(xy 2.637282 -0.903986) (xy 2.637282 -0.395986) (xy 1.875282 -0.649986)
			)
			(stroke
				(width 0)
				(type default)
			)
			(fill yes)
			(layer "B.SilkS")
		)
		(fp_line
			(start 0.700024 1.074928)
			(end -0.700024 1.074928)
			(stroke
				(width 0.1)
				(type default)
			)
			(layer "B.Fab")
		)
		(fp_line
			(start 0.700024 -1.074928)
			(end 0.700024 1.074928)
			(stroke
				(width 0.1)
				(type default)
			)
			(layer "B.Fab")
		)
		(fp_line
			(start -0.700024 1.074928)
			(end -0.700024 -1.074928)
			(stroke
				(width 0.1)
				(type default)
			)
			(layer "B.Fab")
		)
		(fp_line
			(start -0.700024 -1.074928)
			(end 0.700024 -1.074928)
			(stroke
				(width 0.1)
				(type default)
			)
			(layer "B.Fab")
		)
		(fp_poly
			(pts
				(xy 2.637282 -0.903986) (xy 2.637282 -0.395986) (xy 1.875282 -0.649986)
			)
			(stroke
				(width 0)
				(type default)
			)
			(fill yes)
			(layer "B.Fab")
		)
		(pad "1" smd rect
			(at 1.100074 -0.649986 90)
			(size 0.4064 0.9144)
			(layers "B.Cu" "B.Mask" "B.Paste")
			(net "Net_8456")
		)
		(pad "2" smd rect
			(at 1.100074 0 90)
			(size 0.4064 0.9144)
			(layers "B.Cu" "B.Mask" "B.Paste")
			(net "RST_HP_NIC0_N")
		)
		(pad "3" smd rect
			(at 1.100074 0.649986 90)
			(size 0.4064 0.9144)
			(layers "B.Cu" "B.Mask" "B.Paste")
			(net "GND")
		)
		(pad "4" smd rect
			(at -1.100074 0.649986 90)
			(size 0.4064 0.9144)
			(layers "B.Cu" "B.Mask" "B.Paste")
			(net "RST_HP_NIC0_BUF_N")
		)
		(pad "5" smd rect
			(at -1.100074 -0.649986 90)
			(size 0.4064 0.9144)
			(layers "B.Cu" "B.Mask" "B.Paste")
			(net "P3V3_AUX")
		)
	)
	(footprint ""
		(layer "B.Cu")
		(at 407.949908 -301.599854 -90)
		(property "Reference" "C1989"
			(at 0 0 90)
			(layer "B.SilkS")
			(hide yes)
			(effects
				(font
					(size 1.27 1.27)
				)
				(justify mirror)
			)
		)
		(property "Value" ""
			(at 0 0 90)
			(layer "B.Fab")
			(effects
				(font
					(size 1.27 1.27)
				)
				(justify mirror)
			)
		)
		(duplicate_pad_numbers_are_jumpers no)
		(fp_line
			(start -0.299974 0.150114)
			(end 0.299974 0.150114)
			(stroke
				(width 0.1)
				(type default)
			)
			(layer "B.Fab")
		)
		(fp_line
			(start 0.299974 0.150114)
			(end 0.299974 -0.150114)
			(stroke
				(width 0.1)
				(type default)
			)
			(layer "B.Fab")
		)
		(fp_line
			(start -0.299974 -0.150114)
			(end -0.299974 0.150114)
			(stroke
				(width 0.1)
				(type default)
			)
			(layer "B.Fab")
		)
		(fp_line
			(start 0.299974 -0.150114)
			(end -0.299974 -0.150114)
			(stroke
				(width 0.1)
				(type default)
			)
			(layer "B.Fab")
		)
		(pad "1" smd rect
			(at 0.2667 0 90)
			(size 0.3048 0.381)
			(layers "B.Cu" "B.Mask" "B.Paste")
			(net "P0V8_SERDES_VDDA_PEX3")
		)
		(pad "2" smd rect
			(at -0.2667 0 90)
			(size 0.3048 0.381)
			(layers "B.Cu" "B.Mask" "B.Paste")
			(net "GND")
		)
	)
	(footprint ""
		(layer "B.Cu")
		(at 181.44998 -290.199826 90)
		(property "Reference" "C1427"
			(at 0 0 90)
			(layer "B.SilkS")
			(hide yes)
			(effects
				(font
					(size 1.27 1.27)
				)
				(justify mirror)
			)
		)
		(property "Value" ""
			(at 0 0 90)
			(layer "B.Fab")
			(effects
				(font
					(size 1.27 1.27)
				)
				(justify mirror)
			)
		)
		(duplicate_pad_numbers_are_jumpers no)
		(fp_line
			(start 0.299974 -0.150114)
			(end -0.299974 -0.150114)
			(stroke
				(width 0.1)
				(type default)
			)
			(layer "B.Fab")
		)
		(fp_line
			(start -0.299974 -0.150114)
			(end -0.299974 0.150114)
			(stroke
				(width 0.1)
				(type default)
			)
			(layer "B.Fab")
		)
		(fp_line
			(start 0.299974 0.150114)
			(end 0.299974 -0.150114)
			(stroke
				(width 0.1)
				(type default)
			)
			(layer "B.Fab")
		)
		(fp_line
			(start -0.299974 0.150114)
			(end 0.299974 0.150114)
			(stroke
				(width 0.1)
				(type default)
			)
			(layer "B.Fab")
		)
		(pad "1" smd rect
			(at 0.2667 0 270)
			(size 0.3048 0.381)
			(layers "B.Cu" "B.Mask" "B.Paste")
			(net "P0V8_SERDES_VDDA_PEX1")
		)
		(pad "2" smd rect
			(at -0.2667 0 270)
			(size 0.3048 0.381)
			(layers "B.Cu" "B.Mask" "B.Paste")
			(net "GND")
		)
	)
	(footprint ""
		(layer "B.Cu")
		(at 372.974108 -223.315276 180)
		(property "Reference" "C2504"
			(at 0 0 0)
			(layer "B.SilkS")
			(hide yes)
			(effects
				(font
					(size 1.27 1.27)
				)
				(justify mirror)
			)
		)
		(property "Value" ""
			(at 0 0 0)
			(layer "B.Fab")
			(effects
				(font
					(size 1.27 1.27)
				)
				(justify mirror)
			)
		)
		(duplicate_pad_numbers_are_jumpers no)
		(fp_line
			(start 0.7874 0.4064)
			(end 0.7874 -0.4064)
			(stroke
				(width 0.1524)
				(type default)
			)
			(layer "B.SilkS")
		)
		(fp_line
			(start 0.7874 -0.4064)
			(end -0.7874 -0.4064)
			(stroke
				(width 0.1524)
				(type default)
			)
			(layer "B.SilkS")
		)
		(fp_line
			(start -0.7874 0.4064)
			(end 0.7874 0.4064)
			(stroke
				(width 0.1524)
				(type default)
			)
			(layer "B.SilkS")
		)
		(fp_line
			(start -0.7874 -0.4064)
			(end -0.7874 0.4064)
			(stroke
				(width 0.1524)
				(type default)
			)
			(layer "B.SilkS")
		)
		(fp_line
			(start 0.67945 0.3048)
			(end 0.67945 -0.305054)
			(stroke
				(width 0.1)
				(type default)
			)
			(layer "B.Fab")
		)
		(fp_line
			(start 0.67945 -0.305054)
			(end 0.12065 -0.305054)
			(stroke
				(width 0.1)
				(type default)
			)
			(layer "B.Fab")
		)
		(fp_line
			(start 0.12065 0.3048)
			(end 0.67945 0.3048)
			(stroke
				(width 0.1)
				(type default)
			)
			(layer "B.Fab")
		)
		(fp_line
			(start 0.12065 0.2794)
			(end 0.12065 0.3048)
			(stroke
				(width 0.1)
				(type default)
			)
			(layer "B.Fab")
		)
		(fp_line
			(start 0.12065 -0.2794)
			(end -0.12065 -0.2794)
			(stroke
				(width 0.1)
				(type default)
			)
			(layer "B.Fab")
		)
		(fp_line
			(start 0.12065 -0.305054)
			(end 0.12065 -0.2794)
			(stroke
				(width 0.1)
				(type default)
			)
			(layer "B.Fab")
		)
		(fp_line
			(start -0.120396 0.3048)
			(end -0.120396 0.2794)
			(stroke
				(width 0.1)
				(type default)
			)
			(layer "B.Fab")
		)
		(fp_line
			(start -0.120396 0.2794)
			(end 0.12065 0.2794)
			(stroke
				(width 0.1)
				(type default)
			)
			(layer "B.Fab")
		)
		(fp_line
			(start -0.12065 -0.2794)
			(end -0.12065 -0.3048)
			(stroke
				(width 0.1)
				(type default)
			)
			(layer "B.Fab")
		)
		(fp_line
			(start -0.12065 -0.3048)
			(end -0.67945 -0.3048)
			(stroke
				(width 0.1)
				(type default)
			)
			(layer "B.Fab")
		)
		(fp_line
			(start -0.67945 0.3048)
			(end -0.120396 0.3048)
			(stroke
				(width 0.1)
				(type default)
			)
			(layer "B.Fab")
		)
		(fp_line
			(start -0.67945 -0.3048)
			(end -0.67945 0.3048)
			(stroke
				(width 0.1)
				(type default)
			)
			(layer "B.Fab")
		)
		(pad "1" smd circle
			(at 0.40005 0)
			(size 0 0)
			(layers "B.Cu" "B.Mask" "B.Paste")
			(net "GND")
		)
		(pad "2" smd circle
			(at -0.40005 0)
			(size 0 0)
			(layers "B.Cu" "B.Mask" "B.Paste")
			(net "P1V8_PEX")
		)
	)
	(footprint ""
		(layer "B.Cu")
		(at 2.840736 -382.780032 90)
		(property "Reference" "L150"
			(at 2.087118 0.013462 270)
			(unlocked yes)
			(layer "B.SilkS")
			(effects
				(font
					(size 0.7874 0.5842)
					(thickness 0.1524)
				)
				(justify left mirror)
			)
		)
		(property "Value" ""
			(at 0 0 90)
			(layer "B.Fab")
			(effects
				(font
					(size 1.27 1.27)
				)
				(justify mirror)
			)
		)
		(duplicate_pad_numbers_are_jumpers no)
		(fp_line
			(start 1.63576 -0.8128)
			(end -1.63576 -0.8128)
			(stroke
				(width 0.1524)
				(type default)
			)
			(layer "B.SilkS")
		)
		(fp_line
			(start 1.63576 -0.8128)
			(end 1.63576 0.8128)
			(stroke
				(width 0.1524)
				(type default)
			)
			(layer "B.SilkS")
		)
		(fp_line
			(start -1.63576 -0.8128)
			(end -1.63576 0.8128)
			(stroke
				(width 0.1524)
				(type default)
			)
			(layer "B.SilkS")
		)
		(fp_line
			(start -1.63576 0.8128)
			(end 1.63576 0.8128)
			(stroke
				(width 0.1524)
				(type default)
			)
			(layer "B.SilkS")
		)
		(fp_line
			(start 1.56083 -0.738632)
			(end 1.56083 0.7366)
			(stroke
				(width 0.1)
				(type default)
			)
			(layer "B.Fab")
		)
		(fp_line
			(start -1.560576 -0.738632)
			(end 1.56083 -0.738632)
			(stroke
				(width 0.1)
				(type default)
			)
			(layer "B.Fab")
		)
		(fp_line
			(start 1.56083 0.7366)
			(end 1.524 0.7366)
			(stroke
				(width 0.1)
				(type default)
			)
			(layer "B.Fab")
		)
		(fp_line
			(start 1.524 0.7366)
			(end -1.524 0.7366)
			(stroke
				(width 0.1)
				(type default)
			)
			(layer "B.Fab")
		)
		(fp_line
			(start -1.524 0.7366)
			(end -1.560576 0.7366)
			(stroke
				(width 0.1)
				(type default)
			)
			(layer "B.Fab")
		)
		(fp_line
			(start -1.560576 0.7366)
			(end -1.560576 -0.738632)
			(stroke
				(width 0.1)
				(type default)
			)
			(layer "B.Fab")
		)
		(pad "1" smd rect
			(at 0.94996 0 90)
			(size 1.1176 1.3716)
			(layers "B.Cu" "B.Mask" "B.Paste")
			(net "P3V3_USB_8042")
		)
		(pad "2" smd rect
			(at -0.94996 0 90)
			(size 1.1176 1.3716)
			(layers "B.Cu" "B.Mask" "B.Paste")
			(net "P3V3_USB_HUB")
		)
	)
	(footprint ""
		(layer "B.Cu")
		(at 298.05122 -305.399948 -90)
		(property "Reference" "C3305"
			(at 0 0 90)
			(layer "B.SilkS")
			(hide yes)
			(effects
				(font
					(size 1.27 1.27)
				)
				(justify mirror)
			)
		)
		(property "Value" ""
			(at 0 0 90)
			(layer "B.Fab")
			(effects
				(font
					(size 1.27 1.27)
				)
				(justify mirror)
			)
		)
		(duplicate_pad_numbers_are_jumpers no)
		(fp_line
			(start -0.299974 0.150114)
			(end 0.299974 0.150114)
			(stroke
				(width 0.1)
				(type default)
			)
			(layer "B.Fab")
		)
		(fp_line
			(start 0.299974 0.150114)
			(end 0.299974 -0.150114)
			(stroke
				(width 0.1)
				(type default)
			)
			(layer "B.Fab")
		)
		(fp_line
			(start -0.299974 -0.150114)
			(end -0.299974 0.150114)
			(stroke
				(width 0.1)
				(type default)
			)
			(layer "B.Fab")
		)
		(fp_line
			(start 0.299974 -0.150114)
			(end -0.299974 -0.150114)
			(stroke
				(width 0.1)
				(type default)
			)
			(layer "B.Fab")
		)
		(pad "1" smd rect
			(at 0.2667 0 90)
			(size 0.3048 0.381)
			(layers "B.Cu" "B.Mask" "B.Paste")
			(net "P1V25_SERDES_VDDPLL_PEX2")
		)
		(pad "2" smd rect
			(at -0.2667 0 90)
			(size 0.3048 0.381)
			(layers "B.Cu" "B.Mask" "B.Paste")
			(net "GND")
		)
	)
	(footprint ""
		(layer "B.Cu")
		(at 347.390974 -326.945498 -90)
		(property "Reference" "C4324"
			(at 0 0 90)
			(layer "B.SilkS")
			(hide yes)
			(effects
				(font
					(size 1.27 1.27)
				)
				(justify mirror)
			)
		)
		(property "Value" ""
			(at 0 0 90)
			(layer "B.Fab")
			(effects
				(font
					(size 1.27 1.27)
				)
				(justify mirror)
			)
		)
		(duplicate_pad_numbers_are_jumpers no)
		(fp_line
			(start -1.2954 0.5842)
			(end 1.2954 0.5842)
			(stroke
				(width 0.1524)
				(type default)
			)
			(layer "B.SilkS")
		)
		(fp_line
			(start 1.2954 0.5842)
			(end 1.2954 -0.5842)
			(stroke
				(width 0.1524)
				(type default)
			)
			(layer "B.SilkS")
		)
		(fp_line
			(start -1.2954 -0.5842)
			(end -1.2954 0.5842)
			(stroke
				(width 0.1524)
				(type default)
			)
			(layer "B.SilkS")
		)
		(fp_line
			(start 1.2954 -0.5842)
			(end -1.2954 -0.5842)
			(stroke
				(width 0.1524)
				(type default)
			)
			(layer "B.SilkS")
		)
		(fp_line
			(start -0.8636 0.4572)
			(end 0.8636 0.4572)
			(stroke
				(width 0.1)
				(type default)
			)
			(layer "B.Fab")
		)
		(fp_line
			(start 0.8636 0.4572)
			(end 0.8636 0.4064)
			(stroke
				(width 0.1)
				(type default)
			)
			(layer "B.Fab")
		)
		(fp_line
			(start -1.1938 0.4064)
			(end -0.8636 0.4064)
			(stroke
				(width 0.1)
				(type default)
			)
			(layer "B.Fab")
		)
		(fp_line
			(start -0.8636 0.4064)
			(end -0.8636 0.4572)
			(stroke
				(width 0.1)
				(type default)
			)
			(layer "B.Fab")
		)
		(fp_line
			(start 0.8636 0.4064)
			(end 1.1938 0.4064)
			(stroke
				(width 0.1)
				(type default)
			)
			(layer "B.Fab")
		)
		(fp_line
			(start 1.1938 0.4064)
			(end 1.1938 -0.4064)
			(stroke
				(width 0.1)
				(type default)
			)
			(layer "B.Fab")
		)
		(fp_line
			(start -1.1938 -0.4064)
			(end -1.1938 0.4064)
			(stroke
				(width 0.1)
				(type default)
			)
			(layer "B.Fab")
		)
		(fp_line
			(start -0.8636 -0.4064)
			(end -1.1938 -0.4064)
			(stroke
				(width 0.1)
				(type default)
			)
			(layer "B.Fab")
		)
		(fp_line
			(start 0.8636 -0.4064)
			(end 0.8636 -0.4572)
			(stroke
				(width 0.1)
				(type default)
			)
			(layer "B.Fab")
		)
		(fp_line
			(start 1.1938 -0.4064)
			(end 0.8636 -0.4064)
			(stroke
				(width 0.1)
				(type default)
			)
			(layer "B.Fab")
		)
		(fp_line
			(start -0.8636 -0.4572)
			(end -0.8636 -0.4064)
			(stroke
				(width 0.1)
				(type default)
			)
			(layer "B.Fab")
		)
		(fp_line
			(start 0.8636 -0.4572)
			(end -0.8636 -0.4572)
			(stroke
				(width 0.1)
				(type default)
			)
			(layer "B.Fab")
		)
		(pad "1" smd rect
			(at 0.7366 0 180)
			(size 0.7112 0.8128)
			(layers "B.Cu" "B.Mask" "B.Paste")
			(net "P0V8_SERDES_VDDA_PEX2_C6")
		)
		(pad "2" smd rect
			(at -0.7366 0 180)
			(size 0.7112 0.8128)
			(layers "B.Cu" "B.Mask" "B.Paste")
			(net "GND")
		)
	)
	(footprint ""
		(layer "B.Cu")
		(at 129.23774 -281.024838 90)
		(property "Reference" "PC112"
			(at 0 0 90)
			(layer "B.SilkS")
			(hide yes)
			(effects
				(font
					(size 1.27 1.27)
				)
				(justify mirror)
			)
		)
		(property "Value" ""
			(at 0 0 90)
			(layer "B.Fab")
			(effects
				(font
					(size 1.27 1.27)
				)
				(justify mirror)
			)
		)
		(duplicate_pad_numbers_are_jumpers no)
		(fp_line
			(start 1.524 -0.762)
			(end -1.524 -0.762)
			(stroke
				(width 0.1524)
				(type default)
			)
			(layer "B.SilkS")
		)
		(fp_line
			(start -1.524 -0.762)
			(end -1.524 0.762)
			(stroke
				(width 0.1524)
				(type default)
			)
			(layer "B.SilkS")
		)
		(fp_line
			(start 1.524 0.762)
			(end 1.524 -0.762)
			(stroke
				(width 0.1524)
				(type default)
			)
			(layer "B.SilkS")
		)
		(fp_line
			(start -1.524 0.762)
			(end 1.524 0.762)
			(stroke
				(width 0.1524)
				(type default)
			)
			(layer "B.SilkS")
		)
		(fp_line
			(start 1.1049 -0.724916)
			(end 1.1049 0.724916)
			(stroke
				(width 0.1)
				(type default)
			)
			(layer "B.Fab")
		)
		(fp_line
			(start -1.1049 -0.724916)
			(end 1.1049 -0.724916)
			(stroke
				(width 0.1)
				(type default)
			)
			(layer "B.Fab")
		)
		(fp_line
			(start 1.1049 0.724916)
			(end -1.1049 0.724916)
			(stroke
				(width 0.1)
				(type default)
			)
			(layer "B.Fab")
		)
		(fp_line
			(start -1.1049 0.724916)
			(end -1.1049 -0.724916)
			(stroke
				(width 0.1)
				(type default)
			)
			(layer "B.Fab")
		)
		(pad "1" smd rect
			(at 0.889 0 90)
			(size 1.016 1.27)
			(layers "B.Cu" "B.Mask" "B.Paste")
			(net "SW_P12V_P0V8_PEX1_FLT")
		)
		(pad "2" smd rect
			(at -0.889 0 90)
			(size 1.016 1.27)
			(layers "B.Cu" "B.Mask" "B.Paste")
			(net "GND")
		)
	)
	(footprint ""
		(layer "B.Cu")
		(at 297.570144 -296.37482)
		(property "Reference" "C1632"
			(at 0 0 0)
			(layer "B.SilkS")
			(hide yes)
			(effects
				(font
					(size 1.27 1.27)
				)
				(justify mirror)
			)
		)
		(property "Value" ""
			(at 0 0 0)
			(layer "B.Fab")
			(effects
				(font
					(size 1.27 1.27)
				)
				(justify mirror)
			)
		)
		(duplicate_pad_numbers_are_jumpers no)
		(fp_line
			(start -0.299974 -0.150114)
			(end -0.299974 0.150114)
			(stroke
				(width 0.1)
				(type default)
			)
			(layer "B.Fab")
		)
		(fp_line
			(start -0.299974 0.150114)
			(end 0.299974 0.150114)
			(stroke
				(width 0.1)
				(type default)
			)
			(layer "B.Fab")
		)
		(fp_line
			(start 0.299974 -0.150114)
			(end -0.299974 -0.150114)
			(stroke
				(width 0.1)
				(type default)
			)
			(layer "B.Fab")
		)
		(fp_line
			(start 0.299974 0.150114)
			(end 0.299974 -0.150114)
			(stroke
				(width 0.1)
				(type default)
			)
			(layer "B.Fab")
		)
		(pad "1" smd rect
			(at 0.2667 0 180)
			(size 0.3048 0.381)
			(layers "B.Cu" "B.Mask" "B.Paste")
			(net "P0V8_PEX2")
		)
		(pad "2" smd rect
			(at -0.2667 0 180)
			(size 0.3048 0.381)
			(layers "B.Cu" "B.Mask" "B.Paste")
			(net "GND")
		)
	)
	(footprint ""
		(layer "B.Cu")
		(at 378.587 -241.3 90)
		(property "Reference" "C2568"
			(at 0 0 90)
			(layer "B.SilkS")
			(hide yes)
			(effects
				(font
					(size 1.27 1.27)
				)
				(justify mirror)
			)
		)
		(property "Value" ""
			(at 0 0 90)
			(layer "B.Fab")
			(effects
				(font
					(size 1.27 1.27)
				)
				(justify mirror)
			)
		)
		(duplicate_pad_numbers_are_jumpers no)
		(fp_line
			(start 0.7874 -0.4064)
			(end -0.7874 -0.4064)
			(stroke
				(width 0.1524)
				(type default)
			)
			(layer "B.SilkS")
		)
		(fp_line
			(start -0.7874 -0.4064)
			(end -0.7874 0.4064)
			(stroke
				(width 0.1524)
				(type default)
			)
			(layer "B.SilkS")
		)
		(fp_line
			(start 0.7874 0.4064)
			(end 0.7874 -0.4064)
			(stroke
				(width 0.1524)
				(type default)
			)
			(layer "B.SilkS")
		)
		(fp_line
			(start -0.7874 0.4064)
			(end 0.7874 0.4064)
			(stroke
				(width 0.1524)
				(type default)
			)
			(layer "B.SilkS")
		)
		(fp_line
			(start 0.67945 -0.305054)
			(end 0.12065 -0.305054)
			(stroke
				(width 0.1)
				(type default)
			)
			(layer "B.Fab")
		)
		(fp_line
			(start 0.12065 -0.305054)
			(end 0.12065 -0.2794)
			(stroke
				(width 0.1)
				(type default)
			)
			(layer "B.Fab")
		)
		(fp_line
			(start -0.12065 -0.3048)
			(end -0.67945 -0.3048)
			(stroke
				(width 0.1)
				(type default)
			)
			(layer "B.Fab")
		)
		(fp_line
			(start -0.67945 -0.3048)
			(end -0.67945 0.3048)
			(stroke
				(width 0.1)
				(type default)
			)
			(layer "B.Fab")
		)
		(fp_line
			(start 0.12065 -0.2794)
			(end -0.12065 -0.2794)
			(stroke
				(width 0.1)
				(type default)
			)
			(layer "B.Fab")
		)
		(fp_line
			(start -0.12065 -0.2794)
			(end -0.12065 -0.3048)
			(stroke
				(width 0.1)
				(type default)
			)
			(layer "B.Fab")
		)
		(fp_line
			(start 0.12065 0.2794)
			(end 0.12065 0.3048)
			(stroke
				(width 0.1)
				(type default)
			)
			(layer "B.Fab")
		)
		(fp_line
			(start -0.120396 0.2794)
			(end 0.12065 0.2794)
			(stroke
				(width 0.1)
				(type default)
			)
			(layer "B.Fab")
		)
		(fp_line
			(start 0.67945 0.3048)
			(end 0.67945 -0.305054)
			(stroke
				(width 0.1)
				(type default)
			)
			(layer "B.Fab")
		)
		(fp_line
			(start 0.12065 0.3048)
			(end 0.67945 0.3048)
			(stroke
				(width 0.1)
				(type default)
			)
			(layer "B.Fab")
		)
		(fp_line
			(start -0.120396 0.3048)
			(end -0.120396 0.2794)
			(stroke
				(width 0.1)
				(type default)
			)
			(layer "B.Fab")
		)
		(fp_line
			(start -0.67945 0.3048)
			(end -0.120396 0.3048)
			(stroke
				(width 0.1)
				(type default)
			)
			(layer "B.Fab")
		)
		(pad "1" smd circle
			(at 0.40005 0 270)
			(size 0 0)
			(layers "B.Cu" "B.Mask" "B.Paste")
			(net "P3V3_AUX")
		)
		(pad "2" smd circle
			(at -0.40005 0 270)
			(size 0 0)
			(layers "B.Cu" "B.Mask" "B.Paste")
			(net "GND")
		)
	)
	(footprint ""
		(layer "B.Cu")
		(at 14.830298 -227.965 180)
		(property "Reference" "R3441"
			(at 0 0 0)
			(layer "B.SilkS")
			(hide yes)
			(effects
				(font
					(size 1.27 1.27)
				)
				(justify mirror)
			)
		)
		(property "Value" ""
			(at 0 0 0)
			(layer "B.Fab")
			(effects
				(font
					(size 1.27 1.27)
				)
				(justify mirror)
			)
		)
		(duplicate_pad_numbers_are_jumpers no)
		(fp_line
			(start 0.7874 0.4064)
			(end 0.7874 -0.4064)
			(stroke
				(width 0.1524)
				(type default)
			)
			(layer "B.SilkS")
		)
		(fp_line
			(start 0.7874 -0.4064)
			(end -0.7874 -0.4064)
			(stroke
				(width 0.1524)
				(type default)
			)
			(layer "B.SilkS")
		)
		(fp_line
			(start -0.7874 0.4064)
			(end 0.7874 0.4064)
			(stroke
				(width 0.1524)
				(type default)
			)
			(layer "B.SilkS")
		)
		(fp_line
			(start -0.7874 -0.4064)
			(end -0.7874 0.4064)
			(stroke
				(width 0.1524)
				(type default)
			)
			(layer "B.SilkS")
		)
		(fp_line
			(start 0.67945 0.3048)
			(end 0.67945 -0.305054)
			(stroke
				(width 0.1)
				(type default)
			)
			(layer "B.Fab")
		)
		(fp_line
			(start 0.67945 -0.305054)
			(end 0.12065 -0.305054)
			(stroke
				(width 0.1)
				(type default)
			)
			(layer "B.Fab")
		)
		(fp_line
			(start 0.12065 0.3048)
			(end 0.67945 0.3048)
			(stroke
				(width 0.1)
				(type default)
			)
			(layer "B.Fab")
		)
		(fp_line
			(start 0.12065 0.2794)
			(end 0.12065 0.3048)
			(stroke
				(width 0.1)
				(type default)
			)
			(layer "B.Fab")
		)
		(fp_line
			(start 0.12065 -0.2794)
			(end -0.12065 -0.2794)
			(stroke
				(width 0.1)
				(type default)
			)
			(layer "B.Fab")
		)
		(fp_line
			(start 0.12065 -0.305054)
			(end 0.12065 -0.2794)
			(stroke
				(width 0.1)
				(type default)
			)
			(layer "B.Fab")
		)
		(fp_line
			(start -0.120396 0.3048)
			(end -0.120396 0.2794)
			(stroke
				(width 0.1)
				(type default)
			)
			(layer "B.Fab")
		)
		(fp_line
			(start -0.120396 0.2794)
			(end 0.12065 0.2794)
			(stroke
				(width 0.1)
				(type default)
			)
			(layer "B.Fab")
		)
		(fp_line
			(start -0.12065 -0.2794)
			(end -0.12065 -0.3048)
			(stroke
				(width 0.1)
				(type default)
			)
			(layer "B.Fab")
		)
		(fp_line
			(start -0.12065 -0.3048)
			(end -0.67945 -0.3048)
			(stroke
				(width 0.1)
				(type default)
			)
			(layer "B.Fab")
		)
		(fp_line
			(start -0.67945 0.3048)
			(end -0.120396 0.3048)
			(stroke
				(width 0.1)
				(type default)
			)
			(layer "B.Fab")
		)
		(fp_line
			(start -0.67945 -0.3048)
			(end -0.67945 0.3048)
			(stroke
				(width 0.1)
				(type default)
			)
			(layer "B.Fab")
		)
		(pad "1" smd circle
			(at 0.40005 0)
			(size 0 0)
			(layers "B.Cu" "B.Mask" "B.Paste")
			(net "SPI_PEX0_SDIO2_R1")
		)
		(pad "2" smd circle
			(at -0.40005 0)
			(size 0 0)
			(layers "B.Cu" "B.Mask" "B.Paste")
			(net "GND")
		)
	)
	(footprint ""
		(layer "B.Cu")
		(at 425.841922 -100.056696 180)
		(property "Reference" "R383"
			(at 0 0 0)
			(layer "B.SilkS")
			(hide yes)
			(effects
				(font
					(size 1.27 1.27)
				)
				(justify mirror)
			)
		)
		(property "Value" ""
			(at 0 0 0)
			(layer "B.Fab")
			(effects
				(font
					(size 1.27 1.27)
				)
				(justify mirror)
			)
		)
		(duplicate_pad_numbers_are_jumpers no)
		(fp_line
			(start 0.7874 0.4064)
			(end 0.7874 -0.4064)
			(stroke
				(width 0.1524)
				(type default)
			)
			(layer "B.SilkS")
		)
		(fp_line
			(start 0.7874 -0.4064)
			(end -0.7874 -0.4064)
			(stroke
				(width 0.1524)
				(type default)
			)
			(layer "B.SilkS")
		)
		(fp_line
			(start -0.7874 0.4064)
			(end 0.7874 0.4064)
			(stroke
				(width 0.1524)
				(type default)
			)
			(layer "B.SilkS")
		)
		(fp_line
			(start -0.7874 -0.4064)
			(end -0.7874 0.4064)
			(stroke
				(width 0.1524)
				(type default)
			)
			(layer "B.SilkS")
		)
		(fp_line
			(start 0.67945 0.3048)
			(end 0.67945 -0.305054)
			(stroke
				(width 0.1)
				(type default)
			)
			(layer "B.Fab")
		)
		(fp_line
			(start 0.67945 -0.305054)
			(end 0.12065 -0.305054)
			(stroke
				(width 0.1)
				(type default)
			)
			(layer "B.Fab")
		)
		(fp_line
			(start 0.12065 0.3048)
			(end 0.67945 0.3048)
			(stroke
				(width 0.1)
				(type default)
			)
			(layer "B.Fab")
		)
		(fp_line
			(start 0.12065 0.2794)
			(end 0.12065 0.3048)
			(stroke
				(width 0.1)
				(type default)
			)
			(layer "B.Fab")
		)
		(fp_line
			(start 0.12065 -0.2794)
			(end -0.12065 -0.2794)
			(stroke
				(width 0.1)
				(type default)
			)
			(layer "B.Fab")
		)
		(fp_line
			(start 0.12065 -0.305054)
			(end 0.12065 -0.2794)
			(stroke
				(width 0.1)
				(type default)
			)
			(layer "B.Fab")
		)
		(fp_line
			(start -0.120396 0.3048)
			(end -0.120396 0.2794)
			(stroke
				(width 0.1)
				(type default)
			)
			(layer "B.Fab")
		)
		(fp_line
			(start -0.120396 0.2794)
			(end 0.12065 0.2794)
			(stroke
				(width 0.1)
				(type default)
			)
			(layer "B.Fab")
		)
		(fp_line
			(start -0.12065 -0.2794)
			(end -0.12065 -0.3048)
			(stroke
				(width 0.1)
				(type default)
			)
			(layer "B.Fab")
		)
		(fp_line
			(start -0.12065 -0.3048)
			(end -0.67945 -0.3048)
			(stroke
				(width 0.1)
				(type default)
			)
			(layer "B.Fab")
		)
		(fp_line
			(start -0.67945 0.3048)
			(end -0.120396 0.3048)
			(stroke
				(width 0.1)
				(type default)
			)
			(layer "B.Fab")
		)
		(fp_line
			(start -0.67945 -0.3048)
			(end -0.67945 0.3048)
			(stroke
				(width 0.1)
				(type default)
			)
			(layer "B.Fab")
		)
		(pad "1" smd circle
			(at 0.40005 0)
			(size 0 0)
			(layers "B.Cu" "B.Mask" "B.Paste")
			(net "NIC7_SLOT_ID0")
		)
		(pad "2" smd circle
			(at -0.40005 0)
			(size 0 0)
			(layers "B.Cu" "B.Mask" "B.Paste")
			(net "GND")
		)
	)
	(footprint ""
		(layer "B.Cu")
		(at 234.978956 -278.894286 -90)
		(property "Reference" "C4345"
			(at 0 0 90)
			(layer "B.SilkS")
			(hide yes)
			(effects
				(font
					(size 1.27 1.27)
				)
				(justify mirror)
			)
		)
		(property "Value" ""
			(at 0 0 90)
			(layer "B.Fab")
			(effects
				(font
					(size 1.27 1.27)
				)
				(justify mirror)
			)
		)
		(duplicate_pad_numbers_are_jumpers no)
		(fp_line
			(start -1.2954 0.5842)
			(end 1.2954 0.5842)
			(stroke
				(width 0.1524)
				(type default)
			)
			(layer "B.SilkS")
		)
		(fp_line
			(start 1.2954 0.5842)
			(end 1.2954 -0.5842)
			(stroke
				(width 0.1524)
				(type default)
			)
			(layer "B.SilkS")
		)
		(fp_line
			(start -1.2954 -0.5842)
			(end -1.2954 0.5842)
			(stroke
				(width 0.1524)
				(type default)
			)
			(layer "B.SilkS")
		)
		(fp_line
			(start 1.2954 -0.5842)
			(end -1.2954 -0.5842)
			(stroke
				(width 0.1524)
				(type default)
			)
			(layer "B.SilkS")
		)
		(fp_line
			(start -0.8636 0.4572)
			(end 0.8636 0.4572)
			(stroke
				(width 0.1)
				(type default)
			)
			(layer "B.Fab")
		)
		(fp_line
			(start 0.8636 0.4572)
			(end 0.8636 0.4064)
			(stroke
				(width 0.1)
				(type default)
			)
			(layer "B.Fab")
		)
		(fp_line
			(start -1.1938 0.4064)
			(end -0.8636 0.4064)
			(stroke
				(width 0.1)
				(type default)
			)
			(layer "B.Fab")
		)
		(fp_line
			(start -0.8636 0.4064)
			(end -0.8636 0.4572)
			(stroke
				(width 0.1)
				(type default)
			)
			(layer "B.Fab")
		)
		(fp_line
			(start 0.8636 0.4064)
			(end 1.1938 0.4064)
			(stroke
				(width 0.1)
				(type default)
			)
			(layer "B.Fab")
		)
		(fp_line
			(start 1.1938 0.4064)
			(end 1.1938 -0.4064)
			(stroke
				(width 0.1)
				(type default)
			)
			(layer "B.Fab")
		)
		(fp_line
			(start -1.1938 -0.4064)
			(end -1.1938 0.4064)
			(stroke
				(width 0.1)
				(type default)
			)
			(layer "B.Fab")
		)
		(fp_line
			(start -0.8636 -0.4064)
			(end -1.1938 -0.4064)
			(stroke
				(width 0.1)
				(type default)
			)
			(layer "B.Fab")
		)
		(fp_line
			(start 0.8636 -0.4064)
			(end 0.8636 -0.4572)
			(stroke
				(width 0.1)
				(type default)
			)
			(layer "B.Fab")
		)
		(fp_line
			(start 1.1938 -0.4064)
			(end 0.8636 -0.4064)
			(stroke
				(width 0.1)
				(type default)
			)
			(layer "B.Fab")
		)
		(fp_line
			(start -0.8636 -0.4572)
			(end -0.8636 -0.4064)
			(stroke
				(width 0.1)
				(type default)
			)
			(layer "B.Fab")
		)
		(fp_line
			(start 0.8636 -0.4572)
			(end -0.8636 -0.4572)
			(stroke
				(width 0.1)
				(type default)
			)
			(layer "B.Fab")
		)
		(pad "1" smd rect
			(at 0.7366 0 180)
			(size 0.7112 0.8128)
			(layers "B.Cu" "B.Mask" "B.Paste")
			(net "P1V25_PEX2")
		)
		(pad "2" smd rect
			(at -0.7366 0 180)
			(size 0.7112 0.8128)
			(layers "B.Cu" "B.Mask" "B.Paste")
			(net "GND")
		)
	)
	(footprint ""
		(layer "B.Cu")
		(at 191.81699 -295.42486)
		(property "Reference" "C3075"
			(at 0 0 0)
			(layer "B.SilkS")
			(hide yes)
			(effects
				(font
					(size 1.27 1.27)
				)
				(justify mirror)
			)
		)
		(property "Value" ""
			(at 0 0 0)
			(layer "B.Fab")
			(effects
				(font
					(size 1.27 1.27)
				)
				(justify mirror)
			)
		)
		(duplicate_pad_numbers_are_jumpers no)
		(fp_line
			(start -1.2954 -0.5842)
			(end -1.2954 0.5842)
			(stroke
				(width 0.1524)
				(type default)
			)
			(layer "B.SilkS")
		)
		(fp_line
			(start -1.2954 0.5842)
			(end 1.2954 0.5842)
			(stroke
				(width 0.1524)
				(type default)
			)
			(layer "B.SilkS")
		)
		(fp_line
			(start 1.2954 -0.5842)
			(end -1.2954 -0.5842)
			(stroke
				(width 0.1524)
				(type default)
			)
			(layer "B.SilkS")
		)
		(fp_line
			(start 1.2954 0.5842)
			(end 1.2954 -0.5842)
			(stroke
				(width 0.1524)
				(type default)
			)
			(layer "B.SilkS")
		)
		(fp_line
			(start -1.1938 -0.4064)
			(end -1.1938 0.4064)
			(stroke
				(width 0.1)
				(type default)
			)
			(layer "B.Fab")
		)
		(fp_line
			(start -1.1938 0.4064)
			(end -0.8636 0.4064)
			(stroke
				(width 0.1)
				(type default)
			)
			(layer "B.Fab")
		)
		(fp_line
			(start -0.8636 -0.4572)
			(end -0.8636 -0.4064)
			(stroke
				(width 0.1)
				(type default)
			)
			(layer "B.Fab")
		)
		(fp_line
			(start -0.8636 -0.4064)
			(end -1.1938 -0.4064)
			(stroke
				(width 0.1)
				(type default)
			)
			(layer "B.Fab")
		)
		(fp_line
			(start -0.8636 0.4064)
			(end -0.8636 0.4572)
			(stroke
				(width 0.1)
				(type default)
			)
			(layer "B.Fab")
		)
		(fp_line
			(start -0.8636 0.4572)
			(end 0.8636 0.4572)
			(stroke
				(width 0.1)
				(type default)
			)
			(layer "B.Fab")
		)
		(fp_line
			(start 0.8636 -0.4572)
			(end -0.8636 -0.4572)
			(stroke
				(width 0.1)
				(type default)
			)
			(layer "B.Fab")
		)
		(fp_line
			(start 0.8636 -0.4064)
			(end 0.8636 -0.4572)
			(stroke
				(width 0.1)
				(type default)
			)
			(layer "B.Fab")
		)
		(fp_line
			(start 0.8636 0.4064)
			(end 1.1938 0.4064)
			(stroke
				(width 0.1)
				(type default)
			)
			(layer "B.Fab")
		)
		(fp_line
			(start 0.8636 0.4572)
			(end 0.8636 0.4064)
			(stroke
				(width 0.1)
				(type default)
			)
			(layer "B.Fab")
		)
		(fp_line
			(start 1.1938 -0.4064)
			(end 0.8636 -0.4064)
			(stroke
				(width 0.1)
				(type default)
			)
			(layer "B.Fab")
		)
		(fp_line
			(start 1.1938 0.4064)
			(end 1.1938 -0.4064)
			(stroke
				(width 0.1)
				(type default)
			)
			(layer "B.Fab")
		)
		(pad "1" smd rect
			(at 0.7366 0 270)
			(size 0.7112 0.8128)
			(layers "B.Cu" "B.Mask" "B.Paste")
			(net "P1V25_PEX1")
		)
		(pad "2" smd rect
			(at -0.7366 0 270)
			(size 0.7112 0.8128)
			(layers "B.Cu" "B.Mask" "B.Paste")
			(net "GND")
		)
	)
	(footprint ""
		(layer "B.Cu")
		(at 165.655244 -154.0256)
		(property "Reference" "R123"
			(at 0 0 0)
			(layer "B.SilkS")
			(hide yes)
			(effects
				(font
					(size 1.27 1.27)
				)
				(justify mirror)
			)
		)
		(property "Value" ""
			(at 0 0 0)
			(layer "B.Fab")
			(effects
				(font
					(size 1.27 1.27)
				)
				(justify mirror)
			)
		)
		(duplicate_pad_numbers_are_jumpers no)
		(fp_line
			(start -0.7874 -0.4064)
			(end -0.7874 0.4064)
			(stroke
				(width 0.1524)
				(type default)
			)
			(layer "B.SilkS")
		)
		(fp_line
			(start -0.7874 0.4064)
			(end 0.7874 0.4064)
			(stroke
				(width 0.1524)
				(type default)
			)
			(layer "B.SilkS")
		)
		(fp_line
			(start 0.7874 -0.4064)
			(end -0.7874 -0.4064)
			(stroke
				(width 0.1524)
				(type default)
			)
			(layer "B.SilkS")
		)
		(fp_line
			(start 0.7874 0.4064)
			(end 0.7874 -0.4064)
			(stroke
				(width 0.1524)
				(type default)
			)
			(layer "B.SilkS")
		)
		(fp_line
			(start -0.67945 -0.3048)
			(end -0.67945 0.3048)
			(stroke
				(width 0.1)
				(type default)
			)
			(layer "B.Fab")
		)
		(fp_line
			(start -0.67945 0.3048)
			(end -0.120396 0.3048)
			(stroke
				(width 0.1)
				(type default)
			)
			(layer "B.Fab")
		)
		(fp_line
			(start -0.12065 -0.3048)
			(end -0.67945 -0.3048)
			(stroke
				(width 0.1)
				(type default)
			)
			(layer "B.Fab")
		)
		(fp_line
			(start -0.12065 -0.2794)
			(end -0.12065 -0.3048)
			(stroke
				(width 0.1)
				(type default)
			)
			(layer "B.Fab")
		)
		(fp_line
			(start -0.120396 0.2794)
			(end 0.12065 0.2794)
			(stroke
				(width 0.1)
				(type default)
			)
			(layer "B.Fab")
		)
		(fp_line
			(start -0.120396 0.3048)
			(end -0.120396 0.2794)
			(stroke
				(width 0.1)
				(type default)
			)
			(layer "B.Fab")
		)
		(fp_line
			(start 0.12065 -0.305054)
			(end 0.12065 -0.2794)
			(stroke
				(width 0.1)
				(type default)
			)
			(layer "B.Fab")
		)
		(fp_line
			(start 0.12065 -0.2794)
			(end -0.12065 -0.2794)
			(stroke
				(width 0.1)
				(type default)
			)
			(layer "B.Fab")
		)
		(fp_line
			(start 0.12065 0.2794)
			(end 0.12065 0.3048)
			(stroke
				(width 0.1)
				(type default)
			)
			(layer "B.Fab")
		)
		(fp_line
			(start 0.12065 0.3048)
			(end 0.67945 0.3048)
			(stroke
				(width 0.1)
				(type default)
			)
			(layer "B.Fab")
		)
		(fp_line
			(start 0.67945 -0.305054)
			(end 0.12065 -0.305054)
			(stroke
				(width 0.1)
				(type default)
			)
			(layer "B.Fab")
		)
		(fp_line
			(start 0.67945 0.3048)
			(end 0.67945 -0.305054)
			(stroke
				(width 0.1)
				(type default)
			)
			(layer "B.Fab")
		)
		(pad "1" smd circle
			(at 0.40005 0 180)
			(size 0 0)
			(layers "B.Cu" "B.Mask" "B.Paste")
			(net "NCSI_NIC2_TX_EN")
		)
		(pad "2" smd circle
			(at -0.40005 0 180)
			(size 0 0)
			(layers "B.Cu" "B.Mask" "B.Paste")
			(net "GND")
		)
	)
	(footprint ""
		(layer "B.Cu")
		(at 8.861044 -277.83155 180)
		(property "Reference" "C4222"
			(at 0 0 0)
			(layer "B.SilkS")
			(hide yes)
			(effects
				(font
					(size 1.27 1.27)
				)
				(justify mirror)
			)
		)
		(property "Value" ""
			(at 0 0 0)
			(layer "B.Fab")
			(effects
				(font
					(size 1.27 1.27)
				)
				(justify mirror)
			)
		)
		(duplicate_pad_numbers_are_jumpers no)
		(fp_line
			(start 0.299974 0.150114)
			(end 0.299974 -0.150114)
			(stroke
				(width 0.1)
				(type default)
			)
			(layer "B.Fab")
		)
		(fp_line
			(start 0.299974 -0.150114)
			(end -0.299974 -0.150114)
			(stroke
				(width 0.1)
				(type default)
			)
			(layer "B.Fab")
		)
		(fp_line
			(start -0.299974 0.150114)
			(end 0.299974 0.150114)
			(stroke
				(width 0.1)
				(type default)
			)
			(layer "B.Fab")
		)
		(fp_line
			(start -0.299974 -0.150114)
			(end -0.299974 0.150114)
			(stroke
				(width 0.1)
				(type default)
			)
			(layer "B.Fab")
		)
		(pad "1" smd rect
			(at 0.2667 0)
			(size 0.3048 0.381)
			(layers "B.Cu" "B.Mask" "B.Paste")
			(net "P1V25_PEX0")
		)
		(pad "2" smd rect
			(at -0.2667 0)
			(size 0.3048 0.381)
			(layers "B.Cu" "B.Mask" "B.Paste")
			(net "GND")
		)
	)
	(footprint ""
		(layer "B.Cu")
		(at 402.67001 -305.399948 -90)
		(property "Reference" "C3499"
			(at 0 0 90)
			(layer "B.SilkS")
			(hide yes)
			(effects
				(font
					(size 1.27 1.27)
				)
				(justify mirror)
			)
		)
		(property "Value" ""
			(at 0 0 90)
			(layer "B.Fab")
			(effects
				(font
					(size 1.27 1.27)
				)
				(justify mirror)
			)
		)
		(duplicate_pad_numbers_are_jumpers no)
		(fp_line
			(start -0.299974 0.150114)
			(end 0.299974 0.150114)
			(stroke
				(width 0.1)
				(type default)
			)
			(layer "B.Fab")
		)
		(fp_line
			(start 0.299974 0.150114)
			(end 0.299974 -0.150114)
			(stroke
				(width 0.1)
				(type default)
			)
			(layer "B.Fab")
		)
		(fp_line
			(start -0.299974 -0.150114)
			(end -0.299974 0.150114)
			(stroke
				(width 0.1)
				(type default)
			)
			(layer "B.Fab")
		)
		(fp_line
			(start 0.299974 -0.150114)
			(end -0.299974 -0.150114)
			(stroke
				(width 0.1)
				(type default)
			)
			(layer "B.Fab")
		)
		(pad "1" smd rect
			(at 0.2667 0 90)
			(size 0.3048 0.381)
			(layers "B.Cu" "B.Mask" "B.Paste")
			(net "P1V25_SERDES_VDDPLL_PEX3")
		)
		(pad "2" smd rect
			(at -0.2667 0 90)
			(size 0.3048 0.381)
			(layers "B.Cu" "B.Mask" "B.Paste")
			(net "GND")
		)
	)
	(footprint ""
		(layer "B.Cu")
		(at 286.149796 -288.299906 90)
		(property "Reference" "C3281"
			(at 0 0 90)
			(layer "B.SilkS")
			(hide yes)
			(effects
				(font
					(size 1.27 1.27)
				)
				(justify mirror)
			)
		)
		(property "Value" ""
			(at 0 0 90)
			(layer "B.Fab")
			(effects
				(font
					(size 1.27 1.27)
				)
				(justify mirror)
			)
		)
		(duplicate_pad_numbers_are_jumpers no)
		(fp_line
			(start 0.299974 -0.150114)
			(end -0.299974 -0.150114)
			(stroke
				(width 0.1)
				(type default)
			)
			(layer "B.Fab")
		)
		(fp_line
			(start -0.299974 -0.150114)
			(end -0.299974 0.150114)
			(stroke
				(width 0.1)
				(type default)
			)
			(layer "B.Fab")
		)
		(fp_line
			(start 0.299974 0.150114)
			(end 0.299974 -0.150114)
			(stroke
				(width 0.1)
				(type default)
			)
			(layer "B.Fab")
		)
		(fp_line
			(start -0.299974 0.150114)
			(end 0.299974 0.150114)
			(stroke
				(width 0.1)
				(type default)
			)
			(layer "B.Fab")
		)
		(pad "1" smd rect
			(at 0.2667 0 270)
			(size 0.3048 0.381)
			(layers "B.Cu" "B.Mask" "B.Paste")
			(net "P1V25_PEX2")
		)
		(pad "2" smd rect
			(at -0.2667 0 270)
			(size 0.3048 0.381)
			(layers "B.Cu" "B.Mask" "B.Paste")
			(net "GND")
		)
	)
	(footprint ""
		(layer "B.Cu")
		(at 240.467388 -220.514672 180)
		(property "Reference" "C3617"
			(at 0 0 0)
			(layer "B.SilkS")
			(hide yes)
			(effects
				(font
					(size 1.27 1.27)
				)
				(justify mirror)
			)
		)
		(property "Value" ""
			(at 0 0 0)
			(layer "B.Fab")
			(effects
				(font
					(size 1.27 1.27)
				)
				(justify mirror)
			)
		)
		(duplicate_pad_numbers_are_jumpers no)
		(fp_line
			(start 0.69215 0.2921)
			(end 0.69215 -0.2921)
			(stroke
				(width 0.1524)
				(type default)
			)
			(layer "B.SilkS")
		)
		(fp_line
			(start 0.69215 -0.2921)
			(end -0.69215 -0.2921)
			(stroke
				(width 0.1524)
				(type default)
			)
			(layer "B.SilkS")
		)
		(fp_line
			(start -0.69215 0.2921)
			(end 0.69215 0.2921)
			(stroke
				(width 0.1524)
				(type default)
			)
			(layer "B.SilkS")
		)
		(fp_line
			(start -0.69215 -0.2921)
			(end -0.69215 0.2921)
			(stroke
				(width 0.1524)
				(type default)
			)
			(layer "B.SilkS")
		)
		(fp_line
			(start 0.51435 0.2794)
			(end 0.51435 -0.2794)
			(stroke
				(width 0.1)
				(type default)
			)
			(layer "B.Fab")
		)
		(fp_line
			(start 0.51435 -0.2794)
			(end -0.51435 -0.2794)
			(stroke
				(width 0.1)
				(type default)
			)
			(layer "B.Fab")
		)
		(fp_line
			(start -0.51435 0.2794)
			(end 0.51435 0.2794)
			(stroke
				(width 0.1)
				(type default)
			)
			(layer "B.Fab")
		)
		(fp_line
			(start -0.51435 -0.2794)
			(end -0.51435 0.2794)
			(stroke
				(width 0.1)
				(type default)
			)
			(layer "B.Fab")
		)
		(pad "1" smd circle
			(at 0.40005 0)
			(size 0 0)
			(layers "B.Cu" "B.Mask" "B.Paste")
			(net "BIC_ADCVREFP1")
		)
		(pad "2" smd circle
			(at -0.40005 0)
			(size 0 0)
			(layers "B.Cu" "B.Mask" "B.Paste")
			(net "GND")
		)
		(zone
			(layer "B.Cu")
			(hatch none 0.5)
			(connect_pads
				(clearance 0)
			)
			(min_thickness 0.25)
			(keepout
				(tracks not_allowed)
				(vias allowed)
				(pads allowed)
				(copperpour not_allowed)
				(footprints allowed)
			)
			(placement
				(enabled no)
				(sheetname "")
			)
			(fill
				(thermal_gap 0.5)
				(thermal_bridge_width 0.5)
				(island_removal_mode 0)
			)
			(polygon
				(pts
					(xy 240.276888 -220.602302) (xy 240.368328 -220.660468) (xy 240.567718 -220.660468) (xy 240.657888 -220.602302)
					(xy 240.657888 -220.427042) (xy 240.567718 -220.368622) (xy 240.368328 -220.368622) (xy 240.276888 -220.426788)
				)
			)
		)
	)
	(footprint ""
		(layer "B.Cu")
		(at 355.803962 -325.310246 -90)
		(property "Reference" "C4369"
			(at 0 0 90)
			(layer "B.SilkS")
			(hide yes)
			(effects
				(font
					(size 1.27 1.27)
				)
				(justify mirror)
			)
		)
		(property "Value" ""
			(at 0 0 90)
			(layer "B.Fab")
			(effects
				(font
					(size 1.27 1.27)
				)
				(justify mirror)
			)
		)
		(duplicate_pad_numbers_are_jumpers no)
		(fp_line
			(start -1.2954 0.5842)
			(end 1.2954 0.5842)
			(stroke
				(width 0.1524)
				(type default)
			)
			(layer "B.SilkS")
		)
		(fp_line
			(start 1.2954 0.5842)
			(end 1.2954 -0.5842)
			(stroke
				(width 0.1524)
				(type default)
			)
			(layer "B.SilkS")
		)
		(fp_line
			(start -1.2954 -0.5842)
			(end -1.2954 0.5842)
			(stroke
				(width 0.1524)
				(type default)
			)
			(layer "B.SilkS")
		)
		(fp_line
			(start 1.2954 -0.5842)
			(end -1.2954 -0.5842)
			(stroke
				(width 0.1524)
				(type default)
			)
			(layer "B.SilkS")
		)
		(fp_line
			(start -0.8636 0.4572)
			(end 0.8636 0.4572)
			(stroke
				(width 0.1)
				(type default)
			)
			(layer "B.Fab")
		)
		(fp_line
			(start 0.8636 0.4572)
			(end 0.8636 0.4064)
			(stroke
				(width 0.1)
				(type default)
			)
			(layer "B.Fab")
		)
		(fp_line
			(start -1.1938 0.4064)
			(end -0.8636 0.4064)
			(stroke
				(width 0.1)
				(type default)
			)
			(layer "B.Fab")
		)
		(fp_line
			(start -0.8636 0.4064)
			(end -0.8636 0.4572)
			(stroke
				(width 0.1)
				(type default)
			)
			(layer "B.Fab")
		)
		(fp_line
			(start 0.8636 0.4064)
			(end 1.1938 0.4064)
			(stroke
				(width 0.1)
				(type default)
			)
			(layer "B.Fab")
		)
		(fp_line
			(start 1.1938 0.4064)
			(end 1.1938 -0.4064)
			(stroke
				(width 0.1)
				(type default)
			)
			(layer "B.Fab")
		)
		(fp_line
			(start -1.1938 -0.4064)
			(end -1.1938 0.4064)
			(stroke
				(width 0.1)
				(type default)
			)
			(layer "B.Fab")
		)
		(fp_line
			(start -0.8636 -0.4064)
			(end -1.1938 -0.4064)
			(stroke
				(width 0.1)
				(type default)
			)
			(layer "B.Fab")
		)
		(fp_line
			(start 0.8636 -0.4064)
			(end 0.8636 -0.4572)
			(stroke
				(width 0.1)
				(type default)
			)
			(layer "B.Fab")
		)
		(fp_line
			(start 1.1938 -0.4064)
			(end 0.8636 -0.4064)
			(stroke
				(width 0.1)
				(type default)
			)
			(layer "B.Fab")
		)
		(fp_line
			(start -0.8636 -0.4572)
			(end -0.8636 -0.4064)
			(stroke
				(width 0.1)
				(type default)
			)
			(layer "B.Fab")
		)
		(fp_line
			(start 0.8636 -0.4572)
			(end -0.8636 -0.4572)
			(stroke
				(width 0.1)
				(type default)
			)
			(layer "B.Fab")
		)
		(pad "1" smd rect
			(at 0.7366 0 180)
			(size 0.7112 0.8128)
			(layers "B.Cu" "B.Mask" "B.Paste")
			(net "P0V8_SERDES_VDDA_PEX3_C3")
		)
		(pad "2" smd rect
			(at -0.7366 0 180)
			(size 0.7112 0.8128)
			(layers "B.Cu" "B.Mask" "B.Paste")
			(net "GND")
		)
	)
	(footprint ""
		(layer "B.Cu")
		(at 121.077228 -281.024838 90)
		(property "Reference" "PC95"
			(at 0 0 90)
			(layer "B.SilkS")
			(hide yes)
			(effects
				(font
					(size 1.27 1.27)
				)
				(justify mirror)
			)
		)
		(property "Value" ""
			(at 0 0 90)
			(layer "B.Fab")
			(effects
				(font
					(size 1.27 1.27)
				)
				(justify mirror)
			)
		)
		(duplicate_pad_numbers_are_jumpers no)
		(fp_line
			(start 1.524 -0.762)
			(end -1.524 -0.762)
			(stroke
				(width 0.1524)
				(type default)
			)
			(layer "B.SilkS")
		)
		(fp_line
			(start -1.524 -0.762)
			(end -1.524 0.762)
			(stroke
				(width 0.1524)
				(type default)
			)
			(layer "B.SilkS")
		)
		(fp_line
			(start 1.524 0.762)
			(end 1.524 -0.762)
			(stroke
				(width 0.1524)
				(type default)
			)
			(layer "B.SilkS")
		)
		(fp_line
			(start -1.524 0.762)
			(end 1.524 0.762)
			(stroke
				(width 0.1524)
				(type default)
			)
			(layer "B.SilkS")
		)
		(fp_line
			(start 1.1049 -0.724916)
			(end 1.1049 0.724916)
			(stroke
				(width 0.1)
				(type default)
			)
			(layer "B.Fab")
		)
		(fp_line
			(start -1.1049 -0.724916)
			(end 1.1049 -0.724916)
			(stroke
				(width 0.1)
				(type default)
			)
			(layer "B.Fab")
		)
		(fp_line
			(start 1.1049 0.724916)
			(end -1.1049 0.724916)
			(stroke
				(width 0.1)
				(type default)
			)
			(layer "B.Fab")
		)
		(fp_line
			(start -1.1049 0.724916)
			(end -1.1049 -0.724916)
			(stroke
				(width 0.1)
				(type default)
			)
			(layer "B.Fab")
		)
		(pad "1" smd rect
			(at 0.889 0 90)
			(size 1.016 1.27)
			(layers "B.Cu" "B.Mask" "B.Paste")
			(net "SW_P12V_P0V8_PEX1_FLT")
		)
		(pad "2" smd rect
			(at -0.889 0 90)
			(size 1.016 1.27)
			(layers "B.Cu" "B.Mask" "B.Paste")
			(net "GND")
		)
	)
	(footprint ""
		(layer "B.Cu")
		(at 231.86771 -216.704164)
		(property "Reference" "C3608"
			(at 0 0 0)
			(layer "B.SilkS")
			(hide yes)
			(effects
				(font
					(size 1.27 1.27)
				)
				(justify mirror)
			)
		)
		(property "Value" ""
			(at 0 0 0)
			(layer "B.Fab")
			(effects
				(font
					(size 1.27 1.27)
				)
				(justify mirror)
			)
		)
		(duplicate_pad_numbers_are_jumpers no)
		(fp_line
			(start -0.69215 -0.2921)
			(end -0.69215 0.2921)
			(stroke
				(width 0.1524)
				(type default)
			)
			(layer "B.SilkS")
		)
		(fp_line
			(start -0.69215 0.2921)
			(end 0.69215 0.2921)
			(stroke
				(width 0.1524)
				(type default)
			)
			(layer "B.SilkS")
		)
		(fp_line
			(start 0.69215 -0.2921)
			(end -0.69215 -0.2921)
			(stroke
				(width 0.1524)
				(type default)
			)
			(layer "B.SilkS")
		)
		(fp_line
			(start 0.69215 0.2921)
			(end 0.69215 -0.2921)
			(stroke
				(width 0.1524)
				(type default)
			)
			(layer "B.SilkS")
		)
		(fp_line
			(start -0.51435 -0.2794)
			(end -0.51435 0.2794)
			(stroke
				(width 0.1)
				(type default)
			)
			(layer "B.Fab")
		)
		(fp_line
			(start -0.51435 0.2794)
			(end 0.51435 0.2794)
			(stroke
				(width 0.1)
				(type default)
			)
			(layer "B.Fab")
		)
		(fp_line
			(start 0.51435 -0.2794)
			(end -0.51435 -0.2794)
			(stroke
				(width 0.1)
				(type default)
			)
			(layer "B.Fab")
		)
		(fp_line
			(start 0.51435 0.2794)
			(end 0.51435 -0.2794)
			(stroke
				(width 0.1)
				(type default)
			)
			(layer "B.Fab")
		)
		(pad "1" smd circle
			(at 0.40005 0 180)
			(size 0 0)
			(layers "B.Cu" "B.Mask" "B.Paste")
			(net "P3V3_BIC_USB2AV33")
		)
		(pad "2" smd circle
			(at -0.40005 0 180)
			(size 0 0)
			(layers "B.Cu" "B.Mask" "B.Paste")
			(net "GND")
		)
		(zone
			(layer "B.Cu")
			(hatch none 0.5)
			(connect_pads
				(clearance 0)
			)
			(min_thickness 0.25)
			(keepout
				(tracks not_allowed)
				(vias allowed)
				(pads allowed)
				(copperpour not_allowed)
				(footprints allowed)
			)
			(placement
				(enabled no)
				(sheetname "")
			)
			(fill
				(thermal_gap 0.5)
				(thermal_bridge_width 0.5)
				(island_removal_mode 0)
			)
			(polygon
				(pts
					(xy 232.05821 -216.616534) (xy 231.96677 -216.558368) (xy 231.76738 -216.558368) (xy 231.67721 -216.616534)
					(xy 231.67721 -216.791794) (xy 231.76738 -216.850214) (xy 231.96677 -216.850214) (xy 232.05821 -216.792048)
				)
			)
		)
	)
	(footprint ""
		(layer "B.Cu")
		(at 164.141658 -303.024794)
		(property "Reference" "C3169"
			(at 0 0 0)
			(layer "B.SilkS")
			(hide yes)
			(effects
				(font
					(size 1.27 1.27)
				)
				(justify mirror)
			)
		)
		(property "Value" ""
			(at 0 0 0)
			(layer "B.Fab")
			(effects
				(font
					(size 1.27 1.27)
				)
				(justify mirror)
			)
		)
		(duplicate_pad_numbers_are_jumpers no)
		(fp_line
			(start -0.299974 -0.150114)
			(end -0.299974 0.150114)
			(stroke
				(width 0.1)
				(type default)
			)
			(layer "B.Fab")
		)
		(fp_line
			(start -0.299974 0.150114)
			(end 0.299974 0.150114)
			(stroke
				(width 0.1)
				(type default)
			)
			(layer "B.Fab")
		)
		(fp_line
			(start 0.299974 -0.150114)
			(end -0.299974 -0.150114)
			(stroke
				(width 0.1)
				(type default)
			)
			(layer "B.Fab")
		)
		(fp_line
			(start 0.299974 0.150114)
			(end 0.299974 -0.150114)
			(stroke
				(width 0.1)
				(type default)
			)
			(layer "B.Fab")
		)
		(pad "1" smd rect
			(at 0.2667 0 180)
			(size 0.3048 0.381)
			(layers "B.Cu" "B.Mask" "B.Paste")
			(net "P1V8_VDDA_PEX1")
		)
		(pad "2" smd rect
			(at -0.2667 0 180)
			(size 0.3048 0.381)
			(layers "B.Cu" "B.Mask" "B.Paste")
			(net "GND")
		)
	)
	(footprint ""
		(layer "B.Cu")
		(at 50.624994 -286.399732 90)
		(property "Reference" "C2946"
			(at 0 0 90)
			(layer "B.SilkS")
			(hide yes)
			(effects
				(font
					(size 1.27 1.27)
				)
				(justify mirror)
			)
		)
		(property "Value" ""
			(at 0 0 90)
			(layer "B.Fab")
			(effects
				(font
					(size 1.27 1.27)
				)
				(justify mirror)
			)
		)
		(duplicate_pad_numbers_are_jumpers no)
		(fp_line
			(start 0.299974 -0.150114)
			(end -0.299974 -0.150114)
			(stroke
				(width 0.1)
				(type default)
			)
			(layer "B.Fab")
		)
		(fp_line
			(start -0.299974 -0.150114)
			(end -0.299974 0.150114)
			(stroke
				(width 0.1)
				(type default)
			)
			(layer "B.Fab")
		)
		(fp_line
			(start 0.299974 0.150114)
			(end 0.299974 -0.150114)
			(stroke
				(width 0.1)
				(type default)
			)
			(layer "B.Fab")
		)
		(fp_line
			(start -0.299974 0.150114)
			(end 0.299974 0.150114)
			(stroke
				(width 0.1)
				(type default)
			)
			(layer "B.Fab")
		)
		(pad "1" smd rect
			(at 0.2667 0 270)
			(size 0.3048 0.381)
			(layers "B.Cu" "B.Mask" "B.Paste")
			(net "P1V25_SERDES_VDDPLL_PEX0")
		)
		(pad "2" smd rect
			(at -0.2667 0 270)
			(size 0.3048 0.381)
			(layers "B.Cu" "B.Mask" "B.Paste")
			(net "GND")
		)
	)
	(footprint ""
		(layer "B.Cu")
		(at 305.6001 -111.791496)
		(property "Reference" "C923"
			(at 0 0 0)
			(layer "B.SilkS")
			(hide yes)
			(effects
				(font
					(size 1.27 1.27)
				)
				(justify mirror)
			)
		)
		(property "Value" ""
			(at 0 0 0)
			(layer "B.Fab")
			(effects
				(font
					(size 1.27 1.27)
				)
				(justify mirror)
			)
		)
		(duplicate_pad_numbers_are_jumpers no)
		(fp_line
			(start -0.299974 -0.150114)
			(end -0.299974 0.150114)
			(stroke
				(width 0.1)
				(type default)
			)
			(layer "B.Fab")
		)
		(fp_line
			(start -0.299974 0.150114)
			(end 0.299974 0.150114)
			(stroke
				(width 0.1)
				(type default)
			)
			(layer "B.Fab")
		)
		(fp_line
			(start 0.299974 -0.150114)
			(end -0.299974 -0.150114)
			(stroke
				(width 0.1)
				(type default)
			)
			(layer "B.Fab")
		)
		(fp_line
			(start 0.299974 0.150114)
			(end 0.299974 -0.150114)
			(stroke
				(width 0.1)
				(type default)
			)
			(layer "B.Fab")
		)
		(pad "1" smd rect
			(at 0.2667 0 180)
			(size 0.3048 0.381)
			(layers "B.Cu" "B.Mask" "B.Paste")
			(net "P12V_NIC5")
		)
		(pad "2" smd rect
			(at -0.2667 0 180)
			(size 0.3048 0.381)
			(layers "B.Cu" "B.Mask" "B.Paste")
			(net "GND")
		)
	)
	(footprint ""
		(layer "B.Cu")
		(at 302.299878 -289.724846 180)
		(property "Reference" "C3350"
			(at 0 0 0)
			(layer "B.SilkS")
			(hide yes)
			(effects
				(font
					(size 1.27 1.27)
				)
				(justify mirror)
			)
		)
		(property "Value" ""
			(at 0 0 0)
			(layer "B.Fab")
			(effects
				(font
					(size 1.27 1.27)
				)
				(justify mirror)
			)
		)
		(duplicate_pad_numbers_are_jumpers no)
		(fp_line
			(start 0.299974 0.150114)
			(end 0.299974 -0.150114)
			(stroke
				(width 0.1)
				(type default)
			)
			(layer "B.Fab")
		)
		(fp_line
			(start 0.299974 -0.150114)
			(end -0.299974 -0.150114)
			(stroke
				(width 0.1)
				(type default)
			)
			(layer "B.Fab")
		)
		(fp_line
			(start -0.299974 0.150114)
			(end 0.299974 0.150114)
			(stroke
				(width 0.1)
				(type default)
			)
			(layer "B.Fab")
		)
		(fp_line
			(start -0.299974 -0.150114)
			(end -0.299974 0.150114)
			(stroke
				(width 0.1)
				(type default)
			)
			(layer "B.Fab")
		)
		(pad "1" smd rect
			(at 0.2667 0)
			(size 0.3048 0.381)
			(layers "B.Cu" "B.Mask" "B.Paste")
			(net "P1V8_PEX")
		)
		(pad "2" smd rect
			(at -0.2667 0)
			(size 0.3048 0.381)
			(layers "B.Cu" "B.Mask" "B.Paste")
			(net "GND")
		)
	)
	(footprint ""
		(layer "B.Cu")
		(at 133.411214 -201.967846 90)
		(property "Reference" "C2592"
			(at 0 0 90)
			(layer "B.SilkS")
			(hide yes)
			(effects
				(font
					(size 1.27 1.27)
				)
				(justify mirror)
			)
		)
		(property "Value" ""
			(at 0 0 90)
			(layer "B.Fab")
			(effects
				(font
					(size 1.27 1.27)
				)
				(justify mirror)
			)
		)
		(duplicate_pad_numbers_are_jumpers no)
		(fp_line
			(start 0.7874 -0.4064)
			(end -0.7874 -0.4064)
			(stroke
				(width 0.1524)
				(type default)
			)
			(layer "B.SilkS")
		)
		(fp_line
			(start -0.7874 -0.4064)
			(end -0.7874 0.4064)
			(stroke
				(width 0.1524)
				(type default)
			)
			(layer "B.SilkS")
		)
		(fp_line
			(start 0.7874 0.4064)
			(end 0.7874 -0.4064)
			(stroke
				(width 0.1524)
				(type default)
			)
			(layer "B.SilkS")
		)
		(fp_line
			(start -0.7874 0.4064)
			(end 0.7874 0.4064)
			(stroke
				(width 0.1524)
				(type default)
			)
			(layer "B.SilkS")
		)
		(fp_line
			(start 0.67945 -0.305054)
			(end 0.12065 -0.305054)
			(stroke
				(width 0.1)
				(type default)
			)
			(layer "B.Fab")
		)
		(fp_line
			(start 0.12065 -0.305054)
			(end 0.12065 -0.2794)
			(stroke
				(width 0.1)
				(type default)
			)
			(layer "B.Fab")
		)
		(fp_line
			(start -0.12065 -0.3048)
			(end -0.67945 -0.3048)
			(stroke
				(width 0.1)
				(type default)
			)
			(layer "B.Fab")
		)
		(fp_line
			(start -0.67945 -0.3048)
			(end -0.67945 0.3048)
			(stroke
				(width 0.1)
				(type default)
			)
			(layer "B.Fab")
		)
		(fp_line
			(start 0.12065 -0.2794)
			(end -0.12065 -0.2794)
			(stroke
				(width 0.1)
				(type default)
			)
			(layer "B.Fab")
		)
		(fp_line
			(start -0.12065 -0.2794)
			(end -0.12065 -0.3048)
			(stroke
				(width 0.1)
				(type default)
			)
			(layer "B.Fab")
		)
		(fp_line
			(start 0.12065 0.2794)
			(end 0.12065 0.3048)
			(stroke
				(width 0.1)
				(type default)
			)
			(layer "B.Fab")
		)
		(fp_line
			(start -0.120396 0.2794)
			(end 0.12065 0.2794)
			(stroke
				(width 0.1)
				(type default)
			)
			(layer "B.Fab")
		)
		(fp_line
			(start 0.67945 0.3048)
			(end 0.67945 -0.305054)
			(stroke
				(width 0.1)
				(type default)
			)
			(layer "B.Fab")
		)
		(fp_line
			(start 0.12065 0.3048)
			(end 0.67945 0.3048)
			(stroke
				(width 0.1)
				(type default)
			)
			(layer "B.Fab")
		)
		(fp_line
			(start -0.120396 0.3048)
			(end -0.120396 0.2794)
			(stroke
				(width 0.1)
				(type default)
			)
			(layer "B.Fab")
		)
		(fp_line
			(start -0.67945 0.3048)
			(end -0.120396 0.3048)
			(stroke
				(width 0.1)
				(type default)
			)
			(layer "B.Fab")
		)
		(pad "1" smd circle
			(at 0.40005 0 270)
			(size 0 0)
			(layers "B.Cu" "B.Mask" "B.Paste")
			(net "P1V8_CLI_VCORE")
		)
		(pad "2" smd circle
			(at -0.40005 0 270)
			(size 0 0)
			(layers "B.Cu" "B.Mask" "B.Paste")
			(net "GND")
		)
	)
	(footprint ""
		(layer "B.Cu")
		(at 181.92496 -286.399732 90)
		(property "Reference" "C3148"
			(at 0 0 90)
			(layer "B.SilkS")
			(hide yes)
			(effects
				(font
					(size 1.27 1.27)
				)
				(justify mirror)
			)
		)
		(property "Value" ""
			(at 0 0 90)
			(layer "B.Fab")
			(effects
				(font
					(size 1.27 1.27)
				)
				(justify mirror)
			)
		)
		(duplicate_pad_numbers_are_jumpers no)
		(fp_line
			(start 0.299974 -0.150114)
			(end -0.299974 -0.150114)
			(stroke
				(width 0.1)
				(type default)
			)
			(layer "B.Fab")
		)
		(fp_line
			(start -0.299974 -0.150114)
			(end -0.299974 0.150114)
			(stroke
				(width 0.1)
				(type default)
			)
			(layer "B.Fab")
		)
		(fp_line
			(start 0.299974 0.150114)
			(end 0.299974 -0.150114)
			(stroke
				(width 0.1)
				(type default)
			)
			(layer "B.Fab")
		)
		(fp_line
			(start -0.299974 0.150114)
			(end 0.299974 0.150114)
			(stroke
				(width 0.1)
				(type default)
			)
			(layer "B.Fab")
		)
		(pad "1" smd rect
			(at 0.2667 0 270)
			(size 0.3048 0.381)
			(layers "B.Cu" "B.Mask" "B.Paste")
			(net "P1V25_SERDES_VDDPLL_PEX1")
		)
		(pad "2" smd rect
			(at -0.2667 0 270)
			(size 0.3048 0.381)
			(layers "B.Cu" "B.Mask" "B.Paste")
			(net "GND")
		)
	)
	(footprint ""
		(layer "B.Cu")
		(at 5.956554 -390.073642 90)
		(property "Reference" "C4472"
			(at 0 0 90)
			(layer "B.SilkS")
			(hide yes)
			(effects
				(font
					(size 1.27 1.27)
				)
				(justify mirror)
			)
		)
		(property "Value" ""
			(at 0 0 90)
			(layer "B.Fab")
			(effects
				(font
					(size 1.27 1.27)
				)
				(justify mirror)
			)
		)
		(duplicate_pad_numbers_are_jumpers no)
		(fp_line
			(start 0.7874 -0.4064)
			(end -0.7874 -0.4064)
			(stroke
				(width 0.1524)
				(type default)
			)
			(layer "B.SilkS")
		)
		(fp_line
			(start -0.7874 -0.4064)
			(end -0.7874 0.4064)
			(stroke
				(width 0.1524)
				(type default)
			)
			(layer "B.SilkS")
		)
		(fp_line
			(start 0.7874 0.4064)
			(end 0.7874 -0.4064)
			(stroke
				(width 0.1524)
				(type default)
			)
			(layer "B.SilkS")
		)
		(fp_line
			(start -0.7874 0.4064)
			(end 0.7874 0.4064)
			(stroke
				(width 0.1524)
				(type default)
			)
			(layer "B.SilkS")
		)
		(fp_line
			(start 0.67945 -0.305054)
			(end 0.12065 -0.305054)
			(stroke
				(width 0.1)
				(type default)
			)
			(layer "B.Fab")
		)
		(fp_line
			(start 0.12065 -0.305054)
			(end 0.12065 -0.2794)
			(stroke
				(width 0.1)
				(type default)
			)
			(layer "B.Fab")
		)
		(fp_line
			(start -0.12065 -0.3048)
			(end -0.67945 -0.3048)
			(stroke
				(width 0.1)
				(type default)
			)
			(layer "B.Fab")
		)
		(fp_line
			(start -0.67945 -0.3048)
			(end -0.67945 0.3048)
			(stroke
				(width 0.1)
				(type default)
			)
			(layer "B.Fab")
		)
		(fp_line
			(start 0.12065 -0.2794)
			(end -0.12065 -0.2794)
			(stroke
				(width 0.1)
				(type default)
			)
			(layer "B.Fab")
		)
		(fp_line
			(start -0.12065 -0.2794)
			(end -0.12065 -0.3048)
			(stroke
				(width 0.1)
				(type default)
			)
			(layer "B.Fab")
		)
		(fp_line
			(start 0.12065 0.2794)
			(end 0.12065 0.3048)
			(stroke
				(width 0.1)
				(type default)
			)
			(layer "B.Fab")
		)
		(fp_line
			(start -0.120396 0.2794)
			(end 0.12065 0.2794)
			(stroke
				(width 0.1)
				(type default)
			)
			(layer "B.Fab")
		)
		(fp_line
			(start 0.67945 0.3048)
			(end 0.67945 -0.305054)
			(stroke
				(width 0.1)
				(type default)
			)
			(layer "B.Fab")
		)
		(fp_line
			(start 0.12065 0.3048)
			(end 0.67945 0.3048)
			(stroke
				(width 0.1)
				(type default)
			)
			(layer "B.Fab")
		)
		(fp_line
			(start -0.120396 0.3048)
			(end -0.120396 0.2794)
			(stroke
				(width 0.1)
				(type default)
			)
			(layer "B.Fab")
		)
		(fp_line
			(start -0.67945 0.3048)
			(end -0.120396 0.3048)
			(stroke
				(width 0.1)
				(type default)
			)
			(layer "B.Fab")
		)
		(pad "1" smd circle
			(at 0.40005 0 270)
			(size 0 0)
			(layers "B.Cu" "B.Mask" "B.Paste")
			(net "P1V2_USB_8042")
		)
		(pad "2" smd circle
			(at -0.40005 0 270)
			(size 0 0)
			(layers "B.Cu" "B.Mask" "B.Paste")
			(net "GND")
		)
	)
	(footprint ""
		(layer "B.Cu")
		(at 5.617718 -264.586466)
		(property "Reference" "R6126"
			(at 0 0 0)
			(layer "B.SilkS")
			(hide yes)
			(effects
				(font
					(size 1.27 1.27)
				)
				(justify mirror)
			)
		)
		(property "Value" ""
			(at 0 0 0)
			(layer "B.Fab")
			(effects
				(font
					(size 1.27 1.27)
				)
				(justify mirror)
			)
		)
		(duplicate_pad_numbers_are_jumpers no)
		(fp_line
			(start -2.576322 -1.1303)
			(end -2.576322 1.1303)
			(stroke
				(width 0.1524)
				(type default)
			)
			(layer "B.SilkS")
		)
		(fp_line
			(start -2.576322 1.1303)
			(end 2.576322 1.1303)
			(stroke
				(width 0.1524)
				(type default)
			)
			(layer "B.SilkS")
		)
		(fp_line
			(start 2.576322 -1.1303)
			(end -2.576322 -1.1303)
			(stroke
				(width 0.1524)
				(type default)
			)
			(layer "B.SilkS")
		)
		(fp_line
			(start 2.576322 1.1303)
			(end 2.576322 -1.1303)
			(stroke
				(width 0.1524)
				(type default)
			)
			(layer "B.SilkS")
		)
		(fp_line
			(start -1.649984 -0.899922)
			(end 1.649984 -0.899922)
			(stroke
				(width 0.1)
				(type default)
			)
			(layer "B.Fab")
		)
		(fp_line
			(start -1.649984 0.899922)
			(end -1.649984 -0.899922)
			(stroke
				(width 0.1)
				(type default)
			)
			(layer "B.Fab")
		)
		(fp_line
			(start 1.649984 -0.899922)
			(end 1.649984 0.899922)
			(stroke
				(width 0.1)
				(type default)
			)
			(layer "B.Fab")
		)
		(fp_line
			(start 1.649984 0.899922)
			(end -1.649984 0.899922)
			(stroke
				(width 0.1)
				(type default)
			)
			(layer "B.Fab")
		)
		(pad "1A" smd rect
			(at 1.700022 0 180)
			(size 1.4986 2.0066)
			(layers "B.Cu" "B.Mask" "B.Paste")
			(net "P1V25_PEX0")
		)
		(pad "1B" smd rect
			(at 1.077722 0 180)
			(size 0.254 0.508)
			(layers "B.Cu" "B.Mask" "B.Paste")
			(net "P1V25_PEX0")
		)
		(pad "2A" smd rect
			(at -1.700022 0 180)
			(size 1.4986 2.0066)
			(layers "B.Cu" "B.Mask" "B.Paste")
			(net "P1V25_SERDES_VDDPLL_PEX0")
		)
		(pad "2B" smd rect
			(at -1.077722 0 180)
			(size 0.254 0.508)
			(layers "B.Cu" "B.Mask" "B.Paste")
			(net "P1V25_SERDES_VDDPLL_PEX0")
		)
	)
	(footprint ""
		(layer "B.Cu")
		(at 403.674834 -297.79976 90)
		(property "Reference" "C1885"
			(at 0 0 90)
			(layer "B.SilkS")
			(hide yes)
			(effects
				(font
					(size 1.27 1.27)
				)
				(justify mirror)
			)
		)
		(property "Value" ""
			(at 0 0 90)
			(layer "B.Fab")
			(effects
				(font
					(size 1.27 1.27)
				)
				(justify mirror)
			)
		)
		(duplicate_pad_numbers_are_jumpers no)
		(fp_line
			(start 0.299974 -0.150114)
			(end -0.299974 -0.150114)
			(stroke
				(width 0.1)
				(type default)
			)
			(layer "B.Fab")
		)
		(fp_line
			(start -0.299974 -0.150114)
			(end -0.299974 0.150114)
			(stroke
				(width 0.1)
				(type default)
			)
			(layer "B.Fab")
		)
		(fp_line
			(start 0.299974 0.150114)
			(end 0.299974 -0.150114)
			(stroke
				(width 0.1)
				(type default)
			)
			(layer "B.Fab")
		)
		(fp_line
			(start -0.299974 0.150114)
			(end 0.299974 0.150114)
			(stroke
				(width 0.1)
				(type default)
			)
			(layer "B.Fab")
		)
		(pad "1" smd rect
			(at 0.2667 0 270)
			(size 0.3048 0.381)
			(layers "B.Cu" "B.Mask" "B.Paste")
			(net "P0V8_PEX3")
		)
		(pad "2" smd rect
			(at -0.2667 0 270)
			(size 0.3048 0.381)
			(layers "B.Cu" "B.Mask" "B.Paste")
			(net "GND")
		)
	)
	(footprint ""
		(layer "B.Cu")
		(at 276.93366 -389.498078 180)
		(property "Reference" "PR7158"
			(at 0 0 0)
			(layer "B.SilkS")
			(hide yes)
			(effects
				(font
					(size 1.27 1.27)
				)
				(justify mirror)
			)
		)
		(property "Value" ""
			(at 0 0 0)
			(layer "B.Fab")
			(effects
				(font
					(size 1.27 1.27)
				)
				(justify mirror)
			)
		)
		(duplicate_pad_numbers_are_jumpers no)
		(fp_line
			(start 0.7874 0.4064)
			(end 0.7874 -0.4064)
			(stroke
				(width 0.1524)
				(type default)
			)
			(layer "B.SilkS")
		)
		(fp_line
			(start 0.7874 -0.4064)
			(end -0.7874 -0.4064)
			(stroke
				(width 0.1524)
				(type default)
			)
			(layer "B.SilkS")
		)
		(fp_line
			(start -0.7874 0.4064)
			(end 0.7874 0.4064)
			(stroke
				(width 0.1524)
				(type default)
			)
			(layer "B.SilkS")
		)
		(fp_line
			(start -0.7874 -0.4064)
			(end -0.7874 0.4064)
			(stroke
				(width 0.1524)
				(type default)
			)
			(layer "B.SilkS")
		)
		(fp_line
			(start 0.67945 0.3048)
			(end 0.67945 -0.305054)
			(stroke
				(width 0.1)
				(type default)
			)
			(layer "B.Fab")
		)
		(fp_line
			(start 0.67945 -0.305054)
			(end 0.12065 -0.305054)
			(stroke
				(width 0.1)
				(type default)
			)
			(layer "B.Fab")
		)
		(fp_line
			(start 0.12065 0.3048)
			(end 0.67945 0.3048)
			(stroke
				(width 0.1)
				(type default)
			)
			(layer "B.Fab")
		)
		(fp_line
			(start 0.12065 0.2794)
			(end 0.12065 0.3048)
			(stroke
				(width 0.1)
				(type default)
			)
			(layer "B.Fab")
		)
		(fp_line
			(start 0.12065 -0.2794)
			(end -0.12065 -0.2794)
			(stroke
				(width 0.1)
				(type default)
			)
			(layer "B.Fab")
		)
		(fp_line
			(start 0.12065 -0.305054)
			(end 0.12065 -0.2794)
			(stroke
				(width 0.1)
				(type default)
			)
			(layer "B.Fab")
		)
		(fp_line
			(start -0.120396 0.3048)
			(end -0.120396 0.2794)
			(stroke
				(width 0.1)
				(type default)
			)
			(layer "B.Fab")
		)
		(fp_line
			(start -0.120396 0.2794)
			(end 0.12065 0.2794)
			(stroke
				(width 0.1)
				(type default)
			)
			(layer "B.Fab")
		)
		(fp_line
			(start -0.12065 -0.2794)
			(end -0.12065 -0.3048)
			(stroke
				(width 0.1)
				(type default)
			)
			(layer "B.Fab")
		)
		(fp_line
			(start -0.12065 -0.3048)
			(end -0.67945 -0.3048)
			(stroke
				(width 0.1)
				(type default)
			)
			(layer "B.Fab")
		)
		(fp_line
			(start -0.67945 0.3048)
			(end -0.120396 0.3048)
			(stroke
				(width 0.1)
				(type default)
			)
			(layer "B.Fab")
		)
		(fp_line
			(start -0.67945 -0.3048)
			(end -0.67945 0.3048)
			(stroke
				(width 0.1)
				(type default)
			)
			(layer "B.Fab")
		)
		(pad "1" smd circle
			(at 0.40005 0)
			(size 0 0)
			(layers "B.Cu" "B.Mask" "B.Paste")
			(net "HSC_ALERT1_R_N")
		)
		(pad "2" smd circle
			(at -0.40005 0)
			(size 0 0)
			(layers "B.Cu" "B.Mask" "B.Paste")
			(net "P3V3_AUX")
		)
	)
	(footprint ""
		(layer "B.Cu")
		(at 71.755 -97.663 180)
		(property "Reference" "R73"
			(at 0 0 0)
			(layer "B.SilkS")
			(hide yes)
			(effects
				(font
					(size 1.27 1.27)
				)
				(justify mirror)
			)
		)
		(property "Value" ""
			(at 0 0 0)
			(layer "B.Fab")
			(effects
				(font
					(size 1.27 1.27)
				)
				(justify mirror)
			)
		)
		(duplicate_pad_numbers_are_jumpers no)
		(fp_line
			(start 0.7874 0.4064)
			(end 0.7874 -0.4064)
			(stroke
				(width 0.1524)
				(type default)
			)
			(layer "B.SilkS")
		)
		(fp_line
			(start 0.7874 -0.4064)
			(end -0.7874 -0.4064)
			(stroke
				(width 0.1524)
				(type default)
			)
			(layer "B.SilkS")
		)
		(fp_line
			(start -0.7874 0.4064)
			(end 0.7874 0.4064)
			(stroke
				(width 0.1524)
				(type default)
			)
			(layer "B.SilkS")
		)
		(fp_line
			(start -0.7874 -0.4064)
			(end -0.7874 0.4064)
			(stroke
				(width 0.1524)
				(type default)
			)
			(layer "B.SilkS")
		)
		(fp_line
			(start 0.67945 0.3048)
			(end 0.67945 -0.305054)
			(stroke
				(width 0.1)
				(type default)
			)
			(layer "B.Fab")
		)
		(fp_line
			(start 0.67945 -0.305054)
			(end 0.12065 -0.305054)
			(stroke
				(width 0.1)
				(type default)
			)
			(layer "B.Fab")
		)
		(fp_line
			(start 0.12065 0.3048)
			(end 0.67945 0.3048)
			(stroke
				(width 0.1)
				(type default)
			)
			(layer "B.Fab")
		)
		(fp_line
			(start 0.12065 0.2794)
			(end 0.12065 0.3048)
			(stroke
				(width 0.1)
				(type default)
			)
			(layer "B.Fab")
		)
		(fp_line
			(start 0.12065 -0.2794)
			(end -0.12065 -0.2794)
			(stroke
				(width 0.1)
				(type default)
			)
			(layer "B.Fab")
		)
		(fp_line
			(start 0.12065 -0.305054)
			(end 0.12065 -0.2794)
			(stroke
				(width 0.1)
				(type default)
			)
			(layer "B.Fab")
		)
		(fp_line
			(start -0.120396 0.3048)
			(end -0.120396 0.2794)
			(stroke
				(width 0.1)
				(type default)
			)
			(layer "B.Fab")
		)
		(fp_line
			(start -0.120396 0.2794)
			(end 0.12065 0.2794)
			(stroke
				(width 0.1)
				(type default)
			)
			(layer "B.Fab")
		)
		(fp_line
			(start -0.12065 -0.2794)
			(end -0.12065 -0.3048)
			(stroke
				(width 0.1)
				(type default)
			)
			(layer "B.Fab")
		)
		(fp_line
			(start -0.12065 -0.3048)
			(end -0.67945 -0.3048)
			(stroke
				(width 0.1)
				(type default)
			)
			(layer "B.Fab")
		)
		(fp_line
			(start -0.67945 0.3048)
			(end -0.120396 0.3048)
			(stroke
				(width 0.1)
				(type default)
			)
			(layer "B.Fab")
		)
		(fp_line
			(start -0.67945 -0.3048)
			(end -0.67945 0.3048)
			(stroke
				(width 0.1)
				(type default)
			)
			(layer "B.Fab")
		)
		(pad "1" smd circle
			(at 0.40005 0)
			(size 0 0)
			(layers "B.Cu" "B.Mask" "B.Paste")
			(net "PWRGD_NIC1_PWR_GOOD")
		)
		(pad "2" smd circle
			(at -0.40005 0)
			(size 0 0)
			(layers "B.Cu" "B.Mask" "B.Paste")
			(net "GND")
		)
	)
	(footprint ""
		(layer "B.Cu")
		(at 62.024768 -286.399732 90)
		(property "Reference" "C2961"
			(at 0 0 90)
			(layer "B.SilkS")
			(hide yes)
			(effects
				(font
					(size 1.27 1.27)
				)
				(justify mirror)
			)
		)
		(property "Value" ""
			(at 0 0 90)
			(layer "B.Fab")
			(effects
				(font
					(size 1.27 1.27)
				)
				(justify mirror)
			)
		)
		(duplicate_pad_numbers_are_jumpers no)
		(fp_line
			(start 0.299974 -0.150114)
			(end -0.299974 -0.150114)
			(stroke
				(width 0.1)
				(type default)
			)
			(layer "B.Fab")
		)
		(fp_line
			(start -0.299974 -0.150114)
			(end -0.299974 0.150114)
			(stroke
				(width 0.1)
				(type default)
			)
			(layer "B.Fab")
		)
		(fp_line
			(start 0.299974 0.150114)
			(end 0.299974 -0.150114)
			(stroke
				(width 0.1)
				(type default)
			)
			(layer "B.Fab")
		)
		(fp_line
			(start -0.299974 0.150114)
			(end 0.299974 0.150114)
			(stroke
				(width 0.1)
				(type default)
			)
			(layer "B.Fab")
		)
		(pad "1" smd rect
			(at 0.2667 0 270)
			(size 0.3048 0.381)
			(layers "B.Cu" "B.Mask" "B.Paste")
			(net "P1V25_SERDES_VDDPLL_PEX0")
		)
		(pad "2" smd rect
			(at -0.2667 0 270)
			(size 0.3048 0.381)
			(layers "B.Cu" "B.Mask" "B.Paste")
			(net "GND")
		)
	)
	(footprint ""
		(layer "B.Cu")
		(at 282.770072 -305.399948 -90)
		(property "Reference" "C3318"
			(at 0 0 90)
			(layer "B.SilkS")
			(hide yes)
			(effects
				(font
					(size 1.27 1.27)
				)
				(justify mirror)
			)
		)
		(property "Value" ""
			(at 0 0 90)
			(layer "B.Fab")
			(effects
				(font
					(size 1.27 1.27)
				)
				(justify mirror)
			)
		)
		(duplicate_pad_numbers_are_jumpers no)
		(fp_line
			(start -0.299974 0.150114)
			(end 0.299974 0.150114)
			(stroke
				(width 0.1)
				(type default)
			)
			(layer "B.Fab")
		)
		(fp_line
			(start 0.299974 0.150114)
			(end 0.299974 -0.150114)
			(stroke
				(width 0.1)
				(type default)
			)
			(layer "B.Fab")
		)
		(fp_line
			(start -0.299974 -0.150114)
			(end -0.299974 0.150114)
			(stroke
				(width 0.1)
				(type default)
			)
			(layer "B.Fab")
		)
		(fp_line
			(start 0.299974 -0.150114)
			(end -0.299974 -0.150114)
			(stroke
				(width 0.1)
				(type default)
			)
			(layer "B.Fab")
		)
		(pad "1" smd rect
			(at 0.2667 0 90)
			(size 0.3048 0.381)
			(layers "B.Cu" "B.Mask" "B.Paste")
			(net "P1V25_SERDES_VDDPLL_PEX2")
		)
		(pad "2" smd rect
			(at -0.2667 0 90)
			(size 0.3048 0.381)
			(layers "B.Cu" "B.Mask" "B.Paste")
			(net "GND")
		)
	)
	(footprint ""
		(layer "B.Cu")
		(at 457.216002 -245.02364)
		(property "Reference" "C4432"
			(at 0 0 0)
			(layer "B.SilkS")
			(hide yes)
			(effects
				(font
					(size 1.27 1.27)
				)
				(justify mirror)
			)
		)
		(property "Value" ""
			(at 0 0 0)
			(layer "B.Fab")
			(effects
				(font
					(size 1.27 1.27)
				)
				(justify mirror)
			)
		)
		(duplicate_pad_numbers_are_jumpers no)
		(fp_line
			(start -0.7874 -0.4064)
			(end -0.7874 0.4064)
			(stroke
				(width 0.1524)
				(type default)
			)
			(layer "B.SilkS")
		)
		(fp_line
			(start -0.7874 0.4064)
			(end 0.7874 0.4064)
			(stroke
				(width 0.1524)
				(type default)
			)
			(layer "B.SilkS")
		)
		(fp_line
			(start 0.7874 -0.4064)
			(end -0.7874 -0.4064)
			(stroke
				(width 0.1524)
				(type default)
			)
			(layer "B.SilkS")
		)
		(fp_line
			(start 0.7874 0.4064)
			(end 0.7874 -0.4064)
			(stroke
				(width 0.1524)
				(type default)
			)
			(layer "B.SilkS")
		)
		(fp_line
			(start -0.67945 -0.3048)
			(end -0.67945 0.3048)
			(stroke
				(width 0.1)
				(type default)
			)
			(layer "B.Fab")
		)
		(fp_line
			(start -0.67945 0.3048)
			(end -0.120396 0.3048)
			(stroke
				(width 0.1)
				(type default)
			)
			(layer "B.Fab")
		)
		(fp_line
			(start -0.12065 -0.3048)
			(end -0.67945 -0.3048)
			(stroke
				(width 0.1)
				(type default)
			)
			(layer "B.Fab")
		)
		(fp_line
			(start -0.12065 -0.2794)
			(end -0.12065 -0.3048)
			(stroke
				(width 0.1)
				(type default)
			)
			(layer "B.Fab")
		)
		(fp_line
			(start -0.120396 0.2794)
			(end 0.12065 0.2794)
			(stroke
				(width 0.1)
				(type default)
			)
			(layer "B.Fab")
		)
		(fp_line
			(start -0.120396 0.3048)
			(end -0.120396 0.2794)
			(stroke
				(width 0.1)
				(type default)
			)
			(layer "B.Fab")
		)
		(fp_line
			(start 0.12065 -0.305054)
			(end 0.12065 -0.2794)
			(stroke
				(width 0.1)
				(type default)
			)
			(layer "B.Fab")
		)
		(fp_line
			(start 0.12065 -0.2794)
			(end -0.12065 -0.2794)
			(stroke
				(width 0.1)
				(type default)
			)
			(layer "B.Fab")
		)
		(fp_line
			(start 0.12065 0.2794)
			(end 0.12065 0.3048)
			(stroke
				(width 0.1)
				(type default)
			)
			(layer "B.Fab")
		)
		(fp_line
			(start 0.12065 0.3048)
			(end 0.67945 0.3048)
			(stroke
				(width 0.1)
				(type default)
			)
			(layer "B.Fab")
		)
		(fp_line
			(start 0.67945 -0.305054)
			(end 0.12065 -0.305054)
			(stroke
				(width 0.1)
				(type default)
			)
			(layer "B.Fab")
		)
		(fp_line
			(start 0.67945 0.3048)
			(end 0.67945 -0.305054)
			(stroke
				(width 0.1)
				(type default)
			)
			(layer "B.Fab")
		)
		(pad "1" smd circle
			(at 0.40005 0 180)
			(size 0 0)
			(layers "B.Cu" "B.Mask" "B.Paste")
			(net "P1V8_PLL0_PEX3")
		)
		(pad "2" smd circle
			(at -0.40005 0 180)
			(size 0 0)
			(layers "B.Cu" "B.Mask" "B.Paste")
			(net "GND")
		)
	)
	(footprint ""
		(layer "B.Cu")
		(at 59.649868 -292.099746 90)
		(property "Reference" "C1224"
			(at 0 0 90)
			(layer "B.SilkS")
			(hide yes)
			(effects
				(font
					(size 1.27 1.27)
				)
				(justify mirror)
			)
		)
		(property "Value" ""
			(at 0 0 90)
			(layer "B.Fab")
			(effects
				(font
					(size 1.27 1.27)
				)
				(justify mirror)
			)
		)
		(duplicate_pad_numbers_are_jumpers no)
		(fp_line
			(start 0.299974 -0.150114)
			(end -0.299974 -0.150114)
			(stroke
				(width 0.1)
				(type default)
			)
			(layer "B.Fab")
		)
		(fp_line
			(start -0.299974 -0.150114)
			(end -0.299974 0.150114)
			(stroke
				(width 0.1)
				(type default)
			)
			(layer "B.Fab")
		)
		(fp_line
			(start 0.299974 0.150114)
			(end 0.299974 -0.150114)
			(stroke
				(width 0.1)
				(type default)
			)
			(layer "B.Fab")
		)
		(fp_line
			(start -0.299974 0.150114)
			(end 0.299974 0.150114)
			(stroke
				(width 0.1)
				(type default)
			)
			(layer "B.Fab")
		)
		(pad "1" smd rect
			(at 0.2667 0 270)
			(size 0.3048 0.381)
			(layers "B.Cu" "B.Mask" "B.Paste")
			(net "P0V8_SERDES_VDDA_PEX0")
		)
		(pad "2" smd rect
			(at -0.2667 0 270)
			(size 0.3048 0.381)
			(layers "B.Cu" "B.Mask" "B.Paste")
			(net "GND")
		)
	)
	(footprint ""
		(layer "B.Cu")
		(at 40.173656 -295.79824 180)
		(property "Reference" "R3295"
			(at 0 0 0)
			(layer "B.SilkS")
			(hide yes)
			(effects
				(font
					(size 1.27 1.27)
				)
				(justify mirror)
			)
		)
		(property "Value" ""
			(at 0 0 0)
			(layer "B.Fab")
			(effects
				(font
					(size 1.27 1.27)
				)
				(justify mirror)
			)
		)
		(duplicate_pad_numbers_are_jumpers no)
		(fp_line
			(start 0.7874 0.4064)
			(end 0.7874 -0.4064)
			(stroke
				(width 0.1524)
				(type default)
			)
			(layer "B.SilkS")
		)
		(fp_line
			(start 0.7874 -0.4064)
			(end -0.7874 -0.4064)
			(stroke
				(width 0.1524)
				(type default)
			)
			(layer "B.SilkS")
		)
		(fp_line
			(start -0.7874 0.4064)
			(end 0.7874 0.4064)
			(stroke
				(width 0.1524)
				(type default)
			)
			(layer "B.SilkS")
		)
		(fp_line
			(start -0.7874 -0.4064)
			(end -0.7874 0.4064)
			(stroke
				(width 0.1524)
				(type default)
			)
			(layer "B.SilkS")
		)
		(fp_line
			(start 0.67945 0.3048)
			(end 0.67945 -0.305054)
			(stroke
				(width 0.1)
				(type default)
			)
			(layer "B.Fab")
		)
		(fp_line
			(start 0.67945 -0.305054)
			(end 0.12065 -0.305054)
			(stroke
				(width 0.1)
				(type default)
			)
			(layer "B.Fab")
		)
		(fp_line
			(start 0.12065 0.3048)
			(end 0.67945 0.3048)
			(stroke
				(width 0.1)
				(type default)
			)
			(layer "B.Fab")
		)
		(fp_line
			(start 0.12065 0.2794)
			(end 0.12065 0.3048)
			(stroke
				(width 0.1)
				(type default)
			)
			(layer "B.Fab")
		)
		(fp_line
			(start 0.12065 -0.2794)
			(end -0.12065 -0.2794)
			(stroke
				(width 0.1)
				(type default)
			)
			(layer "B.Fab")
		)
		(fp_line
			(start 0.12065 -0.305054)
			(end 0.12065 -0.2794)
			(stroke
				(width 0.1)
				(type default)
			)
			(layer "B.Fab")
		)
		(fp_line
			(start -0.120396 0.3048)
			(end -0.120396 0.2794)
			(stroke
				(width 0.1)
				(type default)
			)
			(layer "B.Fab")
		)
		(fp_line
			(start -0.120396 0.2794)
			(end 0.12065 0.2794)
			(stroke
				(width 0.1)
				(type default)
			)
			(layer "B.Fab")
		)
		(fp_line
			(start -0.12065 -0.2794)
			(end -0.12065 -0.3048)
			(stroke
				(width 0.1)
				(type default)
			)
			(layer "B.Fab")
		)
		(fp_line
			(start -0.12065 -0.3048)
			(end -0.67945 -0.3048)
			(stroke
				(width 0.1)
				(type default)
			)
			(layer "B.Fab")
		)
		(fp_line
			(start -0.67945 0.3048)
			(end -0.120396 0.3048)
			(stroke
				(width 0.1)
				(type default)
			)
			(layer "B.Fab")
		)
		(fp_line
			(start -0.67945 -0.3048)
			(end -0.67945 0.3048)
			(stroke
				(width 0.1)
				(type default)
			)
			(layer "B.Fab")
		)
		(pad "1" smd circle
			(at 0.40005 0)
			(size 0 0)
			(layers "B.Cu" "B.Mask" "B.Paste")
			(net "SPI_PEX0_SDIO0_R")
		)
		(pad "2" smd circle
			(at -0.40005 0)
			(size 0 0)
			(layers "B.Cu" "B.Mask" "B.Paste")
			(net "SPI_PEX0_SDIO0")
		)
	)
	(footprint ""
		(layer "B.Cu")
		(at 49.67478 -297.79976 90)
		(property "Reference" "C1152"
			(at 0 0 90)
			(layer "B.SilkS")
			(hide yes)
			(effects
				(font
					(size 1.27 1.27)
				)
				(justify mirror)
			)
		)
		(property "Value" ""
			(at 0 0 90)
			(layer "B.Fab")
			(effects
				(font
					(size 1.27 1.27)
				)
				(justify mirror)
			)
		)
		(duplicate_pad_numbers_are_jumpers no)
		(fp_line
			(start 0.299974 -0.150114)
			(end -0.299974 -0.150114)
			(stroke
				(width 0.1)
				(type default)
			)
			(layer "B.Fab")
		)
		(fp_line
			(start -0.299974 -0.150114)
			(end -0.299974 0.150114)
			(stroke
				(width 0.1)
				(type default)
			)
			(layer "B.Fab")
		)
		(fp_line
			(start 0.299974 0.150114)
			(end 0.299974 -0.150114)
			(stroke
				(width 0.1)
				(type default)
			)
			(layer "B.Fab")
		)
		(fp_line
			(start -0.299974 0.150114)
			(end 0.299974 0.150114)
			(stroke
				(width 0.1)
				(type default)
			)
			(layer "B.Fab")
		)
		(pad "1" smd rect
			(at 0.2667 0 270)
			(size 0.3048 0.381)
			(layers "B.Cu" "B.Mask" "B.Paste")
			(net "P0V8_PEX0")
		)
		(pad "2" smd rect
			(at -0.2667 0 270)
			(size 0.3048 0.381)
			(layers "B.Cu" "B.Mask" "B.Paste")
			(net "GND")
		)
	)
	(footprint ""
		(layer "B.Cu")
		(at 67.249802 -296.37482)
		(property "Reference" "C1192"
			(at 0 0 0)
			(layer "B.SilkS")
			(hide yes)
			(effects
				(font
					(size 1.27 1.27)
				)
				(justify mirror)
			)
		)
		(property "Value" ""
			(at 0 0 0)
			(layer "B.Fab")
			(effects
				(font
					(size 1.27 1.27)
				)
				(justify mirror)
			)
		)
		(duplicate_pad_numbers_are_jumpers no)
		(fp_line
			(start -0.299974 -0.150114)
			(end -0.299974 0.150114)
			(stroke
				(width 0.1)
				(type default)
			)
			(layer "B.Fab")
		)
		(fp_line
			(start -0.299974 0.150114)
			(end 0.299974 0.150114)
			(stroke
				(width 0.1)
				(type default)
			)
			(layer "B.Fab")
		)
		(fp_line
			(start 0.299974 -0.150114)
			(end -0.299974 -0.150114)
			(stroke
				(width 0.1)
				(type default)
			)
			(layer "B.Fab")
		)
		(fp_line
			(start 0.299974 0.150114)
			(end 0.299974 -0.150114)
			(stroke
				(width 0.1)
				(type default)
			)
			(layer "B.Fab")
		)
		(pad "1" smd rect
			(at 0.2667 0 180)
			(size 0.3048 0.381)
			(layers "B.Cu" "B.Mask" "B.Paste")
			(net "P0V8_SERDES_VDDA_PEX0")
		)
		(pad "2" smd rect
			(at -0.2667 0 180)
			(size 0.3048 0.381)
			(layers "B.Cu" "B.Mask" "B.Paste")
			(net "GND")
		)
	)
	(footprint ""
		(layer "B.Cu")
		(at 394.65504 -292.57498)
		(property "Reference" "C3578"
			(at 0 0 0)
			(layer "B.SilkS")
			(hide yes)
			(effects
				(font
					(size 1.27 1.27)
				)
				(justify mirror)
			)
		)
		(property "Value" ""
			(at 0 0 0)
			(layer "B.Fab")
			(effects
				(font
					(size 1.27 1.27)
				)
				(justify mirror)
			)
		)
		(duplicate_pad_numbers_are_jumpers no)
		(fp_line
			(start -0.299974 -0.150114)
			(end -0.299974 0.150114)
			(stroke
				(width 0.1)
				(type default)
			)
			(layer "B.Fab")
		)
		(fp_line
			(start -0.299974 0.150114)
			(end 0.299974 0.150114)
			(stroke
				(width 0.1)
				(type default)
			)
			(layer "B.Fab")
		)
		(fp_line
			(start 0.299974 -0.150114)
			(end -0.299974 -0.150114)
			(stroke
				(width 0.1)
				(type default)
			)
			(layer "B.Fab")
		)
		(fp_line
			(start 0.299974 0.150114)
			(end 0.299974 -0.150114)
			(stroke
				(width 0.1)
				(type default)
			)
			(layer "B.Fab")
		)
		(pad "1" smd rect
			(at 0.2667 0 180)
			(size 0.3048 0.381)
			(layers "B.Cu" "B.Mask" "B.Paste")
			(net "PCEPLL6_VDDA18_PEX3")
		)
		(pad "2" smd rect
			(at -0.2667 0 180)
			(size 0.3048 0.381)
			(layers "B.Cu" "B.Mask" "B.Paste")
			(net "GND")
		)
	)
	(footprint ""
		(layer "B.Cu")
		(at 363.252766 -308.613556 90)
		(property "Reference" "C4373"
			(at 0 0 90)
			(layer "B.SilkS")
			(hide yes)
			(effects
				(font
					(size 1.27 1.27)
				)
				(justify mirror)
			)
		)
		(property "Value" ""
			(at 0 0 90)
			(layer "B.Fab")
			(effects
				(font
					(size 1.27 1.27)
				)
				(justify mirror)
			)
		)
		(duplicate_pad_numbers_are_jumpers no)
		(fp_line
			(start 1.2954 -0.5842)
			(end -1.2954 -0.5842)
			(stroke
				(width 0.1524)
				(type default)
			)
			(layer "B.SilkS")
		)
		(fp_line
			(start -1.2954 -0.5842)
			(end -1.2954 0.5842)
			(stroke
				(width 0.1524)
				(type default)
			)
			(layer "B.SilkS")
		)
		(fp_line
			(start 1.2954 0.5842)
			(end 1.2954 -0.5842)
			(stroke
				(width 0.1524)
				(type default)
			)
			(layer "B.SilkS")
		)
		(fp_line
			(start -1.2954 0.5842)
			(end 1.2954 0.5842)
			(stroke
				(width 0.1524)
				(type default)
			)
			(layer "B.SilkS")
		)
		(fp_line
			(start 0.8636 -0.4572)
			(end -0.8636 -0.4572)
			(stroke
				(width 0.1)
				(type default)
			)
			(layer "B.Fab")
		)
		(fp_line
			(start -0.8636 -0.4572)
			(end -0.8636 -0.4064)
			(stroke
				(width 0.1)
				(type default)
			)
			(layer "B.Fab")
		)
		(fp_line
			(start 1.1938 -0.4064)
			(end 0.8636 -0.4064)
			(stroke
				(width 0.1)
				(type default)
			)
			(layer "B.Fab")
		)
		(fp_line
			(start 0.8636 -0.4064)
			(end 0.8636 -0.4572)
			(stroke
				(width 0.1)
				(type default)
			)
			(layer "B.Fab")
		)
		(fp_line
			(start -0.8636 -0.4064)
			(end -1.1938 -0.4064)
			(stroke
				(width 0.1)
				(type default)
			)
			(layer "B.Fab")
		)
		(fp_line
			(start -1.1938 -0.4064)
			(end -1.1938 0.4064)
			(stroke
				(width 0.1)
				(type default)
			)
			(layer "B.Fab")
		)
		(fp_line
			(start 1.1938 0.4064)
			(end 1.1938 -0.4064)
			(stroke
				(width 0.1)
				(type default)
			)
			(layer "B.Fab")
		)
		(fp_line
			(start 0.8636 0.4064)
			(end 1.1938 0.4064)
			(stroke
				(width 0.1)
				(type default)
			)
			(layer "B.Fab")
		)
		(fp_line
			(start -0.8636 0.4064)
			(end -0.8636 0.4572)
			(stroke
				(width 0.1)
				(type default)
			)
			(layer "B.Fab")
		)
		(fp_line
			(start -1.1938 0.4064)
			(end -0.8636 0.4064)
			(stroke
				(width 0.1)
				(type default)
			)
			(layer "B.Fab")
		)
		(fp_line
			(start 0.8636 0.4572)
			(end 0.8636 0.4064)
			(stroke
				(width 0.1)
				(type default)
			)
			(layer "B.Fab")
		)
		(fp_line
			(start -0.8636 0.4572)
			(end 0.8636 0.4572)
			(stroke
				(width 0.1)
				(type default)
			)
			(layer "B.Fab")
		)
		(pad "1" smd rect
			(at 0.7366 0)
			(size 0.7112 0.8128)
			(layers "B.Cu" "B.Mask" "B.Paste")
			(net "P0V8_PEX3")
		)
		(pad "2" smd rect
			(at -0.7366 0)
			(size 0.7112 0.8128)
			(layers "B.Cu" "B.Mask" "B.Paste")
			(net "GND")
		)
	)
	(footprint ""
		(layer "B.Cu")
		(at 396.0749 -295.3766 90)
		(property "Reference" "C3562"
			(at 0 0 90)
			(layer "B.SilkS")
			(hide yes)
			(effects
				(font
					(size 1.27 1.27)
				)
				(justify mirror)
			)
		)
		(property "Value" ""
			(at 0 0 90)
			(layer "B.Fab")
			(effects
				(font
					(size 1.27 1.27)
				)
				(justify mirror)
			)
		)
		(duplicate_pad_numbers_are_jumpers no)
		(fp_line
			(start 0.299974 -0.150114)
			(end -0.299974 -0.150114)
			(stroke
				(width 0.1)
				(type default)
			)
			(layer "B.Fab")
		)
		(fp_line
			(start -0.299974 -0.150114)
			(end -0.299974 0.150114)
			(stroke
				(width 0.1)
				(type default)
			)
			(layer "B.Fab")
		)
		(fp_line
			(start 0.299974 0.150114)
			(end 0.299974 -0.150114)
			(stroke
				(width 0.1)
				(type default)
			)
			(layer "B.Fab")
		)
		(fp_line
			(start -0.299974 0.150114)
			(end 0.299974 0.150114)
			(stroke
				(width 0.1)
				(type default)
			)
			(layer "B.Fab")
		)
		(pad "1" smd rect
			(at 0.2667 0 270)
			(size 0.3048 0.381)
			(layers "B.Cu" "B.Mask" "B.Paste")
			(net "PCEPLL3_VDDA18_PEX3")
		)
		(pad "2" smd rect
			(at -0.2667 0 270)
			(size 0.3048 0.381)
			(layers "B.Cu" "B.Mask" "B.Paste")
			(net "GND")
		)
	)
	(footprint ""
		(layer "B.Cu")
		(at 403.199854 -299.699934 -90)
		(property "Reference" "C1985"
			(at 0 0 90)
			(layer "B.SilkS")
			(hide yes)
			(effects
				(font
					(size 1.27 1.27)
				)
				(justify mirror)
			)
		)
		(property "Value" ""
			(at 0 0 90)
			(layer "B.Fab")
			(effects
				(font
					(size 1.27 1.27)
				)
				(justify mirror)
			)
		)
		(duplicate_pad_numbers_are_jumpers no)
		(fp_line
			(start -0.299974 0.150114)
			(end 0.299974 0.150114)
			(stroke
				(width 0.1)
				(type default)
			)
			(layer "B.Fab")
		)
		(fp_line
			(start 0.299974 0.150114)
			(end 0.299974 -0.150114)
			(stroke
				(width 0.1)
				(type default)
			)
			(layer "B.Fab")
		)
		(fp_line
			(start -0.299974 -0.150114)
			(end -0.299974 0.150114)
			(stroke
				(width 0.1)
				(type default)
			)
			(layer "B.Fab")
		)
		(fp_line
			(start 0.299974 -0.150114)
			(end -0.299974 -0.150114)
			(stroke
				(width 0.1)
				(type default)
			)
			(layer "B.Fab")
		)
		(pad "1" smd rect
			(at 0.2667 0 90)
			(size 0.3048 0.381)
			(layers "B.Cu" "B.Mask" "B.Paste")
			(net "P0V8_SERDES_VDDA_PEX3")
		)
		(pad "2" smd rect
			(at -0.2667 0 90)
			(size 0.3048 0.381)
			(layers "B.Cu" "B.Mask" "B.Paste")
			(net "GND")
		)
	)
	(footprint ""
		(layer "B.Cu")
		(at 212.09 -201.549 -90)
		(property "Reference" "R1520"
			(at 0 0 90)
			(layer "B.SilkS")
			(hide yes)
			(effects
				(font
					(size 1.27 1.27)
				)
				(justify mirror)
			)
		)
		(property "Value" ""
			(at 0 0 90)
			(layer "B.Fab")
			(effects
				(font
					(size 1.27 1.27)
				)
				(justify mirror)
			)
		)
		(duplicate_pad_numbers_are_jumpers no)
		(fp_line
			(start -0.7874 0.4064)
			(end 0.7874 0.4064)
			(stroke
				(width 0.1524)
				(type default)
			)
			(layer "B.SilkS")
		)
		(fp_line
			(start 0.7874 0.4064)
			(end 0.7874 -0.4064)
			(stroke
				(width 0.1524)
				(type default)
			)
			(layer "B.SilkS")
		)
		(fp_line
			(start -0.7874 -0.4064)
			(end -0.7874 0.4064)
			(stroke
				(width 0.1524)
				(type default)
			)
			(layer "B.SilkS")
		)
		(fp_line
			(start 0.7874 -0.4064)
			(end -0.7874 -0.4064)
			(stroke
				(width 0.1524)
				(type default)
			)
			(layer "B.SilkS")
		)
		(fp_line
			(start -0.67945 0.3048)
			(end -0.120396 0.3048)
			(stroke
				(width 0.1)
				(type default)
			)
			(layer "B.Fab")
		)
		(fp_line
			(start -0.120396 0.3048)
			(end -0.120396 0.2794)
			(stroke
				(width 0.1)
				(type default)
			)
			(layer "B.Fab")
		)
		(fp_line
			(start 0.12065 0.3048)
			(end 0.67945 0.3048)
			(stroke
				(width 0.1)
				(type default)
			)
			(layer "B.Fab")
		)
		(fp_line
			(start 0.67945 0.3048)
			(end 0.67945 -0.305054)
			(stroke
				(width 0.1)
				(type default)
			)
			(layer "B.Fab")
		)
		(fp_line
			(start -0.120396 0.2794)
			(end 0.12065 0.2794)
			(stroke
				(width 0.1)
				(type default)
			)
			(layer "B.Fab")
		)
		(fp_line
			(start 0.12065 0.2794)
			(end 0.12065 0.3048)
			(stroke
				(width 0.1)
				(type default)
			)
			(layer "B.Fab")
		)
		(fp_line
			(start -0.12065 -0.2794)
			(end -0.12065 -0.3048)
			(stroke
				(width 0.1)
				(type default)
			)
			(layer "B.Fab")
		)
		(fp_line
			(start 0.12065 -0.2794)
			(end -0.12065 -0.2794)
			(stroke
				(width 0.1)
				(type default)
			)
			(layer "B.Fab")
		)
		(fp_line
			(start -0.67945 -0.3048)
			(end -0.67945 0.3048)
			(stroke
				(width 0.1)
				(type default)
			)
			(layer "B.Fab")
		)
		(fp_line
			(start -0.12065 -0.3048)
			(end -0.67945 -0.3048)
			(stroke
				(width 0.1)
				(type default)
			)
			(layer "B.Fab")
		)
		(fp_line
			(start 0.12065 -0.305054)
			(end 0.12065 -0.2794)
			(stroke
				(width 0.1)
				(type default)
			)
			(layer "B.Fab")
		)
		(fp_line
			(start 0.67945 -0.305054)
			(end 0.12065 -0.305054)
			(stroke
				(width 0.1)
				(type default)
			)
			(layer "B.Fab")
		)
		(pad "1" smd circle
			(at 0.40005 0 90)
			(size 0 0)
			(layers "B.Cu" "B.Mask" "B.Paste")
			(net "SMB_NIC5_LS_R_SCL")
		)
		(pad "2" smd circle
			(at -0.40005 0 90)
			(size 0 0)
			(layers "B.Cu" "B.Mask" "B.Paste")
			(net "SMB_NIC5_R_SCL")
		)
	)
	(footprint ""
		(layer "B.Cu")
		(at 25.117298 -260.131306)
		(property "Reference" "C3071"
			(at 0 0 0)
			(layer "B.SilkS")
			(hide yes)
			(effects
				(font
					(size 1.27 1.27)
				)
				(justify mirror)
			)
		)
		(property "Value" ""
			(at 0 0 0)
			(layer "B.Fab")
			(effects
				(font
					(size 1.27 1.27)
				)
				(justify mirror)
			)
		)
		(duplicate_pad_numbers_are_jumpers no)
		(fp_line
			(start -0.299974 -0.150114)
			(end -0.299974 0.150114)
			(stroke
				(width 0.1)
				(type default)
			)
			(layer "B.Fab")
		)
		(fp_line
			(start -0.299974 0.150114)
			(end 0.299974 0.150114)
			(stroke
				(width 0.1)
				(type default)
			)
			(layer "B.Fab")
		)
		(fp_line
			(start 0.299974 -0.150114)
			(end -0.299974 -0.150114)
			(stroke
				(width 0.1)
				(type default)
			)
			(layer "B.Fab")
		)
		(fp_line
			(start 0.299974 0.150114)
			(end 0.299974 -0.150114)
			(stroke
				(width 0.1)
				(type default)
			)
			(layer "B.Fab")
		)
		(pad "1" smd rect
			(at 0.2667 0 180)
			(size 0.3048 0.381)
			(layers "B.Cu" "B.Mask" "B.Paste")
			(net "P1V8_VDDA_PEX0")
		)
		(pad "2" smd rect
			(at -0.2667 0 180)
			(size 0.3048 0.381)
			(layers "B.Cu" "B.Mask" "B.Paste")
			(net "GND")
		)
	)
	(footprint ""
		(layer "B.Cu")
		(at 63.001398 -305.399948 -90)
		(property "Reference" "C2966"
			(at 0 0 90)
			(layer "B.SilkS")
			(hide yes)
			(effects
				(font
					(size 1.27 1.27)
				)
				(justify mirror)
			)
		)
		(property "Value" ""
			(at 0 0 90)
			(layer "B.Fab")
			(effects
				(font
					(size 1.27 1.27)
				)
				(justify mirror)
			)
		)
		(duplicate_pad_numbers_are_jumpers no)
		(fp_line
			(start -0.299974 0.150114)
			(end 0.299974 0.150114)
			(stroke
				(width 0.1)
				(type default)
			)
			(layer "B.Fab")
		)
		(fp_line
			(start 0.299974 0.150114)
			(end 0.299974 -0.150114)
			(stroke
				(width 0.1)
				(type default)
			)
			(layer "B.Fab")
		)
		(fp_line
			(start -0.299974 -0.150114)
			(end -0.299974 0.150114)
			(stroke
				(width 0.1)
				(type default)
			)
			(layer "B.Fab")
		)
		(fp_line
			(start 0.299974 -0.150114)
			(end -0.299974 -0.150114)
			(stroke
				(width 0.1)
				(type default)
			)
			(layer "B.Fab")
		)
		(pad "1" smd rect
			(at 0.2667 0 90)
			(size 0.3048 0.381)
			(layers "B.Cu" "B.Mask" "B.Paste")
			(net "P1V25_SERDES_VDDPLL_PEX0")
		)
		(pad "2" smd rect
			(at -0.2667 0 90)
			(size 0.3048 0.381)
			(layers "B.Cu" "B.Mask" "B.Paste")
			(net "GND")
		)
	)
	(footprint ""
		(layer "B.Cu")
		(at 214.472774 -234.205526 -90)
		(property "Reference" "R6334"
			(at 0 0 90)
			(layer "B.SilkS")
			(hide yes)
			(effects
				(font
					(size 1.27 1.27)
				)
				(justify mirror)
			)
		)
		(property "Value" ""
			(at 0 0 90)
			(layer "B.Fab")
			(effects
				(font
					(size 1.27 1.27)
				)
				(justify mirror)
			)
		)
		(duplicate_pad_numbers_are_jumpers no)
		(fp_line
			(start -0.7874 0.4064)
			(end 0.7874 0.4064)
			(stroke
				(width 0.1524)
				(type default)
			)
			(layer "B.SilkS")
		)
		(fp_line
			(start 0.7874 0.4064)
			(end 0.7874 -0.4064)
			(stroke
				(width 0.1524)
				(type default)
			)
			(layer "B.SilkS")
		)
		(fp_line
			(start -0.7874 -0.4064)
			(end -0.7874 0.4064)
			(stroke
				(width 0.1524)
				(type default)
			)
			(layer "B.SilkS")
		)
		(fp_line
			(start 0.7874 -0.4064)
			(end -0.7874 -0.4064)
			(stroke
				(width 0.1524)
				(type default)
			)
			(layer "B.SilkS")
		)
		(fp_line
			(start -0.67945 0.3048)
			(end -0.120396 0.3048)
			(stroke
				(width 0.1)
				(type default)
			)
			(layer "B.Fab")
		)
		(fp_line
			(start -0.120396 0.3048)
			(end -0.120396 0.2794)
			(stroke
				(width 0.1)
				(type default)
			)
			(layer "B.Fab")
		)
		(fp_line
			(start 0.12065 0.3048)
			(end 0.67945 0.3048)
			(stroke
				(width 0.1)
				(type default)
			)
			(layer "B.Fab")
		)
		(fp_line
			(start 0.67945 0.3048)
			(end 0.67945 -0.305054)
			(stroke
				(width 0.1)
				(type default)
			)
			(layer "B.Fab")
		)
		(fp_line
			(start -0.120396 0.2794)
			(end 0.12065 0.2794)
			(stroke
				(width 0.1)
				(type default)
			)
			(layer "B.Fab")
		)
		(fp_line
			(start 0.12065 0.2794)
			(end 0.12065 0.3048)
			(stroke
				(width 0.1)
				(type default)
			)
			(layer "B.Fab")
		)
		(fp_line
			(start -0.12065 -0.2794)
			(end -0.12065 -0.3048)
			(stroke
				(width 0.1)
				(type default)
			)
			(layer "B.Fab")
		)
		(fp_line
			(start 0.12065 -0.2794)
			(end -0.12065 -0.2794)
			(stroke
				(width 0.1)
				(type default)
			)
			(layer "B.Fab")
		)
		(fp_line
			(start -0.67945 -0.3048)
			(end -0.67945 0.3048)
			(stroke
				(width 0.1)
				(type default)
			)
			(layer "B.Fab")
		)
		(fp_line
			(start -0.12065 -0.3048)
			(end -0.67945 -0.3048)
			(stroke
				(width 0.1)
				(type default)
			)
			(layer "B.Fab")
		)
		(fp_line
			(start 0.12065 -0.305054)
			(end 0.12065 -0.2794)
			(stroke
				(width 0.1)
				(type default)
			)
			(layer "B.Fab")
		)
		(fp_line
			(start 0.67945 -0.305054)
			(end 0.12065 -0.305054)
			(stroke
				(width 0.1)
				(type default)
			)
			(layer "B.Fab")
		)
		(pad "1" smd circle
			(at 0.40005 0 90)
			(size 0 0)
			(layers "B.Cu" "B.Mask" "B.Paste")
			(net "SMB_PEX3_SCL")
		)
		(pad "2" smd circle
			(at -0.40005 0 90)
			(size 0 0)
			(layers "B.Cu" "B.Mask" "B.Paste")
			(net "SMB_PEX3_MUX_SCL")
		)
	)
	(footprint ""
		(layer "B.Cu")
		(at 223.90735 -456.90663 180)
		(property "Reference" "X79"
			(at 0.1778 -1.92913 180)
			(unlocked yes)
			(layer "B.SilkS")
			(effects
				(font
					(size 0.7874 0.5842)
					(thickness 0.1524)
				)
				(justify left mirror)
			)
		)
		(property "Value" ""
			(at 0 0 0)
			(layer "B.Fab")
			(effects
				(font
					(size 1.27 1.27)
				)
				(justify mirror)
			)
		)
		(property "Device Type" "TP_TDR_4P_FTS_MPKT4_H025P0200_IO_TP15_TP_TDR_4P_DIP"
			(at -1.30175 1.27 90)
			(unlocked yes)
			(layer "B.Fab")
			(hide yes)
			(effects
				(font
					(size 0.635 0.4064)
					(thickness 0.1524)
				)
				(justify mirror)
			)
		)
		(property "User Part Number" "TP15"
			(at -1.30175 1.27 90)
			(unlocked yes)
			(layer "Cmts.User")
			(hide yes)
			(effects
				(font
					(size 0.635 0.4064)
					(thickness 0.1524)
				)
				(justify mirror)
			)
		)
		(duplicate_pad_numbers_are_jumpers no)
		(fp_line
			(start 0 3.81)
			(end -2.54 3.81)
			(stroke
				(width 0.1524)
				(type default)
			)
			(layer "B.SilkS")
		)
		(fp_line
			(start 0 3.175)
			(end 0 3.81)
			(stroke
				(width 0.1524)
				(type default)
			)
			(layer "B.SilkS")
		)
		(fp_line
			(start 0 0.635)
			(end 0 1.905)
			(stroke
				(width 0.1524)
				(type default)
			)
			(layer "B.SilkS")
		)
		(fp_line
			(start 0 -1.27)
			(end 0 -0.635)
			(stroke
				(width 0.1524)
				(type default)
			)
			(layer "B.SilkS")
		)
		(fp_line
			(start -2.54 3.81)
			(end -2.54 3.6703)
			(stroke
				(width 0.1524)
				(type default)
			)
			(layer "B.SilkS")
		)
		(fp_line
			(start -2.54 1.4097)
			(end -2.54 1.1303)
			(stroke
				(width 0.1524)
				(type default)
			)
			(layer "B.SilkS")
		)
		(fp_line
			(start -2.54 -1.1303)
			(end -2.54 -1.27)
			(stroke
				(width 0.1524)
				(type default)
			)
			(layer "B.SilkS")
		)
		(fp_line
			(start -2.54 -1.27)
			(end 0 -1.27)
			(stroke
				(width 0.1524)
				(type default)
			)
			(layer "B.SilkS")
		)
		(fp_poly
			(pts
				(xy 0.761746 0) (xy 2.285746 -0.762) (xy 2.285746 0.762)
			)
			(stroke
				(width 0)
				(type default)
			)
			(fill yes)
			(layer "B.SilkS")
		)
		(fp_line
			(start 0 3.81)
			(end -2.54 3.81)
			(stroke
				(width 0.1)
				(type default)
			)
			(layer "B.Fab")
		)
		(fp_line
			(start 0 -1.27)
			(end 0 3.81)
			(stroke
				(width 0.1)
				(type default)
			)
			(layer "B.Fab")
		)
		(fp_line
			(start -2.54 3.81)
			(end -2.54 -1.27)
			(stroke
				(width 0.1)
				(type default)
			)
			(layer "B.Fab")
		)
		(fp_line
			(start -2.54 -1.27)
			(end 0 -1.27)
			(stroke
				(width 0.1)
				(type default)
			)
			(layer "B.Fab")
		)
		(fp_poly
			(pts
				(xy 0.761746 0) (xy 2.285746 -0.762) (xy 2.285746 0.762)
			)
			(stroke
				(width 0)
				(type default)
			)
			(fill yes)
			(layer "B.Fab")
		)
		(pad "1" thru_hole circle
			(at 0 0)
			(size 1.0033 1.0033)
			(drill 0.249936)
			(layers "*.Cu" "*.Mask")
			(remove_unused_layers no)
			(net "TDR_DIFF_100_IN6_DIN")
			(clearance 0.10795)
			(padstack
				(mode front_inner_back)
				(layer "Inner"
					(shape circle)
					(size 0.8001 0.8001)
					(clearance 0.1524)
				)
				(layer "B.Cu"
					(shape circle)
					(size 1.0033 1.0033)
					(thermal_gap 0.10795)
					(clearance 0.10795)
				)
			)
		)
		(pad "2" thru_hole circle
			(at -2.54 0)
			(size 1.9939 1.9939)
			(drill 0.249936)
			(layers "*.Cu" "*.Mask")
			(remove_unused_layers no)
			(net "COUPON_GND1")
			(clearance 0.10795)
			(padstack
				(mode front_inner_back)
				(layer "Inner"
					(shape circle)
					(size 0.8001 0.8001)
					(clearance 0.1524)
				)
				(layer "B.Cu"
					(shape circle)
					(size 1.9939 1.9939)
					(thermal_gap 0.10795)
					(clearance 0.10795)
				)
			)
		)
		(pad "3" thru_hole circle
			(at -2.54 2.54)
			(size 1.9939 1.9939)
			(drill 0.249936)
			(layers "*.Cu" "*.Mask")
			(remove_unused_layers no)
			(net "COUPON_GND1")
			(clearance 0.10795)
			(padstack
				(mode front_inner_back)
				(layer "Inner"
					(shape circle)
					(size 0.8001 0.8001)
					(clearance 0.1524)
				)
				(layer "B.Cu"
					(shape circle)
					(size 1.9939 1.9939)
					(thermal_gap 0.10795)
					(clearance 0.10795)
				)
			)
		)
		(pad "4" thru_hole circle
			(at 0 2.54)
			(size 1.0033 1.0033)
			(drill 0.249936)
			(layers "*.Cu" "*.Mask")
			(remove_unused_layers no)
			(net "TDR_DIFF_100_IN6_DIP")
			(clearance 0.10795)
			(padstack
				(mode front_inner_back)
				(layer "Inner"
					(shape circle)
					(size 0.8001 0.8001)
					(clearance 0.1524)
				)
				(layer "B.Cu"
					(shape circle)
					(size 1.0033 1.0033)
					(thermal_gap 0.10795)
					(clearance 0.10795)
				)
			)
		)
	)
	(footprint ""
		(layer "B.Cu")
		(at 100.868734 -237.306612 -90)
		(property "Reference" "PC1005"
			(at 0 0 90)
			(layer "B.SilkS")
			(hide yes)
			(effects
				(font
					(size 1.27 1.27)
				)
				(justify mirror)
			)
		)
		(property "Value" ""
			(at 0 0 90)
			(layer "B.Fab")
			(effects
				(font
					(size 1.27 1.27)
				)
				(justify mirror)
			)
		)
		(duplicate_pad_numbers_are_jumpers no)
		(fp_line
			(start -1.524 0.762)
			(end 1.524 0.762)
			(stroke
				(width 0.1524)
				(type default)
			)
			(layer "B.SilkS")
		)
		(fp_line
			(start 1.524 0.762)
			(end 1.524 -0.762)
			(stroke
				(width 0.1524)
				(type default)
			)
			(layer "B.SilkS")
		)
		(fp_line
			(start -1.524 -0.762)
			(end -1.524 0.762)
			(stroke
				(width 0.1524)
				(type default)
			)
			(layer "B.SilkS")
		)
		(fp_line
			(start 1.524 -0.762)
			(end -1.524 -0.762)
			(stroke
				(width 0.1524)
				(type default)
			)
			(layer "B.SilkS")
		)
		(fp_line
			(start -1.1049 0.724916)
			(end -1.1049 -0.724916)
			(stroke
				(width 0.1)
				(type default)
			)
			(layer "B.Fab")
		)
		(fp_line
			(start 1.1049 0.724916)
			(end -1.1049 0.724916)
			(stroke
				(width 0.1)
				(type default)
			)
			(layer "B.Fab")
		)
		(fp_line
			(start -1.1049 -0.724916)
			(end 1.1049 -0.724916)
			(stroke
				(width 0.1)
				(type default)
			)
			(layer "B.Fab")
		)
		(fp_line
			(start 1.1049 -0.724916)
			(end 1.1049 0.724916)
			(stroke
				(width 0.1)
				(type default)
			)
			(layer "B.Fab")
		)
		(pad "1" smd rect
			(at 0.889 0 270)
			(size 1.016 1.27)
			(layers "B.Cu" "B.Mask" "B.Paste")
			(net "P1V8_PEX_R")
		)
		(pad "2" smd rect
			(at -0.889 0 270)
			(size 1.016 1.27)
			(layers "B.Cu" "B.Mask" "B.Paste")
			(net "GND")
		)
	)
	(footprint ""
		(layer "B.Cu")
		(at 178.124866 -293.99992 -90)
		(property "Reference" "C1397"
			(at 0 0 90)
			(layer "B.SilkS")
			(hide yes)
			(effects
				(font
					(size 1.27 1.27)
				)
				(justify mirror)
			)
		)
		(property "Value" ""
			(at 0 0 90)
			(layer "B.Fab")
			(effects
				(font
					(size 1.27 1.27)
				)
				(justify mirror)
			)
		)
		(duplicate_pad_numbers_are_jumpers no)
		(fp_line
			(start -0.299974 0.150114)
			(end 0.299974 0.150114)
			(stroke
				(width 0.1)
				(type default)
			)
			(layer "B.Fab")
		)
		(fp_line
			(start 0.299974 0.150114)
			(end 0.299974 -0.150114)
			(stroke
				(width 0.1)
				(type default)
			)
			(layer "B.Fab")
		)
		(fp_line
			(start -0.299974 -0.150114)
			(end -0.299974 0.150114)
			(stroke
				(width 0.1)
				(type default)
			)
			(layer "B.Fab")
		)
		(fp_line
			(start 0.299974 -0.150114)
			(end -0.299974 -0.150114)
			(stroke
				(width 0.1)
				(type default)
			)
			(layer "B.Fab")
		)
		(pad "1" smd rect
			(at 0.2667 0 90)
			(size 0.3048 0.381)
			(layers "B.Cu" "B.Mask" "B.Paste")
			(net "P0V8_PEX1")
		)
		(pad "2" smd rect
			(at -0.2667 0 90)
			(size 0.3048 0.381)
			(layers "B.Cu" "B.Mask" "B.Paste")
			(net "GND")
		)
	)
	(footprint ""
		(layer "B.Cu")
		(at 305.6001 -109.251496)
		(property "Reference" "C924"
			(at 0 0 0)
			(layer "B.SilkS")
			(hide yes)
			(effects
				(font
					(size 1.27 1.27)
				)
				(justify mirror)
			)
		)
		(property "Value" ""
			(at 0 0 0)
			(layer "B.Fab")
			(effects
				(font
					(size 1.27 1.27)
				)
				(justify mirror)
			)
		)
		(duplicate_pad_numbers_are_jumpers no)
		(fp_line
			(start -0.299974 -0.150114)
			(end -0.299974 0.150114)
			(stroke
				(width 0.1)
				(type default)
			)
			(layer "B.Fab")
		)
		(fp_line
			(start -0.299974 0.150114)
			(end 0.299974 0.150114)
			(stroke
				(width 0.1)
				(type default)
			)
			(layer "B.Fab")
		)
		(fp_line
			(start 0.299974 -0.150114)
			(end -0.299974 -0.150114)
			(stroke
				(width 0.1)
				(type default)
			)
			(layer "B.Fab")
		)
		(fp_line
			(start 0.299974 0.150114)
			(end 0.299974 -0.150114)
			(stroke
				(width 0.1)
				(type default)
			)
			(layer "B.Fab")
		)
		(pad "1" smd rect
			(at 0.2667 0 180)
			(size 0.3048 0.381)
			(layers "B.Cu" "B.Mask" "B.Paste")
			(net "P12V_NIC5")
		)
		(pad "2" smd rect
			(at -0.2667 0 180)
			(size 0.3048 0.381)
			(layers "B.Cu" "B.Mask" "B.Paste")
			(net "GND")
		)
	)
	(footprint ""
		(layer "B.Cu")
		(at 58.699908 -299.699934 -90)
		(property "Reference" "C1189"
			(at 0 0 90)
			(layer "B.SilkS")
			(hide yes)
			(effects
				(font
					(size 1.27 1.27)
				)
				(justify mirror)
			)
		)
		(property "Value" ""
			(at 0 0 90)
			(layer "B.Fab")
			(effects
				(font
					(size 1.27 1.27)
				)
				(justify mirror)
			)
		)
		(duplicate_pad_numbers_are_jumpers no)
		(fp_line
			(start -0.299974 0.150114)
			(end 0.299974 0.150114)
			(stroke
				(width 0.1)
				(type default)
			)
			(layer "B.Fab")
		)
		(fp_line
			(start 0.299974 0.150114)
			(end 0.299974 -0.150114)
			(stroke
				(width 0.1)
				(type default)
			)
			(layer "B.Fab")
		)
		(fp_line
			(start -0.299974 -0.150114)
			(end -0.299974 0.150114)
			(stroke
				(width 0.1)
				(type default)
			)
			(layer "B.Fab")
		)
		(fp_line
			(start 0.299974 -0.150114)
			(end -0.299974 -0.150114)
			(stroke
				(width 0.1)
				(type default)
			)
			(layer "B.Fab")
		)
		(pad "1" smd rect
			(at 0.2667 0 90)
			(size 0.3048 0.381)
			(layers "B.Cu" "B.Mask" "B.Paste")
			(net "P0V8_SERDES_VDDA_PEX0")
		)
		(pad "2" smd rect
			(at -0.2667 0 90)
			(size 0.3048 0.381)
			(layers "B.Cu" "B.Mask" "B.Paste")
			(net "GND")
		)
	)
	(footprint ""
		(layer "B.Cu")
		(at 331.41158 -211.390738)
		(property "Reference" "C2058"
			(at 0 0 0)
			(layer "B.SilkS")
			(hide yes)
			(effects
				(font
					(size 1.27 1.27)
				)
				(justify mirror)
			)
		)
		(property "Value" ""
			(at 0 0 0)
			(layer "B.Fab")
			(effects
				(font
					(size 1.27 1.27)
				)
				(justify mirror)
			)
		)
		(duplicate_pad_numbers_are_jumpers no)
		(fp_line
			(start -0.69215 -0.2921)
			(end -0.69215 0.2921)
			(stroke
				(width 0.1524)
				(type default)
			)
			(layer "B.SilkS")
		)
		(fp_line
			(start -0.69215 0.2921)
			(end 0.69215 0.2921)
			(stroke
				(width 0.1524)
				(type default)
			)
			(layer "B.SilkS")
		)
		(fp_line
			(start 0.69215 -0.2921)
			(end -0.69215 -0.2921)
			(stroke
				(width 0.1524)
				(type default)
			)
			(layer "B.SilkS")
		)
		(fp_line
			(start 0.69215 0.2921)
			(end 0.69215 -0.2921)
			(stroke
				(width 0.1524)
				(type default)
			)
			(layer "B.SilkS")
		)
		(fp_line
			(start -0.51435 -0.2794)
			(end -0.51435 0.2794)
			(stroke
				(width 0.1)
				(type default)
			)
			(layer "B.Fab")
		)
		(fp_line
			(start -0.51435 0.2794)
			(end 0.51435 0.2794)
			(stroke
				(width 0.1)
				(type default)
			)
			(layer "B.Fab")
		)
		(fp_line
			(start 0.51435 -0.2794)
			(end -0.51435 -0.2794)
			(stroke
				(width 0.1)
				(type default)
			)
			(layer "B.Fab")
		)
		(fp_line
			(start 0.51435 0.2794)
			(end 0.51435 -0.2794)
			(stroke
				(width 0.1)
				(type default)
			)
			(layer "B.Fab")
		)
		(pad "1" smd circle
			(at 0.40005 0 180)
			(size 0 0)
			(layers "B.Cu" "B.Mask" "B.Paste")
			(net "P3V3_FPGA_VCCIO2")
		)
		(pad "2" smd circle
			(at -0.40005 0 180)
			(size 0 0)
			(layers "B.Cu" "B.Mask" "B.Paste")
			(net "GND")
		)
		(zone
			(layer "B.Cu")
			(hatch none 0.5)
			(connect_pads
				(clearance 0)
			)
			(min_thickness 0.25)
			(keepout
				(tracks not_allowed)
				(vias allowed)
				(pads allowed)
				(copperpour not_allowed)
				(footprints allowed)
			)
			(placement
				(enabled no)
				(sheetname "")
			)
			(fill
				(thermal_gap 0.5)
				(thermal_bridge_width 0.5)
				(island_removal_mode 0)
			)
			(polygon
				(pts
					(xy 331.60208 -211.303108) (xy 331.51064 -211.244942) (xy 331.31125 -211.244942) (xy 331.22108 -211.303108)
					(xy 331.22108 -211.478368) (xy 331.31125 -211.536788) (xy 331.51064 -211.536788) (xy 331.60208 -211.478622)
				)
			)
		)
	)
	(footprint ""
		(layer "B.Cu")
		(at 44.449746 -293.04996)
		(property "Reference" "C3004"
			(at 0 0 0)
			(layer "B.SilkS")
			(hide yes)
			(effects
				(font
					(size 1.27 1.27)
				)
				(justify mirror)
			)
		)
		(property "Value" ""
			(at 0 0 0)
			(layer "B.Fab")
			(effects
				(font
					(size 1.27 1.27)
				)
				(justify mirror)
			)
		)
		(duplicate_pad_numbers_are_jumpers no)
		(fp_line
			(start -0.299974 -0.150114)
			(end -0.299974 0.150114)
			(stroke
				(width 0.1)
				(type default)
			)
			(layer "B.Fab")
		)
		(fp_line
			(start -0.299974 0.150114)
			(end 0.299974 0.150114)
			(stroke
				(width 0.1)
				(type default)
			)
			(layer "B.Fab")
		)
		(fp_line
			(start 0.299974 -0.150114)
			(end -0.299974 -0.150114)
			(stroke
				(width 0.1)
				(type default)
			)
			(layer "B.Fab")
		)
		(fp_line
			(start 0.299974 0.150114)
			(end 0.299974 -0.150114)
			(stroke
				(width 0.1)
				(type default)
			)
			(layer "B.Fab")
		)
		(pad "1" smd rect
			(at 0.2667 0 180)
			(size 0.3048 0.381)
			(layers "B.Cu" "B.Mask" "B.Paste")
			(net "P1V8_PEX")
		)
		(pad "2" smd rect
			(at -0.2667 0 180)
			(size 0.3048 0.381)
			(layers "B.Cu" "B.Mask" "B.Paste")
			(net "GND")
		)
	)
	(footprint ""
		(layer "B.Cu")
		(at 300.399704 -293.52494 180)
		(property "Reference" "C1613"
			(at 0 0 0)
			(layer "B.SilkS")
			(hide yes)
			(effects
				(font
					(size 1.27 1.27)
				)
				(justify mirror)
			)
		)
		(property "Value" ""
			(at 0 0 0)
			(layer "B.Fab")
			(effects
				(font
					(size 1.27 1.27)
				)
				(justify mirror)
			)
		)
		(duplicate_pad_numbers_are_jumpers no)
		(fp_line
			(start 0.299974 0.150114)
			(end 0.299974 -0.150114)
			(stroke
				(width 0.1)
				(type default)
			)
			(layer "B.Fab")
		)
		(fp_line
			(start 0.299974 -0.150114)
			(end -0.299974 -0.150114)
			(stroke
				(width 0.1)
				(type default)
			)
			(layer "B.Fab")
		)
		(fp_line
			(start -0.299974 0.150114)
			(end 0.299974 0.150114)
			(stroke
				(width 0.1)
				(type default)
			)
			(layer "B.Fab")
		)
		(fp_line
			(start -0.299974 -0.150114)
			(end -0.299974 0.150114)
			(stroke
				(width 0.1)
				(type default)
			)
			(layer "B.Fab")
		)
		(pad "1" smd rect
			(at 0.2667 0)
			(size 0.3048 0.381)
			(layers "B.Cu" "B.Mask" "B.Paste")
			(net "P0V8_PEX2")
		)
		(pad "2" smd rect
			(at -0.2667 0)
			(size 0.3048 0.381)
			(layers "B.Cu" "B.Mask" "B.Paste")
			(net "GND")
		)
	)
	(footprint ""
		(layer "B.Cu")
		(at 76.824078 -114.35207 90)
		(property "Reference" "C869"
			(at 0 0 90)
			(layer "B.SilkS")
			(hide yes)
			(effects
				(font
					(size 1.27 1.27)
				)
				(justify mirror)
			)
		)
		(property "Value" ""
			(at 0 0 90)
			(layer "B.Fab")
			(effects
				(font
					(size 1.27 1.27)
				)
				(justify mirror)
			)
		)
		(duplicate_pad_numbers_are_jumpers no)
		(fp_line
			(start 0.7874 -0.4064)
			(end -0.7874 -0.4064)
			(stroke
				(width 0.1524)
				(type default)
			)
			(layer "B.SilkS")
		)
		(fp_line
			(start -0.7874 -0.4064)
			(end -0.7874 0.4064)
			(stroke
				(width 0.1524)
				(type default)
			)
			(layer "B.SilkS")
		)
		(fp_line
			(start 0.7874 0.4064)
			(end 0.7874 -0.4064)
			(stroke
				(width 0.1524)
				(type default)
			)
			(layer "B.SilkS")
		)
		(fp_line
			(start -0.7874 0.4064)
			(end 0.7874 0.4064)
			(stroke
				(width 0.1524)
				(type default)
			)
			(layer "B.SilkS")
		)
		(fp_line
			(start 0.67945 -0.305054)
			(end 0.12065 -0.305054)
			(stroke
				(width 0.1)
				(type default)
			)
			(layer "B.Fab")
		)
		(fp_line
			(start 0.12065 -0.305054)
			(end 0.12065 -0.2794)
			(stroke
				(width 0.1)
				(type default)
			)
			(layer "B.Fab")
		)
		(fp_line
			(start -0.12065 -0.3048)
			(end -0.67945 -0.3048)
			(stroke
				(width 0.1)
				(type default)
			)
			(layer "B.Fab")
		)
		(fp_line
			(start -0.67945 -0.3048)
			(end -0.67945 0.3048)
			(stroke
				(width 0.1)
				(type default)
			)
			(layer "B.Fab")
		)
		(fp_line
			(start 0.12065 -0.2794)
			(end -0.12065 -0.2794)
			(stroke
				(width 0.1)
				(type default)
			)
			(layer "B.Fab")
		)
		(fp_line
			(start -0.12065 -0.2794)
			(end -0.12065 -0.3048)
			(stroke
				(width 0.1)
				(type default)
			)
			(layer "B.Fab")
		)
		(fp_line
			(start 0.12065 0.2794)
			(end 0.12065 0.3048)
			(stroke
				(width 0.1)
				(type default)
			)
			(layer "B.Fab")
		)
		(fp_line
			(start -0.120396 0.2794)
			(end 0.12065 0.2794)
			(stroke
				(width 0.1)
				(type default)
			)
			(layer "B.Fab")
		)
		(fp_line
			(start 0.67945 0.3048)
			(end 0.67945 -0.305054)
			(stroke
				(width 0.1)
				(type default)
			)
			(layer "B.Fab")
		)
		(fp_line
			(start 0.12065 0.3048)
			(end 0.67945 0.3048)
			(stroke
				(width 0.1)
				(type default)
			)
			(layer "B.Fab")
		)
		(fp_line
			(start -0.120396 0.3048)
			(end -0.120396 0.2794)
			(stroke
				(width 0.1)
				(type default)
			)
			(layer "B.Fab")
		)
		(fp_line
			(start -0.67945 0.3048)
			(end -0.120396 0.3048)
			(stroke
				(width 0.1)
				(type default)
			)
			(layer "B.Fab")
		)
		(pad "1" smd circle
			(at 0.40005 0 270)
			(size 0 0)
			(layers "B.Cu" "B.Mask" "B.Paste")
			(net "P3V3_NIC1")
		)
		(pad "2" smd circle
			(at -0.40005 0 270)
			(size 0 0)
			(layers "B.Cu" "B.Mask" "B.Paste")
			(net "GND")
		)
	)
	(footprint ""
		(layer "B.Cu")
		(at 240.461038 -218.610434 180)
		(property "Reference" "C3612"
			(at 0 0 0)
			(layer "B.SilkS")
			(hide yes)
			(effects
				(font
					(size 1.27 1.27)
				)
				(justify mirror)
			)
		)
		(property "Value" ""
			(at 0 0 0)
			(layer "B.Fab")
			(effects
				(font
					(size 1.27 1.27)
				)
				(justify mirror)
			)
		)
		(duplicate_pad_numbers_are_jumpers no)
		(fp_line
			(start 0.69215 0.2921)
			(end 0.69215 -0.2921)
			(stroke
				(width 0.1524)
				(type default)
			)
			(layer "B.SilkS")
		)
		(fp_line
			(start 0.69215 -0.2921)
			(end -0.69215 -0.2921)
			(stroke
				(width 0.1524)
				(type default)
			)
			(layer "B.SilkS")
		)
		(fp_line
			(start -0.69215 0.2921)
			(end 0.69215 0.2921)
			(stroke
				(width 0.1524)
				(type default)
			)
			(layer "B.SilkS")
		)
		(fp_line
			(start -0.69215 -0.2921)
			(end -0.69215 0.2921)
			(stroke
				(width 0.1524)
				(type default)
			)
			(layer "B.SilkS")
		)
		(fp_line
			(start 0.51435 0.2794)
			(end 0.51435 -0.2794)
			(stroke
				(width 0.1)
				(type default)
			)
			(layer "B.Fab")
		)
		(fp_line
			(start 0.51435 -0.2794)
			(end -0.51435 -0.2794)
			(stroke
				(width 0.1)
				(type default)
			)
			(layer "B.Fab")
		)
		(fp_line
			(start -0.51435 0.2794)
			(end 0.51435 0.2794)
			(stroke
				(width 0.1)
				(type default)
			)
			(layer "B.Fab")
		)
		(fp_line
			(start -0.51435 -0.2794)
			(end -0.51435 0.2794)
			(stroke
				(width 0.1)
				(type default)
			)
			(layer "B.Fab")
		)
		(pad "1" smd circle
			(at 0.40005 0)
			(size 0 0)
			(layers "B.Cu" "B.Mask" "B.Paste")
			(net "P1V2_BIC_ADCVREFREXT0")
		)
		(pad "2" smd circle
			(at -0.40005 0)
			(size 0 0)
			(layers "B.Cu" "B.Mask" "B.Paste")
			(net "GND")
		)
		(zone
			(layer "B.Cu")
			(hatch none 0.5)
			(connect_pads
				(clearance 0)
			)
			(min_thickness 0.25)
			(keepout
				(tracks not_allowed)
				(vias allowed)
				(pads allowed)
				(copperpour not_allowed)
				(footprints allowed)
			)
			(placement
				(enabled no)
				(sheetname "")
			)
			(fill
				(thermal_gap 0.5)
				(thermal_bridge_width 0.5)
				(island_removal_mode 0)
			)
			(polygon
				(pts
					(xy 240.270538 -218.698064) (xy 240.361978 -218.75623) (xy 240.561368 -218.75623) (xy 240.651538 -218.698064)
					(xy 240.651538 -218.522804) (xy 240.561368 -218.464384) (xy 240.361978 -218.464384) (xy 240.270538 -218.52255)
				)
			)
		)
	)
	(footprint ""
		(layer "B.Cu")
		(at 287.145476 -296.37482)
		(property "Reference" "C1636"
			(at 0 0 0)
			(layer "B.SilkS")
			(hide yes)
			(effects
				(font
					(size 1.27 1.27)
				)
				(justify mirror)
			)
		)
		(property "Value" ""
			(at 0 0 0)
			(layer "B.Fab")
			(effects
				(font
					(size 1.27 1.27)
				)
				(justify mirror)
			)
		)
		(duplicate_pad_numbers_are_jumpers no)
		(fp_line
			(start -0.299974 -0.150114)
			(end -0.299974 0.150114)
			(stroke
				(width 0.1)
				(type default)
			)
			(layer "B.Fab")
		)
		(fp_line
			(start -0.299974 0.150114)
			(end 0.299974 0.150114)
			(stroke
				(width 0.1)
				(type default)
			)
			(layer "B.Fab")
		)
		(fp_line
			(start 0.299974 -0.150114)
			(end -0.299974 -0.150114)
			(stroke
				(width 0.1)
				(type default)
			)
			(layer "B.Fab")
		)
		(fp_line
			(start 0.299974 0.150114)
			(end 0.299974 -0.150114)
			(stroke
				(width 0.1)
				(type default)
			)
			(layer "B.Fab")
		)
		(pad "1" smd rect
			(at 0.2667 0 180)
			(size 0.3048 0.381)
			(layers "B.Cu" "B.Mask" "B.Paste")
			(net "P0V8_PEX2")
		)
		(pad "2" smd rect
			(at -0.2667 0 180)
			(size 0.3048 0.381)
			(layers "B.Cu" "B.Mask" "B.Paste")
			(net "GND")
		)
	)
	(footprint ""
		(layer "B.Cu")
		(at 9.142984 -274.99183 180)
		(property "Reference" "C4236"
			(at 0 0 0)
			(layer "B.SilkS")
			(hide yes)
			(effects
				(font
					(size 1.27 1.27)
				)
				(justify mirror)
			)
		)
		(property "Value" ""
			(at 0 0 0)
			(layer "B.Fab")
			(effects
				(font
					(size 1.27 1.27)
				)
				(justify mirror)
			)
		)
		(duplicate_pad_numbers_are_jumpers no)
		(fp_line
			(start 0.299974 0.150114)
			(end 0.299974 -0.150114)
			(stroke
				(width 0.1)
				(type default)
			)
			(layer "B.Fab")
		)
		(fp_line
			(start 0.299974 -0.150114)
			(end -0.299974 -0.150114)
			(stroke
				(width 0.1)
				(type default)
			)
			(layer "B.Fab")
		)
		(fp_line
			(start -0.299974 0.150114)
			(end 0.299974 0.150114)
			(stroke
				(width 0.1)
				(type default)
			)
			(layer "B.Fab")
		)
		(fp_line
			(start -0.299974 -0.150114)
			(end -0.299974 0.150114)
			(stroke
				(width 0.1)
				(type default)
			)
			(layer "B.Fab")
		)
		(pad "1" smd rect
			(at 0.2667 0)
			(size 0.3048 0.381)
			(layers "B.Cu" "B.Mask" "B.Paste")
			(net "P1V25_PEX0")
		)
		(pad "2" smd rect
			(at -0.2667 0)
			(size 0.3048 0.381)
			(layers "B.Cu" "B.Mask" "B.Paste")
			(net "GND")
		)
	)
	(footprint ""
		(layer "B.Cu")
		(at 164.824918 -293.99992 90)
		(property "Reference" "C1368"
			(at 0 0 90)
			(layer "B.SilkS")
			(hide yes)
			(effects
				(font
					(size 1.27 1.27)
				)
				(justify mirror)
			)
		)
		(property "Value" ""
			(at 0 0 90)
			(layer "B.Fab")
			(effects
				(font
					(size 1.27 1.27)
				)
				(justify mirror)
			)
		)
		(duplicate_pad_numbers_are_jumpers no)
		(fp_line
			(start 0.299974 -0.150114)
			(end -0.299974 -0.150114)
			(stroke
				(width 0.1)
				(type default)
			)
			(layer "B.Fab")
		)
		(fp_line
			(start -0.299974 -0.150114)
			(end -0.299974 0.150114)
			(stroke
				(width 0.1)
				(type default)
			)
			(layer "B.Fab")
		)
		(fp_line
			(start 0.299974 0.150114)
			(end 0.299974 -0.150114)
			(stroke
				(width 0.1)
				(type default)
			)
			(layer "B.Fab")
		)
		(fp_line
			(start -0.299974 0.150114)
			(end 0.299974 0.150114)
			(stroke
				(width 0.1)
				(type default)
			)
			(layer "B.Fab")
		)
		(pad "1" smd rect
			(at 0.2667 0 270)
			(size 0.3048 0.381)
			(layers "B.Cu" "B.Mask" "B.Paste")
			(net "P0V8_PEX1")
		)
		(pad "2" smd rect
			(at -0.2667 0 270)
			(size 0.3048 0.381)
			(layers "B.Cu" "B.Mask" "B.Paste")
			(net "GND")
		)
	)
	(footprint ""
		(layer "B.Cu")
		(at 401.930108 -295.221914)
		(property "Reference" "C1866"
			(at 0 0 0)
			(layer "B.SilkS")
			(hide yes)
			(effects
				(font
					(size 1.27 1.27)
				)
				(justify mirror)
			)
		)
		(property "Value" ""
			(at 0 0 0)
			(layer "B.Fab")
			(effects
				(font
					(size 1.27 1.27)
				)
				(justify mirror)
			)
		)
		(duplicate_pad_numbers_are_jumpers no)
		(fp_line
			(start -1.2954 -0.5842)
			(end -1.2954 0.5842)
			(stroke
				(width 0.1524)
				(type default)
			)
			(layer "B.SilkS")
		)
		(fp_line
			(start -1.2954 0.5842)
			(end 1.2954 0.5842)
			(stroke
				(width 0.1524)
				(type default)
			)
			(layer "B.SilkS")
		)
		(fp_line
			(start 1.2954 -0.5842)
			(end -1.2954 -0.5842)
			(stroke
				(width 0.1524)
				(type default)
			)
			(layer "B.SilkS")
		)
		(fp_line
			(start 1.2954 0.5842)
			(end 1.2954 -0.5842)
			(stroke
				(width 0.1524)
				(type default)
			)
			(layer "B.SilkS")
		)
		(fp_line
			(start -1.1938 -0.4064)
			(end -1.1938 0.4064)
			(stroke
				(width 0.1)
				(type default)
			)
			(layer "B.Fab")
		)
		(fp_line
			(start -1.1938 0.4064)
			(end -0.8636 0.4064)
			(stroke
				(width 0.1)
				(type default)
			)
			(layer "B.Fab")
		)
		(fp_line
			(start -0.8636 -0.4572)
			(end -0.8636 -0.4064)
			(stroke
				(width 0.1)
				(type default)
			)
			(layer "B.Fab")
		)
		(fp_line
			(start -0.8636 -0.4064)
			(end -1.1938 -0.4064)
			(stroke
				(width 0.1)
				(type default)
			)
			(layer "B.Fab")
		)
		(fp_line
			(start -0.8636 0.4064)
			(end -0.8636 0.4572)
			(stroke
				(width 0.1)
				(type default)
			)
			(layer "B.Fab")
		)
		(fp_line
			(start -0.8636 0.4572)
			(end 0.8636 0.4572)
			(stroke
				(width 0.1)
				(type default)
			)
			(layer "B.Fab")
		)
		(fp_line
			(start 0.8636 -0.4572)
			(end -0.8636 -0.4572)
			(stroke
				(width 0.1)
				(type default)
			)
			(layer "B.Fab")
		)
		(fp_line
			(start 0.8636 -0.4064)
			(end 0.8636 -0.4572)
			(stroke
				(width 0.1)
				(type default)
			)
			(layer "B.Fab")
		)
		(fp_line
			(start 0.8636 0.4064)
			(end 1.1938 0.4064)
			(stroke
				(width 0.1)
				(type default)
			)
			(layer "B.Fab")
		)
		(fp_line
			(start 0.8636 0.4572)
			(end 0.8636 0.4064)
			(stroke
				(width 0.1)
				(type default)
			)
			(layer "B.Fab")
		)
		(fp_line
			(start 1.1938 -0.4064)
			(end 0.8636 -0.4064)
			(stroke
				(width 0.1)
				(type default)
			)
			(layer "B.Fab")
		)
		(fp_line
			(start 1.1938 0.4064)
			(end 1.1938 -0.4064)
			(stroke
				(width 0.1)
				(type default)
			)
			(layer "B.Fab")
		)
		(pad "1" smd rect
			(at 0.7366 0 270)
			(size 0.7112 0.8128)
			(layers "B.Cu" "B.Mask" "B.Paste")
			(net "P0V8_PEX3")
		)
		(pad "2" smd rect
			(at -0.7366 0 270)
			(size 0.7112 0.8128)
			(layers "B.Cu" "B.Mask" "B.Paste")
			(net "GND")
		)
	)
	(footprint ""
		(layer "B.Cu")
		(at 170.999912 -303.499774 -90)
		(property "Reference" "C3078"
			(at 0 0 90)
			(layer "B.SilkS")
			(hide yes)
			(effects
				(font
					(size 1.27 1.27)
				)
				(justify mirror)
			)
		)
		(property "Value" ""
			(at 0 0 90)
			(layer "B.Fab")
			(effects
				(font
					(size 1.27 1.27)
				)
				(justify mirror)
			)
		)
		(duplicate_pad_numbers_are_jumpers no)
		(fp_line
			(start -0.299974 0.150114)
			(end 0.299974 0.150114)
			(stroke
				(width 0.1)
				(type default)
			)
			(layer "B.Fab")
		)
		(fp_line
			(start 0.299974 0.150114)
			(end 0.299974 -0.150114)
			(stroke
				(width 0.1)
				(type default)
			)
			(layer "B.Fab")
		)
		(fp_line
			(start -0.299974 -0.150114)
			(end -0.299974 0.150114)
			(stroke
				(width 0.1)
				(type default)
			)
			(layer "B.Fab")
		)
		(fp_line
			(start 0.299974 -0.150114)
			(end -0.299974 -0.150114)
			(stroke
				(width 0.1)
				(type default)
			)
			(layer "B.Fab")
		)
		(pad "1" smd rect
			(at 0.2667 0 90)
			(size 0.3048 0.381)
			(layers "B.Cu" "B.Mask" "B.Paste")
			(net "P1V25_PEX1")
		)
		(pad "2" smd rect
			(at -0.2667 0 90)
			(size 0.3048 0.381)
			(layers "B.Cu" "B.Mask" "B.Paste")
			(net "GND")
		)
	)
	(footprint ""
		(layer "B.Cu")
		(at 341.619586 -282.040584 90)
		(property "Reference" "PR150"
			(at 0 0 90)
			(layer "B.SilkS")
			(hide yes)
			(effects
				(font
					(size 1.27 1.27)
				)
				(justify mirror)
			)
		)
		(property "Value" ""
			(at 0 0 90)
			(layer "B.Fab")
			(effects
				(font
					(size 1.27 1.27)
				)
				(justify mirror)
			)
		)
		(duplicate_pad_numbers_are_jumpers no)
		(fp_line
			(start 0.7874 -0.4064)
			(end -0.7874 -0.4064)
			(stroke
				(width 0.1524)
				(type default)
			)
			(layer "B.SilkS")
		)
		(fp_line
			(start -0.7874 -0.4064)
			(end -0.7874 0.4064)
			(stroke
				(width 0.1524)
				(type default)
			)
			(layer "B.SilkS")
		)
		(fp_line
			(start 0.7874 0.4064)
			(end 0.7874 -0.4064)
			(stroke
				(width 0.1524)
				(type default)
			)
			(layer "B.SilkS")
		)
		(fp_line
			(start -0.7874 0.4064)
			(end 0.7874 0.4064)
			(stroke
				(width 0.1524)
				(type default)
			)
			(layer "B.SilkS")
		)
		(fp_line
			(start 0.67945 -0.305054)
			(end 0.12065 -0.305054)
			(stroke
				(width 0.1)
				(type default)
			)
			(layer "B.Fab")
		)
		(fp_line
			(start 0.12065 -0.305054)
			(end 0.12065 -0.2794)
			(stroke
				(width 0.1)
				(type default)
			)
			(layer "B.Fab")
		)
		(fp_line
			(start -0.12065 -0.3048)
			(end -0.67945 -0.3048)
			(stroke
				(width 0.1)
				(type default)
			)
			(layer "B.Fab")
		)
		(fp_line
			(start -0.67945 -0.3048)
			(end -0.67945 0.3048)
			(stroke
				(width 0.1)
				(type default)
			)
			(layer "B.Fab")
		)
		(fp_line
			(start 0.12065 -0.2794)
			(end -0.12065 -0.2794)
			(stroke
				(width 0.1)
				(type default)
			)
			(layer "B.Fab")
		)
		(fp_line
			(start -0.12065 -0.2794)
			(end -0.12065 -0.3048)
			(stroke
				(width 0.1)
				(type default)
			)
			(layer "B.Fab")
		)
		(fp_line
			(start 0.12065 0.2794)
			(end 0.12065 0.3048)
			(stroke
				(width 0.1)
				(type default)
			)
			(layer "B.Fab")
		)
		(fp_line
			(start -0.120396 0.2794)
			(end 0.12065 0.2794)
			(stroke
				(width 0.1)
				(type default)
			)
			(layer "B.Fab")
		)
		(fp_line
			(start 0.67945 0.3048)
			(end 0.67945 -0.305054)
			(stroke
				(width 0.1)
				(type default)
			)
			(layer "B.Fab")
		)
		(fp_line
			(start 0.12065 0.3048)
			(end 0.67945 0.3048)
			(stroke
				(width 0.1)
				(type default)
			)
			(layer "B.Fab")
		)
		(fp_line
			(start -0.120396 0.3048)
			(end -0.120396 0.2794)
			(stroke
				(width 0.1)
				(type default)
			)
			(layer "B.Fab")
		)
		(fp_line
			(start -0.67945 0.3048)
			(end -0.120396 0.3048)
			(stroke
				(width 0.1)
				(type default)
			)
			(layer "B.Fab")
		)
		(pad "1" smd circle
			(at 0.40005 0 270)
			(size 0 0)
			(layers "B.Cu" "B.Mask" "B.Paste")
			(net "SW_P0V8_PEX2_VOS1")
		)
		(pad "2" smd circle
			(at -0.40005 0 270)
			(size 0 0)
			(layers "B.Cu" "B.Mask" "B.Paste")
			(net "P0V8_PEX2")
		)
	)
	(footprint ""
		(layer "B.Cu")
		(at 372.759224 -226.535996 -90)
		(property "Reference" "R3506"
			(at 0 0 90)
			(layer "B.SilkS")
			(hide yes)
			(effects
				(font
					(size 1.27 1.27)
				)
				(justify mirror)
			)
		)
		(property "Value" ""
			(at 0 0 90)
			(layer "B.Fab")
			(effects
				(font
					(size 1.27 1.27)
				)
				(justify mirror)
			)
		)
		(duplicate_pad_numbers_are_jumpers no)
		(fp_line
			(start -0.7874 0.4064)
			(end 0.7874 0.4064)
			(stroke
				(width 0.1524)
				(type default)
			)
			(layer "B.SilkS")
		)
		(fp_line
			(start 0.7874 0.4064)
			(end 0.7874 -0.4064)
			(stroke
				(width 0.1524)
				(type default)
			)
			(layer "B.SilkS")
		)
		(fp_line
			(start -0.7874 -0.4064)
			(end -0.7874 0.4064)
			(stroke
				(width 0.1524)
				(type default)
			)
			(layer "B.SilkS")
		)
		(fp_line
			(start 0.7874 -0.4064)
			(end -0.7874 -0.4064)
			(stroke
				(width 0.1524)
				(type default)
			)
			(layer "B.SilkS")
		)
		(fp_line
			(start -0.67945 0.3048)
			(end -0.120396 0.3048)
			(stroke
				(width 0.1)
				(type default)
			)
			(layer "B.Fab")
		)
		(fp_line
			(start -0.120396 0.3048)
			(end -0.120396 0.2794)
			(stroke
				(width 0.1)
				(type default)
			)
			(layer "B.Fab")
		)
		(fp_line
			(start 0.12065 0.3048)
			(end 0.67945 0.3048)
			(stroke
				(width 0.1)
				(type default)
			)
			(layer "B.Fab")
		)
		(fp_line
			(start 0.67945 0.3048)
			(end 0.67945 -0.305054)
			(stroke
				(width 0.1)
				(type default)
			)
			(layer "B.Fab")
		)
		(fp_line
			(start -0.120396 0.2794)
			(end 0.12065 0.2794)
			(stroke
				(width 0.1)
				(type default)
			)
			(layer "B.Fab")
		)
		(fp_line
			(start 0.12065 0.2794)
			(end 0.12065 0.3048)
			(stroke
				(width 0.1)
				(type default)
			)
			(layer "B.Fab")
		)
		(fp_line
			(start -0.12065 -0.2794)
			(end -0.12065 -0.3048)
			(stroke
				(width 0.1)
				(type default)
			)
			(layer "B.Fab")
		)
		(fp_line
			(start 0.12065 -0.2794)
			(end -0.12065 -0.2794)
			(stroke
				(width 0.1)
				(type default)
			)
			(layer "B.Fab")
		)
		(fp_line
			(start -0.67945 -0.3048)
			(end -0.67945 0.3048)
			(stroke
				(width 0.1)
				(type default)
			)
			(layer "B.Fab")
		)
		(fp_line
			(start -0.12065 -0.3048)
			(end -0.67945 -0.3048)
			(stroke
				(width 0.1)
				(type default)
			)
			(layer "B.Fab")
		)
		(fp_line
			(start 0.12065 -0.305054)
			(end 0.12065 -0.2794)
			(stroke
				(width 0.1)
				(type default)
			)
			(layer "B.Fab")
		)
		(fp_line
			(start 0.67945 -0.305054)
			(end 0.12065 -0.305054)
			(stroke
				(width 0.1)
				(type default)
			)
			(layer "B.Fab")
		)
		(pad "1" smd circle
			(at 0.40005 0 90)
			(size 0 0)
			(layers "B.Cu" "B.Mask" "B.Paste")
			(net "P1V8_PEX")
		)
		(pad "2" smd circle
			(at -0.40005 0 90)
			(size 0 0)
			(layers "B.Cu" "B.Mask" "B.Paste")
			(net "SPI_PEX3_CS_MUX_R_N")
		)
	)
	(footprint ""
		(layer "B.Cu")
		(at 347.66631 -256.226564 90)
		(property "Reference" "PR147"
			(at 0 0 90)
			(layer "B.SilkS")
			(hide yes)
			(effects
				(font
					(size 1.27 1.27)
				)
				(justify mirror)
			)
		)
		(property "Value" ""
			(at 0 0 90)
			(layer "B.Fab")
			(effects
				(font
					(size 1.27 1.27)
				)
				(justify mirror)
			)
		)
		(duplicate_pad_numbers_are_jumpers no)
		(fp_line
			(start 0.7874 -0.4064)
			(end -0.7874 -0.4064)
			(stroke
				(width 0.1524)
				(type default)
			)
			(layer "B.SilkS")
		)
		(fp_line
			(start -0.7874 -0.4064)
			(end -0.7874 0.4064)
			(stroke
				(width 0.1524)
				(type default)
			)
			(layer "B.SilkS")
		)
		(fp_line
			(start 0.7874 0.4064)
			(end 0.7874 -0.4064)
			(stroke
				(width 0.1524)
				(type default)
			)
			(layer "B.SilkS")
		)
		(fp_line
			(start -0.7874 0.4064)
			(end 0.7874 0.4064)
			(stroke
				(width 0.1524)
				(type default)
			)
			(layer "B.SilkS")
		)
		(fp_line
			(start 0.67945 -0.305054)
			(end 0.12065 -0.305054)
			(stroke
				(width 0.1)
				(type default)
			)
			(layer "B.Fab")
		)
		(fp_line
			(start 0.12065 -0.305054)
			(end 0.12065 -0.2794)
			(stroke
				(width 0.1)
				(type default)
			)
			(layer "B.Fab")
		)
		(fp_line
			(start -0.12065 -0.3048)
			(end -0.67945 -0.3048)
			(stroke
				(width 0.1)
				(type default)
			)
			(layer "B.Fab")
		)
		(fp_line
			(start -0.67945 -0.3048)
			(end -0.67945 0.3048)
			(stroke
				(width 0.1)
				(type default)
			)
			(layer "B.Fab")
		)
		(fp_line
			(start 0.12065 -0.2794)
			(end -0.12065 -0.2794)
			(stroke
				(width 0.1)
				(type default)
			)
			(layer "B.Fab")
		)
		(fp_line
			(start -0.12065 -0.2794)
			(end -0.12065 -0.3048)
			(stroke
				(width 0.1)
				(type default)
			)
			(layer "B.Fab")
		)
		(fp_line
			(start 0.12065 0.2794)
			(end 0.12065 0.3048)
			(stroke
				(width 0.1)
				(type default)
			)
			(layer "B.Fab")
		)
		(fp_line
			(start -0.120396 0.2794)
			(end 0.12065 0.2794)
			(stroke
				(width 0.1)
				(type default)
			)
			(layer "B.Fab")
		)
		(fp_line
			(start 0.67945 0.3048)
			(end 0.67945 -0.305054)
			(stroke
				(width 0.1)
				(type default)
			)
			(layer "B.Fab")
		)
		(fp_line
			(start 0.12065 0.3048)
			(end 0.67945 0.3048)
			(stroke
				(width 0.1)
				(type default)
			)
			(layer "B.Fab")
		)
		(fp_line
			(start -0.120396 0.3048)
			(end -0.120396 0.2794)
			(stroke
				(width 0.1)
				(type default)
			)
			(layer "B.Fab")
		)
		(fp_line
			(start -0.67945 0.3048)
			(end -0.120396 0.3048)
			(stroke
				(width 0.1)
				(type default)
			)
			(layer "B.Fab")
		)
		(pad "1" smd circle
			(at 0.40005 0 270)
			(size 0 0)
			(layers "B.Cu" "B.Mask" "B.Paste")
			(net "P0V8_PEX2_VINSEN")
		)
		(pad "2" smd circle
			(at -0.40005 0 270)
			(size 0 0)
			(layers "B.Cu" "B.Mask" "B.Paste")
			(net "GND")
		)
	)
	(footprint ""
		(layer "B.Cu")
		(at 177.423826 -191.381634)
		(property "Reference" "R1036"
			(at 0 0 0)
			(layer "B.SilkS")
			(hide yes)
			(effects
				(font
					(size 1.27 1.27)
				)
				(justify mirror)
			)
		)
		(property "Value" ""
			(at 0 0 0)
			(layer "B.Fab")
			(effects
				(font
					(size 1.27 1.27)
				)
				(justify mirror)
			)
		)
		(duplicate_pad_numbers_are_jumpers no)
		(fp_line
			(start -0.7874 -0.4064)
			(end -0.7874 0.4064)
			(stroke
				(width 0.1524)
				(type default)
			)
			(layer "B.SilkS")
		)
		(fp_line
			(start -0.7874 0.4064)
			(end 0.7874 0.4064)
			(stroke
				(width 0.1524)
				(type default)
			)
			(layer "B.SilkS")
		)
		(fp_line
			(start 0.7874 -0.4064)
			(end -0.7874 -0.4064)
			(stroke
				(width 0.1524)
				(type default)
			)
			(layer "B.SilkS")
		)
		(fp_line
			(start 0.7874 0.4064)
			(end 0.7874 -0.4064)
			(stroke
				(width 0.1524)
				(type default)
			)
			(layer "B.SilkS")
		)
		(fp_line
			(start -0.67945 -0.3048)
			(end -0.67945 0.3048)
			(stroke
				(width 0.1)
				(type default)
			)
			(layer "B.Fab")
		)
		(fp_line
			(start -0.67945 0.3048)
			(end -0.120396 0.3048)
			(stroke
				(width 0.1)
				(type default)
			)
			(layer "B.Fab")
		)
		(fp_line
			(start -0.12065 -0.3048)
			(end -0.67945 -0.3048)
			(stroke
				(width 0.1)
				(type default)
			)
			(layer "B.Fab")
		)
		(fp_line
			(start -0.12065 -0.2794)
			(end -0.12065 -0.3048)
			(stroke
				(width 0.1)
				(type default)
			)
			(layer "B.Fab")
		)
		(fp_line
			(start -0.120396 0.2794)
			(end 0.12065 0.2794)
			(stroke
				(width 0.1)
				(type default)
			)
			(layer "B.Fab")
		)
		(fp_line
			(start -0.120396 0.3048)
			(end -0.120396 0.2794)
			(stroke
				(width 0.1)
				(type default)
			)
			(layer "B.Fab")
		)
		(fp_line
			(start 0.12065 -0.305054)
			(end 0.12065 -0.2794)
			(stroke
				(width 0.1)
				(type default)
			)
			(layer "B.Fab")
		)
		(fp_line
			(start 0.12065 -0.2794)
			(end -0.12065 -0.2794)
			(stroke
				(width 0.1)
				(type default)
			)
			(layer "B.Fab")
		)
		(fp_line
			(start 0.12065 0.2794)
			(end 0.12065 0.3048)
			(stroke
				(width 0.1)
				(type default)
			)
			(layer "B.Fab")
		)
		(fp_line
			(start 0.12065 0.3048)
			(end 0.67945 0.3048)
			(stroke
				(width 0.1)
				(type default)
			)
			(layer "B.Fab")
		)
		(fp_line
			(start 0.67945 -0.305054)
			(end 0.12065 -0.305054)
			(stroke
				(width 0.1)
				(type default)
			)
			(layer "B.Fab")
		)
		(fp_line
			(start 0.67945 0.3048)
			(end 0.67945 -0.305054)
			(stroke
				(width 0.1)
				(type default)
			)
			(layer "B.Fab")
		)
		(pad "1" smd circle
			(at 0.40005 0 180)
			(size 0 0)
			(layers "B.Cu" "B.Mask" "B.Paste")
			(net "GND")
		)
		(pad "2" smd circle
			(at -0.40005 0 180)
			(size 0 0)
			(layers "B.Cu" "B.Mask" "B.Paste")
			(net "SPI_BIC1_MISO_LS01_DIR4")
		)
	)
	(footprint ""
		(layer "B.Cu")
		(at 168.150032 -292.099746 90)
		(property "Reference" "C1434"
			(at 0 0 90)
			(layer "B.SilkS")
			(hide yes)
			(effects
				(font
					(size 1.27 1.27)
				)
				(justify mirror)
			)
		)
		(property "Value" ""
			(at 0 0 90)
			(layer "B.Fab")
			(effects
				(font
					(size 1.27 1.27)
				)
				(justify mirror)
			)
		)
		(duplicate_pad_numbers_are_jumpers no)
		(fp_line
			(start 0.299974 -0.150114)
			(end -0.299974 -0.150114)
			(stroke
				(width 0.1)
				(type default)
			)
			(layer "B.Fab")
		)
		(fp_line
			(start -0.299974 -0.150114)
			(end -0.299974 0.150114)
			(stroke
				(width 0.1)
				(type default)
			)
			(layer "B.Fab")
		)
		(fp_line
			(start 0.299974 0.150114)
			(end 0.299974 -0.150114)
			(stroke
				(width 0.1)
				(type default)
			)
			(layer "B.Fab")
		)
		(fp_line
			(start -0.299974 0.150114)
			(end 0.299974 0.150114)
			(stroke
				(width 0.1)
				(type default)
			)
			(layer "B.Fab")
		)
		(pad "1" smd rect
			(at 0.2667 0 270)
			(size 0.3048 0.381)
			(layers "B.Cu" "B.Mask" "B.Paste")
			(net "P0V8_SERDES_VDDA_PEX1")
		)
		(pad "2" smd rect
			(at -0.2667 0 270)
			(size 0.3048 0.381)
			(layers "B.Cu" "B.Mask" "B.Paste")
			(net "GND")
		)
	)
	(footprint ""
		(layer "B.Cu")
		(at 65.851278 -305.399948 -90)
		(property "Reference" "C2956"
			(at 0 0 90)
			(layer "B.SilkS")
			(hide yes)
			(effects
				(font
					(size 1.27 1.27)
				)
				(justify mirror)
			)
		)
		(property "Value" ""
			(at 0 0 90)
			(layer "B.Fab")
			(effects
				(font
					(size 1.27 1.27)
				)
				(justify mirror)
			)
		)
		(duplicate_pad_numbers_are_jumpers no)
		(fp_line
			(start -0.299974 0.150114)
			(end 0.299974 0.150114)
			(stroke
				(width 0.1)
				(type default)
			)
			(layer "B.Fab")
		)
		(fp_line
			(start 0.299974 0.150114)
			(end 0.299974 -0.150114)
			(stroke
				(width 0.1)
				(type default)
			)
			(layer "B.Fab")
		)
		(fp_line
			(start -0.299974 -0.150114)
			(end -0.299974 0.150114)
			(stroke
				(width 0.1)
				(type default)
			)
			(layer "B.Fab")
		)
		(fp_line
			(start 0.299974 -0.150114)
			(end -0.299974 -0.150114)
			(stroke
				(width 0.1)
				(type default)
			)
			(layer "B.Fab")
		)
		(pad "1" smd rect
			(at 0.2667 0 90)
			(size 0.3048 0.381)
			(layers "B.Cu" "B.Mask" "B.Paste")
			(net "P1V25_SERDES_VDDPLL_PEX0")
		)
		(pad "2" smd rect
			(at -0.2667 0 90)
			(size 0.3048 0.381)
			(layers "B.Cu" "B.Mask" "B.Paste")
			(net "GND")
		)
	)
)
